(kicad_pcb
	(version 20260206)
	(generator "pcbnew")
	(generator_version "10.0")
	(general
		(thickness 1.6)
		(legacy_teardrops no)
	)
	(paper "A4")
	(layers
		(0 "F.Cu" signal "TOP")
		(4 "In1.Cu" signal "GND")
		(6 "In2.Cu" signal "IN1")
		(8 "In3.Cu" signal "GND1")
		(10 "In4.Cu" signal "IN2")
		(12 "In5.Cu" signal "GND2")
		(14 "In6.Cu" signal "IN3")
		(16 "In7.Cu" signal "GND3")
		(18 "In8.Cu" signal "VCC")
		(20 "In9.Cu" signal "VCC1")
		(22 "In10.Cu" signal "GND4")
		(24 "In11.Cu" signal "IN4")
		(26 "In12.Cu" signal "GND5")
		(28 "In13.Cu" signal "IN5")
		(30 "In14.Cu" signal "GND6")
		(32 "In15.Cu" signal "IN6")
		(34 "In16.Cu" signal "GND7")
		(2 "B.Cu" signal "BOTTOM")
		(9 "F.Adhes" user "F.Adhesive")
		(11 "B.Adhes" user "B.Adhesive")
		(13 "F.Paste" user "Package Geometry/Pastemask Top")
		(15 "B.Paste" user "Package Geometry/Pastemask Bottom")
		(5 "F.SilkS" user "Ref Des/Silkscreen Top")
		(7 "B.SilkS" user "Ref Des/Silkscreen Bottom")
		(1 "F.Mask" user "Board Geometry/Soldermask Top")
		(3 "B.Mask" user "Board Geometry/Soldermask Bottom")
		(17 "Dwgs.User" user "User.Drawings")
		(19 "Cmts.User" user "User.Comments")
		(21 "Eco1.User" user "User.Eco1")
		(23 "Eco2.User" user "User.Eco2")
		(25 "Edge.Cuts" user "Board Geometry/Outline")
		(27 "Margin" user)
		(31 "F.CrtYd" user "Package Geometry/Place Bound Top")
		(29 "B.CrtYd" user "Package Geometry/Place Bound Bottom")
		(35 "F.Fab" user "Ref Des/Assembly Top")
		(33 "B.Fab" user "Ref Des/Assembly Bottom")
	)
	(setup
		(pad_to_mask_clearance 0)
		(allow_soldermask_bridges_in_footprints no)
		(tenting
			(front yes)
			(back yes)
		)
		(covering
			(front no)
			(back no)
		)
		(plugging
			(front no)
			(back no)
		)
		(capping no)
		(filling no)
		(pcbplotparams
			(layerselection 0x00000000_00000000_55555555_5755f5ff)
			(plot_on_all_layers_selection 0x00000000_00000000_00000000_00000000)
			(disableapertmacros no)
			(usegerberextensions no)
			(usegerberattributes yes)
			(usegerberadvancedattributes yes)
			(creategerberjobfile yes)
			(dashed_line_dash_ratio 12)
			(dashed_line_gap_ratio 3)
			(svgprecision 4)
			(plotframeref no)
			(mode 1)
			(useauxorigin no)
			(pdf_front_fp_property_popups yes)
			(pdf_back_fp_property_popups yes)
			(pdf_metadata yes)
			(pdf_single_document no)
			(dxfpolygonmode yes)
			(dxfimperialunits yes)
			(dxfusepcbnewfont yes)
			(psnegative no)
			(psa4output no)
			(plot_black_and_white yes)
			(sketchpadsonfab no)
			(plotpadnumbers no)
			(hidednponfab no)
			(sketchdnponfab yes)
			(crossoutdnponfab yes)
			(subtractmaskfromsilk no)
			(outputformat 1)
			(mirror no)
			(drillshape 1)
			(scaleselection 1)
			(outputdirectory "")
		)
	)
	(footprint ""
		(layer "F.Cu")
		(at 210.74888 -42.382948)
		(property "Reference" "R3529"
			(at 0 0 0)
			(layer "F.SilkS")
			(hide yes)
			(effects
				(font
					(size 1.27 1.27)
				)
			)
		)
		(property "Value" ""
			(at 0 0 0)
			(layer "F.Fab")
			(effects
				(font
					(size 1.27 1.27)
				)
			)
		)
		(duplicate_pad_numbers_are_jumpers no)
		(fp_line
			(start -0.7874 -0.4064)
			(end 0.7874 -0.4064)
			(stroke
				(width 0.1524)
				(type default)
			)
			(layer "F.SilkS")
		)
		(fp_line
			(start -0.7874 0.4064)
			(end -0.7874 -0.4064)
			(stroke
				(width 0.1524)
				(type default)
			)
			(layer "F.SilkS")
		)
		(fp_line
			(start 0.7874 -0.4064)
			(end 0.7874 0.4064)
			(stroke
				(width 0.1524)
				(type default)
			)
			(layer "F.SilkS")
		)
		(fp_line
			(start 0.7874 0.4064)
			(end -0.7874 0.4064)
			(stroke
				(width 0.1524)
				(type default)
			)
			(layer "F.SilkS")
		)
		(fp_line
			(start -0.67945 -0.305054)
			(end -0.12065 -0.305054)
			(stroke
				(width 0.1)
				(type default)
			)
			(layer "F.Fab")
		)
		(fp_line
			(start -0.67945 0.3048)
			(end -0.67945 -0.305054)
			(stroke
				(width 0.1)
				(type default)
			)
			(layer "F.Fab")
		)
		(fp_line
			(start -0.12065 -0.305054)
			(end -0.12065 -0.2794)
			(stroke
				(width 0.1)
				(type default)
			)
			(layer "F.Fab")
		)
		(fp_line
			(start -0.12065 -0.2794)
			(end 0.12065 -0.2794)
			(stroke
				(width 0.1)
				(type default)
			)
			(layer "F.Fab")
		)
		(fp_line
			(start -0.12065 0.2794)
			(end -0.12065 0.3048)
			(stroke
				(width 0.1)
				(type default)
			)
			(layer "F.Fab")
		)
		(fp_line
			(start -0.12065 0.3048)
			(end -0.67945 0.3048)
			(stroke
				(width 0.1)
				(type default)
			)
			(layer "F.Fab")
		)
		(fp_line
			(start 0.120396 0.2794)
			(end -0.12065 0.2794)
			(stroke
				(width 0.1)
				(type default)
			)
			(layer "F.Fab")
		)
		(fp_line
			(start 0.120396 0.3048)
			(end 0.120396 0.2794)
			(stroke
				(width 0.1)
				(type default)
			)
			(layer "F.Fab")
		)
		(fp_line
			(start 0.12065 -0.3048)
			(end 0.67945 -0.3048)
			(stroke
				(width 0.1)
				(type default)
			)
			(layer "F.Fab")
		)
		(fp_line
			(start 0.12065 -0.2794)
			(end 0.12065 -0.3048)
			(stroke
				(width 0.1)
				(type default)
			)
			(layer "F.Fab")
		)
		(fp_line
			(start 0.67945 -0.3048)
			(end 0.67945 0.3048)
			(stroke
				(width 0.1)
				(type default)
			)
			(layer "F.Fab")
		)
		(fp_line
			(start 0.67945 0.3048)
			(end 0.120396 0.3048)
			(stroke
				(width 0.1)
				(type default)
			)
			(layer "F.Fab")
		)
		(pad "1" smd circle
			(at -0.40005 0)
			(size 0 0)
			(layers "F.Cu" "F.Mask" "F.Paste")
			(net "P3V3_AUX")
		)
		(pad "2" smd circle
			(at 0.40005 0)
			(size 0 0)
			(layers "F.Cu" "F.Mask" "F.Paste")
			(net "SMB_PCIE_E1S_ISO_EN_R")
		)
	)
	(footprint ""
		(layer "F.Cu")
		(at 58.93308 -40.404034 180)
		(property "Reference" "R4066"
			(at 0 0 180)
			(layer "F.SilkS")
			(hide yes)
			(effects
				(font
					(size 1.27 1.27)
				)
			)
		)
		(property "Value" ""
			(at 0 0 180)
			(layer "F.Fab")
			(effects
				(font
					(size 1.27 1.27)
				)
			)
		)
		(duplicate_pad_numbers_are_jumpers no)
		(fp_line
			(start 0.7874 0.4064)
			(end -0.7874 0.4064)
			(stroke
				(width 0.1524)
				(type default)
			)
			(layer "F.SilkS")
		)
		(fp_line
			(start 0.7874 -0.4064)
			(end 0.7874 0.4064)
			(stroke
				(width 0.1524)
				(type default)
			)
			(layer "F.SilkS")
		)
		(fp_line
			(start -0.7874 0.4064)
			(end -0.7874 -0.4064)
			(stroke
				(width 0.1524)
				(type default)
			)
			(layer "F.SilkS")
		)
		(fp_line
			(start -0.7874 -0.4064)
			(end 0.7874 -0.4064)
			(stroke
				(width 0.1524)
				(type default)
			)
			(layer "F.SilkS")
		)
		(fp_line
			(start 0.67945 0.3048)
			(end 0.120396 0.3048)
			(stroke
				(width 0.1)
				(type default)
			)
			(layer "F.Fab")
		)
		(fp_line
			(start 0.67945 -0.3048)
			(end 0.67945 0.3048)
			(stroke
				(width 0.1)
				(type default)
			)
			(layer "F.Fab")
		)
		(fp_line
			(start 0.12065 -0.2794)
			(end 0.12065 -0.3048)
			(stroke
				(width 0.1)
				(type default)
			)
			(layer "F.Fab")
		)
		(fp_line
			(start 0.12065 -0.3048)
			(end 0.67945 -0.3048)
			(stroke
				(width 0.1)
				(type default)
			)
			(layer "F.Fab")
		)
		(fp_line
			(start 0.120396 0.3048)
			(end 0.120396 0.2794)
			(stroke
				(width 0.1)
				(type default)
			)
			(layer "F.Fab")
		)
		(fp_line
			(start 0.120396 0.2794)
			(end -0.12065 0.2794)
			(stroke
				(width 0.1)
				(type default)
			)
			(layer "F.Fab")
		)
		(fp_line
			(start -0.12065 0.3048)
			(end -0.67945 0.3048)
			(stroke
				(width 0.1)
				(type default)
			)
			(layer "F.Fab")
		)
		(fp_line
			(start -0.12065 0.2794)
			(end -0.12065 0.3048)
			(stroke
				(width 0.1)
				(type default)
			)
			(layer "F.Fab")
		)
		(fp_line
			(start -0.12065 -0.2794)
			(end 0.12065 -0.2794)
			(stroke
				(width 0.1)
				(type default)
			)
			(layer "F.Fab")
		)
		(fp_line
			(start -0.12065 -0.305054)
			(end -0.12065 -0.2794)
			(stroke
				(width 0.1)
				(type default)
			)
			(layer "F.Fab")
		)
		(fp_line
			(start -0.67945 0.3048)
			(end -0.67945 -0.305054)
			(stroke
				(width 0.1)
				(type default)
			)
			(layer "F.Fab")
		)
		(fp_line
			(start -0.67945 -0.305054)
			(end -0.12065 -0.305054)
			(stroke
				(width 0.1)
				(type default)
			)
			(layer "F.Fab")
		)
		(pad "1" smd circle
			(at -0.40005 0 180)
			(size 0 0)
			(layers "F.Cu" "F.Mask" "F.Paste")
			(net "P3V3_OCP_EN_2_R")
		)
		(pad "2" smd circle
			(at 0.40005 0 180)
			(size 0 0)
			(layers "F.Cu" "F.Mask" "F.Paste")
			(net "GND")
		)
	)
	(footprint ""
		(layer "F.Cu")
		(at 275.142198 -255.560068 180)
		(property "Reference" "J21"
			(at -2.2098 -81.984088 0)
			(unlocked yes)
			(layer "F.SilkS")
			(effects
				(font
					(size 0.7874 0.5842)
					(thickness 0.1524)
				)
			)
		)
		(property "Value" ""
			(at 0 0 180)
			(layer "F.Fab")
			(effects
				(font
					(size 1.27 1.27)
				)
			)
		)
		(duplicate_pad_numbers_are_jumpers no)
		(fp_line
			(start 3.24993 -81.000092)
			(end 3.24993 75.630532)
			(stroke
				(width 0.1524)
				(type default)
			)
			(layer "F.SilkS")
		)
		(fp_line
			(start -3.24993 75.630532)
			(end -3.24993 -81.000092)
			(stroke
				(width 0.1524)
				(type default)
			)
			(layer "F.SilkS")
		)
		(fp_line
			(start -3.24993 72.499982)
			(end 3.24993 72.499982)
			(stroke
				(width 0.1524)
				(type default)
			)
			(layer "F.SilkS")
		)
		(fp_line
			(start -3.24993 -72.499982)
			(end 3.24993 -72.499982)
			(stroke
				(width 0.1524)
				(type default)
			)
			(layer "F.SilkS")
		)
		(fp_line
			(start -3.24993 -81.000092)
			(end 3.24993 -81.000092)
			(stroke
				(width 0.1524)
				(type default)
			)
			(layer "F.SilkS")
		)
		(fp_poly
			(pts
				(xy -3.836924 -64.477138) (xy -3.382518 -63.9318) (xy -4.091432 -63.895478)
			)
			(stroke
				(width 0)
				(type default)
			)
			(fill yes)
			(layer "F.SilkS")
		)
		(fp_line
			(start 3.24993 81.000092)
			(end -3.24993 81.000092)
			(stroke
				(width 0.1)
				(type default)
			)
			(layer "F.Fab")
		)
		(fp_line
			(start 3.24993 -81.000092)
			(end 3.24993 81.000092)
			(stroke
				(width 0.1)
				(type default)
			)
			(layer "F.Fab")
		)
		(fp_line
			(start -3.24993 81.000092)
			(end -3.24993 -81.000092)
			(stroke
				(width 0.1)
				(type default)
			)
			(layer "F.Fab")
		)
		(fp_line
			(start -3.24993 72.499982)
			(end 3.24993 72.499982)
			(stroke
				(width 0.1)
				(type default)
			)
			(layer "F.Fab")
		)
		(fp_line
			(start -3.24993 71.000112)
			(end 3.24993 71.000112)
			(stroke
				(width 0.1)
				(type default)
			)
			(layer "F.Fab")
		)
		(fp_line
			(start -3.24993 -71.000112)
			(end 3.24993 -71.000112)
			(stroke
				(width 0.1)
				(type default)
			)
			(layer "F.Fab")
		)
		(fp_line
			(start -3.24993 -72.499982)
			(end 3.24993 -72.499982)
			(stroke
				(width 0.1)
				(type default)
			)
			(layer "F.Fab")
		)
		(fp_line
			(start -3.24993 -81.000092)
			(end 3.24993 -81.000092)
			(stroke
				(width 0.1)
				(type default)
			)
			(layer "F.Fab")
		)
		(fp_poly
			(pts
				(xy -3.41503 -63.324994) (xy -4.43103 -62.816994) (xy -4.43103 -63.832994)
			)
			(stroke
				(width 0)
				(type default)
			)
			(fill yes)
			(layer "F.Fab")
		)
		(pad "1" smd rect
			(at -2.050034 -63.324994 90)
			(size 0.519938 1.4986)
			(layers "F.Cu" "F.Mask" "F.Paste")
			(net "P12V_MEM_CPU0")
		)
		(pad "2" smd rect
			(at -2.050034 -62.47511 90)
			(size 0.519938 1.4986)
			(layers "F.Cu" "F.Mask" "F.Paste")
			(net "Net_2305")
		)
		(pad "3" smd rect
			(at -2.050034 -61.624972 90)
			(size 0.519938 1.4986)
			(layers "F.Cu" "F.Mask" "F.Paste")
			(net "P3V3_AUX")
		)
		(pad "4" smd rect
			(at -2.050034 -60.775088 90)
			(size 0.519938 1.4986)
			(layers "F.Cu" "F.Mask" "F.Paste")
			(net "I3C_SPD_DDRE_CPU0_SCL")
		)
		(pad "5" smd rect
			(at -2.050034 -59.92495 90)
			(size 0.519938 1.4986)
			(layers "F.Cu" "F.Mask" "F.Paste")
			(net "I3C_SPD_DDRE_CPU0_SDA")
		)
		(pad "6" smd rect
			(at -2.050034 -59.075066 90)
			(size 0.519938 1.4986)
			(layers "F.Cu" "F.Mask" "F.Paste")
			(net "GND")
		)
		(pad "7" smd rect
			(at -2.050034 -58.224928 90)
			(size 0.519938 1.4986)
			(layers "F.Cu" "F.Mask" "F.Paste")
			(net "M_E_CPU0_SA_DQ<0>")
		)
		(pad "8" smd rect
			(at -2.050034 -57.375044 90)
			(size 0.519938 1.4986)
			(layers "F.Cu" "F.Mask" "F.Paste")
			(net "GND")
		)
		(pad "9" smd rect
			(at -2.050034 -56.524906 90)
			(size 0.519938 1.4986)
			(layers "F.Cu" "F.Mask" "F.Paste")
			(net "M_E_CPU0_SA_DQ<1>")
		)
		(pad "10" smd rect
			(at -2.050034 -55.675022 90)
			(size 0.519938 1.4986)
			(layers "F.Cu" "F.Mask" "F.Paste")
			(net "GND")
		)
		(pad "11" smd rect
			(at -2.050034 -54.824884 90)
			(size 0.519938 1.4986)
			(layers "F.Cu" "F.Mask" "F.Paste")
			(net "M_E_CPU0_SA_DQS_DP<0>")
		)
		(pad "12" smd rect
			(at -2.050034 -53.975 90)
			(size 0.519938 1.4986)
			(layers "F.Cu" "F.Mask" "F.Paste")
			(net "M_E_CPU0_SA_DQS_DN<0>")
		)
		(pad "13" smd rect
			(at -2.050034 -53.125116 90)
			(size 0.519938 1.4986)
			(layers "F.Cu" "F.Mask" "F.Paste")
			(net "GND")
		)
		(pad "14" smd rect
			(at -2.050034 -52.274978 90)
			(size 0.519938 1.4986)
			(layers "F.Cu" "F.Mask" "F.Paste")
			(net "M_E_CPU0_SA_DQ<4>")
		)
		(pad "15" smd rect
			(at -2.050034 -51.425094 90)
			(size 0.519938 1.4986)
			(layers "F.Cu" "F.Mask" "F.Paste")
			(net "GND")
		)
		(pad "16" smd rect
			(at -2.050034 -50.574956 90)
			(size 0.519938 1.4986)
			(layers "F.Cu" "F.Mask" "F.Paste")
			(net "M_E_CPU0_SA_DQ<5>")
		)
		(pad "17" smd rect
			(at -2.050034 -49.725072 90)
			(size 0.519938 1.4986)
			(layers "F.Cu" "F.Mask" "F.Paste")
			(net "GND")
		)
		(pad "18" smd rect
			(at -2.050034 -48.874934 90)
			(size 0.519938 1.4986)
			(layers "F.Cu" "F.Mask" "F.Paste")
			(net "M_E_CPU0_SA_DQ<8>")
		)
		(pad "19" smd rect
			(at -2.050034 -48.02505 90)
			(size 0.519938 1.4986)
			(layers "F.Cu" "F.Mask" "F.Paste")
			(net "GND")
		)
		(pad "20" smd rect
			(at -2.050034 -47.174912 90)
			(size 0.519938 1.4986)
			(layers "F.Cu" "F.Mask" "F.Paste")
			(net "M_E_CPU0_SA_DQ<9>")
		)
		(pad "21" smd rect
			(at -2.050034 -46.325028 90)
			(size 0.519938 1.4986)
			(layers "F.Cu" "F.Mask" "F.Paste")
			(net "GND")
		)
		(pad "22" smd rect
			(at -2.050034 -45.47489 90)
			(size 0.519938 1.4986)
			(layers "F.Cu" "F.Mask" "F.Paste")
			(net "M_E_CPU0_SA_DQS_DP<1>")
		)
		(pad "23" smd rect
			(at -2.050034 -44.625006 90)
			(size 0.519938 1.4986)
			(layers "F.Cu" "F.Mask" "F.Paste")
			(net "M_E_CPU0_SA_DQS_DN<1>")
		)
		(pad "24" smd rect
			(at -2.050034 -43.775122 90)
			(size 0.519938 1.4986)
			(layers "F.Cu" "F.Mask" "F.Paste")
			(net "GND")
		)
		(pad "25" smd rect
			(at -2.050034 -42.924984 90)
			(size 0.519938 1.4986)
			(layers "F.Cu" "F.Mask" "F.Paste")
			(net "M_E_CPU0_SA_DQ<12>")
		)
		(pad "26" smd rect
			(at -2.050034 -42.0751 90)
			(size 0.519938 1.4986)
			(layers "F.Cu" "F.Mask" "F.Paste")
			(net "GND")
		)
		(pad "27" smd rect
			(at -2.050034 -41.224962 90)
			(size 0.519938 1.4986)
			(layers "F.Cu" "F.Mask" "F.Paste")
			(net "M_E_CPU0_SA_DQ<13>")
		)
		(pad "28" smd rect
			(at -2.050034 -40.375078 90)
			(size 0.519938 1.4986)
			(layers "F.Cu" "F.Mask" "F.Paste")
			(net "GND")
		)
		(pad "29" smd rect
			(at -2.050034 -39.52494 90)
			(size 0.519938 1.4986)
			(layers "F.Cu" "F.Mask" "F.Paste")
			(net "M_E_CPU0_SA_DQ<16>")
		)
		(pad "30" smd rect
			(at -2.050034 -38.675056 90)
			(size 0.519938 1.4986)
			(layers "F.Cu" "F.Mask" "F.Paste")
			(net "GND")
		)
		(pad "31" smd rect
			(at -2.050034 -37.824918 90)
			(size 0.519938 1.4986)
			(layers "F.Cu" "F.Mask" "F.Paste")
			(net "M_E_CPU0_SA_DQ<17>")
		)
		(pad "32" smd rect
			(at -2.050034 -36.975034 90)
			(size 0.519938 1.4986)
			(layers "F.Cu" "F.Mask" "F.Paste")
			(net "GND")
		)
		(pad "33" smd rect
			(at -2.050034 -36.124896 90)
			(size 0.519938 1.4986)
			(layers "F.Cu" "F.Mask" "F.Paste")
			(net "M_E_CPU0_SA_DQS_DP<2>")
		)
		(pad "34" smd rect
			(at -2.050034 -35.275012 90)
			(size 0.519938 1.4986)
			(layers "F.Cu" "F.Mask" "F.Paste")
			(net "M_E_CPU0_SA_DQS_DN<2>")
		)
		(pad "35" smd rect
			(at -2.050034 -34.425128 90)
			(size 0.519938 1.4986)
			(layers "F.Cu" "F.Mask" "F.Paste")
			(net "GND")
		)
		(pad "36" smd rect
			(at -2.050034 -33.57499 90)
			(size 0.519938 1.4986)
			(layers "F.Cu" "F.Mask" "F.Paste")
			(net "M_E_CPU0_SA_DQ<20>")
		)
		(pad "37" smd rect
			(at -2.050034 -32.725106 90)
			(size 0.519938 1.4986)
			(layers "F.Cu" "F.Mask" "F.Paste")
			(net "GND")
		)
		(pad "38" smd rect
			(at -2.050034 -31.874968 90)
			(size 0.519938 1.4986)
			(layers "F.Cu" "F.Mask" "F.Paste")
			(net "M_E_CPU0_SA_DQ<21>")
		)
		(pad "39" smd rect
			(at -2.050034 -31.025084 90)
			(size 0.519938 1.4986)
			(layers "F.Cu" "F.Mask" "F.Paste")
			(net "GND")
		)
		(pad "40" smd rect
			(at -2.050034 -30.174946 90)
			(size 0.519938 1.4986)
			(layers "F.Cu" "F.Mask" "F.Paste")
			(net "M_E_CPU0_SA_DQ<24>")
		)
		(pad "41" smd rect
			(at -2.050034 -29.325062 90)
			(size 0.519938 1.4986)
			(layers "F.Cu" "F.Mask" "F.Paste")
			(net "GND")
		)
		(pad "42" smd rect
			(at -2.050034 -28.474924 90)
			(size 0.519938 1.4986)
			(layers "F.Cu" "F.Mask" "F.Paste")
			(net "M_E_CPU0_SA_DQ<25>")
		)
		(pad "43" smd rect
			(at -2.050034 -27.62504 90)
			(size 0.519938 1.4986)
			(layers "F.Cu" "F.Mask" "F.Paste")
			(net "GND")
		)
		(pad "44" smd rect
			(at -2.050034 -26.774902 90)
			(size 0.519938 1.4986)
			(layers "F.Cu" "F.Mask" "F.Paste")
			(net "M_E_CPU0_SA_DQS_DP<3>")
		)
		(pad "45" smd rect
			(at -2.050034 -25.925018 90)
			(size 0.519938 1.4986)
			(layers "F.Cu" "F.Mask" "F.Paste")
			(net "M_E_CPU0_SA_DQS_DN<3>")
		)
		(pad "46" smd rect
			(at -2.050034 -25.07488 90)
			(size 0.519938 1.4986)
			(layers "F.Cu" "F.Mask" "F.Paste")
			(net "GND")
		)
		(pad "47" smd rect
			(at -2.050034 -24.224996 90)
			(size 0.519938 1.4986)
			(layers "F.Cu" "F.Mask" "F.Paste")
			(net "M_E_CPU0_SA_DQ<28>")
		)
		(pad "48" smd rect
			(at -2.050034 -23.375112 90)
			(size 0.519938 1.4986)
			(layers "F.Cu" "F.Mask" "F.Paste")
			(net "GND")
		)
		(pad "49" smd rect
			(at -2.050034 -22.524974 90)
			(size 0.519938 1.4986)
			(layers "F.Cu" "F.Mask" "F.Paste")
			(net "M_E_CPU0_SA_DQ<29>")
		)
		(pad "50" smd rect
			(at -2.050034 -21.67509 90)
			(size 0.519938 1.4986)
			(layers "F.Cu" "F.Mask" "F.Paste")
			(net "GND")
		)
		(pad "51" smd rect
			(at -2.050034 -20.824952 90)
			(size 0.519938 1.4986)
			(layers "F.Cu" "F.Mask" "F.Paste")
			(net "M_E_CPU0_SA_CB<0>")
		)
		(pad "52" smd rect
			(at -2.050034 -19.975068 90)
			(size 0.519938 1.4986)
			(layers "F.Cu" "F.Mask" "F.Paste")
			(net "GND")
		)
		(pad "53" smd rect
			(at -2.050034 -19.12493 90)
			(size 0.519938 1.4986)
			(layers "F.Cu" "F.Mask" "F.Paste")
			(net "M_E_CPU0_SA_CB<1>")
		)
		(pad "54" smd rect
			(at -2.050034 -18.275046 90)
			(size 0.519938 1.4986)
			(layers "F.Cu" "F.Mask" "F.Paste")
			(net "GND")
		)
		(pad "55" smd rect
			(at -2.050034 -17.424908 90)
			(size 0.519938 1.4986)
			(layers "F.Cu" "F.Mask" "F.Paste")
			(net "M_E_CPU0_SA_DQS_DP<4>")
		)
		(pad "56" smd rect
			(at -2.050034 -16.575024 90)
			(size 0.519938 1.4986)
			(layers "F.Cu" "F.Mask" "F.Paste")
			(net "M_E_CPU0_SA_DQS_DN<4>")
		)
		(pad "57" smd rect
			(at -2.050034 -15.724886 90)
			(size 0.519938 1.4986)
			(layers "F.Cu" "F.Mask" "F.Paste")
			(net "GND")
		)
		(pad "58" smd rect
			(at -2.050034 -14.875002 90)
			(size 0.519938 1.4986)
			(layers "F.Cu" "F.Mask" "F.Paste")
			(net "M_E_CPU0_SA_CB<4>")
		)
		(pad "59" smd rect
			(at -2.050034 -14.025118 90)
			(size 0.519938 1.4986)
			(layers "F.Cu" "F.Mask" "F.Paste")
			(net "GND")
		)
		(pad "60" smd rect
			(at -2.050034 -13.17498 90)
			(size 0.519938 1.4986)
			(layers "F.Cu" "F.Mask" "F.Paste")
			(net "M_E_CPU0_SA_CB<5>")
		)
		(pad "61" smd rect
			(at -2.050034 -12.325096 90)
			(size 0.519938 1.4986)
			(layers "F.Cu" "F.Mask" "F.Paste")
			(net "GND")
		)
		(pad "62" smd rect
			(at -2.050034 -11.474958 90)
			(size 0.519938 1.4986)
			(layers "F.Cu" "F.Mask" "F.Paste")
			(net "M_E_CPU0_ALERT_N")
		)
		(pad "63" smd rect
			(at -2.050034 -10.625074 90)
			(size 0.519938 1.4986)
			(layers "F.Cu" "F.Mask" "F.Paste")
			(net "GND")
		)
		(pad "64" smd rect
			(at -2.050034 -9.774936 90)
			(size 0.519938 1.4986)
			(layers "F.Cu" "F.Mask" "F.Paste")
			(net "M_E_CPU0_SA_CS_N<0>")
		)
		(pad "65" smd rect
			(at -2.050034 -8.925052 90)
			(size 0.519938 1.4986)
			(layers "F.Cu" "F.Mask" "F.Paste")
			(net "GND")
		)
		(pad "66" smd rect
			(at -2.050034 -8.074914 90)
			(size 0.519938 1.4986)
			(layers "F.Cu" "F.Mask" "F.Paste")
			(net "M_E_CPU0_SA_CA<0>")
		)
		(pad "67" smd rect
			(at -2.050034 -7.22503 90)
			(size 0.519938 1.4986)
			(layers "F.Cu" "F.Mask" "F.Paste")
			(net "GND")
		)
		(pad "68" smd rect
			(at -2.050034 -6.374892 90)
			(size 0.519938 1.4986)
			(layers "F.Cu" "F.Mask" "F.Paste")
			(net "M_E_CPU0_SA_CA<2>")
		)
		(pad "69" smd rect
			(at -2.050034 -5.525008 90)
			(size 0.519938 1.4986)
			(layers "F.Cu" "F.Mask" "F.Paste")
			(net "GND")
		)
		(pad "70" smd rect
			(at -2.050034 -4.675124 90)
			(size 0.519938 1.4986)
			(layers "F.Cu" "F.Mask" "F.Paste")
			(net "M_E_CPU0_SA_CA<4>")
		)
		(pad "71" smd rect
			(at -2.050034 -3.824986 90)
			(size 0.519938 1.4986)
			(layers "F.Cu" "F.Mask" "F.Paste")
			(net "GND")
		)
		(pad "72" smd rect
			(at -2.050034 -2.975102 90)
			(size 0.519938 1.4986)
			(layers "F.Cu" "F.Mask" "F.Paste")
			(net "M_E_CPU0_SA_CA<6>")
		)
		(pad "73" smd rect
			(at -2.050034 -2.124964 90)
			(size 0.519938 1.4986)
			(layers "F.Cu" "F.Mask" "F.Paste")
			(net "GND")
		)
		(pad "74" smd rect
			(at -2.050034 -1.27508 90)
			(size 0.519938 1.4986)
			(layers "F.Cu" "F.Mask" "F.Paste")
			(net "M_E_CPU0_SA_PAR")
		)
		(pad "75" smd rect
			(at -2.050034 -0.424942 90)
			(size 0.519938 1.4986)
			(layers "F.Cu" "F.Mask" "F.Paste")
			(net "GND")
		)
		(pad "76" smd rect
			(at -2.050034 5.525008 90)
			(size 0.519938 1.4986)
			(layers "F.Cu" "F.Mask" "F.Paste")
			(net "M_E_CPU0_SB_CA<0>")
		)
		(pad "77" smd rect
			(at -2.050034 6.374892 90)
			(size 0.519938 1.4986)
			(layers "F.Cu" "F.Mask" "F.Paste")
			(net "GND")
		)
		(pad "78" smd rect
			(at -2.050034 7.22503 90)
			(size 0.519938 1.4986)
			(layers "F.Cu" "F.Mask" "F.Paste")
			(net "M_E_CPU0_SB_CA<2>")
		)
		(pad "79" smd rect
			(at -2.050034 8.074914 90)
			(size 0.519938 1.4986)
			(layers "F.Cu" "F.Mask" "F.Paste")
			(net "GND")
		)
		(pad "80" smd rect
			(at -2.050034 8.925052 90)
			(size 0.519938 1.4986)
			(layers "F.Cu" "F.Mask" "F.Paste")
			(net "M_E_CPU0_SB_CA<4>")
		)
		(pad "81" smd rect
			(at -2.050034 9.774936 90)
			(size 0.519938 1.4986)
			(layers "F.Cu" "F.Mask" "F.Paste")
			(net "GND")
		)
		(pad "82" smd rect
			(at -2.050034 10.625074 90)
			(size 0.519938 1.4986)
			(layers "F.Cu" "F.Mask" "F.Paste")
			(net "M_E_CPU0_SB_CA<6>")
		)
		(pad "83" smd rect
			(at -2.050034 11.474958 90)
			(size 0.519938 1.4986)
			(layers "F.Cu" "F.Mask" "F.Paste")
			(net "GND")
		)
		(pad "84" smd rect
			(at -2.050034 12.325096 90)
			(size 0.519938 1.4986)
			(layers "F.Cu" "F.Mask" "F.Paste")
			(net "M_E_CPU0_SB_CS_N<0>")
		)
		(pad "85" smd rect
			(at -2.050034 13.17498 90)
			(size 0.519938 1.4986)
			(layers "F.Cu" "F.Mask" "F.Paste")
			(net "GND")
		)
		(pad "86" smd rect
			(at -2.050034 14.025118 90)
			(size 0.519938 1.4986)
			(layers "F.Cu" "F.Mask" "F.Paste")
			(net "M_E_CPU0_SA_RSP<0>")
		)
		(pad "87" smd rect
			(at -2.050034 14.875002 90)
			(size 0.519938 1.4986)
			(layers "F.Cu" "F.Mask" "F.Paste")
			(net "M_E_CPU0_SB_RSP<0>")
		)
		(pad "88" smd rect
			(at -2.050034 15.724886 90)
			(size 0.519938 1.4986)
			(layers "F.Cu" "F.Mask" "F.Paste")
			(net "GND")
		)
		(pad "89" smd rect
			(at -2.050034 16.575024 90)
			(size 0.519938 1.4986)
			(layers "F.Cu" "F.Mask" "F.Paste")
			(net "M_E_CPU0_SB_CB<4>")
		)
		(pad "90" smd rect
			(at -2.050034 17.424908 90)
			(size 0.519938 1.4986)
			(layers "F.Cu" "F.Mask" "F.Paste")
			(net "GND")
		)
		(pad "91" smd rect
			(at -2.050034 18.275046 90)
			(size 0.519938 1.4986)
			(layers "F.Cu" "F.Mask" "F.Paste")
			(net "M_E_CPU0_SB_CB<5>")
		)
		(pad "92" smd rect
			(at -2.050034 19.12493 90)
			(size 0.519938 1.4986)
			(layers "F.Cu" "F.Mask" "F.Paste")
			(net "GND")
		)
		(pad "93" smd rect
			(at -2.050034 19.975068 90)
			(size 0.519938 1.4986)
			(layers "F.Cu" "F.Mask" "F.Paste")
			(net "M_E_CPU0_SB_DQS_DP<9>")
		)
		(pad "94" smd rect
			(at -2.050034 20.824952 90)
			(size 0.519938 1.4986)
			(layers "F.Cu" "F.Mask" "F.Paste")
			(net "M_E_CPU0_SB_DQS_DN<9>")
		)
		(pad "95" smd rect
			(at -2.050034 21.67509 90)
			(size 0.519938 1.4986)
			(layers "F.Cu" "F.Mask" "F.Paste")
			(net "GND")
		)
		(pad "96" smd rect
			(at -2.050034 22.524974 90)
			(size 0.519938 1.4986)
			(layers "F.Cu" "F.Mask" "F.Paste")
			(net "M_E_CPU0_SB_CB<0>")
		)
		(pad "97" smd rect
			(at -2.050034 23.375112 90)
			(size 0.519938 1.4986)
			(layers "F.Cu" "F.Mask" "F.Paste")
			(net "GND")
		)
		(pad "98" smd rect
			(at -2.050034 24.224996 90)
			(size 0.519938 1.4986)
			(layers "F.Cu" "F.Mask" "F.Paste")
			(net "M_E_CPU0_SB_CB<1>")
		)
		(pad "99" smd rect
			(at -2.050034 25.07488 90)
			(size 0.519938 1.4986)
			(layers "F.Cu" "F.Mask" "F.Paste")
			(net "GND")
		)
		(pad "100" smd rect
			(at -2.050034 25.925018 90)
			(size 0.519938 1.4986)
			(layers "F.Cu" "F.Mask" "F.Paste")
			(net "M_E_CPU0_SB_DQ<0>")
		)
		(pad "101" smd rect
			(at -2.050034 26.774902 90)
			(size 0.519938 1.4986)
			(layers "F.Cu" "F.Mask" "F.Paste")
			(net "GND")
		)
		(pad "102" smd rect
			(at -2.050034 27.62504 90)
			(size 0.519938 1.4986)
			(layers "F.Cu" "F.Mask" "F.Paste")
			(net "M_E_CPU0_SB_DQ<1>")
		)
		(pad "103" smd rect
			(at -2.050034 28.474924 90)
			(size 0.519938 1.4986)
			(layers "F.Cu" "F.Mask" "F.Paste")
			(net "GND")
		)
		(pad "104" smd rect
			(at -2.050034 29.325062 90)
			(size 0.519938 1.4986)
			(layers "F.Cu" "F.Mask" "F.Paste")
			(net "M_E_CPU0_SB_DQS_DP<0>")
		)
		(pad "105" smd rect
			(at -2.050034 30.174946 90)
			(size 0.519938 1.4986)
			(layers "F.Cu" "F.Mask" "F.Paste")
			(net "M_E_CPU0_SB_DQS_DN<0>")
		)
		(pad "106" smd rect
			(at -2.050034 31.025084 90)
			(size 0.519938 1.4986)
			(layers "F.Cu" "F.Mask" "F.Paste")
			(net "GND")
		)
		(pad "107" smd rect
			(at -2.050034 31.874968 90)
			(size 0.519938 1.4986)
			(layers "F.Cu" "F.Mask" "F.Paste")
			(net "M_E_CPU0_SB_DQ<4>")
		)
		(pad "108" smd rect
			(at -2.050034 32.725106 90)
			(size 0.519938 1.4986)
			(layers "F.Cu" "F.Mask" "F.Paste")
			(net "GND")
		)
		(pad "109" smd rect
			(at -2.050034 33.57499 90)
			(size 0.519938 1.4986)
			(layers "F.Cu" "F.Mask" "F.Paste")
			(net "M_E_CPU0_SB_DQ<5>")
		)
		(pad "110" smd rect
			(at -2.050034 34.425128 90)
			(size 0.519938 1.4986)
			(layers "F.Cu" "F.Mask" "F.Paste")
			(net "GND")
		)
		(pad "111" smd rect
			(at -2.050034 35.275012 90)
			(size 0.519938 1.4986)
			(layers "F.Cu" "F.Mask" "F.Paste")
			(net "M_E_CPU0_SB_DQ<8>")
		)
		(pad "112" smd rect
			(at -2.050034 36.124896 90)
			(size 0.519938 1.4986)
			(layers "F.Cu" "F.Mask" "F.Paste")
			(net "GND")
		)
		(pad "113" smd rect
			(at -2.050034 36.975034 90)
			(size 0.519938 1.4986)
			(layers "F.Cu" "F.Mask" "F.Paste")
			(net "M_E_CPU0_SB_DQ<9>")
		)
		(pad "114" smd rect
			(at -2.050034 37.824918 90)
			(size 0.519938 1.4986)
			(layers "F.Cu" "F.Mask" "F.Paste")
			(net "GND")
		)
		(pad "115" smd rect
			(at -2.050034 38.675056 90)
			(size 0.519938 1.4986)
			(layers "F.Cu" "F.Mask" "F.Paste")
			(net "M_E_CPU0_SB_DQS_DP<1>")
		)
		(pad "116" smd rect
			(at -2.050034 39.52494 90)
			(size 0.519938 1.4986)
			(layers "F.Cu" "F.Mask" "F.Paste")
			(net "M_E_CPU0_SB_DQS_DN<1>")
		)
		(pad "117" smd rect
			(at -2.050034 40.375078 90)
			(size 0.519938 1.4986)
			(layers "F.Cu" "F.Mask" "F.Paste")
			(net "GND")
		)
		(pad "118" smd rect
			(at -2.050034 41.224962 90)
			(size 0.519938 1.4986)
			(layers "F.Cu" "F.Mask" "F.Paste")
			(net "M_E_CPU0_SB_DQ<12>")
		)
		(pad "119" smd rect
			(at -2.050034 42.0751 90)
			(size 0.519938 1.4986)
			(layers "F.Cu" "F.Mask" "F.Paste")
			(net "GND")
		)
		(pad "120" smd rect
			(at -2.050034 42.924984 90)
			(size 0.519938 1.4986)
			(layers "F.Cu" "F.Mask" "F.Paste")
			(net "M_E_CPU0_SB_DQ<13>")
		)
		(pad "121" smd rect
			(at -2.050034 43.775122 90)
			(size 0.519938 1.4986)
			(layers "F.Cu" "F.Mask" "F.Paste")
			(net "GND")
		)
		(pad "122" smd rect
			(at -2.050034 44.625006 90)
			(size 0.519938 1.4986)
			(layers "F.Cu" "F.Mask" "F.Paste")
			(net "M_E_CPU0_SB_DQ<16>")
		)
		(pad "123" smd rect
			(at -2.050034 45.47489 90)
			(size 0.519938 1.4986)
			(layers "F.Cu" "F.Mask" "F.Paste")
			(net "GND")
		)
		(pad "124" smd rect
			(at -2.050034 46.325028 90)
			(size 0.519938 1.4986)
			(layers "F.Cu" "F.Mask" "F.Paste")
			(net "M_E_CPU0_SB_DQ<17>")
		)
		(pad "125" smd rect
			(at -2.050034 47.174912 90)
			(size 0.519938 1.4986)
			(layers "F.Cu" "F.Mask" "F.Paste")
			(net "GND")
		)
		(pad "126" smd rect
			(at -2.050034 48.02505 90)
			(size 0.519938 1.4986)
			(layers "F.Cu" "F.Mask" "F.Paste")
			(net "M_E_CPU0_SB_DQS_DP<2>")
		)
		(pad "127" smd rect
			(at -2.050034 48.874934 90)
			(size 0.519938 1.4986)
			(layers "F.Cu" "F.Mask" "F.Paste")
			(net "M_E_CPU0_SB_DQS_DN<2>")
		)
		(pad "128" smd rect
			(at -2.050034 49.725072 90)
			(size 0.519938 1.4986)
			(layers "F.Cu" "F.Mask" "F.Paste")
			(net "GND")
		)
		(pad "129" smd rect
			(at -2.050034 50.574956 90)
			(size 0.519938 1.4986)
			(layers "F.Cu" "F.Mask" "F.Paste")
			(net "M_E_CPU0_SB_DQ<20>")
		)
		(pad "130" smd rect
			(at -2.050034 51.425094 90)
			(size 0.519938 1.4986)
			(layers "F.Cu" "F.Mask" "F.Paste")
			(net "GND")
		)
		(pad "131" smd rect
			(at -2.050034 52.274978 90)
			(size 0.519938 1.4986)
			(layers "F.Cu" "F.Mask" "F.Paste")
			(net "M_E_CPU0_SB_DQ<21>")
		)
		(pad "132" smd rect
			(at -2.050034 53.125116 90)
			(size 0.519938 1.4986)
			(layers "F.Cu" "F.Mask" "F.Paste")
			(net "GND")
		)
		(pad "133" smd rect
			(at -2.050034 53.975 90)
			(size 0.519938 1.4986)
			(layers "F.Cu" "F.Mask" "F.Paste")
			(net "M_E_CPU0_SB_DQ<24>")
		)
		(pad "134" smd rect
			(at -2.050034 54.824884 90)
			(size 0.519938 1.4986)
			(layers "F.Cu" "F.Mask" "F.Paste")
			(net "GND")
		)
		(pad "135" smd rect
			(at -2.050034 55.675022 90)
			(size 0.519938 1.4986)
			(layers "F.Cu" "F.Mask" "F.Paste")
			(net "M_E_CPU0_SB_DQ<25>")
		)
		(pad "136" smd rect
			(at -2.050034 56.524906 90)
			(size 0.519938 1.4986)
			(layers "F.Cu" "F.Mask" "F.Paste")
			(net "GND")
		)
		(pad "137" smd rect
			(at -2.050034 57.375044 90)
			(size 0.519938 1.4986)
			(layers "F.Cu" "F.Mask" "F.Paste")
			(net "M_E_CPU0_SB_DQS_DP<3>")
		)
		(pad "138" smd rect
			(at -2.050034 58.224928 90)
			(size 0.519938 1.4986)
			(layers "F.Cu" "F.Mask" "F.Paste")
			(net "M_E_CPU0_SB_DQS_DN<3>")
		)
		(pad "139" smd rect
			(at -2.050034 59.075066 90)
			(size 0.519938 1.4986)
			(layers "F.Cu" "F.Mask" "F.Paste")
			(net "GND")
		)
		(pad "140" smd rect
			(at -2.050034 59.92495 90)
			(size 0.519938 1.4986)
			(layers "F.Cu" "F.Mask" "F.Paste")
			(net "M_E_CPU0_SB_DQ<28>")
		)
		(pad "141" smd rect
			(at -2.050034 60.775088 90)
			(size 0.519938 1.4986)
			(layers "F.Cu" "F.Mask" "F.Paste")
			(net "GND")
		)
		(pad "142" smd rect
			(at -2.050034 61.624972 90)
			(size 0.519938 1.4986)
			(layers "F.Cu" "F.Mask" "F.Paste")
			(net "M_E_CPU0_SB_DQ<29>")
		)
		(pad "143" smd rect
			(at -2.050034 62.47511 90)
			(size 0.519938 1.4986)
			(layers "F.Cu" "F.Mask" "F.Paste")
			(net "GND")
		)
		(pad "144" smd rect
			(at -2.050034 63.324994 90)
			(size 0.519938 1.4986)
			(layers "F.Cu" "F.Mask" "F.Paste")
			(net "Net_2306")
		)
		(pad "145" smd rect
			(at 2.050034 -63.324994 90)
			(size 0.519938 1.4986)
			(layers "F.Cu" "F.Mask" "F.Paste")
			(net "P12V_MEM_CPU0")
		)
		(pad "146" smd rect
			(at 2.050034 -62.47511 90)
			(size 0.519938 1.4986)
			(layers "F.Cu" "F.Mask" "F.Paste")
			(net "P12V_MEM_CPU0")
		)
		(pad "147" smd rect
			(at 2.050034 -61.624972 90)
			(size 0.519938 1.4986)
			(layers "F.Cu" "F.Mask" "F.Paste")
			(net "PWRGD_CHE_CPU0_DIMM")
		)
		(pad "148" smd rect
			(at 2.050034 -60.775088 90)
			(size 0.519938 1.4986)
			(layers "F.Cu" "F.Mask" "F.Paste")
			(net "PD_CHE_CPU0_DIMM_SAA")
		)
		(pad "149" smd rect
			(at 2.050034 -59.92495 90)
			(size 0.519938 1.4986)
			(layers "F.Cu" "F.Mask" "F.Paste")
			(net "Net_2307")
		)
		(pad "150" smd rect
			(at 2.050034 -59.075066 90)
			(size 0.519938 1.4986)
			(layers "F.Cu" "F.Mask" "F.Paste")
			(net "Net_2308")
		)
		(pad "151" smd rect
			(at 2.050034 -58.224928 90)
			(size 0.519938 1.4986)
			(layers "F.Cu" "F.Mask" "F.Paste")
			(net "GND")
		)
		(pad "152" smd rect
			(at 2.050034 -57.375044 90)
			(size 0.519938 1.4986)
			(layers "F.Cu" "F.Mask" "F.Paste")
			(net "M_E_CPU0_SA_DQ<2>")
		)
		(pad "153" smd rect
			(at 2.050034 -56.524906 90)
			(size 0.519938 1.4986)
			(layers "F.Cu" "F.Mask" "F.Paste")
			(net "GND")
		)
		(pad "154" smd rect
			(at 2.050034 -55.675022 90)
			(size 0.519938 1.4986)
			(layers "F.Cu" "F.Mask" "F.Paste")
			(net "M_E_CPU0_SA_DQ<3>")
		)
		(pad "155" smd rect
			(at 2.050034 -54.824884 90)
			(size 0.519938 1.4986)
			(layers "F.Cu" "F.Mask" "F.Paste")
			(net "GND")
		)
		(pad "156" smd rect
			(at 2.050034 -53.975 90)
			(size 0.519938 1.4986)
			(layers "F.Cu" "F.Mask" "F.Paste")
			(net "M_E_CPU0_SA_DQS_DN<5>")
		)
		(pad "157" smd rect
			(at 2.050034 -53.125116 90)
			(size 0.519938 1.4986)
			(layers "F.Cu" "F.Mask" "F.Paste")
			(net "M_E_CPU0_SA_DQS_DP<5>")
		)
		(pad "158" smd rect
			(at 2.050034 -52.274978 90)
			(size 0.519938 1.4986)
			(layers "F.Cu" "F.Mask" "F.Paste")
			(net "GND")
		)
		(pad "159" smd rect
			(at 2.050034 -51.425094 90)
			(size 0.519938 1.4986)
			(layers "F.Cu" "F.Mask" "F.Paste")
			(net "M_E_CPU0_SA_DQ<6>")
		)
		(pad "160" smd rect
			(at 2.050034 -50.574956 90)
			(size 0.519938 1.4986)
			(layers "F.Cu" "F.Mask" "F.Paste")
			(net "GND")
		)
		(pad "161" smd rect
			(at 2.050034 -49.725072 90)
			(size 0.519938 1.4986)
			(layers "F.Cu" "F.Mask" "F.Paste")
			(net "M_E_CPU0_SA_DQ<7>")
		)
		(pad "162" smd rect
			(at 2.050034 -48.874934 90)
			(size 0.519938 1.4986)
			(layers "F.Cu" "F.Mask" "F.Paste")
			(net "GND")
		)
		(pad "163" smd rect
			(at 2.050034 -48.02505 90)
			(size 0.519938 1.4986)
			(layers "F.Cu" "F.Mask" "F.Paste")
			(net "M_E_CPU0_SA_DQ<10>")
		)
		(pad "164" smd rect
			(at 2.050034 -47.174912 90)
			(size 0.519938 1.4986)
			(layers "F.Cu" "F.Mask" "F.Paste")
			(net "GND")
		)
		(pad "165" smd rect
			(at 2.050034 -46.325028 90)
			(size 0.519938 1.4986)
			(layers "F.Cu" "F.Mask" "F.Paste")
			(net "M_E_CPU0_SA_DQ<11>")
		)
		(pad "166" smd rect
			(at 2.050034 -45.47489 90)
			(size 0.519938 1.4986)
			(layers "F.Cu" "F.Mask" "F.Paste")
			(net "GND")
		)
		(pad "167" smd rect
			(at 2.050034 -44.625006 90)
			(size 0.519938 1.4986)
			(layers "F.Cu" "F.Mask" "F.Paste")
			(net "M_E_CPU0_SA_DQS_DN<6>")
		)
		(pad "168" smd rect
			(at 2.050034 -43.775122 90)
			(size 0.519938 1.4986)
			(layers "F.Cu" "F.Mask" "F.Paste")
			(net "M_E_CPU0_SA_DQS_DP<6>")
		)
		(pad "169" smd rect
			(at 2.050034 -42.924984 90)
			(size 0.519938 1.4986)
			(layers "F.Cu" "F.Mask" "F.Paste")
			(net "GND")
		)
		(pad "170" smd rect
			(at 2.050034 -42.0751 90)
			(size 0.519938 1.4986)
			(layers "F.Cu" "F.Mask" "F.Paste")
			(net "M_E_CPU0_SA_DQ<14>")
		)
		(pad "171" smd rect
			(at 2.050034 -41.224962 90)
			(size 0.519938 1.4986)
			(layers "F.Cu" "F.Mask" "F.Paste")
			(net "GND")
		)
		(pad "172" smd rect
			(at 2.050034 -40.375078 90)
			(size 0.519938 1.4986)
			(layers "F.Cu" "F.Mask" "F.Paste")
			(net "M_E_CPU0_SA_DQ<15>")
		)
		(pad "173" smd rect
			(at 2.050034 -39.52494 90)
			(size 0.519938 1.4986)
			(layers "F.Cu" "F.Mask" "F.Paste")
			(net "GND")
		)
		(pad "174" smd rect
			(at 2.050034 -38.675056 90)
			(size 0.519938 1.4986)
			(layers "F.Cu" "F.Mask" "F.Paste")
			(net "M_E_CPU0_SA_DQ<18>")
		)
		(pad "175" smd rect
			(at 2.050034 -37.824918 90)
			(size 0.519938 1.4986)
			(layers "F.Cu" "F.Mask" "F.Paste")
			(net "GND")
		)
		(pad "176" smd rect
			(at 2.050034 -36.975034 90)
			(size 0.519938 1.4986)
			(layers "F.Cu" "F.Mask" "F.Paste")
			(net "M_E_CPU0_SA_DQ<19>")
		)
		(pad "177" smd rect
			(at 2.050034 -36.124896 90)
			(size 0.519938 1.4986)
			(layers "F.Cu" "F.Mask" "F.Paste")
			(net "GND")
		)
		(pad "178" smd rect
			(at 2.050034 -35.275012 90)
			(size 0.519938 1.4986)
			(layers "F.Cu" "F.Mask" "F.Paste")
			(net "M_E_CPU0_SA_DQS_DN<7>")
		)
		(pad "179" smd rect
			(at 2.050034 -34.425128 90)
			(size 0.519938 1.4986)
			(layers "F.Cu" "F.Mask" "F.Paste")
			(net "M_E_CPU0_SA_DQS_DP<7>")
		)
		(pad "180" smd rect
			(at 2.050034 -33.57499 90)
			(size 0.519938 1.4986)
			(layers "F.Cu" "F.Mask" "F.Paste")
			(net "GND")
		)
		(pad "181" smd rect
			(at 2.050034 -32.725106 90)
			(size 0.519938 1.4986)
			(layers "F.Cu" "F.Mask" "F.Paste")
			(net "M_E_CPU0_SA_DQ<22>")
		)
		(pad "182" smd rect
			(at 2.050034 -31.874968 90)
			(size 0.519938 1.4986)
			(layers "F.Cu" "F.Mask" "F.Paste")
			(net "GND")
		)
		(pad "183" smd rect
			(at 2.050034 -31.025084 90)
			(size 0.519938 1.4986)
			(layers "F.Cu" "F.Mask" "F.Paste")
			(net "M_E_CPU0_SA_DQ<23>")
		)
		(pad "184" smd rect
			(at 2.050034 -30.174946 90)
			(size 0.519938 1.4986)
			(layers "F.Cu" "F.Mask" "F.Paste")
			(net "GND")
		)
		(pad "185" smd rect
			(at 2.050034 -29.325062 90)
			(size 0.519938 1.4986)
			(layers "F.Cu" "F.Mask" "F.Paste")
			(net "M_E_CPU0_SA_DQ<26>")
		)
		(pad "186" smd rect
			(at 2.050034 -28.474924 90)
			(size 0.519938 1.4986)
			(layers "F.Cu" "F.Mask" "F.Paste")
			(net "GND")
		)
		(pad "187" smd rect
			(at 2.050034 -27.62504 90)
			(size 0.519938 1.4986)
			(layers "F.Cu" "F.Mask" "F.Paste")
			(net "M_E_CPU0_SA_DQ<27>")
		)
		(pad "188" smd rect
			(at 2.050034 -26.774902 90)
			(size 0.519938 1.4986)
			(layers "F.Cu" "F.Mask" "F.Paste")
			(net "GND")
		)
		(pad "189" smd rect
			(at 2.050034 -25.925018 90)
			(size 0.519938 1.4986)
			(layers "F.Cu" "F.Mask" "F.Paste")
			(net "M_E_CPU0_SA_DQS_DN<8>")
		)
		(pad "190" smd rect
			(at 2.050034 -25.07488 90)
			(size 0.519938 1.4986)
			(layers "F.Cu" "F.Mask" "F.Paste")
			(net "M_E_CPU0_SA_DQS_DP<8>")
		)
		(pad "191" smd rect
			(at 2.050034 -24.224996 90)
			(size 0.519938 1.4986)
			(layers "F.Cu" "F.Mask" "F.Paste")
			(net "GND")
		)
		(pad "192" smd rect
			(at 2.050034 -23.375112 90)
			(size 0.519938 1.4986)
			(layers "F.Cu" "F.Mask" "F.Paste")
			(net "M_E_CPU0_SA_DQ<30>")
		)
		(pad "193" smd rect
			(at 2.050034 -22.524974 90)
			(size 0.519938 1.4986)
			(layers "F.Cu" "F.Mask" "F.Paste")
			(net "GND")
		)
		(pad "194" smd rect
			(at 2.050034 -21.67509 90)
			(size 0.519938 1.4986)
			(layers "F.Cu" "F.Mask" "F.Paste")
			(net "M_E_CPU0_SA_DQ<31>")
		)
		(pad "195" smd rect
			(at 2.050034 -20.824952 90)
			(size 0.519938 1.4986)
			(layers "F.Cu" "F.Mask" "F.Paste")
			(net "GND")
		)
		(pad "196" smd rect
			(at 2.050034 -19.975068 90)
			(size 0.519938 1.4986)
			(layers "F.Cu" "F.Mask" "F.Paste")
			(net "M_E_CPU0_SA_CB<2>")
		)
		(pad "197" smd rect
			(at 2.050034 -19.12493 90)
			(size 0.519938 1.4986)
			(layers "F.Cu" "F.Mask" "F.Paste")
			(net "GND")
		)
		(pad "198" smd rect
			(at 2.050034 -18.275046 90)
			(size 0.519938 1.4986)
			(layers "F.Cu" "F.Mask" "F.Paste")
			(net "M_E_CPU0_SA_CB<3>")
		)
		(pad "199" smd rect
			(at 2.050034 -17.424908 90)
			(size 0.519938 1.4986)
			(layers "F.Cu" "F.Mask" "F.Paste")
			(net "GND")
		)
		(pad "200" smd rect
			(at 2.050034 -16.575024 90)
			(size 0.519938 1.4986)
			(layers "F.Cu" "F.Mask" "F.Paste")
			(net "M_E_CPU0_SA_DQS_DN<9>")
		)
		(pad "201" smd rect
			(at 2.050034 -15.724886 90)
			(size 0.519938 1.4986)
			(layers "F.Cu" "F.Mask" "F.Paste")
			(net "M_E_CPU0_SA_DQS_DP<9>")
		)
		(pad "202" smd rect
			(at 2.050034 -14.875002 90)
			(size 0.519938 1.4986)
			(layers "F.Cu" "F.Mask" "F.Paste")
			(net "GND")
		)
		(pad "203" smd rect
			(at 2.050034 -14.025118 90)
			(size 0.519938 1.4986)
			(layers "F.Cu" "F.Mask" "F.Paste")
			(net "M_E_CPU0_SA_CB<6>")
		)
		(pad "204" smd rect
			(at 2.050034 -13.17498 90)
			(size 0.519938 1.4986)
			(layers "F.Cu" "F.Mask" "F.Paste")
			(net "GND")
		)
		(pad "205" smd rect
			(at 2.050034 -12.325096 90)
			(size 0.519938 1.4986)
			(layers "F.Cu" "F.Mask" "F.Paste")
			(net "M_E_CPU0_SA_CB<7>")
		)
		(pad "206" smd rect
			(at 2.050034 -11.474958 90)
			(size 0.519938 1.4986)
			(layers "F.Cu" "F.Mask" "F.Paste")
			(net "GND")
		)
		(pad "207" smd rect
			(at 2.050034 -10.625074 90)
			(size 0.519938 1.4986)
			(layers "F.Cu" "F.Mask" "F.Paste")
			(net "M_E_CPU0_RESET_N")
		)
		(pad "208" smd rect
			(at 2.050034 -9.774936 90)
			(size 0.519938 1.4986)
			(layers "F.Cu" "F.Mask" "F.Paste")
			(net "GND")
		)
		(pad "209" smd rect
			(at 2.050034 -8.925052 90)
			(size 0.519938 1.4986)
			(layers "F.Cu" "F.Mask" "F.Paste")
			(net "M_E_CPU0_SA_CS_N<1>")
		)
		(pad "210" smd rect
			(at 2.050034 -8.074914 90)
			(size 0.519938 1.4986)
			(layers "F.Cu" "F.Mask" "F.Paste")
			(net "GND")
		)
		(pad "211" smd rect
			(at 2.050034 -7.22503 90)
			(size 0.519938 1.4986)
			(layers "F.Cu" "F.Mask" "F.Paste")
			(net "M_E_CPU0_SA_CA<1>")
		)
		(pad "212" smd rect
			(at 2.050034 -6.374892 90)
			(size 0.519938 1.4986)
			(layers "F.Cu" "F.Mask" "F.Paste")
			(net "GND")
		)
		(pad "213" smd rect
			(at 2.050034 -5.525008 90)
			(size 0.519938 1.4986)
			(layers "F.Cu" "F.Mask" "F.Paste")
			(net "M_E_CPU0_SA_CA<3>")
		)
		(pad "214" smd rect
			(at 2.050034 -4.675124 90)
			(size 0.519938 1.4986)
			(layers "F.Cu" "F.Mask" "F.Paste")
			(net "GND")
		)
		(pad "215" smd rect
			(at 2.050034 -3.824986 90)
			(size 0.519938 1.4986)
			(layers "F.Cu" "F.Mask" "F.Paste")
			(net "M_E_CPU0_SA_CA<5>")
		)
		(pad "216" smd rect
			(at 2.050034 -2.975102 90)
			(size 0.519938 1.4986)
			(layers "F.Cu" "F.Mask" "F.Paste")
			(net "GND")
		)
		(pad "217" smd rect
			(at 2.050034 -2.124964 90)
			(size 0.519938 1.4986)
			(layers "F.Cu" "F.Mask" "F.Paste")
			(net "M_E_CPU0_CLK_DP<0>")
		)
		(pad "218" smd rect
			(at 2.050034 -1.27508 90)
			(size 0.519938 1.4986)
			(layers "F.Cu" "F.Mask" "F.Paste")
			(net "M_E_CPU0_CLK_DN<0>")
		)
		(pad "219" smd rect
			(at 2.050034 -0.424942 90)
			(size 0.519938 1.4986)
			(layers "F.Cu" "F.Mask" "F.Paste")
			(net "GND")
		)
		(pad "220" smd rect
			(at 2.050034 5.525008 90)
			(size 0.519938 1.4986)
			(layers "F.Cu" "F.Mask" "F.Paste")
			(net "Net_2309")
		)
		(pad "221" smd rect
			(at 2.050034 6.374892 90)
			(size 0.519938 1.4986)
			(layers "F.Cu" "F.Mask" "F.Paste")
			(net "M_E_CPU0_SB_CA<1>")
		)
		(pad "222" smd rect
			(at 2.050034 7.22503 90)
			(size 0.519938 1.4986)
			(layers "F.Cu" "F.Mask" "F.Paste")
			(net "GND")
		)
		(pad "223" smd rect
			(at 2.050034 8.074914 90)
			(size 0.519938 1.4986)
			(layers "F.Cu" "F.Mask" "F.Paste")
			(net "M_E_CPU0_SB_CA<3>")
		)
		(pad "224" smd rect
			(at 2.050034 8.925052 90)
			(size 0.519938 1.4986)
			(layers "F.Cu" "F.Mask" "F.Paste")
			(net "GND")
		)
		(pad "225" smd rect
			(at 2.050034 9.774936 90)
			(size 0.519938 1.4986)
			(layers "F.Cu" "F.Mask" "F.Paste")
			(net "M_E_CPU0_SB_CA<5>")
		)
		(pad "226" smd rect
			(at 2.050034 10.625074 90)
			(size 0.519938 1.4986)
			(layers "F.Cu" "F.Mask" "F.Paste")
			(net "GND")
		)
		(pad "227" smd rect
			(at 2.050034 11.474958 90)
			(size 0.519938 1.4986)
			(layers "F.Cu" "F.Mask" "F.Paste")
			(net "M_E_CPU0_SB_PAR")
		)
		(pad "228" smd rect
			(at 2.050034 12.325096 90)
			(size 0.519938 1.4986)
			(layers "F.Cu" "F.Mask" "F.Paste")
			(net "GND")
		)
		(pad "229" smd rect
			(at 2.050034 13.17498 90)
			(size 0.519938 1.4986)
			(layers "F.Cu" "F.Mask" "F.Paste")
			(net "M_E_CPU0_SB_CS_N<1>")
		)
		(pad "230" smd rect
			(at 2.050034 14.025118 90)
			(size 0.519938 1.4986)
			(layers "F.Cu" "F.Mask" "F.Paste")
			(net "GND")
		)
		(pad "231" smd rect
			(at 2.050034 14.875002 90)
			(size 0.519938 1.4986)
			(layers "F.Cu" "F.Mask" "F.Paste")
			(net "Net_2310")
		)
		(pad "232" smd rect
			(at 2.050034 15.724886 90)
			(size 0.519938 1.4986)
			(layers "F.Cu" "F.Mask" "F.Paste")
			(net "Net_2311")
		)
		(pad "233" smd rect
			(at 2.050034 16.575024 90)
			(size 0.519938 1.4986)
			(layers "F.Cu" "F.Mask" "F.Paste")
			(net "GND")
		)
		(pad "234" smd rect
			(at 2.050034 17.424908 90)
			(size 0.519938 1.4986)
			(layers "F.Cu" "F.Mask" "F.Paste")
			(net "M_E_CPU0_SB_CB<6>")
		)
		(pad "235" smd rect
			(at 2.050034 18.275046 90)
			(size 0.519938 1.4986)
			(layers "F.Cu" "F.Mask" "F.Paste")
			(net "GND")
		)
		(pad "236" smd rect
			(at 2.050034 19.12493 90)
			(size 0.519938 1.4986)
			(layers "F.Cu" "F.Mask" "F.Paste")
			(net "M_E_CPU0_SB_CB<7>")
		)
		(pad "237" smd rect
			(at 2.050034 19.975068 90)
			(size 0.519938 1.4986)
			(layers "F.Cu" "F.Mask" "F.Paste")
			(net "GND")
		)
		(pad "238" smd rect
			(at 2.050034 20.824952 90)
			(size 0.519938 1.4986)
			(layers "F.Cu" "F.Mask" "F.Paste")
			(net "M_E_CPU0_SB_DQS_DN<4>")
		)
		(pad "239" smd rect
			(at 2.050034 21.67509 90)
			(size 0.519938 1.4986)
			(layers "F.Cu" "F.Mask" "F.Paste")
			(net "M_E_CPU0_SB_DQS_DP<4>")
		)
		(pad "240" smd rect
			(at 2.050034 22.524974 90)
			(size 0.519938 1.4986)
			(layers "F.Cu" "F.Mask" "F.Paste")
			(net "GND")
		)
		(pad "241" smd rect
			(at 2.050034 23.375112 90)
			(size 0.519938 1.4986)
			(layers "F.Cu" "F.Mask" "F.Paste")
			(net "M_E_CPU0_SB_CB<2>")
		)
		(pad "242" smd rect
			(at 2.050034 24.224996 90)
			(size 0.519938 1.4986)
			(layers "F.Cu" "F.Mask" "F.Paste")
			(net "GND")
		)
		(pad "243" smd rect
			(at 2.050034 25.07488 90)
			(size 0.519938 1.4986)
			(layers "F.Cu" "F.Mask" "F.Paste")
			(net "M_E_CPU0_SB_CB<3>")
		)
		(pad "244" smd rect
			(at 2.050034 25.925018 90)
			(size 0.519938 1.4986)
			(layers "F.Cu" "F.Mask" "F.Paste")
			(net "GND")
		)
		(pad "245" smd rect
			(at 2.050034 26.774902 90)
			(size 0.519938 1.4986)
			(layers "F.Cu" "F.Mask" "F.Paste")
			(net "M_E_CPU0_SB_DQ<2>")
		)
		(pad "246" smd rect
			(at 2.050034 27.62504 90)
			(size 0.519938 1.4986)
			(layers "F.Cu" "F.Mask" "F.Paste")
			(net "GND")
		)
		(pad "247" smd rect
			(at 2.050034 28.474924 90)
			(size 0.519938 1.4986)
			(layers "F.Cu" "F.Mask" "F.Paste")
			(net "M_E_CPU0_SB_DQ<3>")
		)
		(pad "248" smd rect
			(at 2.050034 29.325062 90)
			(size 0.519938 1.4986)
			(layers "F.Cu" "F.Mask" "F.Paste")
			(net "GND")
		)
		(pad "249" smd rect
			(at 2.050034 30.174946 90)
			(size 0.519938 1.4986)
			(layers "F.Cu" "F.Mask" "F.Paste")
			(net "M_E_CPU0_SB_DQS_DN<5>")
		)
		(pad "250" smd rect
			(at 2.050034 31.025084 90)
			(size 0.519938 1.4986)
			(layers "F.Cu" "F.Mask" "F.Paste")
			(net "M_E_CPU0_SB_DQS_DP<5>")
		)
		(pad "251" smd rect
			(at 2.050034 31.874968 90)
			(size 0.519938 1.4986)
			(layers "F.Cu" "F.Mask" "F.Paste")
			(net "GND")
		)
		(pad "252" smd rect
			(at 2.050034 32.725106 90)
			(size 0.519938 1.4986)
			(layers "F.Cu" "F.Mask" "F.Paste")
			(net "M_E_CPU0_SB_DQ<6>")
		)
		(pad "253" smd rect
			(at 2.050034 33.57499 90)
			(size 0.519938 1.4986)
			(layers "F.Cu" "F.Mask" "F.Paste")
			(net "GND")
		)
		(pad "254" smd rect
			(at 2.050034 34.425128 90)
			(size 0.519938 1.4986)
			(layers "F.Cu" "F.Mask" "F.Paste")
			(net "M_E_CPU0_SB_DQ<7>")
		)
		(pad "255" smd rect
			(at 2.050034 35.275012 90)
			(size 0.519938 1.4986)
			(layers "F.Cu" "F.Mask" "F.Paste")
			(net "GND")
		)
		(pad "256" smd rect
			(at 2.050034 36.124896 90)
			(size 0.519938 1.4986)
			(layers "F.Cu" "F.Mask" "F.Paste")
			(net "M_E_CPU0_SB_DQ<10>")
		)
		(pad "257" smd rect
			(at 2.050034 36.975034 90)
			(size 0.519938 1.4986)
			(layers "F.Cu" "F.Mask" "F.Paste")
			(net "GND")
		)
		(pad "258" smd rect
			(at 2.050034 37.824918 90)
			(size 0.519938 1.4986)
			(layers "F.Cu" "F.Mask" "F.Paste")
			(net "M_E_CPU0_SB_DQ<11>")
		)
		(pad "259" smd rect
			(at 2.050034 38.675056 90)
			(size 0.519938 1.4986)
			(layers "F.Cu" "F.Mask" "F.Paste")
			(net "GND")
		)
		(pad "260" smd rect
			(at 2.050034 39.52494 90)
			(size 0.519938 1.4986)
			(layers "F.Cu" "F.Mask" "F.Paste")
			(net "M_E_CPU0_SB_DQS_DN<6>")
		)
		(pad "261" smd rect
			(at 2.050034 40.375078 90)
			(size 0.519938 1.4986)
			(layers "F.Cu" "F.Mask" "F.Paste")
			(net "M_E_CPU0_SB_DQS_DP<6>")
		)
		(pad "262" smd rect
			(at 2.050034 41.224962 90)
			(size 0.519938 1.4986)
			(layers "F.Cu" "F.Mask" "F.Paste")
			(net "GND")
		)
		(pad "263" smd rect
			(at 2.050034 42.0751 90)
			(size 0.519938 1.4986)
			(layers "F.Cu" "F.Mask" "F.Paste")
			(net "M_E_CPU0_SB_DQ<14>")
		)
		(pad "264" smd rect
			(at 2.050034 42.924984 90)
			(size 0.519938 1.4986)
			(layers "F.Cu" "F.Mask" "F.Paste")
			(net "GND")
		)
		(pad "265" smd rect
			(at 2.050034 43.775122 90)
			(size 0.519938 1.4986)
			(layers "F.Cu" "F.Mask" "F.Paste")
			(net "M_E_CPU0_SB_DQ<15>")
		)
		(pad "266" smd rect
			(at 2.050034 44.625006 90)
			(size 0.519938 1.4986)
			(layers "F.Cu" "F.Mask" "F.Paste")
			(net "GND")
		)
		(pad "267" smd rect
			(at 2.050034 45.47489 90)
			(size 0.519938 1.4986)
			(layers "F.Cu" "F.Mask" "F.Paste")
			(net "M_E_CPU0_SB_DQ<18>")
		)
		(pad "268" smd rect
			(at 2.050034 46.325028 90)
			(size 0.519938 1.4986)
			(layers "F.Cu" "F.Mask" "F.Paste")
			(net "GND")
		)
		(pad "269" smd rect
			(at 2.050034 47.174912 90)
			(size 0.519938 1.4986)
			(layers "F.Cu" "F.Mask" "F.Paste")
			(net "M_E_CPU0_SB_DQ<19>")
		)
		(pad "270" smd rect
			(at 2.050034 48.02505 90)
			(size 0.519938 1.4986)
			(layers "F.Cu" "F.Mask" "F.Paste")
			(net "GND")
		)
		(pad "271" smd rect
			(at 2.050034 48.874934 90)
			(size 0.519938 1.4986)
			(layers "F.Cu" "F.Mask" "F.Paste")
			(net "M_E_CPU0_SB_DQS_DN<7>")
		)
		(pad "272" smd rect
			(at 2.050034 49.725072 90)
			(size 0.519938 1.4986)
			(layers "F.Cu" "F.Mask" "F.Paste")
			(net "M_E_CPU0_SB_DQS_DP<7>")
		)
		(pad "273" smd rect
			(at 2.050034 50.574956 90)
			(size 0.519938 1.4986)
			(layers "F.Cu" "F.Mask" "F.Paste")
			(net "GND")
		)
		(pad "274" smd rect
			(at 2.050034 51.425094 90)
			(size 0.519938 1.4986)
			(layers "F.Cu" "F.Mask" "F.Paste")
			(net "M_E_CPU0_SB_DQ<22>")
		)
		(pad "275" smd rect
			(at 2.050034 52.274978 90)
			(size 0.519938 1.4986)
			(layers "F.Cu" "F.Mask" "F.Paste")
			(net "GND")
		)
		(pad "276" smd rect
			(at 2.050034 53.125116 90)
			(size 0.519938 1.4986)
			(layers "F.Cu" "F.Mask" "F.Paste")
			(net "M_E_CPU0_SB_DQ<23>")
		)
		(pad "277" smd rect
			(at 2.050034 53.975 90)
			(size 0.519938 1.4986)
			(layers "F.Cu" "F.Mask" "F.Paste")
			(net "GND")
		)
		(pad "278" smd rect
			(at 2.050034 54.824884 90)
			(size 0.519938 1.4986)
			(layers "F.Cu" "F.Mask" "F.Paste")
			(net "M_E_CPU0_SB_DQ<26>")
		)
		(pad "279" smd rect
			(at 2.050034 55.675022 90)
			(size 0.519938 1.4986)
			(layers "F.Cu" "F.Mask" "F.Paste")
			(net "GND")
		)
		(pad "280" smd rect
			(at 2.050034 56.524906 90)
			(size 0.519938 1.4986)
			(layers "F.Cu" "F.Mask" "F.Paste")
			(net "M_E_CPU0_SB_DQ<27>")
		)
		(pad "281" smd rect
			(at 2.050034 57.375044 90)
			(size 0.519938 1.4986)
			(layers "F.Cu" "F.Mask" "F.Paste")
			(net "GND")
		)
		(pad "282" smd rect
			(at 2.050034 58.224928 90)
			(size 0.519938 1.4986)
			(layers "F.Cu" "F.Mask" "F.Paste")
			(net "M_E_CPU0_SB_DQS_DN<8>")
		)
		(pad "283" smd rect
			(at 2.050034 59.075066 90)
			(size 0.519938 1.4986)
			(layers "F.Cu" "F.Mask" "F.Paste")
			(net "M_E_CPU0_SB_DQS_DP<8>")
		)
		(pad "284" smd rect
			(at 2.050034 59.92495 90)
			(size 0.519938 1.4986)
			(layers "F.Cu" "F.Mask" "F.Paste")
			(net "GND")
		)
		(pad "285" smd rect
			(at 2.050034 60.775088 90)
			(size 0.519938 1.4986)
			(layers "F.Cu" "F.Mask" "F.Paste")
			(net "M_E_CPU0_SB_DQ<30>")
		)
		(pad "286" smd rect
			(at 2.050034 61.624972 90)
			(size 0.519938 1.4986)
			(layers "F.Cu" "F.Mask" "F.Paste")
			(net "GND")
		)
		(pad "287" smd rect
			(at 2.050034 62.47511 90)
			(size 0.519938 1.4986)
			(layers "F.Cu" "F.Mask" "F.Paste")
			(net "M_E_CPU0_SB_DQ<31>")
		)
		(pad "288" smd rect
			(at 2.050034 63.324994 90)
			(size 0.519938 1.4986)
			(layers "F.Cu" "F.Mask" "F.Paste")
			(net "GND")
		)
		(pad "G1" thru_hole oval
			(at 0 -68.97497 90)
			(size 1.7272 3.4798)
			(drill oval 1.2192 2.4638)
			(layers "*.Cu" "*.Mask")
			(remove_unused_layers no)
			(net "GND")
			(clearance 0.127)
			(thermal_gap 0.127)
		)
		(pad "G2" thru_hole oval
			(at 0 3.875024 90)
			(size 1.7272 3.4798)
			(drill oval 1.2192 2.4638)
			(layers "*.Cu" "*.Mask")
			(remove_unused_layers no)
			(net "GND")
			(clearance 0.127)
			(thermal_gap 0.127)
		)
		(pad "G3" thru_hole oval
			(at 0 68.97497 90)
			(size 1.7272 3.4798)
			(drill oval 1.2192 2.4638)
			(layers "*.Cu" "*.Mask")
			(remove_unused_layers no)
			(net "GND")
			(clearance 0.127)
			(thermal_gap 0.127)
		)
	)
	(footprint ""
		(layer "F.Cu")
		(at 456.051666 -380.13767 -90)
		(property "Reference" "PC6573"
			(at 4.62534 2.026666 0)
			(unlocked yes)
			(layer "F.SilkS")
			(effects
				(font
					(size 0.7874 0.5842)
					(thickness 0.1524)
				)
				(justify left)
			)
		)
		(property "Value" ""
			(at 0 0 270)
			(layer "F.Fab")
			(effects
				(font
					(size 1.27 1.27)
				)
			)
		)
		(duplicate_pad_numbers_are_jumpers no)
		(fp_line
			(start -1.988058 2.750058)
			(end 2.750058 2.750058)
			(stroke
				(width 0.1524)
				(type default)
			)
			(layer "F.SilkS")
		)
		(fp_line
			(start 2.750058 2.750058)
			(end 2.750058 0.9398)
			(stroke
				(width 0.1524)
				(type default)
			)
			(layer "F.SilkS")
		)
		(fp_line
			(start -2.750058 1.988058)
			(end -1.988058 2.750058)
			(stroke
				(width 0.1524)
				(type default)
			)
			(layer "F.SilkS")
		)
		(fp_line
			(start -2.750058 0.9398)
			(end -2.750058 1.988058)
			(stroke
				(width 0.1524)
				(type default)
			)
			(layer "F.SilkS")
		)
		(fp_line
			(start 2.750058 -0.9398)
			(end 2.750058 -2.750058)
			(stroke
				(width 0.1524)
				(type default)
			)
			(layer "F.SilkS")
		)
		(fp_line
			(start -2.750058 -1.988058)
			(end -2.750058 -0.9398)
			(stroke
				(width 0.1524)
				(type default)
			)
			(layer "F.SilkS")
		)
		(fp_line
			(start -1.988058 -2.750058)
			(end -2.750058 -1.988058)
			(stroke
				(width 0.1524)
				(type default)
			)
			(layer "F.SilkS")
		)
		(fp_line
			(start 2.750058 -2.750058)
			(end -1.988058 -2.750058)
			(stroke
				(width 0.1524)
				(type default)
			)
			(layer "F.SilkS")
		)
		(fp_line
			(start -2.750058 2.750058)
			(end 2.750058 2.750058)
			(stroke
				(width 0.1)
				(type default)
			)
			(layer "F.Fab")
		)
		(fp_line
			(start 2.750058 2.750058)
			(end 2.750058 -2.750058)
			(stroke
				(width 0.1)
				(type default)
			)
			(layer "F.Fab")
		)
		(fp_line
			(start -2.750058 -2.750058)
			(end -2.750058 2.750058)
			(stroke
				(width 0.1)
				(type default)
			)
			(layer "F.Fab")
		)
		(fp_line
			(start 2.750058 -2.750058)
			(end -2.750058 -2.750058)
			(stroke
				(width 0.1)
				(type default)
			)
			(layer "F.Fab")
		)
		(pad "1" smd rect
			(at -2.199894 0)
			(size 1.6002 3.0226)
			(layers "F.Cu" "F.Mask" "F.Paste")
			(net "P0V9_CPU0_RT_2D")
		)
		(pad "2" smd rect
			(at 2.199894 0)
			(size 1.6002 3.0226)
			(layers "F.Cu" "F.Mask" "F.Paste")
			(net "GND")
		)
	)
	(footprint ""
		(layer "F.Cu")
		(at 271.328134 -421.23868 90)
		(property "Reference" "R3907"
			(at 0 0 90)
			(layer "F.SilkS")
			(hide yes)
			(effects
				(font
					(size 1.27 1.27)
				)
			)
		)
		(property "Value" ""
			(at 0 0 90)
			(layer "F.Fab")
			(effects
				(font
					(size 1.27 1.27)
				)
			)
		)
		(duplicate_pad_numbers_are_jumpers no)
		(fp_line
			(start 0.7874 -0.4064)
			(end 0.7874 0.4064)
			(stroke
				(width 0.1524)
				(type default)
			)
			(layer "F.SilkS")
		)
		(fp_line
			(start -0.7874 -0.4064)
			(end 0.7874 -0.4064)
			(stroke
				(width 0.1524)
				(type default)
			)
			(layer "F.SilkS")
		)
		(fp_line
			(start 0.7874 0.4064)
			(end -0.7874 0.4064)
			(stroke
				(width 0.1524)
				(type default)
			)
			(layer "F.SilkS")
		)
		(fp_line
			(start -0.7874 0.4064)
			(end -0.7874 -0.4064)
			(stroke
				(width 0.1524)
				(type default)
			)
			(layer "F.SilkS")
		)
		(fp_line
			(start -0.12065 -0.305054)
			(end -0.12065 -0.2794)
			(stroke
				(width 0.1)
				(type default)
			)
			(layer "F.Fab")
		)
		(fp_line
			(start -0.67945 -0.305054)
			(end -0.12065 -0.305054)
			(stroke
				(width 0.1)
				(type default)
			)
			(layer "F.Fab")
		)
		(fp_line
			(start 0.67945 -0.3048)
			(end 0.67945 0.3048)
			(stroke
				(width 0.1)
				(type default)
			)
			(layer "F.Fab")
		)
		(fp_line
			(start 0.12065 -0.3048)
			(end 0.67945 -0.3048)
			(stroke
				(width 0.1)
				(type default)
			)
			(layer "F.Fab")
		)
		(fp_line
			(start 0.12065 -0.2794)
			(end 0.12065 -0.3048)
			(stroke
				(width 0.1)
				(type default)
			)
			(layer "F.Fab")
		)
		(fp_line
			(start -0.12065 -0.2794)
			(end 0.12065 -0.2794)
			(stroke
				(width 0.1)
				(type default)
			)
			(layer "F.Fab")
		)
		(fp_line
			(start 0.120396 0.2794)
			(end -0.12065 0.2794)
			(stroke
				(width 0.1)
				(type default)
			)
			(layer "F.Fab")
		)
		(fp_line
			(start -0.12065 0.2794)
			(end -0.12065 0.3048)
			(stroke
				(width 0.1)
				(type default)
			)
			(layer "F.Fab")
		)
		(fp_line
			(start 0.67945 0.3048)
			(end 0.120396 0.3048)
			(stroke
				(width 0.1)
				(type default)
			)
			(layer "F.Fab")
		)
		(fp_line
			(start 0.120396 0.3048)
			(end 0.120396 0.2794)
			(stroke
				(width 0.1)
				(type default)
			)
			(layer "F.Fab")
		)
		(fp_line
			(start -0.12065 0.3048)
			(end -0.67945 0.3048)
			(stroke
				(width 0.1)
				(type default)
			)
			(layer "F.Fab")
		)
		(fp_line
			(start -0.67945 0.3048)
			(end -0.67945 -0.305054)
			(stroke
				(width 0.1)
				(type default)
			)
			(layer "F.Fab")
		)
		(pad "1" smd circle
			(at -0.40005 0 90)
			(size 0 0)
			(layers "F.Cu" "F.Mask" "F.Paste")
			(net "PDB_PRSNT_R_N")
		)
		(pad "2" smd circle
			(at 0.40005 0 90)
			(size 0 0)
			(layers "F.Cu" "F.Mask" "F.Paste")
			(net "GND")
		)
	)
	(footprint ""
		(layer "F.Cu")
		(at 327.951084 -349.43161 180)
		(property "Reference" "PC101"
			(at -0.199644 -2.938272 0)
			(unlocked yes)
			(layer "F.SilkS")
			(effects
				(font
					(size 0.7874 0.5842)
					(thickness 0.1524)
				)
				(justify left)
			)
		)
		(property "Value" ""
			(at 0 0 180)
			(layer "F.Fab")
			(effects
				(font
					(size 1.27 1.27)
				)
			)
		)
		(duplicate_pad_numbers_are_jumpers no)
		(fp_line
			(start -3.400044 1.249934)
			(end 3.400044 1.249934)
			(stroke
				(width 0.1524)
				(type default)
			)
			(layer "F.SilkS")
		)
		(fp_circle
			(center 0 1.249934)
			(end -3.400044 1.249934)
			(stroke
				(width 0.1524)
				(type default)
			)
			(fill no)
			(layer "F.SilkS")
		)
		(fp_poly
			(pts
				(arc
					(start 3.400044 1.249934)
					(mid 0 4.649978)
					(end -3.400044 1.249934)
				)
			)
			(stroke
				(width 0)
				(type default)
			)
			(fill yes)
			(layer "F.SilkS")
		)
		(fp_circle
			(center 0 1.249934)
			(end -3.400044 1.249934)
			(stroke
				(width 0.1)
				(type default)
			)
			(fill no)
			(layer "F.Fab")
		)
		(pad "1" thru_hole rect
			(at 0 0 180)
			(size 1.524 1.524)
			(drill 1.016)
			(layers "*.Cu" "*.Mask")
			(remove_unused_layers no)
			(net "SW_P12V_AUX_PVDDCR_CPU1_P0_FLT")
			(clearance 0)
			(padstack
				(mode front_inner_back)
				(layer "Inner"
					(shape circle)
					(size 1.524 1.524)
					(clearance 0)
				)
				(layer "B.Cu"
					(shape rect)
					(size 1.524 1.524)
					(clearance 0)
				)
			)
		)
		(pad "2" thru_hole circle
			(at 0 2.500122 180)
			(size 1.524 1.524)
			(drill 1.016)
			(layers "*.Cu" "*.Mask")
			(remove_unused_layers no)
			(net "GND")
			(clearance 0)
		)
	)
	(footprint ""
		(layer "F.Cu")
		(at 183.769 -100.294948 -90)
		(property "Reference" "R270"
			(at 0 0 270)
			(layer "F.SilkS")
			(hide yes)
			(effects
				(font
					(size 1.27 1.27)
				)
			)
		)
		(property "Value" ""
			(at 0 0 270)
			(layer "F.Fab")
			(effects
				(font
					(size 1.27 1.27)
				)
			)
		)
		(duplicate_pad_numbers_are_jumpers no)
		(fp_line
			(start -0.7874 0.4064)
			(end -0.7874 -0.4064)
			(stroke
				(width 0.1524)
				(type default)
			)
			(layer "F.SilkS")
		)
		(fp_line
			(start 0.7874 0.4064)
			(end -0.7874 0.4064)
			(stroke
				(width 0.1524)
				(type default)
			)
			(layer "F.SilkS")
		)
		(fp_line
			(start -0.7874 -0.4064)
			(end 0.7874 -0.4064)
			(stroke
				(width 0.1524)
				(type default)
			)
			(layer "F.SilkS")
		)
		(fp_line
			(start 0.7874 -0.4064)
			(end 0.7874 0.4064)
			(stroke
				(width 0.1524)
				(type default)
			)
			(layer "F.SilkS")
		)
		(fp_line
			(start -0.67945 0.3048)
			(end -0.67945 -0.305054)
			(stroke
				(width 0.1)
				(type default)
			)
			(layer "F.Fab")
		)
		(fp_line
			(start -0.12065 0.3048)
			(end -0.67945 0.3048)
			(stroke
				(width 0.1)
				(type default)
			)
			(layer "F.Fab")
		)
		(fp_line
			(start 0.120396 0.3048)
			(end 0.120396 0.2794)
			(stroke
				(width 0.1)
				(type default)
			)
			(layer "F.Fab")
		)
		(fp_line
			(start 0.67945 0.3048)
			(end 0.120396 0.3048)
			(stroke
				(width 0.1)
				(type default)
			)
			(layer "F.Fab")
		)
		(fp_line
			(start -0.12065 0.2794)
			(end -0.12065 0.3048)
			(stroke
				(width 0.1)
				(type default)
			)
			(layer "F.Fab")
		)
		(fp_line
			(start 0.120396 0.2794)
			(end -0.12065 0.2794)
			(stroke
				(width 0.1)
				(type default)
			)
			(layer "F.Fab")
		)
		(fp_line
			(start -0.12065 -0.2794)
			(end 0.12065 -0.2794)
			(stroke
				(width 0.1)
				(type default)
			)
			(layer "F.Fab")
		)
		(fp_line
			(start 0.12065 -0.2794)
			(end 0.12065 -0.3048)
			(stroke
				(width 0.1)
				(type default)
			)
			(layer "F.Fab")
		)
		(fp_line
			(start 0.12065 -0.3048)
			(end 0.67945 -0.3048)
			(stroke
				(width 0.1)
				(type default)
			)
			(layer "F.Fab")
		)
		(fp_line
			(start 0.67945 -0.3048)
			(end 0.67945 0.3048)
			(stroke
				(width 0.1)
				(type default)
			)
			(layer "F.Fab")
		)
		(fp_line
			(start -0.67945 -0.305054)
			(end -0.12065 -0.305054)
			(stroke
				(width 0.1)
				(type default)
			)
			(layer "F.Fab")
		)
		(fp_line
			(start -0.12065 -0.305054)
			(end -0.12065 -0.2794)
			(stroke
				(width 0.1)
				(type default)
			)
			(layer "F.Fab")
		)
		(pad "1" smd circle
			(at -0.40005 0 270)
			(size 0 0)
			(layers "F.Cu" "F.Mask" "F.Paste")
			(net "FM_CPU1_PROCHOT_R_N")
		)
		(pad "2" smd circle
			(at 0.40005 0 270)
			(size 0 0)
			(layers "F.Cu" "F.Mask" "F.Paste")
			(net "CPU1_PROCHOT_N")
		)
	)
	(footprint ""
		(layer "F.Cu")
		(at 299.29836 -119.67591 90)
		(property "Reference" "R3586"
			(at 0 0 90)
			(layer "F.SilkS")
			(hide yes)
			(effects
				(font
					(size 1.27 1.27)
				)
			)
		)
		(property "Value" ""
			(at 0 0 90)
			(layer "F.Fab")
			(effects
				(font
					(size 1.27 1.27)
				)
			)
		)
		(duplicate_pad_numbers_are_jumpers no)
		(fp_line
			(start 0.7874 -0.4064)
			(end 0.7874 0.4064)
			(stroke
				(width 0.1524)
				(type default)
			)
			(layer "F.SilkS")
		)
		(fp_line
			(start -0.7874 -0.4064)
			(end 0.7874 -0.4064)
			(stroke
				(width 0.1524)
				(type default)
			)
			(layer "F.SilkS")
		)
		(fp_line
			(start 0.7874 0.4064)
			(end -0.7874 0.4064)
			(stroke
				(width 0.1524)
				(type default)
			)
			(layer "F.SilkS")
		)
		(fp_line
			(start -0.7874 0.4064)
			(end -0.7874 -0.4064)
			(stroke
				(width 0.1524)
				(type default)
			)
			(layer "F.SilkS")
		)
		(fp_line
			(start -0.12065 -0.305054)
			(end -0.12065 -0.2794)
			(stroke
				(width 0.1)
				(type default)
			)
			(layer "F.Fab")
		)
		(fp_line
			(start -0.67945 -0.305054)
			(end -0.12065 -0.305054)
			(stroke
				(width 0.1)
				(type default)
			)
			(layer "F.Fab")
		)
		(fp_line
			(start 0.67945 -0.3048)
			(end 0.67945 0.3048)
			(stroke
				(width 0.1)
				(type default)
			)
			(layer "F.Fab")
		)
		(fp_line
			(start 0.12065 -0.3048)
			(end 0.67945 -0.3048)
			(stroke
				(width 0.1)
				(type default)
			)
			(layer "F.Fab")
		)
		(fp_line
			(start 0.12065 -0.2794)
			(end 0.12065 -0.3048)
			(stroke
				(width 0.1)
				(type default)
			)
			(layer "F.Fab")
		)
		(fp_line
			(start -0.12065 -0.2794)
			(end 0.12065 -0.2794)
			(stroke
				(width 0.1)
				(type default)
			)
			(layer "F.Fab")
		)
		(fp_line
			(start 0.120396 0.2794)
			(end -0.12065 0.2794)
			(stroke
				(width 0.1)
				(type default)
			)
			(layer "F.Fab")
		)
		(fp_line
			(start -0.12065 0.2794)
			(end -0.12065 0.3048)
			(stroke
				(width 0.1)
				(type default)
			)
			(layer "F.Fab")
		)
		(fp_line
			(start 0.67945 0.3048)
			(end 0.120396 0.3048)
			(stroke
				(width 0.1)
				(type default)
			)
			(layer "F.Fab")
		)
		(fp_line
			(start 0.120396 0.3048)
			(end 0.120396 0.2794)
			(stroke
				(width 0.1)
				(type default)
			)
			(layer "F.Fab")
		)
		(fp_line
			(start -0.12065 0.3048)
			(end -0.67945 0.3048)
			(stroke
				(width 0.1)
				(type default)
			)
			(layer "F.Fab")
		)
		(fp_line
			(start -0.67945 0.3048)
			(end -0.67945 -0.305054)
			(stroke
				(width 0.1)
				(type default)
			)
			(layer "F.Fab")
		)
		(pad "1" smd circle
			(at -0.40005 0 90)
			(size 0 0)
			(layers "F.Cu" "F.Mask" "F.Paste")
			(net "SMB_INA230_3V3AUX_SCL")
		)
		(pad "2" smd circle
			(at 0.40005 0 90)
			(size 0 0)
			(layers "F.Cu" "F.Mask" "F.Paste")
			(net "SMB_INA230_1_3V3AUX_SCL_R")
		)
	)
	(footprint ""
		(layer "F.Cu")
		(at 294.365426 -15.414244)
		(property "Reference" "U271"
			(at 3.60934 -2.106168 0)
			(unlocked yes)
			(layer "F.SilkS")
			(effects
				(font
					(size 0.7874 0.5842)
					(thickness 0.1524)
				)
				(justify left)
			)
		)
		(property "Value" ""
			(at 0 0 0)
			(layer "F.Fab")
			(effects
				(font
					(size 1.27 1.27)
				)
			)
		)
		(duplicate_pad_numbers_are_jumpers no)
		(fp_line
			(start -3.447796 -2.500122)
			(end -3.447796 2.500122)
			(stroke
				(width 0.1524)
				(type default)
			)
			(layer "F.SilkS")
		)
		(fp_line
			(start -3.447796 2.500122)
			(end 3.447796 2.500122)
			(stroke
				(width 0.1524)
				(type default)
			)
			(layer "F.SilkS")
		)
		(fp_line
			(start -1.484122 -2.500122)
			(end -3.447796 -2.500122)
			(stroke
				(width 0.1524)
				(type default)
			)
			(layer "F.SilkS")
		)
		(fp_line
			(start 0 -1.016)
			(end -1.484122 -2.500122)
			(stroke
				(width 0.1524)
				(type default)
			)
			(layer "F.SilkS")
		)
		(fp_line
			(start 1.484122 -2.500122)
			(end 0 -1.016)
			(stroke
				(width 0.1524)
				(type default)
			)
			(layer "F.SilkS")
		)
		(fp_line
			(start 3.447796 -2.500122)
			(end 1.484122 -2.500122)
			(stroke
				(width 0.1524)
				(type default)
			)
			(layer "F.SilkS")
		)
		(fp_line
			(start 3.447796 2.500122)
			(end 3.447796 -2.500122)
			(stroke
				(width 0.1524)
				(type default)
			)
			(layer "F.SilkS")
		)
		(fp_poly
			(pts
				(xy -4.5974 -1.397) (xy -4.5974 -2.413) (xy -3.5814 -1.905)
			)
			(stroke
				(width 0)
				(type default)
			)
			(fill yes)
			(layer "F.SilkS")
		)
		(fp_line
			(start -1.999996 -2.500122)
			(end -1.999996 2.500122)
			(stroke
				(width 0.1)
				(type default)
			)
			(layer "F.Fab")
		)
		(fp_line
			(start -1.999996 2.500122)
			(end 1.999996 2.500122)
			(stroke
				(width 0.1)
				(type default)
			)
			(layer "F.Fab")
		)
		(fp_line
			(start 1.999996 -2.500122)
			(end -1.999996 -2.500122)
			(stroke
				(width 0.1)
				(type default)
			)
			(layer "F.Fab")
		)
		(fp_line
			(start 1.999996 2.500122)
			(end 1.999996 -2.500122)
			(stroke
				(width 0.1)
				(type default)
			)
			(layer "F.Fab")
		)
		(fp_poly
			(pts
				(xy -4.5974 -2.413) (xy -4.5974 -1.397) (xy -3.5814 -1.905)
			)
			(stroke
				(width 0)
				(type default)
			)
			(fill yes)
			(layer "F.Fab")
		)
		(pad "1" smd rect
			(at -2.649982 -1.905 270)
			(size 0.6096 1.3208)
			(layers "F.Cu" "F.Mask" "F.Paste")
			(net "SMB_LM75_1_3V3AUX_SDA_R1")
		)
		(pad "2" smd rect
			(at -2.649982 -0.635 270)
			(size 0.6096 1.3208)
			(layers "F.Cu" "F.Mask" "F.Paste")
			(net "SMB_LM75_1_3V3AUX_SCL_R1")
		)
		(pad "3" smd rect
			(at -2.649982 0.635 270)
			(size 0.6096 1.3208)
			(layers "F.Cu" "F.Mask" "F.Paste")
			(net "FM_G751_1_ALERT_N")
		)
		(pad "4" smd rect
			(at -2.649982 1.905 270)
			(size 0.6096 1.3208)
			(layers "F.Cu" "F.Mask" "F.Paste")
			(net "GND")
		)
		(pad "5" smd rect
			(at 2.649982 1.905 270)
			(size 0.6096 1.3208)
			(layers "F.Cu" "F.Mask" "F.Paste")
			(net "U271_1_ADD2")
		)
		(pad "6" smd rect
			(at 2.649982 0.635 270)
			(size 0.6096 1.3208)
			(layers "F.Cu" "F.Mask" "F.Paste")
			(net "U271_1_ADD1")
		)
		(pad "7" smd rect
			(at 2.649982 -0.635 270)
			(size 0.6096 1.3208)
			(layers "F.Cu" "F.Mask" "F.Paste")
			(net "U271_1_ADD0")
		)
		(pad "8" smd rect
			(at 2.649982 -1.905 270)
			(size 0.6096 1.3208)
			(layers "F.Cu" "F.Mask" "F.Paste")
			(net "P3V3_AUX")
		)
	)
	(footprint ""
		(layer "F.Cu")
		(at 395.794738 -395.1732 90)
		(property "Reference" "R1100"
			(at 0 0 90)
			(layer "F.SilkS")
			(hide yes)
			(effects
				(font
					(size 1.27 1.27)
				)
			)
		)
		(property "Value" ""
			(at 0 0 90)
			(layer "F.Fab")
			(effects
				(font
					(size 1.27 1.27)
				)
			)
		)
		(duplicate_pad_numbers_are_jumpers no)
		(fp_line
			(start 0.32512 -0.175006)
			(end 0.32512 0.175006)
			(stroke
				(width 0.1)
				(type default)
			)
			(layer "F.Fab")
		)
		(fp_line
			(start -0.32512 -0.175006)
			(end 0.32512 -0.175006)
			(stroke
				(width 0.1)
				(type default)
			)
			(layer "F.Fab")
		)
		(fp_line
			(start 0.32512 0.175006)
			(end -0.32512 0.175006)
			(stroke
				(width 0.1)
				(type default)
			)
			(layer "F.Fab")
		)
		(fp_line
			(start -0.32512 0.175006)
			(end -0.32512 -0.175006)
			(stroke
				(width 0.1)
				(type default)
			)
			(layer "F.Fab")
		)
		(pad "1" smd rect
			(at -0.2667 0 90)
			(size 0.3048 0.381)
			(layers "F.Cu" "F.Mask" "F.Paste")
			(net "RT_CPU0_P3_ADDR2")
		)
		(pad "2" smd rect
			(at 0.2667 0 270)
			(size 0.3048 0.381)
			(layers "F.Cu" "F.Mask" "F.Paste")
			(net "GND")
		)
	)
	(footprint ""
		(layer "F.Cu")
		(at 391.291318 -74.375264 180)
		(property "Reference" "R1270"
			(at 0 0 180)
			(layer "F.SilkS")
			(hide yes)
			(effects
				(font
					(size 1.27 1.27)
				)
			)
		)
		(property "Value" ""
			(at 0 0 180)
			(layer "F.Fab")
			(effects
				(font
					(size 1.27 1.27)
				)
			)
		)
		(duplicate_pad_numbers_are_jumpers no)
		(fp_line
			(start 0.7874 0.4064)
			(end -0.7874 0.4064)
			(stroke
				(width 0.1524)
				(type default)
			)
			(layer "F.SilkS")
		)
		(fp_line
			(start 0.7874 -0.4064)
			(end 0.7874 0.4064)
			(stroke
				(width 0.1524)
				(type default)
			)
			(layer "F.SilkS")
		)
		(fp_line
			(start -0.7874 0.4064)
			(end -0.7874 -0.4064)
			(stroke
				(width 0.1524)
				(type default)
			)
			(layer "F.SilkS")
		)
		(fp_line
			(start -0.7874 -0.4064)
			(end 0.7874 -0.4064)
			(stroke
				(width 0.1524)
				(type default)
			)
			(layer "F.SilkS")
		)
		(fp_line
			(start 0.67945 0.3048)
			(end 0.120396 0.3048)
			(stroke
				(width 0.1)
				(type default)
			)
			(layer "F.Fab")
		)
		(fp_line
			(start 0.67945 -0.3048)
			(end 0.67945 0.3048)
			(stroke
				(width 0.1)
				(type default)
			)
			(layer "F.Fab")
		)
		(fp_line
			(start 0.12065 -0.2794)
			(end 0.12065 -0.3048)
			(stroke
				(width 0.1)
				(type default)
			)
			(layer "F.Fab")
		)
		(fp_line
			(start 0.12065 -0.3048)
			(end 0.67945 -0.3048)
			(stroke
				(width 0.1)
				(type default)
			)
			(layer "F.Fab")
		)
		(fp_line
			(start 0.120396 0.3048)
			(end 0.120396 0.2794)
			(stroke
				(width 0.1)
				(type default)
			)
			(layer "F.Fab")
		)
		(fp_line
			(start 0.120396 0.2794)
			(end -0.12065 0.2794)
			(stroke
				(width 0.1)
				(type default)
			)
			(layer "F.Fab")
		)
		(fp_line
			(start -0.12065 0.3048)
			(end -0.67945 0.3048)
			(stroke
				(width 0.1)
				(type default)
			)
			(layer "F.Fab")
		)
		(fp_line
			(start -0.12065 0.2794)
			(end -0.12065 0.3048)
			(stroke
				(width 0.1)
				(type default)
			)
			(layer "F.Fab")
		)
		(fp_line
			(start -0.12065 -0.2794)
			(end 0.12065 -0.2794)
			(stroke
				(width 0.1)
				(type default)
			)
			(layer "F.Fab")
		)
		(fp_line
			(start -0.12065 -0.305054)
			(end -0.12065 -0.2794)
			(stroke
				(width 0.1)
				(type default)
			)
			(layer "F.Fab")
		)
		(fp_line
			(start -0.67945 0.3048)
			(end -0.67945 -0.305054)
			(stroke
				(width 0.1)
				(type default)
			)
			(layer "F.Fab")
		)
		(fp_line
			(start -0.67945 -0.305054)
			(end -0.12065 -0.305054)
			(stroke
				(width 0.1)
				(type default)
			)
			(layer "F.Fab")
		)
		(pad "1" smd circle
			(at -0.40005 0 180)
			(size 0 0)
			(layers "F.Cu" "F.Mask" "F.Paste")
			(net "P12V_OCP_SFF_ADC_ALERT_R")
		)
		(pad "2" smd circle
			(at 0.40005 0 180)
			(size 0 0)
			(layers "F.Cu" "F.Mask" "F.Paste")
			(net "OCP_SFF_P3V3_P12V_ADC_R_ALERT")
		)
	)
	(footprint ""
		(layer "F.Cu")
		(at 522.584426 7.535926 -90)
		(property "Reference" "X8001"
			(at -1.918208 5.481574 0)
			(unlocked yes)
			(layer "F.SilkS")
			(effects
				(font
					(size 0.7874 0.5842)
					(thickness 0.1524)
				)
				(justify left)
			)
		)
		(property "Value" ""
			(at 0 0 270)
			(layer "F.Fab")
			(effects
				(font
					(size 1.27 1.27)
				)
			)
		)
		(property "Device Type" "TP_TDR_4P_FTS_TH-TP_TDR_4P_DIP,EMPTY,TP15"
			(at 1.30175 1.27 0)
			(unlocked yes)
			(layer "F.Fab")
			(hide yes)
			(effects
				(font
					(size 0.635 0.4064)
					(thickness 0.1524)
				)
			)
		)
		(property "User Part Number" "N_A"
			(at 1.30175 1.27 0)
			(unlocked yes)
			(layer "Cmts.User")
			(hide yes)
			(effects
				(font
					(size 0.635 0.4064)
					(thickness 0.1524)
				)
			)
		)
		(duplicate_pad_numbers_are_jumpers no)
		(fp_line
			(start 0 3.81)
			(end 2.54 3.81)
			(stroke
				(width 0.1524)
				(type default)
			)
			(layer "F.SilkS")
		)
		(fp_line
			(start 2.54 3.81)
			(end 2.54 3.6703)
			(stroke
				(width 0.1524)
				(type default)
			)
			(layer "F.SilkS")
		)
		(fp_line
			(start 0 3.175)
			(end 0 3.81)
			(stroke
				(width 0.1524)
				(type default)
			)
			(layer "F.SilkS")
		)
		(fp_line
			(start 2.54 1.4097)
			(end 2.54 1.1303)
			(stroke
				(width 0.1524)
				(type default)
			)
			(layer "F.SilkS")
		)
		(fp_line
			(start 0 0.635)
			(end 0 1.905)
			(stroke
				(width 0.1524)
				(type default)
			)
			(layer "F.SilkS")
		)
		(fp_line
			(start 2.54 -1.1303)
			(end 2.54 -1.27)
			(stroke
				(width 0.1524)
				(type default)
			)
			(layer "F.SilkS")
		)
		(fp_line
			(start 0 -1.27)
			(end 0 -0.635)
			(stroke
				(width 0.1524)
				(type default)
			)
			(layer "F.SilkS")
		)
		(fp_line
			(start 2.54 -1.27)
			(end 0 -1.27)
			(stroke
				(width 0.1524)
				(type default)
			)
			(layer "F.SilkS")
		)
		(fp_poly
			(pts
				(xy -2.285746 -0.762) (xy -0.761746 0) (xy -2.285746 0.762)
			)
			(stroke
				(width 0)
				(type default)
			)
			(fill yes)
			(layer "F.SilkS")
		)
		(fp_line
			(start 0 3.81)
			(end 2.54 3.81)
			(stroke
				(width 0.1)
				(type default)
			)
			(layer "F.Fab")
		)
		(fp_line
			(start 2.54 3.81)
			(end 2.54 -1.27)
			(stroke
				(width 0.1)
				(type default)
			)
			(layer "F.Fab")
		)
		(fp_line
			(start 0 -1.27)
			(end 0 3.81)
			(stroke
				(width 0.1)
				(type default)
			)
			(layer "F.Fab")
		)
		(fp_line
			(start 2.54 -1.27)
			(end 0 -1.27)
			(stroke
				(width 0.1)
				(type default)
			)
			(layer "F.Fab")
		)
		(fp_poly
			(pts
				(xy -0.761746 0) (xy -2.285746 -0.762) (xy -2.285746 0.762)
			)
			(stroke
				(width 0)
				(type default)
			)
			(fill yes)
			(layer "F.Fab")
		)
		(pad "1" thru_hole circle
			(at 0 0 270)
			(size 1.0033 1.0033)
			(drill 0.249936)
			(layers "*.Cu" "*.Mask")
			(remove_unused_layers no)
			(net "TDR_DIFF_85_TOP_DP")
			(clearance 0.10795)
			(thermal_gap 0.10795)
			(padstack
				(mode front_inner_back)
				(layer "Inner"
					(shape circle)
					(size 0.8001 0.8001)
					(clearance 0.1524)
				)
				(layer "B.Cu"
					(shape circle)
					(size 1.0033 1.0033)
					(clearance 0.10795)
				)
			)
		)
		(pad "2" thru_hole circle
			(at 2.54 0 270)
			(size 1.9939 1.9939)
			(drill 0.249936)
			(layers "*.Cu" "*.Mask")
			(remove_unused_layers no)
			(net "T1_GND")
			(clearance 0.10795)
			(thermal_gap 0.10795)
			(padstack
				(mode front_inner_back)
				(layer "Inner"
					(shape circle)
					(size 0.8001 0.8001)
					(clearance 0.1524)
				)
				(layer "B.Cu"
					(shape circle)
					(size 1.9939 1.9939)
					(clearance 0.10795)
				)
			)
		)
		(pad "3" thru_hole circle
			(at 2.54 2.54 270)
			(size 1.9939 1.9939)
			(drill 0.249936)
			(layers "*.Cu" "*.Mask")
			(remove_unused_layers no)
			(net "T1_GND")
			(clearance 0.10795)
			(thermal_gap 0.10795)
			(padstack
				(mode front_inner_back)
				(layer "Inner"
					(shape circle)
					(size 0.8001 0.8001)
					(clearance 0.1524)
				)
				(layer "B.Cu"
					(shape circle)
					(size 1.9939 1.9939)
					(clearance 0.10795)
				)
			)
		)
		(pad "4" thru_hole circle
			(at 0 2.54 270)
			(size 1.0033 1.0033)
			(drill 0.249936)
			(layers "*.Cu" "*.Mask")
			(remove_unused_layers no)
			(net "TDR_DIFF_85_TOP_DN")
			(clearance 0.10795)
			(thermal_gap 0.10795)
			(padstack
				(mode front_inner_back)
				(layer "Inner"
					(shape circle)
					(size 0.8001 0.8001)
					(clearance 0.1524)
				)
				(layer "B.Cu"
					(shape circle)
					(size 1.0033 1.0033)
					(clearance 0.10795)
				)
			)
		)
	)
	(footprint ""
		(layer "F.Cu")
		(at 75.705462 -39.675562)
		(property "Reference" "C2017"
			(at 0 0 0)
			(layer "F.SilkS")
			(hide yes)
			(effects
				(font
					(size 1.27 1.27)
				)
			)
		)
		(property "Value" ""
			(at 0 0 0)
			(layer "F.Fab")
			(effects
				(font
					(size 1.27 1.27)
				)
			)
		)
		(duplicate_pad_numbers_are_jumpers no)
		(fp_line
			(start -0.7874 -0.4064)
			(end 0.7874 -0.4064)
			(stroke
				(width 0.1524)
				(type default)
			)
			(layer "F.SilkS")
		)
		(fp_line
			(start -0.7874 0.4064)
			(end -0.7874 -0.4064)
			(stroke
				(width 0.1524)
				(type default)
			)
			(layer "F.SilkS")
		)
		(fp_line
			(start 0.7874 -0.4064)
			(end 0.7874 0.4064)
			(stroke
				(width 0.1524)
				(type default)
			)
			(layer "F.SilkS")
		)
		(fp_line
			(start 0.7874 0.4064)
			(end -0.7874 0.4064)
			(stroke
				(width 0.1524)
				(type default)
			)
			(layer "F.SilkS")
		)
		(fp_line
			(start -0.67945 -0.305054)
			(end -0.12065 -0.305054)
			(stroke
				(width 0.1)
				(type default)
			)
			(layer "F.Fab")
		)
		(fp_line
			(start -0.67945 0.3048)
			(end -0.67945 -0.305054)
			(stroke
				(width 0.1)
				(type default)
			)
			(layer "F.Fab")
		)
		(fp_line
			(start -0.12065 -0.305054)
			(end -0.12065 -0.2794)
			(stroke
				(width 0.1)
				(type default)
			)
			(layer "F.Fab")
		)
		(fp_line
			(start -0.12065 -0.2794)
			(end 0.12065 -0.2794)
			(stroke
				(width 0.1)
				(type default)
			)
			(layer "F.Fab")
		)
		(fp_line
			(start -0.12065 0.2794)
			(end -0.12065 0.3048)
			(stroke
				(width 0.1)
				(type default)
			)
			(layer "F.Fab")
		)
		(fp_line
			(start -0.12065 0.3048)
			(end -0.67945 0.3048)
			(stroke
				(width 0.1)
				(type default)
			)
			(layer "F.Fab")
		)
		(fp_line
			(start 0.120396 0.2794)
			(end -0.12065 0.2794)
			(stroke
				(width 0.1)
				(type default)
			)
			(layer "F.Fab")
		)
		(fp_line
			(start 0.120396 0.3048)
			(end 0.120396 0.2794)
			(stroke
				(width 0.1)
				(type default)
			)
			(layer "F.Fab")
		)
		(fp_line
			(start 0.12065 -0.3048)
			(end 0.67945 -0.3048)
			(stroke
				(width 0.1)
				(type default)
			)
			(layer "F.Fab")
		)
		(fp_line
			(start 0.12065 -0.2794)
			(end 0.12065 -0.3048)
			(stroke
				(width 0.1)
				(type default)
			)
			(layer "F.Fab")
		)
		(fp_line
			(start 0.67945 -0.3048)
			(end 0.67945 0.3048)
			(stroke
				(width 0.1)
				(type default)
			)
			(layer "F.Fab")
		)
		(fp_line
			(start 0.67945 0.3048)
			(end 0.120396 0.3048)
			(stroke
				(width 0.1)
				(type default)
			)
			(layer "F.Fab")
		)
		(pad "1" smd circle
			(at -0.40005 0)
			(size 0 0)
			(layers "F.Cu" "F.Mask" "F.Paste")
			(net "P3V3_OCP_V3_2_R")
		)
		(pad "2" smd circle
			(at 0.40005 0)
			(size 0 0)
			(layers "F.Cu" "F.Mask" "F.Paste")
			(net "GND")
		)
	)
	(footprint ""
		(layer "F.Cu")
		(at 86.487 -72.39)
		(property "Reference" "C1063"
			(at 0 0 0)
			(layer "F.SilkS")
			(hide yes)
			(effects
				(font
					(size 1.27 1.27)
				)
			)
		)
		(property "Value" ""
			(at 0 0 0)
			(layer "F.Fab")
			(effects
				(font
					(size 1.27 1.27)
				)
			)
		)
		(duplicate_pad_numbers_are_jumpers no)
		(fp_line
			(start -0.7874 -0.4064)
			(end 0.7874 -0.4064)
			(stroke
				(width 0.1524)
				(type default)
			)
			(layer "F.SilkS")
		)
		(fp_line
			(start -0.7874 0.4064)
			(end -0.7874 -0.4064)
			(stroke
				(width 0.1524)
				(type default)
			)
			(layer "F.SilkS")
		)
		(fp_line
			(start 0.7874 -0.4064)
			(end 0.7874 0.4064)
			(stroke
				(width 0.1524)
				(type default)
			)
			(layer "F.SilkS")
		)
		(fp_line
			(start 0.7874 0.4064)
			(end -0.7874 0.4064)
			(stroke
				(width 0.1524)
				(type default)
			)
			(layer "F.SilkS")
		)
		(fp_line
			(start -0.67945 -0.305054)
			(end -0.12065 -0.305054)
			(stroke
				(width 0.1)
				(type default)
			)
			(layer "F.Fab")
		)
		(fp_line
			(start -0.67945 0.3048)
			(end -0.67945 -0.305054)
			(stroke
				(width 0.1)
				(type default)
			)
			(layer "F.Fab")
		)
		(fp_line
			(start -0.12065 -0.305054)
			(end -0.12065 -0.2794)
			(stroke
				(width 0.1)
				(type default)
			)
			(layer "F.Fab")
		)
		(fp_line
			(start -0.12065 -0.2794)
			(end 0.12065 -0.2794)
			(stroke
				(width 0.1)
				(type default)
			)
			(layer "F.Fab")
		)
		(fp_line
			(start -0.12065 0.2794)
			(end -0.12065 0.3048)
			(stroke
				(width 0.1)
				(type default)
			)
			(layer "F.Fab")
		)
		(fp_line
			(start -0.12065 0.3048)
			(end -0.67945 0.3048)
			(stroke
				(width 0.1)
				(type default)
			)
			(layer "F.Fab")
		)
		(fp_line
			(start 0.120396 0.2794)
			(end -0.12065 0.2794)
			(stroke
				(width 0.1)
				(type default)
			)
			(layer "F.Fab")
		)
		(fp_line
			(start 0.120396 0.3048)
			(end 0.120396 0.2794)
			(stroke
				(width 0.1)
				(type default)
			)
			(layer "F.Fab")
		)
		(fp_line
			(start 0.12065 -0.3048)
			(end 0.67945 -0.3048)
			(stroke
				(width 0.1)
				(type default)
			)
			(layer "F.Fab")
		)
		(fp_line
			(start 0.12065 -0.2794)
			(end 0.12065 -0.3048)
			(stroke
				(width 0.1)
				(type default)
			)
			(layer "F.Fab")
		)
		(fp_line
			(start 0.67945 -0.3048)
			(end 0.67945 0.3048)
			(stroke
				(width 0.1)
				(type default)
			)
			(layer "F.Fab")
		)
		(fp_line
			(start 0.67945 0.3048)
			(end 0.120396 0.3048)
			(stroke
				(width 0.1)
				(type default)
			)
			(layer "F.Fab")
		)
		(pad "1" smd circle
			(at -0.40005 0)
			(size 0 0)
			(layers "F.Cu" "F.Mask" "F.Paste")
			(net "P3V3_AUX")
		)
		(pad "2" smd circle
			(at 0.40005 0)
			(size 0 0)
			(layers "F.Cu" "F.Mask" "F.Paste")
			(net "GND")
		)
	)
	(footprint ""
		(layer "F.Cu")
		(at 273.35734 -122.880628 180)
		(property "Reference" "R4269"
			(at 0 0 180)
			(layer "F.SilkS")
			(hide yes)
			(effects
				(font
					(size 1.27 1.27)
				)
			)
		)
		(property "Value" ""
			(at 0 0 180)
			(layer "F.Fab")
			(effects
				(font
					(size 1.27 1.27)
				)
			)
		)
		(duplicate_pad_numbers_are_jumpers no)
		(fp_line
			(start 0.7874 0.4064)
			(end -0.7874 0.4064)
			(stroke
				(width 0.1524)
				(type default)
			)
			(layer "F.SilkS")
		)
		(fp_line
			(start 0.7874 -0.4064)
			(end 0.7874 0.4064)
			(stroke
				(width 0.1524)
				(type default)
			)
			(layer "F.SilkS")
		)
		(fp_line
			(start -0.7874 0.4064)
			(end -0.7874 -0.4064)
			(stroke
				(width 0.1524)
				(type default)
			)
			(layer "F.SilkS")
		)
		(fp_line
			(start -0.7874 -0.4064)
			(end 0.7874 -0.4064)
			(stroke
				(width 0.1524)
				(type default)
			)
			(layer "F.SilkS")
		)
		(fp_line
			(start 0.67945 0.3048)
			(end 0.120396 0.3048)
			(stroke
				(width 0.1)
				(type default)
			)
			(layer "F.Fab")
		)
		(fp_line
			(start 0.67945 -0.3048)
			(end 0.67945 0.3048)
			(stroke
				(width 0.1)
				(type default)
			)
			(layer "F.Fab")
		)
		(fp_line
			(start 0.12065 -0.2794)
			(end 0.12065 -0.3048)
			(stroke
				(width 0.1)
				(type default)
			)
			(layer "F.Fab")
		)
		(fp_line
			(start 0.12065 -0.3048)
			(end 0.67945 -0.3048)
			(stroke
				(width 0.1)
				(type default)
			)
			(layer "F.Fab")
		)
		(fp_line
			(start 0.120396 0.3048)
			(end 0.120396 0.2794)
			(stroke
				(width 0.1)
				(type default)
			)
			(layer "F.Fab")
		)
		(fp_line
			(start 0.120396 0.2794)
			(end -0.12065 0.2794)
			(stroke
				(width 0.1)
				(type default)
			)
			(layer "F.Fab")
		)
		(fp_line
			(start -0.12065 0.3048)
			(end -0.67945 0.3048)
			(stroke
				(width 0.1)
				(type default)
			)
			(layer "F.Fab")
		)
		(fp_line
			(start -0.12065 0.2794)
			(end -0.12065 0.3048)
			(stroke
				(width 0.1)
				(type default)
			)
			(layer "F.Fab")
		)
		(fp_line
			(start -0.12065 -0.2794)
			(end 0.12065 -0.2794)
			(stroke
				(width 0.1)
				(type default)
			)
			(layer "F.Fab")
		)
		(fp_line
			(start -0.12065 -0.305054)
			(end -0.12065 -0.2794)
			(stroke
				(width 0.1)
				(type default)
			)
			(layer "F.Fab")
		)
		(fp_line
			(start -0.67945 0.3048)
			(end -0.67945 -0.305054)
			(stroke
				(width 0.1)
				(type default)
			)
			(layer "F.Fab")
		)
		(fp_line
			(start -0.67945 -0.305054)
			(end -0.12065 -0.305054)
			(stroke
				(width 0.1)
				(type default)
			)
			(layer "F.Fab")
		)
		(pad "1" smd circle
			(at -0.40005 0 180)
			(size 0 0)
			(layers "F.Cu" "F.Mask" "F.Paste")
			(net "P3V3_AUX")
		)
		(pad "2" smd circle
			(at 0.40005 0 180)
			(size 0 0)
			(layers "F.Cu" "F.Mask" "F.Paste")
			(net "SMB_VR_SENSOR_3V3AUX_SCL")
		)
	)
	(footprint ""
		(layer "F.Cu")
		(at 9.277096 -100.017834 90)
		(property "Reference" "C2029"
			(at 0 0 90)
			(layer "F.SilkS")
			(hide yes)
			(effects
				(font
					(size 1.27 1.27)
				)
			)
		)
		(property "Value" ""
			(at 0 0 90)
			(layer "F.Fab")
			(effects
				(font
					(size 1.27 1.27)
				)
			)
		)
		(duplicate_pad_numbers_are_jumpers no)
		(fp_line
			(start 0.7874 -0.4064)
			(end 0.7874 0.4064)
			(stroke
				(width 0.1524)
				(type default)
			)
			(layer "F.SilkS")
		)
		(fp_line
			(start -0.7874 -0.4064)
			(end 0.7874 -0.4064)
			(stroke
				(width 0.1524)
				(type default)
			)
			(layer "F.SilkS")
		)
		(fp_line
			(start 0.7874 0.4064)
			(end -0.7874 0.4064)
			(stroke
				(width 0.1524)
				(type default)
			)
			(layer "F.SilkS")
		)
		(fp_line
			(start -0.7874 0.4064)
			(end -0.7874 -0.4064)
			(stroke
				(width 0.1524)
				(type default)
			)
			(layer "F.SilkS")
		)
		(fp_line
			(start -0.12065 -0.305054)
			(end -0.12065 -0.2794)
			(stroke
				(width 0.1)
				(type default)
			)
			(layer "F.Fab")
		)
		(fp_line
			(start -0.67945 -0.305054)
			(end -0.12065 -0.305054)
			(stroke
				(width 0.1)
				(type default)
			)
			(layer "F.Fab")
		)
		(fp_line
			(start 0.67945 -0.3048)
			(end 0.67945 0.3048)
			(stroke
				(width 0.1)
				(type default)
			)
			(layer "F.Fab")
		)
		(fp_line
			(start 0.12065 -0.3048)
			(end 0.67945 -0.3048)
			(stroke
				(width 0.1)
				(type default)
			)
			(layer "F.Fab")
		)
		(fp_line
			(start 0.12065 -0.2794)
			(end 0.12065 -0.3048)
			(stroke
				(width 0.1)
				(type default)
			)
			(layer "F.Fab")
		)
		(fp_line
			(start -0.12065 -0.2794)
			(end 0.12065 -0.2794)
			(stroke
				(width 0.1)
				(type default)
			)
			(layer "F.Fab")
		)
		(fp_line
			(start 0.120396 0.2794)
			(end -0.12065 0.2794)
			(stroke
				(width 0.1)
				(type default)
			)
			(layer "F.Fab")
		)
		(fp_line
			(start -0.12065 0.2794)
			(end -0.12065 0.3048)
			(stroke
				(width 0.1)
				(type default)
			)
			(layer "F.Fab")
		)
		(fp_line
			(start 0.67945 0.3048)
			(end 0.120396 0.3048)
			(stroke
				(width 0.1)
				(type default)
			)
			(layer "F.Fab")
		)
		(fp_line
			(start 0.120396 0.3048)
			(end 0.120396 0.2794)
			(stroke
				(width 0.1)
				(type default)
			)
			(layer "F.Fab")
		)
		(fp_line
			(start -0.12065 0.3048)
			(end -0.67945 0.3048)
			(stroke
				(width 0.1)
				(type default)
			)
			(layer "F.Fab")
		)
		(fp_line
			(start -0.67945 0.3048)
			(end -0.67945 -0.305054)
			(stroke
				(width 0.1)
				(type default)
			)
			(layer "F.Fab")
		)
		(pad "1" smd circle
			(at -0.40005 0 90)
			(size 0 0)
			(layers "F.Cu" "F.Mask" "F.Paste")
			(net "USB_HUB_XTAL_IN")
		)
		(pad "2" smd circle
			(at 0.40005 0 90)
			(size 0 0)
			(layers "F.Cu" "F.Mask" "F.Paste")
			(net "GND")
		)
	)
	(footprint ""
		(layer "F.Cu")
		(at 294.560752 -422.173908 90)
		(property "Reference" "R668"
			(at 0 0 90)
			(layer "F.SilkS")
			(hide yes)
			(effects
				(font
					(size 1.27 1.27)
				)
			)
		)
		(property "Value" ""
			(at 0 0 90)
			(layer "F.Fab")
			(effects
				(font
					(size 1.27 1.27)
				)
			)
		)
		(duplicate_pad_numbers_are_jumpers no)
		(fp_line
			(start 0.32512 -0.175006)
			(end 0.32512 0.175006)
			(stroke
				(width 0.1)
				(type default)
			)
			(layer "F.Fab")
		)
		(fp_line
			(start -0.32512 -0.175006)
			(end 0.32512 -0.175006)
			(stroke
				(width 0.1)
				(type default)
			)
			(layer "F.Fab")
		)
		(fp_line
			(start 0.32512 0.175006)
			(end -0.32512 0.175006)
			(stroke
				(width 0.1)
				(type default)
			)
			(layer "F.Fab")
		)
		(fp_line
			(start -0.32512 0.175006)
			(end -0.32512 -0.175006)
			(stroke
				(width 0.1)
				(type default)
			)
			(layer "F.Fab")
		)
		(pad "1" smd rect
			(at -0.2667 0 90)
			(size 0.3048 0.381)
			(layers "F.Cu" "F.Mask" "F.Paste")
			(net "SMB_RT_CPU0_P0_ROM_R_SCL")
		)
		(pad "2" smd rect
			(at 0.2667 0 270)
			(size 0.3048 0.381)
			(layers "F.Cu" "F.Mask" "F.Paste")
			(net "SMB_RT_CPU0_P0_ROM_SCL")
		)
	)
	(footprint ""
		(layer "F.Cu")
		(at 44.691554 -370.57203 -90)
		(property "Reference" "C831"
			(at 0 0 270)
			(layer "F.SilkS")
			(hide yes)
			(effects
				(font
					(size 1.27 1.27)
				)
			)
		)
		(property "Value" ""
			(at 0 0 270)
			(layer "F.Fab")
			(effects
				(font
					(size 1.27 1.27)
				)
			)
		)
		(duplicate_pad_numbers_are_jumpers no)
		(fp_line
			(start -0.299974 0.150114)
			(end -0.299974 -0.150114)
			(stroke
				(width 0.1)
				(type default)
			)
			(layer "F.Fab")
		)
		(fp_line
			(start 0.299974 0.150114)
			(end -0.299974 0.150114)
			(stroke
				(width 0.1)
				(type default)
			)
			(layer "F.Fab")
		)
		(fp_line
			(start -0.299974 -0.150114)
			(end 0.299974 -0.150114)
			(stroke
				(width 0.1)
				(type default)
			)
			(layer "F.Fab")
		)
		(fp_line
			(start 0.299974 -0.150114)
			(end 0.299974 0.150114)
			(stroke
				(width 0.1)
				(type default)
			)
			(layer "F.Fab")
		)
		(pad "1" smd rect
			(at -0.2667 0 270)
			(size 0.3048 0.381)
			(layers "F.Cu" "F.Mask" "F.Paste")
			(net "P5E_CPU1_P0_TX_C_DP<3>")
		)
		(pad "2" smd rect
			(at 0.2667 0 270)
			(size 0.3048 0.381)
			(layers "F.Cu" "F.Mask" "F.Paste")
			(net "P5E_CPU1_P0_TX_DP<3>")
		)
	)
	(footprint ""
		(layer "F.Cu")
		(at 76.211176 -355.008434 90)
		(property "Reference" "PC393"
			(at -5.277104 -1.789176 0)
			(unlocked yes)
			(layer "F.SilkS")
			(effects
				(font
					(size 0.7874 0.5842)
					(thickness 0.1524)
				)
				(justify left)
			)
		)
		(property "Value" ""
			(at 0 0 90)
			(layer "F.Fab")
			(effects
				(font
					(size 1.27 1.27)
				)
			)
		)
		(duplicate_pad_numbers_are_jumpers no)
		(fp_line
			(start 3.400044 -3.400044)
			(end -2.146046 -3.400044)
			(stroke
				(width 0.1524)
				(type default)
			)
			(layer "F.SilkS")
		)
		(fp_line
			(start -2.146046 -3.400044)
			(end -3.400044 -2.146046)
			(stroke
				(width 0.1524)
				(type default)
			)
			(layer "F.SilkS")
		)
		(fp_line
			(start -3.400044 -2.146046)
			(end -3.400044 -0.9398)
			(stroke
				(width 0.1524)
				(type default)
			)
			(layer "F.SilkS")
		)
		(fp_line
			(start 3.400044 -0.9398)
			(end 3.400044 -3.400044)
			(stroke
				(width 0.1524)
				(type default)
			)
			(layer "F.SilkS")
		)
		(fp_line
			(start 3.400044 0.9398)
			(end 3.400044 3.400044)
			(stroke
				(width 0.1524)
				(type default)
			)
			(layer "F.SilkS")
		)
		(fp_line
			(start -3.400044 2.146046)
			(end -3.400044 0.9398)
			(stroke
				(width 0.1524)
				(type default)
			)
			(layer "F.SilkS")
		)
		(fp_line
			(start 3.400044 3.400044)
			(end -2.146046 3.400044)
			(stroke
				(width 0.1524)
				(type default)
			)
			(layer "F.SilkS")
		)
		(fp_line
			(start -2.146046 3.400044)
			(end -3.400044 2.146046)
			(stroke
				(width 0.1524)
				(type default)
			)
			(layer "F.SilkS")
		)
		(fp_line
			(start 3.400044 -3.400044)
			(end -3.400044 -3.400044)
			(stroke
				(width 0.1)
				(type default)
			)
			(layer "F.Fab")
		)
		(fp_line
			(start -3.400044 -3.400044)
			(end -3.400044 3.400044)
			(stroke
				(width 0.1)
				(type default)
			)
			(layer "F.Fab")
		)
		(fp_line
			(start 3.400044 3.400044)
			(end 3.400044 -3.400044)
			(stroke
				(width 0.1)
				(type default)
			)
			(layer "F.Fab")
		)
		(fp_line
			(start -3.400044 3.400044)
			(end 3.400044 3.400044)
			(stroke
				(width 0.1)
				(type default)
			)
			(layer "F.Fab")
		)
		(pad "1" smd rect
			(at -2.70002 0)
			(size 1.6002 3.5052)
			(layers "F.Cu" "F.Mask" "F.Paste")
			(net "SW_P12V_AUX_PVDDCR_CPU1_P1_FLT")
		)
		(pad "2" smd rect
			(at 2.70002 0)
			(size 1.6002 3.5052)
			(layers "F.Cu" "F.Mask" "F.Paste")
			(net "GND")
		)
	)
	(footprint ""
		(layer "F.Cu")
		(at 177.673 -100.294948 90)
		(property "Reference" "R236"
			(at 0 0 90)
			(layer "F.SilkS")
			(hide yes)
			(effects
				(font
					(size 1.27 1.27)
				)
			)
		)
		(property "Value" ""
			(at 0 0 90)
			(layer "F.Fab")
			(effects
				(font
					(size 1.27 1.27)
				)
			)
		)
		(duplicate_pad_numbers_are_jumpers no)
		(fp_line
			(start 0.7874 -0.4064)
			(end 0.7874 0.4064)
			(stroke
				(width 0.1524)
				(type default)
			)
			(layer "F.SilkS")
		)
		(fp_line
			(start -0.7874 -0.4064)
			(end 0.7874 -0.4064)
			(stroke
				(width 0.1524)
				(type default)
			)
			(layer "F.SilkS")
		)
		(fp_line
			(start 0.7874 0.4064)
			(end -0.7874 0.4064)
			(stroke
				(width 0.1524)
				(type default)
			)
			(layer "F.SilkS")
		)
		(fp_line
			(start -0.7874 0.4064)
			(end -0.7874 -0.4064)
			(stroke
				(width 0.1524)
				(type default)
			)
			(layer "F.SilkS")
		)
		(fp_line
			(start -0.12065 -0.305054)
			(end -0.12065 -0.2794)
			(stroke
				(width 0.1)
				(type default)
			)
			(layer "F.Fab")
		)
		(fp_line
			(start -0.67945 -0.305054)
			(end -0.12065 -0.305054)
			(stroke
				(width 0.1)
				(type default)
			)
			(layer "F.Fab")
		)
		(fp_line
			(start 0.67945 -0.3048)
			(end 0.67945 0.3048)
			(stroke
				(width 0.1)
				(type default)
			)
			(layer "F.Fab")
		)
		(fp_line
			(start 0.12065 -0.3048)
			(end 0.67945 -0.3048)
			(stroke
				(width 0.1)
				(type default)
			)
			(layer "F.Fab")
		)
		(fp_line
			(start 0.12065 -0.2794)
			(end 0.12065 -0.3048)
			(stroke
				(width 0.1)
				(type default)
			)
			(layer "F.Fab")
		)
		(fp_line
			(start -0.12065 -0.2794)
			(end 0.12065 -0.2794)
			(stroke
				(width 0.1)
				(type default)
			)
			(layer "F.Fab")
		)
		(fp_line
			(start 0.120396 0.2794)
			(end -0.12065 0.2794)
			(stroke
				(width 0.1)
				(type default)
			)
			(layer "F.Fab")
		)
		(fp_line
			(start -0.12065 0.2794)
			(end -0.12065 0.3048)
			(stroke
				(width 0.1)
				(type default)
			)
			(layer "F.Fab")
		)
		(fp_line
			(start 0.67945 0.3048)
			(end 0.120396 0.3048)
			(stroke
				(width 0.1)
				(type default)
			)
			(layer "F.Fab")
		)
		(fp_line
			(start 0.120396 0.3048)
			(end 0.120396 0.2794)
			(stroke
				(width 0.1)
				(type default)
			)
			(layer "F.Fab")
		)
		(fp_line
			(start -0.12065 0.3048)
			(end -0.67945 0.3048)
			(stroke
				(width 0.1)
				(type default)
			)
			(layer "F.Fab")
		)
		(fp_line
			(start -0.67945 0.3048)
			(end -0.67945 -0.305054)
			(stroke
				(width 0.1)
				(type default)
			)
			(layer "F.Fab")
		)
		(pad "1" smd circle
			(at -0.40005 0 90)
			(size 0 0)
			(layers "F.Cu" "F.Mask" "F.Paste")
			(net "CPU0_XTRIG_L4")
		)
		(pad "2" smd circle
			(at 0.40005 0 90)
			(size 0 0)
			(layers "F.Cu" "F.Mask" "F.Paste")
			(net "FM_CPU0_XTRIG_L4")
		)
	)
	(footprint ""
		(layer "F.Cu")
		(at 439.029602 -422.52011)
		(property "Reference" "PR6803"
			(at 0 0 0)
			(layer "F.SilkS")
			(hide yes)
			(effects
				(font
					(size 1.27 1.27)
				)
			)
		)
		(property "Value" ""
			(at 0 0 0)
			(layer "F.Fab")
			(effects
				(font
					(size 1.27 1.27)
				)
			)
		)
		(duplicate_pad_numbers_are_jumpers no)
		(fp_line
			(start -0.7874 -0.4064)
			(end 0.7874 -0.4064)
			(stroke
				(width 0.1524)
				(type default)
			)
			(layer "F.SilkS")
		)
		(fp_line
			(start -0.7874 0.4064)
			(end -0.7874 -0.4064)
			(stroke
				(width 0.1524)
				(type default)
			)
			(layer "F.SilkS")
		)
		(fp_line
			(start 0.7874 -0.4064)
			(end 0.7874 0.4064)
			(stroke
				(width 0.1524)
				(type default)
			)
			(layer "F.SilkS")
		)
		(fp_line
			(start 0.7874 0.4064)
			(end -0.7874 0.4064)
			(stroke
				(width 0.1524)
				(type default)
			)
			(layer "F.SilkS")
		)
		(fp_line
			(start -0.67945 -0.305054)
			(end -0.12065 -0.305054)
			(stroke
				(width 0.1)
				(type default)
			)
			(layer "F.Fab")
		)
		(fp_line
			(start -0.67945 0.3048)
			(end -0.67945 -0.305054)
			(stroke
				(width 0.1)
				(type default)
			)
			(layer "F.Fab")
		)
		(fp_line
			(start -0.12065 -0.305054)
			(end -0.12065 -0.2794)
			(stroke
				(width 0.1)
				(type default)
			)
			(layer "F.Fab")
		)
		(fp_line
			(start -0.12065 -0.2794)
			(end 0.12065 -0.2794)
			(stroke
				(width 0.1)
				(type default)
			)
			(layer "F.Fab")
		)
		(fp_line
			(start -0.12065 0.2794)
			(end -0.12065 0.3048)
			(stroke
				(width 0.1)
				(type default)
			)
			(layer "F.Fab")
		)
		(fp_line
			(start -0.12065 0.3048)
			(end -0.67945 0.3048)
			(stroke
				(width 0.1)
				(type default)
			)
			(layer "F.Fab")
		)
		(fp_line
			(start 0.120396 0.2794)
			(end -0.12065 0.2794)
			(stroke
				(width 0.1)
				(type default)
			)
			(layer "F.Fab")
		)
		(fp_line
			(start 0.120396 0.3048)
			(end 0.120396 0.2794)
			(stroke
				(width 0.1)
				(type default)
			)
			(layer "F.Fab")
		)
		(fp_line
			(start 0.12065 -0.3048)
			(end 0.67945 -0.3048)
			(stroke
				(width 0.1)
				(type default)
			)
			(layer "F.Fab")
		)
		(fp_line
			(start 0.12065 -0.2794)
			(end 0.12065 -0.3048)
			(stroke
				(width 0.1)
				(type default)
			)
			(layer "F.Fab")
		)
		(fp_line
			(start 0.67945 -0.3048)
			(end 0.67945 0.3048)
			(stroke
				(width 0.1)
				(type default)
			)
			(layer "F.Fab")
		)
		(fp_line
			(start 0.67945 0.3048)
			(end 0.120396 0.3048)
			(stroke
				(width 0.1)
				(type default)
			)
			(layer "F.Fab")
		)
		(pad "1" smd circle
			(at -0.40005 0)
			(size 0 0)
			(layers "F.Cu" "F.Mask" "F.Paste")
			(net "P3V3_AUX")
		)
		(pad "2" smd circle
			(at 0.40005 0)
			(size 0 0)
			(layers "F.Cu" "F.Mask" "F.Paste")
			(net "P0V9_RETIMER_CPU0_SVID_SDA")
		)
	)
	(footprint ""
		(layer "F.Cu")
		(at 18.650458 -418.690298 -90)
		(property "Reference" "R6176"
			(at 0 0 270)
			(layer "F.SilkS")
			(hide yes)
			(effects
				(font
					(size 1.27 1.27)
				)
			)
		)
		(property "Value" ""
			(at 0 0 270)
			(layer "F.Fab")
			(effects
				(font
					(size 1.27 1.27)
				)
			)
		)
		(duplicate_pad_numbers_are_jumpers no)
		(fp_line
			(start -0.7874 0.4064)
			(end -0.7874 -0.4064)
			(stroke
				(width 0.1524)
				(type default)
			)
			(layer "F.SilkS")
		)
		(fp_line
			(start 0.7874 0.4064)
			(end -0.7874 0.4064)
			(stroke
				(width 0.1524)
				(type default)
			)
			(layer "F.SilkS")
		)
		(fp_line
			(start -0.7874 -0.4064)
			(end 0.7874 -0.4064)
			(stroke
				(width 0.1524)
				(type default)
			)
			(layer "F.SilkS")
		)
		(fp_line
			(start 0.7874 -0.4064)
			(end 0.7874 0.4064)
			(stroke
				(width 0.1524)
				(type default)
			)
			(layer "F.SilkS")
		)
		(fp_line
			(start -0.67945 0.3048)
			(end -0.67945 -0.305054)
			(stroke
				(width 0.1)
				(type default)
			)
			(layer "F.Fab")
		)
		(fp_line
			(start -0.12065 0.3048)
			(end -0.67945 0.3048)
			(stroke
				(width 0.1)
				(type default)
			)
			(layer "F.Fab")
		)
		(fp_line
			(start 0.120396 0.3048)
			(end 0.120396 0.2794)
			(stroke
				(width 0.1)
				(type default)
			)
			(layer "F.Fab")
		)
		(fp_line
			(start 0.67945 0.3048)
			(end 0.120396 0.3048)
			(stroke
				(width 0.1)
				(type default)
			)
			(layer "F.Fab")
		)
		(fp_line
			(start -0.12065 0.2794)
			(end -0.12065 0.3048)
			(stroke
				(width 0.1)
				(type default)
			)
			(layer "F.Fab")
		)
		(fp_line
			(start 0.120396 0.2794)
			(end -0.12065 0.2794)
			(stroke
				(width 0.1)
				(type default)
			)
			(layer "F.Fab")
		)
		(fp_line
			(start -0.12065 -0.2794)
			(end 0.12065 -0.2794)
			(stroke
				(width 0.1)
				(type default)
			)
			(layer "F.Fab")
		)
		(fp_line
			(start 0.12065 -0.2794)
			(end 0.12065 -0.3048)
			(stroke
				(width 0.1)
				(type default)
			)
			(layer "F.Fab")
		)
		(fp_line
			(start 0.12065 -0.3048)
			(end 0.67945 -0.3048)
			(stroke
				(width 0.1)
				(type default)
			)
			(layer "F.Fab")
		)
		(fp_line
			(start 0.67945 -0.3048)
			(end 0.67945 0.3048)
			(stroke
				(width 0.1)
				(type default)
			)
			(layer "F.Fab")
		)
		(fp_line
			(start -0.67945 -0.305054)
			(end -0.12065 -0.305054)
			(stroke
				(width 0.1)
				(type default)
			)
			(layer "F.Fab")
		)
		(fp_line
			(start -0.12065 -0.305054)
			(end -0.12065 -0.2794)
			(stroke
				(width 0.1)
				(type default)
			)
			(layer "F.Fab")
		)
		(pad "1" smd circle
			(at -0.40005 0 270)
			(size 0 0)
			(layers "F.Cu" "F.Mask" "F.Paste")
			(net "FM_P2E_BUF2_RXDET")
		)
		(pad "2" smd circle
			(at 0.40005 0 270)
			(size 0 0)
			(layers "F.Cu" "F.Mask" "F.Paste")
			(net "GND")
		)
	)
	(footprint ""
		(layer "F.Cu")
		(at 399.352262 -416.899344 -90)
		(property "Reference" "C6583"
			(at 0 0 270)
			(layer "F.SilkS")
			(hide yes)
			(effects
				(font
					(size 1.27 1.27)
				)
			)
		)
		(property "Value" ""
			(at 0 0 270)
			(layer "F.Fab")
			(effects
				(font
					(size 1.27 1.27)
				)
			)
		)
		(duplicate_pad_numbers_are_jumpers no)
		(fp_line
			(start -0.299974 0.150114)
			(end -0.299974 -0.150114)
			(stroke
				(width 0.1)
				(type default)
			)
			(layer "F.Fab")
		)
		(fp_line
			(start 0.299974 0.150114)
			(end -0.299974 0.150114)
			(stroke
				(width 0.1)
				(type default)
			)
			(layer "F.Fab")
		)
		(fp_line
			(start -0.299974 -0.150114)
			(end 0.299974 -0.150114)
			(stroke
				(width 0.1)
				(type default)
			)
			(layer "F.Fab")
		)
		(fp_line
			(start 0.299974 -0.150114)
			(end 0.299974 0.150114)
			(stroke
				(width 0.1)
				(type default)
			)
			(layer "F.Fab")
		)
		(pad "1" smd rect
			(at -0.2667 0 270)
			(size 0.3048 0.381)
			(layers "F.Cu" "F.Mask" "F.Paste")
			(net "P5E_CPU0_P2_TX_BUF_C_DP<9>")
		)
		(pad "2" smd rect
			(at 0.2667 0 270)
			(size 0.3048 0.381)
			(layers "F.Cu" "F.Mask" "F.Paste")
			(net "P5E_CPU0_P2_TX_BUF_DP<9>")
		)
	)
	(footprint ""
		(layer "F.Cu")
		(at 493.36833 -298.352718 90)
		(property "Reference" "X10"
			(at -1.985264 1.132586 0)
			(unlocked yes)
			(layer "F.SilkS")
			(effects
				(font
					(size 0.7874 0.5842)
					(thickness 0.1524)
				)
				(justify left)
			)
		)
		(property "Value" ""
			(at 0 0 90)
			(layer "F.Fab")
			(effects
				(font
					(size 1.27 1.27)
				)
			)
		)
		(property "User Part Number" "N_A"
			(at 1.30175 1.27 180)
			(unlocked yes)
			(layer "Cmts.User")
			(hide yes)
			(effects
				(font
					(size 0.635 0.4064)
					(thickness 0.1524)
				)
			)
		)
		(property "Device Type" "TP_TDR_4P_FTS_TH-TP_TDR_4P_DIP,EMPTY,TP15"
			(at 1.30175 1.27 180)
			(unlocked yes)
			(layer "F.Fab")
			(hide yes)
			(effects
				(font
					(size 0.635 0.4064)
					(thickness 0.1524)
				)
			)
		)
		(duplicate_pad_numbers_are_jumpers no)
		(fp_line
			(start 2.54 -1.27)
			(end 0 -1.27)
			(stroke
				(width 0.1524)
				(type default)
			)
			(layer "F.SilkS")
		)
		(fp_line
			(start 0 -1.27)
			(end 0 -0.635)
			(stroke
				(width 0.1524)
				(type default)
			)
			(layer "F.SilkS")
		)
		(fp_line
			(start 2.54 -1.1303)
			(end 2.54 -1.27)
			(stroke
				(width 0.1524)
				(type default)
			)
			(layer "F.SilkS")
		)
		(fp_line
			(start 0 0.635)
			(end 0 1.905)
			(stroke
				(width 0.1524)
				(type default)
			)
			(layer "F.SilkS")
		)
		(fp_line
			(start 2.54 1.4097)
			(end 2.54 1.1303)
			(stroke
				(width 0.1524)
				(type default)
			)
			(layer "F.SilkS")
		)
		(fp_line
			(start 0 3.175)
			(end 0 3.81)
			(stroke
				(width 0.1524)
				(type default)
			)
			(layer "F.SilkS")
		)
		(fp_line
			(start 2.54 3.81)
			(end 2.54 3.6703)
			(stroke
				(width 0.1524)
				(type default)
			)
			(layer "F.SilkS")
		)
		(fp_line
			(start 0 3.81)
			(end 2.54 3.81)
			(stroke
				(width 0.1524)
				(type default)
			)
			(layer "F.SilkS")
		)
		(fp_poly
			(pts
				(xy -0.761746 0) (xy -2.285746 0.762) (xy -2.285746 -0.762)
			)
			(stroke
				(width 0)
				(type default)
			)
			(fill yes)
			(layer "F.SilkS")
		)
		(fp_line
			(start 2.54 -1.27)
			(end 0 -1.27)
			(stroke
				(width 0.1)
				(type default)
			)
			(layer "F.Fab")
		)
		(fp_line
			(start 0 -1.27)
			(end 0 3.81)
			(stroke
				(width 0.1)
				(type default)
			)
			(layer "F.Fab")
		)
		(fp_line
			(start 2.54 3.81)
			(end 2.54 -1.27)
			(stroke
				(width 0.1)
				(type default)
			)
			(layer "F.Fab")
		)
		(fp_line
			(start 0 3.81)
			(end 2.54 3.81)
			(stroke
				(width 0.1)
				(type default)
			)
			(layer "F.Fab")
		)
		(fp_poly
			(pts
				(xy -0.761746 0) (xy -2.285746 -0.762) (xy -2.285746 0.762)
			)
			(stroke
				(width 0)
				(type default)
			)
			(fill yes)
			(layer "F.Fab")
		)
		(pad "1" thru_hole circle
			(at 0 0 90)
			(size 1.0033 1.0033)
			(drill 0.249936)
			(layers "*.Cu" "*.Mask")
			(remove_unused_layers no)
			(net "TDR_DIFF_80_IN3_DN")
			(clearance 0.10795)
			(thermal_gap 0.10795)
			(padstack
				(mode front_inner_back)
				(layer "Inner"
					(shape circle)
					(size 0.8001 0.8001)
					(clearance 0.1524)
				)
				(layer "B.Cu"
					(shape circle)
					(size 1.0033 1.0033)
					(clearance 0.10795)
				)
			)
		)
		(pad "2" thru_hole circle
			(at 2.54 0 90)
			(size 1.9939 1.9939)
			(drill 0.249936)
			(layers "*.Cu" "*.Mask")
			(remove_unused_layers no)
			(net "T1_GND")
			(clearance 0.10795)
			(thermal_gap 0.10795)
			(padstack
				(mode front_inner_back)
				(layer "Inner"
					(shape circle)
					(size 0.8001 0.8001)
					(clearance 0.1524)
				)
				(layer "B.Cu"
					(shape circle)
					(size 1.9939 1.9939)
					(clearance 0.10795)
				)
			)
		)
		(pad "3" thru_hole circle
			(at 2.54 2.54 90)
			(size 1.9939 1.9939)
			(drill 0.249936)
			(layers "*.Cu" "*.Mask")
			(remove_unused_layers no)
			(net "T1_GND")
			(clearance 0.10795)
			(thermal_gap 0.10795)
			(padstack
				(mode front_inner_back)
				(layer "Inner"
					(shape circle)
					(size 0.8001 0.8001)
					(clearance 0.1524)
				)
				(layer "B.Cu"
					(shape circle)
					(size 1.9939 1.9939)
					(clearance 0.10795)
				)
			)
		)
		(pad "4" thru_hole circle
			(at 0 2.54 90)
			(size 1.0033 1.0033)
			(drill 0.249936)
			(layers "*.Cu" "*.Mask")
			(remove_unused_layers no)
			(net "TDR_DIFF_80_IN3_DP")
			(clearance 0.10795)
			(thermal_gap 0.10795)
			(padstack
				(mode front_inner_back)
				(layer "Inner"
					(shape circle)
					(size 0.8001 0.8001)
					(clearance 0.1524)
				)
				(layer "B.Cu"
					(shape circle)
					(size 1.0033 1.0033)
					(clearance 0.10795)
				)
			)
		)
	)
	(footprint ""
		(layer "F.Cu")
		(at 328.092308 -102.52075)
		(property "Reference" "C1096"
			(at 0 0 0)
			(layer "F.SilkS")
			(hide yes)
			(effects
				(font
					(size 1.27 1.27)
				)
			)
		)
		(property "Value" ""
			(at 0 0 0)
			(layer "F.Fab")
			(effects
				(font
					(size 1.27 1.27)
				)
			)
		)
		(duplicate_pad_numbers_are_jumpers no)
		(fp_line
			(start -0.7874 -0.4064)
			(end 0.7874 -0.4064)
			(stroke
				(width 0.1524)
				(type default)
			)
			(layer "F.SilkS")
		)
		(fp_line
			(start -0.7874 0.4064)
			(end -0.7874 -0.4064)
			(stroke
				(width 0.1524)
				(type default)
			)
			(layer "F.SilkS")
		)
		(fp_line
			(start 0.7874 -0.4064)
			(end 0.7874 0.4064)
			(stroke
				(width 0.1524)
				(type default)
			)
			(layer "F.SilkS")
		)
		(fp_line
			(start 0.7874 0.4064)
			(end -0.7874 0.4064)
			(stroke
				(width 0.1524)
				(type default)
			)
			(layer "F.SilkS")
		)
		(fp_line
			(start -0.67945 -0.305054)
			(end -0.12065 -0.305054)
			(stroke
				(width 0.1)
				(type default)
			)
			(layer "F.Fab")
		)
		(fp_line
			(start -0.67945 0.3048)
			(end -0.67945 -0.305054)
			(stroke
				(width 0.1)
				(type default)
			)
			(layer "F.Fab")
		)
		(fp_line
			(start -0.12065 -0.305054)
			(end -0.12065 -0.2794)
			(stroke
				(width 0.1)
				(type default)
			)
			(layer "F.Fab")
		)
		(fp_line
			(start -0.12065 -0.2794)
			(end 0.12065 -0.2794)
			(stroke
				(width 0.1)
				(type default)
			)
			(layer "F.Fab")
		)
		(fp_line
			(start -0.12065 0.2794)
			(end -0.12065 0.3048)
			(stroke
				(width 0.1)
				(type default)
			)
			(layer "F.Fab")
		)
		(fp_line
			(start -0.12065 0.3048)
			(end -0.67945 0.3048)
			(stroke
				(width 0.1)
				(type default)
			)
			(layer "F.Fab")
		)
		(fp_line
			(start 0.120396 0.2794)
			(end -0.12065 0.2794)
			(stroke
				(width 0.1)
				(type default)
			)
			(layer "F.Fab")
		)
		(fp_line
			(start 0.120396 0.3048)
			(end 0.120396 0.2794)
			(stroke
				(width 0.1)
				(type default)
			)
			(layer "F.Fab")
		)
		(fp_line
			(start 0.12065 -0.3048)
			(end 0.67945 -0.3048)
			(stroke
				(width 0.1)
				(type default)
			)
			(layer "F.Fab")
		)
		(fp_line
			(start 0.12065 -0.2794)
			(end 0.12065 -0.3048)
			(stroke
				(width 0.1)
				(type default)
			)
			(layer "F.Fab")
		)
		(fp_line
			(start 0.67945 -0.3048)
			(end 0.67945 0.3048)
			(stroke
				(width 0.1)
				(type default)
			)
			(layer "F.Fab")
		)
		(fp_line
			(start 0.67945 0.3048)
			(end 0.120396 0.3048)
			(stroke
				(width 0.1)
				(type default)
			)
			(layer "F.Fab")
		)
		(pad "1" smd circle
			(at -0.40005 0)
			(size 0 0)
			(layers "F.Cu" "F.Mask" "F.Paste")
			(net "P3V3_AUX")
		)
		(pad "2" smd circle
			(at 0.40005 0)
			(size 0 0)
			(layers "F.Cu" "F.Mask" "F.Paste")
			(net "GND")
		)
	)
	(footprint ""
		(layer "F.Cu")
		(at 218.567 -100.457)
		(property "Reference" "C9008"
			(at 0 0 0)
			(layer "F.SilkS")
			(hide yes)
			(effects
				(font
					(size 1.27 1.27)
				)
			)
		)
		(property "Value" ""
			(at 0 0 0)
			(layer "F.Fab")
			(effects
				(font
					(size 1.27 1.27)
				)
			)
		)
		(duplicate_pad_numbers_are_jumpers no)
		(fp_line
			(start -0.7874 -0.4064)
			(end 0.7874 -0.4064)
			(stroke
				(width 0.1524)
				(type default)
			)
			(layer "F.SilkS")
		)
		(fp_line
			(start -0.7874 0.4064)
			(end -0.7874 -0.4064)
			(stroke
				(width 0.1524)
				(type default)
			)
			(layer "F.SilkS")
		)
		(fp_line
			(start 0.7874 -0.4064)
			(end 0.7874 0.4064)
			(stroke
				(width 0.1524)
				(type default)
			)
			(layer "F.SilkS")
		)
		(fp_line
			(start 0.7874 0.4064)
			(end -0.7874 0.4064)
			(stroke
				(width 0.1524)
				(type default)
			)
			(layer "F.SilkS")
		)
		(fp_line
			(start -0.67945 -0.305054)
			(end -0.12065 -0.305054)
			(stroke
				(width 0.1)
				(type default)
			)
			(layer "F.Fab")
		)
		(fp_line
			(start -0.67945 0.3048)
			(end -0.67945 -0.305054)
			(stroke
				(width 0.1)
				(type default)
			)
			(layer "F.Fab")
		)
		(fp_line
			(start -0.12065 -0.305054)
			(end -0.12065 -0.2794)
			(stroke
				(width 0.1)
				(type default)
			)
			(layer "F.Fab")
		)
		(fp_line
			(start -0.12065 -0.2794)
			(end 0.12065 -0.2794)
			(stroke
				(width 0.1)
				(type default)
			)
			(layer "F.Fab")
		)
		(fp_line
			(start -0.12065 0.2794)
			(end -0.12065 0.3048)
			(stroke
				(width 0.1)
				(type default)
			)
			(layer "F.Fab")
		)
		(fp_line
			(start -0.12065 0.3048)
			(end -0.67945 0.3048)
			(stroke
				(width 0.1)
				(type default)
			)
			(layer "F.Fab")
		)
		(fp_line
			(start 0.120396 0.2794)
			(end -0.12065 0.2794)
			(stroke
				(width 0.1)
				(type default)
			)
			(layer "F.Fab")
		)
		(fp_line
			(start 0.120396 0.3048)
			(end 0.120396 0.2794)
			(stroke
				(width 0.1)
				(type default)
			)
			(layer "F.Fab")
		)
		(fp_line
			(start 0.12065 -0.3048)
			(end 0.67945 -0.3048)
			(stroke
				(width 0.1)
				(type default)
			)
			(layer "F.Fab")
		)
		(fp_line
			(start 0.12065 -0.2794)
			(end 0.12065 -0.3048)
			(stroke
				(width 0.1)
				(type default)
			)
			(layer "F.Fab")
		)
		(fp_line
			(start 0.67945 -0.3048)
			(end 0.67945 0.3048)
			(stroke
				(width 0.1)
				(type default)
			)
			(layer "F.Fab")
		)
		(fp_line
			(start 0.67945 0.3048)
			(end 0.120396 0.3048)
			(stroke
				(width 0.1)
				(type default)
			)
			(layer "F.Fab")
		)
		(pad "1" smd circle
			(at -0.40005 0)
			(size 0 0)
			(layers "F.Cu" "F.Mask" "F.Paste")
			(net "P3V3_AUX")
		)
		(pad "2" smd circle
			(at 0.40005 0)
			(size 0 0)
			(layers "F.Cu" "F.Mask" "F.Paste")
			(net "GND")
		)
	)
	(footprint ""
		(layer "F.Cu")
		(at 163.582096 -102.984046 180)
		(property "Reference" "R6186"
			(at 0 0 180)
			(layer "F.SilkS")
			(hide yes)
			(effects
				(font
					(size 1.27 1.27)
				)
			)
		)
		(property "Value" ""
			(at 0 0 180)
			(layer "F.Fab")
			(effects
				(font
					(size 1.27 1.27)
				)
			)
		)
		(duplicate_pad_numbers_are_jumpers no)
		(fp_line
			(start 0.7874 0.4064)
			(end -0.7874 0.4064)
			(stroke
				(width 0.1524)
				(type default)
			)
			(layer "F.SilkS")
		)
		(fp_line
			(start 0.7874 -0.4064)
			(end 0.7874 0.4064)
			(stroke
				(width 0.1524)
				(type default)
			)
			(layer "F.SilkS")
		)
		(fp_line
			(start -0.7874 0.4064)
			(end -0.7874 -0.4064)
			(stroke
				(width 0.1524)
				(type default)
			)
			(layer "F.SilkS")
		)
		(fp_line
			(start -0.7874 -0.4064)
			(end 0.7874 -0.4064)
			(stroke
				(width 0.1524)
				(type default)
			)
			(layer "F.SilkS")
		)
		(fp_line
			(start 0.67945 0.3048)
			(end 0.120396 0.3048)
			(stroke
				(width 0.1)
				(type default)
			)
			(layer "F.Fab")
		)
		(fp_line
			(start 0.67945 -0.3048)
			(end 0.67945 0.3048)
			(stroke
				(width 0.1)
				(type default)
			)
			(layer "F.Fab")
		)
		(fp_line
			(start 0.12065 -0.2794)
			(end 0.12065 -0.3048)
			(stroke
				(width 0.1)
				(type default)
			)
			(layer "F.Fab")
		)
		(fp_line
			(start 0.12065 -0.3048)
			(end 0.67945 -0.3048)
			(stroke
				(width 0.1)
				(type default)
			)
			(layer "F.Fab")
		)
		(fp_line
			(start 0.120396 0.3048)
			(end 0.120396 0.2794)
			(stroke
				(width 0.1)
				(type default)
			)
			(layer "F.Fab")
		)
		(fp_line
			(start 0.120396 0.2794)
			(end -0.12065 0.2794)
			(stroke
				(width 0.1)
				(type default)
			)
			(layer "F.Fab")
		)
		(fp_line
			(start -0.12065 0.3048)
			(end -0.67945 0.3048)
			(stroke
				(width 0.1)
				(type default)
			)
			(layer "F.Fab")
		)
		(fp_line
			(start -0.12065 0.2794)
			(end -0.12065 0.3048)
			(stroke
				(width 0.1)
				(type default)
			)
			(layer "F.Fab")
		)
		(fp_line
			(start -0.12065 -0.2794)
			(end 0.12065 -0.2794)
			(stroke
				(width 0.1)
				(type default)
			)
			(layer "F.Fab")
		)
		(fp_line
			(start -0.12065 -0.305054)
			(end -0.12065 -0.2794)
			(stroke
				(width 0.1)
				(type default)
			)
			(layer "F.Fab")
		)
		(fp_line
			(start -0.67945 0.3048)
			(end -0.67945 -0.305054)
			(stroke
				(width 0.1)
				(type default)
			)
			(layer "F.Fab")
		)
		(fp_line
			(start -0.67945 -0.305054)
			(end -0.12065 -0.305054)
			(stroke
				(width 0.1)
				(type default)
			)
			(layer "F.Fab")
		)
		(pad "1" smd circle
			(at -0.40005 0 180)
			(size 0 0)
			(layers "F.Cu" "F.Mask" "F.Paste")
			(net "FM_SEC_MUX_OE_N")
		)
		(pad "2" smd circle
			(at 0.40005 0 180)
			(size 0 0)
			(layers "F.Cu" "F.Mask" "F.Paste")
			(net "P3V3_AUX")
		)
	)
	(footprint ""
		(layer "F.Cu")
		(at 65.50914 -346.87129 -90)
		(property "Reference" "PC407_4"
			(at 0 0 270)
			(layer "F.SilkS")
			(hide yes)
			(effects
				(font
					(size 1.27 1.27)
				)
			)
		)
		(property "Value" ""
			(at 0 0 270)
			(layer "F.Fab")
			(effects
				(font
					(size 1.27 1.27)
				)
			)
		)
		(duplicate_pad_numbers_are_jumpers no)
		(fp_line
			(start -0.7874 0.4064)
			(end -0.7874 -0.4064)
			(stroke
				(width 0.1524)
				(type default)
			)
			(layer "F.SilkS")
		)
		(fp_line
			(start 0.7874 0.4064)
			(end -0.7874 0.4064)
			(stroke
				(width 0.1524)
				(type default)
			)
			(layer "F.SilkS")
		)
		(fp_line
			(start -0.7874 -0.4064)
			(end 0.7874 -0.4064)
			(stroke
				(width 0.1524)
				(type default)
			)
			(layer "F.SilkS")
		)
		(fp_line
			(start 0.7874 -0.4064)
			(end 0.7874 0.4064)
			(stroke
				(width 0.1524)
				(type default)
			)
			(layer "F.SilkS")
		)
		(fp_line
			(start -0.67945 0.3048)
			(end -0.67945 -0.305054)
			(stroke
				(width 0.1)
				(type default)
			)
			(layer "F.Fab")
		)
		(fp_line
			(start -0.12065 0.3048)
			(end -0.67945 0.3048)
			(stroke
				(width 0.1)
				(type default)
			)
			(layer "F.Fab")
		)
		(fp_line
			(start 0.120396 0.3048)
			(end 0.120396 0.2794)
			(stroke
				(width 0.1)
				(type default)
			)
			(layer "F.Fab")
		)
		(fp_line
			(start 0.67945 0.3048)
			(end 0.120396 0.3048)
			(stroke
				(width 0.1)
				(type default)
			)
			(layer "F.Fab")
		)
		(fp_line
			(start -0.12065 0.2794)
			(end -0.12065 0.3048)
			(stroke
				(width 0.1)
				(type default)
			)
			(layer "F.Fab")
		)
		(fp_line
			(start 0.120396 0.2794)
			(end -0.12065 0.2794)
			(stroke
				(width 0.1)
				(type default)
			)
			(layer "F.Fab")
		)
		(fp_line
			(start -0.12065 -0.2794)
			(end 0.12065 -0.2794)
			(stroke
				(width 0.1)
				(type default)
			)
			(layer "F.Fab")
		)
		(fp_line
			(start 0.12065 -0.2794)
			(end 0.12065 -0.3048)
			(stroke
				(width 0.1)
				(type default)
			)
			(layer "F.Fab")
		)
		(fp_line
			(start 0.12065 -0.3048)
			(end 0.67945 -0.3048)
			(stroke
				(width 0.1)
				(type default)
			)
			(layer "F.Fab")
		)
		(fp_line
			(start 0.67945 -0.3048)
			(end 0.67945 0.3048)
			(stroke
				(width 0.1)
				(type default)
			)
			(layer "F.Fab")
		)
		(fp_line
			(start -0.67945 -0.305054)
			(end -0.12065 -0.305054)
			(stroke
				(width 0.1)
				(type default)
			)
			(layer "F.Fab")
		)
		(fp_line
			(start -0.12065 -0.305054)
			(end -0.12065 -0.2794)
			(stroke
				(width 0.1)
				(type default)
			)
			(layer "F.Fab")
		)
		(pad "1" smd circle
			(at -0.40005 0 270)
			(size 0 0)
			(layers "F.Cu" "F.Mask" "F.Paste")
			(net "SW_P12V_AUX_PVDDCR_CPU1_P1_FLT")
		)
		(pad "2" smd circle
			(at 0.40005 0 270)
			(size 0 0)
			(layers "F.Cu" "F.Mask" "F.Paste")
			(net "GND")
		)
	)
	(footprint ""
		(layer "F.Cu")
		(at 433.05222 -418.942266 180)
		(property "Reference" ""
			(at 0 0 180)
			(layer "F.SilkS")
			(hide yes)
			(effects
				(font
					(size 1.27 1.27)
				)
			)
		)
		(property "Value" ""
			(at 0 0 180)
			(layer "F.Fab")
			(effects
				(font
					(size 1.27 1.27)
				)
			)
		)
		(duplicate_pad_numbers_are_jumpers no)
		(pad "1" smd circle
			(at 0 0 180)
			(size 0.9906 0.9906)
			(layers "F.Cu" "F.Mask" "F.Paste")
			(net "Net_2241")
		)
		(zone
			(layer "F.Cu")
			(hatch none 0.5)
			(connect_pads
				(clearance 0)
			)
			(min_thickness 0.25)
			(keepout
				(tracks not_allowed)
				(vias allowed)
				(pads allowed)
				(copperpour not_allowed)
				(footprints allowed)
			)
			(placement
				(enabled no)
				(sheetname "")
			)
			(fill
				(thermal_gap 0.5)
				(thermal_bridge_width 0.5)
				(island_removal_mode 0)
			)
			(polygon
				(pts
					(arc
						(start 434.67782 -418.942266)
						(mid 431.42662 -418.942266)
						(end 434.67782 -418.942266)
					)
				)
			)
		)
	)
	(footprint ""
		(layer "F.Cu")
		(at 506.598428 -147.926806 -90)
		(property "Reference" "X9"
			(at -1.73355 3.189224 0)
			(unlocked yes)
			(layer "F.SilkS")
			(effects
				(font
					(size 0.7874 0.5842)
					(thickness 0.1524)
				)
				(justify left)
			)
		)
		(property "Value" ""
			(at 0 0 270)
			(layer "F.Fab")
			(effects
				(font
					(size 1.27 1.27)
				)
			)
		)
		(property "Device Type" "TP_TDR_4P_FTS_TH-TP_TDR_4P_DIP,EMPTY,TP15"
			(at 1.30175 1.27 0)
			(unlocked yes)
			(layer "F.Fab")
			(hide yes)
			(effects
				(font
					(size 0.635 0.4064)
					(thickness 0.1524)
				)
			)
		)
		(property "User Part Number" "N_A"
			(at 1.30175 1.27 0)
			(unlocked yes)
			(layer "Cmts.User")
			(hide yes)
			(effects
				(font
					(size 0.635 0.4064)
					(thickness 0.1524)
				)
			)
		)
		(duplicate_pad_numbers_are_jumpers no)
		(fp_line
			(start 0 3.81)
			(end 2.54 3.81)
			(stroke
				(width 0.1524)
				(type default)
			)
			(layer "F.SilkS")
		)
		(fp_line
			(start 2.54 3.81)
			(end 2.54 3.6703)
			(stroke
				(width 0.1524)
				(type default)
			)
			(layer "F.SilkS")
		)
		(fp_line
			(start 0 3.175)
			(end 0 3.81)
			(stroke
				(width 0.1524)
				(type default)
			)
			(layer "F.SilkS")
		)
		(fp_line
			(start 2.54 1.4097)
			(end 2.54 1.1303)
			(stroke
				(width 0.1524)
				(type default)
			)
			(layer "F.SilkS")
		)
		(fp_line
			(start 0 0.635)
			(end 0 1.905)
			(stroke
				(width 0.1524)
				(type default)
			)
			(layer "F.SilkS")
		)
		(fp_line
			(start 2.54 -1.1303)
			(end 2.54 -1.27)
			(stroke
				(width 0.1524)
				(type default)
			)
			(layer "F.SilkS")
		)
		(fp_line
			(start 0 -1.27)
			(end 0 -0.635)
			(stroke
				(width 0.1524)
				(type default)
			)
			(layer "F.SilkS")
		)
		(fp_line
			(start 2.54 -1.27)
			(end 0 -1.27)
			(stroke
				(width 0.1524)
				(type default)
			)
			(layer "F.SilkS")
		)
		(fp_poly
			(pts
				(xy -0.761746 0) (xy -2.285746 0.762) (xy -2.285746 -0.762)
			)
			(stroke
				(width 0)
				(type default)
			)
			(fill yes)
			(layer "F.SilkS")
		)
		(fp_line
			(start 0 3.81)
			(end 2.54 3.81)
			(stroke
				(width 0.1)
				(type default)
			)
			(layer "F.Fab")
		)
		(fp_line
			(start 2.54 3.81)
			(end 2.54 -1.27)
			(stroke
				(width 0.1)
				(type default)
			)
			(layer "F.Fab")
		)
		(fp_line
			(start 0 -1.27)
			(end 0 3.81)
			(stroke
				(width 0.1)
				(type default)
			)
			(layer "F.Fab")
		)
		(fp_line
			(start 2.54 -1.27)
			(end 0 -1.27)
			(stroke
				(width 0.1)
				(type default)
			)
			(layer "F.Fab")
		)
		(fp_poly
			(pts
				(xy -0.761746 0) (xy -2.285746 -0.762) (xy -2.285746 0.762)
			)
			(stroke
				(width 0)
				(type default)
			)
			(fill yes)
			(layer "F.Fab")
		)
		(pad "1" thru_hole circle
			(at 0 0 270)
			(size 1.0033 1.0033)
			(drill 0.249936)
			(layers "*.Cu" "*.Mask")
			(remove_unused_layers no)
			(net "TDR_DIFF_80_IN2_DN")
			(clearance 0.10795)
			(thermal_gap 0.10795)
			(padstack
				(mode front_inner_back)
				(layer "Inner"
					(shape circle)
					(size 0.8001 0.8001)
					(clearance 0.1524)
				)
				(layer "B.Cu"
					(shape circle)
					(size 1.0033 1.0033)
					(clearance 0.10795)
				)
			)
		)
		(pad "2" thru_hole circle
			(at 2.54 0 270)
			(size 1.9939 1.9939)
			(drill 0.249936)
			(layers "*.Cu" "*.Mask")
			(remove_unused_layers no)
			(net "T1_GND")
			(clearance 0.10795)
			(thermal_gap 0.10795)
			(padstack
				(mode front_inner_back)
				(layer "Inner"
					(shape circle)
					(size 0.8001 0.8001)
					(clearance 0.1524)
				)
				(layer "B.Cu"
					(shape circle)
					(size 1.9939 1.9939)
					(clearance 0.10795)
				)
			)
		)
		(pad "3" thru_hole circle
			(at 2.54 2.54 270)
			(size 1.9939 1.9939)
			(drill 0.249936)
			(layers "*.Cu" "*.Mask")
			(remove_unused_layers no)
			(net "T1_GND")
			(clearance 0.10795)
			(thermal_gap 0.10795)
			(padstack
				(mode front_inner_back)
				(layer "Inner"
					(shape circle)
					(size 0.8001 0.8001)
					(clearance 0.1524)
				)
				(layer "B.Cu"
					(shape circle)
					(size 1.9939 1.9939)
					(clearance 0.10795)
				)
			)
		)
		(pad "4" thru_hole circle
			(at 0 2.54 270)
			(size 1.0033 1.0033)
			(drill 0.249936)
			(layers "*.Cu" "*.Mask")
			(remove_unused_layers no)
			(net "TDR_DIFF_80_IN2_DP")
			(clearance 0.10795)
			(thermal_gap 0.10795)
			(padstack
				(mode front_inner_back)
				(layer "Inner"
					(shape circle)
					(size 0.8001 0.8001)
					(clearance 0.1524)
				)
				(layer "B.Cu"
					(shape circle)
					(size 1.0033 1.0033)
					(clearance 0.10795)
				)
			)
		)
	)
	(footprint ""
		(layer "F.Cu")
		(at 188.122306 -332.744572 -90)
		(property "Reference" "PC532"
			(at -4.24434 12.521692 90)
			(unlocked yes)
			(layer "F.SilkS")
			(effects
				(font
					(size 0.7874 0.5842)
					(thickness 0.1524)
				)
				(justify left)
			)
		)
		(property "Value" ""
			(at 0 0 270)
			(layer "F.Fab")
			(effects
				(font
					(size 1.27 1.27)
				)
			)
		)
		(duplicate_pad_numbers_are_jumpers no)
		(fp_line
			(start -1.988058 2.750058)
			(end 2.750058 2.750058)
			(stroke
				(width 0.1524)
				(type default)
			)
			(layer "F.SilkS")
		)
		(fp_line
			(start 2.750058 2.750058)
			(end 2.750058 0.9398)
			(stroke
				(width 0.1524)
				(type default)
			)
			(layer "F.SilkS")
		)
		(fp_line
			(start -2.750058 1.988058)
			(end -1.988058 2.750058)
			(stroke
				(width 0.1524)
				(type default)
			)
			(layer "F.SilkS")
		)
		(fp_line
			(start -2.750058 0.9398)
			(end -2.750058 1.988058)
			(stroke
				(width 0.1524)
				(type default)
			)
			(layer "F.SilkS")
		)
		(fp_line
			(start 2.750058 -0.9398)
			(end 2.750058 -2.750058)
			(stroke
				(width 0.1524)
				(type default)
			)
			(layer "F.SilkS")
		)
		(fp_line
			(start -2.750058 -1.988058)
			(end -2.750058 -0.9398)
			(stroke
				(width 0.1524)
				(type default)
			)
			(layer "F.SilkS")
		)
		(fp_line
			(start -1.988058 -2.750058)
			(end -2.750058 -1.988058)
			(stroke
				(width 0.1524)
				(type default)
			)
			(layer "F.SilkS")
		)
		(fp_line
			(start 2.750058 -2.750058)
			(end -1.988058 -2.750058)
			(stroke
				(width 0.1524)
				(type default)
			)
			(layer "F.SilkS")
		)
		(fp_line
			(start -2.750058 2.750058)
			(end 2.750058 2.750058)
			(stroke
				(width 0.1)
				(type default)
			)
			(layer "F.Fab")
		)
		(fp_line
			(start 2.750058 2.750058)
			(end 2.750058 -2.750058)
			(stroke
				(width 0.1)
				(type default)
			)
			(layer "F.Fab")
		)
		(fp_line
			(start -2.750058 -2.750058)
			(end -2.750058 2.750058)
			(stroke
				(width 0.1)
				(type default)
			)
			(layer "F.Fab")
		)
		(fp_line
			(start 2.750058 -2.750058)
			(end -2.750058 -2.750058)
			(stroke
				(width 0.1)
				(type default)
			)
			(layer "F.Fab")
		)
		(pad "1" smd rect
			(at -2.199894 0)
			(size 1.6002 3.0226)
			(layers "F.Cu" "F.Mask" "F.Paste")
			(net "PVDD11_S3_P1")
		)
		(pad "2" smd rect
			(at 2.199894 0)
			(size 1.6002 3.0226)
			(layers "F.Cu" "F.Mask" "F.Paste")
			(net "GND")
		)
	)
	(footprint ""
		(layer "F.Cu")
		(at 372.937278 -143.504158)
		(property "Reference" "R8299"
			(at 0 0 0)
			(layer "F.SilkS")
			(hide yes)
			(effects
				(font
					(size 1.27 1.27)
				)
			)
		)
		(property "Value" ""
			(at 0 0 0)
			(layer "F.Fab")
			(effects
				(font
					(size 1.27 1.27)
				)
			)
		)
		(duplicate_pad_numbers_are_jumpers no)
		(fp_line
			(start -0.7874 -0.4064)
			(end 0.7874 -0.4064)
			(stroke
				(width 0.1524)
				(type default)
			)
			(layer "F.SilkS")
		)
		(fp_line
			(start -0.7874 0.4064)
			(end -0.7874 -0.4064)
			(stroke
				(width 0.1524)
				(type default)
			)
			(layer "F.SilkS")
		)
		(fp_line
			(start 0.7874 -0.4064)
			(end 0.7874 0.4064)
			(stroke
				(width 0.1524)
				(type default)
			)
			(layer "F.SilkS")
		)
		(fp_line
			(start 0.7874 0.4064)
			(end -0.7874 0.4064)
			(stroke
				(width 0.1524)
				(type default)
			)
			(layer "F.SilkS")
		)
		(fp_line
			(start -0.67945 -0.305054)
			(end -0.12065 -0.305054)
			(stroke
				(width 0.1)
				(type default)
			)
			(layer "F.Fab")
		)
		(fp_line
			(start -0.67945 0.3048)
			(end -0.67945 -0.305054)
			(stroke
				(width 0.1)
				(type default)
			)
			(layer "F.Fab")
		)
		(fp_line
			(start -0.12065 -0.305054)
			(end -0.12065 -0.2794)
			(stroke
				(width 0.1)
				(type default)
			)
			(layer "F.Fab")
		)
		(fp_line
			(start -0.12065 -0.2794)
			(end 0.12065 -0.2794)
			(stroke
				(width 0.1)
				(type default)
			)
			(layer "F.Fab")
		)
		(fp_line
			(start -0.12065 0.2794)
			(end -0.12065 0.3048)
			(stroke
				(width 0.1)
				(type default)
			)
			(layer "F.Fab")
		)
		(fp_line
			(start -0.12065 0.3048)
			(end -0.67945 0.3048)
			(stroke
				(width 0.1)
				(type default)
			)
			(layer "F.Fab")
		)
		(fp_line
			(start 0.120396 0.2794)
			(end -0.12065 0.2794)
			(stroke
				(width 0.1)
				(type default)
			)
			(layer "F.Fab")
		)
		(fp_line
			(start 0.120396 0.3048)
			(end 0.120396 0.2794)
			(stroke
				(width 0.1)
				(type default)
			)
			(layer "F.Fab")
		)
		(fp_line
			(start 0.12065 -0.3048)
			(end 0.67945 -0.3048)
			(stroke
				(width 0.1)
				(type default)
			)
			(layer "F.Fab")
		)
		(fp_line
			(start 0.12065 -0.2794)
			(end 0.12065 -0.3048)
			(stroke
				(width 0.1)
				(type default)
			)
			(layer "F.Fab")
		)
		(fp_line
			(start 0.67945 -0.3048)
			(end 0.67945 0.3048)
			(stroke
				(width 0.1)
				(type default)
			)
			(layer "F.Fab")
		)
		(fp_line
			(start 0.67945 0.3048)
			(end 0.120396 0.3048)
			(stroke
				(width 0.1)
				(type default)
			)
			(layer "F.Fab")
		)
		(pad "1" smd circle
			(at -0.40005 0)
			(size 0 0)
			(layers "F.Cu" "F.Mask" "F.Paste")
			(net "PWRGD_PVDDCR_SOC_P0")
		)
		(pad "2" smd circle
			(at 0.40005 0)
			(size 0 0)
			(layers "F.Cu" "F.Mask" "F.Paste")
			(net "PWRGD_PVDDCR_SOC_P0_R")
		)
	)
	(footprint ""
		(layer "F.Cu")
		(at 417.018216 -332.628494 -90)
		(property "Reference" "PC222"
			(at 0 0 270)
			(layer "F.SilkS")
			(hide yes)
			(effects
				(font
					(size 1.27 1.27)
				)
			)
		)
		(property "Value" ""
			(at 0 0 270)
			(layer "F.Fab")
			(effects
				(font
					(size 1.27 1.27)
				)
			)
		)
		(duplicate_pad_numbers_are_jumpers no)
		(fp_line
			(start -0.7874 0.4064)
			(end -0.7874 -0.4064)
			(stroke
				(width 0.1524)
				(type default)
			)
			(layer "F.SilkS")
		)
		(fp_line
			(start 0.7874 0.4064)
			(end -0.7874 0.4064)
			(stroke
				(width 0.1524)
				(type default)
			)
			(layer "F.SilkS")
		)
		(fp_line
			(start -0.7874 -0.4064)
			(end 0.7874 -0.4064)
			(stroke
				(width 0.1524)
				(type default)
			)
			(layer "F.SilkS")
		)
		(fp_line
			(start 0.7874 -0.4064)
			(end 0.7874 0.4064)
			(stroke
				(width 0.1524)
				(type default)
			)
			(layer "F.SilkS")
		)
		(fp_line
			(start -0.67945 0.3048)
			(end -0.67945 -0.305054)
			(stroke
				(width 0.1)
				(type default)
			)
			(layer "F.Fab")
		)
		(fp_line
			(start -0.12065 0.3048)
			(end -0.67945 0.3048)
			(stroke
				(width 0.1)
				(type default)
			)
			(layer "F.Fab")
		)
		(fp_line
			(start 0.120396 0.3048)
			(end 0.120396 0.2794)
			(stroke
				(width 0.1)
				(type default)
			)
			(layer "F.Fab")
		)
		(fp_line
			(start 0.67945 0.3048)
			(end 0.120396 0.3048)
			(stroke
				(width 0.1)
				(type default)
			)
			(layer "F.Fab")
		)
		(fp_line
			(start -0.12065 0.2794)
			(end -0.12065 0.3048)
			(stroke
				(width 0.1)
				(type default)
			)
			(layer "F.Fab")
		)
		(fp_line
			(start 0.120396 0.2794)
			(end -0.12065 0.2794)
			(stroke
				(width 0.1)
				(type default)
			)
			(layer "F.Fab")
		)
		(fp_line
			(start -0.12065 -0.2794)
			(end 0.12065 -0.2794)
			(stroke
				(width 0.1)
				(type default)
			)
			(layer "F.Fab")
		)
		(fp_line
			(start 0.12065 -0.2794)
			(end 0.12065 -0.3048)
			(stroke
				(width 0.1)
				(type default)
			)
			(layer "F.Fab")
		)
		(fp_line
			(start 0.12065 -0.3048)
			(end 0.67945 -0.3048)
			(stroke
				(width 0.1)
				(type default)
			)
			(layer "F.Fab")
		)
		(fp_line
			(start 0.67945 -0.3048)
			(end 0.67945 0.3048)
			(stroke
				(width 0.1)
				(type default)
			)
			(layer "F.Fab")
		)
		(fp_line
			(start -0.67945 -0.305054)
			(end -0.12065 -0.305054)
			(stroke
				(width 0.1)
				(type default)
			)
			(layer "F.Fab")
		)
		(fp_line
			(start -0.12065 -0.305054)
			(end -0.12065 -0.2794)
			(stroke
				(width 0.1)
				(type default)
			)
			(layer "F.Fab")
		)
		(pad "1" smd circle
			(at -0.40005 0 270)
			(size 0 0)
			(layers "F.Cu" "F.Mask" "F.Paste")
			(net "PVDD11_S3_P0")
		)
		(pad "2" smd circle
			(at 0.40005 0 270)
			(size 0 0)
			(layers "F.Cu" "F.Mask" "F.Paste")
			(net "GND")
		)
	)
	(footprint ""
		(layer "F.Cu")
		(at 204.197966 -255.560322 180)
		(property "Reference" "J37"
			(at 2.8702 -81.730088 0)
			(unlocked yes)
			(layer "F.SilkS")
			(effects
				(font
					(size 0.7874 0.5842)
					(thickness 0.1524)
				)
			)
		)
		(property "Value" ""
			(at 0 0 180)
			(layer "F.Fab")
			(effects
				(font
					(size 1.27 1.27)
				)
			)
		)
		(duplicate_pad_numbers_are_jumpers no)
		(fp_line
			(start 3.24993 -81.000092)
			(end 3.24993 72.780398)
			(stroke
				(width 0.1524)
				(type default)
			)
			(layer "F.SilkS")
		)
		(fp_line
			(start 1.130046 81.000092)
			(end -3.24993 81.000092)
			(stroke
				(width 0.1524)
				(type default)
			)
			(layer "F.SilkS")
		)
		(fp_line
			(start -1.034034 -81.000092)
			(end 3.24993 -81.000092)
			(stroke
				(width 0.1524)
				(type default)
			)
			(layer "F.SilkS")
		)
		(fp_line
			(start -3.24993 81.000092)
			(end -3.24993 -78.903322)
			(stroke
				(width 0.1524)
				(type default)
			)
			(layer "F.SilkS")
		)
		(fp_line
			(start -3.24993 72.499982)
			(end 3.24993 72.499982)
			(stroke
				(width 0.1524)
				(type default)
			)
			(layer "F.SilkS")
		)
		(fp_line
			(start -3.24993 -72.499982)
			(end 3.24993 -72.499982)
			(stroke
				(width 0.1524)
				(type default)
			)
			(layer "F.SilkS")
		)
		(fp_line
			(start -3.24993 -80.173322)
			(end -3.24993 -81.000092)
			(stroke
				(width 0.1524)
				(type default)
			)
			(layer "F.SilkS")
		)
		(fp_line
			(start -3.24993 -81.000092)
			(end -2.558034 -81.000092)
			(stroke
				(width 0.1524)
				(type default)
			)
			(layer "F.SilkS")
		)
		(fp_poly
			(pts
				(xy -4.215638 -64.84112) (xy -3.545586 -63.923926) (xy -4.68122 -63.93815)
			)
			(stroke
				(width 0)
				(type default)
			)
			(fill yes)
			(layer "F.SilkS")
		)
		(fp_line
			(start 3.24993 81.000092)
			(end -3.24993 81.000092)
			(stroke
				(width 0.1)
				(type default)
			)
			(layer "F.Fab")
		)
		(fp_line
			(start 3.24993 -81.000092)
			(end 3.24993 81.000092)
			(stroke
				(width 0.1)
				(type default)
			)
			(layer "F.Fab")
		)
		(fp_line
			(start -3.24993 81.000092)
			(end -3.24993 -81.000092)
			(stroke
				(width 0.1)
				(type default)
			)
			(layer "F.Fab")
		)
		(fp_line
			(start -3.24993 72.499982)
			(end 3.24993 72.499982)
			(stroke
				(width 0.1)
				(type default)
			)
			(layer "F.Fab")
		)
		(fp_line
			(start -3.24993 71.000112)
			(end 3.24993 71.000112)
			(stroke
				(width 0.1)
				(type default)
			)
			(layer "F.Fab")
		)
		(fp_line
			(start -3.24993 -71.000112)
			(end 3.24993 -71.000112)
			(stroke
				(width 0.1)
				(type default)
			)
			(layer "F.Fab")
		)
		(fp_line
			(start -3.24993 -72.499982)
			(end 3.24993 -72.499982)
			(stroke
				(width 0.1)
				(type default)
			)
			(layer "F.Fab")
		)
		(fp_line
			(start -3.24993 -81.000092)
			(end 3.24993 -81.000092)
			(stroke
				(width 0.1)
				(type default)
			)
			(layer "F.Fab")
		)
		(fp_poly
			(pts
				(xy -3.41503 -63.324994) (xy -4.43103 -62.816994) (xy -4.43103 -63.832994)
			)
			(stroke
				(width 0)
				(type default)
			)
			(fill yes)
			(layer "F.Fab")
		)
		(pad "1" smd rect
			(at -2.050034 -63.324994 90)
			(size 0.519938 1.4986)
			(layers "F.Cu" "F.Mask" "F.Paste")
			(net "P12V_MEM_CPU1")
		)
		(pad "2" smd rect
			(at -2.050034 -62.47511 90)
			(size 0.519938 1.4986)
			(layers "F.Cu" "F.Mask" "F.Paste")
			(net "Net_2410")
		)
		(pad "3" smd rect
			(at -2.050034 -61.624972 90)
			(size 0.519938 1.4986)
			(layers "F.Cu" "F.Mask" "F.Paste")
			(net "P3V3_AUX")
		)
		(pad "4" smd rect
			(at -2.050034 -60.775088 90)
			(size 0.519938 1.4986)
			(layers "F.Cu" "F.Mask" "F.Paste")
			(net "I3C_SPD_DDRL_CPU1_SCL")
		)
		(pad "5" smd rect
			(at -2.050034 -59.92495 90)
			(size 0.519938 1.4986)
			(layers "F.Cu" "F.Mask" "F.Paste")
			(net "I3C_SPD_DDRL_CPU1_SDA")
		)
		(pad "6" smd rect
			(at -2.050034 -59.075066 90)
			(size 0.519938 1.4986)
			(layers "F.Cu" "F.Mask" "F.Paste")
			(net "GND")
		)
		(pad "7" smd rect
			(at -2.050034 -58.224928 90)
			(size 0.519938 1.4986)
			(layers "F.Cu" "F.Mask" "F.Paste")
			(net "M_L_CPU1_SA_DQ<0>")
		)
		(pad "8" smd rect
			(at -2.050034 -57.375044 90)
			(size 0.519938 1.4986)
			(layers "F.Cu" "F.Mask" "F.Paste")
			(net "GND")
		)
		(pad "9" smd rect
			(at -2.050034 -56.524906 90)
			(size 0.519938 1.4986)
			(layers "F.Cu" "F.Mask" "F.Paste")
			(net "M_L_CPU1_SA_DQ<1>")
		)
		(pad "10" smd rect
			(at -2.050034 -55.675022 90)
			(size 0.519938 1.4986)
			(layers "F.Cu" "F.Mask" "F.Paste")
			(net "GND")
		)
		(pad "11" smd rect
			(at -2.050034 -54.824884 90)
			(size 0.519938 1.4986)
			(layers "F.Cu" "F.Mask" "F.Paste")
			(net "M_L_CPU1_SA_DQS_DP<0>")
		)
		(pad "12" smd rect
			(at -2.050034 -53.975 90)
			(size 0.519938 1.4986)
			(layers "F.Cu" "F.Mask" "F.Paste")
			(net "M_L_CPU1_SA_DQS_DN<0>")
		)
		(pad "13" smd rect
			(at -2.050034 -53.125116 90)
			(size 0.519938 1.4986)
			(layers "F.Cu" "F.Mask" "F.Paste")
			(net "GND")
		)
		(pad "14" smd rect
			(at -2.050034 -52.274978 90)
			(size 0.519938 1.4986)
			(layers "F.Cu" "F.Mask" "F.Paste")
			(net "M_L_CPU1_SA_DQ<4>")
		)
		(pad "15" smd rect
			(at -2.050034 -51.425094 90)
			(size 0.519938 1.4986)
			(layers "F.Cu" "F.Mask" "F.Paste")
			(net "GND")
		)
		(pad "16" smd rect
			(at -2.050034 -50.574956 90)
			(size 0.519938 1.4986)
			(layers "F.Cu" "F.Mask" "F.Paste")
			(net "M_L_CPU1_SA_DQ<5>")
		)
		(pad "17" smd rect
			(at -2.050034 -49.725072 90)
			(size 0.519938 1.4986)
			(layers "F.Cu" "F.Mask" "F.Paste")
			(net "GND")
		)
		(pad "18" smd rect
			(at -2.050034 -48.874934 90)
			(size 0.519938 1.4986)
			(layers "F.Cu" "F.Mask" "F.Paste")
			(net "M_L_CPU1_SA_DQ<8>")
		)
		(pad "19" smd rect
			(at -2.050034 -48.02505 90)
			(size 0.519938 1.4986)
			(layers "F.Cu" "F.Mask" "F.Paste")
			(net "GND")
		)
		(pad "20" smd rect
			(at -2.050034 -47.174912 90)
			(size 0.519938 1.4986)
			(layers "F.Cu" "F.Mask" "F.Paste")
			(net "M_L_CPU1_SA_DQ<9>")
		)
		(pad "21" smd rect
			(at -2.050034 -46.325028 90)
			(size 0.519938 1.4986)
			(layers "F.Cu" "F.Mask" "F.Paste")
			(net "GND")
		)
		(pad "22" smd rect
			(at -2.050034 -45.47489 90)
			(size 0.519938 1.4986)
			(layers "F.Cu" "F.Mask" "F.Paste")
			(net "M_L_CPU1_SA_DQS_DP<1>")
		)
		(pad "23" smd rect
			(at -2.050034 -44.625006 90)
			(size 0.519938 1.4986)
			(layers "F.Cu" "F.Mask" "F.Paste")
			(net "M_L_CPU1_SA_DQS_DN<1>")
		)
		(pad "24" smd rect
			(at -2.050034 -43.775122 90)
			(size 0.519938 1.4986)
			(layers "F.Cu" "F.Mask" "F.Paste")
			(net "GND")
		)
		(pad "25" smd rect
			(at -2.050034 -42.924984 90)
			(size 0.519938 1.4986)
			(layers "F.Cu" "F.Mask" "F.Paste")
			(net "M_L_CPU1_SA_DQ<12>")
		)
		(pad "26" smd rect
			(at -2.050034 -42.0751 90)
			(size 0.519938 1.4986)
			(layers "F.Cu" "F.Mask" "F.Paste")
			(net "GND")
		)
		(pad "27" smd rect
			(at -2.050034 -41.224962 90)
			(size 0.519938 1.4986)
			(layers "F.Cu" "F.Mask" "F.Paste")
			(net "M_L_CPU1_SA_DQ<13>")
		)
		(pad "28" smd rect
			(at -2.050034 -40.375078 90)
			(size 0.519938 1.4986)
			(layers "F.Cu" "F.Mask" "F.Paste")
			(net "GND")
		)
		(pad "29" smd rect
			(at -2.050034 -39.52494 90)
			(size 0.519938 1.4986)
			(layers "F.Cu" "F.Mask" "F.Paste")
			(net "M_L_CPU1_SA_DQ<16>")
		)
		(pad "30" smd rect
			(at -2.050034 -38.675056 90)
			(size 0.519938 1.4986)
			(layers "F.Cu" "F.Mask" "F.Paste")
			(net "GND")
		)
		(pad "31" smd rect
			(at -2.050034 -37.824918 90)
			(size 0.519938 1.4986)
			(layers "F.Cu" "F.Mask" "F.Paste")
			(net "M_L_CPU1_SA_DQ<17>")
		)
		(pad "32" smd rect
			(at -2.050034 -36.975034 90)
			(size 0.519938 1.4986)
			(layers "F.Cu" "F.Mask" "F.Paste")
			(net "GND")
		)
		(pad "33" smd rect
			(at -2.050034 -36.124896 90)
			(size 0.519938 1.4986)
			(layers "F.Cu" "F.Mask" "F.Paste")
			(net "M_L_CPU1_SA_DQS_DP<2>")
		)
		(pad "34" smd rect
			(at -2.050034 -35.275012 90)
			(size 0.519938 1.4986)
			(layers "F.Cu" "F.Mask" "F.Paste")
			(net "M_L_CPU1_SA_DQS_DN<2>")
		)
		(pad "35" smd rect
			(at -2.050034 -34.425128 90)
			(size 0.519938 1.4986)
			(layers "F.Cu" "F.Mask" "F.Paste")
			(net "GND")
		)
		(pad "36" smd rect
			(at -2.050034 -33.57499 90)
			(size 0.519938 1.4986)
			(layers "F.Cu" "F.Mask" "F.Paste")
			(net "M_L_CPU1_SA_DQ<20>")
		)
		(pad "37" smd rect
			(at -2.050034 -32.725106 90)
			(size 0.519938 1.4986)
			(layers "F.Cu" "F.Mask" "F.Paste")
			(net "GND")
		)
		(pad "38" smd rect
			(at -2.050034 -31.874968 90)
			(size 0.519938 1.4986)
			(layers "F.Cu" "F.Mask" "F.Paste")
			(net "M_L_CPU1_SA_DQ<21>")
		)
		(pad "39" smd rect
			(at -2.050034 -31.025084 90)
			(size 0.519938 1.4986)
			(layers "F.Cu" "F.Mask" "F.Paste")
			(net "GND")
		)
		(pad "40" smd rect
			(at -2.050034 -30.174946 90)
			(size 0.519938 1.4986)
			(layers "F.Cu" "F.Mask" "F.Paste")
			(net "M_L_CPU1_SA_DQ<24>")
		)
		(pad "41" smd rect
			(at -2.050034 -29.325062 90)
			(size 0.519938 1.4986)
			(layers "F.Cu" "F.Mask" "F.Paste")
			(net "GND")
		)
		(pad "42" smd rect
			(at -2.050034 -28.474924 90)
			(size 0.519938 1.4986)
			(layers "F.Cu" "F.Mask" "F.Paste")
			(net "M_L_CPU1_SA_DQ<25>")
		)
		(pad "43" smd rect
			(at -2.050034 -27.62504 90)
			(size 0.519938 1.4986)
			(layers "F.Cu" "F.Mask" "F.Paste")
			(net "GND")
		)
		(pad "44" smd rect
			(at -2.050034 -26.774902 90)
			(size 0.519938 1.4986)
			(layers "F.Cu" "F.Mask" "F.Paste")
			(net "M_L_CPU1_SA_DQS_DP<3>")
		)
		(pad "45" smd rect
			(at -2.050034 -25.925018 90)
			(size 0.519938 1.4986)
			(layers "F.Cu" "F.Mask" "F.Paste")
			(net "M_L_CPU1_SA_DQS_DN<3>")
		)
		(pad "46" smd rect
			(at -2.050034 -25.07488 90)
			(size 0.519938 1.4986)
			(layers "F.Cu" "F.Mask" "F.Paste")
			(net "GND")
		)
		(pad "47" smd rect
			(at -2.050034 -24.224996 90)
			(size 0.519938 1.4986)
			(layers "F.Cu" "F.Mask" "F.Paste")
			(net "M_L_CPU1_SA_DQ<28>")
		)
		(pad "48" smd rect
			(at -2.050034 -23.375112 90)
			(size 0.519938 1.4986)
			(layers "F.Cu" "F.Mask" "F.Paste")
			(net "GND")
		)
		(pad "49" smd rect
			(at -2.050034 -22.524974 90)
			(size 0.519938 1.4986)
			(layers "F.Cu" "F.Mask" "F.Paste")
			(net "M_L_CPU1_SA_DQ<29>")
		)
		(pad "50" smd rect
			(at -2.050034 -21.67509 90)
			(size 0.519938 1.4986)
			(layers "F.Cu" "F.Mask" "F.Paste")
			(net "GND")
		)
		(pad "51" smd rect
			(at -2.050034 -20.824952 90)
			(size 0.519938 1.4986)
			(layers "F.Cu" "F.Mask" "F.Paste")
			(net "M_L_CPU1_SA_CB<0>")
		)
		(pad "52" smd rect
			(at -2.050034 -19.975068 90)
			(size 0.519938 1.4986)
			(layers "F.Cu" "F.Mask" "F.Paste")
			(net "GND")
		)
		(pad "53" smd rect
			(at -2.050034 -19.12493 90)
			(size 0.519938 1.4986)
			(layers "F.Cu" "F.Mask" "F.Paste")
			(net "M_L_CPU1_SA_CB<1>")
		)
		(pad "54" smd rect
			(at -2.050034 -18.275046 90)
			(size 0.519938 1.4986)
			(layers "F.Cu" "F.Mask" "F.Paste")
			(net "GND")
		)
		(pad "55" smd rect
			(at -2.050034 -17.424908 90)
			(size 0.519938 1.4986)
			(layers "F.Cu" "F.Mask" "F.Paste")
			(net "M_L_CPU1_SA_DQS_DP<4>")
		)
		(pad "56" smd rect
			(at -2.050034 -16.575024 90)
			(size 0.519938 1.4986)
			(layers "F.Cu" "F.Mask" "F.Paste")
			(net "M_L_CPU1_SA_DQS_DN<4>")
		)
		(pad "57" smd rect
			(at -2.050034 -15.724886 90)
			(size 0.519938 1.4986)
			(layers "F.Cu" "F.Mask" "F.Paste")
			(net "GND")
		)
		(pad "58" smd rect
			(at -2.050034 -14.875002 90)
			(size 0.519938 1.4986)
			(layers "F.Cu" "F.Mask" "F.Paste")
			(net "M_L_CPU1_SA_CB<4>")
		)
		(pad "59" smd rect
			(at -2.050034 -14.025118 90)
			(size 0.519938 1.4986)
			(layers "F.Cu" "F.Mask" "F.Paste")
			(net "GND")
		)
		(pad "60" smd rect
			(at -2.050034 -13.17498 90)
			(size 0.519938 1.4986)
			(layers "F.Cu" "F.Mask" "F.Paste")
			(net "M_L_CPU1_SA_CB<5>")
		)
		(pad "61" smd rect
			(at -2.050034 -12.325096 90)
			(size 0.519938 1.4986)
			(layers "F.Cu" "F.Mask" "F.Paste")
			(net "GND")
		)
		(pad "62" smd rect
			(at -2.050034 -11.474958 90)
			(size 0.519938 1.4986)
			(layers "F.Cu" "F.Mask" "F.Paste")
			(net "M_L_CPU1_ALERT_N")
		)
		(pad "63" smd rect
			(at -2.050034 -10.625074 90)
			(size 0.519938 1.4986)
			(layers "F.Cu" "F.Mask" "F.Paste")
			(net "GND")
		)
		(pad "64" smd rect
			(at -2.050034 -9.774936 90)
			(size 0.519938 1.4986)
			(layers "F.Cu" "F.Mask" "F.Paste")
			(net "M_L_CPU1_SA_CS_N<0>")
		)
		(pad "65" smd rect
			(at -2.050034 -8.925052 90)
			(size 0.519938 1.4986)
			(layers "F.Cu" "F.Mask" "F.Paste")
			(net "GND")
		)
		(pad "66" smd rect
			(at -2.050034 -8.074914 90)
			(size 0.519938 1.4986)
			(layers "F.Cu" "F.Mask" "F.Paste")
			(net "M_L_CPU1_SA_CA<0>")
		)
		(pad "67" smd rect
			(at -2.050034 -7.22503 90)
			(size 0.519938 1.4986)
			(layers "F.Cu" "F.Mask" "F.Paste")
			(net "GND")
		)
		(pad "68" smd rect
			(at -2.050034 -6.374892 90)
			(size 0.519938 1.4986)
			(layers "F.Cu" "F.Mask" "F.Paste")
			(net "M_L_CPU1_SA_CA<2>")
		)
		(pad "69" smd rect
			(at -2.050034 -5.525008 90)
			(size 0.519938 1.4986)
			(layers "F.Cu" "F.Mask" "F.Paste")
			(net "GND")
		)
		(pad "70" smd rect
			(at -2.050034 -4.675124 90)
			(size 0.519938 1.4986)
			(layers "F.Cu" "F.Mask" "F.Paste")
			(net "M_L_CPU1_SA_CA<4>")
		)
		(pad "71" smd rect
			(at -2.050034 -3.824986 90)
			(size 0.519938 1.4986)
			(layers "F.Cu" "F.Mask" "F.Paste")
			(net "GND")
		)
		(pad "72" smd rect
			(at -2.050034 -2.975102 90)
			(size 0.519938 1.4986)
			(layers "F.Cu" "F.Mask" "F.Paste")
			(net "M_L_CPU1_SA_CA<6>")
		)
		(pad "73" smd rect
			(at -2.050034 -2.124964 90)
			(size 0.519938 1.4986)
			(layers "F.Cu" "F.Mask" "F.Paste")
			(net "GND")
		)
		(pad "74" smd rect
			(at -2.050034 -1.27508 90)
			(size 0.519938 1.4986)
			(layers "F.Cu" "F.Mask" "F.Paste")
			(net "M_L_CPU1_SA_PAR")
		)
		(pad "75" smd rect
			(at -2.050034 -0.424942 90)
			(size 0.519938 1.4986)
			(layers "F.Cu" "F.Mask" "F.Paste")
			(net "GND")
		)
		(pad "76" smd rect
			(at -2.050034 5.525008 90)
			(size 0.519938 1.4986)
			(layers "F.Cu" "F.Mask" "F.Paste")
			(net "M_L_CPU1_SB_CA<0>")
		)
		(pad "77" smd rect
			(at -2.050034 6.374892 90)
			(size 0.519938 1.4986)
			(layers "F.Cu" "F.Mask" "F.Paste")
			(net "GND")
		)
		(pad "78" smd rect
			(at -2.050034 7.22503 90)
			(size 0.519938 1.4986)
			(layers "F.Cu" "F.Mask" "F.Paste")
			(net "M_L_CPU1_SB_CA<2>")
		)
		(pad "79" smd rect
			(at -2.050034 8.074914 90)
			(size 0.519938 1.4986)
			(layers "F.Cu" "F.Mask" "F.Paste")
			(net "GND")
		)
		(pad "80" smd rect
			(at -2.050034 8.925052 90)
			(size 0.519938 1.4986)
			(layers "F.Cu" "F.Mask" "F.Paste")
			(net "M_L_CPU1_SB_CA<4>")
		)
		(pad "81" smd rect
			(at -2.050034 9.774936 90)
			(size 0.519938 1.4986)
			(layers "F.Cu" "F.Mask" "F.Paste")
			(net "GND")
		)
		(pad "82" smd rect
			(at -2.050034 10.625074 90)
			(size 0.519938 1.4986)
			(layers "F.Cu" "F.Mask" "F.Paste")
			(net "M_L_CPU1_SB_CA<6>")
		)
		(pad "83" smd rect
			(at -2.050034 11.474958 90)
			(size 0.519938 1.4986)
			(layers "F.Cu" "F.Mask" "F.Paste")
			(net "GND")
		)
		(pad "84" smd rect
			(at -2.050034 12.325096 90)
			(size 0.519938 1.4986)
			(layers "F.Cu" "F.Mask" "F.Paste")
			(net "M_L_CPU1_SB_CS_N<0>")
		)
		(pad "85" smd rect
			(at -2.050034 13.17498 90)
			(size 0.519938 1.4986)
			(layers "F.Cu" "F.Mask" "F.Paste")
			(net "GND")
		)
		(pad "86" smd rect
			(at -2.050034 14.025118 90)
			(size 0.519938 1.4986)
			(layers "F.Cu" "F.Mask" "F.Paste")
			(net "M_L_CPU1_SA_RSP<0>")
		)
		(pad "87" smd rect
			(at -2.050034 14.875002 90)
			(size 0.519938 1.4986)
			(layers "F.Cu" "F.Mask" "F.Paste")
			(net "M_L_CPU1_SB_RSP<0>")
		)
		(pad "88" smd rect
			(at -2.050034 15.724886 90)
			(size 0.519938 1.4986)
			(layers "F.Cu" "F.Mask" "F.Paste")
			(net "GND")
		)
		(pad "89" smd rect
			(at -2.050034 16.575024 90)
			(size 0.519938 1.4986)
			(layers "F.Cu" "F.Mask" "F.Paste")
			(net "M_L_CPU1_SB_CB<4>")
		)
		(pad "90" smd rect
			(at -2.050034 17.424908 90)
			(size 0.519938 1.4986)
			(layers "F.Cu" "F.Mask" "F.Paste")
			(net "GND")
		)
		(pad "91" smd rect
			(at -2.050034 18.275046 90)
			(size 0.519938 1.4986)
			(layers "F.Cu" "F.Mask" "F.Paste")
			(net "M_L_CPU1_SB_CB<5>")
		)
		(pad "92" smd rect
			(at -2.050034 19.12493 90)
			(size 0.519938 1.4986)
			(layers "F.Cu" "F.Mask" "F.Paste")
			(net "GND")
		)
		(pad "93" smd rect
			(at -2.050034 19.975068 90)
			(size 0.519938 1.4986)
			(layers "F.Cu" "F.Mask" "F.Paste")
			(net "M_L_CPU1_SB_DQS_DP<9>")
		)
		(pad "94" smd rect
			(at -2.050034 20.824952 90)
			(size 0.519938 1.4986)
			(layers "F.Cu" "F.Mask" "F.Paste")
			(net "M_L_CPU1_SB_DQS_DN<9>")
		)
		(pad "95" smd rect
			(at -2.050034 21.67509 90)
			(size 0.519938 1.4986)
			(layers "F.Cu" "F.Mask" "F.Paste")
			(net "GND")
		)
		(pad "96" smd rect
			(at -2.050034 22.524974 90)
			(size 0.519938 1.4986)
			(layers "F.Cu" "F.Mask" "F.Paste")
			(net "M_L_CPU1_SB_CB<0>")
		)
		(pad "97" smd rect
			(at -2.050034 23.375112 90)
			(size 0.519938 1.4986)
			(layers "F.Cu" "F.Mask" "F.Paste")
			(net "GND")
		)
		(pad "98" smd rect
			(at -2.050034 24.224996 90)
			(size 0.519938 1.4986)
			(layers "F.Cu" "F.Mask" "F.Paste")
			(net "M_L_CPU1_SB_CB<1>")
		)
		(pad "99" smd rect
			(at -2.050034 25.07488 90)
			(size 0.519938 1.4986)
			(layers "F.Cu" "F.Mask" "F.Paste")
			(net "GND")
		)
		(pad "100" smd rect
			(at -2.050034 25.925018 90)
			(size 0.519938 1.4986)
			(layers "F.Cu" "F.Mask" "F.Paste")
			(net "M_L_CPU1_SB_DQ<0>")
		)
		(pad "101" smd rect
			(at -2.050034 26.774902 90)
			(size 0.519938 1.4986)
			(layers "F.Cu" "F.Mask" "F.Paste")
			(net "GND")
		)
		(pad "102" smd rect
			(at -2.050034 27.62504 90)
			(size 0.519938 1.4986)
			(layers "F.Cu" "F.Mask" "F.Paste")
			(net "M_L_CPU1_SB_DQ<1>")
		)
		(pad "103" smd rect
			(at -2.050034 28.474924 90)
			(size 0.519938 1.4986)
			(layers "F.Cu" "F.Mask" "F.Paste")
			(net "GND")
		)
		(pad "104" smd rect
			(at -2.050034 29.325062 90)
			(size 0.519938 1.4986)
			(layers "F.Cu" "F.Mask" "F.Paste")
			(net "M_L_CPU1_SB_DQS_DP<0>")
		)
		(pad "105" smd rect
			(at -2.050034 30.174946 90)
			(size 0.519938 1.4986)
			(layers "F.Cu" "F.Mask" "F.Paste")
			(net "M_L_CPU1_SB_DQS_DN<0>")
		)
		(pad "106" smd rect
			(at -2.050034 31.025084 90)
			(size 0.519938 1.4986)
			(layers "F.Cu" "F.Mask" "F.Paste")
			(net "GND")
		)
		(pad "107" smd rect
			(at -2.050034 31.874968 90)
			(size 0.519938 1.4986)
			(layers "F.Cu" "F.Mask" "F.Paste")
			(net "M_L_CPU1_SB_DQ<4>")
		)
		(pad "108" smd rect
			(at -2.050034 32.725106 90)
			(size 0.519938 1.4986)
			(layers "F.Cu" "F.Mask" "F.Paste")
			(net "GND")
		)
		(pad "109" smd rect
			(at -2.050034 33.57499 90)
			(size 0.519938 1.4986)
			(layers "F.Cu" "F.Mask" "F.Paste")
			(net "M_L_CPU1_SB_DQ<5>")
		)
		(pad "110" smd rect
			(at -2.050034 34.425128 90)
			(size 0.519938 1.4986)
			(layers "F.Cu" "F.Mask" "F.Paste")
			(net "GND")
		)
		(pad "111" smd rect
			(at -2.050034 35.275012 90)
			(size 0.519938 1.4986)
			(layers "F.Cu" "F.Mask" "F.Paste")
			(net "M_L_CPU1_SB_DQ<8>")
		)
		(pad "112" smd rect
			(at -2.050034 36.124896 90)
			(size 0.519938 1.4986)
			(layers "F.Cu" "F.Mask" "F.Paste")
			(net "GND")
		)
		(pad "113" smd rect
			(at -2.050034 36.975034 90)
			(size 0.519938 1.4986)
			(layers "F.Cu" "F.Mask" "F.Paste")
			(net "M_L_CPU1_SB_DQ<9>")
		)
		(pad "114" smd rect
			(at -2.050034 37.824918 90)
			(size 0.519938 1.4986)
			(layers "F.Cu" "F.Mask" "F.Paste")
			(net "GND")
		)
		(pad "115" smd rect
			(at -2.050034 38.675056 90)
			(size 0.519938 1.4986)
			(layers "F.Cu" "F.Mask" "F.Paste")
			(net "M_L_CPU1_SB_DQS_DP<1>")
		)
		(pad "116" smd rect
			(at -2.050034 39.52494 90)
			(size 0.519938 1.4986)
			(layers "F.Cu" "F.Mask" "F.Paste")
			(net "M_L_CPU1_SB_DQS_DN<1>")
		)
		(pad "117" smd rect
			(at -2.050034 40.375078 90)
			(size 0.519938 1.4986)
			(layers "F.Cu" "F.Mask" "F.Paste")
			(net "GND")
		)
		(pad "118" smd rect
			(at -2.050034 41.224962 90)
			(size 0.519938 1.4986)
			(layers "F.Cu" "F.Mask" "F.Paste")
			(net "M_L_CPU1_SB_DQ<12>")
		)
		(pad "119" smd rect
			(at -2.050034 42.0751 90)
			(size 0.519938 1.4986)
			(layers "F.Cu" "F.Mask" "F.Paste")
			(net "GND")
		)
		(pad "120" smd rect
			(at -2.050034 42.924984 90)
			(size 0.519938 1.4986)
			(layers "F.Cu" "F.Mask" "F.Paste")
			(net "M_L_CPU1_SB_DQ<13>")
		)
		(pad "121" smd rect
			(at -2.050034 43.775122 90)
			(size 0.519938 1.4986)
			(layers "F.Cu" "F.Mask" "F.Paste")
			(net "GND")
		)
		(pad "122" smd rect
			(at -2.050034 44.625006 90)
			(size 0.519938 1.4986)
			(layers "F.Cu" "F.Mask" "F.Paste")
			(net "M_L_CPU1_SB_DQ<16>")
		)
		(pad "123" smd rect
			(at -2.050034 45.47489 90)
			(size 0.519938 1.4986)
			(layers "F.Cu" "F.Mask" "F.Paste")
			(net "GND")
		)
		(pad "124" smd rect
			(at -2.050034 46.325028 90)
			(size 0.519938 1.4986)
			(layers "F.Cu" "F.Mask" "F.Paste")
			(net "M_L_CPU1_SB_DQ<17>")
		)
		(pad "125" smd rect
			(at -2.050034 47.174912 90)
			(size 0.519938 1.4986)
			(layers "F.Cu" "F.Mask" "F.Paste")
			(net "GND")
		)
		(pad "126" smd rect
			(at -2.050034 48.02505 90)
			(size 0.519938 1.4986)
			(layers "F.Cu" "F.Mask" "F.Paste")
			(net "M_L_CPU1_SB_DQS_DP<2>")
		)
		(pad "127" smd rect
			(at -2.050034 48.874934 90)
			(size 0.519938 1.4986)
			(layers "F.Cu" "F.Mask" "F.Paste")
			(net "M_L_CPU1_SB_DQS_DN<2>")
		)
		(pad "128" smd rect
			(at -2.050034 49.725072 90)
			(size 0.519938 1.4986)
			(layers "F.Cu" "F.Mask" "F.Paste")
			(net "GND")
		)
		(pad "129" smd rect
			(at -2.050034 50.574956 90)
			(size 0.519938 1.4986)
			(layers "F.Cu" "F.Mask" "F.Paste")
			(net "M_L_CPU1_SB_DQ<20>")
		)
		(pad "130" smd rect
			(at -2.050034 51.425094 90)
			(size 0.519938 1.4986)
			(layers "F.Cu" "F.Mask" "F.Paste")
			(net "GND")
		)
		(pad "131" smd rect
			(at -2.050034 52.274978 90)
			(size 0.519938 1.4986)
			(layers "F.Cu" "F.Mask" "F.Paste")
			(net "M_L_CPU1_SB_DQ<21>")
		)
		(pad "132" smd rect
			(at -2.050034 53.125116 90)
			(size 0.519938 1.4986)
			(layers "F.Cu" "F.Mask" "F.Paste")
			(net "GND")
		)
		(pad "133" smd rect
			(at -2.050034 53.975 90)
			(size 0.519938 1.4986)
			(layers "F.Cu" "F.Mask" "F.Paste")
			(net "M_L_CPU1_SB_DQ<24>")
		)
		(pad "134" smd rect
			(at -2.050034 54.824884 90)
			(size 0.519938 1.4986)
			(layers "F.Cu" "F.Mask" "F.Paste")
			(net "GND")
		)
		(pad "135" smd rect
			(at -2.050034 55.675022 90)
			(size 0.519938 1.4986)
			(layers "F.Cu" "F.Mask" "F.Paste")
			(net "M_L_CPU1_SB_DQ<25>")
		)
		(pad "136" smd rect
			(at -2.050034 56.524906 90)
			(size 0.519938 1.4986)
			(layers "F.Cu" "F.Mask" "F.Paste")
			(net "GND")
		)
		(pad "137" smd rect
			(at -2.050034 57.375044 90)
			(size 0.519938 1.4986)
			(layers "F.Cu" "F.Mask" "F.Paste")
			(net "M_L_CPU1_SB_DQS_DP<3>")
		)
		(pad "138" smd rect
			(at -2.050034 58.224928 90)
			(size 0.519938 1.4986)
			(layers "F.Cu" "F.Mask" "F.Paste")
			(net "M_L_CPU1_SB_DQS_DN<3>")
		)
		(pad "139" smd rect
			(at -2.050034 59.075066 90)
			(size 0.519938 1.4986)
			(layers "F.Cu" "F.Mask" "F.Paste")
			(net "GND")
		)
		(pad "140" smd rect
			(at -2.050034 59.92495 90)
			(size 0.519938 1.4986)
			(layers "F.Cu" "F.Mask" "F.Paste")
			(net "M_L_CPU1_SB_DQ<28>")
		)
		(pad "141" smd rect
			(at -2.050034 60.775088 90)
			(size 0.519938 1.4986)
			(layers "F.Cu" "F.Mask" "F.Paste")
			(net "GND")
		)
		(pad "142" smd rect
			(at -2.050034 61.624972 90)
			(size 0.519938 1.4986)
			(layers "F.Cu" "F.Mask" "F.Paste")
			(net "M_L_CPU1_SB_DQ<29>")
		)
		(pad "143" smd rect
			(at -2.050034 62.47511 90)
			(size 0.519938 1.4986)
			(layers "F.Cu" "F.Mask" "F.Paste")
			(net "GND")
		)
		(pad "144" smd rect
			(at -2.050034 63.324994 90)
			(size 0.519938 1.4986)
			(layers "F.Cu" "F.Mask" "F.Paste")
			(net "Net_2411")
		)
		(pad "145" smd rect
			(at 2.050034 -63.324994 90)
			(size 0.519938 1.4986)
			(layers "F.Cu" "F.Mask" "F.Paste")
			(net "P12V_MEM_CPU1")
		)
		(pad "146" smd rect
			(at 2.050034 -62.47511 90)
			(size 0.519938 1.4986)
			(layers "F.Cu" "F.Mask" "F.Paste")
			(net "P12V_MEM_CPU1")
		)
		(pad "147" smd rect
			(at 2.050034 -61.624972 90)
			(size 0.519938 1.4986)
			(layers "F.Cu" "F.Mask" "F.Paste")
			(net "PWRGD_CHL_CPU1_DIMM")
		)
		(pad "148" smd rect
			(at 2.050034 -60.775088 90)
			(size 0.519938 1.4986)
			(layers "F.Cu" "F.Mask" "F.Paste")
			(net "PD_CHL_CPU1_DIMM_SAA")
		)
		(pad "149" smd rect
			(at 2.050034 -59.92495 90)
			(size 0.519938 1.4986)
			(layers "F.Cu" "F.Mask" "F.Paste")
			(net "Net_2412")
		)
		(pad "150" smd rect
			(at 2.050034 -59.075066 90)
			(size 0.519938 1.4986)
			(layers "F.Cu" "F.Mask" "F.Paste")
			(net "Net_2413")
		)
		(pad "151" smd rect
			(at 2.050034 -58.224928 90)
			(size 0.519938 1.4986)
			(layers "F.Cu" "F.Mask" "F.Paste")
			(net "GND")
		)
		(pad "152" smd rect
			(at 2.050034 -57.375044 90)
			(size 0.519938 1.4986)
			(layers "F.Cu" "F.Mask" "F.Paste")
			(net "M_L_CPU1_SA_DQ<2>")
		)
		(pad "153" smd rect
			(at 2.050034 -56.524906 90)
			(size 0.519938 1.4986)
			(layers "F.Cu" "F.Mask" "F.Paste")
			(net "GND")
		)
		(pad "154" smd rect
			(at 2.050034 -55.675022 90)
			(size 0.519938 1.4986)
			(layers "F.Cu" "F.Mask" "F.Paste")
			(net "M_L_CPU1_SA_DQ<3>")
		)
		(pad "155" smd rect
			(at 2.050034 -54.824884 90)
			(size 0.519938 1.4986)
			(layers "F.Cu" "F.Mask" "F.Paste")
			(net "GND")
		)
		(pad "156" smd rect
			(at 2.050034 -53.975 90)
			(size 0.519938 1.4986)
			(layers "F.Cu" "F.Mask" "F.Paste")
			(net "M_L_CPU1_SA_DQS_DN<5>")
		)
		(pad "157" smd rect
			(at 2.050034 -53.125116 90)
			(size 0.519938 1.4986)
			(layers "F.Cu" "F.Mask" "F.Paste")
			(net "M_L_CPU1_SA_DQS_DP<5>")
		)
		(pad "158" smd rect
			(at 2.050034 -52.274978 90)
			(size 0.519938 1.4986)
			(layers "F.Cu" "F.Mask" "F.Paste")
			(net "GND")
		)
		(pad "159" smd rect
			(at 2.050034 -51.425094 90)
			(size 0.519938 1.4986)
			(layers "F.Cu" "F.Mask" "F.Paste")
			(net "M_L_CPU1_SA_DQ<6>")
		)
		(pad "160" smd rect
			(at 2.050034 -50.574956 90)
			(size 0.519938 1.4986)
			(layers "F.Cu" "F.Mask" "F.Paste")
			(net "GND")
		)
		(pad "161" smd rect
			(at 2.050034 -49.725072 90)
			(size 0.519938 1.4986)
			(layers "F.Cu" "F.Mask" "F.Paste")
			(net "M_L_CPU1_SA_DQ<7>")
		)
		(pad "162" smd rect
			(at 2.050034 -48.874934 90)
			(size 0.519938 1.4986)
			(layers "F.Cu" "F.Mask" "F.Paste")
			(net "GND")
		)
		(pad "163" smd rect
			(at 2.050034 -48.02505 90)
			(size 0.519938 1.4986)
			(layers "F.Cu" "F.Mask" "F.Paste")
			(net "M_L_CPU1_SA_DQ<10>")
		)
		(pad "164" smd rect
			(at 2.050034 -47.174912 90)
			(size 0.519938 1.4986)
			(layers "F.Cu" "F.Mask" "F.Paste")
			(net "GND")
		)
		(pad "165" smd rect
			(at 2.050034 -46.325028 90)
			(size 0.519938 1.4986)
			(layers "F.Cu" "F.Mask" "F.Paste")
			(net "M_L_CPU1_SA_DQ<11>")
		)
		(pad "166" smd rect
			(at 2.050034 -45.47489 90)
			(size 0.519938 1.4986)
			(layers "F.Cu" "F.Mask" "F.Paste")
			(net "GND")
		)
		(pad "167" smd rect
			(at 2.050034 -44.625006 90)
			(size 0.519938 1.4986)
			(layers "F.Cu" "F.Mask" "F.Paste")
			(net "M_L_CPU1_SA_DQS_DN<6>")
		)
		(pad "168" smd rect
			(at 2.050034 -43.775122 90)
			(size 0.519938 1.4986)
			(layers "F.Cu" "F.Mask" "F.Paste")
			(net "M_L_CPU1_SA_DQS_DP<6>")
		)
		(pad "169" smd rect
			(at 2.050034 -42.924984 90)
			(size 0.519938 1.4986)
			(layers "F.Cu" "F.Mask" "F.Paste")
			(net "GND")
		)
		(pad "170" smd rect
			(at 2.050034 -42.0751 90)
			(size 0.519938 1.4986)
			(layers "F.Cu" "F.Mask" "F.Paste")
			(net "M_L_CPU1_SA_DQ<14>")
		)
		(pad "171" smd rect
			(at 2.050034 -41.224962 90)
			(size 0.519938 1.4986)
			(layers "F.Cu" "F.Mask" "F.Paste")
			(net "GND")
		)
		(pad "172" smd rect
			(at 2.050034 -40.375078 90)
			(size 0.519938 1.4986)
			(layers "F.Cu" "F.Mask" "F.Paste")
			(net "M_L_CPU1_SA_DQ<15>")
		)
		(pad "173" smd rect
			(at 2.050034 -39.52494 90)
			(size 0.519938 1.4986)
			(layers "F.Cu" "F.Mask" "F.Paste")
			(net "GND")
		)
		(pad "174" smd rect
			(at 2.050034 -38.675056 90)
			(size 0.519938 1.4986)
			(layers "F.Cu" "F.Mask" "F.Paste")
			(net "M_L_CPU1_SA_DQ<18>")
		)
		(pad "175" smd rect
			(at 2.050034 -37.824918 90)
			(size 0.519938 1.4986)
			(layers "F.Cu" "F.Mask" "F.Paste")
			(net "GND")
		)
		(pad "176" smd rect
			(at 2.050034 -36.975034 90)
			(size 0.519938 1.4986)
			(layers "F.Cu" "F.Mask" "F.Paste")
			(net "M_L_CPU1_SA_DQ<19>")
		)
		(pad "177" smd rect
			(at 2.050034 -36.124896 90)
			(size 0.519938 1.4986)
			(layers "F.Cu" "F.Mask" "F.Paste")
			(net "GND")
		)
		(pad "178" smd rect
			(at 2.050034 -35.275012 90)
			(size 0.519938 1.4986)
			(layers "F.Cu" "F.Mask" "F.Paste")
			(net "M_L_CPU1_SA_DQS_DN<7>")
		)
		(pad "179" smd rect
			(at 2.050034 -34.425128 90)
			(size 0.519938 1.4986)
			(layers "F.Cu" "F.Mask" "F.Paste")
			(net "M_L_CPU1_SA_DQS_DP<7>")
		)
		(pad "180" smd rect
			(at 2.050034 -33.57499 90)
			(size 0.519938 1.4986)
			(layers "F.Cu" "F.Mask" "F.Paste")
			(net "GND")
		)
		(pad "181" smd rect
			(at 2.050034 -32.725106 90)
			(size 0.519938 1.4986)
			(layers "F.Cu" "F.Mask" "F.Paste")
			(net "M_L_CPU1_SA_DQ<22>")
		)
		(pad "182" smd rect
			(at 2.050034 -31.874968 90)
			(size 0.519938 1.4986)
			(layers "F.Cu" "F.Mask" "F.Paste")
			(net "GND")
		)
		(pad "183" smd rect
			(at 2.050034 -31.025084 90)
			(size 0.519938 1.4986)
			(layers "F.Cu" "F.Mask" "F.Paste")
			(net "M_L_CPU1_SA_DQ<23>")
		)
		(pad "184" smd rect
			(at 2.050034 -30.174946 90)
			(size 0.519938 1.4986)
			(layers "F.Cu" "F.Mask" "F.Paste")
			(net "GND")
		)
		(pad "185" smd rect
			(at 2.050034 -29.325062 90)
			(size 0.519938 1.4986)
			(layers "F.Cu" "F.Mask" "F.Paste")
			(net "M_L_CPU1_SA_DQ<26>")
		)
		(pad "186" smd rect
			(at 2.050034 -28.474924 90)
			(size 0.519938 1.4986)
			(layers "F.Cu" "F.Mask" "F.Paste")
			(net "GND")
		)
		(pad "187" smd rect
			(at 2.050034 -27.62504 90)
			(size 0.519938 1.4986)
			(layers "F.Cu" "F.Mask" "F.Paste")
			(net "M_L_CPU1_SA_DQ<27>")
		)
		(pad "188" smd rect
			(at 2.050034 -26.774902 90)
			(size 0.519938 1.4986)
			(layers "F.Cu" "F.Mask" "F.Paste")
			(net "GND")
		)
		(pad "189" smd rect
			(at 2.050034 -25.925018 90)
			(size 0.519938 1.4986)
			(layers "F.Cu" "F.Mask" "F.Paste")
			(net "M_L_CPU1_SA_DQS_DN<8>")
		)
		(pad "190" smd rect
			(at 2.050034 -25.07488 90)
			(size 0.519938 1.4986)
			(layers "F.Cu" "F.Mask" "F.Paste")
			(net "M_L_CPU1_SA_DQS_DP<8>")
		)
		(pad "191" smd rect
			(at 2.050034 -24.224996 90)
			(size 0.519938 1.4986)
			(layers "F.Cu" "F.Mask" "F.Paste")
			(net "GND")
		)
		(pad "192" smd rect
			(at 2.050034 -23.375112 90)
			(size 0.519938 1.4986)
			(layers "F.Cu" "F.Mask" "F.Paste")
			(net "M_L_CPU1_SA_DQ<30>")
		)
		(pad "193" smd rect
			(at 2.050034 -22.524974 90)
			(size 0.519938 1.4986)
			(layers "F.Cu" "F.Mask" "F.Paste")
			(net "GND")
		)
		(pad "194" smd rect
			(at 2.050034 -21.67509 90)
			(size 0.519938 1.4986)
			(layers "F.Cu" "F.Mask" "F.Paste")
			(net "M_L_CPU1_SA_DQ<31>")
		)
		(pad "195" smd rect
			(at 2.050034 -20.824952 90)
			(size 0.519938 1.4986)
			(layers "F.Cu" "F.Mask" "F.Paste")
			(net "GND")
		)
		(pad "196" smd rect
			(at 2.050034 -19.975068 90)
			(size 0.519938 1.4986)
			(layers "F.Cu" "F.Mask" "F.Paste")
			(net "M_L_CPU1_SA_CB<2>")
		)
		(pad "197" smd rect
			(at 2.050034 -19.12493 90)
			(size 0.519938 1.4986)
			(layers "F.Cu" "F.Mask" "F.Paste")
			(net "GND")
		)
		(pad "198" smd rect
			(at 2.050034 -18.275046 90)
			(size 0.519938 1.4986)
			(layers "F.Cu" "F.Mask" "F.Paste")
			(net "M_L_CPU1_SA_CB<3>")
		)
		(pad "199" smd rect
			(at 2.050034 -17.424908 90)
			(size 0.519938 1.4986)
			(layers "F.Cu" "F.Mask" "F.Paste")
			(net "GND")
		)
		(pad "200" smd rect
			(at 2.050034 -16.575024 90)
			(size 0.519938 1.4986)
			(layers "F.Cu" "F.Mask" "F.Paste")
			(net "M_L_CPU1_SA_DQS_DN<9>")
		)
		(pad "201" smd rect
			(at 2.050034 -15.724886 90)
			(size 0.519938 1.4986)
			(layers "F.Cu" "F.Mask" "F.Paste")
			(net "M_L_CPU1_SA_DQS_DP<9>")
		)
		(pad "202" smd rect
			(at 2.050034 -14.875002 90)
			(size 0.519938 1.4986)
			(layers "F.Cu" "F.Mask" "F.Paste")
			(net "GND")
		)
		(pad "203" smd rect
			(at 2.050034 -14.025118 90)
			(size 0.519938 1.4986)
			(layers "F.Cu" "F.Mask" "F.Paste")
			(net "M_L_CPU1_SA_CB<6>")
		)
		(pad "204" smd rect
			(at 2.050034 -13.17498 90)
			(size 0.519938 1.4986)
			(layers "F.Cu" "F.Mask" "F.Paste")
			(net "GND")
		)
		(pad "205" smd rect
			(at 2.050034 -12.325096 90)
			(size 0.519938 1.4986)
			(layers "F.Cu" "F.Mask" "F.Paste")
			(net "M_L_CPU1_SA_CB<7>")
		)
		(pad "206" smd rect
			(at 2.050034 -11.474958 90)
			(size 0.519938 1.4986)
			(layers "F.Cu" "F.Mask" "F.Paste")
			(net "GND")
		)
		(pad "207" smd rect
			(at 2.050034 -10.625074 90)
			(size 0.519938 1.4986)
			(layers "F.Cu" "F.Mask" "F.Paste")
			(net "M_L_CPU1_RESET_N")
		)
		(pad "208" smd rect
			(at 2.050034 -9.774936 90)
			(size 0.519938 1.4986)
			(layers "F.Cu" "F.Mask" "F.Paste")
			(net "GND")
		)
		(pad "209" smd rect
			(at 2.050034 -8.925052 90)
			(size 0.519938 1.4986)
			(layers "F.Cu" "F.Mask" "F.Paste")
			(net "M_L_CPU1_SA_CS_N<1>")
		)
		(pad "210" smd rect
			(at 2.050034 -8.074914 90)
			(size 0.519938 1.4986)
			(layers "F.Cu" "F.Mask" "F.Paste")
			(net "GND")
		)
		(pad "211" smd rect
			(at 2.050034 -7.22503 90)
			(size 0.519938 1.4986)
			(layers "F.Cu" "F.Mask" "F.Paste")
			(net "M_L_CPU1_SA_CA<1>")
		)
		(pad "212" smd rect
			(at 2.050034 -6.374892 90)
			(size 0.519938 1.4986)
			(layers "F.Cu" "F.Mask" "F.Paste")
			(net "GND")
		)
		(pad "213" smd rect
			(at 2.050034 -5.525008 90)
			(size 0.519938 1.4986)
			(layers "F.Cu" "F.Mask" "F.Paste")
			(net "M_L_CPU1_SA_CA<3>")
		)
		(pad "214" smd rect
			(at 2.050034 -4.675124 90)
			(size 0.519938 1.4986)
			(layers "F.Cu" "F.Mask" "F.Paste")
			(net "GND")
		)
		(pad "215" smd rect
			(at 2.050034 -3.824986 90)
			(size 0.519938 1.4986)
			(layers "F.Cu" "F.Mask" "F.Paste")
			(net "M_L_CPU1_SA_CA<5>")
		)
		(pad "216" smd rect
			(at 2.050034 -2.975102 90)
			(size 0.519938 1.4986)
			(layers "F.Cu" "F.Mask" "F.Paste")
			(net "GND")
		)
		(pad "217" smd rect
			(at 2.050034 -2.124964 90)
			(size 0.519938 1.4986)
			(layers "F.Cu" "F.Mask" "F.Paste")
			(net "M_L_CPU1_CLK_DP<0>")
		)
		(pad "218" smd rect
			(at 2.050034 -1.27508 90)
			(size 0.519938 1.4986)
			(layers "F.Cu" "F.Mask" "F.Paste")
			(net "M_L_CPU1_CLK_DN<0>")
		)
		(pad "219" smd rect
			(at 2.050034 -0.424942 90)
			(size 0.519938 1.4986)
			(layers "F.Cu" "F.Mask" "F.Paste")
			(net "GND")
		)
		(pad "220" smd rect
			(at 2.050034 5.525008 90)
			(size 0.519938 1.4986)
			(layers "F.Cu" "F.Mask" "F.Paste")
			(net "Net_2414")
		)
		(pad "221" smd rect
			(at 2.050034 6.374892 90)
			(size 0.519938 1.4986)
			(layers "F.Cu" "F.Mask" "F.Paste")
			(net "M_L_CPU1_SB_CA<1>")
		)
		(pad "222" smd rect
			(at 2.050034 7.22503 90)
			(size 0.519938 1.4986)
			(layers "F.Cu" "F.Mask" "F.Paste")
			(net "GND")
		)
		(pad "223" smd rect
			(at 2.050034 8.074914 90)
			(size 0.519938 1.4986)
			(layers "F.Cu" "F.Mask" "F.Paste")
			(net "M_L_CPU1_SB_CA<3>")
		)
		(pad "224" smd rect
			(at 2.050034 8.925052 90)
			(size 0.519938 1.4986)
			(layers "F.Cu" "F.Mask" "F.Paste")
			(net "GND")
		)
		(pad "225" smd rect
			(at 2.050034 9.774936 90)
			(size 0.519938 1.4986)
			(layers "F.Cu" "F.Mask" "F.Paste")
			(net "M_L_CPU1_SB_CA<5>")
		)
		(pad "226" smd rect
			(at 2.050034 10.625074 90)
			(size 0.519938 1.4986)
			(layers "F.Cu" "F.Mask" "F.Paste")
			(net "GND")
		)
		(pad "227" smd rect
			(at 2.050034 11.474958 90)
			(size 0.519938 1.4986)
			(layers "F.Cu" "F.Mask" "F.Paste")
			(net "M_L_CPU1_SB_PAR")
		)
		(pad "228" smd rect
			(at 2.050034 12.325096 90)
			(size 0.519938 1.4986)
			(layers "F.Cu" "F.Mask" "F.Paste")
			(net "GND")
		)
		(pad "229" smd rect
			(at 2.050034 13.17498 90)
			(size 0.519938 1.4986)
			(layers "F.Cu" "F.Mask" "F.Paste")
			(net "M_L_CPU1_SB_CS_N<1>")
		)
		(pad "230" smd rect
			(at 2.050034 14.025118 90)
			(size 0.519938 1.4986)
			(layers "F.Cu" "F.Mask" "F.Paste")
			(net "GND")
		)
		(pad "231" smd rect
			(at 2.050034 14.875002 90)
			(size 0.519938 1.4986)
			(layers "F.Cu" "F.Mask" "F.Paste")
			(net "Net_2415")
		)
		(pad "232" smd rect
			(at 2.050034 15.724886 90)
			(size 0.519938 1.4986)
			(layers "F.Cu" "F.Mask" "F.Paste")
			(net "Net_2416")
		)
		(pad "233" smd rect
			(at 2.050034 16.575024 90)
			(size 0.519938 1.4986)
			(layers "F.Cu" "F.Mask" "F.Paste")
			(net "GND")
		)
		(pad "234" smd rect
			(at 2.050034 17.424908 90)
			(size 0.519938 1.4986)
			(layers "F.Cu" "F.Mask" "F.Paste")
			(net "M_L_CPU1_SB_CB<6>")
		)
		(pad "235" smd rect
			(at 2.050034 18.275046 90)
			(size 0.519938 1.4986)
			(layers "F.Cu" "F.Mask" "F.Paste")
			(net "GND")
		)
		(pad "236" smd rect
			(at 2.050034 19.12493 90)
			(size 0.519938 1.4986)
			(layers "F.Cu" "F.Mask" "F.Paste")
			(net "M_L_CPU1_SB_CB<7>")
		)
		(pad "237" smd rect
			(at 2.050034 19.975068 90)
			(size 0.519938 1.4986)
			(layers "F.Cu" "F.Mask" "F.Paste")
			(net "GND")
		)
		(pad "238" smd rect
			(at 2.050034 20.824952 90)
			(size 0.519938 1.4986)
			(layers "F.Cu" "F.Mask" "F.Paste")
			(net "M_L_CPU1_SB_DQS_DN<4>")
		)
		(pad "239" smd rect
			(at 2.050034 21.67509 90)
			(size 0.519938 1.4986)
			(layers "F.Cu" "F.Mask" "F.Paste")
			(net "M_L_CPU1_SB_DQS_DP<4>")
		)
		(pad "240" smd rect
			(at 2.050034 22.524974 90)
			(size 0.519938 1.4986)
			(layers "F.Cu" "F.Mask" "F.Paste")
			(net "GND")
		)
		(pad "241" smd rect
			(at 2.050034 23.375112 90)
			(size 0.519938 1.4986)
			(layers "F.Cu" "F.Mask" "F.Paste")
			(net "M_L_CPU1_SB_CB<2>")
		)
		(pad "242" smd rect
			(at 2.050034 24.224996 90)
			(size 0.519938 1.4986)
			(layers "F.Cu" "F.Mask" "F.Paste")
			(net "GND")
		)
		(pad "243" smd rect
			(at 2.050034 25.07488 90)
			(size 0.519938 1.4986)
			(layers "F.Cu" "F.Mask" "F.Paste")
			(net "M_L_CPU1_SB_CB<3>")
		)
		(pad "244" smd rect
			(at 2.050034 25.925018 90)
			(size 0.519938 1.4986)
			(layers "F.Cu" "F.Mask" "F.Paste")
			(net "GND")
		)
		(pad "245" smd rect
			(at 2.050034 26.774902 90)
			(size 0.519938 1.4986)
			(layers "F.Cu" "F.Mask" "F.Paste")
			(net "M_L_CPU1_SB_DQ<2>")
		)
		(pad "246" smd rect
			(at 2.050034 27.62504 90)
			(size 0.519938 1.4986)
			(layers "F.Cu" "F.Mask" "F.Paste")
			(net "GND")
		)
		(pad "247" smd rect
			(at 2.050034 28.474924 90)
			(size 0.519938 1.4986)
			(layers "F.Cu" "F.Mask" "F.Paste")
			(net "M_L_CPU1_SB_DQ<3>")
		)
		(pad "248" smd rect
			(at 2.050034 29.325062 90)
			(size 0.519938 1.4986)
			(layers "F.Cu" "F.Mask" "F.Paste")
			(net "GND")
		)
		(pad "249" smd rect
			(at 2.050034 30.174946 90)
			(size 0.519938 1.4986)
			(layers "F.Cu" "F.Mask" "F.Paste")
			(net "M_L_CPU1_SB_DQS_DN<5>")
		)
		(pad "250" smd rect
			(at 2.050034 31.025084 90)
			(size 0.519938 1.4986)
			(layers "F.Cu" "F.Mask" "F.Paste")
			(net "M_L_CPU1_SB_DQS_DP<5>")
		)
		(pad "251" smd rect
			(at 2.050034 31.874968 90)
			(size 0.519938 1.4986)
			(layers "F.Cu" "F.Mask" "F.Paste")
			(net "GND")
		)
		(pad "252" smd rect
			(at 2.050034 32.725106 90)
			(size 0.519938 1.4986)
			(layers "F.Cu" "F.Mask" "F.Paste")
			(net "M_L_CPU1_SB_DQ<6>")
		)
		(pad "253" smd rect
			(at 2.050034 33.57499 90)
			(size 0.519938 1.4986)
			(layers "F.Cu" "F.Mask" "F.Paste")
			(net "GND")
		)
		(pad "254" smd rect
			(at 2.050034 34.425128 90)
			(size 0.519938 1.4986)
			(layers "F.Cu" "F.Mask" "F.Paste")
			(net "M_L_CPU1_SB_DQ<7>")
		)
		(pad "255" smd rect
			(at 2.050034 35.275012 90)
			(size 0.519938 1.4986)
			(layers "F.Cu" "F.Mask" "F.Paste")
			(net "GND")
		)
		(pad "256" smd rect
			(at 2.050034 36.124896 90)
			(size 0.519938 1.4986)
			(layers "F.Cu" "F.Mask" "F.Paste")
			(net "M_L_CPU1_SB_DQ<10>")
		)
		(pad "257" smd rect
			(at 2.050034 36.975034 90)
			(size 0.519938 1.4986)
			(layers "F.Cu" "F.Mask" "F.Paste")
			(net "GND")
		)
		(pad "258" smd rect
			(at 2.050034 37.824918 90)
			(size 0.519938 1.4986)
			(layers "F.Cu" "F.Mask" "F.Paste")
			(net "M_L_CPU1_SB_DQ<11>")
		)
		(pad "259" smd rect
			(at 2.050034 38.675056 90)
			(size 0.519938 1.4986)
			(layers "F.Cu" "F.Mask" "F.Paste")
			(net "GND")
		)
		(pad "260" smd rect
			(at 2.050034 39.52494 90)
			(size 0.519938 1.4986)
			(layers "F.Cu" "F.Mask" "F.Paste")
			(net "M_L_CPU1_SB_DQS_DN<6>")
		)
		(pad "261" smd rect
			(at 2.050034 40.375078 90)
			(size 0.519938 1.4986)
			(layers "F.Cu" "F.Mask" "F.Paste")
			(net "M_L_CPU1_SB_DQS_DP<6>")
		)
		(pad "262" smd rect
			(at 2.050034 41.224962 90)
			(size 0.519938 1.4986)
			(layers "F.Cu" "F.Mask" "F.Paste")
			(net "GND")
		)
		(pad "263" smd rect
			(at 2.050034 42.0751 90)
			(size 0.519938 1.4986)
			(layers "F.Cu" "F.Mask" "F.Paste")
			(net "M_L_CPU1_SB_DQ<14>")
		)
		(pad "264" smd rect
			(at 2.050034 42.924984 90)
			(size 0.519938 1.4986)
			(layers "F.Cu" "F.Mask" "F.Paste")
			(net "GND")
		)
		(pad "265" smd rect
			(at 2.050034 43.775122 90)
			(size 0.519938 1.4986)
			(layers "F.Cu" "F.Mask" "F.Paste")
			(net "M_L_CPU1_SB_DQ<15>")
		)
		(pad "266" smd rect
			(at 2.050034 44.625006 90)
			(size 0.519938 1.4986)
			(layers "F.Cu" "F.Mask" "F.Paste")
			(net "GND")
		)
		(pad "267" smd rect
			(at 2.050034 45.47489 90)
			(size 0.519938 1.4986)
			(layers "F.Cu" "F.Mask" "F.Paste")
			(net "M_L_CPU1_SB_DQ<18>")
		)
		(pad "268" smd rect
			(at 2.050034 46.325028 90)
			(size 0.519938 1.4986)
			(layers "F.Cu" "F.Mask" "F.Paste")
			(net "GND")
		)
		(pad "269" smd rect
			(at 2.050034 47.174912 90)
			(size 0.519938 1.4986)
			(layers "F.Cu" "F.Mask" "F.Paste")
			(net "M_L_CPU1_SB_DQ<19>")
		)
		(pad "270" smd rect
			(at 2.050034 48.02505 90)
			(size 0.519938 1.4986)
			(layers "F.Cu" "F.Mask" "F.Paste")
			(net "GND")
		)
		(pad "271" smd rect
			(at 2.050034 48.874934 90)
			(size 0.519938 1.4986)
			(layers "F.Cu" "F.Mask" "F.Paste")
			(net "M_L_CPU1_SB_DQS_DN<7>")
		)
		(pad "272" smd rect
			(at 2.050034 49.725072 90)
			(size 0.519938 1.4986)
			(layers "F.Cu" "F.Mask" "F.Paste")
			(net "M_L_CPU1_SB_DQS_DP<7>")
		)
		(pad "273" smd rect
			(at 2.050034 50.574956 90)
			(size 0.519938 1.4986)
			(layers "F.Cu" "F.Mask" "F.Paste")
			(net "GND")
		)
		(pad "274" smd rect
			(at 2.050034 51.425094 90)
			(size 0.519938 1.4986)
			(layers "F.Cu" "F.Mask" "F.Paste")
			(net "M_L_CPU1_SB_DQ<22>")
		)
		(pad "275" smd rect
			(at 2.050034 52.274978 90)
			(size 0.519938 1.4986)
			(layers "F.Cu" "F.Mask" "F.Paste")
			(net "GND")
		)
		(pad "276" smd rect
			(at 2.050034 53.125116 90)
			(size 0.519938 1.4986)
			(layers "F.Cu" "F.Mask" "F.Paste")
			(net "M_L_CPU1_SB_DQ<23>")
		)
		(pad "277" smd rect
			(at 2.050034 53.975 90)
			(size 0.519938 1.4986)
			(layers "F.Cu" "F.Mask" "F.Paste")
			(net "GND")
		)
		(pad "278" smd rect
			(at 2.050034 54.824884 90)
			(size 0.519938 1.4986)
			(layers "F.Cu" "F.Mask" "F.Paste")
			(net "M_L_CPU1_SB_DQ<26>")
		)
		(pad "279" smd rect
			(at 2.050034 55.675022 90)
			(size 0.519938 1.4986)
			(layers "F.Cu" "F.Mask" "F.Paste")
			(net "GND")
		)
		(pad "280" smd rect
			(at 2.050034 56.524906 90)
			(size 0.519938 1.4986)
			(layers "F.Cu" "F.Mask" "F.Paste")
			(net "M_L_CPU1_SB_DQ<27>")
		)
		(pad "281" smd rect
			(at 2.050034 57.375044 90)
			(size 0.519938 1.4986)
			(layers "F.Cu" "F.Mask" "F.Paste")
			(net "GND")
		)
		(pad "282" smd rect
			(at 2.050034 58.224928 90)
			(size 0.519938 1.4986)
			(layers "F.Cu" "F.Mask" "F.Paste")
			(net "M_L_CPU1_SB_DQS_DN<8>")
		)
		(pad "283" smd rect
			(at 2.050034 59.075066 90)
			(size 0.519938 1.4986)
			(layers "F.Cu" "F.Mask" "F.Paste")
			(net "M_L_CPU1_SB_DQS_DP<8>")
		)
		(pad "284" smd rect
			(at 2.050034 59.92495 90)
			(size 0.519938 1.4986)
			(layers "F.Cu" "F.Mask" "F.Paste")
			(net "GND")
		)
		(pad "285" smd rect
			(at 2.050034 60.775088 90)
			(size 0.519938 1.4986)
			(layers "F.Cu" "F.Mask" "F.Paste")
			(net "M_L_CPU1_SB_DQ<30>")
		)
		(pad "286" smd rect
			(at 2.050034 61.624972 90)
			(size 0.519938 1.4986)
			(layers "F.Cu" "F.Mask" "F.Paste")
			(net "GND")
		)
		(pad "287" smd rect
			(at 2.050034 62.47511 90)
			(size 0.519938 1.4986)
			(layers "F.Cu" "F.Mask" "F.Paste")
			(net "M_L_CPU1_SB_DQ<31>")
		)
		(pad "288" smd rect
			(at 2.050034 63.324994 90)
			(size 0.519938 1.4986)
			(layers "F.Cu" "F.Mask" "F.Paste")
			(net "GND")
		)
		(pad "G1" thru_hole oval
			(at 0 -68.97497 90)
			(size 1.7272 3.4798)
			(drill oval 1.2192 2.4638)
			(layers "*.Cu" "*.Mask")
			(remove_unused_layers no)
			(net "GND")
			(clearance 0.127)
			(thermal_gap 0.127)
		)
		(pad "G2" thru_hole oval
			(at 0 3.875024 90)
			(size 1.7272 3.4798)
			(drill oval 1.2192 2.4638)
			(layers "*.Cu" "*.Mask")
			(remove_unused_layers no)
			(net "GND")
			(clearance 0.127)
			(thermal_gap 0.127)
		)
		(pad "G3" thru_hole oval
			(at 0 68.97497 90)
			(size 1.7272 3.4798)
			(drill oval 1.2192 2.4638)
			(layers "*.Cu" "*.Mask")
			(remove_unused_layers no)
			(net "GND")
			(clearance 0.127)
			(thermal_gap 0.127)
		)
	)
	(footprint ""
		(layer "F.Cu")
		(at 336.622644 -383.88163 -90)
		(property "Reference" "C957"
			(at 0 0 270)
			(layer "F.SilkS")
			(hide yes)
			(effects
				(font
					(size 1.27 1.27)
				)
			)
		)
		(property "Value" ""
			(at 0 0 270)
			(layer "F.Fab")
			(effects
				(font
					(size 1.27 1.27)
				)
			)
		)
		(duplicate_pad_numbers_are_jumpers no)
		(fp_line
			(start -0.299974 0.150114)
			(end -0.299974 -0.150114)
			(stroke
				(width 0.1)
				(type default)
			)
			(layer "F.Fab")
		)
		(fp_line
			(start 0.299974 0.150114)
			(end -0.299974 0.150114)
			(stroke
				(width 0.1)
				(type default)
			)
			(layer "F.Fab")
		)
		(fp_line
			(start -0.299974 -0.150114)
			(end 0.299974 -0.150114)
			(stroke
				(width 0.1)
				(type default)
			)
			(layer "F.Fab")
		)
		(fp_line
			(start 0.299974 -0.150114)
			(end 0.299974 0.150114)
			(stroke
				(width 0.1)
				(type default)
			)
			(layer "F.Fab")
		)
		(pad "1" smd rect
			(at -0.2667 0 270)
			(size 0.3048 0.381)
			(layers "F.Cu" "F.Mask" "F.Paste")
			(net "P5E_CPU0_P1_TX_C_DP<4>")
		)
		(pad "2" smd rect
			(at 0.2667 0 270)
			(size 0.3048 0.381)
			(layers "F.Cu" "F.Mask" "F.Paste")
			(net "P5E_CPU0_P1_TX_DP<4>")
		)
	)
	(footprint ""
		(layer "F.Cu")
		(at 66.42862 -394.78458 90)
		(property "Reference" "R699"
			(at 0 0 90)
			(layer "F.SilkS")
			(hide yes)
			(effects
				(font
					(size 1.27 1.27)
				)
			)
		)
		(property "Value" ""
			(at 0 0 90)
			(layer "F.Fab")
			(effects
				(font
					(size 1.27 1.27)
				)
			)
		)
		(duplicate_pad_numbers_are_jumpers no)
		(fp_line
			(start 0.32512 -0.175006)
			(end 0.32512 0.175006)
			(stroke
				(width 0.1)
				(type default)
			)
			(layer "F.Fab")
		)
		(fp_line
			(start -0.32512 -0.175006)
			(end 0.32512 -0.175006)
			(stroke
				(width 0.1)
				(type default)
			)
			(layer "F.Fab")
		)
		(fp_line
			(start 0.32512 0.175006)
			(end -0.32512 0.175006)
			(stroke
				(width 0.1)
				(type default)
			)
			(layer "F.Fab")
		)
		(fp_line
			(start -0.32512 0.175006)
			(end -0.32512 -0.175006)
			(stroke
				(width 0.1)
				(type default)
			)
			(layer "F.Fab")
		)
		(pad "1" smd rect
			(at -0.2667 0 90)
			(size 0.3048 0.381)
			(layers "F.Cu" "F.Mask" "F.Paste")
			(net "P1V8_CPU1_RT_1D")
		)
		(pad "2" smd rect
			(at 0.2667 0 270)
			(size 0.3048 0.381)
			(layers "F.Cu" "F.Mask" "F.Paste")
			(net "RT_CPU1_P0_VQPS")
		)
	)
	(footprint ""
		(layer "F.Cu")
		(at 133.223 -112.268)
		(property "Reference" "U8008"
			(at -1.405382 -3.298444 0)
			(unlocked yes)
			(layer "F.SilkS")
			(effects
				(font
					(size 0.7874 0.5842)
					(thickness 0.1524)
				)
			)
		)
		(property "Value" ""
			(at 0 0 0)
			(layer "F.Fab")
			(effects
				(font
					(size 1.27 1.27)
				)
			)
		)
		(duplicate_pad_numbers_are_jumpers no)
		(fp_line
			(start -2.032 -1.549908)
			(end -0.508 -1.549908)
			(stroke
				(width 0.1524)
				(type default)
			)
			(layer "F.SilkS")
		)
		(fp_line
			(start -2.032 1.549908)
			(end -2.032 -1.549908)
			(stroke
				(width 0.1524)
				(type default)
			)
			(layer "F.SilkS")
		)
		(fp_line
			(start -0.508 -1.549908)
			(end 0 -0.762)
			(stroke
				(width 0.1524)
				(type default)
			)
			(layer "F.SilkS")
		)
		(fp_line
			(start 0 -0.762)
			(end 0.508 -1.549908)
			(stroke
				(width 0.1524)
				(type default)
			)
			(layer "F.SilkS")
		)
		(fp_line
			(start 0.508 -1.549908)
			(end 2.032 -1.549908)
			(stroke
				(width 0.1524)
				(type default)
			)
			(layer "F.SilkS")
		)
		(fp_line
			(start 2.032 -1.549908)
			(end 2.032 1.549908)
			(stroke
				(width 0.1524)
				(type default)
			)
			(layer "F.SilkS")
		)
		(fp_line
			(start 2.032 1.549908)
			(end -2.032 1.549908)
			(stroke
				(width 0.1524)
				(type default)
			)
			(layer "F.SilkS")
		)
		(fp_poly
			(pts
				(xy -2.78003 -2.518918) (xy -3.441192 -1.74752) (xy -2.339086 -1.47193)
			)
			(stroke
				(width 0)
				(type default)
			)
			(fill yes)
			(layer "F.SilkS")
		)
		(fp_line
			(start -0.849884 -1.549908)
			(end 0.849884 -1.549908)
			(stroke
				(width 0.1)
				(type default)
			)
			(layer "F.Fab")
		)
		(fp_line
			(start -0.849884 1.549908)
			(end -0.849884 -1.549908)
			(stroke
				(width 0.1)
				(type default)
			)
			(layer "F.Fab")
		)
		(fp_line
			(start 0.849884 -1.549908)
			(end 0.849884 1.549908)
			(stroke
				(width 0.1)
				(type default)
			)
			(layer "F.Fab")
		)
		(fp_line
			(start 0.849884 1.549908)
			(end -0.849884 1.549908)
			(stroke
				(width 0.1)
				(type default)
			)
			(layer "F.Fab")
		)
		(fp_poly
			(pts
				(xy -3.2004 -1.45796) (xy -3.2004 -0.44196) (xy -2.1844 -0.94996)
			)
			(stroke
				(width 0)
				(type default)
			)
			(fill yes)
			(layer "F.Fab")
		)
		(pad "1" smd rect
			(at -1.35001 -0.94996 270)
			(size 0.6096 1.0668)
			(layers "F.Cu" "F.Mask" "F.Paste")
			(net "UV_ADR_P2V5_COMP")
		)
		(pad "2" smd rect
			(at -1.35001 0 270)
			(size 0.6096 1.0668)
			(layers "F.Cu" "F.Mask" "F.Paste")
			(net "GND")
		)
		(pad "3" smd rect
			(at -1.35001 0.94996 270)
			(size 0.6096 1.0668)
			(layers "F.Cu" "F.Mask" "F.Paste")
			(net "P12V_AUX_UV_ADR_TRIGGER")
		)
		(pad "4" smd rect
			(at 1.35001 0.94996 270)
			(size 0.6096 1.0668)
			(layers "F.Cu" "F.Mask" "F.Paste")
			(net "FM_UV_ADR_TRIGGER_N_R2")
		)
		(pad "5" smd rect
			(at 1.35001 -0.94996 270)
			(size 0.6096 1.0668)
			(layers "F.Cu" "F.Mask" "F.Paste")
			(net "P12V_AUX")
		)
	)
	(footprint ""
		(layer "F.Cu")
		(at 24.923496 -344.986864 90)
		(property "Reference" "PR491"
			(at 0 0 90)
			(layer "F.SilkS")
			(hide yes)
			(effects
				(font
					(size 1.27 1.27)
				)
			)
		)
		(property "Value" ""
			(at 0 0 90)
			(layer "F.Fab")
			(effects
				(font
					(size 1.27 1.27)
				)
			)
		)
		(duplicate_pad_numbers_are_jumpers no)
		(fp_line
			(start 0.7874 -0.4064)
			(end 0.7874 0.4064)
			(stroke
				(width 0.1524)
				(type default)
			)
			(layer "F.SilkS")
		)
		(fp_line
			(start -0.7874 -0.4064)
			(end 0.7874 -0.4064)
			(stroke
				(width 0.1524)
				(type default)
			)
			(layer "F.SilkS")
		)
		(fp_line
			(start 0.7874 0.4064)
			(end -0.7874 0.4064)
			(stroke
				(width 0.1524)
				(type default)
			)
			(layer "F.SilkS")
		)
		(fp_line
			(start -0.7874 0.4064)
			(end -0.7874 -0.4064)
			(stroke
				(width 0.1524)
				(type default)
			)
			(layer "F.SilkS")
		)
		(fp_line
			(start -0.12065 -0.305054)
			(end -0.12065 -0.2794)
			(stroke
				(width 0.1)
				(type default)
			)
			(layer "F.Fab")
		)
		(fp_line
			(start -0.67945 -0.305054)
			(end -0.12065 -0.305054)
			(stroke
				(width 0.1)
				(type default)
			)
			(layer "F.Fab")
		)
		(fp_line
			(start 0.67945 -0.3048)
			(end 0.67945 0.3048)
			(stroke
				(width 0.1)
				(type default)
			)
			(layer "F.Fab")
		)
		(fp_line
			(start 0.12065 -0.3048)
			(end 0.67945 -0.3048)
			(stroke
				(width 0.1)
				(type default)
			)
			(layer "F.Fab")
		)
		(fp_line
			(start 0.12065 -0.2794)
			(end 0.12065 -0.3048)
			(stroke
				(width 0.1)
				(type default)
			)
			(layer "F.Fab")
		)
		(fp_line
			(start -0.12065 -0.2794)
			(end 0.12065 -0.2794)
			(stroke
				(width 0.1)
				(type default)
			)
			(layer "F.Fab")
		)
		(fp_line
			(start 0.120396 0.2794)
			(end -0.12065 0.2794)
			(stroke
				(width 0.1)
				(type default)
			)
			(layer "F.Fab")
		)
		(fp_line
			(start -0.12065 0.2794)
			(end -0.12065 0.3048)
			(stroke
				(width 0.1)
				(type default)
			)
			(layer "F.Fab")
		)
		(fp_line
			(start 0.67945 0.3048)
			(end 0.120396 0.3048)
			(stroke
				(width 0.1)
				(type default)
			)
			(layer "F.Fab")
		)
		(fp_line
			(start 0.120396 0.3048)
			(end 0.120396 0.2794)
			(stroke
				(width 0.1)
				(type default)
			)
			(layer "F.Fab")
		)
		(fp_line
			(start -0.12065 0.3048)
			(end -0.67945 0.3048)
			(stroke
				(width 0.1)
				(type default)
			)
			(layer "F.Fab")
		)
		(fp_line
			(start -0.67945 0.3048)
			(end -0.67945 -0.305054)
			(stroke
				(width 0.1)
				(type default)
			)
			(layer "F.Fab")
		)
		(pad "1" smd circle
			(at -0.40005 0 90)
			(size 0 0)
			(layers "F.Cu" "F.Mask" "F.Paste")
			(net "SW_PVDDIO_P1_SW4_RC")
		)
		(pad "2" smd circle
			(at 0.40005 0 90)
			(size 0 0)
			(layers "F.Cu" "F.Mask" "F.Paste")
			(net "GND")
		)
	)
	(footprint ""
		(layer "F.Cu")
		(at 90.563954 -192.038732 180)
		(property "Reference" "PL29"
			(at -14.231112 3.341878 90)
			(unlocked yes)
			(layer "F.SilkS")
			(effects
				(font
					(size 0.7874 0.5842)
					(thickness 0.1524)
				)
				(justify left)
			)
		)
		(property "Value" ""
			(at 0 0 180)
			(layer "F.Fab")
			(effects
				(font
					(size 1.27 1.27)
				)
			)
		)
		(duplicate_pad_numbers_are_jumpers no)
		(fp_line
			(start 3.750056 5.500116)
			(end 3.750056 -5.500116)
			(stroke
				(width 0.1524)
				(type default)
			)
			(layer "F.SilkS")
		)
		(fp_line
			(start 3.750056 -5.500116)
			(end 2.393442 -5.500116)
			(stroke
				(width 0.1524)
				(type default)
			)
			(layer "F.SilkS")
		)
		(fp_line
			(start 2.393442 5.500116)
			(end 3.750056 5.500116)
			(stroke
				(width 0.1524)
				(type default)
			)
			(layer "F.SilkS")
		)
		(fp_line
			(start -2.393442 5.500116)
			(end -3.750056 5.500116)
			(stroke
				(width 0.1524)
				(type default)
			)
			(layer "F.SilkS")
		)
		(fp_line
			(start -3.750056 5.500116)
			(end -3.750056 -5.500116)
			(stroke
				(width 0.1524)
				(type default)
			)
			(layer "F.SilkS")
		)
		(fp_line
			(start -3.750056 -5.500116)
			(end -2.393442 -5.500116)
			(stroke
				(width 0.1524)
				(type default)
			)
			(layer "F.SilkS")
		)
		(fp_poly
			(pts
				(xy -3.9116 -4.249928) (xy -4.445 -3.983228) (xy -4.445 -4.516628)
			)
			(stroke
				(width 0)
				(type default)
			)
			(fill yes)
			(layer "F.SilkS")
		)
		(fp_line
			(start 3.750056 5.500116)
			(end 3.750056 -5.500116)
			(stroke
				(width 0.1)
				(type default)
			)
			(layer "F.Fab")
		)
		(fp_line
			(start 3.750056 -5.500116)
			(end -3.750056 -5.500116)
			(stroke
				(width 0.1)
				(type default)
			)
			(layer "F.Fab")
		)
		(fp_line
			(start -3.750056 5.500116)
			(end 3.750056 5.500116)
			(stroke
				(width 0.1)
				(type default)
			)
			(layer "F.Fab")
		)
		(fp_line
			(start -3.750056 -5.500116)
			(end -3.750056 5.500116)
			(stroke
				(width 0.1)
				(type default)
			)
			(layer "F.Fab")
		)
		(fp_poly
			(pts
				(xy -4.9276 -4.757928) (xy -4.9276 -3.741928) (xy -3.9116 -4.249928)
			)
			(stroke
				(width 0)
				(type default)
			)
			(fill yes)
			(layer "F.Fab")
		)
		(pad "1" smd rect
			(at 0 -4.249928 90)
			(size 2.413 4.5212)
			(layers "F.Cu" "F.Mask" "F.Paste")
			(net "SW_PVDDCR_CPU0_P1_SW2")
		)
		(pad "2" smd rect
			(at 0 -1.175004 90)
			(size 1.3716 4.5212)
			(layers "F.Cu" "F.Mask" "F.Paste")
			(net "IND_CPU0_P1_CPL1")
		)
		(pad "3" smd rect
			(at 0 1.175004 90)
			(size 1.3716 4.5212)
			(layers "F.Cu" "F.Mask" "F.Paste")
			(net "IND_CPU0_P1_CPL2")
		)
		(pad "4" smd rect
			(at 0 4.249928 90)
			(size 2.413 4.5212)
			(layers "F.Cu" "F.Mask" "F.Paste")
			(net "PVDDCR_CPU0_P1")
		)
	)
	(footprint ""
		(layer "F.Cu")
		(at 163.4236 -437.423052)
		(property "Reference" "R3429"
			(at 0 0 0)
			(layer "F.SilkS")
			(hide yes)
			(effects
				(font
					(size 1.27 1.27)
				)
			)
		)
		(property "Value" ""
			(at 0 0 0)
			(layer "F.Fab")
			(effects
				(font
					(size 1.27 1.27)
				)
			)
		)
		(duplicate_pad_numbers_are_jumpers no)
		(fp_line
			(start -0.7874 -0.4064)
			(end 0.7874 -0.4064)
			(stroke
				(width 0.1524)
				(type default)
			)
			(layer "F.SilkS")
		)
		(fp_line
			(start -0.7874 0.4064)
			(end -0.7874 -0.4064)
			(stroke
				(width 0.1524)
				(type default)
			)
			(layer "F.SilkS")
		)
		(fp_line
			(start 0.7874 -0.4064)
			(end 0.7874 0.4064)
			(stroke
				(width 0.1524)
				(type default)
			)
			(layer "F.SilkS")
		)
		(fp_line
			(start 0.7874 0.4064)
			(end -0.7874 0.4064)
			(stroke
				(width 0.1524)
				(type default)
			)
			(layer "F.SilkS")
		)
		(fp_line
			(start -0.67945 -0.305054)
			(end -0.12065 -0.305054)
			(stroke
				(width 0.1)
				(type default)
			)
			(layer "F.Fab")
		)
		(fp_line
			(start -0.67945 0.3048)
			(end -0.67945 -0.305054)
			(stroke
				(width 0.1)
				(type default)
			)
			(layer "F.Fab")
		)
		(fp_line
			(start -0.12065 -0.305054)
			(end -0.12065 -0.2794)
			(stroke
				(width 0.1)
				(type default)
			)
			(layer "F.Fab")
		)
		(fp_line
			(start -0.12065 -0.2794)
			(end 0.12065 -0.2794)
			(stroke
				(width 0.1)
				(type default)
			)
			(layer "F.Fab")
		)
		(fp_line
			(start -0.12065 0.2794)
			(end -0.12065 0.3048)
			(stroke
				(width 0.1)
				(type default)
			)
			(layer "F.Fab")
		)
		(fp_line
			(start -0.12065 0.3048)
			(end -0.67945 0.3048)
			(stroke
				(width 0.1)
				(type default)
			)
			(layer "F.Fab")
		)
		(fp_line
			(start 0.120396 0.2794)
			(end -0.12065 0.2794)
			(stroke
				(width 0.1)
				(type default)
			)
			(layer "F.Fab")
		)
		(fp_line
			(start 0.120396 0.3048)
			(end 0.120396 0.2794)
			(stroke
				(width 0.1)
				(type default)
			)
			(layer "F.Fab")
		)
		(fp_line
			(start 0.12065 -0.3048)
			(end 0.67945 -0.3048)
			(stroke
				(width 0.1)
				(type default)
			)
			(layer "F.Fab")
		)
		(fp_line
			(start 0.12065 -0.2794)
			(end 0.12065 -0.3048)
			(stroke
				(width 0.1)
				(type default)
			)
			(layer "F.Fab")
		)
		(fp_line
			(start 0.67945 -0.3048)
			(end 0.67945 0.3048)
			(stroke
				(width 0.1)
				(type default)
			)
			(layer "F.Fab")
		)
		(fp_line
			(start 0.67945 0.3048)
			(end 0.120396 0.3048)
			(stroke
				(width 0.1)
				(type default)
			)
			(layer "F.Fab")
		)
		(pad "1" smd circle
			(at -0.40005 0)
			(size 0 0)
			(layers "F.Cu" "F.Mask" "F.Paste")
			(net "P3V3_AUX")
		)
		(pad "2" smd circle
			(at 0.40005 0)
			(size 0 0)
			(layers "F.Cu" "F.Mask" "F.Paste")
			(net "GPU_BASE_HMC_READY")
		)
	)
	(footprint ""
		(layer "F.Cu")
		(at 134.162546 -408.517344 -90)
		(property "Reference" "C6705"
			(at 0 0 270)
			(layer "F.SilkS")
			(hide yes)
			(effects
				(font
					(size 1.27 1.27)
				)
			)
		)
		(property "Value" ""
			(at 0 0 270)
			(layer "F.Fab")
			(effects
				(font
					(size 1.27 1.27)
				)
			)
		)
		(duplicate_pad_numbers_are_jumpers no)
		(fp_line
			(start -0.299974 0.150114)
			(end -0.299974 -0.150114)
			(stroke
				(width 0.1)
				(type default)
			)
			(layer "F.Fab")
		)
		(fp_line
			(start 0.299974 0.150114)
			(end -0.299974 0.150114)
			(stroke
				(width 0.1)
				(type default)
			)
			(layer "F.Fab")
		)
		(fp_line
			(start -0.299974 -0.150114)
			(end 0.299974 -0.150114)
			(stroke
				(width 0.1)
				(type default)
			)
			(layer "F.Fab")
		)
		(fp_line
			(start 0.299974 -0.150114)
			(end 0.299974 0.150114)
			(stroke
				(width 0.1)
				(type default)
			)
			(layer "F.Fab")
		)
		(pad "1" smd rect
			(at -0.2667 0 270)
			(size 0.3048 0.381)
			(layers "F.Cu" "F.Mask" "F.Paste")
			(net "P5E_CPU1_P2_TX_BUF_C_DP<6>")
		)
		(pad "2" smd rect
			(at 0.2667 0 270)
			(size 0.3048 0.381)
			(layers "F.Cu" "F.Mask" "F.Paste")
			(net "P5E_CPU1_P2_TX_BUF_DP<6>")
		)
	)
	(footprint ""
		(layer "F.Cu")
		(at 22.479 -358.775 180)
		(property "Reference" "C308"
			(at 0 0 180)
			(layer "F.SilkS")
			(hide yes)
			(effects
				(font
					(size 1.27 1.27)
				)
			)
		)
		(property "Value" ""
			(at 0 0 180)
			(layer "F.Fab")
			(effects
				(font
					(size 1.27 1.27)
				)
			)
		)
		(duplicate_pad_numbers_are_jumpers no)
		(fp_line
			(start 0.7874 0.4064)
			(end -0.7874 0.4064)
			(stroke
				(width 0.1524)
				(type default)
			)
			(layer "F.SilkS")
		)
		(fp_line
			(start 0.7874 -0.4064)
			(end 0.7874 0.4064)
			(stroke
				(width 0.1524)
				(type default)
			)
			(layer "F.SilkS")
		)
		(fp_line
			(start -0.7874 0.4064)
			(end -0.7874 -0.4064)
			(stroke
				(width 0.1524)
				(type default)
			)
			(layer "F.SilkS")
		)
		(fp_line
			(start -0.7874 -0.4064)
			(end 0.7874 -0.4064)
			(stroke
				(width 0.1524)
				(type default)
			)
			(layer "F.SilkS")
		)
		(fp_line
			(start 0.67945 0.3048)
			(end 0.120396 0.3048)
			(stroke
				(width 0.1)
				(type default)
			)
			(layer "F.Fab")
		)
		(fp_line
			(start 0.67945 -0.3048)
			(end 0.67945 0.3048)
			(stroke
				(width 0.1)
				(type default)
			)
			(layer "F.Fab")
		)
		(fp_line
			(start 0.12065 -0.2794)
			(end 0.12065 -0.3048)
			(stroke
				(width 0.1)
				(type default)
			)
			(layer "F.Fab")
		)
		(fp_line
			(start 0.12065 -0.3048)
			(end 0.67945 -0.3048)
			(stroke
				(width 0.1)
				(type default)
			)
			(layer "F.Fab")
		)
		(fp_line
			(start 0.120396 0.3048)
			(end 0.120396 0.2794)
			(stroke
				(width 0.1)
				(type default)
			)
			(layer "F.Fab")
		)
		(fp_line
			(start 0.120396 0.2794)
			(end -0.12065 0.2794)
			(stroke
				(width 0.1)
				(type default)
			)
			(layer "F.Fab")
		)
		(fp_line
			(start -0.12065 0.3048)
			(end -0.67945 0.3048)
			(stroke
				(width 0.1)
				(type default)
			)
			(layer "F.Fab")
		)
		(fp_line
			(start -0.12065 0.2794)
			(end -0.12065 0.3048)
			(stroke
				(width 0.1)
				(type default)
			)
			(layer "F.Fab")
		)
		(fp_line
			(start -0.12065 -0.2794)
			(end 0.12065 -0.2794)
			(stroke
				(width 0.1)
				(type default)
			)
			(layer "F.Fab")
		)
		(fp_line
			(start -0.12065 -0.305054)
			(end -0.12065 -0.2794)
			(stroke
				(width 0.1)
				(type default)
			)
			(layer "F.Fab")
		)
		(fp_line
			(start -0.67945 0.3048)
			(end -0.67945 -0.305054)
			(stroke
				(width 0.1)
				(type default)
			)
			(layer "F.Fab")
		)
		(fp_line
			(start -0.67945 -0.305054)
			(end -0.12065 -0.305054)
			(stroke
				(width 0.1)
				(type default)
			)
			(layer "F.Fab")
		)
		(pad "1" smd circle
			(at -0.40005 0 180)
			(size 0 0)
			(layers "F.Cu" "F.Mask" "F.Paste")
			(net "SVID_PVDDCR_CPU1_P1_SVTO")
		)
		(pad "2" smd circle
			(at 0.40005 0 180)
			(size 0 0)
			(layers "F.Cu" "F.Mask" "F.Paste")
			(net "GND")
		)
	)
	(footprint ""
		(layer "F.Cu")
		(at 277.352252 -119.91467 180)
		(property "Reference" "R6201"
			(at 0 0 180)
			(layer "F.SilkS")
			(hide yes)
			(effects
				(font
					(size 1.27 1.27)
				)
			)
		)
		(property "Value" ""
			(at 0 0 180)
			(layer "F.Fab")
			(effects
				(font
					(size 1.27 1.27)
				)
			)
		)
		(duplicate_pad_numbers_are_jumpers no)
		(fp_line
			(start 0.7874 0.4064)
			(end -0.7874 0.4064)
			(stroke
				(width 0.1524)
				(type default)
			)
			(layer "F.SilkS")
		)
		(fp_line
			(start 0.7874 -0.4064)
			(end 0.7874 0.4064)
			(stroke
				(width 0.1524)
				(type default)
			)
			(layer "F.SilkS")
		)
		(fp_line
			(start -0.7874 0.4064)
			(end -0.7874 -0.4064)
			(stroke
				(width 0.1524)
				(type default)
			)
			(layer "F.SilkS")
		)
		(fp_line
			(start -0.7874 -0.4064)
			(end 0.7874 -0.4064)
			(stroke
				(width 0.1524)
				(type default)
			)
			(layer "F.SilkS")
		)
		(fp_line
			(start 0.67945 0.3048)
			(end 0.120396 0.3048)
			(stroke
				(width 0.1)
				(type default)
			)
			(layer "F.Fab")
		)
		(fp_line
			(start 0.67945 -0.3048)
			(end 0.67945 0.3048)
			(stroke
				(width 0.1)
				(type default)
			)
			(layer "F.Fab")
		)
		(fp_line
			(start 0.12065 -0.2794)
			(end 0.12065 -0.3048)
			(stroke
				(width 0.1)
				(type default)
			)
			(layer "F.Fab")
		)
		(fp_line
			(start 0.12065 -0.3048)
			(end 0.67945 -0.3048)
			(stroke
				(width 0.1)
				(type default)
			)
			(layer "F.Fab")
		)
		(fp_line
			(start 0.120396 0.3048)
			(end 0.120396 0.2794)
			(stroke
				(width 0.1)
				(type default)
			)
			(layer "F.Fab")
		)
		(fp_line
			(start 0.120396 0.2794)
			(end -0.12065 0.2794)
			(stroke
				(width 0.1)
				(type default)
			)
			(layer "F.Fab")
		)
		(fp_line
			(start -0.12065 0.3048)
			(end -0.67945 0.3048)
			(stroke
				(width 0.1)
				(type default)
			)
			(layer "F.Fab")
		)
		(fp_line
			(start -0.12065 0.2794)
			(end -0.12065 0.3048)
			(stroke
				(width 0.1)
				(type default)
			)
			(layer "F.Fab")
		)
		(fp_line
			(start -0.12065 -0.2794)
			(end 0.12065 -0.2794)
			(stroke
				(width 0.1)
				(type default)
			)
			(layer "F.Fab")
		)
		(fp_line
			(start -0.12065 -0.305054)
			(end -0.12065 -0.2794)
			(stroke
				(width 0.1)
				(type default)
			)
			(layer "F.Fab")
		)
		(fp_line
			(start -0.67945 0.3048)
			(end -0.67945 -0.305054)
			(stroke
				(width 0.1)
				(type default)
			)
			(layer "F.Fab")
		)
		(fp_line
			(start -0.67945 -0.305054)
			(end -0.12065 -0.305054)
			(stroke
				(width 0.1)
				(type default)
			)
			(layer "F.Fab")
		)
		(pad "1" smd circle
			(at -0.40005 0 180)
			(size 0 0)
			(layers "F.Cu" "F.Mask" "F.Paste")
			(net "SMB_USB_CPU0_HUB1_SCL_R")
		)
		(pad "2" smd circle
			(at 0.40005 0 180)
			(size 0 0)
			(layers "F.Cu" "F.Mask" "F.Paste")
			(net "SMB_USB_CPU0_HUB1_SCL")
		)
	)
	(footprint ""
		(layer "F.Cu")
		(at 26.954734 -394.733526 180)
		(property "Reference" "PC6633_2"
			(at 0 0 180)
			(layer "F.SilkS")
			(hide yes)
			(effects
				(font
					(size 1.27 1.27)
				)
			)
		)
		(property "Value" ""
			(at 0 0 180)
			(layer "F.Fab")
			(effects
				(font
					(size 1.27 1.27)
				)
			)
		)
		(duplicate_pad_numbers_are_jumpers no)
		(fp_line
			(start 0.7874 0.4064)
			(end -0.7874 0.4064)
			(stroke
				(width 0.1524)
				(type default)
			)
			(layer "F.SilkS")
		)
		(fp_line
			(start 0.7874 -0.4064)
			(end 0.7874 0.4064)
			(stroke
				(width 0.1524)
				(type default)
			)
			(layer "F.SilkS")
		)
		(fp_line
			(start -0.7874 0.4064)
			(end -0.7874 -0.4064)
			(stroke
				(width 0.1524)
				(type default)
			)
			(layer "F.SilkS")
		)
		(fp_line
			(start -0.7874 -0.4064)
			(end 0.7874 -0.4064)
			(stroke
				(width 0.1524)
				(type default)
			)
			(layer "F.SilkS")
		)
		(fp_line
			(start 0.67945 0.3048)
			(end 0.120396 0.3048)
			(stroke
				(width 0.1)
				(type default)
			)
			(layer "F.Fab")
		)
		(fp_line
			(start 0.67945 -0.3048)
			(end 0.67945 0.3048)
			(stroke
				(width 0.1)
				(type default)
			)
			(layer "F.Fab")
		)
		(fp_line
			(start 0.12065 -0.2794)
			(end 0.12065 -0.3048)
			(stroke
				(width 0.1)
				(type default)
			)
			(layer "F.Fab")
		)
		(fp_line
			(start 0.12065 -0.3048)
			(end 0.67945 -0.3048)
			(stroke
				(width 0.1)
				(type default)
			)
			(layer "F.Fab")
		)
		(fp_line
			(start 0.120396 0.3048)
			(end 0.120396 0.2794)
			(stroke
				(width 0.1)
				(type default)
			)
			(layer "F.Fab")
		)
		(fp_line
			(start 0.120396 0.2794)
			(end -0.12065 0.2794)
			(stroke
				(width 0.1)
				(type default)
			)
			(layer "F.Fab")
		)
		(fp_line
			(start -0.12065 0.3048)
			(end -0.67945 0.3048)
			(stroke
				(width 0.1)
				(type default)
			)
			(layer "F.Fab")
		)
		(fp_line
			(start -0.12065 0.2794)
			(end -0.12065 0.3048)
			(stroke
				(width 0.1)
				(type default)
			)
			(layer "F.Fab")
		)
		(fp_line
			(start -0.12065 -0.2794)
			(end 0.12065 -0.2794)
			(stroke
				(width 0.1)
				(type default)
			)
			(layer "F.Fab")
		)
		(fp_line
			(start -0.12065 -0.305054)
			(end -0.12065 -0.2794)
			(stroke
				(width 0.1)
				(type default)
			)
			(layer "F.Fab")
		)
		(fp_line
			(start -0.67945 0.3048)
			(end -0.67945 -0.305054)
			(stroke
				(width 0.1)
				(type default)
			)
			(layer "F.Fab")
		)
		(fp_line
			(start -0.67945 -0.305054)
			(end -0.12065 -0.305054)
			(stroke
				(width 0.1)
				(type default)
			)
			(layer "F.Fab")
		)
		(pad "1" smd circle
			(at -0.40005 0 180)
			(size 0 0)
			(layers "F.Cu" "F.Mask" "F.Paste")
			(net "SW_P12V_AUX_P0V9_RETIMER_CPU1_FLT")
		)
		(pad "2" smd circle
			(at 0.40005 0 180)
			(size 0 0)
			(layers "F.Cu" "F.Mask" "F.Paste")
			(net "GND")
		)
	)
	(footprint ""
		(layer "F.Cu")
		(at 118.491 -421.513)
		(property "Reference" "R3436"
			(at 0 0 0)
			(layer "F.SilkS")
			(hide yes)
			(effects
				(font
					(size 1.27 1.27)
				)
			)
		)
		(property "Value" ""
			(at 0 0 0)
			(layer "F.Fab")
			(effects
				(font
					(size 1.27 1.27)
				)
			)
		)
		(duplicate_pad_numbers_are_jumpers no)
		(fp_line
			(start -0.7874 -0.4064)
			(end 0.7874 -0.4064)
			(stroke
				(width 0.1524)
				(type default)
			)
			(layer "F.SilkS")
		)
		(fp_line
			(start -0.7874 0.4064)
			(end -0.7874 -0.4064)
			(stroke
				(width 0.1524)
				(type default)
			)
			(layer "F.SilkS")
		)
		(fp_line
			(start 0.7874 -0.4064)
			(end 0.7874 0.4064)
			(stroke
				(width 0.1524)
				(type default)
			)
			(layer "F.SilkS")
		)
		(fp_line
			(start 0.7874 0.4064)
			(end -0.7874 0.4064)
			(stroke
				(width 0.1524)
				(type default)
			)
			(layer "F.SilkS")
		)
		(fp_line
			(start -0.67945 -0.305054)
			(end -0.12065 -0.305054)
			(stroke
				(width 0.1)
				(type default)
			)
			(layer "F.Fab")
		)
		(fp_line
			(start -0.67945 0.3048)
			(end -0.67945 -0.305054)
			(stroke
				(width 0.1)
				(type default)
			)
			(layer "F.Fab")
		)
		(fp_line
			(start -0.12065 -0.305054)
			(end -0.12065 -0.2794)
			(stroke
				(width 0.1)
				(type default)
			)
			(layer "F.Fab")
		)
		(fp_line
			(start -0.12065 -0.2794)
			(end 0.12065 -0.2794)
			(stroke
				(width 0.1)
				(type default)
			)
			(layer "F.Fab")
		)
		(fp_line
			(start -0.12065 0.2794)
			(end -0.12065 0.3048)
			(stroke
				(width 0.1)
				(type default)
			)
			(layer "F.Fab")
		)
		(fp_line
			(start -0.12065 0.3048)
			(end -0.67945 0.3048)
			(stroke
				(width 0.1)
				(type default)
			)
			(layer "F.Fab")
		)
		(fp_line
			(start 0.120396 0.2794)
			(end -0.12065 0.2794)
			(stroke
				(width 0.1)
				(type default)
			)
			(layer "F.Fab")
		)
		(fp_line
			(start 0.120396 0.3048)
			(end 0.120396 0.2794)
			(stroke
				(width 0.1)
				(type default)
			)
			(layer "F.Fab")
		)
		(fp_line
			(start 0.12065 -0.3048)
			(end 0.67945 -0.3048)
			(stroke
				(width 0.1)
				(type default)
			)
			(layer "F.Fab")
		)
		(fp_line
			(start 0.12065 -0.2794)
			(end 0.12065 -0.3048)
			(stroke
				(width 0.1)
				(type default)
			)
			(layer "F.Fab")
		)
		(fp_line
			(start 0.67945 -0.3048)
			(end 0.67945 0.3048)
			(stroke
				(width 0.1)
				(type default)
			)
			(layer "F.Fab")
		)
		(fp_line
			(start 0.67945 0.3048)
			(end 0.120396 0.3048)
			(stroke
				(width 0.1)
				(type default)
			)
			(layer "F.Fab")
		)
		(pad "1" smd circle
			(at -0.40005 0)
			(size 0 0)
			(layers "F.Cu" "F.Mask" "F.Paste")
			(net "P3V3_AUX")
		)
		(pad "2" smd circle
			(at 0.40005 0)
			(size 0 0)
			(layers "F.Cu" "F.Mask" "F.Paste")
			(net "GPU_HMC_PRSNT_ISO_N")
		)
	)
	(footprint ""
		(layer "F.Cu")
		(at 88.177878 -148.94941 180)
		(property "Reference" "C295"
			(at 0 0 180)
			(layer "F.SilkS")
			(hide yes)
			(effects
				(font
					(size 1.27 1.27)
				)
			)
		)
		(property "Value" ""
			(at 0 0 180)
			(layer "F.Fab")
			(effects
				(font
					(size 1.27 1.27)
				)
			)
		)
		(duplicate_pad_numbers_are_jumpers no)
		(fp_line
			(start 0.7874 0.4064)
			(end -0.7874 0.4064)
			(stroke
				(width 0.1524)
				(type default)
			)
			(layer "F.SilkS")
		)
		(fp_line
			(start 0.7874 -0.4064)
			(end 0.7874 0.4064)
			(stroke
				(width 0.1524)
				(type default)
			)
			(layer "F.SilkS")
		)
		(fp_line
			(start -0.7874 0.4064)
			(end -0.7874 -0.4064)
			(stroke
				(width 0.1524)
				(type default)
			)
			(layer "F.SilkS")
		)
		(fp_line
			(start -0.7874 -0.4064)
			(end 0.7874 -0.4064)
			(stroke
				(width 0.1524)
				(type default)
			)
			(layer "F.SilkS")
		)
		(fp_line
			(start 0.67945 0.3048)
			(end 0.120396 0.3048)
			(stroke
				(width 0.1)
				(type default)
			)
			(layer "F.Fab")
		)
		(fp_line
			(start 0.67945 -0.3048)
			(end 0.67945 0.3048)
			(stroke
				(width 0.1)
				(type default)
			)
			(layer "F.Fab")
		)
		(fp_line
			(start 0.12065 -0.2794)
			(end 0.12065 -0.3048)
			(stroke
				(width 0.1)
				(type default)
			)
			(layer "F.Fab")
		)
		(fp_line
			(start 0.12065 -0.3048)
			(end 0.67945 -0.3048)
			(stroke
				(width 0.1)
				(type default)
			)
			(layer "F.Fab")
		)
		(fp_line
			(start 0.120396 0.3048)
			(end 0.120396 0.2794)
			(stroke
				(width 0.1)
				(type default)
			)
			(layer "F.Fab")
		)
		(fp_line
			(start 0.120396 0.2794)
			(end -0.12065 0.2794)
			(stroke
				(width 0.1)
				(type default)
			)
			(layer "F.Fab")
		)
		(fp_line
			(start -0.12065 0.3048)
			(end -0.67945 0.3048)
			(stroke
				(width 0.1)
				(type default)
			)
			(layer "F.Fab")
		)
		(fp_line
			(start -0.12065 0.2794)
			(end -0.12065 0.3048)
			(stroke
				(width 0.1)
				(type default)
			)
			(layer "F.Fab")
		)
		(fp_line
			(start -0.12065 -0.2794)
			(end 0.12065 -0.2794)
			(stroke
				(width 0.1)
				(type default)
			)
			(layer "F.Fab")
		)
		(fp_line
			(start -0.12065 -0.305054)
			(end -0.12065 -0.2794)
			(stroke
				(width 0.1)
				(type default)
			)
			(layer "F.Fab")
		)
		(fp_line
			(start -0.67945 0.3048)
			(end -0.67945 -0.305054)
			(stroke
				(width 0.1)
				(type default)
			)
			(layer "F.Fab")
		)
		(fp_line
			(start -0.67945 -0.305054)
			(end -0.12065 -0.305054)
			(stroke
				(width 0.1)
				(type default)
			)
			(layer "F.Fab")
		)
		(pad "1" smd circle
			(at -0.40005 0 180)
			(size 0 0)
			(layers "F.Cu" "F.Mask" "F.Paste")
			(net "SVID_PVDDCR_CPU0_P1_SVTO")
		)
		(pad "2" smd circle
			(at 0.40005 0 180)
			(size 0 0)
			(layers "F.Cu" "F.Mask" "F.Paste")
			(net "GND")
		)
	)
	(footprint ""
		(layer "F.Cu")
		(at 176.855882 -137.740898 -90)
		(property "Reference" "R6853"
			(at 0 0 270)
			(layer "F.SilkS")
			(hide yes)
			(effects
				(font
					(size 1.27 1.27)
				)
			)
		)
		(property "Value" ""
			(at 0 0 270)
			(layer "F.Fab")
			(effects
				(font
					(size 1.27 1.27)
				)
			)
		)
		(duplicate_pad_numbers_are_jumpers no)
		(fp_line
			(start -0.7874 0.4064)
			(end -0.7874 -0.4064)
			(stroke
				(width 0.1524)
				(type default)
			)
			(layer "F.SilkS")
		)
		(fp_line
			(start 0.7874 0.4064)
			(end -0.7874 0.4064)
			(stroke
				(width 0.1524)
				(type default)
			)
			(layer "F.SilkS")
		)
		(fp_line
			(start -0.7874 -0.4064)
			(end 0.7874 -0.4064)
			(stroke
				(width 0.1524)
				(type default)
			)
			(layer "F.SilkS")
		)
		(fp_line
			(start 0.7874 -0.4064)
			(end 0.7874 0.4064)
			(stroke
				(width 0.1524)
				(type default)
			)
			(layer "F.SilkS")
		)
		(fp_line
			(start -0.67945 0.3048)
			(end -0.67945 -0.305054)
			(stroke
				(width 0.1)
				(type default)
			)
			(layer "F.Fab")
		)
		(fp_line
			(start -0.12065 0.3048)
			(end -0.67945 0.3048)
			(stroke
				(width 0.1)
				(type default)
			)
			(layer "F.Fab")
		)
		(fp_line
			(start 0.120396 0.3048)
			(end 0.120396 0.2794)
			(stroke
				(width 0.1)
				(type default)
			)
			(layer "F.Fab")
		)
		(fp_line
			(start 0.67945 0.3048)
			(end 0.120396 0.3048)
			(stroke
				(width 0.1)
				(type default)
			)
			(layer "F.Fab")
		)
		(fp_line
			(start -0.12065 0.2794)
			(end -0.12065 0.3048)
			(stroke
				(width 0.1)
				(type default)
			)
			(layer "F.Fab")
		)
		(fp_line
			(start 0.120396 0.2794)
			(end -0.12065 0.2794)
			(stroke
				(width 0.1)
				(type default)
			)
			(layer "F.Fab")
		)
		(fp_line
			(start -0.12065 -0.2794)
			(end 0.12065 -0.2794)
			(stroke
				(width 0.1)
				(type default)
			)
			(layer "F.Fab")
		)
		(fp_line
			(start 0.12065 -0.2794)
			(end 0.12065 -0.3048)
			(stroke
				(width 0.1)
				(type default)
			)
			(layer "F.Fab")
		)
		(fp_line
			(start 0.12065 -0.3048)
			(end 0.67945 -0.3048)
			(stroke
				(width 0.1)
				(type default)
			)
			(layer "F.Fab")
		)
		(fp_line
			(start 0.67945 -0.3048)
			(end 0.67945 0.3048)
			(stroke
				(width 0.1)
				(type default)
			)
			(layer "F.Fab")
		)
		(fp_line
			(start -0.67945 -0.305054)
			(end -0.12065 -0.305054)
			(stroke
				(width 0.1)
				(type default)
			)
			(layer "F.Fab")
		)
		(fp_line
			(start -0.12065 -0.305054)
			(end -0.12065 -0.2794)
			(stroke
				(width 0.1)
				(type default)
			)
			(layer "F.Fab")
		)
		(pad "1" smd circle
			(at -0.40005 0 270)
			(size 0 0)
			(layers "F.Cu" "F.Mask" "F.Paste")
			(net "PWRGD_P0V9_RETIMER_CPU1")
		)
		(pad "2" smd circle
			(at 0.40005 0 270)
			(size 0 0)
			(layers "F.Cu" "F.Mask" "F.Paste")
			(net "PWRGD_P0V9_RETIMER_CPU1_R2")
		)
	)
	(footprint ""
		(layer "F.Cu")
		(at 143.96339 -31.18739 180)
		(property "Reference" "R342"
			(at 0 0 180)
			(layer "F.SilkS")
			(hide yes)
			(effects
				(font
					(size 1.27 1.27)
				)
			)
		)
		(property "Value" ""
			(at 0 0 180)
			(layer "F.Fab")
			(effects
				(font
					(size 1.27 1.27)
				)
			)
		)
		(duplicate_pad_numbers_are_jumpers no)
		(fp_line
			(start 0.7874 0.4064)
			(end -0.7874 0.4064)
			(stroke
				(width 0.1524)
				(type default)
			)
			(layer "F.SilkS")
		)
		(fp_line
			(start 0.7874 -0.4064)
			(end 0.7874 0.4064)
			(stroke
				(width 0.1524)
				(type default)
			)
			(layer "F.SilkS")
		)
		(fp_line
			(start -0.7874 0.4064)
			(end -0.7874 -0.4064)
			(stroke
				(width 0.1524)
				(type default)
			)
			(layer "F.SilkS")
		)
		(fp_line
			(start -0.7874 -0.4064)
			(end 0.7874 -0.4064)
			(stroke
				(width 0.1524)
				(type default)
			)
			(layer "F.SilkS")
		)
		(fp_line
			(start 0.67945 0.3048)
			(end 0.120396 0.3048)
			(stroke
				(width 0.1)
				(type default)
			)
			(layer "F.Fab")
		)
		(fp_line
			(start 0.67945 -0.3048)
			(end 0.67945 0.3048)
			(stroke
				(width 0.1)
				(type default)
			)
			(layer "F.Fab")
		)
		(fp_line
			(start 0.12065 -0.2794)
			(end 0.12065 -0.3048)
			(stroke
				(width 0.1)
				(type default)
			)
			(layer "F.Fab")
		)
		(fp_line
			(start 0.12065 -0.3048)
			(end 0.67945 -0.3048)
			(stroke
				(width 0.1)
				(type default)
			)
			(layer "F.Fab")
		)
		(fp_line
			(start 0.120396 0.3048)
			(end 0.120396 0.2794)
			(stroke
				(width 0.1)
				(type default)
			)
			(layer "F.Fab")
		)
		(fp_line
			(start 0.120396 0.2794)
			(end -0.12065 0.2794)
			(stroke
				(width 0.1)
				(type default)
			)
			(layer "F.Fab")
		)
		(fp_line
			(start -0.12065 0.3048)
			(end -0.67945 0.3048)
			(stroke
				(width 0.1)
				(type default)
			)
			(layer "F.Fab")
		)
		(fp_line
			(start -0.12065 0.2794)
			(end -0.12065 0.3048)
			(stroke
				(width 0.1)
				(type default)
			)
			(layer "F.Fab")
		)
		(fp_line
			(start -0.12065 -0.2794)
			(end 0.12065 -0.2794)
			(stroke
				(width 0.1)
				(type default)
			)
			(layer "F.Fab")
		)
		(fp_line
			(start -0.12065 -0.305054)
			(end -0.12065 -0.2794)
			(stroke
				(width 0.1)
				(type default)
			)
			(layer "F.Fab")
		)
		(fp_line
			(start -0.67945 0.3048)
			(end -0.67945 -0.305054)
			(stroke
				(width 0.1)
				(type default)
			)
			(layer "F.Fab")
		)
		(fp_line
			(start -0.67945 -0.305054)
			(end -0.12065 -0.305054)
			(stroke
				(width 0.1)
				(type default)
			)
			(layer "F.Fab")
		)
		(pad "1" smd rect
			(at -0.40005 0)
			(size 0.4572 0.508)
			(layers "F.Cu" "F.Mask" "F.Paste")
			(net "USB3_CPU0_BMC_TX_DN")
		)
		(pad "2" smd rect
			(at 0.40005 0)
			(size 0.4572 0.508)
			(layers "F.Cu" "F.Mask" "F.Paste")
			(net "GND")
		)
	)
	(footprint ""
		(layer "F.Cu")
		(at 196.088 -133.568948 -90)
		(property "Reference" "R6085"
			(at 0 0 270)
			(layer "F.SilkS")
			(hide yes)
			(effects
				(font
					(size 1.27 1.27)
				)
			)
		)
		(property "Value" ""
			(at 0 0 270)
			(layer "F.Fab")
			(effects
				(font
					(size 1.27 1.27)
				)
			)
		)
		(duplicate_pad_numbers_are_jumpers no)
		(fp_line
			(start -0.7874 0.4064)
			(end -0.7874 -0.4064)
			(stroke
				(width 0.1524)
				(type default)
			)
			(layer "F.SilkS")
		)
		(fp_line
			(start 0.7874 0.4064)
			(end -0.7874 0.4064)
			(stroke
				(width 0.1524)
				(type default)
			)
			(layer "F.SilkS")
		)
		(fp_line
			(start -0.7874 -0.4064)
			(end 0.7874 -0.4064)
			(stroke
				(width 0.1524)
				(type default)
			)
			(layer "F.SilkS")
		)
		(fp_line
			(start 0.7874 -0.4064)
			(end 0.7874 0.4064)
			(stroke
				(width 0.1524)
				(type default)
			)
			(layer "F.SilkS")
		)
		(fp_line
			(start -0.67945 0.3048)
			(end -0.67945 -0.305054)
			(stroke
				(width 0.1)
				(type default)
			)
			(layer "F.Fab")
		)
		(fp_line
			(start -0.12065 0.3048)
			(end -0.67945 0.3048)
			(stroke
				(width 0.1)
				(type default)
			)
			(layer "F.Fab")
		)
		(fp_line
			(start 0.120396 0.3048)
			(end 0.120396 0.2794)
			(stroke
				(width 0.1)
				(type default)
			)
			(layer "F.Fab")
		)
		(fp_line
			(start 0.67945 0.3048)
			(end 0.120396 0.3048)
			(stroke
				(width 0.1)
				(type default)
			)
			(layer "F.Fab")
		)
		(fp_line
			(start -0.12065 0.2794)
			(end -0.12065 0.3048)
			(stroke
				(width 0.1)
				(type default)
			)
			(layer "F.Fab")
		)
		(fp_line
			(start 0.120396 0.2794)
			(end -0.12065 0.2794)
			(stroke
				(width 0.1)
				(type default)
			)
			(layer "F.Fab")
		)
		(fp_line
			(start -0.12065 -0.2794)
			(end 0.12065 -0.2794)
			(stroke
				(width 0.1)
				(type default)
			)
			(layer "F.Fab")
		)
		(fp_line
			(start 0.12065 -0.2794)
			(end 0.12065 -0.3048)
			(stroke
				(width 0.1)
				(type default)
			)
			(layer "F.Fab")
		)
		(fp_line
			(start 0.12065 -0.3048)
			(end 0.67945 -0.3048)
			(stroke
				(width 0.1)
				(type default)
			)
			(layer "F.Fab")
		)
		(fp_line
			(start 0.67945 -0.3048)
			(end 0.67945 0.3048)
			(stroke
				(width 0.1)
				(type default)
			)
			(layer "F.Fab")
		)
		(fp_line
			(start -0.67945 -0.305054)
			(end -0.12065 -0.305054)
			(stroke
				(width 0.1)
				(type default)
			)
			(layer "F.Fab")
		)
		(fp_line
			(start -0.12065 -0.305054)
			(end -0.12065 -0.2794)
			(stroke
				(width 0.1)
				(type default)
			)
			(layer "F.Fab")
		)
		(pad "1" smd circle
			(at -0.40005 0 270)
			(size 0 0)
			(layers "F.Cu" "F.Mask" "F.Paste")
			(net "P3V3_AUX")
		)
		(pad "2" smd circle
			(at 0.40005 0 270)
			(size 0 0)
			(layers "F.Cu" "F.Mask" "F.Paste")
			(net "PU_SPI_PLD_CS_N")
		)
	)
	(footprint ""
		(layer "F.Cu")
		(at 115.024408 -71.962772 180)
		(property "Reference" "PC6023"
			(at 0 0 180)
			(layer "F.SilkS")
			(hide yes)
			(effects
				(font
					(size 1.27 1.27)
				)
			)
		)
		(property "Value" ""
			(at 0 0 180)
			(layer "F.Fab")
			(effects
				(font
					(size 1.27 1.27)
				)
			)
		)
		(duplicate_pad_numbers_are_jumpers no)
		(fp_line
			(start 0.7874 0.4064)
			(end -0.7874 0.4064)
			(stroke
				(width 0.1524)
				(type default)
			)
			(layer "F.SilkS")
		)
		(fp_line
			(start 0.7874 -0.4064)
			(end 0.7874 0.4064)
			(stroke
				(width 0.1524)
				(type default)
			)
			(layer "F.SilkS")
		)
		(fp_line
			(start -0.7874 0.4064)
			(end -0.7874 -0.4064)
			(stroke
				(width 0.1524)
				(type default)
			)
			(layer "F.SilkS")
		)
		(fp_line
			(start -0.7874 -0.4064)
			(end 0.7874 -0.4064)
			(stroke
				(width 0.1524)
				(type default)
			)
			(layer "F.SilkS")
		)
		(fp_line
			(start 0.67945 0.3048)
			(end 0.120396 0.3048)
			(stroke
				(width 0.1)
				(type default)
			)
			(layer "F.Fab")
		)
		(fp_line
			(start 0.67945 -0.3048)
			(end 0.67945 0.3048)
			(stroke
				(width 0.1)
				(type default)
			)
			(layer "F.Fab")
		)
		(fp_line
			(start 0.12065 -0.2794)
			(end 0.12065 -0.3048)
			(stroke
				(width 0.1)
				(type default)
			)
			(layer "F.Fab")
		)
		(fp_line
			(start 0.12065 -0.3048)
			(end 0.67945 -0.3048)
			(stroke
				(width 0.1)
				(type default)
			)
			(layer "F.Fab")
		)
		(fp_line
			(start 0.120396 0.3048)
			(end 0.120396 0.2794)
			(stroke
				(width 0.1)
				(type default)
			)
			(layer "F.Fab")
		)
		(fp_line
			(start 0.120396 0.2794)
			(end -0.12065 0.2794)
			(stroke
				(width 0.1)
				(type default)
			)
			(layer "F.Fab")
		)
		(fp_line
			(start -0.12065 0.3048)
			(end -0.67945 0.3048)
			(stroke
				(width 0.1)
				(type default)
			)
			(layer "F.Fab")
		)
		(fp_line
			(start -0.12065 0.2794)
			(end -0.12065 0.3048)
			(stroke
				(width 0.1)
				(type default)
			)
			(layer "F.Fab")
		)
		(fp_line
			(start -0.12065 -0.2794)
			(end 0.12065 -0.2794)
			(stroke
				(width 0.1)
				(type default)
			)
			(layer "F.Fab")
		)
		(fp_line
			(start -0.12065 -0.305054)
			(end -0.12065 -0.2794)
			(stroke
				(width 0.1)
				(type default)
			)
			(layer "F.Fab")
		)
		(fp_line
			(start -0.67945 0.3048)
			(end -0.67945 -0.305054)
			(stroke
				(width 0.1)
				(type default)
			)
			(layer "F.Fab")
		)
		(fp_line
			(start -0.67945 -0.305054)
			(end -0.12065 -0.305054)
			(stroke
				(width 0.1)
				(type default)
			)
			(layer "F.Fab")
		)
		(pad "1" smd circle
			(at -0.40005 0 180)
			(size 0 0)
			(layers "F.Cu" "F.Mask" "F.Paste")
			(net "P12V_AUX")
		)
		(pad "2" smd circle
			(at 0.40005 0 180)
			(size 0 0)
			(layers "F.Cu" "F.Mask" "F.Paste")
			(net "GND")
		)
	)
	(footprint ""
		(layer "F.Cu")
		(at 75.49515 -376.85726 180)
		(property "Reference" "C738"
			(at 0 0 180)
			(layer "F.SilkS")
			(hide yes)
			(effects
				(font
					(size 1.27 1.27)
				)
			)
		)
		(property "Value" ""
			(at 0 0 180)
			(layer "F.Fab")
			(effects
				(font
					(size 1.27 1.27)
				)
			)
		)
		(duplicate_pad_numbers_are_jumpers no)
		(fp_line
			(start 0.299974 0.150114)
			(end -0.299974 0.150114)
			(stroke
				(width 0.1)
				(type default)
			)
			(layer "F.Fab")
		)
		(fp_line
			(start 0.299974 -0.150114)
			(end 0.299974 0.150114)
			(stroke
				(width 0.1)
				(type default)
			)
			(layer "F.Fab")
		)
		(fp_line
			(start -0.299974 0.150114)
			(end -0.299974 -0.150114)
			(stroke
				(width 0.1)
				(type default)
			)
			(layer "F.Fab")
		)
		(fp_line
			(start -0.299974 -0.150114)
			(end 0.299974 -0.150114)
			(stroke
				(width 0.1)
				(type default)
			)
			(layer "F.Fab")
		)
		(pad "1" smd rect
			(at -0.2667 0 180)
			(size 0.3048 0.381)
			(layers "F.Cu" "F.Mask" "F.Paste")
			(net "P5E_CPU1_P1_TX_C_DN<1>")
		)
		(pad "2" smd rect
			(at 0.2667 0 180)
			(size 0.3048 0.381)
			(layers "F.Cu" "F.Mask" "F.Paste")
			(net "P5E_CPU1_P1_TX_DN<1>")
		)
	)
	(footprint ""
		(layer "F.Cu")
		(at 441.050172 -32.173418 90)
		(property "Reference" "PC2155"
			(at 0 0 90)
			(layer "F.SilkS")
			(hide yes)
			(effects
				(font
					(size 1.27 1.27)
				)
			)
		)
		(property "Value" ""
			(at 0 0 90)
			(layer "F.Fab")
			(effects
				(font
					(size 1.27 1.27)
				)
			)
		)
		(duplicate_pad_numbers_are_jumpers no)
		(fp_line
			(start 0.7874 -0.4064)
			(end 0.7874 0.4064)
			(stroke
				(width 0.1524)
				(type default)
			)
			(layer "F.SilkS")
		)
		(fp_line
			(start -0.7874 -0.4064)
			(end 0.7874 -0.4064)
			(stroke
				(width 0.1524)
				(type default)
			)
			(layer "F.SilkS")
		)
		(fp_line
			(start 0.7874 0.4064)
			(end -0.7874 0.4064)
			(stroke
				(width 0.1524)
				(type default)
			)
			(layer "F.SilkS")
		)
		(fp_line
			(start -0.7874 0.4064)
			(end -0.7874 -0.4064)
			(stroke
				(width 0.1524)
				(type default)
			)
			(layer "F.SilkS")
		)
		(fp_line
			(start -0.12065 -0.305054)
			(end -0.12065 -0.2794)
			(stroke
				(width 0.1)
				(type default)
			)
			(layer "F.Fab")
		)
		(fp_line
			(start -0.67945 -0.305054)
			(end -0.12065 -0.305054)
			(stroke
				(width 0.1)
				(type default)
			)
			(layer "F.Fab")
		)
		(fp_line
			(start 0.67945 -0.3048)
			(end 0.67945 0.3048)
			(stroke
				(width 0.1)
				(type default)
			)
			(layer "F.Fab")
		)
		(fp_line
			(start 0.12065 -0.3048)
			(end 0.67945 -0.3048)
			(stroke
				(width 0.1)
				(type default)
			)
			(layer "F.Fab")
		)
		(fp_line
			(start 0.12065 -0.2794)
			(end 0.12065 -0.3048)
			(stroke
				(width 0.1)
				(type default)
			)
			(layer "F.Fab")
		)
		(fp_line
			(start -0.12065 -0.2794)
			(end 0.12065 -0.2794)
			(stroke
				(width 0.1)
				(type default)
			)
			(layer "F.Fab")
		)
		(fp_line
			(start 0.120396 0.2794)
			(end -0.12065 0.2794)
			(stroke
				(width 0.1)
				(type default)
			)
			(layer "F.Fab")
		)
		(fp_line
			(start -0.12065 0.2794)
			(end -0.12065 0.3048)
			(stroke
				(width 0.1)
				(type default)
			)
			(layer "F.Fab")
		)
		(fp_line
			(start 0.67945 0.3048)
			(end 0.120396 0.3048)
			(stroke
				(width 0.1)
				(type default)
			)
			(layer "F.Fab")
		)
		(fp_line
			(start 0.120396 0.3048)
			(end 0.120396 0.2794)
			(stroke
				(width 0.1)
				(type default)
			)
			(layer "F.Fab")
		)
		(fp_line
			(start -0.12065 0.3048)
			(end -0.67945 0.3048)
			(stroke
				(width 0.1)
				(type default)
			)
			(layer "F.Fab")
		)
		(fp_line
			(start -0.67945 0.3048)
			(end -0.67945 -0.305054)
			(stroke
				(width 0.1)
				(type default)
			)
			(layer "F.Fab")
		)
		(pad "1" smd circle
			(at -0.40005 0 90)
			(size 0 0)
			(layers "F.Cu" "F.Mask" "F.Paste")
			(net "P12V_OCP_SS_1")
		)
		(pad "2" smd circle
			(at 0.40005 0 90)
			(size 0 0)
			(layers "F.Cu" "F.Mask" "F.Paste")
			(net "GND")
		)
	)
	(footprint ""
		(layer "F.Cu")
		(at 194.2211 -400.998182 180)
		(property "Reference" "PR3918"
			(at 0 0 180)
			(layer "F.SilkS")
			(hide yes)
			(effects
				(font
					(size 1.27 1.27)
				)
			)
		)
		(property "Value" ""
			(at 0 0 180)
			(layer "F.Fab")
			(effects
				(font
					(size 1.27 1.27)
				)
			)
		)
		(duplicate_pad_numbers_are_jumpers no)
		(fp_line
			(start 0.7874 0.4064)
			(end -0.7874 0.4064)
			(stroke
				(width 0.1524)
				(type default)
			)
			(layer "F.SilkS")
		)
		(fp_line
			(start 0.7874 -0.4064)
			(end 0.7874 0.4064)
			(stroke
				(width 0.1524)
				(type default)
			)
			(layer "F.SilkS")
		)
		(fp_line
			(start -0.7874 0.4064)
			(end -0.7874 -0.4064)
			(stroke
				(width 0.1524)
				(type default)
			)
			(layer "F.SilkS")
		)
		(fp_line
			(start -0.7874 -0.4064)
			(end 0.7874 -0.4064)
			(stroke
				(width 0.1524)
				(type default)
			)
			(layer "F.SilkS")
		)
		(fp_line
			(start 0.67945 0.3048)
			(end 0.120396 0.3048)
			(stroke
				(width 0.1)
				(type default)
			)
			(layer "F.Fab")
		)
		(fp_line
			(start 0.67945 -0.3048)
			(end 0.67945 0.3048)
			(stroke
				(width 0.1)
				(type default)
			)
			(layer "F.Fab")
		)
		(fp_line
			(start 0.12065 -0.2794)
			(end 0.12065 -0.3048)
			(stroke
				(width 0.1)
				(type default)
			)
			(layer "F.Fab")
		)
		(fp_line
			(start 0.12065 -0.3048)
			(end 0.67945 -0.3048)
			(stroke
				(width 0.1)
				(type default)
			)
			(layer "F.Fab")
		)
		(fp_line
			(start 0.120396 0.3048)
			(end 0.120396 0.2794)
			(stroke
				(width 0.1)
				(type default)
			)
			(layer "F.Fab")
		)
		(fp_line
			(start 0.120396 0.2794)
			(end -0.12065 0.2794)
			(stroke
				(width 0.1)
				(type default)
			)
			(layer "F.Fab")
		)
		(fp_line
			(start -0.12065 0.3048)
			(end -0.67945 0.3048)
			(stroke
				(width 0.1)
				(type default)
			)
			(layer "F.Fab")
		)
		(fp_line
			(start -0.12065 0.2794)
			(end -0.12065 0.3048)
			(stroke
				(width 0.1)
				(type default)
			)
			(layer "F.Fab")
		)
		(fp_line
			(start -0.12065 -0.2794)
			(end 0.12065 -0.2794)
			(stroke
				(width 0.1)
				(type default)
			)
			(layer "F.Fab")
		)
		(fp_line
			(start -0.12065 -0.305054)
			(end -0.12065 -0.2794)
			(stroke
				(width 0.1)
				(type default)
			)
			(layer "F.Fab")
		)
		(fp_line
			(start -0.67945 0.3048)
			(end -0.67945 -0.305054)
			(stroke
				(width 0.1)
				(type default)
			)
			(layer "F.Fab")
		)
		(fp_line
			(start -0.67945 -0.305054)
			(end -0.12065 -0.305054)
			(stroke
				(width 0.1)
				(type default)
			)
			(layer "F.Fab")
		)
		(pad "1" smd circle
			(at -0.40005 0 180)
			(size 0 0)
			(layers "F.Cu" "F.Mask" "F.Paste")
			(net "HSC_IMON")
		)
		(pad "2" smd circle
			(at 0.40005 0 180)
			(size 0 0)
			(layers "F.Cu" "F.Mask" "F.Paste")
			(net "AGND_HSC")
		)
	)
	(footprint ""
		(layer "F.Cu")
		(at 328.694542 -395.1732 90)
		(property "Reference" "R967"
			(at 0 0 90)
			(layer "F.SilkS")
			(hide yes)
			(effects
				(font
					(size 1.27 1.27)
				)
			)
		)
		(property "Value" ""
			(at 0 0 90)
			(layer "F.Fab")
			(effects
				(font
					(size 1.27 1.27)
				)
			)
		)
		(duplicate_pad_numbers_are_jumpers no)
		(fp_line
			(start 0.32512 -0.175006)
			(end 0.32512 0.175006)
			(stroke
				(width 0.1)
				(type default)
			)
			(layer "F.Fab")
		)
		(fp_line
			(start -0.32512 -0.175006)
			(end 0.32512 -0.175006)
			(stroke
				(width 0.1)
				(type default)
			)
			(layer "F.Fab")
		)
		(fp_line
			(start 0.32512 0.175006)
			(end -0.32512 0.175006)
			(stroke
				(width 0.1)
				(type default)
			)
			(layer "F.Fab")
		)
		(fp_line
			(start -0.32512 0.175006)
			(end -0.32512 -0.175006)
			(stroke
				(width 0.1)
				(type default)
			)
			(layer "F.Fab")
		)
		(pad "1" smd rect
			(at -0.2667 0 90)
			(size 0.3048 0.381)
			(layers "F.Cu" "F.Mask" "F.Paste")
			(net "RT_CPU0_P0_ADDR2")
		)
		(pad "2" smd rect
			(at 0.2667 0 270)
			(size 0.3048 0.381)
			(layers "F.Cu" "F.Mask" "F.Paste")
			(net "GND")
		)
	)
	(footprint ""
		(layer "F.Cu")
		(at 69.741034 -380.385828)
		(property "Reference" "C806"
			(at 0 0 0)
			(layer "F.SilkS")
			(hide yes)
			(effects
				(font
					(size 1.27 1.27)
				)
			)
		)
		(property "Value" ""
			(at 0 0 0)
			(layer "F.Fab")
			(effects
				(font
					(size 1.27 1.27)
				)
			)
		)
		(duplicate_pad_numbers_are_jumpers no)
		(fp_line
			(start -0.299974 -0.150114)
			(end 0.299974 -0.150114)
			(stroke
				(width 0.1)
				(type default)
			)
			(layer "F.Fab")
		)
		(fp_line
			(start -0.299974 0.150114)
			(end -0.299974 -0.150114)
			(stroke
				(width 0.1)
				(type default)
			)
			(layer "F.Fab")
		)
		(fp_line
			(start 0.299974 -0.150114)
			(end 0.299974 0.150114)
			(stroke
				(width 0.1)
				(type default)
			)
			(layer "F.Fab")
		)
		(fp_line
			(start 0.299974 0.150114)
			(end -0.299974 0.150114)
			(stroke
				(width 0.1)
				(type default)
			)
			(layer "F.Fab")
		)
		(pad "1" smd rect
			(at -0.2667 0)
			(size 0.3048 0.381)
			(layers "F.Cu" "F.Mask" "F.Paste")
			(net "P5E_CPU1_P0_TX_C_DN<15>")
		)
		(pad "2" smd rect
			(at 0.2667 0)
			(size 0.3048 0.381)
			(layers "F.Cu" "F.Mask" "F.Paste")
			(net "P5E_CPU1_P0_TX_DN<15>")
		)
	)
	(footprint ""
		(layer "F.Cu")
		(at 414.337246 -360.7943)
		(property "Reference" "R8458"
			(at 0 0 0)
			(layer "F.SilkS")
			(hide yes)
			(effects
				(font
					(size 1.27 1.27)
				)
			)
		)
		(property "Value" ""
			(at 0 0 0)
			(layer "F.Fab")
			(effects
				(font
					(size 1.27 1.27)
				)
			)
		)
		(duplicate_pad_numbers_are_jumpers no)
		(fp_line
			(start -0.7874 -0.4064)
			(end 0.7874 -0.4064)
			(stroke
				(width 0.1524)
				(type default)
			)
			(layer "F.SilkS")
		)
		(fp_line
			(start -0.7874 0.4064)
			(end -0.7874 -0.4064)
			(stroke
				(width 0.1524)
				(type default)
			)
			(layer "F.SilkS")
		)
		(fp_line
			(start 0.7874 -0.4064)
			(end 0.7874 0.4064)
			(stroke
				(width 0.1524)
				(type default)
			)
			(layer "F.SilkS")
		)
		(fp_line
			(start 0.7874 0.4064)
			(end -0.7874 0.4064)
			(stroke
				(width 0.1524)
				(type default)
			)
			(layer "F.SilkS")
		)
		(fp_line
			(start -0.67945 -0.305054)
			(end -0.12065 -0.305054)
			(stroke
				(width 0.1)
				(type default)
			)
			(layer "F.Fab")
		)
		(fp_line
			(start -0.67945 0.3048)
			(end -0.67945 -0.305054)
			(stroke
				(width 0.1)
				(type default)
			)
			(layer "F.Fab")
		)
		(fp_line
			(start -0.12065 -0.305054)
			(end -0.12065 -0.2794)
			(stroke
				(width 0.1)
				(type default)
			)
			(layer "F.Fab")
		)
		(fp_line
			(start -0.12065 -0.2794)
			(end 0.12065 -0.2794)
			(stroke
				(width 0.1)
				(type default)
			)
			(layer "F.Fab")
		)
		(fp_line
			(start -0.12065 0.2794)
			(end -0.12065 0.3048)
			(stroke
				(width 0.1)
				(type default)
			)
			(layer "F.Fab")
		)
		(fp_line
			(start -0.12065 0.3048)
			(end -0.67945 0.3048)
			(stroke
				(width 0.1)
				(type default)
			)
			(layer "F.Fab")
		)
		(fp_line
			(start 0.120396 0.2794)
			(end -0.12065 0.2794)
			(stroke
				(width 0.1)
				(type default)
			)
			(layer "F.Fab")
		)
		(fp_line
			(start 0.120396 0.3048)
			(end 0.120396 0.2794)
			(stroke
				(width 0.1)
				(type default)
			)
			(layer "F.Fab")
		)
		(fp_line
			(start 0.12065 -0.3048)
			(end 0.67945 -0.3048)
			(stroke
				(width 0.1)
				(type default)
			)
			(layer "F.Fab")
		)
		(fp_line
			(start 0.12065 -0.2794)
			(end 0.12065 -0.3048)
			(stroke
				(width 0.1)
				(type default)
			)
			(layer "F.Fab")
		)
		(fp_line
			(start 0.67945 -0.3048)
			(end 0.67945 0.3048)
			(stroke
				(width 0.1)
				(type default)
			)
			(layer "F.Fab")
		)
		(fp_line
			(start 0.67945 0.3048)
			(end 0.120396 0.3048)
			(stroke
				(width 0.1)
				(type default)
			)
			(layer "F.Fab")
		)
		(pad "1" smd circle
			(at -0.40005 0)
			(size 0 0)
			(layers "F.Cu" "F.Mask" "F.Paste")
			(net "P3V3_AUX")
		)
		(pad "2" smd circle
			(at 0.40005 0)
			(size 0 0)
			(layers "F.Cu" "F.Mask" "F.Paste")
			(net "PVDD11_S3_P0_VDDIO")
		)
	)
	(footprint ""
		(layer "F.Cu")
		(at 423.796206 -404.0124 -90)
		(property "Reference" "R1047"
			(at 0 0 270)
			(layer "F.SilkS")
			(hide yes)
			(effects
				(font
					(size 1.27 1.27)
				)
			)
		)
		(property "Value" ""
			(at 0 0 270)
			(layer "F.Fab")
			(effects
				(font
					(size 1.27 1.27)
				)
			)
		)
		(duplicate_pad_numbers_are_jumpers no)
		(fp_line
			(start -0.32512 0.175006)
			(end -0.32512 -0.175006)
			(stroke
				(width 0.1)
				(type default)
			)
			(layer "F.Fab")
		)
		(fp_line
			(start 0.32512 0.175006)
			(end -0.32512 0.175006)
			(stroke
				(width 0.1)
				(type default)
			)
			(layer "F.Fab")
		)
		(fp_line
			(start -0.32512 -0.175006)
			(end 0.32512 -0.175006)
			(stroke
				(width 0.1)
				(type default)
			)
			(layer "F.Fab")
		)
		(fp_line
			(start 0.32512 -0.175006)
			(end 0.32512 0.175006)
			(stroke
				(width 0.1)
				(type default)
			)
			(layer "F.Fab")
		)
		(pad "1" smd rect
			(at -0.2667 0 270)
			(size 0.3048 0.381)
			(layers "F.Cu" "F.Mask" "F.Paste")
			(net "RST_RT_CPU0_P2_PERST_N")
		)
		(pad "2" smd rect
			(at 0.2667 0 90)
			(size 0.3048 0.381)
			(layers "F.Cu" "F.Mask" "F.Paste")
			(net "RST_RT_CPU0_P2_PERST_R_N")
		)
	)
	(footprint ""
		(layer "F.Cu")
		(at 89.564972 -68.02374 90)
		(property "Reference" "PC2142"
			(at 0 0 90)
			(layer "F.SilkS")
			(hide yes)
			(effects
				(font
					(size 1.27 1.27)
				)
			)
		)
		(property "Value" ""
			(at 0 0 90)
			(layer "F.Fab")
			(effects
				(font
					(size 1.27 1.27)
				)
			)
		)
		(duplicate_pad_numbers_are_jumpers no)
		(fp_line
			(start 1.524 -0.762)
			(end 1.524 0.762)
			(stroke
				(width 0.1524)
				(type default)
			)
			(layer "F.SilkS")
		)
		(fp_line
			(start -1.524 -0.762)
			(end 1.524 -0.762)
			(stroke
				(width 0.1524)
				(type default)
			)
			(layer "F.SilkS")
		)
		(fp_line
			(start 1.524 0.762)
			(end -1.524 0.762)
			(stroke
				(width 0.1524)
				(type default)
			)
			(layer "F.SilkS")
		)
		(fp_line
			(start -1.524 0.762)
			(end -1.524 -0.762)
			(stroke
				(width 0.1524)
				(type default)
			)
			(layer "F.SilkS")
		)
		(fp_line
			(start 1.1049 -0.724916)
			(end -1.1049 -0.724916)
			(stroke
				(width 0.1)
				(type default)
			)
			(layer "F.Fab")
		)
		(fp_line
			(start -1.1049 -0.724916)
			(end -1.1049 0.724916)
			(stroke
				(width 0.1)
				(type default)
			)
			(layer "F.Fab")
		)
		(fp_line
			(start 1.1049 0.724916)
			(end 1.1049 -0.724916)
			(stroke
				(width 0.1)
				(type default)
			)
			(layer "F.Fab")
		)
		(fp_line
			(start -1.1049 0.724916)
			(end 1.1049 0.724916)
			(stroke
				(width 0.1)
				(type default)
			)
			(layer "F.Fab")
		)
		(pad "1" smd rect
			(at -0.889 0 270)
			(size 1.016 1.27)
			(layers "F.Cu" "F.Mask" "F.Paste")
			(net "P3V3_OCP_V3_2_R")
		)
		(pad "2" smd rect
			(at 0.889 0 270)
			(size 1.016 1.27)
			(layers "F.Cu" "F.Mask" "F.Paste")
			(net "GND")
		)
	)
	(footprint ""
		(layer "F.Cu")
		(at 335.114646 -404.873206 -90)
		(property "Reference" "R1024"
			(at 0 0 270)
			(layer "F.SilkS")
			(hide yes)
			(effects
				(font
					(size 1.27 1.27)
				)
			)
		)
		(property "Value" ""
			(at 0 0 270)
			(layer "F.Fab")
			(effects
				(font
					(size 1.27 1.27)
				)
			)
		)
		(duplicate_pad_numbers_are_jumpers no)
		(fp_line
			(start -0.32512 0.175006)
			(end -0.32512 -0.175006)
			(stroke
				(width 0.1)
				(type default)
			)
			(layer "F.Fab")
		)
		(fp_line
			(start 0.32512 0.175006)
			(end -0.32512 0.175006)
			(stroke
				(width 0.1)
				(type default)
			)
			(layer "F.Fab")
		)
		(fp_line
			(start -0.32512 -0.175006)
			(end 0.32512 -0.175006)
			(stroke
				(width 0.1)
				(type default)
			)
			(layer "F.Fab")
		)
		(fp_line
			(start 0.32512 -0.175006)
			(end 0.32512 0.175006)
			(stroke
				(width 0.1)
				(type default)
			)
			(layer "F.Fab")
		)
		(pad "1" smd rect
			(at -0.2667 0 270)
			(size 0.3048 0.381)
			(layers "F.Cu" "F.Mask" "F.Paste")
			(net "P1V8_CPU0_RT_1D")
		)
		(pad "2" smd rect
			(at 0.2667 0 90)
			(size 0.3048 0.381)
			(layers "F.Cu" "F.Mask" "F.Paste")
			(net "JTAG_TEST_MODE_RT_CPU0_P1")
		)
	)
	(footprint ""
		(layer "F.Cu")
		(at 160.441386 -117.206014 180)
		(property "Reference" "R2233"
			(at 0 0 180)
			(layer "F.SilkS")
			(hide yes)
			(effects
				(font
					(size 1.27 1.27)
				)
			)
		)
		(property "Value" ""
			(at 0 0 180)
			(layer "F.Fab")
			(effects
				(font
					(size 1.27 1.27)
				)
			)
		)
		(duplicate_pad_numbers_are_jumpers no)
		(fp_line
			(start 0.7874 0.4064)
			(end -0.7874 0.4064)
			(stroke
				(width 0.1524)
				(type default)
			)
			(layer "F.SilkS")
		)
		(fp_line
			(start 0.7874 -0.4064)
			(end 0.7874 0.4064)
			(stroke
				(width 0.1524)
				(type default)
			)
			(layer "F.SilkS")
		)
		(fp_line
			(start -0.7874 0.4064)
			(end -0.7874 -0.4064)
			(stroke
				(width 0.1524)
				(type default)
			)
			(layer "F.SilkS")
		)
		(fp_line
			(start -0.7874 -0.4064)
			(end 0.7874 -0.4064)
			(stroke
				(width 0.1524)
				(type default)
			)
			(layer "F.SilkS")
		)
		(fp_line
			(start 0.67945 0.3048)
			(end 0.120396 0.3048)
			(stroke
				(width 0.1)
				(type default)
			)
			(layer "F.Fab")
		)
		(fp_line
			(start 0.67945 -0.3048)
			(end 0.67945 0.3048)
			(stroke
				(width 0.1)
				(type default)
			)
			(layer "F.Fab")
		)
		(fp_line
			(start 0.12065 -0.2794)
			(end 0.12065 -0.3048)
			(stroke
				(width 0.1)
				(type default)
			)
			(layer "F.Fab")
		)
		(fp_line
			(start 0.12065 -0.3048)
			(end 0.67945 -0.3048)
			(stroke
				(width 0.1)
				(type default)
			)
			(layer "F.Fab")
		)
		(fp_line
			(start 0.120396 0.3048)
			(end 0.120396 0.2794)
			(stroke
				(width 0.1)
				(type default)
			)
			(layer "F.Fab")
		)
		(fp_line
			(start 0.120396 0.2794)
			(end -0.12065 0.2794)
			(stroke
				(width 0.1)
				(type default)
			)
			(layer "F.Fab")
		)
		(fp_line
			(start -0.12065 0.3048)
			(end -0.67945 0.3048)
			(stroke
				(width 0.1)
				(type default)
			)
			(layer "F.Fab")
		)
		(fp_line
			(start -0.12065 0.2794)
			(end -0.12065 0.3048)
			(stroke
				(width 0.1)
				(type default)
			)
			(layer "F.Fab")
		)
		(fp_line
			(start -0.12065 -0.2794)
			(end 0.12065 -0.2794)
			(stroke
				(width 0.1)
				(type default)
			)
			(layer "F.Fab")
		)
		(fp_line
			(start -0.12065 -0.305054)
			(end -0.12065 -0.2794)
			(stroke
				(width 0.1)
				(type default)
			)
			(layer "F.Fab")
		)
		(fp_line
			(start -0.67945 0.3048)
			(end -0.67945 -0.305054)
			(stroke
				(width 0.1)
				(type default)
			)
			(layer "F.Fab")
		)
		(fp_line
			(start -0.67945 -0.305054)
			(end -0.12065 -0.305054)
			(stroke
				(width 0.1)
				(type default)
			)
			(layer "F.Fab")
		)
		(pad "1" smd circle
			(at -0.40005 0 180)
			(size 0 0)
			(layers "F.Cu" "F.Mask" "F.Paste")
			(net "P3V3_AUX")
		)
		(pad "2" smd circle
			(at 0.40005 0 180)
			(size 0 0)
			(layers "F.Cu" "F.Mask" "F.Paste")
			(net "FM_UV_ADR_TRIGGER_N")
		)
	)
	(footprint ""
		(layer "F.Cu")
		(at 23.433278 -437.599074 -90)
		(property "Reference" "R2987"
			(at 0 0 270)
			(layer "F.SilkS")
			(hide yes)
			(effects
				(font
					(size 1.27 1.27)
				)
			)
		)
		(property "Value" ""
			(at 0 0 270)
			(layer "F.Fab")
			(effects
				(font
					(size 1.27 1.27)
				)
			)
		)
		(duplicate_pad_numbers_are_jumpers no)
		(fp_line
			(start -0.7874 0.4064)
			(end -0.7874 -0.4064)
			(stroke
				(width 0.1524)
				(type default)
			)
			(layer "F.SilkS")
		)
		(fp_line
			(start 0.7874 0.4064)
			(end -0.7874 0.4064)
			(stroke
				(width 0.1524)
				(type default)
			)
			(layer "F.SilkS")
		)
		(fp_line
			(start -0.7874 -0.4064)
			(end 0.7874 -0.4064)
			(stroke
				(width 0.1524)
				(type default)
			)
			(layer "F.SilkS")
		)
		(fp_line
			(start 0.7874 -0.4064)
			(end 0.7874 0.4064)
			(stroke
				(width 0.1524)
				(type default)
			)
			(layer "F.SilkS")
		)
		(fp_line
			(start -0.67945 0.3048)
			(end -0.67945 -0.305054)
			(stroke
				(width 0.1)
				(type default)
			)
			(layer "F.Fab")
		)
		(fp_line
			(start -0.12065 0.3048)
			(end -0.67945 0.3048)
			(stroke
				(width 0.1)
				(type default)
			)
			(layer "F.Fab")
		)
		(fp_line
			(start 0.120396 0.3048)
			(end 0.120396 0.2794)
			(stroke
				(width 0.1)
				(type default)
			)
			(layer "F.Fab")
		)
		(fp_line
			(start 0.67945 0.3048)
			(end 0.120396 0.3048)
			(stroke
				(width 0.1)
				(type default)
			)
			(layer "F.Fab")
		)
		(fp_line
			(start -0.12065 0.2794)
			(end -0.12065 0.3048)
			(stroke
				(width 0.1)
				(type default)
			)
			(layer "F.Fab")
		)
		(fp_line
			(start 0.120396 0.2794)
			(end -0.12065 0.2794)
			(stroke
				(width 0.1)
				(type default)
			)
			(layer "F.Fab")
		)
		(fp_line
			(start -0.12065 -0.2794)
			(end 0.12065 -0.2794)
			(stroke
				(width 0.1)
				(type default)
			)
			(layer "F.Fab")
		)
		(fp_line
			(start 0.12065 -0.2794)
			(end 0.12065 -0.3048)
			(stroke
				(width 0.1)
				(type default)
			)
			(layer "F.Fab")
		)
		(fp_line
			(start 0.12065 -0.3048)
			(end 0.67945 -0.3048)
			(stroke
				(width 0.1)
				(type default)
			)
			(layer "F.Fab")
		)
		(fp_line
			(start 0.67945 -0.3048)
			(end 0.67945 0.3048)
			(stroke
				(width 0.1)
				(type default)
			)
			(layer "F.Fab")
		)
		(fp_line
			(start -0.67945 -0.305054)
			(end -0.12065 -0.305054)
			(stroke
				(width 0.1)
				(type default)
			)
			(layer "F.Fab")
		)
		(fp_line
			(start -0.12065 -0.305054)
			(end -0.12065 -0.2794)
			(stroke
				(width 0.1)
				(type default)
			)
			(layer "F.Fab")
		)
		(pad "1" smd circle
			(at -0.40005 0 270)
			(size 0 0)
			(layers "F.Cu" "F.Mask" "F.Paste")
			(net "SMB_2_BMC_GPU_R_SDA")
		)
		(pad "2" smd circle
			(at 0.40005 0 270)
			(size 0 0)
			(layers "F.Cu" "F.Mask" "F.Paste")
			(net "SMB_2_BMC_GPU_BUF_R_SDA")
		)
	)
	(footprint ""
		(layer "F.Cu")
		(at 73.15073 -392.521694)
		(property "Reference" "L6"
			(at -2.3876 -2.969768 0)
			(unlocked yes)
			(layer "F.SilkS")
			(effects
				(font
					(size 0.7874 0.5842)
					(thickness 0.1524)
				)
				(justify left)
			)
		)
		(property "Value" ""
			(at 0 0 0)
			(layer "F.Fab")
			(effects
				(font
					(size 1.27 1.27)
				)
			)
		)
		(duplicate_pad_numbers_are_jumpers no)
		(fp_line
			(start -2.249932 -2.249932)
			(end 2.249932 -2.249932)
			(stroke
				(width 0.1524)
				(type default)
			)
			(layer "F.SilkS")
		)
		(fp_line
			(start -2.249932 -1.3843)
			(end -2.249932 -2.249932)
			(stroke
				(width 0.1524)
				(type default)
			)
			(layer "F.SilkS")
		)
		(fp_line
			(start -2.249932 2.249932)
			(end -2.249932 1.3843)
			(stroke
				(width 0.1524)
				(type default)
			)
			(layer "F.SilkS")
		)
		(fp_line
			(start 2.249932 -2.249932)
			(end 2.249932 -1.3843)
			(stroke
				(width 0.1524)
				(type default)
			)
			(layer "F.SilkS")
		)
		(fp_line
			(start 2.249932 1.3843)
			(end 2.249932 2.249932)
			(stroke
				(width 0.1524)
				(type default)
			)
			(layer "F.SilkS")
		)
		(fp_line
			(start 2.249932 2.249932)
			(end -2.249932 2.249932)
			(stroke
				(width 0.1524)
				(type default)
			)
			(layer "F.SilkS")
		)
		(fp_line
			(start -2.249932 -2.249932)
			(end 2.249932 -2.249932)
			(stroke
				(width 0.1)
				(type default)
			)
			(layer "F.Fab")
		)
		(fp_line
			(start -2.249932 2.249932)
			(end -2.249932 -2.249932)
			(stroke
				(width 0.1)
				(type default)
			)
			(layer "F.Fab")
		)
		(fp_line
			(start 2.249932 -2.249932)
			(end 2.249932 2.249932)
			(stroke
				(width 0.1)
				(type default)
			)
			(layer "F.Fab")
		)
		(fp_line
			(start 2.249932 2.249932)
			(end -2.249932 2.249932)
			(stroke
				(width 0.1)
				(type default)
			)
			(layer "F.Fab")
		)
		(pad "1" smd rect
			(at -1.82499 0)
			(size 1.0668 2.5146)
			(layers "F.Cu" "F.Mask" "F.Paste")
			(net "P0V9_CPU1_RT_2D")
		)
		(pad "2" smd rect
			(at 1.82499 0)
			(size 1.0668 2.5146)
			(layers "F.Cu" "F.Mask" "F.Paste")
			(net "P0V9_CPU1_RT1_2A")
		)
	)
	(footprint ""
		(layer "F.Cu")
		(at 178.689 -405.511 180)
		(property "Reference" "PC2192"
			(at 0 0 180)
			(layer "F.SilkS")
			(hide yes)
			(effects
				(font
					(size 1.27 1.27)
				)
			)
		)
		(property "Value" ""
			(at 0 0 180)
			(layer "F.Fab")
			(effects
				(font
					(size 1.27 1.27)
				)
			)
		)
		(duplicate_pad_numbers_are_jumpers no)
		(fp_line
			(start 0.7874 0.4064)
			(end -0.7874 0.4064)
			(stroke
				(width 0.1524)
				(type default)
			)
			(layer "F.SilkS")
		)
		(fp_line
			(start 0.7874 -0.4064)
			(end 0.7874 0.4064)
			(stroke
				(width 0.1524)
				(type default)
			)
			(layer "F.SilkS")
		)
		(fp_line
			(start -0.7874 0.4064)
			(end -0.7874 -0.4064)
			(stroke
				(width 0.1524)
				(type default)
			)
			(layer "F.SilkS")
		)
		(fp_line
			(start -0.7874 -0.4064)
			(end 0.7874 -0.4064)
			(stroke
				(width 0.1524)
				(type default)
			)
			(layer "F.SilkS")
		)
		(fp_line
			(start 0.67945 0.3048)
			(end 0.120396 0.3048)
			(stroke
				(width 0.1)
				(type default)
			)
			(layer "F.Fab")
		)
		(fp_line
			(start 0.67945 -0.3048)
			(end 0.67945 0.3048)
			(stroke
				(width 0.1)
				(type default)
			)
			(layer "F.Fab")
		)
		(fp_line
			(start 0.12065 -0.2794)
			(end 0.12065 -0.3048)
			(stroke
				(width 0.1)
				(type default)
			)
			(layer "F.Fab")
		)
		(fp_line
			(start 0.12065 -0.3048)
			(end 0.67945 -0.3048)
			(stroke
				(width 0.1)
				(type default)
			)
			(layer "F.Fab")
		)
		(fp_line
			(start 0.120396 0.3048)
			(end 0.120396 0.2794)
			(stroke
				(width 0.1)
				(type default)
			)
			(layer "F.Fab")
		)
		(fp_line
			(start 0.120396 0.2794)
			(end -0.12065 0.2794)
			(stroke
				(width 0.1)
				(type default)
			)
			(layer "F.Fab")
		)
		(fp_line
			(start -0.12065 0.3048)
			(end -0.67945 0.3048)
			(stroke
				(width 0.1)
				(type default)
			)
			(layer "F.Fab")
		)
		(fp_line
			(start -0.12065 0.2794)
			(end -0.12065 0.3048)
			(stroke
				(width 0.1)
				(type default)
			)
			(layer "F.Fab")
		)
		(fp_line
			(start -0.12065 -0.2794)
			(end 0.12065 -0.2794)
			(stroke
				(width 0.1)
				(type default)
			)
			(layer "F.Fab")
		)
		(fp_line
			(start -0.12065 -0.305054)
			(end -0.12065 -0.2794)
			(stroke
				(width 0.1)
				(type default)
			)
			(layer "F.Fab")
		)
		(fp_line
			(start -0.67945 0.3048)
			(end -0.67945 -0.305054)
			(stroke
				(width 0.1)
				(type default)
			)
			(layer "F.Fab")
		)
		(fp_line
			(start -0.67945 -0.305054)
			(end -0.12065 -0.305054)
			(stroke
				(width 0.1)
				(type default)
			)
			(layer "F.Fab")
		)
		(pad "1" smd circle
			(at -0.40005 0 180)
			(size 0 0)
			(layers "F.Cu" "F.Mask" "F.Paste")
			(net "HSC_VTEMP")
		)
		(pad "2" smd circle
			(at 0.40005 0 180)
			(size 0 0)
			(layers "F.Cu" "F.Mask" "F.Paste")
			(net "AGND_HSC")
		)
	)
	(footprint ""
		(layer "F.Cu")
		(at 389.653018 -404.0124 -90)
		(property "Reference" "R1123"
			(at 0 0 270)
			(layer "F.SilkS")
			(hide yes)
			(effects
				(font
					(size 1.27 1.27)
				)
			)
		)
		(property "Value" ""
			(at 0 0 270)
			(layer "F.Fab")
			(effects
				(font
					(size 1.27 1.27)
				)
			)
		)
		(duplicate_pad_numbers_are_jumpers no)
		(fp_line
			(start -0.32512 0.175006)
			(end -0.32512 -0.175006)
			(stroke
				(width 0.1)
				(type default)
			)
			(layer "F.Fab")
		)
		(fp_line
			(start 0.32512 0.175006)
			(end -0.32512 0.175006)
			(stroke
				(width 0.1)
				(type default)
			)
			(layer "F.Fab")
		)
		(fp_line
			(start -0.32512 -0.175006)
			(end 0.32512 -0.175006)
			(stroke
				(width 0.1)
				(type default)
			)
			(layer "F.Fab")
		)
		(fp_line
			(start 0.32512 -0.175006)
			(end 0.32512 0.175006)
			(stroke
				(width 0.1)
				(type default)
			)
			(layer "F.Fab")
		)
		(pad "1" smd rect
			(at -0.2667 0 270)
			(size 0.3048 0.381)
			(layers "F.Cu" "F.Mask" "F.Paste")
			(net "P1V8_CPU0_RT_1D")
		)
		(pad "2" smd rect
			(at 0.2667 0 90)
			(size 0.3048 0.381)
			(layers "F.Cu" "F.Mask" "F.Paste")
			(net "RT_CPU0_P3_VQPS")
		)
	)
	(footprint ""
		(layer "F.Cu")
		(at 145.669 -118.364)
		(property "Reference" "C8021"
			(at 0 0 0)
			(layer "F.SilkS")
			(hide yes)
			(effects
				(font
					(size 1.27 1.27)
				)
			)
		)
		(property "Value" ""
			(at 0 0 0)
			(layer "F.Fab")
			(effects
				(font
					(size 1.27 1.27)
				)
			)
		)
		(duplicate_pad_numbers_are_jumpers no)
		(fp_line
			(start -0.7874 -0.4064)
			(end 0.7874 -0.4064)
			(stroke
				(width 0.1524)
				(type default)
			)
			(layer "F.SilkS")
		)
		(fp_line
			(start -0.7874 0.4064)
			(end -0.7874 -0.4064)
			(stroke
				(width 0.1524)
				(type default)
			)
			(layer "F.SilkS")
		)
		(fp_line
			(start 0.7874 -0.4064)
			(end 0.7874 0.4064)
			(stroke
				(width 0.1524)
				(type default)
			)
			(layer "F.SilkS")
		)
		(fp_line
			(start 0.7874 0.4064)
			(end -0.7874 0.4064)
			(stroke
				(width 0.1524)
				(type default)
			)
			(layer "F.SilkS")
		)
		(fp_line
			(start -0.67945 -0.305054)
			(end -0.12065 -0.305054)
			(stroke
				(width 0.1)
				(type default)
			)
			(layer "F.Fab")
		)
		(fp_line
			(start -0.67945 0.3048)
			(end -0.67945 -0.305054)
			(stroke
				(width 0.1)
				(type default)
			)
			(layer "F.Fab")
		)
		(fp_line
			(start -0.12065 -0.305054)
			(end -0.12065 -0.2794)
			(stroke
				(width 0.1)
				(type default)
			)
			(layer "F.Fab")
		)
		(fp_line
			(start -0.12065 -0.2794)
			(end 0.12065 -0.2794)
			(stroke
				(width 0.1)
				(type default)
			)
			(layer "F.Fab")
		)
		(fp_line
			(start -0.12065 0.2794)
			(end -0.12065 0.3048)
			(stroke
				(width 0.1)
				(type default)
			)
			(layer "F.Fab")
		)
		(fp_line
			(start -0.12065 0.3048)
			(end -0.67945 0.3048)
			(stroke
				(width 0.1)
				(type default)
			)
			(layer "F.Fab")
		)
		(fp_line
			(start 0.120396 0.2794)
			(end -0.12065 0.2794)
			(stroke
				(width 0.1)
				(type default)
			)
			(layer "F.Fab")
		)
		(fp_line
			(start 0.120396 0.3048)
			(end 0.120396 0.2794)
			(stroke
				(width 0.1)
				(type default)
			)
			(layer "F.Fab")
		)
		(fp_line
			(start 0.12065 -0.3048)
			(end 0.67945 -0.3048)
			(stroke
				(width 0.1)
				(type default)
			)
			(layer "F.Fab")
		)
		(fp_line
			(start 0.12065 -0.2794)
			(end 0.12065 -0.3048)
			(stroke
				(width 0.1)
				(type default)
			)
			(layer "F.Fab")
		)
		(fp_line
			(start 0.67945 -0.3048)
			(end 0.67945 0.3048)
			(stroke
				(width 0.1)
				(type default)
			)
			(layer "F.Fab")
		)
		(fp_line
			(start 0.67945 0.3048)
			(end 0.120396 0.3048)
			(stroke
				(width 0.1)
				(type default)
			)
			(layer "F.Fab")
		)
		(pad "1" smd circle
			(at -0.40005 0)
			(size 0 0)
			(layers "F.Cu" "F.Mask" "F.Paste")
			(net "P12V_AUX_UV_TRIGGER")
		)
		(pad "2" smd circle
			(at 0.40005 0)
			(size 0 0)
			(layers "F.Cu" "F.Mask" "F.Paste")
			(net "GND")
		)
	)
	(footprint ""
		(layer "F.Cu")
		(at 424.609006 -402.7424 -90)
		(property "Reference" "R1084"
			(at 0 0 270)
			(layer "F.SilkS")
			(hide yes)
			(effects
				(font
					(size 1.27 1.27)
				)
			)
		)
		(property "Value" ""
			(at 0 0 270)
			(layer "F.Fab")
			(effects
				(font
					(size 1.27 1.27)
				)
			)
		)
		(duplicate_pad_numbers_are_jumpers no)
		(fp_line
			(start -0.32512 0.175006)
			(end -0.32512 -0.175006)
			(stroke
				(width 0.1)
				(type default)
			)
			(layer "F.Fab")
		)
		(fp_line
			(start 0.32512 0.175006)
			(end -0.32512 0.175006)
			(stroke
				(width 0.1)
				(type default)
			)
			(layer "F.Fab")
		)
		(fp_line
			(start -0.32512 -0.175006)
			(end 0.32512 -0.175006)
			(stroke
				(width 0.1)
				(type default)
			)
			(layer "F.Fab")
		)
		(fp_line
			(start 0.32512 -0.175006)
			(end 0.32512 0.175006)
			(stroke
				(width 0.1)
				(type default)
			)
			(layer "F.Fab")
		)
		(pad "1" smd rect
			(at -0.2667 0 270)
			(size 0.3048 0.381)
			(layers "F.Cu" "F.Mask" "F.Paste")
			(net "NCF_A1_CPU0_P2_GND")
		)
		(pad "2" smd rect
			(at 0.2667 0 90)
			(size 0.3048 0.381)
			(layers "F.Cu" "F.Mask" "F.Paste")
			(net "GND")
		)
	)
	(footprint ""
		(layer "F.Cu")
		(at 219.276676 -67.954144 -90)
		(property "Reference" "PR3964"
			(at 0 0 270)
			(layer "F.SilkS")
			(hide yes)
			(effects
				(font
					(size 1.27 1.27)
				)
			)
		)
		(property "Value" ""
			(at 0 0 270)
			(layer "F.Fab")
			(effects
				(font
					(size 1.27 1.27)
				)
			)
		)
		(duplicate_pad_numbers_are_jumpers no)
		(fp_line
			(start -0.7874 0.4064)
			(end -0.7874 -0.4064)
			(stroke
				(width 0.1524)
				(type default)
			)
			(layer "F.SilkS")
		)
		(fp_line
			(start 0.7874 0.4064)
			(end -0.7874 0.4064)
			(stroke
				(width 0.1524)
				(type default)
			)
			(layer "F.SilkS")
		)
		(fp_line
			(start -0.7874 -0.4064)
			(end 0.7874 -0.4064)
			(stroke
				(width 0.1524)
				(type default)
			)
			(layer "F.SilkS")
		)
		(fp_line
			(start 0.7874 -0.4064)
			(end 0.7874 0.4064)
			(stroke
				(width 0.1524)
				(type default)
			)
			(layer "F.SilkS")
		)
		(fp_line
			(start -0.67945 0.3048)
			(end -0.67945 -0.305054)
			(stroke
				(width 0.1)
				(type default)
			)
			(layer "F.Fab")
		)
		(fp_line
			(start -0.12065 0.3048)
			(end -0.67945 0.3048)
			(stroke
				(width 0.1)
				(type default)
			)
			(layer "F.Fab")
		)
		(fp_line
			(start 0.120396 0.3048)
			(end 0.120396 0.2794)
			(stroke
				(width 0.1)
				(type default)
			)
			(layer "F.Fab")
		)
		(fp_line
			(start 0.67945 0.3048)
			(end 0.120396 0.3048)
			(stroke
				(width 0.1)
				(type default)
			)
			(layer "F.Fab")
		)
		(fp_line
			(start -0.12065 0.2794)
			(end -0.12065 0.3048)
			(stroke
				(width 0.1)
				(type default)
			)
			(layer "F.Fab")
		)
		(fp_line
			(start 0.120396 0.2794)
			(end -0.12065 0.2794)
			(stroke
				(width 0.1)
				(type default)
			)
			(layer "F.Fab")
		)
		(fp_line
			(start -0.12065 -0.2794)
			(end 0.12065 -0.2794)
			(stroke
				(width 0.1)
				(type default)
			)
			(layer "F.Fab")
		)
		(fp_line
			(start 0.12065 -0.2794)
			(end 0.12065 -0.3048)
			(stroke
				(width 0.1)
				(type default)
			)
			(layer "F.Fab")
		)
		(fp_line
			(start 0.12065 -0.3048)
			(end 0.67945 -0.3048)
			(stroke
				(width 0.1)
				(type default)
			)
			(layer "F.Fab")
		)
		(fp_line
			(start 0.67945 -0.3048)
			(end 0.67945 0.3048)
			(stroke
				(width 0.1)
				(type default)
			)
			(layer "F.Fab")
		)
		(fp_line
			(start -0.67945 -0.305054)
			(end -0.12065 -0.305054)
			(stroke
				(width 0.1)
				(type default)
			)
			(layer "F.Fab")
		)
		(fp_line
			(start -0.12065 -0.305054)
			(end -0.12065 -0.2794)
			(stroke
				(width 0.1)
				(type default)
			)
			(layer "F.Fab")
		)
		(pad "1" smd circle
			(at -0.40005 0 270)
			(size 0 0)
			(layers "F.Cu" "F.Mask" "F.Paste")
			(net "P3V3_E1S_UV_0")
		)
		(pad "2" smd circle
			(at 0.40005 0 270)
			(size 0 0)
			(layers "F.Cu" "F.Mask" "F.Paste")
			(net "P3V3_E1S_OV_0")
		)
	)
	(footprint ""
		(layer "F.Cu")
		(at 205.243684 -120.944386)
		(property "Reference" "R4144"
			(at 0 0 0)
			(layer "F.SilkS")
			(hide yes)
			(effects
				(font
					(size 1.27 1.27)
				)
			)
		)
		(property "Value" ""
			(at 0 0 0)
			(layer "F.Fab")
			(effects
				(font
					(size 1.27 1.27)
				)
			)
		)
		(duplicate_pad_numbers_are_jumpers no)
		(fp_line
			(start -0.7874 -0.4064)
			(end 0.7874 -0.4064)
			(stroke
				(width 0.1524)
				(type default)
			)
			(layer "F.SilkS")
		)
		(fp_line
			(start -0.7874 0.4064)
			(end -0.7874 -0.4064)
			(stroke
				(width 0.1524)
				(type default)
			)
			(layer "F.SilkS")
		)
		(fp_line
			(start 0.7874 -0.4064)
			(end 0.7874 0.4064)
			(stroke
				(width 0.1524)
				(type default)
			)
			(layer "F.SilkS")
		)
		(fp_line
			(start 0.7874 0.4064)
			(end -0.7874 0.4064)
			(stroke
				(width 0.1524)
				(type default)
			)
			(layer "F.SilkS")
		)
		(fp_line
			(start -0.67945 -0.305054)
			(end -0.12065 -0.305054)
			(stroke
				(width 0.1)
				(type default)
			)
			(layer "F.Fab")
		)
		(fp_line
			(start -0.67945 0.3048)
			(end -0.67945 -0.305054)
			(stroke
				(width 0.1)
				(type default)
			)
			(layer "F.Fab")
		)
		(fp_line
			(start -0.12065 -0.305054)
			(end -0.12065 -0.2794)
			(stroke
				(width 0.1)
				(type default)
			)
			(layer "F.Fab")
		)
		(fp_line
			(start -0.12065 -0.2794)
			(end 0.12065 -0.2794)
			(stroke
				(width 0.1)
				(type default)
			)
			(layer "F.Fab")
		)
		(fp_line
			(start -0.12065 0.2794)
			(end -0.12065 0.3048)
			(stroke
				(width 0.1)
				(type default)
			)
			(layer "F.Fab")
		)
		(fp_line
			(start -0.12065 0.3048)
			(end -0.67945 0.3048)
			(stroke
				(width 0.1)
				(type default)
			)
			(layer "F.Fab")
		)
		(fp_line
			(start 0.120396 0.2794)
			(end -0.12065 0.2794)
			(stroke
				(width 0.1)
				(type default)
			)
			(layer "F.Fab")
		)
		(fp_line
			(start 0.120396 0.3048)
			(end 0.120396 0.2794)
			(stroke
				(width 0.1)
				(type default)
			)
			(layer "F.Fab")
		)
		(fp_line
			(start 0.12065 -0.3048)
			(end 0.67945 -0.3048)
			(stroke
				(width 0.1)
				(type default)
			)
			(layer "F.Fab")
		)
		(fp_line
			(start 0.12065 -0.2794)
			(end 0.12065 -0.3048)
			(stroke
				(width 0.1)
				(type default)
			)
			(layer "F.Fab")
		)
		(fp_line
			(start 0.67945 -0.3048)
			(end 0.67945 0.3048)
			(stroke
				(width 0.1)
				(type default)
			)
			(layer "F.Fab")
		)
		(fp_line
			(start 0.67945 0.3048)
			(end 0.120396 0.3048)
			(stroke
				(width 0.1)
				(type default)
			)
			(layer "F.Fab")
		)
		(pad "1" smd circle
			(at -0.40005 0)
			(size 0 0)
			(layers "F.Cu" "F.Mask" "F.Paste")
			(net "GPU_3V3IO_RSVD1_FFU_ISO_R")
		)
		(pad "2" smd circle
			(at 0.40005 0)
			(size 0 0)
			(layers "F.Cu" "F.Mask" "F.Paste")
			(net "GPU_3V3IO_RSVD1_FFU_ISO")
		)
	)
	(footprint ""
		(layer "F.Cu")
		(at 331.381862 -333.239364 90)
		(property "Reference" "PR506"
			(at 0 0 90)
			(layer "F.SilkS")
			(hide yes)
			(effects
				(font
					(size 1.27 1.27)
				)
			)
		)
		(property "Value" ""
			(at 0 0 90)
			(layer "F.Fab")
			(effects
				(font
					(size 1.27 1.27)
				)
			)
		)
		(duplicate_pad_numbers_are_jumpers no)
		(fp_line
			(start 0.7874 -0.4064)
			(end 0.7874 0.4064)
			(stroke
				(width 0.1524)
				(type default)
			)
			(layer "F.SilkS")
		)
		(fp_line
			(start -0.7874 -0.4064)
			(end 0.7874 -0.4064)
			(stroke
				(width 0.1524)
				(type default)
			)
			(layer "F.SilkS")
		)
		(fp_line
			(start 0.7874 0.4064)
			(end -0.7874 0.4064)
			(stroke
				(width 0.1524)
				(type default)
			)
			(layer "F.SilkS")
		)
		(fp_line
			(start -0.7874 0.4064)
			(end -0.7874 -0.4064)
			(stroke
				(width 0.1524)
				(type default)
			)
			(layer "F.SilkS")
		)
		(fp_line
			(start -0.12065 -0.305054)
			(end -0.12065 -0.2794)
			(stroke
				(width 0.1)
				(type default)
			)
			(layer "F.Fab")
		)
		(fp_line
			(start -0.67945 -0.305054)
			(end -0.12065 -0.305054)
			(stroke
				(width 0.1)
				(type default)
			)
			(layer "F.Fab")
		)
		(fp_line
			(start 0.67945 -0.3048)
			(end 0.67945 0.3048)
			(stroke
				(width 0.1)
				(type default)
			)
			(layer "F.Fab")
		)
		(fp_line
			(start 0.12065 -0.3048)
			(end 0.67945 -0.3048)
			(stroke
				(width 0.1)
				(type default)
			)
			(layer "F.Fab")
		)
		(fp_line
			(start 0.12065 -0.2794)
			(end 0.12065 -0.3048)
			(stroke
				(width 0.1)
				(type default)
			)
			(layer "F.Fab")
		)
		(fp_line
			(start -0.12065 -0.2794)
			(end 0.12065 -0.2794)
			(stroke
				(width 0.1)
				(type default)
			)
			(layer "F.Fab")
		)
		(fp_line
			(start 0.120396 0.2794)
			(end -0.12065 0.2794)
			(stroke
				(width 0.1)
				(type default)
			)
			(layer "F.Fab")
		)
		(fp_line
			(start -0.12065 0.2794)
			(end -0.12065 0.3048)
			(stroke
				(width 0.1)
				(type default)
			)
			(layer "F.Fab")
		)
		(fp_line
			(start 0.67945 0.3048)
			(end 0.120396 0.3048)
			(stroke
				(width 0.1)
				(type default)
			)
			(layer "F.Fab")
		)
		(fp_line
			(start 0.120396 0.3048)
			(end 0.120396 0.2794)
			(stroke
				(width 0.1)
				(type default)
			)
			(layer "F.Fab")
		)
		(fp_line
			(start -0.12065 0.3048)
			(end -0.67945 0.3048)
			(stroke
				(width 0.1)
				(type default)
			)
			(layer "F.Fab")
		)
		(fp_line
			(start -0.67945 0.3048)
			(end -0.67945 -0.305054)
			(stroke
				(width 0.1)
				(type default)
			)
			(layer "F.Fab")
		)
		(pad "1" smd circle
			(at -0.40005 0 90)
			(size 0 0)
			(layers "F.Cu" "F.Mask" "F.Paste")
			(net "SW_PVDDCR_CPU1_P0_SW1_RC")
		)
		(pad "2" smd circle
			(at 0.40005 0 90)
			(size 0 0)
			(layers "F.Cu" "F.Mask" "F.Paste")
			(net "GND")
		)
	)
	(footprint ""
		(layer "F.Cu")
		(at 177.927 -133.568948 -90)
		(property "Reference" "R197"
			(at 0 0 270)
			(layer "F.SilkS")
			(hide yes)
			(effects
				(font
					(size 1.27 1.27)
				)
			)
		)
		(property "Value" ""
			(at 0 0 270)
			(layer "F.Fab")
			(effects
				(font
					(size 1.27 1.27)
				)
			)
		)
		(duplicate_pad_numbers_are_jumpers no)
		(fp_line
			(start -0.7874 0.4064)
			(end -0.7874 -0.4064)
			(stroke
				(width 0.1524)
				(type default)
			)
			(layer "F.SilkS")
		)
		(fp_line
			(start 0.7874 0.4064)
			(end -0.7874 0.4064)
			(stroke
				(width 0.1524)
				(type default)
			)
			(layer "F.SilkS")
		)
		(fp_line
			(start -0.7874 -0.4064)
			(end 0.7874 -0.4064)
			(stroke
				(width 0.1524)
				(type default)
			)
			(layer "F.SilkS")
		)
		(fp_line
			(start 0.7874 -0.4064)
			(end 0.7874 0.4064)
			(stroke
				(width 0.1524)
				(type default)
			)
			(layer "F.SilkS")
		)
		(fp_line
			(start -0.67945 0.3048)
			(end -0.67945 -0.305054)
			(stroke
				(width 0.1)
				(type default)
			)
			(layer "F.Fab")
		)
		(fp_line
			(start -0.12065 0.3048)
			(end -0.67945 0.3048)
			(stroke
				(width 0.1)
				(type default)
			)
			(layer "F.Fab")
		)
		(fp_line
			(start 0.120396 0.3048)
			(end 0.120396 0.2794)
			(stroke
				(width 0.1)
				(type default)
			)
			(layer "F.Fab")
		)
		(fp_line
			(start 0.67945 0.3048)
			(end 0.120396 0.3048)
			(stroke
				(width 0.1)
				(type default)
			)
			(layer "F.Fab")
		)
		(fp_line
			(start -0.12065 0.2794)
			(end -0.12065 0.3048)
			(stroke
				(width 0.1)
				(type default)
			)
			(layer "F.Fab")
		)
		(fp_line
			(start 0.120396 0.2794)
			(end -0.12065 0.2794)
			(stroke
				(width 0.1)
				(type default)
			)
			(layer "F.Fab")
		)
		(fp_line
			(start -0.12065 -0.2794)
			(end 0.12065 -0.2794)
			(stroke
				(width 0.1)
				(type default)
			)
			(layer "F.Fab")
		)
		(fp_line
			(start 0.12065 -0.2794)
			(end 0.12065 -0.3048)
			(stroke
				(width 0.1)
				(type default)
			)
			(layer "F.Fab")
		)
		(fp_line
			(start 0.12065 -0.3048)
			(end 0.67945 -0.3048)
			(stroke
				(width 0.1)
				(type default)
			)
			(layer "F.Fab")
		)
		(fp_line
			(start 0.67945 -0.3048)
			(end 0.67945 0.3048)
			(stroke
				(width 0.1)
				(type default)
			)
			(layer "F.Fab")
		)
		(fp_line
			(start -0.67945 -0.305054)
			(end -0.12065 -0.305054)
			(stroke
				(width 0.1)
				(type default)
			)
			(layer "F.Fab")
		)
		(fp_line
			(start -0.12065 -0.305054)
			(end -0.12065 -0.2794)
			(stroke
				(width 0.1)
				(type default)
			)
			(layer "F.Fab")
		)
		(pad "1" smd circle
			(at -0.40005 0 270)
			(size 0 0)
			(layers "F.Cu" "F.Mask" "F.Paste")
			(net "RST_CPU1_PERST0_N")
		)
		(pad "2" smd circle
			(at 0.40005 0 270)
			(size 0 0)
			(layers "F.Cu" "F.Mask" "F.Paste")
			(net "RST_CPU1_PERST0_R_N")
		)
	)
	(footprint ""
		(layer "F.Cu")
		(at 359.567988 -409.388818 90)
		(property "Reference" "R3033"
			(at 0 0 90)
			(layer "F.SilkS")
			(hide yes)
			(effects
				(font
					(size 1.27 1.27)
				)
			)
		)
		(property "Value" ""
			(at 0 0 90)
			(layer "F.Fab")
			(effects
				(font
					(size 1.27 1.27)
				)
			)
		)
		(duplicate_pad_numbers_are_jumpers no)
		(fp_line
			(start 0.7874 -0.4064)
			(end 0.7874 0.4064)
			(stroke
				(width 0.1524)
				(type default)
			)
			(layer "F.SilkS")
		)
		(fp_line
			(start -0.7874 -0.4064)
			(end 0.7874 -0.4064)
			(stroke
				(width 0.1524)
				(type default)
			)
			(layer "F.SilkS")
		)
		(fp_line
			(start 0.7874 0.4064)
			(end -0.7874 0.4064)
			(stroke
				(width 0.1524)
				(type default)
			)
			(layer "F.SilkS")
		)
		(fp_line
			(start -0.7874 0.4064)
			(end -0.7874 -0.4064)
			(stroke
				(width 0.1524)
				(type default)
			)
			(layer "F.SilkS")
		)
		(fp_line
			(start -0.12065 -0.305054)
			(end -0.12065 -0.2794)
			(stroke
				(width 0.1)
				(type default)
			)
			(layer "F.Fab")
		)
		(fp_line
			(start -0.67945 -0.305054)
			(end -0.12065 -0.305054)
			(stroke
				(width 0.1)
				(type default)
			)
			(layer "F.Fab")
		)
		(fp_line
			(start 0.67945 -0.3048)
			(end 0.67945 0.3048)
			(stroke
				(width 0.1)
				(type default)
			)
			(layer "F.Fab")
		)
		(fp_line
			(start 0.12065 -0.3048)
			(end 0.67945 -0.3048)
			(stroke
				(width 0.1)
				(type default)
			)
			(layer "F.Fab")
		)
		(fp_line
			(start 0.12065 -0.2794)
			(end 0.12065 -0.3048)
			(stroke
				(width 0.1)
				(type default)
			)
			(layer "F.Fab")
		)
		(fp_line
			(start -0.12065 -0.2794)
			(end 0.12065 -0.2794)
			(stroke
				(width 0.1)
				(type default)
			)
			(layer "F.Fab")
		)
		(fp_line
			(start 0.120396 0.2794)
			(end -0.12065 0.2794)
			(stroke
				(width 0.1)
				(type default)
			)
			(layer "F.Fab")
		)
		(fp_line
			(start -0.12065 0.2794)
			(end -0.12065 0.3048)
			(stroke
				(width 0.1)
				(type default)
			)
			(layer "F.Fab")
		)
		(fp_line
			(start 0.67945 0.3048)
			(end 0.120396 0.3048)
			(stroke
				(width 0.1)
				(type default)
			)
			(layer "F.Fab")
		)
		(fp_line
			(start 0.120396 0.3048)
			(end 0.120396 0.2794)
			(stroke
				(width 0.1)
				(type default)
			)
			(layer "F.Fab")
		)
		(fp_line
			(start -0.12065 0.3048)
			(end -0.67945 0.3048)
			(stroke
				(width 0.1)
				(type default)
			)
			(layer "F.Fab")
		)
		(fp_line
			(start -0.67945 0.3048)
			(end -0.67945 -0.305054)
			(stroke
				(width 0.1)
				(type default)
			)
			(layer "F.Fab")
		)
		(pad "1" smd circle
			(at -0.40005 0 90)
			(size 0 0)
			(layers "F.Cu" "F.Mask" "F.Paste")
			(net "UART_BMC_BIC_RX")
		)
		(pad "2" smd circle
			(at 0.40005 0 90)
			(size 0 0)
			(layers "F.Cu" "F.Mask" "F.Paste")
			(net "UART_BMC_BIC_R_RX")
		)
	)
	(footprint ""
		(layer "F.Cu")
		(at 320.131694 -339.647022 -90)
		(property "Reference" "PC122"
			(at 0 0 270)
			(layer "F.SilkS")
			(hide yes)
			(effects
				(font
					(size 1.27 1.27)
				)
			)
		)
		(property "Value" ""
			(at 0 0 270)
			(layer "F.Fab")
			(effects
				(font
					(size 1.27 1.27)
				)
			)
		)
		(duplicate_pad_numbers_are_jumpers no)
		(fp_line
			(start -0.7874 0.4064)
			(end -0.7874 -0.4064)
			(stroke
				(width 0.1524)
				(type default)
			)
			(layer "F.SilkS")
		)
		(fp_line
			(start 0.7874 0.4064)
			(end -0.7874 0.4064)
			(stroke
				(width 0.1524)
				(type default)
			)
			(layer "F.SilkS")
		)
		(fp_line
			(start -0.7874 -0.4064)
			(end 0.7874 -0.4064)
			(stroke
				(width 0.1524)
				(type default)
			)
			(layer "F.SilkS")
		)
		(fp_line
			(start 0.7874 -0.4064)
			(end 0.7874 0.4064)
			(stroke
				(width 0.1524)
				(type default)
			)
			(layer "F.SilkS")
		)
		(fp_line
			(start -0.67945 0.3048)
			(end -0.67945 -0.305054)
			(stroke
				(width 0.1)
				(type default)
			)
			(layer "F.Fab")
		)
		(fp_line
			(start -0.12065 0.3048)
			(end -0.67945 0.3048)
			(stroke
				(width 0.1)
				(type default)
			)
			(layer "F.Fab")
		)
		(fp_line
			(start 0.120396 0.3048)
			(end 0.120396 0.2794)
			(stroke
				(width 0.1)
				(type default)
			)
			(layer "F.Fab")
		)
		(fp_line
			(start 0.67945 0.3048)
			(end 0.120396 0.3048)
			(stroke
				(width 0.1)
				(type default)
			)
			(layer "F.Fab")
		)
		(fp_line
			(start -0.12065 0.2794)
			(end -0.12065 0.3048)
			(stroke
				(width 0.1)
				(type default)
			)
			(layer "F.Fab")
		)
		(fp_line
			(start 0.120396 0.2794)
			(end -0.12065 0.2794)
			(stroke
				(width 0.1)
				(type default)
			)
			(layer "F.Fab")
		)
		(fp_line
			(start -0.12065 -0.2794)
			(end 0.12065 -0.2794)
			(stroke
				(width 0.1)
				(type default)
			)
			(layer "F.Fab")
		)
		(fp_line
			(start 0.12065 -0.2794)
			(end 0.12065 -0.3048)
			(stroke
				(width 0.1)
				(type default)
			)
			(layer "F.Fab")
		)
		(fp_line
			(start 0.12065 -0.3048)
			(end 0.67945 -0.3048)
			(stroke
				(width 0.1)
				(type default)
			)
			(layer "F.Fab")
		)
		(fp_line
			(start 0.67945 -0.3048)
			(end 0.67945 0.3048)
			(stroke
				(width 0.1)
				(type default)
			)
			(layer "F.Fab")
		)
		(fp_line
			(start -0.67945 -0.305054)
			(end -0.12065 -0.305054)
			(stroke
				(width 0.1)
				(type default)
			)
			(layer "F.Fab")
		)
		(fp_line
			(start -0.12065 -0.305054)
			(end -0.12065 -0.2794)
			(stroke
				(width 0.1)
				(type default)
			)
			(layer "F.Fab")
		)
		(pad "1" smd circle
			(at -0.40005 0 270)
			(size 0 0)
			(layers "F.Cu" "F.Mask" "F.Paste")
			(net "SW_PVDDCR_CPU1_P0_BOOT3_R")
		)
		(pad "2" smd circle
			(at 0.40005 0 270)
			(size 0 0)
			(layers "F.Cu" "F.Mask" "F.Paste")
			(net "SW_PVDDCR_CPU1_P0_BOOTR3")
		)
	)
	(footprint ""
		(layer "F.Cu")
		(at 100.920296 -425.82973 -90)
		(property "Reference" "R4186"
			(at 0 0 270)
			(layer "F.SilkS")
			(hide yes)
			(effects
				(font
					(size 1.27 1.27)
				)
			)
		)
		(property "Value" ""
			(at 0 0 270)
			(layer "F.Fab")
			(effects
				(font
					(size 1.27 1.27)
				)
			)
		)
		(duplicate_pad_numbers_are_jumpers no)
		(fp_line
			(start -0.7874 0.4064)
			(end -0.7874 -0.4064)
			(stroke
				(width 0.1524)
				(type default)
			)
			(layer "F.SilkS")
		)
		(fp_line
			(start 0.7874 0.4064)
			(end -0.7874 0.4064)
			(stroke
				(width 0.1524)
				(type default)
			)
			(layer "F.SilkS")
		)
		(fp_line
			(start -0.7874 -0.4064)
			(end 0.7874 -0.4064)
			(stroke
				(width 0.1524)
				(type default)
			)
			(layer "F.SilkS")
		)
		(fp_line
			(start 0.7874 -0.4064)
			(end 0.7874 0.4064)
			(stroke
				(width 0.1524)
				(type default)
			)
			(layer "F.SilkS")
		)
		(fp_line
			(start -0.67945 0.3048)
			(end -0.67945 -0.305054)
			(stroke
				(width 0.1)
				(type default)
			)
			(layer "F.Fab")
		)
		(fp_line
			(start -0.12065 0.3048)
			(end -0.67945 0.3048)
			(stroke
				(width 0.1)
				(type default)
			)
			(layer "F.Fab")
		)
		(fp_line
			(start 0.120396 0.3048)
			(end 0.120396 0.2794)
			(stroke
				(width 0.1)
				(type default)
			)
			(layer "F.Fab")
		)
		(fp_line
			(start 0.67945 0.3048)
			(end 0.120396 0.3048)
			(stroke
				(width 0.1)
				(type default)
			)
			(layer "F.Fab")
		)
		(fp_line
			(start -0.12065 0.2794)
			(end -0.12065 0.3048)
			(stroke
				(width 0.1)
				(type default)
			)
			(layer "F.Fab")
		)
		(fp_line
			(start 0.120396 0.2794)
			(end -0.12065 0.2794)
			(stroke
				(width 0.1)
				(type default)
			)
			(layer "F.Fab")
		)
		(fp_line
			(start -0.12065 -0.2794)
			(end 0.12065 -0.2794)
			(stroke
				(width 0.1)
				(type default)
			)
			(layer "F.Fab")
		)
		(fp_line
			(start 0.12065 -0.2794)
			(end 0.12065 -0.3048)
			(stroke
				(width 0.1)
				(type default)
			)
			(layer "F.Fab")
		)
		(fp_line
			(start 0.12065 -0.3048)
			(end 0.67945 -0.3048)
			(stroke
				(width 0.1)
				(type default)
			)
			(layer "F.Fab")
		)
		(fp_line
			(start 0.67945 -0.3048)
			(end 0.67945 0.3048)
			(stroke
				(width 0.1)
				(type default)
			)
			(layer "F.Fab")
		)
		(fp_line
			(start -0.67945 -0.305054)
			(end -0.12065 -0.305054)
			(stroke
				(width 0.1)
				(type default)
			)
			(layer "F.Fab")
		)
		(fp_line
			(start -0.12065 -0.305054)
			(end -0.12065 -0.2794)
			(stroke
				(width 0.1)
				(type default)
			)
			(layer "F.Fab")
		)
		(pad "1" smd circle
			(at -0.40005 0 270)
			(size 0 0)
			(layers "F.Cu" "F.Mask" "F.Paste")
			(net "P3V3_AUX")
		)
		(pad "2" smd circle
			(at 0.40005 0 270)
			(size 0 0)
			(layers "F.Cu" "F.Mask" "F.Paste")
			(net "U272_2_ADD2")
		)
	)
	(footprint ""
		(layer "F.Cu")
		(at 110.527084 -261.748016 -90)
		(property "Reference" "C2504"
			(at 0 0 270)
			(layer "F.SilkS")
			(hide yes)
			(effects
				(font
					(size 1.27 1.27)
				)
			)
		)
		(property "Value" ""
			(at 0 0 270)
			(layer "F.Fab")
			(effects
				(font
					(size 1.27 1.27)
				)
			)
		)
		(duplicate_pad_numbers_are_jumpers no)
		(fp_line
			(start -0.7874 0.4064)
			(end -0.7874 -0.4064)
			(stroke
				(width 0.1524)
				(type default)
			)
			(layer "F.SilkS")
		)
		(fp_line
			(start 0.7874 0.4064)
			(end -0.7874 0.4064)
			(stroke
				(width 0.1524)
				(type default)
			)
			(layer "F.SilkS")
		)
		(fp_line
			(start -0.7874 -0.4064)
			(end 0.7874 -0.4064)
			(stroke
				(width 0.1524)
				(type default)
			)
			(layer "F.SilkS")
		)
		(fp_line
			(start 0.7874 -0.4064)
			(end 0.7874 0.4064)
			(stroke
				(width 0.1524)
				(type default)
			)
			(layer "F.SilkS")
		)
		(fp_line
			(start -0.67945 0.3048)
			(end -0.67945 -0.305054)
			(stroke
				(width 0.1)
				(type default)
			)
			(layer "F.Fab")
		)
		(fp_line
			(start -0.12065 0.3048)
			(end -0.67945 0.3048)
			(stroke
				(width 0.1)
				(type default)
			)
			(layer "F.Fab")
		)
		(fp_line
			(start 0.120396 0.3048)
			(end 0.120396 0.2794)
			(stroke
				(width 0.1)
				(type default)
			)
			(layer "F.Fab")
		)
		(fp_line
			(start 0.67945 0.3048)
			(end 0.120396 0.3048)
			(stroke
				(width 0.1)
				(type default)
			)
			(layer "F.Fab")
		)
		(fp_line
			(start -0.12065 0.2794)
			(end -0.12065 0.3048)
			(stroke
				(width 0.1)
				(type default)
			)
			(layer "F.Fab")
		)
		(fp_line
			(start 0.120396 0.2794)
			(end -0.12065 0.2794)
			(stroke
				(width 0.1)
				(type default)
			)
			(layer "F.Fab")
		)
		(fp_line
			(start -0.12065 -0.2794)
			(end 0.12065 -0.2794)
			(stroke
				(width 0.1)
				(type default)
			)
			(layer "F.Fab")
		)
		(fp_line
			(start 0.12065 -0.2794)
			(end 0.12065 -0.3048)
			(stroke
				(width 0.1)
				(type default)
			)
			(layer "F.Fab")
		)
		(fp_line
			(start 0.12065 -0.3048)
			(end 0.67945 -0.3048)
			(stroke
				(width 0.1)
				(type default)
			)
			(layer "F.Fab")
		)
		(fp_line
			(start 0.67945 -0.3048)
			(end 0.67945 0.3048)
			(stroke
				(width 0.1)
				(type default)
			)
			(layer "F.Fab")
		)
		(fp_line
			(start -0.67945 -0.305054)
			(end -0.12065 -0.305054)
			(stroke
				(width 0.1)
				(type default)
			)
			(layer "F.Fab")
		)
		(fp_line
			(start -0.12065 -0.305054)
			(end -0.12065 -0.2794)
			(stroke
				(width 0.1)
				(type default)
			)
			(layer "F.Fab")
		)
		(pad "1" smd circle
			(at -0.40005 0 270)
			(size 0 0)
			(layers "F.Cu" "F.Mask" "F.Paste")
			(net "PVDD11_S3_P1")
		)
		(pad "2" smd circle
			(at 0.40005 0 270)
			(size 0 0)
			(layers "F.Cu" "F.Mask" "F.Paste")
			(net "GND")
		)
	)
	(footprint ""
		(layer "F.Cu")
		(at 403.013418 -135.58139 180)
		(property "Reference" "Q50"
			(at 0.719074 2.0066 0)
			(unlocked yes)
			(layer "F.SilkS")
			(effects
				(font
					(size 0.7874 0.5842)
					(thickness 0.1524)
				)
				(justify left)
			)
		)
		(property "Value" ""
			(at 0 0 180)
			(layer "F.Fab")
			(effects
				(font
					(size 1.27 1.27)
				)
			)
		)
		(duplicate_pad_numbers_are_jumpers no)
		(fp_line
			(start 1.332738 1.100074)
			(end -1.332738 1.100074)
			(stroke
				(width 0.1524)
				(type default)
			)
			(layer "F.SilkS")
		)
		(fp_line
			(start 1.332738 -1.100074)
			(end 1.332738 1.100074)
			(stroke
				(width 0.1524)
				(type default)
			)
			(layer "F.SilkS")
		)
		(fp_line
			(start 0.4826 -1.100074)
			(end 1.332738 -1.100074)
			(stroke
				(width 0.1524)
				(type default)
			)
			(layer "F.SilkS")
		)
		(fp_line
			(start 0 -0.541274)
			(end 0.4826 -1.100074)
			(stroke
				(width 0.1524)
				(type default)
			)
			(layer "F.SilkS")
		)
		(fp_line
			(start -0.4826 -1.100074)
			(end 0 -0.541274)
			(stroke
				(width 0.1524)
				(type default)
			)
			(layer "F.SilkS")
		)
		(fp_line
			(start -1.332738 1.100074)
			(end -1.332738 -1.100074)
			(stroke
				(width 0.1524)
				(type default)
			)
			(layer "F.SilkS")
		)
		(fp_line
			(start -1.332738 -1.100074)
			(end -0.4826 -1.100074)
			(stroke
				(width 0.1524)
				(type default)
			)
			(layer "F.SilkS")
		)
		(fp_poly
			(pts
				(xy -1.823212 -0.905764) (xy -2.525268 -0.554736) (xy -2.525268 -1.256792)
			)
			(stroke
				(width 0)
				(type default)
			)
			(fill yes)
			(layer "F.SilkS")
		)
		(fp_line
			(start 0.674878 1.100074)
			(end -0.674878 1.100074)
			(stroke
				(width 0.1)
				(type default)
			)
			(layer "F.Fab")
		)
		(fp_line
			(start 0.674878 -1.100074)
			(end 0.674878 1.100074)
			(stroke
				(width 0.1)
				(type default)
			)
			(layer "F.Fab")
		)
		(fp_line
			(start -0.674878 1.100074)
			(end -0.674878 -1.100074)
			(stroke
				(width 0.1)
				(type default)
			)
			(layer "F.Fab")
		)
		(fp_line
			(start -0.674878 -1.100074)
			(end 0.674878 -1.100074)
			(stroke
				(width 0.1)
				(type default)
			)
			(layer "F.Fab")
		)
		(fp_poly
			(pts
				(xy -2.2352 -0.298958) (xy -2.2352 -1.001014) (xy -1.533144 -0.649986)
			)
			(stroke
				(width 0)
				(type default)
			)
			(fill yes)
			(layer "F.Fab")
		)
		(pad "1" smd rect
			(at -0.94996 -0.649986 270)
			(size 0.4318 0.508)
			(layers "F.Cu" "F.Mask" "F.Paste")
			(net "GND")
		)
		(pad "2" smd rect
			(at -0.94996 0 270)
			(size 0.4318 0.508)
			(layers "F.Cu" "F.Mask" "F.Paste")
			(net "PWRGD_P5V_AUX")
		)
		(pad "3" smd rect
			(at -0.94996 0.649986 270)
			(size 0.4318 0.508)
			(layers "F.Cu" "F.Mask" "F.Paste")
			(net "PWRGD_P5V_AUX_R2")
		)
		(pad "4" smd rect
			(at 0.94996 0.649986 270)
			(size 0.4318 0.508)
			(layers "F.Cu" "F.Mask" "F.Paste")
			(net "GND")
		)
		(pad "5" smd rect
			(at 0.94996 0 270)
			(size 0.4318 0.508)
			(layers "F.Cu" "F.Mask" "F.Paste")
			(net "PWRGD_P5V_AUX_R1")
		)
		(pad "6" smd rect
			(at 0.94996 -0.649986 270)
			(size 0.4318 0.508)
			(layers "F.Cu" "F.Mask" "F.Paste")
			(net "PWRGD_P5V_AUX_R1")
		)
	)
	(footprint ""
		(layer "F.Cu")
		(at 332.807564 -135.156702 180)
		(property "Reference" "PC254"
			(at 0 0 180)
			(layer "F.SilkS")
			(hide yes)
			(effects
				(font
					(size 1.27 1.27)
				)
			)
		)
		(property "Value" ""
			(at 0 0 180)
			(layer "F.Fab")
			(effects
				(font
					(size 1.27 1.27)
				)
			)
		)
		(duplicate_pad_numbers_are_jumpers no)
		(fp_line
			(start 1.524 0.762)
			(end -1.524 0.762)
			(stroke
				(width 0.1524)
				(type default)
			)
			(layer "F.SilkS")
		)
		(fp_line
			(start 1.524 -0.762)
			(end 1.524 0.762)
			(stroke
				(width 0.1524)
				(type default)
			)
			(layer "F.SilkS")
		)
		(fp_line
			(start -1.524 0.762)
			(end -1.524 -0.762)
			(stroke
				(width 0.1524)
				(type default)
			)
			(layer "F.SilkS")
		)
		(fp_line
			(start -1.524 -0.762)
			(end 1.524 -0.762)
			(stroke
				(width 0.1524)
				(type default)
			)
			(layer "F.SilkS")
		)
		(fp_line
			(start 1.1049 0.724916)
			(end 1.1049 -0.724916)
			(stroke
				(width 0.1)
				(type default)
			)
			(layer "F.Fab")
		)
		(fp_line
			(start 1.1049 -0.724916)
			(end -1.1049 -0.724916)
			(stroke
				(width 0.1)
				(type default)
			)
			(layer "F.Fab")
		)
		(fp_line
			(start -1.1049 0.724916)
			(end 1.1049 0.724916)
			(stroke
				(width 0.1)
				(type default)
			)
			(layer "F.Fab")
		)
		(fp_line
			(start -1.1049 -0.724916)
			(end -1.1049 0.724916)
			(stroke
				(width 0.1)
				(type default)
			)
			(layer "F.Fab")
		)
		(pad "1" smd rect
			(at -0.889 0)
			(size 1.016 1.27)
			(layers "F.Cu" "F.Mask" "F.Paste")
			(net "SW_P12V_AUX_PVDD18_S5_P0_FLT")
		)
		(pad "2" smd rect
			(at 0.889 0)
			(size 1.016 1.27)
			(layers "F.Cu" "F.Mask" "F.Paste")
			(net "GND")
		)
	)
	(footprint ""
		(layer "F.Cu")
		(at 362.528104 -173.119542 90)
		(property "Reference" "PC489"
			(at 0 0 90)
			(layer "F.SilkS")
			(hide yes)
			(effects
				(font
					(size 1.27 1.27)
				)
			)
		)
		(property "Value" ""
			(at 0 0 90)
			(layer "F.Fab")
			(effects
				(font
					(size 1.27 1.27)
				)
			)
		)
		(duplicate_pad_numbers_are_jumpers no)
		(fp_line
			(start 0.7874 -0.4064)
			(end 0.7874 0.4064)
			(stroke
				(width 0.1524)
				(type default)
			)
			(layer "F.SilkS")
		)
		(fp_line
			(start -0.7874 -0.4064)
			(end 0.7874 -0.4064)
			(stroke
				(width 0.1524)
				(type default)
			)
			(layer "F.SilkS")
		)
		(fp_line
			(start 0.7874 0.4064)
			(end -0.7874 0.4064)
			(stroke
				(width 0.1524)
				(type default)
			)
			(layer "F.SilkS")
		)
		(fp_line
			(start -0.7874 0.4064)
			(end -0.7874 -0.4064)
			(stroke
				(width 0.1524)
				(type default)
			)
			(layer "F.SilkS")
		)
		(fp_line
			(start -0.12065 -0.305054)
			(end -0.12065 -0.2794)
			(stroke
				(width 0.1)
				(type default)
			)
			(layer "F.Fab")
		)
		(fp_line
			(start -0.67945 -0.305054)
			(end -0.12065 -0.305054)
			(stroke
				(width 0.1)
				(type default)
			)
			(layer "F.Fab")
		)
		(fp_line
			(start 0.67945 -0.3048)
			(end 0.67945 0.3048)
			(stroke
				(width 0.1)
				(type default)
			)
			(layer "F.Fab")
		)
		(fp_line
			(start 0.12065 -0.3048)
			(end 0.67945 -0.3048)
			(stroke
				(width 0.1)
				(type default)
			)
			(layer "F.Fab")
		)
		(fp_line
			(start 0.12065 -0.2794)
			(end 0.12065 -0.3048)
			(stroke
				(width 0.1)
				(type default)
			)
			(layer "F.Fab")
		)
		(fp_line
			(start -0.12065 -0.2794)
			(end 0.12065 -0.2794)
			(stroke
				(width 0.1)
				(type default)
			)
			(layer "F.Fab")
		)
		(fp_line
			(start 0.120396 0.2794)
			(end -0.12065 0.2794)
			(stroke
				(width 0.1)
				(type default)
			)
			(layer "F.Fab")
		)
		(fp_line
			(start -0.12065 0.2794)
			(end -0.12065 0.3048)
			(stroke
				(width 0.1)
				(type default)
			)
			(layer "F.Fab")
		)
		(fp_line
			(start 0.67945 0.3048)
			(end 0.120396 0.3048)
			(stroke
				(width 0.1)
				(type default)
			)
			(layer "F.Fab")
		)
		(fp_line
			(start 0.120396 0.3048)
			(end 0.120396 0.2794)
			(stroke
				(width 0.1)
				(type default)
			)
			(layer "F.Fab")
		)
		(fp_line
			(start -0.12065 0.3048)
			(end -0.67945 0.3048)
			(stroke
				(width 0.1)
				(type default)
			)
			(layer "F.Fab")
		)
		(fp_line
			(start -0.67945 0.3048)
			(end -0.67945 -0.305054)
			(stroke
				(width 0.1)
				(type default)
			)
			(layer "F.Fab")
		)
		(pad "1" smd circle
			(at -0.40005 0 90)
			(size 0 0)
			(layers "F.Cu" "F.Mask" "F.Paste")
			(net "SW_PVDDCR_CPU0_P0_BOOT1_RC")
		)
		(pad "2" smd circle
			(at 0.40005 0 90)
			(size 0 0)
			(layers "F.Cu" "F.Mask" "F.Paste")
			(net "SW_PVDDCR_CPU0_P0_PH1")
		)
	)
	(footprint ""
		(layer "F.Cu")
		(at 159.893 -108.458 180)
		(property "Reference" "R9026"
			(at 0 0 180)
			(layer "F.SilkS")
			(hide yes)
			(effects
				(font
					(size 1.27 1.27)
				)
			)
		)
		(property "Value" ""
			(at 0 0 180)
			(layer "F.Fab")
			(effects
				(font
					(size 1.27 1.27)
				)
			)
		)
		(duplicate_pad_numbers_are_jumpers no)
		(fp_line
			(start 0.7874 0.4064)
			(end -0.7874 0.4064)
			(stroke
				(width 0.1524)
				(type default)
			)
			(layer "F.SilkS")
		)
		(fp_line
			(start 0.7874 -0.4064)
			(end 0.7874 0.4064)
			(stroke
				(width 0.1524)
				(type default)
			)
			(layer "F.SilkS")
		)
		(fp_line
			(start -0.7874 0.4064)
			(end -0.7874 -0.4064)
			(stroke
				(width 0.1524)
				(type default)
			)
			(layer "F.SilkS")
		)
		(fp_line
			(start -0.7874 -0.4064)
			(end 0.7874 -0.4064)
			(stroke
				(width 0.1524)
				(type default)
			)
			(layer "F.SilkS")
		)
		(fp_line
			(start 0.67945 0.3048)
			(end 0.120396 0.3048)
			(stroke
				(width 0.1)
				(type default)
			)
			(layer "F.Fab")
		)
		(fp_line
			(start 0.67945 -0.3048)
			(end 0.67945 0.3048)
			(stroke
				(width 0.1)
				(type default)
			)
			(layer "F.Fab")
		)
		(fp_line
			(start 0.12065 -0.2794)
			(end 0.12065 -0.3048)
			(stroke
				(width 0.1)
				(type default)
			)
			(layer "F.Fab")
		)
		(fp_line
			(start 0.12065 -0.3048)
			(end 0.67945 -0.3048)
			(stroke
				(width 0.1)
				(type default)
			)
			(layer "F.Fab")
		)
		(fp_line
			(start 0.120396 0.3048)
			(end 0.120396 0.2794)
			(stroke
				(width 0.1)
				(type default)
			)
			(layer "F.Fab")
		)
		(fp_line
			(start 0.120396 0.2794)
			(end -0.12065 0.2794)
			(stroke
				(width 0.1)
				(type default)
			)
			(layer "F.Fab")
		)
		(fp_line
			(start -0.12065 0.3048)
			(end -0.67945 0.3048)
			(stroke
				(width 0.1)
				(type default)
			)
			(layer "F.Fab")
		)
		(fp_line
			(start -0.12065 0.2794)
			(end -0.12065 0.3048)
			(stroke
				(width 0.1)
				(type default)
			)
			(layer "F.Fab")
		)
		(fp_line
			(start -0.12065 -0.2794)
			(end 0.12065 -0.2794)
			(stroke
				(width 0.1)
				(type default)
			)
			(layer "F.Fab")
		)
		(fp_line
			(start -0.12065 -0.305054)
			(end -0.12065 -0.2794)
			(stroke
				(width 0.1)
				(type default)
			)
			(layer "F.Fab")
		)
		(fp_line
			(start -0.67945 0.3048)
			(end -0.67945 -0.305054)
			(stroke
				(width 0.1)
				(type default)
			)
			(layer "F.Fab")
		)
		(fp_line
			(start -0.67945 -0.305054)
			(end -0.12065 -0.305054)
			(stroke
				(width 0.1)
				(type default)
			)
			(layer "F.Fab")
		)
		(pad "1" smd circle
			(at -0.40005 0 180)
			(size 0 0)
			(layers "F.Cu" "F.Mask" "F.Paste")
			(net "P3V3_AUX")
		)
		(pad "2" smd circle
			(at 0.40005 0 180)
			(size 0 0)
			(layers "F.Cu" "F.Mask" "F.Paste")
			(net "IRQ_HSC_FAULT")
		)
	)
	(footprint ""
		(layer "F.Cu")
		(at 166.18077 -395.6304 -90)
		(property "Reference" "R6794"
			(at 0 0 270)
			(layer "F.SilkS")
			(hide yes)
			(effects
				(font
					(size 1.27 1.27)
				)
			)
		)
		(property "Value" ""
			(at 0 0 270)
			(layer "F.Fab")
			(effects
				(font
					(size 1.27 1.27)
				)
			)
		)
		(duplicate_pad_numbers_are_jumpers no)
		(fp_line
			(start -0.32512 0.175006)
			(end -0.32512 -0.175006)
			(stroke
				(width 0.1)
				(type default)
			)
			(layer "F.Fab")
		)
		(fp_line
			(start 0.32512 0.175006)
			(end -0.32512 0.175006)
			(stroke
				(width 0.1)
				(type default)
			)
			(layer "F.Fab")
		)
		(fp_line
			(start -0.32512 -0.175006)
			(end 0.32512 -0.175006)
			(stroke
				(width 0.1)
				(type default)
			)
			(layer "F.Fab")
		)
		(fp_line
			(start 0.32512 -0.175006)
			(end 0.32512 0.175006)
			(stroke
				(width 0.1)
				(type default)
			)
			(layer "F.Fab")
		)
		(pad "1" smd rect
			(at -0.2667 0 270)
			(size 0.3048 0.381)
			(layers "F.Cu" "F.Mask" "F.Paste")
			(net "P1V8_CPU1_RT_1D")
		)
		(pad "2" smd rect
			(at 0.2667 0 90)
			(size 0.3048 0.381)
			(layers "F.Cu" "F.Mask" "F.Paste")
			(net "RT_CPU1_P2_VQPS")
		)
	)
	(footprint ""
		(layer "F.Cu")
		(at 441.530486 -21.676106)
		(property "Reference" "R1301"
			(at 0 0 0)
			(layer "F.SilkS")
			(hide yes)
			(effects
				(font
					(size 1.27 1.27)
				)
			)
		)
		(property "Value" ""
			(at 0 0 0)
			(layer "F.Fab")
			(effects
				(font
					(size 1.27 1.27)
				)
			)
		)
		(duplicate_pad_numbers_are_jumpers no)
		(fp_line
			(start -0.7874 -0.4064)
			(end 0.7874 -0.4064)
			(stroke
				(width 0.1524)
				(type default)
			)
			(layer "F.SilkS")
		)
		(fp_line
			(start -0.7874 0.4064)
			(end -0.7874 -0.4064)
			(stroke
				(width 0.1524)
				(type default)
			)
			(layer "F.SilkS")
		)
		(fp_line
			(start 0.7874 -0.4064)
			(end 0.7874 0.4064)
			(stroke
				(width 0.1524)
				(type default)
			)
			(layer "F.SilkS")
		)
		(fp_line
			(start 0.7874 0.4064)
			(end -0.7874 0.4064)
			(stroke
				(width 0.1524)
				(type default)
			)
			(layer "F.SilkS")
		)
		(fp_line
			(start -0.67945 -0.305054)
			(end -0.12065 -0.305054)
			(stroke
				(width 0.1)
				(type default)
			)
			(layer "F.Fab")
		)
		(fp_line
			(start -0.67945 0.3048)
			(end -0.67945 -0.305054)
			(stroke
				(width 0.1)
				(type default)
			)
			(layer "F.Fab")
		)
		(fp_line
			(start -0.12065 -0.305054)
			(end -0.12065 -0.2794)
			(stroke
				(width 0.1)
				(type default)
			)
			(layer "F.Fab")
		)
		(fp_line
			(start -0.12065 -0.2794)
			(end 0.12065 -0.2794)
			(stroke
				(width 0.1)
				(type default)
			)
			(layer "F.Fab")
		)
		(fp_line
			(start -0.12065 0.2794)
			(end -0.12065 0.3048)
			(stroke
				(width 0.1)
				(type default)
			)
			(layer "F.Fab")
		)
		(fp_line
			(start -0.12065 0.3048)
			(end -0.67945 0.3048)
			(stroke
				(width 0.1)
				(type default)
			)
			(layer "F.Fab")
		)
		(fp_line
			(start 0.120396 0.2794)
			(end -0.12065 0.2794)
			(stroke
				(width 0.1)
				(type default)
			)
			(layer "F.Fab")
		)
		(fp_line
			(start 0.120396 0.3048)
			(end 0.120396 0.2794)
			(stroke
				(width 0.1)
				(type default)
			)
			(layer "F.Fab")
		)
		(fp_line
			(start 0.12065 -0.3048)
			(end 0.67945 -0.3048)
			(stroke
				(width 0.1)
				(type default)
			)
			(layer "F.Fab")
		)
		(fp_line
			(start 0.12065 -0.2794)
			(end 0.12065 -0.3048)
			(stroke
				(width 0.1)
				(type default)
			)
			(layer "F.Fab")
		)
		(fp_line
			(start 0.67945 -0.3048)
			(end 0.67945 0.3048)
			(stroke
				(width 0.1)
				(type default)
			)
			(layer "F.Fab")
		)
		(fp_line
			(start 0.67945 0.3048)
			(end 0.120396 0.3048)
			(stroke
				(width 0.1)
				(type default)
			)
			(layer "F.Fab")
		)
		(pad "1" smd circle
			(at -0.40005 0)
			(size 0 0)
			(layers "F.Cu" "F.Mask" "F.Paste")
			(net "P12V_OCP_SFF_R")
		)
		(pad "2" smd circle
			(at 0.40005 0)
			(size 0 0)
			(layers "F.Cu" "F.Mask" "F.Paste")
			(net "VSENSE_P12V_INA230_6_INN")
		)
	)
	(footprint ""
		(layer "F.Cu")
		(at 412.472886 -76.896468 180)
		(property "Reference" "R47"
			(at 0 0 180)
			(layer "F.SilkS")
			(hide yes)
			(effects
				(font
					(size 1.27 1.27)
				)
			)
		)
		(property "Value" ""
			(at 0 0 180)
			(layer "F.Fab")
			(effects
				(font
					(size 1.27 1.27)
				)
			)
		)
		(duplicate_pad_numbers_are_jumpers no)
		(fp_line
			(start 0.7874 0.4064)
			(end -0.7874 0.4064)
			(stroke
				(width 0.1524)
				(type default)
			)
			(layer "F.SilkS")
		)
		(fp_line
			(start 0.7874 -0.4064)
			(end 0.7874 0.4064)
			(stroke
				(width 0.1524)
				(type default)
			)
			(layer "F.SilkS")
		)
		(fp_line
			(start -0.7874 0.4064)
			(end -0.7874 -0.4064)
			(stroke
				(width 0.1524)
				(type default)
			)
			(layer "F.SilkS")
		)
		(fp_line
			(start -0.7874 -0.4064)
			(end 0.7874 -0.4064)
			(stroke
				(width 0.1524)
				(type default)
			)
			(layer "F.SilkS")
		)
		(fp_line
			(start 0.67945 0.3048)
			(end 0.120396 0.3048)
			(stroke
				(width 0.1)
				(type default)
			)
			(layer "F.Fab")
		)
		(fp_line
			(start 0.67945 -0.3048)
			(end 0.67945 0.3048)
			(stroke
				(width 0.1)
				(type default)
			)
			(layer "F.Fab")
		)
		(fp_line
			(start 0.12065 -0.2794)
			(end 0.12065 -0.3048)
			(stroke
				(width 0.1)
				(type default)
			)
			(layer "F.Fab")
		)
		(fp_line
			(start 0.12065 -0.3048)
			(end 0.67945 -0.3048)
			(stroke
				(width 0.1)
				(type default)
			)
			(layer "F.Fab")
		)
		(fp_line
			(start 0.120396 0.3048)
			(end 0.120396 0.2794)
			(stroke
				(width 0.1)
				(type default)
			)
			(layer "F.Fab")
		)
		(fp_line
			(start 0.120396 0.2794)
			(end -0.12065 0.2794)
			(stroke
				(width 0.1)
				(type default)
			)
			(layer "F.Fab")
		)
		(fp_line
			(start -0.12065 0.3048)
			(end -0.67945 0.3048)
			(stroke
				(width 0.1)
				(type default)
			)
			(layer "F.Fab")
		)
		(fp_line
			(start -0.12065 0.2794)
			(end -0.12065 0.3048)
			(stroke
				(width 0.1)
				(type default)
			)
			(layer "F.Fab")
		)
		(fp_line
			(start -0.12065 -0.2794)
			(end 0.12065 -0.2794)
			(stroke
				(width 0.1)
				(type default)
			)
			(layer "F.Fab")
		)
		(fp_line
			(start -0.12065 -0.305054)
			(end -0.12065 -0.2794)
			(stroke
				(width 0.1)
				(type default)
			)
			(layer "F.Fab")
		)
		(fp_line
			(start -0.67945 0.3048)
			(end -0.67945 -0.305054)
			(stroke
				(width 0.1)
				(type default)
			)
			(layer "F.Fab")
		)
		(fp_line
			(start -0.67945 -0.305054)
			(end -0.12065 -0.305054)
			(stroke
				(width 0.1)
				(type default)
			)
			(layer "F.Fab")
		)
		(pad "1" smd circle
			(at -0.40005 0 180)
			(size 0 0)
			(layers "F.Cu" "F.Mask" "F.Paste")
			(net "SMB_OCP_SFF_3V3AUX_BUF_R_SCL")
		)
		(pad "2" smd circle
			(at 0.40005 0 180)
			(size 0 0)
			(layers "F.Cu" "F.Mask" "F.Paste")
			(net "SMB_OCP_SFF_3V3AUX_BUF_SCL")
		)
	)
	(footprint ""
		(layer "F.Cu")
		(at 100.48367 -407.167588 180)
		(property "Reference" "R594"
			(at 0 0 180)
			(layer "F.SilkS")
			(hide yes)
			(effects
				(font
					(size 1.27 1.27)
				)
			)
		)
		(property "Value" ""
			(at 0 0 180)
			(layer "F.Fab")
			(effects
				(font
					(size 1.27 1.27)
				)
			)
		)
		(duplicate_pad_numbers_are_jumpers no)
		(fp_line
			(start 0.7874 0.4064)
			(end -0.7874 0.4064)
			(stroke
				(width 0.1524)
				(type default)
			)
			(layer "F.SilkS")
		)
		(fp_line
			(start 0.7874 -0.4064)
			(end 0.7874 0.4064)
			(stroke
				(width 0.1524)
				(type default)
			)
			(layer "F.SilkS")
		)
		(fp_line
			(start -0.7874 0.4064)
			(end -0.7874 -0.4064)
			(stroke
				(width 0.1524)
				(type default)
			)
			(layer "F.SilkS")
		)
		(fp_line
			(start -0.7874 -0.4064)
			(end 0.7874 -0.4064)
			(stroke
				(width 0.1524)
				(type default)
			)
			(layer "F.SilkS")
		)
		(fp_line
			(start 0.67945 0.3048)
			(end 0.120396 0.3048)
			(stroke
				(width 0.1)
				(type default)
			)
			(layer "F.Fab")
		)
		(fp_line
			(start 0.67945 -0.3048)
			(end 0.67945 0.3048)
			(stroke
				(width 0.1)
				(type default)
			)
			(layer "F.Fab")
		)
		(fp_line
			(start 0.12065 -0.2794)
			(end 0.12065 -0.3048)
			(stroke
				(width 0.1)
				(type default)
			)
			(layer "F.Fab")
		)
		(fp_line
			(start 0.12065 -0.3048)
			(end 0.67945 -0.3048)
			(stroke
				(width 0.1)
				(type default)
			)
			(layer "F.Fab")
		)
		(fp_line
			(start 0.120396 0.3048)
			(end 0.120396 0.2794)
			(stroke
				(width 0.1)
				(type default)
			)
			(layer "F.Fab")
		)
		(fp_line
			(start 0.120396 0.2794)
			(end -0.12065 0.2794)
			(stroke
				(width 0.1)
				(type default)
			)
			(layer "F.Fab")
		)
		(fp_line
			(start -0.12065 0.3048)
			(end -0.67945 0.3048)
			(stroke
				(width 0.1)
				(type default)
			)
			(layer "F.Fab")
		)
		(fp_line
			(start -0.12065 0.2794)
			(end -0.12065 0.3048)
			(stroke
				(width 0.1)
				(type default)
			)
			(layer "F.Fab")
		)
		(fp_line
			(start -0.12065 -0.2794)
			(end 0.12065 -0.2794)
			(stroke
				(width 0.1)
				(type default)
			)
			(layer "F.Fab")
		)
		(fp_line
			(start -0.12065 -0.305054)
			(end -0.12065 -0.2794)
			(stroke
				(width 0.1)
				(type default)
			)
			(layer "F.Fab")
		)
		(fp_line
			(start -0.67945 0.3048)
			(end -0.67945 -0.305054)
			(stroke
				(width 0.1)
				(type default)
			)
			(layer "F.Fab")
		)
		(fp_line
			(start -0.67945 -0.305054)
			(end -0.12065 -0.305054)
			(stroke
				(width 0.1)
				(type default)
			)
			(layer "F.Fab")
		)
		(pad "1" smd circle
			(at -0.40005 0 180)
			(size 0 0)
			(layers "F.Cu" "F.Mask" "F.Paste")
			(net "FM_9ZXL045_P1_0_OE_N")
		)
		(pad "2" smd circle
			(at 0.40005 0 180)
			(size 0 0)
			(layers "F.Cu" "F.Mask" "F.Paste")
			(net "GND")
		)
	)
	(footprint ""
		(layer "F.Cu")
		(at 146.776186 -54.913784 -90)
		(property "Reference" "C1503"
			(at 0 0 270)
			(layer "F.SilkS")
			(hide yes)
			(effects
				(font
					(size 1.27 1.27)
				)
			)
		)
		(property "Value" ""
			(at 0 0 270)
			(layer "F.Fab")
			(effects
				(font
					(size 1.27 1.27)
				)
			)
		)
		(duplicate_pad_numbers_are_jumpers no)
		(fp_line
			(start -0.7874 0.4064)
			(end -0.7874 -0.4064)
			(stroke
				(width 0.1524)
				(type default)
			)
			(layer "F.SilkS")
		)
		(fp_line
			(start 0.7874 0.4064)
			(end -0.7874 0.4064)
			(stroke
				(width 0.1524)
				(type default)
			)
			(layer "F.SilkS")
		)
		(fp_line
			(start -0.7874 -0.4064)
			(end 0.7874 -0.4064)
			(stroke
				(width 0.1524)
				(type default)
			)
			(layer "F.SilkS")
		)
		(fp_line
			(start 0.7874 -0.4064)
			(end 0.7874 0.4064)
			(stroke
				(width 0.1524)
				(type default)
			)
			(layer "F.SilkS")
		)
		(fp_line
			(start -0.67945 0.3048)
			(end -0.67945 -0.305054)
			(stroke
				(width 0.1)
				(type default)
			)
			(layer "F.Fab")
		)
		(fp_line
			(start -0.12065 0.3048)
			(end -0.67945 0.3048)
			(stroke
				(width 0.1)
				(type default)
			)
			(layer "F.Fab")
		)
		(fp_line
			(start 0.120396 0.3048)
			(end 0.120396 0.2794)
			(stroke
				(width 0.1)
				(type default)
			)
			(layer "F.Fab")
		)
		(fp_line
			(start 0.67945 0.3048)
			(end 0.120396 0.3048)
			(stroke
				(width 0.1)
				(type default)
			)
			(layer "F.Fab")
		)
		(fp_line
			(start -0.12065 0.2794)
			(end -0.12065 0.3048)
			(stroke
				(width 0.1)
				(type default)
			)
			(layer "F.Fab")
		)
		(fp_line
			(start 0.120396 0.2794)
			(end -0.12065 0.2794)
			(stroke
				(width 0.1)
				(type default)
			)
			(layer "F.Fab")
		)
		(fp_line
			(start -0.12065 -0.2794)
			(end 0.12065 -0.2794)
			(stroke
				(width 0.1)
				(type default)
			)
			(layer "F.Fab")
		)
		(fp_line
			(start 0.12065 -0.2794)
			(end 0.12065 -0.3048)
			(stroke
				(width 0.1)
				(type default)
			)
			(layer "F.Fab")
		)
		(fp_line
			(start 0.12065 -0.3048)
			(end 0.67945 -0.3048)
			(stroke
				(width 0.1)
				(type default)
			)
			(layer "F.Fab")
		)
		(fp_line
			(start 0.67945 -0.3048)
			(end 0.67945 0.3048)
			(stroke
				(width 0.1)
				(type default)
			)
			(layer "F.Fab")
		)
		(fp_line
			(start -0.67945 -0.305054)
			(end -0.12065 -0.305054)
			(stroke
				(width 0.1)
				(type default)
			)
			(layer "F.Fab")
		)
		(fp_line
			(start -0.12065 -0.305054)
			(end -0.12065 -0.2794)
			(stroke
				(width 0.1)
				(type default)
			)
			(layer "F.Fab")
		)
		(pad "1" smd circle
			(at -0.40005 0 270)
			(size 0 0)
			(layers "F.Cu" "F.Mask" "F.Paste")
			(net "P3V3_AUX")
		)
		(pad "2" smd circle
			(at 0.40005 0 270)
			(size 0 0)
			(layers "F.Cu" "F.Mask" "F.Paste")
			(net "GND")
		)
	)
	(footprint ""
		(layer "F.Cu")
		(at 446.634616 -390.076944 -90)
		(property "Reference" "PL6505"
			(at 1.075944 -11.862054 90)
			(unlocked yes)
			(layer "F.SilkS")
			(effects
				(font
					(size 0.7874 0.5842)
					(thickness 0.1524)
				)
				(justify left)
			)
		)
		(property "Value" ""
			(at 0 0 270)
			(layer "F.Fab")
			(effects
				(font
					(size 1.27 1.27)
				)
			)
		)
		(duplicate_pad_numbers_are_jumpers no)
		(fp_line
			(start -3.24993 3.24993)
			(end -3.24993 2.2352)
			(stroke
				(width 0.1524)
				(type default)
			)
			(layer "F.SilkS")
		)
		(fp_line
			(start 3.24993 3.24993)
			(end -3.24993 3.24993)
			(stroke
				(width 0.1524)
				(type default)
			)
			(layer "F.SilkS")
		)
		(fp_line
			(start 3.24993 2.2352)
			(end 3.24993 3.24993)
			(stroke
				(width 0.1524)
				(type default)
			)
			(layer "F.SilkS")
		)
		(fp_line
			(start -3.24993 -2.2352)
			(end -3.24993 -3.24993)
			(stroke
				(width 0.1524)
				(type default)
			)
			(layer "F.SilkS")
		)
		(fp_line
			(start -3.24993 -3.24993)
			(end 3.24993 -3.24993)
			(stroke
				(width 0.1524)
				(type default)
			)
			(layer "F.SilkS")
		)
		(fp_line
			(start 3.24993 -3.24993)
			(end 3.24993 -2.2352)
			(stroke
				(width 0.1524)
				(type default)
			)
			(layer "F.SilkS")
		)
		(fp_line
			(start -3.24993 3.24993)
			(end -3.24993 -3.24993)
			(stroke
				(width 0.1)
				(type default)
			)
			(layer "F.Fab")
		)
		(fp_line
			(start 3.24993 3.24993)
			(end -3.24993 3.24993)
			(stroke
				(width 0.1)
				(type default)
			)
			(layer "F.Fab")
		)
		(fp_line
			(start -3.24993 -3.24993)
			(end 3.24993 -3.24993)
			(stroke
				(width 0.1)
				(type default)
			)
			(layer "F.Fab")
		)
		(fp_line
			(start 3.24993 -3.24993)
			(end 3.24993 3.24993)
			(stroke
				(width 0.1)
				(type default)
			)
			(layer "F.Fab")
		)
		(pad "1" smd rect
			(at -2.29997 0 270)
			(size 2.0066 4.2164)
			(layers "F.Cu" "F.Mask" "F.Paste")
			(net "SW_P0V9_RETIMER_CPU0_SW1")
		)
		(pad "2" smd rect
			(at 2.29997 0 270)
			(size 2.0066 4.2164)
			(layers "F.Cu" "F.Mask" "F.Paste")
			(net "P0V9_CPU0_RT_2D")
		)
	)
	(footprint ""
		(layer "F.Cu")
		(at 165.2016 -440.182)
		(property "Reference" "R2831"
			(at 0 0 0)
			(layer "F.SilkS")
			(hide yes)
			(effects
				(font
					(size 1.27 1.27)
				)
			)
		)
		(property "Value" ""
			(at 0 0 0)
			(layer "F.Fab")
			(effects
				(font
					(size 1.27 1.27)
				)
			)
		)
		(duplicate_pad_numbers_are_jumpers no)
		(fp_line
			(start -0.7874 -0.4064)
			(end 0.7874 -0.4064)
			(stroke
				(width 0.1524)
				(type default)
			)
			(layer "F.SilkS")
		)
		(fp_line
			(start -0.7874 0.4064)
			(end -0.7874 -0.4064)
			(stroke
				(width 0.1524)
				(type default)
			)
			(layer "F.SilkS")
		)
		(fp_line
			(start 0.7874 -0.4064)
			(end 0.7874 0.4064)
			(stroke
				(width 0.1524)
				(type default)
			)
			(layer "F.SilkS")
		)
		(fp_line
			(start 0.7874 0.4064)
			(end -0.7874 0.4064)
			(stroke
				(width 0.1524)
				(type default)
			)
			(layer "F.SilkS")
		)
		(fp_line
			(start -0.67945 -0.305054)
			(end -0.12065 -0.305054)
			(stroke
				(width 0.1)
				(type default)
			)
			(layer "F.Fab")
		)
		(fp_line
			(start -0.67945 0.3048)
			(end -0.67945 -0.305054)
			(stroke
				(width 0.1)
				(type default)
			)
			(layer "F.Fab")
		)
		(fp_line
			(start -0.12065 -0.305054)
			(end -0.12065 -0.2794)
			(stroke
				(width 0.1)
				(type default)
			)
			(layer "F.Fab")
		)
		(fp_line
			(start -0.12065 -0.2794)
			(end 0.12065 -0.2794)
			(stroke
				(width 0.1)
				(type default)
			)
			(layer "F.Fab")
		)
		(fp_line
			(start -0.12065 0.2794)
			(end -0.12065 0.3048)
			(stroke
				(width 0.1)
				(type default)
			)
			(layer "F.Fab")
		)
		(fp_line
			(start -0.12065 0.3048)
			(end -0.67945 0.3048)
			(stroke
				(width 0.1)
				(type default)
			)
			(layer "F.Fab")
		)
		(fp_line
			(start 0.120396 0.2794)
			(end -0.12065 0.2794)
			(stroke
				(width 0.1)
				(type default)
			)
			(layer "F.Fab")
		)
		(fp_line
			(start 0.120396 0.3048)
			(end 0.120396 0.2794)
			(stroke
				(width 0.1)
				(type default)
			)
			(layer "F.Fab")
		)
		(fp_line
			(start 0.12065 -0.3048)
			(end 0.67945 -0.3048)
			(stroke
				(width 0.1)
				(type default)
			)
			(layer "F.Fab")
		)
		(fp_line
			(start 0.12065 -0.2794)
			(end 0.12065 -0.3048)
			(stroke
				(width 0.1)
				(type default)
			)
			(layer "F.Fab")
		)
		(fp_line
			(start 0.67945 -0.3048)
			(end 0.67945 0.3048)
			(stroke
				(width 0.1)
				(type default)
			)
			(layer "F.Fab")
		)
		(fp_line
			(start 0.67945 0.3048)
			(end 0.120396 0.3048)
			(stroke
				(width 0.1)
				(type default)
			)
			(layer "F.Fab")
		)
		(pad "1" smd circle
			(at -0.40005 0)
			(size 0 0)
			(layers "F.Cu" "F.Mask" "F.Paste")
			(net "BIC_MONITER")
		)
		(pad "2" smd circle
			(at 0.40005 0)
			(size 0 0)
			(layers "F.Cu" "F.Mask" "F.Paste")
			(net "GND")
		)
	)
	(footprint ""
		(layer "F.Cu")
		(at 273.635978 -380.66853)
		(property "Reference" "PR2531"
			(at 0 0 0)
			(layer "F.SilkS")
			(hide yes)
			(effects
				(font
					(size 1.27 1.27)
				)
			)
		)
		(property "Value" ""
			(at 0 0 0)
			(layer "F.Fab")
			(effects
				(font
					(size 1.27 1.27)
				)
			)
		)
		(duplicate_pad_numbers_are_jumpers no)
		(fp_line
			(start -0.7874 -0.4064)
			(end 0.7874 -0.4064)
			(stroke
				(width 0.1524)
				(type default)
			)
			(layer "F.SilkS")
		)
		(fp_line
			(start -0.7874 0.4064)
			(end -0.7874 -0.4064)
			(stroke
				(width 0.1524)
				(type default)
			)
			(layer "F.SilkS")
		)
		(fp_line
			(start 0.7874 -0.4064)
			(end 0.7874 0.4064)
			(stroke
				(width 0.1524)
				(type default)
			)
			(layer "F.SilkS")
		)
		(fp_line
			(start 0.7874 0.4064)
			(end -0.7874 0.4064)
			(stroke
				(width 0.1524)
				(type default)
			)
			(layer "F.SilkS")
		)
		(fp_line
			(start -0.67945 -0.305054)
			(end -0.12065 -0.305054)
			(stroke
				(width 0.1)
				(type default)
			)
			(layer "F.Fab")
		)
		(fp_line
			(start -0.67945 0.3048)
			(end -0.67945 -0.305054)
			(stroke
				(width 0.1)
				(type default)
			)
			(layer "F.Fab")
		)
		(fp_line
			(start -0.12065 -0.305054)
			(end -0.12065 -0.2794)
			(stroke
				(width 0.1)
				(type default)
			)
			(layer "F.Fab")
		)
		(fp_line
			(start -0.12065 -0.2794)
			(end 0.12065 -0.2794)
			(stroke
				(width 0.1)
				(type default)
			)
			(layer "F.Fab")
		)
		(fp_line
			(start -0.12065 0.2794)
			(end -0.12065 0.3048)
			(stroke
				(width 0.1)
				(type default)
			)
			(layer "F.Fab")
		)
		(fp_line
			(start -0.12065 0.3048)
			(end -0.67945 0.3048)
			(stroke
				(width 0.1)
				(type default)
			)
			(layer "F.Fab")
		)
		(fp_line
			(start 0.120396 0.2794)
			(end -0.12065 0.2794)
			(stroke
				(width 0.1)
				(type default)
			)
			(layer "F.Fab")
		)
		(fp_line
			(start 0.120396 0.3048)
			(end 0.120396 0.2794)
			(stroke
				(width 0.1)
				(type default)
			)
			(layer "F.Fab")
		)
		(fp_line
			(start 0.12065 -0.3048)
			(end 0.67945 -0.3048)
			(stroke
				(width 0.1)
				(type default)
			)
			(layer "F.Fab")
		)
		(fp_line
			(start 0.12065 -0.2794)
			(end 0.12065 -0.3048)
			(stroke
				(width 0.1)
				(type default)
			)
			(layer "F.Fab")
		)
		(fp_line
			(start 0.67945 -0.3048)
			(end 0.67945 0.3048)
			(stroke
				(width 0.1)
				(type default)
			)
			(layer "F.Fab")
		)
		(fp_line
			(start 0.67945 0.3048)
			(end 0.120396 0.3048)
			(stroke
				(width 0.1)
				(type default)
			)
			(layer "F.Fab")
		)
		(pad "1" smd circle
			(at -0.40005 0)
			(size 0 0)
			(layers "F.Cu" "F.Mask" "F.Paste")
			(net "P12V_HSC_GATE_G4")
		)
		(pad "2" smd circle
			(at 0.40005 0)
			(size 0 0)
			(layers "F.Cu" "F.Mask" "F.Paste")
			(net "P12V_HSC_GATE2")
		)
	)
	(footprint ""
		(layer "F.Cu")
		(at 95.428816 -182.616602 90)
		(property "Reference" "PC292_3"
			(at 0 0 90)
			(layer "F.SilkS")
			(hide yes)
			(effects
				(font
					(size 1.27 1.27)
				)
			)
		)
		(property "Value" ""
			(at 0 0 90)
			(layer "F.Fab")
			(effects
				(font
					(size 1.27 1.27)
				)
			)
		)
		(duplicate_pad_numbers_are_jumpers no)
		(fp_line
			(start 0.7874 -0.4064)
			(end 0.7874 0.4064)
			(stroke
				(width 0.1524)
				(type default)
			)
			(layer "F.SilkS")
		)
		(fp_line
			(start -0.7874 -0.4064)
			(end 0.7874 -0.4064)
			(stroke
				(width 0.1524)
				(type default)
			)
			(layer "F.SilkS")
		)
		(fp_line
			(start 0.7874 0.4064)
			(end -0.7874 0.4064)
			(stroke
				(width 0.1524)
				(type default)
			)
			(layer "F.SilkS")
		)
		(fp_line
			(start -0.7874 0.4064)
			(end -0.7874 -0.4064)
			(stroke
				(width 0.1524)
				(type default)
			)
			(layer "F.SilkS")
		)
		(fp_line
			(start -0.12065 -0.305054)
			(end -0.12065 -0.2794)
			(stroke
				(width 0.1)
				(type default)
			)
			(layer "F.Fab")
		)
		(fp_line
			(start -0.67945 -0.305054)
			(end -0.12065 -0.305054)
			(stroke
				(width 0.1)
				(type default)
			)
			(layer "F.Fab")
		)
		(fp_line
			(start 0.67945 -0.3048)
			(end 0.67945 0.3048)
			(stroke
				(width 0.1)
				(type default)
			)
			(layer "F.Fab")
		)
		(fp_line
			(start 0.12065 -0.3048)
			(end 0.67945 -0.3048)
			(stroke
				(width 0.1)
				(type default)
			)
			(layer "F.Fab")
		)
		(fp_line
			(start 0.12065 -0.2794)
			(end 0.12065 -0.3048)
			(stroke
				(width 0.1)
				(type default)
			)
			(layer "F.Fab")
		)
		(fp_line
			(start -0.12065 -0.2794)
			(end 0.12065 -0.2794)
			(stroke
				(width 0.1)
				(type default)
			)
			(layer "F.Fab")
		)
		(fp_line
			(start 0.120396 0.2794)
			(end -0.12065 0.2794)
			(stroke
				(width 0.1)
				(type default)
			)
			(layer "F.Fab")
		)
		(fp_line
			(start -0.12065 0.2794)
			(end -0.12065 0.3048)
			(stroke
				(width 0.1)
				(type default)
			)
			(layer "F.Fab")
		)
		(fp_line
			(start 0.67945 0.3048)
			(end 0.120396 0.3048)
			(stroke
				(width 0.1)
				(type default)
			)
			(layer "F.Fab")
		)
		(fp_line
			(start 0.120396 0.3048)
			(end 0.120396 0.2794)
			(stroke
				(width 0.1)
				(type default)
			)
			(layer "F.Fab")
		)
		(fp_line
			(start -0.12065 0.3048)
			(end -0.67945 0.3048)
			(stroke
				(width 0.1)
				(type default)
			)
			(layer "F.Fab")
		)
		(fp_line
			(start -0.67945 0.3048)
			(end -0.67945 -0.305054)
			(stroke
				(width 0.1)
				(type default)
			)
			(layer "F.Fab")
		)
		(pad "1" smd circle
			(at -0.40005 0 90)
			(size 0 0)
			(layers "F.Cu" "F.Mask" "F.Paste")
			(net "SW_P12V_AUX_PVDDCR_CPU0_P1_FLT")
		)
		(pad "2" smd circle
			(at 0.40005 0 90)
			(size 0 0)
			(layers "F.Cu" "F.Mask" "F.Paste")
			(net "GND")
		)
	)
	(footprint ""
		(layer "F.Cu")
		(at 83.222084 -40.67048 180)
		(property "Reference" "R6056"
			(at 0 0 180)
			(layer "F.SilkS")
			(hide yes)
			(effects
				(font
					(size 1.27 1.27)
				)
			)
		)
		(property "Value" ""
			(at 0 0 180)
			(layer "F.Fab")
			(effects
				(font
					(size 1.27 1.27)
				)
			)
		)
		(duplicate_pad_numbers_are_jumpers no)
		(fp_line
			(start 0.7874 0.4064)
			(end -0.7874 0.4064)
			(stroke
				(width 0.1524)
				(type default)
			)
			(layer "F.SilkS")
		)
		(fp_line
			(start 0.7874 -0.4064)
			(end 0.7874 0.4064)
			(stroke
				(width 0.1524)
				(type default)
			)
			(layer "F.SilkS")
		)
		(fp_line
			(start -0.7874 0.4064)
			(end -0.7874 -0.4064)
			(stroke
				(width 0.1524)
				(type default)
			)
			(layer "F.SilkS")
		)
		(fp_line
			(start -0.7874 -0.4064)
			(end 0.7874 -0.4064)
			(stroke
				(width 0.1524)
				(type default)
			)
			(layer "F.SilkS")
		)
		(fp_line
			(start 0.67945 0.3048)
			(end 0.120396 0.3048)
			(stroke
				(width 0.1)
				(type default)
			)
			(layer "F.Fab")
		)
		(fp_line
			(start 0.67945 -0.3048)
			(end 0.67945 0.3048)
			(stroke
				(width 0.1)
				(type default)
			)
			(layer "F.Fab")
		)
		(fp_line
			(start 0.12065 -0.2794)
			(end 0.12065 -0.3048)
			(stroke
				(width 0.1)
				(type default)
			)
			(layer "F.Fab")
		)
		(fp_line
			(start 0.12065 -0.3048)
			(end 0.67945 -0.3048)
			(stroke
				(width 0.1)
				(type default)
			)
			(layer "F.Fab")
		)
		(fp_line
			(start 0.120396 0.3048)
			(end 0.120396 0.2794)
			(stroke
				(width 0.1)
				(type default)
			)
			(layer "F.Fab")
		)
		(fp_line
			(start 0.120396 0.2794)
			(end -0.12065 0.2794)
			(stroke
				(width 0.1)
				(type default)
			)
			(layer "F.Fab")
		)
		(fp_line
			(start -0.12065 0.3048)
			(end -0.67945 0.3048)
			(stroke
				(width 0.1)
				(type default)
			)
			(layer "F.Fab")
		)
		(fp_line
			(start -0.12065 0.2794)
			(end -0.12065 0.3048)
			(stroke
				(width 0.1)
				(type default)
			)
			(layer "F.Fab")
		)
		(fp_line
			(start -0.12065 -0.2794)
			(end 0.12065 -0.2794)
			(stroke
				(width 0.1)
				(type default)
			)
			(layer "F.Fab")
		)
		(fp_line
			(start -0.12065 -0.305054)
			(end -0.12065 -0.2794)
			(stroke
				(width 0.1)
				(type default)
			)
			(layer "F.Fab")
		)
		(fp_line
			(start -0.67945 0.3048)
			(end -0.67945 -0.305054)
			(stroke
				(width 0.1)
				(type default)
			)
			(layer "F.Fab")
		)
		(fp_line
			(start -0.67945 -0.305054)
			(end -0.12065 -0.305054)
			(stroke
				(width 0.1)
				(type default)
			)
			(layer "F.Fab")
		)
		(pad "1" smd circle
			(at -0.40005 0 180)
			(size 0 0)
			(layers "F.Cu" "F.Mask" "F.Paste")
			(net "RST_PERST_OCP_V3_2_BUF2_N")
		)
		(pad "2" smd circle
			(at 0.40005 0 180)
			(size 0 0)
			(layers "F.Cu" "F.Mask" "F.Paste")
			(net "RST_PERST0_OCP_V3_2_N")
		)
	)
	(footprint ""
		(layer "F.Cu")
		(at 75.7936 -385.58216)
		(property "Reference" "R782"
			(at 0 0 0)
			(layer "F.SilkS")
			(hide yes)
			(effects
				(font
					(size 1.27 1.27)
				)
			)
		)
		(property "Value" ""
			(at 0 0 0)
			(layer "F.Fab")
			(effects
				(font
					(size 1.27 1.27)
				)
			)
		)
		(duplicate_pad_numbers_are_jumpers no)
		(fp_line
			(start -0.32512 -0.175006)
			(end 0.32512 -0.175006)
			(stroke
				(width 0.1)
				(type default)
			)
			(layer "F.Fab")
		)
		(fp_line
			(start -0.32512 0.175006)
			(end -0.32512 -0.175006)
			(stroke
				(width 0.1)
				(type default)
			)
			(layer "F.Fab")
		)
		(fp_line
			(start 0.32512 -0.175006)
			(end 0.32512 0.175006)
			(stroke
				(width 0.1)
				(type default)
			)
			(layer "F.Fab")
		)
		(fp_line
			(start 0.32512 0.175006)
			(end -0.32512 0.175006)
			(stroke
				(width 0.1)
				(type default)
			)
			(layer "F.Fab")
		)
		(pad "1" smd rect
			(at -0.2667 0)
			(size 0.3048 0.381)
			(layers "F.Cu" "F.Mask" "F.Paste")
			(net "GPIO2_RT_CPU1_P1")
		)
		(pad "2" smd rect
			(at 0.2667 0 180)
			(size 0.3048 0.381)
			(layers "F.Cu" "F.Mask" "F.Paste")
			(net "GND")
		)
	)
	(footprint ""
		(layer "F.Cu")
		(at 444.700152 -47.522384 -90)
		(property "Reference" "PC2262"
			(at 0 0 270)
			(layer "F.SilkS")
			(hide yes)
			(effects
				(font
					(size 1.27 1.27)
				)
			)
		)
		(property "Value" ""
			(at 0 0 270)
			(layer "F.Fab")
			(effects
				(font
					(size 1.27 1.27)
				)
			)
		)
		(duplicate_pad_numbers_are_jumpers no)
		(fp_line
			(start -1.524 0.762)
			(end -1.524 -0.762)
			(stroke
				(width 0.1524)
				(type default)
			)
			(layer "F.SilkS")
		)
		(fp_line
			(start 1.524 0.762)
			(end -1.524 0.762)
			(stroke
				(width 0.1524)
				(type default)
			)
			(layer "F.SilkS")
		)
		(fp_line
			(start -1.524 -0.762)
			(end 1.524 -0.762)
			(stroke
				(width 0.1524)
				(type default)
			)
			(layer "F.SilkS")
		)
		(fp_line
			(start 1.524 -0.762)
			(end 1.524 0.762)
			(stroke
				(width 0.1524)
				(type default)
			)
			(layer "F.SilkS")
		)
		(fp_line
			(start -1.1049 0.724916)
			(end 1.1049 0.724916)
			(stroke
				(width 0.1)
				(type default)
			)
			(layer "F.Fab")
		)
		(fp_line
			(start 1.1049 0.724916)
			(end 1.1049 -0.724916)
			(stroke
				(width 0.1)
				(type default)
			)
			(layer "F.Fab")
		)
		(fp_line
			(start -1.1049 -0.724916)
			(end -1.1049 0.724916)
			(stroke
				(width 0.1)
				(type default)
			)
			(layer "F.Fab")
		)
		(fp_line
			(start 1.1049 -0.724916)
			(end -1.1049 -0.724916)
			(stroke
				(width 0.1)
				(type default)
			)
			(layer "F.Fab")
		)
		(pad "1" smd rect
			(at -0.889 0 90)
			(size 1.016 1.27)
			(layers "F.Cu" "F.Mask" "F.Paste")
			(net "SW_P3V3_AUX_FLT")
		)
		(pad "2" smd rect
			(at 0.889 0 90)
			(size 1.016 1.27)
			(layers "F.Cu" "F.Mask" "F.Paste")
			(net "GND")
		)
	)
	(footprint ""
		(layer "F.Cu")
		(at 296.681906 -346.714572 -90)
		(property "Reference" "PC147_IOP0_1"
			(at 0 0 270)
			(layer "F.SilkS")
			(hide yes)
			(effects
				(font
					(size 1.27 1.27)
				)
			)
		)
		(property "Value" ""
			(at 0 0 270)
			(layer "F.Fab")
			(effects
				(font
					(size 1.27 1.27)
				)
			)
		)
		(duplicate_pad_numbers_are_jumpers no)
		(fp_line
			(start -0.7874 0.4064)
			(end -0.7874 -0.4064)
			(stroke
				(width 0.1524)
				(type default)
			)
			(layer "F.SilkS")
		)
		(fp_line
			(start 0.7874 0.4064)
			(end -0.7874 0.4064)
			(stroke
				(width 0.1524)
				(type default)
			)
			(layer "F.SilkS")
		)
		(fp_line
			(start -0.7874 -0.4064)
			(end 0.7874 -0.4064)
			(stroke
				(width 0.1524)
				(type default)
			)
			(layer "F.SilkS")
		)
		(fp_line
			(start 0.7874 -0.4064)
			(end 0.7874 0.4064)
			(stroke
				(width 0.1524)
				(type default)
			)
			(layer "F.SilkS")
		)
		(fp_line
			(start -0.67945 0.3048)
			(end -0.67945 -0.305054)
			(stroke
				(width 0.1)
				(type default)
			)
			(layer "F.Fab")
		)
		(fp_line
			(start -0.12065 0.3048)
			(end -0.67945 0.3048)
			(stroke
				(width 0.1)
				(type default)
			)
			(layer "F.Fab")
		)
		(fp_line
			(start 0.120396 0.3048)
			(end 0.120396 0.2794)
			(stroke
				(width 0.1)
				(type default)
			)
			(layer "F.Fab")
		)
		(fp_line
			(start 0.67945 0.3048)
			(end 0.120396 0.3048)
			(stroke
				(width 0.1)
				(type default)
			)
			(layer "F.Fab")
		)
		(fp_line
			(start -0.12065 0.2794)
			(end -0.12065 0.3048)
			(stroke
				(width 0.1)
				(type default)
			)
			(layer "F.Fab")
		)
		(fp_line
			(start 0.120396 0.2794)
			(end -0.12065 0.2794)
			(stroke
				(width 0.1)
				(type default)
			)
			(layer "F.Fab")
		)
		(fp_line
			(start -0.12065 -0.2794)
			(end 0.12065 -0.2794)
			(stroke
				(width 0.1)
				(type default)
			)
			(layer "F.Fab")
		)
		(fp_line
			(start 0.12065 -0.2794)
			(end 0.12065 -0.3048)
			(stroke
				(width 0.1)
				(type default)
			)
			(layer "F.Fab")
		)
		(fp_line
			(start 0.12065 -0.3048)
			(end 0.67945 -0.3048)
			(stroke
				(width 0.1)
				(type default)
			)
			(layer "F.Fab")
		)
		(fp_line
			(start 0.67945 -0.3048)
			(end 0.67945 0.3048)
			(stroke
				(width 0.1)
				(type default)
			)
			(layer "F.Fab")
		)
		(fp_line
			(start -0.67945 -0.305054)
			(end -0.12065 -0.305054)
			(stroke
				(width 0.1)
				(type default)
			)
			(layer "F.Fab")
		)
		(fp_line
			(start -0.12065 -0.305054)
			(end -0.12065 -0.2794)
			(stroke
				(width 0.1)
				(type default)
			)
			(layer "F.Fab")
		)
		(pad "1" smd circle
			(at -0.40005 0 270)
			(size 0 0)
			(layers "F.Cu" "F.Mask" "F.Paste")
			(net "PVDDCR_CPU1_P0_PVCC")
		)
		(pad "2" smd circle
			(at 0.40005 0 270)
			(size 0 0)
			(layers "F.Cu" "F.Mask" "F.Paste")
			(net "GND")
		)
	)
	(footprint ""
		(layer "F.Cu")
		(at 44.069 -437.134)
		(property "Reference" "R2936"
			(at 0 0 0)
			(layer "F.SilkS")
			(hide yes)
			(effects
				(font
					(size 1.27 1.27)
				)
			)
		)
		(property "Value" ""
			(at 0 0 0)
			(layer "F.Fab")
			(effects
				(font
					(size 1.27 1.27)
				)
			)
		)
		(duplicate_pad_numbers_are_jumpers no)
		(fp_line
			(start -0.7874 -0.4064)
			(end 0.7874 -0.4064)
			(stroke
				(width 0.1524)
				(type default)
			)
			(layer "F.SilkS")
		)
		(fp_line
			(start -0.7874 0.4064)
			(end -0.7874 -0.4064)
			(stroke
				(width 0.1524)
				(type default)
			)
			(layer "F.SilkS")
		)
		(fp_line
			(start 0.7874 -0.4064)
			(end 0.7874 0.4064)
			(stroke
				(width 0.1524)
				(type default)
			)
			(layer "F.SilkS")
		)
		(fp_line
			(start 0.7874 0.4064)
			(end -0.7874 0.4064)
			(stroke
				(width 0.1524)
				(type default)
			)
			(layer "F.SilkS")
		)
		(fp_line
			(start -0.67945 -0.305054)
			(end -0.12065 -0.305054)
			(stroke
				(width 0.1)
				(type default)
			)
			(layer "F.Fab")
		)
		(fp_line
			(start -0.67945 0.3048)
			(end -0.67945 -0.305054)
			(stroke
				(width 0.1)
				(type default)
			)
			(layer "F.Fab")
		)
		(fp_line
			(start -0.12065 -0.305054)
			(end -0.12065 -0.2794)
			(stroke
				(width 0.1)
				(type default)
			)
			(layer "F.Fab")
		)
		(fp_line
			(start -0.12065 -0.2794)
			(end 0.12065 -0.2794)
			(stroke
				(width 0.1)
				(type default)
			)
			(layer "F.Fab")
		)
		(fp_line
			(start -0.12065 0.2794)
			(end -0.12065 0.3048)
			(stroke
				(width 0.1)
				(type default)
			)
			(layer "F.Fab")
		)
		(fp_line
			(start -0.12065 0.3048)
			(end -0.67945 0.3048)
			(stroke
				(width 0.1)
				(type default)
			)
			(layer "F.Fab")
		)
		(fp_line
			(start 0.120396 0.2794)
			(end -0.12065 0.2794)
			(stroke
				(width 0.1)
				(type default)
			)
			(layer "F.Fab")
		)
		(fp_line
			(start 0.120396 0.3048)
			(end 0.120396 0.2794)
			(stroke
				(width 0.1)
				(type default)
			)
			(layer "F.Fab")
		)
		(fp_line
			(start 0.12065 -0.3048)
			(end 0.67945 -0.3048)
			(stroke
				(width 0.1)
				(type default)
			)
			(layer "F.Fab")
		)
		(fp_line
			(start 0.12065 -0.2794)
			(end 0.12065 -0.3048)
			(stroke
				(width 0.1)
				(type default)
			)
			(layer "F.Fab")
		)
		(fp_line
			(start 0.67945 -0.3048)
			(end 0.67945 0.3048)
			(stroke
				(width 0.1)
				(type default)
			)
			(layer "F.Fab")
		)
		(fp_line
			(start 0.67945 0.3048)
			(end 0.120396 0.3048)
			(stroke
				(width 0.1)
				(type default)
			)
			(layer "F.Fab")
		)
		(pad "1" smd circle
			(at -0.40005 0)
			(size 0 0)
			(layers "F.Cu" "F.Mask" "F.Paste")
			(net "P3V3_AUX")
		)
		(pad "2" smd circle
			(at 0.40005 0)
			(size 0 0)
			(layers "F.Cu" "F.Mask" "F.Paste")
			(net "FM_GPU_PWR_EN_R")
		)
	)
	(footprint ""
		(layer "F.Cu")
		(at 173.216062 -29.430472)
		(property "Reference" "R3836"
			(at 0 0 0)
			(layer "F.SilkS")
			(hide yes)
			(effects
				(font
					(size 1.27 1.27)
				)
			)
		)
		(property "Value" ""
			(at 0 0 0)
			(layer "F.Fab")
			(effects
				(font
					(size 1.27 1.27)
				)
			)
		)
		(duplicate_pad_numbers_are_jumpers no)
		(fp_line
			(start -0.7874 -0.4064)
			(end 0.7874 -0.4064)
			(stroke
				(width 0.1524)
				(type default)
			)
			(layer "F.SilkS")
		)
		(fp_line
			(start -0.7874 0.4064)
			(end -0.7874 -0.4064)
			(stroke
				(width 0.1524)
				(type default)
			)
			(layer "F.SilkS")
		)
		(fp_line
			(start 0.7874 -0.4064)
			(end 0.7874 0.4064)
			(stroke
				(width 0.1524)
				(type default)
			)
			(layer "F.SilkS")
		)
		(fp_line
			(start 0.7874 0.4064)
			(end -0.7874 0.4064)
			(stroke
				(width 0.1524)
				(type default)
			)
			(layer "F.SilkS")
		)
		(fp_line
			(start -0.67945 -0.305054)
			(end -0.12065 -0.305054)
			(stroke
				(width 0.1)
				(type default)
			)
			(layer "F.Fab")
		)
		(fp_line
			(start -0.67945 0.3048)
			(end -0.67945 -0.305054)
			(stroke
				(width 0.1)
				(type default)
			)
			(layer "F.Fab")
		)
		(fp_line
			(start -0.12065 -0.305054)
			(end -0.12065 -0.2794)
			(stroke
				(width 0.1)
				(type default)
			)
			(layer "F.Fab")
		)
		(fp_line
			(start -0.12065 -0.2794)
			(end 0.12065 -0.2794)
			(stroke
				(width 0.1)
				(type default)
			)
			(layer "F.Fab")
		)
		(fp_line
			(start -0.12065 0.2794)
			(end -0.12065 0.3048)
			(stroke
				(width 0.1)
				(type default)
			)
			(layer "F.Fab")
		)
		(fp_line
			(start -0.12065 0.3048)
			(end -0.67945 0.3048)
			(stroke
				(width 0.1)
				(type default)
			)
			(layer "F.Fab")
		)
		(fp_line
			(start 0.120396 0.2794)
			(end -0.12065 0.2794)
			(stroke
				(width 0.1)
				(type default)
			)
			(layer "F.Fab")
		)
		(fp_line
			(start 0.120396 0.3048)
			(end 0.120396 0.2794)
			(stroke
				(width 0.1)
				(type default)
			)
			(layer "F.Fab")
		)
		(fp_line
			(start 0.12065 -0.3048)
			(end 0.67945 -0.3048)
			(stroke
				(width 0.1)
				(type default)
			)
			(layer "F.Fab")
		)
		(fp_line
			(start 0.12065 -0.2794)
			(end 0.12065 -0.3048)
			(stroke
				(width 0.1)
				(type default)
			)
			(layer "F.Fab")
		)
		(fp_line
			(start 0.67945 -0.3048)
			(end 0.67945 0.3048)
			(stroke
				(width 0.1)
				(type default)
			)
			(layer "F.Fab")
		)
		(fp_line
			(start 0.67945 0.3048)
			(end 0.120396 0.3048)
			(stroke
				(width 0.1)
				(type default)
			)
			(layer "F.Fab")
		)
		(pad "1" smd circle
			(at -0.40005 0)
			(size 0 0)
			(layers "F.Cu" "F.Mask" "F.Paste")
			(net "P3V3_AUX")
		)
		(pad "2" smd circle
			(at 0.40005 0)
			(size 0 0)
			(layers "F.Cu" "F.Mask" "F.Paste")
			(net "HP_LVC3_SCM_HSC_PWRGD_R")
		)
	)
	(footprint ""
		(layer "F.Cu")
		(at 405.42464 -381.41783 -90)
		(property "Reference" "C859"
			(at 0 0 270)
			(layer "F.SilkS")
			(hide yes)
			(effects
				(font
					(size 1.27 1.27)
				)
			)
		)
		(property "Value" ""
			(at 0 0 270)
			(layer "F.Fab")
			(effects
				(font
					(size 1.27 1.27)
				)
			)
		)
		(duplicate_pad_numbers_are_jumpers no)
		(fp_line
			(start -0.299974 0.150114)
			(end -0.299974 -0.150114)
			(stroke
				(width 0.1)
				(type default)
			)
			(layer "F.Fab")
		)
		(fp_line
			(start 0.299974 0.150114)
			(end -0.299974 0.150114)
			(stroke
				(width 0.1)
				(type default)
			)
			(layer "F.Fab")
		)
		(fp_line
			(start -0.299974 -0.150114)
			(end 0.299974 -0.150114)
			(stroke
				(width 0.1)
				(type default)
			)
			(layer "F.Fab")
		)
		(fp_line
			(start 0.299974 -0.150114)
			(end 0.299974 0.150114)
			(stroke
				(width 0.1)
				(type default)
			)
			(layer "F.Fab")
		)
		(pad "1" smd rect
			(at -0.2667 0 270)
			(size 0.3048 0.381)
			(layers "F.Cu" "F.Mask" "F.Paste")
			(net "P5E_CPU0_P2_TX_C_DP<5>")
		)
		(pad "2" smd rect
			(at 0.2667 0 270)
			(size 0.3048 0.381)
			(layers "F.Cu" "F.Mask" "F.Paste")
			(net "P5E_CPU0_P2_TX_DP<5>")
		)
	)
	(footprint ""
		(layer "F.Cu")
		(at 140.250672 -392.521694)
		(property "Reference" "L8"
			(at -2.3876 -2.969768 0)
			(unlocked yes)
			(layer "F.SilkS")
			(effects
				(font
					(size 0.7874 0.5842)
					(thickness 0.1524)
				)
				(justify left)
			)
		)
		(property "Value" ""
			(at 0 0 0)
			(layer "F.Fab")
			(effects
				(font
					(size 1.27 1.27)
				)
			)
		)
		(duplicate_pad_numbers_are_jumpers no)
		(fp_line
			(start -2.249932 -2.249932)
			(end 2.249932 -2.249932)
			(stroke
				(width 0.1524)
				(type default)
			)
			(layer "F.SilkS")
		)
		(fp_line
			(start -2.249932 -1.3843)
			(end -2.249932 -2.249932)
			(stroke
				(width 0.1524)
				(type default)
			)
			(layer "F.SilkS")
		)
		(fp_line
			(start -2.249932 2.249932)
			(end -2.249932 1.3843)
			(stroke
				(width 0.1524)
				(type default)
			)
			(layer "F.SilkS")
		)
		(fp_line
			(start 2.249932 -2.249932)
			(end 2.249932 -1.3843)
			(stroke
				(width 0.1524)
				(type default)
			)
			(layer "F.SilkS")
		)
		(fp_line
			(start 2.249932 1.3843)
			(end 2.249932 2.249932)
			(stroke
				(width 0.1524)
				(type default)
			)
			(layer "F.SilkS")
		)
		(fp_line
			(start 2.249932 2.249932)
			(end -2.249932 2.249932)
			(stroke
				(width 0.1524)
				(type default)
			)
			(layer "F.SilkS")
		)
		(fp_line
			(start -2.249932 -2.249932)
			(end 2.249932 -2.249932)
			(stroke
				(width 0.1)
				(type default)
			)
			(layer "F.Fab")
		)
		(fp_line
			(start -2.249932 2.249932)
			(end -2.249932 -2.249932)
			(stroke
				(width 0.1)
				(type default)
			)
			(layer "F.Fab")
		)
		(fp_line
			(start 2.249932 -2.249932)
			(end 2.249932 2.249932)
			(stroke
				(width 0.1)
				(type default)
			)
			(layer "F.Fab")
		)
		(fp_line
			(start 2.249932 2.249932)
			(end -2.249932 2.249932)
			(stroke
				(width 0.1)
				(type default)
			)
			(layer "F.Fab")
		)
		(pad "1" smd rect
			(at -1.82499 0)
			(size 1.0668 2.5146)
			(layers "F.Cu" "F.Mask" "F.Paste")
			(net "P0V9_CPU1_RT_2D")
		)
		(pad "2" smd rect
			(at 1.82499 0)
			(size 1.0668 2.5146)
			(layers "F.Cu" "F.Mask" "F.Paste")
			(net "P0V9_CPU1_RT2_2A")
		)
	)
	(footprint ""
		(layer "F.Cu")
		(at 183.6547 -406.636982 90)
		(property "Reference" "PC2189"
			(at 0 0 90)
			(layer "F.SilkS")
			(hide yes)
			(effects
				(font
					(size 1.27 1.27)
				)
			)
		)
		(property "Value" ""
			(at 0 0 90)
			(layer "F.Fab")
			(effects
				(font
					(size 1.27 1.27)
				)
			)
		)
		(duplicate_pad_numbers_are_jumpers no)
		(fp_line
			(start 0.7874 -0.4064)
			(end 0.7874 0.4064)
			(stroke
				(width 0.1524)
				(type default)
			)
			(layer "F.SilkS")
		)
		(fp_line
			(start -0.7874 -0.4064)
			(end 0.7874 -0.4064)
			(stroke
				(width 0.1524)
				(type default)
			)
			(layer "F.SilkS")
		)
		(fp_line
			(start 0.7874 0.4064)
			(end -0.7874 0.4064)
			(stroke
				(width 0.1524)
				(type default)
			)
			(layer "F.SilkS")
		)
		(fp_line
			(start -0.7874 0.4064)
			(end -0.7874 -0.4064)
			(stroke
				(width 0.1524)
				(type default)
			)
			(layer "F.SilkS")
		)
		(fp_line
			(start -0.12065 -0.305054)
			(end -0.12065 -0.2794)
			(stroke
				(width 0.1)
				(type default)
			)
			(layer "F.Fab")
		)
		(fp_line
			(start -0.67945 -0.305054)
			(end -0.12065 -0.305054)
			(stroke
				(width 0.1)
				(type default)
			)
			(layer "F.Fab")
		)
		(fp_line
			(start 0.67945 -0.3048)
			(end 0.67945 0.3048)
			(stroke
				(width 0.1)
				(type default)
			)
			(layer "F.Fab")
		)
		(fp_line
			(start 0.12065 -0.3048)
			(end 0.67945 -0.3048)
			(stroke
				(width 0.1)
				(type default)
			)
			(layer "F.Fab")
		)
		(fp_line
			(start 0.12065 -0.2794)
			(end 0.12065 -0.3048)
			(stroke
				(width 0.1)
				(type default)
			)
			(layer "F.Fab")
		)
		(fp_line
			(start -0.12065 -0.2794)
			(end 0.12065 -0.2794)
			(stroke
				(width 0.1)
				(type default)
			)
			(layer "F.Fab")
		)
		(fp_line
			(start 0.120396 0.2794)
			(end -0.12065 0.2794)
			(stroke
				(width 0.1)
				(type default)
			)
			(layer "F.Fab")
		)
		(fp_line
			(start -0.12065 0.2794)
			(end -0.12065 0.3048)
			(stroke
				(width 0.1)
				(type default)
			)
			(layer "F.Fab")
		)
		(fp_line
			(start 0.67945 0.3048)
			(end 0.120396 0.3048)
			(stroke
				(width 0.1)
				(type default)
			)
			(layer "F.Fab")
		)
		(fp_line
			(start 0.120396 0.3048)
			(end 0.120396 0.2794)
			(stroke
				(width 0.1)
				(type default)
			)
			(layer "F.Fab")
		)
		(fp_line
			(start -0.12065 0.3048)
			(end -0.67945 0.3048)
			(stroke
				(width 0.1)
				(type default)
			)
			(layer "F.Fab")
		)
		(fp_line
			(start -0.67945 0.3048)
			(end -0.67945 -0.305054)
			(stroke
				(width 0.1)
				(type default)
			)
			(layer "F.Fab")
		)
		(pad "1" smd circle
			(at -0.40005 0 90)
			(size 0 0)
			(layers "F.Cu" "F.Mask" "F.Paste")
			(net "HSC_VSENSE")
		)
		(pad "2" smd circle
			(at 0.40005 0 90)
			(size 0 0)
			(layers "F.Cu" "F.Mask" "F.Paste")
			(net "AGND_HSC")
		)
	)
	(footprint ""
		(layer "F.Cu")
		(at 140.420344 -39.793418 180)
		(property "Reference" "R6208"
			(at 0 0 180)
			(layer "F.SilkS")
			(hide yes)
			(effects
				(font
					(size 1.27 1.27)
				)
			)
		)
		(property "Value" ""
			(at 0 0 180)
			(layer "F.Fab")
			(effects
				(font
					(size 1.27 1.27)
				)
			)
		)
		(duplicate_pad_numbers_are_jumpers no)
		(fp_line
			(start 0.7874 0.4064)
			(end -0.7874 0.4064)
			(stroke
				(width 0.1524)
				(type default)
			)
			(layer "F.SilkS")
		)
		(fp_line
			(start 0.7874 -0.4064)
			(end 0.7874 0.4064)
			(stroke
				(width 0.1524)
				(type default)
			)
			(layer "F.SilkS")
		)
		(fp_line
			(start -0.7874 0.4064)
			(end -0.7874 -0.4064)
			(stroke
				(width 0.1524)
				(type default)
			)
			(layer "F.SilkS")
		)
		(fp_line
			(start -0.7874 -0.4064)
			(end 0.7874 -0.4064)
			(stroke
				(width 0.1524)
				(type default)
			)
			(layer "F.SilkS")
		)
		(fp_line
			(start 0.67945 0.3048)
			(end 0.120396 0.3048)
			(stroke
				(width 0.1)
				(type default)
			)
			(layer "F.Fab")
		)
		(fp_line
			(start 0.67945 -0.3048)
			(end 0.67945 0.3048)
			(stroke
				(width 0.1)
				(type default)
			)
			(layer "F.Fab")
		)
		(fp_line
			(start 0.12065 -0.2794)
			(end 0.12065 -0.3048)
			(stroke
				(width 0.1)
				(type default)
			)
			(layer "F.Fab")
		)
		(fp_line
			(start 0.12065 -0.3048)
			(end 0.67945 -0.3048)
			(stroke
				(width 0.1)
				(type default)
			)
			(layer "F.Fab")
		)
		(fp_line
			(start 0.120396 0.3048)
			(end 0.120396 0.2794)
			(stroke
				(width 0.1)
				(type default)
			)
			(layer "F.Fab")
		)
		(fp_line
			(start 0.120396 0.2794)
			(end -0.12065 0.2794)
			(stroke
				(width 0.1)
				(type default)
			)
			(layer "F.Fab")
		)
		(fp_line
			(start -0.12065 0.3048)
			(end -0.67945 0.3048)
			(stroke
				(width 0.1)
				(type default)
			)
			(layer "F.Fab")
		)
		(fp_line
			(start -0.12065 0.2794)
			(end -0.12065 0.3048)
			(stroke
				(width 0.1)
				(type default)
			)
			(layer "F.Fab")
		)
		(fp_line
			(start -0.12065 -0.2794)
			(end 0.12065 -0.2794)
			(stroke
				(width 0.1)
				(type default)
			)
			(layer "F.Fab")
		)
		(fp_line
			(start -0.12065 -0.305054)
			(end -0.12065 -0.2794)
			(stroke
				(width 0.1)
				(type default)
			)
			(layer "F.Fab")
		)
		(fp_line
			(start -0.67945 0.3048)
			(end -0.67945 -0.305054)
			(stroke
				(width 0.1)
				(type default)
			)
			(layer "F.Fab")
		)
		(fp_line
			(start -0.67945 -0.305054)
			(end -0.12065 -0.305054)
			(stroke
				(width 0.1)
				(type default)
			)
			(layer "F.Fab")
		)
		(pad "1" smd circle
			(at -0.40005 0 180)
			(size 0 0)
			(layers "F.Cu" "F.Mask" "F.Paste")
			(net "P5V_AUX")
		)
		(pad "2" smd circle
			(at 0.40005 0 180)
			(size 0 0)
			(layers "F.Cu" "F.Mask" "F.Paste")
			(net "USB_CPU0_HUB1_VBUS_US")
		)
	)
	(footprint ""
		(layer "F.Cu")
		(at 386.211826 -53.1495 180)
		(property "Reference" "R1352"
			(at 0 0 180)
			(layer "F.SilkS")
			(hide yes)
			(effects
				(font
					(size 1.27 1.27)
				)
			)
		)
		(property "Value" ""
			(at 0 0 180)
			(layer "F.Fab")
			(effects
				(font
					(size 1.27 1.27)
				)
			)
		)
		(duplicate_pad_numbers_are_jumpers no)
		(fp_line
			(start 0.7874 0.4064)
			(end -0.7874 0.4064)
			(stroke
				(width 0.1524)
				(type default)
			)
			(layer "F.SilkS")
		)
		(fp_line
			(start 0.7874 -0.4064)
			(end 0.7874 0.4064)
			(stroke
				(width 0.1524)
				(type default)
			)
			(layer "F.SilkS")
		)
		(fp_line
			(start -0.7874 0.4064)
			(end -0.7874 -0.4064)
			(stroke
				(width 0.1524)
				(type default)
			)
			(layer "F.SilkS")
		)
		(fp_line
			(start -0.7874 -0.4064)
			(end 0.7874 -0.4064)
			(stroke
				(width 0.1524)
				(type default)
			)
			(layer "F.SilkS")
		)
		(fp_line
			(start 0.67945 0.3048)
			(end 0.120396 0.3048)
			(stroke
				(width 0.1)
				(type default)
			)
			(layer "F.Fab")
		)
		(fp_line
			(start 0.67945 -0.3048)
			(end 0.67945 0.3048)
			(stroke
				(width 0.1)
				(type default)
			)
			(layer "F.Fab")
		)
		(fp_line
			(start 0.12065 -0.2794)
			(end 0.12065 -0.3048)
			(stroke
				(width 0.1)
				(type default)
			)
			(layer "F.Fab")
		)
		(fp_line
			(start 0.12065 -0.3048)
			(end 0.67945 -0.3048)
			(stroke
				(width 0.1)
				(type default)
			)
			(layer "F.Fab")
		)
		(fp_line
			(start 0.120396 0.3048)
			(end 0.120396 0.2794)
			(stroke
				(width 0.1)
				(type default)
			)
			(layer "F.Fab")
		)
		(fp_line
			(start 0.120396 0.2794)
			(end -0.12065 0.2794)
			(stroke
				(width 0.1)
				(type default)
			)
			(layer "F.Fab")
		)
		(fp_line
			(start -0.12065 0.3048)
			(end -0.67945 0.3048)
			(stroke
				(width 0.1)
				(type default)
			)
			(layer "F.Fab")
		)
		(fp_line
			(start -0.12065 0.2794)
			(end -0.12065 0.3048)
			(stroke
				(width 0.1)
				(type default)
			)
			(layer "F.Fab")
		)
		(fp_line
			(start -0.12065 -0.2794)
			(end 0.12065 -0.2794)
			(stroke
				(width 0.1)
				(type default)
			)
			(layer "F.Fab")
		)
		(fp_line
			(start -0.12065 -0.305054)
			(end -0.12065 -0.2794)
			(stroke
				(width 0.1)
				(type default)
			)
			(layer "F.Fab")
		)
		(fp_line
			(start -0.67945 0.3048)
			(end -0.67945 -0.305054)
			(stroke
				(width 0.1)
				(type default)
			)
			(layer "F.Fab")
		)
		(fp_line
			(start -0.67945 -0.305054)
			(end -0.12065 -0.305054)
			(stroke
				(width 0.1)
				(type default)
			)
			(layer "F.Fab")
		)
		(pad "1" smd circle
			(at -0.40005 0 180)
			(size 0 0)
			(layers "F.Cu" "F.Mask" "F.Paste")
			(net "HDT_HDR_R_TCK")
		)
		(pad "2" smd circle
			(at 0.40005 0 180)
			(size 0 0)
			(layers "F.Cu" "F.Mask" "F.Paste")
			(net "HDT_HDR_TCK")
		)
	)
	(footprint ""
		(layer "F.Cu")
		(at 271.085056 -115.22837)
		(property "Reference" "R3721"
			(at 0 0 0)
			(layer "F.SilkS")
			(hide yes)
			(effects
				(font
					(size 1.27 1.27)
				)
			)
		)
		(property "Value" ""
			(at 0 0 0)
			(layer "F.Fab")
			(effects
				(font
					(size 1.27 1.27)
				)
			)
		)
		(duplicate_pad_numbers_are_jumpers no)
		(fp_line
			(start -0.7874 -0.4064)
			(end 0.7874 -0.4064)
			(stroke
				(width 0.1524)
				(type default)
			)
			(layer "F.SilkS")
		)
		(fp_line
			(start -0.7874 0.4064)
			(end -0.7874 -0.4064)
			(stroke
				(width 0.1524)
				(type default)
			)
			(layer "F.SilkS")
		)
		(fp_line
			(start 0.7874 -0.4064)
			(end 0.7874 0.4064)
			(stroke
				(width 0.1524)
				(type default)
			)
			(layer "F.SilkS")
		)
		(fp_line
			(start 0.7874 0.4064)
			(end -0.7874 0.4064)
			(stroke
				(width 0.1524)
				(type default)
			)
			(layer "F.SilkS")
		)
		(fp_line
			(start -0.67945 -0.305054)
			(end -0.12065 -0.305054)
			(stroke
				(width 0.1)
				(type default)
			)
			(layer "F.Fab")
		)
		(fp_line
			(start -0.67945 0.3048)
			(end -0.67945 -0.305054)
			(stroke
				(width 0.1)
				(type default)
			)
			(layer "F.Fab")
		)
		(fp_line
			(start -0.12065 -0.305054)
			(end -0.12065 -0.2794)
			(stroke
				(width 0.1)
				(type default)
			)
			(layer "F.Fab")
		)
		(fp_line
			(start -0.12065 -0.2794)
			(end 0.12065 -0.2794)
			(stroke
				(width 0.1)
				(type default)
			)
			(layer "F.Fab")
		)
		(fp_line
			(start -0.12065 0.2794)
			(end -0.12065 0.3048)
			(stroke
				(width 0.1)
				(type default)
			)
			(layer "F.Fab")
		)
		(fp_line
			(start -0.12065 0.3048)
			(end -0.67945 0.3048)
			(stroke
				(width 0.1)
				(type default)
			)
			(layer "F.Fab")
		)
		(fp_line
			(start 0.120396 0.2794)
			(end -0.12065 0.2794)
			(stroke
				(width 0.1)
				(type default)
			)
			(layer "F.Fab")
		)
		(fp_line
			(start 0.120396 0.3048)
			(end 0.120396 0.2794)
			(stroke
				(width 0.1)
				(type default)
			)
			(layer "F.Fab")
		)
		(fp_line
			(start 0.12065 -0.3048)
			(end 0.67945 -0.3048)
			(stroke
				(width 0.1)
				(type default)
			)
			(layer "F.Fab")
		)
		(fp_line
			(start 0.12065 -0.2794)
			(end 0.12065 -0.3048)
			(stroke
				(width 0.1)
				(type default)
			)
			(layer "F.Fab")
		)
		(fp_line
			(start 0.67945 -0.3048)
			(end 0.67945 0.3048)
			(stroke
				(width 0.1)
				(type default)
			)
			(layer "F.Fab")
		)
		(fp_line
			(start 0.67945 0.3048)
			(end 0.120396 0.3048)
			(stroke
				(width 0.1)
				(type default)
			)
			(layer "F.Fab")
		)
		(pad "1" smd circle
			(at -0.40005 0)
			(size 0 0)
			(layers "F.Cu" "F.Mask" "F.Paste")
			(net "SMB_LM75_3_3V3AUX_SCL_R")
		)
		(pad "2" smd circle
			(at 0.40005 0)
			(size 0 0)
			(layers "F.Cu" "F.Mask" "F.Paste")
			(net "SMB_LM75_3_3V3AUX_SCL")
		)
	)
	(footprint ""
		(layer "F.Cu")
		(at 296.22877 -351.100644)
		(property "Reference" "PC148_1"
			(at 0 0 0)
			(layer "F.SilkS")
			(hide yes)
			(effects
				(font
					(size 1.27 1.27)
				)
			)
		)
		(property "Value" ""
			(at 0 0 0)
			(layer "F.Fab")
			(effects
				(font
					(size 1.27 1.27)
				)
			)
		)
		(duplicate_pad_numbers_are_jumpers no)
		(fp_line
			(start -0.7874 -0.4064)
			(end 0.7874 -0.4064)
			(stroke
				(width 0.1524)
				(type default)
			)
			(layer "F.SilkS")
		)
		(fp_line
			(start -0.7874 0.4064)
			(end -0.7874 -0.4064)
			(stroke
				(width 0.1524)
				(type default)
			)
			(layer "F.SilkS")
		)
		(fp_line
			(start 0.7874 -0.4064)
			(end 0.7874 0.4064)
			(stroke
				(width 0.1524)
				(type default)
			)
			(layer "F.SilkS")
		)
		(fp_line
			(start 0.7874 0.4064)
			(end -0.7874 0.4064)
			(stroke
				(width 0.1524)
				(type default)
			)
			(layer "F.SilkS")
		)
		(fp_line
			(start -0.67945 -0.305054)
			(end -0.12065 -0.305054)
			(stroke
				(width 0.1)
				(type default)
			)
			(layer "F.Fab")
		)
		(fp_line
			(start -0.67945 0.3048)
			(end -0.67945 -0.305054)
			(stroke
				(width 0.1)
				(type default)
			)
			(layer "F.Fab")
		)
		(fp_line
			(start -0.12065 -0.305054)
			(end -0.12065 -0.2794)
			(stroke
				(width 0.1)
				(type default)
			)
			(layer "F.Fab")
		)
		(fp_line
			(start -0.12065 -0.2794)
			(end 0.12065 -0.2794)
			(stroke
				(width 0.1)
				(type default)
			)
			(layer "F.Fab")
		)
		(fp_line
			(start -0.12065 0.2794)
			(end -0.12065 0.3048)
			(stroke
				(width 0.1)
				(type default)
			)
			(layer "F.Fab")
		)
		(fp_line
			(start -0.12065 0.3048)
			(end -0.67945 0.3048)
			(stroke
				(width 0.1)
				(type default)
			)
			(layer "F.Fab")
		)
		(fp_line
			(start 0.120396 0.2794)
			(end -0.12065 0.2794)
			(stroke
				(width 0.1)
				(type default)
			)
			(layer "F.Fab")
		)
		(fp_line
			(start 0.120396 0.3048)
			(end 0.120396 0.2794)
			(stroke
				(width 0.1)
				(type default)
			)
			(layer "F.Fab")
		)
		(fp_line
			(start 0.12065 -0.3048)
			(end 0.67945 -0.3048)
			(stroke
				(width 0.1)
				(type default)
			)
			(layer "F.Fab")
		)
		(fp_line
			(start 0.12065 -0.2794)
			(end 0.12065 -0.3048)
			(stroke
				(width 0.1)
				(type default)
			)
			(layer "F.Fab")
		)
		(fp_line
			(start 0.67945 -0.3048)
			(end 0.67945 0.3048)
			(stroke
				(width 0.1)
				(type default)
			)
			(layer "F.Fab")
		)
		(fp_line
			(start 0.67945 0.3048)
			(end 0.120396 0.3048)
			(stroke
				(width 0.1)
				(type default)
			)
			(layer "F.Fab")
		)
		(pad "1" smd circle
			(at -0.40005 0)
			(size 0 0)
			(layers "F.Cu" "F.Mask" "F.Paste")
			(net "SW_P12V_AUX_PVDDIO_P0_FLT")
		)
		(pad "2" smd circle
			(at 0.40005 0)
			(size 0 0)
			(layers "F.Cu" "F.Mask" "F.Paste")
			(net "GND")
		)
	)
	(footprint ""
		(layer "F.Cu")
		(at 22.147784 -393.539726 180)
		(property "Reference" "PC6646"
			(at 0 0 180)
			(layer "F.SilkS")
			(hide yes)
			(effects
				(font
					(size 1.27 1.27)
				)
			)
		)
		(property "Value" ""
			(at 0 0 180)
			(layer "F.Fab")
			(effects
				(font
					(size 1.27 1.27)
				)
			)
		)
		(duplicate_pad_numbers_are_jumpers no)
		(fp_line
			(start 0.7874 0.4064)
			(end -0.7874 0.4064)
			(stroke
				(width 0.1524)
				(type default)
			)
			(layer "F.SilkS")
		)
		(fp_line
			(start 0.7874 -0.4064)
			(end 0.7874 0.4064)
			(stroke
				(width 0.1524)
				(type default)
			)
			(layer "F.SilkS")
		)
		(fp_line
			(start -0.7874 0.4064)
			(end -0.7874 -0.4064)
			(stroke
				(width 0.1524)
				(type default)
			)
			(layer "F.SilkS")
		)
		(fp_line
			(start -0.7874 -0.4064)
			(end 0.7874 -0.4064)
			(stroke
				(width 0.1524)
				(type default)
			)
			(layer "F.SilkS")
		)
		(fp_line
			(start 0.67945 0.3048)
			(end 0.120396 0.3048)
			(stroke
				(width 0.1)
				(type default)
			)
			(layer "F.Fab")
		)
		(fp_line
			(start 0.67945 -0.3048)
			(end 0.67945 0.3048)
			(stroke
				(width 0.1)
				(type default)
			)
			(layer "F.Fab")
		)
		(fp_line
			(start 0.12065 -0.2794)
			(end 0.12065 -0.3048)
			(stroke
				(width 0.1)
				(type default)
			)
			(layer "F.Fab")
		)
		(fp_line
			(start 0.12065 -0.3048)
			(end 0.67945 -0.3048)
			(stroke
				(width 0.1)
				(type default)
			)
			(layer "F.Fab")
		)
		(fp_line
			(start 0.120396 0.3048)
			(end 0.120396 0.2794)
			(stroke
				(width 0.1)
				(type default)
			)
			(layer "F.Fab")
		)
		(fp_line
			(start 0.120396 0.2794)
			(end -0.12065 0.2794)
			(stroke
				(width 0.1)
				(type default)
			)
			(layer "F.Fab")
		)
		(fp_line
			(start -0.12065 0.3048)
			(end -0.67945 0.3048)
			(stroke
				(width 0.1)
				(type default)
			)
			(layer "F.Fab")
		)
		(fp_line
			(start -0.12065 0.2794)
			(end -0.12065 0.3048)
			(stroke
				(width 0.1)
				(type default)
			)
			(layer "F.Fab")
		)
		(fp_line
			(start -0.12065 -0.2794)
			(end 0.12065 -0.2794)
			(stroke
				(width 0.1)
				(type default)
			)
			(layer "F.Fab")
		)
		(fp_line
			(start -0.12065 -0.305054)
			(end -0.12065 -0.2794)
			(stroke
				(width 0.1)
				(type default)
			)
			(layer "F.Fab")
		)
		(fp_line
			(start -0.67945 0.3048)
			(end -0.67945 -0.305054)
			(stroke
				(width 0.1)
				(type default)
			)
			(layer "F.Fab")
		)
		(fp_line
			(start -0.67945 -0.305054)
			(end -0.12065 -0.305054)
			(stroke
				(width 0.1)
				(type default)
			)
			(layer "F.Fab")
		)
		(pad "1" smd circle
			(at -0.40005 0 180)
			(size 0 0)
			(layers "F.Cu" "F.Mask" "F.Paste")
			(net "PV09_RETIMER_CPU1_VCCS")
		)
		(pad "2" smd circle
			(at 0.40005 0 180)
			(size 0 0)
			(layers "F.Cu" "F.Mask" "F.Paste")
			(net "GND")
		)
	)
	(footprint ""
		(layer "F.Cu")
		(at 439.512456 -43.929554 90)
		(property "Reference" "PC1649"
			(at 0 0 90)
			(layer "F.SilkS")
			(hide yes)
			(effects
				(font
					(size 1.27 1.27)
				)
			)
		)
		(property "Value" ""
			(at 0 0 90)
			(layer "F.Fab")
			(effects
				(font
					(size 1.27 1.27)
				)
			)
		)
		(duplicate_pad_numbers_are_jumpers no)
		(fp_line
			(start 0.7874 -0.4064)
			(end 0.7874 0.4064)
			(stroke
				(width 0.1524)
				(type default)
			)
			(layer "F.SilkS")
		)
		(fp_line
			(start -0.7874 -0.4064)
			(end 0.7874 -0.4064)
			(stroke
				(width 0.1524)
				(type default)
			)
			(layer "F.SilkS")
		)
		(fp_line
			(start 0.7874 0.4064)
			(end -0.7874 0.4064)
			(stroke
				(width 0.1524)
				(type default)
			)
			(layer "F.SilkS")
		)
		(fp_line
			(start -0.7874 0.4064)
			(end -0.7874 -0.4064)
			(stroke
				(width 0.1524)
				(type default)
			)
			(layer "F.SilkS")
		)
		(fp_line
			(start -0.12065 -0.305054)
			(end -0.12065 -0.2794)
			(stroke
				(width 0.1)
				(type default)
			)
			(layer "F.Fab")
		)
		(fp_line
			(start -0.67945 -0.305054)
			(end -0.12065 -0.305054)
			(stroke
				(width 0.1)
				(type default)
			)
			(layer "F.Fab")
		)
		(fp_line
			(start 0.67945 -0.3048)
			(end 0.67945 0.3048)
			(stroke
				(width 0.1)
				(type default)
			)
			(layer "F.Fab")
		)
		(fp_line
			(start 0.12065 -0.3048)
			(end 0.67945 -0.3048)
			(stroke
				(width 0.1)
				(type default)
			)
			(layer "F.Fab")
		)
		(fp_line
			(start 0.12065 -0.2794)
			(end 0.12065 -0.3048)
			(stroke
				(width 0.1)
				(type default)
			)
			(layer "F.Fab")
		)
		(fp_line
			(start -0.12065 -0.2794)
			(end 0.12065 -0.2794)
			(stroke
				(width 0.1)
				(type default)
			)
			(layer "F.Fab")
		)
		(fp_line
			(start 0.120396 0.2794)
			(end -0.12065 0.2794)
			(stroke
				(width 0.1)
				(type default)
			)
			(layer "F.Fab")
		)
		(fp_line
			(start -0.12065 0.2794)
			(end -0.12065 0.3048)
			(stroke
				(width 0.1)
				(type default)
			)
			(layer "F.Fab")
		)
		(fp_line
			(start 0.67945 0.3048)
			(end 0.120396 0.3048)
			(stroke
				(width 0.1)
				(type default)
			)
			(layer "F.Fab")
		)
		(fp_line
			(start 0.120396 0.3048)
			(end 0.120396 0.2794)
			(stroke
				(width 0.1)
				(type default)
			)
			(layer "F.Fab")
		)
		(fp_line
			(start -0.12065 0.3048)
			(end -0.67945 0.3048)
			(stroke
				(width 0.1)
				(type default)
			)
			(layer "F.Fab")
		)
		(fp_line
			(start -0.67945 0.3048)
			(end -0.67945 -0.305054)
			(stroke
				(width 0.1)
				(type default)
			)
			(layer "F.Fab")
		)
		(pad "1" smd circle
			(at -0.40005 0 90)
			(size 0 0)
			(layers "F.Cu" "F.Mask" "F.Paste")
			(net "P12V_AUX")
		)
		(pad "2" smd circle
			(at 0.40005 0 90)
			(size 0 0)
			(layers "F.Cu" "F.Mask" "F.Paste")
			(net "GND")
		)
	)
	(footprint ""
		(layer "F.Cu")
		(at 435.43982 -399.029936)
		(property "Reference" "H10"
			(at -3.815588 -3.882644 0)
			(unlocked yes)
			(layer "F.SilkS")
			(effects
				(font
					(size 0.7874 0.5842)
					(thickness 0.1524)
				)
				(justify left)
			)
		)
		(property "Value" ""
			(at 0 0 0)
			(layer "F.Fab")
			(effects
				(font
					(size 1.27 1.27)
				)
			)
		)
		(duplicate_pad_numbers_are_jumpers no)
		(pad "1" thru_hole circle
			(at 0 0)
			(size 6.1976 6.1976)
			(drill 3.7338)
			(layers "*.Cu" "*.Mask")
			(remove_unused_layers no)
			(net "GND")
			(clearance -0.9779)
			(padstack
				(mode front_inner_back)
				(layer "Inner"
					(shape circle)
					(size 5.5372 5.5372)
					(clearance -0.6477)
				)
				(layer "B.Cu"
					(shape circle)
					(size 6.1976 6.1976)
					(clearance -0.9779)
				)
			)
		)
	)
	(footprint ""
		(layer "F.Cu")
		(at 279.513792 -120.74017 180)
		(property "Reference" "R6200"
			(at 0 0 180)
			(layer "F.SilkS")
			(hide yes)
			(effects
				(font
					(size 1.27 1.27)
				)
			)
		)
		(property "Value" ""
			(at 0 0 180)
			(layer "F.Fab")
			(effects
				(font
					(size 1.27 1.27)
				)
			)
		)
		(duplicate_pad_numbers_are_jumpers no)
		(fp_line
			(start 0.7874 0.4064)
			(end -0.7874 0.4064)
			(stroke
				(width 0.1524)
				(type default)
			)
			(layer "F.SilkS")
		)
		(fp_line
			(start 0.7874 -0.4064)
			(end 0.7874 0.4064)
			(stroke
				(width 0.1524)
				(type default)
			)
			(layer "F.SilkS")
		)
		(fp_line
			(start -0.7874 0.4064)
			(end -0.7874 -0.4064)
			(stroke
				(width 0.1524)
				(type default)
			)
			(layer "F.SilkS")
		)
		(fp_line
			(start -0.7874 -0.4064)
			(end 0.7874 -0.4064)
			(stroke
				(width 0.1524)
				(type default)
			)
			(layer "F.SilkS")
		)
		(fp_line
			(start 0.67945 0.3048)
			(end 0.120396 0.3048)
			(stroke
				(width 0.1)
				(type default)
			)
			(layer "F.Fab")
		)
		(fp_line
			(start 0.67945 -0.3048)
			(end 0.67945 0.3048)
			(stroke
				(width 0.1)
				(type default)
			)
			(layer "F.Fab")
		)
		(fp_line
			(start 0.12065 -0.2794)
			(end 0.12065 -0.3048)
			(stroke
				(width 0.1)
				(type default)
			)
			(layer "F.Fab")
		)
		(fp_line
			(start 0.12065 -0.3048)
			(end 0.67945 -0.3048)
			(stroke
				(width 0.1)
				(type default)
			)
			(layer "F.Fab")
		)
		(fp_line
			(start 0.120396 0.3048)
			(end 0.120396 0.2794)
			(stroke
				(width 0.1)
				(type default)
			)
			(layer "F.Fab")
		)
		(fp_line
			(start 0.120396 0.2794)
			(end -0.12065 0.2794)
			(stroke
				(width 0.1)
				(type default)
			)
			(layer "F.Fab")
		)
		(fp_line
			(start -0.12065 0.3048)
			(end -0.67945 0.3048)
			(stroke
				(width 0.1)
				(type default)
			)
			(layer "F.Fab")
		)
		(fp_line
			(start -0.12065 0.2794)
			(end -0.12065 0.3048)
			(stroke
				(width 0.1)
				(type default)
			)
			(layer "F.Fab")
		)
		(fp_line
			(start -0.12065 -0.2794)
			(end 0.12065 -0.2794)
			(stroke
				(width 0.1)
				(type default)
			)
			(layer "F.Fab")
		)
		(fp_line
			(start -0.12065 -0.305054)
			(end -0.12065 -0.2794)
			(stroke
				(width 0.1)
				(type default)
			)
			(layer "F.Fab")
		)
		(fp_line
			(start -0.67945 0.3048)
			(end -0.67945 -0.305054)
			(stroke
				(width 0.1)
				(type default)
			)
			(layer "F.Fab")
		)
		(fp_line
			(start -0.67945 -0.305054)
			(end -0.12065 -0.305054)
			(stroke
				(width 0.1)
				(type default)
			)
			(layer "F.Fab")
		)
		(pad "1" smd circle
			(at -0.40005 0 180)
			(size 0 0)
			(layers "F.Cu" "F.Mask" "F.Paste")
			(net "SMB_USB_CPU0_HUB1_SDA_R")
		)
		(pad "2" smd circle
			(at 0.40005 0 180)
			(size 0 0)
			(layers "F.Cu" "F.Mask" "F.Paste")
			(net "SMB_USB_CPU0_HUB1_SDA")
		)
	)
	(footprint ""
		(layer "F.Cu")
		(at 438.257442 -428.918624 -90)
		(property "Reference" "R6860"
			(at 0 0 270)
			(layer "F.SilkS")
			(hide yes)
			(effects
				(font
					(size 1.27 1.27)
				)
			)
		)
		(property "Value" ""
			(at 0 0 270)
			(layer "F.Fab")
			(effects
				(font
					(size 1.27 1.27)
				)
			)
		)
		(duplicate_pad_numbers_are_jumpers no)
		(fp_line
			(start -0.7874 0.4064)
			(end -0.7874 -0.4064)
			(stroke
				(width 0.1524)
				(type default)
			)
			(layer "F.SilkS")
		)
		(fp_line
			(start 0.7874 0.4064)
			(end -0.7874 0.4064)
			(stroke
				(width 0.1524)
				(type default)
			)
			(layer "F.SilkS")
		)
		(fp_line
			(start -0.7874 -0.4064)
			(end 0.7874 -0.4064)
			(stroke
				(width 0.1524)
				(type default)
			)
			(layer "F.SilkS")
		)
		(fp_line
			(start 0.7874 -0.4064)
			(end 0.7874 0.4064)
			(stroke
				(width 0.1524)
				(type default)
			)
			(layer "F.SilkS")
		)
		(fp_line
			(start -0.67945 0.3048)
			(end -0.67945 -0.305054)
			(stroke
				(width 0.1)
				(type default)
			)
			(layer "F.Fab")
		)
		(fp_line
			(start -0.12065 0.3048)
			(end -0.67945 0.3048)
			(stroke
				(width 0.1)
				(type default)
			)
			(layer "F.Fab")
		)
		(fp_line
			(start 0.120396 0.3048)
			(end 0.120396 0.2794)
			(stroke
				(width 0.1)
				(type default)
			)
			(layer "F.Fab")
		)
		(fp_line
			(start 0.67945 0.3048)
			(end 0.120396 0.3048)
			(stroke
				(width 0.1)
				(type default)
			)
			(layer "F.Fab")
		)
		(fp_line
			(start -0.12065 0.2794)
			(end -0.12065 0.3048)
			(stroke
				(width 0.1)
				(type default)
			)
			(layer "F.Fab")
		)
		(fp_line
			(start 0.120396 0.2794)
			(end -0.12065 0.2794)
			(stroke
				(width 0.1)
				(type default)
			)
			(layer "F.Fab")
		)
		(fp_line
			(start -0.12065 -0.2794)
			(end 0.12065 -0.2794)
			(stroke
				(width 0.1)
				(type default)
			)
			(layer "F.Fab")
		)
		(fp_line
			(start 0.12065 -0.2794)
			(end 0.12065 -0.3048)
			(stroke
				(width 0.1)
				(type default)
			)
			(layer "F.Fab")
		)
		(fp_line
			(start 0.12065 -0.3048)
			(end 0.67945 -0.3048)
			(stroke
				(width 0.1)
				(type default)
			)
			(layer "F.Fab")
		)
		(fp_line
			(start 0.67945 -0.3048)
			(end 0.67945 0.3048)
			(stroke
				(width 0.1)
				(type default)
			)
			(layer "F.Fab")
		)
		(fp_line
			(start -0.67945 -0.305054)
			(end -0.12065 -0.305054)
			(stroke
				(width 0.1)
				(type default)
			)
			(layer "F.Fab")
		)
		(fp_line
			(start -0.12065 -0.305054)
			(end -0.12065 -0.2794)
			(stroke
				(width 0.1)
				(type default)
			)
			(layer "F.Fab")
		)
		(pad "1" smd circle
			(at -0.40005 0 270)
			(size 0 0)
			(layers "F.Cu" "F.Mask" "F.Paste")
			(net "P1V8_AUX")
		)
		(pad "2" smd circle
			(at 0.40005 0 270)
			(size 0 0)
			(layers "F.Cu" "F.Mask" "F.Paste")
			(net "PWRGD_P0V9_RETIMER_CPU0_R")
		)
	)
	(footprint ""
		(layer "F.Cu")
		(at 431.970688 -351.140268)
		(property "Reference" "PU23"
			(at 5.206238 -1.0922 90)
			(unlocked yes)
			(layer "F.SilkS")
			(effects
				(font
					(size 0.7874 0.5842)
					(thickness 0.1524)
				)
				(justify left)
			)
		)
		(property "Value" ""
			(at 0 0 0)
			(layer "F.Fab")
			(effects
				(font
					(size 1.27 1.27)
				)
			)
		)
		(duplicate_pad_numbers_are_jumpers no)
		(fp_line
			(start -2.500122 -2.999994)
			(end -2.24409 -2.999994)
			(stroke
				(width 0.1524)
				(type default)
			)
			(layer "F.SilkS")
		)
		(fp_line
			(start -2.500122 -2.529078)
			(end -2.500122 -2.999994)
			(stroke
				(width 0.1524)
				(type default)
			)
			(layer "F.SilkS")
		)
		(fp_line
			(start -2.500122 0.6604)
			(end -2.500122 0.229108)
			(stroke
				(width 0.1524)
				(type default)
			)
			(layer "F.SilkS")
		)
		(fp_line
			(start -2.500122 2.999994)
			(end -2.500122 2.339594)
			(stroke
				(width 0.1524)
				(type default)
			)
			(layer "F.SilkS")
		)
		(fp_line
			(start -2.2987 2.999994)
			(end -2.500122 2.999994)
			(stroke
				(width 0.1524)
				(type default)
			)
			(layer "F.SilkS")
		)
		(fp_line
			(start 2.31394 -2.999994)
			(end 2.500122 -2.999994)
			(stroke
				(width 0.1524)
				(type default)
			)
			(layer "F.SilkS")
		)
		(fp_line
			(start 2.500122 -2.999994)
			(end 2.500122 -2.44348)
			(stroke
				(width 0.1524)
				(type default)
			)
			(layer "F.SilkS")
		)
		(fp_line
			(start 2.500122 2.339594)
			(end 2.500122 2.999994)
			(stroke
				(width 0.1524)
				(type default)
			)
			(layer "F.SilkS")
		)
		(fp_line
			(start 2.500122 2.999994)
			(end 2.2987 2.999994)
			(stroke
				(width 0.1524)
				(type default)
			)
			(layer "F.SilkS")
		)
		(fp_poly
			(pts
				(xy -3.43535 -2.660142) (xy -2.99339 -3.102356) (xy -2.771902 -2.438908)
			)
			(stroke
				(width 0)
				(type default)
			)
			(fill yes)
			(layer "F.SilkS")
		)
		(fp_line
			(start -2.500122 -2.999994)
			(end 2.500122 -2.999994)
			(stroke
				(width 0.1)
				(type default)
			)
			(layer "F.Fab")
		)
		(fp_line
			(start -2.500122 2.999994)
			(end -2.500122 -2.999994)
			(stroke
				(width 0.1)
				(type default)
			)
			(layer "F.Fab")
		)
		(fp_line
			(start 2.500122 -2.999994)
			(end 2.500122 2.999994)
			(stroke
				(width 0.1)
				(type default)
			)
			(layer "F.Fab")
		)
		(fp_line
			(start 2.500122 2.999994)
			(end -2.500122 2.999994)
			(stroke
				(width 0.1)
				(type default)
			)
			(layer "F.Fab")
		)
		(fp_poly
			(pts
				(xy -4.218432 -2.783078) (xy -4.218432 -1.767078) (xy -3.202432 -2.275078)
			)
			(stroke
				(width 0)
				(type default)
			)
			(fill yes)
			(layer "F.Fab")
		)
		(pad "1" smd rect
			(at -2.400046 -2.275078 90)
			(size 0.2286 0.6096)
			(layers "F.Cu" "F.Mask" "F.Paste")
			(net "PVDD11_S3_P0_VOS2")
		)
		(pad "2" smd rect
			(at -2.400046 -1.82499 90)
			(size 0.2286 0.6096)
			(layers "F.Cu" "F.Mask" "F.Paste")
			(net "GND")
		)
		(pad "3" smd rect
			(at -2.400046 -1.374902 90)
			(size 0.2286 0.6096)
			(layers "F.Cu" "F.Mask" "F.Paste")
			(net "PVDD11_S3_P0_VCC2")
		)
		(pad "4" smd rect
			(at -2.400046 -0.925068 90)
			(size 0.2286 0.6096)
			(layers "F.Cu" "F.Mask" "F.Paste")
			(net "PVDD11_S3_P0_PVCC")
		)
		(pad "5" smd rect
			(at -2.400046 -0.47498 90)
			(size 0.2286 0.6096)
			(layers "F.Cu" "F.Mask" "F.Paste")
			(net "GND")
		)
		(pad "6" smd rect
			(at -2.400046 -0.024892 90)
			(size 0.2286 0.6096)
			(layers "F.Cu" "F.Mask" "F.Paste")
			(net "NC_PVDD11_S3_P0_GL1_2")
		)
		(pad "7_9-20_24" smd circle
			(at 0 1.150112 90)
			(size 0 0)
			(layers "F.Cu" "F.Mask" "F.Paste")
			(net "GND")
		)
		(pad "10_19" smd rect
			(at 0 2.899918 90)
			(size 0.6096 4.318)
			(layers "F.Cu" "F.Mask" "F.Paste")
			(net "SW_PVDD11_S3_P0_SW2")
		)
		(pad "25_29" smd rect
			(at 1.549908 -1.279906 270)
			(size 2.0574 2.3114)
			(layers "F.Cu" "F.Mask" "F.Paste")
			(net "SW_P12V_AUX_PVDD11_S3_P0_FLT")
		)
		(pad "30" smd rect
			(at 2.05994 -2.899918)
			(size 0.2286 0.6096)
			(layers "F.Cu" "F.Mask" "F.Paste")
			(net "SW_P12V_AUX_PVDD11_S3_P0_FLT")
		)
		(pad "31" smd rect
			(at 1.610106 -2.899918)
			(size 0.2286 0.6096)
			(layers "F.Cu" "F.Mask" "F.Paste")
			(net "NC_PVDD11_S3_P0_DNC2")
		)
		(pad "32" smd rect
			(at 1.160018 -2.899918)
			(size 0.2286 0.6096)
			(layers "F.Cu" "F.Mask" "F.Paste")
			(net "SW_PVDD11_S3_P0_PH2")
		)
		(pad "33" smd rect
			(at 0.70993 -2.899918)
			(size 0.2286 0.6096)
			(layers "F.Cu" "F.Mask" "F.Paste")
			(net "SW_PVDD11_S3_P0_BOOT2")
		)
		(pad "34" smd rect
			(at 0.260096 -2.899918)
			(size 0.2286 0.6096)
			(layers "F.Cu" "F.Mask" "F.Paste")
			(net "PVDD11_S3_P0_PWM2")
		)
		(pad "35" smd rect
			(at -0.189992 -2.899918)
			(size 0.2286 0.6096)
			(layers "F.Cu" "F.Mask" "F.Paste")
			(net "PVDD11_S3_P0_VCC2")
		)
		(pad "36" smd rect
			(at -0.64008 -2.899918)
			(size 0.2286 0.6096)
			(layers "F.Cu" "F.Mask" "F.Paste")
			(net "PVDD11_S3_P0_TEMP0")
		)
		(pad "37" smd rect
			(at -1.089914 -2.899918)
			(size 0.2286 0.6096)
			(layers "F.Cu" "F.Mask" "F.Paste")
			(net "PVDD11_S3_P0_LSET2")
		)
		(pad "38" smd rect
			(at -1.540002 -2.899918)
			(size 0.2286 0.6096)
			(layers "F.Cu" "F.Mask" "F.Paste")
			(net "PVDD11_S3_P0_IMON2")
		)
		(pad "39" smd rect
			(at -1.99009 -2.899918)
			(size 0.2286 0.6096)
			(layers "F.Cu" "F.Mask" "F.Paste")
			(net "PVDD11_S3_P0_VCCS")
		)
		(pad "40" smd rect
			(at -0.87503 -1.27508)
			(size 1.7526 1.9558)
			(layers "F.Cu" "F.Mask" "F.Paste")
			(net "GND")
		)
		(pad "41" smd rect
			(at -1.525016 0.249936 270)
			(size 0.3048 0.4572)
			(layers "F.Cu" "F.Mask" "F.Paste")
			(net "NC_PVDD11_S3_P0_GL2_2")
		)
		(zone
			(layer "F.Cu")
			(hatch none 0.5)
			(connect_pads
				(clearance 0)
			)
			(min_thickness 0.25)
			(keepout
				(tracks not_allowed)
				(vias allowed)
				(pads allowed)
				(copperpour not_allowed)
				(footprints allowed)
			)
			(placement
				(enabled no)
				(sheetname "")
			)
			(fill
				(thermal_gap 0.5)
				(thermal_bridge_width 0.5)
				(island_removal_mode 0)
			)
			(polygon
				(pts
					(xy 429.470566 -348.584266) (xy 429.470566 -348.889574) (xy 434.47081 -348.889574) (xy 434.47081 -348.140274)
					(xy 434.180488 -348.140274) (xy 434.180488 -348.59595) (xy 429.760888 -348.59595) (xy 429.760888 -348.584266)
				)
			)
		)
		(zone
			(layer "F.Cu")
			(hatch none 0.5)
			(connect_pads
				(clearance 0)
			)
			(min_thickness 0.25)
			(keepout
				(tracks not_allowed)
				(vias allowed)
				(pads allowed)
				(copperpour not_allowed)
				(footprints allowed)
			)
			(placement
				(enabled no)
				(sheetname "")
			)
			(fill
				(thermal_gap 0.5)
				(thermal_bridge_width 0.5)
				(island_removal_mode 0)
			)
			(polygon
				(pts
					(xy 432.022758 -351.38868) (xy 432.022758 -353.444048) (xy 430.168558 -353.444048) (xy 430.168558 -353.203002)
					(xy 429.926242 -353.203002) (xy 429.926242 -353.684586) (xy 433.731162 -353.684586) (xy 433.731162 -353.499674)
					(xy 432.314096 -353.499674) (xy 432.314096 -351.340674) (xy 434.47081 -351.340674) (xy 434.47081 -351.090992)
					(xy 432.320446 -351.090992)
				)
			)
		)
	)
	(footprint ""
		(layer "F.Cu")
		(at 183.650128 -133.55701 -90)
		(property "Reference" "R196"
			(at 0 0 270)
			(layer "F.SilkS")
			(hide yes)
			(effects
				(font
					(size 1.27 1.27)
				)
			)
		)
		(property "Value" ""
			(at 0 0 270)
			(layer "F.Fab")
			(effects
				(font
					(size 1.27 1.27)
				)
			)
		)
		(duplicate_pad_numbers_are_jumpers no)
		(fp_line
			(start -0.7874 0.4064)
			(end -0.7874 -0.4064)
			(stroke
				(width 0.1524)
				(type default)
			)
			(layer "F.SilkS")
		)
		(fp_line
			(start 0.7874 0.4064)
			(end -0.7874 0.4064)
			(stroke
				(width 0.1524)
				(type default)
			)
			(layer "F.SilkS")
		)
		(fp_line
			(start -0.7874 -0.4064)
			(end 0.7874 -0.4064)
			(stroke
				(width 0.1524)
				(type default)
			)
			(layer "F.SilkS")
		)
		(fp_line
			(start 0.7874 -0.4064)
			(end 0.7874 0.4064)
			(stroke
				(width 0.1524)
				(type default)
			)
			(layer "F.SilkS")
		)
		(fp_line
			(start -0.67945 0.3048)
			(end -0.67945 -0.305054)
			(stroke
				(width 0.1)
				(type default)
			)
			(layer "F.Fab")
		)
		(fp_line
			(start -0.12065 0.3048)
			(end -0.67945 0.3048)
			(stroke
				(width 0.1)
				(type default)
			)
			(layer "F.Fab")
		)
		(fp_line
			(start 0.120396 0.3048)
			(end 0.120396 0.2794)
			(stroke
				(width 0.1)
				(type default)
			)
			(layer "F.Fab")
		)
		(fp_line
			(start 0.67945 0.3048)
			(end 0.120396 0.3048)
			(stroke
				(width 0.1)
				(type default)
			)
			(layer "F.Fab")
		)
		(fp_line
			(start -0.12065 0.2794)
			(end -0.12065 0.3048)
			(stroke
				(width 0.1)
				(type default)
			)
			(layer "F.Fab")
		)
		(fp_line
			(start 0.120396 0.2794)
			(end -0.12065 0.2794)
			(stroke
				(width 0.1)
				(type default)
			)
			(layer "F.Fab")
		)
		(fp_line
			(start -0.12065 -0.2794)
			(end 0.12065 -0.2794)
			(stroke
				(width 0.1)
				(type default)
			)
			(layer "F.Fab")
		)
		(fp_line
			(start 0.12065 -0.2794)
			(end 0.12065 -0.3048)
			(stroke
				(width 0.1)
				(type default)
			)
			(layer "F.Fab")
		)
		(fp_line
			(start 0.12065 -0.3048)
			(end 0.67945 -0.3048)
			(stroke
				(width 0.1)
				(type default)
			)
			(layer "F.Fab")
		)
		(fp_line
			(start 0.67945 -0.3048)
			(end 0.67945 0.3048)
			(stroke
				(width 0.1)
				(type default)
			)
			(layer "F.Fab")
		)
		(fp_line
			(start -0.67945 -0.305054)
			(end -0.12065 -0.305054)
			(stroke
				(width 0.1)
				(type default)
			)
			(layer "F.Fab")
		)
		(fp_line
			(start -0.12065 -0.305054)
			(end -0.12065 -0.2794)
			(stroke
				(width 0.1)
				(type default)
			)
			(layer "F.Fab")
		)
		(pad "1" smd circle
			(at -0.40005 0 270)
			(size 0 0)
			(layers "F.Cu" "F.Mask" "F.Paste")
			(net "CPU1_NV_SAVE_N")
		)
		(pad "2" smd circle
			(at 0.40005 0 270)
			(size 0 0)
			(layers "F.Cu" "F.Mask" "F.Paste")
			(net "FM_CPU1_NV_SAVE_N")
		)
	)
	(footprint ""
		(layer "F.Cu")
		(at 396.038324 -172.51934 90)
		(property "Reference" "PC593"
			(at 0 0 90)
			(layer "F.SilkS")
			(hide yes)
			(effects
				(font
					(size 1.27 1.27)
				)
			)
		)
		(property "Value" ""
			(at 0 0 90)
			(layer "F.Fab")
			(effects
				(font
					(size 1.27 1.27)
				)
			)
		)
		(duplicate_pad_numbers_are_jumpers no)
		(fp_line
			(start 0.7874 -0.4064)
			(end 0.7874 0.4064)
			(stroke
				(width 0.1524)
				(type default)
			)
			(layer "F.SilkS")
		)
		(fp_line
			(start -0.7874 -0.4064)
			(end 0.7874 -0.4064)
			(stroke
				(width 0.1524)
				(type default)
			)
			(layer "F.SilkS")
		)
		(fp_line
			(start 0.7874 0.4064)
			(end -0.7874 0.4064)
			(stroke
				(width 0.1524)
				(type default)
			)
			(layer "F.SilkS")
		)
		(fp_line
			(start -0.7874 0.4064)
			(end -0.7874 -0.4064)
			(stroke
				(width 0.1524)
				(type default)
			)
			(layer "F.SilkS")
		)
		(fp_line
			(start -0.12065 -0.305054)
			(end -0.12065 -0.2794)
			(stroke
				(width 0.1)
				(type default)
			)
			(layer "F.Fab")
		)
		(fp_line
			(start -0.67945 -0.305054)
			(end -0.12065 -0.305054)
			(stroke
				(width 0.1)
				(type default)
			)
			(layer "F.Fab")
		)
		(fp_line
			(start 0.67945 -0.3048)
			(end 0.67945 0.3048)
			(stroke
				(width 0.1)
				(type default)
			)
			(layer "F.Fab")
		)
		(fp_line
			(start 0.12065 -0.3048)
			(end 0.67945 -0.3048)
			(stroke
				(width 0.1)
				(type default)
			)
			(layer "F.Fab")
		)
		(fp_line
			(start 0.12065 -0.2794)
			(end 0.12065 -0.3048)
			(stroke
				(width 0.1)
				(type default)
			)
			(layer "F.Fab")
		)
		(fp_line
			(start -0.12065 -0.2794)
			(end 0.12065 -0.2794)
			(stroke
				(width 0.1)
				(type default)
			)
			(layer "F.Fab")
		)
		(fp_line
			(start 0.120396 0.2794)
			(end -0.12065 0.2794)
			(stroke
				(width 0.1)
				(type default)
			)
			(layer "F.Fab")
		)
		(fp_line
			(start -0.12065 0.2794)
			(end -0.12065 0.3048)
			(stroke
				(width 0.1)
				(type default)
			)
			(layer "F.Fab")
		)
		(fp_line
			(start 0.67945 0.3048)
			(end 0.120396 0.3048)
			(stroke
				(width 0.1)
				(type default)
			)
			(layer "F.Fab")
		)
		(fp_line
			(start 0.120396 0.3048)
			(end 0.120396 0.2794)
			(stroke
				(width 0.1)
				(type default)
			)
			(layer "F.Fab")
		)
		(fp_line
			(start -0.12065 0.3048)
			(end -0.67945 0.3048)
			(stroke
				(width 0.1)
				(type default)
			)
			(layer "F.Fab")
		)
		(fp_line
			(start -0.67945 0.3048)
			(end -0.67945 -0.305054)
			(stroke
				(width 0.1)
				(type default)
			)
			(layer "F.Fab")
		)
		(pad "1" smd circle
			(at -0.40005 0 90)
			(size 0 0)
			(layers "F.Cu" "F.Mask" "F.Paste")
			(net "SW_PVDDCR_SOC_P0_BOOT1_RC")
		)
		(pad "2" smd circle
			(at 0.40005 0 90)
			(size 0 0)
			(layers "F.Cu" "F.Mask" "F.Paste")
			(net "SW_PVDDCR_SOC_P0_PH1")
		)
	)
	(footprint ""
		(layer "F.Cu")
		(at 406.771348 -16.100298 90)
		(property "Reference" "C1560"
			(at 0 0 90)
			(layer "F.SilkS")
			(hide yes)
			(effects
				(font
					(size 1.27 1.27)
				)
			)
		)
		(property "Value" ""
			(at 0 0 90)
			(layer "F.Fab")
			(effects
				(font
					(size 1.27 1.27)
				)
			)
		)
		(duplicate_pad_numbers_are_jumpers no)
		(fp_line
			(start 0.299974 -0.150114)
			(end 0.299974 0.150114)
			(stroke
				(width 0.1)
				(type default)
			)
			(layer "F.Fab")
		)
		(fp_line
			(start -0.299974 -0.150114)
			(end 0.299974 -0.150114)
			(stroke
				(width 0.1)
				(type default)
			)
			(layer "F.Fab")
		)
		(fp_line
			(start 0.299974 0.150114)
			(end -0.299974 0.150114)
			(stroke
				(width 0.1)
				(type default)
			)
			(layer "F.Fab")
		)
		(fp_line
			(start -0.299974 0.150114)
			(end -0.299974 -0.150114)
			(stroke
				(width 0.1)
				(type default)
			)
			(layer "F.Fab")
		)
		(pad "1" smd rect
			(at -0.2667 0 90)
			(size 0.3048 0.381)
			(layers "F.Cu" "F.Mask" "F.Paste")
			(net "P5E_CPU0_G3_TX_C_DN<9>")
		)
		(pad "2" smd rect
			(at 0.2667 0 90)
			(size 0.3048 0.381)
			(layers "F.Cu" "F.Mask" "F.Paste")
			(net "P5E_CPU0_G3_TX_DN<9>")
		)
	)
	(footprint ""
		(layer "F.Cu")
		(at 282.985718 -390.49452 -90)
		(property "Reference" "R2626"
			(at 0 0 270)
			(layer "F.SilkS")
			(hide yes)
			(effects
				(font
					(size 1.27 1.27)
				)
			)
		)
		(property "Value" ""
			(at 0 0 270)
			(layer "F.Fab")
			(effects
				(font
					(size 1.27 1.27)
				)
			)
		)
		(duplicate_pad_numbers_are_jumpers no)
		(fp_line
			(start -0.7874 0.4064)
			(end -0.7874 -0.4064)
			(stroke
				(width 0.1524)
				(type default)
			)
			(layer "F.SilkS")
		)
		(fp_line
			(start 0.7874 0.4064)
			(end -0.7874 0.4064)
			(stroke
				(width 0.1524)
				(type default)
			)
			(layer "F.SilkS")
		)
		(fp_line
			(start -0.7874 -0.4064)
			(end 0.7874 -0.4064)
			(stroke
				(width 0.1524)
				(type default)
			)
			(layer "F.SilkS")
		)
		(fp_line
			(start 0.7874 -0.4064)
			(end 0.7874 0.4064)
			(stroke
				(width 0.1524)
				(type default)
			)
			(layer "F.SilkS")
		)
		(fp_line
			(start -0.67945 0.3048)
			(end -0.67945 -0.305054)
			(stroke
				(width 0.1)
				(type default)
			)
			(layer "F.Fab")
		)
		(fp_line
			(start -0.12065 0.3048)
			(end -0.67945 0.3048)
			(stroke
				(width 0.1)
				(type default)
			)
			(layer "F.Fab")
		)
		(fp_line
			(start 0.120396 0.3048)
			(end 0.120396 0.2794)
			(stroke
				(width 0.1)
				(type default)
			)
			(layer "F.Fab")
		)
		(fp_line
			(start 0.67945 0.3048)
			(end 0.120396 0.3048)
			(stroke
				(width 0.1)
				(type default)
			)
			(layer "F.Fab")
		)
		(fp_line
			(start -0.12065 0.2794)
			(end -0.12065 0.3048)
			(stroke
				(width 0.1)
				(type default)
			)
			(layer "F.Fab")
		)
		(fp_line
			(start 0.120396 0.2794)
			(end -0.12065 0.2794)
			(stroke
				(width 0.1)
				(type default)
			)
			(layer "F.Fab")
		)
		(fp_line
			(start -0.12065 -0.2794)
			(end 0.12065 -0.2794)
			(stroke
				(width 0.1)
				(type default)
			)
			(layer "F.Fab")
		)
		(fp_line
			(start 0.12065 -0.2794)
			(end 0.12065 -0.3048)
			(stroke
				(width 0.1)
				(type default)
			)
			(layer "F.Fab")
		)
		(fp_line
			(start 0.12065 -0.3048)
			(end 0.67945 -0.3048)
			(stroke
				(width 0.1)
				(type default)
			)
			(layer "F.Fab")
		)
		(fp_line
			(start 0.67945 -0.3048)
			(end 0.67945 0.3048)
			(stroke
				(width 0.1)
				(type default)
			)
			(layer "F.Fab")
		)
		(fp_line
			(start -0.67945 -0.305054)
			(end -0.12065 -0.305054)
			(stroke
				(width 0.1)
				(type default)
			)
			(layer "F.Fab")
		)
		(fp_line
			(start -0.12065 -0.305054)
			(end -0.12065 -0.2794)
			(stroke
				(width 0.1)
				(type default)
			)
			(layer "F.Fab")
		)
		(pad "1" smd circle
			(at -0.40005 0 270)
			(size 0 0)
			(layers "F.Cu" "F.Mask" "F.Paste")
			(net "SMB_P12V_HSC_TEMP_SCL")
		)
		(pad "2" smd circle
			(at 0.40005 0 270)
			(size 0 0)
			(layers "F.Cu" "F.Mask" "F.Paste")
			(net "SMB_P12V_HSC_SCL")
		)
	)
	(footprint ""
		(layer "F.Cu")
		(at 82.437478 -335.134458 -90)
		(property "Reference" "PC378_2"
			(at 0 0 270)
			(layer "F.SilkS")
			(hide yes)
			(effects
				(font
					(size 1.27 1.27)
				)
			)
		)
		(property "Value" ""
			(at 0 0 270)
			(layer "F.Fab")
			(effects
				(font
					(size 1.27 1.27)
				)
			)
		)
		(duplicate_pad_numbers_are_jumpers no)
		(fp_line
			(start -0.7874 0.4064)
			(end -0.7874 -0.4064)
			(stroke
				(width 0.1524)
				(type default)
			)
			(layer "F.SilkS")
		)
		(fp_line
			(start 0.7874 0.4064)
			(end -0.7874 0.4064)
			(stroke
				(width 0.1524)
				(type default)
			)
			(layer "F.SilkS")
		)
		(fp_line
			(start -0.7874 -0.4064)
			(end 0.7874 -0.4064)
			(stroke
				(width 0.1524)
				(type default)
			)
			(layer "F.SilkS")
		)
		(fp_line
			(start 0.7874 -0.4064)
			(end 0.7874 0.4064)
			(stroke
				(width 0.1524)
				(type default)
			)
			(layer "F.SilkS")
		)
		(fp_line
			(start -0.67945 0.3048)
			(end -0.67945 -0.305054)
			(stroke
				(width 0.1)
				(type default)
			)
			(layer "F.Fab")
		)
		(fp_line
			(start -0.12065 0.3048)
			(end -0.67945 0.3048)
			(stroke
				(width 0.1)
				(type default)
			)
			(layer "F.Fab")
		)
		(fp_line
			(start 0.120396 0.3048)
			(end 0.120396 0.2794)
			(stroke
				(width 0.1)
				(type default)
			)
			(layer "F.Fab")
		)
		(fp_line
			(start 0.67945 0.3048)
			(end 0.120396 0.3048)
			(stroke
				(width 0.1)
				(type default)
			)
			(layer "F.Fab")
		)
		(fp_line
			(start -0.12065 0.2794)
			(end -0.12065 0.3048)
			(stroke
				(width 0.1)
				(type default)
			)
			(layer "F.Fab")
		)
		(fp_line
			(start 0.120396 0.2794)
			(end -0.12065 0.2794)
			(stroke
				(width 0.1)
				(type default)
			)
			(layer "F.Fab")
		)
		(fp_line
			(start -0.12065 -0.2794)
			(end 0.12065 -0.2794)
			(stroke
				(width 0.1)
				(type default)
			)
			(layer "F.Fab")
		)
		(fp_line
			(start 0.12065 -0.2794)
			(end 0.12065 -0.3048)
			(stroke
				(width 0.1)
				(type default)
			)
			(layer "F.Fab")
		)
		(fp_line
			(start 0.12065 -0.3048)
			(end 0.67945 -0.3048)
			(stroke
				(width 0.1)
				(type default)
			)
			(layer "F.Fab")
		)
		(fp_line
			(start 0.67945 -0.3048)
			(end 0.67945 0.3048)
			(stroke
				(width 0.1)
				(type default)
			)
			(layer "F.Fab")
		)
		(fp_line
			(start -0.67945 -0.305054)
			(end -0.12065 -0.305054)
			(stroke
				(width 0.1)
				(type default)
			)
			(layer "F.Fab")
		)
		(fp_line
			(start -0.12065 -0.305054)
			(end -0.12065 -0.2794)
			(stroke
				(width 0.1)
				(type default)
			)
			(layer "F.Fab")
		)
		(pad "1" smd circle
			(at -0.40005 0 270)
			(size 0 0)
			(layers "F.Cu" "F.Mask" "F.Paste")
			(net "SW_P12V_AUX_PVDDCR_CPU1_P1_FLT")
		)
		(pad "2" smd circle
			(at 0.40005 0 270)
			(size 0 0)
			(layers "F.Cu" "F.Mask" "F.Paste")
			(net "GND")
		)
	)
	(footprint ""
		(layer "F.Cu")
		(at 297.554142 -399.034)
		(property "Reference" "R1001"
			(at 0 0 0)
			(layer "F.SilkS")
			(hide yes)
			(effects
				(font
					(size 1.27 1.27)
				)
			)
		)
		(property "Value" ""
			(at 0 0 0)
			(layer "F.Fab")
			(effects
				(font
					(size 1.27 1.27)
				)
			)
		)
		(duplicate_pad_numbers_are_jumpers no)
		(fp_line
			(start -0.32512 -0.175006)
			(end 0.32512 -0.175006)
			(stroke
				(width 0.1)
				(type default)
			)
			(layer "F.Fab")
		)
		(fp_line
			(start -0.32512 0.175006)
			(end -0.32512 -0.175006)
			(stroke
				(width 0.1)
				(type default)
			)
			(layer "F.Fab")
		)
		(fp_line
			(start 0.32512 -0.175006)
			(end 0.32512 0.175006)
			(stroke
				(width 0.1)
				(type default)
			)
			(layer "F.Fab")
		)
		(fp_line
			(start 0.32512 0.175006)
			(end -0.32512 0.175006)
			(stroke
				(width 0.1)
				(type default)
			)
			(layer "F.Fab")
		)
		(pad "1" smd rect
			(at -0.2667 0)
			(size 0.3048 0.381)
			(layers "F.Cu" "F.Mask" "F.Paste")
			(net "MODE_RT_CPU0_P0")
		)
		(pad "2" smd rect
			(at 0.2667 0 180)
			(size 0.3048 0.381)
			(layers "F.Cu" "F.Mask" "F.Paste")
			(net "GND")
		)
	)
	(footprint ""
		(layer "F.Cu")
		(at 101.509068 -394.3604 -90)
		(property "Reference" "R6732"
			(at 0 0 270)
			(layer "F.SilkS")
			(hide yes)
			(effects
				(font
					(size 1.27 1.27)
				)
			)
		)
		(property "Value" ""
			(at 0 0 270)
			(layer "F.Fab")
			(effects
				(font
					(size 1.27 1.27)
				)
			)
		)
		(duplicate_pad_numbers_are_jumpers no)
		(fp_line
			(start -0.32512 0.175006)
			(end -0.32512 -0.175006)
			(stroke
				(width 0.1)
				(type default)
			)
			(layer "F.Fab")
		)
		(fp_line
			(start 0.32512 0.175006)
			(end -0.32512 0.175006)
			(stroke
				(width 0.1)
				(type default)
			)
			(layer "F.Fab")
		)
		(fp_line
			(start -0.32512 -0.175006)
			(end 0.32512 -0.175006)
			(stroke
				(width 0.1)
				(type default)
			)
			(layer "F.Fab")
		)
		(fp_line
			(start 0.32512 -0.175006)
			(end 0.32512 0.175006)
			(stroke
				(width 0.1)
				(type default)
			)
			(layer "F.Fab")
		)
		(pad "1" smd rect
			(at -0.2667 0 270)
			(size 0.3048 0.381)
			(layers "F.Cu" "F.Mask" "F.Paste")
			(net "NCF_A1_CPU1_P1_GND")
		)
		(pad "2" smd rect
			(at 0.2667 0 90)
			(size 0.3048 0.381)
			(layers "F.Cu" "F.Mask" "F.Paste")
			(net "GND")
		)
	)
	(footprint ""
		(layer "F.Cu")
		(at 138.981942 -386.7912 90)
		(property "Reference" "R903"
			(at 0 0 90)
			(layer "F.SilkS")
			(hide yes)
			(effects
				(font
					(size 1.27 1.27)
				)
			)
		)
		(property "Value" ""
			(at 0 0 90)
			(layer "F.Fab")
			(effects
				(font
					(size 1.27 1.27)
				)
			)
		)
		(duplicate_pad_numbers_are_jumpers no)
		(fp_line
			(start 0.32512 -0.175006)
			(end 0.32512 0.175006)
			(stroke
				(width 0.1)
				(type default)
			)
			(layer "F.Fab")
		)
		(fp_line
			(start -0.32512 -0.175006)
			(end 0.32512 -0.175006)
			(stroke
				(width 0.1)
				(type default)
			)
			(layer "F.Fab")
		)
		(fp_line
			(start 0.32512 0.175006)
			(end -0.32512 0.175006)
			(stroke
				(width 0.1)
				(type default)
			)
			(layer "F.Fab")
		)
		(fp_line
			(start -0.32512 0.175006)
			(end -0.32512 -0.175006)
			(stroke
				(width 0.1)
				(type default)
			)
			(layer "F.Fab")
		)
		(pad "1" smd rect
			(at -0.2667 0 90)
			(size 0.3048 0.381)
			(layers "F.Cu" "F.Mask" "F.Paste")
			(net "RT_CPU1_P3_ADDR3")
		)
		(pad "2" smd rect
			(at 0.2667 0 270)
			(size 0.3048 0.381)
			(layers "F.Cu" "F.Mask" "F.Paste")
			(net "GND")
		)
	)
	(footprint ""
		(layer "F.Cu")
		(at 369.455446 -28.306522 90)
		(property "Reference" "R822"
			(at 0 0 90)
			(layer "F.SilkS")
			(hide yes)
			(effects
				(font
					(size 1.27 1.27)
				)
			)
		)
		(property "Value" ""
			(at 0 0 90)
			(layer "F.Fab")
			(effects
				(font
					(size 1.27 1.27)
				)
			)
		)
		(duplicate_pad_numbers_are_jumpers no)
		(fp_line
			(start 0.7874 -0.4064)
			(end 0.7874 0.4064)
			(stroke
				(width 0.1524)
				(type default)
			)
			(layer "F.SilkS")
		)
		(fp_line
			(start -0.7874 -0.4064)
			(end 0.7874 -0.4064)
			(stroke
				(width 0.1524)
				(type default)
			)
			(layer "F.SilkS")
		)
		(fp_line
			(start 0.7874 0.4064)
			(end -0.7874 0.4064)
			(stroke
				(width 0.1524)
				(type default)
			)
			(layer "F.SilkS")
		)
		(fp_line
			(start -0.7874 0.4064)
			(end -0.7874 -0.4064)
			(stroke
				(width 0.1524)
				(type default)
			)
			(layer "F.SilkS")
		)
		(fp_line
			(start -0.12065 -0.305054)
			(end -0.12065 -0.2794)
			(stroke
				(width 0.1)
				(type default)
			)
			(layer "F.Fab")
		)
		(fp_line
			(start -0.67945 -0.305054)
			(end -0.12065 -0.305054)
			(stroke
				(width 0.1)
				(type default)
			)
			(layer "F.Fab")
		)
		(fp_line
			(start 0.67945 -0.3048)
			(end 0.67945 0.3048)
			(stroke
				(width 0.1)
				(type default)
			)
			(layer "F.Fab")
		)
		(fp_line
			(start 0.12065 -0.3048)
			(end 0.67945 -0.3048)
			(stroke
				(width 0.1)
				(type default)
			)
			(layer "F.Fab")
		)
		(fp_line
			(start 0.12065 -0.2794)
			(end 0.12065 -0.3048)
			(stroke
				(width 0.1)
				(type default)
			)
			(layer "F.Fab")
		)
		(fp_line
			(start -0.12065 -0.2794)
			(end 0.12065 -0.2794)
			(stroke
				(width 0.1)
				(type default)
			)
			(layer "F.Fab")
		)
		(fp_line
			(start 0.120396 0.2794)
			(end -0.12065 0.2794)
			(stroke
				(width 0.1)
				(type default)
			)
			(layer "F.Fab")
		)
		(fp_line
			(start -0.12065 0.2794)
			(end -0.12065 0.3048)
			(stroke
				(width 0.1)
				(type default)
			)
			(layer "F.Fab")
		)
		(fp_line
			(start 0.67945 0.3048)
			(end 0.120396 0.3048)
			(stroke
				(width 0.1)
				(type default)
			)
			(layer "F.Fab")
		)
		(fp_line
			(start 0.120396 0.3048)
			(end 0.120396 0.2794)
			(stroke
				(width 0.1)
				(type default)
			)
			(layer "F.Fab")
		)
		(fp_line
			(start -0.12065 0.3048)
			(end -0.67945 0.3048)
			(stroke
				(width 0.1)
				(type default)
			)
			(layer "F.Fab")
		)
		(fp_line
			(start -0.67945 0.3048)
			(end -0.67945 -0.305054)
			(stroke
				(width 0.1)
				(type default)
			)
			(layer "F.Fab")
		)
		(pad "1" smd circle
			(at -0.40005 0 90)
			(size 0 0)
			(layers "F.Cu" "F.Mask" "F.Paste")
			(net "P3V3_AUX")
		)
		(pad "2" smd circle
			(at 0.40005 0 90)
			(size 0 0)
			(layers "F.Cu" "F.Mask" "F.Paste")
			(net "UART_CPU0_SCM_LVC3_UART1_TX")
		)
	)
	(footprint ""
		(layer "F.Cu")
		(at 183.007 -129.377948 -90)
		(property "Reference" "R241"
			(at 0 0 270)
			(layer "F.SilkS")
			(hide yes)
			(effects
				(font
					(size 1.27 1.27)
				)
			)
		)
		(property "Value" ""
			(at 0 0 270)
			(layer "F.Fab")
			(effects
				(font
					(size 1.27 1.27)
				)
			)
		)
		(duplicate_pad_numbers_are_jumpers no)
		(fp_line
			(start -0.7874 0.4064)
			(end -0.7874 -0.4064)
			(stroke
				(width 0.1524)
				(type default)
			)
			(layer "F.SilkS")
		)
		(fp_line
			(start 0.7874 0.4064)
			(end -0.7874 0.4064)
			(stroke
				(width 0.1524)
				(type default)
			)
			(layer "F.SilkS")
		)
		(fp_line
			(start -0.7874 -0.4064)
			(end 0.7874 -0.4064)
			(stroke
				(width 0.1524)
				(type default)
			)
			(layer "F.SilkS")
		)
		(fp_line
			(start 0.7874 -0.4064)
			(end 0.7874 0.4064)
			(stroke
				(width 0.1524)
				(type default)
			)
			(layer "F.SilkS")
		)
		(fp_line
			(start -0.67945 0.3048)
			(end -0.67945 -0.305054)
			(stroke
				(width 0.1)
				(type default)
			)
			(layer "F.Fab")
		)
		(fp_line
			(start -0.12065 0.3048)
			(end -0.67945 0.3048)
			(stroke
				(width 0.1)
				(type default)
			)
			(layer "F.Fab")
		)
		(fp_line
			(start 0.120396 0.3048)
			(end 0.120396 0.2794)
			(stroke
				(width 0.1)
				(type default)
			)
			(layer "F.Fab")
		)
		(fp_line
			(start 0.67945 0.3048)
			(end 0.120396 0.3048)
			(stroke
				(width 0.1)
				(type default)
			)
			(layer "F.Fab")
		)
		(fp_line
			(start -0.12065 0.2794)
			(end -0.12065 0.3048)
			(stroke
				(width 0.1)
				(type default)
			)
			(layer "F.Fab")
		)
		(fp_line
			(start 0.120396 0.2794)
			(end -0.12065 0.2794)
			(stroke
				(width 0.1)
				(type default)
			)
			(layer "F.Fab")
		)
		(fp_line
			(start -0.12065 -0.2794)
			(end 0.12065 -0.2794)
			(stroke
				(width 0.1)
				(type default)
			)
			(layer "F.Fab")
		)
		(fp_line
			(start 0.12065 -0.2794)
			(end 0.12065 -0.3048)
			(stroke
				(width 0.1)
				(type default)
			)
			(layer "F.Fab")
		)
		(fp_line
			(start 0.12065 -0.3048)
			(end 0.67945 -0.3048)
			(stroke
				(width 0.1)
				(type default)
			)
			(layer "F.Fab")
		)
		(fp_line
			(start 0.67945 -0.3048)
			(end 0.67945 0.3048)
			(stroke
				(width 0.1)
				(type default)
			)
			(layer "F.Fab")
		)
		(fp_line
			(start -0.67945 -0.305054)
			(end -0.12065 -0.305054)
			(stroke
				(width 0.1)
				(type default)
			)
			(layer "F.Fab")
		)
		(fp_line
			(start -0.12065 -0.305054)
			(end -0.12065 -0.2794)
			(stroke
				(width 0.1)
				(type default)
			)
			(layer "F.Fab")
		)
		(pad "1" smd circle
			(at -0.40005 0 270)
			(size 0 0)
			(layers "F.Cu" "F.Mask" "F.Paste")
			(net "RST_CPU0_RESETL_N")
		)
		(pad "2" smd circle
			(at 0.40005 0 270)
			(size 0 0)
			(layers "F.Cu" "F.Mask" "F.Paste")
			(net "FM_RST_CPU0_RESETL_N")
		)
	)
	(footprint ""
		(layer "F.Cu")
		(at 439.072782 -435.27726 -90)
		(property "Reference" "R3470"
			(at 0 0 270)
			(layer "F.SilkS")
			(hide yes)
			(effects
				(font
					(size 1.27 1.27)
				)
			)
		)
		(property "Value" ""
			(at 0 0 270)
			(layer "F.Fab")
			(effects
				(font
					(size 1.27 1.27)
				)
			)
		)
		(duplicate_pad_numbers_are_jumpers no)
		(fp_line
			(start -0.7874 0.4064)
			(end -0.7874 -0.4064)
			(stroke
				(width 0.1524)
				(type default)
			)
			(layer "F.SilkS")
		)
		(fp_line
			(start 0.7874 0.4064)
			(end -0.7874 0.4064)
			(stroke
				(width 0.1524)
				(type default)
			)
			(layer "F.SilkS")
		)
		(fp_line
			(start -0.7874 -0.4064)
			(end 0.7874 -0.4064)
			(stroke
				(width 0.1524)
				(type default)
			)
			(layer "F.SilkS")
		)
		(fp_line
			(start 0.7874 -0.4064)
			(end 0.7874 0.4064)
			(stroke
				(width 0.1524)
				(type default)
			)
			(layer "F.SilkS")
		)
		(fp_line
			(start -0.67945 0.3048)
			(end -0.67945 -0.305054)
			(stroke
				(width 0.1)
				(type default)
			)
			(layer "F.Fab")
		)
		(fp_line
			(start -0.12065 0.3048)
			(end -0.67945 0.3048)
			(stroke
				(width 0.1)
				(type default)
			)
			(layer "F.Fab")
		)
		(fp_line
			(start 0.120396 0.3048)
			(end 0.120396 0.2794)
			(stroke
				(width 0.1)
				(type default)
			)
			(layer "F.Fab")
		)
		(fp_line
			(start 0.67945 0.3048)
			(end 0.120396 0.3048)
			(stroke
				(width 0.1)
				(type default)
			)
			(layer "F.Fab")
		)
		(fp_line
			(start -0.12065 0.2794)
			(end -0.12065 0.3048)
			(stroke
				(width 0.1)
				(type default)
			)
			(layer "F.Fab")
		)
		(fp_line
			(start 0.120396 0.2794)
			(end -0.12065 0.2794)
			(stroke
				(width 0.1)
				(type default)
			)
			(layer "F.Fab")
		)
		(fp_line
			(start -0.12065 -0.2794)
			(end 0.12065 -0.2794)
			(stroke
				(width 0.1)
				(type default)
			)
			(layer "F.Fab")
		)
		(fp_line
			(start 0.12065 -0.2794)
			(end 0.12065 -0.3048)
			(stroke
				(width 0.1)
				(type default)
			)
			(layer "F.Fab")
		)
		(fp_line
			(start 0.12065 -0.3048)
			(end 0.67945 -0.3048)
			(stroke
				(width 0.1)
				(type default)
			)
			(layer "F.Fab")
		)
		(fp_line
			(start 0.67945 -0.3048)
			(end 0.67945 0.3048)
			(stroke
				(width 0.1)
				(type default)
			)
			(layer "F.Fab")
		)
		(fp_line
			(start -0.67945 -0.305054)
			(end -0.12065 -0.305054)
			(stroke
				(width 0.1)
				(type default)
			)
			(layer "F.Fab")
		)
		(fp_line
			(start -0.12065 -0.305054)
			(end -0.12065 -0.2794)
			(stroke
				(width 0.1)
				(type default)
			)
			(layer "F.Fab")
		)
		(pad "1" smd circle
			(at -0.40005 0 270)
			(size 0 0)
			(layers "F.Cu" "F.Mask" "F.Paste")
			(net "P3V3_AUX")
		)
		(pad "2" smd circle
			(at 0.40005 0 270)
			(size 0 0)
			(layers "F.Cu" "F.Mask" "F.Paste")
			(net "GPU_WP_HW_CTRL_N")
		)
	)
	(footprint ""
		(layer "F.Cu")
		(at 110.365794 -385.58216)
		(property "Reference" "R916"
			(at 0 0 0)
			(layer "F.SilkS")
			(hide yes)
			(effects
				(font
					(size 1.27 1.27)
				)
			)
		)
		(property "Value" ""
			(at 0 0 0)
			(layer "F.Fab")
			(effects
				(font
					(size 1.27 1.27)
				)
			)
		)
		(duplicate_pad_numbers_are_jumpers no)
		(fp_line
			(start -0.32512 -0.175006)
			(end 0.32512 -0.175006)
			(stroke
				(width 0.1)
				(type default)
			)
			(layer "F.Fab")
		)
		(fp_line
			(start -0.32512 0.175006)
			(end -0.32512 -0.175006)
			(stroke
				(width 0.1)
				(type default)
			)
			(layer "F.Fab")
		)
		(fp_line
			(start 0.32512 -0.175006)
			(end 0.32512 0.175006)
			(stroke
				(width 0.1)
				(type default)
			)
			(layer "F.Fab")
		)
		(fp_line
			(start 0.32512 0.175006)
			(end -0.32512 0.175006)
			(stroke
				(width 0.1)
				(type default)
			)
			(layer "F.Fab")
		)
		(pad "1" smd rect
			(at -0.2667 0)
			(size 0.3048 0.381)
			(layers "F.Cu" "F.Mask" "F.Paste")
			(net "GPIO2_RT_CPU1_P3")
		)
		(pad "2" smd rect
			(at 0.2667 0 180)
			(size 0.3048 0.381)
			(layers "F.Cu" "F.Mask" "F.Paste")
			(net "GND")
		)
	)
	(footprint ""
		(layer "F.Cu")
		(at 11.843258 -427.13783 180)
		(property "Reference" "R6162"
			(at 0 0 180)
			(layer "F.SilkS")
			(hide yes)
			(effects
				(font
					(size 1.27 1.27)
				)
			)
		)
		(property "Value" ""
			(at 0 0 180)
			(layer "F.Fab")
			(effects
				(font
					(size 1.27 1.27)
				)
			)
		)
		(duplicate_pad_numbers_are_jumpers no)
		(fp_line
			(start 0.7874 0.4064)
			(end -0.7874 0.4064)
			(stroke
				(width 0.1524)
				(type default)
			)
			(layer "F.SilkS")
		)
		(fp_line
			(start 0.7874 -0.4064)
			(end 0.7874 0.4064)
			(stroke
				(width 0.1524)
				(type default)
			)
			(layer "F.SilkS")
		)
		(fp_line
			(start -0.7874 0.4064)
			(end -0.7874 -0.4064)
			(stroke
				(width 0.1524)
				(type default)
			)
			(layer "F.SilkS")
		)
		(fp_line
			(start -0.7874 -0.4064)
			(end 0.7874 -0.4064)
			(stroke
				(width 0.1524)
				(type default)
			)
			(layer "F.SilkS")
		)
		(fp_line
			(start 0.67945 0.3048)
			(end 0.120396 0.3048)
			(stroke
				(width 0.1)
				(type default)
			)
			(layer "F.Fab")
		)
		(fp_line
			(start 0.67945 -0.3048)
			(end 0.67945 0.3048)
			(stroke
				(width 0.1)
				(type default)
			)
			(layer "F.Fab")
		)
		(fp_line
			(start 0.12065 -0.2794)
			(end 0.12065 -0.3048)
			(stroke
				(width 0.1)
				(type default)
			)
			(layer "F.Fab")
		)
		(fp_line
			(start 0.12065 -0.3048)
			(end 0.67945 -0.3048)
			(stroke
				(width 0.1)
				(type default)
			)
			(layer "F.Fab")
		)
		(fp_line
			(start 0.120396 0.3048)
			(end 0.120396 0.2794)
			(stroke
				(width 0.1)
				(type default)
			)
			(layer "F.Fab")
		)
		(fp_line
			(start 0.120396 0.2794)
			(end -0.12065 0.2794)
			(stroke
				(width 0.1)
				(type default)
			)
			(layer "F.Fab")
		)
		(fp_line
			(start -0.12065 0.3048)
			(end -0.67945 0.3048)
			(stroke
				(width 0.1)
				(type default)
			)
			(layer "F.Fab")
		)
		(fp_line
			(start -0.12065 0.2794)
			(end -0.12065 0.3048)
			(stroke
				(width 0.1)
				(type default)
			)
			(layer "F.Fab")
		)
		(fp_line
			(start -0.12065 -0.2794)
			(end 0.12065 -0.2794)
			(stroke
				(width 0.1)
				(type default)
			)
			(layer "F.Fab")
		)
		(fp_line
			(start -0.12065 -0.305054)
			(end -0.12065 -0.2794)
			(stroke
				(width 0.1)
				(type default)
			)
			(layer "F.Fab")
		)
		(fp_line
			(start -0.67945 0.3048)
			(end -0.67945 -0.305054)
			(stroke
				(width 0.1)
				(type default)
			)
			(layer "F.Fab")
		)
		(fp_line
			(start -0.67945 -0.305054)
			(end -0.12065 -0.305054)
			(stroke
				(width 0.1)
				(type default)
			)
			(layer "F.Fab")
		)
		(pad "1" smd circle
			(at -0.40005 0 180)
			(size 0 0)
			(layers "F.Cu" "F.Mask" "F.Paste")
			(net "FM_P2E_EN2_N")
		)
		(pad "2" smd circle
			(at 0.40005 0 180)
			(size 0 0)
			(layers "F.Cu" "F.Mask" "F.Paste")
			(net "CLK_GEN2_GPU_FPGA_OE_OR_N")
		)
	)
	(footprint ""
		(layer "F.Cu")
		(at 73.201784 -172.974 -90)
		(property "Reference" "PR203"
			(at 0 0 270)
			(layer "F.SilkS")
			(hide yes)
			(effects
				(font
					(size 1.27 1.27)
				)
			)
		)
		(property "Value" ""
			(at 0 0 270)
			(layer "F.Fab")
			(effects
				(font
					(size 1.27 1.27)
				)
			)
		)
		(duplicate_pad_numbers_are_jumpers no)
		(fp_line
			(start -0.7874 0.4064)
			(end -0.7874 -0.4064)
			(stroke
				(width 0.1524)
				(type default)
			)
			(layer "F.SilkS")
		)
		(fp_line
			(start 0.7874 0.4064)
			(end -0.7874 0.4064)
			(stroke
				(width 0.1524)
				(type default)
			)
			(layer "F.SilkS")
		)
		(fp_line
			(start -0.7874 -0.4064)
			(end 0.7874 -0.4064)
			(stroke
				(width 0.1524)
				(type default)
			)
			(layer "F.SilkS")
		)
		(fp_line
			(start 0.7874 -0.4064)
			(end 0.7874 0.4064)
			(stroke
				(width 0.1524)
				(type default)
			)
			(layer "F.SilkS")
		)
		(fp_line
			(start -0.67945 0.3048)
			(end -0.67945 -0.305054)
			(stroke
				(width 0.1)
				(type default)
			)
			(layer "F.Fab")
		)
		(fp_line
			(start -0.12065 0.3048)
			(end -0.67945 0.3048)
			(stroke
				(width 0.1)
				(type default)
			)
			(layer "F.Fab")
		)
		(fp_line
			(start 0.120396 0.3048)
			(end 0.120396 0.2794)
			(stroke
				(width 0.1)
				(type default)
			)
			(layer "F.Fab")
		)
		(fp_line
			(start 0.67945 0.3048)
			(end 0.120396 0.3048)
			(stroke
				(width 0.1)
				(type default)
			)
			(layer "F.Fab")
		)
		(fp_line
			(start -0.12065 0.2794)
			(end -0.12065 0.3048)
			(stroke
				(width 0.1)
				(type default)
			)
			(layer "F.Fab")
		)
		(fp_line
			(start 0.120396 0.2794)
			(end -0.12065 0.2794)
			(stroke
				(width 0.1)
				(type default)
			)
			(layer "F.Fab")
		)
		(fp_line
			(start -0.12065 -0.2794)
			(end 0.12065 -0.2794)
			(stroke
				(width 0.1)
				(type default)
			)
			(layer "F.Fab")
		)
		(fp_line
			(start 0.12065 -0.2794)
			(end 0.12065 -0.3048)
			(stroke
				(width 0.1)
				(type default)
			)
			(layer "F.Fab")
		)
		(fp_line
			(start 0.12065 -0.3048)
			(end 0.67945 -0.3048)
			(stroke
				(width 0.1)
				(type default)
			)
			(layer "F.Fab")
		)
		(fp_line
			(start 0.67945 -0.3048)
			(end 0.67945 0.3048)
			(stroke
				(width 0.1)
				(type default)
			)
			(layer "F.Fab")
		)
		(fp_line
			(start -0.67945 -0.305054)
			(end -0.12065 -0.305054)
			(stroke
				(width 0.1)
				(type default)
			)
			(layer "F.Fab")
		)
		(fp_line
			(start -0.12065 -0.305054)
			(end -0.12065 -0.2794)
			(stroke
				(width 0.1)
				(type default)
			)
			(layer "F.Fab")
		)
		(pad "1" smd circle
			(at -0.40005 0 270)
			(size 0 0)
			(layers "F.Cu" "F.Mask" "F.Paste")
			(net "SW_PVDDCR_CPU0_P1_BOOT5")
		)
		(pad "2" smd circle
			(at 0.40005 0 270)
			(size 0 0)
			(layers "F.Cu" "F.Mask" "F.Paste")
			(net "SW_PVDDCR_CPU0_P1_BOOT5_RC")
		)
	)
	(footprint ""
		(layer "F.Cu")
		(at 42.967402 -375.94286 180)
		(property "Reference" "C835"
			(at 0 0 180)
			(layer "F.SilkS")
			(hide yes)
			(effects
				(font
					(size 1.27 1.27)
				)
			)
		)
		(property "Value" ""
			(at 0 0 180)
			(layer "F.Fab")
			(effects
				(font
					(size 1.27 1.27)
				)
			)
		)
		(duplicate_pad_numbers_are_jumpers no)
		(fp_line
			(start 0.299974 0.150114)
			(end -0.299974 0.150114)
			(stroke
				(width 0.1)
				(type default)
			)
			(layer "F.Fab")
		)
		(fp_line
			(start 0.299974 -0.150114)
			(end 0.299974 0.150114)
			(stroke
				(width 0.1)
				(type default)
			)
			(layer "F.Fab")
		)
		(fp_line
			(start -0.299974 0.150114)
			(end -0.299974 -0.150114)
			(stroke
				(width 0.1)
				(type default)
			)
			(layer "F.Fab")
		)
		(fp_line
			(start -0.299974 -0.150114)
			(end 0.299974 -0.150114)
			(stroke
				(width 0.1)
				(type default)
			)
			(layer "F.Fab")
		)
		(pad "1" smd rect
			(at -0.2667 0 180)
			(size 0.3048 0.381)
			(layers "F.Cu" "F.Mask" "F.Paste")
			(net "P5E_CPU1_P0_TX_C_DP<1>")
		)
		(pad "2" smd rect
			(at 0.2667 0 180)
			(size 0.3048 0.381)
			(layers "F.Cu" "F.Mask" "F.Paste")
			(net "P5E_CPU1_P0_TX_DP<1>")
		)
	)
	(footprint ""
		(layer "F.Cu")
		(at 130.23088 -27.25928 180)
		(property "Reference" "R339"
			(at 0 0 180)
			(layer "F.SilkS")
			(hide yes)
			(effects
				(font
					(size 1.27 1.27)
				)
			)
		)
		(property "Value" ""
			(at 0 0 180)
			(layer "F.Fab")
			(effects
				(font
					(size 1.27 1.27)
				)
			)
		)
		(duplicate_pad_numbers_are_jumpers no)
		(fp_line
			(start 0.32512 0.175006)
			(end -0.32512 0.175006)
			(stroke
				(width 0.1)
				(type default)
			)
			(layer "F.Fab")
		)
		(fp_line
			(start 0.32512 -0.175006)
			(end 0.32512 0.175006)
			(stroke
				(width 0.1)
				(type default)
			)
			(layer "F.Fab")
		)
		(fp_line
			(start -0.32512 0.175006)
			(end -0.32512 -0.175006)
			(stroke
				(width 0.1)
				(type default)
			)
			(layer "F.Fab")
		)
		(fp_line
			(start -0.32512 -0.175006)
			(end 0.32512 -0.175006)
			(stroke
				(width 0.1)
				(type default)
			)
			(layer "F.Fab")
		)
		(pad "1" smd rect
			(at -0.2667 0 180)
			(size 0.3048 0.381)
			(layers "F.Cu" "F.Mask" "F.Paste")
			(net "USB2_CPU0_P0_DP")
		)
		(pad "2" smd rect
			(at 0.2667 0)
			(size 0.3048 0.381)
			(layers "F.Cu" "F.Mask" "F.Paste")
			(net "GND")
		)
	)
	(footprint ""
		(layer "F.Cu")
		(at 473.706444 -353.119436)
		(property "Reference" "DB8"
			(at 1.09601 3.154934 0)
			(unlocked yes)
			(layer "F.SilkS")
			(effects
				(font
					(size 0.7874 0.5842)
					(thickness 0.1524)
				)
				(justify left)
			)
		)
		(property "Value" ""
			(at 0 0 0)
			(layer "F.Fab")
			(effects
				(font
					(size 1.27 1.27)
				)
			)
		)
		(duplicate_pad_numbers_are_jumpers no)
		(fp_line
			(start -3.330702 -4.771136)
			(end 3.330702 -4.771136)
			(stroke
				(width 0.1524)
				(type default)
			)
			(layer "F.SilkS")
		)
		(fp_line
			(start 0 4.011168)
			(end -3.330702 -4.771136)
			(stroke
				(width 0.1524)
				(type default)
			)
			(layer "F.SilkS")
		)
		(fp_line
			(start 2.71653 -3.151378)
			(end 0 4.011168)
			(stroke
				(width 0.1524)
				(type default)
			)
			(layer "F.SilkS")
		)
		(fp_line
			(start -3.330702 -4.771136)
			(end 3.330702 -4.771136)
			(stroke
				(width 0.1)
				(type default)
			)
			(layer "F.Fab")
		)
		(fp_line
			(start 0 4.011168)
			(end -3.330702 -4.771136)
			(stroke
				(width 0.1)
				(type default)
			)
			(layer "F.Fab")
		)
		(fp_line
			(start 3.330702 -4.771136)
			(end 0 4.011168)
			(stroke
				(width 0.1)
				(type default)
			)
			(layer "F.Fab")
		)
		(pad "1" thru_hole circle
			(at 0 0)
			(size 2.159 2.159)
			(drill 1.7018)
			(layers "*.Cu" "*.Mask")
			(remove_unused_layers no)
			(net "T1_GND")
			(clearance 0.0254)
			(thermal_gap 0.0254)
		)
		(pad "2" thru_hole circle
			(at -1.27 -3.348736)
			(size 2.159 2.159)
			(drill 1.7018)
			(layers "*.Cu" "*.Mask")
			(remove_unused_layers no)
			(net "TDR_SE_50_OHM_IN1")
			(clearance 0.0254)
			(thermal_gap 0.0254)
		)
		(pad "3" thru_hole circle
			(at 1.27 -3.348736)
			(size 2.159 2.159)
			(drill 1.7018)
			(layers "*.Cu" "*.Mask")
			(remove_unused_layers no)
			(net "TDR_SE_50_OHM_IN1")
			(clearance 0.0254)
			(thermal_gap 0.0254)
		)
	)
	(footprint ""
		(layer "F.Cu")
		(at 441.89523 -153.774394)
		(property "Reference" "H124"
			(at -3.257296 -7.931912 0)
			(unlocked yes)
			(layer "F.SilkS")
			(effects
				(font
					(size 0.7874 0.5842)
					(thickness 0.1524)
				)
				(justify left)
			)
		)
		(property "Value" ""
			(at 0 0 0)
			(layer "F.Fab")
			(effects
				(font
					(size 1.27 1.27)
				)
			)
		)
		(duplicate_pad_numbers_are_jumpers no)
		(fp_circle
			(center 0 0)
			(end 5.8166 0)
			(stroke
				(width 0.1524)
				(type default)
			)
			(fill no)
			(layer "F.SilkS")
		)
		(fp_circle
			(center 0 0)
			(end 5.8166 0)
			(stroke
				(width 0.1524)
				(type default)
			)
			(fill no)
			(layer "B.SilkS")
		)
		(fp_circle
			(center 0 0)
			(end 5.8166 0)
			(stroke
				(width 0.1)
				(type default)
			)
			(fill no)
			(layer "B.Fab")
		)
		(fp_circle
			(center 0 0)
			(end 5.8166 0)
			(stroke
				(width 0.1)
				(type default)
			)
			(fill no)
			(layer "F.Fab")
		)
		(pad "" np_thru_hole circle
			(at 0 0)
			(size 10.0076 10.0076)
			(drill 10.0076)
			(layers "*.Cu" "*.Mask")
			(clearance 0.381)
			(thermal_gap 0.381)
		)
	)
	(footprint ""
		(layer "F.Cu")
		(at 47.868586 -396.010892)
		(property "Reference" "C247"
			(at 0 0 0)
			(layer "F.SilkS")
			(hide yes)
			(effects
				(font
					(size 1.27 1.27)
				)
			)
		)
		(property "Value" ""
			(at 0 0 0)
			(layer "F.Fab")
			(effects
				(font
					(size 1.27 1.27)
				)
			)
		)
		(duplicate_pad_numbers_are_jumpers no)
		(fp_line
			(start -1.524 -0.762)
			(end 1.524 -0.762)
			(stroke
				(width 0.1524)
				(type default)
			)
			(layer "F.SilkS")
		)
		(fp_line
			(start -1.524 0.762)
			(end -1.524 -0.762)
			(stroke
				(width 0.1524)
				(type default)
			)
			(layer "F.SilkS")
		)
		(fp_line
			(start 1.524 -0.762)
			(end 1.524 0.762)
			(stroke
				(width 0.1524)
				(type default)
			)
			(layer "F.SilkS")
		)
		(fp_line
			(start 1.524 0.762)
			(end -1.524 0.762)
			(stroke
				(width 0.1524)
				(type default)
			)
			(layer "F.SilkS")
		)
		(fp_line
			(start -1.1049 -0.724916)
			(end -1.1049 0.724916)
			(stroke
				(width 0.1)
				(type default)
			)
			(layer "F.Fab")
		)
		(fp_line
			(start -1.1049 0.724916)
			(end 1.1049 0.724916)
			(stroke
				(width 0.1)
				(type default)
			)
			(layer "F.Fab")
		)
		(fp_line
			(start 1.1049 -0.724916)
			(end -1.1049 -0.724916)
			(stroke
				(width 0.1)
				(type default)
			)
			(layer "F.Fab")
		)
		(fp_line
			(start 1.1049 0.724916)
			(end 1.1049 -0.724916)
			(stroke
				(width 0.1)
				(type default)
			)
			(layer "F.Fab")
		)
		(pad "1" smd rect
			(at -0.889 0 180)
			(size 1.016 1.27)
			(layers "F.Cu" "F.Mask" "F.Paste")
			(net "P0V9_CPU1_RT0_2A")
		)
		(pad "2" smd rect
			(at 0.889 0 180)
			(size 1.016 1.27)
			(layers "F.Cu" "F.Mask" "F.Paste")
			(net "GND")
		)
	)
	(footprint ""
		(layer "F.Cu")
		(at 186.055 -137.668 90)
		(property "Reference" "R8032"
			(at 0 0 90)
			(layer "F.SilkS")
			(hide yes)
			(effects
				(font
					(size 1.27 1.27)
				)
			)
		)
		(property "Value" ""
			(at 0 0 90)
			(layer "F.Fab")
			(effects
				(font
					(size 1.27 1.27)
				)
			)
		)
		(duplicate_pad_numbers_are_jumpers no)
		(fp_line
			(start 0.7874 -0.4064)
			(end 0.7874 0.4064)
			(stroke
				(width 0.1524)
				(type default)
			)
			(layer "F.SilkS")
		)
		(fp_line
			(start -0.7874 -0.4064)
			(end 0.7874 -0.4064)
			(stroke
				(width 0.1524)
				(type default)
			)
			(layer "F.SilkS")
		)
		(fp_line
			(start 0.7874 0.4064)
			(end -0.7874 0.4064)
			(stroke
				(width 0.1524)
				(type default)
			)
			(layer "F.SilkS")
		)
		(fp_line
			(start -0.7874 0.4064)
			(end -0.7874 -0.4064)
			(stroke
				(width 0.1524)
				(type default)
			)
			(layer "F.SilkS")
		)
		(fp_line
			(start -0.12065 -0.305054)
			(end -0.12065 -0.2794)
			(stroke
				(width 0.1)
				(type default)
			)
			(layer "F.Fab")
		)
		(fp_line
			(start -0.67945 -0.305054)
			(end -0.12065 -0.305054)
			(stroke
				(width 0.1)
				(type default)
			)
			(layer "F.Fab")
		)
		(fp_line
			(start 0.67945 -0.3048)
			(end 0.67945 0.3048)
			(stroke
				(width 0.1)
				(type default)
			)
			(layer "F.Fab")
		)
		(fp_line
			(start 0.12065 -0.3048)
			(end 0.67945 -0.3048)
			(stroke
				(width 0.1)
				(type default)
			)
			(layer "F.Fab")
		)
		(fp_line
			(start 0.12065 -0.2794)
			(end 0.12065 -0.3048)
			(stroke
				(width 0.1)
				(type default)
			)
			(layer "F.Fab")
		)
		(fp_line
			(start -0.12065 -0.2794)
			(end 0.12065 -0.2794)
			(stroke
				(width 0.1)
				(type default)
			)
			(layer "F.Fab")
		)
		(fp_line
			(start 0.120396 0.2794)
			(end -0.12065 0.2794)
			(stroke
				(width 0.1)
				(type default)
			)
			(layer "F.Fab")
		)
		(fp_line
			(start -0.12065 0.2794)
			(end -0.12065 0.3048)
			(stroke
				(width 0.1)
				(type default)
			)
			(layer "F.Fab")
		)
		(fp_line
			(start 0.67945 0.3048)
			(end 0.120396 0.3048)
			(stroke
				(width 0.1)
				(type default)
			)
			(layer "F.Fab")
		)
		(fp_line
			(start 0.120396 0.3048)
			(end 0.120396 0.2794)
			(stroke
				(width 0.1)
				(type default)
			)
			(layer "F.Fab")
		)
		(fp_line
			(start -0.12065 0.3048)
			(end -0.67945 0.3048)
			(stroke
				(width 0.1)
				(type default)
			)
			(layer "F.Fab")
		)
		(fp_line
			(start -0.67945 0.3048)
			(end -0.67945 -0.305054)
			(stroke
				(width 0.1)
				(type default)
			)
			(layer "F.Fab")
		)
		(pad "1" smd circle
			(at -0.40005 0 90)
			(size 0 0)
			(layers "F.Cu" "F.Mask" "F.Paste")
			(net "FM_ESPI_CPU0_ALERT_SEL")
		)
		(pad "2" smd circle
			(at 0.40005 0 90)
			(size 0 0)
			(layers "F.Cu" "F.Mask" "F.Paste")
			(net "FM_ESPI_CPU0_ALERT_R_SEL")
		)
	)
	(footprint ""
		(layer "F.Cu")
		(at 316.738 -358.267 180)
		(property "Reference" "R8064"
			(at 0 0 180)
			(layer "F.SilkS")
			(hide yes)
			(effects
				(font
					(size 1.27 1.27)
				)
			)
		)
		(property "Value" ""
			(at 0 0 180)
			(layer "F.Fab")
			(effects
				(font
					(size 1.27 1.27)
				)
			)
		)
		(duplicate_pad_numbers_are_jumpers no)
		(fp_line
			(start 0.7874 0.4064)
			(end -0.7874 0.4064)
			(stroke
				(width 0.1524)
				(type default)
			)
			(layer "F.SilkS")
		)
		(fp_line
			(start 0.7874 -0.4064)
			(end 0.7874 0.4064)
			(stroke
				(width 0.1524)
				(type default)
			)
			(layer "F.SilkS")
		)
		(fp_line
			(start -0.7874 0.4064)
			(end -0.7874 -0.4064)
			(stroke
				(width 0.1524)
				(type default)
			)
			(layer "F.SilkS")
		)
		(fp_line
			(start -0.7874 -0.4064)
			(end 0.7874 -0.4064)
			(stroke
				(width 0.1524)
				(type default)
			)
			(layer "F.SilkS")
		)
		(fp_line
			(start 0.67945 0.3048)
			(end 0.120396 0.3048)
			(stroke
				(width 0.1)
				(type default)
			)
			(layer "F.Fab")
		)
		(fp_line
			(start 0.67945 -0.3048)
			(end 0.67945 0.3048)
			(stroke
				(width 0.1)
				(type default)
			)
			(layer "F.Fab")
		)
		(fp_line
			(start 0.12065 -0.2794)
			(end 0.12065 -0.3048)
			(stroke
				(width 0.1)
				(type default)
			)
			(layer "F.Fab")
		)
		(fp_line
			(start 0.12065 -0.3048)
			(end 0.67945 -0.3048)
			(stroke
				(width 0.1)
				(type default)
			)
			(layer "F.Fab")
		)
		(fp_line
			(start 0.120396 0.3048)
			(end 0.120396 0.2794)
			(stroke
				(width 0.1)
				(type default)
			)
			(layer "F.Fab")
		)
		(fp_line
			(start 0.120396 0.2794)
			(end -0.12065 0.2794)
			(stroke
				(width 0.1)
				(type default)
			)
			(layer "F.Fab")
		)
		(fp_line
			(start -0.12065 0.3048)
			(end -0.67945 0.3048)
			(stroke
				(width 0.1)
				(type default)
			)
			(layer "F.Fab")
		)
		(fp_line
			(start -0.12065 0.2794)
			(end -0.12065 0.3048)
			(stroke
				(width 0.1)
				(type default)
			)
			(layer "F.Fab")
		)
		(fp_line
			(start -0.12065 -0.2794)
			(end 0.12065 -0.2794)
			(stroke
				(width 0.1)
				(type default)
			)
			(layer "F.Fab")
		)
		(fp_line
			(start -0.12065 -0.305054)
			(end -0.12065 -0.2794)
			(stroke
				(width 0.1)
				(type default)
			)
			(layer "F.Fab")
		)
		(fp_line
			(start -0.67945 0.3048)
			(end -0.67945 -0.305054)
			(stroke
				(width 0.1)
				(type default)
			)
			(layer "F.Fab")
		)
		(fp_line
			(start -0.67945 -0.305054)
			(end -0.12065 -0.305054)
			(stroke
				(width 0.1)
				(type default)
			)
			(layer "F.Fab")
		)
		(pad "1" smd circle
			(at -0.40005 0 180)
			(size 0 0)
			(layers "F.Cu" "F.Mask" "F.Paste")
			(net "PVDDCR_CPU1_P0_OCP_N")
		)
		(pad "2" smd circle
			(at 0.40005 0 180)
			(size 0 0)
			(layers "F.Cu" "F.Mask" "F.Paste")
			(net "PVDDCR_CPU1_P0_OCP_N_R")
		)
	)
	(footprint ""
		(layer "F.Cu")
		(at 328.367644 -138.893042 -90)
		(property "Reference" "PR434"
			(at 0 0 270)
			(layer "F.SilkS")
			(hide yes)
			(effects
				(font
					(size 1.27 1.27)
				)
			)
		)
		(property "Value" ""
			(at 0 0 270)
			(layer "F.Fab")
			(effects
				(font
					(size 1.27 1.27)
				)
			)
		)
		(duplicate_pad_numbers_are_jumpers no)
		(fp_line
			(start -0.7874 0.4064)
			(end -0.7874 -0.4064)
			(stroke
				(width 0.1524)
				(type default)
			)
			(layer "F.SilkS")
		)
		(fp_line
			(start 0.7874 0.4064)
			(end -0.7874 0.4064)
			(stroke
				(width 0.1524)
				(type default)
			)
			(layer "F.SilkS")
		)
		(fp_line
			(start -0.7874 -0.4064)
			(end 0.7874 -0.4064)
			(stroke
				(width 0.1524)
				(type default)
			)
			(layer "F.SilkS")
		)
		(fp_line
			(start 0.7874 -0.4064)
			(end 0.7874 0.4064)
			(stroke
				(width 0.1524)
				(type default)
			)
			(layer "F.SilkS")
		)
		(fp_line
			(start -0.67945 0.3048)
			(end -0.67945 -0.305054)
			(stroke
				(width 0.1)
				(type default)
			)
			(layer "F.Fab")
		)
		(fp_line
			(start -0.12065 0.3048)
			(end -0.67945 0.3048)
			(stroke
				(width 0.1)
				(type default)
			)
			(layer "F.Fab")
		)
		(fp_line
			(start 0.120396 0.3048)
			(end 0.120396 0.2794)
			(stroke
				(width 0.1)
				(type default)
			)
			(layer "F.Fab")
		)
		(fp_line
			(start 0.67945 0.3048)
			(end 0.120396 0.3048)
			(stroke
				(width 0.1)
				(type default)
			)
			(layer "F.Fab")
		)
		(fp_line
			(start -0.12065 0.2794)
			(end -0.12065 0.3048)
			(stroke
				(width 0.1)
				(type default)
			)
			(layer "F.Fab")
		)
		(fp_line
			(start 0.120396 0.2794)
			(end -0.12065 0.2794)
			(stroke
				(width 0.1)
				(type default)
			)
			(layer "F.Fab")
		)
		(fp_line
			(start -0.12065 -0.2794)
			(end 0.12065 -0.2794)
			(stroke
				(width 0.1)
				(type default)
			)
			(layer "F.Fab")
		)
		(fp_line
			(start 0.12065 -0.2794)
			(end 0.12065 -0.3048)
			(stroke
				(width 0.1)
				(type default)
			)
			(layer "F.Fab")
		)
		(fp_line
			(start 0.12065 -0.3048)
			(end 0.67945 -0.3048)
			(stroke
				(width 0.1)
				(type default)
			)
			(layer "F.Fab")
		)
		(fp_line
			(start 0.67945 -0.3048)
			(end 0.67945 0.3048)
			(stroke
				(width 0.1)
				(type default)
			)
			(layer "F.Fab")
		)
		(fp_line
			(start -0.67945 -0.305054)
			(end -0.12065 -0.305054)
			(stroke
				(width 0.1)
				(type default)
			)
			(layer "F.Fab")
		)
		(fp_line
			(start -0.12065 -0.305054)
			(end -0.12065 -0.2794)
			(stroke
				(width 0.1)
				(type default)
			)
			(layer "F.Fab")
		)
		(pad "1" smd circle
			(at -0.40005 0 270)
			(size 0 0)
			(layers "F.Cu" "F.Mask" "F.Paste")
			(net "PVDD18_S5_P0_FB_RC")
		)
		(pad "2" smd circle
			(at 0.40005 0 270)
			(size 0 0)
			(layers "F.Cu" "F.Mask" "F.Paste")
			(net "VSENSE_PVDD18_S5_P0_DP")
		)
	)
	(footprint ""
		(layer "F.Cu")
		(at 458.346302 -407.877264)
		(property "Reference" "PC6582_2"
			(at 0 0 0)
			(layer "F.SilkS")
			(hide yes)
			(effects
				(font
					(size 1.27 1.27)
				)
			)
		)
		(property "Value" ""
			(at 0 0 0)
			(layer "F.Fab")
			(effects
				(font
					(size 1.27 1.27)
				)
			)
		)
		(duplicate_pad_numbers_are_jumpers no)
		(fp_line
			(start -1.524 -0.762)
			(end 1.524 -0.762)
			(stroke
				(width 0.1524)
				(type default)
			)
			(layer "F.SilkS")
		)
		(fp_line
			(start -1.524 0.762)
			(end -1.524 -0.762)
			(stroke
				(width 0.1524)
				(type default)
			)
			(layer "F.SilkS")
		)
		(fp_line
			(start 1.524 -0.762)
			(end 1.524 0.762)
			(stroke
				(width 0.1524)
				(type default)
			)
			(layer "F.SilkS")
		)
		(fp_line
			(start 1.524 0.762)
			(end -1.524 0.762)
			(stroke
				(width 0.1524)
				(type default)
			)
			(layer "F.SilkS")
		)
		(fp_line
			(start -1.1049 -0.724916)
			(end -1.1049 0.724916)
			(stroke
				(width 0.1)
				(type default)
			)
			(layer "F.Fab")
		)
		(fp_line
			(start -1.1049 0.724916)
			(end 1.1049 0.724916)
			(stroke
				(width 0.1)
				(type default)
			)
			(layer "F.Fab")
		)
		(fp_line
			(start 1.1049 -0.724916)
			(end -1.1049 -0.724916)
			(stroke
				(width 0.1)
				(type default)
			)
			(layer "F.Fab")
		)
		(fp_line
			(start 1.1049 0.724916)
			(end 1.1049 -0.724916)
			(stroke
				(width 0.1)
				(type default)
			)
			(layer "F.Fab")
		)
		(pad "1" smd rect
			(at -0.889 0 180)
			(size 1.016 1.27)
			(layers "F.Cu" "F.Mask" "F.Paste")
			(net "SW_P12V_AUX_P0V9_RETIMER_CPU0_FLT")
		)
		(pad "2" smd rect
			(at 0.889 0 180)
			(size 1.016 1.27)
			(layers "F.Cu" "F.Mask" "F.Paste")
			(net "GND")
		)
	)
	(footprint ""
		(layer "F.Cu")
		(at 7.899908 -51.999896)
		(property "Reference" "J7"
			(at -1.016 -3.495548 0)
			(unlocked yes)
			(layer "F.SilkS")
			(effects
				(font
					(size 0.7874 0.5842)
					(thickness 0.1524)
				)
			)
		)
		(property "Value" ""
			(at 0 0 0)
			(layer "F.Fab")
			(effects
				(font
					(size 1.27 1.27)
				)
			)
		)
		(duplicate_pad_numbers_are_jumpers no)
		(fp_line
			(start -1.700022 -2.739898)
			(end 1.700022 -2.739898)
			(stroke
				(width 0.1524)
				(type default)
			)
			(layer "F.SilkS")
		)
		(fp_line
			(start -1.700022 -2.4257)
			(end -1.700022 -2.739898)
			(stroke
				(width 0.1524)
				(type default)
			)
			(layer "F.SilkS")
		)
		(fp_line
			(start -1.700022 -1.1557)
			(end -1.700022 -1.3843)
			(stroke
				(width 0.1524)
				(type default)
			)
			(layer "F.SilkS")
		)
		(fp_line
			(start -1.700022 0.1143)
			(end -1.700022 -0.1143)
			(stroke
				(width 0.1524)
				(type default)
			)
			(layer "F.SilkS")
		)
		(fp_line
			(start -1.700022 1.3843)
			(end -1.700022 1.1557)
			(stroke
				(width 0.1524)
				(type default)
			)
			(layer "F.SilkS")
		)
		(fp_line
			(start -1.700022 2.739898)
			(end -1.700022 2.4257)
			(stroke
				(width 0.1524)
				(type default)
			)
			(layer "F.SilkS")
		)
		(fp_line
			(start 1.700022 -2.739898)
			(end 1.700022 -2.4257)
			(stroke
				(width 0.1524)
				(type default)
			)
			(layer "F.SilkS")
		)
		(fp_line
			(start 1.700022 -1.3843)
			(end 1.700022 -1.1557)
			(stroke
				(width 0.1524)
				(type default)
			)
			(layer "F.SilkS")
		)
		(fp_line
			(start 1.700022 -0.1143)
			(end 1.700022 0.1143)
			(stroke
				(width 0.1524)
				(type default)
			)
			(layer "F.SilkS")
		)
		(fp_line
			(start 1.700022 1.1557)
			(end 1.700022 1.3843)
			(stroke
				(width 0.1524)
				(type default)
			)
			(layer "F.SilkS")
		)
		(fp_line
			(start 1.700022 2.4257)
			(end 1.700022 2.739898)
			(stroke
				(width 0.1524)
				(type default)
			)
			(layer "F.SilkS")
		)
		(fp_line
			(start 1.700022 2.739898)
			(end -1.700022 2.739898)
			(stroke
				(width 0.1524)
				(type default)
			)
			(layer "F.SilkS")
		)
		(fp_poly
			(pts
				(xy -3.383534 -1.905) (xy -4.399534 -1.397) (xy -4.399534 -2.413)
			)
			(stroke
				(width 0)
				(type default)
			)
			(fill yes)
			(layer "F.SilkS")
		)
		(fp_line
			(start -1.700022 -2.739898)
			(end 1.700022 -2.739898)
			(stroke
				(width 0.1)
				(type default)
			)
			(layer "F.Fab")
		)
		(fp_line
			(start -1.700022 2.739898)
			(end -1.700022 -2.739898)
			(stroke
				(width 0.1)
				(type default)
			)
			(layer "F.Fab")
		)
		(fp_line
			(start 1.700022 -2.739898)
			(end 1.700022 2.739898)
			(stroke
				(width 0.1)
				(type default)
			)
			(layer "F.Fab")
		)
		(fp_line
			(start 1.700022 2.739898)
			(end -1.700022 2.739898)
			(stroke
				(width 0.1)
				(type default)
			)
			(layer "F.Fab")
		)
		(fp_poly
			(pts
				(xy -4.399534 -2.413) (xy -4.399534 -1.397) (xy -3.383534 -1.905)
			)
			(stroke
				(width 0)
				(type default)
			)
			(fill yes)
			(layer "F.Fab")
		)
		(pad "1" smd rect
			(at -2.050034 -1.905 270)
			(size 0.762 2.413)
			(layers "F.Cu" "F.Mask" "F.Paste")
			(net "CPU1_XTRIG_R1_L4")
		)
		(pad "2" smd rect
			(at 2.050034 -1.905 270)
			(size 0.762 2.413)
			(layers "F.Cu" "F.Mask" "F.Paste")
			(net "GND")
		)
		(pad "3" smd rect
			(at -2.050034 -0.635 270)
			(size 0.762 2.413)
			(layers "F.Cu" "F.Mask" "F.Paste")
			(net "CPU1_XTRIG_R1_L5")
		)
		(pad "4" smd rect
			(at 2.050034 -0.635 270)
			(size 0.762 2.413)
			(layers "F.Cu" "F.Mask" "F.Paste")
			(net "GND")
		)
		(pad "5" smd rect
			(at -2.050034 0.635 270)
			(size 0.762 2.413)
			(layers "F.Cu" "F.Mask" "F.Paste")
			(net "CPU1_XTRIG_R1_L6")
		)
		(pad "6" smd rect
			(at 2.050034 0.635 270)
			(size 0.762 2.413)
			(layers "F.Cu" "F.Mask" "F.Paste")
			(net "GND")
		)
		(pad "7" smd rect
			(at -2.050034 1.905 270)
			(size 0.762 2.413)
			(layers "F.Cu" "F.Mask" "F.Paste")
			(net "CPU1_XTRIG_R1_L7")
		)
		(pad "8" smd rect
			(at 2.050034 1.905 270)
			(size 0.762 2.413)
			(layers "F.Cu" "F.Mask" "F.Paste")
			(net "GND")
		)
	)
	(footprint ""
		(layer "F.Cu")
		(at 79.315564 -408.517344 -90)
		(property "Reference" "C6649"
			(at 0 0 270)
			(layer "F.SilkS")
			(hide yes)
			(effects
				(font
					(size 1.27 1.27)
				)
			)
		)
		(property "Value" ""
			(at 0 0 270)
			(layer "F.Fab")
			(effects
				(font
					(size 1.27 1.27)
				)
			)
		)
		(duplicate_pad_numbers_are_jumpers no)
		(fp_line
			(start -0.299974 0.150114)
			(end -0.299974 -0.150114)
			(stroke
				(width 0.1)
				(type default)
			)
			(layer "F.Fab")
		)
		(fp_line
			(start 0.299974 0.150114)
			(end -0.299974 0.150114)
			(stroke
				(width 0.1)
				(type default)
			)
			(layer "F.Fab")
		)
		(fp_line
			(start -0.299974 -0.150114)
			(end 0.299974 -0.150114)
			(stroke
				(width 0.1)
				(type default)
			)
			(layer "F.Fab")
		)
		(fp_line
			(start 0.299974 -0.150114)
			(end 0.299974 0.150114)
			(stroke
				(width 0.1)
				(type default)
			)
			(layer "F.Fab")
		)
		(pad "1" smd rect
			(at -0.2667 0 270)
			(size 0.3048 0.381)
			(layers "F.Cu" "F.Mask" "F.Paste")
			(net "P5E_CPU1_P0_TX_BUF_C_DP<10>")
		)
		(pad "2" smd rect
			(at 0.2667 0 270)
			(size 0.3048 0.381)
			(layers "F.Cu" "F.Mask" "F.Paste")
			(net "P5E_CPU1_P0_TX_BUF_DP<10>")
		)
	)
	(footprint ""
		(layer "F.Cu")
		(at 253.97841 -45.865542 90)
		(property "Reference" "PR3970"
			(at 0 0 90)
			(layer "F.SilkS")
			(hide yes)
			(effects
				(font
					(size 1.27 1.27)
				)
			)
		)
		(property "Value" ""
			(at 0 0 90)
			(layer "F.Fab")
			(effects
				(font
					(size 1.27 1.27)
				)
			)
		)
		(duplicate_pad_numbers_are_jumpers no)
		(fp_line
			(start 0.7874 -0.4064)
			(end 0.7874 0.4064)
			(stroke
				(width 0.1524)
				(type default)
			)
			(layer "F.SilkS")
		)
		(fp_line
			(start -0.7874 -0.4064)
			(end 0.7874 -0.4064)
			(stroke
				(width 0.1524)
				(type default)
			)
			(layer "F.SilkS")
		)
		(fp_line
			(start 0.7874 0.4064)
			(end -0.7874 0.4064)
			(stroke
				(width 0.1524)
				(type default)
			)
			(layer "F.SilkS")
		)
		(fp_line
			(start -0.7874 0.4064)
			(end -0.7874 -0.4064)
			(stroke
				(width 0.1524)
				(type default)
			)
			(layer "F.SilkS")
		)
		(fp_line
			(start -0.12065 -0.305054)
			(end -0.12065 -0.2794)
			(stroke
				(width 0.1)
				(type default)
			)
			(layer "F.Fab")
		)
		(fp_line
			(start -0.67945 -0.305054)
			(end -0.12065 -0.305054)
			(stroke
				(width 0.1)
				(type default)
			)
			(layer "F.Fab")
		)
		(fp_line
			(start 0.67945 -0.3048)
			(end 0.67945 0.3048)
			(stroke
				(width 0.1)
				(type default)
			)
			(layer "F.Fab")
		)
		(fp_line
			(start 0.12065 -0.3048)
			(end 0.67945 -0.3048)
			(stroke
				(width 0.1)
				(type default)
			)
			(layer "F.Fab")
		)
		(fp_line
			(start 0.12065 -0.2794)
			(end 0.12065 -0.3048)
			(stroke
				(width 0.1)
				(type default)
			)
			(layer "F.Fab")
		)
		(fp_line
			(start -0.12065 -0.2794)
			(end 0.12065 -0.2794)
			(stroke
				(width 0.1)
				(type default)
			)
			(layer "F.Fab")
		)
		(fp_line
			(start 0.120396 0.2794)
			(end -0.12065 0.2794)
			(stroke
				(width 0.1)
				(type default)
			)
			(layer "F.Fab")
		)
		(fp_line
			(start -0.12065 0.2794)
			(end -0.12065 0.3048)
			(stroke
				(width 0.1)
				(type default)
			)
			(layer "F.Fab")
		)
		(fp_line
			(start 0.67945 0.3048)
			(end 0.120396 0.3048)
			(stroke
				(width 0.1)
				(type default)
			)
			(layer "F.Fab")
		)
		(fp_line
			(start 0.120396 0.3048)
			(end 0.120396 0.2794)
			(stroke
				(width 0.1)
				(type default)
			)
			(layer "F.Fab")
		)
		(fp_line
			(start -0.12065 0.3048)
			(end -0.67945 0.3048)
			(stroke
				(width 0.1)
				(type default)
			)
			(layer "F.Fab")
		)
		(fp_line
			(start -0.67945 0.3048)
			(end -0.67945 -0.305054)
			(stroke
				(width 0.1)
				(type default)
			)
			(layer "F.Fab")
		)
		(pad "1" smd circle
			(at -0.40005 0 90)
			(size 0 0)
			(layers "F.Cu" "F.Mask" "F.Paste")
			(net "P12V_E1S_SENSE_0")
		)
		(pad "2" smd circle
			(at 0.40005 0 90)
			(size 0 0)
			(layers "F.Cu" "F.Mask" "F.Paste")
			(net "GND")
		)
	)
	(footprint ""
		(layer "F.Cu")
		(at 448.672458 -93.509592 180)
		(property "Reference" "R3617"
			(at 0 0 180)
			(layer "F.SilkS")
			(hide yes)
			(effects
				(font
					(size 1.27 1.27)
				)
			)
		)
		(property "Value" ""
			(at 0 0 180)
			(layer "F.Fab")
			(effects
				(font
					(size 1.27 1.27)
				)
			)
		)
		(duplicate_pad_numbers_are_jumpers no)
		(fp_line
			(start 0.7874 0.4064)
			(end -0.7874 0.4064)
			(stroke
				(width 0.1524)
				(type default)
			)
			(layer "F.SilkS")
		)
		(fp_line
			(start 0.7874 -0.4064)
			(end 0.7874 0.4064)
			(stroke
				(width 0.1524)
				(type default)
			)
			(layer "F.SilkS")
		)
		(fp_line
			(start -0.7874 0.4064)
			(end -0.7874 -0.4064)
			(stroke
				(width 0.1524)
				(type default)
			)
			(layer "F.SilkS")
		)
		(fp_line
			(start -0.7874 -0.4064)
			(end 0.7874 -0.4064)
			(stroke
				(width 0.1524)
				(type default)
			)
			(layer "F.SilkS")
		)
		(fp_line
			(start 0.67945 0.3048)
			(end 0.120396 0.3048)
			(stroke
				(width 0.1)
				(type default)
			)
			(layer "F.Fab")
		)
		(fp_line
			(start 0.67945 -0.3048)
			(end 0.67945 0.3048)
			(stroke
				(width 0.1)
				(type default)
			)
			(layer "F.Fab")
		)
		(fp_line
			(start 0.12065 -0.2794)
			(end 0.12065 -0.3048)
			(stroke
				(width 0.1)
				(type default)
			)
			(layer "F.Fab")
		)
		(fp_line
			(start 0.12065 -0.3048)
			(end 0.67945 -0.3048)
			(stroke
				(width 0.1)
				(type default)
			)
			(layer "F.Fab")
		)
		(fp_line
			(start 0.120396 0.3048)
			(end 0.120396 0.2794)
			(stroke
				(width 0.1)
				(type default)
			)
			(layer "F.Fab")
		)
		(fp_line
			(start 0.120396 0.2794)
			(end -0.12065 0.2794)
			(stroke
				(width 0.1)
				(type default)
			)
			(layer "F.Fab")
		)
		(fp_line
			(start -0.12065 0.3048)
			(end -0.67945 0.3048)
			(stroke
				(width 0.1)
				(type default)
			)
			(layer "F.Fab")
		)
		(fp_line
			(start -0.12065 0.2794)
			(end -0.12065 0.3048)
			(stroke
				(width 0.1)
				(type default)
			)
			(layer "F.Fab")
		)
		(fp_line
			(start -0.12065 -0.2794)
			(end 0.12065 -0.2794)
			(stroke
				(width 0.1)
				(type default)
			)
			(layer "F.Fab")
		)
		(fp_line
			(start -0.12065 -0.305054)
			(end -0.12065 -0.2794)
			(stroke
				(width 0.1)
				(type default)
			)
			(layer "F.Fab")
		)
		(fp_line
			(start -0.67945 0.3048)
			(end -0.67945 -0.305054)
			(stroke
				(width 0.1)
				(type default)
			)
			(layer "F.Fab")
		)
		(fp_line
			(start -0.67945 -0.305054)
			(end -0.12065 -0.305054)
			(stroke
				(width 0.1)
				(type default)
			)
			(layer "F.Fab")
		)
		(pad "1" smd circle
			(at -0.40005 0 180)
			(size 0 0)
			(layers "F.Cu" "F.Mask" "F.Paste")
			(net "GND")
		)
		(pad "2" smd circle
			(at 0.40005 0 180)
			(size 0 0)
			(layers "F.Cu" "F.Mask" "F.Paste")
			(net "INA230_1_A0")
		)
	)
	(footprint ""
		(layer "F.Cu")
		(at 102.268782 -376.982228)
		(property "Reference" "C713"
			(at 0 0 0)
			(layer "F.SilkS")
			(hide yes)
			(effects
				(font
					(size 1.27 1.27)
				)
			)
		)
		(property "Value" ""
			(at 0 0 0)
			(layer "F.Fab")
			(effects
				(font
					(size 1.27 1.27)
				)
			)
		)
		(duplicate_pad_numbers_are_jumpers no)
		(fp_line
			(start -0.299974 -0.150114)
			(end 0.299974 -0.150114)
			(stroke
				(width 0.1)
				(type default)
			)
			(layer "F.Fab")
		)
		(fp_line
			(start -0.299974 0.150114)
			(end -0.299974 -0.150114)
			(stroke
				(width 0.1)
				(type default)
			)
			(layer "F.Fab")
		)
		(fp_line
			(start 0.299974 -0.150114)
			(end 0.299974 0.150114)
			(stroke
				(width 0.1)
				(type default)
			)
			(layer "F.Fab")
		)
		(fp_line
			(start 0.299974 0.150114)
			(end -0.299974 0.150114)
			(stroke
				(width 0.1)
				(type default)
			)
			(layer "F.Fab")
		)
		(pad "1" smd rect
			(at -0.2667 0)
			(size 0.3048 0.381)
			(layers "F.Cu" "F.Mask" "F.Paste")
			(net "P5E_CPU1_P1_TX_C_DP<14>")
		)
		(pad "2" smd rect
			(at 0.2667 0)
			(size 0.3048 0.381)
			(layers "F.Cu" "F.Mask" "F.Paste")
			(net "P5E_CPU1_P1_TX_DP<14>")
		)
	)
	(footprint ""
		(layer "F.Cu")
		(at 178.221894 -353.966272 90)
		(property "Reference" "PR394"
			(at 0 0 90)
			(layer "F.SilkS")
			(hide yes)
			(effects
				(font
					(size 1.27 1.27)
				)
			)
		)
		(property "Value" ""
			(at 0 0 90)
			(layer "F.Fab")
			(effects
				(font
					(size 1.27 1.27)
				)
			)
		)
		(duplicate_pad_numbers_are_jumpers no)
		(fp_line
			(start 0.7874 -0.4064)
			(end 0.7874 0.4064)
			(stroke
				(width 0.1524)
				(type default)
			)
			(layer "F.SilkS")
		)
		(fp_line
			(start -0.7874 -0.4064)
			(end 0.7874 -0.4064)
			(stroke
				(width 0.1524)
				(type default)
			)
			(layer "F.SilkS")
		)
		(fp_line
			(start 0.7874 0.4064)
			(end -0.7874 0.4064)
			(stroke
				(width 0.1524)
				(type default)
			)
			(layer "F.SilkS")
		)
		(fp_line
			(start -0.7874 0.4064)
			(end -0.7874 -0.4064)
			(stroke
				(width 0.1524)
				(type default)
			)
			(layer "F.SilkS")
		)
		(fp_line
			(start -0.12065 -0.305054)
			(end -0.12065 -0.2794)
			(stroke
				(width 0.1)
				(type default)
			)
			(layer "F.Fab")
		)
		(fp_line
			(start -0.67945 -0.305054)
			(end -0.12065 -0.305054)
			(stroke
				(width 0.1)
				(type default)
			)
			(layer "F.Fab")
		)
		(fp_line
			(start 0.67945 -0.3048)
			(end 0.67945 0.3048)
			(stroke
				(width 0.1)
				(type default)
			)
			(layer "F.Fab")
		)
		(fp_line
			(start 0.12065 -0.3048)
			(end 0.67945 -0.3048)
			(stroke
				(width 0.1)
				(type default)
			)
			(layer "F.Fab")
		)
		(fp_line
			(start 0.12065 -0.2794)
			(end 0.12065 -0.3048)
			(stroke
				(width 0.1)
				(type default)
			)
			(layer "F.Fab")
		)
		(fp_line
			(start -0.12065 -0.2794)
			(end 0.12065 -0.2794)
			(stroke
				(width 0.1)
				(type default)
			)
			(layer "F.Fab")
		)
		(fp_line
			(start 0.120396 0.2794)
			(end -0.12065 0.2794)
			(stroke
				(width 0.1)
				(type default)
			)
			(layer "F.Fab")
		)
		(fp_line
			(start -0.12065 0.2794)
			(end -0.12065 0.3048)
			(stroke
				(width 0.1)
				(type default)
			)
			(layer "F.Fab")
		)
		(fp_line
			(start 0.67945 0.3048)
			(end 0.120396 0.3048)
			(stroke
				(width 0.1)
				(type default)
			)
			(layer "F.Fab")
		)
		(fp_line
			(start 0.120396 0.3048)
			(end 0.120396 0.2794)
			(stroke
				(width 0.1)
				(type default)
			)
			(layer "F.Fab")
		)
		(fp_line
			(start -0.12065 0.3048)
			(end -0.67945 0.3048)
			(stroke
				(width 0.1)
				(type default)
			)
			(layer "F.Fab")
		)
		(fp_line
			(start -0.67945 0.3048)
			(end -0.67945 -0.305054)
			(stroke
				(width 0.1)
				(type default)
			)
			(layer "F.Fab")
		)
		(pad "1" smd circle
			(at -0.40005 0 90)
			(size 0 0)
			(layers "F.Cu" "F.Mask" "F.Paste")
			(net "PVDD11_S3_P1_PVCC")
		)
		(pad "2" smd circle
			(at 0.40005 0 90)
			(size 0 0)
			(layers "F.Cu" "F.Mask" "F.Paste")
			(net "P3V3_AUX")
		)
	)
	(footprint ""
		(layer "F.Cu")
		(at 27.487626 -427.612302 180)
		(property "Reference" "R6159"
			(at 0 0 180)
			(layer "F.SilkS")
			(hide yes)
			(effects
				(font
					(size 1.27 1.27)
				)
			)
		)
		(property "Value" ""
			(at 0 0 180)
			(layer "F.Fab")
			(effects
				(font
					(size 1.27 1.27)
				)
			)
		)
		(duplicate_pad_numbers_are_jumpers no)
		(fp_line
			(start 0.32512 0.175006)
			(end -0.32512 0.175006)
			(stroke
				(width 0.1)
				(type default)
			)
			(layer "F.Fab")
		)
		(fp_line
			(start 0.32512 -0.175006)
			(end 0.32512 0.175006)
			(stroke
				(width 0.1)
				(type default)
			)
			(layer "F.Fab")
		)
		(fp_line
			(start -0.32512 0.175006)
			(end -0.32512 -0.175006)
			(stroke
				(width 0.1)
				(type default)
			)
			(layer "F.Fab")
		)
		(fp_line
			(start -0.32512 -0.175006)
			(end 0.32512 -0.175006)
			(stroke
				(width 0.1)
				(type default)
			)
			(layer "F.Fab")
		)
		(pad "1" smd rect
			(at -0.2667 0 180)
			(size 0.3048 0.381)
			(layers "F.Cu" "F.Mask" "F.Paste")
			(net "P2E_MB_BMC_RX_DN<0>")
		)
		(pad "2" smd rect
			(at 0.2667 0)
			(size 0.3048 0.381)
			(layers "F.Cu" "F.Mask" "F.Paste")
			(net "P2E_MB_BMC_RX_R2_DN<0>")
		)
	)
	(footprint ""
		(layer "F.Cu")
		(at 277.591774 -414.00603)
		(property "Reference" "R6782"
			(at 0 0 0)
			(layer "F.SilkS")
			(hide yes)
			(effects
				(font
					(size 1.27 1.27)
				)
			)
		)
		(property "Value" ""
			(at 0 0 0)
			(layer "F.Fab")
			(effects
				(font
					(size 1.27 1.27)
				)
			)
		)
		(duplicate_pad_numbers_are_jumpers no)
		(fp_line
			(start -0.7874 -0.4064)
			(end 0.7874 -0.4064)
			(stroke
				(width 0.1524)
				(type default)
			)
			(layer "F.SilkS")
		)
		(fp_line
			(start -0.7874 0.4064)
			(end -0.7874 -0.4064)
			(stroke
				(width 0.1524)
				(type default)
			)
			(layer "F.SilkS")
		)
		(fp_line
			(start 0.7874 -0.4064)
			(end 0.7874 0.4064)
			(stroke
				(width 0.1524)
				(type default)
			)
			(layer "F.SilkS")
		)
		(fp_line
			(start 0.7874 0.4064)
			(end -0.7874 0.4064)
			(stroke
				(width 0.1524)
				(type default)
			)
			(layer "F.SilkS")
		)
		(fp_line
			(start -0.67945 -0.305054)
			(end -0.12065 -0.305054)
			(stroke
				(width 0.1)
				(type default)
			)
			(layer "F.Fab")
		)
		(fp_line
			(start -0.67945 0.3048)
			(end -0.67945 -0.305054)
			(stroke
				(width 0.1)
				(type default)
			)
			(layer "F.Fab")
		)
		(fp_line
			(start -0.12065 -0.305054)
			(end -0.12065 -0.2794)
			(stroke
				(width 0.1)
				(type default)
			)
			(layer "F.Fab")
		)
		(fp_line
			(start -0.12065 -0.2794)
			(end 0.12065 -0.2794)
			(stroke
				(width 0.1)
				(type default)
			)
			(layer "F.Fab")
		)
		(fp_line
			(start -0.12065 0.2794)
			(end -0.12065 0.3048)
			(stroke
				(width 0.1)
				(type default)
			)
			(layer "F.Fab")
		)
		(fp_line
			(start -0.12065 0.3048)
			(end -0.67945 0.3048)
			(stroke
				(width 0.1)
				(type default)
			)
			(layer "F.Fab")
		)
		(fp_line
			(start 0.120396 0.2794)
			(end -0.12065 0.2794)
			(stroke
				(width 0.1)
				(type default)
			)
			(layer "F.Fab")
		)
		(fp_line
			(start 0.120396 0.3048)
			(end 0.120396 0.2794)
			(stroke
				(width 0.1)
				(type default)
			)
			(layer "F.Fab")
		)
		(fp_line
			(start 0.12065 -0.3048)
			(end 0.67945 -0.3048)
			(stroke
				(width 0.1)
				(type default)
			)
			(layer "F.Fab")
		)
		(fp_line
			(start 0.12065 -0.2794)
			(end 0.12065 -0.3048)
			(stroke
				(width 0.1)
				(type default)
			)
			(layer "F.Fab")
		)
		(fp_line
			(start 0.67945 -0.3048)
			(end 0.67945 0.3048)
			(stroke
				(width 0.1)
				(type default)
			)
			(layer "F.Fab")
		)
		(fp_line
			(start 0.67945 0.3048)
			(end 0.120396 0.3048)
			(stroke
				(width 0.1)
				(type default)
			)
			(layer "F.Fab")
		)
		(pad "1" smd circle
			(at -0.40005 0)
			(size 0 0)
			(layers "F.Cu" "F.Mask" "F.Paste")
			(net "SMB_MUX_RT_ROM_R1_SCL")
		)
		(pad "2" smd circle
			(at 0.40005 0)
			(size 0 0)
			(layers "F.Cu" "F.Mask" "F.Paste")
			(net "SMB_HOST_CLK_3V3AUX_SCL_R1")
		)
	)
	(footprint ""
		(layer "F.Cu")
		(at 374.131586 -426.567854 -90)
		(property "Reference" "U46"
			(at -3.060192 -0.117602 0)
			(unlocked yes)
			(layer "F.SilkS")
			(effects
				(font
					(size 0.7874 0.5842)
					(thickness 0.1524)
				)
			)
		)
		(property "Value" ""
			(at 0 0 270)
			(layer "F.Fab")
			(effects
				(font
					(size 1.27 1.27)
				)
			)
		)
		(duplicate_pad_numbers_are_jumpers no)
		(fp_line
			(start -1.03378 1.284478)
			(end -1.03378 -1.284478)
			(stroke
				(width 0.1524)
				(type default)
			)
			(layer "F.SilkS")
		)
		(fp_line
			(start 1.03378 1.284478)
			(end -1.03378 1.284478)
			(stroke
				(width 0.1524)
				(type default)
			)
			(layer "F.SilkS")
		)
		(fp_line
			(start -1.03378 -1.284478)
			(end 1.03378 -1.284478)
			(stroke
				(width 0.1524)
				(type default)
			)
			(layer "F.SilkS")
		)
		(fp_line
			(start 1.03378 -1.284478)
			(end 1.03378 1.284478)
			(stroke
				(width 0.1524)
				(type default)
			)
			(layer "F.SilkS")
		)
		(fp_poly
			(pts
				(xy -1.201674 -0.750062) (xy -1.806702 -0.447548) (xy -1.806702 -1.052576)
			)
			(stroke
				(width 0)
				(type default)
			)
			(fill yes)
			(layer "F.SilkS")
		)
		(fp_line
			(start -0.774954 1.02489)
			(end -0.774954 -1.02489)
			(stroke
				(width 0.1)
				(type default)
			)
			(layer "F.Fab")
		)
		(fp_line
			(start 0.774954 1.02489)
			(end -0.774954 1.02489)
			(stroke
				(width 0.1)
				(type default)
			)
			(layer "F.Fab")
		)
		(fp_line
			(start -0.774954 -1.02489)
			(end 0.774954 -1.02489)
			(stroke
				(width 0.1)
				(type default)
			)
			(layer "F.Fab")
		)
		(fp_line
			(start 0.774954 -1.02489)
			(end 0.774954 1.02489)
			(stroke
				(width 0.1)
				(type default)
			)
			(layer "F.Fab")
		)
		(fp_poly
			(pts
				(xy -1.201674 -0.750062) (xy -1.806702 -0.447548) (xy -1.806702 -1.052576)
			)
			(stroke
				(width 0)
				(type default)
			)
			(fill yes)
			(layer "F.Fab")
		)
		(pad "1" smd rect
			(at -0.64008 -0.750062)
			(size 0.3048 0.5334)
			(layers "F.Cu" "F.Mask" "F.Paste")
			(net "SMB_RT_CPU0_P3_ROM_MUX_1D_SCL")
		)
		(pad "2" smd rect
			(at -0.64008 -0.249936)
			(size 0.254 0.5334)
			(layers "F.Cu" "F.Mask" "F.Paste")
			(net "SMB_RT_CPU0_P3_ROM_MUX_1D_SDA")
		)
		(pad "3" smd rect
			(at -0.64008 0.249936)
			(size 0.254 0.5334)
			(layers "F.Cu" "F.Mask" "F.Paste")
			(net "SMB_RT_CPU0_P3_ROM_MUX_2D_SCL")
		)
		(pad "4" smd rect
			(at -0.64008 0.750062)
			(size 0.3048 0.5334)
			(layers "F.Cu" "F.Mask" "F.Paste")
			(net "SMB_RT_CPU0_P3_ROM_MUX_2D_SDA")
		)
		(pad "5" smd rect
			(at 0 0.839978 270)
			(size 0.3302 0.635)
			(layers "F.Cu" "F.Mask" "F.Paste")
			(net "GND")
		)
		(pad "6" smd rect
			(at 0.64008 0.750062)
			(size 0.3048 0.5334)
			(layers "F.Cu" "F.Mask" "F.Paste")
			(net "RT_ROM_MUX7_OE_N")
		)
		(pad "7" smd rect
			(at 0.64008 0.249936)
			(size 0.254 0.5334)
			(layers "F.Cu" "F.Mask" "F.Paste")
			(net "SMB_RT_CPU0_P3_ROM_R_SDA")
		)
		(pad "8" smd rect
			(at 0.64008 -0.249936)
			(size 0.254 0.5334)
			(layers "F.Cu" "F.Mask" "F.Paste")
			(net "SMB_RT_CPU0_P3_ROM_R_SCL")
		)
		(pad "9" smd rect
			(at 0.64008 -0.750062)
			(size 0.3048 0.5334)
			(layers "F.Cu" "F.Mask" "F.Paste")
			(net "FM_SMB_RT_ROM_MUX7_SEL")
		)
		(pad "10" smd rect
			(at 0 -0.839978 270)
			(size 0.3302 0.635)
			(layers "F.Cu" "F.Mask" "F.Paste")
			(net "P3V3_AUX")
		)
	)
	(footprint ""
		(layer "F.Cu")
		(at 368.955066 -424.002962 90)
		(property "Reference" "R4199"
			(at 0 0 90)
			(layer "F.SilkS")
			(hide yes)
			(effects
				(font
					(size 1.27 1.27)
				)
			)
		)
		(property "Value" ""
			(at 0 0 90)
			(layer "F.Fab")
			(effects
				(font
					(size 1.27 1.27)
				)
			)
		)
		(duplicate_pad_numbers_are_jumpers no)
		(fp_line
			(start 0.7874 -0.4064)
			(end 0.7874 0.4064)
			(stroke
				(width 0.1524)
				(type default)
			)
			(layer "F.SilkS")
		)
		(fp_line
			(start -0.7874 -0.4064)
			(end 0.7874 -0.4064)
			(stroke
				(width 0.1524)
				(type default)
			)
			(layer "F.SilkS")
		)
		(fp_line
			(start 0.7874 0.4064)
			(end -0.7874 0.4064)
			(stroke
				(width 0.1524)
				(type default)
			)
			(layer "F.SilkS")
		)
		(fp_line
			(start -0.7874 0.4064)
			(end -0.7874 -0.4064)
			(stroke
				(width 0.1524)
				(type default)
			)
			(layer "F.SilkS")
		)
		(fp_line
			(start -0.12065 -0.305054)
			(end -0.12065 -0.2794)
			(stroke
				(width 0.1)
				(type default)
			)
			(layer "F.Fab")
		)
		(fp_line
			(start -0.67945 -0.305054)
			(end -0.12065 -0.305054)
			(stroke
				(width 0.1)
				(type default)
			)
			(layer "F.Fab")
		)
		(fp_line
			(start 0.67945 -0.3048)
			(end 0.67945 0.3048)
			(stroke
				(width 0.1)
				(type default)
			)
			(layer "F.Fab")
		)
		(fp_line
			(start 0.12065 -0.3048)
			(end 0.67945 -0.3048)
			(stroke
				(width 0.1)
				(type default)
			)
			(layer "F.Fab")
		)
		(fp_line
			(start 0.12065 -0.2794)
			(end 0.12065 -0.3048)
			(stroke
				(width 0.1)
				(type default)
			)
			(layer "F.Fab")
		)
		(fp_line
			(start -0.12065 -0.2794)
			(end 0.12065 -0.2794)
			(stroke
				(width 0.1)
				(type default)
			)
			(layer "F.Fab")
		)
		(fp_line
			(start 0.120396 0.2794)
			(end -0.12065 0.2794)
			(stroke
				(width 0.1)
				(type default)
			)
			(layer "F.Fab")
		)
		(fp_line
			(start -0.12065 0.2794)
			(end -0.12065 0.3048)
			(stroke
				(width 0.1)
				(type default)
			)
			(layer "F.Fab")
		)
		(fp_line
			(start 0.67945 0.3048)
			(end 0.120396 0.3048)
			(stroke
				(width 0.1)
				(type default)
			)
			(layer "F.Fab")
		)
		(fp_line
			(start 0.120396 0.3048)
			(end 0.120396 0.2794)
			(stroke
				(width 0.1)
				(type default)
			)
			(layer "F.Fab")
		)
		(fp_line
			(start -0.12065 0.3048)
			(end -0.67945 0.3048)
			(stroke
				(width 0.1)
				(type default)
			)
			(layer "F.Fab")
		)
		(fp_line
			(start -0.67945 0.3048)
			(end -0.67945 -0.305054)
			(stroke
				(width 0.1)
				(type default)
			)
			(layer "F.Fab")
		)
		(pad "1" smd circle
			(at -0.40005 0 90)
			(size 0 0)
			(layers "F.Cu" "F.Mask" "F.Paste")
			(net "U270_0_ADD1")
		)
		(pad "2" smd circle
			(at 0.40005 0 90)
			(size 0 0)
			(layers "F.Cu" "F.Mask" "F.Paste")
			(net "GND")
		)
	)
	(footprint ""
		(layer "F.Cu")
		(at 83.40725 -141.308836 90)
		(property "Reference" "U40"
			(at 1.051814 -2.801112 90)
			(unlocked yes)
			(layer "F.SilkS")
			(effects
				(font
					(size 0.7874 0.5842)
					(thickness 0.1524)
				)
			)
		)
		(property "Value" ""
			(at 0 0 90)
			(layer "F.Fab")
			(effects
				(font
					(size 1.27 1.27)
				)
			)
		)
		(duplicate_pad_numbers_are_jumpers no)
		(fp_line
			(start 1.7272 -1.1176)
			(end 0.254 -1.1176)
			(stroke
				(width 0.1524)
				(type default)
			)
			(layer "F.SilkS")
		)
		(fp_line
			(start 1.7272 -1.1176)
			(end 1.7272 1.1176)
			(stroke
				(width 0.1524)
				(type default)
			)
			(layer "F.SilkS")
		)
		(fp_line
			(start 0.254 -1.1176)
			(end 0 -0.7366)
			(stroke
				(width 0.1524)
				(type default)
			)
			(layer "F.SilkS")
		)
		(fp_line
			(start -0.254 -1.1176)
			(end -1.7272 -1.1176)
			(stroke
				(width 0.1524)
				(type default)
			)
			(layer "F.SilkS")
		)
		(fp_line
			(start 0 -0.7366)
			(end -0.254 -1.1176)
			(stroke
				(width 0.1524)
				(type default)
			)
			(layer "F.SilkS")
		)
		(fp_line
			(start 1.7272 1.1176)
			(end -1.7272 1.1176)
			(stroke
				(width 0.1524)
				(type default)
			)
			(layer "F.SilkS")
		)
		(fp_line
			(start -1.7272 1.1176)
			(end -1.7272 -1.1176)
			(stroke
				(width 0.1524)
				(type default)
			)
			(layer "F.SilkS")
		)
		(fp_poly
			(pts
				(xy -0.618998 -2.367788) (xy -0.999998 -1.605788) (xy -1.380998 -2.367788)
			)
			(stroke
				(width 0)
				(type default)
			)
			(fill yes)
			(layer "F.SilkS")
		)
		(fp_line
			(start 1.5748 -1.1176)
			(end -1.5748 -1.1176)
			(stroke
				(width 0.1)
				(type default)
			)
			(layer "F.Fab")
		)
		(fp_line
			(start -1.5748 -1.1176)
			(end -1.5748 1.1176)
			(stroke
				(width 0.1)
				(type default)
			)
			(layer "F.Fab")
		)
		(fp_line
			(start 1.5748 1.1176)
			(end 1.5748 -1.1176)
			(stroke
				(width 0.1)
				(type default)
			)
			(layer "F.Fab")
		)
		(fp_line
			(start -1.5748 1.1176)
			(end 1.5748 1.1176)
			(stroke
				(width 0.1)
				(type default)
			)
			(layer "F.Fab")
		)
		(fp_poly
			(pts
				(xy -1.9558 -0.649986) (xy -2.7178 -0.268986) (xy -2.7178 -1.030986)
			)
			(stroke
				(width 0)
				(type default)
			)
			(fill yes)
			(layer "F.Fab")
		)
		(pad "1" smd rect
			(at -0.999998 -0.649986)
			(size 0.3556 1.1176)
			(layers "F.Cu" "F.Mask" "F.Paste")
			(net "PWRGD_CPU1_PWROK")
		)
		(pad "2" smd rect
			(at -0.999998 0)
			(size 0.3556 1.1176)
			(layers "F.Cu" "F.Mask" "F.Paste")
			(net "GND")
		)
		(pad "3" smd rect
			(at -0.999998 0.649986)
			(size 0.3556 1.1176)
			(layers "F.Cu" "F.Mask" "F.Paste")
			(net "PWRGD_CPU1_PWROK")
		)
		(pad "4" smd rect
			(at 0.999998 0.649986)
			(size 0.3556 1.1176)
			(layers "F.Cu" "F.Mask" "F.Paste")
			(net "PVDDCR_CPU1_P1_RESET_N")
		)
		(pad "5" smd rect
			(at 0.999998 0)
			(size 0.3556 1.1176)
			(layers "F.Cu" "F.Mask" "F.Paste")
			(net "P1V8_AUX")
		)
		(pad "6" smd rect
			(at 0.999998 -0.649986)
			(size 0.3556 1.1176)
			(layers "F.Cu" "F.Mask" "F.Paste")
			(net "PVDDCR_CPU0_P1_RESET_N")
		)
	)
	(footprint ""
		(layer "F.Cu")
		(at 152.541986 -408.517344 -90)
		(property "Reference" "C6717"
			(at 0 0 270)
			(layer "F.SilkS")
			(hide yes)
			(effects
				(font
					(size 1.27 1.27)
				)
			)
		)
		(property "Value" ""
			(at 0 0 270)
			(layer "F.Fab")
			(effects
				(font
					(size 1.27 1.27)
				)
			)
		)
		(duplicate_pad_numbers_are_jumpers no)
		(fp_line
			(start -0.299974 0.150114)
			(end -0.299974 -0.150114)
			(stroke
				(width 0.1)
				(type default)
			)
			(layer "F.Fab")
		)
		(fp_line
			(start 0.299974 0.150114)
			(end -0.299974 0.150114)
			(stroke
				(width 0.1)
				(type default)
			)
			(layer "F.Fab")
		)
		(fp_line
			(start -0.299974 -0.150114)
			(end 0.299974 -0.150114)
			(stroke
				(width 0.1)
				(type default)
			)
			(layer "F.Fab")
		)
		(fp_line
			(start 0.299974 -0.150114)
			(end 0.299974 0.150114)
			(stroke
				(width 0.1)
				(type default)
			)
			(layer "F.Fab")
		)
		(pad "1" smd rect
			(at -0.2667 0 270)
			(size 0.3048 0.381)
			(layers "F.Cu" "F.Mask" "F.Paste")
			(net "P5E_CPU1_P2_TX_BUF_C_DP<12>")
		)
		(pad "2" smd rect
			(at 0.2667 0 270)
			(size 0.3048 0.381)
			(layers "F.Cu" "F.Mask" "F.Paste")
			(net "P5E_CPU1_P2_TX_BUF_DP<12>")
		)
	)
	(footprint ""
		(layer "F.Cu")
		(at 17.658842 -105.537762 90)
		(property "Reference" "R4420"
			(at 0 0 90)
			(layer "F.SilkS")
			(hide yes)
			(effects
				(font
					(size 1.27 1.27)
				)
			)
		)
		(property "Value" ""
			(at 0 0 90)
			(layer "F.Fab")
			(effects
				(font
					(size 1.27 1.27)
				)
			)
		)
		(duplicate_pad_numbers_are_jumpers no)
		(fp_line
			(start 0.7874 -0.4064)
			(end 0.7874 0.4064)
			(stroke
				(width 0.1524)
				(type default)
			)
			(layer "F.SilkS")
		)
		(fp_line
			(start -0.7874 -0.4064)
			(end 0.7874 -0.4064)
			(stroke
				(width 0.1524)
				(type default)
			)
			(layer "F.SilkS")
		)
		(fp_line
			(start 0.7874 0.4064)
			(end -0.7874 0.4064)
			(stroke
				(width 0.1524)
				(type default)
			)
			(layer "F.SilkS")
		)
		(fp_line
			(start -0.7874 0.4064)
			(end -0.7874 -0.4064)
			(stroke
				(width 0.1524)
				(type default)
			)
			(layer "F.SilkS")
		)
		(fp_line
			(start -0.12065 -0.305054)
			(end -0.12065 -0.2794)
			(stroke
				(width 0.1)
				(type default)
			)
			(layer "F.Fab")
		)
		(fp_line
			(start -0.67945 -0.305054)
			(end -0.12065 -0.305054)
			(stroke
				(width 0.1)
				(type default)
			)
			(layer "F.Fab")
		)
		(fp_line
			(start 0.67945 -0.3048)
			(end 0.67945 0.3048)
			(stroke
				(width 0.1)
				(type default)
			)
			(layer "F.Fab")
		)
		(fp_line
			(start 0.12065 -0.3048)
			(end 0.67945 -0.3048)
			(stroke
				(width 0.1)
				(type default)
			)
			(layer "F.Fab")
		)
		(fp_line
			(start 0.12065 -0.2794)
			(end 0.12065 -0.3048)
			(stroke
				(width 0.1)
				(type default)
			)
			(layer "F.Fab")
		)
		(fp_line
			(start -0.12065 -0.2794)
			(end 0.12065 -0.2794)
			(stroke
				(width 0.1)
				(type default)
			)
			(layer "F.Fab")
		)
		(fp_line
			(start 0.120396 0.2794)
			(end -0.12065 0.2794)
			(stroke
				(width 0.1)
				(type default)
			)
			(layer "F.Fab")
		)
		(fp_line
			(start -0.12065 0.2794)
			(end -0.12065 0.3048)
			(stroke
				(width 0.1)
				(type default)
			)
			(layer "F.Fab")
		)
		(fp_line
			(start 0.67945 0.3048)
			(end 0.120396 0.3048)
			(stroke
				(width 0.1)
				(type default)
			)
			(layer "F.Fab")
		)
		(fp_line
			(start 0.120396 0.3048)
			(end 0.120396 0.2794)
			(stroke
				(width 0.1)
				(type default)
			)
			(layer "F.Fab")
		)
		(fp_line
			(start -0.12065 0.3048)
			(end -0.67945 0.3048)
			(stroke
				(width 0.1)
				(type default)
			)
			(layer "F.Fab")
		)
		(fp_line
			(start -0.67945 0.3048)
			(end -0.67945 -0.305054)
			(stroke
				(width 0.1)
				(type default)
			)
			(layer "F.Fab")
		)
		(pad "1" smd circle
			(at -0.40005 0 90)
			(size 0 0)
			(layers "F.Cu" "F.Mask" "F.Paste")
			(net "USB2_HOST_BMC_B_DN")
		)
		(pad "2" smd circle
			(at 0.40005 0 90)
			(size 0 0)
			(layers "F.Cu" "F.Mask" "F.Paste")
			(net "GND")
		)
	)
	(footprint ""
		(layer "F.Cu")
		(at 85.442044 -408.517344 -90)
		(property "Reference" "C6653"
			(at 0 0 270)
			(layer "F.SilkS")
			(hide yes)
			(effects
				(font
					(size 1.27 1.27)
				)
			)
		)
		(property "Value" ""
			(at 0 0 270)
			(layer "F.Fab")
			(effects
				(font
					(size 1.27 1.27)
				)
			)
		)
		(duplicate_pad_numbers_are_jumpers no)
		(fp_line
			(start -0.299974 0.150114)
			(end -0.299974 -0.150114)
			(stroke
				(width 0.1)
				(type default)
			)
			(layer "F.Fab")
		)
		(fp_line
			(start 0.299974 0.150114)
			(end -0.299974 0.150114)
			(stroke
				(width 0.1)
				(type default)
			)
			(layer "F.Fab")
		)
		(fp_line
			(start -0.299974 -0.150114)
			(end 0.299974 -0.150114)
			(stroke
				(width 0.1)
				(type default)
			)
			(layer "F.Fab")
		)
		(fp_line
			(start 0.299974 -0.150114)
			(end 0.299974 0.150114)
			(stroke
				(width 0.1)
				(type default)
			)
			(layer "F.Fab")
		)
		(pad "1" smd rect
			(at -0.2667 0 270)
			(size 0.3048 0.381)
			(layers "F.Cu" "F.Mask" "F.Paste")
			(net "P5E_CPU1_P0_TX_BUF_C_DP<12>")
		)
		(pad "2" smd rect
			(at 0.2667 0 270)
			(size 0.3048 0.381)
			(layers "F.Cu" "F.Mask" "F.Paste")
			(net "P5E_CPU1_P0_TX_BUF_DP<12>")
		)
	)
	(footprint ""
		(layer "F.Cu")
		(at 420.913306 -432.876198)
		(property "Reference" "R1085"
			(at 0 0 0)
			(layer "F.SilkS")
			(hide yes)
			(effects
				(font
					(size 1.27 1.27)
				)
			)
		)
		(property "Value" ""
			(at 0 0 0)
			(layer "F.Fab")
			(effects
				(font
					(size 1.27 1.27)
				)
			)
		)
		(duplicate_pad_numbers_are_jumpers no)
		(fp_line
			(start -0.32512 -0.175006)
			(end 0.32512 -0.175006)
			(stroke
				(width 0.1)
				(type default)
			)
			(layer "F.Fab")
		)
		(fp_line
			(start -0.32512 0.175006)
			(end -0.32512 -0.175006)
			(stroke
				(width 0.1)
				(type default)
			)
			(layer "F.Fab")
		)
		(fp_line
			(start 0.32512 -0.175006)
			(end 0.32512 0.175006)
			(stroke
				(width 0.1)
				(type default)
			)
			(layer "F.Fab")
		)
		(fp_line
			(start 0.32512 0.175006)
			(end -0.32512 0.175006)
			(stroke
				(width 0.1)
				(type default)
			)
			(layer "F.Fab")
		)
		(pad "1" smd rect
			(at -0.2667 0)
			(size 0.3048 0.381)
			(layers "F.Cu" "F.Mask" "F.Paste")
			(net "U16_E2")
		)
		(pad "2" smd rect
			(at 0.2667 0 180)
			(size 0.3048 0.381)
			(layers "F.Cu" "F.Mask" "F.Paste")
			(net "GND")
		)
	)
	(footprint ""
		(layer "F.Cu")
		(at 116.225828 -256.012442 90)
		(property "Reference" "C3900"
			(at 0 0 90)
			(layer "F.SilkS")
			(hide yes)
			(effects
				(font
					(size 1.27 1.27)
				)
			)
		)
		(property "Value" ""
			(at 0 0 90)
			(layer "F.Fab")
			(effects
				(font
					(size 1.27 1.27)
				)
			)
		)
		(duplicate_pad_numbers_are_jumpers no)
		(fp_line
			(start 0.7874 -0.4064)
			(end 0.7874 0.4064)
			(stroke
				(width 0.1524)
				(type default)
			)
			(layer "F.SilkS")
		)
		(fp_line
			(start -0.7874 -0.4064)
			(end 0.7874 -0.4064)
			(stroke
				(width 0.1524)
				(type default)
			)
			(layer "F.SilkS")
		)
		(fp_line
			(start 0.7874 0.4064)
			(end -0.7874 0.4064)
			(stroke
				(width 0.1524)
				(type default)
			)
			(layer "F.SilkS")
		)
		(fp_line
			(start -0.7874 0.4064)
			(end -0.7874 -0.4064)
			(stroke
				(width 0.1524)
				(type default)
			)
			(layer "F.SilkS")
		)
		(fp_line
			(start -0.12065 -0.305054)
			(end -0.12065 -0.2794)
			(stroke
				(width 0.1)
				(type default)
			)
			(layer "F.Fab")
		)
		(fp_line
			(start -0.67945 -0.305054)
			(end -0.12065 -0.305054)
			(stroke
				(width 0.1)
				(type default)
			)
			(layer "F.Fab")
		)
		(fp_line
			(start 0.67945 -0.3048)
			(end 0.67945 0.3048)
			(stroke
				(width 0.1)
				(type default)
			)
			(layer "F.Fab")
		)
		(fp_line
			(start 0.12065 -0.3048)
			(end 0.67945 -0.3048)
			(stroke
				(width 0.1)
				(type default)
			)
			(layer "F.Fab")
		)
		(fp_line
			(start 0.12065 -0.2794)
			(end 0.12065 -0.3048)
			(stroke
				(width 0.1)
				(type default)
			)
			(layer "F.Fab")
		)
		(fp_line
			(start -0.12065 -0.2794)
			(end 0.12065 -0.2794)
			(stroke
				(width 0.1)
				(type default)
			)
			(layer "F.Fab")
		)
		(fp_line
			(start 0.120396 0.2794)
			(end -0.12065 0.2794)
			(stroke
				(width 0.1)
				(type default)
			)
			(layer "F.Fab")
		)
		(fp_line
			(start -0.12065 0.2794)
			(end -0.12065 0.3048)
			(stroke
				(width 0.1)
				(type default)
			)
			(layer "F.Fab")
		)
		(fp_line
			(start 0.67945 0.3048)
			(end 0.120396 0.3048)
			(stroke
				(width 0.1)
				(type default)
			)
			(layer "F.Fab")
		)
		(fp_line
			(start 0.120396 0.3048)
			(end 0.120396 0.2794)
			(stroke
				(width 0.1)
				(type default)
			)
			(layer "F.Fab")
		)
		(fp_line
			(start -0.12065 0.3048)
			(end -0.67945 0.3048)
			(stroke
				(width 0.1)
				(type default)
			)
			(layer "F.Fab")
		)
		(fp_line
			(start -0.67945 0.3048)
			(end -0.67945 -0.305054)
			(stroke
				(width 0.1)
				(type default)
			)
			(layer "F.Fab")
		)
		(pad "1" smd circle
			(at -0.40005 0 90)
			(size 0 0)
			(layers "F.Cu" "F.Mask" "F.Paste")
			(net "PVDDCR_SOC_P1")
		)
		(pad "2" smd circle
			(at 0.40005 0 90)
			(size 0 0)
			(layers "F.Cu" "F.Mask" "F.Paste")
			(net "GND")
		)
	)
	(footprint ""
		(layer "F.Cu")
		(at 350.44761 -61.364876 180)
		(property "Reference" "R483"
			(at 0 0 180)
			(layer "F.SilkS")
			(hide yes)
			(effects
				(font
					(size 1.27 1.27)
				)
			)
		)
		(property "Value" ""
			(at 0 0 180)
			(layer "F.Fab")
			(effects
				(font
					(size 1.27 1.27)
				)
			)
		)
		(duplicate_pad_numbers_are_jumpers no)
		(fp_line
			(start 0.7874 0.4064)
			(end -0.7874 0.4064)
			(stroke
				(width 0.1524)
				(type default)
			)
			(layer "F.SilkS")
		)
		(fp_line
			(start 0.7874 -0.4064)
			(end 0.7874 0.4064)
			(stroke
				(width 0.1524)
				(type default)
			)
			(layer "F.SilkS")
		)
		(fp_line
			(start -0.7874 0.4064)
			(end -0.7874 -0.4064)
			(stroke
				(width 0.1524)
				(type default)
			)
			(layer "F.SilkS")
		)
		(fp_line
			(start -0.7874 -0.4064)
			(end 0.7874 -0.4064)
			(stroke
				(width 0.1524)
				(type default)
			)
			(layer "F.SilkS")
		)
		(fp_line
			(start 0.67945 0.3048)
			(end 0.120396 0.3048)
			(stroke
				(width 0.1)
				(type default)
			)
			(layer "F.Fab")
		)
		(fp_line
			(start 0.67945 -0.3048)
			(end 0.67945 0.3048)
			(stroke
				(width 0.1)
				(type default)
			)
			(layer "F.Fab")
		)
		(fp_line
			(start 0.12065 -0.2794)
			(end 0.12065 -0.3048)
			(stroke
				(width 0.1)
				(type default)
			)
			(layer "F.Fab")
		)
		(fp_line
			(start 0.12065 -0.3048)
			(end 0.67945 -0.3048)
			(stroke
				(width 0.1)
				(type default)
			)
			(layer "F.Fab")
		)
		(fp_line
			(start 0.120396 0.3048)
			(end 0.120396 0.2794)
			(stroke
				(width 0.1)
				(type default)
			)
			(layer "F.Fab")
		)
		(fp_line
			(start 0.120396 0.2794)
			(end -0.12065 0.2794)
			(stroke
				(width 0.1)
				(type default)
			)
			(layer "F.Fab")
		)
		(fp_line
			(start -0.12065 0.3048)
			(end -0.67945 0.3048)
			(stroke
				(width 0.1)
				(type default)
			)
			(layer "F.Fab")
		)
		(fp_line
			(start -0.12065 0.2794)
			(end -0.12065 0.3048)
			(stroke
				(width 0.1)
				(type default)
			)
			(layer "F.Fab")
		)
		(fp_line
			(start -0.12065 -0.2794)
			(end 0.12065 -0.2794)
			(stroke
				(width 0.1)
				(type default)
			)
			(layer "F.Fab")
		)
		(fp_line
			(start -0.12065 -0.305054)
			(end -0.12065 -0.2794)
			(stroke
				(width 0.1)
				(type default)
			)
			(layer "F.Fab")
		)
		(fp_line
			(start -0.67945 0.3048)
			(end -0.67945 -0.305054)
			(stroke
				(width 0.1)
				(type default)
			)
			(layer "F.Fab")
		)
		(fp_line
			(start -0.67945 -0.305054)
			(end -0.12065 -0.305054)
			(stroke
				(width 0.1)
				(type default)
			)
			(layer "F.Fab")
		)
		(pad "1" smd circle
			(at -0.40005 0 180)
			(size 0 0)
			(layers "F.Cu" "F.Mask" "F.Paste")
			(net "CPU0_XTRIG_L5")
		)
		(pad "2" smd circle
			(at 0.40005 0 180)
			(size 0 0)
			(layers "F.Cu" "F.Mask" "F.Paste")
			(net "CPU0_XTRIG_R1_L5")
		)
	)
	(footprint ""
		(layer "F.Cu")
		(at 209.423 -129.54 90)
		(property "Reference" "C29"
			(at 0 0 90)
			(layer "F.SilkS")
			(hide yes)
			(effects
				(font
					(size 1.27 1.27)
				)
			)
		)
		(property "Value" ""
			(at 0 0 90)
			(layer "F.Fab")
			(effects
				(font
					(size 1.27 1.27)
				)
			)
		)
		(duplicate_pad_numbers_are_jumpers no)
		(fp_line
			(start 0.7874 -0.4064)
			(end 0.7874 0.4064)
			(stroke
				(width 0.1524)
				(type default)
			)
			(layer "F.SilkS")
		)
		(fp_line
			(start -0.7874 -0.4064)
			(end 0.7874 -0.4064)
			(stroke
				(width 0.1524)
				(type default)
			)
			(layer "F.SilkS")
		)
		(fp_line
			(start 0.7874 0.4064)
			(end -0.7874 0.4064)
			(stroke
				(width 0.1524)
				(type default)
			)
			(layer "F.SilkS")
		)
		(fp_line
			(start -0.7874 0.4064)
			(end -0.7874 -0.4064)
			(stroke
				(width 0.1524)
				(type default)
			)
			(layer "F.SilkS")
		)
		(fp_line
			(start -0.12065 -0.305054)
			(end -0.12065 -0.2794)
			(stroke
				(width 0.1)
				(type default)
			)
			(layer "F.Fab")
		)
		(fp_line
			(start -0.67945 -0.305054)
			(end -0.12065 -0.305054)
			(stroke
				(width 0.1)
				(type default)
			)
			(layer "F.Fab")
		)
		(fp_line
			(start 0.67945 -0.3048)
			(end 0.67945 0.3048)
			(stroke
				(width 0.1)
				(type default)
			)
			(layer "F.Fab")
		)
		(fp_line
			(start 0.12065 -0.3048)
			(end 0.67945 -0.3048)
			(stroke
				(width 0.1)
				(type default)
			)
			(layer "F.Fab")
		)
		(fp_line
			(start 0.12065 -0.2794)
			(end 0.12065 -0.3048)
			(stroke
				(width 0.1)
				(type default)
			)
			(layer "F.Fab")
		)
		(fp_line
			(start -0.12065 -0.2794)
			(end 0.12065 -0.2794)
			(stroke
				(width 0.1)
				(type default)
			)
			(layer "F.Fab")
		)
		(fp_line
			(start 0.120396 0.2794)
			(end -0.12065 0.2794)
			(stroke
				(width 0.1)
				(type default)
			)
			(layer "F.Fab")
		)
		(fp_line
			(start -0.12065 0.2794)
			(end -0.12065 0.3048)
			(stroke
				(width 0.1)
				(type default)
			)
			(layer "F.Fab")
		)
		(fp_line
			(start 0.67945 0.3048)
			(end 0.120396 0.3048)
			(stroke
				(width 0.1)
				(type default)
			)
			(layer "F.Fab")
		)
		(fp_line
			(start 0.120396 0.3048)
			(end 0.120396 0.2794)
			(stroke
				(width 0.1)
				(type default)
			)
			(layer "F.Fab")
		)
		(fp_line
			(start -0.12065 0.3048)
			(end -0.67945 0.3048)
			(stroke
				(width 0.1)
				(type default)
			)
			(layer "F.Fab")
		)
		(fp_line
			(start -0.67945 0.3048)
			(end -0.67945 -0.305054)
			(stroke
				(width 0.1)
				(type default)
			)
			(layer "F.Fab")
		)
		(pad "1" smd circle
			(at -0.40005 0 90)
			(size 0 0)
			(layers "F.Cu" "F.Mask" "F.Paste")
			(net "SW_P3V3_EN_ISO_R")
		)
		(pad "2" smd circle
			(at 0.40005 0 90)
			(size 0 0)
			(layers "F.Cu" "F.Mask" "F.Paste")
			(net "GND")
		)
	)
	(footprint ""
		(layer "F.Cu")
		(at 358.389936 -393.47648 180)
		(property "Reference" "R1002"
			(at 0 0 180)
			(layer "F.SilkS")
			(hide yes)
			(effects
				(font
					(size 1.27 1.27)
				)
			)
		)
		(property "Value" ""
			(at 0 0 180)
			(layer "F.Fab")
			(effects
				(font
					(size 1.27 1.27)
				)
			)
		)
		(duplicate_pad_numbers_are_jumpers no)
		(fp_line
			(start 0.7874 0.4064)
			(end -0.7874 0.4064)
			(stroke
				(width 0.1524)
				(type default)
			)
			(layer "F.SilkS")
		)
		(fp_line
			(start 0.7874 -0.4064)
			(end 0.7874 0.4064)
			(stroke
				(width 0.1524)
				(type default)
			)
			(layer "F.SilkS")
		)
		(fp_line
			(start -0.7874 0.4064)
			(end -0.7874 -0.4064)
			(stroke
				(width 0.1524)
				(type default)
			)
			(layer "F.SilkS")
		)
		(fp_line
			(start -0.7874 -0.4064)
			(end 0.7874 -0.4064)
			(stroke
				(width 0.1524)
				(type default)
			)
			(layer "F.SilkS")
		)
		(fp_line
			(start 0.67945 0.3048)
			(end 0.120396 0.3048)
			(stroke
				(width 0.1)
				(type default)
			)
			(layer "F.Fab")
		)
		(fp_line
			(start 0.67945 -0.3048)
			(end 0.67945 0.3048)
			(stroke
				(width 0.1)
				(type default)
			)
			(layer "F.Fab")
		)
		(fp_line
			(start 0.12065 -0.2794)
			(end 0.12065 -0.3048)
			(stroke
				(width 0.1)
				(type default)
			)
			(layer "F.Fab")
		)
		(fp_line
			(start 0.12065 -0.3048)
			(end 0.67945 -0.3048)
			(stroke
				(width 0.1)
				(type default)
			)
			(layer "F.Fab")
		)
		(fp_line
			(start 0.120396 0.3048)
			(end 0.120396 0.2794)
			(stroke
				(width 0.1)
				(type default)
			)
			(layer "F.Fab")
		)
		(fp_line
			(start 0.120396 0.2794)
			(end -0.12065 0.2794)
			(stroke
				(width 0.1)
				(type default)
			)
			(layer "F.Fab")
		)
		(fp_line
			(start -0.12065 0.3048)
			(end -0.67945 0.3048)
			(stroke
				(width 0.1)
				(type default)
			)
			(layer "F.Fab")
		)
		(fp_line
			(start -0.12065 0.2794)
			(end -0.12065 0.3048)
			(stroke
				(width 0.1)
				(type default)
			)
			(layer "F.Fab")
		)
		(fp_line
			(start -0.12065 -0.2794)
			(end 0.12065 -0.2794)
			(stroke
				(width 0.1)
				(type default)
			)
			(layer "F.Fab")
		)
		(fp_line
			(start -0.12065 -0.305054)
			(end -0.12065 -0.2794)
			(stroke
				(width 0.1)
				(type default)
			)
			(layer "F.Fab")
		)
		(fp_line
			(start -0.67945 0.3048)
			(end -0.67945 -0.305054)
			(stroke
				(width 0.1)
				(type default)
			)
			(layer "F.Fab")
		)
		(fp_line
			(start -0.67945 -0.305054)
			(end -0.12065 -0.305054)
			(stroke
				(width 0.1)
				(type default)
			)
			(layer "F.Fab")
		)
		(pad "1" smd rect
			(at -0.40005 0)
			(size 0.4572 0.508)
			(layers "F.Cu" "F.Mask" "F.Paste")
			(net "P1V8_CPU0_RT1_1A_1D")
		)
		(pad "2" smd rect
			(at 0.40005 0)
			(size 0.4572 0.508)
			(layers "F.Cu" "F.Mask" "F.Paste")
			(net "P1V8_CPU0_RT1_1A")
		)
	)
	(footprint ""
		(layer "F.Cu")
		(at 452.115174 -413.0167 90)
		(property "Reference" "PL6504"
			(at -3.72237 -2.281174 0)
			(unlocked yes)
			(layer "F.SilkS")
			(effects
				(font
					(size 0.7874 0.5842)
					(thickness 0.1524)
				)
				(justify left)
			)
		)
		(property "Value" ""
			(at 0 0 90)
			(layer "F.Fab")
			(effects
				(font
					(size 1.27 1.27)
				)
			)
		)
		(duplicate_pad_numbers_are_jumpers no)
		(fp_line
			(start 2.249932 -2.249932)
			(end 2.249932 -1.3843)
			(stroke
				(width 0.1524)
				(type default)
			)
			(layer "F.SilkS")
		)
		(fp_line
			(start -2.249932 -2.249932)
			(end 2.249932 -2.249932)
			(stroke
				(width 0.1524)
				(type default)
			)
			(layer "F.SilkS")
		)
		(fp_line
			(start -2.249932 -1.3843)
			(end -2.249932 -2.249932)
			(stroke
				(width 0.1524)
				(type default)
			)
			(layer "F.SilkS")
		)
		(fp_line
			(start 2.249932 1.3843)
			(end 2.249932 2.249932)
			(stroke
				(width 0.1524)
				(type default)
			)
			(layer "F.SilkS")
		)
		(fp_line
			(start 2.249932 2.249932)
			(end -2.249932 2.249932)
			(stroke
				(width 0.1524)
				(type default)
			)
			(layer "F.SilkS")
		)
		(fp_line
			(start -2.249932 2.249932)
			(end -2.249932 1.3843)
			(stroke
				(width 0.1524)
				(type default)
			)
			(layer "F.SilkS")
		)
		(fp_line
			(start 2.249932 -2.249932)
			(end 2.249932 2.249932)
			(stroke
				(width 0.1)
				(type default)
			)
			(layer "F.Fab")
		)
		(fp_line
			(start -2.249932 -2.249932)
			(end 2.249932 -2.249932)
			(stroke
				(width 0.1)
				(type default)
			)
			(layer "F.Fab")
		)
		(fp_line
			(start 2.249932 2.249932)
			(end -2.249932 2.249932)
			(stroke
				(width 0.1)
				(type default)
			)
			(layer "F.Fab")
		)
		(fp_line
			(start -2.249932 2.249932)
			(end -2.249932 -2.249932)
			(stroke
				(width 0.1)
				(type default)
			)
			(layer "F.Fab")
		)
		(pad "1" smd rect
			(at -1.82499 0 90)
			(size 1.0668 2.5146)
			(layers "F.Cu" "F.Mask" "F.Paste")
			(net "SW_P12V_AUX_P0V9_RETIMER_CPU0_FLT")
		)
		(pad "2" smd rect
			(at 1.82499 0 90)
			(size 1.0668 2.5146)
			(layers "F.Cu" "F.Mask" "F.Paste")
			(net "P12V_AUX")
		)
	)
	(footprint ""
		(layer "F.Cu")
		(at 426.6692 -17.624298 90)
		(property "Reference" "C1574"
			(at 0 0 90)
			(layer "F.SilkS")
			(hide yes)
			(effects
				(font
					(size 1.27 1.27)
				)
			)
		)
		(property "Value" ""
			(at 0 0 90)
			(layer "F.Fab")
			(effects
				(font
					(size 1.27 1.27)
				)
			)
		)
		(duplicate_pad_numbers_are_jumpers no)
		(fp_line
			(start 0.299974 -0.150114)
			(end 0.299974 0.150114)
			(stroke
				(width 0.1)
				(type default)
			)
			(layer "F.Fab")
		)
		(fp_line
			(start -0.299974 -0.150114)
			(end 0.299974 -0.150114)
			(stroke
				(width 0.1)
				(type default)
			)
			(layer "F.Fab")
		)
		(fp_line
			(start 0.299974 0.150114)
			(end -0.299974 0.150114)
			(stroke
				(width 0.1)
				(type default)
			)
			(layer "F.Fab")
		)
		(fp_line
			(start -0.299974 0.150114)
			(end -0.299974 -0.150114)
			(stroke
				(width 0.1)
				(type default)
			)
			(layer "F.Fab")
		)
		(pad "1" smd rect
			(at -0.2667 0 90)
			(size 0.3048 0.381)
			(layers "F.Cu" "F.Mask" "F.Paste")
			(net "P5E_CPU0_G3_TX_C_DN<2>")
		)
		(pad "2" smd rect
			(at 0.2667 0 90)
			(size 0.3048 0.381)
			(layers "F.Cu" "F.Mask" "F.Paste")
			(net "P5E_CPU0_G3_TX_DN<2>")
		)
	)
	(footprint ""
		(layer "F.Cu")
		(at 440.333384 -16.014954 180)
		(property "Reference" "C1213"
			(at 0 0 180)
			(layer "F.SilkS")
			(hide yes)
			(effects
				(font
					(size 1.27 1.27)
				)
			)
		)
		(property "Value" ""
			(at 0 0 180)
			(layer "F.Fab")
			(effects
				(font
					(size 1.27 1.27)
				)
			)
		)
		(duplicate_pad_numbers_are_jumpers no)
		(fp_line
			(start 1.524 0.762)
			(end -1.524 0.762)
			(stroke
				(width 0.1524)
				(type default)
			)
			(layer "F.SilkS")
		)
		(fp_line
			(start 1.524 -0.762)
			(end 1.524 0.762)
			(stroke
				(width 0.1524)
				(type default)
			)
			(layer "F.SilkS")
		)
		(fp_line
			(start -1.524 0.762)
			(end -1.524 -0.762)
			(stroke
				(width 0.1524)
				(type default)
			)
			(layer "F.SilkS")
		)
		(fp_line
			(start -1.524 -0.762)
			(end 1.524 -0.762)
			(stroke
				(width 0.1524)
				(type default)
			)
			(layer "F.SilkS")
		)
		(fp_line
			(start 1.1049 0.724916)
			(end 1.1049 -0.724916)
			(stroke
				(width 0.1)
				(type default)
			)
			(layer "F.Fab")
		)
		(fp_line
			(start 1.1049 -0.724916)
			(end -1.1049 -0.724916)
			(stroke
				(width 0.1)
				(type default)
			)
			(layer "F.Fab")
		)
		(fp_line
			(start -1.1049 0.724916)
			(end 1.1049 0.724916)
			(stroke
				(width 0.1)
				(type default)
			)
			(layer "F.Fab")
		)
		(fp_line
			(start -1.1049 -0.724916)
			(end -1.1049 0.724916)
			(stroke
				(width 0.1)
				(type default)
			)
			(layer "F.Fab")
		)
		(pad "1" smd rect
			(at -0.889 0)
			(size 1.016 1.27)
			(layers "F.Cu" "F.Mask" "F.Paste")
			(net "P12V_OCP_SFF_R")
		)
		(pad "2" smd rect
			(at 0.889 0)
			(size 1.016 1.27)
			(layers "F.Cu" "F.Mask" "F.Paste")
			(net "GND")
		)
	)
	(footprint ""
		(layer "F.Cu")
		(at 398.473168 -45.272706 180)
		(property "Reference" ""
			(at 0 0 180)
			(layer "F.SilkS")
			(hide yes)
			(effects
				(font
					(size 1.27 1.27)
				)
			)
		)
		(property "Value" ""
			(at 0 0 180)
			(layer "F.Fab")
			(effects
				(font
					(size 1.27 1.27)
				)
			)
		)
		(duplicate_pad_numbers_are_jumpers no)
		(pad "1" smd circle
			(at 0 0 180)
			(size 0.9906 0.9906)
			(layers "F.Cu" "F.Mask" "F.Paste")
			(net "Net_2239")
		)
		(zone
			(layer "F.Cu")
			(hatch none 0.5)
			(connect_pads
				(clearance 0)
			)
			(min_thickness 0.25)
			(keepout
				(tracks not_allowed)
				(vias allowed)
				(pads allowed)
				(copperpour not_allowed)
				(footprints allowed)
			)
			(placement
				(enabled no)
				(sheetname "")
			)
			(fill
				(thermal_gap 0.5)
				(thermal_bridge_width 0.5)
				(island_removal_mode 0)
			)
			(polygon
				(pts
					(arc
						(start 400.098768 -45.272706)
						(mid 396.847568 -45.272706)
						(end 400.098768 -45.272706)
					)
				)
			)
		)
	)
	(footprint ""
		(layer "F.Cu")
		(at 359.716578 -166.830756 -90)
		(property "Reference" "PC567"
			(at 0 0 270)
			(layer "F.SilkS")
			(hide yes)
			(effects
				(font
					(size 1.27 1.27)
				)
			)
		)
		(property "Value" ""
			(at 0 0 270)
			(layer "F.Fab")
			(effects
				(font
					(size 1.27 1.27)
				)
			)
		)
		(duplicate_pad_numbers_are_jumpers no)
		(fp_line
			(start -0.7874 0.4064)
			(end -0.7874 -0.4064)
			(stroke
				(width 0.1524)
				(type default)
			)
			(layer "F.SilkS")
		)
		(fp_line
			(start -0.199644 0.4064)
			(end -0.7874 0.4064)
			(stroke
				(width 0.1524)
				(type default)
			)
			(layer "F.SilkS")
		)
		(fp_line
			(start 0.7874 0.4064)
			(end 0.409956 0.4064)
			(stroke
				(width 0.1524)
				(type default)
			)
			(layer "F.SilkS")
		)
		(fp_line
			(start -0.7874 -0.4064)
			(end 0.7874 -0.4064)
			(stroke
				(width 0.1524)
				(type default)
			)
			(layer "F.SilkS")
		)
		(fp_line
			(start 0.7874 -0.4064)
			(end 0.7874 0.4064)
			(stroke
				(width 0.1524)
				(type default)
			)
			(layer "F.SilkS")
		)
		(fp_line
			(start -0.67945 0.3048)
			(end -0.67945 -0.305054)
			(stroke
				(width 0.1)
				(type default)
			)
			(layer "F.Fab")
		)
		(fp_line
			(start -0.12065 0.3048)
			(end -0.67945 0.3048)
			(stroke
				(width 0.1)
				(type default)
			)
			(layer "F.Fab")
		)
		(fp_line
			(start 0.120396 0.3048)
			(end 0.120396 0.2794)
			(stroke
				(width 0.1)
				(type default)
			)
			(layer "F.Fab")
		)
		(fp_line
			(start 0.67945 0.3048)
			(end 0.120396 0.3048)
			(stroke
				(width 0.1)
				(type default)
			)
			(layer "F.Fab")
		)
		(fp_line
			(start -0.12065 0.2794)
			(end -0.12065 0.3048)
			(stroke
				(width 0.1)
				(type default)
			)
			(layer "F.Fab")
		)
		(fp_line
			(start 0.120396 0.2794)
			(end -0.12065 0.2794)
			(stroke
				(width 0.1)
				(type default)
			)
			(layer "F.Fab")
		)
		(fp_line
			(start -0.12065 -0.2794)
			(end 0.12065 -0.2794)
			(stroke
				(width 0.1)
				(type default)
			)
			(layer "F.Fab")
		)
		(fp_line
			(start 0.12065 -0.2794)
			(end 0.12065 -0.3048)
			(stroke
				(width 0.1)
				(type default)
			)
			(layer "F.Fab")
		)
		(fp_line
			(start 0.12065 -0.3048)
			(end 0.67945 -0.3048)
			(stroke
				(width 0.1)
				(type default)
			)
			(layer "F.Fab")
		)
		(fp_line
			(start 0.67945 -0.3048)
			(end 0.67945 0.3048)
			(stroke
				(width 0.1)
				(type default)
			)
			(layer "F.Fab")
		)
		(fp_line
			(start -0.67945 -0.305054)
			(end -0.12065 -0.305054)
			(stroke
				(width 0.1)
				(type default)
			)
			(layer "F.Fab")
		)
		(fp_line
			(start -0.12065 -0.305054)
			(end -0.12065 -0.2794)
			(stroke
				(width 0.1)
				(type default)
			)
			(layer "F.Fab")
		)
		(pad "1" smd circle
			(at -0.40005 0 270)
			(size 0 0)
			(layers "F.Cu" "F.Mask" "F.Paste")
			(net "PVDDCR_CPU0_P0_VCC5")
		)
		(pad "2" smd circle
			(at 0.40005 0 270)
			(size 0 0)
			(layers "F.Cu" "F.Mask" "F.Paste")
			(net "GND")
		)
	)
	(footprint ""
		(layer "F.Cu")
		(at 424.403266 -355.718364 90)
		(property "Reference" "PR135"
			(at 0 0 90)
			(layer "F.SilkS")
			(hide yes)
			(effects
				(font
					(size 1.27 1.27)
				)
			)
		)
		(property "Value" ""
			(at 0 0 90)
			(layer "F.Fab")
			(effects
				(font
					(size 1.27 1.27)
				)
			)
		)
		(duplicate_pad_numbers_are_jumpers no)
		(fp_line
			(start 0.7874 -0.4064)
			(end 0.7874 0.4064)
			(stroke
				(width 0.1524)
				(type default)
			)
			(layer "F.SilkS")
		)
		(fp_line
			(start -0.7874 -0.4064)
			(end 0.7874 -0.4064)
			(stroke
				(width 0.1524)
				(type default)
			)
			(layer "F.SilkS")
		)
		(fp_line
			(start 0.7874 0.4064)
			(end -0.7874 0.4064)
			(stroke
				(width 0.1524)
				(type default)
			)
			(layer "F.SilkS")
		)
		(fp_line
			(start -0.7874 0.4064)
			(end -0.7874 -0.4064)
			(stroke
				(width 0.1524)
				(type default)
			)
			(layer "F.SilkS")
		)
		(fp_line
			(start -0.12065 -0.305054)
			(end -0.12065 -0.2794)
			(stroke
				(width 0.1)
				(type default)
			)
			(layer "F.Fab")
		)
		(fp_line
			(start -0.67945 -0.305054)
			(end -0.12065 -0.305054)
			(stroke
				(width 0.1)
				(type default)
			)
			(layer "F.Fab")
		)
		(fp_line
			(start 0.67945 -0.3048)
			(end 0.67945 0.3048)
			(stroke
				(width 0.1)
				(type default)
			)
			(layer "F.Fab")
		)
		(fp_line
			(start 0.12065 -0.3048)
			(end 0.67945 -0.3048)
			(stroke
				(width 0.1)
				(type default)
			)
			(layer "F.Fab")
		)
		(fp_line
			(start 0.12065 -0.2794)
			(end 0.12065 -0.3048)
			(stroke
				(width 0.1)
				(type default)
			)
			(layer "F.Fab")
		)
		(fp_line
			(start -0.12065 -0.2794)
			(end 0.12065 -0.2794)
			(stroke
				(width 0.1)
				(type default)
			)
			(layer "F.Fab")
		)
		(fp_line
			(start 0.120396 0.2794)
			(end -0.12065 0.2794)
			(stroke
				(width 0.1)
				(type default)
			)
			(layer "F.Fab")
		)
		(fp_line
			(start -0.12065 0.2794)
			(end -0.12065 0.3048)
			(stroke
				(width 0.1)
				(type default)
			)
			(layer "F.Fab")
		)
		(fp_line
			(start 0.67945 0.3048)
			(end 0.120396 0.3048)
			(stroke
				(width 0.1)
				(type default)
			)
			(layer "F.Fab")
		)
		(fp_line
			(start 0.120396 0.3048)
			(end 0.120396 0.2794)
			(stroke
				(width 0.1)
				(type default)
			)
			(layer "F.Fab")
		)
		(fp_line
			(start -0.12065 0.3048)
			(end -0.67945 0.3048)
			(stroke
				(width 0.1)
				(type default)
			)
			(layer "F.Fab")
		)
		(fp_line
			(start -0.67945 0.3048)
			(end -0.67945 -0.305054)
			(stroke
				(width 0.1)
				(type default)
			)
			(layer "F.Fab")
		)
		(pad "1" smd circle
			(at -0.40005 0 90)
			(size 0 0)
			(layers "F.Cu" "F.Mask" "F.Paste")
			(net "SW_PVDD11_S3_P0_BOOT1")
		)
		(pad "2" smd circle
			(at 0.40005 0 90)
			(size 0 0)
			(layers "F.Cu" "F.Mask" "F.Paste")
			(net "SW_PVDD11_S3_P0_BOOT1_RC")
		)
	)
	(footprint ""
		(layer "F.Cu")
		(at 35.881818 -436.433214)
		(property "Reference" "R2990"
			(at 0 0 0)
			(layer "F.SilkS")
			(hide yes)
			(effects
				(font
					(size 1.27 1.27)
				)
			)
		)
		(property "Value" ""
			(at 0 0 0)
			(layer "F.Fab")
			(effects
				(font
					(size 1.27 1.27)
				)
			)
		)
		(duplicate_pad_numbers_are_jumpers no)
		(fp_line
			(start -0.7874 -0.4064)
			(end 0.7874 -0.4064)
			(stroke
				(width 0.1524)
				(type default)
			)
			(layer "F.SilkS")
		)
		(fp_line
			(start -0.7874 0.4064)
			(end -0.7874 -0.4064)
			(stroke
				(width 0.1524)
				(type default)
			)
			(layer "F.SilkS")
		)
		(fp_line
			(start 0.7874 -0.4064)
			(end 0.7874 0.4064)
			(stroke
				(width 0.1524)
				(type default)
			)
			(layer "F.SilkS")
		)
		(fp_line
			(start 0.7874 0.4064)
			(end -0.7874 0.4064)
			(stroke
				(width 0.1524)
				(type default)
			)
			(layer "F.SilkS")
		)
		(fp_line
			(start -0.67945 -0.305054)
			(end -0.12065 -0.305054)
			(stroke
				(width 0.1)
				(type default)
			)
			(layer "F.Fab")
		)
		(fp_line
			(start -0.67945 0.3048)
			(end -0.67945 -0.305054)
			(stroke
				(width 0.1)
				(type default)
			)
			(layer "F.Fab")
		)
		(fp_line
			(start -0.12065 -0.305054)
			(end -0.12065 -0.2794)
			(stroke
				(width 0.1)
				(type default)
			)
			(layer "F.Fab")
		)
		(fp_line
			(start -0.12065 -0.2794)
			(end 0.12065 -0.2794)
			(stroke
				(width 0.1)
				(type default)
			)
			(layer "F.Fab")
		)
		(fp_line
			(start -0.12065 0.2794)
			(end -0.12065 0.3048)
			(stroke
				(width 0.1)
				(type default)
			)
			(layer "F.Fab")
		)
		(fp_line
			(start -0.12065 0.3048)
			(end -0.67945 0.3048)
			(stroke
				(width 0.1)
				(type default)
			)
			(layer "F.Fab")
		)
		(fp_line
			(start 0.120396 0.2794)
			(end -0.12065 0.2794)
			(stroke
				(width 0.1)
				(type default)
			)
			(layer "F.Fab")
		)
		(fp_line
			(start 0.120396 0.3048)
			(end 0.120396 0.2794)
			(stroke
				(width 0.1)
				(type default)
			)
			(layer "F.Fab")
		)
		(fp_line
			(start 0.12065 -0.3048)
			(end 0.67945 -0.3048)
			(stroke
				(width 0.1)
				(type default)
			)
			(layer "F.Fab")
		)
		(fp_line
			(start 0.12065 -0.2794)
			(end 0.12065 -0.3048)
			(stroke
				(width 0.1)
				(type default)
			)
			(layer "F.Fab")
		)
		(fp_line
			(start 0.67945 -0.3048)
			(end 0.67945 0.3048)
			(stroke
				(width 0.1)
				(type default)
			)
			(layer "F.Fab")
		)
		(fp_line
			(start 0.67945 0.3048)
			(end 0.120396 0.3048)
			(stroke
				(width 0.1)
				(type default)
			)
			(layer "F.Fab")
		)
		(pad "1" smd circle
			(at -0.40005 0)
			(size 0 0)
			(layers "F.Cu" "F.Mask" "F.Paste")
			(net "SMB_2_BMC_GPU_BUF_R_SCL")
		)
		(pad "2" smd circle
			(at 0.40005 0)
			(size 0 0)
			(layers "F.Cu" "F.Mask" "F.Paste")
			(net "SMB_2_BMC_GPU_BUF_SCL")
		)
	)
	(footprint ""
		(layer "F.Cu")
		(at 68.16852 -395.6304 -90)
		(property "Reference" "R6708"
			(at 0 0 270)
			(layer "F.SilkS")
			(hide yes)
			(effects
				(font
					(size 1.27 1.27)
				)
			)
		)
		(property "Value" ""
			(at 0 0 270)
			(layer "F.Fab")
			(effects
				(font
					(size 1.27 1.27)
				)
			)
		)
		(duplicate_pad_numbers_are_jumpers no)
		(fp_line
			(start -0.32512 0.175006)
			(end -0.32512 -0.175006)
			(stroke
				(width 0.1)
				(type default)
			)
			(layer "F.Fab")
		)
		(fp_line
			(start 0.32512 0.175006)
			(end -0.32512 0.175006)
			(stroke
				(width 0.1)
				(type default)
			)
			(layer "F.Fab")
		)
		(fp_line
			(start -0.32512 -0.175006)
			(end 0.32512 -0.175006)
			(stroke
				(width 0.1)
				(type default)
			)
			(layer "F.Fab")
		)
		(fp_line
			(start 0.32512 -0.175006)
			(end 0.32512 0.175006)
			(stroke
				(width 0.1)
				(type default)
			)
			(layer "F.Fab")
		)
		(pad "1" smd rect
			(at -0.2667 0 270)
			(size 0.3048 0.381)
			(layers "F.Cu" "F.Mask" "F.Paste")
			(net "RST_RT_CPU1_P0_PERST_N")
		)
		(pad "2" smd rect
			(at 0.2667 0 90)
			(size 0.3048 0.381)
			(layers "F.Cu" "F.Mask" "F.Paste")
			(net "RST_RT_CPU1_P0_PERST_R_N")
		)
	)
	(footprint ""
		(layer "F.Cu")
		(at 359.297986 -332.580996 90)
		(property "Reference" "PL9"
			(at -3.302 4.149852 90)
			(unlocked yes)
			(layer "F.SilkS")
			(effects
				(font
					(size 0.7874 0.5842)
					(thickness 0.1524)
				)
				(justify left)
			)
		)
		(property "Value" ""
			(at 0 0 90)
			(layer "F.Fab")
			(effects
				(font
					(size 1.27 1.27)
				)
			)
		)
		(duplicate_pad_numbers_are_jumpers no)
		(fp_line
			(start 3.24993 -3.24993)
			(end 3.24993 -2.2352)
			(stroke
				(width 0.1524)
				(type default)
			)
			(layer "F.SilkS")
		)
		(fp_line
			(start -3.24993 -3.24993)
			(end 3.24993 -3.24993)
			(stroke
				(width 0.1524)
				(type default)
			)
			(layer "F.SilkS")
		)
		(fp_line
			(start -3.24993 -2.2352)
			(end -3.24993 -3.24993)
			(stroke
				(width 0.1524)
				(type default)
			)
			(layer "F.SilkS")
		)
		(fp_line
			(start 3.24993 2.2352)
			(end 3.24993 3.24993)
			(stroke
				(width 0.1524)
				(type default)
			)
			(layer "F.SilkS")
		)
		(fp_line
			(start 3.24993 3.24993)
			(end -3.24993 3.24993)
			(stroke
				(width 0.1524)
				(type default)
			)
			(layer "F.SilkS")
		)
		(fp_line
			(start -3.24993 3.24993)
			(end -3.24993 2.2352)
			(stroke
				(width 0.1524)
				(type default)
			)
			(layer "F.SilkS")
		)
		(fp_line
			(start 3.24993 -3.24993)
			(end 3.24993 3.24993)
			(stroke
				(width 0.1)
				(type default)
			)
			(layer "F.Fab")
		)
		(fp_line
			(start -3.24993 -3.24993)
			(end 3.24993 -3.24993)
			(stroke
				(width 0.1)
				(type default)
			)
			(layer "F.Fab")
		)
		(fp_line
			(start 3.24993 3.24993)
			(end -3.24993 3.24993)
			(stroke
				(width 0.1)
				(type default)
			)
			(layer "F.Fab")
		)
		(fp_line
			(start -3.24993 3.24993)
			(end -3.24993 -3.24993)
			(stroke
				(width 0.1)
				(type default)
			)
			(layer "F.Fab")
		)
		(pad "1" smd rect
			(at -2.29997 0 90)
			(size 2.0066 4.2164)
			(layers "F.Cu" "F.Mask" "F.Paste")
			(net "IND_CPU1_P0_CPL0")
		)
		(pad "2" smd rect
			(at 2.29997 0 90)
			(size 2.0066 4.2164)
			(layers "F.Cu" "F.Mask" "F.Paste")
			(net "GND")
		)
	)
	(footprint ""
		(layer "F.Cu")
		(at 68.98132 -394.5382 -90)
		(property "Reference" "R711"
			(at 0 0 270)
			(layer "F.SilkS")
			(hide yes)
			(effects
				(font
					(size 1.27 1.27)
				)
			)
		)
		(property "Value" ""
			(at 0 0 270)
			(layer "F.Fab")
			(effects
				(font
					(size 1.27 1.27)
				)
			)
		)
		(duplicate_pad_numbers_are_jumpers no)
		(fp_line
			(start -0.32512 0.175006)
			(end -0.32512 -0.175006)
			(stroke
				(width 0.1)
				(type default)
			)
			(layer "F.Fab")
		)
		(fp_line
			(start 0.32512 0.175006)
			(end -0.32512 0.175006)
			(stroke
				(width 0.1)
				(type default)
			)
			(layer "F.Fab")
		)
		(fp_line
			(start -0.32512 -0.175006)
			(end 0.32512 -0.175006)
			(stroke
				(width 0.1)
				(type default)
			)
			(layer "F.Fab")
		)
		(fp_line
			(start 0.32512 -0.175006)
			(end 0.32512 0.175006)
			(stroke
				(width 0.1)
				(type default)
			)
			(layer "F.Fab")
		)
		(pad "1" smd rect
			(at -0.2667 0 270)
			(size 0.3048 0.381)
			(layers "F.Cu" "F.Mask" "F.Paste")
			(net "NCF_A1_CPU1_P0_GND")
		)
		(pad "2" smd rect
			(at 0.2667 0 90)
			(size 0.3048 0.381)
			(layers "F.Cu" "F.Mask" "F.Paste")
			(net "GND")
		)
	)
	(footprint ""
		(layer "F.Cu")
		(at 138.067542 -381.7874)
		(property "Reference" "R1433"
			(at 0 0 0)
			(layer "F.SilkS")
			(hide yes)
			(effects
				(font
					(size 1.27 1.27)
				)
			)
		)
		(property "Value" ""
			(at 0 0 0)
			(layer "F.Fab")
			(effects
				(font
					(size 1.27 1.27)
				)
			)
		)
		(duplicate_pad_numbers_are_jumpers no)
		(fp_line
			(start -0.32512 -0.175006)
			(end 0.32512 -0.175006)
			(stroke
				(width 0.1)
				(type default)
			)
			(layer "F.Fab")
		)
		(fp_line
			(start -0.32512 0.175006)
			(end -0.32512 -0.175006)
			(stroke
				(width 0.1)
				(type default)
			)
			(layer "F.Fab")
		)
		(fp_line
			(start 0.32512 -0.175006)
			(end 0.32512 0.175006)
			(stroke
				(width 0.1)
				(type default)
			)
			(layer "F.Fab")
		)
		(fp_line
			(start 0.32512 0.175006)
			(end -0.32512 0.175006)
			(stroke
				(width 0.1)
				(type default)
			)
			(layer "F.Fab")
		)
		(pad "1" smd rect
			(at -0.2667 0)
			(size 0.3048 0.381)
			(layers "F.Cu" "F.Mask" "F.Paste")
			(net "CLKREQ_RT_CPU1_P3_N")
		)
		(pad "2" smd rect
			(at 0.2667 0 180)
			(size 0.3048 0.381)
			(layers "F.Cu" "F.Mask" "F.Paste")
			(net "GND")
		)
	)
	(footprint ""
		(layer "F.Cu")
		(at 124.840238 -43.59275)
		(property "Reference" "R6278"
			(at 0 0 0)
			(layer "F.SilkS")
			(hide yes)
			(effects
				(font
					(size 1.27 1.27)
				)
			)
		)
		(property "Value" ""
			(at 0 0 0)
			(layer "F.Fab")
			(effects
				(font
					(size 1.27 1.27)
				)
			)
		)
		(duplicate_pad_numbers_are_jumpers no)
		(fp_line
			(start -0.7874 -0.4064)
			(end 0.7874 -0.4064)
			(stroke
				(width 0.1524)
				(type default)
			)
			(layer "F.SilkS")
		)
		(fp_line
			(start -0.7874 0.4064)
			(end -0.7874 -0.4064)
			(stroke
				(width 0.1524)
				(type default)
			)
			(layer "F.SilkS")
		)
		(fp_line
			(start 0.7874 -0.4064)
			(end 0.7874 0.4064)
			(stroke
				(width 0.1524)
				(type default)
			)
			(layer "F.SilkS")
		)
		(fp_line
			(start 0.7874 0.4064)
			(end -0.7874 0.4064)
			(stroke
				(width 0.1524)
				(type default)
			)
			(layer "F.SilkS")
		)
		(fp_line
			(start -0.67945 -0.305054)
			(end -0.12065 -0.305054)
			(stroke
				(width 0.1)
				(type default)
			)
			(layer "F.Fab")
		)
		(fp_line
			(start -0.67945 0.3048)
			(end -0.67945 -0.305054)
			(stroke
				(width 0.1)
				(type default)
			)
			(layer "F.Fab")
		)
		(fp_line
			(start -0.12065 -0.305054)
			(end -0.12065 -0.2794)
			(stroke
				(width 0.1)
				(type default)
			)
			(layer "F.Fab")
		)
		(fp_line
			(start -0.12065 -0.2794)
			(end 0.12065 -0.2794)
			(stroke
				(width 0.1)
				(type default)
			)
			(layer "F.Fab")
		)
		(fp_line
			(start -0.12065 0.2794)
			(end -0.12065 0.3048)
			(stroke
				(width 0.1)
				(type default)
			)
			(layer "F.Fab")
		)
		(fp_line
			(start -0.12065 0.3048)
			(end -0.67945 0.3048)
			(stroke
				(width 0.1)
				(type default)
			)
			(layer "F.Fab")
		)
		(fp_line
			(start 0.120396 0.2794)
			(end -0.12065 0.2794)
			(stroke
				(width 0.1)
				(type default)
			)
			(layer "F.Fab")
		)
		(fp_line
			(start 0.120396 0.3048)
			(end 0.120396 0.2794)
			(stroke
				(width 0.1)
				(type default)
			)
			(layer "F.Fab")
		)
		(fp_line
			(start 0.12065 -0.3048)
			(end 0.67945 -0.3048)
			(stroke
				(width 0.1)
				(type default)
			)
			(layer "F.Fab")
		)
		(fp_line
			(start 0.12065 -0.2794)
			(end 0.12065 -0.3048)
			(stroke
				(width 0.1)
				(type default)
			)
			(layer "F.Fab")
		)
		(fp_line
			(start 0.67945 -0.3048)
			(end 0.67945 0.3048)
			(stroke
				(width 0.1)
				(type default)
			)
			(layer "F.Fab")
		)
		(fp_line
			(start 0.67945 0.3048)
			(end 0.120396 0.3048)
			(stroke
				(width 0.1)
				(type default)
			)
			(layer "F.Fab")
		)
		(pad "1" smd circle
			(at -0.40005 0)
			(size 0 0)
			(layers "F.Cu" "F.Mask" "F.Paste")
			(net "USB_HUB2_MRP_PRT_CTL4_GANGPWR")
		)
		(pad "2" smd circle
			(at 0.40005 0)
			(size 0 0)
			(layers "F.Cu" "F.Mask" "F.Paste")
			(net "GND")
		)
	)
	(footprint ""
		(layer "F.Cu")
		(at 413.273748 -16.100298 90)
		(property "Reference" "C1565"
			(at 0 0 90)
			(layer "F.SilkS")
			(hide yes)
			(effects
				(font
					(size 1.27 1.27)
				)
			)
		)
		(property "Value" ""
			(at 0 0 90)
			(layer "F.Fab")
			(effects
				(font
					(size 1.27 1.27)
				)
			)
		)
		(duplicate_pad_numbers_are_jumpers no)
		(fp_line
			(start 0.299974 -0.150114)
			(end 0.299974 0.150114)
			(stroke
				(width 0.1)
				(type default)
			)
			(layer "F.Fab")
		)
		(fp_line
			(start -0.299974 -0.150114)
			(end 0.299974 -0.150114)
			(stroke
				(width 0.1)
				(type default)
			)
			(layer "F.Fab")
		)
		(fp_line
			(start 0.299974 0.150114)
			(end -0.299974 0.150114)
			(stroke
				(width 0.1)
				(type default)
			)
			(layer "F.Fab")
		)
		(fp_line
			(start -0.299974 0.150114)
			(end -0.299974 -0.150114)
			(stroke
				(width 0.1)
				(type default)
			)
			(layer "F.Fab")
		)
		(pad "1" smd rect
			(at -0.2667 0 90)
			(size 0.3048 0.381)
			(layers "F.Cu" "F.Mask" "F.Paste")
			(net "P5E_CPU0_G3_TX_C_DP<7>")
		)
		(pad "2" smd rect
			(at 0.2667 0 90)
			(size 0.3048 0.381)
			(layers "F.Cu" "F.Mask" "F.Paste")
			(net "P5E_CPU0_G3_TX_DP<7>")
		)
	)
	(footprint ""
		(layer "F.Cu")
		(at 195.961 -100.294948 90)
		(property "Reference" "R2261"
			(at 0 0 90)
			(layer "F.SilkS")
			(hide yes)
			(effects
				(font
					(size 1.27 1.27)
				)
			)
		)
		(property "Value" ""
			(at 0 0 90)
			(layer "F.Fab")
			(effects
				(font
					(size 1.27 1.27)
				)
			)
		)
		(duplicate_pad_numbers_are_jumpers no)
		(fp_line
			(start 0.7874 -0.4064)
			(end 0.7874 0.4064)
			(stroke
				(width 0.1524)
				(type default)
			)
			(layer "F.SilkS")
		)
		(fp_line
			(start -0.7874 -0.4064)
			(end 0.7874 -0.4064)
			(stroke
				(width 0.1524)
				(type default)
			)
			(layer "F.SilkS")
		)
		(fp_line
			(start 0.7874 0.4064)
			(end -0.7874 0.4064)
			(stroke
				(width 0.1524)
				(type default)
			)
			(layer "F.SilkS")
		)
		(fp_line
			(start -0.7874 0.4064)
			(end -0.7874 -0.4064)
			(stroke
				(width 0.1524)
				(type default)
			)
			(layer "F.SilkS")
		)
		(fp_line
			(start -0.12065 -0.305054)
			(end -0.12065 -0.2794)
			(stroke
				(width 0.1)
				(type default)
			)
			(layer "F.Fab")
		)
		(fp_line
			(start -0.67945 -0.305054)
			(end -0.12065 -0.305054)
			(stroke
				(width 0.1)
				(type default)
			)
			(layer "F.Fab")
		)
		(fp_line
			(start 0.67945 -0.3048)
			(end 0.67945 0.3048)
			(stroke
				(width 0.1)
				(type default)
			)
			(layer "F.Fab")
		)
		(fp_line
			(start 0.12065 -0.3048)
			(end 0.67945 -0.3048)
			(stroke
				(width 0.1)
				(type default)
			)
			(layer "F.Fab")
		)
		(fp_line
			(start 0.12065 -0.2794)
			(end 0.12065 -0.3048)
			(stroke
				(width 0.1)
				(type default)
			)
			(layer "F.Fab")
		)
		(fp_line
			(start -0.12065 -0.2794)
			(end 0.12065 -0.2794)
			(stroke
				(width 0.1)
				(type default)
			)
			(layer "F.Fab")
		)
		(fp_line
			(start 0.120396 0.2794)
			(end -0.12065 0.2794)
			(stroke
				(width 0.1)
				(type default)
			)
			(layer "F.Fab")
		)
		(fp_line
			(start -0.12065 0.2794)
			(end -0.12065 0.3048)
			(stroke
				(width 0.1)
				(type default)
			)
			(layer "F.Fab")
		)
		(fp_line
			(start 0.67945 0.3048)
			(end 0.120396 0.3048)
			(stroke
				(width 0.1)
				(type default)
			)
			(layer "F.Fab")
		)
		(fp_line
			(start 0.120396 0.3048)
			(end 0.120396 0.2794)
			(stroke
				(width 0.1)
				(type default)
			)
			(layer "F.Fab")
		)
		(fp_line
			(start -0.12065 0.3048)
			(end -0.67945 0.3048)
			(stroke
				(width 0.1)
				(type default)
			)
			(layer "F.Fab")
		)
		(fp_line
			(start -0.67945 0.3048)
			(end -0.67945 -0.305054)
			(stroke
				(width 0.1)
				(type default)
			)
			(layer "F.Fab")
		)
		(pad "1" smd circle
			(at -0.40005 0 90)
			(size 0 0)
			(layers "F.Cu" "F.Mask" "F.Paste")
			(net "FM_SWB_PWR_EN_R")
		)
		(pad "2" smd circle
			(at 0.40005 0 90)
			(size 0 0)
			(layers "F.Cu" "F.Mask" "F.Paste")
			(net "FM_SWB_PWR_EN")
		)
	)
	(footprint ""
		(layer "F.Cu")
		(at 191.52362 -422.804082 90)
		(property "Reference" "R2944"
			(at 0 0 90)
			(layer "F.SilkS")
			(hide yes)
			(effects
				(font
					(size 1.27 1.27)
				)
			)
		)
		(property "Value" ""
			(at 0 0 90)
			(layer "F.Fab")
			(effects
				(font
					(size 1.27 1.27)
				)
			)
		)
		(duplicate_pad_numbers_are_jumpers no)
		(fp_line
			(start 0.7874 -0.4064)
			(end 0.7874 0.4064)
			(stroke
				(width 0.1524)
				(type default)
			)
			(layer "F.SilkS")
		)
		(fp_line
			(start -0.7874 -0.4064)
			(end 0.7874 -0.4064)
			(stroke
				(width 0.1524)
				(type default)
			)
			(layer "F.SilkS")
		)
		(fp_line
			(start 0.7874 0.4064)
			(end -0.7874 0.4064)
			(stroke
				(width 0.1524)
				(type default)
			)
			(layer "F.SilkS")
		)
		(fp_line
			(start -0.7874 0.4064)
			(end -0.7874 -0.4064)
			(stroke
				(width 0.1524)
				(type default)
			)
			(layer "F.SilkS")
		)
		(fp_line
			(start -0.12065 -0.305054)
			(end -0.12065 -0.2794)
			(stroke
				(width 0.1)
				(type default)
			)
			(layer "F.Fab")
		)
		(fp_line
			(start -0.67945 -0.305054)
			(end -0.12065 -0.305054)
			(stroke
				(width 0.1)
				(type default)
			)
			(layer "F.Fab")
		)
		(fp_line
			(start 0.67945 -0.3048)
			(end 0.67945 0.3048)
			(stroke
				(width 0.1)
				(type default)
			)
			(layer "F.Fab")
		)
		(fp_line
			(start 0.12065 -0.3048)
			(end 0.67945 -0.3048)
			(stroke
				(width 0.1)
				(type default)
			)
			(layer "F.Fab")
		)
		(fp_line
			(start 0.12065 -0.2794)
			(end 0.12065 -0.3048)
			(stroke
				(width 0.1)
				(type default)
			)
			(layer "F.Fab")
		)
		(fp_line
			(start -0.12065 -0.2794)
			(end 0.12065 -0.2794)
			(stroke
				(width 0.1)
				(type default)
			)
			(layer "F.Fab")
		)
		(fp_line
			(start 0.120396 0.2794)
			(end -0.12065 0.2794)
			(stroke
				(width 0.1)
				(type default)
			)
			(layer "F.Fab")
		)
		(fp_line
			(start -0.12065 0.2794)
			(end -0.12065 0.3048)
			(stroke
				(width 0.1)
				(type default)
			)
			(layer "F.Fab")
		)
		(fp_line
			(start 0.67945 0.3048)
			(end 0.120396 0.3048)
			(stroke
				(width 0.1)
				(type default)
			)
			(layer "F.Fab")
		)
		(fp_line
			(start 0.120396 0.3048)
			(end 0.120396 0.2794)
			(stroke
				(width 0.1)
				(type default)
			)
			(layer "F.Fab")
		)
		(fp_line
			(start -0.12065 0.3048)
			(end -0.67945 0.3048)
			(stroke
				(width 0.1)
				(type default)
			)
			(layer "F.Fab")
		)
		(fp_line
			(start -0.67945 0.3048)
			(end -0.67945 -0.305054)
			(stroke
				(width 0.1)
				(type default)
			)
			(layer "F.Fab")
		)
		(pad "1" smd circle
			(at -0.40005 0 90)
			(size 0 0)
			(layers "F.Cu" "F.Mask" "F.Paste")
			(net "FM_GPU_HSC_EN_BUF_R")
		)
		(pad "2" smd circle
			(at 0.40005 0 90)
			(size 0 0)
			(layers "F.Cu" "F.Mask" "F.Paste")
			(net "FM_GPU_HSC_EN_BUF")
		)
	)
	(footprint ""
		(layer "F.Cu")
		(at 175.961294 -332.734412 -90)
		(property "Reference" "PC803"
			(at -4.13512 4.721352 90)
			(unlocked yes)
			(layer "F.SilkS")
			(effects
				(font
					(size 0.7874 0.5842)
					(thickness 0.1524)
				)
				(justify left)
			)
		)
		(property "Value" ""
			(at 0 0 270)
			(layer "F.Fab")
			(effects
				(font
					(size 1.27 1.27)
				)
			)
		)
		(duplicate_pad_numbers_are_jumpers no)
		(fp_line
			(start -1.988058 2.750058)
			(end 2.750058 2.750058)
			(stroke
				(width 0.1524)
				(type default)
			)
			(layer "F.SilkS")
		)
		(fp_line
			(start 2.750058 2.750058)
			(end 2.750058 0.9398)
			(stroke
				(width 0.1524)
				(type default)
			)
			(layer "F.SilkS")
		)
		(fp_line
			(start -2.750058 1.988058)
			(end -1.988058 2.750058)
			(stroke
				(width 0.1524)
				(type default)
			)
			(layer "F.SilkS")
		)
		(fp_line
			(start -2.750058 0.9398)
			(end -2.750058 1.988058)
			(stroke
				(width 0.1524)
				(type default)
			)
			(layer "F.SilkS")
		)
		(fp_line
			(start 2.750058 -0.9398)
			(end 2.750058 -2.750058)
			(stroke
				(width 0.1524)
				(type default)
			)
			(layer "F.SilkS")
		)
		(fp_line
			(start -2.750058 -1.988058)
			(end -2.750058 -0.9398)
			(stroke
				(width 0.1524)
				(type default)
			)
			(layer "F.SilkS")
		)
		(fp_line
			(start -1.988058 -2.750058)
			(end -2.750058 -1.988058)
			(stroke
				(width 0.1524)
				(type default)
			)
			(layer "F.SilkS")
		)
		(fp_line
			(start 2.750058 -2.750058)
			(end -1.988058 -2.750058)
			(stroke
				(width 0.1524)
				(type default)
			)
			(layer "F.SilkS")
		)
		(fp_line
			(start -2.750058 2.750058)
			(end 2.750058 2.750058)
			(stroke
				(width 0.1)
				(type default)
			)
			(layer "F.Fab")
		)
		(fp_line
			(start 2.750058 2.750058)
			(end 2.750058 -2.750058)
			(stroke
				(width 0.1)
				(type default)
			)
			(layer "F.Fab")
		)
		(fp_line
			(start -2.750058 -2.750058)
			(end -2.750058 2.750058)
			(stroke
				(width 0.1)
				(type default)
			)
			(layer "F.Fab")
		)
		(fp_line
			(start 2.750058 -2.750058)
			(end -2.750058 -2.750058)
			(stroke
				(width 0.1)
				(type default)
			)
			(layer "F.Fab")
		)
		(pad "1" smd rect
			(at -2.199894 0)
			(size 1.6002 3.0226)
			(layers "F.Cu" "F.Mask" "F.Paste")
			(net "PVDD11_S3_P1")
		)
		(pad "2" smd rect
			(at 2.199894 0)
			(size 1.6002 3.0226)
			(layers "F.Cu" "F.Mask" "F.Paste")
			(net "GND")
		)
	)
	(footprint ""
		(layer "F.Cu")
		(at 279.022556 -438.001664 -90)
		(property "Reference" "R4551"
			(at 0 0 270)
			(layer "F.SilkS")
			(hide yes)
			(effects
				(font
					(size 1.27 1.27)
				)
			)
		)
		(property "Value" ""
			(at 0 0 270)
			(layer "F.Fab")
			(effects
				(font
					(size 1.27 1.27)
				)
			)
		)
		(duplicate_pad_numbers_are_jumpers no)
		(fp_line
			(start -0.7874 0.4064)
			(end -0.7874 -0.4064)
			(stroke
				(width 0.1524)
				(type default)
			)
			(layer "F.SilkS")
		)
		(fp_line
			(start 0.7874 0.4064)
			(end -0.7874 0.4064)
			(stroke
				(width 0.1524)
				(type default)
			)
			(layer "F.SilkS")
		)
		(fp_line
			(start -0.7874 -0.4064)
			(end 0.7874 -0.4064)
			(stroke
				(width 0.1524)
				(type default)
			)
			(layer "F.SilkS")
		)
		(fp_line
			(start 0.7874 -0.4064)
			(end 0.7874 0.4064)
			(stroke
				(width 0.1524)
				(type default)
			)
			(layer "F.SilkS")
		)
		(fp_line
			(start -0.67945 0.3048)
			(end -0.67945 -0.305054)
			(stroke
				(width 0.1)
				(type default)
			)
			(layer "F.Fab")
		)
		(fp_line
			(start -0.12065 0.3048)
			(end -0.67945 0.3048)
			(stroke
				(width 0.1)
				(type default)
			)
			(layer "F.Fab")
		)
		(fp_line
			(start 0.120396 0.3048)
			(end 0.120396 0.2794)
			(stroke
				(width 0.1)
				(type default)
			)
			(layer "F.Fab")
		)
		(fp_line
			(start 0.67945 0.3048)
			(end 0.120396 0.3048)
			(stroke
				(width 0.1)
				(type default)
			)
			(layer "F.Fab")
		)
		(fp_line
			(start -0.12065 0.2794)
			(end -0.12065 0.3048)
			(stroke
				(width 0.1)
				(type default)
			)
			(layer "F.Fab")
		)
		(fp_line
			(start 0.120396 0.2794)
			(end -0.12065 0.2794)
			(stroke
				(width 0.1)
				(type default)
			)
			(layer "F.Fab")
		)
		(fp_line
			(start -0.12065 -0.2794)
			(end 0.12065 -0.2794)
			(stroke
				(width 0.1)
				(type default)
			)
			(layer "F.Fab")
		)
		(fp_line
			(start 0.12065 -0.2794)
			(end 0.12065 -0.3048)
			(stroke
				(width 0.1)
				(type default)
			)
			(layer "F.Fab")
		)
		(fp_line
			(start 0.12065 -0.3048)
			(end 0.67945 -0.3048)
			(stroke
				(width 0.1)
				(type default)
			)
			(layer "F.Fab")
		)
		(fp_line
			(start 0.67945 -0.3048)
			(end 0.67945 0.3048)
			(stroke
				(width 0.1)
				(type default)
			)
			(layer "F.Fab")
		)
		(fp_line
			(start -0.67945 -0.305054)
			(end -0.12065 -0.305054)
			(stroke
				(width 0.1)
				(type default)
			)
			(layer "F.Fab")
		)
		(fp_line
			(start -0.12065 -0.305054)
			(end -0.12065 -0.2794)
			(stroke
				(width 0.1)
				(type default)
			)
			(layer "F.Fab")
		)
		(pad "1" smd circle
			(at -0.40005 0 270)
			(size 0 0)
			(layers "F.Cu" "F.Mask" "F.Paste")
			(net "P3V3_AUX")
		)
		(pad "2" smd circle
			(at 0.40005 0 270)
			(size 0 0)
			(layers "F.Cu" "F.Mask" "F.Paste")
			(net "HPDB_HSC_PWRGD")
		)
	)
	(footprint ""
		(layer "F.Cu")
		(at 60.021724 -408.517344 -90)
		(property "Reference" "C6638"
			(at 0 0 270)
			(layer "F.SilkS")
			(hide yes)
			(effects
				(font
					(size 1.27 1.27)
				)
			)
		)
		(property "Value" ""
			(at 0 0 270)
			(layer "F.Fab")
			(effects
				(font
					(size 1.27 1.27)
				)
			)
		)
		(duplicate_pad_numbers_are_jumpers no)
		(fp_line
			(start -0.299974 0.150114)
			(end -0.299974 -0.150114)
			(stroke
				(width 0.1)
				(type default)
			)
			(layer "F.Fab")
		)
		(fp_line
			(start 0.299974 0.150114)
			(end -0.299974 0.150114)
			(stroke
				(width 0.1)
				(type default)
			)
			(layer "F.Fab")
		)
		(fp_line
			(start -0.299974 -0.150114)
			(end 0.299974 -0.150114)
			(stroke
				(width 0.1)
				(type default)
			)
			(layer "F.Fab")
		)
		(fp_line
			(start 0.299974 -0.150114)
			(end 0.299974 0.150114)
			(stroke
				(width 0.1)
				(type default)
			)
			(layer "F.Fab")
		)
		(pad "1" smd rect
			(at -0.2667 0 270)
			(size 0.3048 0.381)
			(layers "F.Cu" "F.Mask" "F.Paste")
			(net "P5E_CPU1_P0_TX_BUF_C_DN<4>")
		)
		(pad "2" smd rect
			(at 0.2667 0 270)
			(size 0.3048 0.381)
			(layers "F.Cu" "F.Mask" "F.Paste")
			(net "P5E_CPU1_P0_TX_BUF_DN<4>")
		)
	)
	(footprint ""
		(layer "F.Cu")
		(at 448.799966 -435.59984)
		(property "Reference" "H90"
			(at -2.943352 -3.737864 0)
			(unlocked yes)
			(layer "F.SilkS")
			(effects
				(font
					(size 0.7874 0.5842)
					(thickness 0.1524)
				)
				(justify left)
			)
		)
		(property "Value" ""
			(at 0 0 0)
			(layer "F.Fab")
			(effects
				(font
					(size 1.27 1.27)
				)
			)
		)
		(duplicate_pad_numbers_are_jumpers no)
		(fp_circle
			(center 0 0)
			(end 2.6289 0)
			(stroke
				(width 0.1524)
				(type default)
			)
			(fill no)
			(layer "F.SilkS")
		)
		(fp_circle
			(center 0 0)
			(end 2.6289 0)
			(stroke
				(width 0.1524)
				(type default)
			)
			(fill no)
			(layer "B.SilkS")
		)
		(fp_circle
			(center 0 0)
			(end 2.6289 0)
			(stroke
				(width 0.1)
				(type default)
			)
			(fill no)
			(layer "B.Fab")
		)
		(fp_circle
			(center 0 0)
			(end 2.6289 0)
			(stroke
				(width 0.1)
				(type default)
			)
			(fill no)
			(layer "F.Fab")
		)
		(pad "" np_thru_hole circle
			(at 0 0)
			(size 3.0988 3.0988)
			(drill 3.0988)
			(layers "*.Cu" "*.Mask")
			(clearance 0.254)
			(thermal_gap 0.254)
		)
		(zone
			(layers "F.Cu" "B.Cu" "In1.Cu" "In2.Cu" "In3.Cu" "In4.Cu" "In5.Cu" "In6.Cu"
				"In7.Cu" "In8.Cu" "In9.Cu" "In10.Cu" "In11.Cu" "In12.Cu" "In13.Cu" "In14.Cu"
				"In15.Cu" "In16.Cu"
			)
			(hatch none 0.5)
			(connect_pads
				(clearance 0)
			)
			(min_thickness 0.25)
			(keepout
				(tracks not_allowed)
				(vias allowed)
				(pads allowed)
				(copperpour not_allowed)
				(footprints allowed)
			)
			(placement
				(enabled no)
				(sheetname "")
			)
			(fill
				(thermal_gap 0.5)
				(thermal_bridge_width 0.5)
				(island_removal_mode 0)
			)
			(polygon
				(pts
					(arc
						(start 450.857366 -435.59984)
						(mid 446.742566 -435.59984)
						(end 450.857366 -435.59984)
					)
				)
			)
		)
	)
	(footprint ""
		(layer "F.Cu")
		(at 226.0981 -408.084782)
		(property "Reference" "PR3989"
			(at 0 0 0)
			(layer "F.SilkS")
			(hide yes)
			(effects
				(font
					(size 1.27 1.27)
				)
			)
		)
		(property "Value" ""
			(at 0 0 0)
			(layer "F.Fab")
			(effects
				(font
					(size 1.27 1.27)
				)
			)
		)
		(duplicate_pad_numbers_are_jumpers no)
		(fp_line
			(start -0.7874 -0.4064)
			(end 0.7874 -0.4064)
			(stroke
				(width 0.1524)
				(type default)
			)
			(layer "F.SilkS")
		)
		(fp_line
			(start -0.7874 0.4064)
			(end -0.7874 -0.4064)
			(stroke
				(width 0.1524)
				(type default)
			)
			(layer "F.SilkS")
		)
		(fp_line
			(start 0.7874 -0.4064)
			(end 0.7874 0.4064)
			(stroke
				(width 0.1524)
				(type default)
			)
			(layer "F.SilkS")
		)
		(fp_line
			(start 0.7874 0.4064)
			(end -0.7874 0.4064)
			(stroke
				(width 0.1524)
				(type default)
			)
			(layer "F.SilkS")
		)
		(fp_line
			(start -0.67945 -0.305054)
			(end -0.12065 -0.305054)
			(stroke
				(width 0.1)
				(type default)
			)
			(layer "F.Fab")
		)
		(fp_line
			(start -0.67945 0.3048)
			(end -0.67945 -0.305054)
			(stroke
				(width 0.1)
				(type default)
			)
			(layer "F.Fab")
		)
		(fp_line
			(start -0.12065 -0.305054)
			(end -0.12065 -0.2794)
			(stroke
				(width 0.1)
				(type default)
			)
			(layer "F.Fab")
		)
		(fp_line
			(start -0.12065 -0.2794)
			(end 0.12065 -0.2794)
			(stroke
				(width 0.1)
				(type default)
			)
			(layer "F.Fab")
		)
		(fp_line
			(start -0.12065 0.2794)
			(end -0.12065 0.3048)
			(stroke
				(width 0.1)
				(type default)
			)
			(layer "F.Fab")
		)
		(fp_line
			(start -0.12065 0.3048)
			(end -0.67945 0.3048)
			(stroke
				(width 0.1)
				(type default)
			)
			(layer "F.Fab")
		)
		(fp_line
			(start 0.120396 0.2794)
			(end -0.12065 0.2794)
			(stroke
				(width 0.1)
				(type default)
			)
			(layer "F.Fab")
		)
		(fp_line
			(start 0.120396 0.3048)
			(end 0.120396 0.2794)
			(stroke
				(width 0.1)
				(type default)
			)
			(layer "F.Fab")
		)
		(fp_line
			(start 0.12065 -0.3048)
			(end 0.67945 -0.3048)
			(stroke
				(width 0.1)
				(type default)
			)
			(layer "F.Fab")
		)
		(fp_line
			(start 0.12065 -0.2794)
			(end 0.12065 -0.3048)
			(stroke
				(width 0.1)
				(type default)
			)
			(layer "F.Fab")
		)
		(fp_line
			(start 0.67945 -0.3048)
			(end 0.67945 0.3048)
			(stroke
				(width 0.1)
				(type default)
			)
			(layer "F.Fab")
		)
		(fp_line
			(start 0.67945 0.3048)
			(end 0.120396 0.3048)
			(stroke
				(width 0.1)
				(type default)
			)
			(layer "F.Fab")
		)
		(pad "1" smd circle
			(at -0.40005 0)
			(size 0 0)
			(layers "F.Cu" "F.Mask" "F.Paste")
			(net "HSC_SCREF")
		)
		(pad "2" smd circle
			(at 0.40005 0)
			(size 0 0)
			(layers "F.Cu" "F.Mask" "F.Paste")
			(net "HSC_SCREF_4")
		)
	)
	(footprint ""
		(layer "F.Cu")
		(at 366.534446 -30.084522 -90)
		(property "Reference" "R818"
			(at 0 0 270)
			(layer "F.SilkS")
			(hide yes)
			(effects
				(font
					(size 1.27 1.27)
				)
			)
		)
		(property "Value" ""
			(at 0 0 270)
			(layer "F.Fab")
			(effects
				(font
					(size 1.27 1.27)
				)
			)
		)
		(duplicate_pad_numbers_are_jumpers no)
		(fp_line
			(start -0.7874 0.4064)
			(end -0.7874 -0.4064)
			(stroke
				(width 0.1524)
				(type default)
			)
			(layer "F.SilkS")
		)
		(fp_line
			(start 0.7874 0.4064)
			(end -0.7874 0.4064)
			(stroke
				(width 0.1524)
				(type default)
			)
			(layer "F.SilkS")
		)
		(fp_line
			(start -0.7874 -0.4064)
			(end 0.7874 -0.4064)
			(stroke
				(width 0.1524)
				(type default)
			)
			(layer "F.SilkS")
		)
		(fp_line
			(start 0.7874 -0.4064)
			(end 0.7874 0.4064)
			(stroke
				(width 0.1524)
				(type default)
			)
			(layer "F.SilkS")
		)
		(fp_line
			(start -0.67945 0.3048)
			(end -0.67945 -0.305054)
			(stroke
				(width 0.1)
				(type default)
			)
			(layer "F.Fab")
		)
		(fp_line
			(start -0.12065 0.3048)
			(end -0.67945 0.3048)
			(stroke
				(width 0.1)
				(type default)
			)
			(layer "F.Fab")
		)
		(fp_line
			(start 0.120396 0.3048)
			(end 0.120396 0.2794)
			(stroke
				(width 0.1)
				(type default)
			)
			(layer "F.Fab")
		)
		(fp_line
			(start 0.67945 0.3048)
			(end 0.120396 0.3048)
			(stroke
				(width 0.1)
				(type default)
			)
			(layer "F.Fab")
		)
		(fp_line
			(start -0.12065 0.2794)
			(end -0.12065 0.3048)
			(stroke
				(width 0.1)
				(type default)
			)
			(layer "F.Fab")
		)
		(fp_line
			(start 0.120396 0.2794)
			(end -0.12065 0.2794)
			(stroke
				(width 0.1)
				(type default)
			)
			(layer "F.Fab")
		)
		(fp_line
			(start -0.12065 -0.2794)
			(end 0.12065 -0.2794)
			(stroke
				(width 0.1)
				(type default)
			)
			(layer "F.Fab")
		)
		(fp_line
			(start 0.12065 -0.2794)
			(end 0.12065 -0.3048)
			(stroke
				(width 0.1)
				(type default)
			)
			(layer "F.Fab")
		)
		(fp_line
			(start 0.12065 -0.3048)
			(end 0.67945 -0.3048)
			(stroke
				(width 0.1)
				(type default)
			)
			(layer "F.Fab")
		)
		(fp_line
			(start 0.67945 -0.3048)
			(end 0.67945 0.3048)
			(stroke
				(width 0.1)
				(type default)
			)
			(layer "F.Fab")
		)
		(fp_line
			(start -0.67945 -0.305054)
			(end -0.12065 -0.305054)
			(stroke
				(width 0.1)
				(type default)
			)
			(layer "F.Fab")
		)
		(fp_line
			(start -0.12065 -0.305054)
			(end -0.12065 -0.2794)
			(stroke
				(width 0.1)
				(type default)
			)
			(layer "F.Fab")
		)
		(pad "1" smd circle
			(at -0.40005 0 270)
			(size 0 0)
			(layers "F.Cu" "F.Mask" "F.Paste")
			(net "UART_CPU0_LVC3_UART0_R_TX")
		)
		(pad "2" smd circle
			(at 0.40005 0 270)
			(size 0 0)
			(layers "F.Cu" "F.Mask" "F.Paste")
			(net "UART_CPU0_LVC3_UART0_TX")
		)
	)
	(footprint ""
		(layer "F.Cu")
		(at 366.36579 -392.1252)
		(property "Reference" "R1120"
			(at 0 0 0)
			(layer "F.SilkS")
			(hide yes)
			(effects
				(font
					(size 1.27 1.27)
				)
			)
		)
		(property "Value" ""
			(at 0 0 0)
			(layer "F.Fab")
			(effects
				(font
					(size 1.27 1.27)
				)
			)
		)
		(duplicate_pad_numbers_are_jumpers no)
		(fp_line
			(start -0.32512 -0.175006)
			(end 0.32512 -0.175006)
			(stroke
				(width 0.1)
				(type default)
			)
			(layer "F.Fab")
		)
		(fp_line
			(start -0.32512 0.175006)
			(end -0.32512 -0.175006)
			(stroke
				(width 0.1)
				(type default)
			)
			(layer "F.Fab")
		)
		(fp_line
			(start 0.32512 -0.175006)
			(end 0.32512 0.175006)
			(stroke
				(width 0.1)
				(type default)
			)
			(layer "F.Fab")
		)
		(fp_line
			(start 0.32512 0.175006)
			(end -0.32512 0.175006)
			(stroke
				(width 0.1)
				(type default)
			)
			(layer "F.Fab")
		)
		(pad "1" smd rect
			(at -0.2667 0)
			(size 0.3048 0.381)
			(layers "F.Cu" "F.Mask" "F.Paste")
			(net "TEST2_RT_CPU0_P3")
		)
		(pad "2" smd rect
			(at 0.2667 0 180)
			(size 0.3048 0.381)
			(layers "F.Cu" "F.Mask" "F.Paste")
			(net "GND")
		)
	)
	(footprint ""
		(layer "F.Cu")
		(at 410.846524 -143.872204 90)
		(property "Reference" "PC1847"
			(at 0 0 90)
			(layer "F.SilkS")
			(hide yes)
			(effects
				(font
					(size 1.27 1.27)
				)
			)
		)
		(property "Value" ""
			(at 0 0 90)
			(layer "F.Fab")
			(effects
				(font
					(size 1.27 1.27)
				)
			)
		)
		(duplicate_pad_numbers_are_jumpers no)
		(fp_line
			(start 0.7874 -0.4064)
			(end 0.7874 0.4064)
			(stroke
				(width 0.1524)
				(type default)
			)
			(layer "F.SilkS")
		)
		(fp_line
			(start -0.7874 -0.4064)
			(end 0.7874 -0.4064)
			(stroke
				(width 0.1524)
				(type default)
			)
			(layer "F.SilkS")
		)
		(fp_line
			(start 0.7874 0.4064)
			(end -0.7874 0.4064)
			(stroke
				(width 0.1524)
				(type default)
			)
			(layer "F.SilkS")
		)
		(fp_line
			(start -0.7874 0.4064)
			(end -0.7874 -0.4064)
			(stroke
				(width 0.1524)
				(type default)
			)
			(layer "F.SilkS")
		)
		(fp_line
			(start -0.12065 -0.305054)
			(end -0.12065 -0.2794)
			(stroke
				(width 0.1)
				(type default)
			)
			(layer "F.Fab")
		)
		(fp_line
			(start -0.67945 -0.305054)
			(end -0.12065 -0.305054)
			(stroke
				(width 0.1)
				(type default)
			)
			(layer "F.Fab")
		)
		(fp_line
			(start 0.67945 -0.3048)
			(end 0.67945 0.3048)
			(stroke
				(width 0.1)
				(type default)
			)
			(layer "F.Fab")
		)
		(fp_line
			(start 0.12065 -0.3048)
			(end 0.67945 -0.3048)
			(stroke
				(width 0.1)
				(type default)
			)
			(layer "F.Fab")
		)
		(fp_line
			(start 0.12065 -0.2794)
			(end 0.12065 -0.3048)
			(stroke
				(width 0.1)
				(type default)
			)
			(layer "F.Fab")
		)
		(fp_line
			(start -0.12065 -0.2794)
			(end 0.12065 -0.2794)
			(stroke
				(width 0.1)
				(type default)
			)
			(layer "F.Fab")
		)
		(fp_line
			(start 0.120396 0.2794)
			(end -0.12065 0.2794)
			(stroke
				(width 0.1)
				(type default)
			)
			(layer "F.Fab")
		)
		(fp_line
			(start -0.12065 0.2794)
			(end -0.12065 0.3048)
			(stroke
				(width 0.1)
				(type default)
			)
			(layer "F.Fab")
		)
		(fp_line
			(start 0.67945 0.3048)
			(end 0.120396 0.3048)
			(stroke
				(width 0.1)
				(type default)
			)
			(layer "F.Fab")
		)
		(fp_line
			(start 0.120396 0.3048)
			(end 0.120396 0.2794)
			(stroke
				(width 0.1)
				(type default)
			)
			(layer "F.Fab")
		)
		(fp_line
			(start -0.12065 0.3048)
			(end -0.67945 0.3048)
			(stroke
				(width 0.1)
				(type default)
			)
			(layer "F.Fab")
		)
		(fp_line
			(start -0.67945 0.3048)
			(end -0.67945 -0.305054)
			(stroke
				(width 0.1)
				(type default)
			)
			(layer "F.Fab")
		)
		(pad "1" smd circle
			(at -0.40005 0 90)
			(size 0 0)
			(layers "F.Cu" "F.Mask" "F.Paste")
			(net "SW_P5V_AUX_BST")
		)
		(pad "2" smd circle
			(at 0.40005 0 90)
			(size 0 0)
			(layers "F.Cu" "F.Mask" "F.Paste")
			(net "SW_P5V_AUX_SW")
		)
	)
	(footprint ""
		(layer "F.Cu")
		(at 461.342232 -51.696366 -90)
		(property "Reference" "PR8389"
			(at 0 0 270)
			(layer "F.SilkS")
			(hide yes)
			(effects
				(font
					(size 1.27 1.27)
				)
			)
		)
		(property "Value" ""
			(at 0 0 270)
			(layer "F.Fab")
			(effects
				(font
					(size 1.27 1.27)
				)
			)
		)
		(duplicate_pad_numbers_are_jumpers no)
		(fp_line
			(start -0.7874 0.4064)
			(end -0.7874 -0.4064)
			(stroke
				(width 0.1524)
				(type default)
			)
			(layer "F.SilkS")
		)
		(fp_line
			(start 0.7874 0.4064)
			(end -0.7874 0.4064)
			(stroke
				(width 0.1524)
				(type default)
			)
			(layer "F.SilkS")
		)
		(fp_line
			(start -0.7874 -0.4064)
			(end 0.7874 -0.4064)
			(stroke
				(width 0.1524)
				(type default)
			)
			(layer "F.SilkS")
		)
		(fp_line
			(start 0.7874 -0.4064)
			(end 0.7874 0.4064)
			(stroke
				(width 0.1524)
				(type default)
			)
			(layer "F.SilkS")
		)
		(fp_line
			(start -0.67945 0.3048)
			(end -0.67945 -0.305054)
			(stroke
				(width 0.1)
				(type default)
			)
			(layer "F.Fab")
		)
		(fp_line
			(start -0.12065 0.3048)
			(end -0.67945 0.3048)
			(stroke
				(width 0.1)
				(type default)
			)
			(layer "F.Fab")
		)
		(fp_line
			(start 0.120396 0.3048)
			(end 0.120396 0.2794)
			(stroke
				(width 0.1)
				(type default)
			)
			(layer "F.Fab")
		)
		(fp_line
			(start 0.67945 0.3048)
			(end 0.120396 0.3048)
			(stroke
				(width 0.1)
				(type default)
			)
			(layer "F.Fab")
		)
		(fp_line
			(start -0.12065 0.2794)
			(end -0.12065 0.3048)
			(stroke
				(width 0.1)
				(type default)
			)
			(layer "F.Fab")
		)
		(fp_line
			(start 0.120396 0.2794)
			(end -0.12065 0.2794)
			(stroke
				(width 0.1)
				(type default)
			)
			(layer "F.Fab")
		)
		(fp_line
			(start -0.12065 -0.2794)
			(end 0.12065 -0.2794)
			(stroke
				(width 0.1)
				(type default)
			)
			(layer "F.Fab")
		)
		(fp_line
			(start 0.12065 -0.2794)
			(end 0.12065 -0.3048)
			(stroke
				(width 0.1)
				(type default)
			)
			(layer "F.Fab")
		)
		(fp_line
			(start 0.12065 -0.3048)
			(end 0.67945 -0.3048)
			(stroke
				(width 0.1)
				(type default)
			)
			(layer "F.Fab")
		)
		(fp_line
			(start 0.67945 -0.3048)
			(end 0.67945 0.3048)
			(stroke
				(width 0.1)
				(type default)
			)
			(layer "F.Fab")
		)
		(fp_line
			(start -0.67945 -0.305054)
			(end -0.12065 -0.305054)
			(stroke
				(width 0.1)
				(type default)
			)
			(layer "F.Fab")
		)
		(fp_line
			(start -0.12065 -0.305054)
			(end -0.12065 -0.2794)
			(stroke
				(width 0.1)
				(type default)
			)
			(layer "F.Fab")
		)
		(pad "1" smd circle
			(at -0.40005 0 270)
			(size 0 0)
			(layers "F.Cu" "F.Mask" "F.Paste")
			(net "P3V3_AUX_VDRV")
		)
		(pad "2" smd circle
			(at 0.40005 0 270)
			(size 0 0)
			(layers "F.Cu" "F.Mask" "F.Paste")
			(net "P3V3_AUX_VCC")
		)
	)
	(footprint ""
		(layer "F.Cu")
		(at 184.023 -137.632948 -90)
		(property "Reference" "R1280"
			(at 0 0 270)
			(layer "F.SilkS")
			(hide yes)
			(effects
				(font
					(size 1.27 1.27)
				)
			)
		)
		(property "Value" ""
			(at 0 0 270)
			(layer "F.Fab")
			(effects
				(font
					(size 1.27 1.27)
				)
			)
		)
		(duplicate_pad_numbers_are_jumpers no)
		(fp_line
			(start -0.7874 0.4064)
			(end -0.7874 -0.4064)
			(stroke
				(width 0.1524)
				(type default)
			)
			(layer "F.SilkS")
		)
		(fp_line
			(start 0.7874 0.4064)
			(end -0.7874 0.4064)
			(stroke
				(width 0.1524)
				(type default)
			)
			(layer "F.SilkS")
		)
		(fp_line
			(start -0.7874 -0.4064)
			(end 0.7874 -0.4064)
			(stroke
				(width 0.1524)
				(type default)
			)
			(layer "F.SilkS")
		)
		(fp_line
			(start 0.7874 -0.4064)
			(end 0.7874 0.4064)
			(stroke
				(width 0.1524)
				(type default)
			)
			(layer "F.SilkS")
		)
		(fp_line
			(start -0.67945 0.3048)
			(end -0.67945 -0.305054)
			(stroke
				(width 0.1)
				(type default)
			)
			(layer "F.Fab")
		)
		(fp_line
			(start -0.12065 0.3048)
			(end -0.67945 0.3048)
			(stroke
				(width 0.1)
				(type default)
			)
			(layer "F.Fab")
		)
		(fp_line
			(start 0.120396 0.3048)
			(end 0.120396 0.2794)
			(stroke
				(width 0.1)
				(type default)
			)
			(layer "F.Fab")
		)
		(fp_line
			(start 0.67945 0.3048)
			(end 0.120396 0.3048)
			(stroke
				(width 0.1)
				(type default)
			)
			(layer "F.Fab")
		)
		(fp_line
			(start -0.12065 0.2794)
			(end -0.12065 0.3048)
			(stroke
				(width 0.1)
				(type default)
			)
			(layer "F.Fab")
		)
		(fp_line
			(start 0.120396 0.2794)
			(end -0.12065 0.2794)
			(stroke
				(width 0.1)
				(type default)
			)
			(layer "F.Fab")
		)
		(fp_line
			(start -0.12065 -0.2794)
			(end 0.12065 -0.2794)
			(stroke
				(width 0.1)
				(type default)
			)
			(layer "F.Fab")
		)
		(fp_line
			(start 0.12065 -0.2794)
			(end 0.12065 -0.3048)
			(stroke
				(width 0.1)
				(type default)
			)
			(layer "F.Fab")
		)
		(fp_line
			(start 0.12065 -0.3048)
			(end 0.67945 -0.3048)
			(stroke
				(width 0.1)
				(type default)
			)
			(layer "F.Fab")
		)
		(fp_line
			(start 0.67945 -0.3048)
			(end 0.67945 0.3048)
			(stroke
				(width 0.1)
				(type default)
			)
			(layer "F.Fab")
		)
		(fp_line
			(start -0.67945 -0.305054)
			(end -0.12065 -0.305054)
			(stroke
				(width 0.1)
				(type default)
			)
			(layer "F.Fab")
		)
		(fp_line
			(start -0.12065 -0.305054)
			(end -0.12065 -0.2794)
			(stroke
				(width 0.1)
				(type default)
			)
			(layer "F.Fab")
		)
		(pad "1" smd circle
			(at -0.40005 0 270)
			(size 0 0)
			(layers "F.Cu" "F.Mask" "F.Paste")
			(net "FM_P0_PCC0_N")
		)
		(pad "2" smd circle
			(at 0.40005 0 270)
			(size 0 0)
			(layers "F.Cu" "F.Mask" "F.Paste")
			(net "FM_P0_PCC0_R_N")
		)
	)
	(footprint ""
		(layer "F.Cu")
		(at 45.907706 19.444716 -90)
		(property "Reference" "JP6000_23"
			(at 0 0 270)
			(layer "F.SilkS")
			(hide yes)
			(effects
				(font
					(size 1.27 1.27)
				)
			)
		)
		(property "Value" ""
			(at 0 0 270)
			(layer "F.Fab")
			(effects
				(font
					(size 1.27 1.27)
				)
			)
		)
		(duplicate_pad_numbers_are_jumpers no)
		(pad "1" smd circle
			(at 0 0 270)
			(size 0.762 0.762)
			(layers "F.Cu" "F.Mask" "F.Paste")
			(net "Net_10792")
		)
	)
	(footprint ""
		(layer "F.Cu")
		(at 322.837048 -45.86351)
		(property "Reference" "R3866"
			(at 0 0 0)
			(layer "F.SilkS")
			(hide yes)
			(effects
				(font
					(size 1.27 1.27)
				)
			)
		)
		(property "Value" ""
			(at 0 0 0)
			(layer "F.Fab")
			(effects
				(font
					(size 1.27 1.27)
				)
			)
		)
		(duplicate_pad_numbers_are_jumpers no)
		(fp_line
			(start -0.7874 -0.4064)
			(end 0.7874 -0.4064)
			(stroke
				(width 0.1524)
				(type default)
			)
			(layer "F.SilkS")
		)
		(fp_line
			(start -0.7874 0.4064)
			(end -0.7874 -0.4064)
			(stroke
				(width 0.1524)
				(type default)
			)
			(layer "F.SilkS")
		)
		(fp_line
			(start 0.7874 -0.4064)
			(end 0.7874 0.4064)
			(stroke
				(width 0.1524)
				(type default)
			)
			(layer "F.SilkS")
		)
		(fp_line
			(start 0.7874 0.4064)
			(end -0.7874 0.4064)
			(stroke
				(width 0.1524)
				(type default)
			)
			(layer "F.SilkS")
		)
		(fp_line
			(start -0.67945 -0.305054)
			(end -0.12065 -0.305054)
			(stroke
				(width 0.1)
				(type default)
			)
			(layer "F.Fab")
		)
		(fp_line
			(start -0.67945 0.3048)
			(end -0.67945 -0.305054)
			(stroke
				(width 0.1)
				(type default)
			)
			(layer "F.Fab")
		)
		(fp_line
			(start -0.12065 -0.305054)
			(end -0.12065 -0.2794)
			(stroke
				(width 0.1)
				(type default)
			)
			(layer "F.Fab")
		)
		(fp_line
			(start -0.12065 -0.2794)
			(end 0.12065 -0.2794)
			(stroke
				(width 0.1)
				(type default)
			)
			(layer "F.Fab")
		)
		(fp_line
			(start -0.12065 0.2794)
			(end -0.12065 0.3048)
			(stroke
				(width 0.1)
				(type default)
			)
			(layer "F.Fab")
		)
		(fp_line
			(start -0.12065 0.3048)
			(end -0.67945 0.3048)
			(stroke
				(width 0.1)
				(type default)
			)
			(layer "F.Fab")
		)
		(fp_line
			(start 0.120396 0.2794)
			(end -0.12065 0.2794)
			(stroke
				(width 0.1)
				(type default)
			)
			(layer "F.Fab")
		)
		(fp_line
			(start 0.120396 0.3048)
			(end 0.120396 0.2794)
			(stroke
				(width 0.1)
				(type default)
			)
			(layer "F.Fab")
		)
		(fp_line
			(start 0.12065 -0.3048)
			(end 0.67945 -0.3048)
			(stroke
				(width 0.1)
				(type default)
			)
			(layer "F.Fab")
		)
		(fp_line
			(start 0.12065 -0.2794)
			(end 0.12065 -0.3048)
			(stroke
				(width 0.1)
				(type default)
			)
			(layer "F.Fab")
		)
		(fp_line
			(start 0.67945 -0.3048)
			(end 0.67945 0.3048)
			(stroke
				(width 0.1)
				(type default)
			)
			(layer "F.Fab")
		)
		(fp_line
			(start 0.67945 0.3048)
			(end 0.120396 0.3048)
			(stroke
				(width 0.1)
				(type default)
			)
			(layer "F.Fab")
		)
		(pad "1" smd rect
			(at -0.40005 0 180)
			(size 0.4572 0.508)
			(layers "F.Cu" "F.Mask" "F.Paste")
			(net "P12V_OCP_SFF_ISENSE_MPS_TIC")
		)
		(pad "2" smd rect
			(at 0.40005 0 180)
			(size 0.4572 0.508)
			(layers "F.Cu" "F.Mask" "F.Paste")
			(net "P12V_OCP_SFF_ISENSE_TIC")
		)
	)
	(footprint ""
		(layer "F.Cu")
		(at 413.770572 -159.116014 -90)
		(property "Reference" "PR366"
			(at 0 0 270)
			(layer "F.SilkS")
			(hide yes)
			(effects
				(font
					(size 1.27 1.27)
				)
			)
		)
		(property "Value" ""
			(at 0 0 270)
			(layer "F.Fab")
			(effects
				(font
					(size 1.27 1.27)
				)
			)
		)
		(duplicate_pad_numbers_are_jumpers no)
		(fp_line
			(start -0.7874 0.4064)
			(end -0.7874 -0.4064)
			(stroke
				(width 0.1524)
				(type default)
			)
			(layer "F.SilkS")
		)
		(fp_line
			(start 0.7874 0.4064)
			(end -0.7874 0.4064)
			(stroke
				(width 0.1524)
				(type default)
			)
			(layer "F.SilkS")
		)
		(fp_line
			(start -0.7874 -0.4064)
			(end 0.7874 -0.4064)
			(stroke
				(width 0.1524)
				(type default)
			)
			(layer "F.SilkS")
		)
		(fp_line
			(start 0.7874 -0.4064)
			(end 0.7874 0.4064)
			(stroke
				(width 0.1524)
				(type default)
			)
			(layer "F.SilkS")
		)
		(fp_line
			(start -0.67945 0.3048)
			(end -0.67945 -0.305054)
			(stroke
				(width 0.1)
				(type default)
			)
			(layer "F.Fab")
		)
		(fp_line
			(start -0.12065 0.3048)
			(end -0.67945 0.3048)
			(stroke
				(width 0.1)
				(type default)
			)
			(layer "F.Fab")
		)
		(fp_line
			(start 0.120396 0.3048)
			(end 0.120396 0.2794)
			(stroke
				(width 0.1)
				(type default)
			)
			(layer "F.Fab")
		)
		(fp_line
			(start 0.67945 0.3048)
			(end 0.120396 0.3048)
			(stroke
				(width 0.1)
				(type default)
			)
			(layer "F.Fab")
		)
		(fp_line
			(start -0.12065 0.2794)
			(end -0.12065 0.3048)
			(stroke
				(width 0.1)
				(type default)
			)
			(layer "F.Fab")
		)
		(fp_line
			(start 0.120396 0.2794)
			(end -0.12065 0.2794)
			(stroke
				(width 0.1)
				(type default)
			)
			(layer "F.Fab")
		)
		(fp_line
			(start -0.12065 -0.2794)
			(end 0.12065 -0.2794)
			(stroke
				(width 0.1)
				(type default)
			)
			(layer "F.Fab")
		)
		(fp_line
			(start 0.12065 -0.2794)
			(end 0.12065 -0.3048)
			(stroke
				(width 0.1)
				(type default)
			)
			(layer "F.Fab")
		)
		(fp_line
			(start 0.12065 -0.3048)
			(end 0.67945 -0.3048)
			(stroke
				(width 0.1)
				(type default)
			)
			(layer "F.Fab")
		)
		(fp_line
			(start 0.67945 -0.3048)
			(end 0.67945 0.3048)
			(stroke
				(width 0.1)
				(type default)
			)
			(layer "F.Fab")
		)
		(fp_line
			(start -0.67945 -0.305054)
			(end -0.12065 -0.305054)
			(stroke
				(width 0.1)
				(type default)
			)
			(layer "F.Fab")
		)
		(fp_line
			(start -0.12065 -0.305054)
			(end -0.12065 -0.2794)
			(stroke
				(width 0.1)
				(type default)
			)
			(layer "F.Fab")
		)
		(pad "1" smd circle
			(at -0.40005 0 270)
			(size 0 0)
			(layers "F.Cu" "F.Mask" "F.Paste")
			(net "SW_PVDDCR_SOC_P0_BOOT3")
		)
		(pad "2" smd circle
			(at 0.40005 0 270)
			(size 0 0)
			(layers "F.Cu" "F.Mask" "F.Paste")
			(net "SW_PVDDCR_SOC_P0_BOOT3_RC")
		)
	)
	(footprint ""
		(layer "F.Cu")
		(at 224.21215 -47.612046)
		(property "Reference" "R10287"
			(at 0 0 0)
			(layer "F.SilkS")
			(hide yes)
			(effects
				(font
					(size 1.27 1.27)
				)
			)
		)
		(property "Value" ""
			(at 0 0 0)
			(layer "F.Fab")
			(effects
				(font
					(size 1.27 1.27)
				)
			)
		)
		(duplicate_pad_numbers_are_jumpers no)
		(fp_line
			(start -0.7874 -0.4064)
			(end 0.7874 -0.4064)
			(stroke
				(width 0.1524)
				(type default)
			)
			(layer "F.SilkS")
		)
		(fp_line
			(start -0.7874 0.4064)
			(end -0.7874 -0.4064)
			(stroke
				(width 0.1524)
				(type default)
			)
			(layer "F.SilkS")
		)
		(fp_line
			(start 0.7874 -0.4064)
			(end 0.7874 0.4064)
			(stroke
				(width 0.1524)
				(type default)
			)
			(layer "F.SilkS")
		)
		(fp_line
			(start 0.7874 0.4064)
			(end -0.7874 0.4064)
			(stroke
				(width 0.1524)
				(type default)
			)
			(layer "F.SilkS")
		)
		(fp_line
			(start -0.67945 -0.305054)
			(end -0.12065 -0.305054)
			(stroke
				(width 0.1)
				(type default)
			)
			(layer "F.Fab")
		)
		(fp_line
			(start -0.67945 0.3048)
			(end -0.67945 -0.305054)
			(stroke
				(width 0.1)
				(type default)
			)
			(layer "F.Fab")
		)
		(fp_line
			(start -0.12065 -0.305054)
			(end -0.12065 -0.2794)
			(stroke
				(width 0.1)
				(type default)
			)
			(layer "F.Fab")
		)
		(fp_line
			(start -0.12065 -0.2794)
			(end 0.12065 -0.2794)
			(stroke
				(width 0.1)
				(type default)
			)
			(layer "F.Fab")
		)
		(fp_line
			(start -0.12065 0.2794)
			(end -0.12065 0.3048)
			(stroke
				(width 0.1)
				(type default)
			)
			(layer "F.Fab")
		)
		(fp_line
			(start -0.12065 0.3048)
			(end -0.67945 0.3048)
			(stroke
				(width 0.1)
				(type default)
			)
			(layer "F.Fab")
		)
		(fp_line
			(start 0.120396 0.2794)
			(end -0.12065 0.2794)
			(stroke
				(width 0.1)
				(type default)
			)
			(layer "F.Fab")
		)
		(fp_line
			(start 0.120396 0.3048)
			(end 0.120396 0.2794)
			(stroke
				(width 0.1)
				(type default)
			)
			(layer "F.Fab")
		)
		(fp_line
			(start 0.12065 -0.3048)
			(end 0.67945 -0.3048)
			(stroke
				(width 0.1)
				(type default)
			)
			(layer "F.Fab")
		)
		(fp_line
			(start 0.12065 -0.2794)
			(end 0.12065 -0.3048)
			(stroke
				(width 0.1)
				(type default)
			)
			(layer "F.Fab")
		)
		(fp_line
			(start 0.67945 -0.3048)
			(end 0.67945 0.3048)
			(stroke
				(width 0.1)
				(type default)
			)
			(layer "F.Fab")
		)
		(fp_line
			(start 0.67945 0.3048)
			(end 0.120396 0.3048)
			(stroke
				(width 0.1)
				(type default)
			)
			(layer "F.Fab")
		)
		(pad "1" smd circle
			(at -0.40005 0)
			(size 0 0)
			(layers "F.Cu" "F.Mask" "F.Paste")
			(net "P3V3_E1S_0")
		)
		(pad "2" smd circle
			(at 0.40005 0)
			(size 0 0)
			(layers "F.Cu" "F.Mask" "F.Paste")
			(net "E1S_0_PERST1_CLKREQ_N")
		)
	)
	(footprint ""
		(layer "F.Cu")
		(at 27.686 -434.9623 180)
		(property "Reference" "R2899"
			(at 0 0 180)
			(layer "F.SilkS")
			(hide yes)
			(effects
				(font
					(size 1.27 1.27)
				)
			)
		)
		(property "Value" ""
			(at 0 0 180)
			(layer "F.Fab")
			(effects
				(font
					(size 1.27 1.27)
				)
			)
		)
		(duplicate_pad_numbers_are_jumpers no)
		(fp_line
			(start 0.7874 0.4064)
			(end -0.7874 0.4064)
			(stroke
				(width 0.1524)
				(type default)
			)
			(layer "F.SilkS")
		)
		(fp_line
			(start 0.7874 -0.4064)
			(end 0.7874 0.4064)
			(stroke
				(width 0.1524)
				(type default)
			)
			(layer "F.SilkS")
		)
		(fp_line
			(start -0.7874 0.4064)
			(end -0.7874 -0.4064)
			(stroke
				(width 0.1524)
				(type default)
			)
			(layer "F.SilkS")
		)
		(fp_line
			(start -0.7874 -0.4064)
			(end 0.7874 -0.4064)
			(stroke
				(width 0.1524)
				(type default)
			)
			(layer "F.SilkS")
		)
		(fp_line
			(start 0.67945 0.3048)
			(end 0.120396 0.3048)
			(stroke
				(width 0.1)
				(type default)
			)
			(layer "F.Fab")
		)
		(fp_line
			(start 0.67945 -0.3048)
			(end 0.67945 0.3048)
			(stroke
				(width 0.1)
				(type default)
			)
			(layer "F.Fab")
		)
		(fp_line
			(start 0.12065 -0.2794)
			(end 0.12065 -0.3048)
			(stroke
				(width 0.1)
				(type default)
			)
			(layer "F.Fab")
		)
		(fp_line
			(start 0.12065 -0.3048)
			(end 0.67945 -0.3048)
			(stroke
				(width 0.1)
				(type default)
			)
			(layer "F.Fab")
		)
		(fp_line
			(start 0.120396 0.3048)
			(end 0.120396 0.2794)
			(stroke
				(width 0.1)
				(type default)
			)
			(layer "F.Fab")
		)
		(fp_line
			(start 0.120396 0.2794)
			(end -0.12065 0.2794)
			(stroke
				(width 0.1)
				(type default)
			)
			(layer "F.Fab")
		)
		(fp_line
			(start -0.12065 0.3048)
			(end -0.67945 0.3048)
			(stroke
				(width 0.1)
				(type default)
			)
			(layer "F.Fab")
		)
		(fp_line
			(start -0.12065 0.2794)
			(end -0.12065 0.3048)
			(stroke
				(width 0.1)
				(type default)
			)
			(layer "F.Fab")
		)
		(fp_line
			(start -0.12065 -0.2794)
			(end 0.12065 -0.2794)
			(stroke
				(width 0.1)
				(type default)
			)
			(layer "F.Fab")
		)
		(fp_line
			(start -0.12065 -0.305054)
			(end -0.12065 -0.2794)
			(stroke
				(width 0.1)
				(type default)
			)
			(layer "F.Fab")
		)
		(fp_line
			(start -0.67945 0.3048)
			(end -0.67945 -0.305054)
			(stroke
				(width 0.1)
				(type default)
			)
			(layer "F.Fab")
		)
		(fp_line
			(start -0.67945 -0.305054)
			(end -0.12065 -0.305054)
			(stroke
				(width 0.1)
				(type default)
			)
			(layer "F.Fab")
		)
		(pad "1" smd circle
			(at -0.40005 0 180)
			(size 0 0)
			(layers "F.Cu" "F.Mask" "F.Paste")
			(net "SMB_BMC_GPU_EN")
		)
		(pad "2" smd circle
			(at 0.40005 0 180)
			(size 0 0)
			(layers "F.Cu" "F.Mask" "F.Paste")
			(net "SMB_BMC_GPU_EN_R1")
		)
	)
	(footprint ""
		(layer "F.Cu")
		(at 436.613046 -351.22866 -90)
		(property "Reference" "PC208_2"
			(at 0 0 270)
			(layer "F.SilkS")
			(hide yes)
			(effects
				(font
					(size 1.27 1.27)
				)
			)
		)
		(property "Value" ""
			(at 0 0 270)
			(layer "F.Fab")
			(effects
				(font
					(size 1.27 1.27)
				)
			)
		)
		(duplicate_pad_numbers_are_jumpers no)
		(fp_line
			(start -0.7874 0.4064)
			(end -0.7874 -0.4064)
			(stroke
				(width 0.1524)
				(type default)
			)
			(layer "F.SilkS")
		)
		(fp_line
			(start 0.7874 0.4064)
			(end -0.7874 0.4064)
			(stroke
				(width 0.1524)
				(type default)
			)
			(layer "F.SilkS")
		)
		(fp_line
			(start -0.7874 -0.4064)
			(end 0.7874 -0.4064)
			(stroke
				(width 0.1524)
				(type default)
			)
			(layer "F.SilkS")
		)
		(fp_line
			(start 0.7874 -0.4064)
			(end 0.7874 0.4064)
			(stroke
				(width 0.1524)
				(type default)
			)
			(layer "F.SilkS")
		)
		(fp_line
			(start -0.67945 0.3048)
			(end -0.67945 -0.305054)
			(stroke
				(width 0.1)
				(type default)
			)
			(layer "F.Fab")
		)
		(fp_line
			(start -0.12065 0.3048)
			(end -0.67945 0.3048)
			(stroke
				(width 0.1)
				(type default)
			)
			(layer "F.Fab")
		)
		(fp_line
			(start 0.120396 0.3048)
			(end 0.120396 0.2794)
			(stroke
				(width 0.1)
				(type default)
			)
			(layer "F.Fab")
		)
		(fp_line
			(start 0.67945 0.3048)
			(end 0.120396 0.3048)
			(stroke
				(width 0.1)
				(type default)
			)
			(layer "F.Fab")
		)
		(fp_line
			(start -0.12065 0.2794)
			(end -0.12065 0.3048)
			(stroke
				(width 0.1)
				(type default)
			)
			(layer "F.Fab")
		)
		(fp_line
			(start 0.120396 0.2794)
			(end -0.12065 0.2794)
			(stroke
				(width 0.1)
				(type default)
			)
			(layer "F.Fab")
		)
		(fp_line
			(start -0.12065 -0.2794)
			(end 0.12065 -0.2794)
			(stroke
				(width 0.1)
				(type default)
			)
			(layer "F.Fab")
		)
		(fp_line
			(start 0.12065 -0.2794)
			(end 0.12065 -0.3048)
			(stroke
				(width 0.1)
				(type default)
			)
			(layer "F.Fab")
		)
		(fp_line
			(start 0.12065 -0.3048)
			(end 0.67945 -0.3048)
			(stroke
				(width 0.1)
				(type default)
			)
			(layer "F.Fab")
		)
		(fp_line
			(start 0.67945 -0.3048)
			(end 0.67945 0.3048)
			(stroke
				(width 0.1)
				(type default)
			)
			(layer "F.Fab")
		)
		(fp_line
			(start -0.67945 -0.305054)
			(end -0.12065 -0.305054)
			(stroke
				(width 0.1)
				(type default)
			)
			(layer "F.Fab")
		)
		(fp_line
			(start -0.12065 -0.305054)
			(end -0.12065 -0.2794)
			(stroke
				(width 0.1)
				(type default)
			)
			(layer "F.Fab")
		)
		(pad "1" smd circle
			(at -0.40005 0 270)
			(size 0 0)
			(layers "F.Cu" "F.Mask" "F.Paste")
			(net "SW_P12V_AUX_PVDD11_S3_P0_FLT")
		)
		(pad "2" smd circle
			(at 0.40005 0 270)
			(size 0 0)
			(layers "F.Cu" "F.Mask" "F.Paste")
			(net "GND")
		)
	)
	(footprint ""
		(layer "F.Cu")
		(at 123.96597 -165.192456 180)
		(property "Reference" "PU31"
			(at 2.577592 -7.079742 0)
			(unlocked yes)
			(layer "F.SilkS")
			(effects
				(font
					(size 0.7874 0.5842)
					(thickness 0.1524)
				)
				(justify left)
			)
		)
		(property "Value" ""
			(at 0 0 180)
			(layer "F.Fab")
			(effects
				(font
					(size 1.27 1.27)
				)
			)
		)
		(duplicate_pad_numbers_are_jumpers no)
		(fp_line
			(start 2.500122 2.999994)
			(end 2.2987 2.999994)
			(stroke
				(width 0.1524)
				(type default)
			)
			(layer "F.SilkS")
		)
		(fp_line
			(start 2.500122 2.339594)
			(end 2.500122 2.999994)
			(stroke
				(width 0.1524)
				(type default)
			)
			(layer "F.SilkS")
		)
		(fp_line
			(start 2.500122 -2.999994)
			(end 2.500122 -2.44348)
			(stroke
				(width 0.1524)
				(type default)
			)
			(layer "F.SilkS")
		)
		(fp_line
			(start 2.31394 -2.999994)
			(end 2.500122 -2.999994)
			(stroke
				(width 0.1524)
				(type default)
			)
			(layer "F.SilkS")
		)
		(fp_line
			(start -2.2987 2.999994)
			(end -2.500122 2.999994)
			(stroke
				(width 0.1524)
				(type default)
			)
			(layer "F.SilkS")
		)
		(fp_line
			(start -2.500122 2.999994)
			(end -2.500122 2.339594)
			(stroke
				(width 0.1524)
				(type default)
			)
			(layer "F.SilkS")
		)
		(fp_line
			(start -2.500122 0.6604)
			(end -2.500122 0.229108)
			(stroke
				(width 0.1524)
				(type default)
			)
			(layer "F.SilkS")
		)
		(fp_line
			(start -2.500122 -2.529078)
			(end -2.500122 -2.999994)
			(stroke
				(width 0.1524)
				(type default)
			)
			(layer "F.SilkS")
		)
		(fp_line
			(start -2.500122 -2.999994)
			(end -2.24409 -2.999994)
			(stroke
				(width 0.1524)
				(type default)
			)
			(layer "F.SilkS")
		)
		(fp_poly
			(pts
				(xy -2.757424 -2.445004) (xy -3.431032 -2.66954) (xy -2.98196 -3.118612)
			)
			(stroke
				(width 0)
				(type default)
			)
			(fill yes)
			(layer "F.SilkS")
		)
		(fp_line
			(start 2.500122 2.999994)
			(end -2.500122 2.999994)
			(stroke
				(width 0.1)
				(type default)
			)
			(layer "F.Fab")
		)
		(fp_line
			(start 2.500122 -2.999994)
			(end 2.500122 2.999994)
			(stroke
				(width 0.1)
				(type default)
			)
			(layer "F.Fab")
		)
		(fp_line
			(start -2.500122 2.999994)
			(end -2.500122 -2.999994)
			(stroke
				(width 0.1)
				(type default)
			)
			(layer "F.Fab")
		)
		(fp_line
			(start -2.500122 -2.999994)
			(end 2.500122 -2.999994)
			(stroke
				(width 0.1)
				(type default)
			)
			(layer "F.Fab")
		)
		(fp_poly
			(pts
				(xy -4.218432 -2.783078) (xy -4.218432 -1.767078) (xy -3.202432 -2.275078)
			)
			(stroke
				(width 0)
				(type default)
			)
			(fill yes)
			(layer "F.Fab")
		)
		(pad "1" smd rect
			(at -2.400046 -2.275078 270)
			(size 0.2286 0.6096)
			(layers "F.Cu" "F.Mask" "F.Paste")
			(net "PVDDCR_SOC_P1_VOS2")
		)
		(pad "2" smd rect
			(at -2.400046 -1.82499 270)
			(size 0.2286 0.6096)
			(layers "F.Cu" "F.Mask" "F.Paste")
			(net "GND")
		)
		(pad "3" smd rect
			(at -2.400046 -1.374902 270)
			(size 0.2286 0.6096)
			(layers "F.Cu" "F.Mask" "F.Paste")
			(net "PVDDCR_SOC_P1_VCC2")
		)
		(pad "4" smd rect
			(at -2.400046 -0.925068 270)
			(size 0.2286 0.6096)
			(layers "F.Cu" "F.Mask" "F.Paste")
			(net "PVDDCR_CPU0_P1_PVCC")
		)
		(pad "5" smd rect
			(at -2.400046 -0.47498 270)
			(size 0.2286 0.6096)
			(layers "F.Cu" "F.Mask" "F.Paste")
			(net "GND")
		)
		(pad "6" smd rect
			(at -2.400046 -0.024892 270)
			(size 0.2286 0.6096)
			(layers "F.Cu" "F.Mask" "F.Paste")
			(net "NC_PVDDCR_SOC_P1_GL1_2")
		)
		(pad "7_9-20_24" smd circle
			(at 0 1.150112 270)
			(size 0 0)
			(layers "F.Cu" "F.Mask" "F.Paste")
			(net "GND")
		)
		(pad "10_19" smd rect
			(at 0 2.899918 270)
			(size 0.6096 4.318)
			(layers "F.Cu" "F.Mask" "F.Paste")
			(net "SW_PVDDCR_SOC_P1_SW2")
		)
		(pad "25_29" smd rect
			(at 1.549908 -1.279906 90)
			(size 2.0574 2.3114)
			(layers "F.Cu" "F.Mask" "F.Paste")
			(net "SW_P12V_AUX_PVDDCR_SOC_P1_FLT")
		)
		(pad "30" smd rect
			(at 2.05994 -2.899918 180)
			(size 0.2286 0.6096)
			(layers "F.Cu" "F.Mask" "F.Paste")
			(net "SW_P12V_AUX_PVDDCR_SOC_P1_FLT")
		)
		(pad "31" smd rect
			(at 1.610106 -2.899918 180)
			(size 0.2286 0.6096)
			(layers "F.Cu" "F.Mask" "F.Paste")
			(net "NC_PVDDCR_SOC_P1_DNC2")
		)
		(pad "32" smd rect
			(at 1.160018 -2.899918 180)
			(size 0.2286 0.6096)
			(layers "F.Cu" "F.Mask" "F.Paste")
			(net "SW_PVDDCR_SOC_P1_PH2")
		)
		(pad "33" smd rect
			(at 0.70993 -2.899918 180)
			(size 0.2286 0.6096)
			(layers "F.Cu" "F.Mask" "F.Paste")
			(net "SW_PVDDCR_SOC_P1_BOOT2")
		)
		(pad "34" smd rect
			(at 0.260096 -2.899918 180)
			(size 0.2286 0.6096)
			(layers "F.Cu" "F.Mask" "F.Paste")
			(net "PVDDCR_SOC_P1_PWM2")
		)
		(pad "35" smd rect
			(at -0.189992 -2.899918 180)
			(size 0.2286 0.6096)
			(layers "F.Cu" "F.Mask" "F.Paste")
			(net "PVDDCR_SOC_P1_VCC2")
		)
		(pad "36" smd rect
			(at -0.64008 -2.899918 180)
			(size 0.2286 0.6096)
			(layers "F.Cu" "F.Mask" "F.Paste")
			(net "PVDDCR_SOC_P1_TEMP1")
		)
		(pad "37" smd rect
			(at -1.089914 -2.899918 180)
			(size 0.2286 0.6096)
			(layers "F.Cu" "F.Mask" "F.Paste")
			(net "PVDDCR_SOC_P1_LSET2")
		)
		(pad "38" smd rect
			(at -1.540002 -2.899918 180)
			(size 0.2286 0.6096)
			(layers "F.Cu" "F.Mask" "F.Paste")
			(net "PVDDCR_SOC_P1_IMON2")
		)
		(pad "39" smd rect
			(at -1.99009 -2.899918 180)
			(size 0.2286 0.6096)
			(layers "F.Cu" "F.Mask" "F.Paste")
			(net "PVDDCR_CPU0_P1_VCCS")
		)
		(pad "40" smd rect
			(at -0.87503 -1.27508 180)
			(size 1.7526 1.9558)
			(layers "F.Cu" "F.Mask" "F.Paste")
			(net "GND")
		)
		(pad "41" smd rect
			(at -1.525016 0.249936 90)
			(size 0.3048 0.4572)
			(layers "F.Cu" "F.Mask" "F.Paste")
			(net "NC_PVDDCR_SOC_P1_GL2_2")
		)
		(zone
			(layer "F.Cu")
			(hatch none 0.5)
			(connect_pads
				(clearance 0)
			)
			(min_thickness 0.25)
			(keepout
				(tracks not_allowed)
				(vias allowed)
				(pads allowed)
				(copperpour not_allowed)
				(footprints allowed)
			)
			(placement
				(enabled no)
				(sheetname "")
			)
			(fill
				(thermal_gap 0.5)
				(thermal_bridge_width 0.5)
				(island_removal_mode 0)
			)
			(polygon
				(pts
					(xy 126.466092 -167.736774) (xy 126.466092 -167.44315) (xy 121.465848 -167.44315) (xy 121.465848 -167.736774)
					(xy 121.75617 -167.736774) (xy 126.17577 -167.736774)
				)
			)
		)
		(zone
			(layer "F.Cu")
			(hatch none 0.5)
			(connect_pads
				(clearance 0)
			)
			(min_thickness 0.25)
			(keepout
				(tracks not_allowed)
				(vias allowed)
				(pads allowed)
				(copperpour not_allowed)
				(footprints allowed)
			)
			(placement
				(enabled no)
				(sheetname "")
			)
			(fill
				(thermal_gap 0.5)
				(thermal_bridge_width 0.5)
				(island_removal_mode 0)
			)
			(polygon
				(pts
					(xy 123.9139 -164.946076) (xy 123.9139 -162.888676) (xy 125.7681 -162.888676) (xy 125.7681 -163.129722)
					(xy 126.010416 -163.129722) (xy 126.010416 -162.648138) (xy 122.131582 -162.648138) (xy 122.131582 -162.83305)
					(xy 123.622562 -162.83305) (xy 123.622562 -164.99205) (xy 121.465848 -164.99205) (xy 121.465848 -165.241732)
					(xy 123.618244 -165.241732)
				)
			)
		)
	)
	(footprint ""
		(layer "F.Cu")
		(at 193.089022 -24.091392 -90)
		(property "Reference" "R4015"
			(at 0 0 270)
			(layer "F.SilkS")
			(hide yes)
			(effects
				(font
					(size 1.27 1.27)
				)
			)
		)
		(property "Value" ""
			(at 0 0 270)
			(layer "F.Fab")
			(effects
				(font
					(size 1.27 1.27)
				)
			)
		)
		(duplicate_pad_numbers_are_jumpers no)
		(fp_line
			(start -0.7874 0.4064)
			(end -0.7874 -0.4064)
			(stroke
				(width 0.1524)
				(type default)
			)
			(layer "F.SilkS")
		)
		(fp_line
			(start 0.7874 0.4064)
			(end -0.7874 0.4064)
			(stroke
				(width 0.1524)
				(type default)
			)
			(layer "F.SilkS")
		)
		(fp_line
			(start -0.7874 -0.4064)
			(end 0.7874 -0.4064)
			(stroke
				(width 0.1524)
				(type default)
			)
			(layer "F.SilkS")
		)
		(fp_line
			(start 0.7874 -0.4064)
			(end 0.7874 0.4064)
			(stroke
				(width 0.1524)
				(type default)
			)
			(layer "F.SilkS")
		)
		(fp_line
			(start -0.67945 0.3048)
			(end -0.67945 -0.305054)
			(stroke
				(width 0.1)
				(type default)
			)
			(layer "F.Fab")
		)
		(fp_line
			(start -0.12065 0.3048)
			(end -0.67945 0.3048)
			(stroke
				(width 0.1)
				(type default)
			)
			(layer "F.Fab")
		)
		(fp_line
			(start 0.120396 0.3048)
			(end 0.120396 0.2794)
			(stroke
				(width 0.1)
				(type default)
			)
			(layer "F.Fab")
		)
		(fp_line
			(start 0.67945 0.3048)
			(end 0.120396 0.3048)
			(stroke
				(width 0.1)
				(type default)
			)
			(layer "F.Fab")
		)
		(fp_line
			(start -0.12065 0.2794)
			(end -0.12065 0.3048)
			(stroke
				(width 0.1)
				(type default)
			)
			(layer "F.Fab")
		)
		(fp_line
			(start 0.120396 0.2794)
			(end -0.12065 0.2794)
			(stroke
				(width 0.1)
				(type default)
			)
			(layer "F.Fab")
		)
		(fp_line
			(start -0.12065 -0.2794)
			(end 0.12065 -0.2794)
			(stroke
				(width 0.1)
				(type default)
			)
			(layer "F.Fab")
		)
		(fp_line
			(start 0.12065 -0.2794)
			(end 0.12065 -0.3048)
			(stroke
				(width 0.1)
				(type default)
			)
			(layer "F.Fab")
		)
		(fp_line
			(start 0.12065 -0.3048)
			(end 0.67945 -0.3048)
			(stroke
				(width 0.1)
				(type default)
			)
			(layer "F.Fab")
		)
		(fp_line
			(start 0.67945 -0.3048)
			(end 0.67945 0.3048)
			(stroke
				(width 0.1)
				(type default)
			)
			(layer "F.Fab")
		)
		(fp_line
			(start -0.67945 -0.305054)
			(end -0.12065 -0.305054)
			(stroke
				(width 0.1)
				(type default)
			)
			(layer "F.Fab")
		)
		(fp_line
			(start -0.12065 -0.305054)
			(end -0.12065 -0.2794)
			(stroke
				(width 0.1)
				(type default)
			)
			(layer "F.Fab")
		)
		(pad "1" smd circle
			(at -0.40005 0 270)
			(size 0 0)
			(layers "F.Cu" "F.Mask" "F.Paste")
			(net "P3V3_AUX")
		)
		(pad "2" smd circle
			(at 0.40005 0 270)
			(size 0 0)
			(layers "F.Cu" "F.Mask" "F.Paste")
			(net "HP_LVC3_SCM_HSC_PWRGD")
		)
	)
	(footprint ""
		(layer "F.Cu")
		(at 492.985044 -457.29398 90)
		(property "Reference" "X9009"
			(at -1.979168 1.12141 0)
			(unlocked yes)
			(layer "F.SilkS")
			(effects
				(font
					(size 0.7874 0.5842)
					(thickness 0.1524)
				)
				(justify left)
			)
		)
		(property "Value" ""
			(at 0 0 90)
			(layer "F.Fab")
			(effects
				(font
					(size 1.27 1.27)
				)
			)
		)
		(property "User Part Number" "N_A"
			(at 1.30175 1.27 180)
			(unlocked yes)
			(layer "Cmts.User")
			(hide yes)
			(effects
				(font
					(size 0.635 0.4064)
					(thickness 0.1524)
				)
			)
		)
		(property "Device Type" "TP_TDR_4P_FTS_TH-TP_TDR_4P_DIP,EMPTY,TP15"
			(at 1.30175 1.27 180)
			(unlocked yes)
			(layer "F.Fab")
			(hide yes)
			(effects
				(font
					(size 0.635 0.4064)
					(thickness 0.1524)
				)
			)
		)
		(duplicate_pad_numbers_are_jumpers no)
		(fp_line
			(start 2.54 -1.27)
			(end 0 -1.27)
			(stroke
				(width 0.1524)
				(type default)
			)
			(layer "F.SilkS")
		)
		(fp_line
			(start 0 -1.27)
			(end 0 -0.635)
			(stroke
				(width 0.1524)
				(type default)
			)
			(layer "F.SilkS")
		)
		(fp_line
			(start 2.54 -1.1303)
			(end 2.54 -1.27)
			(stroke
				(width 0.1524)
				(type default)
			)
			(layer "F.SilkS")
		)
		(fp_line
			(start 0 0.635)
			(end 0 1.905)
			(stroke
				(width 0.1524)
				(type default)
			)
			(layer "F.SilkS")
		)
		(fp_line
			(start 2.54 1.4097)
			(end 2.54 1.1303)
			(stroke
				(width 0.1524)
				(type default)
			)
			(layer "F.SilkS")
		)
		(fp_line
			(start 0 3.175)
			(end 0 3.81)
			(stroke
				(width 0.1524)
				(type default)
			)
			(layer "F.SilkS")
		)
		(fp_line
			(start 2.54 3.81)
			(end 2.54 3.6703)
			(stroke
				(width 0.1524)
				(type default)
			)
			(layer "F.SilkS")
		)
		(fp_line
			(start 0 3.81)
			(end 2.54 3.81)
			(stroke
				(width 0.1524)
				(type default)
			)
			(layer "F.SilkS")
		)
		(fp_poly
			(pts
				(xy -2.285746 -0.762) (xy -0.761746 0) (xy -2.285746 0.762)
			)
			(stroke
				(width 0)
				(type default)
			)
			(fill yes)
			(layer "F.SilkS")
		)
		(fp_line
			(start 2.54 -1.27)
			(end 0 -1.27)
			(stroke
				(width 0.1)
				(type default)
			)
			(layer "F.Fab")
		)
		(fp_line
			(start 0 -1.27)
			(end 0 3.81)
			(stroke
				(width 0.1)
				(type default)
			)
			(layer "F.Fab")
		)
		(fp_line
			(start 2.54 3.81)
			(end 2.54 -1.27)
			(stroke
				(width 0.1)
				(type default)
			)
			(layer "F.Fab")
		)
		(fp_line
			(start 0 3.81)
			(end 2.54 3.81)
			(stroke
				(width 0.1)
				(type default)
			)
			(layer "F.Fab")
		)
		(fp_poly
			(pts
				(xy -0.761746 0) (xy -2.285746 -0.762) (xy -2.285746 0.762)
			)
			(stroke
				(width 0)
				(type default)
			)
			(fill yes)
			(layer "F.Fab")
		)
		(pad "1" thru_hole circle
			(at 0 0 90)
			(size 1.0033 1.0033)
			(drill 0.249936)
			(layers "*.Cu" "*.Mask")
			(remove_unused_layers no)
			(net "TDR_DIFF_85_NECK_IN2_DN")
			(clearance 0.10795)
			(thermal_gap 0.10795)
			(padstack
				(mode front_inner_back)
				(layer "Inner"
					(shape circle)
					(size 0.8001 0.8001)
					(clearance 0.1524)
				)
				(layer "B.Cu"
					(shape circle)
					(size 1.0033 1.0033)
					(clearance 0.10795)
				)
			)
		)
		(pad "2" thru_hole circle
			(at 2.54 0 90)
			(size 1.9939 1.9939)
			(drill 0.249936)
			(layers "*.Cu" "*.Mask")
			(remove_unused_layers no)
			(net "T1_GND")
			(clearance 0.10795)
			(thermal_gap 0.10795)
			(padstack
				(mode front_inner_back)
				(layer "Inner"
					(shape circle)
					(size 0.8001 0.8001)
					(clearance 0.1524)
				)
				(layer "B.Cu"
					(shape circle)
					(size 1.9939 1.9939)
					(clearance 0.10795)
				)
			)
		)
		(pad "3" thru_hole circle
			(at 2.54 2.54 90)
			(size 1.9939 1.9939)
			(drill 0.249936)
			(layers "*.Cu" "*.Mask")
			(remove_unused_layers no)
			(net "T1_GND")
			(clearance 0.10795)
			(thermal_gap 0.10795)
			(padstack
				(mode front_inner_back)
				(layer "Inner"
					(shape circle)
					(size 0.8001 0.8001)
					(clearance 0.1524)
				)
				(layer "B.Cu"
					(shape circle)
					(size 1.9939 1.9939)
					(clearance 0.10795)
				)
			)
		)
		(pad "4" thru_hole circle
			(at 0 2.54 90)
			(size 1.0033 1.0033)
			(drill 0.249936)
			(layers "*.Cu" "*.Mask")
			(remove_unused_layers no)
			(net "TDR_DIFF_85_NECK_IN2_DP")
			(clearance 0.10795)
			(thermal_gap 0.10795)
			(padstack
				(mode front_inner_back)
				(layer "Inner"
					(shape circle)
					(size 0.8001 0.8001)
					(clearance 0.1524)
				)
				(layer "B.Cu"
					(shape circle)
					(size 1.0033 1.0033)
					(clearance 0.10795)
				)
			)
		)
	)
	(footprint ""
		(layer "F.Cu")
		(at 136.803638 -389.816086)
		(property "Reference" "R1429"
			(at 0 0 0)
			(layer "F.SilkS")
			(hide yes)
			(effects
				(font
					(size 1.27 1.27)
				)
			)
		)
		(property "Value" ""
			(at 0 0 0)
			(layer "F.Fab")
			(effects
				(font
					(size 1.27 1.27)
				)
			)
		)
		(duplicate_pad_numbers_are_jumpers no)
		(fp_line
			(start -0.32512 -0.175006)
			(end 0.32512 -0.175006)
			(stroke
				(width 0.1)
				(type default)
			)
			(layer "F.Fab")
		)
		(fp_line
			(start -0.32512 0.175006)
			(end -0.32512 -0.175006)
			(stroke
				(width 0.1)
				(type default)
			)
			(layer "F.Fab")
		)
		(fp_line
			(start 0.32512 -0.175006)
			(end 0.32512 0.175006)
			(stroke
				(width 0.1)
				(type default)
			)
			(layer "F.Fab")
		)
		(fp_line
			(start 0.32512 0.175006)
			(end -0.32512 0.175006)
			(stroke
				(width 0.1)
				(type default)
			)
			(layer "F.Fab")
		)
		(pad "1" smd rect
			(at -0.2667 0)
			(size 0.3048 0.381)
			(layers "F.Cu" "F.Mask" "F.Paste")
			(net "JTAG_TRST_RT_CPU1_P3_N")
		)
		(pad "2" smd rect
			(at 0.2667 0 180)
			(size 0.3048 0.381)
			(layers "F.Cu" "F.Mask" "F.Paste")
			(net "GND")
		)
	)
	(footprint ""
		(layer "F.Cu")
		(at 111.476028 -256.012442 90)
		(property "Reference" "C2460"
			(at 0 0 90)
			(layer "F.SilkS")
			(hide yes)
			(effects
				(font
					(size 1.27 1.27)
				)
			)
		)
		(property "Value" ""
			(at 0 0 90)
			(layer "F.Fab")
			(effects
				(font
					(size 1.27 1.27)
				)
			)
		)
		(duplicate_pad_numbers_are_jumpers no)
		(fp_line
			(start 0.7874 -0.4064)
			(end 0.7874 0.4064)
			(stroke
				(width 0.1524)
				(type default)
			)
			(layer "F.SilkS")
		)
		(fp_line
			(start -0.7874 -0.4064)
			(end 0.7874 -0.4064)
			(stroke
				(width 0.1524)
				(type default)
			)
			(layer "F.SilkS")
		)
		(fp_line
			(start 0.7874 0.4064)
			(end -0.7874 0.4064)
			(stroke
				(width 0.1524)
				(type default)
			)
			(layer "F.SilkS")
		)
		(fp_line
			(start -0.7874 0.4064)
			(end -0.7874 -0.4064)
			(stroke
				(width 0.1524)
				(type default)
			)
			(layer "F.SilkS")
		)
		(fp_line
			(start -0.12065 -0.305054)
			(end -0.12065 -0.2794)
			(stroke
				(width 0.1)
				(type default)
			)
			(layer "F.Fab")
		)
		(fp_line
			(start -0.67945 -0.305054)
			(end -0.12065 -0.305054)
			(stroke
				(width 0.1)
				(type default)
			)
			(layer "F.Fab")
		)
		(fp_line
			(start 0.67945 -0.3048)
			(end 0.67945 0.3048)
			(stroke
				(width 0.1)
				(type default)
			)
			(layer "F.Fab")
		)
		(fp_line
			(start 0.12065 -0.3048)
			(end 0.67945 -0.3048)
			(stroke
				(width 0.1)
				(type default)
			)
			(layer "F.Fab")
		)
		(fp_line
			(start 0.12065 -0.2794)
			(end 0.12065 -0.3048)
			(stroke
				(width 0.1)
				(type default)
			)
			(layer "F.Fab")
		)
		(fp_line
			(start -0.12065 -0.2794)
			(end 0.12065 -0.2794)
			(stroke
				(width 0.1)
				(type default)
			)
			(layer "F.Fab")
		)
		(fp_line
			(start 0.120396 0.2794)
			(end -0.12065 0.2794)
			(stroke
				(width 0.1)
				(type default)
			)
			(layer "F.Fab")
		)
		(fp_line
			(start -0.12065 0.2794)
			(end -0.12065 0.3048)
			(stroke
				(width 0.1)
				(type default)
			)
			(layer "F.Fab")
		)
		(fp_line
			(start 0.67945 0.3048)
			(end 0.120396 0.3048)
			(stroke
				(width 0.1)
				(type default)
			)
			(layer "F.Fab")
		)
		(fp_line
			(start 0.120396 0.3048)
			(end 0.120396 0.2794)
			(stroke
				(width 0.1)
				(type default)
			)
			(layer "F.Fab")
		)
		(fp_line
			(start -0.12065 0.3048)
			(end -0.67945 0.3048)
			(stroke
				(width 0.1)
				(type default)
			)
			(layer "F.Fab")
		)
		(fp_line
			(start -0.67945 0.3048)
			(end -0.67945 -0.305054)
			(stroke
				(width 0.1)
				(type default)
			)
			(layer "F.Fab")
		)
		(pad "1" smd circle
			(at -0.40005 0 90)
			(size 0 0)
			(layers "F.Cu" "F.Mask" "F.Paste")
			(net "PVDDCR_SOC_P1")
		)
		(pad "2" smd circle
			(at 0.40005 0 90)
			(size 0 0)
			(layers "F.Cu" "F.Mask" "F.Paste")
			(net "GND")
		)
	)
	(footprint ""
		(layer "F.Cu")
		(at 38.180772 -53.837332 -90)
		(property "Reference" "R8026"
			(at 0 0 270)
			(layer "F.SilkS")
			(hide yes)
			(effects
				(font
					(size 1.27 1.27)
				)
			)
		)
		(property "Value" ""
			(at 0 0 270)
			(layer "F.Fab")
			(effects
				(font
					(size 1.27 1.27)
				)
			)
		)
		(duplicate_pad_numbers_are_jumpers no)
		(fp_line
			(start -0.7874 0.4064)
			(end -0.7874 -0.4064)
			(stroke
				(width 0.1524)
				(type default)
			)
			(layer "F.SilkS")
		)
		(fp_line
			(start 0.7874 0.4064)
			(end -0.7874 0.4064)
			(stroke
				(width 0.1524)
				(type default)
			)
			(layer "F.SilkS")
		)
		(fp_line
			(start -0.7874 -0.4064)
			(end 0.7874 -0.4064)
			(stroke
				(width 0.1524)
				(type default)
			)
			(layer "F.SilkS")
		)
		(fp_line
			(start 0.7874 -0.4064)
			(end 0.7874 0.4064)
			(stroke
				(width 0.1524)
				(type default)
			)
			(layer "F.SilkS")
		)
		(fp_line
			(start -0.67945 0.3048)
			(end -0.67945 -0.305054)
			(stroke
				(width 0.1)
				(type default)
			)
			(layer "F.Fab")
		)
		(fp_line
			(start -0.12065 0.3048)
			(end -0.67945 0.3048)
			(stroke
				(width 0.1)
				(type default)
			)
			(layer "F.Fab")
		)
		(fp_line
			(start 0.120396 0.3048)
			(end 0.120396 0.2794)
			(stroke
				(width 0.1)
				(type default)
			)
			(layer "F.Fab")
		)
		(fp_line
			(start 0.67945 0.3048)
			(end 0.120396 0.3048)
			(stroke
				(width 0.1)
				(type default)
			)
			(layer "F.Fab")
		)
		(fp_line
			(start -0.12065 0.2794)
			(end -0.12065 0.3048)
			(stroke
				(width 0.1)
				(type default)
			)
			(layer "F.Fab")
		)
		(fp_line
			(start 0.120396 0.2794)
			(end -0.12065 0.2794)
			(stroke
				(width 0.1)
				(type default)
			)
			(layer "F.Fab")
		)
		(fp_line
			(start -0.12065 -0.2794)
			(end 0.12065 -0.2794)
			(stroke
				(width 0.1)
				(type default)
			)
			(layer "F.Fab")
		)
		(fp_line
			(start 0.12065 -0.2794)
			(end 0.12065 -0.3048)
			(stroke
				(width 0.1)
				(type default)
			)
			(layer "F.Fab")
		)
		(fp_line
			(start 0.12065 -0.3048)
			(end 0.67945 -0.3048)
			(stroke
				(width 0.1)
				(type default)
			)
			(layer "F.Fab")
		)
		(fp_line
			(start 0.67945 -0.3048)
			(end 0.67945 0.3048)
			(stroke
				(width 0.1)
				(type default)
			)
			(layer "F.Fab")
		)
		(fp_line
			(start -0.67945 -0.305054)
			(end -0.12065 -0.305054)
			(stroke
				(width 0.1)
				(type default)
			)
			(layer "F.Fab")
		)
		(fp_line
			(start -0.12065 -0.305054)
			(end -0.12065 -0.2794)
			(stroke
				(width 0.1)
				(type default)
			)
			(layer "F.Fab")
		)
		(pad "1" smd circle
			(at -0.40005 0 270)
			(size 0 0)
			(layers "F.Cu" "F.Mask" "F.Paste")
			(net "LED_P12V_PSU_R2")
		)
		(pad "2" smd circle
			(at 0.40005 0 270)
			(size 0 0)
			(layers "F.Cu" "F.Mask" "F.Paste")
			(net "LED_P12V_PSU_R3")
		)
	)
	(footprint ""
		(layer "F.Cu")
		(at 257.951478 -106.909108)
		(property "Reference" "R3191"
			(at 0 0 0)
			(layer "F.SilkS")
			(hide yes)
			(effects
				(font
					(size 1.27 1.27)
				)
			)
		)
		(property "Value" ""
			(at 0 0 0)
			(layer "F.Fab")
			(effects
				(font
					(size 1.27 1.27)
				)
			)
		)
		(duplicate_pad_numbers_are_jumpers no)
		(fp_line
			(start -0.7874 -0.4064)
			(end 0.7874 -0.4064)
			(stroke
				(width 0.1524)
				(type default)
			)
			(layer "F.SilkS")
		)
		(fp_line
			(start -0.7874 0.4064)
			(end -0.7874 -0.4064)
			(stroke
				(width 0.1524)
				(type default)
			)
			(layer "F.SilkS")
		)
		(fp_line
			(start 0.7874 -0.4064)
			(end 0.7874 0.4064)
			(stroke
				(width 0.1524)
				(type default)
			)
			(layer "F.SilkS")
		)
		(fp_line
			(start 0.7874 0.4064)
			(end -0.7874 0.4064)
			(stroke
				(width 0.1524)
				(type default)
			)
			(layer "F.SilkS")
		)
		(fp_line
			(start -0.67945 -0.305054)
			(end -0.12065 -0.305054)
			(stroke
				(width 0.1)
				(type default)
			)
			(layer "F.Fab")
		)
		(fp_line
			(start -0.67945 0.3048)
			(end -0.67945 -0.305054)
			(stroke
				(width 0.1)
				(type default)
			)
			(layer "F.Fab")
		)
		(fp_line
			(start -0.12065 -0.305054)
			(end -0.12065 -0.2794)
			(stroke
				(width 0.1)
				(type default)
			)
			(layer "F.Fab")
		)
		(fp_line
			(start -0.12065 -0.2794)
			(end 0.12065 -0.2794)
			(stroke
				(width 0.1)
				(type default)
			)
			(layer "F.Fab")
		)
		(fp_line
			(start -0.12065 0.2794)
			(end -0.12065 0.3048)
			(stroke
				(width 0.1)
				(type default)
			)
			(layer "F.Fab")
		)
		(fp_line
			(start -0.12065 0.3048)
			(end -0.67945 0.3048)
			(stroke
				(width 0.1)
				(type default)
			)
			(layer "F.Fab")
		)
		(fp_line
			(start 0.120396 0.2794)
			(end -0.12065 0.2794)
			(stroke
				(width 0.1)
				(type default)
			)
			(layer "F.Fab")
		)
		(fp_line
			(start 0.120396 0.3048)
			(end 0.120396 0.2794)
			(stroke
				(width 0.1)
				(type default)
			)
			(layer "F.Fab")
		)
		(fp_line
			(start 0.12065 -0.3048)
			(end 0.67945 -0.3048)
			(stroke
				(width 0.1)
				(type default)
			)
			(layer "F.Fab")
		)
		(fp_line
			(start 0.12065 -0.2794)
			(end 0.12065 -0.3048)
			(stroke
				(width 0.1)
				(type default)
			)
			(layer "F.Fab")
		)
		(fp_line
			(start 0.67945 -0.3048)
			(end 0.67945 0.3048)
			(stroke
				(width 0.1)
				(type default)
			)
			(layer "F.Fab")
		)
		(fp_line
			(start 0.67945 0.3048)
			(end 0.120396 0.3048)
			(stroke
				(width 0.1)
				(type default)
			)
			(layer "F.Fab")
		)
		(pad "1" smd circle
			(at -0.40005 0)
			(size 0 0)
			(layers "F.Cu" "F.Mask" "F.Paste")
			(net "OCP_V3_2_PWRBRK_BUFF_N")
		)
		(pad "2" smd circle
			(at 0.40005 0)
			(size 0 0)
			(layers "F.Cu" "F.Mask" "F.Paste")
			(net "OCP_V3_2_PWRBRK_N")
		)
	)
	(footprint ""
		(layer "F.Cu")
		(at 239.152684 -53.821838)
		(property "Reference" "C1993"
			(at 0 0 0)
			(layer "F.SilkS")
			(hide yes)
			(effects
				(font
					(size 1.27 1.27)
				)
			)
		)
		(property "Value" ""
			(at 0 0 0)
			(layer "F.Fab")
			(effects
				(font
					(size 1.27 1.27)
				)
			)
		)
		(duplicate_pad_numbers_are_jumpers no)
		(fp_line
			(start -0.299974 -0.150114)
			(end 0.299974 -0.150114)
			(stroke
				(width 0.1)
				(type default)
			)
			(layer "F.Fab")
		)
		(fp_line
			(start -0.299974 0.150114)
			(end -0.299974 -0.150114)
			(stroke
				(width 0.1)
				(type default)
			)
			(layer "F.Fab")
		)
		(fp_line
			(start 0.299974 -0.150114)
			(end 0.299974 0.150114)
			(stroke
				(width 0.1)
				(type default)
			)
			(layer "F.Fab")
		)
		(fp_line
			(start 0.299974 0.150114)
			(end -0.299974 0.150114)
			(stroke
				(width 0.1)
				(type default)
			)
			(layer "F.Fab")
		)
		(pad "1" smd rect
			(at -0.2667 0)
			(size 0.3048 0.381)
			(layers "F.Cu" "F.Mask" "F.Paste")
			(net "P3E_CPU0_P4_TX_C_DP<1>")
		)
		(pad "2" smd rect
			(at 0.2667 0)
			(size 0.3048 0.381)
			(layers "F.Cu" "F.Mask" "F.Paste")
			(net "P3E_CPU0_P4_TX_DP<1>")
		)
	)
	(footprint ""
		(layer "F.Cu")
		(at 134.23138 -394.3477 -90)
		(property "Reference" "R6901"
			(at 0 0 270)
			(layer "F.SilkS")
			(hide yes)
			(effects
				(font
					(size 1.27 1.27)
				)
			)
		)
		(property "Value" ""
			(at 0 0 270)
			(layer "F.Fab")
			(effects
				(font
					(size 1.27 1.27)
				)
			)
		)
		(duplicate_pad_numbers_are_jumpers no)
		(fp_line
			(start -0.32512 0.175006)
			(end -0.32512 -0.175006)
			(stroke
				(width 0.1)
				(type default)
			)
			(layer "F.Fab")
		)
		(fp_line
			(start 0.32512 0.175006)
			(end -0.32512 0.175006)
			(stroke
				(width 0.1)
				(type default)
			)
			(layer "F.Fab")
		)
		(fp_line
			(start -0.32512 -0.175006)
			(end 0.32512 -0.175006)
			(stroke
				(width 0.1)
				(type default)
			)
			(layer "F.Fab")
		)
		(fp_line
			(start 0.32512 -0.175006)
			(end 0.32512 0.175006)
			(stroke
				(width 0.1)
				(type default)
			)
			(layer "F.Fab")
		)
		(pad "1" smd rect
			(at -0.2667 0 270)
			(size 0.3048 0.381)
			(layers "F.Cu" "F.Mask" "F.Paste")
			(net "RT_CPU1_P3_VQPS")
		)
		(pad "2" smd rect
			(at 0.2667 0 90)
			(size 0.3048 0.381)
			(layers "F.Cu" "F.Mask" "F.Paste")
			(net "GND")
		)
	)
	(footprint ""
		(layer "F.Cu")
		(at 409.434792 -140.884656 180)
		(property "Reference" "PC1853"
			(at 0 0 180)
			(layer "F.SilkS")
			(hide yes)
			(effects
				(font
					(size 1.27 1.27)
				)
			)
		)
		(property "Value" ""
			(at 0 0 180)
			(layer "F.Fab")
			(effects
				(font
					(size 1.27 1.27)
				)
			)
		)
		(duplicate_pad_numbers_are_jumpers no)
		(fp_line
			(start 0.7874 0.4064)
			(end -0.7874 0.4064)
			(stroke
				(width 0.1524)
				(type default)
			)
			(layer "F.SilkS")
		)
		(fp_line
			(start 0.7874 -0.4064)
			(end 0.7874 0.4064)
			(stroke
				(width 0.1524)
				(type default)
			)
			(layer "F.SilkS")
		)
		(fp_line
			(start -0.7874 0.4064)
			(end -0.7874 -0.4064)
			(stroke
				(width 0.1524)
				(type default)
			)
			(layer "F.SilkS")
		)
		(fp_line
			(start -0.7874 -0.4064)
			(end 0.7874 -0.4064)
			(stroke
				(width 0.1524)
				(type default)
			)
			(layer "F.SilkS")
		)
		(fp_line
			(start 0.67945 0.3048)
			(end 0.120396 0.3048)
			(stroke
				(width 0.1)
				(type default)
			)
			(layer "F.Fab")
		)
		(fp_line
			(start 0.67945 -0.3048)
			(end 0.67945 0.3048)
			(stroke
				(width 0.1)
				(type default)
			)
			(layer "F.Fab")
		)
		(fp_line
			(start 0.12065 -0.2794)
			(end 0.12065 -0.3048)
			(stroke
				(width 0.1)
				(type default)
			)
			(layer "F.Fab")
		)
		(fp_line
			(start 0.12065 -0.3048)
			(end 0.67945 -0.3048)
			(stroke
				(width 0.1)
				(type default)
			)
			(layer "F.Fab")
		)
		(fp_line
			(start 0.120396 0.3048)
			(end 0.120396 0.2794)
			(stroke
				(width 0.1)
				(type default)
			)
			(layer "F.Fab")
		)
		(fp_line
			(start 0.120396 0.2794)
			(end -0.12065 0.2794)
			(stroke
				(width 0.1)
				(type default)
			)
			(layer "F.Fab")
		)
		(fp_line
			(start -0.12065 0.3048)
			(end -0.67945 0.3048)
			(stroke
				(width 0.1)
				(type default)
			)
			(layer "F.Fab")
		)
		(fp_line
			(start -0.12065 0.2794)
			(end -0.12065 0.3048)
			(stroke
				(width 0.1)
				(type default)
			)
			(layer "F.Fab")
		)
		(fp_line
			(start -0.12065 -0.2794)
			(end 0.12065 -0.2794)
			(stroke
				(width 0.1)
				(type default)
			)
			(layer "F.Fab")
		)
		(fp_line
			(start -0.12065 -0.305054)
			(end -0.12065 -0.2794)
			(stroke
				(width 0.1)
				(type default)
			)
			(layer "F.Fab")
		)
		(fp_line
			(start -0.67945 0.3048)
			(end -0.67945 -0.305054)
			(stroke
				(width 0.1)
				(type default)
			)
			(layer "F.Fab")
		)
		(fp_line
			(start -0.67945 -0.305054)
			(end -0.12065 -0.305054)
			(stroke
				(width 0.1)
				(type default)
			)
			(layer "F.Fab")
		)
		(pad "1" smd circle
			(at -0.40005 0 180)
			(size 0 0)
			(layers "F.Cu" "F.Mask" "F.Paste")
			(net "P5V_AUX_REF")
		)
		(pad "2" smd circle
			(at 0.40005 0 180)
			(size 0 0)
			(layers "F.Cu" "F.Mask" "F.Paste")
			(net "GND")
		)
	)
	(footprint ""
		(layer "F.Cu")
		(at 105.659936 -123.623832 -90)
		(property "Reference" "Q19"
			(at -0.177546 1.643126 90)
			(unlocked yes)
			(layer "F.SilkS")
			(effects
				(font
					(size 0.7874 0.5842)
					(thickness 0.1524)
				)
			)
		)
		(property "Value" ""
			(at 0 0 270)
			(layer "F.Fab")
			(effects
				(font
					(size 1.27 1.27)
				)
			)
		)
		(duplicate_pad_numbers_are_jumpers no)
		(fp_line
			(start -1.7018 1.100074)
			(end -1.7018 -1.100074)
			(stroke
				(width 0.1524)
				(type default)
			)
			(layer "F.SilkS")
		)
		(fp_line
			(start 1.7018 1.100074)
			(end -1.7018 1.100074)
			(stroke
				(width 0.1524)
				(type default)
			)
			(layer "F.SilkS")
		)
		(fp_line
			(start -1.7018 -1.100074)
			(end 1.7018 -1.100074)
			(stroke
				(width 0.1524)
				(type default)
			)
			(layer "F.SilkS")
		)
		(fp_line
			(start 1.7018 -1.100074)
			(end 1.7018 1.100074)
			(stroke
				(width 0.1524)
				(type default)
			)
			(layer "F.SilkS")
		)
		(fp_poly
			(pts
				(xy -2.277618 -0.710946) (xy -2.831338 -0.414274) (xy -2.831338 -1.039114)
			)
			(stroke
				(width 0)
				(type default)
			)
			(fill yes)
			(layer "F.SilkS")
		)
		(fp_line
			(start -0.670052 1.100074)
			(end -0.670052 0.8001)
			(stroke
				(width 0.1)
				(type default)
			)
			(layer "F.Fab")
		)
		(fp_line
			(start 0.670052 1.100074)
			(end -0.670052 1.100074)
			(stroke
				(width 0.1)
				(type default)
			)
			(layer "F.Fab")
		)
		(fp_line
			(start -1.100074 0.8001)
			(end -1.100074 -0.8001)
			(stroke
				(width 0.1)
				(type default)
			)
			(layer "F.Fab")
		)
		(fp_line
			(start -0.670052 0.8001)
			(end -1.100074 0.8001)
			(stroke
				(width 0.1)
				(type default)
			)
			(layer "F.Fab")
		)
		(fp_line
			(start -0.670052 0.8001)
			(end -0.670052 -0.8001)
			(stroke
				(width 0.1)
				(type default)
			)
			(layer "F.Fab")
		)
		(fp_line
			(start 0.670052 0.8001)
			(end 0.670052 1.100074)
			(stroke
				(width 0.1)
				(type default)
			)
			(layer "F.Fab")
		)
		(fp_line
			(start 1.100074 0.8001)
			(end 0.670052 0.8001)
			(stroke
				(width 0.1)
				(type default)
			)
			(layer "F.Fab")
		)
		(fp_line
			(start -1.100074 -0.8001)
			(end -0.670052 -0.8001)
			(stroke
				(width 0.1)
				(type default)
			)
			(layer "F.Fab")
		)
		(fp_line
			(start -0.670052 -0.8001)
			(end -0.670052 -1.100074)
			(stroke
				(width 0.1)
				(type default)
			)
			(layer "F.Fab")
		)
		(fp_line
			(start 0.670052 -0.8001)
			(end 0.670052 0.8001)
			(stroke
				(width 0.1)
				(type default)
			)
			(layer "F.Fab")
		)
		(fp_line
			(start 0.670052 -0.8001)
			(end 1.100074 -0.8001)
			(stroke
				(width 0.1)
				(type default)
			)
			(layer "F.Fab")
		)
		(fp_line
			(start 1.100074 -0.8001)
			(end 1.100074 0.8001)
			(stroke
				(width 0.1)
				(type default)
			)
			(layer "F.Fab")
		)
		(fp_line
			(start -0.670052 -1.100074)
			(end 0.670052 -1.100074)
			(stroke
				(width 0.1)
				(type default)
			)
			(layer "F.Fab")
		)
		(fp_line
			(start 0.670052 -1.100074)
			(end 0.670052 -0.8001)
			(stroke
				(width 0.1)
				(type default)
			)
			(layer "F.Fab")
		)
		(fp_poly
			(pts
				(xy -2.33172 -0.338328) (xy -2.33172 -0.963168) (xy -1.778 -0.635)
			)
			(stroke
				(width 0)
				(type default)
			)
			(fill yes)
			(layer "F.Fab")
		)
		(pad "1" smd rect
			(at -0.937514 -0.649986)
			(size 0.3048 1.2446)
			(layers "F.Cu" "F.Mask" "F.Paste")
			(net "GND")
		)
		(pad "2" smd rect
			(at -0.937514 0)
			(size 0.3048 1.2446)
			(layers "F.Cu" "F.Mask" "F.Paste")
			(net "PWRGD_P12V_MEM_CPU1_EN")
		)
		(pad "3" smd rect
			(at -0.937514 0.649986)
			(size 0.3048 1.2446)
			(layers "F.Cu" "F.Mask" "F.Paste")
			(net "PWRGD_P12V_MEM_CPU1")
		)
		(pad "4" smd rect
			(at 0.937514 0.649986)
			(size 0.3048 1.2446)
			(layers "F.Cu" "F.Mask" "F.Paste")
			(net "GND")
		)
		(pad "5" smd rect
			(at 0.937514 0)
			(size 0.3048 1.2446)
			(layers "F.Cu" "F.Mask" "F.Paste")
			(net "PWRGD_P12V_MEM_CPU1_EN_N")
		)
		(pad "6" smd rect
			(at 0.937514 -0.649986)
			(size 0.3048 1.2446)
			(layers "F.Cu" "F.Mask" "F.Paste")
			(net "PWRGD_P12V_MEM_CPU1_EN_N")
		)
	)
	(footprint ""
		(layer "F.Cu")
		(at 127.705104 -53.15839 180)
		(property "Reference" "C86"
			(at 0 0 180)
			(layer "F.SilkS")
			(hide yes)
			(effects
				(font
					(size 1.27 1.27)
				)
			)
		)
		(property "Value" ""
			(at 0 0 180)
			(layer "F.Fab")
			(effects
				(font
					(size 1.27 1.27)
				)
			)
		)
		(duplicate_pad_numbers_are_jumpers no)
		(fp_line
			(start 0.7874 0.4064)
			(end -0.7874 0.4064)
			(stroke
				(width 0.1524)
				(type default)
			)
			(layer "F.SilkS")
		)
		(fp_line
			(start 0.7874 -0.4064)
			(end 0.7874 0.4064)
			(stroke
				(width 0.1524)
				(type default)
			)
			(layer "F.SilkS")
		)
		(fp_line
			(start -0.7874 0.4064)
			(end -0.7874 -0.4064)
			(stroke
				(width 0.1524)
				(type default)
			)
			(layer "F.SilkS")
		)
		(fp_line
			(start -0.7874 -0.4064)
			(end 0.7874 -0.4064)
			(stroke
				(width 0.1524)
				(type default)
			)
			(layer "F.SilkS")
		)
		(fp_line
			(start 0.67945 0.3048)
			(end 0.120396 0.3048)
			(stroke
				(width 0.1)
				(type default)
			)
			(layer "F.Fab")
		)
		(fp_line
			(start 0.67945 -0.3048)
			(end 0.67945 0.3048)
			(stroke
				(width 0.1)
				(type default)
			)
			(layer "F.Fab")
		)
		(fp_line
			(start 0.12065 -0.2794)
			(end 0.12065 -0.3048)
			(stroke
				(width 0.1)
				(type default)
			)
			(layer "F.Fab")
		)
		(fp_line
			(start 0.12065 -0.3048)
			(end 0.67945 -0.3048)
			(stroke
				(width 0.1)
				(type default)
			)
			(layer "F.Fab")
		)
		(fp_line
			(start 0.120396 0.3048)
			(end 0.120396 0.2794)
			(stroke
				(width 0.1)
				(type default)
			)
			(layer "F.Fab")
		)
		(fp_line
			(start 0.120396 0.2794)
			(end -0.12065 0.2794)
			(stroke
				(width 0.1)
				(type default)
			)
			(layer "F.Fab")
		)
		(fp_line
			(start -0.12065 0.3048)
			(end -0.67945 0.3048)
			(stroke
				(width 0.1)
				(type default)
			)
			(layer "F.Fab")
		)
		(fp_line
			(start -0.12065 0.2794)
			(end -0.12065 0.3048)
			(stroke
				(width 0.1)
				(type default)
			)
			(layer "F.Fab")
		)
		(fp_line
			(start -0.12065 -0.2794)
			(end 0.12065 -0.2794)
			(stroke
				(width 0.1)
				(type default)
			)
			(layer "F.Fab")
		)
		(fp_line
			(start -0.12065 -0.305054)
			(end -0.12065 -0.2794)
			(stroke
				(width 0.1)
				(type default)
			)
			(layer "F.Fab")
		)
		(fp_line
			(start -0.67945 0.3048)
			(end -0.67945 -0.305054)
			(stroke
				(width 0.1)
				(type default)
			)
			(layer "F.Fab")
		)
		(fp_line
			(start -0.67945 -0.305054)
			(end -0.12065 -0.305054)
			(stroke
				(width 0.1)
				(type default)
			)
			(layer "F.Fab")
		)
		(pad "1" smd circle
			(at -0.40005 0 180)
			(size 0 0)
			(layers "F.Cu" "F.Mask" "F.Paste")
			(net "JTAG_TDI")
		)
		(pad "2" smd circle
			(at 0.40005 0 180)
			(size 0 0)
			(layers "F.Cu" "F.Mask" "F.Paste")
			(net "GND")
		)
	)
	(footprint ""
		(layer "F.Cu")
		(at 259.461 -385.27736 90)
		(property "Reference" "PPQ6"
			(at -7.487412 -2.39268 0)
			(unlocked yes)
			(layer "F.SilkS")
			(effects
				(font
					(size 0.7874 0.5842)
					(thickness 0.1524)
				)
				(justify left)
			)
		)
		(property "Value" ""
			(at 0 0 90)
			(layer "F.Fab")
			(effects
				(font
					(size 1.27 1.27)
				)
			)
		)
		(duplicate_pad_numbers_are_jumpers no)
		(fp_line
			(start 2.350008 -2.649982)
			(end 2.350008 -2.4892)
			(stroke
				(width 0.1524)
				(type default)
			)
			(layer "F.SilkS")
		)
		(fp_line
			(start -2.350008 -2.649982)
			(end 2.350008 -2.649982)
			(stroke
				(width 0.1524)
				(type default)
			)
			(layer "F.SilkS")
		)
		(fp_line
			(start -2.350008 -2.4384)
			(end -2.350008 -2.649982)
			(stroke
				(width 0.1524)
				(type default)
			)
			(layer "F.SilkS")
		)
		(fp_line
			(start 2.350008 2.4892)
			(end 2.350008 2.649982)
			(stroke
				(width 0.1524)
				(type default)
			)
			(layer "F.SilkS")
		)
		(fp_line
			(start 2.350008 2.649982)
			(end -2.350008 2.649982)
			(stroke
				(width 0.1524)
				(type default)
			)
			(layer "F.SilkS")
		)
		(fp_line
			(start -2.350008 2.649982)
			(end -2.350008 2.413)
			(stroke
				(width 0.1524)
				(type default)
			)
			(layer "F.SilkS")
		)
		(fp_poly
			(pts
				(xy -3.506216 -3.488944) (xy -2.706116 -3.488944) (xy -3.125216 -2.447544)
			)
			(stroke
				(width 0)
				(type default)
			)
			(fill yes)
			(layer "F.SilkS")
		)
		(fp_line
			(start 2.350008 -2.649982)
			(end 2.350008 2.649982)
			(stroke
				(width 0.1)
				(type default)
			)
			(layer "F.Fab")
		)
		(fp_line
			(start -2.350008 -2.649982)
			(end 2.350008 -2.649982)
			(stroke
				(width 0.1)
				(type default)
			)
			(layer "F.Fab")
		)
		(fp_line
			(start 2.350008 2.649982)
			(end -2.350008 2.649982)
			(stroke
				(width 0.1)
				(type default)
			)
			(layer "F.Fab")
		)
		(fp_line
			(start -2.350008 2.649982)
			(end -2.350008 -2.649982)
			(stroke
				(width 0.1)
				(type default)
			)
			(layer "F.Fab")
		)
		(fp_poly
			(pts
				(xy -3.717544 -1.905) (xy -4.758944 -2.3241) (xy -4.758944 -1.524)
			)
			(stroke
				(width 0)
				(type default)
			)
			(fill yes)
			(layer "F.Fab")
		)
		(pad "1" smd rect
			(at -2.999994 -1.905)
			(size 0.7112 1.1684)
			(layers "F.Cu" "F.Mask" "F.Paste")
			(net "P12V_AUX")
		)
		(pad "2" smd rect
			(at -2.999994 -0.635)
			(size 0.7112 1.1684)
			(layers "F.Cu" "F.Mask" "F.Paste")
			(net "P12V_AUX")
		)
		(pad "3" smd rect
			(at -2.999994 0.635)
			(size 0.7112 1.1684)
			(layers "F.Cu" "F.Mask" "F.Paste")
			(net "P12V_AUX")
		)
		(pad "4" smd rect
			(at -2.999994 1.905)
			(size 0.7112 1.1684)
			(layers "F.Cu" "F.Mask" "F.Paste")
			(net "P12V_HSC_GATE_G2")
		)
		(pad "5" smd circle
			(at 0.925068 0)
			(size 0 0)
			(layers "F.Cu" "F.Mask" "F.Paste")
			(net "P12V_MAIN_R")
		)
		(zone
			(layer "F.Cu")
			(hatch none 0.5)
			(connect_pads
				(clearance 0)
			)
			(min_thickness 0.25)
			(keepout
				(tracks not_allowed)
				(vias allowed)
				(pads allowed)
				(copperpour not_allowed)
				(footprints allowed)
			)
			(placement
				(enabled no)
				(sheetname "")
			)
			(fill
				(thermal_gap 0.5)
				(thermal_bridge_width 0.5)
				(island_removal_mode 0)
			)
			(polygon
				(pts
					(xy 256.8194 -383.7178) (xy 262.1026 -383.7178) (xy 262.1026 -382.92786) (xy 256.8194 -382.92786)
				)
			)
		)
	)
	(footprint ""
		(layer "F.Cu")
		(at 85.81771 -340.190074)
		(property "Reference" "PR255"
			(at 0 0 0)
			(layer "F.SilkS")
			(hide yes)
			(effects
				(font
					(size 1.27 1.27)
				)
			)
		)
		(property "Value" ""
			(at 0 0 0)
			(layer "F.Fab")
			(effects
				(font
					(size 1.27 1.27)
				)
			)
		)
		(duplicate_pad_numbers_are_jumpers no)
		(fp_line
			(start -0.7874 -0.4064)
			(end 0.7874 -0.4064)
			(stroke
				(width 0.1524)
				(type default)
			)
			(layer "F.SilkS")
		)
		(fp_line
			(start -0.7874 0.4064)
			(end -0.7874 -0.4064)
			(stroke
				(width 0.1524)
				(type default)
			)
			(layer "F.SilkS")
		)
		(fp_line
			(start 0.7874 -0.4064)
			(end 0.7874 0.4064)
			(stroke
				(width 0.1524)
				(type default)
			)
			(layer "F.SilkS")
		)
		(fp_line
			(start 0.7874 0.4064)
			(end -0.7874 0.4064)
			(stroke
				(width 0.1524)
				(type default)
			)
			(layer "F.SilkS")
		)
		(fp_line
			(start -0.67945 -0.305054)
			(end -0.12065 -0.305054)
			(stroke
				(width 0.1)
				(type default)
			)
			(layer "F.Fab")
		)
		(fp_line
			(start -0.67945 0.3048)
			(end -0.67945 -0.305054)
			(stroke
				(width 0.1)
				(type default)
			)
			(layer "F.Fab")
		)
		(fp_line
			(start -0.12065 -0.305054)
			(end -0.12065 -0.2794)
			(stroke
				(width 0.1)
				(type default)
			)
			(layer "F.Fab")
		)
		(fp_line
			(start -0.12065 -0.2794)
			(end 0.12065 -0.2794)
			(stroke
				(width 0.1)
				(type default)
			)
			(layer "F.Fab")
		)
		(fp_line
			(start -0.12065 0.2794)
			(end -0.12065 0.3048)
			(stroke
				(width 0.1)
				(type default)
			)
			(layer "F.Fab")
		)
		(fp_line
			(start -0.12065 0.3048)
			(end -0.67945 0.3048)
			(stroke
				(width 0.1)
				(type default)
			)
			(layer "F.Fab")
		)
		(fp_line
			(start 0.120396 0.2794)
			(end -0.12065 0.2794)
			(stroke
				(width 0.1)
				(type default)
			)
			(layer "F.Fab")
		)
		(fp_line
			(start 0.120396 0.3048)
			(end 0.120396 0.2794)
			(stroke
				(width 0.1)
				(type default)
			)
			(layer "F.Fab")
		)
		(fp_line
			(start 0.12065 -0.3048)
			(end 0.67945 -0.3048)
			(stroke
				(width 0.1)
				(type default)
			)
			(layer "F.Fab")
		)
		(fp_line
			(start 0.12065 -0.2794)
			(end 0.12065 -0.3048)
			(stroke
				(width 0.1)
				(type default)
			)
			(layer "F.Fab")
		)
		(fp_line
			(start 0.67945 -0.3048)
			(end 0.67945 0.3048)
			(stroke
				(width 0.1)
				(type default)
			)
			(layer "F.Fab")
		)
		(fp_line
			(start 0.67945 0.3048)
			(end 0.120396 0.3048)
			(stroke
				(width 0.1)
				(type default)
			)
			(layer "F.Fab")
		)
		(pad "1" smd circle
			(at -0.40005 0)
			(size 0 0)
			(layers "F.Cu" "F.Mask" "F.Paste")
			(net "PVDDCR_CPU1_P1_LSET1")
		)
		(pad "2" smd circle
			(at 0.40005 0)
			(size 0 0)
			(layers "F.Cu" "F.Mask" "F.Paste")
			(net "GND")
		)
	)
	(footprint ""
		(layer "F.Cu")
		(at 182.5625 -397.848582 180)
		(property "Reference" "PC2190"
			(at 0 0 180)
			(layer "F.SilkS")
			(hide yes)
			(effects
				(font
					(size 1.27 1.27)
				)
			)
		)
		(property "Value" ""
			(at 0 0 180)
			(layer "F.Fab")
			(effects
				(font
					(size 1.27 1.27)
				)
			)
		)
		(duplicate_pad_numbers_are_jumpers no)
		(fp_line
			(start 0.7874 0.4064)
			(end -0.7874 0.4064)
			(stroke
				(width 0.1524)
				(type default)
			)
			(layer "F.SilkS")
		)
		(fp_line
			(start 0.7874 -0.4064)
			(end 0.7874 0.4064)
			(stroke
				(width 0.1524)
				(type default)
			)
			(layer "F.SilkS")
		)
		(fp_line
			(start -0.7874 0.4064)
			(end -0.7874 -0.4064)
			(stroke
				(width 0.1524)
				(type default)
			)
			(layer "F.SilkS")
		)
		(fp_line
			(start -0.7874 -0.4064)
			(end 0.7874 -0.4064)
			(stroke
				(width 0.1524)
				(type default)
			)
			(layer "F.SilkS")
		)
		(fp_line
			(start 0.67945 0.3048)
			(end 0.120396 0.3048)
			(stroke
				(width 0.1)
				(type default)
			)
			(layer "F.Fab")
		)
		(fp_line
			(start 0.67945 -0.3048)
			(end 0.67945 0.3048)
			(stroke
				(width 0.1)
				(type default)
			)
			(layer "F.Fab")
		)
		(fp_line
			(start 0.12065 -0.2794)
			(end 0.12065 -0.3048)
			(stroke
				(width 0.1)
				(type default)
			)
			(layer "F.Fab")
		)
		(fp_line
			(start 0.12065 -0.3048)
			(end 0.67945 -0.3048)
			(stroke
				(width 0.1)
				(type default)
			)
			(layer "F.Fab")
		)
		(fp_line
			(start 0.120396 0.3048)
			(end 0.120396 0.2794)
			(stroke
				(width 0.1)
				(type default)
			)
			(layer "F.Fab")
		)
		(fp_line
			(start 0.120396 0.2794)
			(end -0.12065 0.2794)
			(stroke
				(width 0.1)
				(type default)
			)
			(layer "F.Fab")
		)
		(fp_line
			(start -0.12065 0.3048)
			(end -0.67945 0.3048)
			(stroke
				(width 0.1)
				(type default)
			)
			(layer "F.Fab")
		)
		(fp_line
			(start -0.12065 0.2794)
			(end -0.12065 0.3048)
			(stroke
				(width 0.1)
				(type default)
			)
			(layer "F.Fab")
		)
		(fp_line
			(start -0.12065 -0.2794)
			(end 0.12065 -0.2794)
			(stroke
				(width 0.1)
				(type default)
			)
			(layer "F.Fab")
		)
		(fp_line
			(start -0.12065 -0.305054)
			(end -0.12065 -0.2794)
			(stroke
				(width 0.1)
				(type default)
			)
			(layer "F.Fab")
		)
		(fp_line
			(start -0.67945 0.3048)
			(end -0.67945 -0.305054)
			(stroke
				(width 0.1)
				(type default)
			)
			(layer "F.Fab")
		)
		(fp_line
			(start -0.67945 -0.305054)
			(end -0.12065 -0.305054)
			(stroke
				(width 0.1)
				(type default)
			)
			(layer "F.Fab")
		)
		(pad "1" smd circle
			(at -0.40005 0 180)
			(size 0 0)
			(layers "F.Cu" "F.Mask" "F.Paste")
			(net "HSC_VOSEN")
		)
		(pad "2" smd circle
			(at 0.40005 0 180)
			(size 0 0)
			(layers "F.Cu" "F.Mask" "F.Paste")
			(net "AGND_HSC")
		)
	)
	(footprint ""
		(layer "F.Cu")
		(at 80.622902 -375.49963 -90)
		(property "Reference" "C733"
			(at 0 0 270)
			(layer "F.SilkS")
			(hide yes)
			(effects
				(font
					(size 1.27 1.27)
				)
			)
		)
		(property "Value" ""
			(at 0 0 270)
			(layer "F.Fab")
			(effects
				(font
					(size 1.27 1.27)
				)
			)
		)
		(duplicate_pad_numbers_are_jumpers no)
		(fp_line
			(start -0.299974 0.150114)
			(end -0.299974 -0.150114)
			(stroke
				(width 0.1)
				(type default)
			)
			(layer "F.Fab")
		)
		(fp_line
			(start 0.299974 0.150114)
			(end -0.299974 0.150114)
			(stroke
				(width 0.1)
				(type default)
			)
			(layer "F.Fab")
		)
		(fp_line
			(start -0.299974 -0.150114)
			(end 0.299974 -0.150114)
			(stroke
				(width 0.1)
				(type default)
			)
			(layer "F.Fab")
		)
		(fp_line
			(start 0.299974 -0.150114)
			(end 0.299974 0.150114)
			(stroke
				(width 0.1)
				(type default)
			)
			(layer "F.Fab")
		)
		(pad "1" smd rect
			(at -0.2667 0 270)
			(size 0.3048 0.381)
			(layers "F.Cu" "F.Mask" "F.Paste")
			(net "P5E_CPU1_P1_TX_C_DP<4>")
		)
		(pad "2" smd rect
			(at 0.2667 0 270)
			(size 0.3048 0.381)
			(layers "F.Cu" "F.Mask" "F.Paste")
			(net "P5E_CPU1_P1_TX_DP<4>")
		)
	)
	(footprint ""
		(layer "F.Cu")
		(at 128.036066 -408.517344 -90)
		(property "Reference" "C6701"
			(at 0 0 270)
			(layer "F.SilkS")
			(hide yes)
			(effects
				(font
					(size 1.27 1.27)
				)
			)
		)
		(property "Value" ""
			(at 0 0 270)
			(layer "F.Fab")
			(effects
				(font
					(size 1.27 1.27)
				)
			)
		)
		(duplicate_pad_numbers_are_jumpers no)
		(fp_line
			(start -0.299974 0.150114)
			(end -0.299974 -0.150114)
			(stroke
				(width 0.1)
				(type default)
			)
			(layer "F.Fab")
		)
		(fp_line
			(start 0.299974 0.150114)
			(end -0.299974 0.150114)
			(stroke
				(width 0.1)
				(type default)
			)
			(layer "F.Fab")
		)
		(fp_line
			(start -0.299974 -0.150114)
			(end 0.299974 -0.150114)
			(stroke
				(width 0.1)
				(type default)
			)
			(layer "F.Fab")
		)
		(fp_line
			(start 0.299974 -0.150114)
			(end 0.299974 0.150114)
			(stroke
				(width 0.1)
				(type default)
			)
			(layer "F.Fab")
		)
		(pad "1" smd rect
			(at -0.2667 0 270)
			(size 0.3048 0.381)
			(layers "F.Cu" "F.Mask" "F.Paste")
			(net "P5E_CPU1_P2_TX_BUF_C_DP<4>")
		)
		(pad "2" smd rect
			(at 0.2667 0 270)
			(size 0.3048 0.381)
			(layers "F.Cu" "F.Mask" "F.Paste")
			(net "P5E_CPU1_P2_TX_BUF_DP<4>")
		)
	)
	(footprint ""
		(layer "F.Cu")
		(at 343.458546 -23.8887 -90)
		(property "Reference" "R945"
			(at 0 0 270)
			(layer "F.SilkS")
			(hide yes)
			(effects
				(font
					(size 1.27 1.27)
				)
			)
		)
		(property "Value" ""
			(at 0 0 270)
			(layer "F.Fab")
			(effects
				(font
					(size 1.27 1.27)
				)
			)
		)
		(duplicate_pad_numbers_are_jumpers no)
		(fp_line
			(start -0.7874 0.4064)
			(end -0.7874 -0.4064)
			(stroke
				(width 0.1524)
				(type default)
			)
			(layer "F.SilkS")
		)
		(fp_line
			(start 0.7874 0.4064)
			(end -0.7874 0.4064)
			(stroke
				(width 0.1524)
				(type default)
			)
			(layer "F.SilkS")
		)
		(fp_line
			(start -0.7874 -0.4064)
			(end 0.7874 -0.4064)
			(stroke
				(width 0.1524)
				(type default)
			)
			(layer "F.SilkS")
		)
		(fp_line
			(start 0.7874 -0.4064)
			(end 0.7874 0.4064)
			(stroke
				(width 0.1524)
				(type default)
			)
			(layer "F.SilkS")
		)
		(fp_line
			(start -0.67945 0.3048)
			(end -0.67945 -0.305054)
			(stroke
				(width 0.1)
				(type default)
			)
			(layer "F.Fab")
		)
		(fp_line
			(start -0.12065 0.3048)
			(end -0.67945 0.3048)
			(stroke
				(width 0.1)
				(type default)
			)
			(layer "F.Fab")
		)
		(fp_line
			(start 0.120396 0.3048)
			(end 0.120396 0.2794)
			(stroke
				(width 0.1)
				(type default)
			)
			(layer "F.Fab")
		)
		(fp_line
			(start 0.67945 0.3048)
			(end 0.120396 0.3048)
			(stroke
				(width 0.1)
				(type default)
			)
			(layer "F.Fab")
		)
		(fp_line
			(start -0.12065 0.2794)
			(end -0.12065 0.3048)
			(stroke
				(width 0.1)
				(type default)
			)
			(layer "F.Fab")
		)
		(fp_line
			(start 0.120396 0.2794)
			(end -0.12065 0.2794)
			(stroke
				(width 0.1)
				(type default)
			)
			(layer "F.Fab")
		)
		(fp_line
			(start -0.12065 -0.2794)
			(end 0.12065 -0.2794)
			(stroke
				(width 0.1)
				(type default)
			)
			(layer "F.Fab")
		)
		(fp_line
			(start 0.12065 -0.2794)
			(end 0.12065 -0.3048)
			(stroke
				(width 0.1)
				(type default)
			)
			(layer "F.Fab")
		)
		(fp_line
			(start 0.12065 -0.3048)
			(end 0.67945 -0.3048)
			(stroke
				(width 0.1)
				(type default)
			)
			(layer "F.Fab")
		)
		(fp_line
			(start 0.67945 -0.3048)
			(end 0.67945 0.3048)
			(stroke
				(width 0.1)
				(type default)
			)
			(layer "F.Fab")
		)
		(fp_line
			(start -0.67945 -0.305054)
			(end -0.12065 -0.305054)
			(stroke
				(width 0.1)
				(type default)
			)
			(layer "F.Fab")
		)
		(fp_line
			(start -0.12065 -0.305054)
			(end -0.12065 -0.2794)
			(stroke
				(width 0.1)
				(type default)
			)
			(layer "F.Fab")
		)
		(pad "1" smd circle
			(at -0.40005 0 270)
			(size 0 0)
			(layers "F.Cu" "F.Mask" "F.Paste")
			(net "P3V3_AUX")
		)
		(pad "2" smd circle
			(at 0.40005 0 270)
			(size 0 0)
			(layers "F.Cu" "F.Mask" "F.Paste")
			(net "FM_SMERR_BUF_R_LED_N")
		)
	)
	(footprint ""
		(layer "F.Cu")
		(at 103.453946 -54.882034 -90)
		(property "Reference" "R6320"
			(at 0 0 270)
			(layer "F.SilkS")
			(hide yes)
			(effects
				(font
					(size 1.27 1.27)
				)
			)
		)
		(property "Value" ""
			(at 0 0 270)
			(layer "F.Fab")
			(effects
				(font
					(size 1.27 1.27)
				)
			)
		)
		(duplicate_pad_numbers_are_jumpers no)
		(fp_line
			(start -0.7874 0.4064)
			(end -0.7874 -0.4064)
			(stroke
				(width 0.1524)
				(type default)
			)
			(layer "F.SilkS")
		)
		(fp_line
			(start 0.7874 0.4064)
			(end -0.7874 0.4064)
			(stroke
				(width 0.1524)
				(type default)
			)
			(layer "F.SilkS")
		)
		(fp_line
			(start -0.7874 -0.4064)
			(end 0.7874 -0.4064)
			(stroke
				(width 0.1524)
				(type default)
			)
			(layer "F.SilkS")
		)
		(fp_line
			(start 0.7874 -0.4064)
			(end 0.7874 0.4064)
			(stroke
				(width 0.1524)
				(type default)
			)
			(layer "F.SilkS")
		)
		(fp_line
			(start -0.67945 0.3048)
			(end -0.67945 -0.305054)
			(stroke
				(width 0.1)
				(type default)
			)
			(layer "F.Fab")
		)
		(fp_line
			(start -0.12065 0.3048)
			(end -0.67945 0.3048)
			(stroke
				(width 0.1)
				(type default)
			)
			(layer "F.Fab")
		)
		(fp_line
			(start 0.120396 0.3048)
			(end 0.120396 0.2794)
			(stroke
				(width 0.1)
				(type default)
			)
			(layer "F.Fab")
		)
		(fp_line
			(start 0.67945 0.3048)
			(end 0.120396 0.3048)
			(stroke
				(width 0.1)
				(type default)
			)
			(layer "F.Fab")
		)
		(fp_line
			(start -0.12065 0.2794)
			(end -0.12065 0.3048)
			(stroke
				(width 0.1)
				(type default)
			)
			(layer "F.Fab")
		)
		(fp_line
			(start 0.120396 0.2794)
			(end -0.12065 0.2794)
			(stroke
				(width 0.1)
				(type default)
			)
			(layer "F.Fab")
		)
		(fp_line
			(start -0.12065 -0.2794)
			(end 0.12065 -0.2794)
			(stroke
				(width 0.1)
				(type default)
			)
			(layer "F.Fab")
		)
		(fp_line
			(start 0.12065 -0.2794)
			(end 0.12065 -0.3048)
			(stroke
				(width 0.1)
				(type default)
			)
			(layer "F.Fab")
		)
		(fp_line
			(start 0.12065 -0.3048)
			(end 0.67945 -0.3048)
			(stroke
				(width 0.1)
				(type default)
			)
			(layer "F.Fab")
		)
		(fp_line
			(start 0.67945 -0.3048)
			(end 0.67945 0.3048)
			(stroke
				(width 0.1)
				(type default)
			)
			(layer "F.Fab")
		)
		(fp_line
			(start -0.67945 -0.305054)
			(end -0.12065 -0.305054)
			(stroke
				(width 0.1)
				(type default)
			)
			(layer "F.Fab")
		)
		(fp_line
			(start -0.12065 -0.305054)
			(end -0.12065 -0.2794)
			(stroke
				(width 0.1)
				(type default)
			)
			(layer "F.Fab")
		)
		(pad "1" smd circle
			(at -0.40005 0 270)
			(size 0 0)
			(layers "F.Cu" "F.Mask" "F.Paste")
			(net "P3V3_AUX")
		)
		(pad "2" smd circle
			(at 0.40005 0 270)
			(size 0 0)
			(layers "F.Cu" "F.Mask" "F.Paste")
			(net "USB_HUB2_MRP_RESET_N")
		)
	)
	(footprint ""
		(layer "F.Cu")
		(at 174.030894 -391.34288 180)
		(property "Reference" "R865"
			(at 0 0 180)
			(layer "F.SilkS")
			(hide yes)
			(effects
				(font
					(size 1.27 1.27)
				)
			)
		)
		(property "Value" ""
			(at 0 0 180)
			(layer "F.Fab")
			(effects
				(font
					(size 1.27 1.27)
				)
			)
		)
		(duplicate_pad_numbers_are_jumpers no)
		(fp_line
			(start 0.32512 0.175006)
			(end -0.32512 0.175006)
			(stroke
				(width 0.1)
				(type default)
			)
			(layer "F.Fab")
		)
		(fp_line
			(start 0.32512 -0.175006)
			(end 0.32512 0.175006)
			(stroke
				(width 0.1)
				(type default)
			)
			(layer "F.Fab")
		)
		(fp_line
			(start -0.32512 0.175006)
			(end -0.32512 -0.175006)
			(stroke
				(width 0.1)
				(type default)
			)
			(layer "F.Fab")
		)
		(fp_line
			(start -0.32512 -0.175006)
			(end 0.32512 -0.175006)
			(stroke
				(width 0.1)
				(type default)
			)
			(layer "F.Fab")
		)
		(pad "1" smd rect
			(at -0.2667 0 180)
			(size 0.3048 0.381)
			(layers "F.Cu" "F.Mask" "F.Paste")
			(net "RT_CPU1_P2_ADDR2")
		)
		(pad "2" smd rect
			(at 0.2667 0)
			(size 0.3048 0.381)
			(layers "F.Cu" "F.Mask" "F.Paste")
			(net "GND")
		)
	)
	(footprint ""
		(layer "F.Cu")
		(at 306.388516 -438.476644 90)
		(property "Reference" "R4576"
			(at 0 0 90)
			(layer "F.SilkS")
			(hide yes)
			(effects
				(font
					(size 1.27 1.27)
				)
			)
		)
		(property "Value" ""
			(at 0 0 90)
			(layer "F.Fab")
			(effects
				(font
					(size 1.27 1.27)
				)
			)
		)
		(duplicate_pad_numbers_are_jumpers no)
		(fp_line
			(start 0.7874 -0.4064)
			(end 0.7874 0.4064)
			(stroke
				(width 0.1524)
				(type default)
			)
			(layer "F.SilkS")
		)
		(fp_line
			(start -0.7874 -0.4064)
			(end 0.7874 -0.4064)
			(stroke
				(width 0.1524)
				(type default)
			)
			(layer "F.SilkS")
		)
		(fp_line
			(start 0.7874 0.4064)
			(end -0.7874 0.4064)
			(stroke
				(width 0.1524)
				(type default)
			)
			(layer "F.SilkS")
		)
		(fp_line
			(start -0.7874 0.4064)
			(end -0.7874 -0.4064)
			(stroke
				(width 0.1524)
				(type default)
			)
			(layer "F.SilkS")
		)
		(fp_line
			(start -0.12065 -0.305054)
			(end -0.12065 -0.2794)
			(stroke
				(width 0.1)
				(type default)
			)
			(layer "F.Fab")
		)
		(fp_line
			(start -0.67945 -0.305054)
			(end -0.12065 -0.305054)
			(stroke
				(width 0.1)
				(type default)
			)
			(layer "F.Fab")
		)
		(fp_line
			(start 0.67945 -0.3048)
			(end 0.67945 0.3048)
			(stroke
				(width 0.1)
				(type default)
			)
			(layer "F.Fab")
		)
		(fp_line
			(start 0.12065 -0.3048)
			(end 0.67945 -0.3048)
			(stroke
				(width 0.1)
				(type default)
			)
			(layer "F.Fab")
		)
		(fp_line
			(start 0.12065 -0.2794)
			(end 0.12065 -0.3048)
			(stroke
				(width 0.1)
				(type default)
			)
			(layer "F.Fab")
		)
		(fp_line
			(start -0.12065 -0.2794)
			(end 0.12065 -0.2794)
			(stroke
				(width 0.1)
				(type default)
			)
			(layer "F.Fab")
		)
		(fp_line
			(start 0.120396 0.2794)
			(end -0.12065 0.2794)
			(stroke
				(width 0.1)
				(type default)
			)
			(layer "F.Fab")
		)
		(fp_line
			(start -0.12065 0.2794)
			(end -0.12065 0.3048)
			(stroke
				(width 0.1)
				(type default)
			)
			(layer "F.Fab")
		)
		(fp_line
			(start 0.67945 0.3048)
			(end 0.120396 0.3048)
			(stroke
				(width 0.1)
				(type default)
			)
			(layer "F.Fab")
		)
		(fp_line
			(start 0.120396 0.3048)
			(end 0.120396 0.2794)
			(stroke
				(width 0.1)
				(type default)
			)
			(layer "F.Fab")
		)
		(fp_line
			(start -0.12065 0.3048)
			(end -0.67945 0.3048)
			(stroke
				(width 0.1)
				(type default)
			)
			(layer "F.Fab")
		)
		(fp_line
			(start -0.67945 0.3048)
			(end -0.67945 -0.305054)
			(stroke
				(width 0.1)
				(type default)
			)
			(layer "F.Fab")
		)
		(pad "1" smd circle
			(at -0.40005 0 90)
			(size 0 0)
			(layers "F.Cu" "F.Mask" "F.Paste")
			(net "GPU_3V3IO_RSVD5_FFU")
		)
		(pad "2" smd circle
			(at 0.40005 0 90)
			(size 0 0)
			(layers "F.Cu" "F.Mask" "F.Paste")
			(net "GPU_3V3IO_RSVD5_FFU_ISO")
		)
	)
	(footprint ""
		(layer "F.Cu")
		(at 33.865058 -173.55566)
		(property "Reference" "R1335"
			(at 0 0 0)
			(layer "F.SilkS")
			(hide yes)
			(effects
				(font
					(size 1.27 1.27)
				)
			)
		)
		(property "Value" ""
			(at 0 0 0)
			(layer "F.Fab")
			(effects
				(font
					(size 1.27 1.27)
				)
			)
		)
		(duplicate_pad_numbers_are_jumpers no)
		(fp_line
			(start -0.7874 -0.4064)
			(end 0.7874 -0.4064)
			(stroke
				(width 0.1524)
				(type default)
			)
			(layer "F.SilkS")
		)
		(fp_line
			(start -0.7874 0.4064)
			(end -0.7874 -0.4064)
			(stroke
				(width 0.1524)
				(type default)
			)
			(layer "F.SilkS")
		)
		(fp_line
			(start 0.7874 -0.4064)
			(end 0.7874 0.4064)
			(stroke
				(width 0.1524)
				(type default)
			)
			(layer "F.SilkS")
		)
		(fp_line
			(start 0.7874 0.4064)
			(end -0.7874 0.4064)
			(stroke
				(width 0.1524)
				(type default)
			)
			(layer "F.SilkS")
		)
		(fp_line
			(start -0.67945 -0.305054)
			(end -0.12065 -0.305054)
			(stroke
				(width 0.1)
				(type default)
			)
			(layer "F.Fab")
		)
		(fp_line
			(start -0.67945 0.3048)
			(end -0.67945 -0.305054)
			(stroke
				(width 0.1)
				(type default)
			)
			(layer "F.Fab")
		)
		(fp_line
			(start -0.12065 -0.305054)
			(end -0.12065 -0.2794)
			(stroke
				(width 0.1)
				(type default)
			)
			(layer "F.Fab")
		)
		(fp_line
			(start -0.12065 -0.2794)
			(end 0.12065 -0.2794)
			(stroke
				(width 0.1)
				(type default)
			)
			(layer "F.Fab")
		)
		(fp_line
			(start -0.12065 0.2794)
			(end -0.12065 0.3048)
			(stroke
				(width 0.1)
				(type default)
			)
			(layer "F.Fab")
		)
		(fp_line
			(start -0.12065 0.3048)
			(end -0.67945 0.3048)
			(stroke
				(width 0.1)
				(type default)
			)
			(layer "F.Fab")
		)
		(fp_line
			(start 0.120396 0.2794)
			(end -0.12065 0.2794)
			(stroke
				(width 0.1)
				(type default)
			)
			(layer "F.Fab")
		)
		(fp_line
			(start 0.120396 0.3048)
			(end 0.120396 0.2794)
			(stroke
				(width 0.1)
				(type default)
			)
			(layer "F.Fab")
		)
		(fp_line
			(start 0.12065 -0.3048)
			(end 0.67945 -0.3048)
			(stroke
				(width 0.1)
				(type default)
			)
			(layer "F.Fab")
		)
		(fp_line
			(start 0.12065 -0.2794)
			(end 0.12065 -0.3048)
			(stroke
				(width 0.1)
				(type default)
			)
			(layer "F.Fab")
		)
		(fp_line
			(start 0.67945 -0.3048)
			(end 0.67945 0.3048)
			(stroke
				(width 0.1)
				(type default)
			)
			(layer "F.Fab")
		)
		(fp_line
			(start 0.67945 0.3048)
			(end 0.120396 0.3048)
			(stroke
				(width 0.1)
				(type default)
			)
			(layer "F.Fab")
		)
		(pad "1" smd rect
			(at -0.40005 0 180)
			(size 0.4572 0.508)
			(layers "F.Cu" "F.Mask" "F.Paste")
			(net "I3C_SPD_DDRAF_CPU1_BYPASS_SDA")
		)
		(pad "2" smd rect
			(at 0.40005 0 180)
			(size 0.4572 0.508)
			(layers "F.Cu" "F.Mask" "F.Paste")
			(net "I3C_SPD_DDRAF_CPU1_SDA")
		)
	)
	(footprint ""
		(layer "F.Cu")
		(at 339.70976 -15.924276 90)
		(property "Reference" "D5"
			(at -2.9718 -0.079248 90)
			(unlocked yes)
			(layer "F.SilkS")
			(effects
				(font
					(size 0.7874 0.5842)
					(thickness 0.1524)
				)
				(justify left)
			)
		)
		(property "Value" ""
			(at 0 0 90)
			(layer "F.Fab")
			(effects
				(font
					(size 1.27 1.27)
				)
			)
		)
		(duplicate_pad_numbers_are_jumpers no)
		(fp_line
			(start 1.16078 -0.4826)
			(end 1.16078 0.4826)
			(stroke
				(width 0.1524)
				(type default)
			)
			(layer "F.SilkS")
		)
		(fp_line
			(start 1.03378 -0.4826)
			(end 1.03378 0.4826)
			(stroke
				(width 0.1524)
				(type default)
			)
			(layer "F.SilkS")
		)
		(fp_line
			(start 0.90678 -0.4826)
			(end 0.90678 0.4826)
			(stroke
				(width 0.1524)
				(type default)
			)
			(layer "F.SilkS")
		)
		(fp_line
			(start -0.64008 -0.4826)
			(end 1.16078 -0.4826)
			(stroke
				(width 0.1524)
				(type default)
			)
			(layer "F.SilkS")
		)
		(fp_line
			(start -0.79248 -0.4826)
			(end 1.03378 -0.4826)
			(stroke
				(width 0.1524)
				(type default)
			)
			(layer "F.SilkS")
		)
		(fp_line
			(start -0.89408 -0.4826)
			(end 0.90678 -0.4826)
			(stroke
				(width 0.1524)
				(type default)
			)
			(layer "F.SilkS")
		)
		(fp_line
			(start 1.16078 0.4826)
			(end -0.64008 0.4826)
			(stroke
				(width 0.1524)
				(type default)
			)
			(layer "F.SilkS")
		)
		(fp_line
			(start 1.03378 0.4826)
			(end -0.79248 0.4826)
			(stroke
				(width 0.1524)
				(type default)
			)
			(layer "F.SilkS")
		)
		(fp_line
			(start 0.90678 0.4826)
			(end -0.90678 0.4826)
			(stroke
				(width 0.1524)
				(type default)
			)
			(layer "F.SilkS")
		)
		(fp_line
			(start -0.90678 0.4826)
			(end -0.90678 -0.4699)
			(stroke
				(width 0.1524)
				(type default)
			)
			(layer "F.SilkS")
		)
		(fp_line
			(start 0.499872 -0.249936)
			(end 0.499872 0.249936)
			(stroke
				(width 0.1)
				(type default)
			)
			(layer "F.Fab")
		)
		(fp_line
			(start -0.499872 -0.249936)
			(end 0.499872 -0.249936)
			(stroke
				(width 0.1)
				(type default)
			)
			(layer "F.Fab")
		)
		(fp_line
			(start 0.499872 0.249936)
			(end -0.499872 0.249936)
			(stroke
				(width 0.1)
				(type default)
			)
			(layer "F.Fab")
		)
		(fp_line
			(start -0.499872 0.249936)
			(end -0.499872 -0.249936)
			(stroke
				(width 0.1)
				(type default)
			)
			(layer "F.Fab")
		)
		(pad "A" smd rect
			(at -0.47498 0 90)
			(size 0.6096 0.7112)
			(layers "F.Cu" "F.Mask" "F.Paste")
			(net "PU_BOOT_RDY_LED")
		)
		(pad "C" smd rect
			(at 0.47498 0 90)
			(size 0.6096 0.7112)
			(layers "F.Cu" "F.Mask" "F.Paste")
			(net "BOOT_RDY_LED_N")
		)
	)
	(footprint ""
		(layer "F.Cu")
		(at 303.69383 -153.917142 180)
		(property "Reference" "TP9"
			(at 2.88544 -0.005334 0)
			(unlocked yes)
			(layer "F.SilkS")
			(effects
				(font
					(size 0.7874 0.5842)
					(thickness 0.1524)
				)
				(justify left)
			)
		)
		(property "Value" ""
			(at 0 0 180)
			(layer "F.Fab")
			(effects
				(font
					(size 1.27 1.27)
				)
			)
		)
		(duplicate_pad_numbers_are_jumpers no)
		(pad "1" smd circle
			(at 0 0 180)
			(size 0.762 0.762)
			(layers "F.Cu" "F.Mask" "F.Paste")
			(net "VSENSE_PVDD18_S5_P0_DP")
		)
	)
	(footprint ""
		(layer "F.Cu")
		(at 344.344244 -383.88163 -90)
		(property "Reference" "C950"
			(at 0 0 270)
			(layer "F.SilkS")
			(hide yes)
			(effects
				(font
					(size 1.27 1.27)
				)
			)
		)
		(property "Value" ""
			(at 0 0 270)
			(layer "F.Fab")
			(effects
				(font
					(size 1.27 1.27)
				)
			)
		)
		(duplicate_pad_numbers_are_jumpers no)
		(fp_line
			(start -0.299974 0.150114)
			(end -0.299974 -0.150114)
			(stroke
				(width 0.1)
				(type default)
			)
			(layer "F.Fab")
		)
		(fp_line
			(start 0.299974 0.150114)
			(end -0.299974 0.150114)
			(stroke
				(width 0.1)
				(type default)
			)
			(layer "F.Fab")
		)
		(fp_line
			(start -0.299974 -0.150114)
			(end 0.299974 -0.150114)
			(stroke
				(width 0.1)
				(type default)
			)
			(layer "F.Fab")
		)
		(fp_line
			(start 0.299974 -0.150114)
			(end 0.299974 0.150114)
			(stroke
				(width 0.1)
				(type default)
			)
			(layer "F.Fab")
		)
		(pad "1" smd rect
			(at -0.2667 0 270)
			(size 0.3048 0.381)
			(layers "F.Cu" "F.Mask" "F.Paste")
			(net "P5E_CPU0_P1_TX_C_DN<7>")
		)
		(pad "2" smd rect
			(at 0.2667 0 270)
			(size 0.3048 0.381)
			(layers "F.Cu" "F.Mask" "F.Paste")
			(net "P5E_CPU0_P1_TX_DN<7>")
		)
	)
	(footprint ""
		(layer "F.Cu")
		(at 398.595088 -389.86206 180)
		(property "Reference" "C868"
			(at 0 0 180)
			(layer "F.SilkS")
			(hide yes)
			(effects
				(font
					(size 1.27 1.27)
				)
			)
		)
		(property "Value" ""
			(at 0 0 180)
			(layer "F.Fab")
			(effects
				(font
					(size 1.27 1.27)
				)
			)
		)
		(duplicate_pad_numbers_are_jumpers no)
		(fp_line
			(start 0.299974 0.150114)
			(end -0.299974 0.150114)
			(stroke
				(width 0.1)
				(type default)
			)
			(layer "F.Fab")
		)
		(fp_line
			(start 0.299974 -0.150114)
			(end 0.299974 0.150114)
			(stroke
				(width 0.1)
				(type default)
			)
			(layer "F.Fab")
		)
		(fp_line
			(start -0.299974 0.150114)
			(end -0.299974 -0.150114)
			(stroke
				(width 0.1)
				(type default)
			)
			(layer "F.Fab")
		)
		(fp_line
			(start -0.299974 -0.150114)
			(end 0.299974 -0.150114)
			(stroke
				(width 0.1)
				(type default)
			)
			(layer "F.Fab")
		)
		(pad "1" smd rect
			(at -0.2667 0 180)
			(size 0.3048 0.381)
			(layers "F.Cu" "F.Mask" "F.Paste")
			(net "P5E_CPU0_P2_TX_C_DN<0>")
		)
		(pad "2" smd rect
			(at 0.2667 0 180)
			(size 0.3048 0.381)
			(layers "F.Cu" "F.Mask" "F.Paste")
			(net "P5E_CPU0_P2_TX_DN<0>")
		)
	)
	(footprint ""
		(layer "F.Cu")
		(at 118.718584 -60.900056)
		(property "Reference" "R1736"
			(at 0 0 0)
			(layer "F.SilkS")
			(hide yes)
			(effects
				(font
					(size 1.27 1.27)
				)
			)
		)
		(property "Value" ""
			(at 0 0 0)
			(layer "F.Fab")
			(effects
				(font
					(size 1.27 1.27)
				)
			)
		)
		(duplicate_pad_numbers_are_jumpers no)
		(fp_line
			(start -0.7874 -0.4064)
			(end 0.7874 -0.4064)
			(stroke
				(width 0.1524)
				(type default)
			)
			(layer "F.SilkS")
		)
		(fp_line
			(start -0.7874 0.4064)
			(end -0.7874 -0.4064)
			(stroke
				(width 0.1524)
				(type default)
			)
			(layer "F.SilkS")
		)
		(fp_line
			(start 0.7874 -0.4064)
			(end 0.7874 0.4064)
			(stroke
				(width 0.1524)
				(type default)
			)
			(layer "F.SilkS")
		)
		(fp_line
			(start 0.7874 0.4064)
			(end -0.7874 0.4064)
			(stroke
				(width 0.1524)
				(type default)
			)
			(layer "F.SilkS")
		)
		(fp_line
			(start -0.67945 -0.305054)
			(end -0.12065 -0.305054)
			(stroke
				(width 0.1)
				(type default)
			)
			(layer "F.Fab")
		)
		(fp_line
			(start -0.67945 0.3048)
			(end -0.67945 -0.305054)
			(stroke
				(width 0.1)
				(type default)
			)
			(layer "F.Fab")
		)
		(fp_line
			(start -0.12065 -0.305054)
			(end -0.12065 -0.2794)
			(stroke
				(width 0.1)
				(type default)
			)
			(layer "F.Fab")
		)
		(fp_line
			(start -0.12065 -0.2794)
			(end 0.12065 -0.2794)
			(stroke
				(width 0.1)
				(type default)
			)
			(layer "F.Fab")
		)
		(fp_line
			(start -0.12065 0.2794)
			(end -0.12065 0.3048)
			(stroke
				(width 0.1)
				(type default)
			)
			(layer "F.Fab")
		)
		(fp_line
			(start -0.12065 0.3048)
			(end -0.67945 0.3048)
			(stroke
				(width 0.1)
				(type default)
			)
			(layer "F.Fab")
		)
		(fp_line
			(start 0.120396 0.2794)
			(end -0.12065 0.2794)
			(stroke
				(width 0.1)
				(type default)
			)
			(layer "F.Fab")
		)
		(fp_line
			(start 0.120396 0.3048)
			(end 0.120396 0.2794)
			(stroke
				(width 0.1)
				(type default)
			)
			(layer "F.Fab")
		)
		(fp_line
			(start 0.12065 -0.3048)
			(end 0.67945 -0.3048)
			(stroke
				(width 0.1)
				(type default)
			)
			(layer "F.Fab")
		)
		(fp_line
			(start 0.12065 -0.2794)
			(end 0.12065 -0.3048)
			(stroke
				(width 0.1)
				(type default)
			)
			(layer "F.Fab")
		)
		(fp_line
			(start 0.67945 -0.3048)
			(end 0.67945 0.3048)
			(stroke
				(width 0.1)
				(type default)
			)
			(layer "F.Fab")
		)
		(fp_line
			(start 0.67945 0.3048)
			(end 0.120396 0.3048)
			(stroke
				(width 0.1)
				(type default)
			)
			(layer "F.Fab")
		)
		(pad "1" smd circle
			(at -0.40005 0)
			(size 0 0)
			(layers "F.Cu" "F.Mask" "F.Paste")
			(net "JTAG_SCM_MUX_R_TCK")
		)
		(pad "2" smd circle
			(at 0.40005 0)
			(size 0 0)
			(layers "F.Cu" "F.Mask" "F.Paste")
			(net "JTAG_SCM_MUX_TCK")
		)
	)
	(footprint ""
		(layer "F.Cu")
		(at 398.61744 -381.41783 -90)
		(property "Reference" "C865"
			(at 0 0 270)
			(layer "F.SilkS")
			(hide yes)
			(effects
				(font
					(size 1.27 1.27)
				)
			)
		)
		(property "Value" ""
			(at 0 0 270)
			(layer "F.Fab")
			(effects
				(font
					(size 1.27 1.27)
				)
			)
		)
		(duplicate_pad_numbers_are_jumpers no)
		(fp_line
			(start -0.299974 0.150114)
			(end -0.299974 -0.150114)
			(stroke
				(width 0.1)
				(type default)
			)
			(layer "F.Fab")
		)
		(fp_line
			(start 0.299974 0.150114)
			(end -0.299974 0.150114)
			(stroke
				(width 0.1)
				(type default)
			)
			(layer "F.Fab")
		)
		(fp_line
			(start -0.299974 -0.150114)
			(end 0.299974 -0.150114)
			(stroke
				(width 0.1)
				(type default)
			)
			(layer "F.Fab")
		)
		(fp_line
			(start 0.299974 -0.150114)
			(end 0.299974 0.150114)
			(stroke
				(width 0.1)
				(type default)
			)
			(layer "F.Fab")
		)
		(pad "1" smd rect
			(at -0.2667 0 270)
			(size 0.3048 0.381)
			(layers "F.Cu" "F.Mask" "F.Paste")
			(net "P5E_CPU0_P2_TX_C_DP<2>")
		)
		(pad "2" smd rect
			(at 0.2667 0 270)
			(size 0.3048 0.381)
			(layers "F.Cu" "F.Mask" "F.Paste")
			(net "P5E_CPU0_P2_TX_DP<2>")
		)
	)
	(footprint ""
		(layer "F.Cu")
		(at 87.557864 -57.16778)
		(property "Reference" "R3833"
			(at 0 0 0)
			(layer "F.SilkS")
			(hide yes)
			(effects
				(font
					(size 1.27 1.27)
				)
			)
		)
		(property "Value" ""
			(at 0 0 0)
			(layer "F.Fab")
			(effects
				(font
					(size 1.27 1.27)
				)
			)
		)
		(duplicate_pad_numbers_are_jumpers no)
		(fp_line
			(start -0.7874 -0.4064)
			(end 0.7874 -0.4064)
			(stroke
				(width 0.1524)
				(type default)
			)
			(layer "F.SilkS")
		)
		(fp_line
			(start -0.7874 0.4064)
			(end -0.7874 -0.4064)
			(stroke
				(width 0.1524)
				(type default)
			)
			(layer "F.SilkS")
		)
		(fp_line
			(start 0.7874 -0.4064)
			(end 0.7874 0.4064)
			(stroke
				(width 0.1524)
				(type default)
			)
			(layer "F.SilkS")
		)
		(fp_line
			(start 0.7874 0.4064)
			(end -0.7874 0.4064)
			(stroke
				(width 0.1524)
				(type default)
			)
			(layer "F.SilkS")
		)
		(fp_line
			(start -0.67945 -0.305054)
			(end -0.12065 -0.305054)
			(stroke
				(width 0.1)
				(type default)
			)
			(layer "F.Fab")
		)
		(fp_line
			(start -0.67945 0.3048)
			(end -0.67945 -0.305054)
			(stroke
				(width 0.1)
				(type default)
			)
			(layer "F.Fab")
		)
		(fp_line
			(start -0.12065 -0.305054)
			(end -0.12065 -0.2794)
			(stroke
				(width 0.1)
				(type default)
			)
			(layer "F.Fab")
		)
		(fp_line
			(start -0.12065 -0.2794)
			(end 0.12065 -0.2794)
			(stroke
				(width 0.1)
				(type default)
			)
			(layer "F.Fab")
		)
		(fp_line
			(start -0.12065 0.2794)
			(end -0.12065 0.3048)
			(stroke
				(width 0.1)
				(type default)
			)
			(layer "F.Fab")
		)
		(fp_line
			(start -0.12065 0.3048)
			(end -0.67945 0.3048)
			(stroke
				(width 0.1)
				(type default)
			)
			(layer "F.Fab")
		)
		(fp_line
			(start 0.120396 0.2794)
			(end -0.12065 0.2794)
			(stroke
				(width 0.1)
				(type default)
			)
			(layer "F.Fab")
		)
		(fp_line
			(start 0.120396 0.3048)
			(end 0.120396 0.2794)
			(stroke
				(width 0.1)
				(type default)
			)
			(layer "F.Fab")
		)
		(fp_line
			(start 0.12065 -0.3048)
			(end 0.67945 -0.3048)
			(stroke
				(width 0.1)
				(type default)
			)
			(layer "F.Fab")
		)
		(fp_line
			(start 0.12065 -0.2794)
			(end 0.12065 -0.3048)
			(stroke
				(width 0.1)
				(type default)
			)
			(layer "F.Fab")
		)
		(fp_line
			(start 0.67945 -0.3048)
			(end 0.67945 0.3048)
			(stroke
				(width 0.1)
				(type default)
			)
			(layer "F.Fab")
		)
		(fp_line
			(start 0.67945 0.3048)
			(end 0.120396 0.3048)
			(stroke
				(width 0.1)
				(type default)
			)
			(layer "F.Fab")
		)
		(pad "1" smd circle
			(at -0.40005 0)
			(size 0 0)
			(layers "F.Cu" "F.Mask" "F.Paste")
			(net "P3V3_AUX")
		)
		(pad "2" smd circle
			(at 0.40005 0)
			(size 0 0)
			(layers "F.Cu" "F.Mask" "F.Paste")
			(net "P3V3_OCP_FAULT_2")
		)
	)
	(footprint ""
		(layer "F.Cu")
		(at 435.102 -165.9509 90)
		(property "Reference" "R1332"
			(at 0 0 90)
			(layer "F.SilkS")
			(hide yes)
			(effects
				(font
					(size 1.27 1.27)
				)
			)
		)
		(property "Value" ""
			(at 0 0 90)
			(layer "F.Fab")
			(effects
				(font
					(size 1.27 1.27)
				)
			)
		)
		(duplicate_pad_numbers_are_jumpers no)
		(fp_line
			(start 0.7874 -0.4064)
			(end 0.7874 0.4064)
			(stroke
				(width 0.1524)
				(type default)
			)
			(layer "F.SilkS")
		)
		(fp_line
			(start -0.7874 -0.4064)
			(end 0.7874 -0.4064)
			(stroke
				(width 0.1524)
				(type default)
			)
			(layer "F.SilkS")
		)
		(fp_line
			(start 0.7874 0.4064)
			(end -0.7874 0.4064)
			(stroke
				(width 0.1524)
				(type default)
			)
			(layer "F.SilkS")
		)
		(fp_line
			(start -0.7874 0.4064)
			(end -0.7874 -0.4064)
			(stroke
				(width 0.1524)
				(type default)
			)
			(layer "F.SilkS")
		)
		(fp_line
			(start -0.12065 -0.305054)
			(end -0.12065 -0.2794)
			(stroke
				(width 0.1)
				(type default)
			)
			(layer "F.Fab")
		)
		(fp_line
			(start -0.67945 -0.305054)
			(end -0.12065 -0.305054)
			(stroke
				(width 0.1)
				(type default)
			)
			(layer "F.Fab")
		)
		(fp_line
			(start 0.67945 -0.3048)
			(end 0.67945 0.3048)
			(stroke
				(width 0.1)
				(type default)
			)
			(layer "F.Fab")
		)
		(fp_line
			(start 0.12065 -0.3048)
			(end 0.67945 -0.3048)
			(stroke
				(width 0.1)
				(type default)
			)
			(layer "F.Fab")
		)
		(fp_line
			(start 0.12065 -0.2794)
			(end 0.12065 -0.3048)
			(stroke
				(width 0.1)
				(type default)
			)
			(layer "F.Fab")
		)
		(fp_line
			(start -0.12065 -0.2794)
			(end 0.12065 -0.2794)
			(stroke
				(width 0.1)
				(type default)
			)
			(layer "F.Fab")
		)
		(fp_line
			(start 0.120396 0.2794)
			(end -0.12065 0.2794)
			(stroke
				(width 0.1)
				(type default)
			)
			(layer "F.Fab")
		)
		(fp_line
			(start -0.12065 0.2794)
			(end -0.12065 0.3048)
			(stroke
				(width 0.1)
				(type default)
			)
			(layer "F.Fab")
		)
		(fp_line
			(start 0.67945 0.3048)
			(end 0.120396 0.3048)
			(stroke
				(width 0.1)
				(type default)
			)
			(layer "F.Fab")
		)
		(fp_line
			(start 0.120396 0.3048)
			(end 0.120396 0.2794)
			(stroke
				(width 0.1)
				(type default)
			)
			(layer "F.Fab")
		)
		(fp_line
			(start -0.12065 0.3048)
			(end -0.67945 0.3048)
			(stroke
				(width 0.1)
				(type default)
			)
			(layer "F.Fab")
		)
		(fp_line
			(start -0.67945 0.3048)
			(end -0.67945 -0.305054)
			(stroke
				(width 0.1)
				(type default)
			)
			(layer "F.Fab")
		)
		(pad "1" smd rect
			(at -0.40005 0 270)
			(size 0.4572 0.508)
			(layers "F.Cu" "F.Mask" "F.Paste")
			(net "I3C_SPD_DDRGL_CPU0_BYPASS_SCL")
		)
		(pad "2" smd rect
			(at 0.40005 0 270)
			(size 0.4572 0.508)
			(layers "F.Cu" "F.Mask" "F.Paste")
			(net "I3C_SPD_DDRGL_CPU0_SCL")
		)
	)
	(footprint ""
		(layer "F.Cu")
		(at 12.896342 -194.36715 -90)
		(property "Reference" "R1837"
			(at -4.2799 1.094232 90)
			(unlocked yes)
			(layer "F.SilkS")
			(effects
				(font
					(size 0.7874 0.5842)
					(thickness 0.1524)
				)
				(justify left)
			)
		)
		(property "Value" ""
			(at 0 0 270)
			(layer "F.Fab")
			(effects
				(font
					(size 1.27 1.27)
				)
			)
		)
		(duplicate_pad_numbers_are_jumpers no)
		(fp_line
			(start -4.0386 1.7526)
			(end -4.0386 -1.7526)
			(stroke
				(width 0.1524)
				(type default)
			)
			(layer "F.SilkS")
		)
		(fp_line
			(start 4.0386 1.7526)
			(end -4.0386 1.7526)
			(stroke
				(width 0.1524)
				(type default)
			)
			(layer "F.SilkS")
		)
		(fp_line
			(start -4.0386 -1.7526)
			(end 4.0386 -1.7526)
			(stroke
				(width 0.1524)
				(type default)
			)
			(layer "F.SilkS")
		)
		(fp_line
			(start 4.0386 -1.7526)
			(end 4.0386 1.7526)
			(stroke
				(width 0.1524)
				(type default)
			)
			(layer "F.SilkS")
		)
		(fp_line
			(start -4.0386 1.7526)
			(end -4.0386 -1.7526)
			(stroke
				(width 0.1)
				(type default)
			)
			(layer "F.Fab")
		)
		(fp_line
			(start 4.0386 1.7526)
			(end -4.0386 1.7526)
			(stroke
				(width 0.1)
				(type default)
			)
			(layer "F.Fab")
		)
		(fp_line
			(start -4.0386 -1.7526)
			(end 4.0386 -1.7526)
			(stroke
				(width 0.1)
				(type default)
			)
			(layer "F.Fab")
		)
		(fp_line
			(start 4.0386 -1.7526)
			(end 4.0386 1.7526)
			(stroke
				(width 0.1)
				(type default)
			)
			(layer "F.Fab")
		)
		(pad "1" smd circle
			(at -3.700018 0 180)
			(size 0 0)
			(layers "F.Cu" "F.Mask" "F.Paste")
			(net "P12V_AUX")
		)
		(pad "2" smd circle
			(at 3.700018 0)
			(size 0 0)
			(layers "F.Cu" "F.Mask" "F.Paste")
			(net "P12V_MEM_CPU1")
		)
		(pad "3" smd rect
			(at -2.70002 0)
			(size 0.4064 1.1176)
			(layers "F.Cu" "F.Mask" "F.Paste")
			(net "TP_P12V_AUX_CPU1_DIMM_ISEN_P")
		)
		(pad "4" smd rect
			(at 2.70002 0)
			(size 0.4064 1.1176)
			(layers "F.Cu" "F.Mask" "F.Paste")
			(net "TP_P12V_AUX_CPU1_DIMM_ISEN_N")
		)
	)
	(footprint ""
		(layer "F.Cu")
		(at 380.899924 -22.29993)
		(property "Reference" "H87"
			(at -5.041392 -5.687568 0)
			(unlocked yes)
			(layer "F.SilkS")
			(effects
				(font
					(size 0.7874 0.5842)
					(thickness 0.1524)
				)
				(justify left)
			)
		)
		(property "Value" ""
			(at 0 0 0)
			(layer "F.Fab")
			(effects
				(font
					(size 1.27 1.27)
				)
			)
		)
		(duplicate_pad_numbers_are_jumpers no)
		(pad "1" thru_hole circle
			(at 0 0)
			(size 10.0076 10.0076)
			(drill 5.6134)
			(layers "*.Cu" "*.Mask")
			(remove_unused_layers no)
			(net "GND")
			(clearance -1.9431)
		)
	)
	(footprint ""
		(layer "F.Cu")
		(at 429.4632 -16.100298 90)
		(property "Reference" "C1576"
			(at 0 0 90)
			(layer "F.SilkS")
			(hide yes)
			(effects
				(font
					(size 1.27 1.27)
				)
			)
		)
		(property "Value" ""
			(at 0 0 90)
			(layer "F.Fab")
			(effects
				(font
					(size 1.27 1.27)
				)
			)
		)
		(duplicate_pad_numbers_are_jumpers no)
		(fp_line
			(start 0.299974 -0.150114)
			(end 0.299974 0.150114)
			(stroke
				(width 0.1)
				(type default)
			)
			(layer "F.Fab")
		)
		(fp_line
			(start -0.299974 -0.150114)
			(end 0.299974 -0.150114)
			(stroke
				(width 0.1)
				(type default)
			)
			(layer "F.Fab")
		)
		(fp_line
			(start 0.299974 0.150114)
			(end -0.299974 0.150114)
			(stroke
				(width 0.1)
				(type default)
			)
			(layer "F.Fab")
		)
		(fp_line
			(start -0.299974 0.150114)
			(end -0.299974 -0.150114)
			(stroke
				(width 0.1)
				(type default)
			)
			(layer "F.Fab")
		)
		(pad "1" smd rect
			(at -0.2667 0 90)
			(size 0.3048 0.381)
			(layers "F.Cu" "F.Mask" "F.Paste")
			(net "P5E_CPU0_G3_TX_C_DN<1>")
		)
		(pad "2" smd rect
			(at 0.2667 0 90)
			(size 0.3048 0.381)
			(layers "F.Cu" "F.Mask" "F.Paste")
			(net "P5E_CPU0_G3_TX_DN<1>")
		)
	)
	(footprint ""
		(layer "F.Cu")
		(at 110.63732 -325.116444 180)
		(property "Reference" "TP16"
			(at -0.91948 -0.099314 0)
			(unlocked yes)
			(layer "F.SilkS")
			(effects
				(font
					(size 0.7874 0.5842)
					(thickness 0.1524)
				)
				(justify left)
			)
		)
		(property "Value" ""
			(at 0 0 180)
			(layer "F.Fab")
			(effects
				(font
					(size 1.27 1.27)
				)
			)
		)
		(duplicate_pad_numbers_are_jumpers no)
		(pad "1" smd circle
			(at 0 0 180)
			(size 0.762 0.762)
			(layers "F.Cu" "F.Mask" "F.Paste")
			(net "VSENSE_PVDDCR_CPU1_P1_DP")
		)
	)
	(footprint ""
		(layer "F.Cu")
		(at 40.51554 -346.813632 -90)
		(property "Reference" "PC624_3"
			(at 0 0 270)
			(layer "F.SilkS")
			(hide yes)
			(effects
				(font
					(size 1.27 1.27)
				)
			)
		)
		(property "Value" ""
			(at 0 0 270)
			(layer "F.Fab")
			(effects
				(font
					(size 1.27 1.27)
				)
			)
		)
		(duplicate_pad_numbers_are_jumpers no)
		(fp_line
			(start -0.7874 0.4064)
			(end -0.7874 -0.4064)
			(stroke
				(width 0.1524)
				(type default)
			)
			(layer "F.SilkS")
		)
		(fp_line
			(start 0.7874 0.4064)
			(end -0.7874 0.4064)
			(stroke
				(width 0.1524)
				(type default)
			)
			(layer "F.SilkS")
		)
		(fp_line
			(start -0.7874 -0.4064)
			(end 0.7874 -0.4064)
			(stroke
				(width 0.1524)
				(type default)
			)
			(layer "F.SilkS")
		)
		(fp_line
			(start 0.7874 -0.4064)
			(end 0.7874 0.4064)
			(stroke
				(width 0.1524)
				(type default)
			)
			(layer "F.SilkS")
		)
		(fp_line
			(start -0.67945 0.3048)
			(end -0.67945 -0.305054)
			(stroke
				(width 0.1)
				(type default)
			)
			(layer "F.Fab")
		)
		(fp_line
			(start -0.12065 0.3048)
			(end -0.67945 0.3048)
			(stroke
				(width 0.1)
				(type default)
			)
			(layer "F.Fab")
		)
		(fp_line
			(start 0.120396 0.3048)
			(end 0.120396 0.2794)
			(stroke
				(width 0.1)
				(type default)
			)
			(layer "F.Fab")
		)
		(fp_line
			(start 0.67945 0.3048)
			(end 0.120396 0.3048)
			(stroke
				(width 0.1)
				(type default)
			)
			(layer "F.Fab")
		)
		(fp_line
			(start -0.12065 0.2794)
			(end -0.12065 0.3048)
			(stroke
				(width 0.1)
				(type default)
			)
			(layer "F.Fab")
		)
		(fp_line
			(start 0.120396 0.2794)
			(end -0.12065 0.2794)
			(stroke
				(width 0.1)
				(type default)
			)
			(layer "F.Fab")
		)
		(fp_line
			(start -0.12065 -0.2794)
			(end 0.12065 -0.2794)
			(stroke
				(width 0.1)
				(type default)
			)
			(layer "F.Fab")
		)
		(fp_line
			(start 0.12065 -0.2794)
			(end 0.12065 -0.3048)
			(stroke
				(width 0.1)
				(type default)
			)
			(layer "F.Fab")
		)
		(fp_line
			(start 0.12065 -0.3048)
			(end 0.67945 -0.3048)
			(stroke
				(width 0.1)
				(type default)
			)
			(layer "F.Fab")
		)
		(fp_line
			(start 0.67945 -0.3048)
			(end 0.67945 0.3048)
			(stroke
				(width 0.1)
				(type default)
			)
			(layer "F.Fab")
		)
		(fp_line
			(start -0.67945 -0.305054)
			(end -0.12065 -0.305054)
			(stroke
				(width 0.1)
				(type default)
			)
			(layer "F.Fab")
		)
		(fp_line
			(start -0.12065 -0.305054)
			(end -0.12065 -0.2794)
			(stroke
				(width 0.1)
				(type default)
			)
			(layer "F.Fab")
		)
		(pad "1" smd circle
			(at -0.40005 0 270)
			(size 0 0)
			(layers "F.Cu" "F.Mask" "F.Paste")
			(net "SW_P12V_AUX_PVDDIO_P1_FLT")
		)
		(pad "2" smd circle
			(at 0.40005 0 270)
			(size 0 0)
			(layers "F.Cu" "F.Mask" "F.Paste")
			(net "GND")
		)
	)
	(footprint ""
		(layer "F.Cu")
		(at 49.784 -39.751)
		(property "Reference" "R1165"
			(at 0 0 0)
			(layer "F.SilkS")
			(hide yes)
			(effects
				(font
					(size 1.27 1.27)
				)
			)
		)
		(property "Value" ""
			(at 0 0 0)
			(layer "F.Fab")
			(effects
				(font
					(size 1.27 1.27)
				)
			)
		)
		(duplicate_pad_numbers_are_jumpers no)
		(fp_line
			(start -0.7874 -0.4064)
			(end 0.7874 -0.4064)
			(stroke
				(width 0.1524)
				(type default)
			)
			(layer "F.SilkS")
		)
		(fp_line
			(start -0.7874 0.4064)
			(end -0.7874 -0.4064)
			(stroke
				(width 0.1524)
				(type default)
			)
			(layer "F.SilkS")
		)
		(fp_line
			(start 0.7874 -0.4064)
			(end 0.7874 0.4064)
			(stroke
				(width 0.1524)
				(type default)
			)
			(layer "F.SilkS")
		)
		(fp_line
			(start 0.7874 0.4064)
			(end -0.7874 0.4064)
			(stroke
				(width 0.1524)
				(type default)
			)
			(layer "F.SilkS")
		)
		(fp_line
			(start -0.67945 -0.305054)
			(end -0.12065 -0.305054)
			(stroke
				(width 0.1)
				(type default)
			)
			(layer "F.Fab")
		)
		(fp_line
			(start -0.67945 0.3048)
			(end -0.67945 -0.305054)
			(stroke
				(width 0.1)
				(type default)
			)
			(layer "F.Fab")
		)
		(fp_line
			(start -0.12065 -0.305054)
			(end -0.12065 -0.2794)
			(stroke
				(width 0.1)
				(type default)
			)
			(layer "F.Fab")
		)
		(fp_line
			(start -0.12065 -0.2794)
			(end 0.12065 -0.2794)
			(stroke
				(width 0.1)
				(type default)
			)
			(layer "F.Fab")
		)
		(fp_line
			(start -0.12065 0.2794)
			(end -0.12065 0.3048)
			(stroke
				(width 0.1)
				(type default)
			)
			(layer "F.Fab")
		)
		(fp_line
			(start -0.12065 0.3048)
			(end -0.67945 0.3048)
			(stroke
				(width 0.1)
				(type default)
			)
			(layer "F.Fab")
		)
		(fp_line
			(start 0.120396 0.2794)
			(end -0.12065 0.2794)
			(stroke
				(width 0.1)
				(type default)
			)
			(layer "F.Fab")
		)
		(fp_line
			(start 0.120396 0.3048)
			(end 0.120396 0.2794)
			(stroke
				(width 0.1)
				(type default)
			)
			(layer "F.Fab")
		)
		(fp_line
			(start 0.12065 -0.3048)
			(end 0.67945 -0.3048)
			(stroke
				(width 0.1)
				(type default)
			)
			(layer "F.Fab")
		)
		(fp_line
			(start 0.12065 -0.2794)
			(end 0.12065 -0.3048)
			(stroke
				(width 0.1)
				(type default)
			)
			(layer "F.Fab")
		)
		(fp_line
			(start 0.67945 -0.3048)
			(end 0.67945 0.3048)
			(stroke
				(width 0.1)
				(type default)
			)
			(layer "F.Fab")
		)
		(fp_line
			(start 0.67945 0.3048)
			(end 0.120396 0.3048)
			(stroke
				(width 0.1)
				(type default)
			)
			(layer "F.Fab")
		)
		(pad "1" smd circle
			(at -0.40005 0)
			(size 0 0)
			(layers "F.Cu" "F.Mask" "F.Paste")
			(net "P3V3_AUX")
		)
		(pad "2" smd circle
			(at 0.40005 0)
			(size 0 0)
			(layers "F.Cu" "F.Mask" "F.Paste")
			(net "P12V_OCP_V3_2_EN_R3")
		)
	)
	(footprint ""
		(layer "F.Cu")
		(at 49.657 -37.846)
		(property "Reference" "R1149"
			(at 0 0 0)
			(layer "F.SilkS")
			(hide yes)
			(effects
				(font
					(size 1.27 1.27)
				)
			)
		)
		(property "Value" ""
			(at 0 0 0)
			(layer "F.Fab")
			(effects
				(font
					(size 1.27 1.27)
				)
			)
		)
		(duplicate_pad_numbers_are_jumpers no)
		(fp_line
			(start -0.7874 -0.4064)
			(end 0.7874 -0.4064)
			(stroke
				(width 0.1524)
				(type default)
			)
			(layer "F.SilkS")
		)
		(fp_line
			(start -0.7874 0.4064)
			(end -0.7874 -0.4064)
			(stroke
				(width 0.1524)
				(type default)
			)
			(layer "F.SilkS")
		)
		(fp_line
			(start 0.7874 -0.4064)
			(end 0.7874 0.4064)
			(stroke
				(width 0.1524)
				(type default)
			)
			(layer "F.SilkS")
		)
		(fp_line
			(start 0.7874 0.4064)
			(end -0.7874 0.4064)
			(stroke
				(width 0.1524)
				(type default)
			)
			(layer "F.SilkS")
		)
		(fp_line
			(start -0.67945 -0.305054)
			(end -0.12065 -0.305054)
			(stroke
				(width 0.1)
				(type default)
			)
			(layer "F.Fab")
		)
		(fp_line
			(start -0.67945 0.3048)
			(end -0.67945 -0.305054)
			(stroke
				(width 0.1)
				(type default)
			)
			(layer "F.Fab")
		)
		(fp_line
			(start -0.12065 -0.305054)
			(end -0.12065 -0.2794)
			(stroke
				(width 0.1)
				(type default)
			)
			(layer "F.Fab")
		)
		(fp_line
			(start -0.12065 -0.2794)
			(end 0.12065 -0.2794)
			(stroke
				(width 0.1)
				(type default)
			)
			(layer "F.Fab")
		)
		(fp_line
			(start -0.12065 0.2794)
			(end -0.12065 0.3048)
			(stroke
				(width 0.1)
				(type default)
			)
			(layer "F.Fab")
		)
		(fp_line
			(start -0.12065 0.3048)
			(end -0.67945 0.3048)
			(stroke
				(width 0.1)
				(type default)
			)
			(layer "F.Fab")
		)
		(fp_line
			(start 0.120396 0.2794)
			(end -0.12065 0.2794)
			(stroke
				(width 0.1)
				(type default)
			)
			(layer "F.Fab")
		)
		(fp_line
			(start 0.120396 0.3048)
			(end 0.120396 0.2794)
			(stroke
				(width 0.1)
				(type default)
			)
			(layer "F.Fab")
		)
		(fp_line
			(start 0.12065 -0.3048)
			(end 0.67945 -0.3048)
			(stroke
				(width 0.1)
				(type default)
			)
			(layer "F.Fab")
		)
		(fp_line
			(start 0.12065 -0.2794)
			(end 0.12065 -0.3048)
			(stroke
				(width 0.1)
				(type default)
			)
			(layer "F.Fab")
		)
		(fp_line
			(start 0.67945 -0.3048)
			(end 0.67945 0.3048)
			(stroke
				(width 0.1)
				(type default)
			)
			(layer "F.Fab")
		)
		(fp_line
			(start 0.67945 0.3048)
			(end 0.120396 0.3048)
			(stroke
				(width 0.1)
				(type default)
			)
			(layer "F.Fab")
		)
		(pad "1" smd circle
			(at -0.40005 0)
			(size 0 0)
			(layers "F.Cu" "F.Mask" "F.Paste")
			(net "P3V3_AUX")
		)
		(pad "2" smd circle
			(at 0.40005 0)
			(size 0 0)
			(layers "F.Cu" "F.Mask" "F.Paste")
			(net "HP_LVC3_OCP_V3_2_PRSNT2")
		)
	)
	(footprint ""
		(layer "F.Cu")
		(at 283.310076 -412.579058 -90)
		(property "Reference" "C2328"
			(at 0 0 270)
			(layer "F.SilkS")
			(hide yes)
			(effects
				(font
					(size 1.27 1.27)
				)
			)
		)
		(property "Value" ""
			(at 0 0 270)
			(layer "F.Fab")
			(effects
				(font
					(size 1.27 1.27)
				)
			)
		)
		(duplicate_pad_numbers_are_jumpers no)
		(fp_line
			(start -0.7874 0.4064)
			(end -0.7874 -0.4064)
			(stroke
				(width 0.1524)
				(type default)
			)
			(layer "F.SilkS")
		)
		(fp_line
			(start 0.7874 0.4064)
			(end -0.7874 0.4064)
			(stroke
				(width 0.1524)
				(type default)
			)
			(layer "F.SilkS")
		)
		(fp_line
			(start -0.7874 -0.4064)
			(end 0.7874 -0.4064)
			(stroke
				(width 0.1524)
				(type default)
			)
			(layer "F.SilkS")
		)
		(fp_line
			(start 0.7874 -0.4064)
			(end 0.7874 0.4064)
			(stroke
				(width 0.1524)
				(type default)
			)
			(layer "F.SilkS")
		)
		(fp_line
			(start -0.67945 0.3048)
			(end -0.67945 -0.305054)
			(stroke
				(width 0.1)
				(type default)
			)
			(layer "F.Fab")
		)
		(fp_line
			(start -0.12065 0.3048)
			(end -0.67945 0.3048)
			(stroke
				(width 0.1)
				(type default)
			)
			(layer "F.Fab")
		)
		(fp_line
			(start 0.120396 0.3048)
			(end 0.120396 0.2794)
			(stroke
				(width 0.1)
				(type default)
			)
			(layer "F.Fab")
		)
		(fp_line
			(start 0.67945 0.3048)
			(end 0.120396 0.3048)
			(stroke
				(width 0.1)
				(type default)
			)
			(layer "F.Fab")
		)
		(fp_line
			(start -0.12065 0.2794)
			(end -0.12065 0.3048)
			(stroke
				(width 0.1)
				(type default)
			)
			(layer "F.Fab")
		)
		(fp_line
			(start 0.120396 0.2794)
			(end -0.12065 0.2794)
			(stroke
				(width 0.1)
				(type default)
			)
			(layer "F.Fab")
		)
		(fp_line
			(start -0.12065 -0.2794)
			(end 0.12065 -0.2794)
			(stroke
				(width 0.1)
				(type default)
			)
			(layer "F.Fab")
		)
		(fp_line
			(start 0.12065 -0.2794)
			(end 0.12065 -0.3048)
			(stroke
				(width 0.1)
				(type default)
			)
			(layer "F.Fab")
		)
		(fp_line
			(start 0.12065 -0.3048)
			(end 0.67945 -0.3048)
			(stroke
				(width 0.1)
				(type default)
			)
			(layer "F.Fab")
		)
		(fp_line
			(start 0.67945 -0.3048)
			(end 0.67945 0.3048)
			(stroke
				(width 0.1)
				(type default)
			)
			(layer "F.Fab")
		)
		(fp_line
			(start -0.67945 -0.305054)
			(end -0.12065 -0.305054)
			(stroke
				(width 0.1)
				(type default)
			)
			(layer "F.Fab")
		)
		(fp_line
			(start -0.12065 -0.305054)
			(end -0.12065 -0.2794)
			(stroke
				(width 0.1)
				(type default)
			)
			(layer "F.Fab")
		)
		(pad "1" smd circle
			(at -0.40005 0 270)
			(size 0 0)
			(layers "F.Cu" "F.Mask" "F.Paste")
			(net "P3V3_9ZXL045_P0_VDD")
		)
		(pad "2" smd circle
			(at 0.40005 0 270)
			(size 0 0)
			(layers "F.Cu" "F.Mask" "F.Paste")
			(net "GND")
		)
	)
	(footprint ""
		(layer "F.Cu")
		(at 69.917818 -25.192482)
		(property "Reference" "PC2174"
			(at 0 0 0)
			(layer "F.SilkS")
			(hide yes)
			(effects
				(font
					(size 1.27 1.27)
				)
			)
		)
		(property "Value" ""
			(at 0 0 0)
			(layer "F.Fab")
			(effects
				(font
					(size 1.27 1.27)
				)
			)
		)
		(duplicate_pad_numbers_are_jumpers no)
		(fp_line
			(start -0.7874 -0.4064)
			(end 0.7874 -0.4064)
			(stroke
				(width 0.1524)
				(type default)
			)
			(layer "F.SilkS")
		)
		(fp_line
			(start -0.7874 0.4064)
			(end -0.7874 -0.4064)
			(stroke
				(width 0.1524)
				(type default)
			)
			(layer "F.SilkS")
		)
		(fp_line
			(start 0.7874 -0.4064)
			(end 0.7874 0.4064)
			(stroke
				(width 0.1524)
				(type default)
			)
			(layer "F.SilkS")
		)
		(fp_line
			(start 0.7874 0.4064)
			(end -0.7874 0.4064)
			(stroke
				(width 0.1524)
				(type default)
			)
			(layer "F.SilkS")
		)
		(fp_line
			(start -0.67945 -0.305054)
			(end -0.12065 -0.305054)
			(stroke
				(width 0.1)
				(type default)
			)
			(layer "F.Fab")
		)
		(fp_line
			(start -0.67945 0.3048)
			(end -0.67945 -0.305054)
			(stroke
				(width 0.1)
				(type default)
			)
			(layer "F.Fab")
		)
		(fp_line
			(start -0.12065 -0.305054)
			(end -0.12065 -0.2794)
			(stroke
				(width 0.1)
				(type default)
			)
			(layer "F.Fab")
		)
		(fp_line
			(start -0.12065 -0.2794)
			(end 0.12065 -0.2794)
			(stroke
				(width 0.1)
				(type default)
			)
			(layer "F.Fab")
		)
		(fp_line
			(start -0.12065 0.2794)
			(end -0.12065 0.3048)
			(stroke
				(width 0.1)
				(type default)
			)
			(layer "F.Fab")
		)
		(fp_line
			(start -0.12065 0.3048)
			(end -0.67945 0.3048)
			(stroke
				(width 0.1)
				(type default)
			)
			(layer "F.Fab")
		)
		(fp_line
			(start 0.120396 0.2794)
			(end -0.12065 0.2794)
			(stroke
				(width 0.1)
				(type default)
			)
			(layer "F.Fab")
		)
		(fp_line
			(start 0.120396 0.3048)
			(end 0.120396 0.2794)
			(stroke
				(width 0.1)
				(type default)
			)
			(layer "F.Fab")
		)
		(fp_line
			(start 0.12065 -0.3048)
			(end 0.67945 -0.3048)
			(stroke
				(width 0.1)
				(type default)
			)
			(layer "F.Fab")
		)
		(fp_line
			(start 0.12065 -0.2794)
			(end 0.12065 -0.3048)
			(stroke
				(width 0.1)
				(type default)
			)
			(layer "F.Fab")
		)
		(fp_line
			(start 0.67945 -0.3048)
			(end 0.67945 0.3048)
			(stroke
				(width 0.1)
				(type default)
			)
			(layer "F.Fab")
		)
		(fp_line
			(start 0.67945 0.3048)
			(end 0.120396 0.3048)
			(stroke
				(width 0.1)
				(type default)
			)
			(layer "F.Fab")
		)
		(pad "1" smd circle
			(at -0.40005 0)
			(size 0 0)
			(layers "F.Cu" "F.Mask" "F.Paste")
			(net "P12V_OCP_V3_2")
		)
		(pad "2" smd circle
			(at 0.40005 0)
			(size 0 0)
			(layers "F.Cu" "F.Mask" "F.Paste")
			(net "GND")
		)
	)
	(footprint ""
		(layer "F.Cu")
		(at 139.749784 -47.309024 -90)
		(property "Reference" "R6207"
			(at 0 0 270)
			(layer "F.SilkS")
			(hide yes)
			(effects
				(font
					(size 1.27 1.27)
				)
			)
		)
		(property "Value" ""
			(at 0 0 270)
			(layer "F.Fab")
			(effects
				(font
					(size 1.27 1.27)
				)
			)
		)
		(duplicate_pad_numbers_are_jumpers no)
		(fp_line
			(start -0.7874 0.4064)
			(end -0.7874 -0.4064)
			(stroke
				(width 0.1524)
				(type default)
			)
			(layer "F.SilkS")
		)
		(fp_line
			(start 0.7874 0.4064)
			(end -0.7874 0.4064)
			(stroke
				(width 0.1524)
				(type default)
			)
			(layer "F.SilkS")
		)
		(fp_line
			(start -0.7874 -0.4064)
			(end 0.7874 -0.4064)
			(stroke
				(width 0.1524)
				(type default)
			)
			(layer "F.SilkS")
		)
		(fp_line
			(start 0.7874 -0.4064)
			(end 0.7874 0.4064)
			(stroke
				(width 0.1524)
				(type default)
			)
			(layer "F.SilkS")
		)
		(fp_line
			(start -0.67945 0.3048)
			(end -0.67945 -0.305054)
			(stroke
				(width 0.1)
				(type default)
			)
			(layer "F.Fab")
		)
		(fp_line
			(start -0.12065 0.3048)
			(end -0.67945 0.3048)
			(stroke
				(width 0.1)
				(type default)
			)
			(layer "F.Fab")
		)
		(fp_line
			(start 0.120396 0.3048)
			(end 0.120396 0.2794)
			(stroke
				(width 0.1)
				(type default)
			)
			(layer "F.Fab")
		)
		(fp_line
			(start 0.67945 0.3048)
			(end 0.120396 0.3048)
			(stroke
				(width 0.1)
				(type default)
			)
			(layer "F.Fab")
		)
		(fp_line
			(start -0.12065 0.2794)
			(end -0.12065 0.3048)
			(stroke
				(width 0.1)
				(type default)
			)
			(layer "F.Fab")
		)
		(fp_line
			(start 0.120396 0.2794)
			(end -0.12065 0.2794)
			(stroke
				(width 0.1)
				(type default)
			)
			(layer "F.Fab")
		)
		(fp_line
			(start -0.12065 -0.2794)
			(end 0.12065 -0.2794)
			(stroke
				(width 0.1)
				(type default)
			)
			(layer "F.Fab")
		)
		(fp_line
			(start 0.12065 -0.2794)
			(end 0.12065 -0.3048)
			(stroke
				(width 0.1)
				(type default)
			)
			(layer "F.Fab")
		)
		(fp_line
			(start 0.12065 -0.3048)
			(end 0.67945 -0.3048)
			(stroke
				(width 0.1)
				(type default)
			)
			(layer "F.Fab")
		)
		(fp_line
			(start 0.67945 -0.3048)
			(end 0.67945 0.3048)
			(stroke
				(width 0.1)
				(type default)
			)
			(layer "F.Fab")
		)
		(fp_line
			(start -0.67945 -0.305054)
			(end -0.12065 -0.305054)
			(stroke
				(width 0.1)
				(type default)
			)
			(layer "F.Fab")
		)
		(fp_line
			(start -0.12065 -0.305054)
			(end -0.12065 -0.2794)
			(stroke
				(width 0.1)
				(type default)
			)
			(layer "F.Fab")
		)
		(pad "1" smd circle
			(at -0.40005 0 270)
			(size 0 0)
			(layers "F.Cu" "F.Mask" "F.Paste")
			(net "P3V3_AUX")
		)
		(pad "2" smd circle
			(at 0.40005 0 270)
			(size 0 0)
			(layers "F.Cu" "F.Mask" "F.Paste")
			(net "PU_CPU0_USB_HUB_RESERVED1")
		)
	)
	(footprint ""
		(layer "F.Cu")
		(at 55.87873 -16.099536 90)
		(property "Reference" "C707"
			(at 0 0 90)
			(layer "F.SilkS")
			(hide yes)
			(effects
				(font
					(size 1.27 1.27)
				)
			)
		)
		(property "Value" ""
			(at 0 0 90)
			(layer "F.Fab")
			(effects
				(font
					(size 1.27 1.27)
				)
			)
		)
		(duplicate_pad_numbers_are_jumpers no)
		(fp_line
			(start 0.299974 -0.150114)
			(end 0.299974 0.150114)
			(stroke
				(width 0.1)
				(type default)
			)
			(layer "F.Fab")
		)
		(fp_line
			(start -0.299974 -0.150114)
			(end 0.299974 -0.150114)
			(stroke
				(width 0.1)
				(type default)
			)
			(layer "F.Fab")
		)
		(fp_line
			(start 0.299974 0.150114)
			(end -0.299974 0.150114)
			(stroke
				(width 0.1)
				(type default)
			)
			(layer "F.Fab")
		)
		(fp_line
			(start -0.299974 0.150114)
			(end -0.299974 -0.150114)
			(stroke
				(width 0.1)
				(type default)
			)
			(layer "F.Fab")
		)
		(pad "1" smd rect
			(at -0.2667 0 90)
			(size 0.3048 0.381)
			(layers "F.Cu" "F.Mask" "F.Paste")
			(net "P5E_CPU1_G1_TX_C_DP<1>")
		)
		(pad "2" smd rect
			(at 0.2667 0 90)
			(size 0.3048 0.381)
			(layers "F.Cu" "F.Mask" "F.Paste")
			(net "P5E_CPU1_G1_TX_DP<1>")
		)
	)
	(footprint ""
		(layer "F.Cu")
		(at 136.50468 -28.48102 90)
		(property "Reference" "R6196"
			(at 0 0 90)
			(layer "F.SilkS")
			(hide yes)
			(effects
				(font
					(size 1.27 1.27)
				)
			)
		)
		(property "Value" ""
			(at 0 0 90)
			(layer "F.Fab")
			(effects
				(font
					(size 1.27 1.27)
				)
			)
		)
		(duplicate_pad_numbers_are_jumpers no)
		(fp_line
			(start 0.32512 -0.175006)
			(end 0.32512 0.175006)
			(stroke
				(width 0.1)
				(type default)
			)
			(layer "F.Fab")
		)
		(fp_line
			(start -0.32512 -0.175006)
			(end 0.32512 -0.175006)
			(stroke
				(width 0.1)
				(type default)
			)
			(layer "F.Fab")
		)
		(fp_line
			(start 0.32512 0.175006)
			(end -0.32512 0.175006)
			(stroke
				(width 0.1)
				(type default)
			)
			(layer "F.Fab")
		)
		(fp_line
			(start -0.32512 0.175006)
			(end -0.32512 -0.175006)
			(stroke
				(width 0.1)
				(type default)
			)
			(layer "F.Fab")
		)
		(pad "1" smd rect
			(at -0.2667 0 90)
			(size 0.3048 0.381)
			(layers "F.Cu" "F.Mask" "F.Paste")
			(net "USB2_CPU0_P0_HUB2_R_DP")
		)
		(pad "2" smd rect
			(at 0.2667 0 270)
			(size 0.3048 0.381)
			(layers "F.Cu" "F.Mask" "F.Paste")
			(net "USB2_HUB_EXT_DP")
		)
	)
	(footprint ""
		(layer "F.Cu")
		(at 34.252662 -424.710098 180)
		(property "Reference" "U237"
			(at -6.560312 3.07086 0)
			(unlocked yes)
			(layer "F.SilkS")
			(effects
				(font
					(size 0.7874 0.5842)
					(thickness 0.1524)
				)
				(justify left)
			)
		)
		(property "Value" ""
			(at 0 0 180)
			(layer "F.Fab")
			(effects
				(font
					(size 1.27 1.27)
				)
			)
		)
		(duplicate_pad_numbers_are_jumpers no)
		(fp_line
			(start 2.5146 0.2032)
			(end 1.7018 0.2032)
			(stroke
				(width 0.1524)
				(type default)
			)
			(layer "F.SilkS")
		)
		(fp_line
			(start 1.6891 -1.8034)
			(end 2.0701 -1.8034)
			(stroke
				(width 0.1524)
				(type default)
			)
			(layer "F.SilkS")
		)
		(fp_line
			(start 1.299972 2.29997)
			(end 1.299972 2.015998)
			(stroke
				(width 0.1524)
				(type default)
			)
			(layer "F.SilkS")
		)
		(fp_line
			(start 1.299972 -2.015998)
			(end 1.299972 -2.29997)
			(stroke
				(width 0.1524)
				(type default)
			)
			(layer "F.SilkS")
		)
		(fp_line
			(start 1.299972 -2.29997)
			(end 1.016 -2.29997)
			(stroke
				(width 0.1524)
				(type default)
			)
			(layer "F.SilkS")
		)
		(fp_line
			(start 1.016 2.29997)
			(end 1.299972 2.29997)
			(stroke
				(width 0.1524)
				(type default)
			)
			(layer "F.SilkS")
		)
		(fp_line
			(start 0.7874 3.0861)
			(end 0.7874 2.7051)
			(stroke
				(width 0.1524)
				(type default)
			)
			(layer "F.SilkS")
		)
		(fp_line
			(start -0.8128 -2.6924)
			(end -0.8128 -3.5052)
			(stroke
				(width 0.1524)
				(type default)
			)
			(layer "F.SilkS")
		)
		(fp_line
			(start -1.016 -2.29997)
			(end -1.299972 -2.29997)
			(stroke
				(width 0.1524)
				(type default)
			)
			(layer "F.SilkS")
		)
		(fp_line
			(start -1.299972 2.29997)
			(end -1.016 2.29997)
			(stroke
				(width 0.1524)
				(type default)
			)
			(layer "F.SilkS")
		)
		(fp_line
			(start -1.299972 2.015998)
			(end -1.299972 2.29997)
			(stroke
				(width 0.1524)
				(type default)
			)
			(layer "F.SilkS")
		)
		(fp_line
			(start -1.299972 -2.29997)
			(end -1.299972 -2.015998)
			(stroke
				(width 0.1524)
				(type default)
			)
			(layer "F.SilkS")
		)
		(fp_line
			(start -1.6891 -0.2032)
			(end -1.974596 -0.2032)
			(stroke
				(width 0.1524)
				(type default)
			)
			(layer "F.SilkS")
		)
		(fp_line
			(start -1.7018 1.8034)
			(end -2.5146 1.8034)
			(stroke
				(width 0.1524)
				(type default)
			)
			(layer "F.SilkS")
		)
		(fp_poly
			(pts
				(xy -2.238248 -2.068322) (xy -1.7018 -1.800098) (xy -2.238248 -1.531874)
			)
			(stroke
				(width 0)
				(type default)
			)
			(fill yes)
			(layer "F.SilkS")
		)
		(fp_line
			(start 2.5146 0.2032)
			(end 1.7018 0.2032)
			(stroke
				(width 0.1)
				(type default)
			)
			(layer "F.Fab")
		)
		(fp_line
			(start 1.6891 -1.8034)
			(end 2.0701 -1.8034)
			(stroke
				(width 0.1)
				(type default)
			)
			(layer "F.Fab")
		)
		(fp_line
			(start 1.299972 2.29997)
			(end 1.299972 -2.29997)
			(stroke
				(width 0.1)
				(type default)
			)
			(layer "F.Fab")
		)
		(fp_line
			(start 1.299972 -2.29997)
			(end -1.299972 -2.29997)
			(stroke
				(width 0.1)
				(type default)
			)
			(layer "F.Fab")
		)
		(fp_line
			(start 0.7874 3.0861)
			(end 0.7874 2.7051)
			(stroke
				(width 0.1)
				(type default)
			)
			(layer "F.Fab")
		)
		(fp_line
			(start -0.8128 -2.6924)
			(end -0.8128 -3.5052)
			(stroke
				(width 0.1)
				(type default)
			)
			(layer "F.Fab")
		)
		(fp_line
			(start -1.299972 2.29997)
			(end 1.299972 2.29997)
			(stroke
				(width 0.1)
				(type default)
			)
			(layer "F.Fab")
		)
		(fp_line
			(start -1.299972 -2.29997)
			(end -1.299972 2.29997)
			(stroke
				(width 0.1)
				(type default)
			)
			(layer "F.Fab")
		)
		(fp_line
			(start -1.6891 -0.2032)
			(end -2.0701 -0.2032)
			(stroke
				(width 0.1)
				(type default)
			)
			(layer "F.Fab")
		)
		(fp_line
			(start -1.7018 1.8034)
			(end -2.5146 1.8034)
			(stroke
				(width 0.1)
				(type default)
			)
			(layer "F.Fab")
		)
		(fp_poly
			(pts
				(xy -2.7178 -2.308098) (xy -2.7178 -1.292098) (xy -1.7018 -1.800098)
			)
			(stroke
				(width 0)
				(type default)
			)
			(fill yes)
			(layer "F.Fab")
		)
		(fp_text user "25"
			(at 4.134358 -1.752854 90)
			(unlocked yes)
			(layer "F.SilkS")
			(effects
				(font
					(size 0.635 0.4064)
					(thickness 0.1524)
				)
			)
		)
		(fp_text user "16"
			(at 2.821432 2.50317 90)
			(unlocked yes)
			(layer "F.SilkS")
			(effects
				(font
					(size 0.635 0.4064)
					(thickness 0.1524)
				)
			)
		)
		(fp_text user "26"
			(at 2.66446 -4.066794 90)
			(unlocked yes)
			(layer "F.SilkS")
			(effects
				(font
					(size 0.635 0.4064)
					(thickness 0.1524)
				)
			)
		)
		(fp_text user "15"
			(at 1.616456 3.538728 90)
			(unlocked yes)
			(layer "F.SilkS")
			(effects
				(font
					(size 0.635 0.4064)
					(thickness 0.1524)
				)
			)
		)
		(fp_text user "11"
			(at -1.56337 3.733292 90)
			(unlocked yes)
			(layer "F.SilkS")
			(effects
				(font
					(size 0.635 0.4064)
					(thickness 0.1524)
				)
			)
		)
		(fp_text user "30"
			(at -2.718816 -2.527808 90)
			(unlocked yes)
			(layer "F.SilkS")
			(effects
				(font
					(size 0.635 0.4064)
					(thickness 0.1524)
				)
			)
		)
		(fp_text user "10"
			(at -4.529582 2.764028 90)
			(unlocked yes)
			(layer "F.SilkS")
			(effects
				(font
					(size 0.635 0.4064)
					(thickness 0.1524)
				)
			)
		)
		(fp_text user "16"
			(at 2.029968 2.0574 90)
			(unlocked yes)
			(layer "F.Fab")
			(effects
				(font
					(size 0.635 0.4064)
					(thickness 0.1524)
				)
			)
		)
		(fp_text user "25"
			(at 1.979168 -2.4384 90)
			(unlocked yes)
			(layer "F.Fab")
			(effects
				(font
					(size 0.635 0.4064)
					(thickness 0.1524)
				)
			)
		)
		(fp_text user "15"
			(at 1.3716 2.948432 180)
			(unlocked yes)
			(layer "F.Fab")
			(effects
				(font
					(size 0.635 0.4064)
					(thickness 0.1524)
				)
			)
		)
		(fp_text user "26"
			(at 1.0922 -3.071368 180)
			(unlocked yes)
			(layer "F.Fab")
			(effects
				(font
					(size 0.635 0.4064)
					(thickness 0.1524)
				)
			)
		)
		(fp_text user "11"
			(at -1.2192 3.075432 180)
			(unlocked yes)
			(layer "F.Fab")
			(effects
				(font
					(size 0.635 0.4064)
					(thickness 0.1524)
				)
			)
		)
		(fp_text user "30"
			(at -1.4478 -2.842768 180)
			(unlocked yes)
			(layer "F.Fab")
			(effects
				(font
					(size 0.635 0.4064)
					(thickness 0.1524)
				)
			)
		)
		(fp_text user "10"
			(at -2.084832 2.3876 90)
			(unlocked yes)
			(layer "F.Fab")
			(effects
				(font
					(size 0.635 0.4064)
					(thickness 0.1524)
				)
			)
		)
		(pad "1" smd circle
			(at -1.249934 -1.800098 90)
			(size 0 0)
			(layers "F.Cu" "F.Mask" "F.Paste")
			(net "P3V3_AUX")
		)
		(pad "2" smd circle
			(at -1.249934 -1.400048 90)
			(size 0 0)
			(layers "F.Cu" "F.Mask" "F.Paste")
			(net "P2E_MB_BMC_TX_C_R1_DP<0>")
		)
		(pad "3" smd circle
			(at -1.249934 -0.999998 90)
			(size 0 0)
			(layers "F.Cu" "F.Mask" "F.Paste")
			(net "P2E_MB_BMC_TX_C_R1_DN<0>")
		)
		(pad "4" smd circle
			(at -1.249934 -0.599948 90)
			(size 0 0)
			(layers "F.Cu" "F.Mask" "F.Paste")
			(net "GND")
		)
		(pad "5" smd circle
			(at -1.249934 -0.199898 90)
			(size 0 0)
			(layers "F.Cu" "F.Mask" "F.Paste")
			(net "PU_TEST")
		)
		(pad "6" smd circle
			(at -1.249934 0.199898 90)
			(size 0 0)
			(layers "F.Cu" "F.Mask" "F.Paste")
			(net "GND")
		)
		(pad "7" smd circle
			(at -1.249934 0.599948 90)
			(size 0 0)
			(layers "F.Cu" "F.Mask" "F.Paste")
			(net "GND")
		)
		(pad "8" smd circle
			(at -1.249934 0.999998 90)
			(size 0 0)
			(layers "F.Cu" "F.Mask" "F.Paste")
			(net "P2E_MB_BMC_RX_BUF_C_DN<0>")
		)
		(pad "9" smd circle
			(at -1.249934 1.400048 90)
			(size 0 0)
			(layers "F.Cu" "F.Mask" "F.Paste")
			(net "P2E_MB_BMC_RX_BUF_C_DP<0>")
		)
		(pad "10" smd circle
			(at -1.249934 1.800098 90)
			(size 0 0)
			(layers "F.Cu" "F.Mask" "F.Paste")
			(net "P3V3_AUX")
		)
		(pad "11" smd circle
			(at -0.8001 2.249932 180)
			(size 0 0)
			(layers "F.Cu" "F.Mask" "F.Paste")
			(net "FM_P2E_EN_N")
		)
		(pad "12" smd circle
			(at -0.40005 2.249932 180)
			(size 0 0)
			(layers "F.Cu" "F.Mask" "F.Paste")
			(net "FM_P2E_SWB")
		)
		(pad "13" smd circle
			(at 0 2.249932 180)
			(size 0 0)
			(layers "F.Cu" "F.Mask" "F.Paste")
			(net "GND")
		)
		(pad "14" smd circle
			(at 0.40005 2.249932 180)
			(size 0 0)
			(layers "F.Cu" "F.Mask" "F.Paste")
			(net "FM_P2E_FGB")
		)
		(pad "15" smd circle
			(at 0.8001 2.249932 180)
			(size 0 0)
			(layers "F.Cu" "F.Mask" "F.Paste")
			(net "FM_P2E_EQB1")
		)
		(pad "16" smd circle
			(at 1.249934 1.800098 270)
			(size 0 0)
			(layers "F.Cu" "F.Mask" "F.Paste")
			(net "P3V3_AUX")
		)
		(pad "17" smd circle
			(at 1.249934 1.400048 270)
			(size 0 0)
			(layers "F.Cu" "F.Mask" "F.Paste")
			(net "P2E_MB_BMC_RX_R1_DP<0>")
		)
		(pad "18" smd circle
			(at 1.249934 0.999998 270)
			(size 0 0)
			(layers "F.Cu" "F.Mask" "F.Paste")
			(net "P2E_MB_BMC_RX_R1_DN<0>")
		)
		(pad "19" smd circle
			(at 1.249934 0.599948 270)
			(size 0 0)
			(layers "F.Cu" "F.Mask" "F.Paste")
			(net "GND")
		)
		(pad "20" smd circle
			(at 1.249934 0.199898 270)
			(size 0 0)
			(layers "F.Cu" "F.Mask" "F.Paste")
			(net "FM_P2E_EQB0")
		)
		(pad "21" smd circle
			(at 1.249934 -0.199898 270)
			(size 0 0)
			(layers "F.Cu" "F.Mask" "F.Paste")
			(net "FM_P2E_EQA0")
		)
		(pad "22" smd circle
			(at 1.249934 -0.599948 270)
			(size 0 0)
			(layers "F.Cu" "F.Mask" "F.Paste")
			(net "GND")
		)
		(pad "23" smd circle
			(at 1.249934 -0.999998 270)
			(size 0 0)
			(layers "F.Cu" "F.Mask" "F.Paste")
			(net "P2E_MB_BMC_TX_BUF_DN<0>")
		)
		(pad "24" smd circle
			(at 1.249934 -1.400048 270)
			(size 0 0)
			(layers "F.Cu" "F.Mask" "F.Paste")
			(net "P2E_MB_BMC_TX_BUF_DP<0>")
		)
		(pad "25" smd circle
			(at 1.249934 -1.800098 270)
			(size 0 0)
			(layers "F.Cu" "F.Mask" "F.Paste")
			(net "P3V3_AUX")
		)
		(pad "26" smd circle
			(at 0.8001 -2.249932)
			(size 0 0)
			(layers "F.Cu" "F.Mask" "F.Paste")
			(net "FM_P2E_EQA1")
		)
		(pad "27" smd circle
			(at 0.40005 -2.249932)
			(size 0 0)
			(layers "F.Cu" "F.Mask" "F.Paste")
			(net "FM_P2E_FGA")
		)
		(pad "28" smd circle
			(at 0 -2.249932)
			(size 0 0)
			(layers "F.Cu" "F.Mask" "F.Paste")
			(net "GND")
		)
		(pad "29" smd circle
			(at -0.40005 -2.249932)
			(size 0 0)
			(layers "F.Cu" "F.Mask" "F.Paste")
			(net "FM_P2E_SWA")
		)
		(pad "30" smd circle
			(at -0.8001 -2.249932)
			(size 0 0)
			(layers "F.Cu" "F.Mask" "F.Paste")
			(net "FM_P2E_MODE")
		)
		(pad "TH" smd rect
			(at 0 0 180)
			(size 1.2192 3.2004)
			(layers "F.Cu" "F.Mask" "F.Paste")
			(net "GND")
		)
	)
	(footprint ""
		(layer "F.Cu")
		(at 130.49758 -27.52598 90)
		(property "Reference" "R6190"
			(at 0 0 90)
			(layer "F.SilkS")
			(hide yes)
			(effects
				(font
					(size 1.27 1.27)
				)
			)
		)
		(property "Value" ""
			(at 0 0 90)
			(layer "F.Fab")
			(effects
				(font
					(size 1.27 1.27)
				)
			)
		)
		(duplicate_pad_numbers_are_jumpers no)
		(fp_line
			(start 0.32512 -0.175006)
			(end 0.32512 0.175006)
			(stroke
				(width 0.1)
				(type default)
			)
			(layer "F.Fab")
		)
		(fp_line
			(start -0.32512 -0.175006)
			(end 0.32512 -0.175006)
			(stroke
				(width 0.1)
				(type default)
			)
			(layer "F.Fab")
		)
		(fp_line
			(start 0.32512 0.175006)
			(end -0.32512 0.175006)
			(stroke
				(width 0.1)
				(type default)
			)
			(layer "F.Fab")
		)
		(fp_line
			(start -0.32512 0.175006)
			(end -0.32512 -0.175006)
			(stroke
				(width 0.1)
				(type default)
			)
			(layer "F.Fab")
		)
		(pad "1" smd rect
			(at -0.2667 0 90)
			(size 0.3048 0.381)
			(layers "F.Cu" "F.Mask" "F.Paste")
			(net "USB2_CPU0_P0_DP")
		)
		(pad "2" smd rect
			(at 0.2667 0 270)
			(size 0.3048 0.381)
			(layers "F.Cu" "F.Mask" "F.Paste")
			(net "USB2_CPU0_P0_R1_DP")
		)
	)
	(footprint ""
		(layer "F.Cu")
		(at 170.970702 -437.032146 90)
		(property "Reference" "R3433"
			(at 0 0 90)
			(layer "F.SilkS")
			(hide yes)
			(effects
				(font
					(size 1.27 1.27)
				)
			)
		)
		(property "Value" ""
			(at 0 0 90)
			(layer "F.Fab")
			(effects
				(font
					(size 1.27 1.27)
				)
			)
		)
		(duplicate_pad_numbers_are_jumpers no)
		(fp_line
			(start 0.7874 -0.4064)
			(end 0.7874 0.4064)
			(stroke
				(width 0.1524)
				(type default)
			)
			(layer "F.SilkS")
		)
		(fp_line
			(start -0.7874 -0.4064)
			(end 0.7874 -0.4064)
			(stroke
				(width 0.1524)
				(type default)
			)
			(layer "F.SilkS")
		)
		(fp_line
			(start 0.7874 0.4064)
			(end -0.7874 0.4064)
			(stroke
				(width 0.1524)
				(type default)
			)
			(layer "F.SilkS")
		)
		(fp_line
			(start -0.7874 0.4064)
			(end -0.7874 -0.4064)
			(stroke
				(width 0.1524)
				(type default)
			)
			(layer "F.SilkS")
		)
		(fp_line
			(start -0.12065 -0.305054)
			(end -0.12065 -0.2794)
			(stroke
				(width 0.1)
				(type default)
			)
			(layer "F.Fab")
		)
		(fp_line
			(start -0.67945 -0.305054)
			(end -0.12065 -0.305054)
			(stroke
				(width 0.1)
				(type default)
			)
			(layer "F.Fab")
		)
		(fp_line
			(start 0.67945 -0.3048)
			(end 0.67945 0.3048)
			(stroke
				(width 0.1)
				(type default)
			)
			(layer "F.Fab")
		)
		(fp_line
			(start 0.12065 -0.3048)
			(end 0.67945 -0.3048)
			(stroke
				(width 0.1)
				(type default)
			)
			(layer "F.Fab")
		)
		(fp_line
			(start 0.12065 -0.2794)
			(end 0.12065 -0.3048)
			(stroke
				(width 0.1)
				(type default)
			)
			(layer "F.Fab")
		)
		(fp_line
			(start -0.12065 -0.2794)
			(end 0.12065 -0.2794)
			(stroke
				(width 0.1)
				(type default)
			)
			(layer "F.Fab")
		)
		(fp_line
			(start 0.120396 0.2794)
			(end -0.12065 0.2794)
			(stroke
				(width 0.1)
				(type default)
			)
			(layer "F.Fab")
		)
		(fp_line
			(start -0.12065 0.2794)
			(end -0.12065 0.3048)
			(stroke
				(width 0.1)
				(type default)
			)
			(layer "F.Fab")
		)
		(fp_line
			(start 0.67945 0.3048)
			(end 0.120396 0.3048)
			(stroke
				(width 0.1)
				(type default)
			)
			(layer "F.Fab")
		)
		(fp_line
			(start 0.120396 0.3048)
			(end 0.120396 0.2794)
			(stroke
				(width 0.1)
				(type default)
			)
			(layer "F.Fab")
		)
		(fp_line
			(start -0.12065 0.3048)
			(end -0.67945 0.3048)
			(stroke
				(width 0.1)
				(type default)
			)
			(layer "F.Fab")
		)
		(fp_line
			(start -0.67945 0.3048)
			(end -0.67945 -0.305054)
			(stroke
				(width 0.1)
				(type default)
			)
			(layer "F.Fab")
		)
		(pad "1" smd circle
			(at -0.40005 0 90)
			(size 0 0)
			(layers "F.Cu" "F.Mask" "F.Paste")
			(net "P3V3_AUX")
		)
		(pad "2" smd circle
			(at 0.40005 0 90)
			(size 0 0)
			(layers "F.Cu" "F.Mask" "F.Paste")
			(net "GPU_BASE_HMC_READY_N")
		)
	)
	(footprint ""
		(layer "F.Cu")
		(at 328.506836 -150.589234 180)
		(property "Reference" "PR418"
			(at 0 0 180)
			(layer "F.SilkS")
			(hide yes)
			(effects
				(font
					(size 1.27 1.27)
				)
			)
		)
		(property "Value" ""
			(at 0 0 180)
			(layer "F.Fab")
			(effects
				(font
					(size 1.27 1.27)
				)
			)
		)
		(duplicate_pad_numbers_are_jumpers no)
		(fp_line
			(start 0.7874 0.4064)
			(end -0.7874 0.4064)
			(stroke
				(width 0.1524)
				(type default)
			)
			(layer "F.SilkS")
		)
		(fp_line
			(start 0.7874 -0.4064)
			(end 0.7874 0.4064)
			(stroke
				(width 0.1524)
				(type default)
			)
			(layer "F.SilkS")
		)
		(fp_line
			(start -0.7874 0.4064)
			(end -0.7874 -0.4064)
			(stroke
				(width 0.1524)
				(type default)
			)
			(layer "F.SilkS")
		)
		(fp_line
			(start -0.7874 -0.4064)
			(end 0.7874 -0.4064)
			(stroke
				(width 0.1524)
				(type default)
			)
			(layer "F.SilkS")
		)
		(fp_line
			(start 0.67945 0.3048)
			(end 0.120396 0.3048)
			(stroke
				(width 0.1)
				(type default)
			)
			(layer "F.Fab")
		)
		(fp_line
			(start 0.67945 -0.3048)
			(end 0.67945 0.3048)
			(stroke
				(width 0.1)
				(type default)
			)
			(layer "F.Fab")
		)
		(fp_line
			(start 0.12065 -0.2794)
			(end 0.12065 -0.3048)
			(stroke
				(width 0.1)
				(type default)
			)
			(layer "F.Fab")
		)
		(fp_line
			(start 0.12065 -0.3048)
			(end 0.67945 -0.3048)
			(stroke
				(width 0.1)
				(type default)
			)
			(layer "F.Fab")
		)
		(fp_line
			(start 0.120396 0.3048)
			(end 0.120396 0.2794)
			(stroke
				(width 0.1)
				(type default)
			)
			(layer "F.Fab")
		)
		(fp_line
			(start 0.120396 0.2794)
			(end -0.12065 0.2794)
			(stroke
				(width 0.1)
				(type default)
			)
			(layer "F.Fab")
		)
		(fp_line
			(start -0.12065 0.3048)
			(end -0.67945 0.3048)
			(stroke
				(width 0.1)
				(type default)
			)
			(layer "F.Fab")
		)
		(fp_line
			(start -0.12065 0.2794)
			(end -0.12065 0.3048)
			(stroke
				(width 0.1)
				(type default)
			)
			(layer "F.Fab")
		)
		(fp_line
			(start -0.12065 -0.2794)
			(end 0.12065 -0.2794)
			(stroke
				(width 0.1)
				(type default)
			)
			(layer "F.Fab")
		)
		(fp_line
			(start -0.12065 -0.305054)
			(end -0.12065 -0.2794)
			(stroke
				(width 0.1)
				(type default)
			)
			(layer "F.Fab")
		)
		(fp_line
			(start -0.67945 0.3048)
			(end -0.67945 -0.305054)
			(stroke
				(width 0.1)
				(type default)
			)
			(layer "F.Fab")
		)
		(fp_line
			(start -0.67945 -0.305054)
			(end -0.12065 -0.305054)
			(stroke
				(width 0.1)
				(type default)
			)
			(layer "F.Fab")
		)
		(pad "1" smd circle
			(at -0.40005 0 180)
			(size 0 0)
			(layers "F.Cu" "F.Mask" "F.Paste")
			(net "GND")
		)
		(pad "2" smd circle
			(at 0.40005 0 180)
			(size 0 0)
			(layers "F.Cu" "F.Mask" "F.Paste")
			(net "PVDD18_S5_P0_RGND")
		)
	)
	(footprint ""
		(layer "F.Cu")
		(at 445.19088 -94.602808)
		(property "Reference" "R3563"
			(at 0 0 0)
			(layer "F.SilkS")
			(hide yes)
			(effects
				(font
					(size 1.27 1.27)
				)
			)
		)
		(property "Value" ""
			(at 0 0 0)
			(layer "F.Fab")
			(effects
				(font
					(size 1.27 1.27)
				)
			)
		)
		(duplicate_pad_numbers_are_jumpers no)
		(fp_line
			(start -0.7874 -0.4064)
			(end 0.7874 -0.4064)
			(stroke
				(width 0.1524)
				(type default)
			)
			(layer "F.SilkS")
		)
		(fp_line
			(start -0.7874 0.4064)
			(end -0.7874 -0.4064)
			(stroke
				(width 0.1524)
				(type default)
			)
			(layer "F.SilkS")
		)
		(fp_line
			(start 0.7874 -0.4064)
			(end 0.7874 0.4064)
			(stroke
				(width 0.1524)
				(type default)
			)
			(layer "F.SilkS")
		)
		(fp_line
			(start 0.7874 0.4064)
			(end -0.7874 0.4064)
			(stroke
				(width 0.1524)
				(type default)
			)
			(layer "F.SilkS")
		)
		(fp_line
			(start -0.67945 -0.305054)
			(end -0.12065 -0.305054)
			(stroke
				(width 0.1)
				(type default)
			)
			(layer "F.Fab")
		)
		(fp_line
			(start -0.67945 0.3048)
			(end -0.67945 -0.305054)
			(stroke
				(width 0.1)
				(type default)
			)
			(layer "F.Fab")
		)
		(fp_line
			(start -0.12065 -0.305054)
			(end -0.12065 -0.2794)
			(stroke
				(width 0.1)
				(type default)
			)
			(layer "F.Fab")
		)
		(fp_line
			(start -0.12065 -0.2794)
			(end 0.12065 -0.2794)
			(stroke
				(width 0.1)
				(type default)
			)
			(layer "F.Fab")
		)
		(fp_line
			(start -0.12065 0.2794)
			(end -0.12065 0.3048)
			(stroke
				(width 0.1)
				(type default)
			)
			(layer "F.Fab")
		)
		(fp_line
			(start -0.12065 0.3048)
			(end -0.67945 0.3048)
			(stroke
				(width 0.1)
				(type default)
			)
			(layer "F.Fab")
		)
		(fp_line
			(start 0.120396 0.2794)
			(end -0.12065 0.2794)
			(stroke
				(width 0.1)
				(type default)
			)
			(layer "F.Fab")
		)
		(fp_line
			(start 0.120396 0.3048)
			(end 0.120396 0.2794)
			(stroke
				(width 0.1)
				(type default)
			)
			(layer "F.Fab")
		)
		(fp_line
			(start 0.12065 -0.3048)
			(end 0.67945 -0.3048)
			(stroke
				(width 0.1)
				(type default)
			)
			(layer "F.Fab")
		)
		(fp_line
			(start 0.12065 -0.2794)
			(end 0.12065 -0.3048)
			(stroke
				(width 0.1)
				(type default)
			)
			(layer "F.Fab")
		)
		(fp_line
			(start 0.67945 -0.3048)
			(end 0.67945 0.3048)
			(stroke
				(width 0.1)
				(type default)
			)
			(layer "F.Fab")
		)
		(fp_line
			(start 0.67945 0.3048)
			(end 0.120396 0.3048)
			(stroke
				(width 0.1)
				(type default)
			)
			(layer "F.Fab")
		)
		(pad "1" smd circle
			(at -0.40005 0)
			(size 0 0)
			(layers "F.Cu" "F.Mask" "F.Paste")
			(net "OCP_SFF_P3V3_ADC_ALERT_R")
		)
		(pad "2" smd circle
			(at 0.40005 0)
			(size 0 0)
			(layers "F.Cu" "F.Mask" "F.Paste")
			(net "OCP_SFF_P3V3_P12V_ADC_R_ALERT")
		)
	)
	(footprint ""
		(layer "F.Cu")
		(at 269.85087 -351.540572 90)
		(property "Reference" "PR442"
			(at 0 0 90)
			(layer "F.SilkS")
			(hide yes)
			(effects
				(font
					(size 1.27 1.27)
				)
			)
		)
		(property "Value" ""
			(at 0 0 90)
			(layer "F.Fab")
			(effects
				(font
					(size 1.27 1.27)
				)
			)
		)
		(duplicate_pad_numbers_are_jumpers no)
		(fp_line
			(start 0.7874 -0.4064)
			(end 0.7874 0.4064)
			(stroke
				(width 0.1524)
				(type default)
			)
			(layer "F.SilkS")
		)
		(fp_line
			(start -0.7874 -0.4064)
			(end 0.7874 -0.4064)
			(stroke
				(width 0.1524)
				(type default)
			)
			(layer "F.SilkS")
		)
		(fp_line
			(start 0.7874 0.4064)
			(end -0.7874 0.4064)
			(stroke
				(width 0.1524)
				(type default)
			)
			(layer "F.SilkS")
		)
		(fp_line
			(start -0.7874 0.4064)
			(end -0.7874 -0.4064)
			(stroke
				(width 0.1524)
				(type default)
			)
			(layer "F.SilkS")
		)
		(fp_line
			(start -0.12065 -0.305054)
			(end -0.12065 -0.2794)
			(stroke
				(width 0.1)
				(type default)
			)
			(layer "F.Fab")
		)
		(fp_line
			(start -0.67945 -0.305054)
			(end -0.12065 -0.305054)
			(stroke
				(width 0.1)
				(type default)
			)
			(layer "F.Fab")
		)
		(fp_line
			(start 0.67945 -0.3048)
			(end 0.67945 0.3048)
			(stroke
				(width 0.1)
				(type default)
			)
			(layer "F.Fab")
		)
		(fp_line
			(start 0.12065 -0.3048)
			(end 0.67945 -0.3048)
			(stroke
				(width 0.1)
				(type default)
			)
			(layer "F.Fab")
		)
		(fp_line
			(start 0.12065 -0.2794)
			(end 0.12065 -0.3048)
			(stroke
				(width 0.1)
				(type default)
			)
			(layer "F.Fab")
		)
		(fp_line
			(start -0.12065 -0.2794)
			(end 0.12065 -0.2794)
			(stroke
				(width 0.1)
				(type default)
			)
			(layer "F.Fab")
		)
		(fp_line
			(start 0.120396 0.2794)
			(end -0.12065 0.2794)
			(stroke
				(width 0.1)
				(type default)
			)
			(layer "F.Fab")
		)
		(fp_line
			(start -0.12065 0.2794)
			(end -0.12065 0.3048)
			(stroke
				(width 0.1)
				(type default)
			)
			(layer "F.Fab")
		)
		(fp_line
			(start 0.67945 0.3048)
			(end 0.120396 0.3048)
			(stroke
				(width 0.1)
				(type default)
			)
			(layer "F.Fab")
		)
		(fp_line
			(start 0.120396 0.3048)
			(end 0.120396 0.2794)
			(stroke
				(width 0.1)
				(type default)
			)
			(layer "F.Fab")
		)
		(fp_line
			(start -0.12065 0.3048)
			(end -0.67945 0.3048)
			(stroke
				(width 0.1)
				(type default)
			)
			(layer "F.Fab")
		)
		(fp_line
			(start -0.67945 0.3048)
			(end -0.67945 -0.305054)
			(stroke
				(width 0.1)
				(type default)
			)
			(layer "F.Fab")
		)
		(pad "1" smd circle
			(at -0.40005 0 90)
			(size 0 0)
			(layers "F.Cu" "F.Mask" "F.Paste")
			(net "PVDDCR_CPU1_P0_PVCC")
		)
		(pad "2" smd circle
			(at 0.40005 0 90)
			(size 0 0)
			(layers "F.Cu" "F.Mask" "F.Paste")
			(net "P5V_AUX")
		)
	)
	(footprint ""
		(layer "F.Cu")
		(at 116.314474 -55.036212 -90)
		(property "Reference" "R1729"
			(at 0 0 270)
			(layer "F.SilkS")
			(hide yes)
			(effects
				(font
					(size 1.27 1.27)
				)
			)
		)
		(property "Value" ""
			(at 0 0 270)
			(layer "F.Fab")
			(effects
				(font
					(size 1.27 1.27)
				)
			)
		)
		(duplicate_pad_numbers_are_jumpers no)
		(fp_line
			(start -0.7874 0.4064)
			(end -0.7874 -0.4064)
			(stroke
				(width 0.1524)
				(type default)
			)
			(layer "F.SilkS")
		)
		(fp_line
			(start 0.7874 0.4064)
			(end -0.7874 0.4064)
			(stroke
				(width 0.1524)
				(type default)
			)
			(layer "F.SilkS")
		)
		(fp_line
			(start -0.7874 -0.4064)
			(end 0.7874 -0.4064)
			(stroke
				(width 0.1524)
				(type default)
			)
			(layer "F.SilkS")
		)
		(fp_line
			(start 0.7874 -0.4064)
			(end 0.7874 0.4064)
			(stroke
				(width 0.1524)
				(type default)
			)
			(layer "F.SilkS")
		)
		(fp_line
			(start -0.67945 0.3048)
			(end -0.67945 -0.305054)
			(stroke
				(width 0.1)
				(type default)
			)
			(layer "F.Fab")
		)
		(fp_line
			(start -0.12065 0.3048)
			(end -0.67945 0.3048)
			(stroke
				(width 0.1)
				(type default)
			)
			(layer "F.Fab")
		)
		(fp_line
			(start 0.120396 0.3048)
			(end 0.120396 0.2794)
			(stroke
				(width 0.1)
				(type default)
			)
			(layer "F.Fab")
		)
		(fp_line
			(start 0.67945 0.3048)
			(end 0.120396 0.3048)
			(stroke
				(width 0.1)
				(type default)
			)
			(layer "F.Fab")
		)
		(fp_line
			(start -0.12065 0.2794)
			(end -0.12065 0.3048)
			(stroke
				(width 0.1)
				(type default)
			)
			(layer "F.Fab")
		)
		(fp_line
			(start 0.120396 0.2794)
			(end -0.12065 0.2794)
			(stroke
				(width 0.1)
				(type default)
			)
			(layer "F.Fab")
		)
		(fp_line
			(start -0.12065 -0.2794)
			(end 0.12065 -0.2794)
			(stroke
				(width 0.1)
				(type default)
			)
			(layer "F.Fab")
		)
		(fp_line
			(start 0.12065 -0.2794)
			(end 0.12065 -0.3048)
			(stroke
				(width 0.1)
				(type default)
			)
			(layer "F.Fab")
		)
		(fp_line
			(start 0.12065 -0.3048)
			(end 0.67945 -0.3048)
			(stroke
				(width 0.1)
				(type default)
			)
			(layer "F.Fab")
		)
		(fp_line
			(start 0.67945 -0.3048)
			(end 0.67945 0.3048)
			(stroke
				(width 0.1)
				(type default)
			)
			(layer "F.Fab")
		)
		(fp_line
			(start -0.67945 -0.305054)
			(end -0.12065 -0.305054)
			(stroke
				(width 0.1)
				(type default)
			)
			(layer "F.Fab")
		)
		(fp_line
			(start -0.12065 -0.305054)
			(end -0.12065 -0.2794)
			(stroke
				(width 0.1)
				(type default)
			)
			(layer "F.Fab")
		)
		(pad "1" smd circle
			(at -0.40005 0 270)
			(size 0 0)
			(layers "F.Cu" "F.Mask" "F.Paste")
			(net "SCM_JTAG_MUX_S1")
		)
		(pad "2" smd circle
			(at 0.40005 0 270)
			(size 0 0)
			(layers "F.Cu" "F.Mask" "F.Paste")
			(net "GND")
		)
	)
	(footprint ""
		(layer "F.Cu")
		(at 29.478478 -17.623536 90)
		(property "Reference" "C688"
			(at 0 0 90)
			(layer "F.SilkS")
			(hide yes)
			(effects
				(font
					(size 1.27 1.27)
				)
			)
		)
		(property "Value" ""
			(at 0 0 90)
			(layer "F.Fab")
			(effects
				(font
					(size 1.27 1.27)
				)
			)
		)
		(duplicate_pad_numbers_are_jumpers no)
		(fp_line
			(start 0.299974 -0.150114)
			(end 0.299974 0.150114)
			(stroke
				(width 0.1)
				(type default)
			)
			(layer "F.Fab")
		)
		(fp_line
			(start -0.299974 -0.150114)
			(end 0.299974 -0.150114)
			(stroke
				(width 0.1)
				(type default)
			)
			(layer "F.Fab")
		)
		(fp_line
			(start 0.299974 0.150114)
			(end -0.299974 0.150114)
			(stroke
				(width 0.1)
				(type default)
			)
			(layer "F.Fab")
		)
		(fp_line
			(start -0.299974 0.150114)
			(end -0.299974 -0.150114)
			(stroke
				(width 0.1)
				(type default)
			)
			(layer "F.Fab")
		)
		(pad "1" smd rect
			(at -0.2667 0 90)
			(size 0.3048 0.381)
			(layers "F.Cu" "F.Mask" "F.Paste")
			(net "P5E_CPU1_G1_TX_C_DN<10>")
		)
		(pad "2" smd rect
			(at 0.2667 0 90)
			(size 0.3048 0.381)
			(layers "F.Cu" "F.Mask" "F.Paste")
			(net "P5E_CPU1_G1_TX_DN<10>")
		)
	)
	(footprint ""
		(layer "F.Cu")
		(at 181.566058 -255.560322 180)
		(property "Reference" "J100"
			(at -2.7178 -81.857088 0)
			(unlocked yes)
			(layer "F.SilkS")
			(effects
				(font
					(size 0.7874 0.5842)
					(thickness 0.1524)
				)
			)
		)
		(property "Value" ""
			(at 0 0 180)
			(layer "F.Fab")
			(effects
				(font
					(size 1.27 1.27)
				)
			)
		)
		(duplicate_pad_numbers_are_jumpers no)
		(fp_line
			(start 3.24993 81.000092)
			(end -3.24993 81.000092)
			(stroke
				(width 0.1524)
				(type default)
			)
			(layer "F.SilkS")
		)
		(fp_line
			(start 3.24993 80.634078)
			(end 3.24993 81.000092)
			(stroke
				(width 0.1524)
				(type default)
			)
			(layer "F.SilkS")
		)
		(fp_line
			(start 3.24993 -81.000092)
			(end 3.24993 73.928478)
			(stroke
				(width 0.1524)
				(type default)
			)
			(layer "F.SilkS")
		)
		(fp_line
			(start -3.24993 81.000092)
			(end -3.24993 80.583278)
			(stroke
				(width 0.1524)
				(type default)
			)
			(layer "F.SilkS")
		)
		(fp_line
			(start -3.24993 73.928478)
			(end -3.24993 -81.000092)
			(stroke
				(width 0.1524)
				(type default)
			)
			(layer "F.SilkS")
		)
		(fp_line
			(start -3.24993 72.499982)
			(end 3.24993 72.499982)
			(stroke
				(width 0.1524)
				(type default)
			)
			(layer "F.SilkS")
		)
		(fp_line
			(start -3.24993 -72.499982)
			(end 3.24993 -72.499982)
			(stroke
				(width 0.1524)
				(type default)
			)
			(layer "F.SilkS")
		)
		(fp_line
			(start -3.24993 -81.000092)
			(end 3.24993 -81.000092)
			(stroke
				(width 0.1524)
				(type default)
			)
			(layer "F.SilkS")
		)
		(fp_poly
			(pts
				(xy -3.734816 -64.758316) (xy -3.064764 -63.841122) (xy -4.200398 -63.855346)
			)
			(stroke
				(width 0)
				(type default)
			)
			(fill yes)
			(layer "F.SilkS")
		)
		(fp_line
			(start 3.24993 81.000092)
			(end -3.24993 81.000092)
			(stroke
				(width 0.1)
				(type default)
			)
			(layer "F.Fab")
		)
		(fp_line
			(start 3.24993 -81.000092)
			(end 3.24993 81.000092)
			(stroke
				(width 0.1)
				(type default)
			)
			(layer "F.Fab")
		)
		(fp_line
			(start -3.24993 81.000092)
			(end -3.24993 -81.000092)
			(stroke
				(width 0.1)
				(type default)
			)
			(layer "F.Fab")
		)
		(fp_line
			(start -3.24993 72.499982)
			(end 3.24993 72.499982)
			(stroke
				(width 0.1)
				(type default)
			)
			(layer "F.Fab")
		)
		(fp_line
			(start -3.24993 71.000112)
			(end 3.24993 71.000112)
			(stroke
				(width 0.1)
				(type default)
			)
			(layer "F.Fab")
		)
		(fp_line
			(start -3.24993 -71.000112)
			(end 3.24993 -71.000112)
			(stroke
				(width 0.1)
				(type default)
			)
			(layer "F.Fab")
		)
		(fp_line
			(start -3.24993 -72.499982)
			(end 3.24993 -72.499982)
			(stroke
				(width 0.1)
				(type default)
			)
			(layer "F.Fab")
		)
		(fp_line
			(start -3.24993 -81.000092)
			(end 3.24993 -81.000092)
			(stroke
				(width 0.1)
				(type default)
			)
			(layer "F.Fab")
		)
		(fp_poly
			(pts
				(xy -3.41503 -63.324994) (xy -4.43103 -62.816994) (xy -4.43103 -63.832994)
			)
			(stroke
				(width 0)
				(type default)
			)
			(fill yes)
			(layer "F.Fab")
		)
		(pad "1" smd rect
			(at -2.050034 -63.324994 90)
			(size 0.519938 1.4986)
			(layers "F.Cu" "F.Mask" "F.Paste")
			(net "P12V_MEM_CPU1")
		)
		(pad "2" smd rect
			(at -2.050034 -62.47511 90)
			(size 0.519938 1.4986)
			(layers "F.Cu" "F.Mask" "F.Paste")
			(net "Net_2368")
		)
		(pad "3" smd rect
			(at -2.050034 -61.624972 90)
			(size 0.519938 1.4986)
			(layers "F.Cu" "F.Mask" "F.Paste")
			(net "P3V3_AUX")
		)
		(pad "4" smd rect
			(at -2.050034 -60.775088 90)
			(size 0.519938 1.4986)
			(layers "F.Cu" "F.Mask" "F.Paste")
			(net "I3C_SPD_DDRI_CPU1_SCL")
		)
		(pad "5" smd rect
			(at -2.050034 -59.92495 90)
			(size 0.519938 1.4986)
			(layers "F.Cu" "F.Mask" "F.Paste")
			(net "I3C_SPD_DDRI_CPU1_SDA")
		)
		(pad "6" smd rect
			(at -2.050034 -59.075066 90)
			(size 0.519938 1.4986)
			(layers "F.Cu" "F.Mask" "F.Paste")
			(net "GND")
		)
		(pad "7" smd rect
			(at -2.050034 -58.224928 90)
			(size 0.519938 1.4986)
			(layers "F.Cu" "F.Mask" "F.Paste")
			(net "M_I_CPU1_SA_DQ<0>")
		)
		(pad "8" smd rect
			(at -2.050034 -57.375044 90)
			(size 0.519938 1.4986)
			(layers "F.Cu" "F.Mask" "F.Paste")
			(net "GND")
		)
		(pad "9" smd rect
			(at -2.050034 -56.524906 90)
			(size 0.519938 1.4986)
			(layers "F.Cu" "F.Mask" "F.Paste")
			(net "M_I_CPU1_SA_DQ<1>")
		)
		(pad "10" smd rect
			(at -2.050034 -55.675022 90)
			(size 0.519938 1.4986)
			(layers "F.Cu" "F.Mask" "F.Paste")
			(net "GND")
		)
		(pad "11" smd rect
			(at -2.050034 -54.824884 90)
			(size 0.519938 1.4986)
			(layers "F.Cu" "F.Mask" "F.Paste")
			(net "M_I_CPU1_SA_DQS_DP<0>")
		)
		(pad "12" smd rect
			(at -2.050034 -53.975 90)
			(size 0.519938 1.4986)
			(layers "F.Cu" "F.Mask" "F.Paste")
			(net "M_I_CPU1_SA_DQS_DN<0>")
		)
		(pad "13" smd rect
			(at -2.050034 -53.125116 90)
			(size 0.519938 1.4986)
			(layers "F.Cu" "F.Mask" "F.Paste")
			(net "GND")
		)
		(pad "14" smd rect
			(at -2.050034 -52.274978 90)
			(size 0.519938 1.4986)
			(layers "F.Cu" "F.Mask" "F.Paste")
			(net "M_I_CPU1_SA_DQ<4>")
		)
		(pad "15" smd rect
			(at -2.050034 -51.425094 90)
			(size 0.519938 1.4986)
			(layers "F.Cu" "F.Mask" "F.Paste")
			(net "GND")
		)
		(pad "16" smd rect
			(at -2.050034 -50.574956 90)
			(size 0.519938 1.4986)
			(layers "F.Cu" "F.Mask" "F.Paste")
			(net "M_I_CPU1_SA_DQ<5>")
		)
		(pad "17" smd rect
			(at -2.050034 -49.725072 90)
			(size 0.519938 1.4986)
			(layers "F.Cu" "F.Mask" "F.Paste")
			(net "GND")
		)
		(pad "18" smd rect
			(at -2.050034 -48.874934 90)
			(size 0.519938 1.4986)
			(layers "F.Cu" "F.Mask" "F.Paste")
			(net "M_I_CPU1_SA_DQ<8>")
		)
		(pad "19" smd rect
			(at -2.050034 -48.02505 90)
			(size 0.519938 1.4986)
			(layers "F.Cu" "F.Mask" "F.Paste")
			(net "GND")
		)
		(pad "20" smd rect
			(at -2.050034 -47.174912 90)
			(size 0.519938 1.4986)
			(layers "F.Cu" "F.Mask" "F.Paste")
			(net "M_I_CPU1_SA_DQ<9>")
		)
		(pad "21" smd rect
			(at -2.050034 -46.325028 90)
			(size 0.519938 1.4986)
			(layers "F.Cu" "F.Mask" "F.Paste")
			(net "GND")
		)
		(pad "22" smd rect
			(at -2.050034 -45.47489 90)
			(size 0.519938 1.4986)
			(layers "F.Cu" "F.Mask" "F.Paste")
			(net "M_I_CPU1_SA_DQS_DP<1>")
		)
		(pad "23" smd rect
			(at -2.050034 -44.625006 90)
			(size 0.519938 1.4986)
			(layers "F.Cu" "F.Mask" "F.Paste")
			(net "M_I_CPU1_SA_DQS_DN<1>")
		)
		(pad "24" smd rect
			(at -2.050034 -43.775122 90)
			(size 0.519938 1.4986)
			(layers "F.Cu" "F.Mask" "F.Paste")
			(net "GND")
		)
		(pad "25" smd rect
			(at -2.050034 -42.924984 90)
			(size 0.519938 1.4986)
			(layers "F.Cu" "F.Mask" "F.Paste")
			(net "M_I_CPU1_SA_DQ<12>")
		)
		(pad "26" smd rect
			(at -2.050034 -42.0751 90)
			(size 0.519938 1.4986)
			(layers "F.Cu" "F.Mask" "F.Paste")
			(net "GND")
		)
		(pad "27" smd rect
			(at -2.050034 -41.224962 90)
			(size 0.519938 1.4986)
			(layers "F.Cu" "F.Mask" "F.Paste")
			(net "M_I_CPU1_SA_DQ<13>")
		)
		(pad "28" smd rect
			(at -2.050034 -40.375078 90)
			(size 0.519938 1.4986)
			(layers "F.Cu" "F.Mask" "F.Paste")
			(net "GND")
		)
		(pad "29" smd rect
			(at -2.050034 -39.52494 90)
			(size 0.519938 1.4986)
			(layers "F.Cu" "F.Mask" "F.Paste")
			(net "M_I_CPU1_SA_DQ<16>")
		)
		(pad "30" smd rect
			(at -2.050034 -38.675056 90)
			(size 0.519938 1.4986)
			(layers "F.Cu" "F.Mask" "F.Paste")
			(net "GND")
		)
		(pad "31" smd rect
			(at -2.050034 -37.824918 90)
			(size 0.519938 1.4986)
			(layers "F.Cu" "F.Mask" "F.Paste")
			(net "M_I_CPU1_SA_DQ<17>")
		)
		(pad "32" smd rect
			(at -2.050034 -36.975034 90)
			(size 0.519938 1.4986)
			(layers "F.Cu" "F.Mask" "F.Paste")
			(net "GND")
		)
		(pad "33" smd rect
			(at -2.050034 -36.124896 90)
			(size 0.519938 1.4986)
			(layers "F.Cu" "F.Mask" "F.Paste")
			(net "M_I_CPU1_SA_DQS_DP<2>")
		)
		(pad "34" smd rect
			(at -2.050034 -35.275012 90)
			(size 0.519938 1.4986)
			(layers "F.Cu" "F.Mask" "F.Paste")
			(net "M_I_CPU1_SA_DQS_DN<2>")
		)
		(pad "35" smd rect
			(at -2.050034 -34.425128 90)
			(size 0.519938 1.4986)
			(layers "F.Cu" "F.Mask" "F.Paste")
			(net "GND")
		)
		(pad "36" smd rect
			(at -2.050034 -33.57499 90)
			(size 0.519938 1.4986)
			(layers "F.Cu" "F.Mask" "F.Paste")
			(net "M_I_CPU1_SA_DQ<20>")
		)
		(pad "37" smd rect
			(at -2.050034 -32.725106 90)
			(size 0.519938 1.4986)
			(layers "F.Cu" "F.Mask" "F.Paste")
			(net "GND")
		)
		(pad "38" smd rect
			(at -2.050034 -31.874968 90)
			(size 0.519938 1.4986)
			(layers "F.Cu" "F.Mask" "F.Paste")
			(net "M_I_CPU1_SA_DQ<21>")
		)
		(pad "39" smd rect
			(at -2.050034 -31.025084 90)
			(size 0.519938 1.4986)
			(layers "F.Cu" "F.Mask" "F.Paste")
			(net "GND")
		)
		(pad "40" smd rect
			(at -2.050034 -30.174946 90)
			(size 0.519938 1.4986)
			(layers "F.Cu" "F.Mask" "F.Paste")
			(net "M_I_CPU1_SA_DQ<24>")
		)
		(pad "41" smd rect
			(at -2.050034 -29.325062 90)
			(size 0.519938 1.4986)
			(layers "F.Cu" "F.Mask" "F.Paste")
			(net "GND")
		)
		(pad "42" smd rect
			(at -2.050034 -28.474924 90)
			(size 0.519938 1.4986)
			(layers "F.Cu" "F.Mask" "F.Paste")
			(net "M_I_CPU1_SA_DQ<25>")
		)
		(pad "43" smd rect
			(at -2.050034 -27.62504 90)
			(size 0.519938 1.4986)
			(layers "F.Cu" "F.Mask" "F.Paste")
			(net "GND")
		)
		(pad "44" smd rect
			(at -2.050034 -26.774902 90)
			(size 0.519938 1.4986)
			(layers "F.Cu" "F.Mask" "F.Paste")
			(net "M_I_CPU1_SA_DQS_DP<3>")
		)
		(pad "45" smd rect
			(at -2.050034 -25.925018 90)
			(size 0.519938 1.4986)
			(layers "F.Cu" "F.Mask" "F.Paste")
			(net "M_I_CPU1_SA_DQS_DN<3>")
		)
		(pad "46" smd rect
			(at -2.050034 -25.07488 90)
			(size 0.519938 1.4986)
			(layers "F.Cu" "F.Mask" "F.Paste")
			(net "GND")
		)
		(pad "47" smd rect
			(at -2.050034 -24.224996 90)
			(size 0.519938 1.4986)
			(layers "F.Cu" "F.Mask" "F.Paste")
			(net "M_I_CPU1_SA_DQ<28>")
		)
		(pad "48" smd rect
			(at -2.050034 -23.375112 90)
			(size 0.519938 1.4986)
			(layers "F.Cu" "F.Mask" "F.Paste")
			(net "GND")
		)
		(pad "49" smd rect
			(at -2.050034 -22.524974 90)
			(size 0.519938 1.4986)
			(layers "F.Cu" "F.Mask" "F.Paste")
			(net "M_I_CPU1_SA_DQ<29>")
		)
		(pad "50" smd rect
			(at -2.050034 -21.67509 90)
			(size 0.519938 1.4986)
			(layers "F.Cu" "F.Mask" "F.Paste")
			(net "GND")
		)
		(pad "51" smd rect
			(at -2.050034 -20.824952 90)
			(size 0.519938 1.4986)
			(layers "F.Cu" "F.Mask" "F.Paste")
			(net "M_I_CPU1_SA_CB<0>")
		)
		(pad "52" smd rect
			(at -2.050034 -19.975068 90)
			(size 0.519938 1.4986)
			(layers "F.Cu" "F.Mask" "F.Paste")
			(net "GND")
		)
		(pad "53" smd rect
			(at -2.050034 -19.12493 90)
			(size 0.519938 1.4986)
			(layers "F.Cu" "F.Mask" "F.Paste")
			(net "M_I_CPU1_SA_CB<1>")
		)
		(pad "54" smd rect
			(at -2.050034 -18.275046 90)
			(size 0.519938 1.4986)
			(layers "F.Cu" "F.Mask" "F.Paste")
			(net "GND")
		)
		(pad "55" smd rect
			(at -2.050034 -17.424908 90)
			(size 0.519938 1.4986)
			(layers "F.Cu" "F.Mask" "F.Paste")
			(net "M_I_CPU1_SA_DQS_DP<4>")
		)
		(pad "56" smd rect
			(at -2.050034 -16.575024 90)
			(size 0.519938 1.4986)
			(layers "F.Cu" "F.Mask" "F.Paste")
			(net "M_I_CPU1_SA_DQS_DN<4>")
		)
		(pad "57" smd rect
			(at -2.050034 -15.724886 90)
			(size 0.519938 1.4986)
			(layers "F.Cu" "F.Mask" "F.Paste")
			(net "GND")
		)
		(pad "58" smd rect
			(at -2.050034 -14.875002 90)
			(size 0.519938 1.4986)
			(layers "F.Cu" "F.Mask" "F.Paste")
			(net "M_I_CPU1_SA_CB<4>")
		)
		(pad "59" smd rect
			(at -2.050034 -14.025118 90)
			(size 0.519938 1.4986)
			(layers "F.Cu" "F.Mask" "F.Paste")
			(net "GND")
		)
		(pad "60" smd rect
			(at -2.050034 -13.17498 90)
			(size 0.519938 1.4986)
			(layers "F.Cu" "F.Mask" "F.Paste")
			(net "M_I_CPU1_SA_CB<5>")
		)
		(pad "61" smd rect
			(at -2.050034 -12.325096 90)
			(size 0.519938 1.4986)
			(layers "F.Cu" "F.Mask" "F.Paste")
			(net "GND")
		)
		(pad "62" smd rect
			(at -2.050034 -11.474958 90)
			(size 0.519938 1.4986)
			(layers "F.Cu" "F.Mask" "F.Paste")
			(net "M_I_CPU1_ALERT_N")
		)
		(pad "63" smd rect
			(at -2.050034 -10.625074 90)
			(size 0.519938 1.4986)
			(layers "F.Cu" "F.Mask" "F.Paste")
			(net "GND")
		)
		(pad "64" smd rect
			(at -2.050034 -9.774936 90)
			(size 0.519938 1.4986)
			(layers "F.Cu" "F.Mask" "F.Paste")
			(net "M_I_CPU1_SA_CS_N<0>")
		)
		(pad "65" smd rect
			(at -2.050034 -8.925052 90)
			(size 0.519938 1.4986)
			(layers "F.Cu" "F.Mask" "F.Paste")
			(net "GND")
		)
		(pad "66" smd rect
			(at -2.050034 -8.074914 90)
			(size 0.519938 1.4986)
			(layers "F.Cu" "F.Mask" "F.Paste")
			(net "M_I_CPU1_SA_CA<0>")
		)
		(pad "67" smd rect
			(at -2.050034 -7.22503 90)
			(size 0.519938 1.4986)
			(layers "F.Cu" "F.Mask" "F.Paste")
			(net "GND")
		)
		(pad "68" smd rect
			(at -2.050034 -6.374892 90)
			(size 0.519938 1.4986)
			(layers "F.Cu" "F.Mask" "F.Paste")
			(net "M_I_CPU1_SA_CA<2>")
		)
		(pad "69" smd rect
			(at -2.050034 -5.525008 90)
			(size 0.519938 1.4986)
			(layers "F.Cu" "F.Mask" "F.Paste")
			(net "GND")
		)
		(pad "70" smd rect
			(at -2.050034 -4.675124 90)
			(size 0.519938 1.4986)
			(layers "F.Cu" "F.Mask" "F.Paste")
			(net "M_I_CPU1_SA_CA<4>")
		)
		(pad "71" smd rect
			(at -2.050034 -3.824986 90)
			(size 0.519938 1.4986)
			(layers "F.Cu" "F.Mask" "F.Paste")
			(net "GND")
		)
		(pad "72" smd rect
			(at -2.050034 -2.975102 90)
			(size 0.519938 1.4986)
			(layers "F.Cu" "F.Mask" "F.Paste")
			(net "M_I_CPU1_SA_CA<6>")
		)
		(pad "73" smd rect
			(at -2.050034 -2.124964 90)
			(size 0.519938 1.4986)
			(layers "F.Cu" "F.Mask" "F.Paste")
			(net "GND")
		)
		(pad "74" smd rect
			(at -2.050034 -1.27508 90)
			(size 0.519938 1.4986)
			(layers "F.Cu" "F.Mask" "F.Paste")
			(net "M_I_CPU1_SA_PAR")
		)
		(pad "75" smd rect
			(at -2.050034 -0.424942 90)
			(size 0.519938 1.4986)
			(layers "F.Cu" "F.Mask" "F.Paste")
			(net "GND")
		)
		(pad "76" smd rect
			(at -2.050034 5.525008 90)
			(size 0.519938 1.4986)
			(layers "F.Cu" "F.Mask" "F.Paste")
			(net "M_I_CPU1_SB_CA<0>")
		)
		(pad "77" smd rect
			(at -2.050034 6.374892 90)
			(size 0.519938 1.4986)
			(layers "F.Cu" "F.Mask" "F.Paste")
			(net "GND")
		)
		(pad "78" smd rect
			(at -2.050034 7.22503 90)
			(size 0.519938 1.4986)
			(layers "F.Cu" "F.Mask" "F.Paste")
			(net "M_I_CPU1_SB_CA<2>")
		)
		(pad "79" smd rect
			(at -2.050034 8.074914 90)
			(size 0.519938 1.4986)
			(layers "F.Cu" "F.Mask" "F.Paste")
			(net "GND")
		)
		(pad "80" smd rect
			(at -2.050034 8.925052 90)
			(size 0.519938 1.4986)
			(layers "F.Cu" "F.Mask" "F.Paste")
			(net "M_I_CPU1_SB_CA<4>")
		)
		(pad "81" smd rect
			(at -2.050034 9.774936 90)
			(size 0.519938 1.4986)
			(layers "F.Cu" "F.Mask" "F.Paste")
			(net "GND")
		)
		(pad "82" smd rect
			(at -2.050034 10.625074 90)
			(size 0.519938 1.4986)
			(layers "F.Cu" "F.Mask" "F.Paste")
			(net "M_I_CPU1_SB_CA<6>")
		)
		(pad "83" smd rect
			(at -2.050034 11.474958 90)
			(size 0.519938 1.4986)
			(layers "F.Cu" "F.Mask" "F.Paste")
			(net "GND")
		)
		(pad "84" smd rect
			(at -2.050034 12.325096 90)
			(size 0.519938 1.4986)
			(layers "F.Cu" "F.Mask" "F.Paste")
			(net "M_I_CPU1_SB_CS_N<0>")
		)
		(pad "85" smd rect
			(at -2.050034 13.17498 90)
			(size 0.519938 1.4986)
			(layers "F.Cu" "F.Mask" "F.Paste")
			(net "GND")
		)
		(pad "86" smd rect
			(at -2.050034 14.025118 90)
			(size 0.519938 1.4986)
			(layers "F.Cu" "F.Mask" "F.Paste")
			(net "M_I_CPU1_SA_RSP<0>")
		)
		(pad "87" smd rect
			(at -2.050034 14.875002 90)
			(size 0.519938 1.4986)
			(layers "F.Cu" "F.Mask" "F.Paste")
			(net "M_I_CPU1_SB_RSP<0>")
		)
		(pad "88" smd rect
			(at -2.050034 15.724886 90)
			(size 0.519938 1.4986)
			(layers "F.Cu" "F.Mask" "F.Paste")
			(net "GND")
		)
		(pad "89" smd rect
			(at -2.050034 16.575024 90)
			(size 0.519938 1.4986)
			(layers "F.Cu" "F.Mask" "F.Paste")
			(net "M_I_CPU1_SB_CB<4>")
		)
		(pad "90" smd rect
			(at -2.050034 17.424908 90)
			(size 0.519938 1.4986)
			(layers "F.Cu" "F.Mask" "F.Paste")
			(net "GND")
		)
		(pad "91" smd rect
			(at -2.050034 18.275046 90)
			(size 0.519938 1.4986)
			(layers "F.Cu" "F.Mask" "F.Paste")
			(net "M_I_CPU1_SB_CB<5>")
		)
		(pad "92" smd rect
			(at -2.050034 19.12493 90)
			(size 0.519938 1.4986)
			(layers "F.Cu" "F.Mask" "F.Paste")
			(net "GND")
		)
		(pad "93" smd rect
			(at -2.050034 19.975068 90)
			(size 0.519938 1.4986)
			(layers "F.Cu" "F.Mask" "F.Paste")
			(net "M_I_CPU1_SB_DQS_DP<9>")
		)
		(pad "94" smd rect
			(at -2.050034 20.824952 90)
			(size 0.519938 1.4986)
			(layers "F.Cu" "F.Mask" "F.Paste")
			(net "M_I_CPU1_SB_DQS_DN<9>")
		)
		(pad "95" smd rect
			(at -2.050034 21.67509 90)
			(size 0.519938 1.4986)
			(layers "F.Cu" "F.Mask" "F.Paste")
			(net "GND")
		)
		(pad "96" smd rect
			(at -2.050034 22.524974 90)
			(size 0.519938 1.4986)
			(layers "F.Cu" "F.Mask" "F.Paste")
			(net "M_I_CPU1_SB_CB<0>")
		)
		(pad "97" smd rect
			(at -2.050034 23.375112 90)
			(size 0.519938 1.4986)
			(layers "F.Cu" "F.Mask" "F.Paste")
			(net "GND")
		)
		(pad "98" smd rect
			(at -2.050034 24.224996 90)
			(size 0.519938 1.4986)
			(layers "F.Cu" "F.Mask" "F.Paste")
			(net "M_I_CPU1_SB_CB<1>")
		)
		(pad "99" smd rect
			(at -2.050034 25.07488 90)
			(size 0.519938 1.4986)
			(layers "F.Cu" "F.Mask" "F.Paste")
			(net "GND")
		)
		(pad "100" smd rect
			(at -2.050034 25.925018 90)
			(size 0.519938 1.4986)
			(layers "F.Cu" "F.Mask" "F.Paste")
			(net "M_I_CPU1_SB_DQ<0>")
		)
		(pad "101" smd rect
			(at -2.050034 26.774902 90)
			(size 0.519938 1.4986)
			(layers "F.Cu" "F.Mask" "F.Paste")
			(net "GND")
		)
		(pad "102" smd rect
			(at -2.050034 27.62504 90)
			(size 0.519938 1.4986)
			(layers "F.Cu" "F.Mask" "F.Paste")
			(net "M_I_CPU1_SB_DQ<1>")
		)
		(pad "103" smd rect
			(at -2.050034 28.474924 90)
			(size 0.519938 1.4986)
			(layers "F.Cu" "F.Mask" "F.Paste")
			(net "GND")
		)
		(pad "104" smd rect
			(at -2.050034 29.325062 90)
			(size 0.519938 1.4986)
			(layers "F.Cu" "F.Mask" "F.Paste")
			(net "M_I_CPU1_SB_DQS_DP<0>")
		)
		(pad "105" smd rect
			(at -2.050034 30.174946 90)
			(size 0.519938 1.4986)
			(layers "F.Cu" "F.Mask" "F.Paste")
			(net "M_I_CPU1_SB_DQS_DN<0>")
		)
		(pad "106" smd rect
			(at -2.050034 31.025084 90)
			(size 0.519938 1.4986)
			(layers "F.Cu" "F.Mask" "F.Paste")
			(net "GND")
		)
		(pad "107" smd rect
			(at -2.050034 31.874968 90)
			(size 0.519938 1.4986)
			(layers "F.Cu" "F.Mask" "F.Paste")
			(net "M_I_CPU1_SB_DQ<4>")
		)
		(pad "108" smd rect
			(at -2.050034 32.725106 90)
			(size 0.519938 1.4986)
			(layers "F.Cu" "F.Mask" "F.Paste")
			(net "GND")
		)
		(pad "109" smd rect
			(at -2.050034 33.57499 90)
			(size 0.519938 1.4986)
			(layers "F.Cu" "F.Mask" "F.Paste")
			(net "M_I_CPU1_SB_DQ<5>")
		)
		(pad "110" smd rect
			(at -2.050034 34.425128 90)
			(size 0.519938 1.4986)
			(layers "F.Cu" "F.Mask" "F.Paste")
			(net "GND")
		)
		(pad "111" smd rect
			(at -2.050034 35.275012 90)
			(size 0.519938 1.4986)
			(layers "F.Cu" "F.Mask" "F.Paste")
			(net "M_I_CPU1_SB_DQ<8>")
		)
		(pad "112" smd rect
			(at -2.050034 36.124896 90)
			(size 0.519938 1.4986)
			(layers "F.Cu" "F.Mask" "F.Paste")
			(net "GND")
		)
		(pad "113" smd rect
			(at -2.050034 36.975034 90)
			(size 0.519938 1.4986)
			(layers "F.Cu" "F.Mask" "F.Paste")
			(net "M_I_CPU1_SB_DQ<9>")
		)
		(pad "114" smd rect
			(at -2.050034 37.824918 90)
			(size 0.519938 1.4986)
			(layers "F.Cu" "F.Mask" "F.Paste")
			(net "GND")
		)
		(pad "115" smd rect
			(at -2.050034 38.675056 90)
			(size 0.519938 1.4986)
			(layers "F.Cu" "F.Mask" "F.Paste")
			(net "M_I_CPU1_SB_DQS_DP<1>")
		)
		(pad "116" smd rect
			(at -2.050034 39.52494 90)
			(size 0.519938 1.4986)
			(layers "F.Cu" "F.Mask" "F.Paste")
			(net "M_I_CPU1_SB_DQS_DN<1>")
		)
		(pad "117" smd rect
			(at -2.050034 40.375078 90)
			(size 0.519938 1.4986)
			(layers "F.Cu" "F.Mask" "F.Paste")
			(net "GND")
		)
		(pad "118" smd rect
			(at -2.050034 41.224962 90)
			(size 0.519938 1.4986)
			(layers "F.Cu" "F.Mask" "F.Paste")
			(net "M_I_CPU1_SB_DQ<12>")
		)
		(pad "119" smd rect
			(at -2.050034 42.0751 90)
			(size 0.519938 1.4986)
			(layers "F.Cu" "F.Mask" "F.Paste")
			(net "GND")
		)
		(pad "120" smd rect
			(at -2.050034 42.924984 90)
			(size 0.519938 1.4986)
			(layers "F.Cu" "F.Mask" "F.Paste")
			(net "M_I_CPU1_SB_DQ<13>")
		)
		(pad "121" smd rect
			(at -2.050034 43.775122 90)
			(size 0.519938 1.4986)
			(layers "F.Cu" "F.Mask" "F.Paste")
			(net "GND")
		)
		(pad "122" smd rect
			(at -2.050034 44.625006 90)
			(size 0.519938 1.4986)
			(layers "F.Cu" "F.Mask" "F.Paste")
			(net "M_I_CPU1_SB_DQ<16>")
		)
		(pad "123" smd rect
			(at -2.050034 45.47489 90)
			(size 0.519938 1.4986)
			(layers "F.Cu" "F.Mask" "F.Paste")
			(net "GND")
		)
		(pad "124" smd rect
			(at -2.050034 46.325028 90)
			(size 0.519938 1.4986)
			(layers "F.Cu" "F.Mask" "F.Paste")
			(net "M_I_CPU1_SB_DQ<17>")
		)
		(pad "125" smd rect
			(at -2.050034 47.174912 90)
			(size 0.519938 1.4986)
			(layers "F.Cu" "F.Mask" "F.Paste")
			(net "GND")
		)
		(pad "126" smd rect
			(at -2.050034 48.02505 90)
			(size 0.519938 1.4986)
			(layers "F.Cu" "F.Mask" "F.Paste")
			(net "M_I_CPU1_SB_DQS_DP<2>")
		)
		(pad "127" smd rect
			(at -2.050034 48.874934 90)
			(size 0.519938 1.4986)
			(layers "F.Cu" "F.Mask" "F.Paste")
			(net "M_I_CPU1_SB_DQS_DN<2>")
		)
		(pad "128" smd rect
			(at -2.050034 49.725072 90)
			(size 0.519938 1.4986)
			(layers "F.Cu" "F.Mask" "F.Paste")
			(net "GND")
		)
		(pad "129" smd rect
			(at -2.050034 50.574956 90)
			(size 0.519938 1.4986)
			(layers "F.Cu" "F.Mask" "F.Paste")
			(net "M_I_CPU1_SB_DQ<20>")
		)
		(pad "130" smd rect
			(at -2.050034 51.425094 90)
			(size 0.519938 1.4986)
			(layers "F.Cu" "F.Mask" "F.Paste")
			(net "GND")
		)
		(pad "131" smd rect
			(at -2.050034 52.274978 90)
			(size 0.519938 1.4986)
			(layers "F.Cu" "F.Mask" "F.Paste")
			(net "M_I_CPU1_SB_DQ<21>")
		)
		(pad "132" smd rect
			(at -2.050034 53.125116 90)
			(size 0.519938 1.4986)
			(layers "F.Cu" "F.Mask" "F.Paste")
			(net "GND")
		)
		(pad "133" smd rect
			(at -2.050034 53.975 90)
			(size 0.519938 1.4986)
			(layers "F.Cu" "F.Mask" "F.Paste")
			(net "M_I_CPU1_SB_DQ<24>")
		)
		(pad "134" smd rect
			(at -2.050034 54.824884 90)
			(size 0.519938 1.4986)
			(layers "F.Cu" "F.Mask" "F.Paste")
			(net "GND")
		)
		(pad "135" smd rect
			(at -2.050034 55.675022 90)
			(size 0.519938 1.4986)
			(layers "F.Cu" "F.Mask" "F.Paste")
			(net "M_I_CPU1_SB_DQ<25>")
		)
		(pad "136" smd rect
			(at -2.050034 56.524906 90)
			(size 0.519938 1.4986)
			(layers "F.Cu" "F.Mask" "F.Paste")
			(net "GND")
		)
		(pad "137" smd rect
			(at -2.050034 57.375044 90)
			(size 0.519938 1.4986)
			(layers "F.Cu" "F.Mask" "F.Paste")
			(net "M_I_CPU1_SB_DQS_DP<3>")
		)
		(pad "138" smd rect
			(at -2.050034 58.224928 90)
			(size 0.519938 1.4986)
			(layers "F.Cu" "F.Mask" "F.Paste")
			(net "M_I_CPU1_SB_DQS_DN<3>")
		)
		(pad "139" smd rect
			(at -2.050034 59.075066 90)
			(size 0.519938 1.4986)
			(layers "F.Cu" "F.Mask" "F.Paste")
			(net "GND")
		)
		(pad "140" smd rect
			(at -2.050034 59.92495 90)
			(size 0.519938 1.4986)
			(layers "F.Cu" "F.Mask" "F.Paste")
			(net "M_I_CPU1_SB_DQ<28>")
		)
		(pad "141" smd rect
			(at -2.050034 60.775088 90)
			(size 0.519938 1.4986)
			(layers "F.Cu" "F.Mask" "F.Paste")
			(net "GND")
		)
		(pad "142" smd rect
			(at -2.050034 61.624972 90)
			(size 0.519938 1.4986)
			(layers "F.Cu" "F.Mask" "F.Paste")
			(net "M_I_CPU1_SB_DQ<29>")
		)
		(pad "143" smd rect
			(at -2.050034 62.47511 90)
			(size 0.519938 1.4986)
			(layers "F.Cu" "F.Mask" "F.Paste")
			(net "GND")
		)
		(pad "144" smd rect
			(at -2.050034 63.324994 90)
			(size 0.519938 1.4986)
			(layers "F.Cu" "F.Mask" "F.Paste")
			(net "Net_2369")
		)
		(pad "145" smd rect
			(at 2.050034 -63.324994 90)
			(size 0.519938 1.4986)
			(layers "F.Cu" "F.Mask" "F.Paste")
			(net "P12V_MEM_CPU1")
		)
		(pad "146" smd rect
			(at 2.050034 -62.47511 90)
			(size 0.519938 1.4986)
			(layers "F.Cu" "F.Mask" "F.Paste")
			(net "P12V_MEM_CPU1")
		)
		(pad "147" smd rect
			(at 2.050034 -61.624972 90)
			(size 0.519938 1.4986)
			(layers "F.Cu" "F.Mask" "F.Paste")
			(net "PWRGD_CHI_CPU1_DIMM")
		)
		(pad "148" smd rect
			(at 2.050034 -60.775088 90)
			(size 0.519938 1.4986)
			(layers "F.Cu" "F.Mask" "F.Paste")
			(net "PD_CHI_CPU1_DIMM_SAA")
		)
		(pad "149" smd rect
			(at 2.050034 -59.92495 90)
			(size 0.519938 1.4986)
			(layers "F.Cu" "F.Mask" "F.Paste")
			(net "Net_2370")
		)
		(pad "150" smd rect
			(at 2.050034 -59.075066 90)
			(size 0.519938 1.4986)
			(layers "F.Cu" "F.Mask" "F.Paste")
			(net "Net_2371")
		)
		(pad "151" smd rect
			(at 2.050034 -58.224928 90)
			(size 0.519938 1.4986)
			(layers "F.Cu" "F.Mask" "F.Paste")
			(net "GND")
		)
		(pad "152" smd rect
			(at 2.050034 -57.375044 90)
			(size 0.519938 1.4986)
			(layers "F.Cu" "F.Mask" "F.Paste")
			(net "M_I_CPU1_SA_DQ<2>")
		)
		(pad "153" smd rect
			(at 2.050034 -56.524906 90)
			(size 0.519938 1.4986)
			(layers "F.Cu" "F.Mask" "F.Paste")
			(net "GND")
		)
		(pad "154" smd rect
			(at 2.050034 -55.675022 90)
			(size 0.519938 1.4986)
			(layers "F.Cu" "F.Mask" "F.Paste")
			(net "M_I_CPU1_SA_DQ<3>")
		)
		(pad "155" smd rect
			(at 2.050034 -54.824884 90)
			(size 0.519938 1.4986)
			(layers "F.Cu" "F.Mask" "F.Paste")
			(net "GND")
		)
		(pad "156" smd rect
			(at 2.050034 -53.975 90)
			(size 0.519938 1.4986)
			(layers "F.Cu" "F.Mask" "F.Paste")
			(net "M_I_CPU1_SA_DQS_DN<5>")
		)
		(pad "157" smd rect
			(at 2.050034 -53.125116 90)
			(size 0.519938 1.4986)
			(layers "F.Cu" "F.Mask" "F.Paste")
			(net "M_I_CPU1_SA_DQS_DP<5>")
		)
		(pad "158" smd rect
			(at 2.050034 -52.274978 90)
			(size 0.519938 1.4986)
			(layers "F.Cu" "F.Mask" "F.Paste")
			(net "GND")
		)
		(pad "159" smd rect
			(at 2.050034 -51.425094 90)
			(size 0.519938 1.4986)
			(layers "F.Cu" "F.Mask" "F.Paste")
			(net "M_I_CPU1_SA_DQ<6>")
		)
		(pad "160" smd rect
			(at 2.050034 -50.574956 90)
			(size 0.519938 1.4986)
			(layers "F.Cu" "F.Mask" "F.Paste")
			(net "GND")
		)
		(pad "161" smd rect
			(at 2.050034 -49.725072 90)
			(size 0.519938 1.4986)
			(layers "F.Cu" "F.Mask" "F.Paste")
			(net "M_I_CPU1_SA_DQ<7>")
		)
		(pad "162" smd rect
			(at 2.050034 -48.874934 90)
			(size 0.519938 1.4986)
			(layers "F.Cu" "F.Mask" "F.Paste")
			(net "GND")
		)
		(pad "163" smd rect
			(at 2.050034 -48.02505 90)
			(size 0.519938 1.4986)
			(layers "F.Cu" "F.Mask" "F.Paste")
			(net "M_I_CPU1_SA_DQ<10>")
		)
		(pad "164" smd rect
			(at 2.050034 -47.174912 90)
			(size 0.519938 1.4986)
			(layers "F.Cu" "F.Mask" "F.Paste")
			(net "GND")
		)
		(pad "165" smd rect
			(at 2.050034 -46.325028 90)
			(size 0.519938 1.4986)
			(layers "F.Cu" "F.Mask" "F.Paste")
			(net "M_I_CPU1_SA_DQ<11>")
		)
		(pad "166" smd rect
			(at 2.050034 -45.47489 90)
			(size 0.519938 1.4986)
			(layers "F.Cu" "F.Mask" "F.Paste")
			(net "GND")
		)
		(pad "167" smd rect
			(at 2.050034 -44.625006 90)
			(size 0.519938 1.4986)
			(layers "F.Cu" "F.Mask" "F.Paste")
			(net "M_I_CPU1_SA_DQS_DN<6>")
		)
		(pad "168" smd rect
			(at 2.050034 -43.775122 90)
			(size 0.519938 1.4986)
			(layers "F.Cu" "F.Mask" "F.Paste")
			(net "M_I_CPU1_SA_DQS_DP<6>")
		)
		(pad "169" smd rect
			(at 2.050034 -42.924984 90)
			(size 0.519938 1.4986)
			(layers "F.Cu" "F.Mask" "F.Paste")
			(net "GND")
		)
		(pad "170" smd rect
			(at 2.050034 -42.0751 90)
			(size 0.519938 1.4986)
			(layers "F.Cu" "F.Mask" "F.Paste")
			(net "M_I_CPU1_SA_DQ<14>")
		)
		(pad "171" smd rect
			(at 2.050034 -41.224962 90)
			(size 0.519938 1.4986)
			(layers "F.Cu" "F.Mask" "F.Paste")
			(net "GND")
		)
		(pad "172" smd rect
			(at 2.050034 -40.375078 90)
			(size 0.519938 1.4986)
			(layers "F.Cu" "F.Mask" "F.Paste")
			(net "M_I_CPU1_SA_DQ<15>")
		)
		(pad "173" smd rect
			(at 2.050034 -39.52494 90)
			(size 0.519938 1.4986)
			(layers "F.Cu" "F.Mask" "F.Paste")
			(net "GND")
		)
		(pad "174" smd rect
			(at 2.050034 -38.675056 90)
			(size 0.519938 1.4986)
			(layers "F.Cu" "F.Mask" "F.Paste")
			(net "M_I_CPU1_SA_DQ<18>")
		)
		(pad "175" smd rect
			(at 2.050034 -37.824918 90)
			(size 0.519938 1.4986)
			(layers "F.Cu" "F.Mask" "F.Paste")
			(net "GND")
		)
		(pad "176" smd rect
			(at 2.050034 -36.975034 90)
			(size 0.519938 1.4986)
			(layers "F.Cu" "F.Mask" "F.Paste")
			(net "M_I_CPU1_SA_DQ<19>")
		)
		(pad "177" smd rect
			(at 2.050034 -36.124896 90)
			(size 0.519938 1.4986)
			(layers "F.Cu" "F.Mask" "F.Paste")
			(net "GND")
		)
		(pad "178" smd rect
			(at 2.050034 -35.275012 90)
			(size 0.519938 1.4986)
			(layers "F.Cu" "F.Mask" "F.Paste")
			(net "M_I_CPU1_SA_DQS_DN<7>")
		)
		(pad "179" smd rect
			(at 2.050034 -34.425128 90)
			(size 0.519938 1.4986)
			(layers "F.Cu" "F.Mask" "F.Paste")
			(net "M_I_CPU1_SA_DQS_DP<7>")
		)
		(pad "180" smd rect
			(at 2.050034 -33.57499 90)
			(size 0.519938 1.4986)
			(layers "F.Cu" "F.Mask" "F.Paste")
			(net "GND")
		)
		(pad "181" smd rect
			(at 2.050034 -32.725106 90)
			(size 0.519938 1.4986)
			(layers "F.Cu" "F.Mask" "F.Paste")
			(net "M_I_CPU1_SA_DQ<22>")
		)
		(pad "182" smd rect
			(at 2.050034 -31.874968 90)
			(size 0.519938 1.4986)
			(layers "F.Cu" "F.Mask" "F.Paste")
			(net "GND")
		)
		(pad "183" smd rect
			(at 2.050034 -31.025084 90)
			(size 0.519938 1.4986)
			(layers "F.Cu" "F.Mask" "F.Paste")
			(net "M_I_CPU1_SA_DQ<23>")
		)
		(pad "184" smd rect
			(at 2.050034 -30.174946 90)
			(size 0.519938 1.4986)
			(layers "F.Cu" "F.Mask" "F.Paste")
			(net "GND")
		)
		(pad "185" smd rect
			(at 2.050034 -29.325062 90)
			(size 0.519938 1.4986)
			(layers "F.Cu" "F.Mask" "F.Paste")
			(net "M_I_CPU1_SA_DQ<26>")
		)
		(pad "186" smd rect
			(at 2.050034 -28.474924 90)
			(size 0.519938 1.4986)
			(layers "F.Cu" "F.Mask" "F.Paste")
			(net "GND")
		)
		(pad "187" smd rect
			(at 2.050034 -27.62504 90)
			(size 0.519938 1.4986)
			(layers "F.Cu" "F.Mask" "F.Paste")
			(net "M_I_CPU1_SA_DQ<27>")
		)
		(pad "188" smd rect
			(at 2.050034 -26.774902 90)
			(size 0.519938 1.4986)
			(layers "F.Cu" "F.Mask" "F.Paste")
			(net "GND")
		)
		(pad "189" smd rect
			(at 2.050034 -25.925018 90)
			(size 0.519938 1.4986)
			(layers "F.Cu" "F.Mask" "F.Paste")
			(net "M_I_CPU1_SA_DQS_DN<8>")
		)
		(pad "190" smd rect
			(at 2.050034 -25.07488 90)
			(size 0.519938 1.4986)
			(layers "F.Cu" "F.Mask" "F.Paste")
			(net "M_I_CPU1_SA_DQS_DP<8>")
		)
		(pad "191" smd rect
			(at 2.050034 -24.224996 90)
			(size 0.519938 1.4986)
			(layers "F.Cu" "F.Mask" "F.Paste")
			(net "GND")
		)
		(pad "192" smd rect
			(at 2.050034 -23.375112 90)
			(size 0.519938 1.4986)
			(layers "F.Cu" "F.Mask" "F.Paste")
			(net "M_I_CPU1_SA_DQ<30>")
		)
		(pad "193" smd rect
			(at 2.050034 -22.524974 90)
			(size 0.519938 1.4986)
			(layers "F.Cu" "F.Mask" "F.Paste")
			(net "GND")
		)
		(pad "194" smd rect
			(at 2.050034 -21.67509 90)
			(size 0.519938 1.4986)
			(layers "F.Cu" "F.Mask" "F.Paste")
			(net "M_I_CPU1_SA_DQ<31>")
		)
		(pad "195" smd rect
			(at 2.050034 -20.824952 90)
			(size 0.519938 1.4986)
			(layers "F.Cu" "F.Mask" "F.Paste")
			(net "GND")
		)
		(pad "196" smd rect
			(at 2.050034 -19.975068 90)
			(size 0.519938 1.4986)
			(layers "F.Cu" "F.Mask" "F.Paste")
			(net "M_I_CPU1_SA_CB<2>")
		)
		(pad "197" smd rect
			(at 2.050034 -19.12493 90)
			(size 0.519938 1.4986)
			(layers "F.Cu" "F.Mask" "F.Paste")
			(net "GND")
		)
		(pad "198" smd rect
			(at 2.050034 -18.275046 90)
			(size 0.519938 1.4986)
			(layers "F.Cu" "F.Mask" "F.Paste")
			(net "M_I_CPU1_SA_CB<3>")
		)
		(pad "199" smd rect
			(at 2.050034 -17.424908 90)
			(size 0.519938 1.4986)
			(layers "F.Cu" "F.Mask" "F.Paste")
			(net "GND")
		)
		(pad "200" smd rect
			(at 2.050034 -16.575024 90)
			(size 0.519938 1.4986)
			(layers "F.Cu" "F.Mask" "F.Paste")
			(net "M_I_CPU1_SA_DQS_DN<9>")
		)
		(pad "201" smd rect
			(at 2.050034 -15.724886 90)
			(size 0.519938 1.4986)
			(layers "F.Cu" "F.Mask" "F.Paste")
			(net "M_I_CPU1_SA_DQS_DP<9>")
		)
		(pad "202" smd rect
			(at 2.050034 -14.875002 90)
			(size 0.519938 1.4986)
			(layers "F.Cu" "F.Mask" "F.Paste")
			(net "GND")
		)
		(pad "203" smd rect
			(at 2.050034 -14.025118 90)
			(size 0.519938 1.4986)
			(layers "F.Cu" "F.Mask" "F.Paste")
			(net "M_I_CPU1_SA_CB<6>")
		)
		(pad "204" smd rect
			(at 2.050034 -13.17498 90)
			(size 0.519938 1.4986)
			(layers "F.Cu" "F.Mask" "F.Paste")
			(net "GND")
		)
		(pad "205" smd rect
			(at 2.050034 -12.325096 90)
			(size 0.519938 1.4986)
			(layers "F.Cu" "F.Mask" "F.Paste")
			(net "M_I_CPU1_SA_CB<7>")
		)
		(pad "206" smd rect
			(at 2.050034 -11.474958 90)
			(size 0.519938 1.4986)
			(layers "F.Cu" "F.Mask" "F.Paste")
			(net "GND")
		)
		(pad "207" smd rect
			(at 2.050034 -10.625074 90)
			(size 0.519938 1.4986)
			(layers "F.Cu" "F.Mask" "F.Paste")
			(net "M_I_CPU1_RESET_N")
		)
		(pad "208" smd rect
			(at 2.050034 -9.774936 90)
			(size 0.519938 1.4986)
			(layers "F.Cu" "F.Mask" "F.Paste")
			(net "GND")
		)
		(pad "209" smd rect
			(at 2.050034 -8.925052 90)
			(size 0.519938 1.4986)
			(layers "F.Cu" "F.Mask" "F.Paste")
			(net "M_I_CPU1_SA_CS_N<1>")
		)
		(pad "210" smd rect
			(at 2.050034 -8.074914 90)
			(size 0.519938 1.4986)
			(layers "F.Cu" "F.Mask" "F.Paste")
			(net "GND")
		)
		(pad "211" smd rect
			(at 2.050034 -7.22503 90)
			(size 0.519938 1.4986)
			(layers "F.Cu" "F.Mask" "F.Paste")
			(net "M_I_CPU1_SA_CA<1>")
		)
		(pad "212" smd rect
			(at 2.050034 -6.374892 90)
			(size 0.519938 1.4986)
			(layers "F.Cu" "F.Mask" "F.Paste")
			(net "GND")
		)
		(pad "213" smd rect
			(at 2.050034 -5.525008 90)
			(size 0.519938 1.4986)
			(layers "F.Cu" "F.Mask" "F.Paste")
			(net "M_I_CPU1_SA_CA<3>")
		)
		(pad "214" smd rect
			(at 2.050034 -4.675124 90)
			(size 0.519938 1.4986)
			(layers "F.Cu" "F.Mask" "F.Paste")
			(net "GND")
		)
		(pad "215" smd rect
			(at 2.050034 -3.824986 90)
			(size 0.519938 1.4986)
			(layers "F.Cu" "F.Mask" "F.Paste")
			(net "M_I_CPU1_SA_CA<5>")
		)
		(pad "216" smd rect
			(at 2.050034 -2.975102 90)
			(size 0.519938 1.4986)
			(layers "F.Cu" "F.Mask" "F.Paste")
			(net "GND")
		)
		(pad "217" smd rect
			(at 2.050034 -2.124964 90)
			(size 0.519938 1.4986)
			(layers "F.Cu" "F.Mask" "F.Paste")
			(net "M_I_CPU1_CLK_DP<0>")
		)
		(pad "218" smd rect
			(at 2.050034 -1.27508 90)
			(size 0.519938 1.4986)
			(layers "F.Cu" "F.Mask" "F.Paste")
			(net "M_I_CPU1_CLK_DN<0>")
		)
		(pad "219" smd rect
			(at 2.050034 -0.424942 90)
			(size 0.519938 1.4986)
			(layers "F.Cu" "F.Mask" "F.Paste")
			(net "GND")
		)
		(pad "220" smd rect
			(at 2.050034 5.525008 90)
			(size 0.519938 1.4986)
			(layers "F.Cu" "F.Mask" "F.Paste")
			(net "Net_2372")
		)
		(pad "221" smd rect
			(at 2.050034 6.374892 90)
			(size 0.519938 1.4986)
			(layers "F.Cu" "F.Mask" "F.Paste")
			(net "M_I_CPU1_SB_CA<1>")
		)
		(pad "222" smd rect
			(at 2.050034 7.22503 90)
			(size 0.519938 1.4986)
			(layers "F.Cu" "F.Mask" "F.Paste")
			(net "GND")
		)
		(pad "223" smd rect
			(at 2.050034 8.074914 90)
			(size 0.519938 1.4986)
			(layers "F.Cu" "F.Mask" "F.Paste")
			(net "M_I_CPU1_SB_CA<3>")
		)
		(pad "224" smd rect
			(at 2.050034 8.925052 90)
			(size 0.519938 1.4986)
			(layers "F.Cu" "F.Mask" "F.Paste")
			(net "GND")
		)
		(pad "225" smd rect
			(at 2.050034 9.774936 90)
			(size 0.519938 1.4986)
			(layers "F.Cu" "F.Mask" "F.Paste")
			(net "M_I_CPU1_SB_CA<5>")
		)
		(pad "226" smd rect
			(at 2.050034 10.625074 90)
			(size 0.519938 1.4986)
			(layers "F.Cu" "F.Mask" "F.Paste")
			(net "GND")
		)
		(pad "227" smd rect
			(at 2.050034 11.474958 90)
			(size 0.519938 1.4986)
			(layers "F.Cu" "F.Mask" "F.Paste")
			(net "M_I_CPU1_SB_PAR")
		)
		(pad "228" smd rect
			(at 2.050034 12.325096 90)
			(size 0.519938 1.4986)
			(layers "F.Cu" "F.Mask" "F.Paste")
			(net "GND")
		)
		(pad "229" smd rect
			(at 2.050034 13.17498 90)
			(size 0.519938 1.4986)
			(layers "F.Cu" "F.Mask" "F.Paste")
			(net "M_I_CPU1_SB_CS_N<1>")
		)
		(pad "230" smd rect
			(at 2.050034 14.025118 90)
			(size 0.519938 1.4986)
			(layers "F.Cu" "F.Mask" "F.Paste")
			(net "GND")
		)
		(pad "231" smd rect
			(at 2.050034 14.875002 90)
			(size 0.519938 1.4986)
			(layers "F.Cu" "F.Mask" "F.Paste")
			(net "Net_2373")
		)
		(pad "232" smd rect
			(at 2.050034 15.724886 90)
			(size 0.519938 1.4986)
			(layers "F.Cu" "F.Mask" "F.Paste")
			(net "Net_2374")
		)
		(pad "233" smd rect
			(at 2.050034 16.575024 90)
			(size 0.519938 1.4986)
			(layers "F.Cu" "F.Mask" "F.Paste")
			(net "GND")
		)
		(pad "234" smd rect
			(at 2.050034 17.424908 90)
			(size 0.519938 1.4986)
			(layers "F.Cu" "F.Mask" "F.Paste")
			(net "M_I_CPU1_SB_CB<6>")
		)
		(pad "235" smd rect
			(at 2.050034 18.275046 90)
			(size 0.519938 1.4986)
			(layers "F.Cu" "F.Mask" "F.Paste")
			(net "GND")
		)
		(pad "236" smd rect
			(at 2.050034 19.12493 90)
			(size 0.519938 1.4986)
			(layers "F.Cu" "F.Mask" "F.Paste")
			(net "M_I_CPU1_SB_CB<7>")
		)
		(pad "237" smd rect
			(at 2.050034 19.975068 90)
			(size 0.519938 1.4986)
			(layers "F.Cu" "F.Mask" "F.Paste")
			(net "GND")
		)
		(pad "238" smd rect
			(at 2.050034 20.824952 90)
			(size 0.519938 1.4986)
			(layers "F.Cu" "F.Mask" "F.Paste")
			(net "M_I_CPU1_SB_DQS_DN<4>")
		)
		(pad "239" smd rect
			(at 2.050034 21.67509 90)
			(size 0.519938 1.4986)
			(layers "F.Cu" "F.Mask" "F.Paste")
			(net "M_I_CPU1_SB_DQS_DP<4>")
		)
		(pad "240" smd rect
			(at 2.050034 22.524974 90)
			(size 0.519938 1.4986)
			(layers "F.Cu" "F.Mask" "F.Paste")
			(net "GND")
		)
		(pad "241" smd rect
			(at 2.050034 23.375112 90)
			(size 0.519938 1.4986)
			(layers "F.Cu" "F.Mask" "F.Paste")
			(net "M_I_CPU1_SB_CB<2>")
		)
		(pad "242" smd rect
			(at 2.050034 24.224996 90)
			(size 0.519938 1.4986)
			(layers "F.Cu" "F.Mask" "F.Paste")
			(net "GND")
		)
		(pad "243" smd rect
			(at 2.050034 25.07488 90)
			(size 0.519938 1.4986)
			(layers "F.Cu" "F.Mask" "F.Paste")
			(net "M_I_CPU1_SB_CB<3>")
		)
		(pad "244" smd rect
			(at 2.050034 25.925018 90)
			(size 0.519938 1.4986)
			(layers "F.Cu" "F.Mask" "F.Paste")
			(net "GND")
		)
		(pad "245" smd rect
			(at 2.050034 26.774902 90)
			(size 0.519938 1.4986)
			(layers "F.Cu" "F.Mask" "F.Paste")
			(net "M_I_CPU1_SB_DQ<2>")
		)
		(pad "246" smd rect
			(at 2.050034 27.62504 90)
			(size 0.519938 1.4986)
			(layers "F.Cu" "F.Mask" "F.Paste")
			(net "GND")
		)
		(pad "247" smd rect
			(at 2.050034 28.474924 90)
			(size 0.519938 1.4986)
			(layers "F.Cu" "F.Mask" "F.Paste")
			(net "M_I_CPU1_SB_DQ<3>")
		)
		(pad "248" smd rect
			(at 2.050034 29.325062 90)
			(size 0.519938 1.4986)
			(layers "F.Cu" "F.Mask" "F.Paste")
			(net "GND")
		)
		(pad "249" smd rect
			(at 2.050034 30.174946 90)
			(size 0.519938 1.4986)
			(layers "F.Cu" "F.Mask" "F.Paste")
			(net "M_I_CPU1_SB_DQS_DN<5>")
		)
		(pad "250" smd rect
			(at 2.050034 31.025084 90)
			(size 0.519938 1.4986)
			(layers "F.Cu" "F.Mask" "F.Paste")
			(net "M_I_CPU1_SB_DQS_DP<5>")
		)
		(pad "251" smd rect
			(at 2.050034 31.874968 90)
			(size 0.519938 1.4986)
			(layers "F.Cu" "F.Mask" "F.Paste")
			(net "GND")
		)
		(pad "252" smd rect
			(at 2.050034 32.725106 90)
			(size 0.519938 1.4986)
			(layers "F.Cu" "F.Mask" "F.Paste")
			(net "M_I_CPU1_SB_DQ<6>")
		)
		(pad "253" smd rect
			(at 2.050034 33.57499 90)
			(size 0.519938 1.4986)
			(layers "F.Cu" "F.Mask" "F.Paste")
			(net "GND")
		)
		(pad "254" smd rect
			(at 2.050034 34.425128 90)
			(size 0.519938 1.4986)
			(layers "F.Cu" "F.Mask" "F.Paste")
			(net "M_I_CPU1_SB_DQ<7>")
		)
		(pad "255" smd rect
			(at 2.050034 35.275012 90)
			(size 0.519938 1.4986)
			(layers "F.Cu" "F.Mask" "F.Paste")
			(net "GND")
		)
		(pad "256" smd rect
			(at 2.050034 36.124896 90)
			(size 0.519938 1.4986)
			(layers "F.Cu" "F.Mask" "F.Paste")
			(net "M_I_CPU1_SB_DQ<10>")
		)
		(pad "257" smd rect
			(at 2.050034 36.975034 90)
			(size 0.519938 1.4986)
			(layers "F.Cu" "F.Mask" "F.Paste")
			(net "GND")
		)
		(pad "258" smd rect
			(at 2.050034 37.824918 90)
			(size 0.519938 1.4986)
			(layers "F.Cu" "F.Mask" "F.Paste")
			(net "M_I_CPU1_SB_DQ<11>")
		)
		(pad "259" smd rect
			(at 2.050034 38.675056 90)
			(size 0.519938 1.4986)
			(layers "F.Cu" "F.Mask" "F.Paste")
			(net "GND")
		)
		(pad "260" smd rect
			(at 2.050034 39.52494 90)
			(size 0.519938 1.4986)
			(layers "F.Cu" "F.Mask" "F.Paste")
			(net "M_I_CPU1_SB_DQS_DN<6>")
		)
		(pad "261" smd rect
			(at 2.050034 40.375078 90)
			(size 0.519938 1.4986)
			(layers "F.Cu" "F.Mask" "F.Paste")
			(net "M_I_CPU1_SB_DQS_DP<6>")
		)
		(pad "262" smd rect
			(at 2.050034 41.224962 90)
			(size 0.519938 1.4986)
			(layers "F.Cu" "F.Mask" "F.Paste")
			(net "GND")
		)
		(pad "263" smd rect
			(at 2.050034 42.0751 90)
			(size 0.519938 1.4986)
			(layers "F.Cu" "F.Mask" "F.Paste")
			(net "M_I_CPU1_SB_DQ<14>")
		)
		(pad "264" smd rect
			(at 2.050034 42.924984 90)
			(size 0.519938 1.4986)
			(layers "F.Cu" "F.Mask" "F.Paste")
			(net "GND")
		)
		(pad "265" smd rect
			(at 2.050034 43.775122 90)
			(size 0.519938 1.4986)
			(layers "F.Cu" "F.Mask" "F.Paste")
			(net "M_I_CPU1_SB_DQ<15>")
		)
		(pad "266" smd rect
			(at 2.050034 44.625006 90)
			(size 0.519938 1.4986)
			(layers "F.Cu" "F.Mask" "F.Paste")
			(net "GND")
		)
		(pad "267" smd rect
			(at 2.050034 45.47489 90)
			(size 0.519938 1.4986)
			(layers "F.Cu" "F.Mask" "F.Paste")
			(net "M_I_CPU1_SB_DQ<18>")
		)
		(pad "268" smd rect
			(at 2.050034 46.325028 90)
			(size 0.519938 1.4986)
			(layers "F.Cu" "F.Mask" "F.Paste")
			(net "GND")
		)
		(pad "269" smd rect
			(at 2.050034 47.174912 90)
			(size 0.519938 1.4986)
			(layers "F.Cu" "F.Mask" "F.Paste")
			(net "M_I_CPU1_SB_DQ<19>")
		)
		(pad "270" smd rect
			(at 2.050034 48.02505 90)
			(size 0.519938 1.4986)
			(layers "F.Cu" "F.Mask" "F.Paste")
			(net "GND")
		)
		(pad "271" smd rect
			(at 2.050034 48.874934 90)
			(size 0.519938 1.4986)
			(layers "F.Cu" "F.Mask" "F.Paste")
			(net "M_I_CPU1_SB_DQS_DN<7>")
		)
		(pad "272" smd rect
			(at 2.050034 49.725072 90)
			(size 0.519938 1.4986)
			(layers "F.Cu" "F.Mask" "F.Paste")
			(net "M_I_CPU1_SB_DQS_DP<7>")
		)
		(pad "273" smd rect
			(at 2.050034 50.574956 90)
			(size 0.519938 1.4986)
			(layers "F.Cu" "F.Mask" "F.Paste")
			(net "GND")
		)
		(pad "274" smd rect
			(at 2.050034 51.425094 90)
			(size 0.519938 1.4986)
			(layers "F.Cu" "F.Mask" "F.Paste")
			(net "M_I_CPU1_SB_DQ<22>")
		)
		(pad "275" smd rect
			(at 2.050034 52.274978 90)
			(size 0.519938 1.4986)
			(layers "F.Cu" "F.Mask" "F.Paste")
			(net "GND")
		)
		(pad "276" smd rect
			(at 2.050034 53.125116 90)
			(size 0.519938 1.4986)
			(layers "F.Cu" "F.Mask" "F.Paste")
			(net "M_I_CPU1_SB_DQ<23>")
		)
		(pad "277" smd rect
			(at 2.050034 53.975 90)
			(size 0.519938 1.4986)
			(layers "F.Cu" "F.Mask" "F.Paste")
			(net "GND")
		)
		(pad "278" smd rect
			(at 2.050034 54.824884 90)
			(size 0.519938 1.4986)
			(layers "F.Cu" "F.Mask" "F.Paste")
			(net "M_I_CPU1_SB_DQ<26>")
		)
		(pad "279" smd rect
			(at 2.050034 55.675022 90)
			(size 0.519938 1.4986)
			(layers "F.Cu" "F.Mask" "F.Paste")
			(net "GND")
		)
		(pad "280" smd rect
			(at 2.050034 56.524906 90)
			(size 0.519938 1.4986)
			(layers "F.Cu" "F.Mask" "F.Paste")
			(net "M_I_CPU1_SB_DQ<27>")
		)
		(pad "281" smd rect
			(at 2.050034 57.375044 90)
			(size 0.519938 1.4986)
			(layers "F.Cu" "F.Mask" "F.Paste")
			(net "GND")
		)
		(pad "282" smd rect
			(at 2.050034 58.224928 90)
			(size 0.519938 1.4986)
			(layers "F.Cu" "F.Mask" "F.Paste")
			(net "M_I_CPU1_SB_DQS_DN<8>")
		)
		(pad "283" smd rect
			(at 2.050034 59.075066 90)
			(size 0.519938 1.4986)
			(layers "F.Cu" "F.Mask" "F.Paste")
			(net "M_I_CPU1_SB_DQS_DP<8>")
		)
		(pad "284" smd rect
			(at 2.050034 59.92495 90)
			(size 0.519938 1.4986)
			(layers "F.Cu" "F.Mask" "F.Paste")
			(net "GND")
		)
		(pad "285" smd rect
			(at 2.050034 60.775088 90)
			(size 0.519938 1.4986)
			(layers "F.Cu" "F.Mask" "F.Paste")
			(net "M_I_CPU1_SB_DQ<30>")
		)
		(pad "286" smd rect
			(at 2.050034 61.624972 90)
			(size 0.519938 1.4986)
			(layers "F.Cu" "F.Mask" "F.Paste")
			(net "GND")
		)
		(pad "287" smd rect
			(at 2.050034 62.47511 90)
			(size 0.519938 1.4986)
			(layers "F.Cu" "F.Mask" "F.Paste")
			(net "M_I_CPU1_SB_DQ<31>")
		)
		(pad "288" smd rect
			(at 2.050034 63.324994 90)
			(size 0.519938 1.4986)
			(layers "F.Cu" "F.Mask" "F.Paste")
			(net "GND")
		)
		(pad "G1" thru_hole oval
			(at 0 -68.97497 90)
			(size 1.7272 3.4798)
			(drill oval 1.2192 2.4638)
			(layers "*.Cu" "*.Mask")
			(remove_unused_layers no)
			(net "GND")
			(clearance 0.127)
			(thermal_gap 0.127)
		)
		(pad "G2" thru_hole oval
			(at 0 3.875024 90)
			(size 1.7272 3.4798)
			(drill oval 1.2192 2.4638)
			(layers "*.Cu" "*.Mask")
			(remove_unused_layers no)
			(net "GND")
			(clearance 0.127)
			(thermal_gap 0.127)
		)
		(pad "G3" thru_hole oval
			(at 0 68.97497 90)
			(size 1.7272 3.4798)
			(drill oval 1.2192 2.4638)
			(layers "*.Cu" "*.Mask")
			(remove_unused_layers no)
			(net "GND")
			(clearance 0.127)
			(thermal_gap 0.127)
		)
	)
	(footprint ""
		(layer "F.Cu")
		(at 76.115164 -17.050512 180)
		(property "Reference" "PR3828"
			(at 0 0 180)
			(layer "F.SilkS")
			(hide yes)
			(effects
				(font
					(size 1.27 1.27)
				)
			)
		)
		(property "Value" ""
			(at 0 0 180)
			(layer "F.Fab")
			(effects
				(font
					(size 1.27 1.27)
				)
			)
		)
		(duplicate_pad_numbers_are_jumpers no)
		(fp_line
			(start 0.7874 0.4064)
			(end -0.7874 0.4064)
			(stroke
				(width 0.1524)
				(type default)
			)
			(layer "F.SilkS")
		)
		(fp_line
			(start 0.7874 -0.4064)
			(end 0.7874 0.4064)
			(stroke
				(width 0.1524)
				(type default)
			)
			(layer "F.SilkS")
		)
		(fp_line
			(start -0.7874 0.4064)
			(end -0.7874 -0.4064)
			(stroke
				(width 0.1524)
				(type default)
			)
			(layer "F.SilkS")
		)
		(fp_line
			(start -0.7874 -0.4064)
			(end 0.7874 -0.4064)
			(stroke
				(width 0.1524)
				(type default)
			)
			(layer "F.SilkS")
		)
		(fp_line
			(start 0.67945 0.3048)
			(end 0.120396 0.3048)
			(stroke
				(width 0.1)
				(type default)
			)
			(layer "F.Fab")
		)
		(fp_line
			(start 0.67945 -0.3048)
			(end 0.67945 0.3048)
			(stroke
				(width 0.1)
				(type default)
			)
			(layer "F.Fab")
		)
		(fp_line
			(start 0.12065 -0.2794)
			(end 0.12065 -0.3048)
			(stroke
				(width 0.1)
				(type default)
			)
			(layer "F.Fab")
		)
		(fp_line
			(start 0.12065 -0.3048)
			(end 0.67945 -0.3048)
			(stroke
				(width 0.1)
				(type default)
			)
			(layer "F.Fab")
		)
		(fp_line
			(start 0.120396 0.3048)
			(end 0.120396 0.2794)
			(stroke
				(width 0.1)
				(type default)
			)
			(layer "F.Fab")
		)
		(fp_line
			(start 0.120396 0.2794)
			(end -0.12065 0.2794)
			(stroke
				(width 0.1)
				(type default)
			)
			(layer "F.Fab")
		)
		(fp_line
			(start -0.12065 0.3048)
			(end -0.67945 0.3048)
			(stroke
				(width 0.1)
				(type default)
			)
			(layer "F.Fab")
		)
		(fp_line
			(start -0.12065 0.2794)
			(end -0.12065 0.3048)
			(stroke
				(width 0.1)
				(type default)
			)
			(layer "F.Fab")
		)
		(fp_line
			(start -0.12065 -0.2794)
			(end 0.12065 -0.2794)
			(stroke
				(width 0.1)
				(type default)
			)
			(layer "F.Fab")
		)
		(fp_line
			(start -0.12065 -0.305054)
			(end -0.12065 -0.2794)
			(stroke
				(width 0.1)
				(type default)
			)
			(layer "F.Fab")
		)
		(fp_line
			(start -0.67945 0.3048)
			(end -0.67945 -0.305054)
			(stroke
				(width 0.1)
				(type default)
			)
			(layer "F.Fab")
		)
		(fp_line
			(start -0.67945 -0.305054)
			(end -0.12065 -0.305054)
			(stroke
				(width 0.1)
				(type default)
			)
			(layer "F.Fab")
		)
		(pad "1" smd circle
			(at -0.40005 0 180)
			(size 0 0)
			(layers "F.Cu" "F.Mask" "F.Paste")
			(net "P12V_OCP_OV_2")
		)
		(pad "2" smd circle
			(at 0.40005 0 180)
			(size 0 0)
			(layers "F.Cu" "F.Mask" "F.Paste")
			(net "GND")
		)
	)
	(footprint ""
		(layer "F.Cu")
		(at 23.229316 -39.824914)
		(property "Reference" "U56"
			(at -1.567942 -4.057904 0)
			(unlocked yes)
			(layer "F.SilkS")
			(effects
				(font
					(size 0.7874 0.5842)
					(thickness 0.1524)
				)
			)
		)
		(property "Value" ""
			(at 0 0 0)
			(layer "F.Fab")
			(effects
				(font
					(size 1.27 1.27)
				)
			)
		)
		(duplicate_pad_numbers_are_jumpers no)
		(fp_line
			(start -1.500124 -1.500124)
			(end -1.004062 -1.500124)
			(stroke
				(width 0.1524)
				(type default)
			)
			(layer "F.SilkS")
		)
		(fp_line
			(start -1.500124 -1.004062)
			(end -1.500124 -1.500124)
			(stroke
				(width 0.1524)
				(type default)
			)
			(layer "F.SilkS")
		)
		(fp_line
			(start -1.500124 1.500124)
			(end -1.500124 1.004062)
			(stroke
				(width 0.1524)
				(type default)
			)
			(layer "F.SilkS")
		)
		(fp_line
			(start -1.004062 1.500124)
			(end -1.500124 1.500124)
			(stroke
				(width 0.1524)
				(type default)
			)
			(layer "F.SilkS")
		)
		(fp_line
			(start 1.004062 -1.500124)
			(end 1.500124 -1.500124)
			(stroke
				(width 0.1524)
				(type default)
			)
			(layer "F.SilkS")
		)
		(fp_line
			(start 1.500124 -1.500124)
			(end 1.500124 -1.004062)
			(stroke
				(width 0.1524)
				(type default)
			)
			(layer "F.SilkS")
		)
		(fp_line
			(start 1.500124 1.004062)
			(end 1.500124 1.500124)
			(stroke
				(width 0.1524)
				(type default)
			)
			(layer "F.SilkS")
		)
		(fp_line
			(start 1.500124 1.500124)
			(end 1.004062 1.500124)
			(stroke
				(width 0.1524)
				(type default)
			)
			(layer "F.SilkS")
		)
		(fp_poly
			(pts
				(xy -2.335784 -2.746502) (xy -3.134868 -2.119122) (xy -2.107946 -1.633728)
			)
			(stroke
				(width 0)
				(type default)
			)
			(fill yes)
			(layer "F.SilkS")
		)
		(fp_line
			(start -1.500124 -1.500124)
			(end 1.500124 -1.500124)
			(stroke
				(width 0.1)
				(type default)
			)
			(layer "F.Fab")
		)
		(fp_line
			(start -1.500124 1.500124)
			(end -1.500124 -1.500124)
			(stroke
				(width 0.1)
				(type default)
			)
			(layer "F.Fab")
		)
		(fp_line
			(start 1.500124 -1.500124)
			(end 1.500124 1.500124)
			(stroke
				(width 0.1)
				(type default)
			)
			(layer "F.Fab")
		)
		(fp_line
			(start 1.500124 1.500124)
			(end -1.500124 1.500124)
			(stroke
				(width 0.1)
				(type default)
			)
			(layer "F.Fab")
		)
		(fp_poly
			(pts
				(xy -2.847848 -1.258062) (xy -2.847848 -0.242062) (xy -1.831848 -0.750062)
			)
			(stroke
				(width 0)
				(type default)
			)
			(fill yes)
			(layer "F.Fab")
		)
		(pad "1" smd rect
			(at -1.400048 -0.750062 270)
			(size 0.2286 0.6096)
			(layers "F.Cu" "F.Mask" "F.Paste")
			(net "INA230_7_A1")
		)
		(pad "2" smd rect
			(at -1.400048 -0.249936 270)
			(size 0.2286 0.6096)
			(layers "F.Cu" "F.Mask" "F.Paste")
			(net "INA230_7_A0")
		)
		(pad "3" smd rect
			(at -1.400048 0.249936 270)
			(size 0.2286 0.6096)
			(layers "F.Cu" "F.Mask" "F.Paste")
			(net "P12V_OCP_V3_2_ADC_ALERT_R")
		)
		(pad "4" smd rect
			(at -1.400048 0.750062 270)
			(size 0.2286 0.6096)
			(layers "F.Cu" "F.Mask" "F.Paste")
			(net "SMB_INA230_7_3V3AUX_SDA_R1")
		)
		(pad "5" smd rect
			(at -0.750062 1.400048)
			(size 0.2286 0.6096)
			(layers "F.Cu" "F.Mask" "F.Paste")
			(net "SMB_INA230_7_3V3AUX_SCL_R1")
		)
		(pad "6" smd rect
			(at -0.249936 1.400048)
			(size 0.2286 0.6096)
			(layers "F.Cu" "F.Mask" "F.Paste")
			(net "NC_INA230_7_NC0")
		)
		(pad "7" smd rect
			(at 0.249936 1.400048)
			(size 0.2286 0.6096)
			(layers "F.Cu" "F.Mask" "F.Paste")
			(net "NC_INA230_7_NC1")
		)
		(pad "8" smd rect
			(at 0.750062 1.400048)
			(size 0.2286 0.6096)
			(layers "F.Cu" "F.Mask" "F.Paste")
			(net "NC_INA230_7_NC2")
		)
		(pad "9" smd rect
			(at 1.400048 0.750062 270)
			(size 0.2286 0.6096)
			(layers "F.Cu" "F.Mask" "F.Paste")
			(net "P3V3_AUX")
		)
		(pad "10" smd rect
			(at 1.400048 0.249936 270)
			(size 0.2286 0.6096)
			(layers "F.Cu" "F.Mask" "F.Paste")
			(net "GND")
		)
		(pad "11" smd rect
			(at 1.400048 -0.249936 270)
			(size 0.2286 0.6096)
			(layers "F.Cu" "F.Mask" "F.Paste")
			(net "P12V_OCP_V3_2")
		)
		(pad "12" smd rect
			(at 1.400048 -0.750062 270)
			(size 0.2286 0.6096)
			(layers "F.Cu" "F.Mask" "F.Paste")
			(net "VSENSE_P12V_INA230_7_INN")
		)
		(pad "13" smd rect
			(at 0.750062 -1.400048)
			(size 0.2286 0.6096)
			(layers "F.Cu" "F.Mask" "F.Paste")
			(net "VSENSE_P12V_INA230_7_INP")
		)
		(pad "14" smd rect
			(at 0.249936 -1.400048)
			(size 0.2286 0.6096)
			(layers "F.Cu" "F.Mask" "F.Paste")
			(net "NC_INA230_7_NC3")
		)
		(pad "15" smd rect
			(at -0.249936 -1.400048)
			(size 0.2286 0.6096)
			(layers "F.Cu" "F.Mask" "F.Paste")
			(net "NC_INA230_7_NC4")
		)
		(pad "16" smd rect
			(at -0.750062 -1.400048)
			(size 0.2286 0.6096)
			(layers "F.Cu" "F.Mask" "F.Paste")
			(net "NC_INA230_7_NC5")
		)
		(pad "TH" smd rect
			(at 0 0)
			(size 1.7018 1.7018)
			(layers "F.Cu" "F.Mask" "F.Paste")
			(net "GND")
		)
		(zone
			(layer "F.Cu")
			(hatch none 0.5)
			(connect_pads
				(clearance 0)
			)
			(min_thickness 0.25)
			(keepout
				(tracks not_allowed)
				(vias allowed)
				(pads allowed)
				(copperpour not_allowed)
				(footprints allowed)
			)
			(placement
				(enabled no)
				(sheetname "")
			)
			(fill
				(thermal_gap 0.5)
				(thermal_bridge_width 0.5)
				(island_removal_mode 0)
			)
			(polygon
				(pts
					(xy 22.184868 -39.850314) (xy 22.184868 -40.869362) (xy 24.273764 -40.869362) (xy 24.273764 -38.780466)
					(xy 22.184868 -38.780466) (xy 22.184868 -39.824914) (xy 22.327616 -39.824914) (xy 22.327616 -38.923214)
					(xy 24.131016 -38.923214) (xy 24.131016 -40.726614) (xy 22.327616 -40.726614) (xy 22.327616 -39.850314)
				)
			)
		)
	)
	(footprint ""
		(layer "F.Cu")
		(at 441.776866 -402.838412 90)
		(property "Reference" "PC6553_1"
			(at 0 0 90)
			(layer "F.SilkS")
			(hide yes)
			(effects
				(font
					(size 1.27 1.27)
				)
			)
		)
		(property "Value" ""
			(at 0 0 90)
			(layer "F.Fab")
			(effects
				(font
					(size 1.27 1.27)
				)
			)
		)
		(duplicate_pad_numbers_are_jumpers no)
		(fp_line
			(start 0.7874 -0.4064)
			(end 0.7874 0.4064)
			(stroke
				(width 0.1524)
				(type default)
			)
			(layer "F.SilkS")
		)
		(fp_line
			(start -0.7874 -0.4064)
			(end 0.7874 -0.4064)
			(stroke
				(width 0.1524)
				(type default)
			)
			(layer "F.SilkS")
		)
		(fp_line
			(start 0.7874 0.4064)
			(end -0.7874 0.4064)
			(stroke
				(width 0.1524)
				(type default)
			)
			(layer "F.SilkS")
		)
		(fp_line
			(start -0.7874 0.4064)
			(end -0.7874 -0.4064)
			(stroke
				(width 0.1524)
				(type default)
			)
			(layer "F.SilkS")
		)
		(fp_line
			(start -0.12065 -0.305054)
			(end -0.12065 -0.2794)
			(stroke
				(width 0.1)
				(type default)
			)
			(layer "F.Fab")
		)
		(fp_line
			(start -0.67945 -0.305054)
			(end -0.12065 -0.305054)
			(stroke
				(width 0.1)
				(type default)
			)
			(layer "F.Fab")
		)
		(fp_line
			(start 0.67945 -0.3048)
			(end 0.67945 0.3048)
			(stroke
				(width 0.1)
				(type default)
			)
			(layer "F.Fab")
		)
		(fp_line
			(start 0.12065 -0.3048)
			(end 0.67945 -0.3048)
			(stroke
				(width 0.1)
				(type default)
			)
			(layer "F.Fab")
		)
		(fp_line
			(start 0.12065 -0.2794)
			(end 0.12065 -0.3048)
			(stroke
				(width 0.1)
				(type default)
			)
			(layer "F.Fab")
		)
		(fp_line
			(start -0.12065 -0.2794)
			(end 0.12065 -0.2794)
			(stroke
				(width 0.1)
				(type default)
			)
			(layer "F.Fab")
		)
		(fp_line
			(start 0.120396 0.2794)
			(end -0.12065 0.2794)
			(stroke
				(width 0.1)
				(type default)
			)
			(layer "F.Fab")
		)
		(fp_line
			(start -0.12065 0.2794)
			(end -0.12065 0.3048)
			(stroke
				(width 0.1)
				(type default)
			)
			(layer "F.Fab")
		)
		(fp_line
			(start 0.67945 0.3048)
			(end 0.120396 0.3048)
			(stroke
				(width 0.1)
				(type default)
			)
			(layer "F.Fab")
		)
		(fp_line
			(start 0.120396 0.3048)
			(end 0.120396 0.2794)
			(stroke
				(width 0.1)
				(type default)
			)
			(layer "F.Fab")
		)
		(fp_line
			(start -0.12065 0.3048)
			(end -0.67945 0.3048)
			(stroke
				(width 0.1)
				(type default)
			)
			(layer "F.Fab")
		)
		(fp_line
			(start -0.67945 0.3048)
			(end -0.67945 -0.305054)
			(stroke
				(width 0.1)
				(type default)
			)
			(layer "F.Fab")
		)
		(pad "1" smd circle
			(at -0.40005 0 90)
			(size 0 0)
			(layers "F.Cu" "F.Mask" "F.Paste")
			(net "PV09_RETIMER_CPU0_VCCS")
		)
		(pad "2" smd circle
			(at 0.40005 0 90)
			(size 0 0)
			(layers "F.Cu" "F.Mask" "F.Paste")
			(net "GND")
		)
	)
	(footprint ""
		(layer "F.Cu")
		(at 191.67983 -362.430568 180)
		(property "Reference" "PC522"
			(at -1.14554 -2.774188 0)
			(unlocked yes)
			(layer "F.SilkS")
			(effects
				(font
					(size 0.7874 0.5842)
					(thickness 0.1524)
				)
				(justify left)
			)
		)
		(property "Value" ""
			(at 0 0 180)
			(layer "F.Fab")
			(effects
				(font
					(size 1.27 1.27)
				)
			)
		)
		(duplicate_pad_numbers_are_jumpers no)
		(fp_line
			(start -3.400044 1.249934)
			(end 3.400044 1.249934)
			(stroke
				(width 0.1524)
				(type default)
			)
			(layer "F.SilkS")
		)
		(fp_circle
			(center 0 1.249934)
			(end -3.400044 1.249934)
			(stroke
				(width 0.1524)
				(type default)
			)
			(fill no)
			(layer "F.SilkS")
		)
		(fp_poly
			(pts
				(arc
					(start 3.400044 1.249934)
					(mid 0 4.649978)
					(end -3.400044 1.249934)
				)
			)
			(stroke
				(width 0)
				(type default)
			)
			(fill yes)
			(layer "F.SilkS")
		)
		(fp_circle
			(center 0 1.249934)
			(end -3.400044 1.249934)
			(stroke
				(width 0.1)
				(type default)
			)
			(fill no)
			(layer "F.Fab")
		)
		(pad "1" thru_hole rect
			(at 0 0 180)
			(size 1.524 1.524)
			(drill 1.016)
			(layers "*.Cu" "*.Mask")
			(remove_unused_layers no)
			(net "SW_P12V_AUX_PVDD11_S3_P1_FLT")
			(clearance 0)
			(padstack
				(mode front_inner_back)
				(layer "Inner"
					(shape circle)
					(size 1.524 1.524)
					(clearance 0)
				)
				(layer "B.Cu"
					(shape rect)
					(size 1.524 1.524)
					(clearance 0)
				)
			)
		)
		(pad "2" thru_hole circle
			(at 0 2.500122 180)
			(size 1.524 1.524)
			(drill 1.016)
			(layers "*.Cu" "*.Mask")
			(remove_unused_layers no)
			(net "GND")
			(clearance 0)
		)
	)
	(footprint ""
		(layer "F.Cu")
		(at 68.42887 -148.21789 -90)
		(property "Reference" "PR8"
			(at 0 0 270)
			(layer "F.SilkS")
			(hide yes)
			(effects
				(font
					(size 1.27 1.27)
				)
			)
		)
		(property "Value" ""
			(at 0 0 270)
			(layer "F.Fab")
			(effects
				(font
					(size 1.27 1.27)
				)
			)
		)
		(duplicate_pad_numbers_are_jumpers no)
		(fp_line
			(start -0.7874 0.4064)
			(end -0.7874 -0.4064)
			(stroke
				(width 0.1524)
				(type default)
			)
			(layer "F.SilkS")
		)
		(fp_line
			(start 0.7874 0.4064)
			(end -0.7874 0.4064)
			(stroke
				(width 0.1524)
				(type default)
			)
			(layer "F.SilkS")
		)
		(fp_line
			(start -0.7874 -0.4064)
			(end 0.7874 -0.4064)
			(stroke
				(width 0.1524)
				(type default)
			)
			(layer "F.SilkS")
		)
		(fp_line
			(start 0.7874 -0.4064)
			(end 0.7874 0.4064)
			(stroke
				(width 0.1524)
				(type default)
			)
			(layer "F.SilkS")
		)
		(fp_line
			(start -0.67945 0.3048)
			(end -0.67945 -0.305054)
			(stroke
				(width 0.1)
				(type default)
			)
			(layer "F.Fab")
		)
		(fp_line
			(start -0.12065 0.3048)
			(end -0.67945 0.3048)
			(stroke
				(width 0.1)
				(type default)
			)
			(layer "F.Fab")
		)
		(fp_line
			(start 0.120396 0.3048)
			(end 0.120396 0.2794)
			(stroke
				(width 0.1)
				(type default)
			)
			(layer "F.Fab")
		)
		(fp_line
			(start 0.67945 0.3048)
			(end 0.120396 0.3048)
			(stroke
				(width 0.1)
				(type default)
			)
			(layer "F.Fab")
		)
		(fp_line
			(start -0.12065 0.2794)
			(end -0.12065 0.3048)
			(stroke
				(width 0.1)
				(type default)
			)
			(layer "F.Fab")
		)
		(fp_line
			(start 0.120396 0.2794)
			(end -0.12065 0.2794)
			(stroke
				(width 0.1)
				(type default)
			)
			(layer "F.Fab")
		)
		(fp_line
			(start -0.12065 -0.2794)
			(end 0.12065 -0.2794)
			(stroke
				(width 0.1)
				(type default)
			)
			(layer "F.Fab")
		)
		(fp_line
			(start 0.12065 -0.2794)
			(end 0.12065 -0.3048)
			(stroke
				(width 0.1)
				(type default)
			)
			(layer "F.Fab")
		)
		(fp_line
			(start 0.12065 -0.3048)
			(end 0.67945 -0.3048)
			(stroke
				(width 0.1)
				(type default)
			)
			(layer "F.Fab")
		)
		(fp_line
			(start 0.67945 -0.3048)
			(end 0.67945 0.3048)
			(stroke
				(width 0.1)
				(type default)
			)
			(layer "F.Fab")
		)
		(fp_line
			(start -0.67945 -0.305054)
			(end -0.12065 -0.305054)
			(stroke
				(width 0.1)
				(type default)
			)
			(layer "F.Fab")
		)
		(fp_line
			(start -0.12065 -0.305054)
			(end -0.12065 -0.2794)
			(stroke
				(width 0.1)
				(type default)
			)
			(layer "F.Fab")
		)
		(pad "1" smd circle
			(at -0.40005 0 270)
			(size 0 0)
			(layers "F.Cu" "F.Mask" "F.Paste")
			(net "PVDD18_S5_P1_CS")
		)
		(pad "2" smd circle
			(at 0.40005 0 270)
			(size 0 0)
			(layers "F.Cu" "F.Mask" "F.Paste")
			(net "GND")
		)
	)
	(footprint ""
		(layer "F.Cu")
		(at 253.10084 -92.719144 -90)
		(property "Reference" "R1639"
			(at 0 0 270)
			(layer "F.SilkS")
			(hide yes)
			(effects
				(font
					(size 1.27 1.27)
				)
			)
		)
		(property "Value" ""
			(at 0 0 270)
			(layer "F.Fab")
			(effects
				(font
					(size 1.27 1.27)
				)
			)
		)
		(duplicate_pad_numbers_are_jumpers no)
		(fp_line
			(start -0.7874 0.4064)
			(end -0.7874 -0.4064)
			(stroke
				(width 0.1524)
				(type default)
			)
			(layer "F.SilkS")
		)
		(fp_line
			(start 0.7874 0.4064)
			(end -0.7874 0.4064)
			(stroke
				(width 0.1524)
				(type default)
			)
			(layer "F.SilkS")
		)
		(fp_line
			(start -0.7874 -0.4064)
			(end 0.7874 -0.4064)
			(stroke
				(width 0.1524)
				(type default)
			)
			(layer "F.SilkS")
		)
		(fp_line
			(start 0.7874 -0.4064)
			(end 0.7874 0.4064)
			(stroke
				(width 0.1524)
				(type default)
			)
			(layer "F.SilkS")
		)
		(fp_line
			(start -0.67945 0.3048)
			(end -0.67945 -0.305054)
			(stroke
				(width 0.1)
				(type default)
			)
			(layer "F.Fab")
		)
		(fp_line
			(start -0.12065 0.3048)
			(end -0.67945 0.3048)
			(stroke
				(width 0.1)
				(type default)
			)
			(layer "F.Fab")
		)
		(fp_line
			(start 0.120396 0.3048)
			(end 0.120396 0.2794)
			(stroke
				(width 0.1)
				(type default)
			)
			(layer "F.Fab")
		)
		(fp_line
			(start 0.67945 0.3048)
			(end 0.120396 0.3048)
			(stroke
				(width 0.1)
				(type default)
			)
			(layer "F.Fab")
		)
		(fp_line
			(start -0.12065 0.2794)
			(end -0.12065 0.3048)
			(stroke
				(width 0.1)
				(type default)
			)
			(layer "F.Fab")
		)
		(fp_line
			(start 0.120396 0.2794)
			(end -0.12065 0.2794)
			(stroke
				(width 0.1)
				(type default)
			)
			(layer "F.Fab")
		)
		(fp_line
			(start -0.12065 -0.2794)
			(end 0.12065 -0.2794)
			(stroke
				(width 0.1)
				(type default)
			)
			(layer "F.Fab")
		)
		(fp_line
			(start 0.12065 -0.2794)
			(end 0.12065 -0.3048)
			(stroke
				(width 0.1)
				(type default)
			)
			(layer "F.Fab")
		)
		(fp_line
			(start 0.12065 -0.3048)
			(end 0.67945 -0.3048)
			(stroke
				(width 0.1)
				(type default)
			)
			(layer "F.Fab")
		)
		(fp_line
			(start 0.67945 -0.3048)
			(end 0.67945 0.3048)
			(stroke
				(width 0.1)
				(type default)
			)
			(layer "F.Fab")
		)
		(fp_line
			(start -0.67945 -0.305054)
			(end -0.12065 -0.305054)
			(stroke
				(width 0.1)
				(type default)
			)
			(layer "F.Fab")
		)
		(fp_line
			(start -0.12065 -0.305054)
			(end -0.12065 -0.2794)
			(stroke
				(width 0.1)
				(type default)
			)
			(layer "F.Fab")
		)
		(pad "1" smd circle
			(at -0.40005 0 270)
			(size 0 0)
			(layers "F.Cu" "F.Mask" "F.Paste")
			(net "JTAG_P0_R_TMS")
		)
		(pad "2" smd circle
			(at 0.40005 0 270)
			(size 0 0)
			(layers "F.Cu" "F.Mask" "F.Paste")
			(net "JTAG_CPU0_TMS")
		)
	)
	(footprint ""
		(layer "F.Cu")
		(at 438.107836 -166.684452 180)
		(property "Reference" "C1337"
			(at 0 0 180)
			(layer "F.SilkS")
			(hide yes)
			(effects
				(font
					(size 1.27 1.27)
				)
			)
		)
		(property "Value" ""
			(at 0 0 180)
			(layer "F.Fab")
			(effects
				(font
					(size 1.27 1.27)
				)
			)
		)
		(duplicate_pad_numbers_are_jumpers no)
		(fp_line
			(start 0.7874 0.4064)
			(end -0.7874 0.4064)
			(stroke
				(width 0.1524)
				(type default)
			)
			(layer "F.SilkS")
		)
		(fp_line
			(start 0.7874 -0.4064)
			(end 0.7874 0.4064)
			(stroke
				(width 0.1524)
				(type default)
			)
			(layer "F.SilkS")
		)
		(fp_line
			(start -0.7874 0.4064)
			(end -0.7874 -0.4064)
			(stroke
				(width 0.1524)
				(type default)
			)
			(layer "F.SilkS")
		)
		(fp_line
			(start -0.7874 -0.4064)
			(end 0.7874 -0.4064)
			(stroke
				(width 0.1524)
				(type default)
			)
			(layer "F.SilkS")
		)
		(fp_line
			(start 0.67945 0.3048)
			(end 0.120396 0.3048)
			(stroke
				(width 0.1)
				(type default)
			)
			(layer "F.Fab")
		)
		(fp_line
			(start 0.67945 -0.3048)
			(end 0.67945 0.3048)
			(stroke
				(width 0.1)
				(type default)
			)
			(layer "F.Fab")
		)
		(fp_line
			(start 0.12065 -0.2794)
			(end 0.12065 -0.3048)
			(stroke
				(width 0.1)
				(type default)
			)
			(layer "F.Fab")
		)
		(fp_line
			(start 0.12065 -0.3048)
			(end 0.67945 -0.3048)
			(stroke
				(width 0.1)
				(type default)
			)
			(layer "F.Fab")
		)
		(fp_line
			(start 0.120396 0.3048)
			(end 0.120396 0.2794)
			(stroke
				(width 0.1)
				(type default)
			)
			(layer "F.Fab")
		)
		(fp_line
			(start 0.120396 0.2794)
			(end -0.12065 0.2794)
			(stroke
				(width 0.1)
				(type default)
			)
			(layer "F.Fab")
		)
		(fp_line
			(start -0.12065 0.3048)
			(end -0.67945 0.3048)
			(stroke
				(width 0.1)
				(type default)
			)
			(layer "F.Fab")
		)
		(fp_line
			(start -0.12065 0.2794)
			(end -0.12065 0.3048)
			(stroke
				(width 0.1)
				(type default)
			)
			(layer "F.Fab")
		)
		(fp_line
			(start -0.12065 -0.2794)
			(end 0.12065 -0.2794)
			(stroke
				(width 0.1)
				(type default)
			)
			(layer "F.Fab")
		)
		(fp_line
			(start -0.12065 -0.305054)
			(end -0.12065 -0.2794)
			(stroke
				(width 0.1)
				(type default)
			)
			(layer "F.Fab")
		)
		(fp_line
			(start -0.67945 0.3048)
			(end -0.67945 -0.305054)
			(stroke
				(width 0.1)
				(type default)
			)
			(layer "F.Fab")
		)
		(fp_line
			(start -0.67945 -0.305054)
			(end -0.12065 -0.305054)
			(stroke
				(width 0.1)
				(type default)
			)
			(layer "F.Fab")
		)
		(pad "1" smd circle
			(at -0.40005 0 180)
			(size 0 0)
			(layers "F.Cu" "F.Mask" "F.Paste")
			(net "P3V3_AUX")
		)
		(pad "2" smd circle
			(at 0.40005 0 180)
			(size 0 0)
			(layers "F.Cu" "F.Mask" "F.Paste")
			(net "GND")
		)
	)
	(footprint ""
		(layer "F.Cu")
		(at 359.520236 -394.82268 90)
		(property "Reference" "C589"
			(at 0 0 90)
			(layer "F.SilkS")
			(hide yes)
			(effects
				(font
					(size 1.27 1.27)
				)
			)
		)
		(property "Value" ""
			(at 0 0 90)
			(layer "F.Fab")
			(effects
				(font
					(size 1.27 1.27)
				)
			)
		)
		(duplicate_pad_numbers_are_jumpers no)
		(fp_line
			(start 0.7874 -0.4064)
			(end 0.7874 0.4064)
			(stroke
				(width 0.1524)
				(type default)
			)
			(layer "F.SilkS")
		)
		(fp_line
			(start -0.7874 -0.4064)
			(end 0.7874 -0.4064)
			(stroke
				(width 0.1524)
				(type default)
			)
			(layer "F.SilkS")
		)
		(fp_line
			(start 0.7874 0.4064)
			(end -0.7874 0.4064)
			(stroke
				(width 0.1524)
				(type default)
			)
			(layer "F.SilkS")
		)
		(fp_line
			(start -0.7874 0.4064)
			(end -0.7874 -0.4064)
			(stroke
				(width 0.1524)
				(type default)
			)
			(layer "F.SilkS")
		)
		(fp_line
			(start -0.12065 -0.305054)
			(end -0.12065 -0.2794)
			(stroke
				(width 0.1)
				(type default)
			)
			(layer "F.Fab")
		)
		(fp_line
			(start -0.67945 -0.305054)
			(end -0.12065 -0.305054)
			(stroke
				(width 0.1)
				(type default)
			)
			(layer "F.Fab")
		)
		(fp_line
			(start 0.67945 -0.3048)
			(end 0.67945 0.3048)
			(stroke
				(width 0.1)
				(type default)
			)
			(layer "F.Fab")
		)
		(fp_line
			(start 0.12065 -0.3048)
			(end 0.67945 -0.3048)
			(stroke
				(width 0.1)
				(type default)
			)
			(layer "F.Fab")
		)
		(fp_line
			(start 0.12065 -0.2794)
			(end 0.12065 -0.3048)
			(stroke
				(width 0.1)
				(type default)
			)
			(layer "F.Fab")
		)
		(fp_line
			(start -0.12065 -0.2794)
			(end 0.12065 -0.2794)
			(stroke
				(width 0.1)
				(type default)
			)
			(layer "F.Fab")
		)
		(fp_line
			(start 0.120396 0.2794)
			(end -0.12065 0.2794)
			(stroke
				(width 0.1)
				(type default)
			)
			(layer "F.Fab")
		)
		(fp_line
			(start -0.12065 0.2794)
			(end -0.12065 0.3048)
			(stroke
				(width 0.1)
				(type default)
			)
			(layer "F.Fab")
		)
		(fp_line
			(start 0.67945 0.3048)
			(end 0.120396 0.3048)
			(stroke
				(width 0.1)
				(type default)
			)
			(layer "F.Fab")
		)
		(fp_line
			(start 0.120396 0.3048)
			(end 0.120396 0.2794)
			(stroke
				(width 0.1)
				(type default)
			)
			(layer "F.Fab")
		)
		(fp_line
			(start -0.12065 0.3048)
			(end -0.67945 0.3048)
			(stroke
				(width 0.1)
				(type default)
			)
			(layer "F.Fab")
		)
		(fp_line
			(start -0.67945 0.3048)
			(end -0.67945 -0.305054)
			(stroke
				(width 0.1)
				(type default)
			)
			(layer "F.Fab")
		)
		(pad "1" smd circle
			(at -0.40005 0 90)
			(size 0 0)
			(layers "F.Cu" "F.Mask" "F.Paste")
			(net "P1V8_CPU0_RT_1D")
		)
		(pad "2" smd circle
			(at 0.40005 0 90)
			(size 0 0)
			(layers "F.Cu" "F.Mask" "F.Paste")
			(net "GND")
		)
	)
	(footprint ""
		(layer "F.Cu")
		(at 107.45597 -178.171856 180)
		(property "Reference" "PU28"
			(at 5.34289 -4.788916 0)
			(unlocked yes)
			(layer "F.SilkS")
			(effects
				(font
					(size 0.7874 0.5842)
					(thickness 0.1524)
				)
				(justify left)
			)
		)
		(property "Value" ""
			(at 0 0 180)
			(layer "F.Fab")
			(effects
				(font
					(size 1.27 1.27)
				)
			)
		)
		(duplicate_pad_numbers_are_jumpers no)
		(fp_line
			(start 2.500122 2.999994)
			(end 2.2987 2.999994)
			(stroke
				(width 0.1524)
				(type default)
			)
			(layer "F.SilkS")
		)
		(fp_line
			(start 2.500122 2.339594)
			(end 2.500122 2.999994)
			(stroke
				(width 0.1524)
				(type default)
			)
			(layer "F.SilkS")
		)
		(fp_line
			(start 2.500122 -2.999994)
			(end 2.500122 -2.44348)
			(stroke
				(width 0.1524)
				(type default)
			)
			(layer "F.SilkS")
		)
		(fp_line
			(start 2.31394 -2.999994)
			(end 2.500122 -2.999994)
			(stroke
				(width 0.1524)
				(type default)
			)
			(layer "F.SilkS")
		)
		(fp_line
			(start -2.2987 2.999994)
			(end -2.500122 2.999994)
			(stroke
				(width 0.1524)
				(type default)
			)
			(layer "F.SilkS")
		)
		(fp_line
			(start -2.500122 2.999994)
			(end -2.500122 2.339594)
			(stroke
				(width 0.1524)
				(type default)
			)
			(layer "F.SilkS")
		)
		(fp_line
			(start -2.500122 0.6604)
			(end -2.500122 0.229108)
			(stroke
				(width 0.1524)
				(type default)
			)
			(layer "F.SilkS")
		)
		(fp_line
			(start -2.500122 -2.529078)
			(end -2.500122 -2.999994)
			(stroke
				(width 0.1524)
				(type default)
			)
			(layer "F.SilkS")
		)
		(fp_line
			(start -2.500122 -2.999994)
			(end -2.24409 -2.999994)
			(stroke
				(width 0.1524)
				(type default)
			)
			(layer "F.SilkS")
		)
		(fp_poly
			(pts
				(xy -2.819908 -2.401316) (xy -3.493262 -2.625852) (xy -3.044444 -3.074924)
			)
			(stroke
				(width 0)
				(type default)
			)
			(fill yes)
			(layer "F.SilkS")
		)
		(fp_line
			(start 2.500122 2.999994)
			(end -2.500122 2.999994)
			(stroke
				(width 0.1)
				(type default)
			)
			(layer "F.Fab")
		)
		(fp_line
			(start 2.500122 -2.999994)
			(end 2.500122 2.999994)
			(stroke
				(width 0.1)
				(type default)
			)
			(layer "F.Fab")
		)
		(fp_line
			(start -2.500122 2.999994)
			(end -2.500122 -2.999994)
			(stroke
				(width 0.1)
				(type default)
			)
			(layer "F.Fab")
		)
		(fp_line
			(start -2.500122 -2.999994)
			(end 2.500122 -2.999994)
			(stroke
				(width 0.1)
				(type default)
			)
			(layer "F.Fab")
		)
		(fp_poly
			(pts
				(xy -4.218432 -2.783078) (xy -4.218432 -1.767078) (xy -3.202432 -2.275078)
			)
			(stroke
				(width 0)
				(type default)
			)
			(fill yes)
			(layer "F.Fab")
		)
		(pad "1" smd rect
			(at -2.400046 -2.275078 270)
			(size 0.2286 0.6096)
			(layers "F.Cu" "F.Mask" "F.Paste")
			(net "PVDDCR_CPU0_P1_VOS4")
		)
		(pad "2" smd rect
			(at -2.400046 -1.82499 270)
			(size 0.2286 0.6096)
			(layers "F.Cu" "F.Mask" "F.Paste")
			(net "GND")
		)
		(pad "3" smd rect
			(at -2.400046 -1.374902 270)
			(size 0.2286 0.6096)
			(layers "F.Cu" "F.Mask" "F.Paste")
			(net "PVDDCR_CPU0_P1_VCC4")
		)
		(pad "4" smd rect
			(at -2.400046 -0.925068 270)
			(size 0.2286 0.6096)
			(layers "F.Cu" "F.Mask" "F.Paste")
			(net "PVDDCR_CPU0_P1_PVCC")
		)
		(pad "5" smd rect
			(at -2.400046 -0.47498 270)
			(size 0.2286 0.6096)
			(layers "F.Cu" "F.Mask" "F.Paste")
			(net "GND")
		)
		(pad "6" smd rect
			(at -2.400046 -0.024892 270)
			(size 0.2286 0.6096)
			(layers "F.Cu" "F.Mask" "F.Paste")
			(net "NC_PVDDCR_CPU0_P1_GL1_4")
		)
		(pad "7_9-20_24" smd circle
			(at 0 1.150112 270)
			(size 0 0)
			(layers "F.Cu" "F.Mask" "F.Paste")
			(net "GND")
		)
		(pad "10_19" smd rect
			(at 0 2.899918 270)
			(size 0.6096 4.318)
			(layers "F.Cu" "F.Mask" "F.Paste")
			(net "SW_PVDDCR_CPU0_P1_SW4")
		)
		(pad "25_29" smd rect
			(at 1.549908 -1.279906 90)
			(size 2.0574 2.3114)
			(layers "F.Cu" "F.Mask" "F.Paste")
			(net "SW_P12V_AUX_PVDDCR_CPU0_P1_FLT")
		)
		(pad "30" smd rect
			(at 2.05994 -2.899918 180)
			(size 0.2286 0.6096)
			(layers "F.Cu" "F.Mask" "F.Paste")
			(net "SW_P12V_AUX_PVDDCR_CPU0_P1_FLT")
		)
		(pad "31" smd rect
			(at 1.610106 -2.899918 180)
			(size 0.2286 0.6096)
			(layers "F.Cu" "F.Mask" "F.Paste")
			(net "NC_PVDDCR_CPU0_P1_DNC4")
		)
		(pad "32" smd rect
			(at 1.160018 -2.899918 180)
			(size 0.2286 0.6096)
			(layers "F.Cu" "F.Mask" "F.Paste")
			(net "SW_PVDDCR_CPU0_P1_PH4")
		)
		(pad "33" smd rect
			(at 0.70993 -2.899918 180)
			(size 0.2286 0.6096)
			(layers "F.Cu" "F.Mask" "F.Paste")
			(net "SW_PVDDCR_CPU0_P1_BOOT4")
		)
		(pad "34" smd rect
			(at 0.260096 -2.899918 180)
			(size 0.2286 0.6096)
			(layers "F.Cu" "F.Mask" "F.Paste")
			(net "PVDDCR_CPU0_P1_PWM4")
		)
		(pad "35" smd rect
			(at -0.189992 -2.899918 180)
			(size 0.2286 0.6096)
			(layers "F.Cu" "F.Mask" "F.Paste")
			(net "PVDDCR_CPU0_P1_VCC4")
		)
		(pad "36" smd rect
			(at -0.64008 -2.899918 180)
			(size 0.2286 0.6096)
			(layers "F.Cu" "F.Mask" "F.Paste")
			(net "PVDDCR_CPU0_P1_TEMP0")
		)
		(pad "37" smd rect
			(at -1.089914 -2.899918 180)
			(size 0.2286 0.6096)
			(layers "F.Cu" "F.Mask" "F.Paste")
			(net "PVDDCR_CPU0_P1_LSET4")
		)
		(pad "38" smd rect
			(at -1.540002 -2.899918 180)
			(size 0.2286 0.6096)
			(layers "F.Cu" "F.Mask" "F.Paste")
			(net "PVDDCR_CPU0_P1_IMON4")
		)
		(pad "39" smd rect
			(at -1.99009 -2.899918 180)
			(size 0.2286 0.6096)
			(layers "F.Cu" "F.Mask" "F.Paste")
			(net "PVDDCR_CPU0_P1_VCCS")
		)
		(pad "40" smd rect
			(at -0.87503 -1.27508 180)
			(size 1.7526 1.9558)
			(layers "F.Cu" "F.Mask" "F.Paste")
			(net "GND")
		)
		(pad "41" smd rect
			(at -1.525016 0.249936 90)
			(size 0.3048 0.4572)
			(layers "F.Cu" "F.Mask" "F.Paste")
			(net "NC_PVDDCR_CPU0_P1_GL2_4")
		)
		(zone
			(layer "F.Cu")
			(hatch none 0.5)
			(connect_pads
				(clearance 0)
			)
			(min_thickness 0.25)
			(keepout
				(tracks not_allowed)
				(vias allowed)
				(pads allowed)
				(copperpour not_allowed)
				(footprints allowed)
			)
			(placement
				(enabled no)
				(sheetname "")
			)
			(fill
				(thermal_gap 0.5)
				(thermal_bridge_width 0.5)
				(island_removal_mode 0)
			)
			(polygon
				(pts
					(xy 109.956092 -180.716174) (xy 109.956092 -180.42255) (xy 104.955848 -180.42255) (xy 104.955848 -180.716174)
					(xy 105.24617 -180.716174) (xy 109.66577 -180.716174)
				)
			)
		)
		(zone
			(layer "F.Cu")
			(hatch none 0.5)
			(connect_pads
				(clearance 0)
			)
			(min_thickness 0.25)
			(keepout
				(tracks not_allowed)
				(vias allowed)
				(pads allowed)
				(copperpour not_allowed)
				(footprints allowed)
			)
			(placement
				(enabled no)
				(sheetname "")
			)
			(fill
				(thermal_gap 0.5)
				(thermal_bridge_width 0.5)
				(island_removal_mode 0)
			)
			(polygon
				(pts
					(xy 107.4039 -177.925476) (xy 107.4039 -175.868076) (xy 109.2581 -175.868076) (xy 109.2581 -176.109122)
					(xy 109.500416 -176.109122) (xy 109.500416 -175.627538) (xy 105.57637 -175.627538) (xy 105.57637 -175.81245)
					(xy 107.112562 -175.81245) (xy 107.112562 -177.97145) (xy 104.955848 -177.97145) (xy 104.955848 -178.221132)
					(xy 107.122468 -178.221132) (xy 107.4039 -177.9397)
				)
			)
		)
	)
	(footprint ""
		(layer "F.Cu")
		(at 68.212462 -40.437562)
		(property "Reference" "R3608"
			(at 0 0 0)
			(layer "F.SilkS")
			(hide yes)
			(effects
				(font
					(size 1.27 1.27)
				)
			)
		)
		(property "Value" ""
			(at 0 0 0)
			(layer "F.Fab")
			(effects
				(font
					(size 1.27 1.27)
				)
			)
		)
		(duplicate_pad_numbers_are_jumpers no)
		(fp_line
			(start -0.7874 -0.4064)
			(end 0.7874 -0.4064)
			(stroke
				(width 0.1524)
				(type default)
			)
			(layer "F.SilkS")
		)
		(fp_line
			(start -0.7874 0.4064)
			(end -0.7874 -0.4064)
			(stroke
				(width 0.1524)
				(type default)
			)
			(layer "F.SilkS")
		)
		(fp_line
			(start 0.7874 -0.4064)
			(end 0.7874 0.4064)
			(stroke
				(width 0.1524)
				(type default)
			)
			(layer "F.SilkS")
		)
		(fp_line
			(start 0.7874 0.4064)
			(end -0.7874 0.4064)
			(stroke
				(width 0.1524)
				(type default)
			)
			(layer "F.SilkS")
		)
		(fp_line
			(start -0.67945 -0.305054)
			(end -0.12065 -0.305054)
			(stroke
				(width 0.1)
				(type default)
			)
			(layer "F.Fab")
		)
		(fp_line
			(start -0.67945 0.3048)
			(end -0.67945 -0.305054)
			(stroke
				(width 0.1)
				(type default)
			)
			(layer "F.Fab")
		)
		(fp_line
			(start -0.12065 -0.305054)
			(end -0.12065 -0.2794)
			(stroke
				(width 0.1)
				(type default)
			)
			(layer "F.Fab")
		)
		(fp_line
			(start -0.12065 -0.2794)
			(end 0.12065 -0.2794)
			(stroke
				(width 0.1)
				(type default)
			)
			(layer "F.Fab")
		)
		(fp_line
			(start -0.12065 0.2794)
			(end -0.12065 0.3048)
			(stroke
				(width 0.1)
				(type default)
			)
			(layer "F.Fab")
		)
		(fp_line
			(start -0.12065 0.3048)
			(end -0.67945 0.3048)
			(stroke
				(width 0.1)
				(type default)
			)
			(layer "F.Fab")
		)
		(fp_line
			(start 0.120396 0.2794)
			(end -0.12065 0.2794)
			(stroke
				(width 0.1)
				(type default)
			)
			(layer "F.Fab")
		)
		(fp_line
			(start 0.120396 0.3048)
			(end 0.120396 0.2794)
			(stroke
				(width 0.1)
				(type default)
			)
			(layer "F.Fab")
		)
		(fp_line
			(start 0.12065 -0.3048)
			(end 0.67945 -0.3048)
			(stroke
				(width 0.1)
				(type default)
			)
			(layer "F.Fab")
		)
		(fp_line
			(start 0.12065 -0.2794)
			(end 0.12065 -0.3048)
			(stroke
				(width 0.1)
				(type default)
			)
			(layer "F.Fab")
		)
		(fp_line
			(start 0.67945 -0.3048)
			(end 0.67945 0.3048)
			(stroke
				(width 0.1)
				(type default)
			)
			(layer "F.Fab")
		)
		(fp_line
			(start 0.67945 0.3048)
			(end 0.120396 0.3048)
			(stroke
				(width 0.1)
				(type default)
			)
			(layer "F.Fab")
		)
		(pad "1" smd circle
			(at -0.40005 0)
			(size 0 0)
			(layers "F.Cu" "F.Mask" "F.Paste")
			(net "GND")
		)
		(pad "2" smd circle
			(at 0.40005 0)
			(size 0 0)
			(layers "F.Cu" "F.Mask" "F.Paste")
			(net "INA230_3_A1")
		)
	)
	(footprint ""
		(layer "F.Cu")
		(at 325.697342 -399.12798)
		(property "Reference" "R1364"
			(at 0 0 0)
			(layer "F.SilkS")
			(hide yes)
			(effects
				(font
					(size 1.27 1.27)
				)
			)
		)
		(property "Value" ""
			(at 0 0 0)
			(layer "F.Fab")
			(effects
				(font
					(size 1.27 1.27)
				)
			)
		)
		(duplicate_pad_numbers_are_jumpers no)
		(fp_line
			(start -0.32512 -0.175006)
			(end 0.32512 -0.175006)
			(stroke
				(width 0.1)
				(type default)
			)
			(layer "F.Fab")
		)
		(fp_line
			(start -0.32512 0.175006)
			(end -0.32512 -0.175006)
			(stroke
				(width 0.1)
				(type default)
			)
			(layer "F.Fab")
		)
		(fp_line
			(start 0.32512 -0.175006)
			(end 0.32512 0.175006)
			(stroke
				(width 0.1)
				(type default)
			)
			(layer "F.Fab")
		)
		(fp_line
			(start 0.32512 0.175006)
			(end -0.32512 0.175006)
			(stroke
				(width 0.1)
				(type default)
			)
			(layer "F.Fab")
		)
		(pad "1" smd rect
			(at -0.2667 0)
			(size 0.3048 0.381)
			(layers "F.Cu" "F.Mask" "F.Paste")
			(net "JTAG_TRST_RT_CPU0_P0_N")
		)
		(pad "2" smd rect
			(at 0.2667 0 180)
			(size 0.3048 0.381)
			(layers "F.Cu" "F.Mask" "F.Paste")
			(net "GND")
		)
	)
	(footprint ""
		(layer "F.Cu")
		(at 372.109492 -383.88163 -90)
		(property "Reference" "C892"
			(at 0 0 270)
			(layer "F.SilkS")
			(hide yes)
			(effects
				(font
					(size 1.27 1.27)
				)
			)
		)
		(property "Value" ""
			(at 0 0 270)
			(layer "F.Fab")
			(effects
				(font
					(size 1.27 1.27)
				)
			)
		)
		(duplicate_pad_numbers_are_jumpers no)
		(fp_line
			(start -0.299974 0.150114)
			(end -0.299974 -0.150114)
			(stroke
				(width 0.1)
				(type default)
			)
			(layer "F.Fab")
		)
		(fp_line
			(start 0.299974 0.150114)
			(end -0.299974 0.150114)
			(stroke
				(width 0.1)
				(type default)
			)
			(layer "F.Fab")
		)
		(fp_line
			(start -0.299974 -0.150114)
			(end 0.299974 -0.150114)
			(stroke
				(width 0.1)
				(type default)
			)
			(layer "F.Fab")
		)
		(fp_line
			(start 0.299974 -0.150114)
			(end 0.299974 0.150114)
			(stroke
				(width 0.1)
				(type default)
			)
			(layer "F.Fab")
		)
		(pad "1" smd rect
			(at -0.2667 0 270)
			(size 0.3048 0.381)
			(layers "F.Cu" "F.Mask" "F.Paste")
			(net "P5E_CPU0_P3_TX_C_DN<4>")
		)
		(pad "2" smd rect
			(at 0.2667 0 270)
			(size 0.3048 0.381)
			(layers "F.Cu" "F.Mask" "F.Paste")
			(net "P5E_CPU0_P3_TX_DN<4>")
		)
	)
	(footprint ""
		(layer "F.Cu")
		(at 355.08057 -402.7424 -90)
		(property "Reference" "R1041"
			(at 0 0 270)
			(layer "F.SilkS")
			(hide yes)
			(effects
				(font
					(size 1.27 1.27)
				)
			)
		)
		(property "Value" ""
			(at 0 0 270)
			(layer "F.Fab")
			(effects
				(font
					(size 1.27 1.27)
				)
			)
		)
		(duplicate_pad_numbers_are_jumpers no)
		(fp_line
			(start -0.32512 0.175006)
			(end -0.32512 -0.175006)
			(stroke
				(width 0.1)
				(type default)
			)
			(layer "F.Fab")
		)
		(fp_line
			(start 0.32512 0.175006)
			(end -0.32512 0.175006)
			(stroke
				(width 0.1)
				(type default)
			)
			(layer "F.Fab")
		)
		(fp_line
			(start -0.32512 -0.175006)
			(end 0.32512 -0.175006)
			(stroke
				(width 0.1)
				(type default)
			)
			(layer "F.Fab")
		)
		(fp_line
			(start 0.32512 -0.175006)
			(end 0.32512 0.175006)
			(stroke
				(width 0.1)
				(type default)
			)
			(layer "F.Fab")
		)
		(pad "1" smd rect
			(at -0.2667 0 270)
			(size 0.3048 0.381)
			(layers "F.Cu" "F.Mask" "F.Paste")
			(net "RT_CPU0_P1_VQPS")
		)
		(pad "2" smd rect
			(at 0.2667 0 90)
			(size 0.3048 0.381)
			(layers "F.Cu" "F.Mask" "F.Paste")
			(net "GND")
		)
	)
	(footprint ""
		(layer "F.Cu")
		(at 385.749038 -182.661052 90)
		(property "Reference" "PC553_4"
			(at 0 0 90)
			(layer "F.SilkS")
			(hide yes)
			(effects
				(font
					(size 1.27 1.27)
				)
			)
		)
		(property "Value" ""
			(at 0 0 90)
			(layer "F.Fab")
			(effects
				(font
					(size 1.27 1.27)
				)
			)
		)
		(duplicate_pad_numbers_are_jumpers no)
		(fp_line
			(start 0.7874 -0.4064)
			(end 0.7874 0.4064)
			(stroke
				(width 0.1524)
				(type default)
			)
			(layer "F.SilkS")
		)
		(fp_line
			(start -0.7874 -0.4064)
			(end 0.7874 -0.4064)
			(stroke
				(width 0.1524)
				(type default)
			)
			(layer "F.SilkS")
		)
		(fp_line
			(start 0.7874 0.4064)
			(end -0.7874 0.4064)
			(stroke
				(width 0.1524)
				(type default)
			)
			(layer "F.SilkS")
		)
		(fp_line
			(start -0.7874 0.4064)
			(end -0.7874 -0.4064)
			(stroke
				(width 0.1524)
				(type default)
			)
			(layer "F.SilkS")
		)
		(fp_line
			(start -0.12065 -0.305054)
			(end -0.12065 -0.2794)
			(stroke
				(width 0.1)
				(type default)
			)
			(layer "F.Fab")
		)
		(fp_line
			(start -0.67945 -0.305054)
			(end -0.12065 -0.305054)
			(stroke
				(width 0.1)
				(type default)
			)
			(layer "F.Fab")
		)
		(fp_line
			(start 0.67945 -0.3048)
			(end 0.67945 0.3048)
			(stroke
				(width 0.1)
				(type default)
			)
			(layer "F.Fab")
		)
		(fp_line
			(start 0.12065 -0.3048)
			(end 0.67945 -0.3048)
			(stroke
				(width 0.1)
				(type default)
			)
			(layer "F.Fab")
		)
		(fp_line
			(start 0.12065 -0.2794)
			(end 0.12065 -0.3048)
			(stroke
				(width 0.1)
				(type default)
			)
			(layer "F.Fab")
		)
		(fp_line
			(start -0.12065 -0.2794)
			(end 0.12065 -0.2794)
			(stroke
				(width 0.1)
				(type default)
			)
			(layer "F.Fab")
		)
		(fp_line
			(start 0.120396 0.2794)
			(end -0.12065 0.2794)
			(stroke
				(width 0.1)
				(type default)
			)
			(layer "F.Fab")
		)
		(fp_line
			(start -0.12065 0.2794)
			(end -0.12065 0.3048)
			(stroke
				(width 0.1)
				(type default)
			)
			(layer "F.Fab")
		)
		(fp_line
			(start 0.67945 0.3048)
			(end 0.120396 0.3048)
			(stroke
				(width 0.1)
				(type default)
			)
			(layer "F.Fab")
		)
		(fp_line
			(start 0.120396 0.3048)
			(end 0.120396 0.2794)
			(stroke
				(width 0.1)
				(type default)
			)
			(layer "F.Fab")
		)
		(fp_line
			(start -0.12065 0.3048)
			(end -0.67945 0.3048)
			(stroke
				(width 0.1)
				(type default)
			)
			(layer "F.Fab")
		)
		(fp_line
			(start -0.67945 0.3048)
			(end -0.67945 -0.305054)
			(stroke
				(width 0.1)
				(type default)
			)
			(layer "F.Fab")
		)
		(pad "1" smd circle
			(at -0.40005 0 90)
			(size 0 0)
			(layers "F.Cu" "F.Mask" "F.Paste")
			(net "SW_P12V_AUX_PVDDCR_CPU0_P0_FLT")
		)
		(pad "2" smd circle
			(at 0.40005 0 90)
			(size 0 0)
			(layers "F.Cu" "F.Mask" "F.Paste")
			(net "GND")
		)
	)
	(footprint ""
		(layer "F.Cu")
		(at 314.567316 -109.53877 180)
		(property "Reference" "R24"
			(at 0 0 180)
			(layer "F.SilkS")
			(hide yes)
			(effects
				(font
					(size 1.27 1.27)
				)
			)
		)
		(property "Value" ""
			(at 0 0 180)
			(layer "F.Fab")
			(effects
				(font
					(size 1.27 1.27)
				)
			)
		)
		(duplicate_pad_numbers_are_jumpers no)
		(fp_line
			(start 0.7874 0.4064)
			(end -0.7874 0.4064)
			(stroke
				(width 0.1524)
				(type default)
			)
			(layer "F.SilkS")
		)
		(fp_line
			(start 0.7874 -0.4064)
			(end 0.7874 0.4064)
			(stroke
				(width 0.1524)
				(type default)
			)
			(layer "F.SilkS")
		)
		(fp_line
			(start -0.7874 0.4064)
			(end -0.7874 -0.4064)
			(stroke
				(width 0.1524)
				(type default)
			)
			(layer "F.SilkS")
		)
		(fp_line
			(start -0.7874 -0.4064)
			(end 0.7874 -0.4064)
			(stroke
				(width 0.1524)
				(type default)
			)
			(layer "F.SilkS")
		)
		(fp_line
			(start 0.67945 0.3048)
			(end 0.120396 0.3048)
			(stroke
				(width 0.1)
				(type default)
			)
			(layer "F.Fab")
		)
		(fp_line
			(start 0.67945 -0.3048)
			(end 0.67945 0.3048)
			(stroke
				(width 0.1)
				(type default)
			)
			(layer "F.Fab")
		)
		(fp_line
			(start 0.12065 -0.2794)
			(end 0.12065 -0.3048)
			(stroke
				(width 0.1)
				(type default)
			)
			(layer "F.Fab")
		)
		(fp_line
			(start 0.12065 -0.3048)
			(end 0.67945 -0.3048)
			(stroke
				(width 0.1)
				(type default)
			)
			(layer "F.Fab")
		)
		(fp_line
			(start 0.120396 0.3048)
			(end 0.120396 0.2794)
			(stroke
				(width 0.1)
				(type default)
			)
			(layer "F.Fab")
		)
		(fp_line
			(start 0.120396 0.2794)
			(end -0.12065 0.2794)
			(stroke
				(width 0.1)
				(type default)
			)
			(layer "F.Fab")
		)
		(fp_line
			(start -0.12065 0.3048)
			(end -0.67945 0.3048)
			(stroke
				(width 0.1)
				(type default)
			)
			(layer "F.Fab")
		)
		(fp_line
			(start -0.12065 0.2794)
			(end -0.12065 0.3048)
			(stroke
				(width 0.1)
				(type default)
			)
			(layer "F.Fab")
		)
		(fp_line
			(start -0.12065 -0.2794)
			(end 0.12065 -0.2794)
			(stroke
				(width 0.1)
				(type default)
			)
			(layer "F.Fab")
		)
		(fp_line
			(start -0.12065 -0.305054)
			(end -0.12065 -0.2794)
			(stroke
				(width 0.1)
				(type default)
			)
			(layer "F.Fab")
		)
		(fp_line
			(start -0.67945 0.3048)
			(end -0.67945 -0.305054)
			(stroke
				(width 0.1)
				(type default)
			)
			(layer "F.Fab")
		)
		(fp_line
			(start -0.67945 -0.305054)
			(end -0.12065 -0.305054)
			(stroke
				(width 0.1)
				(type default)
			)
			(layer "F.Fab")
		)
		(pad "1" smd circle
			(at -0.40005 0 180)
			(size 0 0)
			(layers "F.Cu" "F.Mask" "F.Paste")
			(net "P3V3_AUX")
		)
		(pad "2" smd circle
			(at 0.40005 0 180)
			(size 0 0)
			(layers "F.Cu" "F.Mask" "F.Paste")
			(net "SMB_CPU_FRU_3V3AUX_SDA")
		)
	)
	(footprint ""
		(layer "F.Cu")
		(at 251.474224 -134.892796)
		(property "Reference" "R1547"
			(at 0 0 0)
			(layer "F.SilkS")
			(hide yes)
			(effects
				(font
					(size 1.27 1.27)
				)
			)
		)
		(property "Value" ""
			(at 0 0 0)
			(layer "F.Fab")
			(effects
				(font
					(size 1.27 1.27)
				)
			)
		)
		(duplicate_pad_numbers_are_jumpers no)
		(fp_line
			(start -0.7874 -0.4064)
			(end 0.7874 -0.4064)
			(stroke
				(width 0.1524)
				(type default)
			)
			(layer "F.SilkS")
		)
		(fp_line
			(start -0.7874 0.4064)
			(end -0.7874 -0.4064)
			(stroke
				(width 0.1524)
				(type default)
			)
			(layer "F.SilkS")
		)
		(fp_line
			(start 0.7874 -0.4064)
			(end 0.7874 0.4064)
			(stroke
				(width 0.1524)
				(type default)
			)
			(layer "F.SilkS")
		)
		(fp_line
			(start 0.7874 0.4064)
			(end -0.7874 0.4064)
			(stroke
				(width 0.1524)
				(type default)
			)
			(layer "F.SilkS")
		)
		(fp_line
			(start -0.67945 -0.305054)
			(end -0.12065 -0.305054)
			(stroke
				(width 0.1)
				(type default)
			)
			(layer "F.Fab")
		)
		(fp_line
			(start -0.67945 0.3048)
			(end -0.67945 -0.305054)
			(stroke
				(width 0.1)
				(type default)
			)
			(layer "F.Fab")
		)
		(fp_line
			(start -0.12065 -0.305054)
			(end -0.12065 -0.2794)
			(stroke
				(width 0.1)
				(type default)
			)
			(layer "F.Fab")
		)
		(fp_line
			(start -0.12065 -0.2794)
			(end 0.12065 -0.2794)
			(stroke
				(width 0.1)
				(type default)
			)
			(layer "F.Fab")
		)
		(fp_line
			(start -0.12065 0.2794)
			(end -0.12065 0.3048)
			(stroke
				(width 0.1)
				(type default)
			)
			(layer "F.Fab")
		)
		(fp_line
			(start -0.12065 0.3048)
			(end -0.67945 0.3048)
			(stroke
				(width 0.1)
				(type default)
			)
			(layer "F.Fab")
		)
		(fp_line
			(start 0.120396 0.2794)
			(end -0.12065 0.2794)
			(stroke
				(width 0.1)
				(type default)
			)
			(layer "F.Fab")
		)
		(fp_line
			(start 0.120396 0.3048)
			(end 0.120396 0.2794)
			(stroke
				(width 0.1)
				(type default)
			)
			(layer "F.Fab")
		)
		(fp_line
			(start 0.12065 -0.3048)
			(end 0.67945 -0.3048)
			(stroke
				(width 0.1)
				(type default)
			)
			(layer "F.Fab")
		)
		(fp_line
			(start 0.12065 -0.2794)
			(end 0.12065 -0.3048)
			(stroke
				(width 0.1)
				(type default)
			)
			(layer "F.Fab")
		)
		(fp_line
			(start 0.67945 -0.3048)
			(end 0.67945 0.3048)
			(stroke
				(width 0.1)
				(type default)
			)
			(layer "F.Fab")
		)
		(fp_line
			(start 0.67945 0.3048)
			(end 0.120396 0.3048)
			(stroke
				(width 0.1)
				(type default)
			)
			(layer "F.Fab")
		)
		(pad "1" smd circle
			(at -0.40005 0)
			(size 0 0)
			(layers "F.Cu" "F.Mask" "F.Paste")
			(net "P3V3_AUX")
		)
		(pad "2" smd circle
			(at 0.40005 0)
			(size 0 0)
			(layers "F.Cu" "F.Mask" "F.Paste")
			(net "SPI_CPU0_LVC3_TPM_CS_N")
		)
	)
	(footprint ""
		(layer "F.Cu")
		(at 216.408 -123.825 90)
		(property "Reference" "R9033"
			(at 0 0 90)
			(layer "F.SilkS")
			(hide yes)
			(effects
				(font
					(size 1.27 1.27)
				)
			)
		)
		(property "Value" ""
			(at 0 0 90)
			(layer "F.Fab")
			(effects
				(font
					(size 1.27 1.27)
				)
			)
		)
		(duplicate_pad_numbers_are_jumpers no)
		(fp_line
			(start 0.7874 -0.4064)
			(end 0.7874 0.4064)
			(stroke
				(width 0.1524)
				(type default)
			)
			(layer "F.SilkS")
		)
		(fp_line
			(start -0.7874 -0.4064)
			(end 0.7874 -0.4064)
			(stroke
				(width 0.1524)
				(type default)
			)
			(layer "F.SilkS")
		)
		(fp_line
			(start 0.7874 0.4064)
			(end -0.7874 0.4064)
			(stroke
				(width 0.1524)
				(type default)
			)
			(layer "F.SilkS")
		)
		(fp_line
			(start -0.7874 0.4064)
			(end -0.7874 -0.4064)
			(stroke
				(width 0.1524)
				(type default)
			)
			(layer "F.SilkS")
		)
		(fp_line
			(start -0.12065 -0.305054)
			(end -0.12065 -0.2794)
			(stroke
				(width 0.1)
				(type default)
			)
			(layer "F.Fab")
		)
		(fp_line
			(start -0.67945 -0.305054)
			(end -0.12065 -0.305054)
			(stroke
				(width 0.1)
				(type default)
			)
			(layer "F.Fab")
		)
		(fp_line
			(start 0.67945 -0.3048)
			(end 0.67945 0.3048)
			(stroke
				(width 0.1)
				(type default)
			)
			(layer "F.Fab")
		)
		(fp_line
			(start 0.12065 -0.3048)
			(end 0.67945 -0.3048)
			(stroke
				(width 0.1)
				(type default)
			)
			(layer "F.Fab")
		)
		(fp_line
			(start 0.12065 -0.2794)
			(end 0.12065 -0.3048)
			(stroke
				(width 0.1)
				(type default)
			)
			(layer "F.Fab")
		)
		(fp_line
			(start -0.12065 -0.2794)
			(end 0.12065 -0.2794)
			(stroke
				(width 0.1)
				(type default)
			)
			(layer "F.Fab")
		)
		(fp_line
			(start 0.120396 0.2794)
			(end -0.12065 0.2794)
			(stroke
				(width 0.1)
				(type default)
			)
			(layer "F.Fab")
		)
		(fp_line
			(start -0.12065 0.2794)
			(end -0.12065 0.3048)
			(stroke
				(width 0.1)
				(type default)
			)
			(layer "F.Fab")
		)
		(fp_line
			(start 0.67945 0.3048)
			(end 0.120396 0.3048)
			(stroke
				(width 0.1)
				(type default)
			)
			(layer "F.Fab")
		)
		(fp_line
			(start 0.120396 0.3048)
			(end 0.120396 0.2794)
			(stroke
				(width 0.1)
				(type default)
			)
			(layer "F.Fab")
		)
		(fp_line
			(start -0.12065 0.3048)
			(end -0.67945 0.3048)
			(stroke
				(width 0.1)
				(type default)
			)
			(layer "F.Fab")
		)
		(fp_line
			(start -0.67945 0.3048)
			(end -0.67945 -0.305054)
			(stroke
				(width 0.1)
				(type default)
			)
			(layer "F.Fab")
		)
		(pad "1" smd circle
			(at -0.40005 0 90)
			(size 0 0)
			(layers "F.Cu" "F.Mask" "F.Paste")
			(net "RST_PERST_OCP_SFF_BUF_R_N")
		)
		(pad "2" smd circle
			(at 0.40005 0 90)
			(size 0 0)
			(layers "F.Cu" "F.Mask" "F.Paste")
			(net "RST_PERST_OCP_SFF_BUF_N")
		)
	)
	(footprint ""
		(layer "F.Cu")
		(at 97.652078 -404.593044 90)
		(property "Reference" "C1069"
			(at 0 0 90)
			(layer "F.SilkS")
			(hide yes)
			(effects
				(font
					(size 1.27 1.27)
				)
			)
		)
		(property "Value" ""
			(at 0 0 90)
			(layer "F.Fab")
			(effects
				(font
					(size 1.27 1.27)
				)
			)
		)
		(duplicate_pad_numbers_are_jumpers no)
		(fp_line
			(start 0.299974 -0.150114)
			(end 0.299974 0.150114)
			(stroke
				(width 0.1)
				(type default)
			)
			(layer "F.Fab")
		)
		(fp_line
			(start -0.299974 -0.150114)
			(end 0.299974 -0.150114)
			(stroke
				(width 0.1)
				(type default)
			)
			(layer "F.Fab")
		)
		(fp_line
			(start 0.299974 0.150114)
			(end -0.299974 0.150114)
			(stroke
				(width 0.1)
				(type default)
			)
			(layer "F.Fab")
		)
		(fp_line
			(start -0.299974 0.150114)
			(end -0.299974 -0.150114)
			(stroke
				(width 0.1)
				(type default)
			)
			(layer "F.Fab")
		)
		(pad "1" smd rect
			(at -0.2667 0 90)
			(size 0.3048 0.381)
			(layers "F.Cu" "F.Mask" "F.Paste")
			(net "P3V3_AUX")
		)
		(pad "2" smd rect
			(at 0.2667 0 90)
			(size 0.3048 0.381)
			(layers "F.Cu" "F.Mask" "F.Paste")
			(net "GND")
		)
	)
	(footprint ""
		(layer "F.Cu")
		(at 257.85953 -54.463442)
		(property "Reference" "PC2202"
			(at 0 0 0)
			(layer "F.SilkS")
			(hide yes)
			(effects
				(font
					(size 1.27 1.27)
				)
			)
		)
		(property "Value" ""
			(at 0 0 0)
			(layer "F.Fab")
			(effects
				(font
					(size 1.27 1.27)
				)
			)
		)
		(duplicate_pad_numbers_are_jumpers no)
		(fp_line
			(start -0.7874 -0.4064)
			(end 0.7874 -0.4064)
			(stroke
				(width 0.1524)
				(type default)
			)
			(layer "F.SilkS")
		)
		(fp_line
			(start -0.7874 0.4064)
			(end -0.7874 -0.4064)
			(stroke
				(width 0.1524)
				(type default)
			)
			(layer "F.SilkS")
		)
		(fp_line
			(start 0.7874 -0.4064)
			(end 0.7874 0.4064)
			(stroke
				(width 0.1524)
				(type default)
			)
			(layer "F.SilkS")
		)
		(fp_line
			(start 0.7874 0.4064)
			(end -0.7874 0.4064)
			(stroke
				(width 0.1524)
				(type default)
			)
			(layer "F.SilkS")
		)
		(fp_line
			(start -0.67945 -0.305054)
			(end -0.12065 -0.305054)
			(stroke
				(width 0.1)
				(type default)
			)
			(layer "F.Fab")
		)
		(fp_line
			(start -0.67945 0.3048)
			(end -0.67945 -0.305054)
			(stroke
				(width 0.1)
				(type default)
			)
			(layer "F.Fab")
		)
		(fp_line
			(start -0.12065 -0.305054)
			(end -0.12065 -0.2794)
			(stroke
				(width 0.1)
				(type default)
			)
			(layer "F.Fab")
		)
		(fp_line
			(start -0.12065 -0.2794)
			(end 0.12065 -0.2794)
			(stroke
				(width 0.1)
				(type default)
			)
			(layer "F.Fab")
		)
		(fp_line
			(start -0.12065 0.2794)
			(end -0.12065 0.3048)
			(stroke
				(width 0.1)
				(type default)
			)
			(layer "F.Fab")
		)
		(fp_line
			(start -0.12065 0.3048)
			(end -0.67945 0.3048)
			(stroke
				(width 0.1)
				(type default)
			)
			(layer "F.Fab")
		)
		(fp_line
			(start 0.120396 0.2794)
			(end -0.12065 0.2794)
			(stroke
				(width 0.1)
				(type default)
			)
			(layer "F.Fab")
		)
		(fp_line
			(start 0.120396 0.3048)
			(end 0.120396 0.2794)
			(stroke
				(width 0.1)
				(type default)
			)
			(layer "F.Fab")
		)
		(fp_line
			(start 0.12065 -0.3048)
			(end 0.67945 -0.3048)
			(stroke
				(width 0.1)
				(type default)
			)
			(layer "F.Fab")
		)
		(fp_line
			(start 0.12065 -0.2794)
			(end 0.12065 -0.3048)
			(stroke
				(width 0.1)
				(type default)
			)
			(layer "F.Fab")
		)
		(fp_line
			(start 0.67945 -0.3048)
			(end 0.67945 0.3048)
			(stroke
				(width 0.1)
				(type default)
			)
			(layer "F.Fab")
		)
		(fp_line
			(start 0.67945 0.3048)
			(end 0.120396 0.3048)
			(stroke
				(width 0.1)
				(type default)
			)
			(layer "F.Fab")
		)
		(pad "1" smd circle
			(at -0.40005 0)
			(size 0 0)
			(layers "F.Cu" "F.Mask" "F.Paste")
			(net "P12V_E1S_IMON_0")
		)
		(pad "2" smd circle
			(at 0.40005 0)
			(size 0 0)
			(layers "F.Cu" "F.Mask" "F.Paste")
			(net "GND")
		)
	)
	(footprint ""
		(layer "F.Cu")
		(at 329.360022 -37.017706)
		(property "Reference" "C1757"
			(at 0 0 0)
			(layer "F.SilkS")
			(hide yes)
			(effects
				(font
					(size 1.27 1.27)
				)
			)
		)
		(property "Value" ""
			(at 0 0 0)
			(layer "F.Fab")
			(effects
				(font
					(size 1.27 1.27)
				)
			)
		)
		(duplicate_pad_numbers_are_jumpers no)
		(fp_line
			(start -0.7874 -0.4064)
			(end 0.7874 -0.4064)
			(stroke
				(width 0.1524)
				(type default)
			)
			(layer "F.SilkS")
		)
		(fp_line
			(start -0.7874 0.4064)
			(end -0.7874 -0.4064)
			(stroke
				(width 0.1524)
				(type default)
			)
			(layer "F.SilkS")
		)
		(fp_line
			(start 0.7874 -0.4064)
			(end 0.7874 0.4064)
			(stroke
				(width 0.1524)
				(type default)
			)
			(layer "F.SilkS")
		)
		(fp_line
			(start 0.7874 0.4064)
			(end -0.7874 0.4064)
			(stroke
				(width 0.1524)
				(type default)
			)
			(layer "F.SilkS")
		)
		(fp_line
			(start -0.67945 -0.305054)
			(end -0.12065 -0.305054)
			(stroke
				(width 0.1)
				(type default)
			)
			(layer "F.Fab")
		)
		(fp_line
			(start -0.67945 0.3048)
			(end -0.67945 -0.305054)
			(stroke
				(width 0.1)
				(type default)
			)
			(layer "F.Fab")
		)
		(fp_line
			(start -0.12065 -0.305054)
			(end -0.12065 -0.2794)
			(stroke
				(width 0.1)
				(type default)
			)
			(layer "F.Fab")
		)
		(fp_line
			(start -0.12065 -0.2794)
			(end 0.12065 -0.2794)
			(stroke
				(width 0.1)
				(type default)
			)
			(layer "F.Fab")
		)
		(fp_line
			(start -0.12065 0.2794)
			(end -0.12065 0.3048)
			(stroke
				(width 0.1)
				(type default)
			)
			(layer "F.Fab")
		)
		(fp_line
			(start -0.12065 0.3048)
			(end -0.67945 0.3048)
			(stroke
				(width 0.1)
				(type default)
			)
			(layer "F.Fab")
		)
		(fp_line
			(start 0.120396 0.2794)
			(end -0.12065 0.2794)
			(stroke
				(width 0.1)
				(type default)
			)
			(layer "F.Fab")
		)
		(fp_line
			(start 0.120396 0.3048)
			(end 0.120396 0.2794)
			(stroke
				(width 0.1)
				(type default)
			)
			(layer "F.Fab")
		)
		(fp_line
			(start 0.12065 -0.3048)
			(end 0.67945 -0.3048)
			(stroke
				(width 0.1)
				(type default)
			)
			(layer "F.Fab")
		)
		(fp_line
			(start 0.12065 -0.2794)
			(end 0.12065 -0.3048)
			(stroke
				(width 0.1)
				(type default)
			)
			(layer "F.Fab")
		)
		(fp_line
			(start 0.67945 -0.3048)
			(end 0.67945 0.3048)
			(stroke
				(width 0.1)
				(type default)
			)
			(layer "F.Fab")
		)
		(fp_line
			(start 0.67945 0.3048)
			(end 0.120396 0.3048)
			(stroke
				(width 0.1)
				(type default)
			)
			(layer "F.Fab")
		)
		(pad "1" smd circle
			(at -0.40005 0)
			(size 0 0)
			(layers "F.Cu" "F.Mask" "F.Paste")
			(net "P3V3_MAX11617_VDD")
		)
		(pad "2" smd circle
			(at 0.40005 0)
			(size 0 0)
			(layers "F.Cu" "F.Mask" "F.Paste")
			(net "GND")
		)
	)
	(footprint ""
		(layer "F.Cu")
		(at 384.465576 -54.56555 -90)
		(property "Reference" "R1626"
			(at 0 0 270)
			(layer "F.SilkS")
			(hide yes)
			(effects
				(font
					(size 1.27 1.27)
				)
			)
		)
		(property "Value" ""
			(at 0 0 270)
			(layer "F.Fab")
			(effects
				(font
					(size 1.27 1.27)
				)
			)
		)
		(duplicate_pad_numbers_are_jumpers no)
		(fp_line
			(start -0.7874 0.4064)
			(end -0.7874 -0.4064)
			(stroke
				(width 0.1524)
				(type default)
			)
			(layer "F.SilkS")
		)
		(fp_line
			(start 0.7874 0.4064)
			(end -0.7874 0.4064)
			(stroke
				(width 0.1524)
				(type default)
			)
			(layer "F.SilkS")
		)
		(fp_line
			(start -0.7874 -0.4064)
			(end 0.7874 -0.4064)
			(stroke
				(width 0.1524)
				(type default)
			)
			(layer "F.SilkS")
		)
		(fp_line
			(start 0.7874 -0.4064)
			(end 0.7874 0.4064)
			(stroke
				(width 0.1524)
				(type default)
			)
			(layer "F.SilkS")
		)
		(fp_line
			(start -0.67945 0.3048)
			(end -0.67945 -0.305054)
			(stroke
				(width 0.1)
				(type default)
			)
			(layer "F.Fab")
		)
		(fp_line
			(start -0.12065 0.3048)
			(end -0.67945 0.3048)
			(stroke
				(width 0.1)
				(type default)
			)
			(layer "F.Fab")
		)
		(fp_line
			(start 0.120396 0.3048)
			(end 0.120396 0.2794)
			(stroke
				(width 0.1)
				(type default)
			)
			(layer "F.Fab")
		)
		(fp_line
			(start 0.67945 0.3048)
			(end 0.120396 0.3048)
			(stroke
				(width 0.1)
				(type default)
			)
			(layer "F.Fab")
		)
		(fp_line
			(start -0.12065 0.2794)
			(end -0.12065 0.3048)
			(stroke
				(width 0.1)
				(type default)
			)
			(layer "F.Fab")
		)
		(fp_line
			(start 0.120396 0.2794)
			(end -0.12065 0.2794)
			(stroke
				(width 0.1)
				(type default)
			)
			(layer "F.Fab")
		)
		(fp_line
			(start -0.12065 -0.2794)
			(end 0.12065 -0.2794)
			(stroke
				(width 0.1)
				(type default)
			)
			(layer "F.Fab")
		)
		(fp_line
			(start 0.12065 -0.2794)
			(end 0.12065 -0.3048)
			(stroke
				(width 0.1)
				(type default)
			)
			(layer "F.Fab")
		)
		(fp_line
			(start 0.12065 -0.3048)
			(end 0.67945 -0.3048)
			(stroke
				(width 0.1)
				(type default)
			)
			(layer "F.Fab")
		)
		(fp_line
			(start 0.67945 -0.3048)
			(end 0.67945 0.3048)
			(stroke
				(width 0.1)
				(type default)
			)
			(layer "F.Fab")
		)
		(fp_line
			(start -0.67945 -0.305054)
			(end -0.12065 -0.305054)
			(stroke
				(width 0.1)
				(type default)
			)
			(layer "F.Fab")
		)
		(fp_line
			(start -0.12065 -0.305054)
			(end -0.12065 -0.2794)
			(stroke
				(width 0.1)
				(type default)
			)
			(layer "F.Fab")
		)
		(pad "1" smd circle
			(at -0.40005 0 270)
			(size 0 0)
			(layers "F.Cu" "F.Mask" "F.Paste")
			(net "PVDD18_S5_P0")
		)
		(pad "2" smd circle
			(at 0.40005 0 270)
			(size 0 0)
			(layers "F.Cu" "F.Mask" "F.Paste")
			(net "HDT_HDR_TMS")
		)
	)
	(footprint ""
		(layer "F.Cu")
		(at 279.56637 -351.100644)
		(property "Reference" "PC177_3"
			(at 0 0 0)
			(layer "F.SilkS")
			(hide yes)
			(effects
				(font
					(size 1.27 1.27)
				)
			)
		)
		(property "Value" ""
			(at 0 0 0)
			(layer "F.Fab")
			(effects
				(font
					(size 1.27 1.27)
				)
			)
		)
		(duplicate_pad_numbers_are_jumpers no)
		(fp_line
			(start -0.7874 -0.4064)
			(end 0.7874 -0.4064)
			(stroke
				(width 0.1524)
				(type default)
			)
			(layer "F.SilkS")
		)
		(fp_line
			(start -0.7874 0.4064)
			(end -0.7874 -0.4064)
			(stroke
				(width 0.1524)
				(type default)
			)
			(layer "F.SilkS")
		)
		(fp_line
			(start 0.7874 -0.4064)
			(end 0.7874 0.4064)
			(stroke
				(width 0.1524)
				(type default)
			)
			(layer "F.SilkS")
		)
		(fp_line
			(start 0.7874 0.4064)
			(end -0.7874 0.4064)
			(stroke
				(width 0.1524)
				(type default)
			)
			(layer "F.SilkS")
		)
		(fp_line
			(start -0.67945 -0.305054)
			(end -0.12065 -0.305054)
			(stroke
				(width 0.1)
				(type default)
			)
			(layer "F.Fab")
		)
		(fp_line
			(start -0.67945 0.3048)
			(end -0.67945 -0.305054)
			(stroke
				(width 0.1)
				(type default)
			)
			(layer "F.Fab")
		)
		(fp_line
			(start -0.12065 -0.305054)
			(end -0.12065 -0.2794)
			(stroke
				(width 0.1)
				(type default)
			)
			(layer "F.Fab")
		)
		(fp_line
			(start -0.12065 -0.2794)
			(end 0.12065 -0.2794)
			(stroke
				(width 0.1)
				(type default)
			)
			(layer "F.Fab")
		)
		(fp_line
			(start -0.12065 0.2794)
			(end -0.12065 0.3048)
			(stroke
				(width 0.1)
				(type default)
			)
			(layer "F.Fab")
		)
		(fp_line
			(start -0.12065 0.3048)
			(end -0.67945 0.3048)
			(stroke
				(width 0.1)
				(type default)
			)
			(layer "F.Fab")
		)
		(fp_line
			(start 0.120396 0.2794)
			(end -0.12065 0.2794)
			(stroke
				(width 0.1)
				(type default)
			)
			(layer "F.Fab")
		)
		(fp_line
			(start 0.120396 0.3048)
			(end 0.120396 0.2794)
			(stroke
				(width 0.1)
				(type default)
			)
			(layer "F.Fab")
		)
		(fp_line
			(start 0.12065 -0.3048)
			(end 0.67945 -0.3048)
			(stroke
				(width 0.1)
				(type default)
			)
			(layer "F.Fab")
		)
		(fp_line
			(start 0.12065 -0.2794)
			(end 0.12065 -0.3048)
			(stroke
				(width 0.1)
				(type default)
			)
			(layer "F.Fab")
		)
		(fp_line
			(start 0.67945 -0.3048)
			(end 0.67945 0.3048)
			(stroke
				(width 0.1)
				(type default)
			)
			(layer "F.Fab")
		)
		(fp_line
			(start 0.67945 0.3048)
			(end 0.120396 0.3048)
			(stroke
				(width 0.1)
				(type default)
			)
			(layer "F.Fab")
		)
		(pad "1" smd circle
			(at -0.40005 0)
			(size 0 0)
			(layers "F.Cu" "F.Mask" "F.Paste")
			(net "SW_P12V_AUX_PVDDIO_P0_FLT")
		)
		(pad "2" smd circle
			(at 0.40005 0)
			(size 0 0)
			(layers "F.Cu" "F.Mask" "F.Paste")
			(net "GND")
		)
	)
	(footprint ""
		(layer "F.Cu")
		(at 178.71694 -400.436842 180)
		(property "Reference" "PC2103"
			(at 0 0 180)
			(layer "F.SilkS")
			(hide yes)
			(effects
				(font
					(size 1.27 1.27)
				)
			)
		)
		(property "Value" ""
			(at 0 0 180)
			(layer "F.Fab")
			(effects
				(font
					(size 1.27 1.27)
				)
			)
		)
		(duplicate_pad_numbers_are_jumpers no)
		(fp_line
			(start 0.7874 0.4064)
			(end -0.7874 0.4064)
			(stroke
				(width 0.1524)
				(type default)
			)
			(layer "F.SilkS")
		)
		(fp_line
			(start 0.7874 -0.4064)
			(end 0.7874 0.4064)
			(stroke
				(width 0.1524)
				(type default)
			)
			(layer "F.SilkS")
		)
		(fp_line
			(start -0.7874 0.4064)
			(end -0.7874 -0.4064)
			(stroke
				(width 0.1524)
				(type default)
			)
			(layer "F.SilkS")
		)
		(fp_line
			(start -0.7874 -0.4064)
			(end 0.7874 -0.4064)
			(stroke
				(width 0.1524)
				(type default)
			)
			(layer "F.SilkS")
		)
		(fp_line
			(start 0.67945 0.3048)
			(end 0.120396 0.3048)
			(stroke
				(width 0.1)
				(type default)
			)
			(layer "F.Fab")
		)
		(fp_line
			(start 0.67945 -0.3048)
			(end 0.67945 0.3048)
			(stroke
				(width 0.1)
				(type default)
			)
			(layer "F.Fab")
		)
		(fp_line
			(start 0.12065 -0.2794)
			(end 0.12065 -0.3048)
			(stroke
				(width 0.1)
				(type default)
			)
			(layer "F.Fab")
		)
		(fp_line
			(start 0.12065 -0.3048)
			(end 0.67945 -0.3048)
			(stroke
				(width 0.1)
				(type default)
			)
			(layer "F.Fab")
		)
		(fp_line
			(start 0.120396 0.3048)
			(end 0.120396 0.2794)
			(stroke
				(width 0.1)
				(type default)
			)
			(layer "F.Fab")
		)
		(fp_line
			(start 0.120396 0.2794)
			(end -0.12065 0.2794)
			(stroke
				(width 0.1)
				(type default)
			)
			(layer "F.Fab")
		)
		(fp_line
			(start -0.12065 0.3048)
			(end -0.67945 0.3048)
			(stroke
				(width 0.1)
				(type default)
			)
			(layer "F.Fab")
		)
		(fp_line
			(start -0.12065 0.2794)
			(end -0.12065 0.3048)
			(stroke
				(width 0.1)
				(type default)
			)
			(layer "F.Fab")
		)
		(fp_line
			(start -0.12065 -0.2794)
			(end 0.12065 -0.2794)
			(stroke
				(width 0.1)
				(type default)
			)
			(layer "F.Fab")
		)
		(fp_line
			(start -0.12065 -0.305054)
			(end -0.12065 -0.2794)
			(stroke
				(width 0.1)
				(type default)
			)
			(layer "F.Fab")
		)
		(fp_line
			(start -0.67945 0.3048)
			(end -0.67945 -0.305054)
			(stroke
				(width 0.1)
				(type default)
			)
			(layer "F.Fab")
		)
		(fp_line
			(start -0.67945 -0.305054)
			(end -0.12065 -0.305054)
			(stroke
				(width 0.1)
				(type default)
			)
			(layer "F.Fab")
		)
		(pad "1" smd circle
			(at -0.40005 0 180)
			(size 0 0)
			(layers "F.Cu" "F.Mask" "F.Paste")
			(net "HSC_VDD18")
		)
		(pad "2" smd circle
			(at 0.40005 0 180)
			(size 0 0)
			(layers "F.Cu" "F.Mask" "F.Paste")
			(net "AGND_HSC")
		)
	)
	(footprint ""
		(layer "F.Cu")
		(at 8.081772 -361.761278)
		(property "Reference" "H30"
			(at 2.3114 1.940052 0)
			(unlocked yes)
			(layer "F.SilkS")
			(effects
				(font
					(size 0.7874 0.5842)
					(thickness 0.1524)
				)
				(justify left)
			)
		)
		(property "Value" ""
			(at 0 0 0)
			(layer "F.Fab")
			(effects
				(font
					(size 1.27 1.27)
				)
			)
		)
		(duplicate_pad_numbers_are_jumpers no)
		(fp_circle
			(center 0 0)
			(end 2.4003 0)
			(stroke
				(width 0.1524)
				(type default)
			)
			(fill no)
			(layer "F.SilkS")
		)
		(fp_circle
			(center 0 0)
			(end 6.5913 0)
			(stroke
				(width 0.1524)
				(type default)
			)
			(fill no)
			(layer "B.SilkS")
		)
		(fp_circle
			(center 0 0)
			(end 6.5913 0)
			(stroke
				(width 0.1)
				(type default)
			)
			(fill no)
			(layer "B.Fab")
		)
		(fp_circle
			(center 0 0)
			(end 2.4003 0)
			(stroke
				(width 0.1)
				(type default)
			)
			(fill no)
			(layer "F.Fab")
		)
		(pad "" np_thru_hole circle
			(at 0 0)
			(size 3.175 3.175)
			(drill 3.175)
			(layers "*.Cu" "*.Mask")
			(clearance 0.381)
			(thermal_gap 0.381)
		)
		(zone
			(layers "F.Cu" "B.Cu" "In1.Cu" "In2.Cu" "In3.Cu" "In4.Cu" "In5.Cu" "In6.Cu"
				"In7.Cu" "In8.Cu" "In9.Cu" "In10.Cu" "In11.Cu" "In12.Cu" "In13.Cu" "In14.Cu"
				"In15.Cu" "In16.Cu"
			)
			(hatch none 0.5)
			(connect_pads
				(clearance 0)
			)
			(min_thickness 0.25)
			(keepout
				(tracks not_allowed)
				(vias allowed)
				(pads allowed)
				(copperpour not_allowed)
				(footprints allowed)
			)
			(placement
				(enabled no)
				(sheetname "")
			)
			(fill
				(thermal_gap 0.5)
				(thermal_bridge_width 0.5)
				(island_removal_mode 0)
			)
			(polygon
				(pts
					(arc
						(start 10.177272 -361.761278)
						(mid 5.986272 -361.761278)
						(end 10.177272 -361.761278)
					)
				)
			)
		)
	)
	(footprint ""
		(layer "F.Cu")
		(at 335.28508 -15.996666 -90)
		(property "Reference" "R1444"
			(at 0 0 270)
			(layer "F.SilkS")
			(hide yes)
			(effects
				(font
					(size 1.27 1.27)
				)
			)
		)
		(property "Value" ""
			(at 0 0 270)
			(layer "F.Fab")
			(effects
				(font
					(size 1.27 1.27)
				)
			)
		)
		(duplicate_pad_numbers_are_jumpers no)
		(fp_line
			(start -0.7874 0.4064)
			(end -0.7874 -0.4064)
			(stroke
				(width 0.1524)
				(type default)
			)
			(layer "F.SilkS")
		)
		(fp_line
			(start 0.7874 0.4064)
			(end -0.7874 0.4064)
			(stroke
				(width 0.1524)
				(type default)
			)
			(layer "F.SilkS")
		)
		(fp_line
			(start -0.7874 -0.4064)
			(end 0.7874 -0.4064)
			(stroke
				(width 0.1524)
				(type default)
			)
			(layer "F.SilkS")
		)
		(fp_line
			(start 0.7874 -0.4064)
			(end 0.7874 0.4064)
			(stroke
				(width 0.1524)
				(type default)
			)
			(layer "F.SilkS")
		)
		(fp_line
			(start -0.67945 0.3048)
			(end -0.67945 -0.305054)
			(stroke
				(width 0.1)
				(type default)
			)
			(layer "F.Fab")
		)
		(fp_line
			(start -0.12065 0.3048)
			(end -0.67945 0.3048)
			(stroke
				(width 0.1)
				(type default)
			)
			(layer "F.Fab")
		)
		(fp_line
			(start 0.120396 0.3048)
			(end 0.120396 0.2794)
			(stroke
				(width 0.1)
				(type default)
			)
			(layer "F.Fab")
		)
		(fp_line
			(start 0.67945 0.3048)
			(end 0.120396 0.3048)
			(stroke
				(width 0.1)
				(type default)
			)
			(layer "F.Fab")
		)
		(fp_line
			(start -0.12065 0.2794)
			(end -0.12065 0.3048)
			(stroke
				(width 0.1)
				(type default)
			)
			(layer "F.Fab")
		)
		(fp_line
			(start 0.120396 0.2794)
			(end -0.12065 0.2794)
			(stroke
				(width 0.1)
				(type default)
			)
			(layer "F.Fab")
		)
		(fp_line
			(start -0.12065 -0.2794)
			(end 0.12065 -0.2794)
			(stroke
				(width 0.1)
				(type default)
			)
			(layer "F.Fab")
		)
		(fp_line
			(start 0.12065 -0.2794)
			(end 0.12065 -0.3048)
			(stroke
				(width 0.1)
				(type default)
			)
			(layer "F.Fab")
		)
		(fp_line
			(start 0.12065 -0.3048)
			(end 0.67945 -0.3048)
			(stroke
				(width 0.1)
				(type default)
			)
			(layer "F.Fab")
		)
		(fp_line
			(start 0.67945 -0.3048)
			(end 0.67945 0.3048)
			(stroke
				(width 0.1)
				(type default)
			)
			(layer "F.Fab")
		)
		(fp_line
			(start -0.67945 -0.305054)
			(end -0.12065 -0.305054)
			(stroke
				(width 0.1)
				(type default)
			)
			(layer "F.Fab")
		)
		(fp_line
			(start -0.12065 -0.305054)
			(end -0.12065 -0.2794)
			(stroke
				(width 0.1)
				(type default)
			)
			(layer "F.Fab")
		)
		(pad "1" smd circle
			(at -0.40005 0 270)
			(size 0 0)
			(layers "F.Cu" "F.Mask" "F.Paste")
			(net "P3V3_AUX")
		)
		(pad "2" smd circle
			(at 0.40005 0 270)
			(size 0 0)
			(layers "F.Cu" "F.Mask" "F.Paste")
			(net "LED_BIOS_DBG_MODE_R")
		)
	)
	(footprint ""
		(layer "F.Cu")
		(at 76.971906 -152.990804 90)
		(property "Reference" "PC60"
			(at 0 0 90)
			(layer "F.SilkS")
			(hide yes)
			(effects
				(font
					(size 1.27 1.27)
				)
			)
		)
		(property "Value" ""
			(at 0 0 90)
			(layer "F.Fab")
			(effects
				(font
					(size 1.27 1.27)
				)
			)
		)
		(duplicate_pad_numbers_are_jumpers no)
		(fp_line
			(start 1.524 -0.762)
			(end 1.524 0.762)
			(stroke
				(width 0.1524)
				(type default)
			)
			(layer "F.SilkS")
		)
		(fp_line
			(start -1.524 -0.762)
			(end 1.524 -0.762)
			(stroke
				(width 0.1524)
				(type default)
			)
			(layer "F.SilkS")
		)
		(fp_line
			(start 1.524 0.762)
			(end -1.524 0.762)
			(stroke
				(width 0.1524)
				(type default)
			)
			(layer "F.SilkS")
		)
		(fp_line
			(start -1.524 0.762)
			(end -1.524 -0.762)
			(stroke
				(width 0.1524)
				(type default)
			)
			(layer "F.SilkS")
		)
		(fp_line
			(start 1.1049 -0.724916)
			(end -1.1049 -0.724916)
			(stroke
				(width 0.1)
				(type default)
			)
			(layer "F.Fab")
		)
		(fp_line
			(start -1.1049 -0.724916)
			(end -1.1049 0.724916)
			(stroke
				(width 0.1)
				(type default)
			)
			(layer "F.Fab")
		)
		(fp_line
			(start 1.1049 0.724916)
			(end 1.1049 -0.724916)
			(stroke
				(width 0.1)
				(type default)
			)
			(layer "F.Fab")
		)
		(fp_line
			(start -1.1049 0.724916)
			(end 1.1049 0.724916)
			(stroke
				(width 0.1)
				(type default)
			)
			(layer "F.Fab")
		)
		(pad "1" smd rect
			(at -0.889 0 270)
			(size 1.016 1.27)
			(layers "F.Cu" "F.Mask" "F.Paste")
			(net "SW_P12V_AUX_PVDD18_S5_P1_FLT")
		)
		(pad "2" smd rect
			(at 0.889 0 270)
			(size 1.016 1.27)
			(layers "F.Cu" "F.Mask" "F.Paste")
			(net "GND")
		)
	)
	(footprint ""
		(layer "F.Cu")
		(at 461.689196 -49.453546 -90)
		(property "Reference" "PC591"
			(at 0 0 270)
			(layer "F.SilkS")
			(hide yes)
			(effects
				(font
					(size 1.27 1.27)
				)
			)
		)
		(property "Value" ""
			(at 0 0 270)
			(layer "F.Fab")
			(effects
				(font
					(size 1.27 1.27)
				)
			)
		)
		(duplicate_pad_numbers_are_jumpers no)
		(fp_line
			(start -1.2954 0.5842)
			(end -1.2954 -0.5842)
			(stroke
				(width 0.1524)
				(type default)
			)
			(layer "F.SilkS")
		)
		(fp_line
			(start 1.2954 0.5842)
			(end -1.2954 0.5842)
			(stroke
				(width 0.1524)
				(type default)
			)
			(layer "F.SilkS")
		)
		(fp_line
			(start -1.2954 -0.5842)
			(end 1.2954 -0.5842)
			(stroke
				(width 0.1524)
				(type default)
			)
			(layer "F.SilkS")
		)
		(fp_line
			(start 1.2954 -0.5842)
			(end 1.2954 0.5842)
			(stroke
				(width 0.1524)
				(type default)
			)
			(layer "F.SilkS")
		)
		(fp_line
			(start -0.8636 0.4572)
			(end -0.8636 0.4064)
			(stroke
				(width 0.1)
				(type default)
			)
			(layer "F.Fab")
		)
		(fp_line
			(start 0.8636 0.4572)
			(end -0.8636 0.4572)
			(stroke
				(width 0.1)
				(type default)
			)
			(layer "F.Fab")
		)
		(fp_line
			(start -1.1938 0.4064)
			(end -1.1938 -0.4064)
			(stroke
				(width 0.1)
				(type default)
			)
			(layer "F.Fab")
		)
		(fp_line
			(start -0.8636 0.4064)
			(end -1.1938 0.4064)
			(stroke
				(width 0.1)
				(type default)
			)
			(layer "F.Fab")
		)
		(fp_line
			(start 0.8636 0.4064)
			(end 0.8636 0.4572)
			(stroke
				(width 0.1)
				(type default)
			)
			(layer "F.Fab")
		)
		(fp_line
			(start 1.1938 0.4064)
			(end 0.8636 0.4064)
			(stroke
				(width 0.1)
				(type default)
			)
			(layer "F.Fab")
		)
		(fp_line
			(start -1.1938 -0.4064)
			(end -0.8636 -0.4064)
			(stroke
				(width 0.1)
				(type default)
			)
			(layer "F.Fab")
		)
		(fp_line
			(start -0.8636 -0.4064)
			(end -0.8636 -0.4572)
			(stroke
				(width 0.1)
				(type default)
			)
			(layer "F.Fab")
		)
		(fp_line
			(start 0.8636 -0.4064)
			(end 1.1938 -0.4064)
			(stroke
				(width 0.1)
				(type default)
			)
			(layer "F.Fab")
		)
		(fp_line
			(start 1.1938 -0.4064)
			(end 1.1938 0.4064)
			(stroke
				(width 0.1)
				(type default)
			)
			(layer "F.Fab")
		)
		(fp_line
			(start -0.8636 -0.4572)
			(end 0.8636 -0.4572)
			(stroke
				(width 0.1)
				(type default)
			)
			(layer "F.Fab")
		)
		(fp_line
			(start 0.8636 -0.4572)
			(end 0.8636 -0.4064)
			(stroke
				(width 0.1)
				(type default)
			)
			(layer "F.Fab")
		)
		(pad "1" smd rect
			(at -0.7366 0 180)
			(size 0.7112 0.8128)
			(layers "F.Cu" "F.Mask" "F.Paste")
			(net "P3V3_AUX_VCC")
		)
		(pad "2" smd rect
			(at 0.7366 0 180)
			(size 0.7112 0.8128)
			(layers "F.Cu" "F.Mask" "F.Paste")
			(net "GND")
		)
	)
	(footprint ""
		(layer "F.Cu")
		(at 38.416738 -169.763694 180)
		(property "Reference" "C1338"
			(at 0 0 180)
			(layer "F.SilkS")
			(hide yes)
			(effects
				(font
					(size 1.27 1.27)
				)
			)
		)
		(property "Value" ""
			(at 0 0 180)
			(layer "F.Fab")
			(effects
				(font
					(size 1.27 1.27)
				)
			)
		)
		(duplicate_pad_numbers_are_jumpers no)
		(fp_line
			(start 0.7874 0.4064)
			(end -0.7874 0.4064)
			(stroke
				(width 0.1524)
				(type default)
			)
			(layer "F.SilkS")
		)
		(fp_line
			(start 0.7874 -0.4064)
			(end 0.7874 0.4064)
			(stroke
				(width 0.1524)
				(type default)
			)
			(layer "F.SilkS")
		)
		(fp_line
			(start -0.7874 0.4064)
			(end -0.7874 -0.4064)
			(stroke
				(width 0.1524)
				(type default)
			)
			(layer "F.SilkS")
		)
		(fp_line
			(start -0.7874 -0.4064)
			(end 0.7874 -0.4064)
			(stroke
				(width 0.1524)
				(type default)
			)
			(layer "F.SilkS")
		)
		(fp_line
			(start 0.67945 0.3048)
			(end 0.120396 0.3048)
			(stroke
				(width 0.1)
				(type default)
			)
			(layer "F.Fab")
		)
		(fp_line
			(start 0.67945 -0.3048)
			(end 0.67945 0.3048)
			(stroke
				(width 0.1)
				(type default)
			)
			(layer "F.Fab")
		)
		(fp_line
			(start 0.12065 -0.2794)
			(end 0.12065 -0.3048)
			(stroke
				(width 0.1)
				(type default)
			)
			(layer "F.Fab")
		)
		(fp_line
			(start 0.12065 -0.3048)
			(end 0.67945 -0.3048)
			(stroke
				(width 0.1)
				(type default)
			)
			(layer "F.Fab")
		)
		(fp_line
			(start 0.120396 0.3048)
			(end 0.120396 0.2794)
			(stroke
				(width 0.1)
				(type default)
			)
			(layer "F.Fab")
		)
		(fp_line
			(start 0.120396 0.2794)
			(end -0.12065 0.2794)
			(stroke
				(width 0.1)
				(type default)
			)
			(layer "F.Fab")
		)
		(fp_line
			(start -0.12065 0.3048)
			(end -0.67945 0.3048)
			(stroke
				(width 0.1)
				(type default)
			)
			(layer "F.Fab")
		)
		(fp_line
			(start -0.12065 0.2794)
			(end -0.12065 0.3048)
			(stroke
				(width 0.1)
				(type default)
			)
			(layer "F.Fab")
		)
		(fp_line
			(start -0.12065 -0.2794)
			(end 0.12065 -0.2794)
			(stroke
				(width 0.1)
				(type default)
			)
			(layer "F.Fab")
		)
		(fp_line
			(start -0.12065 -0.305054)
			(end -0.12065 -0.2794)
			(stroke
				(width 0.1)
				(type default)
			)
			(layer "F.Fab")
		)
		(fp_line
			(start -0.67945 0.3048)
			(end -0.67945 -0.305054)
			(stroke
				(width 0.1)
				(type default)
			)
			(layer "F.Fab")
		)
		(fp_line
			(start -0.67945 -0.305054)
			(end -0.12065 -0.305054)
			(stroke
				(width 0.1)
				(type default)
			)
			(layer "F.Fab")
		)
		(pad "1" smd circle
			(at -0.40005 0 180)
			(size 0 0)
			(layers "F.Cu" "F.Mask" "F.Paste")
			(net "P3V3_AUX")
		)
		(pad "2" smd circle
			(at 0.40005 0 180)
			(size 0 0)
			(layers "F.Cu" "F.Mask" "F.Paste")
			(net "GND")
		)
	)
	(footprint ""
		(layer "F.Cu")
		(at 72.099678 -171.2341)
		(property "Reference" "PC309_5"
			(at 0 0 0)
			(layer "F.SilkS")
			(hide yes)
			(effects
				(font
					(size 1.27 1.27)
				)
			)
		)
		(property "Value" ""
			(at 0 0 0)
			(layer "F.Fab")
			(effects
				(font
					(size 1.27 1.27)
				)
			)
		)
		(duplicate_pad_numbers_are_jumpers no)
		(fp_line
			(start -0.7874 -0.4064)
			(end 0.7874 -0.4064)
			(stroke
				(width 0.1524)
				(type default)
			)
			(layer "F.SilkS")
		)
		(fp_line
			(start -0.7874 0.4064)
			(end -0.7874 -0.4064)
			(stroke
				(width 0.1524)
				(type default)
			)
			(layer "F.SilkS")
		)
		(fp_line
			(start 0.7874 -0.4064)
			(end 0.7874 0.4064)
			(stroke
				(width 0.1524)
				(type default)
			)
			(layer "F.SilkS")
		)
		(fp_line
			(start 0.7874 0.4064)
			(end -0.7874 0.4064)
			(stroke
				(width 0.1524)
				(type default)
			)
			(layer "F.SilkS")
		)
		(fp_line
			(start -0.67945 -0.305054)
			(end -0.12065 -0.305054)
			(stroke
				(width 0.1)
				(type default)
			)
			(layer "F.Fab")
		)
		(fp_line
			(start -0.67945 0.3048)
			(end -0.67945 -0.305054)
			(stroke
				(width 0.1)
				(type default)
			)
			(layer "F.Fab")
		)
		(fp_line
			(start -0.12065 -0.305054)
			(end -0.12065 -0.2794)
			(stroke
				(width 0.1)
				(type default)
			)
			(layer "F.Fab")
		)
		(fp_line
			(start -0.12065 -0.2794)
			(end 0.12065 -0.2794)
			(stroke
				(width 0.1)
				(type default)
			)
			(layer "F.Fab")
		)
		(fp_line
			(start -0.12065 0.2794)
			(end -0.12065 0.3048)
			(stroke
				(width 0.1)
				(type default)
			)
			(layer "F.Fab")
		)
		(fp_line
			(start -0.12065 0.3048)
			(end -0.67945 0.3048)
			(stroke
				(width 0.1)
				(type default)
			)
			(layer "F.Fab")
		)
		(fp_line
			(start 0.120396 0.2794)
			(end -0.12065 0.2794)
			(stroke
				(width 0.1)
				(type default)
			)
			(layer "F.Fab")
		)
		(fp_line
			(start 0.120396 0.3048)
			(end 0.120396 0.2794)
			(stroke
				(width 0.1)
				(type default)
			)
			(layer "F.Fab")
		)
		(fp_line
			(start 0.12065 -0.3048)
			(end 0.67945 -0.3048)
			(stroke
				(width 0.1)
				(type default)
			)
			(layer "F.Fab")
		)
		(fp_line
			(start 0.12065 -0.2794)
			(end 0.12065 -0.3048)
			(stroke
				(width 0.1)
				(type default)
			)
			(layer "F.Fab")
		)
		(fp_line
			(start 0.67945 -0.3048)
			(end 0.67945 0.3048)
			(stroke
				(width 0.1)
				(type default)
			)
			(layer "F.Fab")
		)
		(fp_line
			(start 0.67945 0.3048)
			(end 0.120396 0.3048)
			(stroke
				(width 0.1)
				(type default)
			)
			(layer "F.Fab")
		)
		(pad "1" smd circle
			(at -0.40005 0)
			(size 0 0)
			(layers "F.Cu" "F.Mask" "F.Paste")
			(net "SW_P12V_AUX_PVDDCR_CPU0_P1_FLT")
		)
		(pad "2" smd circle
			(at 0.40005 0)
			(size 0 0)
			(layers "F.Cu" "F.Mask" "F.Paste")
			(net "GND")
		)
	)
	(footprint ""
		(layer "F.Cu")
		(at 317.041276 -340.206838)
		(property "Reference" "PR86"
			(at 0 0 0)
			(layer "F.SilkS")
			(hide yes)
			(effects
				(font
					(size 1.27 1.27)
				)
			)
		)
		(property "Value" ""
			(at 0 0 0)
			(layer "F.Fab")
			(effects
				(font
					(size 1.27 1.27)
				)
			)
		)
		(duplicate_pad_numbers_are_jumpers no)
		(fp_line
			(start -0.7874 -0.4064)
			(end 0.7874 -0.4064)
			(stroke
				(width 0.1524)
				(type default)
			)
			(layer "F.SilkS")
		)
		(fp_line
			(start -0.7874 0.4064)
			(end -0.7874 -0.4064)
			(stroke
				(width 0.1524)
				(type default)
			)
			(layer "F.SilkS")
		)
		(fp_line
			(start 0.7874 -0.4064)
			(end 0.7874 0.4064)
			(stroke
				(width 0.1524)
				(type default)
			)
			(layer "F.SilkS")
		)
		(fp_line
			(start 0.7874 0.4064)
			(end -0.7874 0.4064)
			(stroke
				(width 0.1524)
				(type default)
			)
			(layer "F.SilkS")
		)
		(fp_line
			(start -0.67945 -0.305054)
			(end -0.12065 -0.305054)
			(stroke
				(width 0.1)
				(type default)
			)
			(layer "F.Fab")
		)
		(fp_line
			(start -0.67945 0.3048)
			(end -0.67945 -0.305054)
			(stroke
				(width 0.1)
				(type default)
			)
			(layer "F.Fab")
		)
		(fp_line
			(start -0.12065 -0.305054)
			(end -0.12065 -0.2794)
			(stroke
				(width 0.1)
				(type default)
			)
			(layer "F.Fab")
		)
		(fp_line
			(start -0.12065 -0.2794)
			(end 0.12065 -0.2794)
			(stroke
				(width 0.1)
				(type default)
			)
			(layer "F.Fab")
		)
		(fp_line
			(start -0.12065 0.2794)
			(end -0.12065 0.3048)
			(stroke
				(width 0.1)
				(type default)
			)
			(layer "F.Fab")
		)
		(fp_line
			(start -0.12065 0.3048)
			(end -0.67945 0.3048)
			(stroke
				(width 0.1)
				(type default)
			)
			(layer "F.Fab")
		)
		(fp_line
			(start 0.120396 0.2794)
			(end -0.12065 0.2794)
			(stroke
				(width 0.1)
				(type default)
			)
			(layer "F.Fab")
		)
		(fp_line
			(start 0.120396 0.3048)
			(end 0.120396 0.2794)
			(stroke
				(width 0.1)
				(type default)
			)
			(layer "F.Fab")
		)
		(fp_line
			(start 0.12065 -0.3048)
			(end 0.67945 -0.3048)
			(stroke
				(width 0.1)
				(type default)
			)
			(layer "F.Fab")
		)
		(fp_line
			(start 0.12065 -0.2794)
			(end 0.12065 -0.3048)
			(stroke
				(width 0.1)
				(type default)
			)
			(layer "F.Fab")
		)
		(fp_line
			(start 0.67945 -0.3048)
			(end 0.67945 0.3048)
			(stroke
				(width 0.1)
				(type default)
			)
			(layer "F.Fab")
		)
		(fp_line
			(start 0.67945 0.3048)
			(end 0.120396 0.3048)
			(stroke
				(width 0.1)
				(type default)
			)
			(layer "F.Fab")
		)
		(pad "1" smd circle
			(at -0.40005 0)
			(size 0 0)
			(layers "F.Cu" "F.Mask" "F.Paste")
			(net "PVDDCR_CPU1_P0_LSET3")
		)
		(pad "2" smd circle
			(at 0.40005 0)
			(size 0 0)
			(layers "F.Cu" "F.Mask" "F.Paste")
			(net "GND")
		)
	)
	(footprint ""
		(layer "F.Cu")
		(at 180.975 -129.377948 -90)
		(property "Reference" "R272"
			(at 0 0 270)
			(layer "F.SilkS")
			(hide yes)
			(effects
				(font
					(size 1.27 1.27)
				)
			)
		)
		(property "Value" ""
			(at 0 0 270)
			(layer "F.Fab")
			(effects
				(font
					(size 1.27 1.27)
				)
			)
		)
		(duplicate_pad_numbers_are_jumpers no)
		(fp_line
			(start -0.7874 0.4064)
			(end -0.7874 -0.4064)
			(stroke
				(width 0.1524)
				(type default)
			)
			(layer "F.SilkS")
		)
		(fp_line
			(start 0.7874 0.4064)
			(end -0.7874 0.4064)
			(stroke
				(width 0.1524)
				(type default)
			)
			(layer "F.SilkS")
		)
		(fp_line
			(start -0.7874 -0.4064)
			(end 0.7874 -0.4064)
			(stroke
				(width 0.1524)
				(type default)
			)
			(layer "F.SilkS")
		)
		(fp_line
			(start 0.7874 -0.4064)
			(end 0.7874 0.4064)
			(stroke
				(width 0.1524)
				(type default)
			)
			(layer "F.SilkS")
		)
		(fp_line
			(start -0.67945 0.3048)
			(end -0.67945 -0.305054)
			(stroke
				(width 0.1)
				(type default)
			)
			(layer "F.Fab")
		)
		(fp_line
			(start -0.12065 0.3048)
			(end -0.67945 0.3048)
			(stroke
				(width 0.1)
				(type default)
			)
			(layer "F.Fab")
		)
		(fp_line
			(start 0.120396 0.3048)
			(end 0.120396 0.2794)
			(stroke
				(width 0.1)
				(type default)
			)
			(layer "F.Fab")
		)
		(fp_line
			(start 0.67945 0.3048)
			(end 0.120396 0.3048)
			(stroke
				(width 0.1)
				(type default)
			)
			(layer "F.Fab")
		)
		(fp_line
			(start -0.12065 0.2794)
			(end -0.12065 0.3048)
			(stroke
				(width 0.1)
				(type default)
			)
			(layer "F.Fab")
		)
		(fp_line
			(start 0.120396 0.2794)
			(end -0.12065 0.2794)
			(stroke
				(width 0.1)
				(type default)
			)
			(layer "F.Fab")
		)
		(fp_line
			(start -0.12065 -0.2794)
			(end 0.12065 -0.2794)
			(stroke
				(width 0.1)
				(type default)
			)
			(layer "F.Fab")
		)
		(fp_line
			(start 0.12065 -0.2794)
			(end 0.12065 -0.3048)
			(stroke
				(width 0.1)
				(type default)
			)
			(layer "F.Fab")
		)
		(fp_line
			(start 0.12065 -0.3048)
			(end 0.67945 -0.3048)
			(stroke
				(width 0.1)
				(type default)
			)
			(layer "F.Fab")
		)
		(fp_line
			(start 0.67945 -0.3048)
			(end 0.67945 0.3048)
			(stroke
				(width 0.1)
				(type default)
			)
			(layer "F.Fab")
		)
		(fp_line
			(start -0.67945 -0.305054)
			(end -0.12065 -0.305054)
			(stroke
				(width 0.1)
				(type default)
			)
			(layer "F.Fab")
		)
		(fp_line
			(start -0.12065 -0.305054)
			(end -0.12065 -0.2794)
			(stroke
				(width 0.1)
				(type default)
			)
			(layer "F.Fab")
		)
		(pad "1" smd circle
			(at -0.40005 0 270)
			(size 0 0)
			(layers "F.Cu" "F.Mask" "F.Paste")
			(net "RST_CPU1_SYS_N")
		)
		(pad "2" smd circle
			(at 0.40005 0 270)
			(size 0 0)
			(layers "F.Cu" "F.Mask" "F.Paste")
			(net "FM_CPU1_SYS_RESET_N")
		)
	)
	(footprint ""
		(layer "F.Cu")
		(at 48.19904 -438.753504 90)
		(property "Reference" "R2925"
			(at 0 0 90)
			(layer "F.SilkS")
			(hide yes)
			(effects
				(font
					(size 1.27 1.27)
				)
			)
		)
		(property "Value" ""
			(at 0 0 90)
			(layer "F.Fab")
			(effects
				(font
					(size 1.27 1.27)
				)
			)
		)
		(duplicate_pad_numbers_are_jumpers no)
		(fp_line
			(start 0.7874 -0.4064)
			(end 0.7874 0.4064)
			(stroke
				(width 0.1524)
				(type default)
			)
			(layer "F.SilkS")
		)
		(fp_line
			(start -0.7874 -0.4064)
			(end 0.7874 -0.4064)
			(stroke
				(width 0.1524)
				(type default)
			)
			(layer "F.SilkS")
		)
		(fp_line
			(start 0.7874 0.4064)
			(end -0.7874 0.4064)
			(stroke
				(width 0.1524)
				(type default)
			)
			(layer "F.SilkS")
		)
		(fp_line
			(start -0.7874 0.4064)
			(end -0.7874 -0.4064)
			(stroke
				(width 0.1524)
				(type default)
			)
			(layer "F.SilkS")
		)
		(fp_line
			(start -0.12065 -0.305054)
			(end -0.12065 -0.2794)
			(stroke
				(width 0.1)
				(type default)
			)
			(layer "F.Fab")
		)
		(fp_line
			(start -0.67945 -0.305054)
			(end -0.12065 -0.305054)
			(stroke
				(width 0.1)
				(type default)
			)
			(layer "F.Fab")
		)
		(fp_line
			(start 0.67945 -0.3048)
			(end 0.67945 0.3048)
			(stroke
				(width 0.1)
				(type default)
			)
			(layer "F.Fab")
		)
		(fp_line
			(start 0.12065 -0.3048)
			(end 0.67945 -0.3048)
			(stroke
				(width 0.1)
				(type default)
			)
			(layer "F.Fab")
		)
		(fp_line
			(start 0.12065 -0.2794)
			(end 0.12065 -0.3048)
			(stroke
				(width 0.1)
				(type default)
			)
			(layer "F.Fab")
		)
		(fp_line
			(start -0.12065 -0.2794)
			(end 0.12065 -0.2794)
			(stroke
				(width 0.1)
				(type default)
			)
			(layer "F.Fab")
		)
		(fp_line
			(start 0.120396 0.2794)
			(end -0.12065 0.2794)
			(stroke
				(width 0.1)
				(type default)
			)
			(layer "F.Fab")
		)
		(fp_line
			(start -0.12065 0.2794)
			(end -0.12065 0.3048)
			(stroke
				(width 0.1)
				(type default)
			)
			(layer "F.Fab")
		)
		(fp_line
			(start 0.67945 0.3048)
			(end 0.120396 0.3048)
			(stroke
				(width 0.1)
				(type default)
			)
			(layer "F.Fab")
		)
		(fp_line
			(start 0.120396 0.3048)
			(end 0.120396 0.2794)
			(stroke
				(width 0.1)
				(type default)
			)
			(layer "F.Fab")
		)
		(fp_line
			(start -0.12065 0.3048)
			(end -0.67945 0.3048)
			(stroke
				(width 0.1)
				(type default)
			)
			(layer "F.Fab")
		)
		(fp_line
			(start -0.67945 0.3048)
			(end -0.67945 -0.305054)
			(stroke
				(width 0.1)
				(type default)
			)
			(layer "F.Fab")
		)
		(pad "1" smd circle
			(at -0.40005 0 90)
			(size 0 0)
			(layers "F.Cu" "F.Mask" "F.Paste")
			(net "FM_GPU_PWR_EN_R1")
		)
		(pad "2" smd circle
			(at 0.40005 0 90)
			(size 0 0)
			(layers "F.Cu" "F.Mask" "F.Paste")
			(net "FM_GPU_PWR_EN_R_BUF")
		)
	)
	(footprint ""
		(layer "F.Cu")
		(at 175.300894 -390.53008 180)
		(property "Reference" "R861"
			(at 0 0 180)
			(layer "F.SilkS")
			(hide yes)
			(effects
				(font
					(size 1.27 1.27)
				)
			)
		)
		(property "Value" ""
			(at 0 0 180)
			(layer "F.Fab")
			(effects
				(font
					(size 1.27 1.27)
				)
			)
		)
		(duplicate_pad_numbers_are_jumpers no)
		(fp_line
			(start 0.32512 0.175006)
			(end -0.32512 0.175006)
			(stroke
				(width 0.1)
				(type default)
			)
			(layer "F.Fab")
		)
		(fp_line
			(start 0.32512 -0.175006)
			(end 0.32512 0.175006)
			(stroke
				(width 0.1)
				(type default)
			)
			(layer "F.Fab")
		)
		(fp_line
			(start -0.32512 0.175006)
			(end -0.32512 -0.175006)
			(stroke
				(width 0.1)
				(type default)
			)
			(layer "F.Fab")
		)
		(fp_line
			(start -0.32512 -0.175006)
			(end 0.32512 -0.175006)
			(stroke
				(width 0.1)
				(type default)
			)
			(layer "F.Fab")
		)
		(pad "1" smd rect
			(at -0.2667 0 180)
			(size 0.3048 0.381)
			(layers "F.Cu" "F.Mask" "F.Paste")
			(net "P1V8_CPU1_RT_1D")
		)
		(pad "2" smd rect
			(at 0.2667 0)
			(size 0.3048 0.381)
			(layers "F.Cu" "F.Mask" "F.Paste")
			(net "RT_CPU1_P2_ADDR3")
		)
	)
	(footprint ""
		(layer "F.Cu")
		(at 165.3032 -419.7096 180)
		(property "Reference" "C7503"
			(at 0 0 180)
			(layer "F.SilkS")
			(hide yes)
			(effects
				(font
					(size 1.27 1.27)
				)
			)
		)
		(property "Value" ""
			(at 0 0 180)
			(layer "F.Fab")
			(effects
				(font
					(size 1.27 1.27)
				)
			)
		)
		(duplicate_pad_numbers_are_jumpers no)
		(fp_line
			(start 0.299974 0.150114)
			(end -0.299974 0.150114)
			(stroke
				(width 0.1)
				(type default)
			)
			(layer "F.Fab")
		)
		(fp_line
			(start 0.299974 -0.150114)
			(end 0.299974 0.150114)
			(stroke
				(width 0.1)
				(type default)
			)
			(layer "F.Fab")
		)
		(fp_line
			(start -0.299974 0.150114)
			(end -0.299974 -0.150114)
			(stroke
				(width 0.1)
				(type default)
			)
			(layer "F.Fab")
		)
		(fp_line
			(start -0.299974 -0.150114)
			(end 0.299974 -0.150114)
			(stroke
				(width 0.1)
				(type default)
			)
			(layer "F.Fab")
		)
		(pad "1" smd rect
			(at -0.2667 0 180)
			(size 0.3048 0.381)
			(layers "F.Cu" "F.Mask" "F.Paste")
			(net "P1V8_CPU1_RT_1D")
		)
		(pad "2" smd rect
			(at 0.2667 0 180)
			(size 0.3048 0.381)
			(layers "F.Cu" "F.Mask" "F.Paste")
			(net "GND")
		)
	)
	(footprint ""
		(layer "F.Cu")
		(at 422.88206 -163.314888)
		(property "Reference" "H53"
			(at 2.1844 3.91287 0)
			(unlocked yes)
			(layer "F.SilkS")
			(effects
				(font
					(size 0.7874 0.5842)
					(thickness 0.1524)
				)
				(justify left)
			)
		)
		(property "Value" ""
			(at 0 0 0)
			(layer "F.Fab")
			(effects
				(font
					(size 1.27 1.27)
				)
			)
		)
		(duplicate_pad_numbers_are_jumpers no)
		(pad "1" thru_hole circle
			(at 0 0)
			(size 6.1976 6.1976)
			(drill 3.7338)
			(layers "*.Cu" "*.Mask")
			(remove_unused_layers no)
			(net "GND")
			(clearance -0.9779)
			(padstack
				(mode front_inner_back)
				(layer "Inner"
					(shape circle)
					(size 5.5372 5.5372)
					(clearance -0.6477)
				)
				(layer "B.Cu"
					(shape circle)
					(size 6.1976 6.1976)
					(clearance -0.9779)
				)
			)
		)
	)
	(footprint ""
		(layer "F.Cu")
		(at 479.35896 -202.351132 180)
		(property "Reference" "DB3"
			(at -1.527048 3.26771 0)
			(unlocked yes)
			(layer "F.SilkS")
			(effects
				(font
					(size 0.7874 0.5842)
					(thickness 0.1524)
				)
				(justify left)
			)
		)
		(property "Value" ""
			(at 0 0 180)
			(layer "F.Fab")
			(effects
				(font
					(size 1.27 1.27)
				)
			)
		)
		(duplicate_pad_numbers_are_jumpers no)
		(fp_line
			(start 3.330702 -4.771136)
			(end 0 4.011168)
			(stroke
				(width 0.1524)
				(type default)
			)
			(layer "F.SilkS")
		)
		(fp_line
			(start 0 4.011168)
			(end -3.330702 -4.771136)
			(stroke
				(width 0.1524)
				(type default)
			)
			(layer "F.SilkS")
		)
		(fp_line
			(start -3.330702 -4.771136)
			(end 3.330702 -4.771136)
			(stroke
				(width 0.1524)
				(type default)
			)
			(layer "F.SilkS")
		)
		(fp_line
			(start 3.330702 -4.771136)
			(end 0 4.011168)
			(stroke
				(width 0.1)
				(type default)
			)
			(layer "F.Fab")
		)
		(fp_line
			(start 0 4.011168)
			(end -3.330702 -4.771136)
			(stroke
				(width 0.1)
				(type default)
			)
			(layer "F.Fab")
		)
		(fp_line
			(start -3.330702 -4.771136)
			(end 3.330702 -4.771136)
			(stroke
				(width 0.1)
				(type default)
			)
			(layer "F.Fab")
		)
		(pad "1" thru_hole circle
			(at 0 0 180)
			(size 2.159 2.159)
			(drill 1.7018)
			(layers "*.Cu" "*.Mask")
			(remove_unused_layers no)
			(net "T1_GND")
			(clearance 0.0254)
			(thermal_gap 0.0254)
		)
		(pad "2" thru_hole circle
			(at -1.27 -3.348736 180)
			(size 2.159 2.159)
			(drill 1.7018)
			(layers "*.Cu" "*.Mask")
			(remove_unused_layers no)
			(net "TDR_SE_45_OHM_IN2")
			(clearance 0.0254)
			(thermal_gap 0.0254)
		)
		(pad "3" thru_hole circle
			(at 1.27 -3.348736 180)
			(size 2.159 2.159)
			(drill 1.7018)
			(layers "*.Cu" "*.Mask")
			(remove_unused_layers no)
			(net "TDR_SE_45_OHM_IN2")
			(clearance 0.0254)
			(thermal_gap 0.0254)
		)
	)
	(footprint ""
		(layer "F.Cu")
		(at 152.849326 -38.00856 180)
		(property "Reference" "R3520"
			(at 0 0 180)
			(layer "F.SilkS")
			(hide yes)
			(effects
				(font
					(size 1.27 1.27)
				)
			)
		)
		(property "Value" ""
			(at 0 0 180)
			(layer "F.Fab")
			(effects
				(font
					(size 1.27 1.27)
				)
			)
		)
		(duplicate_pad_numbers_are_jumpers no)
		(fp_line
			(start 0.7874 0.4064)
			(end -0.7874 0.4064)
			(stroke
				(width 0.1524)
				(type default)
			)
			(layer "F.SilkS")
		)
		(fp_line
			(start 0.7874 -0.4064)
			(end 0.7874 0.4064)
			(stroke
				(width 0.1524)
				(type default)
			)
			(layer "F.SilkS")
		)
		(fp_line
			(start -0.7874 0.4064)
			(end -0.7874 -0.4064)
			(stroke
				(width 0.1524)
				(type default)
			)
			(layer "F.SilkS")
		)
		(fp_line
			(start -0.7874 -0.4064)
			(end 0.7874 -0.4064)
			(stroke
				(width 0.1524)
				(type default)
			)
			(layer "F.SilkS")
		)
		(fp_line
			(start 0.67945 0.3048)
			(end 0.120396 0.3048)
			(stroke
				(width 0.1)
				(type default)
			)
			(layer "F.Fab")
		)
		(fp_line
			(start 0.67945 -0.3048)
			(end 0.67945 0.3048)
			(stroke
				(width 0.1)
				(type default)
			)
			(layer "F.Fab")
		)
		(fp_line
			(start 0.12065 -0.2794)
			(end 0.12065 -0.3048)
			(stroke
				(width 0.1)
				(type default)
			)
			(layer "F.Fab")
		)
		(fp_line
			(start 0.12065 -0.3048)
			(end 0.67945 -0.3048)
			(stroke
				(width 0.1)
				(type default)
			)
			(layer "F.Fab")
		)
		(fp_line
			(start 0.120396 0.3048)
			(end 0.120396 0.2794)
			(stroke
				(width 0.1)
				(type default)
			)
			(layer "F.Fab")
		)
		(fp_line
			(start 0.120396 0.2794)
			(end -0.12065 0.2794)
			(stroke
				(width 0.1)
				(type default)
			)
			(layer "F.Fab")
		)
		(fp_line
			(start -0.12065 0.3048)
			(end -0.67945 0.3048)
			(stroke
				(width 0.1)
				(type default)
			)
			(layer "F.Fab")
		)
		(fp_line
			(start -0.12065 0.2794)
			(end -0.12065 0.3048)
			(stroke
				(width 0.1)
				(type default)
			)
			(layer "F.Fab")
		)
		(fp_line
			(start -0.12065 -0.2794)
			(end 0.12065 -0.2794)
			(stroke
				(width 0.1)
				(type default)
			)
			(layer "F.Fab")
		)
		(fp_line
			(start -0.12065 -0.305054)
			(end -0.12065 -0.2794)
			(stroke
				(width 0.1)
				(type default)
			)
			(layer "F.Fab")
		)
		(fp_line
			(start -0.67945 0.3048)
			(end -0.67945 -0.305054)
			(stroke
				(width 0.1)
				(type default)
			)
			(layer "F.Fab")
		)
		(fp_line
			(start -0.67945 -0.305054)
			(end -0.12065 -0.305054)
			(stroke
				(width 0.1)
				(type default)
			)
			(layer "F.Fab")
		)
		(pad "1" smd circle
			(at -0.40005 0 180)
			(size 0 0)
			(layers "F.Cu" "F.Mask" "F.Paste")
			(net "P3V3_OCP_V3_2")
		)
		(pad "2" smd circle
			(at 0.40005 0 180)
			(size 0 0)
			(layers "F.Cu" "F.Mask" "F.Paste")
			(net "SMB_OCP_V3_2_3V3AUX_BUF_SDA")
		)
	)
	(footprint ""
		(layer "F.Cu")
		(at 169.220642 -92.268294 180)
		(property "Reference" "R1142"
			(at 0 0 180)
			(layer "F.SilkS")
			(hide yes)
			(effects
				(font
					(size 1.27 1.27)
				)
			)
		)
		(property "Value" ""
			(at 0 0 180)
			(layer "F.Fab")
			(effects
				(font
					(size 1.27 1.27)
				)
			)
		)
		(duplicate_pad_numbers_are_jumpers no)
		(fp_line
			(start 0.7874 0.4064)
			(end -0.7874 0.4064)
			(stroke
				(width 0.1524)
				(type default)
			)
			(layer "F.SilkS")
		)
		(fp_line
			(start 0.7874 -0.4064)
			(end 0.7874 0.4064)
			(stroke
				(width 0.1524)
				(type default)
			)
			(layer "F.SilkS")
		)
		(fp_line
			(start -0.7874 0.4064)
			(end -0.7874 -0.4064)
			(stroke
				(width 0.1524)
				(type default)
			)
			(layer "F.SilkS")
		)
		(fp_line
			(start -0.7874 -0.4064)
			(end 0.7874 -0.4064)
			(stroke
				(width 0.1524)
				(type default)
			)
			(layer "F.SilkS")
		)
		(fp_line
			(start 0.67945 0.3048)
			(end 0.120396 0.3048)
			(stroke
				(width 0.1)
				(type default)
			)
			(layer "F.Fab")
		)
		(fp_line
			(start 0.67945 -0.3048)
			(end 0.67945 0.3048)
			(stroke
				(width 0.1)
				(type default)
			)
			(layer "F.Fab")
		)
		(fp_line
			(start 0.12065 -0.2794)
			(end 0.12065 -0.3048)
			(stroke
				(width 0.1)
				(type default)
			)
			(layer "F.Fab")
		)
		(fp_line
			(start 0.12065 -0.3048)
			(end 0.67945 -0.3048)
			(stroke
				(width 0.1)
				(type default)
			)
			(layer "F.Fab")
		)
		(fp_line
			(start 0.120396 0.3048)
			(end 0.120396 0.2794)
			(stroke
				(width 0.1)
				(type default)
			)
			(layer "F.Fab")
		)
		(fp_line
			(start 0.120396 0.2794)
			(end -0.12065 0.2794)
			(stroke
				(width 0.1)
				(type default)
			)
			(layer "F.Fab")
		)
		(fp_line
			(start -0.12065 0.3048)
			(end -0.67945 0.3048)
			(stroke
				(width 0.1)
				(type default)
			)
			(layer "F.Fab")
		)
		(fp_line
			(start -0.12065 0.2794)
			(end -0.12065 0.3048)
			(stroke
				(width 0.1)
				(type default)
			)
			(layer "F.Fab")
		)
		(fp_line
			(start -0.12065 -0.2794)
			(end 0.12065 -0.2794)
			(stroke
				(width 0.1)
				(type default)
			)
			(layer "F.Fab")
		)
		(fp_line
			(start -0.12065 -0.305054)
			(end -0.12065 -0.2794)
			(stroke
				(width 0.1)
				(type default)
			)
			(layer "F.Fab")
		)
		(fp_line
			(start -0.67945 0.3048)
			(end -0.67945 -0.305054)
			(stroke
				(width 0.1)
				(type default)
			)
			(layer "F.Fab")
		)
		(fp_line
			(start -0.67945 -0.305054)
			(end -0.12065 -0.305054)
			(stroke
				(width 0.1)
				(type default)
			)
			(layer "F.Fab")
		)
		(pad "1" smd circle
			(at -0.40005 0 180)
			(size 0 0)
			(layers "F.Cu" "F.Mask" "F.Paste")
			(net "OCP_V3_1_P3V3_PWRGD")
		)
		(pad "2" smd circle
			(at 0.40005 0 180)
			(size 0 0)
			(layers "F.Cu" "F.Mask" "F.Paste")
			(net "OCP_V3_1_P3V3_R2_PWRGD")
		)
	)
	(footprint ""
		(layer "F.Cu")
		(at 364.302548 -14.450568 90)
		(property "Reference" "R821"
			(at 0 0 90)
			(layer "F.SilkS")
			(hide yes)
			(effects
				(font
					(size 1.27 1.27)
				)
			)
		)
		(property "Value" ""
			(at 0 0 90)
			(layer "F.Fab")
			(effects
				(font
					(size 1.27 1.27)
				)
			)
		)
		(duplicate_pad_numbers_are_jumpers no)
		(fp_line
			(start 0.7874 -0.4064)
			(end 0.7874 0.4064)
			(stroke
				(width 0.1524)
				(type default)
			)
			(layer "F.SilkS")
		)
		(fp_line
			(start -0.7874 -0.4064)
			(end 0.7874 -0.4064)
			(stroke
				(width 0.1524)
				(type default)
			)
			(layer "F.SilkS")
		)
		(fp_line
			(start 0.7874 0.4064)
			(end -0.7874 0.4064)
			(stroke
				(width 0.1524)
				(type default)
			)
			(layer "F.SilkS")
		)
		(fp_line
			(start -0.7874 0.4064)
			(end -0.7874 -0.4064)
			(stroke
				(width 0.1524)
				(type default)
			)
			(layer "F.SilkS")
		)
		(fp_line
			(start -0.12065 -0.305054)
			(end -0.12065 -0.2794)
			(stroke
				(width 0.1)
				(type default)
			)
			(layer "F.Fab")
		)
		(fp_line
			(start -0.67945 -0.305054)
			(end -0.12065 -0.305054)
			(stroke
				(width 0.1)
				(type default)
			)
			(layer "F.Fab")
		)
		(fp_line
			(start 0.67945 -0.3048)
			(end 0.67945 0.3048)
			(stroke
				(width 0.1)
				(type default)
			)
			(layer "F.Fab")
		)
		(fp_line
			(start 0.12065 -0.3048)
			(end 0.67945 -0.3048)
			(stroke
				(width 0.1)
				(type default)
			)
			(layer "F.Fab")
		)
		(fp_line
			(start 0.12065 -0.2794)
			(end 0.12065 -0.3048)
			(stroke
				(width 0.1)
				(type default)
			)
			(layer "F.Fab")
		)
		(fp_line
			(start -0.12065 -0.2794)
			(end 0.12065 -0.2794)
			(stroke
				(width 0.1)
				(type default)
			)
			(layer "F.Fab")
		)
		(fp_line
			(start 0.120396 0.2794)
			(end -0.12065 0.2794)
			(stroke
				(width 0.1)
				(type default)
			)
			(layer "F.Fab")
		)
		(fp_line
			(start -0.12065 0.2794)
			(end -0.12065 0.3048)
			(stroke
				(width 0.1)
				(type default)
			)
			(layer "F.Fab")
		)
		(fp_line
			(start 0.67945 0.3048)
			(end 0.120396 0.3048)
			(stroke
				(width 0.1)
				(type default)
			)
			(layer "F.Fab")
		)
		(fp_line
			(start 0.120396 0.3048)
			(end 0.120396 0.2794)
			(stroke
				(width 0.1)
				(type default)
			)
			(layer "F.Fab")
		)
		(fp_line
			(start -0.12065 0.3048)
			(end -0.67945 0.3048)
			(stroke
				(width 0.1)
				(type default)
			)
			(layer "F.Fab")
		)
		(fp_line
			(start -0.67945 0.3048)
			(end -0.67945 -0.305054)
			(stroke
				(width 0.1)
				(type default)
			)
			(layer "F.Fab")
		)
		(pad "1" smd circle
			(at -0.40005 0 90)
			(size 0 0)
			(layers "F.Cu" "F.Mask" "F.Paste")
			(net "P3V3_AUX")
		)
		(pad "2" smd circle
			(at 0.40005 0 90)
			(size 0 0)
			(layers "F.Cu" "F.Mask" "F.Paste")
			(net "UART_VCC_J13")
		)
	)
	(footprint ""
		(layer "F.Cu")
		(at 315.771022 -34.858706 180)
		(property "Reference" "C1344"
			(at 0 0 180)
			(layer "F.SilkS")
			(hide yes)
			(effects
				(font
					(size 1.27 1.27)
				)
			)
		)
		(property "Value" ""
			(at 0 0 180)
			(layer "F.Fab")
			(effects
				(font
					(size 1.27 1.27)
				)
			)
		)
		(duplicate_pad_numbers_are_jumpers no)
		(fp_line
			(start 0.7874 0.4064)
			(end -0.7874 0.4064)
			(stroke
				(width 0.1524)
				(type default)
			)
			(layer "F.SilkS")
		)
		(fp_line
			(start 0.7874 -0.4064)
			(end 0.7874 0.4064)
			(stroke
				(width 0.1524)
				(type default)
			)
			(layer "F.SilkS")
		)
		(fp_line
			(start -0.7874 0.4064)
			(end -0.7874 -0.4064)
			(stroke
				(width 0.1524)
				(type default)
			)
			(layer "F.SilkS")
		)
		(fp_line
			(start -0.7874 -0.4064)
			(end 0.7874 -0.4064)
			(stroke
				(width 0.1524)
				(type default)
			)
			(layer "F.SilkS")
		)
		(fp_line
			(start 0.67945 0.3048)
			(end 0.120396 0.3048)
			(stroke
				(width 0.1)
				(type default)
			)
			(layer "F.Fab")
		)
		(fp_line
			(start 0.67945 -0.3048)
			(end 0.67945 0.3048)
			(stroke
				(width 0.1)
				(type default)
			)
			(layer "F.Fab")
		)
		(fp_line
			(start 0.12065 -0.2794)
			(end 0.12065 -0.3048)
			(stroke
				(width 0.1)
				(type default)
			)
			(layer "F.Fab")
		)
		(fp_line
			(start 0.12065 -0.3048)
			(end 0.67945 -0.3048)
			(stroke
				(width 0.1)
				(type default)
			)
			(layer "F.Fab")
		)
		(fp_line
			(start 0.120396 0.3048)
			(end 0.120396 0.2794)
			(stroke
				(width 0.1)
				(type default)
			)
			(layer "F.Fab")
		)
		(fp_line
			(start 0.120396 0.2794)
			(end -0.12065 0.2794)
			(stroke
				(width 0.1)
				(type default)
			)
			(layer "F.Fab")
		)
		(fp_line
			(start -0.12065 0.3048)
			(end -0.67945 0.3048)
			(stroke
				(width 0.1)
				(type default)
			)
			(layer "F.Fab")
		)
		(fp_line
			(start -0.12065 0.2794)
			(end -0.12065 0.3048)
			(stroke
				(width 0.1)
				(type default)
			)
			(layer "F.Fab")
		)
		(fp_line
			(start -0.12065 -0.2794)
			(end 0.12065 -0.2794)
			(stroke
				(width 0.1)
				(type default)
			)
			(layer "F.Fab")
		)
		(fp_line
			(start -0.12065 -0.305054)
			(end -0.12065 -0.2794)
			(stroke
				(width 0.1)
				(type default)
			)
			(layer "F.Fab")
		)
		(fp_line
			(start -0.67945 0.3048)
			(end -0.67945 -0.305054)
			(stroke
				(width 0.1)
				(type default)
			)
			(layer "F.Fab")
		)
		(fp_line
			(start -0.67945 -0.305054)
			(end -0.12065 -0.305054)
			(stroke
				(width 0.1)
				(type default)
			)
			(layer "F.Fab")
		)
		(pad "1" smd circle
			(at -0.40005 0 180)
			(size 0 0)
			(layers "F.Cu" "F.Mask" "F.Paste")
			(net "P12V_AUX_ADC_MAM")
		)
		(pad "2" smd circle
			(at 0.40005 0 180)
			(size 0 0)
			(layers "F.Cu" "F.Mask" "F.Paste")
			(net "GND")
		)
	)
	(footprint ""
		(layer "F.Cu")
		(at 226.0981 -399.956782)
		(property "Reference" "PR3992"
			(at 0 0 0)
			(layer "F.SilkS")
			(hide yes)
			(effects
				(font
					(size 1.27 1.27)
				)
			)
		)
		(property "Value" ""
			(at 0 0 0)
			(layer "F.Fab")
			(effects
				(font
					(size 1.27 1.27)
				)
			)
		)
		(duplicate_pad_numbers_are_jumpers no)
		(fp_line
			(start -0.7874 -0.4064)
			(end 0.7874 -0.4064)
			(stroke
				(width 0.1524)
				(type default)
			)
			(layer "F.SilkS")
		)
		(fp_line
			(start -0.7874 0.4064)
			(end -0.7874 -0.4064)
			(stroke
				(width 0.1524)
				(type default)
			)
			(layer "F.SilkS")
		)
		(fp_line
			(start 0.7874 -0.4064)
			(end 0.7874 0.4064)
			(stroke
				(width 0.1524)
				(type default)
			)
			(layer "F.SilkS")
		)
		(fp_line
			(start 0.7874 0.4064)
			(end -0.7874 0.4064)
			(stroke
				(width 0.1524)
				(type default)
			)
			(layer "F.SilkS")
		)
		(fp_line
			(start -0.67945 -0.305054)
			(end -0.12065 -0.305054)
			(stroke
				(width 0.1)
				(type default)
			)
			(layer "F.Fab")
		)
		(fp_line
			(start -0.67945 0.3048)
			(end -0.67945 -0.305054)
			(stroke
				(width 0.1)
				(type default)
			)
			(layer "F.Fab")
		)
		(fp_line
			(start -0.12065 -0.305054)
			(end -0.12065 -0.2794)
			(stroke
				(width 0.1)
				(type default)
			)
			(layer "F.Fab")
		)
		(fp_line
			(start -0.12065 -0.2794)
			(end 0.12065 -0.2794)
			(stroke
				(width 0.1)
				(type default)
			)
			(layer "F.Fab")
		)
		(fp_line
			(start -0.12065 0.2794)
			(end -0.12065 0.3048)
			(stroke
				(width 0.1)
				(type default)
			)
			(layer "F.Fab")
		)
		(fp_line
			(start -0.12065 0.3048)
			(end -0.67945 0.3048)
			(stroke
				(width 0.1)
				(type default)
			)
			(layer "F.Fab")
		)
		(fp_line
			(start 0.120396 0.2794)
			(end -0.12065 0.2794)
			(stroke
				(width 0.1)
				(type default)
			)
			(layer "F.Fab")
		)
		(fp_line
			(start 0.120396 0.3048)
			(end 0.120396 0.2794)
			(stroke
				(width 0.1)
				(type default)
			)
			(layer "F.Fab")
		)
		(fp_line
			(start 0.12065 -0.3048)
			(end 0.67945 -0.3048)
			(stroke
				(width 0.1)
				(type default)
			)
			(layer "F.Fab")
		)
		(fp_line
			(start 0.12065 -0.2794)
			(end 0.12065 -0.3048)
			(stroke
				(width 0.1)
				(type default)
			)
			(layer "F.Fab")
		)
		(fp_line
			(start 0.67945 -0.3048)
			(end 0.67945 0.3048)
			(stroke
				(width 0.1)
				(type default)
			)
			(layer "F.Fab")
		)
		(fp_line
			(start 0.67945 0.3048)
			(end 0.120396 0.3048)
			(stroke
				(width 0.1)
				(type default)
			)
			(layer "F.Fab")
		)
		(pad "1" smd circle
			(at -0.40005 0)
			(size 0 0)
			(layers "F.Cu" "F.Mask" "F.Paste")
			(net "HSC_D_OC_3")
		)
		(pad "2" smd circle
			(at 0.40005 0)
			(size 0 0)
			(layers "F.Cu" "F.Mask" "F.Paste")
			(net "HSC_D_OC_R")
		)
	)
	(footprint ""
		(layer "F.Cu")
		(at 105.537 -419.989 180)
		(property "Reference" "R3462"
			(at 0 0 180)
			(layer "F.SilkS")
			(hide yes)
			(effects
				(font
					(size 1.27 1.27)
				)
			)
		)
		(property "Value" ""
			(at 0 0 180)
			(layer "F.Fab")
			(effects
				(font
					(size 1.27 1.27)
				)
			)
		)
		(duplicate_pad_numbers_are_jumpers no)
		(fp_line
			(start 0.7874 0.4064)
			(end -0.7874 0.4064)
			(stroke
				(width 0.1524)
				(type default)
			)
			(layer "F.SilkS")
		)
		(fp_line
			(start 0.7874 -0.4064)
			(end 0.7874 0.4064)
			(stroke
				(width 0.1524)
				(type default)
			)
			(layer "F.SilkS")
		)
		(fp_line
			(start -0.7874 0.4064)
			(end -0.7874 -0.4064)
			(stroke
				(width 0.1524)
				(type default)
			)
			(layer "F.SilkS")
		)
		(fp_line
			(start -0.7874 -0.4064)
			(end 0.7874 -0.4064)
			(stroke
				(width 0.1524)
				(type default)
			)
			(layer "F.SilkS")
		)
		(fp_line
			(start 0.67945 0.3048)
			(end 0.120396 0.3048)
			(stroke
				(width 0.1)
				(type default)
			)
			(layer "F.Fab")
		)
		(fp_line
			(start 0.67945 -0.3048)
			(end 0.67945 0.3048)
			(stroke
				(width 0.1)
				(type default)
			)
			(layer "F.Fab")
		)
		(fp_line
			(start 0.12065 -0.2794)
			(end 0.12065 -0.3048)
			(stroke
				(width 0.1)
				(type default)
			)
			(layer "F.Fab")
		)
		(fp_line
			(start 0.12065 -0.3048)
			(end 0.67945 -0.3048)
			(stroke
				(width 0.1)
				(type default)
			)
			(layer "F.Fab")
		)
		(fp_line
			(start 0.120396 0.3048)
			(end 0.120396 0.2794)
			(stroke
				(width 0.1)
				(type default)
			)
			(layer "F.Fab")
		)
		(fp_line
			(start 0.120396 0.2794)
			(end -0.12065 0.2794)
			(stroke
				(width 0.1)
				(type default)
			)
			(layer "F.Fab")
		)
		(fp_line
			(start -0.12065 0.3048)
			(end -0.67945 0.3048)
			(stroke
				(width 0.1)
				(type default)
			)
			(layer "F.Fab")
		)
		(fp_line
			(start -0.12065 0.2794)
			(end -0.12065 0.3048)
			(stroke
				(width 0.1)
				(type default)
			)
			(layer "F.Fab")
		)
		(fp_line
			(start -0.12065 -0.2794)
			(end 0.12065 -0.2794)
			(stroke
				(width 0.1)
				(type default)
			)
			(layer "F.Fab")
		)
		(fp_line
			(start -0.12065 -0.305054)
			(end -0.12065 -0.2794)
			(stroke
				(width 0.1)
				(type default)
			)
			(layer "F.Fab")
		)
		(fp_line
			(start -0.67945 0.3048)
			(end -0.67945 -0.305054)
			(stroke
				(width 0.1)
				(type default)
			)
			(layer "F.Fab")
		)
		(fp_line
			(start -0.67945 -0.305054)
			(end -0.12065 -0.305054)
			(stroke
				(width 0.1)
				(type default)
			)
			(layer "F.Fab")
		)
		(pad "1" smd circle
			(at -0.40005 0 180)
			(size 0 0)
			(layers "F.Cu" "F.Mask" "F.Paste")
			(net "GPU_NVS_PWR_BRAKE_N_R")
		)
		(pad "2" smd circle
			(at 0.40005 0 180)
			(size 0 0)
			(layers "F.Cu" "F.Mask" "F.Paste")
			(net "GND")
		)
	)
	(footprint ""
		(layer "F.Cu")
		(at 252.144784 -393.91336 -90)
		(property "Reference" "PR2533"
			(at -4.54406 3.082544 90)
			(unlocked yes)
			(layer "F.SilkS")
			(effects
				(font
					(size 0.7874 0.5842)
					(thickness 0.1524)
				)
				(justify left)
			)
		)
		(property "Value" ""
			(at 0 0 270)
			(layer "F.Fab")
			(effects
				(font
					(size 1.27 1.27)
				)
			)
		)
		(duplicate_pad_numbers_are_jumpers no)
		(fp_line
			(start -3.9878 3.5814)
			(end -3.9878 -3.5814)
			(stroke
				(width 0.1524)
				(type default)
			)
			(layer "F.SilkS")
		)
		(fp_line
			(start 3.9878 3.5814)
			(end -3.9878 3.5814)
			(stroke
				(width 0.1524)
				(type default)
			)
			(layer "F.SilkS")
		)
		(fp_line
			(start -3.9878 -3.5814)
			(end 3.9878 -3.5814)
			(stroke
				(width 0.1524)
				(type default)
			)
			(layer "F.SilkS")
		)
		(fp_line
			(start 3.9878 -3.5814)
			(end 3.9878 3.5814)
			(stroke
				(width 0.1524)
				(type default)
			)
			(layer "F.SilkS")
		)
		(fp_line
			(start -3.5306 3.353054)
			(end -3.5306 -3.353054)
			(stroke
				(width 0.1)
				(type default)
			)
			(layer "F.Fab")
		)
		(fp_line
			(start 3.5306 3.353054)
			(end -3.5306 3.353054)
			(stroke
				(width 0.1)
				(type default)
			)
			(layer "F.Fab")
		)
		(fp_line
			(start -3.5306 -3.353054)
			(end 3.5306 -3.353054)
			(stroke
				(width 0.1)
				(type default)
			)
			(layer "F.Fab")
		)
		(fp_line
			(start 3.5306 -3.353054)
			(end 3.5306 3.353054)
			(stroke
				(width 0.1)
				(type default)
			)
			(layer "F.Fab")
		)
		(pad "1A" smd rect
			(at -2.249932 0 90)
			(size 3.2004 6.858)
			(layers "F.Cu" "F.Mask" "F.Paste")
			(net "P12V_PSU")
		)
		(pad "1B" smd rect
			(at -0.776732 0 270)
			(size 0.254 0.508)
			(layers "F.Cu" "F.Mask" "F.Paste")
			(net "P12V_HSC_SENSE2_R3_P")
		)
		(pad "2A" smd rect
			(at 2.249932 0 90)
			(size 3.2004 6.858)
			(layers "F.Cu" "F.Mask" "F.Paste")
			(net "P12V_MAIN_R")
		)
		(pad "2B" smd rect
			(at 0.776732 0 270)
			(size 0.254 0.508)
			(layers "F.Cu" "F.Mask" "F.Paste")
			(net "P12V_HSC_SENSE2_R3_N")
		)
	)
	(footprint ""
		(layer "F.Cu")
		(at 126.804928 -49.153064)
		(property "Reference" "R6213"
			(at 0 0 0)
			(layer "F.SilkS")
			(hide yes)
			(effects
				(font
					(size 1.27 1.27)
				)
			)
		)
		(property "Value" ""
			(at 0 0 0)
			(layer "F.Fab")
			(effects
				(font
					(size 1.27 1.27)
				)
			)
		)
		(duplicate_pad_numbers_are_jumpers no)
		(fp_line
			(start -0.7874 -0.4064)
			(end 0.7874 -0.4064)
			(stroke
				(width 0.1524)
				(type default)
			)
			(layer "F.SilkS")
		)
		(fp_line
			(start -0.7874 0.4064)
			(end -0.7874 -0.4064)
			(stroke
				(width 0.1524)
				(type default)
			)
			(layer "F.SilkS")
		)
		(fp_line
			(start 0.7874 -0.4064)
			(end 0.7874 0.4064)
			(stroke
				(width 0.1524)
				(type default)
			)
			(layer "F.SilkS")
		)
		(fp_line
			(start 0.7874 0.4064)
			(end -0.7874 0.4064)
			(stroke
				(width 0.1524)
				(type default)
			)
			(layer "F.SilkS")
		)
		(fp_line
			(start -0.67945 -0.305054)
			(end -0.12065 -0.305054)
			(stroke
				(width 0.1)
				(type default)
			)
			(layer "F.Fab")
		)
		(fp_line
			(start -0.67945 0.3048)
			(end -0.67945 -0.305054)
			(stroke
				(width 0.1)
				(type default)
			)
			(layer "F.Fab")
		)
		(fp_line
			(start -0.12065 -0.305054)
			(end -0.12065 -0.2794)
			(stroke
				(width 0.1)
				(type default)
			)
			(layer "F.Fab")
		)
		(fp_line
			(start -0.12065 -0.2794)
			(end 0.12065 -0.2794)
			(stroke
				(width 0.1)
				(type default)
			)
			(layer "F.Fab")
		)
		(fp_line
			(start -0.12065 0.2794)
			(end -0.12065 0.3048)
			(stroke
				(width 0.1)
				(type default)
			)
			(layer "F.Fab")
		)
		(fp_line
			(start -0.12065 0.3048)
			(end -0.67945 0.3048)
			(stroke
				(width 0.1)
				(type default)
			)
			(layer "F.Fab")
		)
		(fp_line
			(start 0.120396 0.2794)
			(end -0.12065 0.2794)
			(stroke
				(width 0.1)
				(type default)
			)
			(layer "F.Fab")
		)
		(fp_line
			(start 0.120396 0.3048)
			(end 0.120396 0.2794)
			(stroke
				(width 0.1)
				(type default)
			)
			(layer "F.Fab")
		)
		(fp_line
			(start 0.12065 -0.3048)
			(end 0.67945 -0.3048)
			(stroke
				(width 0.1)
				(type default)
			)
			(layer "F.Fab")
		)
		(fp_line
			(start 0.12065 -0.2794)
			(end 0.12065 -0.3048)
			(stroke
				(width 0.1)
				(type default)
			)
			(layer "F.Fab")
		)
		(fp_line
			(start 0.67945 -0.3048)
			(end 0.67945 0.3048)
			(stroke
				(width 0.1)
				(type default)
			)
			(layer "F.Fab")
		)
		(fp_line
			(start 0.67945 0.3048)
			(end 0.120396 0.3048)
			(stroke
				(width 0.1)
				(type default)
			)
			(layer "F.Fab")
		)
		(pad "1" smd circle
			(at -0.40005 0)
			(size 0 0)
			(layers "F.Cu" "F.Mask" "F.Paste")
			(net "P3V3_AUX")
		)
		(pad "2" smd circle
			(at 0.40005 0)
			(size 0 0)
			(layers "F.Cu" "F.Mask" "F.Paste")
			(net "USB_CPU0_HUB1_MODE_SEL1")
		)
	)
	(footprint ""
		(layer "F.Cu")
		(at 355.506782 -412.030418 180)
		(property "Reference" "R4154"
			(at 0 0 180)
			(layer "F.SilkS")
			(hide yes)
			(effects
				(font
					(size 1.27 1.27)
				)
			)
		)
		(property "Value" ""
			(at 0 0 180)
			(layer "F.Fab")
			(effects
				(font
					(size 1.27 1.27)
				)
			)
		)
		(duplicate_pad_numbers_are_jumpers no)
		(fp_line
			(start 0.7874 0.4064)
			(end -0.7874 0.4064)
			(stroke
				(width 0.1524)
				(type default)
			)
			(layer "F.SilkS")
		)
		(fp_line
			(start 0.7874 -0.4064)
			(end 0.7874 0.4064)
			(stroke
				(width 0.1524)
				(type default)
			)
			(layer "F.SilkS")
		)
		(fp_line
			(start -0.7874 0.4064)
			(end -0.7874 -0.4064)
			(stroke
				(width 0.1524)
				(type default)
			)
			(layer "F.SilkS")
		)
		(fp_line
			(start -0.7874 -0.4064)
			(end 0.7874 -0.4064)
			(stroke
				(width 0.1524)
				(type default)
			)
			(layer "F.SilkS")
		)
		(fp_line
			(start 0.67945 0.3048)
			(end 0.120396 0.3048)
			(stroke
				(width 0.1)
				(type default)
			)
			(layer "F.Fab")
		)
		(fp_line
			(start 0.67945 -0.3048)
			(end 0.67945 0.3048)
			(stroke
				(width 0.1)
				(type default)
			)
			(layer "F.Fab")
		)
		(fp_line
			(start 0.12065 -0.2794)
			(end 0.12065 -0.3048)
			(stroke
				(width 0.1)
				(type default)
			)
			(layer "F.Fab")
		)
		(fp_line
			(start 0.12065 -0.3048)
			(end 0.67945 -0.3048)
			(stroke
				(width 0.1)
				(type default)
			)
			(layer "F.Fab")
		)
		(fp_line
			(start 0.120396 0.3048)
			(end 0.120396 0.2794)
			(stroke
				(width 0.1)
				(type default)
			)
			(layer "F.Fab")
		)
		(fp_line
			(start 0.120396 0.2794)
			(end -0.12065 0.2794)
			(stroke
				(width 0.1)
				(type default)
			)
			(layer "F.Fab")
		)
		(fp_line
			(start -0.12065 0.3048)
			(end -0.67945 0.3048)
			(stroke
				(width 0.1)
				(type default)
			)
			(layer "F.Fab")
		)
		(fp_line
			(start -0.12065 0.2794)
			(end -0.12065 0.3048)
			(stroke
				(width 0.1)
				(type default)
			)
			(layer "F.Fab")
		)
		(fp_line
			(start -0.12065 -0.2794)
			(end 0.12065 -0.2794)
			(stroke
				(width 0.1)
				(type default)
			)
			(layer "F.Fab")
		)
		(fp_line
			(start -0.12065 -0.305054)
			(end -0.12065 -0.2794)
			(stroke
				(width 0.1)
				(type default)
			)
			(layer "F.Fab")
		)
		(fp_line
			(start -0.67945 0.3048)
			(end -0.67945 -0.305054)
			(stroke
				(width 0.1)
				(type default)
			)
			(layer "F.Fab")
		)
		(fp_line
			(start -0.67945 -0.305054)
			(end -0.12065 -0.305054)
			(stroke
				(width 0.1)
				(type default)
			)
			(layer "F.Fab")
		)
		(pad "1" smd circle
			(at -0.40005 0 180)
			(size 0 0)
			(layers "F.Cu" "F.Mask" "F.Paste")
			(net "PRSNT_CABLE_GPU_A1_N")
		)
		(pad "2" smd circle
			(at 0.40005 0 180)
			(size 0 0)
			(layers "F.Cu" "F.Mask" "F.Paste")
			(net "GND")
		)
	)
	(footprint ""
		(layer "F.Cu")
		(at 181.615334 -356.507034 180)
		(property "Reference" "PR328"
			(at 0 0 180)
			(layer "F.SilkS")
			(hide yes)
			(effects
				(font
					(size 1.27 1.27)
				)
			)
		)
		(property "Value" ""
			(at 0 0 180)
			(layer "F.Fab")
			(effects
				(font
					(size 1.27 1.27)
				)
			)
		)
		(duplicate_pad_numbers_are_jumpers no)
		(fp_line
			(start 0.7874 0.4064)
			(end -0.7874 0.4064)
			(stroke
				(width 0.1524)
				(type default)
			)
			(layer "F.SilkS")
		)
		(fp_line
			(start 0.7874 -0.4064)
			(end 0.7874 0.4064)
			(stroke
				(width 0.1524)
				(type default)
			)
			(layer "F.SilkS")
		)
		(fp_line
			(start -0.7874 0.4064)
			(end -0.7874 -0.4064)
			(stroke
				(width 0.1524)
				(type default)
			)
			(layer "F.SilkS")
		)
		(fp_line
			(start -0.7874 -0.4064)
			(end 0.7874 -0.4064)
			(stroke
				(width 0.1524)
				(type default)
			)
			(layer "F.SilkS")
		)
		(fp_line
			(start 0.67945 0.3048)
			(end 0.120396 0.3048)
			(stroke
				(width 0.1)
				(type default)
			)
			(layer "F.Fab")
		)
		(fp_line
			(start 0.67945 -0.3048)
			(end 0.67945 0.3048)
			(stroke
				(width 0.1)
				(type default)
			)
			(layer "F.Fab")
		)
		(fp_line
			(start 0.12065 -0.2794)
			(end 0.12065 -0.3048)
			(stroke
				(width 0.1)
				(type default)
			)
			(layer "F.Fab")
		)
		(fp_line
			(start 0.12065 -0.3048)
			(end 0.67945 -0.3048)
			(stroke
				(width 0.1)
				(type default)
			)
			(layer "F.Fab")
		)
		(fp_line
			(start 0.120396 0.3048)
			(end 0.120396 0.2794)
			(stroke
				(width 0.1)
				(type default)
			)
			(layer "F.Fab")
		)
		(fp_line
			(start 0.120396 0.2794)
			(end -0.12065 0.2794)
			(stroke
				(width 0.1)
				(type default)
			)
			(layer "F.Fab")
		)
		(fp_line
			(start -0.12065 0.3048)
			(end -0.67945 0.3048)
			(stroke
				(width 0.1)
				(type default)
			)
			(layer "F.Fab")
		)
		(fp_line
			(start -0.12065 0.2794)
			(end -0.12065 0.3048)
			(stroke
				(width 0.1)
				(type default)
			)
			(layer "F.Fab")
		)
		(fp_line
			(start -0.12065 -0.2794)
			(end 0.12065 -0.2794)
			(stroke
				(width 0.1)
				(type default)
			)
			(layer "F.Fab")
		)
		(fp_line
			(start -0.12065 -0.305054)
			(end -0.12065 -0.2794)
			(stroke
				(width 0.1)
				(type default)
			)
			(layer "F.Fab")
		)
		(fp_line
			(start -0.67945 0.3048)
			(end -0.67945 -0.305054)
			(stroke
				(width 0.1)
				(type default)
			)
			(layer "F.Fab")
		)
		(fp_line
			(start -0.67945 -0.305054)
			(end -0.12065 -0.305054)
			(stroke
				(width 0.1)
				(type default)
			)
			(layer "F.Fab")
		)
		(pad "1" smd circle
			(at -0.40005 0 180)
			(size 0 0)
			(layers "F.Cu" "F.Mask" "F.Paste")
			(net "GND")
		)
		(pad "2" smd circle
			(at 0.40005 0 180)
			(size 0 0)
			(layers "F.Cu" "F.Mask" "F.Paste")
			(net "PVDD11_S3_P1_LSET1")
		)
	)
	(footprint ""
		(layer "F.Cu")
		(at 275.14169 -96.323404 180)
		(property "Reference" "R1642"
			(at 0 0 180)
			(layer "F.SilkS")
			(hide yes)
			(effects
				(font
					(size 1.27 1.27)
				)
			)
		)
		(property "Value" ""
			(at 0 0 180)
			(layer "F.Fab")
			(effects
				(font
					(size 1.27 1.27)
				)
			)
		)
		(duplicate_pad_numbers_are_jumpers no)
		(fp_line
			(start 0.7874 0.4064)
			(end -0.7874 0.4064)
			(stroke
				(width 0.1524)
				(type default)
			)
			(layer "F.SilkS")
		)
		(fp_line
			(start 0.7874 -0.4064)
			(end 0.7874 0.4064)
			(stroke
				(width 0.1524)
				(type default)
			)
			(layer "F.SilkS")
		)
		(fp_line
			(start -0.7874 0.4064)
			(end -0.7874 -0.4064)
			(stroke
				(width 0.1524)
				(type default)
			)
			(layer "F.SilkS")
		)
		(fp_line
			(start -0.7874 -0.4064)
			(end 0.7874 -0.4064)
			(stroke
				(width 0.1524)
				(type default)
			)
			(layer "F.SilkS")
		)
		(fp_line
			(start 0.67945 0.3048)
			(end 0.120396 0.3048)
			(stroke
				(width 0.1)
				(type default)
			)
			(layer "F.Fab")
		)
		(fp_line
			(start 0.67945 -0.3048)
			(end 0.67945 0.3048)
			(stroke
				(width 0.1)
				(type default)
			)
			(layer "F.Fab")
		)
		(fp_line
			(start 0.12065 -0.2794)
			(end 0.12065 -0.3048)
			(stroke
				(width 0.1)
				(type default)
			)
			(layer "F.Fab")
		)
		(fp_line
			(start 0.12065 -0.3048)
			(end 0.67945 -0.3048)
			(stroke
				(width 0.1)
				(type default)
			)
			(layer "F.Fab")
		)
		(fp_line
			(start 0.120396 0.3048)
			(end 0.120396 0.2794)
			(stroke
				(width 0.1)
				(type default)
			)
			(layer "F.Fab")
		)
		(fp_line
			(start 0.120396 0.2794)
			(end -0.12065 0.2794)
			(stroke
				(width 0.1)
				(type default)
			)
			(layer "F.Fab")
		)
		(fp_line
			(start -0.12065 0.3048)
			(end -0.67945 0.3048)
			(stroke
				(width 0.1)
				(type default)
			)
			(layer "F.Fab")
		)
		(fp_line
			(start -0.12065 0.2794)
			(end -0.12065 0.3048)
			(stroke
				(width 0.1)
				(type default)
			)
			(layer "F.Fab")
		)
		(fp_line
			(start -0.12065 -0.2794)
			(end 0.12065 -0.2794)
			(stroke
				(width 0.1)
				(type default)
			)
			(layer "F.Fab")
		)
		(fp_line
			(start -0.12065 -0.305054)
			(end -0.12065 -0.2794)
			(stroke
				(width 0.1)
				(type default)
			)
			(layer "F.Fab")
		)
		(fp_line
			(start -0.67945 0.3048)
			(end -0.67945 -0.305054)
			(stroke
				(width 0.1)
				(type default)
			)
			(layer "F.Fab")
		)
		(fp_line
			(start -0.67945 -0.305054)
			(end -0.12065 -0.305054)
			(stroke
				(width 0.1)
				(type default)
			)
			(layer "F.Fab")
		)
		(pad "1" smd circle
			(at -0.40005 0 180)
			(size 0 0)
			(layers "F.Cu" "F.Mask" "F.Paste")
			(net "JTAG_P1_R_TCK")
		)
		(pad "2" smd circle
			(at 0.40005 0 180)
			(size 0 0)
			(layers "F.Cu" "F.Mask" "F.Paste")
			(net "JTAG_CPU1_TCK")
		)
	)
	(footprint ""
		(layer "F.Cu")
		(at 192.599564 -67.391788 180)
		(property "Reference" "PR3945"
			(at 0 0 180)
			(layer "F.SilkS")
			(hide yes)
			(effects
				(font
					(size 1.27 1.27)
				)
			)
		)
		(property "Value" ""
			(at 0 0 180)
			(layer "F.Fab")
			(effects
				(font
					(size 1.27 1.27)
				)
			)
		)
		(duplicate_pad_numbers_are_jumpers no)
		(fp_line
			(start 0.7874 0.4064)
			(end -0.7874 0.4064)
			(stroke
				(width 0.1524)
				(type default)
			)
			(layer "F.SilkS")
		)
		(fp_line
			(start 0.7874 -0.4064)
			(end 0.7874 0.4064)
			(stroke
				(width 0.1524)
				(type default)
			)
			(layer "F.SilkS")
		)
		(fp_line
			(start -0.7874 0.4064)
			(end -0.7874 -0.4064)
			(stroke
				(width 0.1524)
				(type default)
			)
			(layer "F.SilkS")
		)
		(fp_line
			(start -0.7874 -0.4064)
			(end 0.7874 -0.4064)
			(stroke
				(width 0.1524)
				(type default)
			)
			(layer "F.SilkS")
		)
		(fp_line
			(start 0.67945 0.3048)
			(end 0.120396 0.3048)
			(stroke
				(width 0.1)
				(type default)
			)
			(layer "F.Fab")
		)
		(fp_line
			(start 0.67945 -0.3048)
			(end 0.67945 0.3048)
			(stroke
				(width 0.1)
				(type default)
			)
			(layer "F.Fab")
		)
		(fp_line
			(start 0.12065 -0.2794)
			(end 0.12065 -0.3048)
			(stroke
				(width 0.1)
				(type default)
			)
			(layer "F.Fab")
		)
		(fp_line
			(start 0.12065 -0.3048)
			(end 0.67945 -0.3048)
			(stroke
				(width 0.1)
				(type default)
			)
			(layer "F.Fab")
		)
		(fp_line
			(start 0.120396 0.3048)
			(end 0.120396 0.2794)
			(stroke
				(width 0.1)
				(type default)
			)
			(layer "F.Fab")
		)
		(fp_line
			(start 0.120396 0.2794)
			(end -0.12065 0.2794)
			(stroke
				(width 0.1)
				(type default)
			)
			(layer "F.Fab")
		)
		(fp_line
			(start -0.12065 0.3048)
			(end -0.67945 0.3048)
			(stroke
				(width 0.1)
				(type default)
			)
			(layer "F.Fab")
		)
		(fp_line
			(start -0.12065 0.2794)
			(end -0.12065 0.3048)
			(stroke
				(width 0.1)
				(type default)
			)
			(layer "F.Fab")
		)
		(fp_line
			(start -0.12065 -0.2794)
			(end 0.12065 -0.2794)
			(stroke
				(width 0.1)
				(type default)
			)
			(layer "F.Fab")
		)
		(fp_line
			(start -0.12065 -0.305054)
			(end -0.12065 -0.2794)
			(stroke
				(width 0.1)
				(type default)
			)
			(layer "F.Fab")
		)
		(fp_line
			(start -0.67945 0.3048)
			(end -0.67945 -0.305054)
			(stroke
				(width 0.1)
				(type default)
			)
			(layer "F.Fab")
		)
		(fp_line
			(start -0.67945 -0.305054)
			(end -0.12065 -0.305054)
			(stroke
				(width 0.1)
				(type default)
			)
			(layer "F.Fab")
		)
		(pad "1" smd circle
			(at -0.40005 0 180)
			(size 0 0)
			(layers "F.Cu" "F.Mask" "F.Paste")
			(net "P3V3_E1S_MODE_0")
		)
		(pad "2" smd circle
			(at 0.40005 0 180)
			(size 0 0)
			(layers "F.Cu" "F.Mask" "F.Paste")
			(net "GND")
		)
	)
	(footprint ""
		(layer "F.Cu")
		(at 455.228452 -15.503398 180)
		(property "Reference" "PD102"
			(at -3.501136 -2.022348 0)
			(unlocked yes)
			(layer "F.SilkS")
			(effects
				(font
					(size 0.7874 0.5842)
					(thickness 0.1524)
				)
				(justify left)
			)
		)
		(property "Value" ""
			(at 0 0 180)
			(layer "F.Fab")
			(effects
				(font
					(size 1.27 1.27)
				)
			)
		)
		(duplicate_pad_numbers_are_jumpers no)
		(fp_line
			(start 4.107942 1.459992)
			(end -3.400044 1.459992)
			(stroke
				(width 0.1524)
				(type default)
			)
			(layer "F.SilkS")
		)
		(fp_line
			(start 4.107942 -1.459992)
			(end 4.107942 1.459992)
			(stroke
				(width 0.1524)
				(type default)
			)
			(layer "F.SilkS")
		)
		(fp_line
			(start -3.400044 1.459992)
			(end -3.400044 -1.459992)
			(stroke
				(width 0.1524)
				(type default)
			)
			(layer "F.SilkS")
		)
		(fp_line
			(start -3.400044 -1.459992)
			(end 4.107942 -1.459992)
			(stroke
				(width 0.1524)
				(type default)
			)
			(layer "F.SilkS")
		)
		(fp_rect
			(start 4.107942 -1.459992)
			(end 3.308096 1.459992)
			(stroke
				(width 0)
				(type default)
			)
			(fill yes)
			(layer "F.SilkS")
		)
		(fp_line
			(start 2.29997 1.459992)
			(end -2.29997 1.459992)
			(stroke
				(width 0.1)
				(type default)
			)
			(layer "F.Fab")
		)
		(fp_line
			(start 2.29997 -1.459992)
			(end 2.29997 1.459992)
			(stroke
				(width 0.1)
				(type default)
			)
			(layer "F.Fab")
		)
		(fp_line
			(start -2.29997 1.459992)
			(end -2.29997 -1.459992)
			(stroke
				(width 0.1)
				(type default)
			)
			(layer "F.Fab")
		)
		(fp_line
			(start -2.29997 -1.459992)
			(end 2.29997 -1.459992)
			(stroke
				(width 0.1)
				(type default)
			)
			(layer "F.Fab")
		)
		(fp_text user "-"
			(at 5.4102 0.29845 0)
			(unlocked yes)
			(layer "F.SilkS")
			(effects
				(font
					(size 1.905 1.4224)
					(thickness 0.1524)
				)
				(justify left)
			)
		)
		(fp_text user "+"
			(at -5.083302 0.161036 180)
			(unlocked yes)
			(layer "F.SilkS")
			(effects
				(font
					(size 1.905 1.4224)
					(thickness 0.1524)
				)
				(justify left)
			)
		)
		(fp_text user "-"
			(at 5.4102 0.29845 0)
			(unlocked yes)
			(layer "F.Fab")
			(effects
				(font
					(size 1.905 1.4224)
					(thickness 0.1524)
				)
				(justify left)
			)
		)
		(fp_text user "+"
			(at -4.7752 -0.12065 180)
			(unlocked yes)
			(layer "F.Fab")
			(effects
				(font
					(size 1.905 1.4224)
					(thickness 0.1524)
				)
				(justify left)
			)
		)
		(pad "A" smd rect
			(at -1.999996 0 270)
			(size 1.7018 2.5146)
			(layers "F.Cu" "F.Mask" "F.Paste")
			(net "GND")
		)
		(pad "C" smd rect
			(at 1.999996 0 270)
			(size 1.7018 2.5146)
			(layers "F.Cu" "F.Mask" "F.Paste")
			(net "P12V_OCP_SFF")
		)
	)
	(footprint ""
		(layer "F.Cu")
		(at 31.331662 -429.759364 -90)
		(property "Reference" "R3280"
			(at 0 0 270)
			(layer "F.SilkS")
			(hide yes)
			(effects
				(font
					(size 1.27 1.27)
				)
			)
		)
		(property "Value" ""
			(at 0 0 270)
			(layer "F.Fab")
			(effects
				(font
					(size 1.27 1.27)
				)
			)
		)
		(duplicate_pad_numbers_are_jumpers no)
		(fp_line
			(start -0.7874 0.4064)
			(end -0.7874 -0.4064)
			(stroke
				(width 0.1524)
				(type default)
			)
			(layer "F.SilkS")
		)
		(fp_line
			(start 0.7874 0.4064)
			(end -0.7874 0.4064)
			(stroke
				(width 0.1524)
				(type default)
			)
			(layer "F.SilkS")
		)
		(fp_line
			(start -0.7874 -0.4064)
			(end 0.7874 -0.4064)
			(stroke
				(width 0.1524)
				(type default)
			)
			(layer "F.SilkS")
		)
		(fp_line
			(start 0.7874 -0.4064)
			(end 0.7874 0.4064)
			(stroke
				(width 0.1524)
				(type default)
			)
			(layer "F.SilkS")
		)
		(fp_line
			(start -0.67945 0.3048)
			(end -0.67945 -0.305054)
			(stroke
				(width 0.1)
				(type default)
			)
			(layer "F.Fab")
		)
		(fp_line
			(start -0.12065 0.3048)
			(end -0.67945 0.3048)
			(stroke
				(width 0.1)
				(type default)
			)
			(layer "F.Fab")
		)
		(fp_line
			(start 0.120396 0.3048)
			(end 0.120396 0.2794)
			(stroke
				(width 0.1)
				(type default)
			)
			(layer "F.Fab")
		)
		(fp_line
			(start 0.67945 0.3048)
			(end 0.120396 0.3048)
			(stroke
				(width 0.1)
				(type default)
			)
			(layer "F.Fab")
		)
		(fp_line
			(start -0.12065 0.2794)
			(end -0.12065 0.3048)
			(stroke
				(width 0.1)
				(type default)
			)
			(layer "F.Fab")
		)
		(fp_line
			(start 0.120396 0.2794)
			(end -0.12065 0.2794)
			(stroke
				(width 0.1)
				(type default)
			)
			(layer "F.Fab")
		)
		(fp_line
			(start -0.12065 -0.2794)
			(end 0.12065 -0.2794)
			(stroke
				(width 0.1)
				(type default)
			)
			(layer "F.Fab")
		)
		(fp_line
			(start 0.12065 -0.2794)
			(end 0.12065 -0.3048)
			(stroke
				(width 0.1)
				(type default)
			)
			(layer "F.Fab")
		)
		(fp_line
			(start 0.12065 -0.3048)
			(end 0.67945 -0.3048)
			(stroke
				(width 0.1)
				(type default)
			)
			(layer "F.Fab")
		)
		(fp_line
			(start 0.67945 -0.3048)
			(end 0.67945 0.3048)
			(stroke
				(width 0.1)
				(type default)
			)
			(layer "F.Fab")
		)
		(fp_line
			(start -0.67945 -0.305054)
			(end -0.12065 -0.305054)
			(stroke
				(width 0.1)
				(type default)
			)
			(layer "F.Fab")
		)
		(fp_line
			(start -0.12065 -0.305054)
			(end -0.12065 -0.2794)
			(stroke
				(width 0.1)
				(type default)
			)
			(layer "F.Fab")
		)
		(pad "1" smd circle
			(at -0.40005 0 270)
			(size 0 0)
			(layers "F.Cu" "F.Mask" "F.Paste")
			(net "P3V3_AUX")
		)
		(pad "2" smd circle
			(at 0.40005 0 270)
			(size 0 0)
			(layers "F.Cu" "F.Mask" "F.Paste")
			(net "FM_P2E_EQB1")
		)
	)
	(footprint ""
		(layer "F.Cu")
		(at 397.064992 -172.51934 -90)
		(property "Reference" "PR360"
			(at 0 0 270)
			(layer "F.SilkS")
			(hide yes)
			(effects
				(font
					(size 1.27 1.27)
				)
			)
		)
		(property "Value" ""
			(at 0 0 270)
			(layer "F.Fab")
			(effects
				(font
					(size 1.27 1.27)
				)
			)
		)
		(duplicate_pad_numbers_are_jumpers no)
		(fp_line
			(start -0.7874 0.4064)
			(end -0.7874 -0.4064)
			(stroke
				(width 0.1524)
				(type default)
			)
			(layer "F.SilkS")
		)
		(fp_line
			(start 0.7874 0.4064)
			(end -0.7874 0.4064)
			(stroke
				(width 0.1524)
				(type default)
			)
			(layer "F.SilkS")
		)
		(fp_line
			(start -0.7874 -0.4064)
			(end 0.7874 -0.4064)
			(stroke
				(width 0.1524)
				(type default)
			)
			(layer "F.SilkS")
		)
		(fp_line
			(start 0.7874 -0.4064)
			(end 0.7874 0.4064)
			(stroke
				(width 0.1524)
				(type default)
			)
			(layer "F.SilkS")
		)
		(fp_line
			(start -0.67945 0.3048)
			(end -0.67945 -0.305054)
			(stroke
				(width 0.1)
				(type default)
			)
			(layer "F.Fab")
		)
		(fp_line
			(start -0.12065 0.3048)
			(end -0.67945 0.3048)
			(stroke
				(width 0.1)
				(type default)
			)
			(layer "F.Fab")
		)
		(fp_line
			(start 0.120396 0.3048)
			(end 0.120396 0.2794)
			(stroke
				(width 0.1)
				(type default)
			)
			(layer "F.Fab")
		)
		(fp_line
			(start 0.67945 0.3048)
			(end 0.120396 0.3048)
			(stroke
				(width 0.1)
				(type default)
			)
			(layer "F.Fab")
		)
		(fp_line
			(start -0.12065 0.2794)
			(end -0.12065 0.3048)
			(stroke
				(width 0.1)
				(type default)
			)
			(layer "F.Fab")
		)
		(fp_line
			(start 0.120396 0.2794)
			(end -0.12065 0.2794)
			(stroke
				(width 0.1)
				(type default)
			)
			(layer "F.Fab")
		)
		(fp_line
			(start -0.12065 -0.2794)
			(end 0.12065 -0.2794)
			(stroke
				(width 0.1)
				(type default)
			)
			(layer "F.Fab")
		)
		(fp_line
			(start 0.12065 -0.2794)
			(end 0.12065 -0.3048)
			(stroke
				(width 0.1)
				(type default)
			)
			(layer "F.Fab")
		)
		(fp_line
			(start 0.12065 -0.3048)
			(end 0.67945 -0.3048)
			(stroke
				(width 0.1)
				(type default)
			)
			(layer "F.Fab")
		)
		(fp_line
			(start 0.67945 -0.3048)
			(end 0.67945 0.3048)
			(stroke
				(width 0.1)
				(type default)
			)
			(layer "F.Fab")
		)
		(fp_line
			(start -0.67945 -0.305054)
			(end -0.12065 -0.305054)
			(stroke
				(width 0.1)
				(type default)
			)
			(layer "F.Fab")
		)
		(fp_line
			(start -0.12065 -0.305054)
			(end -0.12065 -0.2794)
			(stroke
				(width 0.1)
				(type default)
			)
			(layer "F.Fab")
		)
		(pad "1" smd circle
			(at -0.40005 0 270)
			(size 0 0)
			(layers "F.Cu" "F.Mask" "F.Paste")
			(net "SW_PVDDCR_SOC_P0_BOOT1")
		)
		(pad "2" smd circle
			(at 0.40005 0 270)
			(size 0 0)
			(layers "F.Cu" "F.Mask" "F.Paste")
			(net "SW_PVDDCR_SOC_P0_BOOT1_RC")
		)
	)
	(footprint ""
		(layer "F.Cu")
		(at 179.959 -129.377948 -90)
		(property "Reference" "R273"
			(at 0 0 270)
			(layer "F.SilkS")
			(hide yes)
			(effects
				(font
					(size 1.27 1.27)
				)
			)
		)
		(property "Value" ""
			(at 0 0 270)
			(layer "F.Fab")
			(effects
				(font
					(size 1.27 1.27)
				)
			)
		)
		(duplicate_pad_numbers_are_jumpers no)
		(fp_line
			(start -0.7874 0.4064)
			(end -0.7874 -0.4064)
			(stroke
				(width 0.1524)
				(type default)
			)
			(layer "F.SilkS")
		)
		(fp_line
			(start 0.7874 0.4064)
			(end -0.7874 0.4064)
			(stroke
				(width 0.1524)
				(type default)
			)
			(layer "F.SilkS")
		)
		(fp_line
			(start -0.7874 -0.4064)
			(end 0.7874 -0.4064)
			(stroke
				(width 0.1524)
				(type default)
			)
			(layer "F.SilkS")
		)
		(fp_line
			(start 0.7874 -0.4064)
			(end 0.7874 0.4064)
			(stroke
				(width 0.1524)
				(type default)
			)
			(layer "F.SilkS")
		)
		(fp_line
			(start -0.67945 0.3048)
			(end -0.67945 -0.305054)
			(stroke
				(width 0.1)
				(type default)
			)
			(layer "F.Fab")
		)
		(fp_line
			(start -0.12065 0.3048)
			(end -0.67945 0.3048)
			(stroke
				(width 0.1)
				(type default)
			)
			(layer "F.Fab")
		)
		(fp_line
			(start 0.120396 0.3048)
			(end 0.120396 0.2794)
			(stroke
				(width 0.1)
				(type default)
			)
			(layer "F.Fab")
		)
		(fp_line
			(start 0.67945 0.3048)
			(end 0.120396 0.3048)
			(stroke
				(width 0.1)
				(type default)
			)
			(layer "F.Fab")
		)
		(fp_line
			(start -0.12065 0.2794)
			(end -0.12065 0.3048)
			(stroke
				(width 0.1)
				(type default)
			)
			(layer "F.Fab")
		)
		(fp_line
			(start 0.120396 0.2794)
			(end -0.12065 0.2794)
			(stroke
				(width 0.1)
				(type default)
			)
			(layer "F.Fab")
		)
		(fp_line
			(start -0.12065 -0.2794)
			(end 0.12065 -0.2794)
			(stroke
				(width 0.1)
				(type default)
			)
			(layer "F.Fab")
		)
		(fp_line
			(start 0.12065 -0.2794)
			(end 0.12065 -0.3048)
			(stroke
				(width 0.1)
				(type default)
			)
			(layer "F.Fab")
		)
		(fp_line
			(start 0.12065 -0.3048)
			(end 0.67945 -0.3048)
			(stroke
				(width 0.1)
				(type default)
			)
			(layer "F.Fab")
		)
		(fp_line
			(start 0.67945 -0.3048)
			(end 0.67945 0.3048)
			(stroke
				(width 0.1)
				(type default)
			)
			(layer "F.Fab")
		)
		(fp_line
			(start -0.67945 -0.305054)
			(end -0.12065 -0.305054)
			(stroke
				(width 0.1)
				(type default)
			)
			(layer "F.Fab")
		)
		(fp_line
			(start -0.12065 -0.305054)
			(end -0.12065 -0.2794)
			(stroke
				(width 0.1)
				(type default)
			)
			(layer "F.Fab")
		)
		(pad "1" smd circle
			(at -0.40005 0 270)
			(size 0 0)
			(layers "F.Cu" "F.Mask" "F.Paste")
			(net "RST_CPU1_RSMRST_N")
		)
		(pad "2" smd circle
			(at 0.40005 0 270)
			(size 0 0)
			(layers "F.Cu" "F.Mask" "F.Paste")
			(net "FM_CPU1_RSMRST_N")
		)
	)
	(footprint ""
		(layer "F.Cu")
		(at 150.502366 -58.236358)
		(property "Reference" "R3610"
			(at 0 0 0)
			(layer "F.SilkS")
			(hide yes)
			(effects
				(font
					(size 1.27 1.27)
				)
			)
		)
		(property "Value" ""
			(at 0 0 0)
			(layer "F.Fab")
			(effects
				(font
					(size 1.27 1.27)
				)
			)
		)
		(duplicate_pad_numbers_are_jumpers no)
		(fp_line
			(start -0.7874 -0.4064)
			(end 0.7874 -0.4064)
			(stroke
				(width 0.1524)
				(type default)
			)
			(layer "F.SilkS")
		)
		(fp_line
			(start -0.7874 0.4064)
			(end -0.7874 -0.4064)
			(stroke
				(width 0.1524)
				(type default)
			)
			(layer "F.SilkS")
		)
		(fp_line
			(start 0.7874 -0.4064)
			(end 0.7874 0.4064)
			(stroke
				(width 0.1524)
				(type default)
			)
			(layer "F.SilkS")
		)
		(fp_line
			(start 0.7874 0.4064)
			(end -0.7874 0.4064)
			(stroke
				(width 0.1524)
				(type default)
			)
			(layer "F.SilkS")
		)
		(fp_line
			(start -0.67945 -0.305054)
			(end -0.12065 -0.305054)
			(stroke
				(width 0.1)
				(type default)
			)
			(layer "F.Fab")
		)
		(fp_line
			(start -0.67945 0.3048)
			(end -0.67945 -0.305054)
			(stroke
				(width 0.1)
				(type default)
			)
			(layer "F.Fab")
		)
		(fp_line
			(start -0.12065 -0.305054)
			(end -0.12065 -0.2794)
			(stroke
				(width 0.1)
				(type default)
			)
			(layer "F.Fab")
		)
		(fp_line
			(start -0.12065 -0.2794)
			(end 0.12065 -0.2794)
			(stroke
				(width 0.1)
				(type default)
			)
			(layer "F.Fab")
		)
		(fp_line
			(start -0.12065 0.2794)
			(end -0.12065 0.3048)
			(stroke
				(width 0.1)
				(type default)
			)
			(layer "F.Fab")
		)
		(fp_line
			(start -0.12065 0.3048)
			(end -0.67945 0.3048)
			(stroke
				(width 0.1)
				(type default)
			)
			(layer "F.Fab")
		)
		(fp_line
			(start 0.120396 0.2794)
			(end -0.12065 0.2794)
			(stroke
				(width 0.1)
				(type default)
			)
			(layer "F.Fab")
		)
		(fp_line
			(start 0.120396 0.3048)
			(end 0.120396 0.2794)
			(stroke
				(width 0.1)
				(type default)
			)
			(layer "F.Fab")
		)
		(fp_line
			(start 0.12065 -0.3048)
			(end 0.67945 -0.3048)
			(stroke
				(width 0.1)
				(type default)
			)
			(layer "F.Fab")
		)
		(fp_line
			(start 0.12065 -0.2794)
			(end 0.12065 -0.3048)
			(stroke
				(width 0.1)
				(type default)
			)
			(layer "F.Fab")
		)
		(fp_line
			(start 0.67945 -0.3048)
			(end 0.67945 0.3048)
			(stroke
				(width 0.1)
				(type default)
			)
			(layer "F.Fab")
		)
		(fp_line
			(start 0.67945 0.3048)
			(end 0.120396 0.3048)
			(stroke
				(width 0.1)
				(type default)
			)
			(layer "F.Fab")
		)
		(pad "1" smd circle
			(at -0.40005 0)
			(size 0 0)
			(layers "F.Cu" "F.Mask" "F.Paste")
			(net "GND")
		)
		(pad "2" smd circle
			(at 0.40005 0)
			(size 0 0)
			(layers "F.Cu" "F.Mask" "F.Paste")
			(net "INA230_4_A1")
		)
	)
	(footprint ""
		(layer "F.Cu")
		(at 325.697342 -398.34058)
		(property "Reference" "R1370"
			(at 0 0 0)
			(layer "F.SilkS")
			(hide yes)
			(effects
				(font
					(size 1.27 1.27)
				)
			)
		)
		(property "Value" ""
			(at 0 0 0)
			(layer "F.Fab")
			(effects
				(font
					(size 1.27 1.27)
				)
			)
		)
		(duplicate_pad_numbers_are_jumpers no)
		(fp_line
			(start -0.32512 -0.175006)
			(end 0.32512 -0.175006)
			(stroke
				(width 0.1)
				(type default)
			)
			(layer "F.Fab")
		)
		(fp_line
			(start -0.32512 0.175006)
			(end -0.32512 -0.175006)
			(stroke
				(width 0.1)
				(type default)
			)
			(layer "F.Fab")
		)
		(fp_line
			(start 0.32512 -0.175006)
			(end 0.32512 0.175006)
			(stroke
				(width 0.1)
				(type default)
			)
			(layer "F.Fab")
		)
		(fp_line
			(start 0.32512 0.175006)
			(end -0.32512 0.175006)
			(stroke
				(width 0.1)
				(type default)
			)
			(layer "F.Fab")
		)
		(pad "1" smd rect
			(at -0.2667 0)
			(size 0.3048 0.381)
			(layers "F.Cu" "F.Mask" "F.Paste")
			(net "RXDET_BYP_RT_CPU0_P0")
		)
		(pad "2" smd rect
			(at 0.2667 0 180)
			(size 0.3048 0.381)
			(layers "F.Cu" "F.Mask" "F.Paste")
			(net "GND")
		)
	)
	(footprint ""
		(layer "F.Cu")
		(at 144.315688 -394.166852 -90)
		(property "Reference" "R867"
			(at 0 0 270)
			(layer "F.SilkS")
			(hide yes)
			(effects
				(font
					(size 1.27 1.27)
				)
			)
		)
		(property "Value" ""
			(at 0 0 270)
			(layer "F.Fab")
			(effects
				(font
					(size 1.27 1.27)
				)
			)
		)
		(duplicate_pad_numbers_are_jumpers no)
		(fp_line
			(start -0.32512 0.175006)
			(end -0.32512 -0.175006)
			(stroke
				(width 0.1)
				(type default)
			)
			(layer "F.Fab")
		)
		(fp_line
			(start 0.32512 0.175006)
			(end -0.32512 0.175006)
			(stroke
				(width 0.1)
				(type default)
			)
			(layer "F.Fab")
		)
		(fp_line
			(start -0.32512 -0.175006)
			(end 0.32512 -0.175006)
			(stroke
				(width 0.1)
				(type default)
			)
			(layer "F.Fab")
		)
		(fp_line
			(start 0.32512 -0.175006)
			(end 0.32512 0.175006)
			(stroke
				(width 0.1)
				(type default)
			)
			(layer "F.Fab")
		)
		(pad "1" smd rect
			(at -0.2667 0 270)
			(size 0.3048 0.381)
			(layers "F.Cu" "F.Mask" "F.Paste")
			(net "RST_RT_CPU1_P2_RESET_R_N")
		)
		(pad "2" smd rect
			(at 0.2667 0 90)
			(size 0.3048 0.381)
			(layers "F.Cu" "F.Mask" "F.Paste")
			(net "GND")
		)
	)
	(footprint ""
		(layer "F.Cu")
		(at 152.849326 -35.97656)
		(property "Reference" "R3264"
			(at 0 0 0)
			(layer "F.SilkS")
			(hide yes)
			(effects
				(font
					(size 1.27 1.27)
				)
			)
		)
		(property "Value" ""
			(at 0 0 0)
			(layer "F.Fab")
			(effects
				(font
					(size 1.27 1.27)
				)
			)
		)
		(duplicate_pad_numbers_are_jumpers no)
		(fp_line
			(start -0.7874 -0.4064)
			(end 0.7874 -0.4064)
			(stroke
				(width 0.1524)
				(type default)
			)
			(layer "F.SilkS")
		)
		(fp_line
			(start -0.7874 0.4064)
			(end -0.7874 -0.4064)
			(stroke
				(width 0.1524)
				(type default)
			)
			(layer "F.SilkS")
		)
		(fp_line
			(start 0.7874 -0.4064)
			(end 0.7874 0.4064)
			(stroke
				(width 0.1524)
				(type default)
			)
			(layer "F.SilkS")
		)
		(fp_line
			(start 0.7874 0.4064)
			(end -0.7874 0.4064)
			(stroke
				(width 0.1524)
				(type default)
			)
			(layer "F.SilkS")
		)
		(fp_line
			(start -0.67945 -0.305054)
			(end -0.12065 -0.305054)
			(stroke
				(width 0.1)
				(type default)
			)
			(layer "F.Fab")
		)
		(fp_line
			(start -0.67945 0.3048)
			(end -0.67945 -0.305054)
			(stroke
				(width 0.1)
				(type default)
			)
			(layer "F.Fab")
		)
		(fp_line
			(start -0.12065 -0.305054)
			(end -0.12065 -0.2794)
			(stroke
				(width 0.1)
				(type default)
			)
			(layer "F.Fab")
		)
		(fp_line
			(start -0.12065 -0.2794)
			(end 0.12065 -0.2794)
			(stroke
				(width 0.1)
				(type default)
			)
			(layer "F.Fab")
		)
		(fp_line
			(start -0.12065 0.2794)
			(end -0.12065 0.3048)
			(stroke
				(width 0.1)
				(type default)
			)
			(layer "F.Fab")
		)
		(fp_line
			(start -0.12065 0.3048)
			(end -0.67945 0.3048)
			(stroke
				(width 0.1)
				(type default)
			)
			(layer "F.Fab")
		)
		(fp_line
			(start 0.120396 0.2794)
			(end -0.12065 0.2794)
			(stroke
				(width 0.1)
				(type default)
			)
			(layer "F.Fab")
		)
		(fp_line
			(start 0.120396 0.3048)
			(end 0.120396 0.2794)
			(stroke
				(width 0.1)
				(type default)
			)
			(layer "F.Fab")
		)
		(fp_line
			(start 0.12065 -0.3048)
			(end 0.67945 -0.3048)
			(stroke
				(width 0.1)
				(type default)
			)
			(layer "F.Fab")
		)
		(fp_line
			(start 0.12065 -0.2794)
			(end 0.12065 -0.3048)
			(stroke
				(width 0.1)
				(type default)
			)
			(layer "F.Fab")
		)
		(fp_line
			(start 0.67945 -0.3048)
			(end 0.67945 0.3048)
			(stroke
				(width 0.1)
				(type default)
			)
			(layer "F.Fab")
		)
		(fp_line
			(start 0.67945 0.3048)
			(end 0.120396 0.3048)
			(stroke
				(width 0.1)
				(type default)
			)
			(layer "F.Fab")
		)
		(pad "1" smd circle
			(at -0.40005 0)
			(size 0 0)
			(layers "F.Cu" "F.Mask" "F.Paste")
			(net "HP_LVC3_OCP_V3_2_R_EN")
		)
		(pad "2" smd circle
			(at 0.40005 0)
			(size 0 0)
			(layers "F.Cu" "F.Mask" "F.Paste")
			(net "P3V3_OCP_V3_2_EN_R")
		)
	)
	(footprint ""
		(layer "F.Cu")
		(at 442.233558 -168.710864 180)
		(property "Reference" "R5016"
			(at 0 0 180)
			(layer "F.SilkS")
			(hide yes)
			(effects
				(font
					(size 1.27 1.27)
				)
			)
		)
		(property "Value" ""
			(at 0 0 180)
			(layer "F.Fab")
			(effects
				(font
					(size 1.27 1.27)
				)
			)
		)
		(duplicate_pad_numbers_are_jumpers no)
		(fp_line
			(start 0.7874 0.4064)
			(end -0.7874 0.4064)
			(stroke
				(width 0.1524)
				(type default)
			)
			(layer "F.SilkS")
		)
		(fp_line
			(start 0.7874 -0.4064)
			(end 0.7874 0.4064)
			(stroke
				(width 0.1524)
				(type default)
			)
			(layer "F.SilkS")
		)
		(fp_line
			(start -0.7874 0.4064)
			(end -0.7874 -0.4064)
			(stroke
				(width 0.1524)
				(type default)
			)
			(layer "F.SilkS")
		)
		(fp_line
			(start -0.7874 -0.4064)
			(end 0.7874 -0.4064)
			(stroke
				(width 0.1524)
				(type default)
			)
			(layer "F.SilkS")
		)
		(fp_line
			(start 0.67945 0.3048)
			(end 0.120396 0.3048)
			(stroke
				(width 0.1)
				(type default)
			)
			(layer "F.Fab")
		)
		(fp_line
			(start 0.67945 -0.3048)
			(end 0.67945 0.3048)
			(stroke
				(width 0.1)
				(type default)
			)
			(layer "F.Fab")
		)
		(fp_line
			(start 0.12065 -0.2794)
			(end 0.12065 -0.3048)
			(stroke
				(width 0.1)
				(type default)
			)
			(layer "F.Fab")
		)
		(fp_line
			(start 0.12065 -0.3048)
			(end 0.67945 -0.3048)
			(stroke
				(width 0.1)
				(type default)
			)
			(layer "F.Fab")
		)
		(fp_line
			(start 0.120396 0.3048)
			(end 0.120396 0.2794)
			(stroke
				(width 0.1)
				(type default)
			)
			(layer "F.Fab")
		)
		(fp_line
			(start 0.120396 0.2794)
			(end -0.12065 0.2794)
			(stroke
				(width 0.1)
				(type default)
			)
			(layer "F.Fab")
		)
		(fp_line
			(start -0.12065 0.3048)
			(end -0.67945 0.3048)
			(stroke
				(width 0.1)
				(type default)
			)
			(layer "F.Fab")
		)
		(fp_line
			(start -0.12065 0.2794)
			(end -0.12065 0.3048)
			(stroke
				(width 0.1)
				(type default)
			)
			(layer "F.Fab")
		)
		(fp_line
			(start -0.12065 -0.2794)
			(end 0.12065 -0.2794)
			(stroke
				(width 0.1)
				(type default)
			)
			(layer "F.Fab")
		)
		(fp_line
			(start -0.12065 -0.305054)
			(end -0.12065 -0.2794)
			(stroke
				(width 0.1)
				(type default)
			)
			(layer "F.Fab")
		)
		(fp_line
			(start -0.67945 0.3048)
			(end -0.67945 -0.305054)
			(stroke
				(width 0.1)
				(type default)
			)
			(layer "F.Fab")
		)
		(fp_line
			(start -0.67945 -0.305054)
			(end -0.12065 -0.305054)
			(stroke
				(width 0.1)
				(type default)
			)
			(layer "F.Fab")
		)
		(pad "1" smd circle
			(at -0.40005 0 180)
			(size 0 0)
			(layers "F.Cu" "F.Mask" "F.Paste")
			(net "PVDD11_S3_P0")
		)
		(pad "2" smd circle
			(at 0.40005 0 180)
			(size 0 0)
			(layers "F.Cu" "F.Mask" "F.Paste")
			(net "I3C_SCM_1_R_SCL")
		)
	)
	(footprint ""
		(layer "F.Cu")
		(at 281.659076 -412.452058 90)
		(property "Reference" "L20"
			(at 0 0 90)
			(layer "F.SilkS")
			(hide yes)
			(effects
				(font
					(size 1.27 1.27)
				)
			)
		)
		(property "Value" ""
			(at 0 0 90)
			(layer "F.Fab")
			(effects
				(font
					(size 1.27 1.27)
				)
			)
		)
		(duplicate_pad_numbers_are_jumpers no)
		(fp_line
			(start 1.63576 -0.8128)
			(end 1.63576 0.8128)
			(stroke
				(width 0.1524)
				(type default)
			)
			(layer "F.SilkS")
		)
		(fp_line
			(start -1.63576 -0.8128)
			(end 1.63576 -0.8128)
			(stroke
				(width 0.1524)
				(type default)
			)
			(layer "F.SilkS")
		)
		(fp_line
			(start -1.63576 -0.8128)
			(end -1.63576 0.8128)
			(stroke
				(width 0.1524)
				(type default)
			)
			(layer "F.SilkS")
		)
		(fp_line
			(start 1.63576 0.8128)
			(end -1.63576 0.8128)
			(stroke
				(width 0.1524)
				(type default)
			)
			(layer "F.SilkS")
		)
		(fp_line
			(start 1.560576 -0.738632)
			(end -1.56083 -0.738632)
			(stroke
				(width 0.1)
				(type default)
			)
			(layer "F.Fab")
		)
		(fp_line
			(start -1.56083 -0.738632)
			(end -1.56083 0.7366)
			(stroke
				(width 0.1)
				(type default)
			)
			(layer "F.Fab")
		)
		(fp_line
			(start 1.560576 0.7366)
			(end 1.560576 -0.738632)
			(stroke
				(width 0.1)
				(type default)
			)
			(layer "F.Fab")
		)
		(fp_line
			(start 1.524 0.7366)
			(end 1.560576 0.7366)
			(stroke
				(width 0.1)
				(type default)
			)
			(layer "F.Fab")
		)
		(fp_line
			(start -1.524 0.7366)
			(end 1.524 0.7366)
			(stroke
				(width 0.1)
				(type default)
			)
			(layer "F.Fab")
		)
		(fp_line
			(start -1.56083 0.7366)
			(end -1.524 0.7366)
			(stroke
				(width 0.1)
				(type default)
			)
			(layer "F.Fab")
		)
		(pad "1" smd rect
			(at -0.94996 0 270)
			(size 1.1176 1.3716)
			(layers "F.Cu" "F.Mask" "F.Paste")
			(net "P3V3_AUX")
		)
		(pad "2" smd rect
			(at 0.94996 0 270)
			(size 1.1176 1.3716)
			(layers "F.Cu" "F.Mask" "F.Paste")
			(net "P3V3_9ZXL045_P0_VDD")
		)
	)
	(footprint ""
		(layer "F.Cu")
		(at 419.96106 -351.11309 -90)
		(property "Reference" "PC205_11P0_1"
			(at 0 0 270)
			(layer "F.SilkS")
			(hide yes)
			(effects
				(font
					(size 1.27 1.27)
				)
			)
		)
		(property "Value" ""
			(at 0 0 270)
			(layer "F.Fab")
			(effects
				(font
					(size 1.27 1.27)
				)
			)
		)
		(duplicate_pad_numbers_are_jumpers no)
		(fp_line
			(start -0.7874 0.4064)
			(end -0.7874 -0.4064)
			(stroke
				(width 0.1524)
				(type default)
			)
			(layer "F.SilkS")
		)
		(fp_line
			(start 0.7874 0.4064)
			(end -0.7874 0.4064)
			(stroke
				(width 0.1524)
				(type default)
			)
			(layer "F.SilkS")
		)
		(fp_line
			(start -0.7874 -0.4064)
			(end 0.7874 -0.4064)
			(stroke
				(width 0.1524)
				(type default)
			)
			(layer "F.SilkS")
		)
		(fp_line
			(start 0.7874 -0.4064)
			(end 0.7874 0.4064)
			(stroke
				(width 0.1524)
				(type default)
			)
			(layer "F.SilkS")
		)
		(fp_line
			(start -0.67945 0.3048)
			(end -0.67945 -0.305054)
			(stroke
				(width 0.1)
				(type default)
			)
			(layer "F.Fab")
		)
		(fp_line
			(start -0.12065 0.3048)
			(end -0.67945 0.3048)
			(stroke
				(width 0.1)
				(type default)
			)
			(layer "F.Fab")
		)
		(fp_line
			(start 0.120396 0.3048)
			(end 0.120396 0.2794)
			(stroke
				(width 0.1)
				(type default)
			)
			(layer "F.Fab")
		)
		(fp_line
			(start 0.67945 0.3048)
			(end 0.120396 0.3048)
			(stroke
				(width 0.1)
				(type default)
			)
			(layer "F.Fab")
		)
		(fp_line
			(start -0.12065 0.2794)
			(end -0.12065 0.3048)
			(stroke
				(width 0.1)
				(type default)
			)
			(layer "F.Fab")
		)
		(fp_line
			(start 0.120396 0.2794)
			(end -0.12065 0.2794)
			(stroke
				(width 0.1)
				(type default)
			)
			(layer "F.Fab")
		)
		(fp_line
			(start -0.12065 -0.2794)
			(end 0.12065 -0.2794)
			(stroke
				(width 0.1)
				(type default)
			)
			(layer "F.Fab")
		)
		(fp_line
			(start 0.12065 -0.2794)
			(end 0.12065 -0.3048)
			(stroke
				(width 0.1)
				(type default)
			)
			(layer "F.Fab")
		)
		(fp_line
			(start 0.12065 -0.3048)
			(end 0.67945 -0.3048)
			(stroke
				(width 0.1)
				(type default)
			)
			(layer "F.Fab")
		)
		(fp_line
			(start 0.67945 -0.3048)
			(end 0.67945 0.3048)
			(stroke
				(width 0.1)
				(type default)
			)
			(layer "F.Fab")
		)
		(fp_line
			(start -0.67945 -0.305054)
			(end -0.12065 -0.305054)
			(stroke
				(width 0.1)
				(type default)
			)
			(layer "F.Fab")
		)
		(fp_line
			(start -0.12065 -0.305054)
			(end -0.12065 -0.2794)
			(stroke
				(width 0.1)
				(type default)
			)
			(layer "F.Fab")
		)
		(pad "1" smd circle
			(at -0.40005 0 270)
			(size 0 0)
			(layers "F.Cu" "F.Mask" "F.Paste")
			(net "PVDD11_S3_P0_PVCC")
		)
		(pad "2" smd circle
			(at 0.40005 0 270)
			(size 0 0)
			(layers "F.Cu" "F.Mask" "F.Paste")
			(net "GND")
		)
	)
	(footprint ""
		(layer "F.Cu")
		(at 257.683 -142.367)
		(property "Reference" "R21"
			(at 0 0 0)
			(layer "F.SilkS")
			(hide yes)
			(effects
				(font
					(size 1.27 1.27)
				)
			)
		)
		(property "Value" ""
			(at 0 0 0)
			(layer "F.Fab")
			(effects
				(font
					(size 1.27 1.27)
				)
			)
		)
		(duplicate_pad_numbers_are_jumpers no)
		(fp_line
			(start -0.7874 -0.4064)
			(end 0.7874 -0.4064)
			(stroke
				(width 0.1524)
				(type default)
			)
			(layer "F.SilkS")
		)
		(fp_line
			(start -0.7874 0.4064)
			(end -0.7874 -0.4064)
			(stroke
				(width 0.1524)
				(type default)
			)
			(layer "F.SilkS")
		)
		(fp_line
			(start 0.7874 -0.4064)
			(end 0.7874 0.4064)
			(stroke
				(width 0.1524)
				(type default)
			)
			(layer "F.SilkS")
		)
		(fp_line
			(start 0.7874 0.4064)
			(end -0.7874 0.4064)
			(stroke
				(width 0.1524)
				(type default)
			)
			(layer "F.SilkS")
		)
		(fp_line
			(start -0.67945 -0.305054)
			(end -0.12065 -0.305054)
			(stroke
				(width 0.1)
				(type default)
			)
			(layer "F.Fab")
		)
		(fp_line
			(start -0.67945 0.3048)
			(end -0.67945 -0.305054)
			(stroke
				(width 0.1)
				(type default)
			)
			(layer "F.Fab")
		)
		(fp_line
			(start -0.12065 -0.305054)
			(end -0.12065 -0.2794)
			(stroke
				(width 0.1)
				(type default)
			)
			(layer "F.Fab")
		)
		(fp_line
			(start -0.12065 -0.2794)
			(end 0.12065 -0.2794)
			(stroke
				(width 0.1)
				(type default)
			)
			(layer "F.Fab")
		)
		(fp_line
			(start -0.12065 0.2794)
			(end -0.12065 0.3048)
			(stroke
				(width 0.1)
				(type default)
			)
			(layer "F.Fab")
		)
		(fp_line
			(start -0.12065 0.3048)
			(end -0.67945 0.3048)
			(stroke
				(width 0.1)
				(type default)
			)
			(layer "F.Fab")
		)
		(fp_line
			(start 0.120396 0.2794)
			(end -0.12065 0.2794)
			(stroke
				(width 0.1)
				(type default)
			)
			(layer "F.Fab")
		)
		(fp_line
			(start 0.120396 0.3048)
			(end 0.120396 0.2794)
			(stroke
				(width 0.1)
				(type default)
			)
			(layer "F.Fab")
		)
		(fp_line
			(start 0.12065 -0.3048)
			(end 0.67945 -0.3048)
			(stroke
				(width 0.1)
				(type default)
			)
			(layer "F.Fab")
		)
		(fp_line
			(start 0.12065 -0.2794)
			(end 0.12065 -0.3048)
			(stroke
				(width 0.1)
				(type default)
			)
			(layer "F.Fab")
		)
		(fp_line
			(start 0.67945 -0.3048)
			(end 0.67945 0.3048)
			(stroke
				(width 0.1)
				(type default)
			)
			(layer "F.Fab")
		)
		(fp_line
			(start 0.67945 0.3048)
			(end 0.120396 0.3048)
			(stroke
				(width 0.1)
				(type default)
			)
			(layer "F.Fab")
		)
		(pad "1" smd circle
			(at -0.40005 0)
			(size 0 0)
			(layers "F.Cu" "F.Mask" "F.Paste")
			(net "P3V3_AUX")
		)
		(pad "2" smd circle
			(at 0.40005 0)
			(size 0 0)
			(layers "F.Cu" "F.Mask" "F.Paste")
			(net "SPI_CPU0_LVC3_SCM_D0")
		)
	)
	(footprint ""
		(layer "F.Cu")
		(at 146.304762 -43.03141 180)
		(property "Reference" "R2411"
			(at 0 0 180)
			(layer "F.SilkS")
			(hide yes)
			(effects
				(font
					(size 1.27 1.27)
				)
			)
		)
		(property "Value" ""
			(at 0 0 180)
			(layer "F.Fab")
			(effects
				(font
					(size 1.27 1.27)
				)
			)
		)
		(duplicate_pad_numbers_are_jumpers no)
		(fp_line
			(start 0.7874 0.4064)
			(end -0.7874 0.4064)
			(stroke
				(width 0.1524)
				(type default)
			)
			(layer "F.SilkS")
		)
		(fp_line
			(start 0.7874 -0.4064)
			(end 0.7874 0.4064)
			(stroke
				(width 0.1524)
				(type default)
			)
			(layer "F.SilkS")
		)
		(fp_line
			(start -0.7874 0.4064)
			(end -0.7874 -0.4064)
			(stroke
				(width 0.1524)
				(type default)
			)
			(layer "F.SilkS")
		)
		(fp_line
			(start -0.7874 -0.4064)
			(end 0.7874 -0.4064)
			(stroke
				(width 0.1524)
				(type default)
			)
			(layer "F.SilkS")
		)
		(fp_line
			(start 0.67945 0.3048)
			(end 0.120396 0.3048)
			(stroke
				(width 0.1)
				(type default)
			)
			(layer "F.Fab")
		)
		(fp_line
			(start 0.67945 -0.3048)
			(end 0.67945 0.3048)
			(stroke
				(width 0.1)
				(type default)
			)
			(layer "F.Fab")
		)
		(fp_line
			(start 0.12065 -0.2794)
			(end 0.12065 -0.3048)
			(stroke
				(width 0.1)
				(type default)
			)
			(layer "F.Fab")
		)
		(fp_line
			(start 0.12065 -0.3048)
			(end 0.67945 -0.3048)
			(stroke
				(width 0.1)
				(type default)
			)
			(layer "F.Fab")
		)
		(fp_line
			(start 0.120396 0.3048)
			(end 0.120396 0.2794)
			(stroke
				(width 0.1)
				(type default)
			)
			(layer "F.Fab")
		)
		(fp_line
			(start 0.120396 0.2794)
			(end -0.12065 0.2794)
			(stroke
				(width 0.1)
				(type default)
			)
			(layer "F.Fab")
		)
		(fp_line
			(start -0.12065 0.3048)
			(end -0.67945 0.3048)
			(stroke
				(width 0.1)
				(type default)
			)
			(layer "F.Fab")
		)
		(fp_line
			(start -0.12065 0.2794)
			(end -0.12065 0.3048)
			(stroke
				(width 0.1)
				(type default)
			)
			(layer "F.Fab")
		)
		(fp_line
			(start -0.12065 -0.2794)
			(end 0.12065 -0.2794)
			(stroke
				(width 0.1)
				(type default)
			)
			(layer "F.Fab")
		)
		(fp_line
			(start -0.12065 -0.305054)
			(end -0.12065 -0.2794)
			(stroke
				(width 0.1)
				(type default)
			)
			(layer "F.Fab")
		)
		(fp_line
			(start -0.67945 0.3048)
			(end -0.67945 -0.305054)
			(stroke
				(width 0.1)
				(type default)
			)
			(layer "F.Fab")
		)
		(fp_line
			(start -0.67945 -0.305054)
			(end -0.12065 -0.305054)
			(stroke
				(width 0.1)
				(type default)
			)
			(layer "F.Fab")
		)
		(pad "1" smd circle
			(at -0.40005 0 180)
			(size 0 0)
			(layers "F.Cu" "F.Mask" "F.Paste")
			(net "SMB_M2_P1_1V8AUX_SCL_R")
		)
		(pad "2" smd circle
			(at 0.40005 0 180)
			(size 0 0)
			(layers "F.Cu" "F.Mask" "F.Paste")
			(net "SMB_M2_P1_1V8AUX_SCL")
		)
	)
	(footprint ""
		(layer "F.Cu")
		(at 458.3811 -423.492168)
		(property "Reference" "H27"
			(at 2.5654 2.321052 0)
			(unlocked yes)
			(layer "F.SilkS")
			(effects
				(font
					(size 0.7874 0.5842)
					(thickness 0.1524)
				)
				(justify left)
			)
		)
		(property "Value" ""
			(at 0 0 0)
			(layer "F.Fab")
			(effects
				(font
					(size 1.27 1.27)
				)
			)
		)
		(duplicate_pad_numbers_are_jumpers no)
		(fp_circle
			(center 0 0)
			(end 2.4003 0)
			(stroke
				(width 0.1524)
				(type default)
			)
			(fill no)
			(layer "F.SilkS")
		)
		(fp_circle
			(center 0 0)
			(end 6.5913 0)
			(stroke
				(width 0.1524)
				(type default)
			)
			(fill no)
			(layer "B.SilkS")
		)
		(fp_circle
			(center 0 0)
			(end 6.5913 0)
			(stroke
				(width 0.1)
				(type default)
			)
			(fill no)
			(layer "B.Fab")
		)
		(fp_circle
			(center 0 0)
			(end 2.4003 0)
			(stroke
				(width 0.1)
				(type default)
			)
			(fill no)
			(layer "F.Fab")
		)
		(pad "" np_thru_hole circle
			(at 0 0)
			(size 3.175 3.175)
			(drill 3.175)
			(layers "*.Cu" "*.Mask")
			(clearance 0.381)
			(thermal_gap 0.381)
		)
		(zone
			(layers "F.Cu" "B.Cu" "In1.Cu" "In2.Cu" "In3.Cu" "In4.Cu" "In5.Cu" "In6.Cu"
				"In7.Cu" "In8.Cu" "In9.Cu" "In10.Cu" "In11.Cu" "In12.Cu" "In13.Cu" "In14.Cu"
				"In15.Cu" "In16.Cu"
			)
			(hatch none 0.5)
			(connect_pads
				(clearance 0)
			)
			(min_thickness 0.25)
			(keepout
				(tracks not_allowed)
				(vias allowed)
				(pads allowed)
				(copperpour not_allowed)
				(footprints allowed)
			)
			(placement
				(enabled no)
				(sheetname "")
			)
			(fill
				(thermal_gap 0.5)
				(thermal_bridge_width 0.5)
				(island_removal_mode 0)
			)
			(polygon
				(pts
					(arc
						(start 460.4766 -423.492168)
						(mid 456.2856 -423.492168)
						(end 460.4766 -423.492168)
					)
				)
			)
		)
	)
	(footprint ""
		(layer "F.Cu")
		(at 192.324736 -437.584088)
		(property "Reference" "JP10"
			(at -1.4097 -2.009648 0)
			(unlocked yes)
			(layer "F.SilkS")
			(effects
				(font
					(size 0.7874 0.5842)
					(thickness 0.1524)
				)
				(justify left)
			)
		)
		(property "Value" ""
			(at 0 0 0)
			(layer "F.Fab")
			(effects
				(font
					(size 1.27 1.27)
				)
			)
		)
		(duplicate_pad_numbers_are_jumpers no)
		(fp_line
			(start -1.249934 -1.320038)
			(end 1.249934 -1.320038)
			(stroke
				(width 0.1524)
				(type default)
			)
			(layer "F.SilkS")
		)
		(fp_line
			(start -1.249934 6.400038)
			(end -1.249934 -1.320038)
			(stroke
				(width 0.1524)
				(type default)
			)
			(layer "F.SilkS")
		)
		(fp_line
			(start 1.249934 -1.320038)
			(end 1.249934 6.400038)
			(stroke
				(width 0.1524)
				(type default)
			)
			(layer "F.SilkS")
		)
		(fp_line
			(start 1.249934 6.400038)
			(end -1.249934 6.400038)
			(stroke
				(width 0.1524)
				(type default)
			)
			(layer "F.SilkS")
		)
		(fp_poly
			(pts
				(xy -2.5654 0.556514) (xy -2.5654 -0.556514) (xy -1.452372 0)
			)
			(stroke
				(width 0)
				(type default)
			)
			(fill yes)
			(layer "F.SilkS")
		)
		(fp_line
			(start -1.249934 -1.320038)
			(end 1.249934 -1.320038)
			(stroke
				(width 0.1)
				(type default)
			)
			(layer "F.Fab")
		)
		(fp_line
			(start -1.249934 6.400038)
			(end -1.249934 -1.320038)
			(stroke
				(width 0.1)
				(type default)
			)
			(layer "F.Fab")
		)
		(fp_line
			(start 1.249934 -1.320038)
			(end 1.249934 6.400038)
			(stroke
				(width 0.1)
				(type default)
			)
			(layer "F.Fab")
		)
		(fp_line
			(start 1.249934 6.400038)
			(end -1.249934 6.400038)
			(stroke
				(width 0.1)
				(type default)
			)
			(layer "F.Fab")
		)
		(fp_poly
			(pts
				(xy -2.5654 -0.556514) (xy -1.452372 0) (xy -2.5654 0.556514)
			)
			(stroke
				(width 0)
				(type default)
			)
			(fill yes)
			(layer "F.Fab")
		)
		(fp_text user "3"
			(at -1.778 5.13207 0)
			(unlocked yes)
			(layer "F.SilkS")
			(effects
				(font
					(size 0.7874 0.5842)
					(thickness 0.1524)
				)
			)
		)
		(fp_text user "1"
			(at -1.477264 0.136398 0)
			(unlocked yes)
			(layer "B.SilkS")
			(effects
				(font
					(size 0.7874 0.5842)
					(thickness 0.1524)
				)
				(justify mirror)
			)
		)
		(fp_text user "3"
			(at -1.411732 5.289296 0)
			(unlocked yes)
			(layer "B.SilkS")
			(effects
				(font
					(size 0.7874 0.5842)
					(thickness 0.1524)
				)
				(justify mirror)
			)
		)
		(fp_text user "3"
			(at -1.1557 5.18287 0)
			(unlocked yes)
			(layer "B.Fab")
			(effects
				(font
					(size 0.7874 0.5842)
					(thickness 0.1524)
				)
				(justify mirror)
			)
		)
		(fp_text user "1"
			(at -1.143 0.02667 0)
			(unlocked yes)
			(layer "B.Fab")
			(effects
				(font
					(size 0.7874 0.5842)
					(thickness 0.1524)
				)
				(justify mirror)
			)
		)
		(fp_text user "3"
			(at -1.778 5.13207 0)
			(unlocked yes)
			(layer "F.Fab")
			(effects
				(font
					(size 0.7874 0.5842)
					(thickness 0.1524)
				)
			)
		)
		(pad "1" thru_hole rect
			(at 0 0)
			(size 1.5494 1.5494)
			(drill 1.0414)
			(layers "*.Cu" "*.Mask")
			(remove_unused_layers no)
			(net "SMB_SML1_PMBUS_HSC_R1_SCL")
			(clearance 0)
			(padstack
				(mode front_inner_back)
				(layer "Inner"
					(shape circle)
					(size 1.5494 1.5494)
					(clearance 0)
				)
				(layer "B.Cu"
					(shape rect)
					(size 1.5494 1.5494)
					(clearance 0)
				)
			)
		)
		(pad "2" thru_hole circle
			(at 0 2.54)
			(size 1.5494 1.5494)
			(drill 1.0414)
			(layers "*.Cu" "*.Mask")
			(remove_unused_layers no)
			(net "SMB_SML1_PMBUS_HSC_R1_SDA")
			(clearance 0)
		)
		(pad "3" thru_hole circle
			(at 0 5.08)
			(size 1.5494 1.5494)
			(drill 1.0414)
			(layers "*.Cu" "*.Mask")
			(remove_unused_layers no)
			(net "GND")
			(clearance 0)
		)
	)
	(footprint ""
		(layer "F.Cu")
		(at 393.148058 -177.04562 90)
		(property "Reference" "PC583_1"
			(at 0 0 90)
			(layer "F.SilkS")
			(hide yes)
			(effects
				(font
					(size 1.27 1.27)
				)
			)
		)
		(property "Value" ""
			(at 0 0 90)
			(layer "F.Fab")
			(effects
				(font
					(size 1.27 1.27)
				)
			)
		)
		(duplicate_pad_numbers_are_jumpers no)
		(fp_line
			(start 0.7874 -0.4064)
			(end 0.7874 0.4064)
			(stroke
				(width 0.1524)
				(type default)
			)
			(layer "F.SilkS")
		)
		(fp_line
			(start -0.7874 -0.4064)
			(end 0.7874 -0.4064)
			(stroke
				(width 0.1524)
				(type default)
			)
			(layer "F.SilkS")
		)
		(fp_line
			(start 0.7874 0.4064)
			(end -0.7874 0.4064)
			(stroke
				(width 0.1524)
				(type default)
			)
			(layer "F.SilkS")
		)
		(fp_line
			(start -0.7874 0.4064)
			(end -0.7874 -0.4064)
			(stroke
				(width 0.1524)
				(type default)
			)
			(layer "F.SilkS")
		)
		(fp_line
			(start -0.12065 -0.305054)
			(end -0.12065 -0.2794)
			(stroke
				(width 0.1)
				(type default)
			)
			(layer "F.Fab")
		)
		(fp_line
			(start -0.67945 -0.305054)
			(end -0.12065 -0.305054)
			(stroke
				(width 0.1)
				(type default)
			)
			(layer "F.Fab")
		)
		(fp_line
			(start 0.67945 -0.3048)
			(end 0.67945 0.3048)
			(stroke
				(width 0.1)
				(type default)
			)
			(layer "F.Fab")
		)
		(fp_line
			(start 0.12065 -0.3048)
			(end 0.67945 -0.3048)
			(stroke
				(width 0.1)
				(type default)
			)
			(layer "F.Fab")
		)
		(fp_line
			(start 0.12065 -0.2794)
			(end 0.12065 -0.3048)
			(stroke
				(width 0.1)
				(type default)
			)
			(layer "F.Fab")
		)
		(fp_line
			(start -0.12065 -0.2794)
			(end 0.12065 -0.2794)
			(stroke
				(width 0.1)
				(type default)
			)
			(layer "F.Fab")
		)
		(fp_line
			(start 0.120396 0.2794)
			(end -0.12065 0.2794)
			(stroke
				(width 0.1)
				(type default)
			)
			(layer "F.Fab")
		)
		(fp_line
			(start -0.12065 0.2794)
			(end -0.12065 0.3048)
			(stroke
				(width 0.1)
				(type default)
			)
			(layer "F.Fab")
		)
		(fp_line
			(start 0.67945 0.3048)
			(end 0.120396 0.3048)
			(stroke
				(width 0.1)
				(type default)
			)
			(layer "F.Fab")
		)
		(fp_line
			(start 0.120396 0.3048)
			(end 0.120396 0.2794)
			(stroke
				(width 0.1)
				(type default)
			)
			(layer "F.Fab")
		)
		(fp_line
			(start -0.12065 0.3048)
			(end -0.67945 0.3048)
			(stroke
				(width 0.1)
				(type default)
			)
			(layer "F.Fab")
		)
		(fp_line
			(start -0.67945 0.3048)
			(end -0.67945 -0.305054)
			(stroke
				(width 0.1)
				(type default)
			)
			(layer "F.Fab")
		)
		(pad "1" smd circle
			(at -0.40005 0 90)
			(size 0 0)
			(layers "F.Cu" "F.Mask" "F.Paste")
			(net "SW_P12V_AUX_PVDDCR_SOC_P0_FLT")
		)
		(pad "2" smd circle
			(at 0.40005 0 90)
			(size 0 0)
			(layers "F.Cu" "F.Mask" "F.Paste")
			(net "GND")
		)
	)
	(footprint ""
		(layer "F.Cu")
		(at 136.531096 -370.57203 -90)
		(property "Reference" "C52"
			(at 0 0 270)
			(layer "F.SilkS")
			(hide yes)
			(effects
				(font
					(size 1.27 1.27)
				)
			)
		)
		(property "Value" ""
			(at 0 0 270)
			(layer "F.Fab")
			(effects
				(font
					(size 1.27 1.27)
				)
			)
		)
		(duplicate_pad_numbers_are_jumpers no)
		(fp_line
			(start -0.299974 0.150114)
			(end -0.299974 -0.150114)
			(stroke
				(width 0.1)
				(type default)
			)
			(layer "F.Fab")
		)
		(fp_line
			(start 0.299974 0.150114)
			(end -0.299974 0.150114)
			(stroke
				(width 0.1)
				(type default)
			)
			(layer "F.Fab")
		)
		(fp_line
			(start -0.299974 -0.150114)
			(end 0.299974 -0.150114)
			(stroke
				(width 0.1)
				(type default)
			)
			(layer "F.Fab")
		)
		(fp_line
			(start 0.299974 -0.150114)
			(end 0.299974 0.150114)
			(stroke
				(width 0.1)
				(type default)
			)
			(layer "F.Fab")
		)
		(pad "1" smd rect
			(at -0.2667 0 270)
			(size 0.3048 0.381)
			(layers "F.Cu" "F.Mask" "F.Paste")
			(net "P5E_CPU1_P3_TX_C_DN<13>")
		)
		(pad "2" smd rect
			(at 0.2667 0 270)
			(size 0.3048 0.381)
			(layers "F.Cu" "F.Mask" "F.Paste")
			(net "P5E_CPU1_P3_TX_DN<13>")
		)
	)
	(footprint ""
		(layer "F.Cu")
		(at 72.463914 -147.649692 180)
		(property "Reference" "PR148"
			(at 0 0 180)
			(layer "F.SilkS")
			(hide yes)
			(effects
				(font
					(size 1.27 1.27)
				)
			)
		)
		(property "Value" ""
			(at 0 0 180)
			(layer "F.Fab")
			(effects
				(font
					(size 1.27 1.27)
				)
			)
		)
		(duplicate_pad_numbers_are_jumpers no)
		(fp_line
			(start 0.7874 0.4064)
			(end -0.7874 0.4064)
			(stroke
				(width 0.1524)
				(type default)
			)
			(layer "F.SilkS")
		)
		(fp_line
			(start 0.7874 -0.4064)
			(end 0.7874 0.4064)
			(stroke
				(width 0.1524)
				(type default)
			)
			(layer "F.SilkS")
		)
		(fp_line
			(start -0.7874 0.4064)
			(end -0.7874 -0.4064)
			(stroke
				(width 0.1524)
				(type default)
			)
			(layer "F.SilkS")
		)
		(fp_line
			(start -0.7874 -0.4064)
			(end 0.7874 -0.4064)
			(stroke
				(width 0.1524)
				(type default)
			)
			(layer "F.SilkS")
		)
		(fp_line
			(start 0.67945 0.3048)
			(end 0.120396 0.3048)
			(stroke
				(width 0.1)
				(type default)
			)
			(layer "F.Fab")
		)
		(fp_line
			(start 0.67945 -0.3048)
			(end 0.67945 0.3048)
			(stroke
				(width 0.1)
				(type default)
			)
			(layer "F.Fab")
		)
		(fp_line
			(start 0.12065 -0.2794)
			(end 0.12065 -0.3048)
			(stroke
				(width 0.1)
				(type default)
			)
			(layer "F.Fab")
		)
		(fp_line
			(start 0.12065 -0.3048)
			(end 0.67945 -0.3048)
			(stroke
				(width 0.1)
				(type default)
			)
			(layer "F.Fab")
		)
		(fp_line
			(start 0.120396 0.3048)
			(end 0.120396 0.2794)
			(stroke
				(width 0.1)
				(type default)
			)
			(layer "F.Fab")
		)
		(fp_line
			(start 0.120396 0.2794)
			(end -0.12065 0.2794)
			(stroke
				(width 0.1)
				(type default)
			)
			(layer "F.Fab")
		)
		(fp_line
			(start -0.12065 0.3048)
			(end -0.67945 0.3048)
			(stroke
				(width 0.1)
				(type default)
			)
			(layer "F.Fab")
		)
		(fp_line
			(start -0.12065 0.2794)
			(end -0.12065 0.3048)
			(stroke
				(width 0.1)
				(type default)
			)
			(layer "F.Fab")
		)
		(fp_line
			(start -0.12065 -0.2794)
			(end 0.12065 -0.2794)
			(stroke
				(width 0.1)
				(type default)
			)
			(layer "F.Fab")
		)
		(fp_line
			(start -0.12065 -0.305054)
			(end -0.12065 -0.2794)
			(stroke
				(width 0.1)
				(type default)
			)
			(layer "F.Fab")
		)
		(fp_line
			(start -0.67945 0.3048)
			(end -0.67945 -0.305054)
			(stroke
				(width 0.1)
				(type default)
			)
			(layer "F.Fab")
		)
		(fp_line
			(start -0.67945 -0.305054)
			(end -0.12065 -0.305054)
			(stroke
				(width 0.1)
				(type default)
			)
			(layer "F.Fab")
		)
		(pad "1" smd circle
			(at -0.40005 0 180)
			(size 0 0)
			(layers "F.Cu" "F.Mask" "F.Paste")
			(net "PVDD18_S5_P1_FB")
		)
		(pad "2" smd circle
			(at 0.40005 0 180)
			(size 0 0)
			(layers "F.Cu" "F.Mask" "F.Paste")
			(net "PVDD18_S5_P1_FB_RC")
		)
	)
	(footprint ""
		(layer "F.Cu")
		(at 71.235824 -18.932144 180)
		(property "Reference" "R1291"
			(at 0 0 180)
			(layer "F.SilkS")
			(hide yes)
			(effects
				(font
					(size 1.27 1.27)
				)
			)
		)
		(property "Value" ""
			(at 0 0 180)
			(layer "F.Fab")
			(effects
				(font
					(size 1.27 1.27)
				)
			)
		)
		(duplicate_pad_numbers_are_jumpers no)
		(fp_line
			(start 0.7874 0.4064)
			(end -0.7874 0.4064)
			(stroke
				(width 0.1524)
				(type default)
			)
			(layer "F.SilkS")
		)
		(fp_line
			(start 0.7874 -0.4064)
			(end 0.7874 0.4064)
			(stroke
				(width 0.1524)
				(type default)
			)
			(layer "F.SilkS")
		)
		(fp_line
			(start -0.7874 0.4064)
			(end -0.7874 -0.4064)
			(stroke
				(width 0.1524)
				(type default)
			)
			(layer "F.SilkS")
		)
		(fp_line
			(start -0.7874 -0.4064)
			(end 0.7874 -0.4064)
			(stroke
				(width 0.1524)
				(type default)
			)
			(layer "F.SilkS")
		)
		(fp_line
			(start 0.67945 0.3048)
			(end 0.120396 0.3048)
			(stroke
				(width 0.1)
				(type default)
			)
			(layer "F.Fab")
		)
		(fp_line
			(start 0.67945 -0.3048)
			(end 0.67945 0.3048)
			(stroke
				(width 0.1)
				(type default)
			)
			(layer "F.Fab")
		)
		(fp_line
			(start 0.12065 -0.2794)
			(end 0.12065 -0.3048)
			(stroke
				(width 0.1)
				(type default)
			)
			(layer "F.Fab")
		)
		(fp_line
			(start 0.12065 -0.3048)
			(end 0.67945 -0.3048)
			(stroke
				(width 0.1)
				(type default)
			)
			(layer "F.Fab")
		)
		(fp_line
			(start 0.120396 0.3048)
			(end 0.120396 0.2794)
			(stroke
				(width 0.1)
				(type default)
			)
			(layer "F.Fab")
		)
		(fp_line
			(start 0.120396 0.2794)
			(end -0.12065 0.2794)
			(stroke
				(width 0.1)
				(type default)
			)
			(layer "F.Fab")
		)
		(fp_line
			(start -0.12065 0.3048)
			(end -0.67945 0.3048)
			(stroke
				(width 0.1)
				(type default)
			)
			(layer "F.Fab")
		)
		(fp_line
			(start -0.12065 0.2794)
			(end -0.12065 0.3048)
			(stroke
				(width 0.1)
				(type default)
			)
			(layer "F.Fab")
		)
		(fp_line
			(start -0.12065 -0.2794)
			(end 0.12065 -0.2794)
			(stroke
				(width 0.1)
				(type default)
			)
			(layer "F.Fab")
		)
		(fp_line
			(start -0.12065 -0.305054)
			(end -0.12065 -0.2794)
			(stroke
				(width 0.1)
				(type default)
			)
			(layer "F.Fab")
		)
		(fp_line
			(start -0.67945 0.3048)
			(end -0.67945 -0.305054)
			(stroke
				(width 0.1)
				(type default)
			)
			(layer "F.Fab")
		)
		(fp_line
			(start -0.67945 -0.305054)
			(end -0.12065 -0.305054)
			(stroke
				(width 0.1)
				(type default)
			)
			(layer "F.Fab")
		)
		(pad "1" smd circle
			(at -0.40005 0 180)
			(size 0 0)
			(layers "F.Cu" "F.Mask" "F.Paste")
			(net "P12V_OCP_V3_2")
		)
		(pad "2" smd circle
			(at 0.40005 0 180)
			(size 0 0)
			(layers "F.Cu" "F.Mask" "F.Paste")
			(net "VSENSE_P12V_INA230_7_INP")
		)
	)
	(footprint ""
		(layer "F.Cu")
		(at 254.592836 -114.72545)
		(property "Reference" "R3730"
			(at 0 0 0)
			(layer "F.SilkS")
			(hide yes)
			(effects
				(font
					(size 1.27 1.27)
				)
			)
		)
		(property "Value" ""
			(at 0 0 0)
			(layer "F.Fab")
			(effects
				(font
					(size 1.27 1.27)
				)
			)
		)
		(duplicate_pad_numbers_are_jumpers no)
		(fp_line
			(start -0.7874 -0.4064)
			(end 0.7874 -0.4064)
			(stroke
				(width 0.1524)
				(type default)
			)
			(layer "F.SilkS")
		)
		(fp_line
			(start -0.7874 0.4064)
			(end -0.7874 -0.4064)
			(stroke
				(width 0.1524)
				(type default)
			)
			(layer "F.SilkS")
		)
		(fp_line
			(start 0.7874 -0.4064)
			(end 0.7874 0.4064)
			(stroke
				(width 0.1524)
				(type default)
			)
			(layer "F.SilkS")
		)
		(fp_line
			(start 0.7874 0.4064)
			(end -0.7874 0.4064)
			(stroke
				(width 0.1524)
				(type default)
			)
			(layer "F.SilkS")
		)
		(fp_line
			(start -0.67945 -0.305054)
			(end -0.12065 -0.305054)
			(stroke
				(width 0.1)
				(type default)
			)
			(layer "F.Fab")
		)
		(fp_line
			(start -0.67945 0.3048)
			(end -0.67945 -0.305054)
			(stroke
				(width 0.1)
				(type default)
			)
			(layer "F.Fab")
		)
		(fp_line
			(start -0.12065 -0.305054)
			(end -0.12065 -0.2794)
			(stroke
				(width 0.1)
				(type default)
			)
			(layer "F.Fab")
		)
		(fp_line
			(start -0.12065 -0.2794)
			(end 0.12065 -0.2794)
			(stroke
				(width 0.1)
				(type default)
			)
			(layer "F.Fab")
		)
		(fp_line
			(start -0.12065 0.2794)
			(end -0.12065 0.3048)
			(stroke
				(width 0.1)
				(type default)
			)
			(layer "F.Fab")
		)
		(fp_line
			(start -0.12065 0.3048)
			(end -0.67945 0.3048)
			(stroke
				(width 0.1)
				(type default)
			)
			(layer "F.Fab")
		)
		(fp_line
			(start 0.120396 0.2794)
			(end -0.12065 0.2794)
			(stroke
				(width 0.1)
				(type default)
			)
			(layer "F.Fab")
		)
		(fp_line
			(start 0.120396 0.3048)
			(end 0.120396 0.2794)
			(stroke
				(width 0.1)
				(type default)
			)
			(layer "F.Fab")
		)
		(fp_line
			(start 0.12065 -0.3048)
			(end 0.67945 -0.3048)
			(stroke
				(width 0.1)
				(type default)
			)
			(layer "F.Fab")
		)
		(fp_line
			(start 0.12065 -0.2794)
			(end 0.12065 -0.3048)
			(stroke
				(width 0.1)
				(type default)
			)
			(layer "F.Fab")
		)
		(fp_line
			(start 0.67945 -0.3048)
			(end 0.67945 0.3048)
			(stroke
				(width 0.1)
				(type default)
			)
			(layer "F.Fab")
		)
		(fp_line
			(start 0.67945 0.3048)
			(end 0.120396 0.3048)
			(stroke
				(width 0.1)
				(type default)
			)
			(layer "F.Fab")
		)
		(pad "1" smd circle
			(at -0.40005 0)
			(size 0 0)
			(layers "F.Cu" "F.Mask" "F.Paste")
			(net "P3V3_AUX")
		)
		(pad "2" smd circle
			(at 0.40005 0)
			(size 0 0)
			(layers "F.Cu" "F.Mask" "F.Paste")
			(net "SMB_LM75_2_3V3AUX_SDA")
		)
	)
	(footprint ""
		(layer "F.Cu")
		(at 127.705104 -52.14239)
		(property "Reference" "R1625"
			(at 0 0 0)
			(layer "F.SilkS")
			(hide yes)
			(effects
				(font
					(size 1.27 1.27)
				)
			)
		)
		(property "Value" ""
			(at 0 0 0)
			(layer "F.Fab")
			(effects
				(font
					(size 1.27 1.27)
				)
			)
		)
		(duplicate_pad_numbers_are_jumpers no)
		(fp_line
			(start -0.7874 -0.4064)
			(end 0.7874 -0.4064)
			(stroke
				(width 0.1524)
				(type default)
			)
			(layer "F.SilkS")
		)
		(fp_line
			(start -0.7874 0.4064)
			(end -0.7874 -0.4064)
			(stroke
				(width 0.1524)
				(type default)
			)
			(layer "F.SilkS")
		)
		(fp_line
			(start 0.7874 -0.4064)
			(end 0.7874 0.4064)
			(stroke
				(width 0.1524)
				(type default)
			)
			(layer "F.SilkS")
		)
		(fp_line
			(start 0.7874 0.4064)
			(end -0.7874 0.4064)
			(stroke
				(width 0.1524)
				(type default)
			)
			(layer "F.SilkS")
		)
		(fp_line
			(start -0.67945 -0.305054)
			(end -0.12065 -0.305054)
			(stroke
				(width 0.1)
				(type default)
			)
			(layer "F.Fab")
		)
		(fp_line
			(start -0.67945 0.3048)
			(end -0.67945 -0.305054)
			(stroke
				(width 0.1)
				(type default)
			)
			(layer "F.Fab")
		)
		(fp_line
			(start -0.12065 -0.305054)
			(end -0.12065 -0.2794)
			(stroke
				(width 0.1)
				(type default)
			)
			(layer "F.Fab")
		)
		(fp_line
			(start -0.12065 -0.2794)
			(end 0.12065 -0.2794)
			(stroke
				(width 0.1)
				(type default)
			)
			(layer "F.Fab")
		)
		(fp_line
			(start -0.12065 0.2794)
			(end -0.12065 0.3048)
			(stroke
				(width 0.1)
				(type default)
			)
			(layer "F.Fab")
		)
		(fp_line
			(start -0.12065 0.3048)
			(end -0.67945 0.3048)
			(stroke
				(width 0.1)
				(type default)
			)
			(layer "F.Fab")
		)
		(fp_line
			(start 0.120396 0.2794)
			(end -0.12065 0.2794)
			(stroke
				(width 0.1)
				(type default)
			)
			(layer "F.Fab")
		)
		(fp_line
			(start 0.120396 0.3048)
			(end 0.120396 0.2794)
			(stroke
				(width 0.1)
				(type default)
			)
			(layer "F.Fab")
		)
		(fp_line
			(start 0.12065 -0.3048)
			(end 0.67945 -0.3048)
			(stroke
				(width 0.1)
				(type default)
			)
			(layer "F.Fab")
		)
		(fp_line
			(start 0.12065 -0.2794)
			(end 0.12065 -0.3048)
			(stroke
				(width 0.1)
				(type default)
			)
			(layer "F.Fab")
		)
		(fp_line
			(start 0.67945 -0.3048)
			(end 0.67945 0.3048)
			(stroke
				(width 0.1)
				(type default)
			)
			(layer "F.Fab")
		)
		(fp_line
			(start 0.67945 0.3048)
			(end 0.120396 0.3048)
			(stroke
				(width 0.1)
				(type default)
			)
			(layer "F.Fab")
		)
		(pad "1" smd circle
			(at -0.40005 0)
			(size 0 0)
			(layers "F.Cu" "F.Mask" "F.Paste")
			(net "JTAG_TDI_R")
		)
		(pad "2" smd circle
			(at 0.40005 0)
			(size 0 0)
			(layers "F.Cu" "F.Mask" "F.Paste")
			(net "JTAG_TDI")
		)
	)
	(footprint ""
		(layer "F.Cu")
		(at 69.10451 -340.211664)
		(property "Reference" "PR263"
			(at 0 0 0)
			(layer "F.SilkS")
			(hide yes)
			(effects
				(font
					(size 1.27 1.27)
				)
			)
		)
		(property "Value" ""
			(at 0 0 0)
			(layer "F.Fab")
			(effects
				(font
					(size 1.27 1.27)
				)
			)
		)
		(duplicate_pad_numbers_are_jumpers no)
		(fp_line
			(start -0.7874 -0.4064)
			(end 0.7874 -0.4064)
			(stroke
				(width 0.1524)
				(type default)
			)
			(layer "F.SilkS")
		)
		(fp_line
			(start -0.7874 0.4064)
			(end -0.7874 -0.4064)
			(stroke
				(width 0.1524)
				(type default)
			)
			(layer "F.SilkS")
		)
		(fp_line
			(start 0.7874 -0.4064)
			(end 0.7874 0.4064)
			(stroke
				(width 0.1524)
				(type default)
			)
			(layer "F.SilkS")
		)
		(fp_line
			(start 0.7874 0.4064)
			(end -0.7874 0.4064)
			(stroke
				(width 0.1524)
				(type default)
			)
			(layer "F.SilkS")
		)
		(fp_line
			(start -0.67945 -0.305054)
			(end -0.12065 -0.305054)
			(stroke
				(width 0.1)
				(type default)
			)
			(layer "F.Fab")
		)
		(fp_line
			(start -0.67945 0.3048)
			(end -0.67945 -0.305054)
			(stroke
				(width 0.1)
				(type default)
			)
			(layer "F.Fab")
		)
		(fp_line
			(start -0.12065 -0.305054)
			(end -0.12065 -0.2794)
			(stroke
				(width 0.1)
				(type default)
			)
			(layer "F.Fab")
		)
		(fp_line
			(start -0.12065 -0.2794)
			(end 0.12065 -0.2794)
			(stroke
				(width 0.1)
				(type default)
			)
			(layer "F.Fab")
		)
		(fp_line
			(start -0.12065 0.2794)
			(end -0.12065 0.3048)
			(stroke
				(width 0.1)
				(type default)
			)
			(layer "F.Fab")
		)
		(fp_line
			(start -0.12065 0.3048)
			(end -0.67945 0.3048)
			(stroke
				(width 0.1)
				(type default)
			)
			(layer "F.Fab")
		)
		(fp_line
			(start 0.120396 0.2794)
			(end -0.12065 0.2794)
			(stroke
				(width 0.1)
				(type default)
			)
			(layer "F.Fab")
		)
		(fp_line
			(start 0.120396 0.3048)
			(end 0.120396 0.2794)
			(stroke
				(width 0.1)
				(type default)
			)
			(layer "F.Fab")
		)
		(fp_line
			(start 0.12065 -0.3048)
			(end 0.67945 -0.3048)
			(stroke
				(width 0.1)
				(type default)
			)
			(layer "F.Fab")
		)
		(fp_line
			(start 0.12065 -0.2794)
			(end 0.12065 -0.3048)
			(stroke
				(width 0.1)
				(type default)
			)
			(layer "F.Fab")
		)
		(fp_line
			(start 0.67945 -0.3048)
			(end 0.67945 0.3048)
			(stroke
				(width 0.1)
				(type default)
			)
			(layer "F.Fab")
		)
		(fp_line
			(start 0.67945 0.3048)
			(end 0.120396 0.3048)
			(stroke
				(width 0.1)
				(type default)
			)
			(layer "F.Fab")
		)
		(pad "1" smd circle
			(at -0.40005 0)
			(size 0 0)
			(layers "F.Cu" "F.Mask" "F.Paste")
			(net "PVDDCR_CPU1_P1_LSET3")
		)
		(pad "2" smd circle
			(at 0.40005 0)
			(size 0 0)
			(layers "F.Cu" "F.Mask" "F.Paste")
			(net "GND")
		)
	)
	(footprint ""
		(layer "F.Cu")
		(at 363.217206 -261.747762 -90)
		(property "Reference" "C2641"
			(at 0 0 270)
			(layer "F.SilkS")
			(hide yes)
			(effects
				(font
					(size 1.27 1.27)
				)
			)
		)
		(property "Value" ""
			(at 0 0 270)
			(layer "F.Fab")
			(effects
				(font
					(size 1.27 1.27)
				)
			)
		)
		(duplicate_pad_numbers_are_jumpers no)
		(fp_line
			(start -0.7874 0.4064)
			(end -0.7874 -0.4064)
			(stroke
				(width 0.1524)
				(type default)
			)
			(layer "F.SilkS")
		)
		(fp_line
			(start 0.7874 0.4064)
			(end -0.7874 0.4064)
			(stroke
				(width 0.1524)
				(type default)
			)
			(layer "F.SilkS")
		)
		(fp_line
			(start -0.7874 -0.4064)
			(end 0.7874 -0.4064)
			(stroke
				(width 0.1524)
				(type default)
			)
			(layer "F.SilkS")
		)
		(fp_line
			(start 0.7874 -0.4064)
			(end 0.7874 0.4064)
			(stroke
				(width 0.1524)
				(type default)
			)
			(layer "F.SilkS")
		)
		(fp_line
			(start -0.67945 0.3048)
			(end -0.67945 -0.305054)
			(stroke
				(width 0.1)
				(type default)
			)
			(layer "F.Fab")
		)
		(fp_line
			(start -0.12065 0.3048)
			(end -0.67945 0.3048)
			(stroke
				(width 0.1)
				(type default)
			)
			(layer "F.Fab")
		)
		(fp_line
			(start 0.120396 0.3048)
			(end 0.120396 0.2794)
			(stroke
				(width 0.1)
				(type default)
			)
			(layer "F.Fab")
		)
		(fp_line
			(start 0.67945 0.3048)
			(end 0.120396 0.3048)
			(stroke
				(width 0.1)
				(type default)
			)
			(layer "F.Fab")
		)
		(fp_line
			(start -0.12065 0.2794)
			(end -0.12065 0.3048)
			(stroke
				(width 0.1)
				(type default)
			)
			(layer "F.Fab")
		)
		(fp_line
			(start 0.120396 0.2794)
			(end -0.12065 0.2794)
			(stroke
				(width 0.1)
				(type default)
			)
			(layer "F.Fab")
		)
		(fp_line
			(start -0.12065 -0.2794)
			(end 0.12065 -0.2794)
			(stroke
				(width 0.1)
				(type default)
			)
			(layer "F.Fab")
		)
		(fp_line
			(start 0.12065 -0.2794)
			(end 0.12065 -0.3048)
			(stroke
				(width 0.1)
				(type default)
			)
			(layer "F.Fab")
		)
		(fp_line
			(start 0.12065 -0.3048)
			(end 0.67945 -0.3048)
			(stroke
				(width 0.1)
				(type default)
			)
			(layer "F.Fab")
		)
		(fp_line
			(start 0.67945 -0.3048)
			(end 0.67945 0.3048)
			(stroke
				(width 0.1)
				(type default)
			)
			(layer "F.Fab")
		)
		(fp_line
			(start -0.67945 -0.305054)
			(end -0.12065 -0.305054)
			(stroke
				(width 0.1)
				(type default)
			)
			(layer "F.Fab")
		)
		(fp_line
			(start -0.12065 -0.305054)
			(end -0.12065 -0.2794)
			(stroke
				(width 0.1)
				(type default)
			)
			(layer "F.Fab")
		)
		(pad "1" smd circle
			(at -0.40005 0 270)
			(size 0 0)
			(layers "F.Cu" "F.Mask" "F.Paste")
			(net "PVDD11_S3_P0")
		)
		(pad "2" smd circle
			(at 0.40005 0 270)
			(size 0 0)
			(layers "F.Cu" "F.Mask" "F.Paste")
			(net "GND")
		)
	)
	(footprint ""
		(layer "F.Cu")
		(at 418.25164 -383.88163 -90)
		(property "Reference" "C848"
			(at 0 0 270)
			(layer "F.SilkS")
			(hide yes)
			(effects
				(font
					(size 1.27 1.27)
				)
			)
		)
		(property "Value" ""
			(at 0 0 270)
			(layer "F.Fab")
			(effects
				(font
					(size 1.27 1.27)
				)
			)
		)
		(duplicate_pad_numbers_are_jumpers no)
		(fp_line
			(start -0.299974 0.150114)
			(end -0.299974 -0.150114)
			(stroke
				(width 0.1)
				(type default)
			)
			(layer "F.Fab")
		)
		(fp_line
			(start 0.299974 0.150114)
			(end -0.299974 0.150114)
			(stroke
				(width 0.1)
				(type default)
			)
			(layer "F.Fab")
		)
		(fp_line
			(start -0.299974 -0.150114)
			(end 0.299974 -0.150114)
			(stroke
				(width 0.1)
				(type default)
			)
			(layer "F.Fab")
		)
		(fp_line
			(start 0.299974 -0.150114)
			(end 0.299974 0.150114)
			(stroke
				(width 0.1)
				(type default)
			)
			(layer "F.Fab")
		)
		(pad "1" smd rect
			(at -0.2667 0 270)
			(size 0.3048 0.381)
			(layers "F.Cu" "F.Mask" "F.Paste")
			(net "P5E_CPU0_P2_TX_C_DN<10>")
		)
		(pad "2" smd rect
			(at 0.2667 0 270)
			(size 0.3048 0.381)
			(layers "F.Cu" "F.Mask" "F.Paste")
			(net "P5E_CPU0_P2_TX_DN<10>")
		)
	)
	(footprint ""
		(layer "F.Cu")
		(at 301.419768 -145.877788 180)
		(property "Reference" "C1336"
			(at 0 0 180)
			(layer "F.SilkS")
			(hide yes)
			(effects
				(font
					(size 1.27 1.27)
				)
			)
		)
		(property "Value" ""
			(at 0 0 180)
			(layer "F.Fab")
			(effects
				(font
					(size 1.27 1.27)
				)
			)
		)
		(duplicate_pad_numbers_are_jumpers no)
		(fp_line
			(start 0.7874 0.4064)
			(end -0.7874 0.4064)
			(stroke
				(width 0.1524)
				(type default)
			)
			(layer "F.SilkS")
		)
		(fp_line
			(start 0.7874 -0.4064)
			(end 0.7874 0.4064)
			(stroke
				(width 0.1524)
				(type default)
			)
			(layer "F.SilkS")
		)
		(fp_line
			(start -0.7874 0.4064)
			(end -0.7874 -0.4064)
			(stroke
				(width 0.1524)
				(type default)
			)
			(layer "F.SilkS")
		)
		(fp_line
			(start -0.7874 -0.4064)
			(end 0.7874 -0.4064)
			(stroke
				(width 0.1524)
				(type default)
			)
			(layer "F.SilkS")
		)
		(fp_line
			(start 0.67945 0.3048)
			(end 0.120396 0.3048)
			(stroke
				(width 0.1)
				(type default)
			)
			(layer "F.Fab")
		)
		(fp_line
			(start 0.67945 -0.3048)
			(end 0.67945 0.3048)
			(stroke
				(width 0.1)
				(type default)
			)
			(layer "F.Fab")
		)
		(fp_line
			(start 0.12065 -0.2794)
			(end 0.12065 -0.3048)
			(stroke
				(width 0.1)
				(type default)
			)
			(layer "F.Fab")
		)
		(fp_line
			(start 0.12065 -0.3048)
			(end 0.67945 -0.3048)
			(stroke
				(width 0.1)
				(type default)
			)
			(layer "F.Fab")
		)
		(fp_line
			(start 0.120396 0.3048)
			(end 0.120396 0.2794)
			(stroke
				(width 0.1)
				(type default)
			)
			(layer "F.Fab")
		)
		(fp_line
			(start 0.120396 0.2794)
			(end -0.12065 0.2794)
			(stroke
				(width 0.1)
				(type default)
			)
			(layer "F.Fab")
		)
		(fp_line
			(start -0.12065 0.3048)
			(end -0.67945 0.3048)
			(stroke
				(width 0.1)
				(type default)
			)
			(layer "F.Fab")
		)
		(fp_line
			(start -0.12065 0.2794)
			(end -0.12065 0.3048)
			(stroke
				(width 0.1)
				(type default)
			)
			(layer "F.Fab")
		)
		(fp_line
			(start -0.12065 -0.2794)
			(end 0.12065 -0.2794)
			(stroke
				(width 0.1)
				(type default)
			)
			(layer "F.Fab")
		)
		(fp_line
			(start -0.12065 -0.305054)
			(end -0.12065 -0.2794)
			(stroke
				(width 0.1)
				(type default)
			)
			(layer "F.Fab")
		)
		(fp_line
			(start -0.67945 0.3048)
			(end -0.67945 -0.305054)
			(stroke
				(width 0.1)
				(type default)
			)
			(layer "F.Fab")
		)
		(fp_line
			(start -0.67945 -0.305054)
			(end -0.12065 -0.305054)
			(stroke
				(width 0.1)
				(type default)
			)
			(layer "F.Fab")
		)
		(pad "1" smd circle
			(at -0.40005 0 180)
			(size 0 0)
			(layers "F.Cu" "F.Mask" "F.Paste")
			(net "P3V3_AUX")
		)
		(pad "2" smd circle
			(at 0.40005 0 180)
			(size 0 0)
			(layers "F.Cu" "F.Mask" "F.Paste")
			(net "GND")
		)
	)
	(footprint ""
		(layer "F.Cu")
		(at 131.90728 -27.25928)
		(property "Reference" "R340"
			(at 0 0 0)
			(layer "F.SilkS")
			(hide yes)
			(effects
				(font
					(size 1.27 1.27)
				)
			)
		)
		(property "Value" ""
			(at 0 0 0)
			(layer "F.Fab")
			(effects
				(font
					(size 1.27 1.27)
				)
			)
		)
		(duplicate_pad_numbers_are_jumpers no)
		(fp_line
			(start -0.32512 -0.175006)
			(end 0.32512 -0.175006)
			(stroke
				(width 0.1)
				(type default)
			)
			(layer "F.Fab")
		)
		(fp_line
			(start -0.32512 0.175006)
			(end -0.32512 -0.175006)
			(stroke
				(width 0.1)
				(type default)
			)
			(layer "F.Fab")
		)
		(fp_line
			(start 0.32512 -0.175006)
			(end 0.32512 0.175006)
			(stroke
				(width 0.1)
				(type default)
			)
			(layer "F.Fab")
		)
		(fp_line
			(start 0.32512 0.175006)
			(end -0.32512 0.175006)
			(stroke
				(width 0.1)
				(type default)
			)
			(layer "F.Fab")
		)
		(pad "1" smd rect
			(at -0.2667 0)
			(size 0.3048 0.381)
			(layers "F.Cu" "F.Mask" "F.Paste")
			(net "USB2_CPU0_P0_DN")
		)
		(pad "2" smd rect
			(at 0.2667 0 180)
			(size 0.3048 0.381)
			(layers "F.Cu" "F.Mask" "F.Paste")
			(net "GND")
		)
	)
	(footprint ""
		(layer "F.Cu")
		(at 366.64392 -395.066774 -90)
		(property "Reference" "R635"
			(at 0 0 270)
			(layer "F.SilkS")
			(hide yes)
			(effects
				(font
					(size 1.27 1.27)
				)
			)
		)
		(property "Value" ""
			(at 0 0 270)
			(layer "F.Fab")
			(effects
				(font
					(size 1.27 1.27)
				)
			)
		)
		(duplicate_pad_numbers_are_jumpers no)
		(fp_line
			(start -0.32512 0.175006)
			(end -0.32512 -0.175006)
			(stroke
				(width 0.1)
				(type default)
			)
			(layer "F.Fab")
		)
		(fp_line
			(start 0.32512 0.175006)
			(end -0.32512 0.175006)
			(stroke
				(width 0.1)
				(type default)
			)
			(layer "F.Fab")
		)
		(fp_line
			(start -0.32512 -0.175006)
			(end 0.32512 -0.175006)
			(stroke
				(width 0.1)
				(type default)
			)
			(layer "F.Fab")
		)
		(fp_line
			(start 0.32512 -0.175006)
			(end 0.32512 0.175006)
			(stroke
				(width 0.1)
				(type default)
			)
			(layer "F.Fab")
		)
		(pad "1" smd rect
			(at -0.2667 0 270)
			(size 0.3048 0.381)
			(layers "F.Cu" "F.Mask" "F.Paste")
			(net "CLK_100M_RETIMER_CPU0_P3_DN")
		)
		(pad "2" smd rect
			(at 0.2667 0 90)
			(size 0.3048 0.381)
			(layers "F.Cu" "F.Mask" "F.Paste")
			(net "GND")
		)
	)
	(footprint ""
		(layer "F.Cu")
		(at 193.369438 -427.693328 -90)
		(property "Reference" "U190"
			(at 2.258568 1.78308 0)
			(unlocked yes)
			(layer "F.SilkS")
			(effects
				(font
					(size 0.7874 0.5842)
					(thickness 0.1524)
				)
				(justify left)
			)
		)
		(property "Value" ""
			(at 0 0 270)
			(layer "F.Fab")
			(effects
				(font
					(size 1.27 1.27)
				)
			)
		)
		(duplicate_pad_numbers_are_jumpers no)
		(fp_line
			(start -1.603248 1.500124)
			(end -1.603248 -1.500124)
			(stroke
				(width 0.1524)
				(type default)
			)
			(layer "F.SilkS")
		)
		(fp_line
			(start 1.603248 1.500124)
			(end -1.603248 1.500124)
			(stroke
				(width 0.1524)
				(type default)
			)
			(layer "F.SilkS")
		)
		(fp_line
			(start -1.603248 -1.500124)
			(end 1.603248 -1.500124)
			(stroke
				(width 0.1524)
				(type default)
			)
			(layer "F.SilkS")
		)
		(fp_line
			(start 1.603248 -1.500124)
			(end 1.603248 1.500124)
			(stroke
				(width 0.1524)
				(type default)
			)
			(layer "F.SilkS")
		)
		(fp_line
			(start -0.700024 1.500124)
			(end 0.700024 1.500124)
			(stroke
				(width 0.1)
				(type default)
			)
			(layer "F.Fab")
		)
		(fp_line
			(start 0.700024 1.500124)
			(end 0.700024 0.219964)
			(stroke
				(width 0.1)
				(type default)
			)
			(layer "F.Fab")
		)
		(fp_line
			(start -1.249934 1.169924)
			(end -0.700024 1.169924)
			(stroke
				(width 0.1)
				(type default)
			)
			(layer "F.Fab")
		)
		(fp_line
			(start -0.700024 1.169924)
			(end -0.700024 1.500124)
			(stroke
				(width 0.1)
				(type default)
			)
			(layer "F.Fab")
		)
		(fp_line
			(start -1.249934 0.729996)
			(end -1.249934 1.169924)
			(stroke
				(width 0.1)
				(type default)
			)
			(layer "F.Fab")
		)
		(fp_line
			(start -0.6985 0.729996)
			(end -1.249934 0.729996)
			(stroke
				(width 0.1)
				(type default)
			)
			(layer "F.Fab")
		)
		(fp_line
			(start 0.700024 0.219964)
			(end 1.249934 0.219964)
			(stroke
				(width 0.1)
				(type default)
			)
			(layer "F.Fab")
		)
		(fp_line
			(start 1.249934 0.219964)
			(end 1.249934 -0.219964)
			(stroke
				(width 0.1)
				(type default)
			)
			(layer "F.Fab")
		)
		(fp_line
			(start 0.700024 -0.219964)
			(end 0.700024 -1.500124)
			(stroke
				(width 0.1)
				(type default)
			)
			(layer "F.Fab")
		)
		(fp_line
			(start 1.249934 -0.219964)
			(end 0.700024 -0.219964)
			(stroke
				(width 0.1)
				(type default)
			)
			(layer "F.Fab")
		)
		(fp_line
			(start -1.249934 -0.729996)
			(end -0.6985 -0.729996)
			(stroke
				(width 0.1)
				(type default)
			)
			(layer "F.Fab")
		)
		(fp_line
			(start -0.6985 -0.729996)
			(end -0.6985 0.729996)
			(stroke
				(width 0.1)
				(type default)
			)
			(layer "F.Fab")
		)
		(fp_line
			(start -1.249934 -1.169924)
			(end -1.249934 -0.729996)
			(stroke
				(width 0.1)
				(type default)
			)
			(layer "F.Fab")
		)
		(fp_line
			(start -0.700024 -1.169924)
			(end -1.249934 -1.169924)
			(stroke
				(width 0.1)
				(type default)
			)
			(layer "F.Fab")
		)
		(fp_line
			(start -0.700024 -1.500124)
			(end -0.700024 -1.169924)
			(stroke
				(width 0.1)
				(type default)
			)
			(layer "F.Fab")
		)
		(fp_line
			(start 0.700024 -1.500124)
			(end -0.700024 -1.500124)
			(stroke
				(width 0.1)
				(type default)
			)
			(layer "F.Fab")
		)
		(fp_rect
			(start -0.700024 1.500124)
			(end 0.700024 -1.500124)
			(stroke
				(width 0)
				(type default)
			)
			(fill no)
			(layer "F.Fab")
		)
		(pad "D" smd rect
			(at 0.999998 0 180)
			(size 0.8128 0.9144)
			(layers "F.Cu" "F.Mask" "F.Paste")
			(net "FM_PDB_BUF_EN_R1")
		)
		(pad "G" smd rect
			(at -0.999998 -0.94996 180)
			(size 0.8128 0.9144)
			(layers "F.Cu" "F.Mask" "F.Paste")
			(net "FM_PDB_BUF_EN_R1_N")
		)
		(pad "S" smd rect
			(at -0.999998 0.94996 180)
			(size 0.8128 0.9144)
			(layers "F.Cu" "F.Mask" "F.Paste")
			(net "GND")
		)
	)
	(footprint ""
		(layer "F.Cu")
		(at 302.09617 -407.79446)
		(property "Reference" "R962"
			(at 0 0 0)
			(layer "F.SilkS")
			(hide yes)
			(effects
				(font
					(size 1.27 1.27)
				)
			)
		)
		(property "Value" ""
			(at 0 0 0)
			(layer "F.Fab")
			(effects
				(font
					(size 1.27 1.27)
				)
			)
		)
		(duplicate_pad_numbers_are_jumpers no)
		(fp_line
			(start -1.2954 -0.5842)
			(end 1.2954 -0.5842)
			(stroke
				(width 0.1524)
				(type default)
			)
			(layer "F.SilkS")
		)
		(fp_line
			(start -1.2954 0.5842)
			(end -1.2954 -0.5842)
			(stroke
				(width 0.1524)
				(type default)
			)
			(layer "F.SilkS")
		)
		(fp_line
			(start 1.2954 -0.5842)
			(end 1.2954 0.5842)
			(stroke
				(width 0.1524)
				(type default)
			)
			(layer "F.SilkS")
		)
		(fp_line
			(start 1.2954 0.5842)
			(end -1.2954 0.5842)
			(stroke
				(width 0.1524)
				(type default)
			)
			(layer "F.SilkS")
		)
		(fp_line
			(start -1.1938 -0.406654)
			(end -0.8636 -0.406654)
			(stroke
				(width 0.1)
				(type default)
			)
			(layer "F.Fab")
		)
		(fp_line
			(start -1.1938 0.4064)
			(end -1.1938 -0.406654)
			(stroke
				(width 0.1)
				(type default)
			)
			(layer "F.Fab")
		)
		(fp_line
			(start -0.8636 -0.4572)
			(end 0.8636 -0.4572)
			(stroke
				(width 0.1)
				(type default)
			)
			(layer "F.Fab")
		)
		(fp_line
			(start -0.8636 -0.406654)
			(end -0.8636 -0.4572)
			(stroke
				(width 0.1)
				(type default)
			)
			(layer "F.Fab")
		)
		(fp_line
			(start -0.8636 0.4064)
			(end -1.1938 0.4064)
			(stroke
				(width 0.1)
				(type default)
			)
			(layer "F.Fab")
		)
		(fp_line
			(start -0.8636 0.4318)
			(end -0.8636 0.4064)
			(stroke
				(width 0.1)
				(type default)
			)
			(layer "F.Fab")
		)
		(fp_line
			(start -0.8636 0.4572)
			(end -0.8636 0.4318)
			(stroke
				(width 0.1)
				(type default)
			)
			(layer "F.Fab")
		)
		(fp_line
			(start 0.8636 -0.4572)
			(end 0.8636 -0.406654)
			(stroke
				(width 0.1)
				(type default)
			)
			(layer "F.Fab")
		)
		(fp_line
			(start 0.8636 -0.406654)
			(end 1.1938 -0.406654)
			(stroke
				(width 0.1)
				(type default)
			)
			(layer "F.Fab")
		)
		(fp_line
			(start 0.8636 0.4064)
			(end 0.8636 0.4572)
			(stroke
				(width 0.1)
				(type default)
			)
			(layer "F.Fab")
		)
		(fp_line
			(start 0.8636 0.4572)
			(end -0.8636 0.4572)
			(stroke
				(width 0.1)
				(type default)
			)
			(layer "F.Fab")
		)
		(fp_line
			(start 1.1938 -0.406654)
			(end 1.1938 0.4064)
			(stroke
				(width 0.1)
				(type default)
			)
			(layer "F.Fab")
		)
		(fp_line
			(start 1.1938 0.4064)
			(end 0.8636 0.4064)
			(stroke
				(width 0.1)
				(type default)
			)
			(layer "F.Fab")
		)
		(pad "1" smd rect
			(at -0.7366 0 270)
			(size 0.7112 0.8128)
			(layers "F.Cu" "F.Mask" "F.Paste")
			(net "P0V9_CPU0_RT0_2A_2D")
		)
		(pad "2" smd rect
			(at 0.7366 0 270)
			(size 0.7112 0.8128)
			(layers "F.Cu" "F.Mask" "F.Paste")
			(net "P0V9_CPU0_RT0_2A")
		)
	)
	(footprint ""
		(layer "F.Cu")
		(at 479.621342 -212.758528)
		(property "Reference" "DB1"
			(at 1.409954 2.969514 0)
			(unlocked yes)
			(layer "F.SilkS")
			(effects
				(font
					(size 0.7874 0.5842)
					(thickness 0.1524)
				)
				(justify left)
			)
		)
		(property "Value" ""
			(at 0 0 0)
			(layer "F.Fab")
			(effects
				(font
					(size 1.27 1.27)
				)
			)
		)
		(duplicate_pad_numbers_are_jumpers no)
		(fp_line
			(start -3.330702 -4.771136)
			(end 3.330702 -4.771136)
			(stroke
				(width 0.1524)
				(type default)
			)
			(layer "F.SilkS")
		)
		(fp_line
			(start 0 4.011168)
			(end -3.330702 -4.771136)
			(stroke
				(width 0.1524)
				(type default)
			)
			(layer "F.SilkS")
		)
		(fp_line
			(start 3.330702 -4.771136)
			(end 0 4.011168)
			(stroke
				(width 0.1524)
				(type default)
			)
			(layer "F.SilkS")
		)
		(fp_line
			(start -3.330702 -4.771136)
			(end 3.330702 -4.771136)
			(stroke
				(width 0.1)
				(type default)
			)
			(layer "F.Fab")
		)
		(fp_line
			(start 0 4.011168)
			(end -3.330702 -4.771136)
			(stroke
				(width 0.1)
				(type default)
			)
			(layer "F.Fab")
		)
		(fp_line
			(start 3.330702 -4.771136)
			(end 0 4.011168)
			(stroke
				(width 0.1)
				(type default)
			)
			(layer "F.Fab")
		)
		(pad "1" thru_hole circle
			(at 0 0)
			(size 2.159 2.159)
			(drill 1.7018)
			(layers "*.Cu" "*.Mask")
			(remove_unused_layers no)
			(net "T1_GND")
			(clearance 0.0254)
			(thermal_gap 0.0254)
		)
		(pad "2" thru_hole circle
			(at -1.27 -3.348736)
			(size 2.159 2.159)
			(drill 1.7018)
			(layers "*.Cu" "*.Mask")
			(remove_unused_layers no)
			(net "TDR_SE_45_OHM_TOP")
			(clearance 0.0254)
			(thermal_gap 0.0254)
		)
		(pad "3" thru_hole circle
			(at 1.27 -3.348736)
			(size 2.159 2.159)
			(drill 1.7018)
			(layers "*.Cu" "*.Mask")
			(remove_unused_layers no)
			(net "TDR_SE_45_OHM_TOP")
			(clearance 0.0254)
			(thermal_gap 0.0254)
		)
	)
	(footprint ""
		(layer "F.Cu")
		(at 297.486324 -122.349514 180)
		(property "Reference" "R316"
			(at 0 0 180)
			(layer "F.SilkS")
			(hide yes)
			(effects
				(font
					(size 1.27 1.27)
				)
			)
		)
		(property "Value" ""
			(at 0 0 180)
			(layer "F.Fab")
			(effects
				(font
					(size 1.27 1.27)
				)
			)
		)
		(duplicate_pad_numbers_are_jumpers no)
		(fp_line
			(start 0.7874 0.4064)
			(end -0.7874 0.4064)
			(stroke
				(width 0.1524)
				(type default)
			)
			(layer "F.SilkS")
		)
		(fp_line
			(start 0.7874 -0.4064)
			(end 0.7874 0.4064)
			(stroke
				(width 0.1524)
				(type default)
			)
			(layer "F.SilkS")
		)
		(fp_line
			(start -0.7874 0.4064)
			(end -0.7874 -0.4064)
			(stroke
				(width 0.1524)
				(type default)
			)
			(layer "F.SilkS")
		)
		(fp_line
			(start -0.7874 -0.4064)
			(end 0.7874 -0.4064)
			(stroke
				(width 0.1524)
				(type default)
			)
			(layer "F.SilkS")
		)
		(fp_line
			(start 0.67945 0.3048)
			(end 0.120396 0.3048)
			(stroke
				(width 0.1)
				(type default)
			)
			(layer "F.Fab")
		)
		(fp_line
			(start 0.67945 -0.3048)
			(end 0.67945 0.3048)
			(stroke
				(width 0.1)
				(type default)
			)
			(layer "F.Fab")
		)
		(fp_line
			(start 0.12065 -0.2794)
			(end 0.12065 -0.3048)
			(stroke
				(width 0.1)
				(type default)
			)
			(layer "F.Fab")
		)
		(fp_line
			(start 0.12065 -0.3048)
			(end 0.67945 -0.3048)
			(stroke
				(width 0.1)
				(type default)
			)
			(layer "F.Fab")
		)
		(fp_line
			(start 0.120396 0.3048)
			(end 0.120396 0.2794)
			(stroke
				(width 0.1)
				(type default)
			)
			(layer "F.Fab")
		)
		(fp_line
			(start 0.120396 0.2794)
			(end -0.12065 0.2794)
			(stroke
				(width 0.1)
				(type default)
			)
			(layer "F.Fab")
		)
		(fp_line
			(start -0.12065 0.3048)
			(end -0.67945 0.3048)
			(stroke
				(width 0.1)
				(type default)
			)
			(layer "F.Fab")
		)
		(fp_line
			(start -0.12065 0.2794)
			(end -0.12065 0.3048)
			(stroke
				(width 0.1)
				(type default)
			)
			(layer "F.Fab")
		)
		(fp_line
			(start -0.12065 -0.2794)
			(end 0.12065 -0.2794)
			(stroke
				(width 0.1)
				(type default)
			)
			(layer "F.Fab")
		)
		(fp_line
			(start -0.12065 -0.305054)
			(end -0.12065 -0.2794)
			(stroke
				(width 0.1)
				(type default)
			)
			(layer "F.Fab")
		)
		(fp_line
			(start -0.67945 0.3048)
			(end -0.67945 -0.305054)
			(stroke
				(width 0.1)
				(type default)
			)
			(layer "F.Fab")
		)
		(fp_line
			(start -0.67945 -0.305054)
			(end -0.12065 -0.305054)
			(stroke
				(width 0.1)
				(type default)
			)
			(layer "F.Fab")
		)
		(pad "1" smd circle
			(at -0.40005 0 180)
			(size 0 0)
			(layers "F.Cu" "F.Mask" "F.Paste")
			(net "P3V3_AUX")
		)
		(pad "2" smd circle
			(at 0.40005 0 180)
			(size 0 0)
			(layers "F.Cu" "F.Mask" "F.Paste")
			(net "PCA9548_PCIE3_ADDR2")
		)
	)
	(footprint ""
		(layer "F.Cu")
		(at 115.70589 -259.845302)
		(property "Reference" "C2267"
			(at 0 0 0)
			(layer "F.SilkS")
			(hide yes)
			(effects
				(font
					(size 1.27 1.27)
				)
			)
		)
		(property "Value" ""
			(at 0 0 0)
			(layer "F.Fab")
			(effects
				(font
					(size 1.27 1.27)
				)
			)
		)
		(duplicate_pad_numbers_are_jumpers no)
		(fp_line
			(start -0.7874 -0.4064)
			(end 0.7874 -0.4064)
			(stroke
				(width 0.1524)
				(type default)
			)
			(layer "F.SilkS")
		)
		(fp_line
			(start -0.7874 0.4064)
			(end -0.7874 -0.4064)
			(stroke
				(width 0.1524)
				(type default)
			)
			(layer "F.SilkS")
		)
		(fp_line
			(start 0.7874 -0.4064)
			(end 0.7874 0.4064)
			(stroke
				(width 0.1524)
				(type default)
			)
			(layer "F.SilkS")
		)
		(fp_line
			(start 0.7874 0.4064)
			(end -0.7874 0.4064)
			(stroke
				(width 0.1524)
				(type default)
			)
			(layer "F.SilkS")
		)
		(fp_line
			(start -0.67945 -0.305054)
			(end -0.12065 -0.305054)
			(stroke
				(width 0.1)
				(type default)
			)
			(layer "F.Fab")
		)
		(fp_line
			(start -0.67945 0.3048)
			(end -0.67945 -0.305054)
			(stroke
				(width 0.1)
				(type default)
			)
			(layer "F.Fab")
		)
		(fp_line
			(start -0.12065 -0.305054)
			(end -0.12065 -0.2794)
			(stroke
				(width 0.1)
				(type default)
			)
			(layer "F.Fab")
		)
		(fp_line
			(start -0.12065 -0.2794)
			(end 0.12065 -0.2794)
			(stroke
				(width 0.1)
				(type default)
			)
			(layer "F.Fab")
		)
		(fp_line
			(start -0.12065 0.2794)
			(end -0.12065 0.3048)
			(stroke
				(width 0.1)
				(type default)
			)
			(layer "F.Fab")
		)
		(fp_line
			(start -0.12065 0.3048)
			(end -0.67945 0.3048)
			(stroke
				(width 0.1)
				(type default)
			)
			(layer "F.Fab")
		)
		(fp_line
			(start 0.120396 0.2794)
			(end -0.12065 0.2794)
			(stroke
				(width 0.1)
				(type default)
			)
			(layer "F.Fab")
		)
		(fp_line
			(start 0.120396 0.3048)
			(end 0.120396 0.2794)
			(stroke
				(width 0.1)
				(type default)
			)
			(layer "F.Fab")
		)
		(fp_line
			(start 0.12065 -0.3048)
			(end 0.67945 -0.3048)
			(stroke
				(width 0.1)
				(type default)
			)
			(layer "F.Fab")
		)
		(fp_line
			(start 0.12065 -0.2794)
			(end 0.12065 -0.3048)
			(stroke
				(width 0.1)
				(type default)
			)
			(layer "F.Fab")
		)
		(fp_line
			(start 0.67945 -0.3048)
			(end 0.67945 0.3048)
			(stroke
				(width 0.1)
				(type default)
			)
			(layer "F.Fab")
		)
		(fp_line
			(start 0.67945 0.3048)
			(end 0.120396 0.3048)
			(stroke
				(width 0.1)
				(type default)
			)
			(layer "F.Fab")
		)
		(pad "1" smd circle
			(at -0.40005 0)
			(size 0 0)
			(layers "F.Cu" "F.Mask" "F.Paste")
			(net "PVDD11_S3_P1")
		)
		(pad "2" smd circle
			(at 0.40005 0)
			(size 0 0)
			(layers "F.Cu" "F.Mask" "F.Paste")
			(net "GND")
		)
	)
	(footprint ""
		(layer "F.Cu")
		(at 155.444444 -375.49963 -90)
		(property "Reference" "C758"
			(at 0 0 270)
			(layer "F.SilkS")
			(hide yes)
			(effects
				(font
					(size 1.27 1.27)
				)
			)
		)
		(property "Value" ""
			(at 0 0 270)
			(layer "F.Fab")
			(effects
				(font
					(size 1.27 1.27)
				)
			)
		)
		(duplicate_pad_numbers_are_jumpers no)
		(fp_line
			(start -0.299974 0.150114)
			(end -0.299974 -0.150114)
			(stroke
				(width 0.1)
				(type default)
			)
			(layer "F.Fab")
		)
		(fp_line
			(start 0.299974 0.150114)
			(end -0.299974 0.150114)
			(stroke
				(width 0.1)
				(type default)
			)
			(layer "F.Fab")
		)
		(fp_line
			(start -0.299974 -0.150114)
			(end 0.299974 -0.150114)
			(stroke
				(width 0.1)
				(type default)
			)
			(layer "F.Fab")
		)
		(fp_line
			(start 0.299974 -0.150114)
			(end 0.299974 0.150114)
			(stroke
				(width 0.1)
				(type default)
			)
			(layer "F.Fab")
		)
		(pad "1" smd rect
			(at -0.2667 0 270)
			(size 0.3048 0.381)
			(layers "F.Cu" "F.Mask" "F.Paste")
			(net "P5E_CPU1_P2_TX_C_DN<7>")
		)
		(pad "2" smd rect
			(at 0.2667 0 270)
			(size 0.3048 0.381)
			(layers "F.Cu" "F.Mask" "F.Paste")
			(net "P5E_CPU1_P2_TX_DN<7>")
		)
	)
	(footprint ""
		(layer "F.Cu")
		(at 288.325306 -346.714572 -90)
		(property "Reference" "PC144_IOP0_2"
			(at 0 0 270)
			(layer "F.SilkS")
			(hide yes)
			(effects
				(font
					(size 1.27 1.27)
				)
			)
		)
		(property "Value" ""
			(at 0 0 270)
			(layer "F.Fab")
			(effects
				(font
					(size 1.27 1.27)
				)
			)
		)
		(duplicate_pad_numbers_are_jumpers no)
		(fp_line
			(start -0.7874 0.4064)
			(end -0.7874 -0.4064)
			(stroke
				(width 0.1524)
				(type default)
			)
			(layer "F.SilkS")
		)
		(fp_line
			(start 0.7874 0.4064)
			(end -0.7874 0.4064)
			(stroke
				(width 0.1524)
				(type default)
			)
			(layer "F.SilkS")
		)
		(fp_line
			(start -0.7874 -0.4064)
			(end 0.7874 -0.4064)
			(stroke
				(width 0.1524)
				(type default)
			)
			(layer "F.SilkS")
		)
		(fp_line
			(start 0.7874 -0.4064)
			(end 0.7874 0.4064)
			(stroke
				(width 0.1524)
				(type default)
			)
			(layer "F.SilkS")
		)
		(fp_line
			(start -0.67945 0.3048)
			(end -0.67945 -0.305054)
			(stroke
				(width 0.1)
				(type default)
			)
			(layer "F.Fab")
		)
		(fp_line
			(start -0.12065 0.3048)
			(end -0.67945 0.3048)
			(stroke
				(width 0.1)
				(type default)
			)
			(layer "F.Fab")
		)
		(fp_line
			(start 0.120396 0.3048)
			(end 0.120396 0.2794)
			(stroke
				(width 0.1)
				(type default)
			)
			(layer "F.Fab")
		)
		(fp_line
			(start 0.67945 0.3048)
			(end 0.120396 0.3048)
			(stroke
				(width 0.1)
				(type default)
			)
			(layer "F.Fab")
		)
		(fp_line
			(start -0.12065 0.2794)
			(end -0.12065 0.3048)
			(stroke
				(width 0.1)
				(type default)
			)
			(layer "F.Fab")
		)
		(fp_line
			(start 0.120396 0.2794)
			(end -0.12065 0.2794)
			(stroke
				(width 0.1)
				(type default)
			)
			(layer "F.Fab")
		)
		(fp_line
			(start -0.12065 -0.2794)
			(end 0.12065 -0.2794)
			(stroke
				(width 0.1)
				(type default)
			)
			(layer "F.Fab")
		)
		(fp_line
			(start 0.12065 -0.2794)
			(end 0.12065 -0.3048)
			(stroke
				(width 0.1)
				(type default)
			)
			(layer "F.Fab")
		)
		(fp_line
			(start 0.12065 -0.3048)
			(end 0.67945 -0.3048)
			(stroke
				(width 0.1)
				(type default)
			)
			(layer "F.Fab")
		)
		(fp_line
			(start 0.67945 -0.3048)
			(end 0.67945 0.3048)
			(stroke
				(width 0.1)
				(type default)
			)
			(layer "F.Fab")
		)
		(fp_line
			(start -0.67945 -0.305054)
			(end -0.12065 -0.305054)
			(stroke
				(width 0.1)
				(type default)
			)
			(layer "F.Fab")
		)
		(fp_line
			(start -0.12065 -0.305054)
			(end -0.12065 -0.2794)
			(stroke
				(width 0.1)
				(type default)
			)
			(layer "F.Fab")
		)
		(pad "1" smd circle
			(at -0.40005 0 270)
			(size 0 0)
			(layers "F.Cu" "F.Mask" "F.Paste")
			(net "PVDDCR_CPU1_P0_PVCC")
		)
		(pad "2" smd circle
			(at 0.40005 0 270)
			(size 0 0)
			(layers "F.Cu" "F.Mask" "F.Paste")
			(net "GND")
		)
	)
	(footprint ""
		(layer "F.Cu")
		(at 313.8297 -409.104592)
		(property "Reference" "C7032"
			(at -5.4864 3.171952 0)
			(unlocked yes)
			(layer "F.SilkS")
			(effects
				(font
					(size 0.7874 0.5842)
					(thickness 0.1524)
				)
				(justify left)
			)
		)
		(property "Value" ""
			(at 0 0 0)
			(layer "F.Fab")
			(effects
				(font
					(size 1.27 1.27)
				)
			)
		)
		(duplicate_pad_numbers_are_jumpers no)
		(fp_line
			(start -4.84378 -2.150618)
			(end -4.842256 2.163064)
			(stroke
				(width 0.1524)
				(type default)
			)
			(layer "F.SilkS")
		)
		(fp_line
			(start -4.84378 -2.150618)
			(end -4.53898 -2.150618)
			(stroke
				(width 0.1524)
				(type default)
			)
			(layer "F.SilkS")
		)
		(fp_line
			(start -4.83108 2.150364)
			(end -4.447794 2.149348)
			(stroke
				(width 0.1524)
				(type default)
			)
			(layer "F.SilkS")
		)
		(fp_line
			(start -4.69138 -2.150618)
			(end -4.692396 2.161032)
			(stroke
				(width 0.1524)
				(type default)
			)
			(layer "F.SilkS")
		)
		(fp_line
			(start -4.53898 -2.150618)
			(end -4.539742 2.152142)
			(stroke
				(width 0.1524)
				(type default)
			)
			(layer "F.SilkS")
		)
		(fp_line
			(start -4.53898 -2.15011)
			(end 4.53898 -2.15011)
			(stroke
				(width 0.1524)
				(type default)
			)
			(layer "F.SilkS")
		)
		(fp_line
			(start -4.53898 2.15011)
			(end -4.53898 -2.15011)
			(stroke
				(width 0.1524)
				(type default)
			)
			(layer "F.SilkS")
		)
		(fp_line
			(start 4.53898 -2.15011)
			(end 4.53898 2.15011)
			(stroke
				(width 0.1524)
				(type default)
			)
			(layer "F.SilkS")
		)
		(fp_line
			(start 4.53898 2.15011)
			(end -4.53898 2.15011)
			(stroke
				(width 0.1524)
				(type default)
			)
			(layer "F.SilkS")
		)
		(fp_line
			(start -3.64998 -2.15011)
			(end 3.64998 -2.15011)
			(stroke
				(width 0.1)
				(type default)
			)
			(layer "F.Fab")
		)
		(fp_line
			(start -3.64998 2.15011)
			(end -3.64998 -2.15011)
			(stroke
				(width 0.1)
				(type default)
			)
			(layer "F.Fab")
		)
		(fp_line
			(start 3.64998 -2.15011)
			(end 3.64998 2.15011)
			(stroke
				(width 0.1)
				(type default)
			)
			(layer "F.Fab")
		)
		(fp_line
			(start 3.64998 2.15011)
			(end -3.64998 2.15011)
			(stroke
				(width 0.1)
				(type default)
			)
			(layer "F.Fab")
		)
		(fp_text user "+"
			(at -6.161532 0.996442 0)
			(unlocked yes)
			(layer "F.SilkS")
			(effects
				(font
					(size 1.905 1.4224)
					(thickness 0.1524)
				)
				(justify left)
			)
		)
		(fp_text user "-"
			(at 6.662166 -2.306828 180)
			(unlocked yes)
			(layer "F.SilkS")
			(effects
				(font
					(size 1.905 1.4224)
					(thickness 0.1524)
				)
				(justify left)
			)
		)
		(fp_text user "+"
			(at -6.214872 -0.337058 0)
			(unlocked yes)
			(layer "F.Fab")
			(effects
				(font
					(size 1.905 1.4224)
					(thickness 0.1524)
				)
				(justify left)
			)
		)
		(fp_text user "-"
			(at 4.313174 -0.094488 0)
			(unlocked yes)
			(layer "F.Fab")
			(effects
				(font
					(size 1.905 1.4224)
					(thickness 0.1524)
				)
				(justify left)
			)
		)
		(pad "1" smd rect
			(at -3.199892 0)
			(size 2.413 2.8194)
			(layers "F.Cu" "F.Mask" "F.Paste")
			(net "P0V9_CPU0_RT_2D")
		)
		(pad "2" smd rect
			(at 3.199892 0)
			(size 2.413 2.8194)
			(layers "F.Cu" "F.Mask" "F.Paste")
			(net "GND")
		)
	)
	(footprint ""
		(layer "F.Cu")
		(at 120.396 -432.054)
		(property "Reference" "R3449"
			(at 0 0 0)
			(layer "F.SilkS")
			(hide yes)
			(effects
				(font
					(size 1.27 1.27)
				)
			)
		)
		(property "Value" ""
			(at 0 0 0)
			(layer "F.Fab")
			(effects
				(font
					(size 1.27 1.27)
				)
			)
		)
		(duplicate_pad_numbers_are_jumpers no)
		(fp_line
			(start -0.7874 -0.4064)
			(end 0.7874 -0.4064)
			(stroke
				(width 0.1524)
				(type default)
			)
			(layer "F.SilkS")
		)
		(fp_line
			(start -0.7874 0.4064)
			(end -0.7874 -0.4064)
			(stroke
				(width 0.1524)
				(type default)
			)
			(layer "F.SilkS")
		)
		(fp_line
			(start 0.7874 -0.4064)
			(end 0.7874 0.4064)
			(stroke
				(width 0.1524)
				(type default)
			)
			(layer "F.SilkS")
		)
		(fp_line
			(start 0.7874 0.4064)
			(end -0.7874 0.4064)
			(stroke
				(width 0.1524)
				(type default)
			)
			(layer "F.SilkS")
		)
		(fp_line
			(start -0.67945 -0.305054)
			(end -0.12065 -0.305054)
			(stroke
				(width 0.1)
				(type default)
			)
			(layer "F.Fab")
		)
		(fp_line
			(start -0.67945 0.3048)
			(end -0.67945 -0.305054)
			(stroke
				(width 0.1)
				(type default)
			)
			(layer "F.Fab")
		)
		(fp_line
			(start -0.12065 -0.305054)
			(end -0.12065 -0.2794)
			(stroke
				(width 0.1)
				(type default)
			)
			(layer "F.Fab")
		)
		(fp_line
			(start -0.12065 -0.2794)
			(end 0.12065 -0.2794)
			(stroke
				(width 0.1)
				(type default)
			)
			(layer "F.Fab")
		)
		(fp_line
			(start -0.12065 0.2794)
			(end -0.12065 0.3048)
			(stroke
				(width 0.1)
				(type default)
			)
			(layer "F.Fab")
		)
		(fp_line
			(start -0.12065 0.3048)
			(end -0.67945 0.3048)
			(stroke
				(width 0.1)
				(type default)
			)
			(layer "F.Fab")
		)
		(fp_line
			(start 0.120396 0.2794)
			(end -0.12065 0.2794)
			(stroke
				(width 0.1)
				(type default)
			)
			(layer "F.Fab")
		)
		(fp_line
			(start 0.120396 0.3048)
			(end 0.120396 0.2794)
			(stroke
				(width 0.1)
				(type default)
			)
			(layer "F.Fab")
		)
		(fp_line
			(start 0.12065 -0.3048)
			(end 0.67945 -0.3048)
			(stroke
				(width 0.1)
				(type default)
			)
			(layer "F.Fab")
		)
		(fp_line
			(start 0.12065 -0.2794)
			(end 0.12065 -0.3048)
			(stroke
				(width 0.1)
				(type default)
			)
			(layer "F.Fab")
		)
		(fp_line
			(start 0.67945 -0.3048)
			(end 0.67945 0.3048)
			(stroke
				(width 0.1)
				(type default)
			)
			(layer "F.Fab")
		)
		(fp_line
			(start 0.67945 0.3048)
			(end 0.120396 0.3048)
			(stroke
				(width 0.1)
				(type default)
			)
			(layer "F.Fab")
		)
		(pad "1" smd circle
			(at -0.40005 0)
			(size 0 0)
			(layers "F.Cu" "F.Mask" "F.Paste")
			(net "GPU_FPGA_BOOT_EN")
		)
		(pad "2" smd circle
			(at 0.40005 0)
			(size 0 0)
			(layers "F.Cu" "F.Mask" "F.Paste")
			(net "GND")
		)
	)
	(footprint ""
		(layer "F.Cu")
		(at 35.881818 -437.449214 180)
		(property "Reference" "R3521"
			(at 0 0 180)
			(layer "F.SilkS")
			(hide yes)
			(effects
				(font
					(size 1.27 1.27)
				)
			)
		)
		(property "Value" ""
			(at 0 0 180)
			(layer "F.Fab")
			(effects
				(font
					(size 1.27 1.27)
				)
			)
		)
		(duplicate_pad_numbers_are_jumpers no)
		(fp_line
			(start 0.7874 0.4064)
			(end -0.7874 0.4064)
			(stroke
				(width 0.1524)
				(type default)
			)
			(layer "F.SilkS")
		)
		(fp_line
			(start 0.7874 -0.4064)
			(end 0.7874 0.4064)
			(stroke
				(width 0.1524)
				(type default)
			)
			(layer "F.SilkS")
		)
		(fp_line
			(start -0.7874 0.4064)
			(end -0.7874 -0.4064)
			(stroke
				(width 0.1524)
				(type default)
			)
			(layer "F.SilkS")
		)
		(fp_line
			(start -0.7874 -0.4064)
			(end 0.7874 -0.4064)
			(stroke
				(width 0.1524)
				(type default)
			)
			(layer "F.SilkS")
		)
		(fp_line
			(start 0.67945 0.3048)
			(end 0.120396 0.3048)
			(stroke
				(width 0.1)
				(type default)
			)
			(layer "F.Fab")
		)
		(fp_line
			(start 0.67945 -0.3048)
			(end 0.67945 0.3048)
			(stroke
				(width 0.1)
				(type default)
			)
			(layer "F.Fab")
		)
		(fp_line
			(start 0.12065 -0.2794)
			(end 0.12065 -0.3048)
			(stroke
				(width 0.1)
				(type default)
			)
			(layer "F.Fab")
		)
		(fp_line
			(start 0.12065 -0.3048)
			(end 0.67945 -0.3048)
			(stroke
				(width 0.1)
				(type default)
			)
			(layer "F.Fab")
		)
		(fp_line
			(start 0.120396 0.3048)
			(end 0.120396 0.2794)
			(stroke
				(width 0.1)
				(type default)
			)
			(layer "F.Fab")
		)
		(fp_line
			(start 0.120396 0.2794)
			(end -0.12065 0.2794)
			(stroke
				(width 0.1)
				(type default)
			)
			(layer "F.Fab")
		)
		(fp_line
			(start -0.12065 0.3048)
			(end -0.67945 0.3048)
			(stroke
				(width 0.1)
				(type default)
			)
			(layer "F.Fab")
		)
		(fp_line
			(start -0.12065 0.2794)
			(end -0.12065 0.3048)
			(stroke
				(width 0.1)
				(type default)
			)
			(layer "F.Fab")
		)
		(fp_line
			(start -0.12065 -0.2794)
			(end 0.12065 -0.2794)
			(stroke
				(width 0.1)
				(type default)
			)
			(layer "F.Fab")
		)
		(fp_line
			(start -0.12065 -0.305054)
			(end -0.12065 -0.2794)
			(stroke
				(width 0.1)
				(type default)
			)
			(layer "F.Fab")
		)
		(fp_line
			(start -0.67945 0.3048)
			(end -0.67945 -0.305054)
			(stroke
				(width 0.1)
				(type default)
			)
			(layer "F.Fab")
		)
		(fp_line
			(start -0.67945 -0.305054)
			(end -0.12065 -0.305054)
			(stroke
				(width 0.1)
				(type default)
			)
			(layer "F.Fab")
		)
		(pad "1" smd circle
			(at -0.40005 0 180)
			(size 0 0)
			(layers "F.Cu" "F.Mask" "F.Paste")
			(net "P3V3_AUX")
		)
		(pad "2" smd circle
			(at 0.40005 0 180)
			(size 0 0)
			(layers "F.Cu" "F.Mask" "F.Paste")
			(net "SMB_2_BMC_GPU_BUF_R_SCL")
		)
	)
	(footprint ""
		(layer "F.Cu")
		(at 279.513792 -124.305314 180)
		(property "Reference" "R587"
			(at 0 0 180)
			(layer "F.SilkS")
			(hide yes)
			(effects
				(font
					(size 1.27 1.27)
				)
			)
		)
		(property "Value" ""
			(at 0 0 180)
			(layer "F.Fab")
			(effects
				(font
					(size 1.27 1.27)
				)
			)
		)
		(duplicate_pad_numbers_are_jumpers no)
		(fp_line
			(start 0.7874 0.4064)
			(end -0.7874 0.4064)
			(stroke
				(width 0.1524)
				(type default)
			)
			(layer "F.SilkS")
		)
		(fp_line
			(start 0.7874 -0.4064)
			(end 0.7874 0.4064)
			(stroke
				(width 0.1524)
				(type default)
			)
			(layer "F.SilkS")
		)
		(fp_line
			(start -0.7874 0.4064)
			(end -0.7874 -0.4064)
			(stroke
				(width 0.1524)
				(type default)
			)
			(layer "F.SilkS")
		)
		(fp_line
			(start -0.7874 -0.4064)
			(end 0.7874 -0.4064)
			(stroke
				(width 0.1524)
				(type default)
			)
			(layer "F.SilkS")
		)
		(fp_line
			(start 0.67945 0.3048)
			(end 0.120396 0.3048)
			(stroke
				(width 0.1)
				(type default)
			)
			(layer "F.Fab")
		)
		(fp_line
			(start 0.67945 -0.3048)
			(end 0.67945 0.3048)
			(stroke
				(width 0.1)
				(type default)
			)
			(layer "F.Fab")
		)
		(fp_line
			(start 0.12065 -0.2794)
			(end 0.12065 -0.3048)
			(stroke
				(width 0.1)
				(type default)
			)
			(layer "F.Fab")
		)
		(fp_line
			(start 0.12065 -0.3048)
			(end 0.67945 -0.3048)
			(stroke
				(width 0.1)
				(type default)
			)
			(layer "F.Fab")
		)
		(fp_line
			(start 0.120396 0.3048)
			(end 0.120396 0.2794)
			(stroke
				(width 0.1)
				(type default)
			)
			(layer "F.Fab")
		)
		(fp_line
			(start 0.120396 0.2794)
			(end -0.12065 0.2794)
			(stroke
				(width 0.1)
				(type default)
			)
			(layer "F.Fab")
		)
		(fp_line
			(start -0.12065 0.3048)
			(end -0.67945 0.3048)
			(stroke
				(width 0.1)
				(type default)
			)
			(layer "F.Fab")
		)
		(fp_line
			(start -0.12065 0.2794)
			(end -0.12065 0.3048)
			(stroke
				(width 0.1)
				(type default)
			)
			(layer "F.Fab")
		)
		(fp_line
			(start -0.12065 -0.2794)
			(end 0.12065 -0.2794)
			(stroke
				(width 0.1)
				(type default)
			)
			(layer "F.Fab")
		)
		(fp_line
			(start -0.12065 -0.305054)
			(end -0.12065 -0.2794)
			(stroke
				(width 0.1)
				(type default)
			)
			(layer "F.Fab")
		)
		(fp_line
			(start -0.67945 0.3048)
			(end -0.67945 -0.305054)
			(stroke
				(width 0.1)
				(type default)
			)
			(layer "F.Fab")
		)
		(fp_line
			(start -0.67945 -0.305054)
			(end -0.12065 -0.305054)
			(stroke
				(width 0.1)
				(type default)
			)
			(layer "F.Fab")
		)
		(pad "1" smd circle
			(at -0.40005 0 180)
			(size 0 0)
			(layers "F.Cu" "F.Mask" "F.Paste")
			(net "PCA9548_PCIE3_ADDR0")
		)
		(pad "2" smd circle
			(at 0.40005 0 180)
			(size 0 0)
			(layers "F.Cu" "F.Mask" "F.Paste")
			(net "GND")
		)
	)
	(footprint ""
		(layer "F.Cu")
		(at 12.769088 -373.44985 -90)
		(property "Reference" "PC6629"
			(at 4.41452 2.355088 0)
			(unlocked yes)
			(layer "F.SilkS")
			(effects
				(font
					(size 0.7874 0.5842)
					(thickness 0.1524)
				)
				(justify left)
			)
		)
		(property "Value" ""
			(at 0 0 270)
			(layer "F.Fab")
			(effects
				(font
					(size 1.27 1.27)
				)
			)
		)
		(duplicate_pad_numbers_are_jumpers no)
		(fp_line
			(start -1.988058 2.750058)
			(end 2.750058 2.750058)
			(stroke
				(width 0.1524)
				(type default)
			)
			(layer "F.SilkS")
		)
		(fp_line
			(start 2.750058 2.750058)
			(end 2.750058 0.9398)
			(stroke
				(width 0.1524)
				(type default)
			)
			(layer "F.SilkS")
		)
		(fp_line
			(start -2.750058 1.988058)
			(end -1.988058 2.750058)
			(stroke
				(width 0.1524)
				(type default)
			)
			(layer "F.SilkS")
		)
		(fp_line
			(start -2.750058 0.9398)
			(end -2.750058 1.988058)
			(stroke
				(width 0.1524)
				(type default)
			)
			(layer "F.SilkS")
		)
		(fp_line
			(start 2.750058 -0.9398)
			(end 2.750058 -2.750058)
			(stroke
				(width 0.1524)
				(type default)
			)
			(layer "F.SilkS")
		)
		(fp_line
			(start -2.750058 -1.988058)
			(end -2.750058 -0.9398)
			(stroke
				(width 0.1524)
				(type default)
			)
			(layer "F.SilkS")
		)
		(fp_line
			(start -1.988058 -2.750058)
			(end -2.750058 -1.988058)
			(stroke
				(width 0.1524)
				(type default)
			)
			(layer "F.SilkS")
		)
		(fp_line
			(start 2.750058 -2.750058)
			(end -1.988058 -2.750058)
			(stroke
				(width 0.1524)
				(type default)
			)
			(layer "F.SilkS")
		)
		(fp_line
			(start -2.750058 2.750058)
			(end 2.750058 2.750058)
			(stroke
				(width 0.1)
				(type default)
			)
			(layer "F.Fab")
		)
		(fp_line
			(start 2.750058 2.750058)
			(end 2.750058 -2.750058)
			(stroke
				(width 0.1)
				(type default)
			)
			(layer "F.Fab")
		)
		(fp_line
			(start -2.750058 -2.750058)
			(end -2.750058 2.750058)
			(stroke
				(width 0.1)
				(type default)
			)
			(layer "F.Fab")
		)
		(fp_line
			(start 2.750058 -2.750058)
			(end -2.750058 -2.750058)
			(stroke
				(width 0.1)
				(type default)
			)
			(layer "F.Fab")
		)
		(pad "1" smd rect
			(at -2.199894 0)
			(size 1.6002 3.0226)
			(layers "F.Cu" "F.Mask" "F.Paste")
			(net "P0V9_CPU1_RT_2D")
		)
		(pad "2" smd rect
			(at 2.199894 0)
			(size 1.6002 3.0226)
			(layers "F.Cu" "F.Mask" "F.Paste")
			(net "GND")
		)
	)
	(footprint ""
		(layer "F.Cu")
		(at 118.11 -400.3548)
		(property "Reference" "R1451"
			(at 0 0 0)
			(layer "F.SilkS")
			(hide yes)
			(effects
				(font
					(size 1.27 1.27)
				)
			)
		)
		(property "Value" ""
			(at 0 0 0)
			(layer "F.Fab")
			(effects
				(font
					(size 1.27 1.27)
				)
			)
		)
		(duplicate_pad_numbers_are_jumpers no)
		(fp_line
			(start -0.32512 -0.175006)
			(end 0.32512 -0.175006)
			(stroke
				(width 0.1)
				(type default)
			)
			(layer "F.Fab")
		)
		(fp_line
			(start -0.32512 0.175006)
			(end -0.32512 -0.175006)
			(stroke
				(width 0.1)
				(type default)
			)
			(layer "F.Fab")
		)
		(fp_line
			(start 0.32512 -0.175006)
			(end 0.32512 0.175006)
			(stroke
				(width 0.1)
				(type default)
			)
			(layer "F.Fab")
		)
		(fp_line
			(start 0.32512 0.175006)
			(end -0.32512 0.175006)
			(stroke
				(width 0.1)
				(type default)
			)
			(layer "F.Fab")
		)
		(pad "1" smd rect
			(at -0.2667 0)
			(size 0.3048 0.381)
			(layers "F.Cu" "F.Mask" "F.Paste")
			(net "P1V8_CPU1_RT_1D")
		)
		(pad "2" smd rect
			(at 0.2667 0 180)
			(size 0.3048 0.381)
			(layers "F.Cu" "F.Mask" "F.Paste")
			(net "SMB_RT_CPU1_P1_ROM_MUX_1D_SCL")
		)
	)
	(footprint ""
		(layer "F.Cu")
		(at 420.246302 -436.164736 -90)
		(property "Reference" "R4158"
			(at 0 0 270)
			(layer "F.SilkS")
			(hide yes)
			(effects
				(font
					(size 1.27 1.27)
				)
			)
		)
		(property "Value" ""
			(at 0 0 270)
			(layer "F.Fab")
			(effects
				(font
					(size 1.27 1.27)
				)
			)
		)
		(duplicate_pad_numbers_are_jumpers no)
		(fp_line
			(start -0.7874 0.4064)
			(end -0.7874 -0.4064)
			(stroke
				(width 0.1524)
				(type default)
			)
			(layer "F.SilkS")
		)
		(fp_line
			(start 0.7874 0.4064)
			(end -0.7874 0.4064)
			(stroke
				(width 0.1524)
				(type default)
			)
			(layer "F.SilkS")
		)
		(fp_line
			(start -0.7874 -0.4064)
			(end 0.7874 -0.4064)
			(stroke
				(width 0.1524)
				(type default)
			)
			(layer "F.SilkS")
		)
		(fp_line
			(start 0.7874 -0.4064)
			(end 0.7874 0.4064)
			(stroke
				(width 0.1524)
				(type default)
			)
			(layer "F.SilkS")
		)
		(fp_line
			(start -0.67945 0.3048)
			(end -0.67945 -0.305054)
			(stroke
				(width 0.1)
				(type default)
			)
			(layer "F.Fab")
		)
		(fp_line
			(start -0.12065 0.3048)
			(end -0.67945 0.3048)
			(stroke
				(width 0.1)
				(type default)
			)
			(layer "F.Fab")
		)
		(fp_line
			(start 0.120396 0.3048)
			(end 0.120396 0.2794)
			(stroke
				(width 0.1)
				(type default)
			)
			(layer "F.Fab")
		)
		(fp_line
			(start 0.67945 0.3048)
			(end 0.120396 0.3048)
			(stroke
				(width 0.1)
				(type default)
			)
			(layer "F.Fab")
		)
		(fp_line
			(start -0.12065 0.2794)
			(end -0.12065 0.3048)
			(stroke
				(width 0.1)
				(type default)
			)
			(layer "F.Fab")
		)
		(fp_line
			(start 0.120396 0.2794)
			(end -0.12065 0.2794)
			(stroke
				(width 0.1)
				(type default)
			)
			(layer "F.Fab")
		)
		(fp_line
			(start -0.12065 -0.2794)
			(end 0.12065 -0.2794)
			(stroke
				(width 0.1)
				(type default)
			)
			(layer "F.Fab")
		)
		(fp_line
			(start 0.12065 -0.2794)
			(end 0.12065 -0.3048)
			(stroke
				(width 0.1)
				(type default)
			)
			(layer "F.Fab")
		)
		(fp_line
			(start 0.12065 -0.3048)
			(end 0.67945 -0.3048)
			(stroke
				(width 0.1)
				(type default)
			)
			(layer "F.Fab")
		)
		(fp_line
			(start 0.67945 -0.3048)
			(end 0.67945 0.3048)
			(stroke
				(width 0.1)
				(type default)
			)
			(layer "F.Fab")
		)
		(fp_line
			(start -0.67945 -0.305054)
			(end -0.12065 -0.305054)
			(stroke
				(width 0.1)
				(type default)
			)
			(layer "F.Fab")
		)
		(fp_line
			(start -0.12065 -0.305054)
			(end -0.12065 -0.2794)
			(stroke
				(width 0.1)
				(type default)
			)
			(layer "F.Fab")
		)
		(pad "1" smd circle
			(at -0.40005 0 270)
			(size 0 0)
			(layers "F.Cu" "F.Mask" "F.Paste")
			(net "P3V3_AUX")
		)
		(pad "2" smd circle
			(at 0.40005 0 270)
			(size 0 0)
			(layers "F.Cu" "F.Mask" "F.Paste")
			(net "GPU_3V3IO_RSVD1")
		)
	)
	(footprint ""
		(layer "F.Cu")
		(at 398.06245 -146.148552 -90)
		(property "Reference" "C1331"
			(at 0 0 270)
			(layer "F.SilkS")
			(hide yes)
			(effects
				(font
					(size 1.27 1.27)
				)
			)
		)
		(property "Value" ""
			(at 0 0 270)
			(layer "F.Fab")
			(effects
				(font
					(size 1.27 1.27)
				)
			)
		)
		(duplicate_pad_numbers_are_jumpers no)
		(fp_line
			(start -1.524 0.762)
			(end -1.524 -0.762)
			(stroke
				(width 0.1524)
				(type default)
			)
			(layer "F.SilkS")
		)
		(fp_line
			(start 1.524 0.762)
			(end -1.524 0.762)
			(stroke
				(width 0.1524)
				(type default)
			)
			(layer "F.SilkS")
		)
		(fp_line
			(start -1.524 -0.762)
			(end 1.524 -0.762)
			(stroke
				(width 0.1524)
				(type default)
			)
			(layer "F.SilkS")
		)
		(fp_line
			(start 1.524 -0.762)
			(end 1.524 0.762)
			(stroke
				(width 0.1524)
				(type default)
			)
			(layer "F.SilkS")
		)
		(fp_line
			(start -1.1049 0.724916)
			(end 1.1049 0.724916)
			(stroke
				(width 0.1)
				(type default)
			)
			(layer "F.Fab")
		)
		(fp_line
			(start 1.1049 0.724916)
			(end 1.1049 -0.724916)
			(stroke
				(width 0.1)
				(type default)
			)
			(layer "F.Fab")
		)
		(fp_line
			(start -1.1049 -0.724916)
			(end -1.1049 0.724916)
			(stroke
				(width 0.1)
				(type default)
			)
			(layer "F.Fab")
		)
		(fp_line
			(start 1.1049 -0.724916)
			(end -1.1049 -0.724916)
			(stroke
				(width 0.1)
				(type default)
			)
			(layer "F.Fab")
		)
		(pad "1" smd rect
			(at -0.889 0 90)
			(size 1.016 1.27)
			(layers "F.Cu" "F.Mask" "F.Paste")
			(net "P5V")
		)
		(pad "2" smd rect
			(at 0.889 0 90)
			(size 1.016 1.27)
			(layers "F.Cu" "F.Mask" "F.Paste")
			(net "GND")
		)
	)
	(footprint ""
		(layer "F.Cu")
		(at 145.823178 -75.115166 90)
		(property "Reference" "R6243"
			(at 0 0 90)
			(layer "F.SilkS")
			(hide yes)
			(effects
				(font
					(size 1.27 1.27)
				)
			)
		)
		(property "Value" ""
			(at 0 0 90)
			(layer "F.Fab")
			(effects
				(font
					(size 1.27 1.27)
				)
			)
		)
		(duplicate_pad_numbers_are_jumpers no)
		(fp_line
			(start 0.7874 -0.4064)
			(end 0.7874 0.4064)
			(stroke
				(width 0.1524)
				(type default)
			)
			(layer "F.SilkS")
		)
		(fp_line
			(start -0.7874 -0.4064)
			(end 0.7874 -0.4064)
			(stroke
				(width 0.1524)
				(type default)
			)
			(layer "F.SilkS")
		)
		(fp_line
			(start 0.7874 0.4064)
			(end -0.7874 0.4064)
			(stroke
				(width 0.1524)
				(type default)
			)
			(layer "F.SilkS")
		)
		(fp_line
			(start -0.7874 0.4064)
			(end -0.7874 -0.4064)
			(stroke
				(width 0.1524)
				(type default)
			)
			(layer "F.SilkS")
		)
		(fp_line
			(start -0.12065 -0.305054)
			(end -0.12065 -0.2794)
			(stroke
				(width 0.1)
				(type default)
			)
			(layer "F.Fab")
		)
		(fp_line
			(start -0.67945 -0.305054)
			(end -0.12065 -0.305054)
			(stroke
				(width 0.1)
				(type default)
			)
			(layer "F.Fab")
		)
		(fp_line
			(start 0.67945 -0.3048)
			(end 0.67945 0.3048)
			(stroke
				(width 0.1)
				(type default)
			)
			(layer "F.Fab")
		)
		(fp_line
			(start 0.12065 -0.3048)
			(end 0.67945 -0.3048)
			(stroke
				(width 0.1)
				(type default)
			)
			(layer "F.Fab")
		)
		(fp_line
			(start 0.12065 -0.2794)
			(end 0.12065 -0.3048)
			(stroke
				(width 0.1)
				(type default)
			)
			(layer "F.Fab")
		)
		(fp_line
			(start -0.12065 -0.2794)
			(end 0.12065 -0.2794)
			(stroke
				(width 0.1)
				(type default)
			)
			(layer "F.Fab")
		)
		(fp_line
			(start 0.120396 0.2794)
			(end -0.12065 0.2794)
			(stroke
				(width 0.1)
				(type default)
			)
			(layer "F.Fab")
		)
		(fp_line
			(start -0.12065 0.2794)
			(end -0.12065 0.3048)
			(stroke
				(width 0.1)
				(type default)
			)
			(layer "F.Fab")
		)
		(fp_line
			(start 0.67945 0.3048)
			(end 0.120396 0.3048)
			(stroke
				(width 0.1)
				(type default)
			)
			(layer "F.Fab")
		)
		(fp_line
			(start 0.120396 0.3048)
			(end 0.120396 0.2794)
			(stroke
				(width 0.1)
				(type default)
			)
			(layer "F.Fab")
		)
		(fp_line
			(start -0.12065 0.3048)
			(end -0.67945 0.3048)
			(stroke
				(width 0.1)
				(type default)
			)
			(layer "F.Fab")
		)
		(fp_line
			(start -0.67945 0.3048)
			(end -0.67945 -0.305054)
			(stroke
				(width 0.1)
				(type default)
			)
			(layer "F.Fab")
		)
		(pad "1" smd circle
			(at -0.40005 0 90)
			(size 0 0)
			(layers "F.Cu" "F.Mask" "F.Paste")
			(net "P3V3_AUX")
		)
		(pad "2" smd circle
			(at 0.40005 0 90)
			(size 0 0)
			(layers "F.Cu" "F.Mask" "F.Paste")
			(net "PWRGD_P1V8_AUX")
		)
	)
	(footprint ""
		(layer "F.Cu")
		(at 36.449 -366.776 -90)
		(property "Reference" "PC364"
			(at 0 0 270)
			(layer "F.SilkS")
			(hide yes)
			(effects
				(font
					(size 1.27 1.27)
				)
			)
		)
		(property "Value" ""
			(at 0 0 270)
			(layer "F.Fab")
			(effects
				(font
					(size 1.27 1.27)
				)
			)
		)
		(duplicate_pad_numbers_are_jumpers no)
		(fp_line
			(start -0.7874 0.4064)
			(end -0.7874 -0.4064)
			(stroke
				(width 0.1524)
				(type default)
			)
			(layer "F.SilkS")
		)
		(fp_line
			(start 0.7874 0.4064)
			(end -0.7874 0.4064)
			(stroke
				(width 0.1524)
				(type default)
			)
			(layer "F.SilkS")
		)
		(fp_line
			(start -0.7874 -0.4064)
			(end 0.7874 -0.4064)
			(stroke
				(width 0.1524)
				(type default)
			)
			(layer "F.SilkS")
		)
		(fp_line
			(start 0.7874 -0.4064)
			(end 0.7874 0.4064)
			(stroke
				(width 0.1524)
				(type default)
			)
			(layer "F.SilkS")
		)
		(fp_line
			(start -0.67945 0.3048)
			(end -0.67945 -0.305054)
			(stroke
				(width 0.1)
				(type default)
			)
			(layer "F.Fab")
		)
		(fp_line
			(start -0.12065 0.3048)
			(end -0.67945 0.3048)
			(stroke
				(width 0.1)
				(type default)
			)
			(layer "F.Fab")
		)
		(fp_line
			(start 0.120396 0.3048)
			(end 0.120396 0.2794)
			(stroke
				(width 0.1)
				(type default)
			)
			(layer "F.Fab")
		)
		(fp_line
			(start 0.67945 0.3048)
			(end 0.120396 0.3048)
			(stroke
				(width 0.1)
				(type default)
			)
			(layer "F.Fab")
		)
		(fp_line
			(start -0.12065 0.2794)
			(end -0.12065 0.3048)
			(stroke
				(width 0.1)
				(type default)
			)
			(layer "F.Fab")
		)
		(fp_line
			(start 0.120396 0.2794)
			(end -0.12065 0.2794)
			(stroke
				(width 0.1)
				(type default)
			)
			(layer "F.Fab")
		)
		(fp_line
			(start -0.12065 -0.2794)
			(end 0.12065 -0.2794)
			(stroke
				(width 0.1)
				(type default)
			)
			(layer "F.Fab")
		)
		(fp_line
			(start 0.12065 -0.2794)
			(end 0.12065 -0.3048)
			(stroke
				(width 0.1)
				(type default)
			)
			(layer "F.Fab")
		)
		(fp_line
			(start 0.12065 -0.3048)
			(end 0.67945 -0.3048)
			(stroke
				(width 0.1)
				(type default)
			)
			(layer "F.Fab")
		)
		(fp_line
			(start 0.67945 -0.3048)
			(end 0.67945 0.3048)
			(stroke
				(width 0.1)
				(type default)
			)
			(layer "F.Fab")
		)
		(fp_line
			(start -0.67945 -0.305054)
			(end -0.12065 -0.305054)
			(stroke
				(width 0.1)
				(type default)
			)
			(layer "F.Fab")
		)
		(fp_line
			(start -0.12065 -0.305054)
			(end -0.12065 -0.2794)
			(stroke
				(width 0.1)
				(type default)
			)
			(layer "F.Fab")
		)
		(pad "1" smd circle
			(at -0.40005 0 270)
			(size 0 0)
			(layers "F.Cu" "F.Mask" "F.Paste")
			(net "PVDDCR_CPU1_P1_VINSEN")
		)
		(pad "2" smd circle
			(at 0.40005 0 270)
			(size 0 0)
			(layers "F.Cu" "F.Mask" "F.Paste")
			(net "GND")
		)
	)
	(footprint ""
		(layer "F.Cu")
		(at 385.049268 -33.226502 180)
		(property "Reference" "R4601"
			(at 0 0 180)
			(layer "F.SilkS")
			(hide yes)
			(effects
				(font
					(size 1.27 1.27)
				)
			)
		)
		(property "Value" ""
			(at 0 0 180)
			(layer "F.Fab")
			(effects
				(font
					(size 1.27 1.27)
				)
			)
		)
		(duplicate_pad_numbers_are_jumpers no)
		(fp_line
			(start 0.7874 0.4064)
			(end -0.7874 0.4064)
			(stroke
				(width 0.1524)
				(type default)
			)
			(layer "F.SilkS")
		)
		(fp_line
			(start 0.7874 -0.4064)
			(end 0.7874 0.4064)
			(stroke
				(width 0.1524)
				(type default)
			)
			(layer "F.SilkS")
		)
		(fp_line
			(start -0.7874 0.4064)
			(end -0.7874 -0.4064)
			(stroke
				(width 0.1524)
				(type default)
			)
			(layer "F.SilkS")
		)
		(fp_line
			(start -0.7874 -0.4064)
			(end 0.7874 -0.4064)
			(stroke
				(width 0.1524)
				(type default)
			)
			(layer "F.SilkS")
		)
		(fp_line
			(start 0.67945 0.3048)
			(end 0.120396 0.3048)
			(stroke
				(width 0.1)
				(type default)
			)
			(layer "F.Fab")
		)
		(fp_line
			(start 0.67945 -0.3048)
			(end 0.67945 0.3048)
			(stroke
				(width 0.1)
				(type default)
			)
			(layer "F.Fab")
		)
		(fp_line
			(start 0.12065 -0.2794)
			(end 0.12065 -0.3048)
			(stroke
				(width 0.1)
				(type default)
			)
			(layer "F.Fab")
		)
		(fp_line
			(start 0.12065 -0.3048)
			(end 0.67945 -0.3048)
			(stroke
				(width 0.1)
				(type default)
			)
			(layer "F.Fab")
		)
		(fp_line
			(start 0.120396 0.3048)
			(end 0.120396 0.2794)
			(stroke
				(width 0.1)
				(type default)
			)
			(layer "F.Fab")
		)
		(fp_line
			(start 0.120396 0.2794)
			(end -0.12065 0.2794)
			(stroke
				(width 0.1)
				(type default)
			)
			(layer "F.Fab")
		)
		(fp_line
			(start -0.12065 0.3048)
			(end -0.67945 0.3048)
			(stroke
				(width 0.1)
				(type default)
			)
			(layer "F.Fab")
		)
		(fp_line
			(start -0.12065 0.2794)
			(end -0.12065 0.3048)
			(stroke
				(width 0.1)
				(type default)
			)
			(layer "F.Fab")
		)
		(fp_line
			(start -0.12065 -0.2794)
			(end 0.12065 -0.2794)
			(stroke
				(width 0.1)
				(type default)
			)
			(layer "F.Fab")
		)
		(fp_line
			(start -0.12065 -0.305054)
			(end -0.12065 -0.2794)
			(stroke
				(width 0.1)
				(type default)
			)
			(layer "F.Fab")
		)
		(fp_line
			(start -0.67945 0.3048)
			(end -0.67945 -0.305054)
			(stroke
				(width 0.1)
				(type default)
			)
			(layer "F.Fab")
		)
		(fp_line
			(start -0.67945 -0.305054)
			(end -0.12065 -0.305054)
			(stroke
				(width 0.1)
				(type default)
			)
			(layer "F.Fab")
		)
		(pad "1" smd circle
			(at -0.40005 0 180)
			(size 0 0)
			(layers "F.Cu" "F.Mask" "F.Paste")
			(net "CLK_50M_NCSI_OCP_SFF_ISO")
		)
		(pad "2" smd circle
			(at 0.40005 0 180)
			(size 0 0)
			(layers "F.Cu" "F.Mask" "F.Paste")
			(net "CLK_50M_NCSI_OCP_SFF_ISO_R")
		)
	)
	(footprint ""
		(layer "F.Cu")
		(at 205.214982 -115.657376 180)
		(property "Reference" "R6114"
			(at 0 0 180)
			(layer "F.SilkS")
			(hide yes)
			(effects
				(font
					(size 1.27 1.27)
				)
			)
		)
		(property "Value" ""
			(at 0 0 180)
			(layer "F.Fab")
			(effects
				(font
					(size 1.27 1.27)
				)
			)
		)
		(duplicate_pad_numbers_are_jumpers no)
		(fp_line
			(start 0.7874 0.4064)
			(end -0.7874 0.4064)
			(stroke
				(width 0.1524)
				(type default)
			)
			(layer "F.SilkS")
		)
		(fp_line
			(start 0.7874 -0.4064)
			(end 0.7874 0.4064)
			(stroke
				(width 0.1524)
				(type default)
			)
			(layer "F.SilkS")
		)
		(fp_line
			(start -0.7874 0.4064)
			(end -0.7874 -0.4064)
			(stroke
				(width 0.1524)
				(type default)
			)
			(layer "F.SilkS")
		)
		(fp_line
			(start -0.7874 -0.4064)
			(end 0.7874 -0.4064)
			(stroke
				(width 0.1524)
				(type default)
			)
			(layer "F.SilkS")
		)
		(fp_line
			(start 0.67945 0.3048)
			(end 0.120396 0.3048)
			(stroke
				(width 0.1)
				(type default)
			)
			(layer "F.Fab")
		)
		(fp_line
			(start 0.67945 -0.3048)
			(end 0.67945 0.3048)
			(stroke
				(width 0.1)
				(type default)
			)
			(layer "F.Fab")
		)
		(fp_line
			(start 0.12065 -0.2794)
			(end 0.12065 -0.3048)
			(stroke
				(width 0.1)
				(type default)
			)
			(layer "F.Fab")
		)
		(fp_line
			(start 0.12065 -0.3048)
			(end 0.67945 -0.3048)
			(stroke
				(width 0.1)
				(type default)
			)
			(layer "F.Fab")
		)
		(fp_line
			(start 0.120396 0.3048)
			(end 0.120396 0.2794)
			(stroke
				(width 0.1)
				(type default)
			)
			(layer "F.Fab")
		)
		(fp_line
			(start 0.120396 0.2794)
			(end -0.12065 0.2794)
			(stroke
				(width 0.1)
				(type default)
			)
			(layer "F.Fab")
		)
		(fp_line
			(start -0.12065 0.3048)
			(end -0.67945 0.3048)
			(stroke
				(width 0.1)
				(type default)
			)
			(layer "F.Fab")
		)
		(fp_line
			(start -0.12065 0.2794)
			(end -0.12065 0.3048)
			(stroke
				(width 0.1)
				(type default)
			)
			(layer "F.Fab")
		)
		(fp_line
			(start -0.12065 -0.2794)
			(end 0.12065 -0.2794)
			(stroke
				(width 0.1)
				(type default)
			)
			(layer "F.Fab")
		)
		(fp_line
			(start -0.12065 -0.305054)
			(end -0.12065 -0.2794)
			(stroke
				(width 0.1)
				(type default)
			)
			(layer "F.Fab")
		)
		(fp_line
			(start -0.67945 0.3048)
			(end -0.67945 -0.305054)
			(stroke
				(width 0.1)
				(type default)
			)
			(layer "F.Fab")
		)
		(fp_line
			(start -0.67945 -0.305054)
			(end -0.12065 -0.305054)
			(stroke
				(width 0.1)
				(type default)
			)
			(layer "F.Fab")
		)
		(pad "1" smd circle
			(at -0.40005 0 180)
			(size 0 0)
			(layers "F.Cu" "F.Mask" "F.Paste")
			(net "RST_PERST_CPU0_SWB_N")
		)
		(pad "2" smd circle
			(at 0.40005 0 180)
			(size 0 0)
			(layers "F.Cu" "F.Mask" "F.Paste")
			(net "GND")
		)
	)
	(footprint ""
		(layer "F.Cu")
		(at 451.327012 -30.397958 -90)
		(property "Reference" "PD101"
			(at 1.127506 -2.5654 90)
			(unlocked yes)
			(layer "F.SilkS")
			(effects
				(font
					(size 0.7874 0.5842)
					(thickness 0.1524)
				)
				(justify left)
			)
		)
		(property "Value" ""
			(at 0 0 270)
			(layer "F.Fab")
			(effects
				(font
					(size 1.27 1.27)
				)
			)
		)
		(duplicate_pad_numbers_are_jumpers no)
		(fp_line
			(start -2.250186 0.999998)
			(end 2.631186 0.999998)
			(stroke
				(width 0.1524)
				(type default)
			)
			(layer "F.SilkS")
		)
		(fp_line
			(start 2.631186 0.999998)
			(end 2.631186 -0.999998)
			(stroke
				(width 0.1524)
				(type default)
			)
			(layer "F.SilkS")
		)
		(fp_line
			(start -0.381 0.3302)
			(end -0.381 -0.4318)
			(stroke
				(width 0.1524)
				(type default)
			)
			(layer "F.SilkS")
		)
		(fp_line
			(start -0.381 -0.0508)
			(end -0.6604 -0.0508)
			(stroke
				(width 0.1524)
				(type default)
			)
			(layer "F.SilkS")
		)
		(fp_line
			(start 0.381 -0.0508)
			(end -0.381 0.3302)
			(stroke
				(width 0.1524)
				(type default)
			)
			(layer "F.SilkS")
		)
		(fp_line
			(start 0.381 -0.0508)
			(end 0.635 -0.0508)
			(stroke
				(width 0.1524)
				(type default)
			)
			(layer "F.SilkS")
		)
		(fp_line
			(start -0.381 -0.4318)
			(end 0.381 -0.0508)
			(stroke
				(width 0.1524)
				(type default)
			)
			(layer "F.SilkS")
		)
		(fp_line
			(start 0.381 -0.4318)
			(end 0.381 0.3302)
			(stroke
				(width 0.1524)
				(type default)
			)
			(layer "F.SilkS")
		)
		(fp_line
			(start -2.250186 -0.999998)
			(end -2.250186 0.999998)
			(stroke
				(width 0.1524)
				(type default)
			)
			(layer "F.SilkS")
		)
		(fp_line
			(start 2.631186 -0.999998)
			(end -2.250186 -0.999998)
			(stroke
				(width 0.1524)
				(type default)
			)
			(layer "F.SilkS")
		)
		(fp_rect
			(start 2.6162 1.016)
			(end 2.1844 -0.9652)
			(stroke
				(width 0)
				(type default)
			)
			(fill yes)
			(layer "F.SilkS")
		)
		(fp_line
			(start -1.450086 0.999998)
			(end 1.450086 0.999998)
			(stroke
				(width 0.1)
				(type default)
			)
			(layer "F.Fab")
		)
		(fp_line
			(start 1.450086 0.999998)
			(end 1.450086 -0.999998)
			(stroke
				(width 0.1)
				(type default)
			)
			(layer "F.Fab")
		)
		(fp_line
			(start -1.450086 -0.999998)
			(end -1.450086 0.999998)
			(stroke
				(width 0.1)
				(type default)
			)
			(layer "F.Fab")
		)
		(fp_line
			(start 1.450086 -0.999998)
			(end -1.450086 -0.999998)
			(stroke
				(width 0.1)
				(type default)
			)
			(layer "F.Fab")
		)
		(fp_text user "+"
			(at -3.4798 -0.22225 270)
			(unlocked yes)
			(layer "F.SilkS")
			(effects
				(font
					(size 1.905 1.4224)
					(thickness 0.1524)
				)
				(justify left)
			)
		)
		(fp_text user "-"
			(at 2.4384 -0.22225 270)
			(unlocked yes)
			(layer "F.SilkS")
			(effects
				(font
					(size 1.905 1.4224)
					(thickness 0.1524)
				)
				(justify left)
			)
		)
		(fp_text user "+"
			(at -3.4798 -0.22225 270)
			(unlocked yes)
			(layer "F.Fab")
			(effects
				(font
					(size 1.905 1.4224)
					(thickness 0.1524)
				)
				(justify left)
			)
		)
		(fp_text user "-"
			(at 2.4384 -0.22225 270)
			(unlocked yes)
			(layer "F.Fab")
			(effects
				(font
					(size 1.905 1.4224)
					(thickness 0.1524)
				)
				(justify left)
			)
		)
		(pad "A" smd rect
			(at -1.450086 0 270)
			(size 1.3208 1.4224)
			(layers "F.Cu" "F.Mask" "F.Paste")
			(net "GND")
		)
		(pad "C" smd rect
			(at 1.450086 0 270)
			(size 1.3208 1.4224)
			(layers "F.Cu" "F.Mask" "F.Paste")
			(net "P12V_AUX")
		)
	)
	(footprint ""
		(layer "F.Cu")
		(at 119.513096 -370.57203 -90)
		(property "Reference" "C1534"
			(at 0 0 270)
			(layer "F.SilkS")
			(hide yes)
			(effects
				(font
					(size 1.27 1.27)
				)
			)
		)
		(property "Value" ""
			(at 0 0 270)
			(layer "F.Fab")
			(effects
				(font
					(size 1.27 1.27)
				)
			)
		)
		(duplicate_pad_numbers_are_jumpers no)
		(fp_line
			(start -0.299974 0.150114)
			(end -0.299974 -0.150114)
			(stroke
				(width 0.1)
				(type default)
			)
			(layer "F.Fab")
		)
		(fp_line
			(start 0.299974 0.150114)
			(end -0.299974 0.150114)
			(stroke
				(width 0.1)
				(type default)
			)
			(layer "F.Fab")
		)
		(fp_line
			(start -0.299974 -0.150114)
			(end 0.299974 -0.150114)
			(stroke
				(width 0.1)
				(type default)
			)
			(layer "F.Fab")
		)
		(fp_line
			(start 0.299974 -0.150114)
			(end 0.299974 0.150114)
			(stroke
				(width 0.1)
				(type default)
			)
			(layer "F.Fab")
		)
		(pad "1" smd rect
			(at -0.2667 0 270)
			(size 0.3048 0.381)
			(layers "F.Cu" "F.Mask" "F.Paste")
			(net "P5E_CPU1_P3_TX_C_DN<6>")
		)
		(pad "2" smd rect
			(at 0.2667 0 270)
			(size 0.3048 0.381)
			(layers "F.Cu" "F.Mask" "F.Paste")
			(net "P5E_CPU1_P3_TX_DN<6>")
		)
	)
	(footprint ""
		(layer "F.Cu")
		(at 45.932344 -418.888164)
		(property "Reference" "R1465"
			(at 0 0 0)
			(layer "F.SilkS")
			(hide yes)
			(effects
				(font
					(size 1.27 1.27)
				)
			)
		)
		(property "Value" ""
			(at 0 0 0)
			(layer "F.Fab")
			(effects
				(font
					(size 1.27 1.27)
				)
			)
		)
		(duplicate_pad_numbers_are_jumpers no)
		(fp_line
			(start -0.32512 -0.175006)
			(end 0.32512 -0.175006)
			(stroke
				(width 0.1)
				(type default)
			)
			(layer "F.Fab")
		)
		(fp_line
			(start -0.32512 0.175006)
			(end -0.32512 -0.175006)
			(stroke
				(width 0.1)
				(type default)
			)
			(layer "F.Fab")
		)
		(fp_line
			(start 0.32512 -0.175006)
			(end 0.32512 0.175006)
			(stroke
				(width 0.1)
				(type default)
			)
			(layer "F.Fab")
		)
		(fp_line
			(start 0.32512 0.175006)
			(end -0.32512 0.175006)
			(stroke
				(width 0.1)
				(type default)
			)
			(layer "F.Fab")
		)
		(pad "1" smd rect
			(at -0.2667 0)
			(size 0.3048 0.381)
			(layers "F.Cu" "F.Mask" "F.Paste")
			(net "P1V8_CPU1_RT_1D")
		)
		(pad "2" smd rect
			(at 0.2667 0 180)
			(size 0.3048 0.381)
			(layers "F.Cu" "F.Mask" "F.Paste")
			(net "JTAG_TMS_RT_CPU1_P0")
		)
	)
	(footprint ""
		(layer "F.Cu")
		(at 169.744644 -128.24333)
		(property "Reference" "R6851"
			(at 0 0 0)
			(layer "F.SilkS")
			(hide yes)
			(effects
				(font
					(size 1.27 1.27)
				)
			)
		)
		(property "Value" ""
			(at 0 0 0)
			(layer "F.Fab")
			(effects
				(font
					(size 1.27 1.27)
				)
			)
		)
		(duplicate_pad_numbers_are_jumpers no)
		(fp_line
			(start -0.7874 -0.4064)
			(end 0.7874 -0.4064)
			(stroke
				(width 0.1524)
				(type default)
			)
			(layer "F.SilkS")
		)
		(fp_line
			(start -0.7874 0.4064)
			(end -0.7874 -0.4064)
			(stroke
				(width 0.1524)
				(type default)
			)
			(layer "F.SilkS")
		)
		(fp_line
			(start 0.7874 -0.4064)
			(end 0.7874 0.4064)
			(stroke
				(width 0.1524)
				(type default)
			)
			(layer "F.SilkS")
		)
		(fp_line
			(start 0.7874 0.4064)
			(end -0.7874 0.4064)
			(stroke
				(width 0.1524)
				(type default)
			)
			(layer "F.SilkS")
		)
		(fp_line
			(start -0.67945 -0.305054)
			(end -0.12065 -0.305054)
			(stroke
				(width 0.1)
				(type default)
			)
			(layer "F.Fab")
		)
		(fp_line
			(start -0.67945 0.3048)
			(end -0.67945 -0.305054)
			(stroke
				(width 0.1)
				(type default)
			)
			(layer "F.Fab")
		)
		(fp_line
			(start -0.12065 -0.305054)
			(end -0.12065 -0.2794)
			(stroke
				(width 0.1)
				(type default)
			)
			(layer "F.Fab")
		)
		(fp_line
			(start -0.12065 -0.2794)
			(end 0.12065 -0.2794)
			(stroke
				(width 0.1)
				(type default)
			)
			(layer "F.Fab")
		)
		(fp_line
			(start -0.12065 0.2794)
			(end -0.12065 0.3048)
			(stroke
				(width 0.1)
				(type default)
			)
			(layer "F.Fab")
		)
		(fp_line
			(start -0.12065 0.3048)
			(end -0.67945 0.3048)
			(stroke
				(width 0.1)
				(type default)
			)
			(layer "F.Fab")
		)
		(fp_line
			(start 0.120396 0.2794)
			(end -0.12065 0.2794)
			(stroke
				(width 0.1)
				(type default)
			)
			(layer "F.Fab")
		)
		(fp_line
			(start 0.120396 0.3048)
			(end 0.120396 0.2794)
			(stroke
				(width 0.1)
				(type default)
			)
			(layer "F.Fab")
		)
		(fp_line
			(start 0.12065 -0.3048)
			(end 0.67945 -0.3048)
			(stroke
				(width 0.1)
				(type default)
			)
			(layer "F.Fab")
		)
		(fp_line
			(start 0.12065 -0.2794)
			(end 0.12065 -0.3048)
			(stroke
				(width 0.1)
				(type default)
			)
			(layer "F.Fab")
		)
		(fp_line
			(start 0.67945 -0.3048)
			(end 0.67945 0.3048)
			(stroke
				(width 0.1)
				(type default)
			)
			(layer "F.Fab")
		)
		(fp_line
			(start 0.67945 0.3048)
			(end 0.120396 0.3048)
			(stroke
				(width 0.1)
				(type default)
			)
			(layer "F.Fab")
		)
		(pad "1" smd circle
			(at -0.40005 0)
			(size 0 0)
			(layers "F.Cu" "F.Mask" "F.Paste")
			(net "P1V8_RETIMER_CPU1_EN")
		)
		(pad "2" smd circle
			(at 0.40005 0)
			(size 0 0)
			(layers "F.Cu" "F.Mask" "F.Paste")
			(net "P1V8_RETIMER_CPU1_R_EN")
		)
	)
	(footprint ""
		(layer "F.Cu")
		(at 10.066782 -404.976584 180)
		(property "Reference" "PR6538"
			(at 0 0 180)
			(layer "F.SilkS")
			(hide yes)
			(effects
				(font
					(size 1.27 1.27)
				)
			)
		)
		(property "Value" ""
			(at 0 0 180)
			(layer "F.Fab")
			(effects
				(font
					(size 1.27 1.27)
				)
			)
		)
		(duplicate_pad_numbers_are_jumpers no)
		(fp_line
			(start 0.7874 0.4064)
			(end -0.7874 0.4064)
			(stroke
				(width 0.1524)
				(type default)
			)
			(layer "F.SilkS")
		)
		(fp_line
			(start 0.7874 -0.4064)
			(end 0.7874 0.4064)
			(stroke
				(width 0.1524)
				(type default)
			)
			(layer "F.SilkS")
		)
		(fp_line
			(start -0.7874 0.4064)
			(end -0.7874 -0.4064)
			(stroke
				(width 0.1524)
				(type default)
			)
			(layer "F.SilkS")
		)
		(fp_line
			(start -0.7874 -0.4064)
			(end 0.7874 -0.4064)
			(stroke
				(width 0.1524)
				(type default)
			)
			(layer "F.SilkS")
		)
		(fp_line
			(start 0.67945 0.3048)
			(end 0.120396 0.3048)
			(stroke
				(width 0.1)
				(type default)
			)
			(layer "F.Fab")
		)
		(fp_line
			(start 0.67945 -0.3048)
			(end 0.67945 0.3048)
			(stroke
				(width 0.1)
				(type default)
			)
			(layer "F.Fab")
		)
		(fp_line
			(start 0.12065 -0.2794)
			(end 0.12065 -0.3048)
			(stroke
				(width 0.1)
				(type default)
			)
			(layer "F.Fab")
		)
		(fp_line
			(start 0.12065 -0.3048)
			(end 0.67945 -0.3048)
			(stroke
				(width 0.1)
				(type default)
			)
			(layer "F.Fab")
		)
		(fp_line
			(start 0.120396 0.3048)
			(end 0.120396 0.2794)
			(stroke
				(width 0.1)
				(type default)
			)
			(layer "F.Fab")
		)
		(fp_line
			(start 0.120396 0.2794)
			(end -0.12065 0.2794)
			(stroke
				(width 0.1)
				(type default)
			)
			(layer "F.Fab")
		)
		(fp_line
			(start -0.12065 0.3048)
			(end -0.67945 0.3048)
			(stroke
				(width 0.1)
				(type default)
			)
			(layer "F.Fab")
		)
		(fp_line
			(start -0.12065 0.2794)
			(end -0.12065 0.3048)
			(stroke
				(width 0.1)
				(type default)
			)
			(layer "F.Fab")
		)
		(fp_line
			(start -0.12065 -0.2794)
			(end 0.12065 -0.2794)
			(stroke
				(width 0.1)
				(type default)
			)
			(layer "F.Fab")
		)
		(fp_line
			(start -0.12065 -0.305054)
			(end -0.12065 -0.2794)
			(stroke
				(width 0.1)
				(type default)
			)
			(layer "F.Fab")
		)
		(fp_line
			(start -0.67945 0.3048)
			(end -0.67945 -0.305054)
			(stroke
				(width 0.1)
				(type default)
			)
			(layer "F.Fab")
		)
		(fp_line
			(start -0.67945 -0.305054)
			(end -0.12065 -0.305054)
			(stroke
				(width 0.1)
				(type default)
			)
			(layer "F.Fab")
		)
		(pad "1" smd circle
			(at -0.40005 0 180)
			(size 0 0)
			(layers "F.Cu" "F.Mask" "F.Paste")
			(net "P0V9_RETIMER_CPU1_VCC")
		)
		(pad "2" smd circle
			(at 0.40005 0 180)
			(size 0 0)
			(layers "F.Cu" "F.Mask" "F.Paste")
			(net "P3V3_AUX")
		)
	)
	(footprint ""
		(layer "F.Cu")
		(at 219.47251 -131.454144 90)
		(property "Reference" "R1650"
			(at 0 0 90)
			(layer "F.SilkS")
			(hide yes)
			(effects
				(font
					(size 1.27 1.27)
				)
			)
		)
		(property "Value" ""
			(at 0 0 90)
			(layer "F.Fab")
			(effects
				(font
					(size 1.27 1.27)
				)
			)
		)
		(duplicate_pad_numbers_are_jumpers no)
		(fp_line
			(start 0.7874 -0.4064)
			(end 0.7874 0.4064)
			(stroke
				(width 0.1524)
				(type default)
			)
			(layer "F.SilkS")
		)
		(fp_line
			(start -0.7874 -0.4064)
			(end 0.7874 -0.4064)
			(stroke
				(width 0.1524)
				(type default)
			)
			(layer "F.SilkS")
		)
		(fp_line
			(start 0.7874 0.4064)
			(end -0.7874 0.4064)
			(stroke
				(width 0.1524)
				(type default)
			)
			(layer "F.SilkS")
		)
		(fp_line
			(start -0.7874 0.4064)
			(end -0.7874 -0.4064)
			(stroke
				(width 0.1524)
				(type default)
			)
			(layer "F.SilkS")
		)
		(fp_line
			(start -0.12065 -0.305054)
			(end -0.12065 -0.2794)
			(stroke
				(width 0.1)
				(type default)
			)
			(layer "F.Fab")
		)
		(fp_line
			(start -0.67945 -0.305054)
			(end -0.12065 -0.305054)
			(stroke
				(width 0.1)
				(type default)
			)
			(layer "F.Fab")
		)
		(fp_line
			(start 0.67945 -0.3048)
			(end 0.67945 0.3048)
			(stroke
				(width 0.1)
				(type default)
			)
			(layer "F.Fab")
		)
		(fp_line
			(start 0.12065 -0.3048)
			(end 0.67945 -0.3048)
			(stroke
				(width 0.1)
				(type default)
			)
			(layer "F.Fab")
		)
		(fp_line
			(start 0.12065 -0.2794)
			(end 0.12065 -0.3048)
			(stroke
				(width 0.1)
				(type default)
			)
			(layer "F.Fab")
		)
		(fp_line
			(start -0.12065 -0.2794)
			(end 0.12065 -0.2794)
			(stroke
				(width 0.1)
				(type default)
			)
			(layer "F.Fab")
		)
		(fp_line
			(start 0.120396 0.2794)
			(end -0.12065 0.2794)
			(stroke
				(width 0.1)
				(type default)
			)
			(layer "F.Fab")
		)
		(fp_line
			(start -0.12065 0.2794)
			(end -0.12065 0.3048)
			(stroke
				(width 0.1)
				(type default)
			)
			(layer "F.Fab")
		)
		(fp_line
			(start 0.67945 0.3048)
			(end 0.120396 0.3048)
			(stroke
				(width 0.1)
				(type default)
			)
			(layer "F.Fab")
		)
		(fp_line
			(start 0.120396 0.3048)
			(end 0.120396 0.2794)
			(stroke
				(width 0.1)
				(type default)
			)
			(layer "F.Fab")
		)
		(fp_line
			(start -0.12065 0.3048)
			(end -0.67945 0.3048)
			(stroke
				(width 0.1)
				(type default)
			)
			(layer "F.Fab")
		)
		(fp_line
			(start -0.67945 0.3048)
			(end -0.67945 -0.305054)
			(stroke
				(width 0.1)
				(type default)
			)
			(layer "F.Fab")
		)
		(pad "1" smd circle
			(at -0.40005 0 90)
			(size 0 0)
			(layers "F.Cu" "F.Mask" "F.Paste")
			(net "PVDD18_S5_P0")
		)
		(pad "2" smd circle
			(at 0.40005 0 90)
			(size 0 0)
			(layers "F.Cu" "F.Mask" "F.Paste")
			(net "FM_PLD_CPU1_PRSNT_HDT_N")
		)
	)
	(footprint ""
		(layer "F.Cu")
		(at 296.687748 -344.982038 90)
		(property "Reference" "PR221"
			(at 0 0 90)
			(layer "F.SilkS")
			(hide yes)
			(effects
				(font
					(size 1.27 1.27)
				)
			)
		)
		(property "Value" ""
			(at 0 0 90)
			(layer "F.Fab")
			(effects
				(font
					(size 1.27 1.27)
				)
			)
		)
		(duplicate_pad_numbers_are_jumpers no)
		(fp_line
			(start 0.7874 -0.4064)
			(end 0.7874 0.4064)
			(stroke
				(width 0.1524)
				(type default)
			)
			(layer "F.SilkS")
		)
		(fp_line
			(start -0.7874 -0.4064)
			(end 0.7874 -0.4064)
			(stroke
				(width 0.1524)
				(type default)
			)
			(layer "F.SilkS")
		)
		(fp_line
			(start 0.7874 0.4064)
			(end -0.7874 0.4064)
			(stroke
				(width 0.1524)
				(type default)
			)
			(layer "F.SilkS")
		)
		(fp_line
			(start -0.7874 0.4064)
			(end -0.7874 -0.4064)
			(stroke
				(width 0.1524)
				(type default)
			)
			(layer "F.SilkS")
		)
		(fp_line
			(start -0.12065 -0.305054)
			(end -0.12065 -0.2794)
			(stroke
				(width 0.1)
				(type default)
			)
			(layer "F.Fab")
		)
		(fp_line
			(start -0.67945 -0.305054)
			(end -0.12065 -0.305054)
			(stroke
				(width 0.1)
				(type default)
			)
			(layer "F.Fab")
		)
		(fp_line
			(start 0.67945 -0.3048)
			(end 0.67945 0.3048)
			(stroke
				(width 0.1)
				(type default)
			)
			(layer "F.Fab")
		)
		(fp_line
			(start 0.12065 -0.3048)
			(end 0.67945 -0.3048)
			(stroke
				(width 0.1)
				(type default)
			)
			(layer "F.Fab")
		)
		(fp_line
			(start 0.12065 -0.2794)
			(end 0.12065 -0.3048)
			(stroke
				(width 0.1)
				(type default)
			)
			(layer "F.Fab")
		)
		(fp_line
			(start -0.12065 -0.2794)
			(end 0.12065 -0.2794)
			(stroke
				(width 0.1)
				(type default)
			)
			(layer "F.Fab")
		)
		(fp_line
			(start 0.120396 0.2794)
			(end -0.12065 0.2794)
			(stroke
				(width 0.1)
				(type default)
			)
			(layer "F.Fab")
		)
		(fp_line
			(start -0.12065 0.2794)
			(end -0.12065 0.3048)
			(stroke
				(width 0.1)
				(type default)
			)
			(layer "F.Fab")
		)
		(fp_line
			(start 0.67945 0.3048)
			(end 0.120396 0.3048)
			(stroke
				(width 0.1)
				(type default)
			)
			(layer "F.Fab")
		)
		(fp_line
			(start 0.120396 0.3048)
			(end 0.120396 0.2794)
			(stroke
				(width 0.1)
				(type default)
			)
			(layer "F.Fab")
		)
		(fp_line
			(start -0.12065 0.3048)
			(end -0.67945 0.3048)
			(stroke
				(width 0.1)
				(type default)
			)
			(layer "F.Fab")
		)
		(fp_line
			(start -0.67945 0.3048)
			(end -0.67945 -0.305054)
			(stroke
				(width 0.1)
				(type default)
			)
			(layer "F.Fab")
		)
		(pad "1" smd circle
			(at -0.40005 0 90)
			(size 0 0)
			(layers "F.Cu" "F.Mask" "F.Paste")
			(net "SW_PVDDIO_P0_SW1_RC")
		)
		(pad "2" smd circle
			(at 0.40005 0 90)
			(size 0 0)
			(layers "F.Cu" "F.Mask" "F.Paste")
			(net "GND")
		)
	)
	(footprint ""
		(layer "F.Cu")
		(at 118.718584 -58.868056)
		(property "Reference" "R1735"
			(at 0 0 0)
			(layer "F.SilkS")
			(hide yes)
			(effects
				(font
					(size 1.27 1.27)
				)
			)
		)
		(property "Value" ""
			(at 0 0 0)
			(layer "F.Fab")
			(effects
				(font
					(size 1.27 1.27)
				)
			)
		)
		(duplicate_pad_numbers_are_jumpers no)
		(fp_line
			(start -0.7874 -0.4064)
			(end 0.7874 -0.4064)
			(stroke
				(width 0.1524)
				(type default)
			)
			(layer "F.SilkS")
		)
		(fp_line
			(start -0.7874 0.4064)
			(end -0.7874 -0.4064)
			(stroke
				(width 0.1524)
				(type default)
			)
			(layer "F.SilkS")
		)
		(fp_line
			(start 0.7874 -0.4064)
			(end 0.7874 0.4064)
			(stroke
				(width 0.1524)
				(type default)
			)
			(layer "F.SilkS")
		)
		(fp_line
			(start 0.7874 0.4064)
			(end -0.7874 0.4064)
			(stroke
				(width 0.1524)
				(type default)
			)
			(layer "F.SilkS")
		)
		(fp_line
			(start -0.67945 -0.305054)
			(end -0.12065 -0.305054)
			(stroke
				(width 0.1)
				(type default)
			)
			(layer "F.Fab")
		)
		(fp_line
			(start -0.67945 0.3048)
			(end -0.67945 -0.305054)
			(stroke
				(width 0.1)
				(type default)
			)
			(layer "F.Fab")
		)
		(fp_line
			(start -0.12065 -0.305054)
			(end -0.12065 -0.2794)
			(stroke
				(width 0.1)
				(type default)
			)
			(layer "F.Fab")
		)
		(fp_line
			(start -0.12065 -0.2794)
			(end 0.12065 -0.2794)
			(stroke
				(width 0.1)
				(type default)
			)
			(layer "F.Fab")
		)
		(fp_line
			(start -0.12065 0.2794)
			(end -0.12065 0.3048)
			(stroke
				(width 0.1)
				(type default)
			)
			(layer "F.Fab")
		)
		(fp_line
			(start -0.12065 0.3048)
			(end -0.67945 0.3048)
			(stroke
				(width 0.1)
				(type default)
			)
			(layer "F.Fab")
		)
		(fp_line
			(start 0.120396 0.2794)
			(end -0.12065 0.2794)
			(stroke
				(width 0.1)
				(type default)
			)
			(layer "F.Fab")
		)
		(fp_line
			(start 0.120396 0.3048)
			(end 0.120396 0.2794)
			(stroke
				(width 0.1)
				(type default)
			)
			(layer "F.Fab")
		)
		(fp_line
			(start 0.12065 -0.3048)
			(end 0.67945 -0.3048)
			(stroke
				(width 0.1)
				(type default)
			)
			(layer "F.Fab")
		)
		(fp_line
			(start 0.12065 -0.2794)
			(end 0.12065 -0.3048)
			(stroke
				(width 0.1)
				(type default)
			)
			(layer "F.Fab")
		)
		(fp_line
			(start 0.67945 -0.3048)
			(end 0.67945 0.3048)
			(stroke
				(width 0.1)
				(type default)
			)
			(layer "F.Fab")
		)
		(fp_line
			(start 0.67945 0.3048)
			(end 0.120396 0.3048)
			(stroke
				(width 0.1)
				(type default)
			)
			(layer "F.Fab")
		)
		(pad "1" smd circle
			(at -0.40005 0)
			(size 0 0)
			(layers "F.Cu" "F.Mask" "F.Paste")
			(net "JTAG_SCM_TCK")
		)
		(pad "2" smd circle
			(at 0.40005 0)
			(size 0 0)
			(layers "F.Cu" "F.Mask" "F.Paste")
			(net "GND")
		)
	)
	(footprint ""
		(layer "F.Cu")
		(at 145.161 -120.777)
		(property "Reference" "R8039"
			(at 0 0 0)
			(layer "F.SilkS")
			(hide yes)
			(effects
				(font
					(size 1.27 1.27)
				)
			)
		)
		(property "Value" ""
			(at 0 0 0)
			(layer "F.Fab")
			(effects
				(font
					(size 1.27 1.27)
				)
			)
		)
		(duplicate_pad_numbers_are_jumpers no)
		(fp_line
			(start -0.7874 -0.4064)
			(end 0.7874 -0.4064)
			(stroke
				(width 0.1524)
				(type default)
			)
			(layer "F.SilkS")
		)
		(fp_line
			(start -0.7874 0.4064)
			(end -0.7874 -0.4064)
			(stroke
				(width 0.1524)
				(type default)
			)
			(layer "F.SilkS")
		)
		(fp_line
			(start 0.7874 -0.4064)
			(end 0.7874 0.4064)
			(stroke
				(width 0.1524)
				(type default)
			)
			(layer "F.SilkS")
		)
		(fp_line
			(start 0.7874 0.4064)
			(end -0.7874 0.4064)
			(stroke
				(width 0.1524)
				(type default)
			)
			(layer "F.SilkS")
		)
		(fp_line
			(start -0.67945 -0.305054)
			(end -0.12065 -0.305054)
			(stroke
				(width 0.1)
				(type default)
			)
			(layer "F.Fab")
		)
		(fp_line
			(start -0.67945 0.3048)
			(end -0.67945 -0.305054)
			(stroke
				(width 0.1)
				(type default)
			)
			(layer "F.Fab")
		)
		(fp_line
			(start -0.12065 -0.305054)
			(end -0.12065 -0.2794)
			(stroke
				(width 0.1)
				(type default)
			)
			(layer "F.Fab")
		)
		(fp_line
			(start -0.12065 -0.2794)
			(end 0.12065 -0.2794)
			(stroke
				(width 0.1)
				(type default)
			)
			(layer "F.Fab")
		)
		(fp_line
			(start -0.12065 0.2794)
			(end -0.12065 0.3048)
			(stroke
				(width 0.1)
				(type default)
			)
			(layer "F.Fab")
		)
		(fp_line
			(start -0.12065 0.3048)
			(end -0.67945 0.3048)
			(stroke
				(width 0.1)
				(type default)
			)
			(layer "F.Fab")
		)
		(fp_line
			(start 0.120396 0.2794)
			(end -0.12065 0.2794)
			(stroke
				(width 0.1)
				(type default)
			)
			(layer "F.Fab")
		)
		(fp_line
			(start 0.120396 0.3048)
			(end 0.120396 0.2794)
			(stroke
				(width 0.1)
				(type default)
			)
			(layer "F.Fab")
		)
		(fp_line
			(start 0.12065 -0.3048)
			(end 0.67945 -0.3048)
			(stroke
				(width 0.1)
				(type default)
			)
			(layer "F.Fab")
		)
		(fp_line
			(start 0.12065 -0.2794)
			(end 0.12065 -0.3048)
			(stroke
				(width 0.1)
				(type default)
			)
			(layer "F.Fab")
		)
		(fp_line
			(start 0.67945 -0.3048)
			(end 0.67945 0.3048)
			(stroke
				(width 0.1)
				(type default)
			)
			(layer "F.Fab")
		)
		(fp_line
			(start 0.67945 0.3048)
			(end 0.120396 0.3048)
			(stroke
				(width 0.1)
				(type default)
			)
			(layer "F.Fab")
		)
		(pad "1" smd circle
			(at -0.40005 0)
			(size 0 0)
			(layers "F.Cu" "F.Mask" "F.Paste")
			(net "P3V3_AUX")
		)
		(pad "2" smd circle
			(at 0.40005 0)
			(size 0 0)
			(layers "F.Cu" "F.Mask" "F.Paste")
			(net "PWRGD_CHAF_CPU1")
		)
	)
	(footprint ""
		(layer "F.Cu")
		(at 288.568638 -412.741872 -90)
		(property "Reference" "R4519"
			(at 0 0 270)
			(layer "F.SilkS")
			(hide yes)
			(effects
				(font
					(size 1.27 1.27)
				)
			)
		)
		(property "Value" ""
			(at 0 0 270)
			(layer "F.Fab")
			(effects
				(font
					(size 1.27 1.27)
				)
			)
		)
		(duplicate_pad_numbers_are_jumpers no)
		(fp_line
			(start -0.7874 0.4064)
			(end -0.7874 -0.4064)
			(stroke
				(width 0.1524)
				(type default)
			)
			(layer "F.SilkS")
		)
		(fp_line
			(start 0.7874 0.4064)
			(end -0.7874 0.4064)
			(stroke
				(width 0.1524)
				(type default)
			)
			(layer "F.SilkS")
		)
		(fp_line
			(start -0.7874 -0.4064)
			(end 0.7874 -0.4064)
			(stroke
				(width 0.1524)
				(type default)
			)
			(layer "F.SilkS")
		)
		(fp_line
			(start 0.7874 -0.4064)
			(end 0.7874 0.4064)
			(stroke
				(width 0.1524)
				(type default)
			)
			(layer "F.SilkS")
		)
		(fp_line
			(start -0.67945 0.3048)
			(end -0.67945 -0.305054)
			(stroke
				(width 0.1)
				(type default)
			)
			(layer "F.Fab")
		)
		(fp_line
			(start -0.12065 0.3048)
			(end -0.67945 0.3048)
			(stroke
				(width 0.1)
				(type default)
			)
			(layer "F.Fab")
		)
		(fp_line
			(start 0.120396 0.3048)
			(end 0.120396 0.2794)
			(stroke
				(width 0.1)
				(type default)
			)
			(layer "F.Fab")
		)
		(fp_line
			(start 0.67945 0.3048)
			(end 0.120396 0.3048)
			(stroke
				(width 0.1)
				(type default)
			)
			(layer "F.Fab")
		)
		(fp_line
			(start -0.12065 0.2794)
			(end -0.12065 0.3048)
			(stroke
				(width 0.1)
				(type default)
			)
			(layer "F.Fab")
		)
		(fp_line
			(start 0.120396 0.2794)
			(end -0.12065 0.2794)
			(stroke
				(width 0.1)
				(type default)
			)
			(layer "F.Fab")
		)
		(fp_line
			(start -0.12065 -0.2794)
			(end 0.12065 -0.2794)
			(stroke
				(width 0.1)
				(type default)
			)
			(layer "F.Fab")
		)
		(fp_line
			(start 0.12065 -0.2794)
			(end 0.12065 -0.3048)
			(stroke
				(width 0.1)
				(type default)
			)
			(layer "F.Fab")
		)
		(fp_line
			(start 0.12065 -0.3048)
			(end 0.67945 -0.3048)
			(stroke
				(width 0.1)
				(type default)
			)
			(layer "F.Fab")
		)
		(fp_line
			(start 0.67945 -0.3048)
			(end 0.67945 0.3048)
			(stroke
				(width 0.1)
				(type default)
			)
			(layer "F.Fab")
		)
		(fp_line
			(start -0.67945 -0.305054)
			(end -0.12065 -0.305054)
			(stroke
				(width 0.1)
				(type default)
			)
			(layer "F.Fab")
		)
		(fp_line
			(start -0.12065 -0.305054)
			(end -0.12065 -0.2794)
			(stroke
				(width 0.1)
				(type default)
			)
			(layer "F.Fab")
		)
		(pad "1" smd circle
			(at -0.40005 0 270)
			(size 0 0)
			(layers "F.Cu" "F.Mask" "F.Paste")
			(net "FM_9ZXL045_P0_1_OE_N")
		)
		(pad "2" smd circle
			(at 0.40005 0 270)
			(size 0 0)
			(layers "F.Cu" "F.Mask" "F.Paste")
			(net "GND")
		)
	)
	(footprint ""
		(layer "F.Cu")
		(at 182.753 -100.294948 -90)
		(property "Reference" "R284"
			(at 0 0 270)
			(layer "F.SilkS")
			(hide yes)
			(effects
				(font
					(size 1.27 1.27)
				)
			)
		)
		(property "Value" ""
			(at 0 0 270)
			(layer "F.Fab")
			(effects
				(font
					(size 1.27 1.27)
				)
			)
		)
		(duplicate_pad_numbers_are_jumpers no)
		(fp_line
			(start -0.7874 0.4064)
			(end -0.7874 -0.4064)
			(stroke
				(width 0.1524)
				(type default)
			)
			(layer "F.SilkS")
		)
		(fp_line
			(start 0.7874 0.4064)
			(end -0.7874 0.4064)
			(stroke
				(width 0.1524)
				(type default)
			)
			(layer "F.SilkS")
		)
		(fp_line
			(start -0.7874 -0.4064)
			(end 0.7874 -0.4064)
			(stroke
				(width 0.1524)
				(type default)
			)
			(layer "F.SilkS")
		)
		(fp_line
			(start 0.7874 -0.4064)
			(end 0.7874 0.4064)
			(stroke
				(width 0.1524)
				(type default)
			)
			(layer "F.SilkS")
		)
		(fp_line
			(start -0.67945 0.3048)
			(end -0.67945 -0.305054)
			(stroke
				(width 0.1)
				(type default)
			)
			(layer "F.Fab")
		)
		(fp_line
			(start -0.12065 0.3048)
			(end -0.67945 0.3048)
			(stroke
				(width 0.1)
				(type default)
			)
			(layer "F.Fab")
		)
		(fp_line
			(start 0.120396 0.3048)
			(end 0.120396 0.2794)
			(stroke
				(width 0.1)
				(type default)
			)
			(layer "F.Fab")
		)
		(fp_line
			(start 0.67945 0.3048)
			(end 0.120396 0.3048)
			(stroke
				(width 0.1)
				(type default)
			)
			(layer "F.Fab")
		)
		(fp_line
			(start -0.12065 0.2794)
			(end -0.12065 0.3048)
			(stroke
				(width 0.1)
				(type default)
			)
			(layer "F.Fab")
		)
		(fp_line
			(start 0.120396 0.2794)
			(end -0.12065 0.2794)
			(stroke
				(width 0.1)
				(type default)
			)
			(layer "F.Fab")
		)
		(fp_line
			(start -0.12065 -0.2794)
			(end 0.12065 -0.2794)
			(stroke
				(width 0.1)
				(type default)
			)
			(layer "F.Fab")
		)
		(fp_line
			(start 0.12065 -0.2794)
			(end 0.12065 -0.3048)
			(stroke
				(width 0.1)
				(type default)
			)
			(layer "F.Fab")
		)
		(fp_line
			(start 0.12065 -0.3048)
			(end 0.67945 -0.3048)
			(stroke
				(width 0.1)
				(type default)
			)
			(layer "F.Fab")
		)
		(fp_line
			(start 0.67945 -0.3048)
			(end 0.67945 0.3048)
			(stroke
				(width 0.1)
				(type default)
			)
			(layer "F.Fab")
		)
		(fp_line
			(start -0.67945 -0.305054)
			(end -0.12065 -0.305054)
			(stroke
				(width 0.1)
				(type default)
			)
			(layer "F.Fab")
		)
		(fp_line
			(start -0.12065 -0.305054)
			(end -0.12065 -0.2794)
			(stroke
				(width 0.1)
				(type default)
			)
			(layer "F.Fab")
		)
		(pad "1" smd circle
			(at -0.40005 0 270)
			(size 0 0)
			(layers "F.Cu" "F.Mask" "F.Paste")
			(net "FM_PVDDCR_CPU0_P1_OCP_N")
		)
		(pad "2" smd circle
			(at 0.40005 0 270)
			(size 0 0)
			(layers "F.Cu" "F.Mask" "F.Paste")
			(net "PVDDCR_CPU0_P1_OCP_N")
		)
	)
	(footprint ""
		(layer "F.Cu")
		(at 100.046282 -342.604598 90)
		(property "Reference" "PC138"
			(at 0 0 90)
			(layer "F.SilkS")
			(hide yes)
			(effects
				(font
					(size 1.27 1.27)
				)
			)
		)
		(property "Value" ""
			(at 0 0 90)
			(layer "F.Fab")
			(effects
				(font
					(size 1.27 1.27)
				)
			)
		)
		(duplicate_pad_numbers_are_jumpers no)
		(fp_line
			(start 0.7874 -0.4064)
			(end 0.7874 0.4064)
			(stroke
				(width 0.1524)
				(type default)
			)
			(layer "F.SilkS")
		)
		(fp_line
			(start -0.7874 -0.4064)
			(end 0.7874 -0.4064)
			(stroke
				(width 0.1524)
				(type default)
			)
			(layer "F.SilkS")
		)
		(fp_line
			(start 0.7874 0.4064)
			(end 0.371602 0.4064)
			(stroke
				(width 0.1524)
				(type default)
			)
			(layer "F.SilkS")
		)
		(fp_line
			(start -0.263398 0.4064)
			(end -0.7874 0.4064)
			(stroke
				(width 0.1524)
				(type default)
			)
			(layer "F.SilkS")
		)
		(fp_line
			(start -0.7874 0.4064)
			(end -0.7874 -0.4064)
			(stroke
				(width 0.1524)
				(type default)
			)
			(layer "F.SilkS")
		)
		(fp_line
			(start -0.12065 -0.305054)
			(end -0.12065 -0.2794)
			(stroke
				(width 0.1)
				(type default)
			)
			(layer "F.Fab")
		)
		(fp_line
			(start -0.67945 -0.305054)
			(end -0.12065 -0.305054)
			(stroke
				(width 0.1)
				(type default)
			)
			(layer "F.Fab")
		)
		(fp_line
			(start 0.67945 -0.3048)
			(end 0.67945 0.3048)
			(stroke
				(width 0.1)
				(type default)
			)
			(layer "F.Fab")
		)
		(fp_line
			(start 0.12065 -0.3048)
			(end 0.67945 -0.3048)
			(stroke
				(width 0.1)
				(type default)
			)
			(layer "F.Fab")
		)
		(fp_line
			(start 0.12065 -0.2794)
			(end 0.12065 -0.3048)
			(stroke
				(width 0.1)
				(type default)
			)
			(layer "F.Fab")
		)
		(fp_line
			(start -0.12065 -0.2794)
			(end 0.12065 -0.2794)
			(stroke
				(width 0.1)
				(type default)
			)
			(layer "F.Fab")
		)
		(fp_line
			(start 0.120396 0.2794)
			(end -0.12065 0.2794)
			(stroke
				(width 0.1)
				(type default)
			)
			(layer "F.Fab")
		)
		(fp_line
			(start -0.12065 0.2794)
			(end -0.12065 0.3048)
			(stroke
				(width 0.1)
				(type default)
			)
			(layer "F.Fab")
		)
		(fp_line
			(start 0.67945 0.3048)
			(end 0.120396 0.3048)
			(stroke
				(width 0.1)
				(type default)
			)
			(layer "F.Fab")
		)
		(fp_line
			(start 0.120396 0.3048)
			(end 0.120396 0.2794)
			(stroke
				(width 0.1)
				(type default)
			)
			(layer "F.Fab")
		)
		(fp_line
			(start -0.12065 0.3048)
			(end -0.67945 0.3048)
			(stroke
				(width 0.1)
				(type default)
			)
			(layer "F.Fab")
		)
		(fp_line
			(start -0.67945 0.3048)
			(end -0.67945 -0.305054)
			(stroke
				(width 0.1)
				(type default)
			)
			(layer "F.Fab")
		)
		(pad "1" smd circle
			(at -0.40005 0 90)
			(size 0 0)
			(layers "F.Cu" "F.Mask" "F.Paste")
			(net "PVDDCR_CPU1_P1_VCC6")
		)
		(pad "2" smd circle
			(at 0.40005 0 90)
			(size 0 0)
			(layers "F.Cu" "F.Mask" "F.Paste")
			(net "GND")
		)
	)
	(footprint ""
		(layer "F.Cu")
		(at 372.937278 -147.568158 180)
		(property "Reference" "PR284"
			(at 0 0 180)
			(layer "F.SilkS")
			(hide yes)
			(effects
				(font
					(size 1.27 1.27)
				)
			)
		)
		(property "Value" ""
			(at 0 0 180)
			(layer "F.Fab")
			(effects
				(font
					(size 1.27 1.27)
				)
			)
		)
		(duplicate_pad_numbers_are_jumpers no)
		(fp_line
			(start 0.7874 0.4064)
			(end -0.7874 0.4064)
			(stroke
				(width 0.1524)
				(type default)
			)
			(layer "F.SilkS")
		)
		(fp_line
			(start 0.7874 -0.4064)
			(end 0.7874 0.4064)
			(stroke
				(width 0.1524)
				(type default)
			)
			(layer "F.SilkS")
		)
		(fp_line
			(start -0.7874 0.4064)
			(end -0.7874 -0.4064)
			(stroke
				(width 0.1524)
				(type default)
			)
			(layer "F.SilkS")
		)
		(fp_line
			(start -0.7874 -0.4064)
			(end 0.7874 -0.4064)
			(stroke
				(width 0.1524)
				(type default)
			)
			(layer "F.SilkS")
		)
		(fp_line
			(start 0.67945 0.3048)
			(end 0.120396 0.3048)
			(stroke
				(width 0.1)
				(type default)
			)
			(layer "F.Fab")
		)
		(fp_line
			(start 0.67945 -0.3048)
			(end 0.67945 0.3048)
			(stroke
				(width 0.1)
				(type default)
			)
			(layer "F.Fab")
		)
		(fp_line
			(start 0.12065 -0.2794)
			(end 0.12065 -0.3048)
			(stroke
				(width 0.1)
				(type default)
			)
			(layer "F.Fab")
		)
		(fp_line
			(start 0.12065 -0.3048)
			(end 0.67945 -0.3048)
			(stroke
				(width 0.1)
				(type default)
			)
			(layer "F.Fab")
		)
		(fp_line
			(start 0.120396 0.3048)
			(end 0.120396 0.2794)
			(stroke
				(width 0.1)
				(type default)
			)
			(layer "F.Fab")
		)
		(fp_line
			(start 0.120396 0.2794)
			(end -0.12065 0.2794)
			(stroke
				(width 0.1)
				(type default)
			)
			(layer "F.Fab")
		)
		(fp_line
			(start -0.12065 0.3048)
			(end -0.67945 0.3048)
			(stroke
				(width 0.1)
				(type default)
			)
			(layer "F.Fab")
		)
		(fp_line
			(start -0.12065 0.2794)
			(end -0.12065 0.3048)
			(stroke
				(width 0.1)
				(type default)
			)
			(layer "F.Fab")
		)
		(fp_line
			(start -0.12065 -0.2794)
			(end 0.12065 -0.2794)
			(stroke
				(width 0.1)
				(type default)
			)
			(layer "F.Fab")
		)
		(fp_line
			(start -0.12065 -0.305054)
			(end -0.12065 -0.2794)
			(stroke
				(width 0.1)
				(type default)
			)
			(layer "F.Fab")
		)
		(fp_line
			(start -0.67945 0.3048)
			(end -0.67945 -0.305054)
			(stroke
				(width 0.1)
				(type default)
			)
			(layer "F.Fab")
		)
		(fp_line
			(start -0.67945 -0.305054)
			(end -0.12065 -0.305054)
			(stroke
				(width 0.1)
				(type default)
			)
			(layer "F.Fab")
		)
		(pad "1" smd circle
			(at -0.40005 0 180)
			(size 0 0)
			(layers "F.Cu" "F.Mask" "F.Paste")
			(net "PVDD18_S5_P0")
		)
		(pad "2" smd circle
			(at 0.40005 0 180)
			(size 0 0)
			(layers "F.Cu" "F.Mask" "F.Paste")
			(net "SVID_PVDDCR_CPU0_P0_SVTI")
		)
	)
	(footprint ""
		(layer "F.Cu")
		(at 107.137454 -25.183592)
		(property "Reference" "C6091"
			(at 0 0 0)
			(layer "F.SilkS")
			(hide yes)
			(effects
				(font
					(size 1.27 1.27)
				)
			)
		)
		(property "Value" ""
			(at 0 0 0)
			(layer "F.Fab")
			(effects
				(font
					(size 1.27 1.27)
				)
			)
		)
		(duplicate_pad_numbers_are_jumpers no)
		(fp_line
			(start -0.7874 -0.4064)
			(end 0.7874 -0.4064)
			(stroke
				(width 0.1524)
				(type default)
			)
			(layer "F.SilkS")
		)
		(fp_line
			(start -0.7874 0.4064)
			(end -0.7874 -0.4064)
			(stroke
				(width 0.1524)
				(type default)
			)
			(layer "F.SilkS")
		)
		(fp_line
			(start 0.7874 -0.4064)
			(end 0.7874 0.4064)
			(stroke
				(width 0.1524)
				(type default)
			)
			(layer "F.SilkS")
		)
		(fp_line
			(start 0.7874 0.4064)
			(end -0.7874 0.4064)
			(stroke
				(width 0.1524)
				(type default)
			)
			(layer "F.SilkS")
		)
		(fp_line
			(start -0.67945 -0.305054)
			(end -0.12065 -0.305054)
			(stroke
				(width 0.1)
				(type default)
			)
			(layer "F.Fab")
		)
		(fp_line
			(start -0.67945 0.3048)
			(end -0.67945 -0.305054)
			(stroke
				(width 0.1)
				(type default)
			)
			(layer "F.Fab")
		)
		(fp_line
			(start -0.12065 -0.305054)
			(end -0.12065 -0.2794)
			(stroke
				(width 0.1)
				(type default)
			)
			(layer "F.Fab")
		)
		(fp_line
			(start -0.12065 -0.2794)
			(end 0.12065 -0.2794)
			(stroke
				(width 0.1)
				(type default)
			)
			(layer "F.Fab")
		)
		(fp_line
			(start -0.12065 0.2794)
			(end -0.12065 0.3048)
			(stroke
				(width 0.1)
				(type default)
			)
			(layer "F.Fab")
		)
		(fp_line
			(start -0.12065 0.3048)
			(end -0.67945 0.3048)
			(stroke
				(width 0.1)
				(type default)
			)
			(layer "F.Fab")
		)
		(fp_line
			(start 0.120396 0.2794)
			(end -0.12065 0.2794)
			(stroke
				(width 0.1)
				(type default)
			)
			(layer "F.Fab")
		)
		(fp_line
			(start 0.120396 0.3048)
			(end 0.120396 0.2794)
			(stroke
				(width 0.1)
				(type default)
			)
			(layer "F.Fab")
		)
		(fp_line
			(start 0.12065 -0.3048)
			(end 0.67945 -0.3048)
			(stroke
				(width 0.1)
				(type default)
			)
			(layer "F.Fab")
		)
		(fp_line
			(start 0.12065 -0.2794)
			(end 0.12065 -0.3048)
			(stroke
				(width 0.1)
				(type default)
			)
			(layer "F.Fab")
		)
		(fp_line
			(start 0.67945 -0.3048)
			(end 0.67945 0.3048)
			(stroke
				(width 0.1)
				(type default)
			)
			(layer "F.Fab")
		)
		(fp_line
			(start 0.67945 0.3048)
			(end 0.120396 0.3048)
			(stroke
				(width 0.1)
				(type default)
			)
			(layer "F.Fab")
		)
		(pad "1" smd circle
			(at -0.40005 0)
			(size 0 0)
			(layers "F.Cu" "F.Mask" "F.Paste")
			(net "XTAL_USB_CPU0_HUB2_XIN")
		)
		(pad "2" smd circle
			(at 0.40005 0)
			(size 0 0)
			(layers "F.Cu" "F.Mask" "F.Paste")
			(net "GND")
		)
	)
	(footprint ""
		(layer "F.Cu")
		(at 200.952608 -115.657376)
		(property "Reference" "R6112"
			(at 0 0 0)
			(layer "F.SilkS")
			(hide yes)
			(effects
				(font
					(size 1.27 1.27)
				)
			)
		)
		(property "Value" ""
			(at 0 0 0)
			(layer "F.Fab")
			(effects
				(font
					(size 1.27 1.27)
				)
			)
		)
		(duplicate_pad_numbers_are_jumpers no)
		(fp_line
			(start -0.7874 -0.4064)
			(end 0.7874 -0.4064)
			(stroke
				(width 0.1524)
				(type default)
			)
			(layer "F.SilkS")
		)
		(fp_line
			(start -0.7874 0.4064)
			(end -0.7874 -0.4064)
			(stroke
				(width 0.1524)
				(type default)
			)
			(layer "F.SilkS")
		)
		(fp_line
			(start 0.7874 -0.4064)
			(end 0.7874 0.4064)
			(stroke
				(width 0.1524)
				(type default)
			)
			(layer "F.SilkS")
		)
		(fp_line
			(start 0.7874 0.4064)
			(end -0.7874 0.4064)
			(stroke
				(width 0.1524)
				(type default)
			)
			(layer "F.SilkS")
		)
		(fp_line
			(start -0.67945 -0.305054)
			(end -0.12065 -0.305054)
			(stroke
				(width 0.1)
				(type default)
			)
			(layer "F.Fab")
		)
		(fp_line
			(start -0.67945 0.3048)
			(end -0.67945 -0.305054)
			(stroke
				(width 0.1)
				(type default)
			)
			(layer "F.Fab")
		)
		(fp_line
			(start -0.12065 -0.305054)
			(end -0.12065 -0.2794)
			(stroke
				(width 0.1)
				(type default)
			)
			(layer "F.Fab")
		)
		(fp_line
			(start -0.12065 -0.2794)
			(end 0.12065 -0.2794)
			(stroke
				(width 0.1)
				(type default)
			)
			(layer "F.Fab")
		)
		(fp_line
			(start -0.12065 0.2794)
			(end -0.12065 0.3048)
			(stroke
				(width 0.1)
				(type default)
			)
			(layer "F.Fab")
		)
		(fp_line
			(start -0.12065 0.3048)
			(end -0.67945 0.3048)
			(stroke
				(width 0.1)
				(type default)
			)
			(layer "F.Fab")
		)
		(fp_line
			(start 0.120396 0.2794)
			(end -0.12065 0.2794)
			(stroke
				(width 0.1)
				(type default)
			)
			(layer "F.Fab")
		)
		(fp_line
			(start 0.120396 0.3048)
			(end 0.120396 0.2794)
			(stroke
				(width 0.1)
				(type default)
			)
			(layer "F.Fab")
		)
		(fp_line
			(start 0.12065 -0.3048)
			(end 0.67945 -0.3048)
			(stroke
				(width 0.1)
				(type default)
			)
			(layer "F.Fab")
		)
		(fp_line
			(start 0.12065 -0.2794)
			(end 0.12065 -0.3048)
			(stroke
				(width 0.1)
				(type default)
			)
			(layer "F.Fab")
		)
		(fp_line
			(start 0.67945 -0.3048)
			(end 0.67945 0.3048)
			(stroke
				(width 0.1)
				(type default)
			)
			(layer "F.Fab")
		)
		(fp_line
			(start 0.67945 0.3048)
			(end 0.120396 0.3048)
			(stroke
				(width 0.1)
				(type default)
			)
			(layer "F.Fab")
		)
		(pad "1" smd circle
			(at -0.40005 0)
			(size 0 0)
			(layers "F.Cu" "F.Mask" "F.Paste")
			(net "RST_PERST_CPU0_SWB_N")
		)
		(pad "2" smd circle
			(at 0.40005 0)
			(size 0 0)
			(layers "F.Cu" "F.Mask" "F.Paste")
			(net "RST_PERST_CPU0_SWB_R_N")
		)
	)
	(footprint ""
		(layer "F.Cu")
		(at 32.23514 -346.87129 -90)
		(property "Reference" "PC625_4"
			(at 0 0 270)
			(layer "F.SilkS")
			(hide yes)
			(effects
				(font
					(size 1.27 1.27)
				)
			)
		)
		(property "Value" ""
			(at 0 0 270)
			(layer "F.Fab")
			(effects
				(font
					(size 1.27 1.27)
				)
			)
		)
		(duplicate_pad_numbers_are_jumpers no)
		(fp_line
			(start -0.7874 0.4064)
			(end -0.7874 -0.4064)
			(stroke
				(width 0.1524)
				(type default)
			)
			(layer "F.SilkS")
		)
		(fp_line
			(start 0.7874 0.4064)
			(end -0.7874 0.4064)
			(stroke
				(width 0.1524)
				(type default)
			)
			(layer "F.SilkS")
		)
		(fp_line
			(start -0.7874 -0.4064)
			(end 0.7874 -0.4064)
			(stroke
				(width 0.1524)
				(type default)
			)
			(layer "F.SilkS")
		)
		(fp_line
			(start 0.7874 -0.4064)
			(end 0.7874 0.4064)
			(stroke
				(width 0.1524)
				(type default)
			)
			(layer "F.SilkS")
		)
		(fp_line
			(start -0.67945 0.3048)
			(end -0.67945 -0.305054)
			(stroke
				(width 0.1)
				(type default)
			)
			(layer "F.Fab")
		)
		(fp_line
			(start -0.12065 0.3048)
			(end -0.67945 0.3048)
			(stroke
				(width 0.1)
				(type default)
			)
			(layer "F.Fab")
		)
		(fp_line
			(start 0.120396 0.3048)
			(end 0.120396 0.2794)
			(stroke
				(width 0.1)
				(type default)
			)
			(layer "F.Fab")
		)
		(fp_line
			(start 0.67945 0.3048)
			(end 0.120396 0.3048)
			(stroke
				(width 0.1)
				(type default)
			)
			(layer "F.Fab")
		)
		(fp_line
			(start -0.12065 0.2794)
			(end -0.12065 0.3048)
			(stroke
				(width 0.1)
				(type default)
			)
			(layer "F.Fab")
		)
		(fp_line
			(start 0.120396 0.2794)
			(end -0.12065 0.2794)
			(stroke
				(width 0.1)
				(type default)
			)
			(layer "F.Fab")
		)
		(fp_line
			(start -0.12065 -0.2794)
			(end 0.12065 -0.2794)
			(stroke
				(width 0.1)
				(type default)
			)
			(layer "F.Fab")
		)
		(fp_line
			(start 0.12065 -0.2794)
			(end 0.12065 -0.3048)
			(stroke
				(width 0.1)
				(type default)
			)
			(layer "F.Fab")
		)
		(fp_line
			(start 0.12065 -0.3048)
			(end 0.67945 -0.3048)
			(stroke
				(width 0.1)
				(type default)
			)
			(layer "F.Fab")
		)
		(fp_line
			(start 0.67945 -0.3048)
			(end 0.67945 0.3048)
			(stroke
				(width 0.1)
				(type default)
			)
			(layer "F.Fab")
		)
		(fp_line
			(start -0.67945 -0.305054)
			(end -0.12065 -0.305054)
			(stroke
				(width 0.1)
				(type default)
			)
			(layer "F.Fab")
		)
		(fp_line
			(start -0.12065 -0.305054)
			(end -0.12065 -0.2794)
			(stroke
				(width 0.1)
				(type default)
			)
			(layer "F.Fab")
		)
		(pad "1" smd circle
			(at -0.40005 0 270)
			(size 0 0)
			(layers "F.Cu" "F.Mask" "F.Paste")
			(net "SW_P12V_AUX_PVDDIO_P1_FLT")
		)
		(pad "2" smd circle
			(at 0.40005 0 270)
			(size 0 0)
			(layers "F.Cu" "F.Mask" "F.Paste")
			(net "GND")
		)
	)
	(footprint ""
		(layer "F.Cu")
		(at 49.342294 -16.099536 90)
		(property "Reference" "C702"
			(at 0 0 90)
			(layer "F.SilkS")
			(hide yes)
			(effects
				(font
					(size 1.27 1.27)
				)
			)
		)
		(property "Value" ""
			(at 0 0 90)
			(layer "F.Fab")
			(effects
				(font
					(size 1.27 1.27)
				)
			)
		)
		(duplicate_pad_numbers_are_jumpers no)
		(fp_line
			(start 0.299974 -0.150114)
			(end 0.299974 0.150114)
			(stroke
				(width 0.1)
				(type default)
			)
			(layer "F.Fab")
		)
		(fp_line
			(start -0.299974 -0.150114)
			(end 0.299974 -0.150114)
			(stroke
				(width 0.1)
				(type default)
			)
			(layer "F.Fab")
		)
		(fp_line
			(start 0.299974 0.150114)
			(end -0.299974 0.150114)
			(stroke
				(width 0.1)
				(type default)
			)
			(layer "F.Fab")
		)
		(fp_line
			(start -0.299974 0.150114)
			(end -0.299974 -0.150114)
			(stroke
				(width 0.1)
				(type default)
			)
			(layer "F.Fab")
		)
		(pad "1" smd rect
			(at -0.2667 0 90)
			(size 0.3048 0.381)
			(layers "F.Cu" "F.Mask" "F.Paste")
			(net "P5E_CPU1_G1_TX_C_DN<3>")
		)
		(pad "2" smd rect
			(at 0.2667 0 90)
			(size 0.3048 0.381)
			(layers "F.Cu" "F.Mask" "F.Paste")
			(net "P5E_CPU1_G1_TX_DN<3>")
		)
	)
	(footprint ""
		(layer "F.Cu")
		(at 179.225956 -348.29115 180)
		(property "Reference" "PC315"
			(at 0 0 180)
			(layer "F.SilkS")
			(hide yes)
			(effects
				(font
					(size 1.27 1.27)
				)
			)
		)
		(property "Value" ""
			(at 0 0 180)
			(layer "F.Fab")
			(effects
				(font
					(size 1.27 1.27)
				)
			)
		)
		(duplicate_pad_numbers_are_jumpers no)
		(fp_line
			(start 0.7874 0.4064)
			(end -0.7874 0.4064)
			(stroke
				(width 0.1524)
				(type default)
			)
			(layer "F.SilkS")
		)
		(fp_line
			(start 0.7874 -0.4064)
			(end 0.7874 0.4064)
			(stroke
				(width 0.1524)
				(type default)
			)
			(layer "F.SilkS")
		)
		(fp_line
			(start -0.7874 0.4064)
			(end -0.7874 -0.4064)
			(stroke
				(width 0.1524)
				(type default)
			)
			(layer "F.SilkS")
		)
		(fp_line
			(start -0.7874 -0.4064)
			(end 0.7874 -0.4064)
			(stroke
				(width 0.1524)
				(type default)
			)
			(layer "F.SilkS")
		)
		(fp_line
			(start 0.67945 0.3048)
			(end 0.120396 0.3048)
			(stroke
				(width 0.1)
				(type default)
			)
			(layer "F.Fab")
		)
		(fp_line
			(start 0.67945 -0.3048)
			(end 0.67945 0.3048)
			(stroke
				(width 0.1)
				(type default)
			)
			(layer "F.Fab")
		)
		(fp_line
			(start 0.12065 -0.2794)
			(end 0.12065 -0.3048)
			(stroke
				(width 0.1)
				(type default)
			)
			(layer "F.Fab")
		)
		(fp_line
			(start 0.12065 -0.3048)
			(end 0.67945 -0.3048)
			(stroke
				(width 0.1)
				(type default)
			)
			(layer "F.Fab")
		)
		(fp_line
			(start 0.120396 0.3048)
			(end 0.120396 0.2794)
			(stroke
				(width 0.1)
				(type default)
			)
			(layer "F.Fab")
		)
		(fp_line
			(start 0.120396 0.2794)
			(end -0.12065 0.2794)
			(stroke
				(width 0.1)
				(type default)
			)
			(layer "F.Fab")
		)
		(fp_line
			(start -0.12065 0.3048)
			(end -0.67945 0.3048)
			(stroke
				(width 0.1)
				(type default)
			)
			(layer "F.Fab")
		)
		(fp_line
			(start -0.12065 0.2794)
			(end -0.12065 0.3048)
			(stroke
				(width 0.1)
				(type default)
			)
			(layer "F.Fab")
		)
		(fp_line
			(start -0.12065 -0.2794)
			(end 0.12065 -0.2794)
			(stroke
				(width 0.1)
				(type default)
			)
			(layer "F.Fab")
		)
		(fp_line
			(start -0.12065 -0.305054)
			(end -0.12065 -0.2794)
			(stroke
				(width 0.1)
				(type default)
			)
			(layer "F.Fab")
		)
		(fp_line
			(start -0.67945 0.3048)
			(end -0.67945 -0.305054)
			(stroke
				(width 0.1)
				(type default)
			)
			(layer "F.Fab")
		)
		(fp_line
			(start -0.67945 -0.305054)
			(end -0.12065 -0.305054)
			(stroke
				(width 0.1)
				(type default)
			)
			(layer "F.Fab")
		)
		(pad "1" smd circle
			(at -0.40005 0 180)
			(size 0 0)
			(layers "F.Cu" "F.Mask" "F.Paste")
			(net "SW_PVDD11_S3_P1_SW1")
		)
		(pad "2" smd circle
			(at 0.40005 0 180)
			(size 0 0)
			(layers "F.Cu" "F.Mask" "F.Paste")
			(net "SW_PVDD11_S3_P1_SW1_RC")
		)
	)
	(footprint ""
		(layer "F.Cu")
		(at 284.556962 -426.19549 90)
		(property "Reference" "C76"
			(at 0 0 90)
			(layer "F.SilkS")
			(hide yes)
			(effects
				(font
					(size 1.27 1.27)
				)
			)
		)
		(property "Value" ""
			(at 0 0 90)
			(layer "F.Fab")
			(effects
				(font
					(size 1.27 1.27)
				)
			)
		)
		(duplicate_pad_numbers_are_jumpers no)
		(fp_line
			(start 0.7874 -0.4064)
			(end 0.7874 0.4064)
			(stroke
				(width 0.1524)
				(type default)
			)
			(layer "F.SilkS")
		)
		(fp_line
			(start -0.7874 -0.4064)
			(end 0.7874 -0.4064)
			(stroke
				(width 0.1524)
				(type default)
			)
			(layer "F.SilkS")
		)
		(fp_line
			(start 0.7874 0.4064)
			(end -0.7874 0.4064)
			(stroke
				(width 0.1524)
				(type default)
			)
			(layer "F.SilkS")
		)
		(fp_line
			(start -0.7874 0.4064)
			(end -0.7874 -0.4064)
			(stroke
				(width 0.1524)
				(type default)
			)
			(layer "F.SilkS")
		)
		(fp_line
			(start -0.12065 -0.305054)
			(end -0.12065 -0.2794)
			(stroke
				(width 0.1)
				(type default)
			)
			(layer "F.Fab")
		)
		(fp_line
			(start -0.67945 -0.305054)
			(end -0.12065 -0.305054)
			(stroke
				(width 0.1)
				(type default)
			)
			(layer "F.Fab")
		)
		(fp_line
			(start 0.67945 -0.3048)
			(end 0.67945 0.3048)
			(stroke
				(width 0.1)
				(type default)
			)
			(layer "F.Fab")
		)
		(fp_line
			(start 0.12065 -0.3048)
			(end 0.67945 -0.3048)
			(stroke
				(width 0.1)
				(type default)
			)
			(layer "F.Fab")
		)
		(fp_line
			(start 0.12065 -0.2794)
			(end 0.12065 -0.3048)
			(stroke
				(width 0.1)
				(type default)
			)
			(layer "F.Fab")
		)
		(fp_line
			(start -0.12065 -0.2794)
			(end 0.12065 -0.2794)
			(stroke
				(width 0.1)
				(type default)
			)
			(layer "F.Fab")
		)
		(fp_line
			(start 0.120396 0.2794)
			(end -0.12065 0.2794)
			(stroke
				(width 0.1)
				(type default)
			)
			(layer "F.Fab")
		)
		(fp_line
			(start -0.12065 0.2794)
			(end -0.12065 0.3048)
			(stroke
				(width 0.1)
				(type default)
			)
			(layer "F.Fab")
		)
		(fp_line
			(start 0.67945 0.3048)
			(end 0.120396 0.3048)
			(stroke
				(width 0.1)
				(type default)
			)
			(layer "F.Fab")
		)
		(fp_line
			(start 0.120396 0.3048)
			(end 0.120396 0.2794)
			(stroke
				(width 0.1)
				(type default)
			)
			(layer "F.Fab")
		)
		(fp_line
			(start -0.12065 0.3048)
			(end -0.67945 0.3048)
			(stroke
				(width 0.1)
				(type default)
			)
			(layer "F.Fab")
		)
		(fp_line
			(start -0.67945 0.3048)
			(end -0.67945 -0.305054)
			(stroke
				(width 0.1)
				(type default)
			)
			(layer "F.Fab")
		)
		(pad "1" smd circle
			(at -0.40005 0 90)
			(size 0 0)
			(layers "F.Cu" "F.Mask" "F.Paste")
			(net "P3V3_9ZXL045_P0_VDDA")
		)
		(pad "2" smd circle
			(at 0.40005 0 90)
			(size 0 0)
			(layers "F.Cu" "F.Mask" "F.Paste")
			(net "GND")
		)
	)
	(footprint ""
		(layer "F.Cu")
		(at 210.485482 -102.958138)
		(property "Reference" "R1340"
			(at 0 0 0)
			(layer "F.SilkS")
			(hide yes)
			(effects
				(font
					(size 1.27 1.27)
				)
			)
		)
		(property "Value" ""
			(at 0 0 0)
			(layer "F.Fab")
			(effects
				(font
					(size 1.27 1.27)
				)
			)
		)
		(duplicate_pad_numbers_are_jumpers no)
		(fp_line
			(start -0.7874 -0.4064)
			(end 0.7874 -0.4064)
			(stroke
				(width 0.1524)
				(type default)
			)
			(layer "F.SilkS")
		)
		(fp_line
			(start -0.7874 0.4064)
			(end -0.7874 -0.4064)
			(stroke
				(width 0.1524)
				(type default)
			)
			(layer "F.SilkS")
		)
		(fp_line
			(start 0.7874 -0.4064)
			(end 0.7874 0.4064)
			(stroke
				(width 0.1524)
				(type default)
			)
			(layer "F.SilkS")
		)
		(fp_line
			(start 0.7874 0.4064)
			(end -0.7874 0.4064)
			(stroke
				(width 0.1524)
				(type default)
			)
			(layer "F.SilkS")
		)
		(fp_line
			(start -0.67945 -0.305054)
			(end -0.12065 -0.305054)
			(stroke
				(width 0.1)
				(type default)
			)
			(layer "F.Fab")
		)
		(fp_line
			(start -0.67945 0.3048)
			(end -0.67945 -0.305054)
			(stroke
				(width 0.1)
				(type default)
			)
			(layer "F.Fab")
		)
		(fp_line
			(start -0.12065 -0.305054)
			(end -0.12065 -0.2794)
			(stroke
				(width 0.1)
				(type default)
			)
			(layer "F.Fab")
		)
		(fp_line
			(start -0.12065 -0.2794)
			(end 0.12065 -0.2794)
			(stroke
				(width 0.1)
				(type default)
			)
			(layer "F.Fab")
		)
		(fp_line
			(start -0.12065 0.2794)
			(end -0.12065 0.3048)
			(stroke
				(width 0.1)
				(type default)
			)
			(layer "F.Fab")
		)
		(fp_line
			(start -0.12065 0.3048)
			(end -0.67945 0.3048)
			(stroke
				(width 0.1)
				(type default)
			)
			(layer "F.Fab")
		)
		(fp_line
			(start 0.120396 0.2794)
			(end -0.12065 0.2794)
			(stroke
				(width 0.1)
				(type default)
			)
			(layer "F.Fab")
		)
		(fp_line
			(start 0.120396 0.3048)
			(end 0.120396 0.2794)
			(stroke
				(width 0.1)
				(type default)
			)
			(layer "F.Fab")
		)
		(fp_line
			(start 0.12065 -0.3048)
			(end 0.67945 -0.3048)
			(stroke
				(width 0.1)
				(type default)
			)
			(layer "F.Fab")
		)
		(fp_line
			(start 0.12065 -0.2794)
			(end 0.12065 -0.3048)
			(stroke
				(width 0.1)
				(type default)
			)
			(layer "F.Fab")
		)
		(fp_line
			(start 0.67945 -0.3048)
			(end 0.67945 0.3048)
			(stroke
				(width 0.1)
				(type default)
			)
			(layer "F.Fab")
		)
		(fp_line
			(start 0.67945 0.3048)
			(end 0.120396 0.3048)
			(stroke
				(width 0.1)
				(type default)
			)
			(layer "F.Fab")
		)
		(pad "1" smd circle
			(at -0.40005 0)
			(size 0 0)
			(layers "F.Cu" "F.Mask" "F.Paste")
			(net "OCP_SFF_P3V3_P12V_ADC_ALERT")
		)
		(pad "2" smd circle
			(at 0.40005 0)
			(size 0 0)
			(layers "F.Cu" "F.Mask" "F.Paste")
			(net "OCP_SFF_P3V3_P12V_ADC_R_ALERT")
		)
	)
	(footprint ""
		(layer "F.Cu")
		(at 197.269608 -110.577376 180)
		(property "Reference" "R176"
			(at 0 0 180)
			(layer "F.SilkS")
			(hide yes)
			(effects
				(font
					(size 1.27 1.27)
				)
			)
		)
		(property "Value" ""
			(at 0 0 180)
			(layer "F.Fab")
			(effects
				(font
					(size 1.27 1.27)
				)
			)
		)
		(duplicate_pad_numbers_are_jumpers no)
		(fp_line
			(start 0.7874 0.4064)
			(end -0.7874 0.4064)
			(stroke
				(width 0.1524)
				(type default)
			)
			(layer "F.SilkS")
		)
		(fp_line
			(start 0.7874 -0.4064)
			(end 0.7874 0.4064)
			(stroke
				(width 0.1524)
				(type default)
			)
			(layer "F.SilkS")
		)
		(fp_line
			(start -0.7874 0.4064)
			(end -0.7874 -0.4064)
			(stroke
				(width 0.1524)
				(type default)
			)
			(layer "F.SilkS")
		)
		(fp_line
			(start -0.7874 -0.4064)
			(end 0.7874 -0.4064)
			(stroke
				(width 0.1524)
				(type default)
			)
			(layer "F.SilkS")
		)
		(fp_line
			(start 0.67945 0.3048)
			(end 0.120396 0.3048)
			(stroke
				(width 0.1)
				(type default)
			)
			(layer "F.Fab")
		)
		(fp_line
			(start 0.67945 -0.3048)
			(end 0.67945 0.3048)
			(stroke
				(width 0.1)
				(type default)
			)
			(layer "F.Fab")
		)
		(fp_line
			(start 0.12065 -0.2794)
			(end 0.12065 -0.3048)
			(stroke
				(width 0.1)
				(type default)
			)
			(layer "F.Fab")
		)
		(fp_line
			(start 0.12065 -0.3048)
			(end 0.67945 -0.3048)
			(stroke
				(width 0.1)
				(type default)
			)
			(layer "F.Fab")
		)
		(fp_line
			(start 0.120396 0.3048)
			(end 0.120396 0.2794)
			(stroke
				(width 0.1)
				(type default)
			)
			(layer "F.Fab")
		)
		(fp_line
			(start 0.120396 0.2794)
			(end -0.12065 0.2794)
			(stroke
				(width 0.1)
				(type default)
			)
			(layer "F.Fab")
		)
		(fp_line
			(start -0.12065 0.3048)
			(end -0.67945 0.3048)
			(stroke
				(width 0.1)
				(type default)
			)
			(layer "F.Fab")
		)
		(fp_line
			(start -0.12065 0.2794)
			(end -0.12065 0.3048)
			(stroke
				(width 0.1)
				(type default)
			)
			(layer "F.Fab")
		)
		(fp_line
			(start -0.12065 -0.2794)
			(end 0.12065 -0.2794)
			(stroke
				(width 0.1)
				(type default)
			)
			(layer "F.Fab")
		)
		(fp_line
			(start -0.12065 -0.305054)
			(end -0.12065 -0.2794)
			(stroke
				(width 0.1)
				(type default)
			)
			(layer "F.Fab")
		)
		(fp_line
			(start -0.67945 0.3048)
			(end -0.67945 -0.305054)
			(stroke
				(width 0.1)
				(type default)
			)
			(layer "F.Fab")
		)
		(fp_line
			(start -0.67945 -0.305054)
			(end -0.12065 -0.305054)
			(stroke
				(width 0.1)
				(type default)
			)
			(layer "F.Fab")
		)
		(pad "1" smd circle
			(at -0.40005 0 180)
			(size 0 0)
			(layers "F.Cu" "F.Mask" "F.Paste")
			(net "PVDD18_S5_P0_EN")
		)
		(pad "2" smd circle
			(at 0.40005 0 180)
			(size 0 0)
			(layers "F.Cu" "F.Mask" "F.Paste")
			(net "FM_PVDD18_S5_P0_EN")
		)
	)
	(footprint ""
		(layer "F.Cu")
		(at 208.054956 -30.276292 90)
		(property "Reference" "R3612"
			(at 0 0 90)
			(layer "F.SilkS")
			(hide yes)
			(effects
				(font
					(size 1.27 1.27)
				)
			)
		)
		(property "Value" ""
			(at 0 0 90)
			(layer "F.Fab")
			(effects
				(font
					(size 1.27 1.27)
				)
			)
		)
		(duplicate_pad_numbers_are_jumpers no)
		(fp_line
			(start 0.7874 -0.4064)
			(end 0.7874 0.4064)
			(stroke
				(width 0.1524)
				(type default)
			)
			(layer "F.SilkS")
		)
		(fp_line
			(start -0.7874 -0.4064)
			(end 0.7874 -0.4064)
			(stroke
				(width 0.1524)
				(type default)
			)
			(layer "F.SilkS")
		)
		(fp_line
			(start 0.7874 0.4064)
			(end -0.7874 0.4064)
			(stroke
				(width 0.1524)
				(type default)
			)
			(layer "F.SilkS")
		)
		(fp_line
			(start -0.7874 0.4064)
			(end -0.7874 -0.4064)
			(stroke
				(width 0.1524)
				(type default)
			)
			(layer "F.SilkS")
		)
		(fp_line
			(start -0.12065 -0.305054)
			(end -0.12065 -0.2794)
			(stroke
				(width 0.1)
				(type default)
			)
			(layer "F.Fab")
		)
		(fp_line
			(start -0.67945 -0.305054)
			(end -0.12065 -0.305054)
			(stroke
				(width 0.1)
				(type default)
			)
			(layer "F.Fab")
		)
		(fp_line
			(start 0.67945 -0.3048)
			(end 0.67945 0.3048)
			(stroke
				(width 0.1)
				(type default)
			)
			(layer "F.Fab")
		)
		(fp_line
			(start 0.12065 -0.3048)
			(end 0.67945 -0.3048)
			(stroke
				(width 0.1)
				(type default)
			)
			(layer "F.Fab")
		)
		(fp_line
			(start 0.12065 -0.2794)
			(end 0.12065 -0.3048)
			(stroke
				(width 0.1)
				(type default)
			)
			(layer "F.Fab")
		)
		(fp_line
			(start -0.12065 -0.2794)
			(end 0.12065 -0.2794)
			(stroke
				(width 0.1)
				(type default)
			)
			(layer "F.Fab")
		)
		(fp_line
			(start 0.120396 0.2794)
			(end -0.12065 0.2794)
			(stroke
				(width 0.1)
				(type default)
			)
			(layer "F.Fab")
		)
		(fp_line
			(start -0.12065 0.2794)
			(end -0.12065 0.3048)
			(stroke
				(width 0.1)
				(type default)
			)
			(layer "F.Fab")
		)
		(fp_line
			(start 0.67945 0.3048)
			(end 0.120396 0.3048)
			(stroke
				(width 0.1)
				(type default)
			)
			(layer "F.Fab")
		)
		(fp_line
			(start 0.120396 0.3048)
			(end 0.120396 0.2794)
			(stroke
				(width 0.1)
				(type default)
			)
			(layer "F.Fab")
		)
		(fp_line
			(start -0.12065 0.3048)
			(end -0.67945 0.3048)
			(stroke
				(width 0.1)
				(type default)
			)
			(layer "F.Fab")
		)
		(fp_line
			(start -0.67945 0.3048)
			(end -0.67945 -0.305054)
			(stroke
				(width 0.1)
				(type default)
			)
			(layer "F.Fab")
		)
		(pad "1" smd circle
			(at -0.40005 0 90)
			(size 0 0)
			(layers "F.Cu" "F.Mask" "F.Paste")
			(net "GND")
		)
		(pad "2" smd circle
			(at 0.40005 0 90)
			(size 0 0)
			(layers "F.Cu" "F.Mask" "F.Paste")
			(net "INA230_5_A1")
		)
	)
	(footprint ""
		(layer "F.Cu")
		(at 447.687192 -22.125178 180)
		(property "Reference" "PR3781"
			(at 0 0 180)
			(layer "F.SilkS")
			(hide yes)
			(effects
				(font
					(size 1.27 1.27)
				)
			)
		)
		(property "Value" ""
			(at 0 0 180)
			(layer "F.Fab")
			(effects
				(font
					(size 1.27 1.27)
				)
			)
		)
		(duplicate_pad_numbers_are_jumpers no)
		(fp_line
			(start 0.7874 0.4064)
			(end -0.7874 0.4064)
			(stroke
				(width 0.1524)
				(type default)
			)
			(layer "F.SilkS")
		)
		(fp_line
			(start 0.7874 -0.4064)
			(end 0.7874 0.4064)
			(stroke
				(width 0.1524)
				(type default)
			)
			(layer "F.SilkS")
		)
		(fp_line
			(start -0.7874 0.4064)
			(end -0.7874 -0.4064)
			(stroke
				(width 0.1524)
				(type default)
			)
			(layer "F.SilkS")
		)
		(fp_line
			(start -0.7874 -0.4064)
			(end 0.7874 -0.4064)
			(stroke
				(width 0.1524)
				(type default)
			)
			(layer "F.SilkS")
		)
		(fp_line
			(start 0.67945 0.3048)
			(end 0.120396 0.3048)
			(stroke
				(width 0.1)
				(type default)
			)
			(layer "F.Fab")
		)
		(fp_line
			(start 0.67945 -0.3048)
			(end 0.67945 0.3048)
			(stroke
				(width 0.1)
				(type default)
			)
			(layer "F.Fab")
		)
		(fp_line
			(start 0.12065 -0.2794)
			(end 0.12065 -0.3048)
			(stroke
				(width 0.1)
				(type default)
			)
			(layer "F.Fab")
		)
		(fp_line
			(start 0.12065 -0.3048)
			(end 0.67945 -0.3048)
			(stroke
				(width 0.1)
				(type default)
			)
			(layer "F.Fab")
		)
		(fp_line
			(start 0.120396 0.3048)
			(end 0.120396 0.2794)
			(stroke
				(width 0.1)
				(type default)
			)
			(layer "F.Fab")
		)
		(fp_line
			(start 0.120396 0.2794)
			(end -0.12065 0.2794)
			(stroke
				(width 0.1)
				(type default)
			)
			(layer "F.Fab")
		)
		(fp_line
			(start -0.12065 0.3048)
			(end -0.67945 0.3048)
			(stroke
				(width 0.1)
				(type default)
			)
			(layer "F.Fab")
		)
		(fp_line
			(start -0.12065 0.2794)
			(end -0.12065 0.3048)
			(stroke
				(width 0.1)
				(type default)
			)
			(layer "F.Fab")
		)
		(fp_line
			(start -0.12065 -0.2794)
			(end 0.12065 -0.2794)
			(stroke
				(width 0.1)
				(type default)
			)
			(layer "F.Fab")
		)
		(fp_line
			(start -0.12065 -0.305054)
			(end -0.12065 -0.2794)
			(stroke
				(width 0.1)
				(type default)
			)
			(layer "F.Fab")
		)
		(fp_line
			(start -0.67945 0.3048)
			(end -0.67945 -0.305054)
			(stroke
				(width 0.1)
				(type default)
			)
			(layer "F.Fab")
		)
		(fp_line
			(start -0.67945 -0.305054)
			(end -0.12065 -0.305054)
			(stroke
				(width 0.1)
				(type default)
			)
			(layer "F.Fab")
		)
		(pad "1" smd circle
			(at -0.40005 0 180)
			(size 0 0)
			(layers "F.Cu" "F.Mask" "F.Paste")
			(net "P12V_OCP_SENSE_1")
		)
		(pad "2" smd circle
			(at 0.40005 0 180)
			(size 0 0)
			(layers "F.Cu" "F.Mask" "F.Paste")
			(net "GND")
		)
	)
	(footprint ""
		(layer "F.Cu")
		(at 347.98889 -338.200238 90)
		(property "Reference" "PR155"
			(at 0 0 90)
			(layer "F.SilkS")
			(hide yes)
			(effects
				(font
					(size 1.27 1.27)
				)
			)
		)
		(property "Value" ""
			(at 0 0 90)
			(layer "F.Fab")
			(effects
				(font
					(size 1.27 1.27)
				)
			)
		)
		(duplicate_pad_numbers_are_jumpers no)
		(fp_line
			(start 0.7874 -0.4064)
			(end 0.7874 0.4064)
			(stroke
				(width 0.1524)
				(type default)
			)
			(layer "F.SilkS")
		)
		(fp_line
			(start -0.7874 -0.4064)
			(end 0.7874 -0.4064)
			(stroke
				(width 0.1524)
				(type default)
			)
			(layer "F.SilkS")
		)
		(fp_line
			(start 0.7874 0.4064)
			(end -0.7874 0.4064)
			(stroke
				(width 0.1524)
				(type default)
			)
			(layer "F.SilkS")
		)
		(fp_line
			(start -0.7874 0.4064)
			(end -0.7874 -0.4064)
			(stroke
				(width 0.1524)
				(type default)
			)
			(layer "F.SilkS")
		)
		(fp_line
			(start -0.12065 -0.305054)
			(end -0.12065 -0.2794)
			(stroke
				(width 0.1)
				(type default)
			)
			(layer "F.Fab")
		)
		(fp_line
			(start -0.67945 -0.305054)
			(end -0.12065 -0.305054)
			(stroke
				(width 0.1)
				(type default)
			)
			(layer "F.Fab")
		)
		(fp_line
			(start 0.67945 -0.3048)
			(end 0.67945 0.3048)
			(stroke
				(width 0.1)
				(type default)
			)
			(layer "F.Fab")
		)
		(fp_line
			(start 0.12065 -0.3048)
			(end 0.67945 -0.3048)
			(stroke
				(width 0.1)
				(type default)
			)
			(layer "F.Fab")
		)
		(fp_line
			(start 0.12065 -0.2794)
			(end 0.12065 -0.3048)
			(stroke
				(width 0.1)
				(type default)
			)
			(layer "F.Fab")
		)
		(fp_line
			(start -0.12065 -0.2794)
			(end 0.12065 -0.2794)
			(stroke
				(width 0.1)
				(type default)
			)
			(layer "F.Fab")
		)
		(fp_line
			(start 0.120396 0.2794)
			(end -0.12065 0.2794)
			(stroke
				(width 0.1)
				(type default)
			)
			(layer "F.Fab")
		)
		(fp_line
			(start -0.12065 0.2794)
			(end -0.12065 0.3048)
			(stroke
				(width 0.1)
				(type default)
			)
			(layer "F.Fab")
		)
		(fp_line
			(start 0.67945 0.3048)
			(end 0.120396 0.3048)
			(stroke
				(width 0.1)
				(type default)
			)
			(layer "F.Fab")
		)
		(fp_line
			(start 0.120396 0.3048)
			(end 0.120396 0.2794)
			(stroke
				(width 0.1)
				(type default)
			)
			(layer "F.Fab")
		)
		(fp_line
			(start -0.12065 0.3048)
			(end -0.67945 0.3048)
			(stroke
				(width 0.1)
				(type default)
			)
			(layer "F.Fab")
		)
		(fp_line
			(start -0.67945 0.3048)
			(end -0.67945 -0.305054)
			(stroke
				(width 0.1)
				(type default)
			)
			(layer "F.Fab")
		)
		(pad "1" smd circle
			(at -0.40005 0 90)
			(size 0 0)
			(layers "F.Cu" "F.Mask" "F.Paste")
			(net "SW_PVDDCR_CPU1_P0_SW6_RC")
		)
		(pad "2" smd circle
			(at 0.40005 0 90)
			(size 0 0)
			(layers "F.Cu" "F.Mask" "F.Paste")
			(net "GND")
		)
	)
	(footprint ""
		(layer "F.Cu")
		(at 213.54288 -32.857948 180)
		(property "Reference" "R3577"
			(at 0 0 180)
			(layer "F.SilkS")
			(hide yes)
			(effects
				(font
					(size 1.27 1.27)
				)
			)
		)
		(property "Value" ""
			(at 0 0 180)
			(layer "F.Fab")
			(effects
				(font
					(size 1.27 1.27)
				)
			)
		)
		(duplicate_pad_numbers_are_jumpers no)
		(fp_line
			(start 0.7874 0.4064)
			(end -0.7874 0.4064)
			(stroke
				(width 0.1524)
				(type default)
			)
			(layer "F.SilkS")
		)
		(fp_line
			(start 0.7874 -0.4064)
			(end 0.7874 0.4064)
			(stroke
				(width 0.1524)
				(type default)
			)
			(layer "F.SilkS")
		)
		(fp_line
			(start -0.7874 0.4064)
			(end -0.7874 -0.4064)
			(stroke
				(width 0.1524)
				(type default)
			)
			(layer "F.SilkS")
		)
		(fp_line
			(start -0.7874 -0.4064)
			(end 0.7874 -0.4064)
			(stroke
				(width 0.1524)
				(type default)
			)
			(layer "F.SilkS")
		)
		(fp_line
			(start 0.67945 0.3048)
			(end 0.120396 0.3048)
			(stroke
				(width 0.1)
				(type default)
			)
			(layer "F.Fab")
		)
		(fp_line
			(start 0.67945 -0.3048)
			(end 0.67945 0.3048)
			(stroke
				(width 0.1)
				(type default)
			)
			(layer "F.Fab")
		)
		(fp_line
			(start 0.12065 -0.2794)
			(end 0.12065 -0.3048)
			(stroke
				(width 0.1)
				(type default)
			)
			(layer "F.Fab")
		)
		(fp_line
			(start 0.12065 -0.3048)
			(end 0.67945 -0.3048)
			(stroke
				(width 0.1)
				(type default)
			)
			(layer "F.Fab")
		)
		(fp_line
			(start 0.120396 0.3048)
			(end 0.120396 0.2794)
			(stroke
				(width 0.1)
				(type default)
			)
			(layer "F.Fab")
		)
		(fp_line
			(start 0.120396 0.2794)
			(end -0.12065 0.2794)
			(stroke
				(width 0.1)
				(type default)
			)
			(layer "F.Fab")
		)
		(fp_line
			(start -0.12065 0.3048)
			(end -0.67945 0.3048)
			(stroke
				(width 0.1)
				(type default)
			)
			(layer "F.Fab")
		)
		(fp_line
			(start -0.12065 0.2794)
			(end -0.12065 0.3048)
			(stroke
				(width 0.1)
				(type default)
			)
			(layer "F.Fab")
		)
		(fp_line
			(start -0.12065 -0.2794)
			(end 0.12065 -0.2794)
			(stroke
				(width 0.1)
				(type default)
			)
			(layer "F.Fab")
		)
		(fp_line
			(start -0.12065 -0.305054)
			(end -0.12065 -0.2794)
			(stroke
				(width 0.1)
				(type default)
			)
			(layer "F.Fab")
		)
		(fp_line
			(start -0.67945 0.3048)
			(end -0.67945 -0.305054)
			(stroke
				(width 0.1)
				(type default)
			)
			(layer "F.Fab")
		)
		(fp_line
			(start -0.67945 -0.305054)
			(end -0.12065 -0.305054)
			(stroke
				(width 0.1)
				(type default)
			)
			(layer "F.Fab")
		)
		(pad "1" smd circle
			(at -0.40005 0 180)
			(size 0 0)
			(layers "F.Cu" "F.Mask" "F.Paste")
			(net "SMB_INA230_5_3V3AUX_SDA_R")
		)
		(pad "2" smd circle
			(at 0.40005 0 180)
			(size 0 0)
			(layers "F.Cu" "F.Mask" "F.Paste")
			(net "SMB_INA230_5_3V3AUX_SDA_R1")
		)
	)
	(footprint ""
		(layer "F.Cu")
		(at 399.350484 -403.285452 90)
		(property "Reference" "R1054"
			(at 0 0 90)
			(layer "F.SilkS")
			(hide yes)
			(effects
				(font
					(size 1.27 1.27)
				)
			)
		)
		(property "Value" ""
			(at 0 0 90)
			(layer "F.Fab")
			(effects
				(font
					(size 1.27 1.27)
				)
			)
		)
		(duplicate_pad_numbers_are_jumpers no)
		(fp_line
			(start 0.32512 -0.175006)
			(end 0.32512 0.175006)
			(stroke
				(width 0.1)
				(type default)
			)
			(layer "F.Fab")
		)
		(fp_line
			(start -0.32512 -0.175006)
			(end 0.32512 -0.175006)
			(stroke
				(width 0.1)
				(type default)
			)
			(layer "F.Fab")
		)
		(fp_line
			(start 0.32512 0.175006)
			(end -0.32512 0.175006)
			(stroke
				(width 0.1)
				(type default)
			)
			(layer "F.Fab")
		)
		(fp_line
			(start -0.32512 0.175006)
			(end -0.32512 -0.175006)
			(stroke
				(width 0.1)
				(type default)
			)
			(layer "F.Fab")
		)
		(pad "1" smd rect
			(at -0.2667 0 90)
			(size 0.3048 0.381)
			(layers "F.Cu" "F.Mask" "F.Paste")
			(net "RST_RT_CPU0_P2_RESET_N")
		)
		(pad "2" smd rect
			(at 0.2667 0 270)
			(size 0.3048 0.381)
			(layers "F.Cu" "F.Mask" "F.Paste")
			(net "RST_RT_CPU0_P2_RESET_R_N")
		)
	)
	(footprint ""
		(layer "F.Cu")
		(at 204.851 -337.439 -90)
		(property "Reference" "PC128"
			(at 0 0 270)
			(layer "F.SilkS")
			(hide yes)
			(effects
				(font
					(size 1.27 1.27)
				)
			)
		)
		(property "Value" ""
			(at 0 0 270)
			(layer "F.Fab")
			(effects
				(font
					(size 1.27 1.27)
				)
			)
		)
		(duplicate_pad_numbers_are_jumpers no)
		(fp_line
			(start -0.7874 0.4064)
			(end -0.7874 -0.4064)
			(stroke
				(width 0.1524)
				(type default)
			)
			(layer "F.SilkS")
		)
		(fp_line
			(start 0.7874 0.4064)
			(end -0.7874 0.4064)
			(stroke
				(width 0.1524)
				(type default)
			)
			(layer "F.SilkS")
		)
		(fp_line
			(start -0.7874 -0.4064)
			(end 0.7874 -0.4064)
			(stroke
				(width 0.1524)
				(type default)
			)
			(layer "F.SilkS")
		)
		(fp_line
			(start 0.7874 -0.4064)
			(end 0.7874 0.4064)
			(stroke
				(width 0.1524)
				(type default)
			)
			(layer "F.SilkS")
		)
		(fp_line
			(start -0.67945 0.3048)
			(end -0.67945 -0.305054)
			(stroke
				(width 0.1)
				(type default)
			)
			(layer "F.Fab")
		)
		(fp_line
			(start -0.12065 0.3048)
			(end -0.67945 0.3048)
			(stroke
				(width 0.1)
				(type default)
			)
			(layer "F.Fab")
		)
		(fp_line
			(start 0.120396 0.3048)
			(end 0.120396 0.2794)
			(stroke
				(width 0.1)
				(type default)
			)
			(layer "F.Fab")
		)
		(fp_line
			(start 0.67945 0.3048)
			(end 0.120396 0.3048)
			(stroke
				(width 0.1)
				(type default)
			)
			(layer "F.Fab")
		)
		(fp_line
			(start -0.12065 0.2794)
			(end -0.12065 0.3048)
			(stroke
				(width 0.1)
				(type default)
			)
			(layer "F.Fab")
		)
		(fp_line
			(start 0.120396 0.2794)
			(end -0.12065 0.2794)
			(stroke
				(width 0.1)
				(type default)
			)
			(layer "F.Fab")
		)
		(fp_line
			(start -0.12065 -0.2794)
			(end 0.12065 -0.2794)
			(stroke
				(width 0.1)
				(type default)
			)
			(layer "F.Fab")
		)
		(fp_line
			(start 0.12065 -0.2794)
			(end 0.12065 -0.3048)
			(stroke
				(width 0.1)
				(type default)
			)
			(layer "F.Fab")
		)
		(fp_line
			(start 0.12065 -0.3048)
			(end 0.67945 -0.3048)
			(stroke
				(width 0.1)
				(type default)
			)
			(layer "F.Fab")
		)
		(fp_line
			(start 0.67945 -0.3048)
			(end 0.67945 0.3048)
			(stroke
				(width 0.1)
				(type default)
			)
			(layer "F.Fab")
		)
		(fp_line
			(start -0.67945 -0.305054)
			(end -0.12065 -0.305054)
			(stroke
				(width 0.1)
				(type default)
			)
			(layer "F.Fab")
		)
		(fp_line
			(start -0.12065 -0.305054)
			(end -0.12065 -0.2794)
			(stroke
				(width 0.1)
				(type default)
			)
			(layer "F.Fab")
		)
		(pad "1" smd circle
			(at -0.40005 0 270)
			(size 0 0)
			(layers "F.Cu" "F.Mask" "F.Paste")
			(net "SW_PVDD_33_S5_BST_R")
		)
		(pad "2" smd circle
			(at 0.40005 0 270)
			(size 0 0)
			(layers "F.Cu" "F.Mask" "F.Paste")
			(net "SW_PVDD_33_S5_SW")
		)
	)
	(footprint ""
		(layer "F.Cu")
		(at 425.3484 -421.64 90)
		(property "Reference" "R1482"
			(at 0 0 90)
			(layer "F.SilkS")
			(hide yes)
			(effects
				(font
					(size 1.27 1.27)
				)
			)
		)
		(property "Value" ""
			(at 0 0 90)
			(layer "F.Fab")
			(effects
				(font
					(size 1.27 1.27)
				)
			)
		)
		(duplicate_pad_numbers_are_jumpers no)
		(fp_line
			(start 0.32512 -0.175006)
			(end 0.32512 0.175006)
			(stroke
				(width 0.1)
				(type default)
			)
			(layer "F.Fab")
		)
		(fp_line
			(start -0.32512 -0.175006)
			(end 0.32512 -0.175006)
			(stroke
				(width 0.1)
				(type default)
			)
			(layer "F.Fab")
		)
		(fp_line
			(start 0.32512 0.175006)
			(end -0.32512 0.175006)
			(stroke
				(width 0.1)
				(type default)
			)
			(layer "F.Fab")
		)
		(fp_line
			(start -0.32512 0.175006)
			(end -0.32512 -0.175006)
			(stroke
				(width 0.1)
				(type default)
			)
			(layer "F.Fab")
		)
		(pad "1" smd rect
			(at -0.2667 0 90)
			(size 0.3048 0.381)
			(layers "F.Cu" "F.Mask" "F.Paste")
			(net "P1V8_CPU0_RT_1D")
		)
		(pad "2" smd rect
			(at 0.2667 0 270)
			(size 0.3048 0.381)
			(layers "F.Cu" "F.Mask" "F.Paste")
			(net "JTAG_TDI_RT_CPU0_P3")
		)
	)
	(footprint ""
		(layer "F.Cu")
		(at 381.405892 -378.95403 -90)
		(property "Reference" "C883"
			(at 0 0 270)
			(layer "F.SilkS")
			(hide yes)
			(effects
				(font
					(size 1.27 1.27)
				)
			)
		)
		(property "Value" ""
			(at 0 0 270)
			(layer "F.Fab")
			(effects
				(font
					(size 1.27 1.27)
				)
			)
		)
		(duplicate_pad_numbers_are_jumpers no)
		(fp_line
			(start -0.299974 0.150114)
			(end -0.299974 -0.150114)
			(stroke
				(width 0.1)
				(type default)
			)
			(layer "F.Fab")
		)
		(fp_line
			(start 0.299974 0.150114)
			(end -0.299974 0.150114)
			(stroke
				(width 0.1)
				(type default)
			)
			(layer "F.Fab")
		)
		(fp_line
			(start -0.299974 -0.150114)
			(end 0.299974 -0.150114)
			(stroke
				(width 0.1)
				(type default)
			)
			(layer "F.Fab")
		)
		(fp_line
			(start 0.299974 -0.150114)
			(end 0.299974 0.150114)
			(stroke
				(width 0.1)
				(type default)
			)
			(layer "F.Fab")
		)
		(pad "1" smd rect
			(at -0.2667 0 270)
			(size 0.3048 0.381)
			(layers "F.Cu" "F.Mask" "F.Paste")
			(net "P5E_CPU0_P3_TX_C_DP<9>")
		)
		(pad "2" smd rect
			(at 0.2667 0 270)
			(size 0.3048 0.381)
			(layers "F.Cu" "F.Mask" "F.Paste")
			(net "P5E_CPU0_P3_TX_DP<9>")
		)
	)
	(footprint ""
		(layer "F.Cu")
		(at 170.213782 -392.074146)
		(property "Reference" "C398"
			(at 0 0 0)
			(layer "F.SilkS")
			(hide yes)
			(effects
				(font
					(size 1.27 1.27)
				)
			)
		)
		(property "Value" ""
			(at 0 0 0)
			(layer "F.Fab")
			(effects
				(font
					(size 1.27 1.27)
				)
			)
		)
		(duplicate_pad_numbers_are_jumpers no)
		(fp_line
			(start -1.524 -0.762)
			(end 1.524 -0.762)
			(stroke
				(width 0.1524)
				(type default)
			)
			(layer "F.SilkS")
		)
		(fp_line
			(start -1.524 0.762)
			(end -1.524 -0.762)
			(stroke
				(width 0.1524)
				(type default)
			)
			(layer "F.SilkS")
		)
		(fp_line
			(start 1.524 -0.762)
			(end 1.524 0.762)
			(stroke
				(width 0.1524)
				(type default)
			)
			(layer "F.SilkS")
		)
		(fp_line
			(start 1.524 0.762)
			(end -1.524 0.762)
			(stroke
				(width 0.1524)
				(type default)
			)
			(layer "F.SilkS")
		)
		(fp_line
			(start -1.1049 -0.724916)
			(end -1.1049 0.724916)
			(stroke
				(width 0.1)
				(type default)
			)
			(layer "F.Fab")
		)
		(fp_line
			(start -1.1049 0.724916)
			(end 1.1049 0.724916)
			(stroke
				(width 0.1)
				(type default)
			)
			(layer "F.Fab")
		)
		(fp_line
			(start 1.1049 -0.724916)
			(end -1.1049 -0.724916)
			(stroke
				(width 0.1)
				(type default)
			)
			(layer "F.Fab")
		)
		(fp_line
			(start 1.1049 0.724916)
			(end 1.1049 -0.724916)
			(stroke
				(width 0.1)
				(type default)
			)
			(layer "F.Fab")
		)
		(pad "1" smd rect
			(at -0.889 0 180)
			(size 1.016 1.27)
			(layers "F.Cu" "F.Mask" "F.Paste")
			(net "P0V9_CPU1_RT2_2A")
		)
		(pad "2" smd rect
			(at 0.889 0 180)
			(size 1.016 1.27)
			(layers "F.Cu" "F.Mask" "F.Paste")
			(net "GND")
		)
	)
	(footprint ""
		(layer "F.Cu")
		(at 372.937278 -144.520158 180)
		(property "Reference" "R8289"
			(at 0 0 180)
			(layer "F.SilkS")
			(hide yes)
			(effects
				(font
					(size 1.27 1.27)
				)
			)
		)
		(property "Value" ""
			(at 0 0 180)
			(layer "F.Fab")
			(effects
				(font
					(size 1.27 1.27)
				)
			)
		)
		(duplicate_pad_numbers_are_jumpers no)
		(fp_line
			(start 0.7874 0.4064)
			(end -0.7874 0.4064)
			(stroke
				(width 0.1524)
				(type default)
			)
			(layer "F.SilkS")
		)
		(fp_line
			(start 0.7874 -0.4064)
			(end 0.7874 0.4064)
			(stroke
				(width 0.1524)
				(type default)
			)
			(layer "F.SilkS")
		)
		(fp_line
			(start -0.7874 0.4064)
			(end -0.7874 -0.4064)
			(stroke
				(width 0.1524)
				(type default)
			)
			(layer "F.SilkS")
		)
		(fp_line
			(start -0.7874 -0.4064)
			(end 0.7874 -0.4064)
			(stroke
				(width 0.1524)
				(type default)
			)
			(layer "F.SilkS")
		)
		(fp_line
			(start 0.67945 0.3048)
			(end 0.120396 0.3048)
			(stroke
				(width 0.1)
				(type default)
			)
			(layer "F.Fab")
		)
		(fp_line
			(start 0.67945 -0.3048)
			(end 0.67945 0.3048)
			(stroke
				(width 0.1)
				(type default)
			)
			(layer "F.Fab")
		)
		(fp_line
			(start 0.12065 -0.2794)
			(end 0.12065 -0.3048)
			(stroke
				(width 0.1)
				(type default)
			)
			(layer "F.Fab")
		)
		(fp_line
			(start 0.12065 -0.3048)
			(end 0.67945 -0.3048)
			(stroke
				(width 0.1)
				(type default)
			)
			(layer "F.Fab")
		)
		(fp_line
			(start 0.120396 0.3048)
			(end 0.120396 0.2794)
			(stroke
				(width 0.1)
				(type default)
			)
			(layer "F.Fab")
		)
		(fp_line
			(start 0.120396 0.2794)
			(end -0.12065 0.2794)
			(stroke
				(width 0.1)
				(type default)
			)
			(layer "F.Fab")
		)
		(fp_line
			(start -0.12065 0.3048)
			(end -0.67945 0.3048)
			(stroke
				(width 0.1)
				(type default)
			)
			(layer "F.Fab")
		)
		(fp_line
			(start -0.12065 0.2794)
			(end -0.12065 0.3048)
			(stroke
				(width 0.1)
				(type default)
			)
			(layer "F.Fab")
		)
		(fp_line
			(start -0.12065 -0.2794)
			(end 0.12065 -0.2794)
			(stroke
				(width 0.1)
				(type default)
			)
			(layer "F.Fab")
		)
		(fp_line
			(start -0.12065 -0.305054)
			(end -0.12065 -0.2794)
			(stroke
				(width 0.1)
				(type default)
			)
			(layer "F.Fab")
		)
		(fp_line
			(start -0.67945 0.3048)
			(end -0.67945 -0.305054)
			(stroke
				(width 0.1)
				(type default)
			)
			(layer "F.Fab")
		)
		(fp_line
			(start -0.67945 -0.305054)
			(end -0.12065 -0.305054)
			(stroke
				(width 0.1)
				(type default)
			)
			(layer "F.Fab")
		)
		(pad "1" smd circle
			(at -0.40005 0 180)
			(size 0 0)
			(layers "F.Cu" "F.Mask" "F.Paste")
			(net "PVDD18_S5_P0")
		)
		(pad "2" smd circle
			(at 0.40005 0 180)
			(size 0 0)
			(layers "F.Cu" "F.Mask" "F.Paste")
			(net "SVID_PVDDCR_CPU0_P0_SVD_R")
		)
	)
	(footprint ""
		(layer "F.Cu")
		(at 67.062604 -408.517344 -90)
		(property "Reference" "C6641"
			(at 0 0 270)
			(layer "F.SilkS")
			(hide yes)
			(effects
				(font
					(size 1.27 1.27)
				)
			)
		)
		(property "Value" ""
			(at 0 0 270)
			(layer "F.Fab")
			(effects
				(font
					(size 1.27 1.27)
				)
			)
		)
		(duplicate_pad_numbers_are_jumpers no)
		(fp_line
			(start -0.299974 0.150114)
			(end -0.299974 -0.150114)
			(stroke
				(width 0.1)
				(type default)
			)
			(layer "F.Fab")
		)
		(fp_line
			(start 0.299974 0.150114)
			(end -0.299974 0.150114)
			(stroke
				(width 0.1)
				(type default)
			)
			(layer "F.Fab")
		)
		(fp_line
			(start -0.299974 -0.150114)
			(end 0.299974 -0.150114)
			(stroke
				(width 0.1)
				(type default)
			)
			(layer "F.Fab")
		)
		(fp_line
			(start 0.299974 -0.150114)
			(end 0.299974 0.150114)
			(stroke
				(width 0.1)
				(type default)
			)
			(layer "F.Fab")
		)
		(pad "1" smd rect
			(at -0.2667 0 270)
			(size 0.3048 0.381)
			(layers "F.Cu" "F.Mask" "F.Paste")
			(net "P5E_CPU1_P0_TX_BUF_C_DP<6>")
		)
		(pad "2" smd rect
			(at 0.2667 0 270)
			(size 0.3048 0.381)
			(layers "F.Cu" "F.Mask" "F.Paste")
			(net "P5E_CPU1_P0_TX_BUF_DP<6>")
		)
	)
	(footprint ""
		(layer "F.Cu")
		(at 367.050066 -427.400212 -90)
		(property "Reference" "R4206"
			(at 0 0 270)
			(layer "F.SilkS")
			(hide yes)
			(effects
				(font
					(size 1.27 1.27)
				)
			)
		)
		(property "Value" ""
			(at 0 0 270)
			(layer "F.Fab")
			(effects
				(font
					(size 1.27 1.27)
				)
			)
		)
		(duplicate_pad_numbers_are_jumpers no)
		(fp_line
			(start -0.7874 0.4064)
			(end -0.7874 -0.4064)
			(stroke
				(width 0.1524)
				(type default)
			)
			(layer "F.SilkS")
		)
		(fp_line
			(start 0.7874 0.4064)
			(end -0.7874 0.4064)
			(stroke
				(width 0.1524)
				(type default)
			)
			(layer "F.SilkS")
		)
		(fp_line
			(start -0.7874 -0.4064)
			(end 0.7874 -0.4064)
			(stroke
				(width 0.1524)
				(type default)
			)
			(layer "F.SilkS")
		)
		(fp_line
			(start 0.7874 -0.4064)
			(end 0.7874 0.4064)
			(stroke
				(width 0.1524)
				(type default)
			)
			(layer "F.SilkS")
		)
		(fp_line
			(start -0.67945 0.3048)
			(end -0.67945 -0.305054)
			(stroke
				(width 0.1)
				(type default)
			)
			(layer "F.Fab")
		)
		(fp_line
			(start -0.12065 0.3048)
			(end -0.67945 0.3048)
			(stroke
				(width 0.1)
				(type default)
			)
			(layer "F.Fab")
		)
		(fp_line
			(start 0.120396 0.3048)
			(end 0.120396 0.2794)
			(stroke
				(width 0.1)
				(type default)
			)
			(layer "F.Fab")
		)
		(fp_line
			(start 0.67945 0.3048)
			(end 0.120396 0.3048)
			(stroke
				(width 0.1)
				(type default)
			)
			(layer "F.Fab")
		)
		(fp_line
			(start -0.12065 0.2794)
			(end -0.12065 0.3048)
			(stroke
				(width 0.1)
				(type default)
			)
			(layer "F.Fab")
		)
		(fp_line
			(start 0.120396 0.2794)
			(end -0.12065 0.2794)
			(stroke
				(width 0.1)
				(type default)
			)
			(layer "F.Fab")
		)
		(fp_line
			(start -0.12065 -0.2794)
			(end 0.12065 -0.2794)
			(stroke
				(width 0.1)
				(type default)
			)
			(layer "F.Fab")
		)
		(fp_line
			(start 0.12065 -0.2794)
			(end 0.12065 -0.3048)
			(stroke
				(width 0.1)
				(type default)
			)
			(layer "F.Fab")
		)
		(fp_line
			(start 0.12065 -0.3048)
			(end 0.67945 -0.3048)
			(stroke
				(width 0.1)
				(type default)
			)
			(layer "F.Fab")
		)
		(fp_line
			(start 0.67945 -0.3048)
			(end 0.67945 0.3048)
			(stroke
				(width 0.1)
				(type default)
			)
			(layer "F.Fab")
		)
		(fp_line
			(start -0.67945 -0.305054)
			(end -0.12065 -0.305054)
			(stroke
				(width 0.1)
				(type default)
			)
			(layer "F.Fab")
		)
		(fp_line
			(start -0.12065 -0.305054)
			(end -0.12065 -0.2794)
			(stroke
				(width 0.1)
				(type default)
			)
			(layer "F.Fab")
		)
		(pad "1" smd circle
			(at -0.40005 0 270)
			(size 0 0)
			(layers "F.Cu" "F.Mask" "F.Paste")
			(net "P3V3_AUX")
		)
		(pad "2" smd circle
			(at 0.40005 0 270)
			(size 0 0)
			(layers "F.Cu" "F.Mask" "F.Paste")
			(net "U270_0_ADD0")
		)
	)
	(footprint ""
		(layer "F.Cu")
		(at 116.078 -417.957 -90)
		(property "Reference" "R3030"
			(at 0 0 270)
			(layer "F.SilkS")
			(hide yes)
			(effects
				(font
					(size 1.27 1.27)
				)
			)
		)
		(property "Value" ""
			(at 0 0 270)
			(layer "F.Fab")
			(effects
				(font
					(size 1.27 1.27)
				)
			)
		)
		(duplicate_pad_numbers_are_jumpers no)
		(fp_line
			(start -0.7874 0.4064)
			(end -0.7874 -0.4064)
			(stroke
				(width 0.1524)
				(type default)
			)
			(layer "F.SilkS")
		)
		(fp_line
			(start 0.7874 0.4064)
			(end -0.7874 0.4064)
			(stroke
				(width 0.1524)
				(type default)
			)
			(layer "F.SilkS")
		)
		(fp_line
			(start -0.7874 -0.4064)
			(end 0.7874 -0.4064)
			(stroke
				(width 0.1524)
				(type default)
			)
			(layer "F.SilkS")
		)
		(fp_line
			(start 0.7874 -0.4064)
			(end 0.7874 0.4064)
			(stroke
				(width 0.1524)
				(type default)
			)
			(layer "F.SilkS")
		)
		(fp_line
			(start -0.67945 0.3048)
			(end -0.67945 -0.305054)
			(stroke
				(width 0.1)
				(type default)
			)
			(layer "F.Fab")
		)
		(fp_line
			(start -0.12065 0.3048)
			(end -0.67945 0.3048)
			(stroke
				(width 0.1)
				(type default)
			)
			(layer "F.Fab")
		)
		(fp_line
			(start 0.120396 0.3048)
			(end 0.120396 0.2794)
			(stroke
				(width 0.1)
				(type default)
			)
			(layer "F.Fab")
		)
		(fp_line
			(start 0.67945 0.3048)
			(end 0.120396 0.3048)
			(stroke
				(width 0.1)
				(type default)
			)
			(layer "F.Fab")
		)
		(fp_line
			(start -0.12065 0.2794)
			(end -0.12065 0.3048)
			(stroke
				(width 0.1)
				(type default)
			)
			(layer "F.Fab")
		)
		(fp_line
			(start 0.120396 0.2794)
			(end -0.12065 0.2794)
			(stroke
				(width 0.1)
				(type default)
			)
			(layer "F.Fab")
		)
		(fp_line
			(start -0.12065 -0.2794)
			(end 0.12065 -0.2794)
			(stroke
				(width 0.1)
				(type default)
			)
			(layer "F.Fab")
		)
		(fp_line
			(start 0.12065 -0.2794)
			(end 0.12065 -0.3048)
			(stroke
				(width 0.1)
				(type default)
			)
			(layer "F.Fab")
		)
		(fp_line
			(start 0.12065 -0.3048)
			(end 0.67945 -0.3048)
			(stroke
				(width 0.1)
				(type default)
			)
			(layer "F.Fab")
		)
		(fp_line
			(start 0.67945 -0.3048)
			(end 0.67945 0.3048)
			(stroke
				(width 0.1)
				(type default)
			)
			(layer "F.Fab")
		)
		(fp_line
			(start -0.67945 -0.305054)
			(end -0.12065 -0.305054)
			(stroke
				(width 0.1)
				(type default)
			)
			(layer "F.Fab")
		)
		(fp_line
			(start -0.12065 -0.305054)
			(end -0.12065 -0.2794)
			(stroke
				(width 0.1)
				(type default)
			)
			(layer "F.Fab")
		)
		(pad "1" smd circle
			(at -0.40005 0 270)
			(size 0 0)
			(layers "F.Cu" "F.Mask" "F.Paste")
			(net "P3V3_AUX")
		)
		(pad "2" smd circle
			(at 0.40005 0 270)
			(size 0 0)
			(layers "F.Cu" "F.Mask" "F.Paste")
			(net "FM_SMB_1_ALERT_GPU_ISO_N")
		)
	)
	(footprint ""
		(layer "F.Cu")
		(at 409.8417 -171.598082)
		(property "Reference" "PC187"
			(at 0 0 0)
			(layer "F.SilkS")
			(hide yes)
			(effects
				(font
					(size 1.27 1.27)
				)
			)
		)
		(property "Value" ""
			(at 0 0 0)
			(layer "F.Fab")
			(effects
				(font
					(size 1.27 1.27)
				)
			)
		)
		(duplicate_pad_numbers_are_jumpers no)
		(fp_line
			(start -0.7874 -0.4064)
			(end 0.7874 -0.4064)
			(stroke
				(width 0.1524)
				(type default)
			)
			(layer "F.SilkS")
		)
		(fp_line
			(start -0.7874 0.4064)
			(end -0.7874 -0.4064)
			(stroke
				(width 0.1524)
				(type default)
			)
			(layer "F.SilkS")
		)
		(fp_line
			(start 0.7874 -0.4064)
			(end 0.7874 0.4064)
			(stroke
				(width 0.1524)
				(type default)
			)
			(layer "F.SilkS")
		)
		(fp_line
			(start 0.7874 0.4064)
			(end -0.7874 0.4064)
			(stroke
				(width 0.1524)
				(type default)
			)
			(layer "F.SilkS")
		)
		(fp_line
			(start -0.67945 -0.305054)
			(end -0.12065 -0.305054)
			(stroke
				(width 0.1)
				(type default)
			)
			(layer "F.Fab")
		)
		(fp_line
			(start -0.67945 0.3048)
			(end -0.67945 -0.305054)
			(stroke
				(width 0.1)
				(type default)
			)
			(layer "F.Fab")
		)
		(fp_line
			(start -0.12065 -0.305054)
			(end -0.12065 -0.2794)
			(stroke
				(width 0.1)
				(type default)
			)
			(layer "F.Fab")
		)
		(fp_line
			(start -0.12065 -0.2794)
			(end 0.12065 -0.2794)
			(stroke
				(width 0.1)
				(type default)
			)
			(layer "F.Fab")
		)
		(fp_line
			(start -0.12065 0.2794)
			(end -0.12065 0.3048)
			(stroke
				(width 0.1)
				(type default)
			)
			(layer "F.Fab")
		)
		(fp_line
			(start -0.12065 0.3048)
			(end -0.67945 0.3048)
			(stroke
				(width 0.1)
				(type default)
			)
			(layer "F.Fab")
		)
		(fp_line
			(start 0.120396 0.2794)
			(end -0.12065 0.2794)
			(stroke
				(width 0.1)
				(type default)
			)
			(layer "F.Fab")
		)
		(fp_line
			(start 0.120396 0.3048)
			(end 0.120396 0.2794)
			(stroke
				(width 0.1)
				(type default)
			)
			(layer "F.Fab")
		)
		(fp_line
			(start 0.12065 -0.3048)
			(end 0.67945 -0.3048)
			(stroke
				(width 0.1)
				(type default)
			)
			(layer "F.Fab")
		)
		(fp_line
			(start 0.12065 -0.2794)
			(end 0.12065 -0.3048)
			(stroke
				(width 0.1)
				(type default)
			)
			(layer "F.Fab")
		)
		(fp_line
			(start 0.67945 -0.3048)
			(end 0.67945 0.3048)
			(stroke
				(width 0.1)
				(type default)
			)
			(layer "F.Fab")
		)
		(fp_line
			(start 0.67945 0.3048)
			(end 0.120396 0.3048)
			(stroke
				(width 0.1)
				(type default)
			)
			(layer "F.Fab")
		)
		(pad "1" smd circle
			(at -0.40005 0)
			(size 0 0)
			(layers "F.Cu" "F.Mask" "F.Paste")
			(net "SW_PVDDCR_SOC_P0_SW2")
		)
		(pad "2" smd circle
			(at 0.40005 0)
			(size 0 0)
			(layers "F.Cu" "F.Mask" "F.Paste")
			(net "SW_PVDDCR_SOC_P0_SW2_RC")
		)
	)
	(footprint ""
		(layer "F.Cu")
		(at 136.118092 -159.535368)
		(property "Reference" "PC195"
			(at 0 0 0)
			(layer "F.SilkS")
			(hide yes)
			(effects
				(font
					(size 1.27 1.27)
				)
			)
		)
		(property "Value" ""
			(at 0 0 0)
			(layer "F.Fab")
			(effects
				(font
					(size 1.27 1.27)
				)
			)
		)
		(duplicate_pad_numbers_are_jumpers no)
		(fp_line
			(start -0.7874 -0.4064)
			(end 0.7874 -0.4064)
			(stroke
				(width 0.1524)
				(type default)
			)
			(layer "F.SilkS")
		)
		(fp_line
			(start -0.7874 0.4064)
			(end -0.7874 -0.4064)
			(stroke
				(width 0.1524)
				(type default)
			)
			(layer "F.SilkS")
		)
		(fp_line
			(start 0.7874 -0.4064)
			(end 0.7874 0.4064)
			(stroke
				(width 0.1524)
				(type default)
			)
			(layer "F.SilkS")
		)
		(fp_line
			(start 0.7874 0.4064)
			(end -0.7874 0.4064)
			(stroke
				(width 0.1524)
				(type default)
			)
			(layer "F.SilkS")
		)
		(fp_line
			(start -0.67945 -0.305054)
			(end -0.12065 -0.305054)
			(stroke
				(width 0.1)
				(type default)
			)
			(layer "F.Fab")
		)
		(fp_line
			(start -0.67945 0.3048)
			(end -0.67945 -0.305054)
			(stroke
				(width 0.1)
				(type default)
			)
			(layer "F.Fab")
		)
		(fp_line
			(start -0.12065 -0.305054)
			(end -0.12065 -0.2794)
			(stroke
				(width 0.1)
				(type default)
			)
			(layer "F.Fab")
		)
		(fp_line
			(start -0.12065 -0.2794)
			(end 0.12065 -0.2794)
			(stroke
				(width 0.1)
				(type default)
			)
			(layer "F.Fab")
		)
		(fp_line
			(start -0.12065 0.2794)
			(end -0.12065 0.3048)
			(stroke
				(width 0.1)
				(type default)
			)
			(layer "F.Fab")
		)
		(fp_line
			(start -0.12065 0.3048)
			(end -0.67945 0.3048)
			(stroke
				(width 0.1)
				(type default)
			)
			(layer "F.Fab")
		)
		(fp_line
			(start 0.120396 0.2794)
			(end -0.12065 0.2794)
			(stroke
				(width 0.1)
				(type default)
			)
			(layer "F.Fab")
		)
		(fp_line
			(start 0.120396 0.3048)
			(end 0.120396 0.2794)
			(stroke
				(width 0.1)
				(type default)
			)
			(layer "F.Fab")
		)
		(fp_line
			(start 0.12065 -0.3048)
			(end 0.67945 -0.3048)
			(stroke
				(width 0.1)
				(type default)
			)
			(layer "F.Fab")
		)
		(fp_line
			(start 0.12065 -0.2794)
			(end 0.12065 -0.3048)
			(stroke
				(width 0.1)
				(type default)
			)
			(layer "F.Fab")
		)
		(fp_line
			(start 0.67945 -0.3048)
			(end 0.67945 0.3048)
			(stroke
				(width 0.1)
				(type default)
			)
			(layer "F.Fab")
		)
		(fp_line
			(start 0.67945 0.3048)
			(end 0.120396 0.3048)
			(stroke
				(width 0.1)
				(type default)
			)
			(layer "F.Fab")
		)
		(pad "1" smd circle
			(at -0.40005 0)
			(size 0 0)
			(layers "F.Cu" "F.Mask" "F.Paste")
			(net "SW_PVDDCR_SOC_P1_SW3")
		)
		(pad "2" smd circle
			(at 0.40005 0)
			(size 0 0)
			(layers "F.Cu" "F.Mask" "F.Paste")
			(net "SW_PVDDCR_SOC_P1_SW3_RC")
		)
	)
	(footprint ""
		(layer "F.Cu")
		(at 385.723892 -383.88163 -90)
		(property "Reference" "C880"
			(at 0 0 270)
			(layer "F.SilkS")
			(hide yes)
			(effects
				(font
					(size 1.27 1.27)
				)
			)
		)
		(property "Value" ""
			(at 0 0 270)
			(layer "F.Fab")
			(effects
				(font
					(size 1.27 1.27)
				)
			)
		)
		(duplicate_pad_numbers_are_jumpers no)
		(fp_line
			(start -0.299974 0.150114)
			(end -0.299974 -0.150114)
			(stroke
				(width 0.1)
				(type default)
			)
			(layer "F.Fab")
		)
		(fp_line
			(start 0.299974 0.150114)
			(end -0.299974 0.150114)
			(stroke
				(width 0.1)
				(type default)
			)
			(layer "F.Fab")
		)
		(fp_line
			(start -0.299974 -0.150114)
			(end 0.299974 -0.150114)
			(stroke
				(width 0.1)
				(type default)
			)
			(layer "F.Fab")
		)
		(fp_line
			(start 0.299974 -0.150114)
			(end 0.299974 0.150114)
			(stroke
				(width 0.1)
				(type default)
			)
			(layer "F.Fab")
		)
		(pad "1" smd rect
			(at -0.2667 0 270)
			(size 0.3048 0.381)
			(layers "F.Cu" "F.Mask" "F.Paste")
			(net "P5E_CPU0_P3_TX_C_DN<10>")
		)
		(pad "2" smd rect
			(at 0.2667 0 270)
			(size 0.3048 0.381)
			(layers "F.Cu" "F.Mask" "F.Paste")
			(net "P5E_CPU0_P3_TX_DN<10>")
		)
	)
	(footprint ""
		(layer "F.Cu")
		(at 139.544552 -382.00584)
		(property "Reference" "R949"
			(at 0 0 0)
			(layer "F.SilkS")
			(hide yes)
			(effects
				(font
					(size 1.27 1.27)
				)
			)
		)
		(property "Value" ""
			(at 0 0 0)
			(layer "F.Fab")
			(effects
				(font
					(size 1.27 1.27)
				)
			)
		)
		(duplicate_pad_numbers_are_jumpers no)
		(fp_line
			(start -0.32512 -0.175006)
			(end 0.32512 -0.175006)
			(stroke
				(width 0.1)
				(type default)
			)
			(layer "F.Fab")
		)
		(fp_line
			(start -0.32512 0.175006)
			(end -0.32512 -0.175006)
			(stroke
				(width 0.1)
				(type default)
			)
			(layer "F.Fab")
		)
		(fp_line
			(start 0.32512 -0.175006)
			(end 0.32512 0.175006)
			(stroke
				(width 0.1)
				(type default)
			)
			(layer "F.Fab")
		)
		(fp_line
			(start 0.32512 0.175006)
			(end -0.32512 0.175006)
			(stroke
				(width 0.1)
				(type default)
			)
			(layer "F.Fab")
		)
		(pad "1" smd rect
			(at -0.2667 0)
			(size 0.3048 0.381)
			(layers "F.Cu" "F.Mask" "F.Paste")
			(net "RT_CPU1_P3_ADDR1")
		)
		(pad "2" smd rect
			(at 0.2667 0 180)
			(size 0.3048 0.381)
			(layers "F.Cu" "F.Mask" "F.Paste")
			(net "GND")
		)
	)
	(footprint ""
		(layer "F.Cu")
		(at 96.853502 -373.03583 -90)
		(property "Reference" "C718"
			(at 0 0 270)
			(layer "F.SilkS")
			(hide yes)
			(effects
				(font
					(size 1.27 1.27)
				)
			)
		)
		(property "Value" ""
			(at 0 0 270)
			(layer "F.Fab")
			(effects
				(font
					(size 1.27 1.27)
				)
			)
		)
		(duplicate_pad_numbers_are_jumpers no)
		(fp_line
			(start -0.299974 0.150114)
			(end -0.299974 -0.150114)
			(stroke
				(width 0.1)
				(type default)
			)
			(layer "F.Fab")
		)
		(fp_line
			(start 0.299974 0.150114)
			(end -0.299974 0.150114)
			(stroke
				(width 0.1)
				(type default)
			)
			(layer "F.Fab")
		)
		(fp_line
			(start -0.299974 -0.150114)
			(end 0.299974 -0.150114)
			(stroke
				(width 0.1)
				(type default)
			)
			(layer "F.Fab")
		)
		(fp_line
			(start 0.299974 -0.150114)
			(end 0.299974 0.150114)
			(stroke
				(width 0.1)
				(type default)
			)
			(layer "F.Fab")
		)
		(pad "1" smd rect
			(at -0.2667 0 270)
			(size 0.3048 0.381)
			(layers "F.Cu" "F.Mask" "F.Paste")
			(net "P5E_CPU1_P1_TX_C_DN<11>")
		)
		(pad "2" smd rect
			(at 0.2667 0 270)
			(size 0.3048 0.381)
			(layers "F.Cu" "F.Mask" "F.Paste")
			(net "P5E_CPU1_P1_TX_DN<11>")
		)
	)
	(footprint ""
		(layer "F.Cu")
		(at 204.954886 -111.665512 180)
		(property "Reference" "R1563"
			(at 0 0 180)
			(layer "F.SilkS")
			(hide yes)
			(effects
				(font
					(size 1.27 1.27)
				)
			)
		)
		(property "Value" ""
			(at 0 0 180)
			(layer "F.Fab")
			(effects
				(font
					(size 1.27 1.27)
				)
			)
		)
		(duplicate_pad_numbers_are_jumpers no)
		(fp_line
			(start 0.7874 0.4064)
			(end -0.7874 0.4064)
			(stroke
				(width 0.1524)
				(type default)
			)
			(layer "F.SilkS")
		)
		(fp_line
			(start 0.7874 -0.4064)
			(end 0.7874 0.4064)
			(stroke
				(width 0.1524)
				(type default)
			)
			(layer "F.SilkS")
		)
		(fp_line
			(start -0.7874 0.4064)
			(end -0.7874 -0.4064)
			(stroke
				(width 0.1524)
				(type default)
			)
			(layer "F.SilkS")
		)
		(fp_line
			(start -0.7874 -0.4064)
			(end 0.7874 -0.4064)
			(stroke
				(width 0.1524)
				(type default)
			)
			(layer "F.SilkS")
		)
		(fp_line
			(start 0.67945 0.3048)
			(end 0.120396 0.3048)
			(stroke
				(width 0.1)
				(type default)
			)
			(layer "F.Fab")
		)
		(fp_line
			(start 0.67945 -0.3048)
			(end 0.67945 0.3048)
			(stroke
				(width 0.1)
				(type default)
			)
			(layer "F.Fab")
		)
		(fp_line
			(start 0.12065 -0.2794)
			(end 0.12065 -0.3048)
			(stroke
				(width 0.1)
				(type default)
			)
			(layer "F.Fab")
		)
		(fp_line
			(start 0.12065 -0.3048)
			(end 0.67945 -0.3048)
			(stroke
				(width 0.1)
				(type default)
			)
			(layer "F.Fab")
		)
		(fp_line
			(start 0.120396 0.3048)
			(end 0.120396 0.2794)
			(stroke
				(width 0.1)
				(type default)
			)
			(layer "F.Fab")
		)
		(fp_line
			(start 0.120396 0.2794)
			(end -0.12065 0.2794)
			(stroke
				(width 0.1)
				(type default)
			)
			(layer "F.Fab")
		)
		(fp_line
			(start -0.12065 0.3048)
			(end -0.67945 0.3048)
			(stroke
				(width 0.1)
				(type default)
			)
			(layer "F.Fab")
		)
		(fp_line
			(start -0.12065 0.2794)
			(end -0.12065 0.3048)
			(stroke
				(width 0.1)
				(type default)
			)
			(layer "F.Fab")
		)
		(fp_line
			(start -0.12065 -0.2794)
			(end 0.12065 -0.2794)
			(stroke
				(width 0.1)
				(type default)
			)
			(layer "F.Fab")
		)
		(fp_line
			(start -0.12065 -0.305054)
			(end -0.12065 -0.2794)
			(stroke
				(width 0.1)
				(type default)
			)
			(layer "F.Fab")
		)
		(fp_line
			(start -0.67945 0.3048)
			(end -0.67945 -0.305054)
			(stroke
				(width 0.1)
				(type default)
			)
			(layer "F.Fab")
		)
		(fp_line
			(start -0.67945 -0.305054)
			(end -0.12065 -0.305054)
			(stroke
				(width 0.1)
				(type default)
			)
			(layer "F.Fab")
		)
		(pad "1" smd circle
			(at -0.40005 0 180)
			(size 0 0)
			(layers "F.Cu" "F.Mask" "F.Paste")
			(net "UART_LS_EN")
		)
		(pad "2" smd circle
			(at 0.40005 0 180)
			(size 0 0)
			(layers "F.Cu" "F.Mask" "F.Paste")
			(net "FM_UART_LS_EN")
		)
	)
	(footprint ""
		(layer "F.Cu")
		(at 365.618522 -172.559726)
		(property "Reference" "PR320"
			(at 0 0 0)
			(layer "F.SilkS")
			(hide yes)
			(effects
				(font
					(size 1.27 1.27)
				)
			)
		)
		(property "Value" ""
			(at 0 0 0)
			(layer "F.Fab")
			(effects
				(font
					(size 1.27 1.27)
				)
			)
		)
		(duplicate_pad_numbers_are_jumpers no)
		(fp_line
			(start -0.7874 -0.4064)
			(end 0.7874 -0.4064)
			(stroke
				(width 0.1524)
				(type default)
			)
			(layer "F.SilkS")
		)
		(fp_line
			(start -0.7874 0.4064)
			(end -0.7874 -0.4064)
			(stroke
				(width 0.1524)
				(type default)
			)
			(layer "F.SilkS")
		)
		(fp_line
			(start 0.7874 -0.4064)
			(end 0.7874 0.4064)
			(stroke
				(width 0.1524)
				(type default)
			)
			(layer "F.SilkS")
		)
		(fp_line
			(start 0.7874 0.4064)
			(end -0.7874 0.4064)
			(stroke
				(width 0.1524)
				(type default)
			)
			(layer "F.SilkS")
		)
		(fp_line
			(start -0.67945 -0.305054)
			(end -0.12065 -0.305054)
			(stroke
				(width 0.1)
				(type default)
			)
			(layer "F.Fab")
		)
		(fp_line
			(start -0.67945 0.3048)
			(end -0.67945 -0.305054)
			(stroke
				(width 0.1)
				(type default)
			)
			(layer "F.Fab")
		)
		(fp_line
			(start -0.12065 -0.305054)
			(end -0.12065 -0.2794)
			(stroke
				(width 0.1)
				(type default)
			)
			(layer "F.Fab")
		)
		(fp_line
			(start -0.12065 -0.2794)
			(end 0.12065 -0.2794)
			(stroke
				(width 0.1)
				(type default)
			)
			(layer "F.Fab")
		)
		(fp_line
			(start -0.12065 0.2794)
			(end -0.12065 0.3048)
			(stroke
				(width 0.1)
				(type default)
			)
			(layer "F.Fab")
		)
		(fp_line
			(start -0.12065 0.3048)
			(end -0.67945 0.3048)
			(stroke
				(width 0.1)
				(type default)
			)
			(layer "F.Fab")
		)
		(fp_line
			(start 0.120396 0.2794)
			(end -0.12065 0.2794)
			(stroke
				(width 0.1)
				(type default)
			)
			(layer "F.Fab")
		)
		(fp_line
			(start 0.120396 0.3048)
			(end 0.120396 0.2794)
			(stroke
				(width 0.1)
				(type default)
			)
			(layer "F.Fab")
		)
		(fp_line
			(start 0.12065 -0.3048)
			(end 0.67945 -0.3048)
			(stroke
				(width 0.1)
				(type default)
			)
			(layer "F.Fab")
		)
		(fp_line
			(start 0.12065 -0.2794)
			(end 0.12065 -0.3048)
			(stroke
				(width 0.1)
				(type default)
			)
			(layer "F.Fab")
		)
		(fp_line
			(start 0.67945 -0.3048)
			(end 0.67945 0.3048)
			(stroke
				(width 0.1)
				(type default)
			)
			(layer "F.Fab")
		)
		(fp_line
			(start 0.67945 0.3048)
			(end 0.120396 0.3048)
			(stroke
				(width 0.1)
				(type default)
			)
			(layer "F.Fab")
		)
		(pad "1" smd circle
			(at -0.40005 0)
			(size 0 0)
			(layers "F.Cu" "F.Mask" "F.Paste")
			(net "GND")
		)
		(pad "2" smd circle
			(at 0.40005 0)
			(size 0 0)
			(layers "F.Cu" "F.Mask" "F.Paste")
			(net "PVDDCR_CPU0_P0_LSET1")
		)
	)
	(footprint ""
		(layer "F.Cu")
		(at 404.158958 -321.002152 90)
		(property "Reference" "R448"
			(at 0 0 90)
			(layer "F.SilkS")
			(hide yes)
			(effects
				(font
					(size 1.27 1.27)
				)
			)
		)
		(property "Value" ""
			(at 0 0 90)
			(layer "F.Fab")
			(effects
				(font
					(size 1.27 1.27)
				)
			)
		)
		(duplicate_pad_numbers_are_jumpers no)
		(fp_line
			(start 0.7874 -0.4064)
			(end 0.7874 0.4064)
			(stroke
				(width 0.1524)
				(type default)
			)
			(layer "F.SilkS")
		)
		(fp_line
			(start -0.7874 -0.4064)
			(end 0.7874 -0.4064)
			(stroke
				(width 0.1524)
				(type default)
			)
			(layer "F.SilkS")
		)
		(fp_line
			(start 0.7874 0.4064)
			(end -0.7874 0.4064)
			(stroke
				(width 0.1524)
				(type default)
			)
			(layer "F.SilkS")
		)
		(fp_line
			(start -0.7874 0.4064)
			(end -0.7874 -0.4064)
			(stroke
				(width 0.1524)
				(type default)
			)
			(layer "F.SilkS")
		)
		(fp_line
			(start -0.12065 -0.305054)
			(end -0.12065 -0.2794)
			(stroke
				(width 0.1)
				(type default)
			)
			(layer "F.Fab")
		)
		(fp_line
			(start -0.67945 -0.305054)
			(end -0.12065 -0.305054)
			(stroke
				(width 0.1)
				(type default)
			)
			(layer "F.Fab")
		)
		(fp_line
			(start 0.67945 -0.3048)
			(end 0.67945 0.3048)
			(stroke
				(width 0.1)
				(type default)
			)
			(layer "F.Fab")
		)
		(fp_line
			(start 0.12065 -0.3048)
			(end 0.67945 -0.3048)
			(stroke
				(width 0.1)
				(type default)
			)
			(layer "F.Fab")
		)
		(fp_line
			(start 0.12065 -0.2794)
			(end 0.12065 -0.3048)
			(stroke
				(width 0.1)
				(type default)
			)
			(layer "F.Fab")
		)
		(fp_line
			(start -0.12065 -0.2794)
			(end 0.12065 -0.2794)
			(stroke
				(width 0.1)
				(type default)
			)
			(layer "F.Fab")
		)
		(fp_line
			(start 0.120396 0.2794)
			(end -0.12065 0.2794)
			(stroke
				(width 0.1)
				(type default)
			)
			(layer "F.Fab")
		)
		(fp_line
			(start -0.12065 0.2794)
			(end -0.12065 0.3048)
			(stroke
				(width 0.1)
				(type default)
			)
			(layer "F.Fab")
		)
		(fp_line
			(start 0.67945 0.3048)
			(end 0.120396 0.3048)
			(stroke
				(width 0.1)
				(type default)
			)
			(layer "F.Fab")
		)
		(fp_line
			(start 0.120396 0.3048)
			(end 0.120396 0.2794)
			(stroke
				(width 0.1)
				(type default)
			)
			(layer "F.Fab")
		)
		(fp_line
			(start -0.12065 0.3048)
			(end -0.67945 0.3048)
			(stroke
				(width 0.1)
				(type default)
			)
			(layer "F.Fab")
		)
		(fp_line
			(start -0.67945 0.3048)
			(end -0.67945 -0.305054)
			(stroke
				(width 0.1)
				(type default)
			)
			(layer "F.Fab")
		)
		(pad "1" smd circle
			(at -0.40005 0 90)
			(size 0 0)
			(layers "F.Cu" "F.Mask" "F.Paste")
			(net "CPU0_SLP_S5_N")
		)
		(pad "2" smd circle
			(at 0.40005 0 90)
			(size 0 0)
			(layers "F.Cu" "F.Mask" "F.Paste")
			(net "PVDD18_S5_P0")
		)
	)
	(footprint ""
		(layer "F.Cu")
		(at 180.528468 -45.005498)
		(property "Reference" "C9105"
			(at 0 0 0)
			(layer "F.SilkS")
			(hide yes)
			(effects
				(font
					(size 1.27 1.27)
				)
			)
		)
		(property "Value" ""
			(at 0 0 0)
			(layer "F.Fab")
			(effects
				(font
					(size 1.27 1.27)
				)
			)
		)
		(duplicate_pad_numbers_are_jumpers no)
		(fp_line
			(start -0.299974 -0.150114)
			(end 0.299974 -0.150114)
			(stroke
				(width 0.1)
				(type default)
			)
			(layer "F.Fab")
		)
		(fp_line
			(start -0.299974 0.150114)
			(end -0.299974 -0.150114)
			(stroke
				(width 0.1)
				(type default)
			)
			(layer "F.Fab")
		)
		(fp_line
			(start 0.299974 -0.150114)
			(end 0.299974 0.150114)
			(stroke
				(width 0.1)
				(type default)
			)
			(layer "F.Fab")
		)
		(fp_line
			(start 0.299974 0.150114)
			(end -0.299974 0.150114)
			(stroke
				(width 0.1)
				(type default)
			)
			(layer "F.Fab")
		)
		(pad "1" smd rect
			(at -0.2667 0)
			(size 0.3048 0.381)
			(layers "F.Cu" "F.Mask" "F.Paste")
			(net "P3E_CPU1_P4_TX_C_DN<0>")
		)
		(pad "2" smd rect
			(at 0.2667 0)
			(size 0.3048 0.381)
			(layers "F.Cu" "F.Mask" "F.Paste")
			(net "P3E_CPU1_P4_TX_DN<0>")
		)
	)
	(footprint ""
		(layer "F.Cu")
		(at 422.148 -55.753 90)
		(property "Reference" "R8019"
			(at 0 0 90)
			(layer "F.SilkS")
			(hide yes)
			(effects
				(font
					(size 1.27 1.27)
				)
			)
		)
		(property "Value" ""
			(at 0 0 90)
			(layer "F.Fab")
			(effects
				(font
					(size 1.27 1.27)
				)
			)
		)
		(duplicate_pad_numbers_are_jumpers no)
		(fp_line
			(start 0.7874 -0.4064)
			(end 0.7874 0.4064)
			(stroke
				(width 0.1524)
				(type default)
			)
			(layer "F.SilkS")
		)
		(fp_line
			(start -0.7874 -0.4064)
			(end 0.7874 -0.4064)
			(stroke
				(width 0.1524)
				(type default)
			)
			(layer "F.SilkS")
		)
		(fp_line
			(start 0.7874 0.4064)
			(end -0.7874 0.4064)
			(stroke
				(width 0.1524)
				(type default)
			)
			(layer "F.SilkS")
		)
		(fp_line
			(start -0.7874 0.4064)
			(end -0.7874 -0.4064)
			(stroke
				(width 0.1524)
				(type default)
			)
			(layer "F.SilkS")
		)
		(fp_line
			(start -0.12065 -0.305054)
			(end -0.12065 -0.2794)
			(stroke
				(width 0.1)
				(type default)
			)
			(layer "F.Fab")
		)
		(fp_line
			(start -0.67945 -0.305054)
			(end -0.12065 -0.305054)
			(stroke
				(width 0.1)
				(type default)
			)
			(layer "F.Fab")
		)
		(fp_line
			(start 0.67945 -0.3048)
			(end 0.67945 0.3048)
			(stroke
				(width 0.1)
				(type default)
			)
			(layer "F.Fab")
		)
		(fp_line
			(start 0.12065 -0.3048)
			(end 0.67945 -0.3048)
			(stroke
				(width 0.1)
				(type default)
			)
			(layer "F.Fab")
		)
		(fp_line
			(start 0.12065 -0.2794)
			(end 0.12065 -0.3048)
			(stroke
				(width 0.1)
				(type default)
			)
			(layer "F.Fab")
		)
		(fp_line
			(start -0.12065 -0.2794)
			(end 0.12065 -0.2794)
			(stroke
				(width 0.1)
				(type default)
			)
			(layer "F.Fab")
		)
		(fp_line
			(start 0.120396 0.2794)
			(end -0.12065 0.2794)
			(stroke
				(width 0.1)
				(type default)
			)
			(layer "F.Fab")
		)
		(fp_line
			(start -0.12065 0.2794)
			(end -0.12065 0.3048)
			(stroke
				(width 0.1)
				(type default)
			)
			(layer "F.Fab")
		)
		(fp_line
			(start 0.67945 0.3048)
			(end 0.120396 0.3048)
			(stroke
				(width 0.1)
				(type default)
			)
			(layer "F.Fab")
		)
		(fp_line
			(start 0.120396 0.3048)
			(end 0.120396 0.2794)
			(stroke
				(width 0.1)
				(type default)
			)
			(layer "F.Fab")
		)
		(fp_line
			(start -0.12065 0.3048)
			(end -0.67945 0.3048)
			(stroke
				(width 0.1)
				(type default)
			)
			(layer "F.Fab")
		)
		(fp_line
			(start -0.67945 0.3048)
			(end -0.67945 -0.305054)
			(stroke
				(width 0.1)
				(type default)
			)
			(layer "F.Fab")
		)
		(pad "1" smd circle
			(at -0.40005 0 90)
			(size 0 0)
			(layers "F.Cu" "F.Mask" "F.Paste")
			(net "P3V3_AUX")
		)
		(pad "2" smd circle
			(at 0.40005 0 90)
			(size 0 0)
			(layers "F.Cu" "F.Mask" "F.Paste")
			(net "FM_JTAG_BMC_R_OE")
		)
	)
	(footprint ""
		(layer "F.Cu")
		(at 102.362 -77.216 180)
		(property "Reference" "R1167"
			(at 0 0 180)
			(layer "F.SilkS")
			(hide yes)
			(effects
				(font
					(size 1.27 1.27)
				)
			)
		)
		(property "Value" ""
			(at 0 0 180)
			(layer "F.Fab")
			(effects
				(font
					(size 1.27 1.27)
				)
			)
		)
		(duplicate_pad_numbers_are_jumpers no)
		(fp_line
			(start 0.7874 0.4064)
			(end -0.7874 0.4064)
			(stroke
				(width 0.1524)
				(type default)
			)
			(layer "F.SilkS")
		)
		(fp_line
			(start 0.7874 -0.4064)
			(end 0.7874 0.4064)
			(stroke
				(width 0.1524)
				(type default)
			)
			(layer "F.SilkS")
		)
		(fp_line
			(start -0.7874 0.4064)
			(end -0.7874 -0.4064)
			(stroke
				(width 0.1524)
				(type default)
			)
			(layer "F.SilkS")
		)
		(fp_line
			(start -0.7874 -0.4064)
			(end 0.7874 -0.4064)
			(stroke
				(width 0.1524)
				(type default)
			)
			(layer "F.SilkS")
		)
		(fp_line
			(start 0.67945 0.3048)
			(end 0.120396 0.3048)
			(stroke
				(width 0.1)
				(type default)
			)
			(layer "F.Fab")
		)
		(fp_line
			(start 0.67945 -0.3048)
			(end 0.67945 0.3048)
			(stroke
				(width 0.1)
				(type default)
			)
			(layer "F.Fab")
		)
		(fp_line
			(start 0.12065 -0.2794)
			(end 0.12065 -0.3048)
			(stroke
				(width 0.1)
				(type default)
			)
			(layer "F.Fab")
		)
		(fp_line
			(start 0.12065 -0.3048)
			(end 0.67945 -0.3048)
			(stroke
				(width 0.1)
				(type default)
			)
			(layer "F.Fab")
		)
		(fp_line
			(start 0.120396 0.3048)
			(end 0.120396 0.2794)
			(stroke
				(width 0.1)
				(type default)
			)
			(layer "F.Fab")
		)
		(fp_line
			(start 0.120396 0.2794)
			(end -0.12065 0.2794)
			(stroke
				(width 0.1)
				(type default)
			)
			(layer "F.Fab")
		)
		(fp_line
			(start -0.12065 0.3048)
			(end -0.67945 0.3048)
			(stroke
				(width 0.1)
				(type default)
			)
			(layer "F.Fab")
		)
		(fp_line
			(start -0.12065 0.2794)
			(end -0.12065 0.3048)
			(stroke
				(width 0.1)
				(type default)
			)
			(layer "F.Fab")
		)
		(fp_line
			(start -0.12065 -0.2794)
			(end 0.12065 -0.2794)
			(stroke
				(width 0.1)
				(type default)
			)
			(layer "F.Fab")
		)
		(fp_line
			(start -0.12065 -0.305054)
			(end -0.12065 -0.2794)
			(stroke
				(width 0.1)
				(type default)
			)
			(layer "F.Fab")
		)
		(fp_line
			(start -0.67945 0.3048)
			(end -0.67945 -0.305054)
			(stroke
				(width 0.1)
				(type default)
			)
			(layer "F.Fab")
		)
		(fp_line
			(start -0.67945 -0.305054)
			(end -0.12065 -0.305054)
			(stroke
				(width 0.1)
				(type default)
			)
			(layer "F.Fab")
		)
		(pad "1" smd circle
			(at -0.40005 0 180)
			(size 0 0)
			(layers "F.Cu" "F.Mask" "F.Paste")
			(net "P3V3_AUX")
		)
		(pad "2" smd circle
			(at 0.40005 0 180)
			(size 0 0)
			(layers "F.Cu" "F.Mask" "F.Paste")
			(net "P12V_OCP_V3_2_PLD_PWRGD")
		)
	)
	(footprint ""
		(layer "F.Cu")
		(at 267.45184 -347.8149)
		(property "Reference" "H50"
			(at -1.7526 -4.34213 0)
			(unlocked yes)
			(layer "F.SilkS")
			(effects
				(font
					(size 0.7874 0.5842)
					(thickness 0.1524)
				)
				(justify left)
			)
		)
		(property "Value" ""
			(at 0 0 0)
			(layer "F.Fab")
			(effects
				(font
					(size 1.27 1.27)
				)
			)
		)
		(duplicate_pad_numbers_are_jumpers no)
		(pad "1" thru_hole circle
			(at 0 0)
			(size 6.1976 6.1976)
			(drill 3.7338)
			(layers "*.Cu" "*.Mask")
			(remove_unused_layers no)
			(net "GND")
			(clearance -0.9779)
			(padstack
				(mode front_inner_back)
				(layer "Inner"
					(shape circle)
					(size 5.5372 5.5372)
					(clearance -0.6477)
				)
				(layer "B.Cu"
					(shape circle)
					(size 6.1976 6.1976)
					(clearance -0.9779)
				)
			)
		)
	)
	(footprint ""
		(layer "F.Cu")
		(at 271.739106 -349.381572 90)
		(property "Reference" "PC171"
			(at 0 0 90)
			(layer "F.SilkS")
			(hide yes)
			(effects
				(font
					(size 1.27 1.27)
				)
			)
		)
		(property "Value" ""
			(at 0 0 90)
			(layer "F.Fab")
			(effects
				(font
					(size 1.27 1.27)
				)
			)
		)
		(duplicate_pad_numbers_are_jumpers no)
		(fp_line
			(start 0.7874 -0.4064)
			(end 0.7874 0.4064)
			(stroke
				(width 0.1524)
				(type default)
			)
			(layer "F.SilkS")
		)
		(fp_line
			(start -0.7874 -0.4064)
			(end 0.7874 -0.4064)
			(stroke
				(width 0.1524)
				(type default)
			)
			(layer "F.SilkS")
		)
		(fp_line
			(start 0.7874 0.4064)
			(end 0.503428 0.4064)
			(stroke
				(width 0.1524)
				(type default)
			)
			(layer "F.SilkS")
		)
		(fp_line
			(start -0.258572 0.4064)
			(end -0.7874 0.4064)
			(stroke
				(width 0.1524)
				(type default)
			)
			(layer "F.SilkS")
		)
		(fp_line
			(start -0.7874 0.4064)
			(end -0.7874 -0.4064)
			(stroke
				(width 0.1524)
				(type default)
			)
			(layer "F.SilkS")
		)
		(fp_line
			(start -0.12065 -0.305054)
			(end -0.12065 -0.2794)
			(stroke
				(width 0.1)
				(type default)
			)
			(layer "F.Fab")
		)
		(fp_line
			(start -0.67945 -0.305054)
			(end -0.12065 -0.305054)
			(stroke
				(width 0.1)
				(type default)
			)
			(layer "F.Fab")
		)
		(fp_line
			(start 0.67945 -0.3048)
			(end 0.67945 0.3048)
			(stroke
				(width 0.1)
				(type default)
			)
			(layer "F.Fab")
		)
		(fp_line
			(start 0.12065 -0.3048)
			(end 0.67945 -0.3048)
			(stroke
				(width 0.1)
				(type default)
			)
			(layer "F.Fab")
		)
		(fp_line
			(start 0.12065 -0.2794)
			(end 0.12065 -0.3048)
			(stroke
				(width 0.1)
				(type default)
			)
			(layer "F.Fab")
		)
		(fp_line
			(start -0.12065 -0.2794)
			(end 0.12065 -0.2794)
			(stroke
				(width 0.1)
				(type default)
			)
			(layer "F.Fab")
		)
		(fp_line
			(start 0.120396 0.2794)
			(end -0.12065 0.2794)
			(stroke
				(width 0.1)
				(type default)
			)
			(layer "F.Fab")
		)
		(fp_line
			(start -0.12065 0.2794)
			(end -0.12065 0.3048)
			(stroke
				(width 0.1)
				(type default)
			)
			(layer "F.Fab")
		)
		(fp_line
			(start 0.67945 0.3048)
			(end 0.120396 0.3048)
			(stroke
				(width 0.1)
				(type default)
			)
			(layer "F.Fab")
		)
		(fp_line
			(start 0.120396 0.3048)
			(end 0.120396 0.2794)
			(stroke
				(width 0.1)
				(type default)
			)
			(layer "F.Fab")
		)
		(fp_line
			(start -0.12065 0.3048)
			(end -0.67945 0.3048)
			(stroke
				(width 0.1)
				(type default)
			)
			(layer "F.Fab")
		)
		(fp_line
			(start -0.67945 0.3048)
			(end -0.67945 -0.305054)
			(stroke
				(width 0.1)
				(type default)
			)
			(layer "F.Fab")
		)
		(pad "1" smd circle
			(at -0.40005 0 90)
			(size 0 0)
			(layers "F.Cu" "F.Mask" "F.Paste")
			(net "PVDDIO_P0_VCC4")
		)
		(pad "2" smd circle
			(at 0.40005 0 90)
			(size 0 0)
			(layers "F.Cu" "F.Mask" "F.Paste")
			(net "GND")
		)
	)
	(footprint ""
		(layer "F.Cu")
		(at 152.040844 -370.57203 -90)
		(property "Reference" "C760"
			(at 0 0 270)
			(layer "F.SilkS")
			(hide yes)
			(effects
				(font
					(size 1.27 1.27)
				)
			)
		)
		(property "Value" ""
			(at 0 0 270)
			(layer "F.Fab")
			(effects
				(font
					(size 1.27 1.27)
				)
			)
		)
		(duplicate_pad_numbers_are_jumpers no)
		(fp_line
			(start -0.299974 0.150114)
			(end -0.299974 -0.150114)
			(stroke
				(width 0.1)
				(type default)
			)
			(layer "F.Fab")
		)
		(fp_line
			(start 0.299974 0.150114)
			(end -0.299974 0.150114)
			(stroke
				(width 0.1)
				(type default)
			)
			(layer "F.Fab")
		)
		(fp_line
			(start -0.299974 -0.150114)
			(end 0.299974 -0.150114)
			(stroke
				(width 0.1)
				(type default)
			)
			(layer "F.Fab")
		)
		(fp_line
			(start 0.299974 -0.150114)
			(end 0.299974 0.150114)
			(stroke
				(width 0.1)
				(type default)
			)
			(layer "F.Fab")
		)
		(pad "1" smd rect
			(at -0.2667 0 270)
			(size 0.3048 0.381)
			(layers "F.Cu" "F.Mask" "F.Paste")
			(net "P5E_CPU1_P2_TX_C_DN<6>")
		)
		(pad "2" smd rect
			(at 0.2667 0 270)
			(size 0.3048 0.381)
			(layers "F.Cu" "F.Mask" "F.Paste")
			(net "P5E_CPU1_P2_TX_DN<6>")
		)
	)
	(footprint ""
		(layer "F.Cu")
		(at 69.359526 -148.22678 90)
		(property "Reference" "PR398"
			(at 0 0 90)
			(layer "F.SilkS")
			(hide yes)
			(effects
				(font
					(size 1.27 1.27)
				)
			)
		)
		(property "Value" ""
			(at 0 0 90)
			(layer "F.Fab")
			(effects
				(font
					(size 1.27 1.27)
				)
			)
		)
		(duplicate_pad_numbers_are_jumpers no)
		(fp_line
			(start 0.7874 -0.4064)
			(end 0.7874 0.4064)
			(stroke
				(width 0.1524)
				(type default)
			)
			(layer "F.SilkS")
		)
		(fp_line
			(start -0.7874 -0.4064)
			(end 0.7874 -0.4064)
			(stroke
				(width 0.1524)
				(type default)
			)
			(layer "F.SilkS")
		)
		(fp_line
			(start 0.7874 0.4064)
			(end -0.7874 0.4064)
			(stroke
				(width 0.1524)
				(type default)
			)
			(layer "F.SilkS")
		)
		(fp_line
			(start -0.7874 0.4064)
			(end -0.7874 -0.4064)
			(stroke
				(width 0.1524)
				(type default)
			)
			(layer "F.SilkS")
		)
		(fp_line
			(start -0.12065 -0.305054)
			(end -0.12065 -0.2794)
			(stroke
				(width 0.1)
				(type default)
			)
			(layer "F.Fab")
		)
		(fp_line
			(start -0.67945 -0.305054)
			(end -0.12065 -0.305054)
			(stroke
				(width 0.1)
				(type default)
			)
			(layer "F.Fab")
		)
		(fp_line
			(start 0.67945 -0.3048)
			(end 0.67945 0.3048)
			(stroke
				(width 0.1)
				(type default)
			)
			(layer "F.Fab")
		)
		(fp_line
			(start 0.12065 -0.3048)
			(end 0.67945 -0.3048)
			(stroke
				(width 0.1)
				(type default)
			)
			(layer "F.Fab")
		)
		(fp_line
			(start 0.12065 -0.2794)
			(end 0.12065 -0.3048)
			(stroke
				(width 0.1)
				(type default)
			)
			(layer "F.Fab")
		)
		(fp_line
			(start -0.12065 -0.2794)
			(end 0.12065 -0.2794)
			(stroke
				(width 0.1)
				(type default)
			)
			(layer "F.Fab")
		)
		(fp_line
			(start 0.120396 0.2794)
			(end -0.12065 0.2794)
			(stroke
				(width 0.1)
				(type default)
			)
			(layer "F.Fab")
		)
		(fp_line
			(start -0.12065 0.2794)
			(end -0.12065 0.3048)
			(stroke
				(width 0.1)
				(type default)
			)
			(layer "F.Fab")
		)
		(fp_line
			(start 0.67945 0.3048)
			(end 0.120396 0.3048)
			(stroke
				(width 0.1)
				(type default)
			)
			(layer "F.Fab")
		)
		(fp_line
			(start 0.120396 0.3048)
			(end 0.120396 0.2794)
			(stroke
				(width 0.1)
				(type default)
			)
			(layer "F.Fab")
		)
		(fp_line
			(start -0.12065 0.3048)
			(end -0.67945 0.3048)
			(stroke
				(width 0.1)
				(type default)
			)
			(layer "F.Fab")
		)
		(fp_line
			(start -0.67945 0.3048)
			(end -0.67945 -0.305054)
			(stroke
				(width 0.1)
				(type default)
			)
			(layer "F.Fab")
		)
		(pad "1" smd circle
			(at -0.40005 0 90)
			(size 0 0)
			(layers "F.Cu" "F.Mask" "F.Paste")
			(net "GND")
		)
		(pad "2" smd circle
			(at 0.40005 0 90)
			(size 0 0)
			(layers "F.Cu" "F.Mask" "F.Paste")
			(net "PVDD18_S5_P1_MODE")
		)
	)
	(footprint ""
		(layer "F.Cu")
		(at 268.355318 -103.26624)
		(property "Reference" "C1506"
			(at 0 0 0)
			(layer "F.SilkS")
			(hide yes)
			(effects
				(font
					(size 1.27 1.27)
				)
			)
		)
		(property "Value" ""
			(at 0 0 0)
			(layer "F.Fab")
			(effects
				(font
					(size 1.27 1.27)
				)
			)
		)
		(duplicate_pad_numbers_are_jumpers no)
		(fp_line
			(start -0.7874 -0.4064)
			(end 0.7874 -0.4064)
			(stroke
				(width 0.1524)
				(type default)
			)
			(layer "F.SilkS")
		)
		(fp_line
			(start -0.7874 0.4064)
			(end -0.7874 -0.4064)
			(stroke
				(width 0.1524)
				(type default)
			)
			(layer "F.SilkS")
		)
		(fp_line
			(start 0.7874 -0.4064)
			(end 0.7874 0.4064)
			(stroke
				(width 0.1524)
				(type default)
			)
			(layer "F.SilkS")
		)
		(fp_line
			(start 0.7874 0.4064)
			(end -0.7874 0.4064)
			(stroke
				(width 0.1524)
				(type default)
			)
			(layer "F.SilkS")
		)
		(fp_line
			(start -0.67945 -0.305054)
			(end -0.12065 -0.305054)
			(stroke
				(width 0.1)
				(type default)
			)
			(layer "F.Fab")
		)
		(fp_line
			(start -0.67945 0.3048)
			(end -0.67945 -0.305054)
			(stroke
				(width 0.1)
				(type default)
			)
			(layer "F.Fab")
		)
		(fp_line
			(start -0.12065 -0.305054)
			(end -0.12065 -0.2794)
			(stroke
				(width 0.1)
				(type default)
			)
			(layer "F.Fab")
		)
		(fp_line
			(start -0.12065 -0.2794)
			(end 0.12065 -0.2794)
			(stroke
				(width 0.1)
				(type default)
			)
			(layer "F.Fab")
		)
		(fp_line
			(start -0.12065 0.2794)
			(end -0.12065 0.3048)
			(stroke
				(width 0.1)
				(type default)
			)
			(layer "F.Fab")
		)
		(fp_line
			(start -0.12065 0.3048)
			(end -0.67945 0.3048)
			(stroke
				(width 0.1)
				(type default)
			)
			(layer "F.Fab")
		)
		(fp_line
			(start 0.120396 0.2794)
			(end -0.12065 0.2794)
			(stroke
				(width 0.1)
				(type default)
			)
			(layer "F.Fab")
		)
		(fp_line
			(start 0.120396 0.3048)
			(end 0.120396 0.2794)
			(stroke
				(width 0.1)
				(type default)
			)
			(layer "F.Fab")
		)
		(fp_line
			(start 0.12065 -0.3048)
			(end 0.67945 -0.3048)
			(stroke
				(width 0.1)
				(type default)
			)
			(layer "F.Fab")
		)
		(fp_line
			(start 0.12065 -0.2794)
			(end 0.12065 -0.3048)
			(stroke
				(width 0.1)
				(type default)
			)
			(layer "F.Fab")
		)
		(fp_line
			(start 0.67945 -0.3048)
			(end 0.67945 0.3048)
			(stroke
				(width 0.1)
				(type default)
			)
			(layer "F.Fab")
		)
		(fp_line
			(start 0.67945 0.3048)
			(end 0.120396 0.3048)
			(stroke
				(width 0.1)
				(type default)
			)
			(layer "F.Fab")
		)
		(pad "1" smd circle
			(at -0.40005 0)
			(size 0 0)
			(layers "F.Cu" "F.Mask" "F.Paste")
			(net "P3V3_AUX")
		)
		(pad "2" smd circle
			(at 0.40005 0)
			(size 0 0)
			(layers "F.Cu" "F.Mask" "F.Paste")
			(net "GND")
		)
	)
	(footprint ""
		(layer "F.Cu")
		(at 94.899988 -22.29993)
		(property "Reference" "H93"
			(at -5.235702 -5.709666 0)
			(unlocked yes)
			(layer "F.SilkS")
			(effects
				(font
					(size 0.7874 0.5842)
					(thickness 0.1524)
				)
				(justify left)
			)
		)
		(property "Value" ""
			(at 0 0 0)
			(layer "F.Fab")
			(effects
				(font
					(size 1.27 1.27)
				)
			)
		)
		(duplicate_pad_numbers_are_jumpers no)
		(pad "1" thru_hole circle
			(at 0 0)
			(size 10.0076 10.0076)
			(drill 5.6134)
			(layers "*.Cu" "*.Mask")
			(remove_unused_layers no)
			(net "GND")
			(clearance -1.9431)
		)
	)
	(footprint ""
		(layer "F.Cu")
		(at 365.789718 -429.075342)
		(property "Reference" "R1428"
			(at 0 0 0)
			(layer "F.SilkS")
			(hide yes)
			(effects
				(font
					(size 1.27 1.27)
				)
			)
		)
		(property "Value" ""
			(at 0 0 0)
			(layer "F.Fab")
			(effects
				(font
					(size 1.27 1.27)
				)
			)
		)
		(duplicate_pad_numbers_are_jumpers no)
		(fp_line
			(start -0.32512 -0.175006)
			(end 0.32512 -0.175006)
			(stroke
				(width 0.1)
				(type default)
			)
			(layer "F.Fab")
		)
		(fp_line
			(start -0.32512 0.175006)
			(end -0.32512 -0.175006)
			(stroke
				(width 0.1)
				(type default)
			)
			(layer "F.Fab")
		)
		(fp_line
			(start 0.32512 -0.175006)
			(end 0.32512 0.175006)
			(stroke
				(width 0.1)
				(type default)
			)
			(layer "F.Fab")
		)
		(fp_line
			(start 0.32512 0.175006)
			(end -0.32512 0.175006)
			(stroke
				(width 0.1)
				(type default)
			)
			(layer "F.Fab")
		)
		(pad "1" smd rect
			(at -0.2667 0)
			(size 0.3048 0.381)
			(layers "F.Cu" "F.Mask" "F.Paste")
			(net "P1V8_CPU0_RT_1D")
		)
		(pad "2" smd rect
			(at 0.2667 0 180)
			(size 0.3048 0.381)
			(layers "F.Cu" "F.Mask" "F.Paste")
			(net "SMB_RT_CPU0_P3_ROM_MUX_1D_SCL")
		)
	)
	(footprint ""
		(layer "F.Cu")
		(at 171.196 -117.312948)
		(property "Reference" "R210"
			(at 0 0 0)
			(layer "F.SilkS")
			(hide yes)
			(effects
				(font
					(size 1.27 1.27)
				)
			)
		)
		(property "Value" ""
			(at 0 0 0)
			(layer "F.Fab")
			(effects
				(font
					(size 1.27 1.27)
				)
			)
		)
		(duplicate_pad_numbers_are_jumpers no)
		(fp_line
			(start -0.7874 -0.4064)
			(end 0.7874 -0.4064)
			(stroke
				(width 0.1524)
				(type default)
			)
			(layer "F.SilkS")
		)
		(fp_line
			(start -0.7874 0.4064)
			(end -0.7874 -0.4064)
			(stroke
				(width 0.1524)
				(type default)
			)
			(layer "F.SilkS")
		)
		(fp_line
			(start 0.7874 -0.4064)
			(end 0.7874 0.4064)
			(stroke
				(width 0.1524)
				(type default)
			)
			(layer "F.SilkS")
		)
		(fp_line
			(start 0.7874 0.4064)
			(end -0.7874 0.4064)
			(stroke
				(width 0.1524)
				(type default)
			)
			(layer "F.SilkS")
		)
		(fp_line
			(start -0.67945 -0.305054)
			(end -0.12065 -0.305054)
			(stroke
				(width 0.1)
				(type default)
			)
			(layer "F.Fab")
		)
		(fp_line
			(start -0.67945 0.3048)
			(end -0.67945 -0.305054)
			(stroke
				(width 0.1)
				(type default)
			)
			(layer "F.Fab")
		)
		(fp_line
			(start -0.12065 -0.305054)
			(end -0.12065 -0.2794)
			(stroke
				(width 0.1)
				(type default)
			)
			(layer "F.Fab")
		)
		(fp_line
			(start -0.12065 -0.2794)
			(end 0.12065 -0.2794)
			(stroke
				(width 0.1)
				(type default)
			)
			(layer "F.Fab")
		)
		(fp_line
			(start -0.12065 0.2794)
			(end -0.12065 0.3048)
			(stroke
				(width 0.1)
				(type default)
			)
			(layer "F.Fab")
		)
		(fp_line
			(start -0.12065 0.3048)
			(end -0.67945 0.3048)
			(stroke
				(width 0.1)
				(type default)
			)
			(layer "F.Fab")
		)
		(fp_line
			(start 0.120396 0.2794)
			(end -0.12065 0.2794)
			(stroke
				(width 0.1)
				(type default)
			)
			(layer "F.Fab")
		)
		(fp_line
			(start 0.120396 0.3048)
			(end 0.120396 0.2794)
			(stroke
				(width 0.1)
				(type default)
			)
			(layer "F.Fab")
		)
		(fp_line
			(start 0.12065 -0.3048)
			(end 0.67945 -0.3048)
			(stroke
				(width 0.1)
				(type default)
			)
			(layer "F.Fab")
		)
		(fp_line
			(start 0.12065 -0.2794)
			(end 0.12065 -0.3048)
			(stroke
				(width 0.1)
				(type default)
			)
			(layer "F.Fab")
		)
		(fp_line
			(start 0.67945 -0.3048)
			(end 0.67945 0.3048)
			(stroke
				(width 0.1)
				(type default)
			)
			(layer "F.Fab")
		)
		(fp_line
			(start 0.67945 0.3048)
			(end 0.120396 0.3048)
			(stroke
				(width 0.1)
				(type default)
			)
			(layer "F.Fab")
		)
		(pad "1" smd circle
			(at -0.40005 0)
			(size 0 0)
			(layers "F.Cu" "F.Mask" "F.Paste")
			(net "SMB_2_PLD_3V3AUX_SCL_R1")
		)
		(pad "2" smd circle
			(at 0.40005 0)
			(size 0 0)
			(layers "F.Cu" "F.Mask" "F.Paste")
			(net "SMB_2_PLD_3V3AUX_SCL_R2")
		)
	)
	(footprint ""
		(layer "F.Cu")
		(at 122.3772 -73.271126 180)
		(property "Reference" "PC6016"
			(at 0 0 180)
			(layer "F.SilkS")
			(hide yes)
			(effects
				(font
					(size 1.27 1.27)
				)
			)
		)
		(property "Value" ""
			(at 0 0 180)
			(layer "F.Fab")
			(effects
				(font
					(size 1.27 1.27)
				)
			)
		)
		(duplicate_pad_numbers_are_jumpers no)
		(fp_line
			(start 0.7874 0.4064)
			(end -0.7874 0.4064)
			(stroke
				(width 0.1524)
				(type default)
			)
			(layer "F.SilkS")
		)
		(fp_line
			(start 0.7874 -0.4064)
			(end 0.7874 0.4064)
			(stroke
				(width 0.1524)
				(type default)
			)
			(layer "F.SilkS")
		)
		(fp_line
			(start -0.7874 0.4064)
			(end -0.7874 -0.4064)
			(stroke
				(width 0.1524)
				(type default)
			)
			(layer "F.SilkS")
		)
		(fp_line
			(start -0.7874 -0.4064)
			(end 0.7874 -0.4064)
			(stroke
				(width 0.1524)
				(type default)
			)
			(layer "F.SilkS")
		)
		(fp_line
			(start 0.67945 0.3048)
			(end 0.120396 0.3048)
			(stroke
				(width 0.1)
				(type default)
			)
			(layer "F.Fab")
		)
		(fp_line
			(start 0.67945 -0.3048)
			(end 0.67945 0.3048)
			(stroke
				(width 0.1)
				(type default)
			)
			(layer "F.Fab")
		)
		(fp_line
			(start 0.12065 -0.2794)
			(end 0.12065 -0.3048)
			(stroke
				(width 0.1)
				(type default)
			)
			(layer "F.Fab")
		)
		(fp_line
			(start 0.12065 -0.3048)
			(end 0.67945 -0.3048)
			(stroke
				(width 0.1)
				(type default)
			)
			(layer "F.Fab")
		)
		(fp_line
			(start 0.120396 0.3048)
			(end 0.120396 0.2794)
			(stroke
				(width 0.1)
				(type default)
			)
			(layer "F.Fab")
		)
		(fp_line
			(start 0.120396 0.2794)
			(end -0.12065 0.2794)
			(stroke
				(width 0.1)
				(type default)
			)
			(layer "F.Fab")
		)
		(fp_line
			(start -0.12065 0.3048)
			(end -0.67945 0.3048)
			(stroke
				(width 0.1)
				(type default)
			)
			(layer "F.Fab")
		)
		(fp_line
			(start -0.12065 0.2794)
			(end -0.12065 0.3048)
			(stroke
				(width 0.1)
				(type default)
			)
			(layer "F.Fab")
		)
		(fp_line
			(start -0.12065 -0.2794)
			(end 0.12065 -0.2794)
			(stroke
				(width 0.1)
				(type default)
			)
			(layer "F.Fab")
		)
		(fp_line
			(start -0.12065 -0.305054)
			(end -0.12065 -0.2794)
			(stroke
				(width 0.1)
				(type default)
			)
			(layer "F.Fab")
		)
		(fp_line
			(start -0.67945 0.3048)
			(end -0.67945 -0.305054)
			(stroke
				(width 0.1)
				(type default)
			)
			(layer "F.Fab")
		)
		(fp_line
			(start -0.67945 -0.305054)
			(end -0.12065 -0.305054)
			(stroke
				(width 0.1)
				(type default)
			)
			(layer "F.Fab")
		)
		(pad "1" smd circle
			(at -0.40005 0 180)
			(size 0 0)
			(layers "F.Cu" "F.Mask" "F.Paste")
			(net "P1V2_AUX_REF")
		)
		(pad "2" smd circle
			(at 0.40005 0 180)
			(size 0 0)
			(layers "F.Cu" "F.Mask" "F.Paste")
			(net "GND")
		)
	)
	(footprint ""
		(layer "F.Cu")
		(at 18.064734 -381.6858 -90)
		(property "Reference" "PL6511"
			(at 3.3528 3.814064 90)
			(unlocked yes)
			(layer "F.SilkS")
			(effects
				(font
					(size 0.7874 0.5842)
					(thickness 0.1524)
				)
				(justify left)
			)
		)
		(property "Value" ""
			(at 0 0 270)
			(layer "F.Fab")
			(effects
				(font
					(size 1.27 1.27)
				)
			)
		)
		(duplicate_pad_numbers_are_jumpers no)
		(fp_line
			(start -3.24993 3.24993)
			(end -3.24993 2.2352)
			(stroke
				(width 0.1524)
				(type default)
			)
			(layer "F.SilkS")
		)
		(fp_line
			(start 3.24993 3.24993)
			(end -3.24993 3.24993)
			(stroke
				(width 0.1524)
				(type default)
			)
			(layer "F.SilkS")
		)
		(fp_line
			(start 3.24993 2.2352)
			(end 3.24993 3.24993)
			(stroke
				(width 0.1524)
				(type default)
			)
			(layer "F.SilkS")
		)
		(fp_line
			(start -3.24993 -2.2352)
			(end -3.24993 -3.24993)
			(stroke
				(width 0.1524)
				(type default)
			)
			(layer "F.SilkS")
		)
		(fp_line
			(start -3.24993 -3.24993)
			(end 3.24993 -3.24993)
			(stroke
				(width 0.1524)
				(type default)
			)
			(layer "F.SilkS")
		)
		(fp_line
			(start 3.24993 -3.24993)
			(end 3.24993 -2.2352)
			(stroke
				(width 0.1524)
				(type default)
			)
			(layer "F.SilkS")
		)
		(fp_line
			(start -3.24993 3.24993)
			(end -3.24993 -3.24993)
			(stroke
				(width 0.1)
				(type default)
			)
			(layer "F.Fab")
		)
		(fp_line
			(start 3.24993 3.24993)
			(end -3.24993 3.24993)
			(stroke
				(width 0.1)
				(type default)
			)
			(layer "F.Fab")
		)
		(fp_line
			(start -3.24993 -3.24993)
			(end 3.24993 -3.24993)
			(stroke
				(width 0.1)
				(type default)
			)
			(layer "F.Fab")
		)
		(fp_line
			(start 3.24993 -3.24993)
			(end 3.24993 3.24993)
			(stroke
				(width 0.1)
				(type default)
			)
			(layer "F.Fab")
		)
		(pad "1" smd rect
			(at -2.29997 0 270)
			(size 2.0066 4.2164)
			(layers "F.Cu" "F.Mask" "F.Paste")
			(net "SW_P0V9_RETIMER_CPU1_SW1")
		)
		(pad "2" smd rect
			(at 2.29997 0 270)
			(size 2.0066 4.2164)
			(layers "F.Cu" "F.Mask" "F.Paste")
			(net "P0V9_CPU1_RT_2D")
		)
	)
	(footprint ""
		(layer "F.Cu")
		(at 204.7621 -401.988782 180)
		(property "Reference" "PR1101"
			(at 0 0 180)
			(layer "F.SilkS")
			(hide yes)
			(effects
				(font
					(size 1.27 1.27)
				)
			)
		)
		(property "Value" ""
			(at 0 0 180)
			(layer "F.Fab")
			(effects
				(font
					(size 1.27 1.27)
				)
			)
		)
		(duplicate_pad_numbers_are_jumpers no)
		(fp_line
			(start 0.7874 0.4064)
			(end -0.7874 0.4064)
			(stroke
				(width 0.1524)
				(type default)
			)
			(layer "F.SilkS")
		)
		(fp_line
			(start 0.7874 -0.4064)
			(end 0.7874 0.4064)
			(stroke
				(width 0.1524)
				(type default)
			)
			(layer "F.SilkS")
		)
		(fp_line
			(start -0.7874 0.4064)
			(end -0.7874 -0.4064)
			(stroke
				(width 0.1524)
				(type default)
			)
			(layer "F.SilkS")
		)
		(fp_line
			(start -0.7874 -0.4064)
			(end 0.7874 -0.4064)
			(stroke
				(width 0.1524)
				(type default)
			)
			(layer "F.SilkS")
		)
		(fp_line
			(start 0.67945 0.3048)
			(end 0.120396 0.3048)
			(stroke
				(width 0.1)
				(type default)
			)
			(layer "F.Fab")
		)
		(fp_line
			(start 0.67945 -0.3048)
			(end 0.67945 0.3048)
			(stroke
				(width 0.1)
				(type default)
			)
			(layer "F.Fab")
		)
		(fp_line
			(start 0.12065 -0.2794)
			(end 0.12065 -0.3048)
			(stroke
				(width 0.1)
				(type default)
			)
			(layer "F.Fab")
		)
		(fp_line
			(start 0.12065 -0.3048)
			(end 0.67945 -0.3048)
			(stroke
				(width 0.1)
				(type default)
			)
			(layer "F.Fab")
		)
		(fp_line
			(start 0.120396 0.3048)
			(end 0.120396 0.2794)
			(stroke
				(width 0.1)
				(type default)
			)
			(layer "F.Fab")
		)
		(fp_line
			(start 0.120396 0.2794)
			(end -0.12065 0.2794)
			(stroke
				(width 0.1)
				(type default)
			)
			(layer "F.Fab")
		)
		(fp_line
			(start -0.12065 0.3048)
			(end -0.67945 0.3048)
			(stroke
				(width 0.1)
				(type default)
			)
			(layer "F.Fab")
		)
		(fp_line
			(start -0.12065 0.2794)
			(end -0.12065 0.3048)
			(stroke
				(width 0.1)
				(type default)
			)
			(layer "F.Fab")
		)
		(fp_line
			(start -0.12065 -0.2794)
			(end 0.12065 -0.2794)
			(stroke
				(width 0.1)
				(type default)
			)
			(layer "F.Fab")
		)
		(fp_line
			(start -0.12065 -0.305054)
			(end -0.12065 -0.2794)
			(stroke
				(width 0.1)
				(type default)
			)
			(layer "F.Fab")
		)
		(fp_line
			(start -0.67945 0.3048)
			(end -0.67945 -0.305054)
			(stroke
				(width 0.1)
				(type default)
			)
			(layer "F.Fab")
		)
		(fp_line
			(start -0.67945 -0.305054)
			(end -0.12065 -0.305054)
			(stroke
				(width 0.1)
				(type default)
			)
			(layer "F.Fab")
		)
		(pad "1" smd circle
			(at -0.40005 0 180)
			(size 0 0)
			(layers "F.Cu" "F.Mask" "F.Paste")
			(net "HSC_IMON")
		)
		(pad "2" smd circle
			(at 0.40005 0 180)
			(size 0 0)
			(layers "F.Cu" "F.Mask" "F.Paste")
			(net "AGND_HSC")
		)
	)
	(footprint ""
		(layer "F.Cu")
		(at 391.83945 -140.024612 90)
		(property "Reference" "U29"
			(at 0.762 2.00787 90)
			(unlocked yes)
			(layer "F.SilkS")
			(effects
				(font
					(size 0.7874 0.5842)
					(thickness 0.1524)
				)
			)
		)
		(property "Value" ""
			(at 0 0 90)
			(layer "F.Fab")
			(effects
				(font
					(size 1.27 1.27)
				)
			)
		)
		(duplicate_pad_numbers_are_jumpers no)
		(fp_line
			(start 1.7272 -1.1176)
			(end 0.254 -1.1176)
			(stroke
				(width 0.1524)
				(type default)
			)
			(layer "F.SilkS")
		)
		(fp_line
			(start 1.7272 -1.1176)
			(end 1.7272 1.1176)
			(stroke
				(width 0.1524)
				(type default)
			)
			(layer "F.SilkS")
		)
		(fp_line
			(start 0.254 -1.1176)
			(end 0 -0.7366)
			(stroke
				(width 0.1524)
				(type default)
			)
			(layer "F.SilkS")
		)
		(fp_line
			(start -0.254 -1.1176)
			(end -1.7272 -1.1176)
			(stroke
				(width 0.1524)
				(type default)
			)
			(layer "F.SilkS")
		)
		(fp_line
			(start 0 -0.7366)
			(end -0.254 -1.1176)
			(stroke
				(width 0.1524)
				(type default)
			)
			(layer "F.SilkS")
		)
		(fp_line
			(start 1.7272 1.1176)
			(end -1.7272 1.1176)
			(stroke
				(width 0.1524)
				(type default)
			)
			(layer "F.SilkS")
		)
		(fp_line
			(start -1.7272 1.1176)
			(end -1.7272 -1.1176)
			(stroke
				(width 0.1524)
				(type default)
			)
			(layer "F.SilkS")
		)
		(fp_poly
			(pts
				(xy -0.735076 -2.056638) (xy -1.116076 -1.294638) (xy -1.497076 -2.056638)
			)
			(stroke
				(width 0)
				(type default)
			)
			(fill yes)
			(layer "F.SilkS")
		)
		(fp_line
			(start 1.5748 -1.1176)
			(end -1.5748 -1.1176)
			(stroke
				(width 0.1)
				(type default)
			)
			(layer "F.Fab")
		)
		(fp_line
			(start -1.5748 -1.1176)
			(end -1.5748 1.1176)
			(stroke
				(width 0.1)
				(type default)
			)
			(layer "F.Fab")
		)
		(fp_line
			(start 1.5748 1.1176)
			(end 1.5748 -1.1176)
			(stroke
				(width 0.1)
				(type default)
			)
			(layer "F.Fab")
		)
		(fp_line
			(start -1.5748 1.1176)
			(end 1.5748 1.1176)
			(stroke
				(width 0.1)
				(type default)
			)
			(layer "F.Fab")
		)
		(fp_poly
			(pts
				(xy -1.9558 -0.649986) (xy -2.7178 -0.268986) (xy -2.7178 -1.030986)
			)
			(stroke
				(width 0)
				(type default)
			)
			(fill yes)
			(layer "F.Fab")
		)
		(pad "1" smd rect
			(at -0.999998 -0.649986)
			(size 0.3556 1.1176)
			(layers "F.Cu" "F.Mask" "F.Paste")
			(net "PWRGD_CPU0_PWROK")
		)
		(pad "2" smd rect
			(at -0.999998 0)
			(size 0.3556 1.1176)
			(layers "F.Cu" "F.Mask" "F.Paste")
			(net "GND")
		)
		(pad "3" smd rect
			(at -0.999998 0.649986)
			(size 0.3556 1.1176)
			(layers "F.Cu" "F.Mask" "F.Paste")
			(net "PWRGD_CPU0_PWROK")
		)
		(pad "4" smd rect
			(at 0.999998 0.649986)
			(size 0.3556 1.1176)
			(layers "F.Cu" "F.Mask" "F.Paste")
			(net "PVDDCR_CPU1_P0_RESET_N")
		)
		(pad "5" smd rect
			(at 0.999998 0)
			(size 0.3556 1.1176)
			(layers "F.Cu" "F.Mask" "F.Paste")
			(net "P1V8_AUX")
		)
		(pad "6" smd rect
			(at 0.999998 -0.649986)
			(size 0.3556 1.1176)
			(layers "F.Cu" "F.Mask" "F.Paste")
			(net "PVDDCR_CPU0_P0_RESET_N")
		)
	)
	(footprint ""
		(layer "F.Cu")
		(at 396.279878 -321.148202 90)
		(property "Reference" "R417"
			(at 0 0 90)
			(layer "F.SilkS")
			(hide yes)
			(effects
				(font
					(size 1.27 1.27)
				)
			)
		)
		(property "Value" ""
			(at 0 0 90)
			(layer "F.Fab")
			(effects
				(font
					(size 1.27 1.27)
				)
			)
		)
		(duplicate_pad_numbers_are_jumpers no)
		(fp_line
			(start 0.7874 -0.4064)
			(end 0.7874 0.4064)
			(stroke
				(width 0.1524)
				(type default)
			)
			(layer "F.SilkS")
		)
		(fp_line
			(start -0.7874 -0.4064)
			(end 0.7874 -0.4064)
			(stroke
				(width 0.1524)
				(type default)
			)
			(layer "F.SilkS")
		)
		(fp_line
			(start 0.7874 0.4064)
			(end -0.7874 0.4064)
			(stroke
				(width 0.1524)
				(type default)
			)
			(layer "F.SilkS")
		)
		(fp_line
			(start -0.7874 0.4064)
			(end -0.7874 -0.4064)
			(stroke
				(width 0.1524)
				(type default)
			)
			(layer "F.SilkS")
		)
		(fp_line
			(start -0.12065 -0.305054)
			(end -0.12065 -0.2794)
			(stroke
				(width 0.1)
				(type default)
			)
			(layer "F.Fab")
		)
		(fp_line
			(start -0.67945 -0.305054)
			(end -0.12065 -0.305054)
			(stroke
				(width 0.1)
				(type default)
			)
			(layer "F.Fab")
		)
		(fp_line
			(start 0.67945 -0.3048)
			(end 0.67945 0.3048)
			(stroke
				(width 0.1)
				(type default)
			)
			(layer "F.Fab")
		)
		(fp_line
			(start 0.12065 -0.3048)
			(end 0.67945 -0.3048)
			(stroke
				(width 0.1)
				(type default)
			)
			(layer "F.Fab")
		)
		(fp_line
			(start 0.12065 -0.2794)
			(end 0.12065 -0.3048)
			(stroke
				(width 0.1)
				(type default)
			)
			(layer "F.Fab")
		)
		(fp_line
			(start -0.12065 -0.2794)
			(end 0.12065 -0.2794)
			(stroke
				(width 0.1)
				(type default)
			)
			(layer "F.Fab")
		)
		(fp_line
			(start 0.120396 0.2794)
			(end -0.12065 0.2794)
			(stroke
				(width 0.1)
				(type default)
			)
			(layer "F.Fab")
		)
		(fp_line
			(start -0.12065 0.2794)
			(end -0.12065 0.3048)
			(stroke
				(width 0.1)
				(type default)
			)
			(layer "F.Fab")
		)
		(fp_line
			(start 0.67945 0.3048)
			(end 0.120396 0.3048)
			(stroke
				(width 0.1)
				(type default)
			)
			(layer "F.Fab")
		)
		(fp_line
			(start 0.120396 0.3048)
			(end 0.120396 0.2794)
			(stroke
				(width 0.1)
				(type default)
			)
			(layer "F.Fab")
		)
		(fp_line
			(start -0.12065 0.3048)
			(end -0.67945 0.3048)
			(stroke
				(width 0.1)
				(type default)
			)
			(layer "F.Fab")
		)
		(fp_line
			(start -0.67945 0.3048)
			(end -0.67945 -0.305054)
			(stroke
				(width 0.1)
				(type default)
			)
			(layer "F.Fab")
		)
		(pad "1" smd circle
			(at -0.40005 0 90)
			(size 0 0)
			(layers "F.Cu" "F.Mask" "F.Paste")
			(net "CPU0_THERMTRIP_N")
		)
		(pad "2" smd circle
			(at 0.40005 0 90)
			(size 0 0)
			(layers "F.Cu" "F.Mask" "F.Paste")
			(net "PVDD18_S5_P0")
		)
	)
	(footprint ""
		(layer "F.Cu")
		(at 147.199096 -65.321434 180)
		(property "Reference" "R1619"
			(at 0 0 180)
			(layer "F.SilkS")
			(hide yes)
			(effects
				(font
					(size 1.27 1.27)
				)
			)
		)
		(property "Value" ""
			(at 0 0 180)
			(layer "F.Fab")
			(effects
				(font
					(size 1.27 1.27)
				)
			)
		)
		(duplicate_pad_numbers_are_jumpers no)
		(fp_line
			(start 0.7874 0.4064)
			(end -0.7874 0.4064)
			(stroke
				(width 0.1524)
				(type default)
			)
			(layer "F.SilkS")
		)
		(fp_line
			(start 0.7874 -0.4064)
			(end 0.7874 0.4064)
			(stroke
				(width 0.1524)
				(type default)
			)
			(layer "F.SilkS")
		)
		(fp_line
			(start -0.7874 0.4064)
			(end -0.7874 -0.4064)
			(stroke
				(width 0.1524)
				(type default)
			)
			(layer "F.SilkS")
		)
		(fp_line
			(start -0.7874 -0.4064)
			(end 0.7874 -0.4064)
			(stroke
				(width 0.1524)
				(type default)
			)
			(layer "F.SilkS")
		)
		(fp_line
			(start 0.67945 0.3048)
			(end 0.120396 0.3048)
			(stroke
				(width 0.1)
				(type default)
			)
			(layer "F.Fab")
		)
		(fp_line
			(start 0.67945 -0.3048)
			(end 0.67945 0.3048)
			(stroke
				(width 0.1)
				(type default)
			)
			(layer "F.Fab")
		)
		(fp_line
			(start 0.12065 -0.2794)
			(end 0.12065 -0.3048)
			(stroke
				(width 0.1)
				(type default)
			)
			(layer "F.Fab")
		)
		(fp_line
			(start 0.12065 -0.3048)
			(end 0.67945 -0.3048)
			(stroke
				(width 0.1)
				(type default)
			)
			(layer "F.Fab")
		)
		(fp_line
			(start 0.120396 0.3048)
			(end 0.120396 0.2794)
			(stroke
				(width 0.1)
				(type default)
			)
			(layer "F.Fab")
		)
		(fp_line
			(start 0.120396 0.2794)
			(end -0.12065 0.2794)
			(stroke
				(width 0.1)
				(type default)
			)
			(layer "F.Fab")
		)
		(fp_line
			(start -0.12065 0.3048)
			(end -0.67945 0.3048)
			(stroke
				(width 0.1)
				(type default)
			)
			(layer "F.Fab")
		)
		(fp_line
			(start -0.12065 0.2794)
			(end -0.12065 0.3048)
			(stroke
				(width 0.1)
				(type default)
			)
			(layer "F.Fab")
		)
		(fp_line
			(start -0.12065 -0.2794)
			(end 0.12065 -0.2794)
			(stroke
				(width 0.1)
				(type default)
			)
			(layer "F.Fab")
		)
		(fp_line
			(start -0.12065 -0.305054)
			(end -0.12065 -0.2794)
			(stroke
				(width 0.1)
				(type default)
			)
			(layer "F.Fab")
		)
		(fp_line
			(start -0.67945 0.3048)
			(end -0.67945 -0.305054)
			(stroke
				(width 0.1)
				(type default)
			)
			(layer "F.Fab")
		)
		(fp_line
			(start -0.67945 -0.305054)
			(end -0.12065 -0.305054)
			(stroke
				(width 0.1)
				(type default)
			)
			(layer "F.Fab")
		)
		(pad "1" smd circle
			(at -0.40005 0 180)
			(size 0 0)
			(layers "F.Cu" "F.Mask" "F.Paste")
			(net "JTAG_BMC_OE")
		)
		(pad "2" smd circle
			(at 0.40005 0 180)
			(size 0 0)
			(layers "F.Cu" "F.Mask" "F.Paste")
			(net "JTAG_BMC_R_D_OE")
		)
	)
	(footprint ""
		(layer "F.Cu")
		(at 92.387674 -165.962076 180)
		(property "Reference" "PC273"
			(at -0.974852 -2.775204 0)
			(unlocked yes)
			(layer "F.SilkS")
			(effects
				(font
					(size 0.7874 0.5842)
					(thickness 0.1524)
				)
				(justify left)
			)
		)
		(property "Value" ""
			(at 0 0 180)
			(layer "F.Fab")
			(effects
				(font
					(size 1.27 1.27)
				)
			)
		)
		(duplicate_pad_numbers_are_jumpers no)
		(fp_line
			(start -3.400044 1.249934)
			(end 3.400044 1.249934)
			(stroke
				(width 0.1524)
				(type default)
			)
			(layer "F.SilkS")
		)
		(fp_circle
			(center 0 1.249934)
			(end -3.400044 1.249934)
			(stroke
				(width 0.1524)
				(type default)
			)
			(fill no)
			(layer "F.SilkS")
		)
		(fp_poly
			(pts
				(arc
					(start 3.400044 1.249934)
					(mid 0 4.649978)
					(end -3.400044 1.249934)
				)
			)
			(stroke
				(width 0)
				(type default)
			)
			(fill yes)
			(layer "F.SilkS")
		)
		(fp_circle
			(center 0 1.249934)
			(end -3.400044 1.249934)
			(stroke
				(width 0.1)
				(type default)
			)
			(fill no)
			(layer "F.Fab")
		)
		(pad "1" thru_hole rect
			(at 0 0 180)
			(size 1.524 1.524)
			(drill 1.016)
			(layers "*.Cu" "*.Mask")
			(remove_unused_layers no)
			(net "SW_P12V_AUX_PVDDCR_CPU0_P1_FLT")
			(clearance 0)
			(padstack
				(mode front_inner_back)
				(layer "Inner"
					(shape circle)
					(size 1.524 1.524)
					(clearance 0)
				)
				(layer "B.Cu"
					(shape rect)
					(size 1.524 1.524)
					(clearance 0)
				)
			)
		)
		(pad "2" thru_hole circle
			(at 0 2.500122 180)
			(size 1.524 1.524)
			(drill 1.016)
			(layers "*.Cu" "*.Mask")
			(remove_unused_layers no)
			(net "GND")
			(clearance 0)
		)
	)
	(footprint ""
		(layer "F.Cu")
		(at 247.499632 -40.903144 90)
		(property "Reference" "PD112"
			(at -3.422142 -2.350008 90)
			(unlocked yes)
			(layer "F.SilkS")
			(effects
				(font
					(size 0.7874 0.5842)
					(thickness 0.1524)
				)
				(justify left)
			)
		)
		(property "Value" ""
			(at 0 0 90)
			(layer "F.Fab")
			(effects
				(font
					(size 1.27 1.27)
				)
			)
		)
		(duplicate_pad_numbers_are_jumpers no)
		(fp_line
			(start 4.107942 -1.459992)
			(end 4.107942 1.459992)
			(stroke
				(width 0.1524)
				(type default)
			)
			(layer "F.SilkS")
		)
		(fp_line
			(start -3.400044 -1.459992)
			(end 4.107942 -1.459992)
			(stroke
				(width 0.1524)
				(type default)
			)
			(layer "F.SilkS")
		)
		(fp_line
			(start 4.107942 1.459992)
			(end -3.400044 1.459992)
			(stroke
				(width 0.1524)
				(type default)
			)
			(layer "F.SilkS")
		)
		(fp_line
			(start -3.400044 1.459992)
			(end -3.400044 -1.459992)
			(stroke
				(width 0.1524)
				(type default)
			)
			(layer "F.SilkS")
		)
		(fp_line
			(start 2.29997 -1.459992)
			(end 2.29997 1.459992)
			(stroke
				(width 0.1)
				(type default)
			)
			(layer "F.Fab")
		)
		(fp_line
			(start -2.29997 -1.459992)
			(end 2.29997 -1.459992)
			(stroke
				(width 0.1)
				(type default)
			)
			(layer "F.Fab")
		)
		(fp_line
			(start 2.29997 1.459992)
			(end -2.29997 1.459992)
			(stroke
				(width 0.1)
				(type default)
			)
			(layer "F.Fab")
		)
		(fp_line
			(start -2.29997 1.459992)
			(end -2.29997 -1.459992)
			(stroke
				(width 0.1)
				(type default)
			)
			(layer "F.Fab")
		)
		(fp_text user "+"
			(at -4.7752 -0.12065 90)
			(unlocked yes)
			(layer "F.SilkS")
			(effects
				(font
					(size 1.905 1.4224)
					(thickness 0.1524)
				)
				(justify left)
			)
		)
		(fp_text user "-"
			(at 5.245862 0.80264 270)
			(unlocked yes)
			(layer "F.SilkS")
			(effects
				(font
					(size 1.905 1.4224)
					(thickness 0.1524)
				)
				(justify left)
			)
		)
		(fp_text user "+"
			(at -4.7752 -0.12065 90)
			(unlocked yes)
			(layer "F.Fab")
			(effects
				(font
					(size 1.905 1.4224)
					(thickness 0.1524)
				)
				(justify left)
			)
		)
		(fp_text user "-"
			(at 5.4102 0.29845 270)
			(unlocked yes)
			(layer "F.Fab")
			(effects
				(font
					(size 1.905 1.4224)
					(thickness 0.1524)
				)
				(justify left)
			)
		)
		(pad "A" smd rect
			(at -1.999996 0 180)
			(size 1.7018 2.5146)
			(layers "F.Cu" "F.Mask" "F.Paste")
			(net "GND")
		)
		(pad "C" smd rect
			(at 1.999996 0 180)
			(size 1.7018 2.5146)
			(layers "F.Cu" "F.Mask" "F.Paste")
			(net "P12V_E1S_0")
		)
	)
	(footprint ""
		(layer "F.Cu")
		(at 368.241326 -43.235118 -90)
		(property "Reference" "R1423"
			(at 0 0 270)
			(layer "F.SilkS")
			(hide yes)
			(effects
				(font
					(size 1.27 1.27)
				)
			)
		)
		(property "Value" ""
			(at 0 0 270)
			(layer "F.Fab")
			(effects
				(font
					(size 1.27 1.27)
				)
			)
		)
		(duplicate_pad_numbers_are_jumpers no)
		(fp_line
			(start -0.7874 0.4064)
			(end -0.7874 -0.4064)
			(stroke
				(width 0.1524)
				(type default)
			)
			(layer "F.SilkS")
		)
		(fp_line
			(start 0.7874 0.4064)
			(end -0.7874 0.4064)
			(stroke
				(width 0.1524)
				(type default)
			)
			(layer "F.SilkS")
		)
		(fp_line
			(start -0.7874 -0.4064)
			(end 0.7874 -0.4064)
			(stroke
				(width 0.1524)
				(type default)
			)
			(layer "F.SilkS")
		)
		(fp_line
			(start 0.7874 -0.4064)
			(end 0.7874 0.4064)
			(stroke
				(width 0.1524)
				(type default)
			)
			(layer "F.SilkS")
		)
		(fp_line
			(start -0.67945 0.3048)
			(end -0.67945 -0.305054)
			(stroke
				(width 0.1)
				(type default)
			)
			(layer "F.Fab")
		)
		(fp_line
			(start -0.12065 0.3048)
			(end -0.67945 0.3048)
			(stroke
				(width 0.1)
				(type default)
			)
			(layer "F.Fab")
		)
		(fp_line
			(start 0.120396 0.3048)
			(end 0.120396 0.2794)
			(stroke
				(width 0.1)
				(type default)
			)
			(layer "F.Fab")
		)
		(fp_line
			(start 0.67945 0.3048)
			(end 0.120396 0.3048)
			(stroke
				(width 0.1)
				(type default)
			)
			(layer "F.Fab")
		)
		(fp_line
			(start -0.12065 0.2794)
			(end -0.12065 0.3048)
			(stroke
				(width 0.1)
				(type default)
			)
			(layer "F.Fab")
		)
		(fp_line
			(start 0.120396 0.2794)
			(end -0.12065 0.2794)
			(stroke
				(width 0.1)
				(type default)
			)
			(layer "F.Fab")
		)
		(fp_line
			(start -0.12065 -0.2794)
			(end 0.12065 -0.2794)
			(stroke
				(width 0.1)
				(type default)
			)
			(layer "F.Fab")
		)
		(fp_line
			(start 0.12065 -0.2794)
			(end 0.12065 -0.3048)
			(stroke
				(width 0.1)
				(type default)
			)
			(layer "F.Fab")
		)
		(fp_line
			(start 0.12065 -0.3048)
			(end 0.67945 -0.3048)
			(stroke
				(width 0.1)
				(type default)
			)
			(layer "F.Fab")
		)
		(fp_line
			(start 0.67945 -0.3048)
			(end 0.67945 0.3048)
			(stroke
				(width 0.1)
				(type default)
			)
			(layer "F.Fab")
		)
		(fp_line
			(start -0.67945 -0.305054)
			(end -0.12065 -0.305054)
			(stroke
				(width 0.1)
				(type default)
			)
			(layer "F.Fab")
		)
		(fp_line
			(start -0.12065 -0.305054)
			(end -0.12065 -0.2794)
			(stroke
				(width 0.1)
				(type default)
			)
			(layer "F.Fab")
		)
		(pad "1" smd circle
			(at -0.40005 0 270)
			(size 0 0)
			(layers "F.Cu" "F.Mask" "F.Paste")
			(net "UART_CPU0_SCM_UART1_RX")
		)
		(pad "2" smd circle
			(at 0.40005 0 270)
			(size 0 0)
			(layers "F.Cu" "F.Mask" "F.Paste")
			(net "UART_CPU0_SCM_UART1_R_RX")
		)
	)
	(footprint ""
		(layer "F.Cu")
		(at 159.741108 -344.706956)
		(property "Reference" "PC639"
			(at 0 0 0)
			(layer "F.SilkS")
			(hide yes)
			(effects
				(font
					(size 1.27 1.27)
				)
			)
		)
		(property "Value" ""
			(at 0 0 0)
			(layer "F.Fab")
			(effects
				(font
					(size 1.27 1.27)
				)
			)
		)
		(duplicate_pad_numbers_are_jumpers no)
		(fp_line
			(start -0.7874 -0.4064)
			(end 0.7874 -0.4064)
			(stroke
				(width 0.1524)
				(type default)
			)
			(layer "F.SilkS")
		)
		(fp_line
			(start -0.7874 0.4064)
			(end -0.7874 -0.4064)
			(stroke
				(width 0.1524)
				(type default)
			)
			(layer "F.SilkS")
		)
		(fp_line
			(start 0.7874 -0.4064)
			(end 0.7874 0.4064)
			(stroke
				(width 0.1524)
				(type default)
			)
			(layer "F.SilkS")
		)
		(fp_line
			(start 0.7874 0.4064)
			(end -0.7874 0.4064)
			(stroke
				(width 0.1524)
				(type default)
			)
			(layer "F.SilkS")
		)
		(fp_line
			(start -0.67945 -0.305054)
			(end -0.12065 -0.305054)
			(stroke
				(width 0.1)
				(type default)
			)
			(layer "F.Fab")
		)
		(fp_line
			(start -0.67945 0.3048)
			(end -0.67945 -0.305054)
			(stroke
				(width 0.1)
				(type default)
			)
			(layer "F.Fab")
		)
		(fp_line
			(start -0.12065 -0.305054)
			(end -0.12065 -0.2794)
			(stroke
				(width 0.1)
				(type default)
			)
			(layer "F.Fab")
		)
		(fp_line
			(start -0.12065 -0.2794)
			(end 0.12065 -0.2794)
			(stroke
				(width 0.1)
				(type default)
			)
			(layer "F.Fab")
		)
		(fp_line
			(start -0.12065 0.2794)
			(end -0.12065 0.3048)
			(stroke
				(width 0.1)
				(type default)
			)
			(layer "F.Fab")
		)
		(fp_line
			(start -0.12065 0.3048)
			(end -0.67945 0.3048)
			(stroke
				(width 0.1)
				(type default)
			)
			(layer "F.Fab")
		)
		(fp_line
			(start 0.120396 0.2794)
			(end -0.12065 0.2794)
			(stroke
				(width 0.1)
				(type default)
			)
			(layer "F.Fab")
		)
		(fp_line
			(start 0.120396 0.3048)
			(end 0.120396 0.2794)
			(stroke
				(width 0.1)
				(type default)
			)
			(layer "F.Fab")
		)
		(fp_line
			(start 0.12065 -0.3048)
			(end 0.67945 -0.3048)
			(stroke
				(width 0.1)
				(type default)
			)
			(layer "F.Fab")
		)
		(fp_line
			(start 0.12065 -0.2794)
			(end 0.12065 -0.3048)
			(stroke
				(width 0.1)
				(type default)
			)
			(layer "F.Fab")
		)
		(fp_line
			(start 0.67945 -0.3048)
			(end 0.67945 0.3048)
			(stroke
				(width 0.1)
				(type default)
			)
			(layer "F.Fab")
		)
		(fp_line
			(start 0.67945 0.3048)
			(end 0.120396 0.3048)
			(stroke
				(width 0.1)
				(type default)
			)
			(layer "F.Fab")
		)
		(pad "1" smd circle
			(at -0.40005 0)
			(size 0 0)
			(layers "F.Cu" "F.Mask" "F.Paste")
			(net "VSENSE_PVDD11_S3_P1_R")
		)
		(pad "2" smd circle
			(at 0.40005 0)
			(size 0 0)
			(layers "F.Cu" "F.Mask" "F.Paste")
			(net "VSENSE_VSS_SENSE_C_P1")
		)
	)
	(footprint ""
		(layer "F.Cu")
		(at 444.136018 -76.107798)
		(property "Reference" "C1340"
			(at 0 0 0)
			(layer "F.SilkS")
			(hide yes)
			(effects
				(font
					(size 1.27 1.27)
				)
			)
		)
		(property "Value" ""
			(at 0 0 0)
			(layer "F.Fab")
			(effects
				(font
					(size 1.27 1.27)
				)
			)
		)
		(duplicate_pad_numbers_are_jumpers no)
		(fp_line
			(start -1.524 -0.762)
			(end 1.524 -0.762)
			(stroke
				(width 0.1524)
				(type default)
			)
			(layer "F.SilkS")
		)
		(fp_line
			(start -1.524 0.762)
			(end -1.524 -0.762)
			(stroke
				(width 0.1524)
				(type default)
			)
			(layer "F.SilkS")
		)
		(fp_line
			(start 1.524 -0.762)
			(end 1.524 0.762)
			(stroke
				(width 0.1524)
				(type default)
			)
			(layer "F.SilkS")
		)
		(fp_line
			(start 1.524 0.762)
			(end -1.524 0.762)
			(stroke
				(width 0.1524)
				(type default)
			)
			(layer "F.SilkS")
		)
		(fp_line
			(start -1.1049 -0.724916)
			(end -1.1049 0.724916)
			(stroke
				(width 0.1)
				(type default)
			)
			(layer "F.Fab")
		)
		(fp_line
			(start -1.1049 0.724916)
			(end 1.1049 0.724916)
			(stroke
				(width 0.1)
				(type default)
			)
			(layer "F.Fab")
		)
		(fp_line
			(start 1.1049 -0.724916)
			(end -1.1049 -0.724916)
			(stroke
				(width 0.1)
				(type default)
			)
			(layer "F.Fab")
		)
		(fp_line
			(start 1.1049 0.724916)
			(end 1.1049 -0.724916)
			(stroke
				(width 0.1)
				(type default)
			)
			(layer "F.Fab")
		)
		(pad "1" smd rect
			(at -0.889 0 180)
			(size 1.016 1.27)
			(layers "F.Cu" "F.Mask" "F.Paste")
			(net "P3V3")
		)
		(pad "2" smd rect
			(at 0.889 0 180)
			(size 1.016 1.27)
			(layers "F.Cu" "F.Mask" "F.Paste")
			(net "GND")
		)
	)
	(footprint ""
		(layer "F.Cu")
		(at 69.33057 -166.26332 -90)
		(property "Reference" "PC125"
			(at 0 0 270)
			(layer "F.SilkS")
			(hide yes)
			(effects
				(font
					(size 1.27 1.27)
				)
			)
		)
		(property "Value" ""
			(at 0 0 270)
			(layer "F.Fab")
			(effects
				(font
					(size 1.27 1.27)
				)
			)
		)
		(duplicate_pad_numbers_are_jumpers no)
		(fp_line
			(start -0.7874 0.4064)
			(end -0.7874 -0.4064)
			(stroke
				(width 0.1524)
				(type default)
			)
			(layer "F.SilkS")
		)
		(fp_line
			(start -0.36068 0.4064)
			(end -0.7874 0.4064)
			(stroke
				(width 0.1524)
				(type default)
			)
			(layer "F.SilkS")
		)
		(fp_line
			(start 0.7874 0.4064)
			(end 0.50292 0.4064)
			(stroke
				(width 0.1524)
				(type default)
			)
			(layer "F.SilkS")
		)
		(fp_line
			(start -0.7874 -0.4064)
			(end 0.7874 -0.4064)
			(stroke
				(width 0.1524)
				(type default)
			)
			(layer "F.SilkS")
		)
		(fp_line
			(start 0.7874 -0.4064)
			(end 0.7874 0.4064)
			(stroke
				(width 0.1524)
				(type default)
			)
			(layer "F.SilkS")
		)
		(fp_line
			(start -0.67945 0.3048)
			(end -0.67945 -0.305054)
			(stroke
				(width 0.1)
				(type default)
			)
			(layer "F.Fab")
		)
		(fp_line
			(start -0.12065 0.3048)
			(end -0.67945 0.3048)
			(stroke
				(width 0.1)
				(type default)
			)
			(layer "F.Fab")
		)
		(fp_line
			(start 0.120396 0.3048)
			(end 0.120396 0.2794)
			(stroke
				(width 0.1)
				(type default)
			)
			(layer "F.Fab")
		)
		(fp_line
			(start 0.67945 0.3048)
			(end 0.120396 0.3048)
			(stroke
				(width 0.1)
				(type default)
			)
			(layer "F.Fab")
		)
		(fp_line
			(start -0.12065 0.2794)
			(end -0.12065 0.3048)
			(stroke
				(width 0.1)
				(type default)
			)
			(layer "F.Fab")
		)
		(fp_line
			(start 0.120396 0.2794)
			(end -0.12065 0.2794)
			(stroke
				(width 0.1)
				(type default)
			)
			(layer "F.Fab")
		)
		(fp_line
			(start -0.12065 -0.2794)
			(end 0.12065 -0.2794)
			(stroke
				(width 0.1)
				(type default)
			)
			(layer "F.Fab")
		)
		(fp_line
			(start 0.12065 -0.2794)
			(end 0.12065 -0.3048)
			(stroke
				(width 0.1)
				(type default)
			)
			(layer "F.Fab")
		)
		(fp_line
			(start 0.12065 -0.3048)
			(end 0.67945 -0.3048)
			(stroke
				(width 0.1)
				(type default)
			)
			(layer "F.Fab")
		)
		(fp_line
			(start 0.67945 -0.3048)
			(end 0.67945 0.3048)
			(stroke
				(width 0.1)
				(type default)
			)
			(layer "F.Fab")
		)
		(fp_line
			(start -0.67945 -0.305054)
			(end -0.12065 -0.305054)
			(stroke
				(width 0.1)
				(type default)
			)
			(layer "F.Fab")
		)
		(fp_line
			(start -0.12065 -0.305054)
			(end -0.12065 -0.2794)
			(stroke
				(width 0.1)
				(type default)
			)
			(layer "F.Fab")
		)
		(pad "1" smd circle
			(at -0.40005 0 270)
			(size 0 0)
			(layers "F.Cu" "F.Mask" "F.Paste")
			(net "PVDDCR_CPU0_P1_VCC6")
		)
		(pad "2" smd circle
			(at 0.40005 0 270)
			(size 0 0)
			(layers "F.Cu" "F.Mask" "F.Paste")
			(net "GND")
		)
	)
	(footprint ""
		(layer "F.Cu")
		(at 195.88988 -383.160524 180)
		(property "Reference" "PJ38"
			(at 4.616196 4.675886 90)
			(unlocked yes)
			(layer "F.SilkS")
			(effects
				(font
					(size 0.7874 0.5842)
					(thickness 0.1524)
				)
				(justify left)
			)
		)
		(property "Value" ""
			(at 0 0 180)
			(layer "F.Fab")
			(effects
				(font
					(size 1.27 1.27)
				)
			)
		)
		(duplicate_pad_numbers_are_jumpers no)
		(fp_line
			(start 2.500122 7.649972)
			(end -2.500122 7.649972)
			(stroke
				(width 0.1524)
				(type default)
			)
			(layer "F.SilkS")
		)
		(fp_line
			(start 2.500122 7.570978)
			(end 2.500122 7.649972)
			(stroke
				(width 0.1524)
				(type default)
			)
			(layer "F.SilkS")
		)
		(fp_line
			(start 2.500122 4.944618)
			(end 2.500122 5.869178)
			(stroke
				(width 0.1524)
				(type default)
			)
			(layer "F.SilkS")
		)
		(fp_line
			(start 2.500122 -5.869178)
			(end 2.500122 -4.944618)
			(stroke
				(width 0.1524)
				(type default)
			)
			(layer "F.SilkS")
		)
		(fp_line
			(start 2.500122 -7.649972)
			(end 2.500122 -7.570978)
			(stroke
				(width 0.1524)
				(type default)
			)
			(layer "F.SilkS")
		)
		(fp_line
			(start -2.500122 7.649972)
			(end -2.500122 7.570978)
			(stroke
				(width 0.1524)
				(type default)
			)
			(layer "F.SilkS")
		)
		(fp_line
			(start -2.500122 5.869178)
			(end -2.500122 5.44449)
			(stroke
				(width 0.1524)
				(type default)
			)
			(layer "F.SilkS")
		)
		(fp_line
			(start -2.500122 -5.44449)
			(end -2.500122 -5.869178)
			(stroke
				(width 0.1524)
				(type default)
			)
			(layer "F.SilkS")
		)
		(fp_line
			(start -2.500122 -7.570978)
			(end -2.500122 -7.649972)
			(stroke
				(width 0.1524)
				(type default)
			)
			(layer "F.SilkS")
		)
		(fp_line
			(start -2.500122 -7.649972)
			(end 2.500122 -7.649972)
			(stroke
				(width 0.1524)
				(type default)
			)
			(layer "F.SilkS")
		)
		(fp_poly
			(pts
				(xy -3.078988 -4.99999) (xy -4.094988 -4.49199) (xy -4.094988 -5.50799)
			)
			(stroke
				(width 0)
				(type default)
			)
			(fill yes)
			(layer "F.SilkS")
		)
		(fp_line
			(start 2.500122 7.649972)
			(end -2.500122 7.649972)
			(stroke
				(width 0.1)
				(type default)
			)
			(layer "F.Fab")
		)
		(fp_line
			(start 2.500122 -7.649972)
			(end 2.500122 7.649972)
			(stroke
				(width 0.1)
				(type default)
			)
			(layer "F.Fab")
		)
		(fp_line
			(start -2.500122 7.649972)
			(end -2.500122 -7.649972)
			(stroke
				(width 0.1)
				(type default)
			)
			(layer "F.Fab")
		)
		(fp_line
			(start -2.500122 -7.649972)
			(end 2.500122 -7.649972)
			(stroke
				(width 0.1)
				(type default)
			)
			(layer "F.Fab")
		)
		(fp_poly
			(pts
				(xy -4.094988 -5.50799) (xy -4.094988 -4.49199) (xy -3.078988 -4.99999)
			)
			(stroke
				(width 0)
				(type default)
			)
			(fill yes)
			(layer "F.Fab")
		)
		(pad "" np_thru_hole circle
			(at 1.100074 -5.5245 90)
			(size 0.762 0.762)
			(drill 0.762)
			(layers "*.Cu" "*.Mask")
			(clearance 0.381)
			(thermal_gap 0.381)
		)
		(pad "" np_thru_hole circle
			(at 1.100074 5.5245 90)
			(size 0.762 0.762)
			(drill 0.762)
			(layers "*.Cu" "*.Mask")
			(clearance 0.381)
			(thermal_gap 0.381)
		)
		(pad "1" smd rect
			(at -2.109978 -4.99999 270)
			(size 0.6096 1.651)
			(layers "F.Cu" "F.Mask" "F.Paste")
			(net "P12V_PSU")
		)
		(pad "2" smd rect
			(at -2.109978 -3.999992 270)
			(size 0.6096 1.651)
			(layers "F.Cu" "F.Mask" "F.Paste")
			(net "P12V_HSC_SENSE1_P")
		)
		(pad "3" smd rect
			(at -2.109978 -2.999994 270)
			(size 0.6096 1.651)
			(layers "F.Cu" "F.Mask" "F.Paste")
			(net "P12V_HSC_SENSE1_N")
		)
		(pad "4" smd rect
			(at -2.109978 -1.999996 270)
			(size 0.6096 1.651)
			(layers "F.Cu" "F.Mask" "F.Paste")
			(net "P12V_HSC_SENSE2_P")
		)
		(pad "5" smd rect
			(at -2.109978 -0.999998 270)
			(size 0.6096 1.651)
			(layers "F.Cu" "F.Mask" "F.Paste")
			(net "P12V_HSC_SENSE2_N")
		)
		(pad "6" smd rect
			(at -2.109978 0 270)
			(size 0.6096 1.651)
			(layers "F.Cu" "F.Mask" "F.Paste")
			(net "P12V_HSC_ADC_N")
		)
		(pad "7" smd rect
			(at -2.109978 0.999998 270)
			(size 0.6096 1.651)
			(layers "F.Cu" "F.Mask" "F.Paste")
			(net "P12V_HSC_ADC_P")
		)
		(pad "8" smd rect
			(at -2.109978 1.999996 270)
			(size 0.6096 1.651)
			(layers "F.Cu" "F.Mask" "F.Paste")
			(net "P12V_HSC_GATE1")
		)
		(pad "9" smd rect
			(at -2.109978 2.999994 270)
			(size 0.6096 1.651)
			(layers "F.Cu" "F.Mask" "F.Paste")
			(net "P12V_HSC_GATE2")
		)
		(pad "10" smd rect
			(at -2.109978 3.999992 270)
			(size 0.6096 1.651)
			(layers "F.Cu" "F.Mask" "F.Paste")
			(net "P12V_AUX")
		)
		(pad "11" smd rect
			(at -2.109978 4.99999 270)
			(size 0.6096 1.651)
			(layers "F.Cu" "F.Mask" "F.Paste")
			(net "GND")
		)
		(pad "12" smd rect
			(at 2.109978 -4.500118 90)
			(size 0.6096 1.651)
			(layers "F.Cu" "F.Mask" "F.Paste")
			(net "P3V3_AUX")
		)
		(pad "13" smd rect
			(at 2.109978 -3.50012 90)
			(size 0.6096 1.651)
			(layers "F.Cu" "F.Mask" "F.Paste")
			(net "IRQ_HSC_FAULT_N")
		)
		(pad "14" smd rect
			(at 2.109978 -2.500122 90)
			(size 0.6096 1.651)
			(layers "F.Cu" "F.Mask" "F.Paste")
			(net "HSC_EN")
		)
		(pad "15" smd rect
			(at 2.109978 -1.500124 90)
			(size 0.6096 1.651)
			(layers "F.Cu" "F.Mask" "F.Paste")
			(net "MB0_P12V_STBY_PWRGD")
		)
		(pad "16" smd rect
			(at 2.109978 -0.499872 90)
			(size 0.6096 1.651)
			(layers "F.Cu" "F.Mask" "F.Paste")
			(net "HSC_CSOUT")
		)
		(pad "17" smd rect
			(at 2.109978 0.499872 90)
			(size 0.6096 1.651)
			(layers "F.Cu" "F.Mask" "F.Paste")
			(net "HSC_TYPE_ADC")
		)
		(pad "18" smd rect
			(at 2.109978 1.500124 90)
			(size 0.6096 1.651)
			(layers "F.Cu" "F.Mask" "F.Paste")
			(net "SMB_SML1_PMBUS_HSC_R1_SCL")
		)
		(pad "19" smd rect
			(at 2.109978 2.500122 90)
			(size 0.6096 1.651)
			(layers "F.Cu" "F.Mask" "F.Paste")
			(net "SMB_SML1_PMBUS_HSC_R1_SDA")
		)
		(pad "20" smd rect
			(at 2.109978 3.50012 90)
			(size 0.6096 1.651)
			(layers "F.Cu" "F.Mask" "F.Paste")
			(net "IRQ_SML1_PMBUS_ALERT_N")
		)
		(pad "21" smd rect
			(at 2.109978 4.500118 90)
			(size 0.6096 1.651)
			(layers "F.Cu" "F.Mask" "F.Paste")
			(net "GND")
		)
		(pad "G1" smd circle
			(at 0 -6.720078 90)
			(size 0 0)
			(layers "F.Cu" "F.Mask" "F.Paste")
			(net "GND")
		)
		(pad "G2" smd circle
			(at 0 6.720078 90)
			(size 0 0)
			(layers "F.Cu" "F.Mask" "F.Paste")
			(net "GND")
		)
		(zone
			(layers "F.Cu" "B.Cu" "In1.Cu" "In2.Cu" "In3.Cu" "In4.Cu" "In5.Cu" "In6.Cu"
				"In7.Cu" "In8.Cu" "In9.Cu" "In10.Cu" "In11.Cu" "In12.Cu" "In13.Cu" "In14.Cu"
				"In15.Cu" "In16.Cu"
			)
			(hatch none 0.5)
			(connect_pads
				(clearance 0)
			)
			(min_thickness 0.25)
			(keepout
				(tracks not_allowed)
				(vias allowed)
				(pads allowed)
				(copperpour not_allowed)
				(footprints allowed)
			)
			(placement
				(enabled no)
				(sheetname "")
			)
			(fill
				(thermal_gap 0.5)
				(thermal_bridge_width 0.5)
				(island_removal_mode 0)
			)
			(polygon
				(pts
					(arc
						(start 195.678806 -388.685024)
						(mid 193.900806 -388.685024)
						(end 195.678806 -388.685024)
					)
				)
			)
		)
		(zone
			(layers "F.Cu" "B.Cu" "In1.Cu" "In2.Cu" "In3.Cu" "In4.Cu" "In5.Cu" "In6.Cu"
				"In7.Cu" "In8.Cu" "In9.Cu" "In10.Cu" "In11.Cu" "In12.Cu" "In13.Cu" "In14.Cu"
				"In15.Cu" "In16.Cu"
			)
			(hatch none 0.5)
			(connect_pads
				(clearance 0)
			)
			(min_thickness 0.25)
			(keepout
				(tracks not_allowed)
				(vias allowed)
				(pads allowed)
				(copperpour not_allowed)
				(footprints allowed)
			)
			(placement
				(enabled no)
				(sheetname "")
			)
			(fill
				(thermal_gap 0.5)
				(thermal_bridge_width 0.5)
				(island_removal_mode 0)
			)
			(polygon
				(pts
					(arc
						(start 195.678806 -377.636024)
						(mid 193.900806 -377.636024)
						(end 195.678806 -377.636024)
					)
				)
			)
		)
	)
	(footprint ""
		(layer "F.Cu")
		(at 301.124112 -351.368106 90)
		(property "Reference" "PR101"
			(at 0 0 90)
			(layer "F.SilkS")
			(hide yes)
			(effects
				(font
					(size 1.27 1.27)
				)
			)
		)
		(property "Value" ""
			(at 0 0 90)
			(layer "F.Fab")
			(effects
				(font
					(size 1.27 1.27)
				)
			)
		)
		(duplicate_pad_numbers_are_jumpers no)
		(fp_line
			(start 0.7874 -0.4064)
			(end 0.7874 0.4064)
			(stroke
				(width 0.1524)
				(type default)
			)
			(layer "F.SilkS")
		)
		(fp_line
			(start -0.7874 -0.4064)
			(end 0.7874 -0.4064)
			(stroke
				(width 0.1524)
				(type default)
			)
			(layer "F.SilkS")
		)
		(fp_line
			(start 0.7874 0.4064)
			(end -0.7874 0.4064)
			(stroke
				(width 0.1524)
				(type default)
			)
			(layer "F.SilkS")
		)
		(fp_line
			(start -0.7874 0.4064)
			(end -0.7874 -0.4064)
			(stroke
				(width 0.1524)
				(type default)
			)
			(layer "F.SilkS")
		)
		(fp_line
			(start -0.12065 -0.305054)
			(end -0.12065 -0.2794)
			(stroke
				(width 0.1)
				(type default)
			)
			(layer "F.Fab")
		)
		(fp_line
			(start -0.67945 -0.305054)
			(end -0.12065 -0.305054)
			(stroke
				(width 0.1)
				(type default)
			)
			(layer "F.Fab")
		)
		(fp_line
			(start 0.67945 -0.3048)
			(end 0.67945 0.3048)
			(stroke
				(width 0.1)
				(type default)
			)
			(layer "F.Fab")
		)
		(fp_line
			(start 0.12065 -0.3048)
			(end 0.67945 -0.3048)
			(stroke
				(width 0.1)
				(type default)
			)
			(layer "F.Fab")
		)
		(fp_line
			(start 0.12065 -0.2794)
			(end 0.12065 -0.3048)
			(stroke
				(width 0.1)
				(type default)
			)
			(layer "F.Fab")
		)
		(fp_line
			(start -0.12065 -0.2794)
			(end 0.12065 -0.2794)
			(stroke
				(width 0.1)
				(type default)
			)
			(layer "F.Fab")
		)
		(fp_line
			(start 0.120396 0.2794)
			(end -0.12065 0.2794)
			(stroke
				(width 0.1)
				(type default)
			)
			(layer "F.Fab")
		)
		(fp_line
			(start -0.12065 0.2794)
			(end -0.12065 0.3048)
			(stroke
				(width 0.1)
				(type default)
			)
			(layer "F.Fab")
		)
		(fp_line
			(start 0.67945 0.3048)
			(end 0.120396 0.3048)
			(stroke
				(width 0.1)
				(type default)
			)
			(layer "F.Fab")
		)
		(fp_line
			(start 0.120396 0.3048)
			(end 0.120396 0.2794)
			(stroke
				(width 0.1)
				(type default)
			)
			(layer "F.Fab")
		)
		(fp_line
			(start -0.12065 0.3048)
			(end -0.67945 0.3048)
			(stroke
				(width 0.1)
				(type default)
			)
			(layer "F.Fab")
		)
		(fp_line
			(start -0.67945 0.3048)
			(end -0.67945 -0.305054)
			(stroke
				(width 0.1)
				(type default)
			)
			(layer "F.Fab")
		)
		(pad "1" smd circle
			(at -0.40005 0 90)
			(size 0 0)
			(layers "F.Cu" "F.Mask" "F.Paste")
			(net "SW_PVDDIO_P0_BOOT1")
		)
		(pad "2" smd circle
			(at 0.40005 0 90)
			(size 0 0)
			(layers "F.Cu" "F.Mask" "F.Paste")
			(net "SW_PVDDIO_P0_BOOT1_R")
		)
	)
	(footprint ""
		(layer "F.Cu")
		(at 110.643924 -386.684774 -90)
		(property "Reference" "R641"
			(at 0 0 270)
			(layer "F.SilkS")
			(hide yes)
			(effects
				(font
					(size 1.27 1.27)
				)
			)
		)
		(property "Value" ""
			(at 0 0 270)
			(layer "F.Fab")
			(effects
				(font
					(size 1.27 1.27)
				)
			)
		)
		(duplicate_pad_numbers_are_jumpers no)
		(fp_line
			(start -0.32512 0.175006)
			(end -0.32512 -0.175006)
			(stroke
				(width 0.1)
				(type default)
			)
			(layer "F.Fab")
		)
		(fp_line
			(start 0.32512 0.175006)
			(end -0.32512 0.175006)
			(stroke
				(width 0.1)
				(type default)
			)
			(layer "F.Fab")
		)
		(fp_line
			(start -0.32512 -0.175006)
			(end 0.32512 -0.175006)
			(stroke
				(width 0.1)
				(type default)
			)
			(layer "F.Fab")
		)
		(fp_line
			(start 0.32512 -0.175006)
			(end 0.32512 0.175006)
			(stroke
				(width 0.1)
				(type default)
			)
			(layer "F.Fab")
		)
		(pad "1" smd rect
			(at -0.2667 0 270)
			(size 0.3048 0.381)
			(layers "F.Cu" "F.Mask" "F.Paste")
			(net "CLK_100M_RETIMER_CPU1_P3_DN")
		)
		(pad "2" smd rect
			(at 0.2667 0 90)
			(size 0.3048 0.381)
			(layers "F.Cu" "F.Mask" "F.Paste")
			(net "GND")
		)
	)
	(footprint ""
		(layer "F.Cu")
		(at 97.795842 6.063234)
		(property "Reference" "J77"
			(at 5.390642 -0.182626 0)
			(unlocked yes)
			(layer "F.SilkS")
			(effects
				(font
					(size 0.7874 0.5842)
					(thickness 0.1524)
				)
				(justify left)
			)
		)
		(property "Value" ""
			(at 0 0 0)
			(layer "F.Fab")
			(effects
				(font
					(size 1.27 1.27)
				)
			)
		)
		(duplicate_pad_numbers_are_jumpers no)
		(fp_line
			(start -1.2192 -2.06756)
			(end 1.2192 -2.06756)
			(stroke
				(width 0.1524)
				(type default)
			)
			(layer "F.SilkS")
		)
		(fp_line
			(start -1.2192 2.06756)
			(end -1.2192 -2.06756)
			(stroke
				(width 0.1524)
				(type default)
			)
			(layer "F.SilkS")
		)
		(fp_line
			(start 1.2192 -2.06756)
			(end 1.2192 2.06756)
			(stroke
				(width 0.1524)
				(type default)
			)
			(layer "F.SilkS")
		)
		(fp_line
			(start 1.2192 2.06756)
			(end -1.2192 2.06756)
			(stroke
				(width 0.1524)
				(type default)
			)
			(layer "F.SilkS")
		)
		(pad "" np_thru_hole circle
			(at -2.8829 -1.27 270)
			(size 1.0414 1.0414)
			(drill 1.0414)
			(layers "*.Cu" "*.Mask")
			(clearance 0.381)
			(thermal_gap 0.381)
		)
		(pad "" np_thru_hole circle
			(at -2.8829 1.27 270)
			(size 1.0414 1.0414)
			(drill 1.0414)
			(layers "*.Cu" "*.Mask")
			(clearance 0.381)
			(thermal_gap 0.381)
		)
		(pad "" np_thru_hole circle
			(at 3.4671 -1.27 270)
			(size 1.0414 1.0414)
			(drill 1.0414)
			(layers "*.Cu" "*.Mask")
			(clearance 0.381)
			(thermal_gap 0.381)
		)
		(pad "" np_thru_hole circle
			(at 3.4671 1.27 270)
			(size 1.0414 1.0414)
			(drill 1.0414)
			(layers "*.Cu" "*.Mask")
			(clearance 0.381)
			(thermal_gap 0.381)
		)
		(pad "1" smd rect
			(at 0.8255 -0.249936 270)
			(size 0.3048 0.508)
			(layers "F.Cu" "F.Mask" "F.Paste")
			(net "DELTA_L_85_10INCH_IN1_DP")
		)
		(pad "2" smd rect
			(at 0.8255 0.249936 270)
			(size 0.3048 0.508)
			(layers "F.Cu" "F.Mask" "F.Paste")
			(net "DELTA_L_85_10INCH_IN1_DN")
		)
		(pad "3" smd circle
			(at 0 0)
			(size 0 0)
			(layers "F.Cu" "F.Mask" "F.Paste")
			(net "DELTA_L_GND_1")
		)
		(zone
			(layer "F.Cu")
			(hatch none 0.5)
			(connect_pads
				(clearance 0)
			)
			(min_thickness 0.25)
			(keepout
				(tracks not_allowed)
				(vias allowed)
				(pads allowed)
				(copperpour not_allowed)
				(footprints allowed)
			)
			(placement
				(enabled no)
				(sheetname "")
			)
			(fill
				(thermal_gap 0.5)
				(thermal_bridge_width 0.5)
				(island_removal_mode 0)
			)
			(polygon
				(pts
					(xy 98.913442 5.514594) (xy 98.913442 5.610098) (xy 98.316542 5.610098) (xy 98.316542 6.016498)
					(xy 98.913442 6.016498) (xy 98.913442 6.10997) (xy 98.316542 6.10997) (xy 98.316542 6.51637) (xy 98.913442 6.51637)
					(xy 98.913442 6.611874) (xy 98.214942 6.611874) (xy 98.214942 5.514594)
				)
			)
		)
		(zone
			(layers "F.Cu" "B.Cu" "In1.Cu" "In2.Cu" "In3.Cu" "In4.Cu" "In5.Cu" "In6.Cu"
				"In7.Cu" "In8.Cu" "In9.Cu" "In10.Cu" "In11.Cu" "In12.Cu" "In13.Cu" "In14.Cu"
				"In15.Cu" "In16.Cu"
			)
			(hatch none 0.5)
			(connect_pads
				(clearance 0)
			)
			(min_thickness 0.25)
			(keepout
				(tracks not_allowed)
				(vias allowed)
				(pads allowed)
				(copperpour not_allowed)
				(footprints allowed)
			)
			(placement
				(enabled no)
				(sheetname "")
			)
			(fill
				(thermal_gap 0.5)
				(thermal_bridge_width 0.5)
				(island_removal_mode 0)
			)
			(polygon
				(pts
					(arc
						(start 95.840042 4.793234)
						(mid 93.985842 4.793234)
						(end 95.840042 4.793234)
					)
				)
			)
		)
		(zone
			(layers "F.Cu" "B.Cu" "In1.Cu" "In2.Cu" "In3.Cu" "In4.Cu" "In5.Cu" "In6.Cu"
				"In7.Cu" "In8.Cu" "In9.Cu" "In10.Cu" "In11.Cu" "In12.Cu" "In13.Cu" "In14.Cu"
				"In15.Cu" "In16.Cu"
			)
			(hatch none 0.5)
			(connect_pads
				(clearance 0)
			)
			(min_thickness 0.25)
			(keepout
				(tracks not_allowed)
				(vias allowed)
				(pads allowed)
				(copperpour not_allowed)
				(footprints allowed)
			)
			(placement
				(enabled no)
				(sheetname "")
			)
			(fill
				(thermal_gap 0.5)
				(thermal_bridge_width 0.5)
				(island_removal_mode 0)
			)
			(polygon
				(pts
					(arc
						(start 95.840042 7.333234)
						(mid 93.985842 7.333234)
						(end 95.840042 7.333234)
					)
				)
			)
		)
		(zone
			(layers "F.Cu" "B.Cu" "In1.Cu" "In2.Cu" "In3.Cu" "In4.Cu" "In5.Cu" "In6.Cu"
				"In7.Cu" "In8.Cu" "In9.Cu" "In10.Cu" "In11.Cu" "In12.Cu" "In13.Cu" "In14.Cu"
				"In15.Cu" "In16.Cu"
			)
			(hatch none 0.5)
			(connect_pads
				(clearance 0)
			)
			(min_thickness 0.25)
			(keepout
				(tracks not_allowed)
				(vias allowed)
				(pads allowed)
				(copperpour not_allowed)
				(footprints allowed)
			)
			(placement
				(enabled no)
				(sheetname "")
			)
			(fill
				(thermal_gap 0.5)
				(thermal_bridge_width 0.5)
				(island_removal_mode 0)
			)
			(polygon
				(pts
					(arc
						(start 102.190042 4.793234)
						(mid 100.335842 4.793234)
						(end 102.190042 4.793234)
					)
				)
			)
		)
		(zone
			(layers "F.Cu" "B.Cu" "In1.Cu" "In2.Cu" "In3.Cu" "In4.Cu" "In5.Cu" "In6.Cu"
				"In7.Cu" "In8.Cu" "In9.Cu" "In10.Cu" "In11.Cu" "In12.Cu" "In13.Cu" "In14.Cu"
				"In15.Cu" "In16.Cu"
			)
			(hatch none 0.5)
			(connect_pads
				(clearance 0)
			)
			(min_thickness 0.25)
			(keepout
				(tracks not_allowed)
				(vias allowed)
				(pads allowed)
				(copperpour not_allowed)
				(footprints allowed)
			)
			(placement
				(enabled no)
				(sheetname "")
			)
			(fill
				(thermal_gap 0.5)
				(thermal_bridge_width 0.5)
				(island_removal_mode 0)
			)
			(polygon
				(pts
					(arc
						(start 102.190042 7.333234)
						(mid 100.335842 7.333234)
						(end 102.190042 7.333234)
					)
				)
			)
		)
	)
	(footprint ""
		(layer "F.Cu")
		(at 90.825828 -141.42466 90)
		(property "Reference" "R8178"
			(at 0 0 90)
			(layer "F.SilkS")
			(hide yes)
			(effects
				(font
					(size 1.27 1.27)
				)
			)
		)
		(property "Value" ""
			(at 0 0 90)
			(layer "F.Fab")
			(effects
				(font
					(size 1.27 1.27)
				)
			)
		)
		(duplicate_pad_numbers_are_jumpers no)
		(fp_line
			(start 0.7874 -0.4064)
			(end 0.7874 0.4064)
			(stroke
				(width 0.1524)
				(type default)
			)
			(layer "F.SilkS")
		)
		(fp_line
			(start -0.7874 -0.4064)
			(end 0.7874 -0.4064)
			(stroke
				(width 0.1524)
				(type default)
			)
			(layer "F.SilkS")
		)
		(fp_line
			(start 0.7874 0.4064)
			(end -0.7874 0.4064)
			(stroke
				(width 0.1524)
				(type default)
			)
			(layer "F.SilkS")
		)
		(fp_line
			(start -0.7874 0.4064)
			(end -0.7874 -0.4064)
			(stroke
				(width 0.1524)
				(type default)
			)
			(layer "F.SilkS")
		)
		(fp_line
			(start -0.12065 -0.305054)
			(end -0.12065 -0.2794)
			(stroke
				(width 0.1)
				(type default)
			)
			(layer "F.Fab")
		)
		(fp_line
			(start -0.67945 -0.305054)
			(end -0.12065 -0.305054)
			(stroke
				(width 0.1)
				(type default)
			)
			(layer "F.Fab")
		)
		(fp_line
			(start 0.67945 -0.3048)
			(end 0.67945 0.3048)
			(stroke
				(width 0.1)
				(type default)
			)
			(layer "F.Fab")
		)
		(fp_line
			(start 0.12065 -0.3048)
			(end 0.67945 -0.3048)
			(stroke
				(width 0.1)
				(type default)
			)
			(layer "F.Fab")
		)
		(fp_line
			(start 0.12065 -0.2794)
			(end 0.12065 -0.3048)
			(stroke
				(width 0.1)
				(type default)
			)
			(layer "F.Fab")
		)
		(fp_line
			(start -0.12065 -0.2794)
			(end 0.12065 -0.2794)
			(stroke
				(width 0.1)
				(type default)
			)
			(layer "F.Fab")
		)
		(fp_line
			(start 0.120396 0.2794)
			(end -0.12065 0.2794)
			(stroke
				(width 0.1)
				(type default)
			)
			(layer "F.Fab")
		)
		(fp_line
			(start -0.12065 0.2794)
			(end -0.12065 0.3048)
			(stroke
				(width 0.1)
				(type default)
			)
			(layer "F.Fab")
		)
		(fp_line
			(start 0.67945 0.3048)
			(end 0.120396 0.3048)
			(stroke
				(width 0.1)
				(type default)
			)
			(layer "F.Fab")
		)
		(fp_line
			(start 0.120396 0.3048)
			(end 0.120396 0.2794)
			(stroke
				(width 0.1)
				(type default)
			)
			(layer "F.Fab")
		)
		(fp_line
			(start -0.12065 0.3048)
			(end -0.67945 0.3048)
			(stroke
				(width 0.1)
				(type default)
			)
			(layer "F.Fab")
		)
		(fp_line
			(start -0.67945 0.3048)
			(end -0.67945 -0.305054)
			(stroke
				(width 0.1)
				(type default)
			)
			(layer "F.Fab")
		)
		(pad "1" smd circle
			(at -0.40005 0 90)
			(size 0 0)
			(layers "F.Cu" "F.Mask" "F.Paste")
			(net "PWRGD_PVDDCR_CPU0_P1")
		)
		(pad "2" smd circle
			(at 0.40005 0 90)
			(size 0 0)
			(layers "F.Cu" "F.Mask" "F.Paste")
			(net "PWRGD_PVDDCR_CPU0_P1_R")
		)
	)
	(footprint ""
		(layer "F.Cu")
		(at 438.056782 -437.34736 90)
		(property "Reference" "R4168"
			(at 0 0 90)
			(layer "F.SilkS")
			(hide yes)
			(effects
				(font
					(size 1.27 1.27)
				)
			)
		)
		(property "Value" ""
			(at 0 0 90)
			(layer "F.Fab")
			(effects
				(font
					(size 1.27 1.27)
				)
			)
		)
		(duplicate_pad_numbers_are_jumpers no)
		(fp_line
			(start 0.7874 -0.4064)
			(end 0.7874 0.4064)
			(stroke
				(width 0.1524)
				(type default)
			)
			(layer "F.SilkS")
		)
		(fp_line
			(start -0.7874 -0.4064)
			(end 0.7874 -0.4064)
			(stroke
				(width 0.1524)
				(type default)
			)
			(layer "F.SilkS")
		)
		(fp_line
			(start 0.7874 0.4064)
			(end -0.7874 0.4064)
			(stroke
				(width 0.1524)
				(type default)
			)
			(layer "F.SilkS")
		)
		(fp_line
			(start -0.7874 0.4064)
			(end -0.7874 -0.4064)
			(stroke
				(width 0.1524)
				(type default)
			)
			(layer "F.SilkS")
		)
		(fp_line
			(start -0.12065 -0.305054)
			(end -0.12065 -0.2794)
			(stroke
				(width 0.1)
				(type default)
			)
			(layer "F.Fab")
		)
		(fp_line
			(start -0.67945 -0.305054)
			(end -0.12065 -0.305054)
			(stroke
				(width 0.1)
				(type default)
			)
			(layer "F.Fab")
		)
		(fp_line
			(start 0.67945 -0.3048)
			(end 0.67945 0.3048)
			(stroke
				(width 0.1)
				(type default)
			)
			(layer "F.Fab")
		)
		(fp_line
			(start 0.12065 -0.3048)
			(end 0.67945 -0.3048)
			(stroke
				(width 0.1)
				(type default)
			)
			(layer "F.Fab")
		)
		(fp_line
			(start 0.12065 -0.2794)
			(end 0.12065 -0.3048)
			(stroke
				(width 0.1)
				(type default)
			)
			(layer "F.Fab")
		)
		(fp_line
			(start -0.12065 -0.2794)
			(end 0.12065 -0.2794)
			(stroke
				(width 0.1)
				(type default)
			)
			(layer "F.Fab")
		)
		(fp_line
			(start 0.120396 0.2794)
			(end -0.12065 0.2794)
			(stroke
				(width 0.1)
				(type default)
			)
			(layer "F.Fab")
		)
		(fp_line
			(start -0.12065 0.2794)
			(end -0.12065 0.3048)
			(stroke
				(width 0.1)
				(type default)
			)
			(layer "F.Fab")
		)
		(fp_line
			(start 0.67945 0.3048)
			(end 0.120396 0.3048)
			(stroke
				(width 0.1)
				(type default)
			)
			(layer "F.Fab")
		)
		(fp_line
			(start 0.120396 0.3048)
			(end 0.120396 0.2794)
			(stroke
				(width 0.1)
				(type default)
			)
			(layer "F.Fab")
		)
		(fp_line
			(start -0.12065 0.3048)
			(end -0.67945 0.3048)
			(stroke
				(width 0.1)
				(type default)
			)
			(layer "F.Fab")
		)
		(fp_line
			(start -0.67945 0.3048)
			(end -0.67945 -0.305054)
			(stroke
				(width 0.1)
				(type default)
			)
			(layer "F.Fab")
		)
		(pad "1" smd circle
			(at -0.40005 0 90)
			(size 0 0)
			(layers "F.Cu" "F.Mask" "F.Paste")
			(net "P3V3_AUX")
		)
		(pad "2" smd circle
			(at 0.40005 0 90)
			(size 0 0)
			(layers "F.Cu" "F.Mask" "F.Paste")
			(net "GPU_3V3IO_RSVD4_ISO")
		)
	)
	(footprint ""
		(layer "F.Cu")
		(at 120.396 -421.513 180)
		(property "Reference" "R3465"
			(at 0 0 180)
			(layer "F.SilkS")
			(hide yes)
			(effects
				(font
					(size 1.27 1.27)
				)
			)
		)
		(property "Value" ""
			(at 0 0 180)
			(layer "F.Fab")
			(effects
				(font
					(size 1.27 1.27)
				)
			)
		)
		(duplicate_pad_numbers_are_jumpers no)
		(fp_line
			(start 0.7874 0.4064)
			(end -0.7874 0.4064)
			(stroke
				(width 0.1524)
				(type default)
			)
			(layer "F.SilkS")
		)
		(fp_line
			(start 0.7874 -0.4064)
			(end 0.7874 0.4064)
			(stroke
				(width 0.1524)
				(type default)
			)
			(layer "F.SilkS")
		)
		(fp_line
			(start -0.7874 0.4064)
			(end -0.7874 -0.4064)
			(stroke
				(width 0.1524)
				(type default)
			)
			(layer "F.SilkS")
		)
		(fp_line
			(start -0.7874 -0.4064)
			(end 0.7874 -0.4064)
			(stroke
				(width 0.1524)
				(type default)
			)
			(layer "F.SilkS")
		)
		(fp_line
			(start 0.67945 0.3048)
			(end 0.120396 0.3048)
			(stroke
				(width 0.1)
				(type default)
			)
			(layer "F.Fab")
		)
		(fp_line
			(start 0.67945 -0.3048)
			(end 0.67945 0.3048)
			(stroke
				(width 0.1)
				(type default)
			)
			(layer "F.Fab")
		)
		(fp_line
			(start 0.12065 -0.2794)
			(end 0.12065 -0.3048)
			(stroke
				(width 0.1)
				(type default)
			)
			(layer "F.Fab")
		)
		(fp_line
			(start 0.12065 -0.3048)
			(end 0.67945 -0.3048)
			(stroke
				(width 0.1)
				(type default)
			)
			(layer "F.Fab")
		)
		(fp_line
			(start 0.120396 0.3048)
			(end 0.120396 0.2794)
			(stroke
				(width 0.1)
				(type default)
			)
			(layer "F.Fab")
		)
		(fp_line
			(start 0.120396 0.2794)
			(end -0.12065 0.2794)
			(stroke
				(width 0.1)
				(type default)
			)
			(layer "F.Fab")
		)
		(fp_line
			(start -0.12065 0.3048)
			(end -0.67945 0.3048)
			(stroke
				(width 0.1)
				(type default)
			)
			(layer "F.Fab")
		)
		(fp_line
			(start -0.12065 0.2794)
			(end -0.12065 0.3048)
			(stroke
				(width 0.1)
				(type default)
			)
			(layer "F.Fab")
		)
		(fp_line
			(start -0.12065 -0.2794)
			(end 0.12065 -0.2794)
			(stroke
				(width 0.1)
				(type default)
			)
			(layer "F.Fab")
		)
		(fp_line
			(start -0.12065 -0.305054)
			(end -0.12065 -0.2794)
			(stroke
				(width 0.1)
				(type default)
			)
			(layer "F.Fab")
		)
		(fp_line
			(start -0.67945 0.3048)
			(end -0.67945 -0.305054)
			(stroke
				(width 0.1)
				(type default)
			)
			(layer "F.Fab")
		)
		(fp_line
			(start -0.67945 -0.305054)
			(end -0.12065 -0.305054)
			(stroke
				(width 0.1)
				(type default)
			)
			(layer "F.Fab")
		)
		(pad "1" smd circle
			(at -0.40005 0 180)
			(size 0 0)
			(layers "F.Cu" "F.Mask" "F.Paste")
			(net "P3V3_AUX")
		)
		(pad "2" smd circle
			(at 0.40005 0 180)
			(size 0 0)
			(layers "F.Cu" "F.Mask" "F.Paste")
			(net "GPU_HMC_PRSNT_N")
		)
	)
	(footprint ""
		(layer "F.Cu")
		(at 172.9232 -94.833948 -90)
		(property "Reference" "R6015"
			(at 0 0 270)
			(layer "F.SilkS")
			(hide yes)
			(effects
				(font
					(size 1.27 1.27)
				)
			)
		)
		(property "Value" ""
			(at 0 0 270)
			(layer "F.Fab")
			(effects
				(font
					(size 1.27 1.27)
				)
			)
		)
		(duplicate_pad_numbers_are_jumpers no)
		(fp_line
			(start -0.7874 0.4064)
			(end -0.7874 -0.4064)
			(stroke
				(width 0.1524)
				(type default)
			)
			(layer "F.SilkS")
		)
		(fp_line
			(start 0.7874 0.4064)
			(end -0.7874 0.4064)
			(stroke
				(width 0.1524)
				(type default)
			)
			(layer "F.SilkS")
		)
		(fp_line
			(start -0.7874 -0.4064)
			(end 0.7874 -0.4064)
			(stroke
				(width 0.1524)
				(type default)
			)
			(layer "F.SilkS")
		)
		(fp_line
			(start 0.7874 -0.4064)
			(end 0.7874 0.4064)
			(stroke
				(width 0.1524)
				(type default)
			)
			(layer "F.SilkS")
		)
		(fp_line
			(start -0.67945 0.3048)
			(end -0.67945 -0.305054)
			(stroke
				(width 0.1)
				(type default)
			)
			(layer "F.Fab")
		)
		(fp_line
			(start -0.12065 0.3048)
			(end -0.67945 0.3048)
			(stroke
				(width 0.1)
				(type default)
			)
			(layer "F.Fab")
		)
		(fp_line
			(start 0.120396 0.3048)
			(end 0.120396 0.2794)
			(stroke
				(width 0.1)
				(type default)
			)
			(layer "F.Fab")
		)
		(fp_line
			(start 0.67945 0.3048)
			(end 0.120396 0.3048)
			(stroke
				(width 0.1)
				(type default)
			)
			(layer "F.Fab")
		)
		(fp_line
			(start -0.12065 0.2794)
			(end -0.12065 0.3048)
			(stroke
				(width 0.1)
				(type default)
			)
			(layer "F.Fab")
		)
		(fp_line
			(start 0.120396 0.2794)
			(end -0.12065 0.2794)
			(stroke
				(width 0.1)
				(type default)
			)
			(layer "F.Fab")
		)
		(fp_line
			(start -0.12065 -0.2794)
			(end 0.12065 -0.2794)
			(stroke
				(width 0.1)
				(type default)
			)
			(layer "F.Fab")
		)
		(fp_line
			(start 0.12065 -0.2794)
			(end 0.12065 -0.3048)
			(stroke
				(width 0.1)
				(type default)
			)
			(layer "F.Fab")
		)
		(fp_line
			(start 0.12065 -0.3048)
			(end 0.67945 -0.3048)
			(stroke
				(width 0.1)
				(type default)
			)
			(layer "F.Fab")
		)
		(fp_line
			(start 0.67945 -0.3048)
			(end 0.67945 0.3048)
			(stroke
				(width 0.1)
				(type default)
			)
			(layer "F.Fab")
		)
		(fp_line
			(start -0.67945 -0.305054)
			(end -0.12065 -0.305054)
			(stroke
				(width 0.1)
				(type default)
			)
			(layer "F.Fab")
		)
		(fp_line
			(start -0.12065 -0.305054)
			(end -0.12065 -0.2794)
			(stroke
				(width 0.1)
				(type default)
			)
			(layer "F.Fab")
		)
		(pad "1" smd circle
			(at -0.40005 0 270)
			(size 0 0)
			(layers "F.Cu" "F.Mask" "F.Paste")
			(net "SGPIO_SCM_LD_<1>")
		)
		(pad "2" smd circle
			(at 0.40005 0 270)
			(size 0 0)
			(layers "F.Cu" "F.Mask" "F.Paste")
			(net "SGPIO_SCM_LD_R_<1>")
		)
	)
	(footprint ""
		(layer "F.Cu")
		(at 112.024922 -431.360072 180)
		(property "Reference" "J123"
			(at 1.199134 -11.256772 0)
			(unlocked yes)
			(layer "F.SilkS")
			(effects
				(font
					(size 0.7874 0.5842)
					(thickness 0.1524)
				)
				(justify left)
			)
		)
		(property "Value" ""
			(at 0 0 180)
			(layer "F.Fab")
			(effects
				(font
					(size 1.27 1.27)
				)
			)
		)
		(duplicate_pad_numbers_are_jumpers no)
		(fp_line
			(start 3.525012 9.614408)
			(end 3.525012 6.154928)
			(stroke
				(width 0.1524)
				(type default)
			)
			(layer "F.SilkS")
		)
		(fp_line
			(start 3.525012 2.344928)
			(end 3.525012 -10.489946)
			(stroke
				(width 0.1524)
				(type default)
			)
			(layer "F.SilkS")
		)
		(fp_line
			(start 3.525012 -10.489946)
			(end -3.525012 -10.489946)
			(stroke
				(width 0.1524)
				(type default)
			)
			(layer "F.SilkS")
		)
		(fp_line
			(start -3.525012 -10.489946)
			(end -3.525012 9.614408)
			(stroke
				(width 0.1524)
				(type default)
			)
			(layer "F.SilkS")
		)
		(fp_line
			(start 3.525012 21.310092)
			(end 3.525012 -10.489946)
			(stroke
				(width 0.1)
				(type default)
			)
			(layer "F.Fab")
		)
		(fp_line
			(start 3.525012 -10.489946)
			(end -3.525012 -10.489946)
			(stroke
				(width 0.1)
				(type default)
			)
			(layer "F.Fab")
		)
		(fp_line
			(start -3.525012 21.310092)
			(end 3.525012 21.310092)
			(stroke
				(width 0.1)
				(type default)
			)
			(layer "F.Fab")
		)
		(fp_line
			(start -3.525012 -10.489946)
			(end -3.525012 21.310092)
			(stroke
				(width 0.1)
				(type default)
			)
			(layer "F.Fab")
		)
		(pad "" np_thru_hole circle
			(at 0 -6.620002 180)
			(size 3.175 3.175)
			(drill 3.175)
			(layers "*.Cu" "*.Mask")
			(clearance 0.381)
			(thermal_gap 0.381)
		)
		(pad "" np_thru_hole circle
			(at 0 0 180)
			(size 0 0)
			(drill 3.175)
			(layers "*.Cu" "*.Mask")
			(clearance 0)
		)
		(pad "" np_thru_hole circle
			(at 0 5.130038 180)
			(size 3.175 3.175)
			(drill 3.175)
			(layers "*.Cu" "*.Mask")
			(clearance 0.381)
			(thermal_gap 0.381)
		)
		(zone
			(layers "F.Cu" "B.Cu" "In1.Cu" "In2.Cu" "In3.Cu" "In4.Cu" "In5.Cu" "In6.Cu"
				"In7.Cu" "In8.Cu" "In9.Cu" "In10.Cu" "In11.Cu" "In12.Cu" "In13.Cu" "In14.Cu"
				"In15.Cu" "In16.Cu"
			)
			(hatch none 0.5)
			(connect_pads
				(clearance 0)
			)
			(min_thickness 0.25)
			(keepout
				(tracks not_allowed)
				(vias allowed)
				(pads allowed)
				(copperpour not_allowed)
				(footprints allowed)
			)
			(placement
				(enabled no)
				(sheetname "")
			)
			(fill
				(thermal_gap 0.5)
				(thermal_bridge_width 0.5)
				(island_removal_mode 0)
			)
			(polygon
				(pts
					(arc
						(start 114.120422 -436.49011)
						(mid 109.929422 -436.49011)
						(end 114.120422 -436.49011)
					)
				)
			)
		)
		(zone
			(layers "F.Cu" "B.Cu" "In1.Cu" "In2.Cu" "In3.Cu" "In4.Cu" "In5.Cu" "In6.Cu"
				"In7.Cu" "In8.Cu" "In9.Cu" "In10.Cu" "In11.Cu" "In12.Cu" "In13.Cu" "In14.Cu"
				"In15.Cu" "In16.Cu"
			)
			(hatch none 0.5)
			(connect_pads
				(clearance 0)
			)
			(min_thickness 0.25)
			(keepout
				(tracks not_allowed)
				(vias allowed)
				(pads allowed)
				(copperpour not_allowed)
				(footprints allowed)
			)
			(placement
				(enabled no)
				(sheetname "")
			)
			(fill
				(thermal_gap 0.5)
				(thermal_bridge_width 0.5)
				(island_removal_mode 0)
			)
			(polygon
				(pts
					(arc
						(start 114.120422 -424.74007)
						(mid 109.929422 -424.74007)
						(end 114.120422 -424.74007)
					)
				)
			)
		)
		(zone
			(layers "F.Cu" "B.Cu" "In1.Cu" "In2.Cu" "In3.Cu" "In4.Cu" "In5.Cu" "In6.Cu"
				"In7.Cu" "In8.Cu" "In9.Cu" "In10.Cu" "In11.Cu" "In12.Cu" "In13.Cu" "In14.Cu"
				"In15.Cu" "In16.Cu"
			)
			(hatch none 0.5)
			(connect_pads
				(clearance 0)
			)
			(min_thickness 0.25)
			(keepout
				(tracks not_allowed)
				(vias allowed)
				(pads allowed)
				(copperpour not_allowed)
				(footprints allowed)
			)
			(placement
				(enabled no)
				(sheetname "")
			)
			(fill
				(thermal_gap 0.5)
				(thermal_bridge_width 0.5)
				(island_removal_mode 0)
			)
			(polygon
				(pts
					(arc
						(start 115.644422 -431.360072)
						(mid 108.405422 -431.360072)
						(end 115.644422 -431.360072)
					)
				)
			)
		)
	)
	(footprint ""
		(layer "F.Cu")
		(at 443.89294 -77.496924)
		(property "Reference" "C61"
			(at 0 0 0)
			(layer "F.SilkS")
			(hide yes)
			(effects
				(font
					(size 1.27 1.27)
				)
			)
		)
		(property "Value" ""
			(at 0 0 0)
			(layer "F.Fab")
			(effects
				(font
					(size 1.27 1.27)
				)
			)
		)
		(duplicate_pad_numbers_are_jumpers no)
		(fp_line
			(start -0.7874 -0.4064)
			(end 0.7874 -0.4064)
			(stroke
				(width 0.1524)
				(type default)
			)
			(layer "F.SilkS")
		)
		(fp_line
			(start -0.7874 0.4064)
			(end -0.7874 -0.4064)
			(stroke
				(width 0.1524)
				(type default)
			)
			(layer "F.SilkS")
		)
		(fp_line
			(start 0.7874 -0.4064)
			(end 0.7874 0.4064)
			(stroke
				(width 0.1524)
				(type default)
			)
			(layer "F.SilkS")
		)
		(fp_line
			(start 0.7874 0.4064)
			(end -0.7874 0.4064)
			(stroke
				(width 0.1524)
				(type default)
			)
			(layer "F.SilkS")
		)
		(fp_line
			(start -0.67945 -0.305054)
			(end -0.12065 -0.305054)
			(stroke
				(width 0.1)
				(type default)
			)
			(layer "F.Fab")
		)
		(fp_line
			(start -0.67945 0.3048)
			(end -0.67945 -0.305054)
			(stroke
				(width 0.1)
				(type default)
			)
			(layer "F.Fab")
		)
		(fp_line
			(start -0.12065 -0.305054)
			(end -0.12065 -0.2794)
			(stroke
				(width 0.1)
				(type default)
			)
			(layer "F.Fab")
		)
		(fp_line
			(start -0.12065 -0.2794)
			(end 0.12065 -0.2794)
			(stroke
				(width 0.1)
				(type default)
			)
			(layer "F.Fab")
		)
		(fp_line
			(start -0.12065 0.2794)
			(end -0.12065 0.3048)
			(stroke
				(width 0.1)
				(type default)
			)
			(layer "F.Fab")
		)
		(fp_line
			(start -0.12065 0.3048)
			(end -0.67945 0.3048)
			(stroke
				(width 0.1)
				(type default)
			)
			(layer "F.Fab")
		)
		(fp_line
			(start 0.120396 0.2794)
			(end -0.12065 0.2794)
			(stroke
				(width 0.1)
				(type default)
			)
			(layer "F.Fab")
		)
		(fp_line
			(start 0.120396 0.3048)
			(end 0.120396 0.2794)
			(stroke
				(width 0.1)
				(type default)
			)
			(layer "F.Fab")
		)
		(fp_line
			(start 0.12065 -0.3048)
			(end 0.67945 -0.3048)
			(stroke
				(width 0.1)
				(type default)
			)
			(layer "F.Fab")
		)
		(fp_line
			(start 0.12065 -0.2794)
			(end 0.12065 -0.3048)
			(stroke
				(width 0.1)
				(type default)
			)
			(layer "F.Fab")
		)
		(fp_line
			(start 0.67945 -0.3048)
			(end 0.67945 0.3048)
			(stroke
				(width 0.1)
				(type default)
			)
			(layer "F.Fab")
		)
		(fp_line
			(start 0.67945 0.3048)
			(end 0.120396 0.3048)
			(stroke
				(width 0.1)
				(type default)
			)
			(layer "F.Fab")
		)
		(pad "1" smd circle
			(at -0.40005 0)
			(size 0 0)
			(layers "F.Cu" "F.Mask" "F.Paste")
			(net "P3V3")
		)
		(pad "2" smd circle
			(at 0.40005 0)
			(size 0 0)
			(layers "F.Cu" "F.Mask" "F.Paste")
			(net "GND")
		)
	)
	(footprint ""
		(layer "F.Cu")
		(at 12.733782 -405.611584 -90)
		(property "Reference" "PC6546"
			(at 0 0 270)
			(layer "F.SilkS")
			(hide yes)
			(effects
				(font
					(size 1.27 1.27)
				)
			)
		)
		(property "Value" ""
			(at 0 0 270)
			(layer "F.Fab")
			(effects
				(font
					(size 1.27 1.27)
				)
			)
		)
		(duplicate_pad_numbers_are_jumpers no)
		(fp_line
			(start -0.7874 0.4064)
			(end -0.7874 -0.4064)
			(stroke
				(width 0.1524)
				(type default)
			)
			(layer "F.SilkS")
		)
		(fp_line
			(start 0.7874 0.4064)
			(end -0.7874 0.4064)
			(stroke
				(width 0.1524)
				(type default)
			)
			(layer "F.SilkS")
		)
		(fp_line
			(start -0.7874 -0.4064)
			(end 0.7874 -0.4064)
			(stroke
				(width 0.1524)
				(type default)
			)
			(layer "F.SilkS")
		)
		(fp_line
			(start 0.7874 -0.4064)
			(end 0.7874 0.4064)
			(stroke
				(width 0.1524)
				(type default)
			)
			(layer "F.SilkS")
		)
		(fp_line
			(start -0.67945 0.3048)
			(end -0.67945 -0.305054)
			(stroke
				(width 0.1)
				(type default)
			)
			(layer "F.Fab")
		)
		(fp_line
			(start -0.12065 0.3048)
			(end -0.67945 0.3048)
			(stroke
				(width 0.1)
				(type default)
			)
			(layer "F.Fab")
		)
		(fp_line
			(start 0.120396 0.3048)
			(end 0.120396 0.2794)
			(stroke
				(width 0.1)
				(type default)
			)
			(layer "F.Fab")
		)
		(fp_line
			(start 0.67945 0.3048)
			(end 0.120396 0.3048)
			(stroke
				(width 0.1)
				(type default)
			)
			(layer "F.Fab")
		)
		(fp_line
			(start -0.12065 0.2794)
			(end -0.12065 0.3048)
			(stroke
				(width 0.1)
				(type default)
			)
			(layer "F.Fab")
		)
		(fp_line
			(start 0.120396 0.2794)
			(end -0.12065 0.2794)
			(stroke
				(width 0.1)
				(type default)
			)
			(layer "F.Fab")
		)
		(fp_line
			(start -0.12065 -0.2794)
			(end 0.12065 -0.2794)
			(stroke
				(width 0.1)
				(type default)
			)
			(layer "F.Fab")
		)
		(fp_line
			(start 0.12065 -0.2794)
			(end 0.12065 -0.3048)
			(stroke
				(width 0.1)
				(type default)
			)
			(layer "F.Fab")
		)
		(fp_line
			(start 0.12065 -0.3048)
			(end 0.67945 -0.3048)
			(stroke
				(width 0.1)
				(type default)
			)
			(layer "F.Fab")
		)
		(fp_line
			(start 0.67945 -0.3048)
			(end 0.67945 0.3048)
			(stroke
				(width 0.1)
				(type default)
			)
			(layer "F.Fab")
		)
		(fp_line
			(start -0.67945 -0.305054)
			(end -0.12065 -0.305054)
			(stroke
				(width 0.1)
				(type default)
			)
			(layer "F.Fab")
		)
		(fp_line
			(start -0.12065 -0.305054)
			(end -0.12065 -0.2794)
			(stroke
				(width 0.1)
				(type default)
			)
			(layer "F.Fab")
		)
		(pad "1" smd circle
			(at -0.40005 0 270)
			(size 0 0)
			(layers "F.Cu" "F.Mask" "F.Paste")
			(net "PV09_RETIMER_CPU1_VCCS")
		)
		(pad "2" smd circle
			(at 0.40005 0 270)
			(size 0 0)
			(layers "F.Cu" "F.Mask" "F.Paste")
			(net "GND")
		)
	)
	(footprint ""
		(layer "F.Cu")
		(at 204.7621 -400.972782 180)
		(property "Reference" "PR3915"
			(at 0 0 180)
			(layer "F.SilkS")
			(hide yes)
			(effects
				(font
					(size 1.27 1.27)
				)
			)
		)
		(property "Value" ""
			(at 0 0 180)
			(layer "F.Fab")
			(effects
				(font
					(size 1.27 1.27)
				)
			)
		)
		(duplicate_pad_numbers_are_jumpers no)
		(fp_line
			(start 0.7874 0.4064)
			(end -0.7874 0.4064)
			(stroke
				(width 0.1524)
				(type default)
			)
			(layer "F.SilkS")
		)
		(fp_line
			(start 0.7874 -0.4064)
			(end 0.7874 0.4064)
			(stroke
				(width 0.1524)
				(type default)
			)
			(layer "F.SilkS")
		)
		(fp_line
			(start -0.7874 0.4064)
			(end -0.7874 -0.4064)
			(stroke
				(width 0.1524)
				(type default)
			)
			(layer "F.SilkS")
		)
		(fp_line
			(start -0.7874 -0.4064)
			(end 0.7874 -0.4064)
			(stroke
				(width 0.1524)
				(type default)
			)
			(layer "F.SilkS")
		)
		(fp_line
			(start 0.67945 0.3048)
			(end 0.120396 0.3048)
			(stroke
				(width 0.1)
				(type default)
			)
			(layer "F.Fab")
		)
		(fp_line
			(start 0.67945 -0.3048)
			(end 0.67945 0.3048)
			(stroke
				(width 0.1)
				(type default)
			)
			(layer "F.Fab")
		)
		(fp_line
			(start 0.12065 -0.2794)
			(end 0.12065 -0.3048)
			(stroke
				(width 0.1)
				(type default)
			)
			(layer "F.Fab")
		)
		(fp_line
			(start 0.12065 -0.3048)
			(end 0.67945 -0.3048)
			(stroke
				(width 0.1)
				(type default)
			)
			(layer "F.Fab")
		)
		(fp_line
			(start 0.120396 0.3048)
			(end 0.120396 0.2794)
			(stroke
				(width 0.1)
				(type default)
			)
			(layer "F.Fab")
		)
		(fp_line
			(start 0.120396 0.2794)
			(end -0.12065 0.2794)
			(stroke
				(width 0.1)
				(type default)
			)
			(layer "F.Fab")
		)
		(fp_line
			(start -0.12065 0.3048)
			(end -0.67945 0.3048)
			(stroke
				(width 0.1)
				(type default)
			)
			(layer "F.Fab")
		)
		(fp_line
			(start -0.12065 0.2794)
			(end -0.12065 0.3048)
			(stroke
				(width 0.1)
				(type default)
			)
			(layer "F.Fab")
		)
		(fp_line
			(start -0.12065 -0.2794)
			(end 0.12065 -0.2794)
			(stroke
				(width 0.1)
				(type default)
			)
			(layer "F.Fab")
		)
		(fp_line
			(start -0.12065 -0.305054)
			(end -0.12065 -0.2794)
			(stroke
				(width 0.1)
				(type default)
			)
			(layer "F.Fab")
		)
		(fp_line
			(start -0.67945 0.3048)
			(end -0.67945 -0.305054)
			(stroke
				(width 0.1)
				(type default)
			)
			(layer "F.Fab")
		)
		(fp_line
			(start -0.67945 -0.305054)
			(end -0.12065 -0.305054)
			(stroke
				(width 0.1)
				(type default)
			)
			(layer "F.Fab")
		)
		(pad "1" smd circle
			(at -0.40005 0 180)
			(size 0 0)
			(layers "F.Cu" "F.Mask" "F.Paste")
			(net "HSC_CS_2")
		)
		(pad "2" smd circle
			(at 0.40005 0 180)
			(size 0 0)
			(layers "F.Cu" "F.Mask" "F.Paste")
			(net "AGND_HSC")
		)
	)
	(footprint ""
		(layer "F.Cu")
		(at 383.557018 -154.771852 180)
		(property "Reference" "PL65"
			(at 2.980436 3.704844 0)
			(unlocked yes)
			(layer "F.SilkS")
			(effects
				(font
					(size 0.7874 0.5842)
					(thickness 0.1524)
				)
				(justify left)
			)
		)
		(property "Value" ""
			(at 0 0 180)
			(layer "F.Fab")
			(effects
				(font
					(size 1.27 1.27)
				)
			)
		)
		(duplicate_pad_numbers_are_jumpers no)
		(fp_line
			(start 3.050032 2.999994)
			(end 3.050032 1.4478)
			(stroke
				(width 0.1524)
				(type default)
			)
			(layer "F.SilkS")
		)
		(fp_line
			(start 3.050032 -1.4478)
			(end 3.050032 -2.999994)
			(stroke
				(width 0.1524)
				(type default)
			)
			(layer "F.SilkS")
		)
		(fp_line
			(start 3.050032 -2.999994)
			(end -3.050032 -2.999994)
			(stroke
				(width 0.1524)
				(type default)
			)
			(layer "F.SilkS")
		)
		(fp_line
			(start -3.050032 2.999994)
			(end 3.050032 2.999994)
			(stroke
				(width 0.1524)
				(type default)
			)
			(layer "F.SilkS")
		)
		(fp_line
			(start -3.050032 1.4478)
			(end -3.050032 2.999994)
			(stroke
				(width 0.1524)
				(type default)
			)
			(layer "F.SilkS")
		)
		(fp_line
			(start -3.050032 -2.999994)
			(end -3.050032 -1.4478)
			(stroke
				(width 0.1524)
				(type default)
			)
			(layer "F.SilkS")
		)
		(fp_line
			(start 3.050032 2.999994)
			(end 3.050032 -2.999994)
			(stroke
				(width 0.1)
				(type default)
			)
			(layer "F.Fab")
		)
		(fp_line
			(start 3.050032 -2.999994)
			(end -3.050032 -2.999994)
			(stroke
				(width 0.1)
				(type default)
			)
			(layer "F.Fab")
		)
		(fp_line
			(start -3.050032 2.999994)
			(end 3.050032 2.999994)
			(stroke
				(width 0.1)
				(type default)
			)
			(layer "F.Fab")
		)
		(fp_line
			(start -3.050032 -2.999994)
			(end -3.050032 2.999994)
			(stroke
				(width 0.1)
				(type default)
			)
			(layer "F.Fab")
		)
		(pad "1" smd rect
			(at -2.525014 0 180)
			(size 1.651 2.6162)
			(layers "F.Cu" "F.Mask" "F.Paste")
			(net "SW_P12V_AUX_PVDDCR_SOC_P0_FLT")
		)
		(pad "2" smd rect
			(at 2.525014 0 180)
			(size 1.651 2.6162)
			(layers "F.Cu" "F.Mask" "F.Paste")
			(net "P12V_AUX")
		)
	)
	(footprint ""
		(layer "F.Cu")
		(at 125.38837 -32.751268)
		(property "Reference" "C6019"
			(at 0 0 0)
			(layer "F.SilkS")
			(hide yes)
			(effects
				(font
					(size 1.27 1.27)
				)
			)
		)
		(property "Value" ""
			(at 0 0 0)
			(layer "F.Fab")
			(effects
				(font
					(size 1.27 1.27)
				)
			)
		)
		(duplicate_pad_numbers_are_jumpers no)
		(fp_line
			(start -0.40005 -0.4064)
			(end 0.40005 -0.4064)
			(stroke
				(width 0.1524)
				(type default)
			)
			(layer "F.SilkS")
		)
		(fp_line
			(start 0.40005 0.4064)
			(end -0.40005 0.4064)
			(stroke
				(width 0.1524)
				(type default)
			)
			(layer "F.SilkS")
		)
		(fp_line
			(start -0.6858 -0.3048)
			(end -0.1016 -0.3048)
			(stroke
				(width 0.1)
				(type default)
			)
			(layer "F.Fab")
		)
		(fp_line
			(start -0.6858 0.3048)
			(end -0.6858 -0.3048)
			(stroke
				(width 0.1)
				(type default)
			)
			(layer "F.Fab")
		)
		(fp_line
			(start -0.1016 -0.3048)
			(end -0.1016 -0.2794)
			(stroke
				(width 0.1)
				(type default)
			)
			(layer "F.Fab")
		)
		(fp_line
			(start -0.1016 -0.2794)
			(end 0.1016 -0.2794)
			(stroke
				(width 0.1)
				(type default)
			)
			(layer "F.Fab")
		)
		(fp_line
			(start -0.1016 0.2794)
			(end -0.1016 0.3048)
			(stroke
				(width 0.1)
				(type default)
			)
			(layer "F.Fab")
		)
		(fp_line
			(start -0.1016 0.3048)
			(end -0.6858 0.3048)
			(stroke
				(width 0.1)
				(type default)
			)
			(layer "F.Fab")
		)
		(fp_line
			(start 0.1016 -0.3048)
			(end 0.6858 -0.3048)
			(stroke
				(width 0.1)
				(type default)
			)
			(layer "F.Fab")
		)
		(fp_line
			(start 0.1016 -0.2794)
			(end 0.1016 -0.3048)
			(stroke
				(width 0.1)
				(type default)
			)
			(layer "F.Fab")
		)
		(fp_line
			(start 0.1016 0.2794)
			(end -0.1016 0.2794)
			(stroke
				(width 0.1)
				(type default)
			)
			(layer "F.Fab")
		)
		(fp_line
			(start 0.1016 0.3048)
			(end 0.1016 0.2794)
			(stroke
				(width 0.1)
				(type default)
			)
			(layer "F.Fab")
		)
		(fp_line
			(start 0.6858 -0.3048)
			(end 0.6858 0.3048)
			(stroke
				(width 0.1)
				(type default)
			)
			(layer "F.Fab")
		)
		(fp_line
			(start 0.6858 0.3048)
			(end 0.1016 0.3048)
			(stroke
				(width 0.1)
				(type default)
			)
			(layer "F.Fab")
		)
		(pad "1" smd rect
			(at -0.40005 0 180)
			(size 0.4572 0.508)
			(layers "F.Cu" "F.Mask" "F.Paste")
			(net "USB3_CPU0_BMC_RX_DP")
		)
		(pad "2" smd rect
			(at 0.40005 0 180)
			(size 0.4572 0.508)
			(layers "F.Cu" "F.Mask" "F.Paste")
			(net "USB3_CPU0_BMC_RX_C1_DP")
		)
	)
	(footprint ""
		(layer "F.Cu")
		(at 308.379876 -70.098412 90)
		(property "Reference" "D6000"
			(at -3.75158 -1.438148 90)
			(unlocked yes)
			(layer "F.SilkS")
			(effects
				(font
					(size 0.7874 0.5842)
					(thickness 0.1524)
				)
				(justify left)
			)
		)
		(property "Value" ""
			(at 0 0 90)
			(layer "F.Fab")
			(effects
				(font
					(size 1.27 1.27)
				)
			)
		)
		(duplicate_pad_numbers_are_jumpers no)
		(fp_line
			(start 1.16078 -0.4826)
			(end 1.16078 0.4826)
			(stroke
				(width 0.1524)
				(type default)
			)
			(layer "F.SilkS")
		)
		(fp_line
			(start 1.03378 -0.4826)
			(end 1.03378 0.4826)
			(stroke
				(width 0.1524)
				(type default)
			)
			(layer "F.SilkS")
		)
		(fp_line
			(start 0.90678 -0.4826)
			(end 0.90678 0.4826)
			(stroke
				(width 0.1524)
				(type default)
			)
			(layer "F.SilkS")
		)
		(fp_line
			(start -0.64008 -0.4826)
			(end 1.16078 -0.4826)
			(stroke
				(width 0.1524)
				(type default)
			)
			(layer "F.SilkS")
		)
		(fp_line
			(start -0.79248 -0.4826)
			(end 1.03378 -0.4826)
			(stroke
				(width 0.1524)
				(type default)
			)
			(layer "F.SilkS")
		)
		(fp_line
			(start -0.89408 -0.4826)
			(end 0.90678 -0.4826)
			(stroke
				(width 0.1524)
				(type default)
			)
			(layer "F.SilkS")
		)
		(fp_line
			(start 1.16078 0.4826)
			(end -0.64008 0.4826)
			(stroke
				(width 0.1524)
				(type default)
			)
			(layer "F.SilkS")
		)
		(fp_line
			(start 1.03378 0.4826)
			(end -0.79248 0.4826)
			(stroke
				(width 0.1524)
				(type default)
			)
			(layer "F.SilkS")
		)
		(fp_line
			(start 0.90678 0.4826)
			(end -0.90678 0.4826)
			(stroke
				(width 0.1524)
				(type default)
			)
			(layer "F.SilkS")
		)
		(fp_line
			(start -0.90678 0.4826)
			(end -0.90678 -0.4699)
			(stroke
				(width 0.1524)
				(type default)
			)
			(layer "F.SilkS")
		)
		(fp_line
			(start 0.499872 -0.249936)
			(end 0.499872 0.249936)
			(stroke
				(width 0.1)
				(type default)
			)
			(layer "F.Fab")
		)
		(fp_line
			(start -0.499872 -0.249936)
			(end 0.499872 -0.249936)
			(stroke
				(width 0.1)
				(type default)
			)
			(layer "F.Fab")
		)
		(fp_line
			(start 0.499872 0.249936)
			(end -0.499872 0.249936)
			(stroke
				(width 0.1)
				(type default)
			)
			(layer "F.Fab")
		)
		(fp_line
			(start -0.499872 0.249936)
			(end -0.499872 -0.249936)
			(stroke
				(width 0.1)
				(type default)
			)
			(layer "F.Fab")
		)
		(pad "A" smd rect
			(at -0.47498 0 90)
			(size 0.6096 0.7112)
			(layers "F.Cu" "F.Mask" "F.Paste")
			(net "LED_PWRGD_P1V2_AUX")
		)
		(pad "C" smd rect
			(at 0.47498 0 90)
			(size 0.6096 0.7112)
			(layers "F.Cu" "F.Mask" "F.Paste")
			(net "LED_PWRGD_P1V2_AUX_D")
		)
	)
	(footprint ""
		(layer "F.Cu")
		(at 437.09463 -425.534836 90)
		(property "Reference" "R651"
			(at 0 0 90)
			(layer "F.SilkS")
			(hide yes)
			(effects
				(font
					(size 1.27 1.27)
				)
			)
		)
		(property "Value" ""
			(at 0 0 90)
			(layer "F.Fab")
			(effects
				(font
					(size 1.27 1.27)
				)
			)
		)
		(duplicate_pad_numbers_are_jumpers no)
		(fp_line
			(start 0.7874 -0.4064)
			(end 0.7874 0.4064)
			(stroke
				(width 0.1524)
				(type default)
			)
			(layer "F.SilkS")
		)
		(fp_line
			(start -0.7874 -0.4064)
			(end 0.7874 -0.4064)
			(stroke
				(width 0.1524)
				(type default)
			)
			(layer "F.SilkS")
		)
		(fp_line
			(start 0.7874 0.4064)
			(end -0.7874 0.4064)
			(stroke
				(width 0.1524)
				(type default)
			)
			(layer "F.SilkS")
		)
		(fp_line
			(start -0.7874 0.4064)
			(end -0.7874 -0.4064)
			(stroke
				(width 0.1524)
				(type default)
			)
			(layer "F.SilkS")
		)
		(fp_line
			(start -0.12065 -0.305054)
			(end -0.12065 -0.2794)
			(stroke
				(width 0.1)
				(type default)
			)
			(layer "F.Fab")
		)
		(fp_line
			(start -0.67945 -0.305054)
			(end -0.12065 -0.305054)
			(stroke
				(width 0.1)
				(type default)
			)
			(layer "F.Fab")
		)
		(fp_line
			(start 0.67945 -0.3048)
			(end 0.67945 0.3048)
			(stroke
				(width 0.1)
				(type default)
			)
			(layer "F.Fab")
		)
		(fp_line
			(start 0.12065 -0.3048)
			(end 0.67945 -0.3048)
			(stroke
				(width 0.1)
				(type default)
			)
			(layer "F.Fab")
		)
		(fp_line
			(start 0.12065 -0.2794)
			(end 0.12065 -0.3048)
			(stroke
				(width 0.1)
				(type default)
			)
			(layer "F.Fab")
		)
		(fp_line
			(start -0.12065 -0.2794)
			(end 0.12065 -0.2794)
			(stroke
				(width 0.1)
				(type default)
			)
			(layer "F.Fab")
		)
		(fp_line
			(start 0.120396 0.2794)
			(end -0.12065 0.2794)
			(stroke
				(width 0.1)
				(type default)
			)
			(layer "F.Fab")
		)
		(fp_line
			(start -0.12065 0.2794)
			(end -0.12065 0.3048)
			(stroke
				(width 0.1)
				(type default)
			)
			(layer "F.Fab")
		)
		(fp_line
			(start 0.67945 0.3048)
			(end 0.120396 0.3048)
			(stroke
				(width 0.1)
				(type default)
			)
			(layer "F.Fab")
		)
		(fp_line
			(start 0.120396 0.3048)
			(end 0.120396 0.2794)
			(stroke
				(width 0.1)
				(type default)
			)
			(layer "F.Fab")
		)
		(fp_line
			(start -0.12065 0.3048)
			(end -0.67945 0.3048)
			(stroke
				(width 0.1)
				(type default)
			)
			(layer "F.Fab")
		)
		(fp_line
			(start -0.67945 0.3048)
			(end -0.67945 -0.305054)
			(stroke
				(width 0.1)
				(type default)
			)
			(layer "F.Fab")
		)
		(pad "1" smd circle
			(at -0.40005 0 90)
			(size 0 0)
			(layers "F.Cu" "F.Mask" "F.Paste")
			(net "P0V9_RETIMER_CPU0_EN")
		)
		(pad "2" smd circle
			(at 0.40005 0 90)
			(size 0 0)
			(layers "F.Cu" "F.Mask" "F.Paste")
			(net "P0V9_RETIMER_CPU0_EN0_R")
		)
	)
	(footprint ""
		(layer "F.Cu")
		(at 84.527644 -408.517344 -90)
		(property "Reference" "C6654"
			(at 0 0 270)
			(layer "F.SilkS")
			(hide yes)
			(effects
				(font
					(size 1.27 1.27)
				)
			)
		)
		(property "Value" ""
			(at 0 0 270)
			(layer "F.Fab")
			(effects
				(font
					(size 1.27 1.27)
				)
			)
		)
		(duplicate_pad_numbers_are_jumpers no)
		(fp_line
			(start -0.299974 0.150114)
			(end -0.299974 -0.150114)
			(stroke
				(width 0.1)
				(type default)
			)
			(layer "F.Fab")
		)
		(fp_line
			(start 0.299974 0.150114)
			(end -0.299974 0.150114)
			(stroke
				(width 0.1)
				(type default)
			)
			(layer "F.Fab")
		)
		(fp_line
			(start -0.299974 -0.150114)
			(end 0.299974 -0.150114)
			(stroke
				(width 0.1)
				(type default)
			)
			(layer "F.Fab")
		)
		(fp_line
			(start 0.299974 -0.150114)
			(end 0.299974 0.150114)
			(stroke
				(width 0.1)
				(type default)
			)
			(layer "F.Fab")
		)
		(pad "1" smd rect
			(at -0.2667 0 270)
			(size 0.3048 0.381)
			(layers "F.Cu" "F.Mask" "F.Paste")
			(net "P5E_CPU1_P0_TX_BUF_C_DN<12>")
		)
		(pad "2" smd rect
			(at 0.2667 0 270)
			(size 0.3048 0.381)
			(layers "F.Cu" "F.Mask" "F.Paste")
			(net "P5E_CPU1_P0_TX_BUF_DN<12>")
		)
	)
	(footprint ""
		(layer "F.Cu")
		(at 168.656 -434.869336 180)
		(property "Reference" "R2669"
			(at 0 0 180)
			(layer "F.SilkS")
			(hide yes)
			(effects
				(font
					(size 1.27 1.27)
				)
			)
		)
		(property "Value" ""
			(at 0 0 180)
			(layer "F.Fab")
			(effects
				(font
					(size 1.27 1.27)
				)
			)
		)
		(duplicate_pad_numbers_are_jumpers no)
		(fp_line
			(start 0.7874 0.4064)
			(end -0.7874 0.4064)
			(stroke
				(width 0.1524)
				(type default)
			)
			(layer "F.SilkS")
		)
		(fp_line
			(start 0.7874 -0.4064)
			(end 0.7874 0.4064)
			(stroke
				(width 0.1524)
				(type default)
			)
			(layer "F.SilkS")
		)
		(fp_line
			(start -0.7874 0.4064)
			(end -0.7874 -0.4064)
			(stroke
				(width 0.1524)
				(type default)
			)
			(layer "F.SilkS")
		)
		(fp_line
			(start -0.7874 -0.4064)
			(end 0.7874 -0.4064)
			(stroke
				(width 0.1524)
				(type default)
			)
			(layer "F.SilkS")
		)
		(fp_line
			(start 0.67945 0.3048)
			(end 0.120396 0.3048)
			(stroke
				(width 0.1)
				(type default)
			)
			(layer "F.Fab")
		)
		(fp_line
			(start 0.67945 -0.3048)
			(end 0.67945 0.3048)
			(stroke
				(width 0.1)
				(type default)
			)
			(layer "F.Fab")
		)
		(fp_line
			(start 0.12065 -0.2794)
			(end 0.12065 -0.3048)
			(stroke
				(width 0.1)
				(type default)
			)
			(layer "F.Fab")
		)
		(fp_line
			(start 0.12065 -0.3048)
			(end 0.67945 -0.3048)
			(stroke
				(width 0.1)
				(type default)
			)
			(layer "F.Fab")
		)
		(fp_line
			(start 0.120396 0.3048)
			(end 0.120396 0.2794)
			(stroke
				(width 0.1)
				(type default)
			)
			(layer "F.Fab")
		)
		(fp_line
			(start 0.120396 0.2794)
			(end -0.12065 0.2794)
			(stroke
				(width 0.1)
				(type default)
			)
			(layer "F.Fab")
		)
		(fp_line
			(start -0.12065 0.3048)
			(end -0.67945 0.3048)
			(stroke
				(width 0.1)
				(type default)
			)
			(layer "F.Fab")
		)
		(fp_line
			(start -0.12065 0.2794)
			(end -0.12065 0.3048)
			(stroke
				(width 0.1)
				(type default)
			)
			(layer "F.Fab")
		)
		(fp_line
			(start -0.12065 -0.2794)
			(end 0.12065 -0.2794)
			(stroke
				(width 0.1)
				(type default)
			)
			(layer "F.Fab")
		)
		(fp_line
			(start -0.12065 -0.305054)
			(end -0.12065 -0.2794)
			(stroke
				(width 0.1)
				(type default)
			)
			(layer "F.Fab")
		)
		(fp_line
			(start -0.67945 0.3048)
			(end -0.67945 -0.305054)
			(stroke
				(width 0.1)
				(type default)
			)
			(layer "F.Fab")
		)
		(fp_line
			(start -0.67945 -0.305054)
			(end -0.12065 -0.305054)
			(stroke
				(width 0.1)
				(type default)
			)
			(layer "F.Fab")
		)
		(pad "1" smd circle
			(at -0.40005 0 180)
			(size 0 0)
			(layers "F.Cu" "F.Mask" "F.Paste")
			(net "P3V3_AUX")
		)
		(pad "2" smd circle
			(at 0.40005 0 180)
			(size 0 0)
			(layers "F.Cu" "F.Mask" "F.Paste")
			(net "SMB_BMC_SWB_BUF_R_SDA")
		)
	)
	(footprint ""
		(layer "F.Cu")
		(at 198.247 -94.234)
		(property "Reference" "R8091"
			(at 0 0 0)
			(layer "F.SilkS")
			(hide yes)
			(effects
				(font
					(size 1.27 1.27)
				)
			)
		)
		(property "Value" ""
			(at 0 0 0)
			(layer "F.Fab")
			(effects
				(font
					(size 1.27 1.27)
				)
			)
		)
		(duplicate_pad_numbers_are_jumpers no)
		(fp_line
			(start -0.7874 -0.4064)
			(end 0.7874 -0.4064)
			(stroke
				(width 0.1524)
				(type default)
			)
			(layer "F.SilkS")
		)
		(fp_line
			(start -0.7874 0.4064)
			(end -0.7874 -0.4064)
			(stroke
				(width 0.1524)
				(type default)
			)
			(layer "F.SilkS")
		)
		(fp_line
			(start 0.7874 -0.4064)
			(end 0.7874 0.4064)
			(stroke
				(width 0.1524)
				(type default)
			)
			(layer "F.SilkS")
		)
		(fp_line
			(start 0.7874 0.4064)
			(end -0.7874 0.4064)
			(stroke
				(width 0.1524)
				(type default)
			)
			(layer "F.SilkS")
		)
		(fp_line
			(start -0.67945 -0.305054)
			(end -0.12065 -0.305054)
			(stroke
				(width 0.1)
				(type default)
			)
			(layer "F.Fab")
		)
		(fp_line
			(start -0.67945 0.3048)
			(end -0.67945 -0.305054)
			(stroke
				(width 0.1)
				(type default)
			)
			(layer "F.Fab")
		)
		(fp_line
			(start -0.12065 -0.305054)
			(end -0.12065 -0.2794)
			(stroke
				(width 0.1)
				(type default)
			)
			(layer "F.Fab")
		)
		(fp_line
			(start -0.12065 -0.2794)
			(end 0.12065 -0.2794)
			(stroke
				(width 0.1)
				(type default)
			)
			(layer "F.Fab")
		)
		(fp_line
			(start -0.12065 0.2794)
			(end -0.12065 0.3048)
			(stroke
				(width 0.1)
				(type default)
			)
			(layer "F.Fab")
		)
		(fp_line
			(start -0.12065 0.3048)
			(end -0.67945 0.3048)
			(stroke
				(width 0.1)
				(type default)
			)
			(layer "F.Fab")
		)
		(fp_line
			(start 0.120396 0.2794)
			(end -0.12065 0.2794)
			(stroke
				(width 0.1)
				(type default)
			)
			(layer "F.Fab")
		)
		(fp_line
			(start 0.120396 0.3048)
			(end 0.120396 0.2794)
			(stroke
				(width 0.1)
				(type default)
			)
			(layer "F.Fab")
		)
		(fp_line
			(start 0.12065 -0.3048)
			(end 0.67945 -0.3048)
			(stroke
				(width 0.1)
				(type default)
			)
			(layer "F.Fab")
		)
		(fp_line
			(start 0.12065 -0.2794)
			(end 0.12065 -0.3048)
			(stroke
				(width 0.1)
				(type default)
			)
			(layer "F.Fab")
		)
		(fp_line
			(start 0.67945 -0.3048)
			(end 0.67945 0.3048)
			(stroke
				(width 0.1)
				(type default)
			)
			(layer "F.Fab")
		)
		(fp_line
			(start 0.67945 0.3048)
			(end 0.120396 0.3048)
			(stroke
				(width 0.1)
				(type default)
			)
			(layer "F.Fab")
		)
		(pad "1" smd circle
			(at -0.40005 0)
			(size 0 0)
			(layers "F.Cu" "F.Mask" "F.Paste")
			(net "P3V3_AUX")
		)
		(pad "2" smd circle
			(at 0.40005 0)
			(size 0 0)
			(layers "F.Cu" "F.Mask" "F.Paste")
			(net "PWRGD_CHGL_CPU1_R1")
		)
	)
	(footprint ""
		(layer "F.Cu")
		(at 46.096428 -399.41246)
		(property "Reference" "R6705"
			(at 0 0 0)
			(layer "F.SilkS")
			(hide yes)
			(effects
				(font
					(size 1.27 1.27)
				)
			)
		)
		(property "Value" ""
			(at 0 0 0)
			(layer "F.Fab")
			(effects
				(font
					(size 1.27 1.27)
				)
			)
		)
		(duplicate_pad_numbers_are_jumpers no)
		(fp_line
			(start -1.2954 -0.5842)
			(end 1.2954 -0.5842)
			(stroke
				(width 0.1524)
				(type default)
			)
			(layer "F.SilkS")
		)
		(fp_line
			(start -1.2954 0.5842)
			(end -1.2954 -0.5842)
			(stroke
				(width 0.1524)
				(type default)
			)
			(layer "F.SilkS")
		)
		(fp_line
			(start 1.2954 -0.5842)
			(end 1.2954 0.5842)
			(stroke
				(width 0.1524)
				(type default)
			)
			(layer "F.SilkS")
		)
		(fp_line
			(start 1.2954 0.5842)
			(end -1.2954 0.5842)
			(stroke
				(width 0.1524)
				(type default)
			)
			(layer "F.SilkS")
		)
		(fp_line
			(start -1.1938 -0.406654)
			(end -0.8636 -0.406654)
			(stroke
				(width 0.1)
				(type default)
			)
			(layer "F.Fab")
		)
		(fp_line
			(start -1.1938 0.4064)
			(end -1.1938 -0.406654)
			(stroke
				(width 0.1)
				(type default)
			)
			(layer "F.Fab")
		)
		(fp_line
			(start -0.8636 -0.4572)
			(end 0.8636 -0.4572)
			(stroke
				(width 0.1)
				(type default)
			)
			(layer "F.Fab")
		)
		(fp_line
			(start -0.8636 -0.406654)
			(end -0.8636 -0.4572)
			(stroke
				(width 0.1)
				(type default)
			)
			(layer "F.Fab")
		)
		(fp_line
			(start -0.8636 0.4064)
			(end -1.1938 0.4064)
			(stroke
				(width 0.1)
				(type default)
			)
			(layer "F.Fab")
		)
		(fp_line
			(start -0.8636 0.4318)
			(end -0.8636 0.4064)
			(stroke
				(width 0.1)
				(type default)
			)
			(layer "F.Fab")
		)
		(fp_line
			(start -0.8636 0.4572)
			(end -0.8636 0.4318)
			(stroke
				(width 0.1)
				(type default)
			)
			(layer "F.Fab")
		)
		(fp_line
			(start 0.8636 -0.4572)
			(end 0.8636 -0.406654)
			(stroke
				(width 0.1)
				(type default)
			)
			(layer "F.Fab")
		)
		(fp_line
			(start 0.8636 -0.406654)
			(end 1.1938 -0.406654)
			(stroke
				(width 0.1)
				(type default)
			)
			(layer "F.Fab")
		)
		(fp_line
			(start 0.8636 0.4064)
			(end 0.8636 0.4572)
			(stroke
				(width 0.1)
				(type default)
			)
			(layer "F.Fab")
		)
		(fp_line
			(start 0.8636 0.4572)
			(end -0.8636 0.4572)
			(stroke
				(width 0.1)
				(type default)
			)
			(layer "F.Fab")
		)
		(fp_line
			(start 1.1938 -0.406654)
			(end 1.1938 0.4064)
			(stroke
				(width 0.1)
				(type default)
			)
			(layer "F.Fab")
		)
		(fp_line
			(start 1.1938 0.4064)
			(end 0.8636 0.4064)
			(stroke
				(width 0.1)
				(type default)
			)
			(layer "F.Fab")
		)
		(pad "1" smd rect
			(at -0.7366 0 270)
			(size 0.7112 0.8128)
			(layers "F.Cu" "F.Mask" "F.Paste")
			(net "P0V9_CPU1_RT0_2A_2D")
		)
		(pad "2" smd rect
			(at 0.7366 0 270)
			(size 0.7112 0.8128)
			(layers "F.Cu" "F.Mask" "F.Paste")
			(net "P0V9_CPU1_RT0_2A")
		)
	)
	(footprint ""
		(layer "F.Cu")
		(at 78.826106 -58.382154 -90)
		(property "Reference" "C2020"
			(at 0 0 270)
			(layer "F.SilkS")
			(hide yes)
			(effects
				(font
					(size 1.27 1.27)
				)
			)
		)
		(property "Value" ""
			(at 0 0 270)
			(layer "F.Fab")
			(effects
				(font
					(size 1.27 1.27)
				)
			)
		)
		(duplicate_pad_numbers_are_jumpers no)
		(fp_line
			(start -0.7874 0.4064)
			(end -0.7874 -0.4064)
			(stroke
				(width 0.1524)
				(type default)
			)
			(layer "F.SilkS")
		)
		(fp_line
			(start 0.7874 0.4064)
			(end -0.7874 0.4064)
			(stroke
				(width 0.1524)
				(type default)
			)
			(layer "F.SilkS")
		)
		(fp_line
			(start -0.7874 -0.4064)
			(end 0.7874 -0.4064)
			(stroke
				(width 0.1524)
				(type default)
			)
			(layer "F.SilkS")
		)
		(fp_line
			(start 0.7874 -0.4064)
			(end 0.7874 0.4064)
			(stroke
				(width 0.1524)
				(type default)
			)
			(layer "F.SilkS")
		)
		(fp_line
			(start -0.67945 0.3048)
			(end -0.67945 -0.305054)
			(stroke
				(width 0.1)
				(type default)
			)
			(layer "F.Fab")
		)
		(fp_line
			(start -0.12065 0.3048)
			(end -0.67945 0.3048)
			(stroke
				(width 0.1)
				(type default)
			)
			(layer "F.Fab")
		)
		(fp_line
			(start 0.120396 0.3048)
			(end 0.120396 0.2794)
			(stroke
				(width 0.1)
				(type default)
			)
			(layer "F.Fab")
		)
		(fp_line
			(start 0.67945 0.3048)
			(end 0.120396 0.3048)
			(stroke
				(width 0.1)
				(type default)
			)
			(layer "F.Fab")
		)
		(fp_line
			(start -0.12065 0.2794)
			(end -0.12065 0.3048)
			(stroke
				(width 0.1)
				(type default)
			)
			(layer "F.Fab")
		)
		(fp_line
			(start 0.120396 0.2794)
			(end -0.12065 0.2794)
			(stroke
				(width 0.1)
				(type default)
			)
			(layer "F.Fab")
		)
		(fp_line
			(start -0.12065 -0.2794)
			(end 0.12065 -0.2794)
			(stroke
				(width 0.1)
				(type default)
			)
			(layer "F.Fab")
		)
		(fp_line
			(start 0.12065 -0.2794)
			(end 0.12065 -0.3048)
			(stroke
				(width 0.1)
				(type default)
			)
			(layer "F.Fab")
		)
		(fp_line
			(start 0.12065 -0.3048)
			(end 0.67945 -0.3048)
			(stroke
				(width 0.1)
				(type default)
			)
			(layer "F.Fab")
		)
		(fp_line
			(start 0.67945 -0.3048)
			(end 0.67945 0.3048)
			(stroke
				(width 0.1)
				(type default)
			)
			(layer "F.Fab")
		)
		(fp_line
			(start -0.67945 -0.305054)
			(end -0.12065 -0.305054)
			(stroke
				(width 0.1)
				(type default)
			)
			(layer "F.Fab")
		)
		(fp_line
			(start -0.12065 -0.305054)
			(end -0.12065 -0.2794)
			(stroke
				(width 0.1)
				(type default)
			)
			(layer "F.Fab")
		)
		(pad "1" smd circle
			(at -0.40005 0 270)
			(size 0 0)
			(layers "F.Cu" "F.Mask" "F.Paste")
			(net "VSENSE_P12V_INA230_3_INP")
		)
		(pad "2" smd circle
			(at 0.40005 0 270)
			(size 0 0)
			(layers "F.Cu" "F.Mask" "F.Paste")
			(net "VSENSE_P12V_INA230_3_INN")
		)
	)
	(footprint ""
		(layer "F.Cu")
		(at 363.645958 -258.795012)
		(property "Reference" "C2563"
			(at 0 0 0)
			(layer "F.SilkS")
			(hide yes)
			(effects
				(font
					(size 1.27 1.27)
				)
			)
		)
		(property "Value" ""
			(at 0 0 0)
			(layer "F.Fab")
			(effects
				(font
					(size 1.27 1.27)
				)
			)
		)
		(duplicate_pad_numbers_are_jumpers no)
		(fp_line
			(start -0.7874 -0.4064)
			(end 0.7874 -0.4064)
			(stroke
				(width 0.1524)
				(type default)
			)
			(layer "F.SilkS")
		)
		(fp_line
			(start -0.7874 0.4064)
			(end -0.7874 -0.4064)
			(stroke
				(width 0.1524)
				(type default)
			)
			(layer "F.SilkS")
		)
		(fp_line
			(start 0.7874 -0.4064)
			(end 0.7874 0.4064)
			(stroke
				(width 0.1524)
				(type default)
			)
			(layer "F.SilkS")
		)
		(fp_line
			(start 0.7874 0.4064)
			(end -0.7874 0.4064)
			(stroke
				(width 0.1524)
				(type default)
			)
			(layer "F.SilkS")
		)
		(fp_line
			(start -0.67945 -0.305054)
			(end -0.12065 -0.305054)
			(stroke
				(width 0.1)
				(type default)
			)
			(layer "F.Fab")
		)
		(fp_line
			(start -0.67945 0.3048)
			(end -0.67945 -0.305054)
			(stroke
				(width 0.1)
				(type default)
			)
			(layer "F.Fab")
		)
		(fp_line
			(start -0.12065 -0.305054)
			(end -0.12065 -0.2794)
			(stroke
				(width 0.1)
				(type default)
			)
			(layer "F.Fab")
		)
		(fp_line
			(start -0.12065 -0.2794)
			(end 0.12065 -0.2794)
			(stroke
				(width 0.1)
				(type default)
			)
			(layer "F.Fab")
		)
		(fp_line
			(start -0.12065 0.2794)
			(end -0.12065 0.3048)
			(stroke
				(width 0.1)
				(type default)
			)
			(layer "F.Fab")
		)
		(fp_line
			(start -0.12065 0.3048)
			(end -0.67945 0.3048)
			(stroke
				(width 0.1)
				(type default)
			)
			(layer "F.Fab")
		)
		(fp_line
			(start 0.120396 0.2794)
			(end -0.12065 0.2794)
			(stroke
				(width 0.1)
				(type default)
			)
			(layer "F.Fab")
		)
		(fp_line
			(start 0.120396 0.3048)
			(end 0.120396 0.2794)
			(stroke
				(width 0.1)
				(type default)
			)
			(layer "F.Fab")
		)
		(fp_line
			(start 0.12065 -0.3048)
			(end 0.67945 -0.3048)
			(stroke
				(width 0.1)
				(type default)
			)
			(layer "F.Fab")
		)
		(fp_line
			(start 0.12065 -0.2794)
			(end 0.12065 -0.3048)
			(stroke
				(width 0.1)
				(type default)
			)
			(layer "F.Fab")
		)
		(fp_line
			(start 0.67945 -0.3048)
			(end 0.67945 0.3048)
			(stroke
				(width 0.1)
				(type default)
			)
			(layer "F.Fab")
		)
		(fp_line
			(start 0.67945 0.3048)
			(end 0.120396 0.3048)
			(stroke
				(width 0.1)
				(type default)
			)
			(layer "F.Fab")
		)
		(pad "1" smd circle
			(at -0.40005 0)
			(size 0 0)
			(layers "F.Cu" "F.Mask" "F.Paste")
			(net "PVDDCR_SOC_P0")
		)
		(pad "2" smd circle
			(at 0.40005 0)
			(size 0 0)
			(layers "F.Cu" "F.Mask" "F.Paste")
			(net "GND")
		)
	)
	(footprint ""
		(layer "F.Cu")
		(at 432.308 -405.9174)
		(property "Reference" "R1405"
			(at 0 0 0)
			(layer "F.SilkS")
			(hide yes)
			(effects
				(font
					(size 1.27 1.27)
				)
			)
		)
		(property "Value" ""
			(at 0 0 0)
			(layer "F.Fab")
			(effects
				(font
					(size 1.27 1.27)
				)
			)
		)
		(duplicate_pad_numbers_are_jumpers no)
		(fp_line
			(start -0.32512 -0.175006)
			(end 0.32512 -0.175006)
			(stroke
				(width 0.1)
				(type default)
			)
			(layer "F.Fab")
		)
		(fp_line
			(start -0.32512 0.175006)
			(end -0.32512 -0.175006)
			(stroke
				(width 0.1)
				(type default)
			)
			(layer "F.Fab")
		)
		(fp_line
			(start 0.32512 -0.175006)
			(end 0.32512 0.175006)
			(stroke
				(width 0.1)
				(type default)
			)
			(layer "F.Fab")
		)
		(fp_line
			(start 0.32512 0.175006)
			(end -0.32512 0.175006)
			(stroke
				(width 0.1)
				(type default)
			)
			(layer "F.Fab")
		)
		(pad "1" smd rect
			(at -0.2667 0)
			(size 0.3048 0.381)
			(layers "F.Cu" "F.Mask" "F.Paste")
			(net "P1V8_CPU0_RT_1D")
		)
		(pad "2" smd rect
			(at 0.2667 0 180)
			(size 0.3048 0.381)
			(layers "F.Cu" "F.Mask" "F.Paste")
			(net "RXDET_BYP_RT_CPU0_P2")
		)
	)
	(footprint ""
		(layer "F.Cu")
		(at 461.720946 -103.614728)
		(property "Reference" "C593"
			(at 0 0 0)
			(layer "F.SilkS")
			(hide yes)
			(effects
				(font
					(size 1.27 1.27)
				)
			)
		)
		(property "Value" ""
			(at 0 0 0)
			(layer "F.Fab")
			(effects
				(font
					(size 1.27 1.27)
				)
			)
		)
		(duplicate_pad_numbers_are_jumpers no)
		(fp_line
			(start -0.7874 -0.4064)
			(end 0.7874 -0.4064)
			(stroke
				(width 0.1524)
				(type default)
			)
			(layer "F.SilkS")
		)
		(fp_line
			(start -0.7874 0.4064)
			(end -0.7874 -0.4064)
			(stroke
				(width 0.1524)
				(type default)
			)
			(layer "F.SilkS")
		)
		(fp_line
			(start 0.7874 -0.4064)
			(end 0.7874 0.4064)
			(stroke
				(width 0.1524)
				(type default)
			)
			(layer "F.SilkS")
		)
		(fp_line
			(start 0.7874 0.4064)
			(end -0.7874 0.4064)
			(stroke
				(width 0.1524)
				(type default)
			)
			(layer "F.SilkS")
		)
		(fp_line
			(start -0.67945 -0.305054)
			(end -0.12065 -0.305054)
			(stroke
				(width 0.1)
				(type default)
			)
			(layer "F.Fab")
		)
		(fp_line
			(start -0.67945 0.3048)
			(end -0.67945 -0.305054)
			(stroke
				(width 0.1)
				(type default)
			)
			(layer "F.Fab")
		)
		(fp_line
			(start -0.12065 -0.305054)
			(end -0.12065 -0.2794)
			(stroke
				(width 0.1)
				(type default)
			)
			(layer "F.Fab")
		)
		(fp_line
			(start -0.12065 -0.2794)
			(end 0.12065 -0.2794)
			(stroke
				(width 0.1)
				(type default)
			)
			(layer "F.Fab")
		)
		(fp_line
			(start -0.12065 0.2794)
			(end -0.12065 0.3048)
			(stroke
				(width 0.1)
				(type default)
			)
			(layer "F.Fab")
		)
		(fp_line
			(start -0.12065 0.3048)
			(end -0.67945 0.3048)
			(stroke
				(width 0.1)
				(type default)
			)
			(layer "F.Fab")
		)
		(fp_line
			(start 0.120396 0.2794)
			(end -0.12065 0.2794)
			(stroke
				(width 0.1)
				(type default)
			)
			(layer "F.Fab")
		)
		(fp_line
			(start 0.120396 0.3048)
			(end 0.120396 0.2794)
			(stroke
				(width 0.1)
				(type default)
			)
			(layer "F.Fab")
		)
		(fp_line
			(start 0.12065 -0.3048)
			(end 0.67945 -0.3048)
			(stroke
				(width 0.1)
				(type default)
			)
			(layer "F.Fab")
		)
		(fp_line
			(start 0.12065 -0.2794)
			(end 0.12065 -0.3048)
			(stroke
				(width 0.1)
				(type default)
			)
			(layer "F.Fab")
		)
		(fp_line
			(start 0.67945 -0.3048)
			(end 0.67945 0.3048)
			(stroke
				(width 0.1)
				(type default)
			)
			(layer "F.Fab")
		)
		(fp_line
			(start 0.67945 0.3048)
			(end 0.120396 0.3048)
			(stroke
				(width 0.1)
				(type default)
			)
			(layer "F.Fab")
		)
		(pad "1" smd circle
			(at -0.40005 0)
			(size 0 0)
			(layers "F.Cu" "F.Mask" "F.Paste")
			(net "P3V3_AUX")
		)
		(pad "2" smd circle
			(at 0.40005 0)
			(size 0 0)
			(layers "F.Cu" "F.Mask" "F.Paste")
			(net "GND")
		)
	)
	(footprint ""
		(layer "F.Cu")
		(at 282.133294 -437.2737)
		(property "Reference" "Q145"
			(at -1.4224 -1.768348 0)
			(unlocked yes)
			(layer "F.SilkS")
			(effects
				(font
					(size 0.7874 0.5842)
					(thickness 0.1524)
				)
				(justify left)
			)
		)
		(property "Value" ""
			(at 0 0 0)
			(layer "F.Fab")
			(effects
				(font
					(size 1.27 1.27)
				)
			)
		)
		(duplicate_pad_numbers_are_jumpers no)
		(fp_line
			(start -1.332738 -1.100074)
			(end -0.4826 -1.100074)
			(stroke
				(width 0.1524)
				(type default)
			)
			(layer "F.SilkS")
		)
		(fp_line
			(start -1.332738 1.100074)
			(end -1.332738 -1.100074)
			(stroke
				(width 0.1524)
				(type default)
			)
			(layer "F.SilkS")
		)
		(fp_line
			(start -0.4826 -1.100074)
			(end 0 -0.541274)
			(stroke
				(width 0.1524)
				(type default)
			)
			(layer "F.SilkS")
		)
		(fp_line
			(start 0 -0.541274)
			(end 0.4826 -1.100074)
			(stroke
				(width 0.1524)
				(type default)
			)
			(layer "F.SilkS")
		)
		(fp_line
			(start 0.4826 -1.100074)
			(end 1.332738 -1.100074)
			(stroke
				(width 0.1524)
				(type default)
			)
			(layer "F.SilkS")
		)
		(fp_line
			(start 1.332738 -1.100074)
			(end 1.332738 1.100074)
			(stroke
				(width 0.1524)
				(type default)
			)
			(layer "F.SilkS")
		)
		(fp_line
			(start 1.332738 1.100074)
			(end -1.332738 1.100074)
			(stroke
				(width 0.1524)
				(type default)
			)
			(layer "F.SilkS")
		)
		(fp_poly
			(pts
				(xy -2.252726 -1.230376) (xy -1.756156 -1.726946) (xy -1.507998 -0.982218)
			)
			(stroke
				(width 0)
				(type default)
			)
			(fill yes)
			(layer "F.SilkS")
		)
		(fp_line
			(start -0.674878 -1.100074)
			(end 0.674878 -1.100074)
			(stroke
				(width 0.1)
				(type default)
			)
			(layer "F.Fab")
		)
		(fp_line
			(start -0.674878 1.100074)
			(end -0.674878 -1.100074)
			(stroke
				(width 0.1)
				(type default)
			)
			(layer "F.Fab")
		)
		(fp_line
			(start 0.674878 -1.100074)
			(end 0.674878 1.100074)
			(stroke
				(width 0.1)
				(type default)
			)
			(layer "F.Fab")
		)
		(fp_line
			(start 0.674878 1.100074)
			(end -0.674878 1.100074)
			(stroke
				(width 0.1)
				(type default)
			)
			(layer "F.Fab")
		)
		(fp_poly
			(pts
				(xy -2.2352 -0.298958) (xy -2.2352 -1.001014) (xy -1.533144 -0.649986)
			)
			(stroke
				(width 0)
				(type default)
			)
			(fill yes)
			(layer "F.Fab")
		)
		(pad "1" smd rect
			(at -0.94996 -0.649986 90)
			(size 0.4318 0.508)
			(layers "F.Cu" "F.Mask" "F.Paste")
			(net "GND")
		)
		(pad "2" smd rect
			(at -0.94996 0 90)
			(size 0.4318 0.508)
			(layers "F.Cu" "F.Mask" "F.Paste")
			(net "HPDB_HSC_PWRGD")
		)
		(pad "3" smd rect
			(at -0.94996 0.649986 90)
			(size 0.4318 0.508)
			(layers "F.Cu" "F.Mask" "F.Paste")
			(net "HPDB_HSC_PWRGD_ISO")
		)
		(pad "4" smd rect
			(at 0.94996 0.649986 90)
			(size 0.4318 0.508)
			(layers "F.Cu" "F.Mask" "F.Paste")
			(net "GND")
		)
		(pad "5" smd rect
			(at 0.94996 0 90)
			(size 0.4318 0.508)
			(layers "F.Cu" "F.Mask" "F.Paste")
			(net "HPDB_HSC_PWRGD_N")
		)
		(pad "6" smd rect
			(at 0.94996 -0.649986 90)
			(size 0.4318 0.508)
			(layers "F.Cu" "F.Mask" "F.Paste")
			(net "HPDB_HSC_PWRGD_N")
		)
	)
	(footprint ""
		(layer "F.Cu")
		(at 398.893538 -393.96416)
		(property "Reference" "R1070"
			(at 0 0 0)
			(layer "F.SilkS")
			(hide yes)
			(effects
				(font
					(size 1.27 1.27)
				)
			)
		)
		(property "Value" ""
			(at 0 0 0)
			(layer "F.Fab")
			(effects
				(font
					(size 1.27 1.27)
				)
			)
		)
		(duplicate_pad_numbers_are_jumpers no)
		(fp_line
			(start -0.32512 -0.175006)
			(end 0.32512 -0.175006)
			(stroke
				(width 0.1)
				(type default)
			)
			(layer "F.Fab")
		)
		(fp_line
			(start -0.32512 0.175006)
			(end -0.32512 -0.175006)
			(stroke
				(width 0.1)
				(type default)
			)
			(layer "F.Fab")
		)
		(fp_line
			(start 0.32512 -0.175006)
			(end 0.32512 0.175006)
			(stroke
				(width 0.1)
				(type default)
			)
			(layer "F.Fab")
		)
		(fp_line
			(start 0.32512 0.175006)
			(end -0.32512 0.175006)
			(stroke
				(width 0.1)
				(type default)
			)
			(layer "F.Fab")
		)
		(pad "1" smd rect
			(at -0.2667 0)
			(size 0.3048 0.381)
			(layers "F.Cu" "F.Mask" "F.Paste")
			(net "GPIO2_RT_CPU0_P2")
		)
		(pad "2" smd rect
			(at 0.2667 0 180)
			(size 0.3048 0.381)
			(layers "F.Cu" "F.Mask" "F.Paste")
			(net "GND")
		)
	)
	(footprint ""
		(layer "F.Cu")
		(at 364.314486 -408.931364)
		(property "Reference" "R9017"
			(at 0 0 0)
			(layer "F.SilkS")
			(hide yes)
			(effects
				(font
					(size 1.27 1.27)
				)
			)
		)
		(property "Value" ""
			(at 0 0 0)
			(layer "F.Fab")
			(effects
				(font
					(size 1.27 1.27)
				)
			)
		)
		(duplicate_pad_numbers_are_jumpers no)
		(fp_line
			(start -0.7874 -0.4064)
			(end 0.7874 -0.4064)
			(stroke
				(width 0.1524)
				(type default)
			)
			(layer "F.SilkS")
		)
		(fp_line
			(start -0.7874 0.4064)
			(end -0.7874 -0.4064)
			(stroke
				(width 0.1524)
				(type default)
			)
			(layer "F.SilkS")
		)
		(fp_line
			(start 0.7874 -0.4064)
			(end 0.7874 0.4064)
			(stroke
				(width 0.1524)
				(type default)
			)
			(layer "F.SilkS")
		)
		(fp_line
			(start 0.7874 0.4064)
			(end -0.7874 0.4064)
			(stroke
				(width 0.1524)
				(type default)
			)
			(layer "F.SilkS")
		)
		(fp_line
			(start -0.67945 -0.305054)
			(end -0.12065 -0.305054)
			(stroke
				(width 0.1)
				(type default)
			)
			(layer "F.Fab")
		)
		(fp_line
			(start -0.67945 0.3048)
			(end -0.67945 -0.305054)
			(stroke
				(width 0.1)
				(type default)
			)
			(layer "F.Fab")
		)
		(fp_line
			(start -0.12065 -0.305054)
			(end -0.12065 -0.2794)
			(stroke
				(width 0.1)
				(type default)
			)
			(layer "F.Fab")
		)
		(fp_line
			(start -0.12065 -0.2794)
			(end 0.12065 -0.2794)
			(stroke
				(width 0.1)
				(type default)
			)
			(layer "F.Fab")
		)
		(fp_line
			(start -0.12065 0.2794)
			(end -0.12065 0.3048)
			(stroke
				(width 0.1)
				(type default)
			)
			(layer "F.Fab")
		)
		(fp_line
			(start -0.12065 0.3048)
			(end -0.67945 0.3048)
			(stroke
				(width 0.1)
				(type default)
			)
			(layer "F.Fab")
		)
		(fp_line
			(start 0.120396 0.2794)
			(end -0.12065 0.2794)
			(stroke
				(width 0.1)
				(type default)
			)
			(layer "F.Fab")
		)
		(fp_line
			(start 0.120396 0.3048)
			(end 0.120396 0.2794)
			(stroke
				(width 0.1)
				(type default)
			)
			(layer "F.Fab")
		)
		(fp_line
			(start 0.12065 -0.3048)
			(end 0.67945 -0.3048)
			(stroke
				(width 0.1)
				(type default)
			)
			(layer "F.Fab")
		)
		(fp_line
			(start 0.12065 -0.2794)
			(end 0.12065 -0.3048)
			(stroke
				(width 0.1)
				(type default)
			)
			(layer "F.Fab")
		)
		(fp_line
			(start 0.67945 -0.3048)
			(end 0.67945 0.3048)
			(stroke
				(width 0.1)
				(type default)
			)
			(layer "F.Fab")
		)
		(fp_line
			(start 0.67945 0.3048)
			(end 0.120396 0.3048)
			(stroke
				(width 0.1)
				(type default)
			)
			(layer "F.Fab")
		)
		(pad "1" smd circle
			(at -0.40005 0)
			(size 0 0)
			(layers "F.Cu" "F.Mask" "F.Paste")
			(net "P3V3_AUX")
		)
		(pad "2" smd circle
			(at 0.40005 0)
			(size 0 0)
			(layers "F.Cu" "F.Mask" "F.Paste")
			(net "PRSNT_CABLE_GPU_A3_ISO_N")
		)
	)
	(footprint ""
		(layer "F.Cu")
		(at 112.649 -123.952 90)
		(property "Reference" "R1491"
			(at 0 0 90)
			(layer "F.SilkS")
			(hide yes)
			(effects
				(font
					(size 1.27 1.27)
				)
			)
		)
		(property "Value" ""
			(at 0 0 90)
			(layer "F.Fab")
			(effects
				(font
					(size 1.27 1.27)
				)
			)
		)
		(duplicate_pad_numbers_are_jumpers no)
		(fp_line
			(start 0.7874 -0.4064)
			(end 0.7874 0.4064)
			(stroke
				(width 0.1524)
				(type default)
			)
			(layer "F.SilkS")
		)
		(fp_line
			(start -0.7874 -0.4064)
			(end 0.7874 -0.4064)
			(stroke
				(width 0.1524)
				(type default)
			)
			(layer "F.SilkS")
		)
		(fp_line
			(start 0.7874 0.4064)
			(end -0.7874 0.4064)
			(stroke
				(width 0.1524)
				(type default)
			)
			(layer "F.SilkS")
		)
		(fp_line
			(start -0.7874 0.4064)
			(end -0.7874 -0.4064)
			(stroke
				(width 0.1524)
				(type default)
			)
			(layer "F.SilkS")
		)
		(fp_line
			(start -0.12065 -0.305054)
			(end -0.12065 -0.2794)
			(stroke
				(width 0.1)
				(type default)
			)
			(layer "F.Fab")
		)
		(fp_line
			(start -0.67945 -0.305054)
			(end -0.12065 -0.305054)
			(stroke
				(width 0.1)
				(type default)
			)
			(layer "F.Fab")
		)
		(fp_line
			(start 0.67945 -0.3048)
			(end 0.67945 0.3048)
			(stroke
				(width 0.1)
				(type default)
			)
			(layer "F.Fab")
		)
		(fp_line
			(start 0.12065 -0.3048)
			(end 0.67945 -0.3048)
			(stroke
				(width 0.1)
				(type default)
			)
			(layer "F.Fab")
		)
		(fp_line
			(start 0.12065 -0.2794)
			(end 0.12065 -0.3048)
			(stroke
				(width 0.1)
				(type default)
			)
			(layer "F.Fab")
		)
		(fp_line
			(start -0.12065 -0.2794)
			(end 0.12065 -0.2794)
			(stroke
				(width 0.1)
				(type default)
			)
			(layer "F.Fab")
		)
		(fp_line
			(start 0.120396 0.2794)
			(end -0.12065 0.2794)
			(stroke
				(width 0.1)
				(type default)
			)
			(layer "F.Fab")
		)
		(fp_line
			(start -0.12065 0.2794)
			(end -0.12065 0.3048)
			(stroke
				(width 0.1)
				(type default)
			)
			(layer "F.Fab")
		)
		(fp_line
			(start 0.67945 0.3048)
			(end 0.120396 0.3048)
			(stroke
				(width 0.1)
				(type default)
			)
			(layer "F.Fab")
		)
		(fp_line
			(start 0.120396 0.3048)
			(end 0.120396 0.2794)
			(stroke
				(width 0.1)
				(type default)
			)
			(layer "F.Fab")
		)
		(fp_line
			(start -0.12065 0.3048)
			(end -0.67945 0.3048)
			(stroke
				(width 0.1)
				(type default)
			)
			(layer "F.Fab")
		)
		(fp_line
			(start -0.67945 0.3048)
			(end -0.67945 -0.305054)
			(stroke
				(width 0.1)
				(type default)
			)
			(layer "F.Fab")
		)
		(pad "1" smd circle
			(at -0.40005 0 90)
			(size 0 0)
			(layers "F.Cu" "F.Mask" "F.Paste")
			(net "P3V3")
		)
		(pad "2" smd circle
			(at 0.40005 0 90)
			(size 0 0)
			(layers "F.Cu" "F.Mask" "F.Paste")
			(net "PWRGD_P3V3_EN_R")
		)
	)
	(footprint ""
		(layer "F.Cu")
		(at 268.645386 -51.999896)
		(property "Reference" "H114"
			(at -8.10006 -6.85419 0)
			(unlocked yes)
			(layer "F.SilkS")
			(effects
				(font
					(size 0.7874 0.5842)
					(thickness 0.1524)
				)
				(justify left)
			)
		)
		(property "Value" ""
			(at 0 0 0)
			(layer "F.Fab")
			(effects
				(font
					(size 1.27 1.27)
				)
			)
		)
		(duplicate_pad_numbers_are_jumpers no)
		(fp_circle
			(center 0 0)
			(end 7.999984 0)
			(stroke
				(width 0.1524)
				(type default)
			)
			(fill no)
			(layer "F.SilkS")
		)
		(fp_circle
			(center 0 0)
			(end 7.999984 0)
			(stroke
				(width 0.1524)
				(type default)
			)
			(fill no)
			(layer "B.SilkS")
		)
		(fp_circle
			(center 0 0)
			(end 7.999984 0)
			(stroke
				(width 0.1)
				(type default)
			)
			(fill no)
			(layer "B.Fab")
		)
		(fp_circle
			(center 0 0)
			(end 7.999984 0)
			(stroke
				(width 0.1)
				(type default)
			)
			(fill no)
			(layer "F.Fab")
		)
		(pad "" np_thru_hole circle
			(at 0 0)
			(size 5.5118 5.5118)
			(drill 5.5118)
			(layers "*.Cu" "*.Mask")
			(clearance 0.381)
			(thermal_gap 0.381)
		)
		(pad "2" thru_hole circle
			(at 0 -3.999992)
			(size 0.762 0.762)
			(drill 0.5588)
			(layers "*.Cu" "*.Mask")
			(remove_unused_layers no)
			(net "GND")
			(clearance 0.1524)
			(thermal_gap 0.1524)
		)
		(pad "3" thru_hole circle
			(at -2.999994 -2.500122)
			(size 0.762 0.762)
			(drill 0.5588)
			(layers "*.Cu" "*.Mask")
			(remove_unused_layers no)
			(net "GND")
			(clearance 0.1524)
			(thermal_gap 0.1524)
		)
		(pad "4" thru_hole circle
			(at -3.999992 0)
			(size 0.762 0.762)
			(drill 0.5588)
			(layers "*.Cu" "*.Mask")
			(remove_unused_layers no)
			(net "GND")
			(clearance 0.1524)
			(thermal_gap 0.1524)
		)
		(pad "5" thru_hole circle
			(at -2.999994 2.500122)
			(size 0.762 0.762)
			(drill 0.5588)
			(layers "*.Cu" "*.Mask")
			(remove_unused_layers no)
			(net "GND")
			(clearance 0.1524)
			(thermal_gap 0.1524)
		)
		(pad "6" thru_hole circle
			(at 0 3.999992)
			(size 0.762 0.762)
			(drill 0.5588)
			(layers "*.Cu" "*.Mask")
			(remove_unused_layers no)
			(net "GND")
			(clearance 0.1524)
			(thermal_gap 0.1524)
		)
		(pad "7" thru_hole circle
			(at 2.999994 2.500122)
			(size 0.762 0.762)
			(drill 0.5588)
			(layers "*.Cu" "*.Mask")
			(remove_unused_layers no)
			(net "GND")
			(clearance 0.1524)
			(thermal_gap 0.1524)
		)
		(pad "8" thru_hole circle
			(at 3.999992 0)
			(size 0.762 0.762)
			(drill 0.5588)
			(layers "*.Cu" "*.Mask")
			(remove_unused_layers no)
			(net "GND")
			(clearance 0.1524)
			(thermal_gap 0.1524)
		)
		(pad "9" thru_hole circle
			(at 2.999994 -2.500122)
			(size 0.762 0.762)
			(drill 0.5588)
			(layers "*.Cu" "*.Mask")
			(remove_unused_layers no)
			(net "GND")
			(clearance 0.1524)
			(thermal_gap 0.1524)
		)
		(zone
			(layer "F.Cu")
			(hatch none 0.5)
			(connect_pads
				(clearance 0)
			)
			(min_thickness 0.25)
			(keepout
				(tracks not_allowed)
				(vias allowed)
				(pads allowed)
				(copperpour not_allowed)
				(footprints allowed)
			)
			(placement
				(enabled no)
				(sheetname "")
			)
			(fill
				(thermal_gap 0.5)
				(thermal_bridge_width 0.5)
				(island_removal_mode 0)
			)
			(polygon
				(pts
					(arc
						(start 268.645386 -59.99988)
						(mid 262.988543 -57.656739)
						(end 260.645402 -51.999896)
					)
					(arc
						(start 260.645402 -51.999896)
						(mid 262.988543 -46.343053)
						(end 268.645386 -43.999912)
					)
					(xy 268.645386 -46.74616) (xy 268.594332 -46.74616)
					(arc
						(start 268.594078 -46.74616)
						(mid 263.391399 -51.999896)
						(end 268.594078 -57.253632)
					)
					(xy 268.594332 -57.253632) (xy 268.645386 -57.253632)
				)
			)
		)
		(zone
			(layer "F.Cu")
			(hatch none 0.5)
			(connect_pads
				(clearance 0)
			)
			(min_thickness 0.25)
			(keepout
				(tracks not_allowed)
				(vias allowed)
				(pads allowed)
				(copperpour not_allowed)
				(footprints allowed)
			)
			(placement
				(enabled no)
				(sheetname "")
			)
			(fill
				(thermal_gap 0.5)
				(thermal_bridge_width 0.5)
				(island_removal_mode 0)
			)
			(polygon
				(pts
					(arc
						(start 268.645386 -59.99988)
						(mid 274.302229 -57.656739)
						(end 276.64537 -51.999896)
					)
					(arc
						(start 276.64537 -51.999896)
						(mid 274.302229 -46.343053)
						(end 268.645386 -43.999912)
					)
					(xy 268.645386 -46.74616) (xy 268.69644 -46.74616)
					(arc
						(start 268.696694 -46.74616)
						(mid 273.899373 -51.999896)
						(end 268.696694 -57.253632)
					)
					(xy 268.69644 -57.253632) (xy 268.645386 -57.253632)
				)
			)
		)
		(zone
			(layers "F.Cu" "B.Cu" "In1.Cu" "In2.Cu" "In3.Cu" "In4.Cu" "In5.Cu" "In6.Cu"
				"In7.Cu" "In8.Cu" "In9.Cu" "In10.Cu" "In11.Cu" "In12.Cu" "In13.Cu" "In14.Cu"
				"In15.Cu" "In16.Cu"
			)
			(hatch none 0.5)
			(connect_pads
				(clearance 0)
			)
			(min_thickness 0.25)
			(keepout
				(tracks not_allowed)
				(vias allowed)
				(pads allowed)
				(copperpour not_allowed)
				(footprints allowed)
			)
			(placement
				(enabled no)
				(sheetname "")
			)
			(fill
				(thermal_gap 0.5)
				(thermal_bridge_width 0.5)
				(island_removal_mode 0)
			)
			(polygon
				(pts
					(arc
						(start 271.921986 -51.999896)
						(mid 265.368786 -51.999896)
						(end 271.921986 -51.999896)
					)
				)
			)
		)
		(zone
			(layer "B.Cu")
			(hatch none 0.5)
			(connect_pads
				(clearance 0)
			)
			(min_thickness 0.25)
			(keepout
				(tracks not_allowed)
				(vias allowed)
				(pads allowed)
				(copperpour not_allowed)
				(footprints allowed)
			)
			(placement
				(enabled no)
				(sheetname "")
			)
			(fill
				(thermal_gap 0.5)
				(thermal_bridge_width 0.5)
				(island_removal_mode 0)
			)
			(polygon
				(pts
					(arc
						(start 268.645386 -57.507886)
						(mid 263.137396 -51.999896)
						(end 268.645386 -46.491906)
					)
					(arc
						(start 268.645386 -46.974506)
						(mid 263.619996 -51.999896)
						(end 268.645386 -57.025286)
					)
				)
			)
		)
		(zone
			(layer "B.Cu")
			(hatch none 0.5)
			(connect_pads
				(clearance 0)
			)
			(min_thickness 0.25)
			(keepout
				(tracks not_allowed)
				(vias allowed)
				(pads allowed)
				(copperpour not_allowed)
				(footprints allowed)
			)
			(placement
				(enabled no)
				(sheetname "")
			)
			(fill
				(thermal_gap 0.5)
				(thermal_bridge_width 0.5)
				(island_removal_mode 0)
			)
			(polygon
				(pts
					(arc
						(start 268.645386 -57.507886)
						(mid 274.153376 -51.999896)
						(end 268.645386 -46.491906)
					)
					(arc
						(start 268.645386 -46.974506)
						(mid 273.670776 -51.999896)
						(end 268.645386 -57.025286)
					)
				)
			)
		)
	)
	(footprint ""
		(layer "F.Cu")
		(at 41.741852 -383.7432)
		(property "Reference" "R724"
			(at 0 0 0)
			(layer "F.SilkS")
			(hide yes)
			(effects
				(font
					(size 1.27 1.27)
				)
			)
		)
		(property "Value" ""
			(at 0 0 0)
			(layer "F.Fab")
			(effects
				(font
					(size 1.27 1.27)
				)
			)
		)
		(duplicate_pad_numbers_are_jumpers no)
		(fp_line
			(start -0.32512 -0.175006)
			(end 0.32512 -0.175006)
			(stroke
				(width 0.1)
				(type default)
			)
			(layer "F.Fab")
		)
		(fp_line
			(start -0.32512 0.175006)
			(end -0.32512 -0.175006)
			(stroke
				(width 0.1)
				(type default)
			)
			(layer "F.Fab")
		)
		(fp_line
			(start 0.32512 -0.175006)
			(end 0.32512 0.175006)
			(stroke
				(width 0.1)
				(type default)
			)
			(layer "F.Fab")
		)
		(fp_line
			(start 0.32512 0.175006)
			(end -0.32512 0.175006)
			(stroke
				(width 0.1)
				(type default)
			)
			(layer "F.Fab")
		)
		(pad "1" smd rect
			(at -0.2667 0)
			(size 0.3048 0.381)
			(layers "F.Cu" "F.Mask" "F.Paste")
			(net "P1V8_CPU1_RT_1D")
		)
		(pad "2" smd rect
			(at 0.2667 0 180)
			(size 0.3048 0.381)
			(layers "F.Cu" "F.Mask" "F.Paste")
			(net "TEST2_RT_CPU1_P0")
		)
	)
	(footprint ""
		(layer "F.Cu")
		(at 329.877928 -137.575036 180)
		(property "Reference" "C674"
			(at 0 0 180)
			(layer "F.SilkS")
			(hide yes)
			(effects
				(font
					(size 1.27 1.27)
				)
			)
		)
		(property "Value" ""
			(at 0 0 180)
			(layer "F.Fab")
			(effects
				(font
					(size 1.27 1.27)
				)
			)
		)
		(duplicate_pad_numbers_are_jumpers no)
		(fp_line
			(start 0.7874 0.4064)
			(end -0.7874 0.4064)
			(stroke
				(width 0.1524)
				(type default)
			)
			(layer "F.SilkS")
		)
		(fp_line
			(start 0.7874 -0.4064)
			(end 0.7874 0.4064)
			(stroke
				(width 0.1524)
				(type default)
			)
			(layer "F.SilkS")
		)
		(fp_line
			(start -0.7874 0.4064)
			(end -0.7874 -0.4064)
			(stroke
				(width 0.1524)
				(type default)
			)
			(layer "F.SilkS")
		)
		(fp_line
			(start -0.7874 -0.4064)
			(end 0.7874 -0.4064)
			(stroke
				(width 0.1524)
				(type default)
			)
			(layer "F.SilkS")
		)
		(fp_line
			(start 0.67945 0.3048)
			(end 0.120396 0.3048)
			(stroke
				(width 0.1)
				(type default)
			)
			(layer "F.Fab")
		)
		(fp_line
			(start 0.67945 -0.3048)
			(end 0.67945 0.3048)
			(stroke
				(width 0.1)
				(type default)
			)
			(layer "F.Fab")
		)
		(fp_line
			(start 0.12065 -0.2794)
			(end 0.12065 -0.3048)
			(stroke
				(width 0.1)
				(type default)
			)
			(layer "F.Fab")
		)
		(fp_line
			(start 0.12065 -0.3048)
			(end 0.67945 -0.3048)
			(stroke
				(width 0.1)
				(type default)
			)
			(layer "F.Fab")
		)
		(fp_line
			(start 0.120396 0.3048)
			(end 0.120396 0.2794)
			(stroke
				(width 0.1)
				(type default)
			)
			(layer "F.Fab")
		)
		(fp_line
			(start 0.120396 0.2794)
			(end -0.12065 0.2794)
			(stroke
				(width 0.1)
				(type default)
			)
			(layer "F.Fab")
		)
		(fp_line
			(start -0.12065 0.3048)
			(end -0.67945 0.3048)
			(stroke
				(width 0.1)
				(type default)
			)
			(layer "F.Fab")
		)
		(fp_line
			(start -0.12065 0.2794)
			(end -0.12065 0.3048)
			(stroke
				(width 0.1)
				(type default)
			)
			(layer "F.Fab")
		)
		(fp_line
			(start -0.12065 -0.2794)
			(end 0.12065 -0.2794)
			(stroke
				(width 0.1)
				(type default)
			)
			(layer "F.Fab")
		)
		(fp_line
			(start -0.12065 -0.305054)
			(end -0.12065 -0.2794)
			(stroke
				(width 0.1)
				(type default)
			)
			(layer "F.Fab")
		)
		(fp_line
			(start -0.67945 0.3048)
			(end -0.67945 -0.305054)
			(stroke
				(width 0.1)
				(type default)
			)
			(layer "F.Fab")
		)
		(fp_line
			(start -0.67945 -0.305054)
			(end -0.12065 -0.305054)
			(stroke
				(width 0.1)
				(type default)
			)
			(layer "F.Fab")
		)
		(pad "1" smd circle
			(at -0.40005 0 180)
			(size 0 0)
			(layers "F.Cu" "F.Mask" "F.Paste")
			(net "PVDD18_S5_P0_EN")
		)
		(pad "2" smd circle
			(at 0.40005 0 180)
			(size 0 0)
			(layers "F.Cu" "F.Mask" "F.Paste")
			(net "GND")
		)
	)
	(footprint ""
		(layer "F.Cu")
		(at 37.40658 -116.23802 90)
		(property "Reference" "Q7001"
			(at -2.4384 -3.292348 90)
			(unlocked yes)
			(layer "F.SilkS")
			(effects
				(font
					(size 0.7874 0.5842)
					(thickness 0.1524)
				)
				(justify left)
			)
		)
		(property "Value" ""
			(at 0 0 90)
			(layer "F.Fab")
			(effects
				(font
					(size 1.27 1.27)
				)
			)
		)
		(duplicate_pad_numbers_are_jumpers no)
		(fp_line
			(start 2.350008 -2.649982)
			(end 2.350008 -2.4892)
			(stroke
				(width 0.1524)
				(type default)
			)
			(layer "F.SilkS")
		)
		(fp_line
			(start -2.350008 -2.649982)
			(end 2.350008 -2.649982)
			(stroke
				(width 0.1524)
				(type default)
			)
			(layer "F.SilkS")
		)
		(fp_line
			(start -2.350008 -2.4384)
			(end -2.350008 -2.649982)
			(stroke
				(width 0.1524)
				(type default)
			)
			(layer "F.SilkS")
		)
		(fp_line
			(start 2.350008 2.4892)
			(end 2.350008 2.649982)
			(stroke
				(width 0.1524)
				(type default)
			)
			(layer "F.SilkS")
		)
		(fp_line
			(start 2.350008 2.649982)
			(end -2.350008 2.649982)
			(stroke
				(width 0.1524)
				(type default)
			)
			(layer "F.SilkS")
		)
		(fp_line
			(start -2.350008 2.649982)
			(end -2.350008 2.413)
			(stroke
				(width 0.1524)
				(type default)
			)
			(layer "F.SilkS")
		)
		(fp_poly
			(pts
				(xy -3.717544 -1.905) (xy -4.758944 -2.3241) (xy -4.758944 -1.524)
			)
			(stroke
				(width 0)
				(type default)
			)
			(fill yes)
			(layer "F.SilkS")
		)
		(fp_line
			(start 2.350008 -2.649982)
			(end 2.350008 2.649982)
			(stroke
				(width 0.1)
				(type default)
			)
			(layer "F.Fab")
		)
		(fp_line
			(start -2.350008 -2.649982)
			(end 2.350008 -2.649982)
			(stroke
				(width 0.1)
				(type default)
			)
			(layer "F.Fab")
		)
		(fp_line
			(start 2.350008 2.649982)
			(end -2.350008 2.649982)
			(stroke
				(width 0.1)
				(type default)
			)
			(layer "F.Fab")
		)
		(fp_line
			(start -2.350008 2.649982)
			(end -2.350008 -2.649982)
			(stroke
				(width 0.1)
				(type default)
			)
			(layer "F.Fab")
		)
		(fp_poly
			(pts
				(xy -3.717544 -1.905) (xy -4.758944 -2.3241) (xy -4.758944 -1.524)
			)
			(stroke
				(width 0)
				(type default)
			)
			(fill yes)
			(layer "F.Fab")
		)
		(pad "1" smd rect
			(at -2.999994 -1.905)
			(size 0.7112 1.1684)
			(layers "F.Cu" "F.Mask" "F.Paste")
			(net "GND")
		)
		(pad "2" smd rect
			(at -2.999994 -0.635)
			(size 0.7112 1.1684)
			(layers "F.Cu" "F.Mask" "F.Paste")
			(net "GND")
		)
		(pad "3" smd rect
			(at -2.999994 0.635)
			(size 0.7112 1.1684)
			(layers "F.Cu" "F.Mask" "F.Paste")
			(net "GND")
		)
		(pad "4" smd rect
			(at -2.999994 1.905)
			(size 0.7112 1.1684)
			(layers "F.Cu" "F.Mask" "F.Paste")
			(net "P12V_AUX_DSC_G2")
		)
		(pad "5" smd circle
			(at 0.925068 0)
			(size 0 0)
			(layers "F.Cu" "F.Mask" "F.Paste")
			(net "P12V_AUX_DSC")
		)
		(zone
			(layer "F.Cu")
			(hatch none 0.5)
			(connect_pads
				(clearance 0)
			)
			(min_thickness 0.25)
			(keepout
				(tracks not_allowed)
				(vias allowed)
				(pads allowed)
				(copperpour not_allowed)
				(footprints allowed)
			)
			(placement
				(enabled no)
				(sheetname "")
			)
			(fill
				(thermal_gap 0.5)
				(thermal_bridge_width 0.5)
				(island_removal_mode 0)
			)
			(polygon
				(pts
					(xy 34.76498 -118.57482) (xy 34.99358 -118.57482) (xy 34.99358 -117.88902) (xy 35.24758 -117.88902)
					(xy 35.24758 -114.79022) (xy 39.56558 -114.79022) (xy 39.56558 -117.88902) (xy 39.81958 -117.88902)
					(xy 39.81958 -118.57482) (xy 40.04818 -118.57482) (xy 40.04818 -113.88852) (xy 34.76498 -113.88852)
				)
			)
		)
	)
	(footprint ""
		(layer "F.Cu")
		(at 144.690592 -107.683046 180)
		(property "Reference" "Q37"
			(at 0.715264 1.685036 0)
			(unlocked yes)
			(layer "F.SilkS")
			(effects
				(font
					(size 0.7874 0.5842)
					(thickness 0.1524)
				)
				(justify left)
			)
		)
		(property "Value" ""
			(at 0 0 180)
			(layer "F.Fab")
			(effects
				(font
					(size 1.27 1.27)
				)
			)
		)
		(duplicate_pad_numbers_are_jumpers no)
		(fp_line
			(start 1.332738 1.100074)
			(end -1.332738 1.100074)
			(stroke
				(width 0.1524)
				(type default)
			)
			(layer "F.SilkS")
		)
		(fp_line
			(start 1.332738 -1.100074)
			(end 1.332738 1.100074)
			(stroke
				(width 0.1524)
				(type default)
			)
			(layer "F.SilkS")
		)
		(fp_line
			(start 0.4826 -1.100074)
			(end 1.332738 -1.100074)
			(stroke
				(width 0.1524)
				(type default)
			)
			(layer "F.SilkS")
		)
		(fp_line
			(start 0 -0.541274)
			(end 0.4826 -1.100074)
			(stroke
				(width 0.1524)
				(type default)
			)
			(layer "F.SilkS")
		)
		(fp_line
			(start -0.4826 -1.100074)
			(end 0 -0.541274)
			(stroke
				(width 0.1524)
				(type default)
			)
			(layer "F.SilkS")
		)
		(fp_line
			(start -1.332738 1.100074)
			(end -1.332738 -1.100074)
			(stroke
				(width 0.1524)
				(type default)
			)
			(layer "F.SilkS")
		)
		(fp_line
			(start -1.332738 -1.100074)
			(end -0.4826 -1.100074)
			(stroke
				(width 0.1524)
				(type default)
			)
			(layer "F.SilkS")
		)
		(fp_poly
			(pts
				(xy -1.928876 -0.667512) (xy -2.630932 -0.316484) (xy -2.630932 -1.01854)
			)
			(stroke
				(width 0)
				(type default)
			)
			(fill yes)
			(layer "F.SilkS")
		)
		(fp_line
			(start 0.674878 1.100074)
			(end -0.674878 1.100074)
			(stroke
				(width 0.1)
				(type default)
			)
			(layer "F.Fab")
		)
		(fp_line
			(start 0.674878 -1.100074)
			(end 0.674878 1.100074)
			(stroke
				(width 0.1)
				(type default)
			)
			(layer "F.Fab")
		)
		(fp_line
			(start -0.674878 1.100074)
			(end -0.674878 -1.100074)
			(stroke
				(width 0.1)
				(type default)
			)
			(layer "F.Fab")
		)
		(fp_line
			(start -0.674878 -1.100074)
			(end 0.674878 -1.100074)
			(stroke
				(width 0.1)
				(type default)
			)
			(layer "F.Fab")
		)
		(fp_poly
			(pts
				(xy -2.2352 -0.298958) (xy -2.2352 -1.001014) (xy -1.533144 -0.649986)
			)
			(stroke
				(width 0)
				(type default)
			)
			(fill yes)
			(layer "F.Fab")
		)
		(pad "1" smd rect
			(at -0.94996 -0.649986 270)
			(size 0.4318 0.508)
			(layers "F.Cu" "F.Mask" "F.Paste")
			(net "GND")
		)
		(pad "2" smd rect
			(at -0.94996 0 270)
			(size 0.4318 0.508)
			(layers "F.Cu" "F.Mask" "F.Paste")
			(net "VR_P5V_EN")
		)
		(pad "3" smd rect
			(at -0.94996 0.649986 270)
			(size 0.4318 0.508)
			(layers "F.Cu" "F.Mask" "F.Paste")
			(net "VR_P5V_EN_D_R1")
		)
		(pad "4" smd rect
			(at 0.94996 0.649986 270)
			(size 0.4318 0.508)
			(layers "F.Cu" "F.Mask" "F.Paste")
			(net "GND")
		)
		(pad "5" smd rect
			(at 0.94996 0 270)
			(size 0.4318 0.508)
			(layers "F.Cu" "F.Mask" "F.Paste")
			(net "VR_P5V_EN_N")
		)
		(pad "6" smd rect
			(at 0.94996 -0.649986 270)
			(size 0.4318 0.508)
			(layers "F.Cu" "F.Mask" "F.Paste")
			(net "VR_P5V_EN_N")
		)
	)
	(footprint ""
		(layer "F.Cu")
		(at 402.253958 -324.862952 180)
		(property "Reference" "R461"
			(at 0 0 180)
			(layer "F.SilkS")
			(hide yes)
			(effects
				(font
					(size 1.27 1.27)
				)
			)
		)
		(property "Value" ""
			(at 0 0 180)
			(layer "F.Fab")
			(effects
				(font
					(size 1.27 1.27)
				)
			)
		)
		(duplicate_pad_numbers_are_jumpers no)
		(fp_line
			(start 0.7874 0.4064)
			(end -0.7874 0.4064)
			(stroke
				(width 0.1524)
				(type default)
			)
			(layer "F.SilkS")
		)
		(fp_line
			(start 0.7874 -0.4064)
			(end 0.7874 0.4064)
			(stroke
				(width 0.1524)
				(type default)
			)
			(layer "F.SilkS")
		)
		(fp_line
			(start -0.7874 0.4064)
			(end -0.7874 -0.4064)
			(stroke
				(width 0.1524)
				(type default)
			)
			(layer "F.SilkS")
		)
		(fp_line
			(start -0.7874 -0.4064)
			(end 0.7874 -0.4064)
			(stroke
				(width 0.1524)
				(type default)
			)
			(layer "F.SilkS")
		)
		(fp_line
			(start 0.67945 0.3048)
			(end 0.120396 0.3048)
			(stroke
				(width 0.1)
				(type default)
			)
			(layer "F.Fab")
		)
		(fp_line
			(start 0.67945 -0.3048)
			(end 0.67945 0.3048)
			(stroke
				(width 0.1)
				(type default)
			)
			(layer "F.Fab")
		)
		(fp_line
			(start 0.12065 -0.2794)
			(end 0.12065 -0.3048)
			(stroke
				(width 0.1)
				(type default)
			)
			(layer "F.Fab")
		)
		(fp_line
			(start 0.12065 -0.3048)
			(end 0.67945 -0.3048)
			(stroke
				(width 0.1)
				(type default)
			)
			(layer "F.Fab")
		)
		(fp_line
			(start 0.120396 0.3048)
			(end 0.120396 0.2794)
			(stroke
				(width 0.1)
				(type default)
			)
			(layer "F.Fab")
		)
		(fp_line
			(start 0.120396 0.2794)
			(end -0.12065 0.2794)
			(stroke
				(width 0.1)
				(type default)
			)
			(layer "F.Fab")
		)
		(fp_line
			(start -0.12065 0.3048)
			(end -0.67945 0.3048)
			(stroke
				(width 0.1)
				(type default)
			)
			(layer "F.Fab")
		)
		(fp_line
			(start -0.12065 0.2794)
			(end -0.12065 0.3048)
			(stroke
				(width 0.1)
				(type default)
			)
			(layer "F.Fab")
		)
		(fp_line
			(start -0.12065 -0.2794)
			(end 0.12065 -0.2794)
			(stroke
				(width 0.1)
				(type default)
			)
			(layer "F.Fab")
		)
		(fp_line
			(start -0.12065 -0.305054)
			(end -0.12065 -0.2794)
			(stroke
				(width 0.1)
				(type default)
			)
			(layer "F.Fab")
		)
		(fp_line
			(start -0.67945 0.3048)
			(end -0.67945 -0.305054)
			(stroke
				(width 0.1)
				(type default)
			)
			(layer "F.Fab")
		)
		(fp_line
			(start -0.67945 -0.305054)
			(end -0.12065 -0.305054)
			(stroke
				(width 0.1)
				(type default)
			)
			(layer "F.Fab")
		)
		(pad "1" smd circle
			(at -0.40005 0 180)
			(size 0 0)
			(layers "F.Cu" "F.Mask" "F.Paste")
			(net "SPI_CPU0_CLK")
		)
		(pad "2" smd circle
			(at 0.40005 0 180)
			(size 0 0)
			(layers "F.Cu" "F.Mask" "F.Paste")
			(net "SPI_CPU0_R_CLK")
		)
	)
	(footprint ""
		(layer "F.Cu")
		(at 432.151536 -101.97719)
		(property "Reference" "R3796"
			(at 0 0 0)
			(layer "F.SilkS")
			(hide yes)
			(effects
				(font
					(size 1.27 1.27)
				)
			)
		)
		(property "Value" ""
			(at 0 0 0)
			(layer "F.Fab")
			(effects
				(font
					(size 1.27 1.27)
				)
			)
		)
		(duplicate_pad_numbers_are_jumpers no)
		(fp_line
			(start -0.7874 -0.4064)
			(end 0.7874 -0.4064)
			(stroke
				(width 0.1524)
				(type default)
			)
			(layer "F.SilkS")
		)
		(fp_line
			(start -0.7874 0.4064)
			(end -0.7874 -0.4064)
			(stroke
				(width 0.1524)
				(type default)
			)
			(layer "F.SilkS")
		)
		(fp_line
			(start 0.7874 -0.4064)
			(end 0.7874 0.4064)
			(stroke
				(width 0.1524)
				(type default)
			)
			(layer "F.SilkS")
		)
		(fp_line
			(start 0.7874 0.4064)
			(end -0.7874 0.4064)
			(stroke
				(width 0.1524)
				(type default)
			)
			(layer "F.SilkS")
		)
		(fp_line
			(start -0.67945 -0.305054)
			(end -0.12065 -0.305054)
			(stroke
				(width 0.1)
				(type default)
			)
			(layer "F.Fab")
		)
		(fp_line
			(start -0.67945 0.3048)
			(end -0.67945 -0.305054)
			(stroke
				(width 0.1)
				(type default)
			)
			(layer "F.Fab")
		)
		(fp_line
			(start -0.12065 -0.305054)
			(end -0.12065 -0.2794)
			(stroke
				(width 0.1)
				(type default)
			)
			(layer "F.Fab")
		)
		(fp_line
			(start -0.12065 -0.2794)
			(end 0.12065 -0.2794)
			(stroke
				(width 0.1)
				(type default)
			)
			(layer "F.Fab")
		)
		(fp_line
			(start -0.12065 0.2794)
			(end -0.12065 0.3048)
			(stroke
				(width 0.1)
				(type default)
			)
			(layer "F.Fab")
		)
		(fp_line
			(start -0.12065 0.3048)
			(end -0.67945 0.3048)
			(stroke
				(width 0.1)
				(type default)
			)
			(layer "F.Fab")
		)
		(fp_line
			(start 0.120396 0.2794)
			(end -0.12065 0.2794)
			(stroke
				(width 0.1)
				(type default)
			)
			(layer "F.Fab")
		)
		(fp_line
			(start 0.120396 0.3048)
			(end 0.120396 0.2794)
			(stroke
				(width 0.1)
				(type default)
			)
			(layer "F.Fab")
		)
		(fp_line
			(start 0.12065 -0.3048)
			(end 0.67945 -0.3048)
			(stroke
				(width 0.1)
				(type default)
			)
			(layer "F.Fab")
		)
		(fp_line
			(start 0.12065 -0.2794)
			(end 0.12065 -0.3048)
			(stroke
				(width 0.1)
				(type default)
			)
			(layer "F.Fab")
		)
		(fp_line
			(start 0.67945 -0.3048)
			(end 0.67945 0.3048)
			(stroke
				(width 0.1)
				(type default)
			)
			(layer "F.Fab")
		)
		(fp_line
			(start 0.67945 0.3048)
			(end 0.120396 0.3048)
			(stroke
				(width 0.1)
				(type default)
			)
			(layer "F.Fab")
		)
		(pad "1" smd circle
			(at -0.40005 0)
			(size 0 0)
			(layers "F.Cu" "F.Mask" "F.Paste")
			(net "P3V3_AUX")
		)
		(pad "2" smd circle
			(at 0.40005 0)
			(size 0 0)
			(layers "F.Cu" "F.Mask" "F.Paste")
			(net "P3V3_OCP_FAULT_1")
		)
	)
	(footprint ""
		(layer "F.Cu")
		(at 117.895624 -255.555242 180)
		(property "Reference" "C2283"
			(at 0 0 180)
			(layer "F.SilkS")
			(hide yes)
			(effects
				(font
					(size 1.27 1.27)
				)
			)
		)
		(property "Value" ""
			(at 0 0 180)
			(layer "F.Fab")
			(effects
				(font
					(size 1.27 1.27)
				)
			)
		)
		(duplicate_pad_numbers_are_jumpers no)
		(fp_line
			(start 0.7874 0.4064)
			(end -0.7874 0.4064)
			(stroke
				(width 0.1524)
				(type default)
			)
			(layer "F.SilkS")
		)
		(fp_line
			(start 0.7874 -0.4064)
			(end 0.7874 0.4064)
			(stroke
				(width 0.1524)
				(type default)
			)
			(layer "F.SilkS")
		)
		(fp_line
			(start -0.7874 0.4064)
			(end -0.7874 -0.4064)
			(stroke
				(width 0.1524)
				(type default)
			)
			(layer "F.SilkS")
		)
		(fp_line
			(start -0.7874 -0.4064)
			(end 0.7874 -0.4064)
			(stroke
				(width 0.1524)
				(type default)
			)
			(layer "F.SilkS")
		)
		(fp_line
			(start 0.67945 0.3048)
			(end 0.120396 0.3048)
			(stroke
				(width 0.1)
				(type default)
			)
			(layer "F.Fab")
		)
		(fp_line
			(start 0.67945 -0.3048)
			(end 0.67945 0.3048)
			(stroke
				(width 0.1)
				(type default)
			)
			(layer "F.Fab")
		)
		(fp_line
			(start 0.12065 -0.2794)
			(end 0.12065 -0.3048)
			(stroke
				(width 0.1)
				(type default)
			)
			(layer "F.Fab")
		)
		(fp_line
			(start 0.12065 -0.3048)
			(end 0.67945 -0.3048)
			(stroke
				(width 0.1)
				(type default)
			)
			(layer "F.Fab")
		)
		(fp_line
			(start 0.120396 0.3048)
			(end 0.120396 0.2794)
			(stroke
				(width 0.1)
				(type default)
			)
			(layer "F.Fab")
		)
		(fp_line
			(start 0.120396 0.2794)
			(end -0.12065 0.2794)
			(stroke
				(width 0.1)
				(type default)
			)
			(layer "F.Fab")
		)
		(fp_line
			(start -0.12065 0.3048)
			(end -0.67945 0.3048)
			(stroke
				(width 0.1)
				(type default)
			)
			(layer "F.Fab")
		)
		(fp_line
			(start -0.12065 0.2794)
			(end -0.12065 0.3048)
			(stroke
				(width 0.1)
				(type default)
			)
			(layer "F.Fab")
		)
		(fp_line
			(start -0.12065 -0.2794)
			(end 0.12065 -0.2794)
			(stroke
				(width 0.1)
				(type default)
			)
			(layer "F.Fab")
		)
		(fp_line
			(start -0.12065 -0.305054)
			(end -0.12065 -0.2794)
			(stroke
				(width 0.1)
				(type default)
			)
			(layer "F.Fab")
		)
		(fp_line
			(start -0.67945 0.3048)
			(end -0.67945 -0.305054)
			(stroke
				(width 0.1)
				(type default)
			)
			(layer "F.Fab")
		)
		(fp_line
			(start -0.67945 -0.305054)
			(end -0.12065 -0.305054)
			(stroke
				(width 0.1)
				(type default)
			)
			(layer "F.Fab")
		)
		(pad "1" smd circle
			(at -0.40005 0 180)
			(size 0 0)
			(layers "F.Cu" "F.Mask" "F.Paste")
			(net "PVDDCR_SOC_P1")
		)
		(pad "2" smd circle
			(at 0.40005 0 180)
			(size 0 0)
			(layers "F.Cu" "F.Mask" "F.Paste")
			(net "GND")
		)
	)
	(footprint ""
		(layer "F.Cu")
		(at 368.600736 -402.548852 -90)
		(property "Reference" "R1091"
			(at 0 0 270)
			(layer "F.SilkS")
			(hide yes)
			(effects
				(font
					(size 1.27 1.27)
				)
			)
		)
		(property "Value" ""
			(at 0 0 270)
			(layer "F.Fab")
			(effects
				(font
					(size 1.27 1.27)
				)
			)
		)
		(duplicate_pad_numbers_are_jumpers no)
		(fp_line
			(start -0.32512 0.175006)
			(end -0.32512 -0.175006)
			(stroke
				(width 0.1)
				(type default)
			)
			(layer "F.Fab")
		)
		(fp_line
			(start 0.32512 0.175006)
			(end -0.32512 0.175006)
			(stroke
				(width 0.1)
				(type default)
			)
			(layer "F.Fab")
		)
		(fp_line
			(start -0.32512 -0.175006)
			(end 0.32512 -0.175006)
			(stroke
				(width 0.1)
				(type default)
			)
			(layer "F.Fab")
		)
		(fp_line
			(start 0.32512 -0.175006)
			(end 0.32512 0.175006)
			(stroke
				(width 0.1)
				(type default)
			)
			(layer "F.Fab")
		)
		(pad "1" smd rect
			(at -0.2667 0 270)
			(size 0.3048 0.381)
			(layers "F.Cu" "F.Mask" "F.Paste")
			(net "MODE_RT_CPU0_P3")
		)
		(pad "2" smd rect
			(at 0.2667 0 90)
			(size 0.3048 0.381)
			(layers "F.Cu" "F.Mask" "F.Paste")
			(net "GND")
		)
	)
	(footprint ""
		(layer "F.Cu")
		(at 147.199096 -66.337434)
		(property "Reference" "R8"
			(at 0 0 0)
			(layer "F.SilkS")
			(hide yes)
			(effects
				(font
					(size 1.27 1.27)
				)
			)
		)
		(property "Value" ""
			(at 0 0 0)
			(layer "F.Fab")
			(effects
				(font
					(size 1.27 1.27)
				)
			)
		)
		(duplicate_pad_numbers_are_jumpers no)
		(fp_line
			(start -0.7874 -0.4064)
			(end 0.7874 -0.4064)
			(stroke
				(width 0.1524)
				(type default)
			)
			(layer "F.SilkS")
		)
		(fp_line
			(start -0.7874 0.4064)
			(end -0.7874 -0.4064)
			(stroke
				(width 0.1524)
				(type default)
			)
			(layer "F.SilkS")
		)
		(fp_line
			(start 0.7874 -0.4064)
			(end 0.7874 0.4064)
			(stroke
				(width 0.1524)
				(type default)
			)
			(layer "F.SilkS")
		)
		(fp_line
			(start 0.7874 0.4064)
			(end -0.7874 0.4064)
			(stroke
				(width 0.1524)
				(type default)
			)
			(layer "F.SilkS")
		)
		(fp_line
			(start -0.67945 -0.305054)
			(end -0.12065 -0.305054)
			(stroke
				(width 0.1)
				(type default)
			)
			(layer "F.Fab")
		)
		(fp_line
			(start -0.67945 0.3048)
			(end -0.67945 -0.305054)
			(stroke
				(width 0.1)
				(type default)
			)
			(layer "F.Fab")
		)
		(fp_line
			(start -0.12065 -0.305054)
			(end -0.12065 -0.2794)
			(stroke
				(width 0.1)
				(type default)
			)
			(layer "F.Fab")
		)
		(fp_line
			(start -0.12065 -0.2794)
			(end 0.12065 -0.2794)
			(stroke
				(width 0.1)
				(type default)
			)
			(layer "F.Fab")
		)
		(fp_line
			(start -0.12065 0.2794)
			(end -0.12065 0.3048)
			(stroke
				(width 0.1)
				(type default)
			)
			(layer "F.Fab")
		)
		(fp_line
			(start -0.12065 0.3048)
			(end -0.67945 0.3048)
			(stroke
				(width 0.1)
				(type default)
			)
			(layer "F.Fab")
		)
		(fp_line
			(start 0.120396 0.2794)
			(end -0.12065 0.2794)
			(stroke
				(width 0.1)
				(type default)
			)
			(layer "F.Fab")
		)
		(fp_line
			(start 0.120396 0.3048)
			(end 0.120396 0.2794)
			(stroke
				(width 0.1)
				(type default)
			)
			(layer "F.Fab")
		)
		(fp_line
			(start 0.12065 -0.3048)
			(end 0.67945 -0.3048)
			(stroke
				(width 0.1)
				(type default)
			)
			(layer "F.Fab")
		)
		(fp_line
			(start 0.12065 -0.2794)
			(end 0.12065 -0.3048)
			(stroke
				(width 0.1)
				(type default)
			)
			(layer "F.Fab")
		)
		(fp_line
			(start 0.67945 -0.3048)
			(end 0.67945 0.3048)
			(stroke
				(width 0.1)
				(type default)
			)
			(layer "F.Fab")
		)
		(fp_line
			(start 0.67945 0.3048)
			(end 0.120396 0.3048)
			(stroke
				(width 0.1)
				(type default)
			)
			(layer "F.Fab")
		)
		(pad "1" smd circle
			(at -0.40005 0)
			(size 0 0)
			(layers "F.Cu" "F.Mask" "F.Paste")
			(net "GND")
		)
		(pad "2" smd circle
			(at 0.40005 0)
			(size 0 0)
			(layers "F.Cu" "F.Mask" "F.Paste")
			(net "JTAG_BMC_OE")
		)
	)
	(footprint ""
		(layer "F.Cu")
		(at 48.478694 -32.277558 90)
		(property "Reference" "C1825"
			(at 0 0 90)
			(layer "F.SilkS")
			(hide yes)
			(effects
				(font
					(size 1.27 1.27)
				)
			)
		)
		(property "Value" ""
			(at 0 0 90)
			(layer "F.Fab")
			(effects
				(font
					(size 1.27 1.27)
				)
			)
		)
		(duplicate_pad_numbers_are_jumpers no)
		(fp_line
			(start 0.7874 -0.4064)
			(end 0.7874 0.4064)
			(stroke
				(width 0.1524)
				(type default)
			)
			(layer "F.SilkS")
		)
		(fp_line
			(start -0.7874 -0.4064)
			(end 0.7874 -0.4064)
			(stroke
				(width 0.1524)
				(type default)
			)
			(layer "F.SilkS")
		)
		(fp_line
			(start 0.7874 0.4064)
			(end -0.7874 0.4064)
			(stroke
				(width 0.1524)
				(type default)
			)
			(layer "F.SilkS")
		)
		(fp_line
			(start -0.7874 0.4064)
			(end -0.7874 -0.4064)
			(stroke
				(width 0.1524)
				(type default)
			)
			(layer "F.SilkS")
		)
		(fp_line
			(start -0.12065 -0.305054)
			(end -0.12065 -0.2794)
			(stroke
				(width 0.1)
				(type default)
			)
			(layer "F.Fab")
		)
		(fp_line
			(start -0.67945 -0.305054)
			(end -0.12065 -0.305054)
			(stroke
				(width 0.1)
				(type default)
			)
			(layer "F.Fab")
		)
		(fp_line
			(start 0.67945 -0.3048)
			(end 0.67945 0.3048)
			(stroke
				(width 0.1)
				(type default)
			)
			(layer "F.Fab")
		)
		(fp_line
			(start 0.12065 -0.3048)
			(end 0.67945 -0.3048)
			(stroke
				(width 0.1)
				(type default)
			)
			(layer "F.Fab")
		)
		(fp_line
			(start 0.12065 -0.2794)
			(end 0.12065 -0.3048)
			(stroke
				(width 0.1)
				(type default)
			)
			(layer "F.Fab")
		)
		(fp_line
			(start -0.12065 -0.2794)
			(end 0.12065 -0.2794)
			(stroke
				(width 0.1)
				(type default)
			)
			(layer "F.Fab")
		)
		(fp_line
			(start 0.120396 0.2794)
			(end -0.12065 0.2794)
			(stroke
				(width 0.1)
				(type default)
			)
			(layer "F.Fab")
		)
		(fp_line
			(start -0.12065 0.2794)
			(end -0.12065 0.3048)
			(stroke
				(width 0.1)
				(type default)
			)
			(layer "F.Fab")
		)
		(fp_line
			(start 0.67945 0.3048)
			(end 0.120396 0.3048)
			(stroke
				(width 0.1)
				(type default)
			)
			(layer "F.Fab")
		)
		(fp_line
			(start 0.120396 0.3048)
			(end 0.120396 0.2794)
			(stroke
				(width 0.1)
				(type default)
			)
			(layer "F.Fab")
		)
		(fp_line
			(start -0.12065 0.3048)
			(end -0.67945 0.3048)
			(stroke
				(width 0.1)
				(type default)
			)
			(layer "F.Fab")
		)
		(fp_line
			(start -0.67945 0.3048)
			(end -0.67945 -0.305054)
			(stroke
				(width 0.1)
				(type default)
			)
			(layer "F.Fab")
		)
		(pad "1" smd circle
			(at -0.40005 0 90)
			(size 0 0)
			(layers "F.Cu" "F.Mask" "F.Paste")
			(net "P3V3_AUX")
		)
		(pad "2" smd circle
			(at 0.40005 0 90)
			(size 0 0)
			(layers "F.Cu" "F.Mask" "F.Paste")
			(net "GND")
		)
	)
	(footprint ""
		(layer "F.Cu")
		(at 192.913 -96.103948 90)
		(property "Reference" "R391"
			(at 0 0 90)
			(layer "F.SilkS")
			(hide yes)
			(effects
				(font
					(size 1.27 1.27)
				)
			)
		)
		(property "Value" ""
			(at 0 0 90)
			(layer "F.Fab")
			(effects
				(font
					(size 1.27 1.27)
				)
			)
		)
		(duplicate_pad_numbers_are_jumpers no)
		(fp_line
			(start 0.7874 -0.4064)
			(end 0.7874 0.4064)
			(stroke
				(width 0.1524)
				(type default)
			)
			(layer "F.SilkS")
		)
		(fp_line
			(start -0.7874 -0.4064)
			(end 0.7874 -0.4064)
			(stroke
				(width 0.1524)
				(type default)
			)
			(layer "F.SilkS")
		)
		(fp_line
			(start 0.7874 0.4064)
			(end -0.7874 0.4064)
			(stroke
				(width 0.1524)
				(type default)
			)
			(layer "F.SilkS")
		)
		(fp_line
			(start -0.7874 0.4064)
			(end -0.7874 -0.4064)
			(stroke
				(width 0.1524)
				(type default)
			)
			(layer "F.SilkS")
		)
		(fp_line
			(start -0.12065 -0.305054)
			(end -0.12065 -0.2794)
			(stroke
				(width 0.1)
				(type default)
			)
			(layer "F.Fab")
		)
		(fp_line
			(start -0.67945 -0.305054)
			(end -0.12065 -0.305054)
			(stroke
				(width 0.1)
				(type default)
			)
			(layer "F.Fab")
		)
		(fp_line
			(start 0.67945 -0.3048)
			(end 0.67945 0.3048)
			(stroke
				(width 0.1)
				(type default)
			)
			(layer "F.Fab")
		)
		(fp_line
			(start 0.12065 -0.3048)
			(end 0.67945 -0.3048)
			(stroke
				(width 0.1)
				(type default)
			)
			(layer "F.Fab")
		)
		(fp_line
			(start 0.12065 -0.2794)
			(end 0.12065 -0.3048)
			(stroke
				(width 0.1)
				(type default)
			)
			(layer "F.Fab")
		)
		(fp_line
			(start -0.12065 -0.2794)
			(end 0.12065 -0.2794)
			(stroke
				(width 0.1)
				(type default)
			)
			(layer "F.Fab")
		)
		(fp_line
			(start 0.120396 0.2794)
			(end -0.12065 0.2794)
			(stroke
				(width 0.1)
				(type default)
			)
			(layer "F.Fab")
		)
		(fp_line
			(start -0.12065 0.2794)
			(end -0.12065 0.3048)
			(stroke
				(width 0.1)
				(type default)
			)
			(layer "F.Fab")
		)
		(fp_line
			(start 0.67945 0.3048)
			(end 0.120396 0.3048)
			(stroke
				(width 0.1)
				(type default)
			)
			(layer "F.Fab")
		)
		(fp_line
			(start 0.120396 0.3048)
			(end 0.120396 0.2794)
			(stroke
				(width 0.1)
				(type default)
			)
			(layer "F.Fab")
		)
		(fp_line
			(start -0.12065 0.3048)
			(end -0.67945 0.3048)
			(stroke
				(width 0.1)
				(type default)
			)
			(layer "F.Fab")
		)
		(fp_line
			(start -0.67945 0.3048)
			(end -0.67945 -0.305054)
			(stroke
				(width 0.1)
				(type default)
			)
			(layer "F.Fab")
		)
		(pad "1" smd circle
			(at -0.40005 0 90)
			(size 0 0)
			(layers "F.Cu" "F.Mask" "F.Paste")
			(net "P3V3_AUX")
		)
		(pad "2" smd circle
			(at 0.40005 0 90)
			(size 0 0)
			(layers "F.Cu" "F.Mask" "F.Paste")
			(net "CPU0_SP5R3")
		)
	)
	(footprint ""
		(layer "F.Cu")
		(at 461.592168 -109.646212)
		(property "Reference" "R576"
			(at 0 0 0)
			(layer "F.SilkS")
			(hide yes)
			(effects
				(font
					(size 1.27 1.27)
				)
			)
		)
		(property "Value" ""
			(at 0 0 0)
			(layer "F.Fab")
			(effects
				(font
					(size 1.27 1.27)
				)
			)
		)
		(duplicate_pad_numbers_are_jumpers no)
		(fp_line
			(start -0.7874 -0.4064)
			(end 0.7874 -0.4064)
			(stroke
				(width 0.1524)
				(type default)
			)
			(layer "F.SilkS")
		)
		(fp_line
			(start -0.7874 0.4064)
			(end -0.7874 -0.4064)
			(stroke
				(width 0.1524)
				(type default)
			)
			(layer "F.SilkS")
		)
		(fp_line
			(start 0.7874 -0.4064)
			(end 0.7874 0.4064)
			(stroke
				(width 0.1524)
				(type default)
			)
			(layer "F.SilkS")
		)
		(fp_line
			(start 0.7874 0.4064)
			(end -0.7874 0.4064)
			(stroke
				(width 0.1524)
				(type default)
			)
			(layer "F.SilkS")
		)
		(fp_line
			(start -0.67945 -0.305054)
			(end -0.12065 -0.305054)
			(stroke
				(width 0.1)
				(type default)
			)
			(layer "F.Fab")
		)
		(fp_line
			(start -0.67945 0.3048)
			(end -0.67945 -0.305054)
			(stroke
				(width 0.1)
				(type default)
			)
			(layer "F.Fab")
		)
		(fp_line
			(start -0.12065 -0.305054)
			(end -0.12065 -0.2794)
			(stroke
				(width 0.1)
				(type default)
			)
			(layer "F.Fab")
		)
		(fp_line
			(start -0.12065 -0.2794)
			(end 0.12065 -0.2794)
			(stroke
				(width 0.1)
				(type default)
			)
			(layer "F.Fab")
		)
		(fp_line
			(start -0.12065 0.2794)
			(end -0.12065 0.3048)
			(stroke
				(width 0.1)
				(type default)
			)
			(layer "F.Fab")
		)
		(fp_line
			(start -0.12065 0.3048)
			(end -0.67945 0.3048)
			(stroke
				(width 0.1)
				(type default)
			)
			(layer "F.Fab")
		)
		(fp_line
			(start 0.120396 0.2794)
			(end -0.12065 0.2794)
			(stroke
				(width 0.1)
				(type default)
			)
			(layer "F.Fab")
		)
		(fp_line
			(start 0.120396 0.3048)
			(end 0.120396 0.2794)
			(stroke
				(width 0.1)
				(type default)
			)
			(layer "F.Fab")
		)
		(fp_line
			(start 0.12065 -0.3048)
			(end 0.67945 -0.3048)
			(stroke
				(width 0.1)
				(type default)
			)
			(layer "F.Fab")
		)
		(fp_line
			(start 0.12065 -0.2794)
			(end 0.12065 -0.3048)
			(stroke
				(width 0.1)
				(type default)
			)
			(layer "F.Fab")
		)
		(fp_line
			(start 0.67945 -0.3048)
			(end 0.67945 0.3048)
			(stroke
				(width 0.1)
				(type default)
			)
			(layer "F.Fab")
		)
		(fp_line
			(start 0.67945 0.3048)
			(end 0.120396 0.3048)
			(stroke
				(width 0.1)
				(type default)
			)
			(layer "F.Fab")
		)
		(pad "1" smd circle
			(at -0.40005 0)
			(size 0 0)
			(layers "F.Cu" "F.Mask" "F.Paste")
			(net "HP_LVC3_OCP_V3_1_PRSNT2_N_R")
		)
		(pad "2" smd circle
			(at 0.40005 0)
			(size 0 0)
			(layers "F.Cu" "F.Mask" "F.Paste")
			(net "HP_LVC3_OCP_SFF_PRSNT2_N")
		)
	)
	(footprint ""
		(layer "F.Cu")
		(at 83.428332 -331.97419 180)
		(property "Reference" "PC201"
			(at 0 0 180)
			(layer "F.SilkS")
			(hide yes)
			(effects
				(font
					(size 1.27 1.27)
				)
			)
		)
		(property "Value" ""
			(at 0 0 180)
			(layer "F.Fab")
			(effects
				(font
					(size 1.27 1.27)
				)
			)
		)
		(duplicate_pad_numbers_are_jumpers no)
		(fp_line
			(start 0.7874 0.4064)
			(end -0.7874 0.4064)
			(stroke
				(width 0.1524)
				(type default)
			)
			(layer "F.SilkS")
		)
		(fp_line
			(start 0.7874 -0.4064)
			(end 0.7874 0.4064)
			(stroke
				(width 0.1524)
				(type default)
			)
			(layer "F.SilkS")
		)
		(fp_line
			(start -0.7874 0.4064)
			(end -0.7874 -0.4064)
			(stroke
				(width 0.1524)
				(type default)
			)
			(layer "F.SilkS")
		)
		(fp_line
			(start -0.7874 -0.4064)
			(end 0.7874 -0.4064)
			(stroke
				(width 0.1524)
				(type default)
			)
			(layer "F.SilkS")
		)
		(fp_line
			(start 0.67945 0.3048)
			(end 0.120396 0.3048)
			(stroke
				(width 0.1)
				(type default)
			)
			(layer "F.Fab")
		)
		(fp_line
			(start 0.67945 -0.3048)
			(end 0.67945 0.3048)
			(stroke
				(width 0.1)
				(type default)
			)
			(layer "F.Fab")
		)
		(fp_line
			(start 0.12065 -0.2794)
			(end 0.12065 -0.3048)
			(stroke
				(width 0.1)
				(type default)
			)
			(layer "F.Fab")
		)
		(fp_line
			(start 0.12065 -0.3048)
			(end 0.67945 -0.3048)
			(stroke
				(width 0.1)
				(type default)
			)
			(layer "F.Fab")
		)
		(fp_line
			(start 0.120396 0.3048)
			(end 0.120396 0.2794)
			(stroke
				(width 0.1)
				(type default)
			)
			(layer "F.Fab")
		)
		(fp_line
			(start 0.120396 0.2794)
			(end -0.12065 0.2794)
			(stroke
				(width 0.1)
				(type default)
			)
			(layer "F.Fab")
		)
		(fp_line
			(start -0.12065 0.3048)
			(end -0.67945 0.3048)
			(stroke
				(width 0.1)
				(type default)
			)
			(layer "F.Fab")
		)
		(fp_line
			(start -0.12065 0.2794)
			(end -0.12065 0.3048)
			(stroke
				(width 0.1)
				(type default)
			)
			(layer "F.Fab")
		)
		(fp_line
			(start -0.12065 -0.2794)
			(end 0.12065 -0.2794)
			(stroke
				(width 0.1)
				(type default)
			)
			(layer "F.Fab")
		)
		(fp_line
			(start -0.12065 -0.305054)
			(end -0.12065 -0.2794)
			(stroke
				(width 0.1)
				(type default)
			)
			(layer "F.Fab")
		)
		(fp_line
			(start -0.67945 0.3048)
			(end -0.67945 -0.305054)
			(stroke
				(width 0.1)
				(type default)
			)
			(layer "F.Fab")
		)
		(fp_line
			(start -0.67945 -0.305054)
			(end -0.12065 -0.305054)
			(stroke
				(width 0.1)
				(type default)
			)
			(layer "F.Fab")
		)
		(pad "1" smd circle
			(at -0.40005 0 180)
			(size 0 0)
			(layers "F.Cu" "F.Mask" "F.Paste")
			(net "SW_PVDDCR_CPU1_P1_SW1")
		)
		(pad "2" smd circle
			(at 0.40005 0 180)
			(size 0 0)
			(layers "F.Cu" "F.Mask" "F.Paste")
			(net "SW_PVDDCR_CPU1_P1_SW1_RC")
		)
	)
	(footprint ""
		(layer "F.Cu")
		(at 22.479 -359.918 180)
		(property "Reference" "C310"
			(at 0 0 180)
			(layer "F.SilkS")
			(hide yes)
			(effects
				(font
					(size 1.27 1.27)
				)
			)
		)
		(property "Value" ""
			(at 0 0 180)
			(layer "F.Fab")
			(effects
				(font
					(size 1.27 1.27)
				)
			)
		)
		(duplicate_pad_numbers_are_jumpers no)
		(fp_line
			(start 0.7874 0.4064)
			(end -0.7874 0.4064)
			(stroke
				(width 0.1524)
				(type default)
			)
			(layer "F.SilkS")
		)
		(fp_line
			(start 0.7874 -0.4064)
			(end 0.7874 0.4064)
			(stroke
				(width 0.1524)
				(type default)
			)
			(layer "F.SilkS")
		)
		(fp_line
			(start -0.7874 0.4064)
			(end -0.7874 -0.4064)
			(stroke
				(width 0.1524)
				(type default)
			)
			(layer "F.SilkS")
		)
		(fp_line
			(start -0.7874 -0.4064)
			(end 0.7874 -0.4064)
			(stroke
				(width 0.1524)
				(type default)
			)
			(layer "F.SilkS")
		)
		(fp_line
			(start 0.67945 0.3048)
			(end 0.120396 0.3048)
			(stroke
				(width 0.1)
				(type default)
			)
			(layer "F.Fab")
		)
		(fp_line
			(start 0.67945 -0.3048)
			(end 0.67945 0.3048)
			(stroke
				(width 0.1)
				(type default)
			)
			(layer "F.Fab")
		)
		(fp_line
			(start 0.12065 -0.2794)
			(end 0.12065 -0.3048)
			(stroke
				(width 0.1)
				(type default)
			)
			(layer "F.Fab")
		)
		(fp_line
			(start 0.12065 -0.3048)
			(end 0.67945 -0.3048)
			(stroke
				(width 0.1)
				(type default)
			)
			(layer "F.Fab")
		)
		(fp_line
			(start 0.120396 0.3048)
			(end 0.120396 0.2794)
			(stroke
				(width 0.1)
				(type default)
			)
			(layer "F.Fab")
		)
		(fp_line
			(start 0.120396 0.2794)
			(end -0.12065 0.2794)
			(stroke
				(width 0.1)
				(type default)
			)
			(layer "F.Fab")
		)
		(fp_line
			(start -0.12065 0.3048)
			(end -0.67945 0.3048)
			(stroke
				(width 0.1)
				(type default)
			)
			(layer "F.Fab")
		)
		(fp_line
			(start -0.12065 0.2794)
			(end -0.12065 0.3048)
			(stroke
				(width 0.1)
				(type default)
			)
			(layer "F.Fab")
		)
		(fp_line
			(start -0.12065 -0.2794)
			(end 0.12065 -0.2794)
			(stroke
				(width 0.1)
				(type default)
			)
			(layer "F.Fab")
		)
		(fp_line
			(start -0.12065 -0.305054)
			(end -0.12065 -0.2794)
			(stroke
				(width 0.1)
				(type default)
			)
			(layer "F.Fab")
		)
		(fp_line
			(start -0.67945 0.3048)
			(end -0.67945 -0.305054)
			(stroke
				(width 0.1)
				(type default)
			)
			(layer "F.Fab")
		)
		(fp_line
			(start -0.67945 -0.305054)
			(end -0.12065 -0.305054)
			(stroke
				(width 0.1)
				(type default)
			)
			(layer "F.Fab")
		)
		(pad "1" smd circle
			(at -0.40005 0 180)
			(size 0 0)
			(layers "F.Cu" "F.Mask" "F.Paste")
			(net "SVID_PVDDCR_CPU1_P1_SVC_R")
		)
		(pad "2" smd circle
			(at 0.40005 0 180)
			(size 0 0)
			(layers "F.Cu" "F.Mask" "F.Paste")
			(net "GND")
		)
	)
	(footprint ""
		(layer "F.Cu")
		(at 236.7661 -400.871182)
		(property "Reference" "PR3994"
			(at 0 0 0)
			(layer "F.SilkS")
			(hide yes)
			(effects
				(font
					(size 1.27 1.27)
				)
			)
		)
		(property "Value" ""
			(at 0 0 0)
			(layer "F.Fab")
			(effects
				(font
					(size 1.27 1.27)
				)
			)
		)
		(duplicate_pad_numbers_are_jumpers no)
		(fp_line
			(start -0.7874 -0.4064)
			(end 0.7874 -0.4064)
			(stroke
				(width 0.1524)
				(type default)
			)
			(layer "F.SilkS")
		)
		(fp_line
			(start -0.7874 0.4064)
			(end -0.7874 -0.4064)
			(stroke
				(width 0.1524)
				(type default)
			)
			(layer "F.SilkS")
		)
		(fp_line
			(start 0.7874 -0.4064)
			(end 0.7874 0.4064)
			(stroke
				(width 0.1524)
				(type default)
			)
			(layer "F.SilkS")
		)
		(fp_line
			(start 0.7874 0.4064)
			(end -0.7874 0.4064)
			(stroke
				(width 0.1524)
				(type default)
			)
			(layer "F.SilkS")
		)
		(fp_line
			(start -0.67945 -0.305054)
			(end -0.12065 -0.305054)
			(stroke
				(width 0.1)
				(type default)
			)
			(layer "F.Fab")
		)
		(fp_line
			(start -0.67945 0.3048)
			(end -0.67945 -0.305054)
			(stroke
				(width 0.1)
				(type default)
			)
			(layer "F.Fab")
		)
		(fp_line
			(start -0.12065 -0.305054)
			(end -0.12065 -0.2794)
			(stroke
				(width 0.1)
				(type default)
			)
			(layer "F.Fab")
		)
		(fp_line
			(start -0.12065 -0.2794)
			(end 0.12065 -0.2794)
			(stroke
				(width 0.1)
				(type default)
			)
			(layer "F.Fab")
		)
		(fp_line
			(start -0.12065 0.2794)
			(end -0.12065 0.3048)
			(stroke
				(width 0.1)
				(type default)
			)
			(layer "F.Fab")
		)
		(fp_line
			(start -0.12065 0.3048)
			(end -0.67945 0.3048)
			(stroke
				(width 0.1)
				(type default)
			)
			(layer "F.Fab")
		)
		(fp_line
			(start 0.120396 0.2794)
			(end -0.12065 0.2794)
			(stroke
				(width 0.1)
				(type default)
			)
			(layer "F.Fab")
		)
		(fp_line
			(start 0.120396 0.3048)
			(end 0.120396 0.2794)
			(stroke
				(width 0.1)
				(type default)
			)
			(layer "F.Fab")
		)
		(fp_line
			(start 0.12065 -0.3048)
			(end 0.67945 -0.3048)
			(stroke
				(width 0.1)
				(type default)
			)
			(layer "F.Fab")
		)
		(fp_line
			(start 0.12065 -0.2794)
			(end 0.12065 -0.3048)
			(stroke
				(width 0.1)
				(type default)
			)
			(layer "F.Fab")
		)
		(fp_line
			(start 0.67945 -0.3048)
			(end 0.67945 0.3048)
			(stroke
				(width 0.1)
				(type default)
			)
			(layer "F.Fab")
		)
		(fp_line
			(start 0.67945 0.3048)
			(end 0.120396 0.3048)
			(stroke
				(width 0.1)
				(type default)
			)
			(layer "F.Fab")
		)
		(pad "1" smd circle
			(at -0.40005 0)
			(size 0 0)
			(layers "F.Cu" "F.Mask" "F.Paste")
			(net "HSC_D_OC_4")
		)
		(pad "2" smd circle
			(at 0.40005 0)
			(size 0 0)
			(layers "F.Cu" "F.Mask" "F.Paste")
			(net "HSC_D_OC_R")
		)
	)
	(footprint ""
		(layer "F.Cu")
		(at 55.816754 -375.49963 -90)
		(property "Reference" "C822"
			(at 0 0 270)
			(layer "F.SilkS")
			(hide yes)
			(effects
				(font
					(size 1.27 1.27)
				)
			)
		)
		(property "Value" ""
			(at 0 0 270)
			(layer "F.Fab")
			(effects
				(font
					(size 1.27 1.27)
				)
			)
		)
		(duplicate_pad_numbers_are_jumpers no)
		(fp_line
			(start -0.299974 0.150114)
			(end -0.299974 -0.150114)
			(stroke
				(width 0.1)
				(type default)
			)
			(layer "F.Fab")
		)
		(fp_line
			(start 0.299974 0.150114)
			(end -0.299974 0.150114)
			(stroke
				(width 0.1)
				(type default)
			)
			(layer "F.Fab")
		)
		(fp_line
			(start -0.299974 -0.150114)
			(end 0.299974 -0.150114)
			(stroke
				(width 0.1)
				(type default)
			)
			(layer "F.Fab")
		)
		(fp_line
			(start 0.299974 -0.150114)
			(end 0.299974 0.150114)
			(stroke
				(width 0.1)
				(type default)
			)
			(layer "F.Fab")
		)
		(pad "1" smd rect
			(at -0.2667 0 270)
			(size 0.3048 0.381)
			(layers "F.Cu" "F.Mask" "F.Paste")
			(net "P5E_CPU1_P0_TX_C_DN<7>")
		)
		(pad "2" smd rect
			(at 0.2667 0 270)
			(size 0.3048 0.381)
			(layers "F.Cu" "F.Mask" "F.Paste")
			(net "P5E_CPU1_P0_TX_DN<7>")
		)
	)
	(footprint ""
		(layer "F.Cu")
		(at 36.319968 -134.873238 180)
		(property "Reference" "R3322"
			(at 0 0 180)
			(layer "F.SilkS")
			(hide yes)
			(effects
				(font
					(size 1.27 1.27)
				)
			)
		)
		(property "Value" ""
			(at 0 0 180)
			(layer "F.Fab")
			(effects
				(font
					(size 1.27 1.27)
				)
			)
		)
		(duplicate_pad_numbers_are_jumpers no)
		(fp_line
			(start 0.7874 0.4064)
			(end -0.7874 0.4064)
			(stroke
				(width 0.1524)
				(type default)
			)
			(layer "F.SilkS")
		)
		(fp_line
			(start 0.7874 -0.4064)
			(end 0.7874 0.4064)
			(stroke
				(width 0.1524)
				(type default)
			)
			(layer "F.SilkS")
		)
		(fp_line
			(start -0.7874 0.4064)
			(end -0.7874 -0.4064)
			(stroke
				(width 0.1524)
				(type default)
			)
			(layer "F.SilkS")
		)
		(fp_line
			(start -0.7874 -0.4064)
			(end 0.7874 -0.4064)
			(stroke
				(width 0.1524)
				(type default)
			)
			(layer "F.SilkS")
		)
		(fp_line
			(start 0.67945 0.3048)
			(end 0.120396 0.3048)
			(stroke
				(width 0.1)
				(type default)
			)
			(layer "F.Fab")
		)
		(fp_line
			(start 0.67945 -0.3048)
			(end 0.67945 0.3048)
			(stroke
				(width 0.1)
				(type default)
			)
			(layer "F.Fab")
		)
		(fp_line
			(start 0.12065 -0.2794)
			(end 0.12065 -0.3048)
			(stroke
				(width 0.1)
				(type default)
			)
			(layer "F.Fab")
		)
		(fp_line
			(start 0.12065 -0.3048)
			(end 0.67945 -0.3048)
			(stroke
				(width 0.1)
				(type default)
			)
			(layer "F.Fab")
		)
		(fp_line
			(start 0.120396 0.3048)
			(end 0.120396 0.2794)
			(stroke
				(width 0.1)
				(type default)
			)
			(layer "F.Fab")
		)
		(fp_line
			(start 0.120396 0.2794)
			(end -0.12065 0.2794)
			(stroke
				(width 0.1)
				(type default)
			)
			(layer "F.Fab")
		)
		(fp_line
			(start -0.12065 0.3048)
			(end -0.67945 0.3048)
			(stroke
				(width 0.1)
				(type default)
			)
			(layer "F.Fab")
		)
		(fp_line
			(start -0.12065 0.2794)
			(end -0.12065 0.3048)
			(stroke
				(width 0.1)
				(type default)
			)
			(layer "F.Fab")
		)
		(fp_line
			(start -0.12065 -0.2794)
			(end 0.12065 -0.2794)
			(stroke
				(width 0.1)
				(type default)
			)
			(layer "F.Fab")
		)
		(fp_line
			(start -0.12065 -0.305054)
			(end -0.12065 -0.2794)
			(stroke
				(width 0.1)
				(type default)
			)
			(layer "F.Fab")
		)
		(fp_line
			(start -0.67945 0.3048)
			(end -0.67945 -0.305054)
			(stroke
				(width 0.1)
				(type default)
			)
			(layer "F.Fab")
		)
		(fp_line
			(start -0.67945 -0.305054)
			(end -0.12065 -0.305054)
			(stroke
				(width 0.1)
				(type default)
			)
			(layer "F.Fab")
		)
		(pad "1" smd circle
			(at -0.40005 0 180)
			(size 0 0)
			(layers "F.Cu" "F.Mask" "F.Paste")
			(net "P3V3_AUX")
		)
		(pad "2" smd circle
			(at 0.40005 0 180)
			(size 0 0)
			(layers "F.Cu" "F.Mask" "F.Paste")
			(net "CLK_GEN2_GPU_FPGA_OE_R2_N")
		)
	)
	(footprint ""
		(layer "F.Cu")
		(at 426.213778 -400.456146)
		(property "Reference" "C795"
			(at 0 0 0)
			(layer "F.SilkS")
			(hide yes)
			(effects
				(font
					(size 1.27 1.27)
				)
			)
		)
		(property "Value" ""
			(at 0 0 0)
			(layer "F.Fab")
			(effects
				(font
					(size 1.27 1.27)
				)
			)
		)
		(duplicate_pad_numbers_are_jumpers no)
		(fp_line
			(start -1.524 -0.762)
			(end 1.524 -0.762)
			(stroke
				(width 0.1524)
				(type default)
			)
			(layer "F.SilkS")
		)
		(fp_line
			(start -1.524 0.762)
			(end -1.524 -0.762)
			(stroke
				(width 0.1524)
				(type default)
			)
			(layer "F.SilkS")
		)
		(fp_line
			(start 1.524 -0.762)
			(end 1.524 0.762)
			(stroke
				(width 0.1524)
				(type default)
			)
			(layer "F.SilkS")
		)
		(fp_line
			(start 1.524 0.762)
			(end -1.524 0.762)
			(stroke
				(width 0.1524)
				(type default)
			)
			(layer "F.SilkS")
		)
		(fp_line
			(start -1.1049 -0.724916)
			(end -1.1049 0.724916)
			(stroke
				(width 0.1)
				(type default)
			)
			(layer "F.Fab")
		)
		(fp_line
			(start -1.1049 0.724916)
			(end 1.1049 0.724916)
			(stroke
				(width 0.1)
				(type default)
			)
			(layer "F.Fab")
		)
		(fp_line
			(start 1.1049 -0.724916)
			(end -1.1049 -0.724916)
			(stroke
				(width 0.1)
				(type default)
			)
			(layer "F.Fab")
		)
		(fp_line
			(start 1.1049 0.724916)
			(end 1.1049 -0.724916)
			(stroke
				(width 0.1)
				(type default)
			)
			(layer "F.Fab")
		)
		(pad "1" smd rect
			(at -0.889 0 180)
			(size 1.016 1.27)
			(layers "F.Cu" "F.Mask" "F.Paste")
			(net "P0V9_CPU0_RT2_2A")
		)
		(pad "2" smd rect
			(at 0.889 0 180)
			(size 1.016 1.27)
			(layers "F.Cu" "F.Mask" "F.Paste")
			(net "GND")
		)
	)
	(footprint ""
		(layer "F.Cu")
		(at 340.696296 -339.881972 90)
		(property "Reference" "PC132_5"
			(at 0 0 90)
			(layer "F.SilkS")
			(hide yes)
			(effects
				(font
					(size 1.27 1.27)
				)
			)
		)
		(property "Value" ""
			(at 0 0 90)
			(layer "F.Fab")
			(effects
				(font
					(size 1.27 1.27)
				)
			)
		)
		(duplicate_pad_numbers_are_jumpers no)
		(fp_line
			(start 0.7874 -0.4064)
			(end 0.7874 0.4064)
			(stroke
				(width 0.1524)
				(type default)
			)
			(layer "F.SilkS")
		)
		(fp_line
			(start -0.7874 -0.4064)
			(end 0.7874 -0.4064)
			(stroke
				(width 0.1524)
				(type default)
			)
			(layer "F.SilkS")
		)
		(fp_line
			(start 0.7874 0.4064)
			(end -0.7874 0.4064)
			(stroke
				(width 0.1524)
				(type default)
			)
			(layer "F.SilkS")
		)
		(fp_line
			(start -0.7874 0.4064)
			(end -0.7874 -0.4064)
			(stroke
				(width 0.1524)
				(type default)
			)
			(layer "F.SilkS")
		)
		(fp_line
			(start -0.12065 -0.305054)
			(end -0.12065 -0.2794)
			(stroke
				(width 0.1)
				(type default)
			)
			(layer "F.Fab")
		)
		(fp_line
			(start -0.67945 -0.305054)
			(end -0.12065 -0.305054)
			(stroke
				(width 0.1)
				(type default)
			)
			(layer "F.Fab")
		)
		(fp_line
			(start 0.67945 -0.3048)
			(end 0.67945 0.3048)
			(stroke
				(width 0.1)
				(type default)
			)
			(layer "F.Fab")
		)
		(fp_line
			(start 0.12065 -0.3048)
			(end 0.67945 -0.3048)
			(stroke
				(width 0.1)
				(type default)
			)
			(layer "F.Fab")
		)
		(fp_line
			(start 0.12065 -0.2794)
			(end 0.12065 -0.3048)
			(stroke
				(width 0.1)
				(type default)
			)
			(layer "F.Fab")
		)
		(fp_line
			(start -0.12065 -0.2794)
			(end 0.12065 -0.2794)
			(stroke
				(width 0.1)
				(type default)
			)
			(layer "F.Fab")
		)
		(fp_line
			(start 0.120396 0.2794)
			(end -0.12065 0.2794)
			(stroke
				(width 0.1)
				(type default)
			)
			(layer "F.Fab")
		)
		(fp_line
			(start -0.12065 0.2794)
			(end -0.12065 0.3048)
			(stroke
				(width 0.1)
				(type default)
			)
			(layer "F.Fab")
		)
		(fp_line
			(start 0.67945 0.3048)
			(end 0.120396 0.3048)
			(stroke
				(width 0.1)
				(type default)
			)
			(layer "F.Fab")
		)
		(fp_line
			(start 0.120396 0.3048)
			(end 0.120396 0.2794)
			(stroke
				(width 0.1)
				(type default)
			)
			(layer "F.Fab")
		)
		(fp_line
			(start -0.12065 0.3048)
			(end -0.67945 0.3048)
			(stroke
				(width 0.1)
				(type default)
			)
			(layer "F.Fab")
		)
		(fp_line
			(start -0.67945 0.3048)
			(end -0.67945 -0.305054)
			(stroke
				(width 0.1)
				(type default)
			)
			(layer "F.Fab")
		)
		(pad "1" smd circle
			(at -0.40005 0 90)
			(size 0 0)
			(layers "F.Cu" "F.Mask" "F.Paste")
			(net "PVDDCR_CPU1_P0_VCCS")
		)
		(pad "2" smd circle
			(at 0.40005 0 90)
			(size 0 0)
			(layers "F.Cu" "F.Mask" "F.Paste")
			(net "GND")
		)
	)
	(footprint ""
		(layer "F.Cu")
		(at 179.236878 -351.293684 -90)
		(property "Reference" "PC507_11P1_1"
			(at 0 0 270)
			(layer "F.SilkS")
			(hide yes)
			(effects
				(font
					(size 1.27 1.27)
				)
			)
		)
		(property "Value" ""
			(at 0 0 270)
			(layer "F.Fab")
			(effects
				(font
					(size 1.27 1.27)
				)
			)
		)
		(duplicate_pad_numbers_are_jumpers no)
		(fp_line
			(start -0.7874 0.4064)
			(end -0.7874 -0.4064)
			(stroke
				(width 0.1524)
				(type default)
			)
			(layer "F.SilkS")
		)
		(fp_line
			(start 0.7874 0.4064)
			(end -0.7874 0.4064)
			(stroke
				(width 0.1524)
				(type default)
			)
			(layer "F.SilkS")
		)
		(fp_line
			(start -0.7874 -0.4064)
			(end 0.7874 -0.4064)
			(stroke
				(width 0.1524)
				(type default)
			)
			(layer "F.SilkS")
		)
		(fp_line
			(start 0.7874 -0.4064)
			(end 0.7874 0.4064)
			(stroke
				(width 0.1524)
				(type default)
			)
			(layer "F.SilkS")
		)
		(fp_line
			(start -0.67945 0.3048)
			(end -0.67945 -0.305054)
			(stroke
				(width 0.1)
				(type default)
			)
			(layer "F.Fab")
		)
		(fp_line
			(start -0.12065 0.3048)
			(end -0.67945 0.3048)
			(stroke
				(width 0.1)
				(type default)
			)
			(layer "F.Fab")
		)
		(fp_line
			(start 0.120396 0.3048)
			(end 0.120396 0.2794)
			(stroke
				(width 0.1)
				(type default)
			)
			(layer "F.Fab")
		)
		(fp_line
			(start 0.67945 0.3048)
			(end 0.120396 0.3048)
			(stroke
				(width 0.1)
				(type default)
			)
			(layer "F.Fab")
		)
		(fp_line
			(start -0.12065 0.2794)
			(end -0.12065 0.3048)
			(stroke
				(width 0.1)
				(type default)
			)
			(layer "F.Fab")
		)
		(fp_line
			(start 0.120396 0.2794)
			(end -0.12065 0.2794)
			(stroke
				(width 0.1)
				(type default)
			)
			(layer "F.Fab")
		)
		(fp_line
			(start -0.12065 -0.2794)
			(end 0.12065 -0.2794)
			(stroke
				(width 0.1)
				(type default)
			)
			(layer "F.Fab")
		)
		(fp_line
			(start 0.12065 -0.2794)
			(end 0.12065 -0.3048)
			(stroke
				(width 0.1)
				(type default)
			)
			(layer "F.Fab")
		)
		(fp_line
			(start 0.12065 -0.3048)
			(end 0.67945 -0.3048)
			(stroke
				(width 0.1)
				(type default)
			)
			(layer "F.Fab")
		)
		(fp_line
			(start 0.67945 -0.3048)
			(end 0.67945 0.3048)
			(stroke
				(width 0.1)
				(type default)
			)
			(layer "F.Fab")
		)
		(fp_line
			(start -0.67945 -0.305054)
			(end -0.12065 -0.305054)
			(stroke
				(width 0.1)
				(type default)
			)
			(layer "F.Fab")
		)
		(fp_line
			(start -0.12065 -0.305054)
			(end -0.12065 -0.2794)
			(stroke
				(width 0.1)
				(type default)
			)
			(layer "F.Fab")
		)
		(pad "1" smd circle
			(at -0.40005 0 270)
			(size 0 0)
			(layers "F.Cu" "F.Mask" "F.Paste")
			(net "PVDD11_S3_P1_PVCC")
		)
		(pad "2" smd circle
			(at 0.40005 0 270)
			(size 0 0)
			(layers "F.Cu" "F.Mask" "F.Paste")
			(net "GND")
		)
	)
	(footprint ""
		(layer "F.Cu")
		(at 315.220096 -378.95403 -90)
		(property "Reference" "C914"
			(at 0 0 270)
			(layer "F.SilkS")
			(hide yes)
			(effects
				(font
					(size 1.27 1.27)
				)
			)
		)
		(property "Value" ""
			(at 0 0 270)
			(layer "F.Fab")
			(effects
				(font
					(size 1.27 1.27)
				)
			)
		)
		(duplicate_pad_numbers_are_jumpers no)
		(fp_line
			(start -0.299974 0.150114)
			(end -0.299974 -0.150114)
			(stroke
				(width 0.1)
				(type default)
			)
			(layer "F.Fab")
		)
		(fp_line
			(start 0.299974 0.150114)
			(end -0.299974 0.150114)
			(stroke
				(width 0.1)
				(type default)
			)
			(layer "F.Fab")
		)
		(fp_line
			(start -0.299974 -0.150114)
			(end 0.299974 -0.150114)
			(stroke
				(width 0.1)
				(type default)
			)
			(layer "F.Fab")
		)
		(fp_line
			(start 0.299974 -0.150114)
			(end 0.299974 0.150114)
			(stroke
				(width 0.1)
				(type default)
			)
			(layer "F.Fab")
		)
		(pad "1" smd rect
			(at -0.2667 0 270)
			(size 0.3048 0.381)
			(layers "F.Cu" "F.Mask" "F.Paste")
			(net "P5E_CPU0_P0_TX_C_DN<9>")
		)
		(pad "2" smd rect
			(at 0.2667 0 270)
			(size 0.3048 0.381)
			(layers "F.Cu" "F.Mask" "F.Paste")
			(net "P5E_CPU0_P0_TX_DN<9>")
		)
	)
	(footprint ""
		(layer "F.Cu")
		(at 415.628582 -331.945996)
		(property "Reference" "PR115"
			(at 0 0 0)
			(layer "F.SilkS")
			(hide yes)
			(effects
				(font
					(size 1.27 1.27)
				)
			)
		)
		(property "Value" ""
			(at 0 0 0)
			(layer "F.Fab")
			(effects
				(font
					(size 1.27 1.27)
				)
			)
		)
		(duplicate_pad_numbers_are_jumpers no)
		(fp_line
			(start -0.7874 -0.4064)
			(end 0.7874 -0.4064)
			(stroke
				(width 0.1524)
				(type default)
			)
			(layer "F.SilkS")
		)
		(fp_line
			(start -0.7874 0.4064)
			(end -0.7874 -0.4064)
			(stroke
				(width 0.1524)
				(type default)
			)
			(layer "F.SilkS")
		)
		(fp_line
			(start 0.7874 -0.4064)
			(end 0.7874 0.4064)
			(stroke
				(width 0.1524)
				(type default)
			)
			(layer "F.SilkS")
		)
		(fp_line
			(start 0.7874 0.4064)
			(end -0.7874 0.4064)
			(stroke
				(width 0.1524)
				(type default)
			)
			(layer "F.SilkS")
		)
		(fp_line
			(start -0.67945 -0.305054)
			(end -0.12065 -0.305054)
			(stroke
				(width 0.1)
				(type default)
			)
			(layer "F.Fab")
		)
		(fp_line
			(start -0.67945 0.3048)
			(end -0.67945 -0.305054)
			(stroke
				(width 0.1)
				(type default)
			)
			(layer "F.Fab")
		)
		(fp_line
			(start -0.12065 -0.305054)
			(end -0.12065 -0.2794)
			(stroke
				(width 0.1)
				(type default)
			)
			(layer "F.Fab")
		)
		(fp_line
			(start -0.12065 -0.2794)
			(end 0.12065 -0.2794)
			(stroke
				(width 0.1)
				(type default)
			)
			(layer "F.Fab")
		)
		(fp_line
			(start -0.12065 0.2794)
			(end -0.12065 0.3048)
			(stroke
				(width 0.1)
				(type default)
			)
			(layer "F.Fab")
		)
		(fp_line
			(start -0.12065 0.3048)
			(end -0.67945 0.3048)
			(stroke
				(width 0.1)
				(type default)
			)
			(layer "F.Fab")
		)
		(fp_line
			(start 0.120396 0.2794)
			(end -0.12065 0.2794)
			(stroke
				(width 0.1)
				(type default)
			)
			(layer "F.Fab")
		)
		(fp_line
			(start 0.120396 0.3048)
			(end 0.120396 0.2794)
			(stroke
				(width 0.1)
				(type default)
			)
			(layer "F.Fab")
		)
		(fp_line
			(start 0.12065 -0.3048)
			(end 0.67945 -0.3048)
			(stroke
				(width 0.1)
				(type default)
			)
			(layer "F.Fab")
		)
		(fp_line
			(start 0.12065 -0.2794)
			(end 0.12065 -0.3048)
			(stroke
				(width 0.1)
				(type default)
			)
			(layer "F.Fab")
		)
		(fp_line
			(start 0.67945 -0.3048)
			(end 0.67945 0.3048)
			(stroke
				(width 0.1)
				(type default)
			)
			(layer "F.Fab")
		)
		(fp_line
			(start 0.67945 0.3048)
			(end 0.120396 0.3048)
			(stroke
				(width 0.1)
				(type default)
			)
			(layer "F.Fab")
		)
		(pad "1" smd circle
			(at -0.40005 0)
			(size 0 0)
			(layers "F.Cu" "F.Mask" "F.Paste")
			(net "VSENSE_VSS_SENSE_C_P0")
		)
		(pad "2" smd circle
			(at 0.40005 0)
			(size 0 0)
			(layers "F.Cu" "F.Mask" "F.Paste")
			(net "GND")
		)
	)
	(footprint ""
		(layer "F.Cu")
		(at 163.703 -112.359948 180)
		(property "Reference" "R1071"
			(at 0 0 180)
			(layer "F.SilkS")
			(hide yes)
			(effects
				(font
					(size 1.27 1.27)
				)
			)
		)
		(property "Value" ""
			(at 0 0 180)
			(layer "F.Fab")
			(effects
				(font
					(size 1.27 1.27)
				)
			)
		)
		(duplicate_pad_numbers_are_jumpers no)
		(fp_line
			(start 0.7874 0.4064)
			(end -0.7874 0.4064)
			(stroke
				(width 0.1524)
				(type default)
			)
			(layer "F.SilkS")
		)
		(fp_line
			(start 0.7874 -0.4064)
			(end 0.7874 0.4064)
			(stroke
				(width 0.1524)
				(type default)
			)
			(layer "F.SilkS")
		)
		(fp_line
			(start -0.7874 0.4064)
			(end -0.7874 -0.4064)
			(stroke
				(width 0.1524)
				(type default)
			)
			(layer "F.SilkS")
		)
		(fp_line
			(start -0.7874 -0.4064)
			(end 0.7874 -0.4064)
			(stroke
				(width 0.1524)
				(type default)
			)
			(layer "F.SilkS")
		)
		(fp_line
			(start 0.67945 0.3048)
			(end 0.120396 0.3048)
			(stroke
				(width 0.1)
				(type default)
			)
			(layer "F.Fab")
		)
		(fp_line
			(start 0.67945 -0.3048)
			(end 0.67945 0.3048)
			(stroke
				(width 0.1)
				(type default)
			)
			(layer "F.Fab")
		)
		(fp_line
			(start 0.12065 -0.2794)
			(end 0.12065 -0.3048)
			(stroke
				(width 0.1)
				(type default)
			)
			(layer "F.Fab")
		)
		(fp_line
			(start 0.12065 -0.3048)
			(end 0.67945 -0.3048)
			(stroke
				(width 0.1)
				(type default)
			)
			(layer "F.Fab")
		)
		(fp_line
			(start 0.120396 0.3048)
			(end 0.120396 0.2794)
			(stroke
				(width 0.1)
				(type default)
			)
			(layer "F.Fab")
		)
		(fp_line
			(start 0.120396 0.2794)
			(end -0.12065 0.2794)
			(stroke
				(width 0.1)
				(type default)
			)
			(layer "F.Fab")
		)
		(fp_line
			(start -0.12065 0.3048)
			(end -0.67945 0.3048)
			(stroke
				(width 0.1)
				(type default)
			)
			(layer "F.Fab")
		)
		(fp_line
			(start -0.12065 0.2794)
			(end -0.12065 0.3048)
			(stroke
				(width 0.1)
				(type default)
			)
			(layer "F.Fab")
		)
		(fp_line
			(start -0.12065 -0.2794)
			(end 0.12065 -0.2794)
			(stroke
				(width 0.1)
				(type default)
			)
			(layer "F.Fab")
		)
		(fp_line
			(start -0.12065 -0.305054)
			(end -0.12065 -0.2794)
			(stroke
				(width 0.1)
				(type default)
			)
			(layer "F.Fab")
		)
		(fp_line
			(start -0.67945 0.3048)
			(end -0.67945 -0.305054)
			(stroke
				(width 0.1)
				(type default)
			)
			(layer "F.Fab")
		)
		(fp_line
			(start -0.67945 -0.305054)
			(end -0.12065 -0.305054)
			(stroke
				(width 0.1)
				(type default)
			)
			(layer "F.Fab")
		)
		(pad "1" smd circle
			(at -0.40005 0 180)
			(size 0 0)
			(layers "F.Cu" "F.Mask" "F.Paste")
			(net "P3V3_OCP_SFF_EN_R")
		)
		(pad "2" smd circle
			(at 0.40005 0 180)
			(size 0 0)
			(layers "F.Cu" "F.Mask" "F.Paste")
			(net "P3V3_AUX")
		)
	)
	(footprint ""
		(layer "F.Cu")
		(at 357.50881 -402.7424 -90)
		(property "Reference" "R1043"
			(at 0 0 270)
			(layer "F.SilkS")
			(hide yes)
			(effects
				(font
					(size 1.27 1.27)
				)
			)
		)
		(property "Value" ""
			(at 0 0 270)
			(layer "F.Fab")
			(effects
				(font
					(size 1.27 1.27)
				)
			)
		)
		(duplicate_pad_numbers_are_jumpers no)
		(fp_line
			(start -0.32512 0.175006)
			(end -0.32512 -0.175006)
			(stroke
				(width 0.1)
				(type default)
			)
			(layer "F.Fab")
		)
		(fp_line
			(start 0.32512 0.175006)
			(end -0.32512 0.175006)
			(stroke
				(width 0.1)
				(type default)
			)
			(layer "F.Fab")
		)
		(fp_line
			(start -0.32512 -0.175006)
			(end 0.32512 -0.175006)
			(stroke
				(width 0.1)
				(type default)
			)
			(layer "F.Fab")
		)
		(fp_line
			(start 0.32512 -0.175006)
			(end 0.32512 0.175006)
			(stroke
				(width 0.1)
				(type default)
			)
			(layer "F.Fab")
		)
		(pad "1" smd rect
			(at -0.2667 0 270)
			(size 0.3048 0.381)
			(layers "F.Cu" "F.Mask" "F.Paste")
			(net "NCF_A1_CPU0_P1_GND")
		)
		(pad "2" smd rect
			(at 0.2667 0 90)
			(size 0.3048 0.381)
			(layers "F.Cu" "F.Mask" "F.Paste")
			(net "GND")
		)
	)
	(footprint ""
		(layer "F.Cu")
		(at 204.7621 -405.036782 180)
		(property "Reference" "PC2185"
			(at 0 0 180)
			(layer "F.SilkS")
			(hide yes)
			(effects
				(font
					(size 1.27 1.27)
				)
			)
		)
		(property "Value" ""
			(at 0 0 180)
			(layer "F.Fab")
			(effects
				(font
					(size 1.27 1.27)
				)
			)
		)
		(duplicate_pad_numbers_are_jumpers no)
		(fp_line
			(start 0.7874 0.4064)
			(end -0.7874 0.4064)
			(stroke
				(width 0.1524)
				(type default)
			)
			(layer "F.SilkS")
		)
		(fp_line
			(start 0.7874 -0.4064)
			(end 0.7874 0.4064)
			(stroke
				(width 0.1524)
				(type default)
			)
			(layer "F.SilkS")
		)
		(fp_line
			(start -0.7874 0.4064)
			(end -0.7874 -0.4064)
			(stroke
				(width 0.1524)
				(type default)
			)
			(layer "F.SilkS")
		)
		(fp_line
			(start -0.7874 -0.4064)
			(end 0.7874 -0.4064)
			(stroke
				(width 0.1524)
				(type default)
			)
			(layer "F.SilkS")
		)
		(fp_line
			(start 0.67945 0.3048)
			(end 0.120396 0.3048)
			(stroke
				(width 0.1)
				(type default)
			)
			(layer "F.Fab")
		)
		(fp_line
			(start 0.67945 -0.3048)
			(end 0.67945 0.3048)
			(stroke
				(width 0.1)
				(type default)
			)
			(layer "F.Fab")
		)
		(fp_line
			(start 0.12065 -0.2794)
			(end 0.12065 -0.3048)
			(stroke
				(width 0.1)
				(type default)
			)
			(layer "F.Fab")
		)
		(fp_line
			(start 0.12065 -0.3048)
			(end 0.67945 -0.3048)
			(stroke
				(width 0.1)
				(type default)
			)
			(layer "F.Fab")
		)
		(fp_line
			(start 0.120396 0.3048)
			(end 0.120396 0.2794)
			(stroke
				(width 0.1)
				(type default)
			)
			(layer "F.Fab")
		)
		(fp_line
			(start 0.120396 0.2794)
			(end -0.12065 0.2794)
			(stroke
				(width 0.1)
				(type default)
			)
			(layer "F.Fab")
		)
		(fp_line
			(start -0.12065 0.3048)
			(end -0.67945 0.3048)
			(stroke
				(width 0.1)
				(type default)
			)
			(layer "F.Fab")
		)
		(fp_line
			(start -0.12065 0.2794)
			(end -0.12065 0.3048)
			(stroke
				(width 0.1)
				(type default)
			)
			(layer "F.Fab")
		)
		(fp_line
			(start -0.12065 -0.2794)
			(end 0.12065 -0.2794)
			(stroke
				(width 0.1)
				(type default)
			)
			(layer "F.Fab")
		)
		(fp_line
			(start -0.12065 -0.305054)
			(end -0.12065 -0.2794)
			(stroke
				(width 0.1)
				(type default)
			)
			(layer "F.Fab")
		)
		(fp_line
			(start -0.67945 0.3048)
			(end -0.67945 -0.305054)
			(stroke
				(width 0.1)
				(type default)
			)
			(layer "F.Fab")
		)
		(fp_line
			(start -0.67945 -0.305054)
			(end -0.12065 -0.305054)
			(stroke
				(width 0.1)
				(type default)
			)
			(layer "F.Fab")
		)
		(pad "1" smd circle
			(at -0.40005 0 180)
			(size 0 0)
			(layers "F.Cu" "F.Mask" "F.Paste")
			(net "HSC_SS")
		)
		(pad "2" smd circle
			(at 0.40005 0 180)
			(size 0 0)
			(layers "F.Cu" "F.Mask" "F.Paste")
			(net "AGND_HSC")
		)
	)
	(footprint ""
		(layer "F.Cu")
		(at 174.625 -100.294948 90)
		(property "Reference" "R10"
			(at 0 0 90)
			(layer "F.SilkS")
			(hide yes)
			(effects
				(font
					(size 1.27 1.27)
				)
			)
		)
		(property "Value" ""
			(at 0 0 90)
			(layer "F.Fab")
			(effects
				(font
					(size 1.27 1.27)
				)
			)
		)
		(duplicate_pad_numbers_are_jumpers no)
		(fp_line
			(start 0.7874 -0.4064)
			(end 0.7874 0.4064)
			(stroke
				(width 0.1524)
				(type default)
			)
			(layer "F.SilkS")
		)
		(fp_line
			(start -0.7874 -0.4064)
			(end 0.7874 -0.4064)
			(stroke
				(width 0.1524)
				(type default)
			)
			(layer "F.SilkS")
		)
		(fp_line
			(start 0.7874 0.4064)
			(end -0.7874 0.4064)
			(stroke
				(width 0.1524)
				(type default)
			)
			(layer "F.SilkS")
		)
		(fp_line
			(start -0.7874 0.4064)
			(end -0.7874 -0.4064)
			(stroke
				(width 0.1524)
				(type default)
			)
			(layer "F.SilkS")
		)
		(fp_line
			(start -0.12065 -0.305054)
			(end -0.12065 -0.2794)
			(stroke
				(width 0.1)
				(type default)
			)
			(layer "F.Fab")
		)
		(fp_line
			(start -0.67945 -0.305054)
			(end -0.12065 -0.305054)
			(stroke
				(width 0.1)
				(type default)
			)
			(layer "F.Fab")
		)
		(fp_line
			(start 0.67945 -0.3048)
			(end 0.67945 0.3048)
			(stroke
				(width 0.1)
				(type default)
			)
			(layer "F.Fab")
		)
		(fp_line
			(start 0.12065 -0.3048)
			(end 0.67945 -0.3048)
			(stroke
				(width 0.1)
				(type default)
			)
			(layer "F.Fab")
		)
		(fp_line
			(start 0.12065 -0.2794)
			(end 0.12065 -0.3048)
			(stroke
				(width 0.1)
				(type default)
			)
			(layer "F.Fab")
		)
		(fp_line
			(start -0.12065 -0.2794)
			(end 0.12065 -0.2794)
			(stroke
				(width 0.1)
				(type default)
			)
			(layer "F.Fab")
		)
		(fp_line
			(start 0.120396 0.2794)
			(end -0.12065 0.2794)
			(stroke
				(width 0.1)
				(type default)
			)
			(layer "F.Fab")
		)
		(fp_line
			(start -0.12065 0.2794)
			(end -0.12065 0.3048)
			(stroke
				(width 0.1)
				(type default)
			)
			(layer "F.Fab")
		)
		(fp_line
			(start 0.67945 0.3048)
			(end 0.120396 0.3048)
			(stroke
				(width 0.1)
				(type default)
			)
			(layer "F.Fab")
		)
		(fp_line
			(start 0.120396 0.3048)
			(end 0.120396 0.2794)
			(stroke
				(width 0.1)
				(type default)
			)
			(layer "F.Fab")
		)
		(fp_line
			(start -0.12065 0.3048)
			(end -0.67945 0.3048)
			(stroke
				(width 0.1)
				(type default)
			)
			(layer "F.Fab")
		)
		(fp_line
			(start -0.67945 0.3048)
			(end -0.67945 -0.305054)
			(stroke
				(width 0.1)
				(type default)
			)
			(layer "F.Fab")
		)
		(pad "1" smd circle
			(at -0.40005 0 90)
			(size 0 0)
			(layers "F.Cu" "F.Mask" "F.Paste")
			(net "FM_I3C_CPU0_MUX0_OE_N")
		)
		(pad "2" smd circle
			(at 0.40005 0 90)
			(size 0 0)
			(layers "F.Cu" "F.Mask" "F.Paste")
			(net "GND")
		)
	)
	(footprint ""
		(layer "F.Cu")
		(at 65.64757 -168.928542 180)
		(property "Reference" "PU24"
			(at -0.129032 -6.648704 0)
			(unlocked yes)
			(layer "F.SilkS")
			(effects
				(font
					(size 0.7874 0.5842)
					(thickness 0.1524)
				)
				(justify left)
			)
		)
		(property "Value" ""
			(at 0 0 180)
			(layer "F.Fab")
			(effects
				(font
					(size 1.27 1.27)
				)
			)
		)
		(duplicate_pad_numbers_are_jumpers no)
		(fp_line
			(start 2.500122 2.999994)
			(end 2.2987 2.999994)
			(stroke
				(width 0.1524)
				(type default)
			)
			(layer "F.SilkS")
		)
		(fp_line
			(start 2.500122 2.339594)
			(end 2.500122 2.999994)
			(stroke
				(width 0.1524)
				(type default)
			)
			(layer "F.SilkS")
		)
		(fp_line
			(start 2.500122 -2.999994)
			(end 2.500122 -2.44348)
			(stroke
				(width 0.1524)
				(type default)
			)
			(layer "F.SilkS")
		)
		(fp_line
			(start 2.31394 -2.999994)
			(end 2.500122 -2.999994)
			(stroke
				(width 0.1524)
				(type default)
			)
			(layer "F.SilkS")
		)
		(fp_line
			(start -2.2987 2.999994)
			(end -2.500122 2.999994)
			(stroke
				(width 0.1524)
				(type default)
			)
			(layer "F.SilkS")
		)
		(fp_line
			(start -2.500122 2.999994)
			(end -2.500122 2.339594)
			(stroke
				(width 0.1524)
				(type default)
			)
			(layer "F.SilkS")
		)
		(fp_line
			(start -2.500122 0.6604)
			(end -2.500122 0.229108)
			(stroke
				(width 0.1524)
				(type default)
			)
			(layer "F.SilkS")
		)
		(fp_line
			(start -2.500122 -2.529078)
			(end -2.500122 -2.999994)
			(stroke
				(width 0.1524)
				(type default)
			)
			(layer "F.SilkS")
		)
		(fp_line
			(start -2.500122 -2.999994)
			(end -2.24409 -2.999994)
			(stroke
				(width 0.1524)
				(type default)
			)
			(layer "F.SilkS")
		)
		(fp_poly
			(pts
				(xy -2.695956 -2.436622) (xy -3.492754 -2.702306) (xy -2.96164 -3.233166)
			)
			(stroke
				(width 0)
				(type default)
			)
			(fill yes)
			(layer "F.SilkS")
		)
		(fp_line
			(start 2.500122 2.999994)
			(end -2.500122 2.999994)
			(stroke
				(width 0.1)
				(type default)
			)
			(layer "F.Fab")
		)
		(fp_line
			(start 2.500122 -2.999994)
			(end 2.500122 2.999994)
			(stroke
				(width 0.1)
				(type default)
			)
			(layer "F.Fab")
		)
		(fp_line
			(start -2.500122 2.999994)
			(end -2.500122 -2.999994)
			(stroke
				(width 0.1)
				(type default)
			)
			(layer "F.Fab")
		)
		(fp_line
			(start -2.500122 -2.999994)
			(end 2.500122 -2.999994)
			(stroke
				(width 0.1)
				(type default)
			)
			(layer "F.Fab")
		)
		(fp_poly
			(pts
				(xy -4.218432 -2.783078) (xy -4.218432 -1.767078) (xy -3.202432 -2.275078)
			)
			(stroke
				(width 0)
				(type default)
			)
			(fill yes)
			(layer "F.Fab")
		)
		(pad "1" smd rect
			(at -2.400046 -2.275078 270)
			(size 0.2286 0.6096)
			(layers "F.Cu" "F.Mask" "F.Paste")
			(net "PVDDCR_CPU0_P1_VOS6")
		)
		(pad "2" smd rect
			(at -2.400046 -1.82499 270)
			(size 0.2286 0.6096)
			(layers "F.Cu" "F.Mask" "F.Paste")
			(net "GND")
		)
		(pad "3" smd rect
			(at -2.400046 -1.374902 270)
			(size 0.2286 0.6096)
			(layers "F.Cu" "F.Mask" "F.Paste")
			(net "PVDDCR_CPU0_P1_VCC6")
		)
		(pad "4" smd rect
			(at -2.400046 -0.925068 270)
			(size 0.2286 0.6096)
			(layers "F.Cu" "F.Mask" "F.Paste")
			(net "PVDDCR_CPU0_P1_PVCC")
		)
		(pad "5" smd rect
			(at -2.400046 -0.47498 270)
			(size 0.2286 0.6096)
			(layers "F.Cu" "F.Mask" "F.Paste")
			(net "GND")
		)
		(pad "6" smd rect
			(at -2.400046 -0.024892 270)
			(size 0.2286 0.6096)
			(layers "F.Cu" "F.Mask" "F.Paste")
			(net "NC_PVDDCR_CPU0_P1_GL1_6")
		)
		(pad "7_9-20_24" smd circle
			(at 0 1.150112 270)
			(size 0 0)
			(layers "F.Cu" "F.Mask" "F.Paste")
			(net "GND")
		)
		(pad "10_19" smd rect
			(at 0 2.899918 270)
			(size 0.6096 4.318)
			(layers "F.Cu" "F.Mask" "F.Paste")
			(net "SW_PVDDCR_CPU0_P1_SW6")
		)
		(pad "25_29" smd rect
			(at 1.549908 -1.279906 90)
			(size 2.0574 2.3114)
			(layers "F.Cu" "F.Mask" "F.Paste")
			(net "SW_P12V_AUX_PVDDCR_CPU0_P1_FLT")
		)
		(pad "30" smd rect
			(at 2.05994 -2.899918 180)
			(size 0.2286 0.6096)
			(layers "F.Cu" "F.Mask" "F.Paste")
			(net "SW_P12V_AUX_PVDDCR_CPU0_P1_FLT")
		)
		(pad "31" smd rect
			(at 1.610106 -2.899918 180)
			(size 0.2286 0.6096)
			(layers "F.Cu" "F.Mask" "F.Paste")
			(net "NC_PVDDCR_CPU0_P1_DNC6")
		)
		(pad "32" smd rect
			(at 1.160018 -2.899918 180)
			(size 0.2286 0.6096)
			(layers "F.Cu" "F.Mask" "F.Paste")
			(net "SW_PVDDCR_CPU0_P1_PH6")
		)
		(pad "33" smd rect
			(at 0.70993 -2.899918 180)
			(size 0.2286 0.6096)
			(layers "F.Cu" "F.Mask" "F.Paste")
			(net "SW_PVDDCR_CPU0_P1_BOOT6")
		)
		(pad "34" smd rect
			(at 0.260096 -2.899918 180)
			(size 0.2286 0.6096)
			(layers "F.Cu" "F.Mask" "F.Paste")
			(net "PVDDCR_CPU0_P1_PWM6")
		)
		(pad "35" smd rect
			(at -0.189992 -2.899918 180)
			(size 0.2286 0.6096)
			(layers "F.Cu" "F.Mask" "F.Paste")
			(net "PVDDCR_CPU0_P1_VCC6")
		)
		(pad "36" smd rect
			(at -0.64008 -2.899918 180)
			(size 0.2286 0.6096)
			(layers "F.Cu" "F.Mask" "F.Paste")
			(net "PVDDCR_CPU0_P1_TEMP0")
		)
		(pad "37" smd rect
			(at -1.089914 -2.899918 180)
			(size 0.2286 0.6096)
			(layers "F.Cu" "F.Mask" "F.Paste")
			(net "PVDDCR_CPU0_P1_LSET6")
		)
		(pad "38" smd rect
			(at -1.540002 -2.899918 180)
			(size 0.2286 0.6096)
			(layers "F.Cu" "F.Mask" "F.Paste")
			(net "PVDDCR_CPU0_P1_IMON6")
		)
		(pad "39" smd rect
			(at -1.99009 -2.899918 180)
			(size 0.2286 0.6096)
			(layers "F.Cu" "F.Mask" "F.Paste")
			(net "PVDDCR_CPU0_P1_VCCS")
		)
		(pad "40" smd rect
			(at -0.87503 -1.27508 180)
			(size 1.7526 1.9558)
			(layers "F.Cu" "F.Mask" "F.Paste")
			(net "GND")
		)
		(pad "41" smd rect
			(at -1.525016 0.249936 90)
			(size 0.3048 0.4572)
			(layers "F.Cu" "F.Mask" "F.Paste")
			(net "NC_PVDDCR_CPU0_P1_GL2_6")
		)
		(zone
			(layer "F.Cu")
			(hatch none 0.5)
			(connect_pads
				(clearance 0)
			)
			(min_thickness 0.25)
			(keepout
				(tracks not_allowed)
				(vias allowed)
				(pads allowed)
				(copperpour not_allowed)
				(footprints allowed)
			)
			(placement
				(enabled no)
				(sheetname "")
			)
			(fill
				(thermal_gap 0.5)
				(thermal_bridge_width 0.5)
				(island_removal_mode 0)
			)
			(polygon
				(pts
					(xy 68.147692 -171.47286) (xy 68.147692 -171.179236) (xy 63.147448 -171.179236) (xy 63.147448 -171.47286)
					(xy 63.43777 -171.47286) (xy 67.85737 -171.47286)
				)
			)
		)
		(zone
			(layer "F.Cu")
			(hatch none 0.5)
			(connect_pads
				(clearance 0)
			)
			(min_thickness 0.25)
			(keepout
				(tracks not_allowed)
				(vias allowed)
				(pads allowed)
				(copperpour not_allowed)
				(footprints allowed)
			)
			(placement
				(enabled no)
				(sheetname "")
			)
			(fill
				(thermal_gap 0.5)
				(thermal_bridge_width 0.5)
				(island_removal_mode 0)
			)
			(polygon
				(pts
					(xy 65.5955 -168.682162) (xy 65.5955 -166.624762) (xy 67.4497 -166.624762) (xy 67.4497 -166.865808)
					(xy 67.692016 -166.865808) (xy 67.692016 -166.384224) (xy 63.80353 -166.384224) (xy 63.80353 -166.569136)
					(xy 65.304162 -166.569136) (xy 65.304162 -168.728136) (xy 63.147448 -168.728136) (xy 63.147448 -168.977818)
					(xy 65.299844 -168.977818)
				)
			)
		)
	)
	(footprint ""
		(layer "F.Cu")
		(at 152.849326 -36.99256 180)
		(property "Reference" "R3229"
			(at 0 0 180)
			(layer "F.SilkS")
			(hide yes)
			(effects
				(font
					(size 1.27 1.27)
				)
			)
		)
		(property "Value" ""
			(at 0 0 180)
			(layer "F.Fab")
			(effects
				(font
					(size 1.27 1.27)
				)
			)
		)
		(duplicate_pad_numbers_are_jumpers no)
		(fp_line
			(start 0.7874 0.4064)
			(end -0.7874 0.4064)
			(stroke
				(width 0.1524)
				(type default)
			)
			(layer "F.SilkS")
		)
		(fp_line
			(start 0.7874 -0.4064)
			(end 0.7874 0.4064)
			(stroke
				(width 0.1524)
				(type default)
			)
			(layer "F.SilkS")
		)
		(fp_line
			(start -0.7874 0.4064)
			(end -0.7874 -0.4064)
			(stroke
				(width 0.1524)
				(type default)
			)
			(layer "F.SilkS")
		)
		(fp_line
			(start -0.7874 -0.4064)
			(end 0.7874 -0.4064)
			(stroke
				(width 0.1524)
				(type default)
			)
			(layer "F.SilkS")
		)
		(fp_line
			(start 0.67945 0.3048)
			(end 0.120396 0.3048)
			(stroke
				(width 0.1)
				(type default)
			)
			(layer "F.Fab")
		)
		(fp_line
			(start 0.67945 -0.3048)
			(end 0.67945 0.3048)
			(stroke
				(width 0.1)
				(type default)
			)
			(layer "F.Fab")
		)
		(fp_line
			(start 0.12065 -0.2794)
			(end 0.12065 -0.3048)
			(stroke
				(width 0.1)
				(type default)
			)
			(layer "F.Fab")
		)
		(fp_line
			(start 0.12065 -0.3048)
			(end 0.67945 -0.3048)
			(stroke
				(width 0.1)
				(type default)
			)
			(layer "F.Fab")
		)
		(fp_line
			(start 0.120396 0.3048)
			(end 0.120396 0.2794)
			(stroke
				(width 0.1)
				(type default)
			)
			(layer "F.Fab")
		)
		(fp_line
			(start 0.120396 0.2794)
			(end -0.12065 0.2794)
			(stroke
				(width 0.1)
				(type default)
			)
			(layer "F.Fab")
		)
		(fp_line
			(start -0.12065 0.3048)
			(end -0.67945 0.3048)
			(stroke
				(width 0.1)
				(type default)
			)
			(layer "F.Fab")
		)
		(fp_line
			(start -0.12065 0.2794)
			(end -0.12065 0.3048)
			(stroke
				(width 0.1)
				(type default)
			)
			(layer "F.Fab")
		)
		(fp_line
			(start -0.12065 -0.2794)
			(end 0.12065 -0.2794)
			(stroke
				(width 0.1)
				(type default)
			)
			(layer "F.Fab")
		)
		(fp_line
			(start -0.12065 -0.305054)
			(end -0.12065 -0.2794)
			(stroke
				(width 0.1)
				(type default)
			)
			(layer "F.Fab")
		)
		(fp_line
			(start -0.67945 0.3048)
			(end -0.67945 -0.305054)
			(stroke
				(width 0.1)
				(type default)
			)
			(layer "F.Fab")
		)
		(fp_line
			(start -0.67945 -0.305054)
			(end -0.12065 -0.305054)
			(stroke
				(width 0.1)
				(type default)
			)
			(layer "F.Fab")
		)
		(pad "1" smd circle
			(at -0.40005 0 180)
			(size 0 0)
			(layers "F.Cu" "F.Mask" "F.Paste")
			(net "SMB_OCP_V3_2_3V3AUX_BUF_R_SDA")
		)
		(pad "2" smd circle
			(at 0.40005 0 180)
			(size 0 0)
			(layers "F.Cu" "F.Mask" "F.Paste")
			(net "SMB_OCP_V3_2_3V3AUX_BUF_SDA")
		)
	)
	(footprint ""
		(layer "F.Cu")
		(at 220.872558 -401.920202 180)
		(property "Reference" "PU296"
			(at 2.818384 -5.05206 90)
			(unlocked yes)
			(layer "F.SilkS")
			(effects
				(font
					(size 0.7874 0.5842)
					(thickness 0.1524)
				)
			)
		)
		(property "Value" ""
			(at 0 0 180)
			(layer "F.Fab")
			(effects
				(font
					(size 1.27 1.27)
				)
			)
		)
		(duplicate_pad_numbers_are_jumpers no)
		(fp_line
			(start 2.567686 2.567686)
			(end 2.567686 -2.567686)
			(stroke
				(width 0.1524)
				(type default)
			)
			(layer "F.SilkS")
		)
		(fp_line
			(start 2.567686 -2.567686)
			(end -2.567686 -2.567686)
			(stroke
				(width 0.1524)
				(type default)
			)
			(layer "F.SilkS")
		)
		(fp_line
			(start -2.567686 2.567686)
			(end 2.567686 2.567686)
			(stroke
				(width 0.1524)
				(type default)
			)
			(layer "F.SilkS")
		)
		(fp_line
			(start -2.567686 -2.567686)
			(end -2.567686 2.567686)
			(stroke
				(width 0.1524)
				(type default)
			)
			(layer "F.SilkS")
		)
		(fp_poly
			(pts
				(xy -2.632456 -2.13233) (xy -3.709924 -2.491486) (xy -2.991612 -3.209798)
			)
			(stroke
				(width 0)
				(type default)
			)
			(fill yes)
			(layer "F.SilkS")
		)
		(fp_line
			(start 2.549906 2.549906)
			(end 2.549906 -2.549906)
			(stroke
				(width 0.1)
				(type default)
			)
			(layer "F.Fab")
		)
		(fp_line
			(start 2.549906 -2.549906)
			(end -2.549906 -2.549906)
			(stroke
				(width 0.1)
				(type default)
			)
			(layer "F.Fab")
		)
		(fp_line
			(start -2.549906 2.549906)
			(end 2.549906 2.549906)
			(stroke
				(width 0.1)
				(type default)
			)
			(layer "F.Fab")
		)
		(fp_line
			(start -2.549906 -2.549906)
			(end -2.549906 2.549906)
			(stroke
				(width 0.1)
				(type default)
			)
			(layer "F.Fab")
		)
		(fp_poly
			(pts
				(xy -3.806698 -2.25806) (xy -3.806698 -1.24206) (xy -2.790698 -1.75006)
			)
			(stroke
				(width 0)
				(type default)
			)
			(fill yes)
			(layer "F.Fab")
		)
		(pad "1" smd rect
			(at -2.250186 -1.75006 270)
			(size 0.254 0.3556)
			(layers "F.Cu" "F.Mask" "F.Paste")
			(net "P12V_AUX")
		)
		(pad "2" smd rect
			(at -2.237486 -1.249934 270)
			(size 0.254 0.381)
			(layers "F.Cu" "F.Mask" "F.Paste")
			(net "P12V_AUX")
		)
		(pad "3" smd rect
			(at -2.237486 -0.750062 270)
			(size 0.254 0.381)
			(layers "F.Cu" "F.Mask" "F.Paste")
			(net "HSC_D_OC_3")
		)
		(pad "4" smd rect
			(at -2.237486 -0.249936 270)
			(size 0.254 0.381)
			(layers "F.Cu" "F.Mask" "F.Paste")
			(net "HSC_ON")
		)
		(pad "5" smd rect
			(at -2.237486 0.249936 270)
			(size 0.254 0.381)
			(layers "F.Cu" "F.Mask" "F.Paste")
			(net "HSC_FAULT")
		)
		(pad "6" smd rect
			(at -2.237486 0.750062 270)
			(size 0.254 0.381)
			(layers "F.Cu" "F.Mask" "F.Paste")
			(net "HSC_FLT_TYPE_3")
		)
		(pad "7" smd rect
			(at -2.237486 1.249934 270)
			(size 0.254 0.381)
			(layers "F.Cu" "F.Mask" "F.Paste")
			(net "HSC_NC1_3")
		)
		(pad "8" smd rect
			(at -2.250186 1.75006 270)
			(size 0.254 0.3556)
			(layers "F.Cu" "F.Mask" "F.Paste")
			(net "HSC_MODE_3")
		)
		(pad "9" smd rect
			(at -1.75006 2.250186 180)
			(size 0.254 0.3556)
			(layers "F.Cu" "F.Mask" "F.Paste")
			(net "P12V_PSU")
		)
		(pad "10" smd rect
			(at -1.249934 2.237486 180)
			(size 0.254 0.381)
			(layers "F.Cu" "F.Mask" "F.Paste")
			(net "P12V_PSU")
		)
		(pad "11" smd rect
			(at -0.750062 2.237486 180)
			(size 0.254 0.381)
			(layers "F.Cu" "F.Mask" "F.Paste")
			(net "P12V_PSU")
		)
		(pad "12" smd rect
			(at -0.249936 2.237486 180)
			(size 0.254 0.381)
			(layers "F.Cu" "F.Mask" "F.Paste")
			(net "P12V_PSU")
		)
		(pad "13" smd rect
			(at 0.249936 2.237486 180)
			(size 0.254 0.381)
			(layers "F.Cu" "F.Mask" "F.Paste")
			(net "P12V_PSU")
		)
		(pad "14" smd rect
			(at 0.750062 2.237486 180)
			(size 0.254 0.381)
			(layers "F.Cu" "F.Mask" "F.Paste")
			(net "P12V_PSU")
		)
		(pad "15" smd rect
			(at 1.249934 2.237486 180)
			(size 0.254 0.381)
			(layers "F.Cu" "F.Mask" "F.Paste")
			(net "P12V_PSU")
		)
		(pad "16" smd rect
			(at 1.75006 2.250186 180)
			(size 0.254 0.3556)
			(layers "F.Cu" "F.Mask" "F.Paste")
			(net "P12V_PSU")
		)
		(pad "17" smd rect
			(at 2.250186 1.75006 270)
			(size 0.254 0.3556)
			(layers "F.Cu" "F.Mask" "F.Paste")
			(net "HSC_SCREF_3")
		)
		(pad "18" smd rect
			(at 2.237486 1.249934 270)
			(size 0.254 0.381)
			(layers "F.Cu" "F.Mask" "F.Paste")
			(net "HSC_VTEMP")
		)
		(pad "19" smd rect
			(at 2.237486 0.750062 270)
			(size 0.254 0.381)
			(layers "F.Cu" "F.Mask" "F.Paste")
			(net "HSC_SS")
		)
		(pad "20" smd rect
			(at 2.237486 0.249936 270)
			(size 0.254 0.381)
			(layers "F.Cu" "F.Mask" "F.Paste")
			(net "AGND_HSC")
		)
		(pad "21" smd rect
			(at 2.237486 -0.249936 270)
			(size 0.254 0.381)
			(layers "F.Cu" "F.Mask" "F.Paste")
			(net "HSC_VDD_R_3")
		)
		(pad "22" smd rect
			(at 2.237486 -0.750062 270)
			(size 0.254 0.381)
			(layers "F.Cu" "F.Mask" "F.Paste")
			(net "HSC_IMON")
		)
		(pad "23" smd rect
			(at 2.237486 -1.249934 270)
			(size 0.254 0.381)
			(layers "F.Cu" "F.Mask" "F.Paste")
			(net "HSC_CS_3")
		)
		(pad "24" smd rect
			(at 2.250186 -1.75006 270)
			(size 0.254 0.3556)
			(layers "F.Cu" "F.Mask" "F.Paste")
			(net "HSC_OCREF")
		)
		(pad "25" smd rect
			(at 1.75006 -2.250186 180)
			(size 0.254 0.3556)
			(layers "F.Cu" "F.Mask" "F.Paste")
			(net "P12V_AUX")
		)
		(pad "26" smd rect
			(at 1.249934 -2.237486 180)
			(size 0.254 0.381)
			(layers "F.Cu" "F.Mask" "F.Paste")
			(net "P12V_AUX")
		)
		(pad "27" smd rect
			(at 0.750062 -2.237486 180)
			(size 0.254 0.381)
			(layers "F.Cu" "F.Mask" "F.Paste")
			(net "P12V_AUX")
		)
		(pad "28" smd rect
			(at 0.249936 -2.237486 180)
			(size 0.254 0.381)
			(layers "F.Cu" "F.Mask" "F.Paste")
			(net "P12V_AUX")
		)
		(pad "29" smd rect
			(at -0.249936 -2.237486 180)
			(size 0.254 0.381)
			(layers "F.Cu" "F.Mask" "F.Paste")
			(net "P12V_AUX")
		)
		(pad "30" smd rect
			(at -0.750062 -2.237486 180)
			(size 0.254 0.381)
			(layers "F.Cu" "F.Mask" "F.Paste")
			(net "P12V_AUX")
		)
		(pad "31" smd rect
			(at -1.249934 -2.237486 180)
			(size 0.254 0.381)
			(layers "F.Cu" "F.Mask" "F.Paste")
			(net "P12V_AUX")
		)
		(pad "32" smd rect
			(at -1.75006 -2.250186 180)
			(size 0.254 0.3556)
			(layers "F.Cu" "F.Mask" "F.Paste")
			(net "P12V_AUX")
		)
		(pad "33" smd rect
			(at 0 0 180)
			(size 3.4036 3.4036)
			(layers "F.Cu" "F.Mask" "F.Paste")
			(net "P12V_PSU")
		)
		(zone
			(layer "F.Cu")
			(hatch none 0.5)
			(connect_pads
				(clearance 0)
			)
			(min_thickness 0.25)
			(keepout
				(tracks not_allowed)
				(vias allowed)
				(pads allowed)
				(copperpour not_allowed)
				(footprints allowed)
			)
			(placement
				(enabled no)
				(sheetname "")
			)
			(fill
				(thermal_gap 0.5)
				(thermal_bridge_width 0.5)
				(island_removal_mode 0)
			)
			(polygon
				(pts
					(xy 218.850972 -403.5806) (xy 219.119958 -403.5806) (xy 219.119958 -400.167602) (xy 222.625158 -400.167602)
					(xy 222.625158 -402.428202) (xy 222.868744 -402.428202) (xy 222.868744 -400.472402) (xy 222.894144 -400.472402)
					(xy 222.894144 -399.898616) (xy 222.320358 -399.898616) (xy 222.320358 -399.924016) (xy 219.424758 -399.924016)
					(xy 219.424758 -399.898616) (xy 218.850972 -399.898616) (xy 218.850972 -400.472402) (xy 218.876372 -400.472402)
					(xy 218.876372 -403.368002) (xy 218.850972 -403.368002)
				)
			)
		)
	)
	(footprint ""
		(layer "F.Cu")
		(at 365.835692 -258.405122 180)
		(property "Reference" "C2571"
			(at 0 0 180)
			(layer "F.SilkS")
			(hide yes)
			(effects
				(font
					(size 1.27 1.27)
				)
			)
		)
		(property "Value" ""
			(at 0 0 180)
			(layer "F.Fab")
			(effects
				(font
					(size 1.27 1.27)
				)
			)
		)
		(duplicate_pad_numbers_are_jumpers no)
		(fp_line
			(start 0.7874 0.4064)
			(end -0.7874 0.4064)
			(stroke
				(width 0.1524)
				(type default)
			)
			(layer "F.SilkS")
		)
		(fp_line
			(start 0.7874 -0.4064)
			(end 0.7874 0.4064)
			(stroke
				(width 0.1524)
				(type default)
			)
			(layer "F.SilkS")
		)
		(fp_line
			(start -0.7874 0.4064)
			(end -0.7874 -0.4064)
			(stroke
				(width 0.1524)
				(type default)
			)
			(layer "F.SilkS")
		)
		(fp_line
			(start -0.7874 -0.4064)
			(end 0.7874 -0.4064)
			(stroke
				(width 0.1524)
				(type default)
			)
			(layer "F.SilkS")
		)
		(fp_line
			(start 0.67945 0.3048)
			(end 0.120396 0.3048)
			(stroke
				(width 0.1)
				(type default)
			)
			(layer "F.Fab")
		)
		(fp_line
			(start 0.67945 -0.3048)
			(end 0.67945 0.3048)
			(stroke
				(width 0.1)
				(type default)
			)
			(layer "F.Fab")
		)
		(fp_line
			(start 0.12065 -0.2794)
			(end 0.12065 -0.3048)
			(stroke
				(width 0.1)
				(type default)
			)
			(layer "F.Fab")
		)
		(fp_line
			(start 0.12065 -0.3048)
			(end 0.67945 -0.3048)
			(stroke
				(width 0.1)
				(type default)
			)
			(layer "F.Fab")
		)
		(fp_line
			(start 0.120396 0.3048)
			(end 0.120396 0.2794)
			(stroke
				(width 0.1)
				(type default)
			)
			(layer "F.Fab")
		)
		(fp_line
			(start 0.120396 0.2794)
			(end -0.12065 0.2794)
			(stroke
				(width 0.1)
				(type default)
			)
			(layer "F.Fab")
		)
		(fp_line
			(start -0.12065 0.3048)
			(end -0.67945 0.3048)
			(stroke
				(width 0.1)
				(type default)
			)
			(layer "F.Fab")
		)
		(fp_line
			(start -0.12065 0.2794)
			(end -0.12065 0.3048)
			(stroke
				(width 0.1)
				(type default)
			)
			(layer "F.Fab")
		)
		(fp_line
			(start -0.12065 -0.2794)
			(end 0.12065 -0.2794)
			(stroke
				(width 0.1)
				(type default)
			)
			(layer "F.Fab")
		)
		(fp_line
			(start -0.12065 -0.305054)
			(end -0.12065 -0.2794)
			(stroke
				(width 0.1)
				(type default)
			)
			(layer "F.Fab")
		)
		(fp_line
			(start -0.67945 0.3048)
			(end -0.67945 -0.305054)
			(stroke
				(width 0.1)
				(type default)
			)
			(layer "F.Fab")
		)
		(fp_line
			(start -0.67945 -0.305054)
			(end -0.12065 -0.305054)
			(stroke
				(width 0.1)
				(type default)
			)
			(layer "F.Fab")
		)
		(pad "1" smd circle
			(at -0.40005 0 180)
			(size 0 0)
			(layers "F.Cu" "F.Mask" "F.Paste")
			(net "PVDDCR_SOC_P0")
		)
		(pad "2" smd circle
			(at 0.40005 0 180)
			(size 0 0)
			(layers "F.Cu" "F.Mask" "F.Paste")
			(net "GND")
		)
	)
	(footprint ""
		(layer "F.Cu")
		(at 108.355892 -258.795266)
		(property "Reference" "C2478"
			(at 0 0 0)
			(layer "F.SilkS")
			(hide yes)
			(effects
				(font
					(size 1.27 1.27)
				)
			)
		)
		(property "Value" ""
			(at 0 0 0)
			(layer "F.Fab")
			(effects
				(font
					(size 1.27 1.27)
				)
			)
		)
		(duplicate_pad_numbers_are_jumpers no)
		(fp_line
			(start -0.7874 -0.4064)
			(end 0.7874 -0.4064)
			(stroke
				(width 0.1524)
				(type default)
			)
			(layer "F.SilkS")
		)
		(fp_line
			(start -0.7874 0.4064)
			(end -0.7874 -0.4064)
			(stroke
				(width 0.1524)
				(type default)
			)
			(layer "F.SilkS")
		)
		(fp_line
			(start 0.7874 -0.4064)
			(end 0.7874 0.4064)
			(stroke
				(width 0.1524)
				(type default)
			)
			(layer "F.SilkS")
		)
		(fp_line
			(start 0.7874 0.4064)
			(end -0.7874 0.4064)
			(stroke
				(width 0.1524)
				(type default)
			)
			(layer "F.SilkS")
		)
		(fp_line
			(start -0.67945 -0.305054)
			(end -0.12065 -0.305054)
			(stroke
				(width 0.1)
				(type default)
			)
			(layer "F.Fab")
		)
		(fp_line
			(start -0.67945 0.3048)
			(end -0.67945 -0.305054)
			(stroke
				(width 0.1)
				(type default)
			)
			(layer "F.Fab")
		)
		(fp_line
			(start -0.12065 -0.305054)
			(end -0.12065 -0.2794)
			(stroke
				(width 0.1)
				(type default)
			)
			(layer "F.Fab")
		)
		(fp_line
			(start -0.12065 -0.2794)
			(end 0.12065 -0.2794)
			(stroke
				(width 0.1)
				(type default)
			)
			(layer "F.Fab")
		)
		(fp_line
			(start -0.12065 0.2794)
			(end -0.12065 0.3048)
			(stroke
				(width 0.1)
				(type default)
			)
			(layer "F.Fab")
		)
		(fp_line
			(start -0.12065 0.3048)
			(end -0.67945 0.3048)
			(stroke
				(width 0.1)
				(type default)
			)
			(layer "F.Fab")
		)
		(fp_line
			(start 0.120396 0.2794)
			(end -0.12065 0.2794)
			(stroke
				(width 0.1)
				(type default)
			)
			(layer "F.Fab")
		)
		(fp_line
			(start 0.120396 0.3048)
			(end 0.120396 0.2794)
			(stroke
				(width 0.1)
				(type default)
			)
			(layer "F.Fab")
		)
		(fp_line
			(start 0.12065 -0.3048)
			(end 0.67945 -0.3048)
			(stroke
				(width 0.1)
				(type default)
			)
			(layer "F.Fab")
		)
		(fp_line
			(start 0.12065 -0.2794)
			(end 0.12065 -0.3048)
			(stroke
				(width 0.1)
				(type default)
			)
			(layer "F.Fab")
		)
		(fp_line
			(start 0.67945 -0.3048)
			(end 0.67945 0.3048)
			(stroke
				(width 0.1)
				(type default)
			)
			(layer "F.Fab")
		)
		(fp_line
			(start 0.67945 0.3048)
			(end 0.120396 0.3048)
			(stroke
				(width 0.1)
				(type default)
			)
			(layer "F.Fab")
		)
		(pad "1" smd circle
			(at -0.40005 0)
			(size 0 0)
			(layers "F.Cu" "F.Mask" "F.Paste")
			(net "PVDDIO_P1")
		)
		(pad "2" smd circle
			(at 0.40005 0)
			(size 0 0)
			(layers "F.Cu" "F.Mask" "F.Paste")
			(net "GND")
		)
	)
	(footprint ""
		(layer "F.Cu")
		(at 38.180772 -55.869332 -90)
		(property "Reference" "R8025"
			(at 0 0 270)
			(layer "F.SilkS")
			(hide yes)
			(effects
				(font
					(size 1.27 1.27)
				)
			)
		)
		(property "Value" ""
			(at 0 0 270)
			(layer "F.Fab")
			(effects
				(font
					(size 1.27 1.27)
				)
			)
		)
		(duplicate_pad_numbers_are_jumpers no)
		(fp_line
			(start -0.7874 0.4064)
			(end -0.7874 -0.4064)
			(stroke
				(width 0.1524)
				(type default)
			)
			(layer "F.SilkS")
		)
		(fp_line
			(start 0.7874 0.4064)
			(end -0.7874 0.4064)
			(stroke
				(width 0.1524)
				(type default)
			)
			(layer "F.SilkS")
		)
		(fp_line
			(start -0.7874 -0.4064)
			(end 0.7874 -0.4064)
			(stroke
				(width 0.1524)
				(type default)
			)
			(layer "F.SilkS")
		)
		(fp_line
			(start 0.7874 -0.4064)
			(end 0.7874 0.4064)
			(stroke
				(width 0.1524)
				(type default)
			)
			(layer "F.SilkS")
		)
		(fp_line
			(start -0.67945 0.3048)
			(end -0.67945 -0.305054)
			(stroke
				(width 0.1)
				(type default)
			)
			(layer "F.Fab")
		)
		(fp_line
			(start -0.12065 0.3048)
			(end -0.67945 0.3048)
			(stroke
				(width 0.1)
				(type default)
			)
			(layer "F.Fab")
		)
		(fp_line
			(start 0.120396 0.3048)
			(end 0.120396 0.2794)
			(stroke
				(width 0.1)
				(type default)
			)
			(layer "F.Fab")
		)
		(fp_line
			(start 0.67945 0.3048)
			(end 0.120396 0.3048)
			(stroke
				(width 0.1)
				(type default)
			)
			(layer "F.Fab")
		)
		(fp_line
			(start -0.12065 0.2794)
			(end -0.12065 0.3048)
			(stroke
				(width 0.1)
				(type default)
			)
			(layer "F.Fab")
		)
		(fp_line
			(start 0.120396 0.2794)
			(end -0.12065 0.2794)
			(stroke
				(width 0.1)
				(type default)
			)
			(layer "F.Fab")
		)
		(fp_line
			(start -0.12065 -0.2794)
			(end 0.12065 -0.2794)
			(stroke
				(width 0.1)
				(type default)
			)
			(layer "F.Fab")
		)
		(fp_line
			(start 0.12065 -0.2794)
			(end 0.12065 -0.3048)
			(stroke
				(width 0.1)
				(type default)
			)
			(layer "F.Fab")
		)
		(fp_line
			(start 0.12065 -0.3048)
			(end 0.67945 -0.3048)
			(stroke
				(width 0.1)
				(type default)
			)
			(layer "F.Fab")
		)
		(fp_line
			(start 0.67945 -0.3048)
			(end 0.67945 0.3048)
			(stroke
				(width 0.1)
				(type default)
			)
			(layer "F.Fab")
		)
		(fp_line
			(start -0.67945 -0.305054)
			(end -0.12065 -0.305054)
			(stroke
				(width 0.1)
				(type default)
			)
			(layer "F.Fab")
		)
		(fp_line
			(start -0.12065 -0.305054)
			(end -0.12065 -0.2794)
			(stroke
				(width 0.1)
				(type default)
			)
			(layer "F.Fab")
		)
		(pad "1" smd circle
			(at -0.40005 0 270)
			(size 0 0)
			(layers "F.Cu" "F.Mask" "F.Paste")
			(net "LED_P12V_PSU_R1")
		)
		(pad "2" smd circle
			(at 0.40005 0 270)
			(size 0 0)
			(layers "F.Cu" "F.Mask" "F.Paste")
			(net "LED_P12V_PSU_R2")
		)
	)
	(footprint ""
		(layer "F.Cu")
		(at 420.06266 -109.231176 -90)
		(property "Reference" "R3845"
			(at 0 0 270)
			(layer "F.SilkS")
			(hide yes)
			(effects
				(font
					(size 1.27 1.27)
				)
			)
		)
		(property "Value" ""
			(at 0 0 270)
			(layer "F.Fab")
			(effects
				(font
					(size 1.27 1.27)
				)
			)
		)
		(duplicate_pad_numbers_are_jumpers no)
		(fp_line
			(start -0.7874 0.4064)
			(end -0.7874 -0.4064)
			(stroke
				(width 0.1524)
				(type default)
			)
			(layer "F.SilkS")
		)
		(fp_line
			(start 0.7874 0.4064)
			(end -0.7874 0.4064)
			(stroke
				(width 0.1524)
				(type default)
			)
			(layer "F.SilkS")
		)
		(fp_line
			(start -0.7874 -0.4064)
			(end 0.7874 -0.4064)
			(stroke
				(width 0.1524)
				(type default)
			)
			(layer "F.SilkS")
		)
		(fp_line
			(start 0.7874 -0.4064)
			(end 0.7874 0.4064)
			(stroke
				(width 0.1524)
				(type default)
			)
			(layer "F.SilkS")
		)
		(fp_line
			(start -0.67945 0.3048)
			(end -0.67945 -0.305054)
			(stroke
				(width 0.1)
				(type default)
			)
			(layer "F.Fab")
		)
		(fp_line
			(start -0.12065 0.3048)
			(end -0.67945 0.3048)
			(stroke
				(width 0.1)
				(type default)
			)
			(layer "F.Fab")
		)
		(fp_line
			(start 0.120396 0.3048)
			(end 0.120396 0.2794)
			(stroke
				(width 0.1)
				(type default)
			)
			(layer "F.Fab")
		)
		(fp_line
			(start 0.67945 0.3048)
			(end 0.120396 0.3048)
			(stroke
				(width 0.1)
				(type default)
			)
			(layer "F.Fab")
		)
		(fp_line
			(start -0.12065 0.2794)
			(end -0.12065 0.3048)
			(stroke
				(width 0.1)
				(type default)
			)
			(layer "F.Fab")
		)
		(fp_line
			(start 0.120396 0.2794)
			(end -0.12065 0.2794)
			(stroke
				(width 0.1)
				(type default)
			)
			(layer "F.Fab")
		)
		(fp_line
			(start -0.12065 -0.2794)
			(end 0.12065 -0.2794)
			(stroke
				(width 0.1)
				(type default)
			)
			(layer "F.Fab")
		)
		(fp_line
			(start 0.12065 -0.2794)
			(end 0.12065 -0.3048)
			(stroke
				(width 0.1)
				(type default)
			)
			(layer "F.Fab")
		)
		(fp_line
			(start 0.12065 -0.3048)
			(end 0.67945 -0.3048)
			(stroke
				(width 0.1)
				(type default)
			)
			(layer "F.Fab")
		)
		(fp_line
			(start 0.67945 -0.3048)
			(end 0.67945 0.3048)
			(stroke
				(width 0.1)
				(type default)
			)
			(layer "F.Fab")
		)
		(fp_line
			(start -0.67945 -0.305054)
			(end -0.12065 -0.305054)
			(stroke
				(width 0.1)
				(type default)
			)
			(layer "F.Fab")
		)
		(fp_line
			(start -0.12065 -0.305054)
			(end -0.12065 -0.2794)
			(stroke
				(width 0.1)
				(type default)
			)
			(layer "F.Fab")
		)
		(pad "1" smd circle
			(at -0.40005 0 270)
			(size 0 0)
			(layers "F.Cu" "F.Mask" "F.Paste")
			(net "P3V3_OCP_SFF_EN_R")
		)
		(pad "2" smd circle
			(at 0.40005 0 270)
			(size 0 0)
			(layers "F.Cu" "F.Mask" "F.Paste")
			(net "P3V3_OCP_EN_1_R2")
		)
	)
	(footprint ""
		(layer "F.Cu")
		(at 184.310528 -426.40504 -90)
		(property "Reference" "R3517"
			(at 0 0 270)
			(layer "F.SilkS")
			(hide yes)
			(effects
				(font
					(size 1.27 1.27)
				)
			)
		)
		(property "Value" ""
			(at 0 0 270)
			(layer "F.Fab")
			(effects
				(font
					(size 1.27 1.27)
				)
			)
		)
		(duplicate_pad_numbers_are_jumpers no)
		(fp_line
			(start -0.7874 0.4064)
			(end -0.7874 -0.4064)
			(stroke
				(width 0.1524)
				(type default)
			)
			(layer "F.SilkS")
		)
		(fp_line
			(start 0.7874 0.4064)
			(end -0.7874 0.4064)
			(stroke
				(width 0.1524)
				(type default)
			)
			(layer "F.SilkS")
		)
		(fp_line
			(start -0.7874 -0.4064)
			(end 0.7874 -0.4064)
			(stroke
				(width 0.1524)
				(type default)
			)
			(layer "F.SilkS")
		)
		(fp_line
			(start 0.7874 -0.4064)
			(end 0.7874 0.4064)
			(stroke
				(width 0.1524)
				(type default)
			)
			(layer "F.SilkS")
		)
		(fp_line
			(start -0.67945 0.3048)
			(end -0.67945 -0.305054)
			(stroke
				(width 0.1)
				(type default)
			)
			(layer "F.Fab")
		)
		(fp_line
			(start -0.12065 0.3048)
			(end -0.67945 0.3048)
			(stroke
				(width 0.1)
				(type default)
			)
			(layer "F.Fab")
		)
		(fp_line
			(start 0.120396 0.3048)
			(end 0.120396 0.2794)
			(stroke
				(width 0.1)
				(type default)
			)
			(layer "F.Fab")
		)
		(fp_line
			(start 0.67945 0.3048)
			(end 0.120396 0.3048)
			(stroke
				(width 0.1)
				(type default)
			)
			(layer "F.Fab")
		)
		(fp_line
			(start -0.12065 0.2794)
			(end -0.12065 0.3048)
			(stroke
				(width 0.1)
				(type default)
			)
			(layer "F.Fab")
		)
		(fp_line
			(start 0.120396 0.2794)
			(end -0.12065 0.2794)
			(stroke
				(width 0.1)
				(type default)
			)
			(layer "F.Fab")
		)
		(fp_line
			(start -0.12065 -0.2794)
			(end 0.12065 -0.2794)
			(stroke
				(width 0.1)
				(type default)
			)
			(layer "F.Fab")
		)
		(fp_line
			(start 0.12065 -0.2794)
			(end 0.12065 -0.3048)
			(stroke
				(width 0.1)
				(type default)
			)
			(layer "F.Fab")
		)
		(fp_line
			(start 0.12065 -0.3048)
			(end 0.67945 -0.3048)
			(stroke
				(width 0.1)
				(type default)
			)
			(layer "F.Fab")
		)
		(fp_line
			(start 0.67945 -0.3048)
			(end 0.67945 0.3048)
			(stroke
				(width 0.1)
				(type default)
			)
			(layer "F.Fab")
		)
		(fp_line
			(start -0.67945 -0.305054)
			(end -0.12065 -0.305054)
			(stroke
				(width 0.1)
				(type default)
			)
			(layer "F.Fab")
		)
		(fp_line
			(start -0.12065 -0.305054)
			(end -0.12065 -0.2794)
			(stroke
				(width 0.1)
				(type default)
			)
			(layer "F.Fab")
		)
		(pad "1" smd circle
			(at -0.40005 0 270)
			(size 0 0)
			(layers "F.Cu" "F.Mask" "F.Paste")
			(net "GPU_PEX_STRAP1")
		)
		(pad "2" smd circle
			(at 0.40005 0 270)
			(size 0 0)
			(layers "F.Cu" "F.Mask" "F.Paste")
			(net "GPU_PEX_STRAP1_R")
		)
	)
	(footprint ""
		(layer "F.Cu")
		(at 388.074662 -143.323056 -90)
		(property "Reference" "R6076"
			(at 0 0 270)
			(layer "F.SilkS")
			(hide yes)
			(effects
				(font
					(size 1.27 1.27)
				)
			)
		)
		(property "Value" ""
			(at 0 0 270)
			(layer "F.Fab")
			(effects
				(font
					(size 1.27 1.27)
				)
			)
		)
		(duplicate_pad_numbers_are_jumpers no)
		(fp_line
			(start -0.7874 0.4064)
			(end -0.7874 -0.4064)
			(stroke
				(width 0.1524)
				(type default)
			)
			(layer "F.SilkS")
		)
		(fp_line
			(start 0.7874 0.4064)
			(end -0.7874 0.4064)
			(stroke
				(width 0.1524)
				(type default)
			)
			(layer "F.SilkS")
		)
		(fp_line
			(start -0.7874 -0.4064)
			(end 0.7874 -0.4064)
			(stroke
				(width 0.1524)
				(type default)
			)
			(layer "F.SilkS")
		)
		(fp_line
			(start 0.7874 -0.4064)
			(end 0.7874 0.4064)
			(stroke
				(width 0.1524)
				(type default)
			)
			(layer "F.SilkS")
		)
		(fp_line
			(start -0.67945 0.3048)
			(end -0.67945 -0.305054)
			(stroke
				(width 0.1)
				(type default)
			)
			(layer "F.Fab")
		)
		(fp_line
			(start -0.12065 0.3048)
			(end -0.67945 0.3048)
			(stroke
				(width 0.1)
				(type default)
			)
			(layer "F.Fab")
		)
		(fp_line
			(start 0.120396 0.3048)
			(end 0.120396 0.2794)
			(stroke
				(width 0.1)
				(type default)
			)
			(layer "F.Fab")
		)
		(fp_line
			(start 0.67945 0.3048)
			(end 0.120396 0.3048)
			(stroke
				(width 0.1)
				(type default)
			)
			(layer "F.Fab")
		)
		(fp_line
			(start -0.12065 0.2794)
			(end -0.12065 0.3048)
			(stroke
				(width 0.1)
				(type default)
			)
			(layer "F.Fab")
		)
		(fp_line
			(start 0.120396 0.2794)
			(end -0.12065 0.2794)
			(stroke
				(width 0.1)
				(type default)
			)
			(layer "F.Fab")
		)
		(fp_line
			(start -0.12065 -0.2794)
			(end 0.12065 -0.2794)
			(stroke
				(width 0.1)
				(type default)
			)
			(layer "F.Fab")
		)
		(fp_line
			(start 0.12065 -0.2794)
			(end 0.12065 -0.3048)
			(stroke
				(width 0.1)
				(type default)
			)
			(layer "F.Fab")
		)
		(fp_line
			(start 0.12065 -0.3048)
			(end 0.67945 -0.3048)
			(stroke
				(width 0.1)
				(type default)
			)
			(layer "F.Fab")
		)
		(fp_line
			(start 0.67945 -0.3048)
			(end 0.67945 0.3048)
			(stroke
				(width 0.1)
				(type default)
			)
			(layer "F.Fab")
		)
		(fp_line
			(start -0.67945 -0.305054)
			(end -0.12065 -0.305054)
			(stroke
				(width 0.1)
				(type default)
			)
			(layer "F.Fab")
		)
		(fp_line
			(start -0.12065 -0.305054)
			(end -0.12065 -0.2794)
			(stroke
				(width 0.1)
				(type default)
			)
			(layer "F.Fab")
		)
		(pad "1" smd circle
			(at -0.40005 0 270)
			(size 0 0)
			(layers "F.Cu" "F.Mask" "F.Paste")
			(net "SMB_SCM_2_R3_SCL")
		)
		(pad "2" smd circle
			(at 0.40005 0 270)
			(size 0 0)
			(layers "F.Cu" "F.Mask" "F.Paste")
			(net "SMB_SCM_2_R4_SCL")
		)
	)
	(footprint ""
		(layer "F.Cu")
		(at 365.835692 -262.204962 180)
		(property "Reference" "C2133"
			(at 0 0 180)
			(layer "F.SilkS")
			(hide yes)
			(effects
				(font
					(size 1.27 1.27)
				)
			)
		)
		(property "Value" ""
			(at 0 0 180)
			(layer "F.Fab")
			(effects
				(font
					(size 1.27 1.27)
				)
			)
		)
		(duplicate_pad_numbers_are_jumpers no)
		(fp_line
			(start 0.7874 0.4064)
			(end -0.7874 0.4064)
			(stroke
				(width 0.1524)
				(type default)
			)
			(layer "F.SilkS")
		)
		(fp_line
			(start 0.7874 -0.4064)
			(end 0.7874 0.4064)
			(stroke
				(width 0.1524)
				(type default)
			)
			(layer "F.SilkS")
		)
		(fp_line
			(start -0.7874 0.4064)
			(end -0.7874 -0.4064)
			(stroke
				(width 0.1524)
				(type default)
			)
			(layer "F.SilkS")
		)
		(fp_line
			(start -0.7874 -0.4064)
			(end 0.7874 -0.4064)
			(stroke
				(width 0.1524)
				(type default)
			)
			(layer "F.SilkS")
		)
		(fp_line
			(start 0.67945 0.3048)
			(end 0.120396 0.3048)
			(stroke
				(width 0.1)
				(type default)
			)
			(layer "F.Fab")
		)
		(fp_line
			(start 0.67945 -0.3048)
			(end 0.67945 0.3048)
			(stroke
				(width 0.1)
				(type default)
			)
			(layer "F.Fab")
		)
		(fp_line
			(start 0.12065 -0.2794)
			(end 0.12065 -0.3048)
			(stroke
				(width 0.1)
				(type default)
			)
			(layer "F.Fab")
		)
		(fp_line
			(start 0.12065 -0.3048)
			(end 0.67945 -0.3048)
			(stroke
				(width 0.1)
				(type default)
			)
			(layer "F.Fab")
		)
		(fp_line
			(start 0.120396 0.3048)
			(end 0.120396 0.2794)
			(stroke
				(width 0.1)
				(type default)
			)
			(layer "F.Fab")
		)
		(fp_line
			(start 0.120396 0.2794)
			(end -0.12065 0.2794)
			(stroke
				(width 0.1)
				(type default)
			)
			(layer "F.Fab")
		)
		(fp_line
			(start -0.12065 0.3048)
			(end -0.67945 0.3048)
			(stroke
				(width 0.1)
				(type default)
			)
			(layer "F.Fab")
		)
		(fp_line
			(start -0.12065 0.2794)
			(end -0.12065 0.3048)
			(stroke
				(width 0.1)
				(type default)
			)
			(layer "F.Fab")
		)
		(fp_line
			(start -0.12065 -0.2794)
			(end 0.12065 -0.2794)
			(stroke
				(width 0.1)
				(type default)
			)
			(layer "F.Fab")
		)
		(fp_line
			(start -0.12065 -0.305054)
			(end -0.12065 -0.2794)
			(stroke
				(width 0.1)
				(type default)
			)
			(layer "F.Fab")
		)
		(fp_line
			(start -0.67945 0.3048)
			(end -0.67945 -0.305054)
			(stroke
				(width 0.1)
				(type default)
			)
			(layer "F.Fab")
		)
		(fp_line
			(start -0.67945 -0.305054)
			(end -0.12065 -0.305054)
			(stroke
				(width 0.1)
				(type default)
			)
			(layer "F.Fab")
		)
		(pad "1" smd circle
			(at -0.40005 0 180)
			(size 0 0)
			(layers "F.Cu" "F.Mask" "F.Paste")
			(net "PVDD11_S3_P0")
		)
		(pad "2" smd circle
			(at 0.40005 0 180)
			(size 0 0)
			(layers "F.Cu" "F.Mask" "F.Paste")
			(net "GND")
		)
	)
	(footprint ""
		(layer "F.Cu")
		(at 363.645958 -257.744976)
		(property "Reference" "C2564"
			(at 0 0 0)
			(layer "F.SilkS")
			(hide yes)
			(effects
				(font
					(size 1.27 1.27)
				)
			)
		)
		(property "Value" ""
			(at 0 0 0)
			(layer "F.Fab")
			(effects
				(font
					(size 1.27 1.27)
				)
			)
		)
		(duplicate_pad_numbers_are_jumpers no)
		(fp_line
			(start -0.7874 -0.4064)
			(end 0.7874 -0.4064)
			(stroke
				(width 0.1524)
				(type default)
			)
			(layer "F.SilkS")
		)
		(fp_line
			(start -0.7874 0.4064)
			(end -0.7874 -0.4064)
			(stroke
				(width 0.1524)
				(type default)
			)
			(layer "F.SilkS")
		)
		(fp_line
			(start 0.7874 -0.4064)
			(end 0.7874 0.4064)
			(stroke
				(width 0.1524)
				(type default)
			)
			(layer "F.SilkS")
		)
		(fp_line
			(start 0.7874 0.4064)
			(end -0.7874 0.4064)
			(stroke
				(width 0.1524)
				(type default)
			)
			(layer "F.SilkS")
		)
		(fp_line
			(start -0.67945 -0.305054)
			(end -0.12065 -0.305054)
			(stroke
				(width 0.1)
				(type default)
			)
			(layer "F.Fab")
		)
		(fp_line
			(start -0.67945 0.3048)
			(end -0.67945 -0.305054)
			(stroke
				(width 0.1)
				(type default)
			)
			(layer "F.Fab")
		)
		(fp_line
			(start -0.12065 -0.305054)
			(end -0.12065 -0.2794)
			(stroke
				(width 0.1)
				(type default)
			)
			(layer "F.Fab")
		)
		(fp_line
			(start -0.12065 -0.2794)
			(end 0.12065 -0.2794)
			(stroke
				(width 0.1)
				(type default)
			)
			(layer "F.Fab")
		)
		(fp_line
			(start -0.12065 0.2794)
			(end -0.12065 0.3048)
			(stroke
				(width 0.1)
				(type default)
			)
			(layer "F.Fab")
		)
		(fp_line
			(start -0.12065 0.3048)
			(end -0.67945 0.3048)
			(stroke
				(width 0.1)
				(type default)
			)
			(layer "F.Fab")
		)
		(fp_line
			(start 0.120396 0.2794)
			(end -0.12065 0.2794)
			(stroke
				(width 0.1)
				(type default)
			)
			(layer "F.Fab")
		)
		(fp_line
			(start 0.120396 0.3048)
			(end 0.120396 0.2794)
			(stroke
				(width 0.1)
				(type default)
			)
			(layer "F.Fab")
		)
		(fp_line
			(start 0.12065 -0.3048)
			(end 0.67945 -0.3048)
			(stroke
				(width 0.1)
				(type default)
			)
			(layer "F.Fab")
		)
		(fp_line
			(start 0.12065 -0.2794)
			(end 0.12065 -0.3048)
			(stroke
				(width 0.1)
				(type default)
			)
			(layer "F.Fab")
		)
		(fp_line
			(start 0.67945 -0.3048)
			(end 0.67945 0.3048)
			(stroke
				(width 0.1)
				(type default)
			)
			(layer "F.Fab")
		)
		(fp_line
			(start 0.67945 0.3048)
			(end 0.120396 0.3048)
			(stroke
				(width 0.1)
				(type default)
			)
			(layer "F.Fab")
		)
		(pad "1" smd circle
			(at -0.40005 0)
			(size 0 0)
			(layers "F.Cu" "F.Mask" "F.Paste")
			(net "PVDDCR_SOC_P0")
		)
		(pad "2" smd circle
			(at 0.40005 0)
			(size 0 0)
			(layers "F.Cu" "F.Mask" "F.Paste")
			(net "GND")
		)
	)
	(footprint ""
		(layer "F.Cu")
		(at 463.371946 -108.567728 180)
		(property "Reference" "R1150"
			(at 0 0 180)
			(layer "F.SilkS")
			(hide yes)
			(effects
				(font
					(size 1.27 1.27)
				)
			)
		)
		(property "Value" ""
			(at 0 0 180)
			(layer "F.Fab")
			(effects
				(font
					(size 1.27 1.27)
				)
			)
		)
		(duplicate_pad_numbers_are_jumpers no)
		(fp_line
			(start 0.7874 0.4064)
			(end -0.7874 0.4064)
			(stroke
				(width 0.1524)
				(type default)
			)
			(layer "F.SilkS")
		)
		(fp_line
			(start 0.7874 -0.4064)
			(end 0.7874 0.4064)
			(stroke
				(width 0.1524)
				(type default)
			)
			(layer "F.SilkS")
		)
		(fp_line
			(start -0.7874 0.4064)
			(end -0.7874 -0.4064)
			(stroke
				(width 0.1524)
				(type default)
			)
			(layer "F.SilkS")
		)
		(fp_line
			(start -0.7874 -0.4064)
			(end 0.7874 -0.4064)
			(stroke
				(width 0.1524)
				(type default)
			)
			(layer "F.SilkS")
		)
		(fp_line
			(start 0.67945 0.3048)
			(end 0.120396 0.3048)
			(stroke
				(width 0.1)
				(type default)
			)
			(layer "F.Fab")
		)
		(fp_line
			(start 0.67945 -0.3048)
			(end 0.67945 0.3048)
			(stroke
				(width 0.1)
				(type default)
			)
			(layer "F.Fab")
		)
		(fp_line
			(start 0.12065 -0.2794)
			(end 0.12065 -0.3048)
			(stroke
				(width 0.1)
				(type default)
			)
			(layer "F.Fab")
		)
		(fp_line
			(start 0.12065 -0.3048)
			(end 0.67945 -0.3048)
			(stroke
				(width 0.1)
				(type default)
			)
			(layer "F.Fab")
		)
		(fp_line
			(start 0.120396 0.3048)
			(end 0.120396 0.2794)
			(stroke
				(width 0.1)
				(type default)
			)
			(layer "F.Fab")
		)
		(fp_line
			(start 0.120396 0.2794)
			(end -0.12065 0.2794)
			(stroke
				(width 0.1)
				(type default)
			)
			(layer "F.Fab")
		)
		(fp_line
			(start -0.12065 0.3048)
			(end -0.67945 0.3048)
			(stroke
				(width 0.1)
				(type default)
			)
			(layer "F.Fab")
		)
		(fp_line
			(start -0.12065 0.2794)
			(end -0.12065 0.3048)
			(stroke
				(width 0.1)
				(type default)
			)
			(layer "F.Fab")
		)
		(fp_line
			(start -0.12065 -0.2794)
			(end 0.12065 -0.2794)
			(stroke
				(width 0.1)
				(type default)
			)
			(layer "F.Fab")
		)
		(fp_line
			(start -0.12065 -0.305054)
			(end -0.12065 -0.2794)
			(stroke
				(width 0.1)
				(type default)
			)
			(layer "F.Fab")
		)
		(fp_line
			(start -0.67945 0.3048)
			(end -0.67945 -0.305054)
			(stroke
				(width 0.1)
				(type default)
			)
			(layer "F.Fab")
		)
		(fp_line
			(start -0.67945 -0.305054)
			(end -0.12065 -0.305054)
			(stroke
				(width 0.1)
				(type default)
			)
			(layer "F.Fab")
		)
		(pad "1" smd circle
			(at -0.40005 0 180)
			(size 0 0)
			(layers "F.Cu" "F.Mask" "F.Paste")
			(net "P3V3_AUX")
		)
		(pad "2" smd circle
			(at 0.40005 0 180)
			(size 0 0)
			(layers "F.Cu" "F.Mask" "F.Paste")
			(net "HP_LVC3_OCP_SFF_PRSNT2_PLD_N")
		)
	)
	(footprint ""
		(layer "F.Cu")
		(at 306.262532 -410.406596 90)
		(property "Reference" "C7033"
			(at 0 0 90)
			(layer "F.SilkS")
			(hide yes)
			(effects
				(font
					(size 1.27 1.27)
				)
			)
		)
		(property "Value" ""
			(at 0 0 90)
			(layer "F.Fab")
			(effects
				(font
					(size 1.27 1.27)
				)
			)
		)
		(duplicate_pad_numbers_are_jumpers no)
		(fp_line
			(start 1.524 -0.762)
			(end 1.524 0.762)
			(stroke
				(width 0.1524)
				(type default)
			)
			(layer "F.SilkS")
		)
		(fp_line
			(start -1.524 -0.762)
			(end 1.524 -0.762)
			(stroke
				(width 0.1524)
				(type default)
			)
			(layer "F.SilkS")
		)
		(fp_line
			(start 1.524 0.762)
			(end -1.524 0.762)
			(stroke
				(width 0.1524)
				(type default)
			)
			(layer "F.SilkS")
		)
		(fp_line
			(start -1.524 0.762)
			(end -1.524 -0.762)
			(stroke
				(width 0.1524)
				(type default)
			)
			(layer "F.SilkS")
		)
		(fp_line
			(start 1.1049 -0.724916)
			(end -1.1049 -0.724916)
			(stroke
				(width 0.1)
				(type default)
			)
			(layer "F.Fab")
		)
		(fp_line
			(start -1.1049 -0.724916)
			(end -1.1049 0.724916)
			(stroke
				(width 0.1)
				(type default)
			)
			(layer "F.Fab")
		)
		(fp_line
			(start 1.1049 0.724916)
			(end 1.1049 -0.724916)
			(stroke
				(width 0.1)
				(type default)
			)
			(layer "F.Fab")
		)
		(fp_line
			(start -1.1049 0.724916)
			(end 1.1049 0.724916)
			(stroke
				(width 0.1)
				(type default)
			)
			(layer "F.Fab")
		)
		(pad "1" smd rect
			(at -0.889 0 270)
			(size 1.016 1.27)
			(layers "F.Cu" "F.Mask" "F.Paste")
			(net "P0V9_CPU0_RT_2D")
		)
		(pad "2" smd rect
			(at 0.889 0 270)
			(size 1.016 1.27)
			(layers "F.Cu" "F.Mask" "F.Paste")
			(net "GND")
		)
	)
	(footprint ""
		(layer "F.Cu")
		(at 273.378676 -119.761 180)
		(property "Reference" "R1316"
			(at 0 0 180)
			(layer "F.SilkS")
			(hide yes)
			(effects
				(font
					(size 1.27 1.27)
				)
			)
		)
		(property "Value" ""
			(at 0 0 180)
			(layer "F.Fab")
			(effects
				(font
					(size 1.27 1.27)
				)
			)
		)
		(duplicate_pad_numbers_are_jumpers no)
		(fp_line
			(start 0.7874 0.4064)
			(end -0.7874 0.4064)
			(stroke
				(width 0.1524)
				(type default)
			)
			(layer "F.SilkS")
		)
		(fp_line
			(start 0.7874 -0.4064)
			(end 0.7874 0.4064)
			(stroke
				(width 0.1524)
				(type default)
			)
			(layer "F.SilkS")
		)
		(fp_line
			(start -0.7874 0.4064)
			(end -0.7874 -0.4064)
			(stroke
				(width 0.1524)
				(type default)
			)
			(layer "F.SilkS")
		)
		(fp_line
			(start -0.7874 -0.4064)
			(end 0.7874 -0.4064)
			(stroke
				(width 0.1524)
				(type default)
			)
			(layer "F.SilkS")
		)
		(fp_line
			(start 0.67945 0.3048)
			(end 0.120396 0.3048)
			(stroke
				(width 0.1)
				(type default)
			)
			(layer "F.Fab")
		)
		(fp_line
			(start 0.67945 -0.3048)
			(end 0.67945 0.3048)
			(stroke
				(width 0.1)
				(type default)
			)
			(layer "F.Fab")
		)
		(fp_line
			(start 0.12065 -0.2794)
			(end 0.12065 -0.3048)
			(stroke
				(width 0.1)
				(type default)
			)
			(layer "F.Fab")
		)
		(fp_line
			(start 0.12065 -0.3048)
			(end 0.67945 -0.3048)
			(stroke
				(width 0.1)
				(type default)
			)
			(layer "F.Fab")
		)
		(fp_line
			(start 0.120396 0.3048)
			(end 0.120396 0.2794)
			(stroke
				(width 0.1)
				(type default)
			)
			(layer "F.Fab")
		)
		(fp_line
			(start 0.120396 0.2794)
			(end -0.12065 0.2794)
			(stroke
				(width 0.1)
				(type default)
			)
			(layer "F.Fab")
		)
		(fp_line
			(start -0.12065 0.3048)
			(end -0.67945 0.3048)
			(stroke
				(width 0.1)
				(type default)
			)
			(layer "F.Fab")
		)
		(fp_line
			(start -0.12065 0.2794)
			(end -0.12065 0.3048)
			(stroke
				(width 0.1)
				(type default)
			)
			(layer "F.Fab")
		)
		(fp_line
			(start -0.12065 -0.2794)
			(end 0.12065 -0.2794)
			(stroke
				(width 0.1)
				(type default)
			)
			(layer "F.Fab")
		)
		(fp_line
			(start -0.12065 -0.305054)
			(end -0.12065 -0.2794)
			(stroke
				(width 0.1)
				(type default)
			)
			(layer "F.Fab")
		)
		(fp_line
			(start -0.67945 0.3048)
			(end -0.67945 -0.305054)
			(stroke
				(width 0.1)
				(type default)
			)
			(layer "F.Fab")
		)
		(fp_line
			(start -0.67945 -0.305054)
			(end -0.12065 -0.305054)
			(stroke
				(width 0.1)
				(type default)
			)
			(layer "F.Fab")
		)
		(pad "1" smd circle
			(at -0.40005 0 180)
			(size 0 0)
			(layers "F.Cu" "F.Mask" "F.Paste")
			(net "P3V3_AUX")
		)
		(pad "2" smd circle
			(at 0.40005 0 180)
			(size 0 0)
			(layers "F.Cu" "F.Mask" "F.Paste")
			(net "SMB_ADC_SCL_R")
		)
	)
	(footprint ""
		(layer "F.Cu")
		(at 517.258808 -147.972526 -90)
		(property "Reference" "X2"
			(at -1.903222 3.256788 0)
			(unlocked yes)
			(layer "F.SilkS")
			(effects
				(font
					(size 0.7874 0.5842)
					(thickness 0.1524)
				)
				(justify left)
			)
		)
		(property "Value" ""
			(at 0 0 270)
			(layer "F.Fab")
			(effects
				(font
					(size 1.27 1.27)
				)
			)
		)
		(property "Device Type" "TP_TDR_4P_FTS_TH-TP_TDR_4P_DIP,EMPTY,TP15"
			(at 1.30175 1.27 0)
			(unlocked yes)
			(layer "F.Fab")
			(hide yes)
			(effects
				(font
					(size 0.635 0.4064)
					(thickness 0.1524)
				)
			)
		)
		(property "User Part Number" "N_A"
			(at 1.30175 1.27 0)
			(unlocked yes)
			(layer "Cmts.User")
			(hide yes)
			(effects
				(font
					(size 0.635 0.4064)
					(thickness 0.1524)
				)
			)
		)
		(duplicate_pad_numbers_are_jumpers no)
		(fp_line
			(start 0 3.81)
			(end 2.54 3.81)
			(stroke
				(width 0.1524)
				(type default)
			)
			(layer "F.SilkS")
		)
		(fp_line
			(start 2.54 3.81)
			(end 2.54 3.6703)
			(stroke
				(width 0.1524)
				(type default)
			)
			(layer "F.SilkS")
		)
		(fp_line
			(start 0 3.175)
			(end 0 3.81)
			(stroke
				(width 0.1524)
				(type default)
			)
			(layer "F.SilkS")
		)
		(fp_line
			(start 2.54 1.4097)
			(end 2.54 1.1303)
			(stroke
				(width 0.1524)
				(type default)
			)
			(layer "F.SilkS")
		)
		(fp_line
			(start 0 0.635)
			(end 0 1.905)
			(stroke
				(width 0.1524)
				(type default)
			)
			(layer "F.SilkS")
		)
		(fp_line
			(start 2.54 -1.1303)
			(end 2.54 -1.27)
			(stroke
				(width 0.1524)
				(type default)
			)
			(layer "F.SilkS")
		)
		(fp_line
			(start 0 -1.27)
			(end 0 -0.635)
			(stroke
				(width 0.1524)
				(type default)
			)
			(layer "F.SilkS")
		)
		(fp_line
			(start 2.54 -1.27)
			(end 0 -1.27)
			(stroke
				(width 0.1524)
				(type default)
			)
			(layer "F.SilkS")
		)
		(fp_poly
			(pts
				(xy -0.761746 0) (xy -2.285746 0.762) (xy -2.285746 -0.762)
			)
			(stroke
				(width 0)
				(type default)
			)
			(fill yes)
			(layer "F.SilkS")
		)
		(fp_line
			(start 0 3.81)
			(end 2.54 3.81)
			(stroke
				(width 0.1)
				(type default)
			)
			(layer "F.Fab")
		)
		(fp_line
			(start 2.54 3.81)
			(end 2.54 -1.27)
			(stroke
				(width 0.1)
				(type default)
			)
			(layer "F.Fab")
		)
		(fp_line
			(start 0 -1.27)
			(end 0 3.81)
			(stroke
				(width 0.1)
				(type default)
			)
			(layer "F.Fab")
		)
		(fp_line
			(start 2.54 -1.27)
			(end 0 -1.27)
			(stroke
				(width 0.1)
				(type default)
			)
			(layer "F.Fab")
		)
		(fp_poly
			(pts
				(xy -0.761746 0) (xy -2.285746 -0.762) (xy -2.285746 0.762)
			)
			(stroke
				(width 0)
				(type default)
			)
			(fill yes)
			(layer "F.Fab")
		)
		(pad "1" thru_hole circle
			(at 0 0 270)
			(size 1.0033 1.0033)
			(drill 0.249936)
			(layers "*.Cu" "*.Mask")
			(remove_unused_layers no)
			(net "TDR_DIFF_80_IN1_DP")
			(clearance 0.10795)
			(thermal_gap 0.10795)
			(padstack
				(mode front_inner_back)
				(layer "Inner"
					(shape circle)
					(size 0.8001 0.8001)
					(clearance 0.1524)
				)
				(layer "B.Cu"
					(shape circle)
					(size 1.0033 1.0033)
					(clearance 0.10795)
				)
			)
		)
		(pad "2" thru_hole circle
			(at 2.54 0 270)
			(size 1.9939 1.9939)
			(drill 0.249936)
			(layers "*.Cu" "*.Mask")
			(remove_unused_layers no)
			(net "T1_GND")
			(clearance 0.10795)
			(thermal_gap 0.10795)
			(padstack
				(mode front_inner_back)
				(layer "Inner"
					(shape circle)
					(size 0.8001 0.8001)
					(clearance 0.1524)
				)
				(layer "B.Cu"
					(shape circle)
					(size 1.9939 1.9939)
					(clearance 0.10795)
				)
			)
		)
		(pad "3" thru_hole circle
			(at 2.54 2.54 270)
			(size 1.9939 1.9939)
			(drill 0.249936)
			(layers "*.Cu" "*.Mask")
			(remove_unused_layers no)
			(net "T1_GND")
			(clearance 0.10795)
			(thermal_gap 0.10795)
			(padstack
				(mode front_inner_back)
				(layer "Inner"
					(shape circle)
					(size 0.8001 0.8001)
					(clearance 0.1524)
				)
				(layer "B.Cu"
					(shape circle)
					(size 1.9939 1.9939)
					(clearance 0.10795)
				)
			)
		)
		(pad "4" thru_hole circle
			(at 0 2.54 270)
			(size 1.0033 1.0033)
			(drill 0.249936)
			(layers "*.Cu" "*.Mask")
			(remove_unused_layers no)
			(net "TDR_DIFF_80_IN1_DN")
			(clearance 0.10795)
			(thermal_gap 0.10795)
			(padstack
				(mode front_inner_back)
				(layer "Inner"
					(shape circle)
					(size 0.8001 0.8001)
					(clearance 0.1524)
				)
				(layer "B.Cu"
					(shape circle)
					(size 1.0033 1.0033)
					(clearance 0.10795)
				)
			)
		)
	)
	(footprint ""
		(layer "F.Cu")
		(at 410.936186 -133.594348)
		(property "Reference" "PL8064"
			(at 0 0 0)
			(layer "F.SilkS")
			(hide yes)
			(effects
				(font
					(size 1.27 1.27)
				)
			)
		)
		(property "Value" ""
			(at 0 0 0)
			(layer "F.Fab")
			(effects
				(font
					(size 1.27 1.27)
				)
			)
		)
		(duplicate_pad_numbers_are_jumpers no)
		(fp_line
			(start -1.27 -0.5842)
			(end 1.27 -0.5842)
			(stroke
				(width 0.1524)
				(type default)
			)
			(layer "F.SilkS")
		)
		(fp_line
			(start -1.27 -0.5588)
			(end -1.27 -0.5842)
			(stroke
				(width 0.1524)
				(type default)
			)
			(layer "F.SilkS")
		)
		(fp_line
			(start -1.27 0.5842)
			(end -1.27 -0.5842)
			(stroke
				(width 0.1524)
				(type default)
			)
			(layer "F.SilkS")
		)
		(fp_line
			(start 1.27 0.5842)
			(end -1.27 0.5842)
			(stroke
				(width 0.1524)
				(type default)
			)
			(layer "F.SilkS")
		)
		(fp_line
			(start 1.27 0.5842)
			(end 1.27 -0.5842)
			(stroke
				(width 0.1524)
				(type default)
			)
			(layer "F.SilkS")
		)
		(fp_line
			(start -1.194308 -0.406654)
			(end -0.9144 -0.406654)
			(stroke
				(width 0.1)
				(type default)
			)
			(layer "F.Fab")
		)
		(fp_line
			(start -1.194308 0.406654)
			(end -1.194308 -0.406654)
			(stroke
				(width 0.1)
				(type default)
			)
			(layer "F.Fab")
		)
		(fp_line
			(start -0.9144 -0.508)
			(end 0.9144 -0.508)
			(stroke
				(width 0.1)
				(type default)
			)
			(layer "F.Fab")
		)
		(fp_line
			(start -0.9144 -0.406654)
			(end -0.9144 -0.508)
			(stroke
				(width 0.1)
				(type default)
			)
			(layer "F.Fab")
		)
		(fp_line
			(start -0.9144 0.406654)
			(end -1.194308 0.406654)
			(stroke
				(width 0.1)
				(type default)
			)
			(layer "F.Fab")
		)
		(fp_line
			(start -0.9144 0.508)
			(end -0.9144 0.406654)
			(stroke
				(width 0.1)
				(type default)
			)
			(layer "F.Fab")
		)
		(fp_line
			(start 0.9144 -0.508)
			(end 0.9144 -0.406654)
			(stroke
				(width 0.1)
				(type default)
			)
			(layer "F.Fab")
		)
		(fp_line
			(start 0.9144 -0.406654)
			(end 1.1938 -0.406654)
			(stroke
				(width 0.1)
				(type default)
			)
			(layer "F.Fab")
		)
		(fp_line
			(start 0.9144 0.4064)
			(end 0.9144 0.508)
			(stroke
				(width 0.1)
				(type default)
			)
			(layer "F.Fab")
		)
		(fp_line
			(start 0.9144 0.508)
			(end -0.9144 0.508)
			(stroke
				(width 0.1)
				(type default)
			)
			(layer "F.Fab")
		)
		(fp_line
			(start 1.1938 -0.406654)
			(end 1.1938 0.4064)
			(stroke
				(width 0.1)
				(type default)
			)
			(layer "F.Fab")
		)
		(fp_line
			(start 1.1938 0.4064)
			(end 0.9144 0.4064)
			(stroke
				(width 0.1)
				(type default)
			)
			(layer "F.Fab")
		)
		(pad "1" smd rect
			(at -0.7366 0 270)
			(size 0.7112 0.8128)
			(layers "F.Cu" "F.Mask" "F.Paste")
			(net "P12V_AUX")
		)
		(pad "2" smd rect
			(at 0.7366 0 270)
			(size 0.7112 0.8128)
			(layers "F.Cu" "F.Mask" "F.Paste")
			(net "SW_P5V_AUX_FLT")
		)
	)
	(footprint ""
		(layer "F.Cu")
		(at 239.152684 -52.01285)
		(property "Reference" "C1995"
			(at 0 0 0)
			(layer "F.SilkS")
			(hide yes)
			(effects
				(font
					(size 1.27 1.27)
				)
			)
		)
		(property "Value" ""
			(at 0 0 0)
			(layer "F.Fab")
			(effects
				(font
					(size 1.27 1.27)
				)
			)
		)
		(duplicate_pad_numbers_are_jumpers no)
		(fp_line
			(start -0.299974 -0.150114)
			(end 0.299974 -0.150114)
			(stroke
				(width 0.1)
				(type default)
			)
			(layer "F.Fab")
		)
		(fp_line
			(start -0.299974 0.150114)
			(end -0.299974 -0.150114)
			(stroke
				(width 0.1)
				(type default)
			)
			(layer "F.Fab")
		)
		(fp_line
			(start 0.299974 -0.150114)
			(end 0.299974 0.150114)
			(stroke
				(width 0.1)
				(type default)
			)
			(layer "F.Fab")
		)
		(fp_line
			(start 0.299974 0.150114)
			(end -0.299974 0.150114)
			(stroke
				(width 0.1)
				(type default)
			)
			(layer "F.Fab")
		)
		(pad "1" smd rect
			(at -0.2667 0)
			(size 0.3048 0.381)
			(layers "F.Cu" "F.Mask" "F.Paste")
			(net "P3E_CPU0_P4_TX_C_DP<0>")
		)
		(pad "2" smd rect
			(at 0.2667 0)
			(size 0.3048 0.381)
			(layers "F.Cu" "F.Mask" "F.Paste")
			(net "P3E_CPU0_P4_TX_DP<0>")
		)
	)
	(footprint ""
		(layer "F.Cu")
		(at 75.546458 -20.950682 180)
		(property "Reference" "PR3821"
			(at 0 0 180)
			(layer "F.SilkS")
			(hide yes)
			(effects
				(font
					(size 1.27 1.27)
				)
			)
		)
		(property "Value" ""
			(at 0 0 180)
			(layer "F.Fab")
			(effects
				(font
					(size 1.27 1.27)
				)
			)
		)
		(duplicate_pad_numbers_are_jumpers no)
		(fp_line
			(start 0.7874 0.4064)
			(end -0.7874 0.4064)
			(stroke
				(width 0.1524)
				(type default)
			)
			(layer "F.SilkS")
		)
		(fp_line
			(start 0.7874 -0.4064)
			(end 0.7874 0.4064)
			(stroke
				(width 0.1524)
				(type default)
			)
			(layer "F.SilkS")
		)
		(fp_line
			(start -0.7874 0.4064)
			(end -0.7874 -0.4064)
			(stroke
				(width 0.1524)
				(type default)
			)
			(layer "F.SilkS")
		)
		(fp_line
			(start -0.7874 -0.4064)
			(end 0.7874 -0.4064)
			(stroke
				(width 0.1524)
				(type default)
			)
			(layer "F.SilkS")
		)
		(fp_line
			(start 0.67945 0.3048)
			(end 0.120396 0.3048)
			(stroke
				(width 0.1)
				(type default)
			)
			(layer "F.Fab")
		)
		(fp_line
			(start 0.67945 -0.3048)
			(end 0.67945 0.3048)
			(stroke
				(width 0.1)
				(type default)
			)
			(layer "F.Fab")
		)
		(fp_line
			(start 0.12065 -0.2794)
			(end 0.12065 -0.3048)
			(stroke
				(width 0.1)
				(type default)
			)
			(layer "F.Fab")
		)
		(fp_line
			(start 0.12065 -0.3048)
			(end 0.67945 -0.3048)
			(stroke
				(width 0.1)
				(type default)
			)
			(layer "F.Fab")
		)
		(fp_line
			(start 0.120396 0.3048)
			(end 0.120396 0.2794)
			(stroke
				(width 0.1)
				(type default)
			)
			(layer "F.Fab")
		)
		(fp_line
			(start 0.120396 0.2794)
			(end -0.12065 0.2794)
			(stroke
				(width 0.1)
				(type default)
			)
			(layer "F.Fab")
		)
		(fp_line
			(start -0.12065 0.3048)
			(end -0.67945 0.3048)
			(stroke
				(width 0.1)
				(type default)
			)
			(layer "F.Fab")
		)
		(fp_line
			(start -0.12065 0.2794)
			(end -0.12065 0.3048)
			(stroke
				(width 0.1)
				(type default)
			)
			(layer "F.Fab")
		)
		(fp_line
			(start -0.12065 -0.2794)
			(end 0.12065 -0.2794)
			(stroke
				(width 0.1)
				(type default)
			)
			(layer "F.Fab")
		)
		(fp_line
			(start -0.12065 -0.305054)
			(end -0.12065 -0.2794)
			(stroke
				(width 0.1)
				(type default)
			)
			(layer "F.Fab")
		)
		(fp_line
			(start -0.67945 0.3048)
			(end -0.67945 -0.305054)
			(stroke
				(width 0.1)
				(type default)
			)
			(layer "F.Fab")
		)
		(fp_line
			(start -0.67945 -0.305054)
			(end -0.12065 -0.305054)
			(stroke
				(width 0.1)
				(type default)
			)
			(layer "F.Fab")
		)
		(pad "1" smd circle
			(at -0.40005 0 180)
			(size 0 0)
			(layers "F.Cu" "F.Mask" "F.Paste")
			(net "P12V_OCP_CB_2")
		)
		(pad "2" smd circle
			(at 0.40005 0 180)
			(size 0 0)
			(layers "F.Cu" "F.Mask" "F.Paste")
			(net "GND")
		)
	)
	(footprint ""
		(layer "F.Cu")
		(at 66.726054 -337.665314 90)
		(property "Reference" "PC400"
			(at 0 0 90)
			(layer "F.SilkS")
			(hide yes)
			(effects
				(font
					(size 1.27 1.27)
				)
			)
		)
		(property "Value" ""
			(at 0 0 90)
			(layer "F.Fab")
			(effects
				(font
					(size 1.27 1.27)
				)
			)
		)
		(duplicate_pad_numbers_are_jumpers no)
		(fp_line
			(start 0.7874 -0.4064)
			(end 0.7874 0.4064)
			(stroke
				(width 0.1524)
				(type default)
			)
			(layer "F.SilkS")
		)
		(fp_line
			(start -0.7874 -0.4064)
			(end 0.7874 -0.4064)
			(stroke
				(width 0.1524)
				(type default)
			)
			(layer "F.SilkS")
		)
		(fp_line
			(start 0.7874 0.4064)
			(end 0.408686 0.4064)
			(stroke
				(width 0.1524)
				(type default)
			)
			(layer "F.SilkS")
		)
		(fp_line
			(start -0.226314 0.4064)
			(end -0.7874 0.4064)
			(stroke
				(width 0.1524)
				(type default)
			)
			(layer "F.SilkS")
		)
		(fp_line
			(start -0.7874 0.4064)
			(end -0.7874 -0.4064)
			(stroke
				(width 0.1524)
				(type default)
			)
			(layer "F.SilkS")
		)
		(fp_line
			(start -0.12065 -0.305054)
			(end -0.12065 -0.2794)
			(stroke
				(width 0.1)
				(type default)
			)
			(layer "F.Fab")
		)
		(fp_line
			(start -0.67945 -0.305054)
			(end -0.12065 -0.305054)
			(stroke
				(width 0.1)
				(type default)
			)
			(layer "F.Fab")
		)
		(fp_line
			(start 0.67945 -0.3048)
			(end 0.67945 0.3048)
			(stroke
				(width 0.1)
				(type default)
			)
			(layer "F.Fab")
		)
		(fp_line
			(start 0.12065 -0.3048)
			(end 0.67945 -0.3048)
			(stroke
				(width 0.1)
				(type default)
			)
			(layer "F.Fab")
		)
		(fp_line
			(start 0.12065 -0.2794)
			(end 0.12065 -0.3048)
			(stroke
				(width 0.1)
				(type default)
			)
			(layer "F.Fab")
		)
		(fp_line
			(start -0.12065 -0.2794)
			(end 0.12065 -0.2794)
			(stroke
				(width 0.1)
				(type default)
			)
			(layer "F.Fab")
		)
		(fp_line
			(start 0.120396 0.2794)
			(end -0.12065 0.2794)
			(stroke
				(width 0.1)
				(type default)
			)
			(layer "F.Fab")
		)
		(fp_line
			(start -0.12065 0.2794)
			(end -0.12065 0.3048)
			(stroke
				(width 0.1)
				(type default)
			)
			(layer "F.Fab")
		)
		(fp_line
			(start 0.67945 0.3048)
			(end 0.120396 0.3048)
			(stroke
				(width 0.1)
				(type default)
			)
			(layer "F.Fab")
		)
		(fp_line
			(start 0.120396 0.3048)
			(end 0.120396 0.2794)
			(stroke
				(width 0.1)
				(type default)
			)
			(layer "F.Fab")
		)
		(fp_line
			(start -0.12065 0.3048)
			(end -0.67945 0.3048)
			(stroke
				(width 0.1)
				(type default)
			)
			(layer "F.Fab")
		)
		(fp_line
			(start -0.67945 0.3048)
			(end -0.67945 -0.305054)
			(stroke
				(width 0.1)
				(type default)
			)
			(layer "F.Fab")
		)
		(pad "1" smd circle
			(at -0.40005 0 90)
			(size 0 0)
			(layers "F.Cu" "F.Mask" "F.Paste")
			(net "PVDDCR_CPU1_P1_VCC3")
		)
		(pad "2" smd circle
			(at 0.40005 0 90)
			(size 0 0)
			(layers "F.Cu" "F.Mask" "F.Paste")
			(net "GND")
		)
	)
	(footprint ""
		(layer "F.Cu")
		(at 297.315128 -146.202908 180)
		(property "Reference" "R1330"
			(at 0 0 180)
			(layer "F.SilkS")
			(hide yes)
			(effects
				(font
					(size 1.27 1.27)
				)
			)
		)
		(property "Value" ""
			(at 0 0 180)
			(layer "F.Fab")
			(effects
				(font
					(size 1.27 1.27)
				)
			)
		)
		(duplicate_pad_numbers_are_jumpers no)
		(fp_line
			(start 0.7874 0.4064)
			(end -0.7874 0.4064)
			(stroke
				(width 0.1524)
				(type default)
			)
			(layer "F.SilkS")
		)
		(fp_line
			(start 0.7874 -0.4064)
			(end 0.7874 0.4064)
			(stroke
				(width 0.1524)
				(type default)
			)
			(layer "F.SilkS")
		)
		(fp_line
			(start -0.7874 0.4064)
			(end -0.7874 -0.4064)
			(stroke
				(width 0.1524)
				(type default)
			)
			(layer "F.SilkS")
		)
		(fp_line
			(start -0.7874 -0.4064)
			(end 0.7874 -0.4064)
			(stroke
				(width 0.1524)
				(type default)
			)
			(layer "F.SilkS")
		)
		(fp_line
			(start 0.67945 0.3048)
			(end 0.120396 0.3048)
			(stroke
				(width 0.1)
				(type default)
			)
			(layer "F.Fab")
		)
		(fp_line
			(start 0.67945 -0.3048)
			(end 0.67945 0.3048)
			(stroke
				(width 0.1)
				(type default)
			)
			(layer "F.Fab")
		)
		(fp_line
			(start 0.12065 -0.2794)
			(end 0.12065 -0.3048)
			(stroke
				(width 0.1)
				(type default)
			)
			(layer "F.Fab")
		)
		(fp_line
			(start 0.12065 -0.3048)
			(end 0.67945 -0.3048)
			(stroke
				(width 0.1)
				(type default)
			)
			(layer "F.Fab")
		)
		(fp_line
			(start 0.120396 0.3048)
			(end 0.120396 0.2794)
			(stroke
				(width 0.1)
				(type default)
			)
			(layer "F.Fab")
		)
		(fp_line
			(start 0.120396 0.2794)
			(end -0.12065 0.2794)
			(stroke
				(width 0.1)
				(type default)
			)
			(layer "F.Fab")
		)
		(fp_line
			(start -0.12065 0.3048)
			(end -0.67945 0.3048)
			(stroke
				(width 0.1)
				(type default)
			)
			(layer "F.Fab")
		)
		(fp_line
			(start -0.12065 0.2794)
			(end -0.12065 0.3048)
			(stroke
				(width 0.1)
				(type default)
			)
			(layer "F.Fab")
		)
		(fp_line
			(start -0.12065 -0.2794)
			(end 0.12065 -0.2794)
			(stroke
				(width 0.1)
				(type default)
			)
			(layer "F.Fab")
		)
		(fp_line
			(start -0.12065 -0.305054)
			(end -0.12065 -0.2794)
			(stroke
				(width 0.1)
				(type default)
			)
			(layer "F.Fab")
		)
		(fp_line
			(start -0.67945 0.3048)
			(end -0.67945 -0.305054)
			(stroke
				(width 0.1)
				(type default)
			)
			(layer "F.Fab")
		)
		(fp_line
			(start -0.67945 -0.305054)
			(end -0.12065 -0.305054)
			(stroke
				(width 0.1)
				(type default)
			)
			(layer "F.Fab")
		)
		(pad "1" smd rect
			(at -0.40005 0)
			(size 0.4572 0.508)
			(layers "F.Cu" "F.Mask" "F.Paste")
			(net "I3C_SPD_DDRAF_CPU0_BYPASS_SCL")
		)
		(pad "2" smd rect
			(at 0.40005 0)
			(size 0.4572 0.508)
			(layers "F.Cu" "F.Mask" "F.Paste")
			(net "I3C_SPD_DDRAF_CPU0_SCL")
		)
	)
	(footprint ""
		(layer "F.Cu")
		(at 435.181248 -35.489388 90)
		(property "Reference" "R3870"
			(at 0 0 90)
			(layer "F.SilkS")
			(hide yes)
			(effects
				(font
					(size 1.27 1.27)
				)
			)
		)
		(property "Value" ""
			(at 0 0 90)
			(layer "F.Fab")
			(effects
				(font
					(size 1.27 1.27)
				)
			)
		)
		(duplicate_pad_numbers_are_jumpers no)
		(fp_line
			(start 0.7874 -0.4064)
			(end 0.7874 0.4064)
			(stroke
				(width 0.1524)
				(type default)
			)
			(layer "F.SilkS")
		)
		(fp_line
			(start -0.7874 -0.4064)
			(end 0.7874 -0.4064)
			(stroke
				(width 0.1524)
				(type default)
			)
			(layer "F.SilkS")
		)
		(fp_line
			(start 0.7874 0.4064)
			(end -0.7874 0.4064)
			(stroke
				(width 0.1524)
				(type default)
			)
			(layer "F.SilkS")
		)
		(fp_line
			(start -0.7874 0.4064)
			(end -0.7874 -0.4064)
			(stroke
				(width 0.1524)
				(type default)
			)
			(layer "F.SilkS")
		)
		(fp_line
			(start -0.12065 -0.305054)
			(end -0.12065 -0.2794)
			(stroke
				(width 0.1)
				(type default)
			)
			(layer "F.Fab")
		)
		(fp_line
			(start -0.67945 -0.305054)
			(end -0.12065 -0.305054)
			(stroke
				(width 0.1)
				(type default)
			)
			(layer "F.Fab")
		)
		(fp_line
			(start 0.67945 -0.3048)
			(end 0.67945 0.3048)
			(stroke
				(width 0.1)
				(type default)
			)
			(layer "F.Fab")
		)
		(fp_line
			(start 0.12065 -0.3048)
			(end 0.67945 -0.3048)
			(stroke
				(width 0.1)
				(type default)
			)
			(layer "F.Fab")
		)
		(fp_line
			(start 0.12065 -0.2794)
			(end 0.12065 -0.3048)
			(stroke
				(width 0.1)
				(type default)
			)
			(layer "F.Fab")
		)
		(fp_line
			(start -0.12065 -0.2794)
			(end 0.12065 -0.2794)
			(stroke
				(width 0.1)
				(type default)
			)
			(layer "F.Fab")
		)
		(fp_line
			(start 0.120396 0.2794)
			(end -0.12065 0.2794)
			(stroke
				(width 0.1)
				(type default)
			)
			(layer "F.Fab")
		)
		(fp_line
			(start -0.12065 0.2794)
			(end -0.12065 0.3048)
			(stroke
				(width 0.1)
				(type default)
			)
			(layer "F.Fab")
		)
		(fp_line
			(start 0.67945 0.3048)
			(end 0.120396 0.3048)
			(stroke
				(width 0.1)
				(type default)
			)
			(layer "F.Fab")
		)
		(fp_line
			(start 0.120396 0.3048)
			(end 0.120396 0.2794)
			(stroke
				(width 0.1)
				(type default)
			)
			(layer "F.Fab")
		)
		(fp_line
			(start -0.12065 0.3048)
			(end -0.67945 0.3048)
			(stroke
				(width 0.1)
				(type default)
			)
			(layer "F.Fab")
		)
		(fp_line
			(start -0.67945 0.3048)
			(end -0.67945 -0.305054)
			(stroke
				(width 0.1)
				(type default)
			)
			(layer "F.Fab")
		)
		(pad "1" smd circle
			(at -0.40005 0 90)
			(size 0 0)
			(layers "F.Cu" "F.Mask" "F.Paste")
			(net "P12V_OCP_SENSE_1")
		)
		(pad "2" smd circle
			(at 0.40005 0 90)
			(size 0 0)
			(layers "F.Cu" "F.Mask" "F.Paste")
			(net "P12V_OCP_SFF_ISENSE_MAM_TIC")
		)
	)
	(footprint ""
		(layer "F.Cu")
		(at 53.895244 -408.517344 -90)
		(property "Reference" "C6634"
			(at 0 0 270)
			(layer "F.SilkS")
			(hide yes)
			(effects
				(font
					(size 1.27 1.27)
				)
			)
		)
		(property "Value" ""
			(at 0 0 270)
			(layer "F.Fab")
			(effects
				(font
					(size 1.27 1.27)
				)
			)
		)
		(duplicate_pad_numbers_are_jumpers no)
		(fp_line
			(start -0.299974 0.150114)
			(end -0.299974 -0.150114)
			(stroke
				(width 0.1)
				(type default)
			)
			(layer "F.Fab")
		)
		(fp_line
			(start 0.299974 0.150114)
			(end -0.299974 0.150114)
			(stroke
				(width 0.1)
				(type default)
			)
			(layer "F.Fab")
		)
		(fp_line
			(start -0.299974 -0.150114)
			(end 0.299974 -0.150114)
			(stroke
				(width 0.1)
				(type default)
			)
			(layer "F.Fab")
		)
		(fp_line
			(start 0.299974 -0.150114)
			(end 0.299974 0.150114)
			(stroke
				(width 0.1)
				(type default)
			)
			(layer "F.Fab")
		)
		(pad "1" smd rect
			(at -0.2667 0 270)
			(size 0.3048 0.381)
			(layers "F.Cu" "F.Mask" "F.Paste")
			(net "P5E_CPU1_P0_TX_BUF_C_DN<2>")
		)
		(pad "2" smd rect
			(at 0.2667 0 270)
			(size 0.3048 0.381)
			(layers "F.Cu" "F.Mask" "F.Paste")
			(net "P5E_CPU1_P0_TX_BUF_DN<2>")
		)
	)
	(footprint ""
		(layer "F.Cu")
		(at 300.62297 -407.79446)
		(property "Reference" "R961"
			(at 0 0 0)
			(layer "F.SilkS")
			(hide yes)
			(effects
				(font
					(size 1.27 1.27)
				)
			)
		)
		(property "Value" ""
			(at 0 0 0)
			(layer "F.Fab")
			(effects
				(font
					(size 1.27 1.27)
				)
			)
		)
		(duplicate_pad_numbers_are_jumpers no)
		(fp_line
			(start -1.2954 -0.5842)
			(end 1.2954 -0.5842)
			(stroke
				(width 0.1524)
				(type default)
			)
			(layer "F.SilkS")
		)
		(fp_line
			(start -1.2954 0.5842)
			(end -1.2954 -0.5842)
			(stroke
				(width 0.1524)
				(type default)
			)
			(layer "F.SilkS")
		)
		(fp_line
			(start 1.2954 -0.5842)
			(end 1.2954 0.5842)
			(stroke
				(width 0.1524)
				(type default)
			)
			(layer "F.SilkS")
		)
		(fp_line
			(start 1.2954 0.5842)
			(end -1.2954 0.5842)
			(stroke
				(width 0.1524)
				(type default)
			)
			(layer "F.SilkS")
		)
		(fp_line
			(start -1.1938 -0.406654)
			(end -0.8636 -0.406654)
			(stroke
				(width 0.1)
				(type default)
			)
			(layer "F.Fab")
		)
		(fp_line
			(start -1.1938 0.4064)
			(end -1.1938 -0.406654)
			(stroke
				(width 0.1)
				(type default)
			)
			(layer "F.Fab")
		)
		(fp_line
			(start -0.8636 -0.4572)
			(end 0.8636 -0.4572)
			(stroke
				(width 0.1)
				(type default)
			)
			(layer "F.Fab")
		)
		(fp_line
			(start -0.8636 -0.406654)
			(end -0.8636 -0.4572)
			(stroke
				(width 0.1)
				(type default)
			)
			(layer "F.Fab")
		)
		(fp_line
			(start -0.8636 0.4064)
			(end -1.1938 0.4064)
			(stroke
				(width 0.1)
				(type default)
			)
			(layer "F.Fab")
		)
		(fp_line
			(start -0.8636 0.4318)
			(end -0.8636 0.4064)
			(stroke
				(width 0.1)
				(type default)
			)
			(layer "F.Fab")
		)
		(fp_line
			(start -0.8636 0.4572)
			(end -0.8636 0.4318)
			(stroke
				(width 0.1)
				(type default)
			)
			(layer "F.Fab")
		)
		(fp_line
			(start 0.8636 -0.4572)
			(end 0.8636 -0.406654)
			(stroke
				(width 0.1)
				(type default)
			)
			(layer "F.Fab")
		)
		(fp_line
			(start 0.8636 -0.406654)
			(end 1.1938 -0.406654)
			(stroke
				(width 0.1)
				(type default)
			)
			(layer "F.Fab")
		)
		(fp_line
			(start 0.8636 0.4064)
			(end 0.8636 0.4572)
			(stroke
				(width 0.1)
				(type default)
			)
			(layer "F.Fab")
		)
		(fp_line
			(start 0.8636 0.4572)
			(end -0.8636 0.4572)
			(stroke
				(width 0.1)
				(type default)
			)
			(layer "F.Fab")
		)
		(fp_line
			(start 1.1938 -0.406654)
			(end 1.1938 0.4064)
			(stroke
				(width 0.1)
				(type default)
			)
			(layer "F.Fab")
		)
		(fp_line
			(start 1.1938 0.4064)
			(end 0.8636 0.4064)
			(stroke
				(width 0.1)
				(type default)
			)
			(layer "F.Fab")
		)
		(pad "1" smd rect
			(at -0.7366 0 270)
			(size 0.7112 0.8128)
			(layers "F.Cu" "F.Mask" "F.Paste")
			(net "P0V9_CPU0_RT_2D")
		)
		(pad "2" smd rect
			(at 0.7366 0 270)
			(size 0.7112 0.8128)
			(layers "F.Cu" "F.Mask" "F.Paste")
			(net "P0V9_CPU0_RT0_2A_2D")
		)
	)
	(footprint ""
		(layer "F.Cu")
		(at 308.412896 -378.95403 -90)
		(property "Reference" "C920"
			(at 0 0 270)
			(layer "F.SilkS")
			(hide yes)
			(effects
				(font
					(size 1.27 1.27)
				)
			)
		)
		(property "Value" ""
			(at 0 0 270)
			(layer "F.Fab")
			(effects
				(font
					(size 1.27 1.27)
				)
			)
		)
		(duplicate_pad_numbers_are_jumpers no)
		(fp_line
			(start -0.299974 0.150114)
			(end -0.299974 -0.150114)
			(stroke
				(width 0.1)
				(type default)
			)
			(layer "F.Fab")
		)
		(fp_line
			(start 0.299974 0.150114)
			(end -0.299974 0.150114)
			(stroke
				(width 0.1)
				(type default)
			)
			(layer "F.Fab")
		)
		(fp_line
			(start -0.299974 -0.150114)
			(end 0.299974 -0.150114)
			(stroke
				(width 0.1)
				(type default)
			)
			(layer "F.Fab")
		)
		(fp_line
			(start 0.299974 -0.150114)
			(end 0.299974 0.150114)
			(stroke
				(width 0.1)
				(type default)
			)
			(layer "F.Fab")
		)
		(pad "1" smd rect
			(at -0.2667 0 270)
			(size 0.3048 0.381)
			(layers "F.Cu" "F.Mask" "F.Paste")
			(net "P5E_CPU0_P0_TX_C_DN<6>")
		)
		(pad "2" smd rect
			(at 0.2667 0 270)
			(size 0.3048 0.381)
			(layers "F.Cu" "F.Mask" "F.Paste")
			(net "P5E_CPU0_P0_TX_DN<6>")
		)
	)
	(footprint ""
		(layer "F.Cu")
		(at 105.960164 -257.455416)
		(property "Reference" "C2270"
			(at 0 0 0)
			(layer "F.SilkS")
			(hide yes)
			(effects
				(font
					(size 1.27 1.27)
				)
			)
		)
		(property "Value" ""
			(at 0 0 0)
			(layer "F.Fab")
			(effects
				(font
					(size 1.27 1.27)
				)
			)
		)
		(duplicate_pad_numbers_are_jumpers no)
		(fp_line
			(start -0.7874 -0.4064)
			(end 0.7874 -0.4064)
			(stroke
				(width 0.1524)
				(type default)
			)
			(layer "F.SilkS")
		)
		(fp_line
			(start -0.7874 0.4064)
			(end -0.7874 -0.4064)
			(stroke
				(width 0.1524)
				(type default)
			)
			(layer "F.SilkS")
		)
		(fp_line
			(start 0.7874 -0.4064)
			(end 0.7874 0.4064)
			(stroke
				(width 0.1524)
				(type default)
			)
			(layer "F.SilkS")
		)
		(fp_line
			(start 0.7874 0.4064)
			(end -0.7874 0.4064)
			(stroke
				(width 0.1524)
				(type default)
			)
			(layer "F.SilkS")
		)
		(fp_line
			(start -0.67945 -0.305054)
			(end -0.12065 -0.305054)
			(stroke
				(width 0.1)
				(type default)
			)
			(layer "F.Fab")
		)
		(fp_line
			(start -0.67945 0.3048)
			(end -0.67945 -0.305054)
			(stroke
				(width 0.1)
				(type default)
			)
			(layer "F.Fab")
		)
		(fp_line
			(start -0.12065 -0.305054)
			(end -0.12065 -0.2794)
			(stroke
				(width 0.1)
				(type default)
			)
			(layer "F.Fab")
		)
		(fp_line
			(start -0.12065 -0.2794)
			(end 0.12065 -0.2794)
			(stroke
				(width 0.1)
				(type default)
			)
			(layer "F.Fab")
		)
		(fp_line
			(start -0.12065 0.2794)
			(end -0.12065 0.3048)
			(stroke
				(width 0.1)
				(type default)
			)
			(layer "F.Fab")
		)
		(fp_line
			(start -0.12065 0.3048)
			(end -0.67945 0.3048)
			(stroke
				(width 0.1)
				(type default)
			)
			(layer "F.Fab")
		)
		(fp_line
			(start 0.120396 0.2794)
			(end -0.12065 0.2794)
			(stroke
				(width 0.1)
				(type default)
			)
			(layer "F.Fab")
		)
		(fp_line
			(start 0.120396 0.3048)
			(end 0.120396 0.2794)
			(stroke
				(width 0.1)
				(type default)
			)
			(layer "F.Fab")
		)
		(fp_line
			(start 0.12065 -0.3048)
			(end 0.67945 -0.3048)
			(stroke
				(width 0.1)
				(type default)
			)
			(layer "F.Fab")
		)
		(fp_line
			(start 0.12065 -0.2794)
			(end 0.12065 -0.3048)
			(stroke
				(width 0.1)
				(type default)
			)
			(layer "F.Fab")
		)
		(fp_line
			(start 0.67945 -0.3048)
			(end 0.67945 0.3048)
			(stroke
				(width 0.1)
				(type default)
			)
			(layer "F.Fab")
		)
		(fp_line
			(start 0.67945 0.3048)
			(end 0.120396 0.3048)
			(stroke
				(width 0.1)
				(type default)
			)
			(layer "F.Fab")
		)
		(pad "1" smd circle
			(at -0.40005 0)
			(size 0 0)
			(layers "F.Cu" "F.Mask" "F.Paste")
			(net "PVDDIO_P1")
		)
		(pad "2" smd circle
			(at 0.40005 0)
			(size 0 0)
			(layers "F.Cu" "F.Mask" "F.Paste")
			(net "GND")
		)
	)
	(footprint ""
		(layer "F.Cu")
		(at 194.2211 -403.284182 180)
		(property "Reference" "PC2184"
			(at 0 0 180)
			(layer "F.SilkS")
			(hide yes)
			(effects
				(font
					(size 1.27 1.27)
				)
			)
		)
		(property "Value" ""
			(at 0 0 180)
			(layer "F.Fab")
			(effects
				(font
					(size 1.27 1.27)
				)
			)
		)
		(duplicate_pad_numbers_are_jumpers no)
		(fp_line
			(start 0.7874 0.4064)
			(end -0.7874 0.4064)
			(stroke
				(width 0.1524)
				(type default)
			)
			(layer "F.SilkS")
		)
		(fp_line
			(start 0.7874 -0.4064)
			(end 0.7874 0.4064)
			(stroke
				(width 0.1524)
				(type default)
			)
			(layer "F.SilkS")
		)
		(fp_line
			(start -0.7874 0.4064)
			(end -0.7874 -0.4064)
			(stroke
				(width 0.1524)
				(type default)
			)
			(layer "F.SilkS")
		)
		(fp_line
			(start -0.7874 -0.4064)
			(end 0.7874 -0.4064)
			(stroke
				(width 0.1524)
				(type default)
			)
			(layer "F.SilkS")
		)
		(fp_line
			(start 0.67945 0.3048)
			(end 0.120396 0.3048)
			(stroke
				(width 0.1)
				(type default)
			)
			(layer "F.Fab")
		)
		(fp_line
			(start 0.67945 -0.3048)
			(end 0.67945 0.3048)
			(stroke
				(width 0.1)
				(type default)
			)
			(layer "F.Fab")
		)
		(fp_line
			(start 0.12065 -0.2794)
			(end 0.12065 -0.3048)
			(stroke
				(width 0.1)
				(type default)
			)
			(layer "F.Fab")
		)
		(fp_line
			(start 0.12065 -0.3048)
			(end 0.67945 -0.3048)
			(stroke
				(width 0.1)
				(type default)
			)
			(layer "F.Fab")
		)
		(fp_line
			(start 0.120396 0.3048)
			(end 0.120396 0.2794)
			(stroke
				(width 0.1)
				(type default)
			)
			(layer "F.Fab")
		)
		(fp_line
			(start 0.120396 0.2794)
			(end -0.12065 0.2794)
			(stroke
				(width 0.1)
				(type default)
			)
			(layer "F.Fab")
		)
		(fp_line
			(start -0.12065 0.3048)
			(end -0.67945 0.3048)
			(stroke
				(width 0.1)
				(type default)
			)
			(layer "F.Fab")
		)
		(fp_line
			(start -0.12065 0.2794)
			(end -0.12065 0.3048)
			(stroke
				(width 0.1)
				(type default)
			)
			(layer "F.Fab")
		)
		(fp_line
			(start -0.12065 -0.2794)
			(end 0.12065 -0.2794)
			(stroke
				(width 0.1)
				(type default)
			)
			(layer "F.Fab")
		)
		(fp_line
			(start -0.12065 -0.305054)
			(end -0.12065 -0.2794)
			(stroke
				(width 0.1)
				(type default)
			)
			(layer "F.Fab")
		)
		(fp_line
			(start -0.67945 0.3048)
			(end -0.67945 -0.305054)
			(stroke
				(width 0.1)
				(type default)
			)
			(layer "F.Fab")
		)
		(fp_line
			(start -0.67945 -0.305054)
			(end -0.12065 -0.305054)
			(stroke
				(width 0.1)
				(type default)
			)
			(layer "F.Fab")
		)
		(pad "1" smd circle
			(at -0.40005 0 180)
			(size 0 0)
			(layers "F.Cu" "F.Mask" "F.Paste")
			(net "HSC_SS")
		)
		(pad "2" smd circle
			(at 0.40005 0 180)
			(size 0 0)
			(layers "F.Cu" "F.Mask" "F.Paste")
			(net "AGND_HSC")
		)
	)
	(footprint ""
		(layer "F.Cu")
		(at 122.180096 -160.5407 90)
		(property "Reference" "PC334"
			(at 0 0 90)
			(layer "F.SilkS")
			(hide yes)
			(effects
				(font
					(size 1.27 1.27)
				)
			)
		)
		(property "Value" ""
			(at 0 0 90)
			(layer "F.Fab")
			(effects
				(font
					(size 1.27 1.27)
				)
			)
		)
		(duplicate_pad_numbers_are_jumpers no)
		(fp_line
			(start 0.7874 -0.4064)
			(end 0.7874 0.4064)
			(stroke
				(width 0.1524)
				(type default)
			)
			(layer "F.SilkS")
		)
		(fp_line
			(start -0.7874 -0.4064)
			(end 0.7874 -0.4064)
			(stroke
				(width 0.1524)
				(type default)
			)
			(layer "F.SilkS")
		)
		(fp_line
			(start 0.7874 0.4064)
			(end -0.7874 0.4064)
			(stroke
				(width 0.1524)
				(type default)
			)
			(layer "F.SilkS")
		)
		(fp_line
			(start -0.7874 0.4064)
			(end -0.7874 -0.4064)
			(stroke
				(width 0.1524)
				(type default)
			)
			(layer "F.SilkS")
		)
		(fp_line
			(start -0.12065 -0.305054)
			(end -0.12065 -0.2794)
			(stroke
				(width 0.1)
				(type default)
			)
			(layer "F.Fab")
		)
		(fp_line
			(start -0.67945 -0.305054)
			(end -0.12065 -0.305054)
			(stroke
				(width 0.1)
				(type default)
			)
			(layer "F.Fab")
		)
		(fp_line
			(start 0.67945 -0.3048)
			(end 0.67945 0.3048)
			(stroke
				(width 0.1)
				(type default)
			)
			(layer "F.Fab")
		)
		(fp_line
			(start 0.12065 -0.3048)
			(end 0.67945 -0.3048)
			(stroke
				(width 0.1)
				(type default)
			)
			(layer "F.Fab")
		)
		(fp_line
			(start 0.12065 -0.2794)
			(end 0.12065 -0.3048)
			(stroke
				(width 0.1)
				(type default)
			)
			(layer "F.Fab")
		)
		(fp_line
			(start -0.12065 -0.2794)
			(end 0.12065 -0.2794)
			(stroke
				(width 0.1)
				(type default)
			)
			(layer "F.Fab")
		)
		(fp_line
			(start 0.120396 0.2794)
			(end -0.12065 0.2794)
			(stroke
				(width 0.1)
				(type default)
			)
			(layer "F.Fab")
		)
		(fp_line
			(start -0.12065 0.2794)
			(end -0.12065 0.3048)
			(stroke
				(width 0.1)
				(type default)
			)
			(layer "F.Fab")
		)
		(fp_line
			(start 0.67945 0.3048)
			(end 0.120396 0.3048)
			(stroke
				(width 0.1)
				(type default)
			)
			(layer "F.Fab")
		)
		(fp_line
			(start 0.120396 0.3048)
			(end 0.120396 0.2794)
			(stroke
				(width 0.1)
				(type default)
			)
			(layer "F.Fab")
		)
		(fp_line
			(start -0.12065 0.3048)
			(end -0.67945 0.3048)
			(stroke
				(width 0.1)
				(type default)
			)
			(layer "F.Fab")
		)
		(fp_line
			(start -0.67945 0.3048)
			(end -0.67945 -0.305054)
			(stroke
				(width 0.1)
				(type default)
			)
			(layer "F.Fab")
		)
		(pad "1" smd circle
			(at -0.40005 0 90)
			(size 0 0)
			(layers "F.Cu" "F.Mask" "F.Paste")
			(net "SW_PVDDCR_SOC_P1_BOOT2_RC")
		)
		(pad "2" smd circle
			(at 0.40005 0 90)
			(size 0 0)
			(layers "F.Cu" "F.Mask" "F.Paste")
			(net "SW_PVDDCR_SOC_P1_PH2")
		)
	)
	(footprint ""
		(layer "F.Cu")
		(at 8.334248 -131.32435)
		(property "Reference" "R4081"
			(at 0 0 0)
			(layer "F.SilkS")
			(hide yes)
			(effects
				(font
					(size 1.27 1.27)
				)
			)
		)
		(property "Value" ""
			(at 0 0 0)
			(layer "F.Fab")
			(effects
				(font
					(size 1.27 1.27)
				)
			)
		)
		(duplicate_pad_numbers_are_jumpers no)
		(fp_line
			(start -0.7874 -0.4064)
			(end 0.7874 -0.4064)
			(stroke
				(width 0.1524)
				(type default)
			)
			(layer "F.SilkS")
		)
		(fp_line
			(start -0.7874 0.4064)
			(end -0.7874 -0.4064)
			(stroke
				(width 0.1524)
				(type default)
			)
			(layer "F.SilkS")
		)
		(fp_line
			(start 0.7874 -0.4064)
			(end 0.7874 0.4064)
			(stroke
				(width 0.1524)
				(type default)
			)
			(layer "F.SilkS")
		)
		(fp_line
			(start 0.7874 0.4064)
			(end -0.7874 0.4064)
			(stroke
				(width 0.1524)
				(type default)
			)
			(layer "F.SilkS")
		)
		(fp_line
			(start -0.67945 -0.305054)
			(end -0.12065 -0.305054)
			(stroke
				(width 0.1)
				(type default)
			)
			(layer "F.Fab")
		)
		(fp_line
			(start -0.67945 0.3048)
			(end -0.67945 -0.305054)
			(stroke
				(width 0.1)
				(type default)
			)
			(layer "F.Fab")
		)
		(fp_line
			(start -0.12065 -0.305054)
			(end -0.12065 -0.2794)
			(stroke
				(width 0.1)
				(type default)
			)
			(layer "F.Fab")
		)
		(fp_line
			(start -0.12065 -0.2794)
			(end 0.12065 -0.2794)
			(stroke
				(width 0.1)
				(type default)
			)
			(layer "F.Fab")
		)
		(fp_line
			(start -0.12065 0.2794)
			(end -0.12065 0.3048)
			(stroke
				(width 0.1)
				(type default)
			)
			(layer "F.Fab")
		)
		(fp_line
			(start -0.12065 0.3048)
			(end -0.67945 0.3048)
			(stroke
				(width 0.1)
				(type default)
			)
			(layer "F.Fab")
		)
		(fp_line
			(start 0.120396 0.2794)
			(end -0.12065 0.2794)
			(stroke
				(width 0.1)
				(type default)
			)
			(layer "F.Fab")
		)
		(fp_line
			(start 0.120396 0.3048)
			(end 0.120396 0.2794)
			(stroke
				(width 0.1)
				(type default)
			)
			(layer "F.Fab")
		)
		(fp_line
			(start 0.12065 -0.3048)
			(end 0.67945 -0.3048)
			(stroke
				(width 0.1)
				(type default)
			)
			(layer "F.Fab")
		)
		(fp_line
			(start 0.12065 -0.2794)
			(end 0.12065 -0.3048)
			(stroke
				(width 0.1)
				(type default)
			)
			(layer "F.Fab")
		)
		(fp_line
			(start 0.67945 -0.3048)
			(end 0.67945 0.3048)
			(stroke
				(width 0.1)
				(type default)
			)
			(layer "F.Fab")
		)
		(fp_line
			(start 0.67945 0.3048)
			(end 0.120396 0.3048)
			(stroke
				(width 0.1)
				(type default)
			)
			(layer "F.Fab")
		)
		(pad "1" smd circle
			(at -0.40005 0)
			(size 0 0)
			(layers "F.Cu" "F.Mask" "F.Paste")
			(net "P3V3_AUX")
		)
		(pad "2" smd circle
			(at 0.40005 0)
			(size 0 0)
			(layers "F.Cu" "F.Mask" "F.Paste")
			(net "CLK_GEN2_SMB_SADR")
		)
	)
	(footprint ""
		(layer "F.Cu")
		(at 226.0981 -405.036782 180)
		(property "Reference" "PC2227"
			(at 0 0 180)
			(layer "F.SilkS")
			(hide yes)
			(effects
				(font
					(size 1.27 1.27)
				)
			)
		)
		(property "Value" ""
			(at 0 0 180)
			(layer "F.Fab")
			(effects
				(font
					(size 1.27 1.27)
				)
			)
		)
		(duplicate_pad_numbers_are_jumpers no)
		(fp_line
			(start 0.7874 0.4064)
			(end -0.7874 0.4064)
			(stroke
				(width 0.1524)
				(type default)
			)
			(layer "F.SilkS")
		)
		(fp_line
			(start 0.7874 -0.4064)
			(end 0.7874 0.4064)
			(stroke
				(width 0.1524)
				(type default)
			)
			(layer "F.SilkS")
		)
		(fp_line
			(start -0.7874 0.4064)
			(end -0.7874 -0.4064)
			(stroke
				(width 0.1524)
				(type default)
			)
			(layer "F.SilkS")
		)
		(fp_line
			(start -0.7874 -0.4064)
			(end 0.7874 -0.4064)
			(stroke
				(width 0.1524)
				(type default)
			)
			(layer "F.SilkS")
		)
		(fp_line
			(start 0.67945 0.3048)
			(end 0.120396 0.3048)
			(stroke
				(width 0.1)
				(type default)
			)
			(layer "F.Fab")
		)
		(fp_line
			(start 0.67945 -0.3048)
			(end 0.67945 0.3048)
			(stroke
				(width 0.1)
				(type default)
			)
			(layer "F.Fab")
		)
		(fp_line
			(start 0.12065 -0.2794)
			(end 0.12065 -0.3048)
			(stroke
				(width 0.1)
				(type default)
			)
			(layer "F.Fab")
		)
		(fp_line
			(start 0.12065 -0.3048)
			(end 0.67945 -0.3048)
			(stroke
				(width 0.1)
				(type default)
			)
			(layer "F.Fab")
		)
		(fp_line
			(start 0.120396 0.3048)
			(end 0.120396 0.2794)
			(stroke
				(width 0.1)
				(type default)
			)
			(layer "F.Fab")
		)
		(fp_line
			(start 0.120396 0.2794)
			(end -0.12065 0.2794)
			(stroke
				(width 0.1)
				(type default)
			)
			(layer "F.Fab")
		)
		(fp_line
			(start -0.12065 0.3048)
			(end -0.67945 0.3048)
			(stroke
				(width 0.1)
				(type default)
			)
			(layer "F.Fab")
		)
		(fp_line
			(start -0.12065 0.2794)
			(end -0.12065 0.3048)
			(stroke
				(width 0.1)
				(type default)
			)
			(layer "F.Fab")
		)
		(fp_line
			(start -0.12065 -0.2794)
			(end 0.12065 -0.2794)
			(stroke
				(width 0.1)
				(type default)
			)
			(layer "F.Fab")
		)
		(fp_line
			(start -0.12065 -0.305054)
			(end -0.12065 -0.2794)
			(stroke
				(width 0.1)
				(type default)
			)
			(layer "F.Fab")
		)
		(fp_line
			(start -0.67945 0.3048)
			(end -0.67945 -0.305054)
			(stroke
				(width 0.1)
				(type default)
			)
			(layer "F.Fab")
		)
		(fp_line
			(start -0.67945 -0.305054)
			(end -0.12065 -0.305054)
			(stroke
				(width 0.1)
				(type default)
			)
			(layer "F.Fab")
		)
		(pad "1" smd circle
			(at -0.40005 0 180)
			(size 0 0)
			(layers "F.Cu" "F.Mask" "F.Paste")
			(net "HSC_SS")
		)
		(pad "2" smd circle
			(at 0.40005 0 180)
			(size 0 0)
			(layers "F.Cu" "F.Mask" "F.Paste")
			(net "AGND_HSC")
		)
	)
	(footprint ""
		(layer "F.Cu")
		(at 233.748072 -69.560186 -90)
		(property "Reference" "R1038"
			(at 0 0 270)
			(layer "F.SilkS")
			(hide yes)
			(effects
				(font
					(size 1.27 1.27)
				)
			)
		)
		(property "Value" ""
			(at 0 0 270)
			(layer "F.Fab")
			(effects
				(font
					(size 1.27 1.27)
				)
			)
		)
		(duplicate_pad_numbers_are_jumpers no)
		(fp_line
			(start -0.7874 0.4064)
			(end -0.7874 -0.4064)
			(stroke
				(width 0.1524)
				(type default)
			)
			(layer "F.SilkS")
		)
		(fp_line
			(start 0.7874 0.4064)
			(end -0.7874 0.4064)
			(stroke
				(width 0.1524)
				(type default)
			)
			(layer "F.SilkS")
		)
		(fp_line
			(start -0.7874 -0.4064)
			(end 0.7874 -0.4064)
			(stroke
				(width 0.1524)
				(type default)
			)
			(layer "F.SilkS")
		)
		(fp_line
			(start 0.7874 -0.4064)
			(end 0.7874 0.4064)
			(stroke
				(width 0.1524)
				(type default)
			)
			(layer "F.SilkS")
		)
		(fp_line
			(start -0.67945 0.3048)
			(end -0.67945 -0.305054)
			(stroke
				(width 0.1)
				(type default)
			)
			(layer "F.Fab")
		)
		(fp_line
			(start -0.12065 0.3048)
			(end -0.67945 0.3048)
			(stroke
				(width 0.1)
				(type default)
			)
			(layer "F.Fab")
		)
		(fp_line
			(start 0.120396 0.3048)
			(end 0.120396 0.2794)
			(stroke
				(width 0.1)
				(type default)
			)
			(layer "F.Fab")
		)
		(fp_line
			(start 0.67945 0.3048)
			(end 0.120396 0.3048)
			(stroke
				(width 0.1)
				(type default)
			)
			(layer "F.Fab")
		)
		(fp_line
			(start -0.12065 0.2794)
			(end -0.12065 0.3048)
			(stroke
				(width 0.1)
				(type default)
			)
			(layer "F.Fab")
		)
		(fp_line
			(start 0.120396 0.2794)
			(end -0.12065 0.2794)
			(stroke
				(width 0.1)
				(type default)
			)
			(layer "F.Fab")
		)
		(fp_line
			(start -0.12065 -0.2794)
			(end 0.12065 -0.2794)
			(stroke
				(width 0.1)
				(type default)
			)
			(layer "F.Fab")
		)
		(fp_line
			(start 0.12065 -0.2794)
			(end 0.12065 -0.3048)
			(stroke
				(width 0.1)
				(type default)
			)
			(layer "F.Fab")
		)
		(fp_line
			(start 0.12065 -0.3048)
			(end 0.67945 -0.3048)
			(stroke
				(width 0.1)
				(type default)
			)
			(layer "F.Fab")
		)
		(fp_line
			(start 0.67945 -0.3048)
			(end 0.67945 0.3048)
			(stroke
				(width 0.1)
				(type default)
			)
			(layer "F.Fab")
		)
		(fp_line
			(start -0.67945 -0.305054)
			(end -0.12065 -0.305054)
			(stroke
				(width 0.1)
				(type default)
			)
			(layer "F.Fab")
		)
		(fp_line
			(start -0.12065 -0.305054)
			(end -0.12065 -0.2794)
			(stroke
				(width 0.1)
				(type default)
			)
			(layer "F.Fab")
		)
		(pad "1" smd circle
			(at -0.40005 0 270)
			(size 0 0)
			(layers "F.Cu" "F.Mask" "F.Paste")
			(net "FM_LED_ACTIVE_E1S_0_R_BUF")
		)
		(pad "2" smd circle
			(at 0.40005 0 270)
			(size 0 0)
			(layers "F.Cu" "F.Mask" "F.Paste")
			(net "FM_LED_ACTIVE_E1S_0_BUF")
		)
	)
	(footprint ""
		(layer "F.Cu")
		(at 69.211444 -408.517344 -90)
		(property "Reference" "C6644"
			(at 0 0 270)
			(layer "F.SilkS")
			(hide yes)
			(effects
				(font
					(size 1.27 1.27)
				)
			)
		)
		(property "Value" ""
			(at 0 0 270)
			(layer "F.Fab")
			(effects
				(font
					(size 1.27 1.27)
				)
			)
		)
		(duplicate_pad_numbers_are_jumpers no)
		(fp_line
			(start -0.299974 0.150114)
			(end -0.299974 -0.150114)
			(stroke
				(width 0.1)
				(type default)
			)
			(layer "F.Fab")
		)
		(fp_line
			(start 0.299974 0.150114)
			(end -0.299974 0.150114)
			(stroke
				(width 0.1)
				(type default)
			)
			(layer "F.Fab")
		)
		(fp_line
			(start -0.299974 -0.150114)
			(end 0.299974 -0.150114)
			(stroke
				(width 0.1)
				(type default)
			)
			(layer "F.Fab")
		)
		(fp_line
			(start 0.299974 -0.150114)
			(end 0.299974 0.150114)
			(stroke
				(width 0.1)
				(type default)
			)
			(layer "F.Fab")
		)
		(pad "1" smd rect
			(at -0.2667 0 270)
			(size 0.3048 0.381)
			(layers "F.Cu" "F.Mask" "F.Paste")
			(net "P5E_CPU1_P0_TX_BUF_C_DN<7>")
		)
		(pad "2" smd rect
			(at 0.2667 0 270)
			(size 0.3048 0.381)
			(layers "F.Cu" "F.Mask" "F.Paste")
			(net "P5E_CPU1_P0_TX_BUF_DN<7>")
		)
	)
	(footprint ""
		(layer "F.Cu")
		(at 164.544756 -41.112948)
		(property "Reference" "R3301"
			(at 0 0 0)
			(layer "F.SilkS")
			(hide yes)
			(effects
				(font
					(size 1.27 1.27)
				)
			)
		)
		(property "Value" ""
			(at 0 0 0)
			(layer "F.Fab")
			(effects
				(font
					(size 1.27 1.27)
				)
			)
		)
		(duplicate_pad_numbers_are_jumpers no)
		(fp_line
			(start -0.7874 -0.4064)
			(end 0.7874 -0.4064)
			(stroke
				(width 0.1524)
				(type default)
			)
			(layer "F.SilkS")
		)
		(fp_line
			(start -0.7874 0.4064)
			(end -0.7874 -0.4064)
			(stroke
				(width 0.1524)
				(type default)
			)
			(layer "F.SilkS")
		)
		(fp_line
			(start 0.7874 -0.4064)
			(end 0.7874 0.4064)
			(stroke
				(width 0.1524)
				(type default)
			)
			(layer "F.SilkS")
		)
		(fp_line
			(start 0.7874 0.4064)
			(end -0.7874 0.4064)
			(stroke
				(width 0.1524)
				(type default)
			)
			(layer "F.SilkS")
		)
		(fp_line
			(start -0.67945 -0.305054)
			(end -0.12065 -0.305054)
			(stroke
				(width 0.1)
				(type default)
			)
			(layer "F.Fab")
		)
		(fp_line
			(start -0.67945 0.3048)
			(end -0.67945 -0.305054)
			(stroke
				(width 0.1)
				(type default)
			)
			(layer "F.Fab")
		)
		(fp_line
			(start -0.12065 -0.305054)
			(end -0.12065 -0.2794)
			(stroke
				(width 0.1)
				(type default)
			)
			(layer "F.Fab")
		)
		(fp_line
			(start -0.12065 -0.2794)
			(end 0.12065 -0.2794)
			(stroke
				(width 0.1)
				(type default)
			)
			(layer "F.Fab")
		)
		(fp_line
			(start -0.12065 0.2794)
			(end -0.12065 0.3048)
			(stroke
				(width 0.1)
				(type default)
			)
			(layer "F.Fab")
		)
		(fp_line
			(start -0.12065 0.3048)
			(end -0.67945 0.3048)
			(stroke
				(width 0.1)
				(type default)
			)
			(layer "F.Fab")
		)
		(fp_line
			(start 0.120396 0.2794)
			(end -0.12065 0.2794)
			(stroke
				(width 0.1)
				(type default)
			)
			(layer "F.Fab")
		)
		(fp_line
			(start 0.120396 0.3048)
			(end 0.120396 0.2794)
			(stroke
				(width 0.1)
				(type default)
			)
			(layer "F.Fab")
		)
		(fp_line
			(start 0.12065 -0.3048)
			(end 0.67945 -0.3048)
			(stroke
				(width 0.1)
				(type default)
			)
			(layer "F.Fab")
		)
		(fp_line
			(start 0.12065 -0.2794)
			(end 0.12065 -0.3048)
			(stroke
				(width 0.1)
				(type default)
			)
			(layer "F.Fab")
		)
		(fp_line
			(start 0.67945 -0.3048)
			(end 0.67945 0.3048)
			(stroke
				(width 0.1)
				(type default)
			)
			(layer "F.Fab")
		)
		(fp_line
			(start 0.67945 0.3048)
			(end 0.120396 0.3048)
			(stroke
				(width 0.1)
				(type default)
			)
			(layer "F.Fab")
		)
		(pad "1" smd circle
			(at -0.40005 0)
			(size 0 0)
			(layers "F.Cu" "F.Mask" "F.Paste")
			(net "M2_0_PEWAKE_R_N")
		)
		(pad "2" smd circle
			(at 0.40005 0)
			(size 0 0)
			(layers "F.Cu" "F.Mask" "F.Paste")
			(net "M2_0_PEWAKE_N")
		)
	)
	(footprint ""
		(layer "F.Cu")
		(at 117.895624 -259.355336 180)
		(property "Reference" "C2269"
			(at 0 0 180)
			(layer "F.SilkS")
			(hide yes)
			(effects
				(font
					(size 1.27 1.27)
				)
			)
		)
		(property "Value" ""
			(at 0 0 180)
			(layer "F.Fab")
			(effects
				(font
					(size 1.27 1.27)
				)
			)
		)
		(duplicate_pad_numbers_are_jumpers no)
		(fp_line
			(start 0.7874 0.4064)
			(end -0.7874 0.4064)
			(stroke
				(width 0.1524)
				(type default)
			)
			(layer "F.SilkS")
		)
		(fp_line
			(start 0.7874 -0.4064)
			(end 0.7874 0.4064)
			(stroke
				(width 0.1524)
				(type default)
			)
			(layer "F.SilkS")
		)
		(fp_line
			(start -0.7874 0.4064)
			(end -0.7874 -0.4064)
			(stroke
				(width 0.1524)
				(type default)
			)
			(layer "F.SilkS")
		)
		(fp_line
			(start -0.7874 -0.4064)
			(end 0.7874 -0.4064)
			(stroke
				(width 0.1524)
				(type default)
			)
			(layer "F.SilkS")
		)
		(fp_line
			(start 0.67945 0.3048)
			(end 0.120396 0.3048)
			(stroke
				(width 0.1)
				(type default)
			)
			(layer "F.Fab")
		)
		(fp_line
			(start 0.67945 -0.3048)
			(end 0.67945 0.3048)
			(stroke
				(width 0.1)
				(type default)
			)
			(layer "F.Fab")
		)
		(fp_line
			(start 0.12065 -0.2794)
			(end 0.12065 -0.3048)
			(stroke
				(width 0.1)
				(type default)
			)
			(layer "F.Fab")
		)
		(fp_line
			(start 0.12065 -0.3048)
			(end 0.67945 -0.3048)
			(stroke
				(width 0.1)
				(type default)
			)
			(layer "F.Fab")
		)
		(fp_line
			(start 0.120396 0.3048)
			(end 0.120396 0.2794)
			(stroke
				(width 0.1)
				(type default)
			)
			(layer "F.Fab")
		)
		(fp_line
			(start 0.120396 0.2794)
			(end -0.12065 0.2794)
			(stroke
				(width 0.1)
				(type default)
			)
			(layer "F.Fab")
		)
		(fp_line
			(start -0.12065 0.3048)
			(end -0.67945 0.3048)
			(stroke
				(width 0.1)
				(type default)
			)
			(layer "F.Fab")
		)
		(fp_line
			(start -0.12065 0.2794)
			(end -0.12065 0.3048)
			(stroke
				(width 0.1)
				(type default)
			)
			(layer "F.Fab")
		)
		(fp_line
			(start -0.12065 -0.2794)
			(end 0.12065 -0.2794)
			(stroke
				(width 0.1)
				(type default)
			)
			(layer "F.Fab")
		)
		(fp_line
			(start -0.12065 -0.305054)
			(end -0.12065 -0.2794)
			(stroke
				(width 0.1)
				(type default)
			)
			(layer "F.Fab")
		)
		(fp_line
			(start -0.67945 0.3048)
			(end -0.67945 -0.305054)
			(stroke
				(width 0.1)
				(type default)
			)
			(layer "F.Fab")
		)
		(fp_line
			(start -0.67945 -0.305054)
			(end -0.12065 -0.305054)
			(stroke
				(width 0.1)
				(type default)
			)
			(layer "F.Fab")
		)
		(pad "1" smd circle
			(at -0.40005 0 180)
			(size 0 0)
			(layers "F.Cu" "F.Mask" "F.Paste")
			(net "PVDDCR_SOC_P1")
		)
		(pad "2" smd circle
			(at 0.40005 0 180)
			(size 0 0)
			(layers "F.Cu" "F.Mask" "F.Paste")
			(net "GND")
		)
	)
	(footprint ""
		(layer "F.Cu")
		(at 328.694542 -393.9032 90)
		(property "Reference" "R966"
			(at 0 0 90)
			(layer "F.SilkS")
			(hide yes)
			(effects
				(font
					(size 1.27 1.27)
				)
			)
		)
		(property "Value" ""
			(at 0 0 90)
			(layer "F.Fab")
			(effects
				(font
					(size 1.27 1.27)
				)
			)
		)
		(duplicate_pad_numbers_are_jumpers no)
		(fp_line
			(start 0.32512 -0.175006)
			(end 0.32512 0.175006)
			(stroke
				(width 0.1)
				(type default)
			)
			(layer "F.Fab")
		)
		(fp_line
			(start -0.32512 -0.175006)
			(end 0.32512 -0.175006)
			(stroke
				(width 0.1)
				(type default)
			)
			(layer "F.Fab")
		)
		(fp_line
			(start 0.32512 0.175006)
			(end -0.32512 0.175006)
			(stroke
				(width 0.1)
				(type default)
			)
			(layer "F.Fab")
		)
		(fp_line
			(start -0.32512 0.175006)
			(end -0.32512 -0.175006)
			(stroke
				(width 0.1)
				(type default)
			)
			(layer "F.Fab")
		)
		(pad "1" smd rect
			(at -0.2667 0 90)
			(size 0.3048 0.381)
			(layers "F.Cu" "F.Mask" "F.Paste")
			(net "P1V8_CPU0_RT_1D")
		)
		(pad "2" smd rect
			(at 0.2667 0 270)
			(size 0.3048 0.381)
			(layers "F.Cu" "F.Mask" "F.Paste")
			(net "RT_CPU0_P0_ADDR2")
		)
	)
	(footprint ""
		(layer "F.Cu")
		(at 186.817 -100.294948 90)
		(property "Reference" "R6053"
			(at 0 0 90)
			(layer "F.SilkS")
			(hide yes)
			(effects
				(font
					(size 1.27 1.27)
				)
			)
		)
		(property "Value" ""
			(at 0 0 90)
			(layer "F.Fab")
			(effects
				(font
					(size 1.27 1.27)
				)
			)
		)
		(duplicate_pad_numbers_are_jumpers no)
		(fp_line
			(start 0.7874 -0.4064)
			(end 0.7874 0.4064)
			(stroke
				(width 0.1524)
				(type default)
			)
			(layer "F.SilkS")
		)
		(fp_line
			(start -0.7874 -0.4064)
			(end 0.7874 -0.4064)
			(stroke
				(width 0.1524)
				(type default)
			)
			(layer "F.SilkS")
		)
		(fp_line
			(start 0.7874 0.4064)
			(end -0.7874 0.4064)
			(stroke
				(width 0.1524)
				(type default)
			)
			(layer "F.SilkS")
		)
		(fp_line
			(start -0.7874 0.4064)
			(end -0.7874 -0.4064)
			(stroke
				(width 0.1524)
				(type default)
			)
			(layer "F.SilkS")
		)
		(fp_line
			(start -0.12065 -0.305054)
			(end -0.12065 -0.2794)
			(stroke
				(width 0.1)
				(type default)
			)
			(layer "F.Fab")
		)
		(fp_line
			(start -0.67945 -0.305054)
			(end -0.12065 -0.305054)
			(stroke
				(width 0.1)
				(type default)
			)
			(layer "F.Fab")
		)
		(fp_line
			(start 0.67945 -0.3048)
			(end 0.67945 0.3048)
			(stroke
				(width 0.1)
				(type default)
			)
			(layer "F.Fab")
		)
		(fp_line
			(start 0.12065 -0.3048)
			(end 0.67945 -0.3048)
			(stroke
				(width 0.1)
				(type default)
			)
			(layer "F.Fab")
		)
		(fp_line
			(start 0.12065 -0.2794)
			(end 0.12065 -0.3048)
			(stroke
				(width 0.1)
				(type default)
			)
			(layer "F.Fab")
		)
		(fp_line
			(start -0.12065 -0.2794)
			(end 0.12065 -0.2794)
			(stroke
				(width 0.1)
				(type default)
			)
			(layer "F.Fab")
		)
		(fp_line
			(start 0.120396 0.2794)
			(end -0.12065 0.2794)
			(stroke
				(width 0.1)
				(type default)
			)
			(layer "F.Fab")
		)
		(fp_line
			(start -0.12065 0.2794)
			(end -0.12065 0.3048)
			(stroke
				(width 0.1)
				(type default)
			)
			(layer "F.Fab")
		)
		(fp_line
			(start 0.67945 0.3048)
			(end 0.120396 0.3048)
			(stroke
				(width 0.1)
				(type default)
			)
			(layer "F.Fab")
		)
		(fp_line
			(start 0.120396 0.3048)
			(end 0.120396 0.2794)
			(stroke
				(width 0.1)
				(type default)
			)
			(layer "F.Fab")
		)
		(fp_line
			(start -0.12065 0.3048)
			(end -0.67945 0.3048)
			(stroke
				(width 0.1)
				(type default)
			)
			(layer "F.Fab")
		)
		(fp_line
			(start -0.67945 0.3048)
			(end -0.67945 -0.305054)
			(stroke
				(width 0.1)
				(type default)
			)
			(layer "F.Fab")
		)
		(pad "1" smd circle
			(at -0.40005 0 90)
			(size 0 0)
			(layers "F.Cu" "F.Mask" "F.Paste")
			(net "M2_SSD0_CLKREQ_EN_N")
		)
		(pad "2" smd circle
			(at 0.40005 0 90)
			(size 0 0)
			(layers "F.Cu" "F.Mask" "F.Paste")
			(net "FM_CLKREQ_M2_1_N")
		)
	)
	(footprint ""
		(layer "F.Cu")
		(at 389.291322 -192.061084 180)
		(property "Reference" "PL60"
			(at -5.632196 3.113278 90)
			(unlocked yes)
			(layer "F.SilkS")
			(effects
				(font
					(size 0.7874 0.5842)
					(thickness 0.1524)
				)
				(justify left)
			)
		)
		(property "Value" ""
			(at 0 0 180)
			(layer "F.Fab")
			(effects
				(font
					(size 1.27 1.27)
				)
			)
		)
		(duplicate_pad_numbers_are_jumpers no)
		(fp_line
			(start 3.750056 5.500116)
			(end 3.750056 -5.500116)
			(stroke
				(width 0.1524)
				(type default)
			)
			(layer "F.SilkS")
		)
		(fp_line
			(start 3.750056 -5.500116)
			(end 2.393442 -5.500116)
			(stroke
				(width 0.1524)
				(type default)
			)
			(layer "F.SilkS")
		)
		(fp_line
			(start 2.393442 5.500116)
			(end 3.750056 5.500116)
			(stroke
				(width 0.1524)
				(type default)
			)
			(layer "F.SilkS")
		)
		(fp_line
			(start -2.393442 5.500116)
			(end -3.750056 5.500116)
			(stroke
				(width 0.1524)
				(type default)
			)
			(layer "F.SilkS")
		)
		(fp_line
			(start -3.750056 5.500116)
			(end -3.750056 -5.500116)
			(stroke
				(width 0.1524)
				(type default)
			)
			(layer "F.SilkS")
		)
		(fp_line
			(start -3.750056 -5.500116)
			(end -2.393442 -5.500116)
			(stroke
				(width 0.1524)
				(type default)
			)
			(layer "F.SilkS")
		)
		(fp_poly
			(pts
				(xy -3.9116 -4.249928) (xy -4.662678 -3.874516) (xy -4.662678 -4.62534)
			)
			(stroke
				(width 0)
				(type default)
			)
			(fill yes)
			(layer "F.SilkS")
		)
		(fp_line
			(start 3.750056 5.500116)
			(end 3.750056 -5.500116)
			(stroke
				(width 0.1)
				(type default)
			)
			(layer "F.Fab")
		)
		(fp_line
			(start 3.750056 -5.500116)
			(end -3.750056 -5.500116)
			(stroke
				(width 0.1)
				(type default)
			)
			(layer "F.Fab")
		)
		(fp_line
			(start -3.750056 5.500116)
			(end 3.750056 5.500116)
			(stroke
				(width 0.1)
				(type default)
			)
			(layer "F.Fab")
		)
		(fp_line
			(start -3.750056 -5.500116)
			(end -3.750056 5.500116)
			(stroke
				(width 0.1)
				(type default)
			)
			(layer "F.Fab")
		)
		(fp_poly
			(pts
				(xy -4.9276 -4.757928) (xy -4.9276 -3.741928) (xy -3.9116 -4.249928)
			)
			(stroke
				(width 0)
				(type default)
			)
			(fill yes)
			(layer "F.Fab")
		)
		(pad "1" smd rect
			(at 0 -4.249928 90)
			(size 2.413 4.5212)
			(layers "F.Cu" "F.Mask" "F.Paste")
			(net "SW_PVDDCR_CPU0_P0_SW4")
		)
		(pad "2" smd rect
			(at 0 -1.175004 90)
			(size 1.3716 4.5212)
			(layers "F.Cu" "F.Mask" "F.Paste")
			(net "IND_CPU0_P0_CPL3")
		)
		(pad "3" smd rect
			(at 0 1.175004 90)
			(size 1.3716 4.5212)
			(layers "F.Cu" "F.Mask" "F.Paste")
			(net "GND")
		)
		(pad "4" smd rect
			(at 0 4.249928 90)
			(size 2.413 4.5212)
			(layers "F.Cu" "F.Mask" "F.Paste")
			(net "PVDDCR_CPU0_P0")
		)
	)
	(footprint ""
		(layer "F.Cu")
		(at 50.711354 -373.03583 -90)
		(property "Reference" "C826"
			(at 0 0 270)
			(layer "F.SilkS")
			(hide yes)
			(effects
				(font
					(size 1.27 1.27)
				)
			)
		)
		(property "Value" ""
			(at 0 0 270)
			(layer "F.Fab")
			(effects
				(font
					(size 1.27 1.27)
				)
			)
		)
		(duplicate_pad_numbers_are_jumpers no)
		(fp_line
			(start -0.299974 0.150114)
			(end -0.299974 -0.150114)
			(stroke
				(width 0.1)
				(type default)
			)
			(layer "F.Fab")
		)
		(fp_line
			(start 0.299974 0.150114)
			(end -0.299974 0.150114)
			(stroke
				(width 0.1)
				(type default)
			)
			(layer "F.Fab")
		)
		(fp_line
			(start -0.299974 -0.150114)
			(end 0.299974 -0.150114)
			(stroke
				(width 0.1)
				(type default)
			)
			(layer "F.Fab")
		)
		(fp_line
			(start 0.299974 -0.150114)
			(end 0.299974 0.150114)
			(stroke
				(width 0.1)
				(type default)
			)
			(layer "F.Fab")
		)
		(pad "1" smd rect
			(at -0.2667 0 270)
			(size 0.3048 0.381)
			(layers "F.Cu" "F.Mask" "F.Paste")
			(net "P5E_CPU1_P0_TX_C_DN<5>")
		)
		(pad "2" smd rect
			(at 0.2667 0 270)
			(size 0.3048 0.381)
			(layers "F.Cu" "F.Mask" "F.Paste")
			(net "P5E_CPU1_P0_TX_DN<5>")
		)
	)
	(footprint ""
		(layer "F.Cu")
		(at 103.125524 -414.329626)
		(property "Reference" "R6863"
			(at 0 0 0)
			(layer "F.SilkS")
			(hide yes)
			(effects
				(font
					(size 1.27 1.27)
				)
			)
		)
		(property "Value" ""
			(at 0 0 0)
			(layer "F.Fab")
			(effects
				(font
					(size 1.27 1.27)
				)
			)
		)
		(duplicate_pad_numbers_are_jumpers no)
		(fp_line
			(start -0.7874 -0.4064)
			(end 0.7874 -0.4064)
			(stroke
				(width 0.1524)
				(type default)
			)
			(layer "F.SilkS")
		)
		(fp_line
			(start -0.7874 0.4064)
			(end -0.7874 -0.4064)
			(stroke
				(width 0.1524)
				(type default)
			)
			(layer "F.SilkS")
		)
		(fp_line
			(start 0.7874 -0.4064)
			(end 0.7874 0.4064)
			(stroke
				(width 0.1524)
				(type default)
			)
			(layer "F.SilkS")
		)
		(fp_line
			(start 0.7874 0.4064)
			(end -0.7874 0.4064)
			(stroke
				(width 0.1524)
				(type default)
			)
			(layer "F.SilkS")
		)
		(fp_line
			(start -0.67945 -0.305054)
			(end -0.12065 -0.305054)
			(stroke
				(width 0.1)
				(type default)
			)
			(layer "F.Fab")
		)
		(fp_line
			(start -0.67945 0.3048)
			(end -0.67945 -0.305054)
			(stroke
				(width 0.1)
				(type default)
			)
			(layer "F.Fab")
		)
		(fp_line
			(start -0.12065 -0.305054)
			(end -0.12065 -0.2794)
			(stroke
				(width 0.1)
				(type default)
			)
			(layer "F.Fab")
		)
		(fp_line
			(start -0.12065 -0.2794)
			(end 0.12065 -0.2794)
			(stroke
				(width 0.1)
				(type default)
			)
			(layer "F.Fab")
		)
		(fp_line
			(start -0.12065 0.2794)
			(end -0.12065 0.3048)
			(stroke
				(width 0.1)
				(type default)
			)
			(layer "F.Fab")
		)
		(fp_line
			(start -0.12065 0.3048)
			(end -0.67945 0.3048)
			(stroke
				(width 0.1)
				(type default)
			)
			(layer "F.Fab")
		)
		(fp_line
			(start 0.120396 0.2794)
			(end -0.12065 0.2794)
			(stroke
				(width 0.1)
				(type default)
			)
			(layer "F.Fab")
		)
		(fp_line
			(start 0.120396 0.3048)
			(end 0.120396 0.2794)
			(stroke
				(width 0.1)
				(type default)
			)
			(layer "F.Fab")
		)
		(fp_line
			(start 0.12065 -0.3048)
			(end 0.67945 -0.3048)
			(stroke
				(width 0.1)
				(type default)
			)
			(layer "F.Fab")
		)
		(fp_line
			(start 0.12065 -0.2794)
			(end 0.12065 -0.3048)
			(stroke
				(width 0.1)
				(type default)
			)
			(layer "F.Fab")
		)
		(fp_line
			(start 0.67945 -0.3048)
			(end 0.67945 0.3048)
			(stroke
				(width 0.1)
				(type default)
			)
			(layer "F.Fab")
		)
		(fp_line
			(start 0.67945 0.3048)
			(end 0.120396 0.3048)
			(stroke
				(width 0.1)
				(type default)
			)
			(layer "F.Fab")
		)
		(pad "1" smd circle
			(at -0.40005 0)
			(size 0 0)
			(layers "F.Cu" "F.Mask" "F.Paste")
			(net "SMB_HOST_CLK_3V3AUX_SDA_R1")
		)
		(pad "2" smd circle
			(at 0.40005 0)
			(size 0 0)
			(layers "F.Cu" "F.Mask" "F.Paste")
			(net "SMB_9ZXL045_P1_SDA")
		)
	)
	(footprint ""
		(layer "F.Cu")
		(at 412.472886 -75.880468 180)
		(property "Reference" "R3500"
			(at 0 0 180)
			(layer "F.SilkS")
			(hide yes)
			(effects
				(font
					(size 1.27 1.27)
				)
			)
		)
		(property "Value" ""
			(at 0 0 180)
			(layer "F.Fab")
			(effects
				(font
					(size 1.27 1.27)
				)
			)
		)
		(duplicate_pad_numbers_are_jumpers no)
		(fp_line
			(start 0.7874 0.4064)
			(end -0.7874 0.4064)
			(stroke
				(width 0.1524)
				(type default)
			)
			(layer "F.SilkS")
		)
		(fp_line
			(start 0.7874 -0.4064)
			(end 0.7874 0.4064)
			(stroke
				(width 0.1524)
				(type default)
			)
			(layer "F.SilkS")
		)
		(fp_line
			(start -0.7874 0.4064)
			(end -0.7874 -0.4064)
			(stroke
				(width 0.1524)
				(type default)
			)
			(layer "F.SilkS")
		)
		(fp_line
			(start -0.7874 -0.4064)
			(end 0.7874 -0.4064)
			(stroke
				(width 0.1524)
				(type default)
			)
			(layer "F.SilkS")
		)
		(fp_line
			(start 0.67945 0.3048)
			(end 0.120396 0.3048)
			(stroke
				(width 0.1)
				(type default)
			)
			(layer "F.Fab")
		)
		(fp_line
			(start 0.67945 -0.3048)
			(end 0.67945 0.3048)
			(stroke
				(width 0.1)
				(type default)
			)
			(layer "F.Fab")
		)
		(fp_line
			(start 0.12065 -0.2794)
			(end 0.12065 -0.3048)
			(stroke
				(width 0.1)
				(type default)
			)
			(layer "F.Fab")
		)
		(fp_line
			(start 0.12065 -0.3048)
			(end 0.67945 -0.3048)
			(stroke
				(width 0.1)
				(type default)
			)
			(layer "F.Fab")
		)
		(fp_line
			(start 0.120396 0.3048)
			(end 0.120396 0.2794)
			(stroke
				(width 0.1)
				(type default)
			)
			(layer "F.Fab")
		)
		(fp_line
			(start 0.120396 0.2794)
			(end -0.12065 0.2794)
			(stroke
				(width 0.1)
				(type default)
			)
			(layer "F.Fab")
		)
		(fp_line
			(start -0.12065 0.3048)
			(end -0.67945 0.3048)
			(stroke
				(width 0.1)
				(type default)
			)
			(layer "F.Fab")
		)
		(fp_line
			(start -0.12065 0.2794)
			(end -0.12065 0.3048)
			(stroke
				(width 0.1)
				(type default)
			)
			(layer "F.Fab")
		)
		(fp_line
			(start -0.12065 -0.2794)
			(end 0.12065 -0.2794)
			(stroke
				(width 0.1)
				(type default)
			)
			(layer "F.Fab")
		)
		(fp_line
			(start -0.12065 -0.305054)
			(end -0.12065 -0.2794)
			(stroke
				(width 0.1)
				(type default)
			)
			(layer "F.Fab")
		)
		(fp_line
			(start -0.67945 0.3048)
			(end -0.67945 -0.305054)
			(stroke
				(width 0.1)
				(type default)
			)
			(layer "F.Fab")
		)
		(fp_line
			(start -0.67945 -0.305054)
			(end -0.12065 -0.305054)
			(stroke
				(width 0.1)
				(type default)
			)
			(layer "F.Fab")
		)
		(pad "1" smd circle
			(at -0.40005 0 180)
			(size 0 0)
			(layers "F.Cu" "F.Mask" "F.Paste")
			(net "P3V3_OCP_SFF")
		)
		(pad "2" smd circle
			(at 0.40005 0 180)
			(size 0 0)
			(layers "F.Cu" "F.Mask" "F.Paste")
			(net "SMB_OCP_SFF_3V3AUX_BUF_SCL")
		)
	)
	(footprint ""
		(layer "F.Cu")
		(at 314.649612 -440.489848)
		(property "Reference" "J108"
			(at -7.73303 17.692878 0)
			(unlocked yes)
			(layer "F.SilkS")
			(effects
				(font
					(size 0.7874 0.5842)
					(thickness 0.1524)
				)
				(justify left)
			)
		)
		(property "Value" ""
			(at 0 0 0)
			(layer "F.Fab")
			(effects
				(font
					(size 1.27 1.27)
				)
			)
		)
		(duplicate_pad_numbers_are_jumpers no)
		(fp_line
			(start -4.249928 19.103848)
			(end -4.249928 -0.484124)
			(stroke
				(width 0.1524)
				(type default)
			)
			(layer "F.SilkS")
		)
		(fp_line
			(start -1.848612 22.400006)
			(end -3.855212 22.400006)
			(stroke
				(width 0.1524)
				(type default)
			)
			(layer "F.SilkS")
		)
		(fp_line
			(start -1.249934 -1.500124)
			(end 15.649956 -1.500124)
			(stroke
				(width 0.1524)
				(type default)
			)
			(layer "F.SilkS")
		)
		(fp_line
			(start -1.249934 -0.484124)
			(end -1.249934 19.400012)
			(stroke
				(width 0.1524)
				(type default)
			)
			(layer "F.SilkS")
		)
		(fp_line
			(start -0.451612 19.400012)
			(end 1.046988 19.400012)
			(stroke
				(width 0.1524)
				(type default)
			)
			(layer "F.SilkS")
		)
		(fp_line
			(start 0.0254 -0.9144)
			(end 1.0414 -0.9144)
			(stroke
				(width 0.1524)
				(type default)
			)
			(layer "F.SilkS")
		)
		(fp_line
			(start 0.5334 -1.4224)
			(end 0.0254 -0.9144)
			(stroke
				(width 0.1524)
				(type default)
			)
			(layer "F.SilkS")
		)
		(fp_line
			(start 0.5334 -1.4224)
			(end 0.5334 -0.5588)
			(stroke
				(width 0.1524)
				(type default)
			)
			(layer "F.SilkS")
		)
		(fp_line
			(start 0.5334 -0.5588)
			(end 1.8034 -0.5588)
			(stroke
				(width 0.1524)
				(type default)
			)
			(layer "F.SilkS")
		)
		(fp_line
			(start 1.0414 -0.9144)
			(end 0.5334 -1.4224)
			(stroke
				(width 0.1524)
				(type default)
			)
			(layer "F.SilkS")
		)
		(fp_line
			(start 1.072388 22.400006)
			(end -0.604012 22.400006)
			(stroke
				(width 0.1524)
				(type default)
			)
			(layer "F.SilkS")
		)
		(fp_line
			(start 1.8034 -0.5588)
			(end 2.032 -0.7874)
			(stroke
				(width 0.1524)
				(type default)
			)
			(layer "F.SilkS")
		)
		(fp_line
			(start 2.621788 19.400012)
			(end 4.120388 19.400012)
			(stroke
				(width 0.1524)
				(type default)
			)
			(layer "F.SilkS")
		)
		(fp_line
			(start 4.196588 22.400006)
			(end 2.469388 22.400006)
			(stroke
				(width 0.1524)
				(type default)
			)
			(layer "F.SilkS")
		)
		(fp_line
			(start 5.669788 19.400012)
			(end 7.168388 19.400012)
			(stroke
				(width 0.1524)
				(type default)
			)
			(layer "F.SilkS")
		)
		(fp_line
			(start 7.295388 22.400006)
			(end 5.542788 22.400006)
			(stroke
				(width 0.1524)
				(type default)
			)
			(layer "F.SilkS")
		)
		(fp_line
			(start 8.743188 19.400012)
			(end 10.216388 19.400012)
			(stroke
				(width 0.1524)
				(type default)
			)
			(layer "F.SilkS")
		)
		(fp_line
			(start 10.317988 22.400006)
			(end 8.616188 22.400006)
			(stroke
				(width 0.1524)
				(type default)
			)
			(layer "F.SilkS")
		)
		(fp_line
			(start 11.841988 19.400012)
			(end 13.315188 19.400012)
			(stroke
				(width 0.1524)
				(type default)
			)
			(layer "F.SilkS")
		)
		(fp_line
			(start 13.391388 22.400006)
			(end 11.740388 22.400006)
			(stroke
				(width 0.1524)
				(type default)
			)
			(layer "F.SilkS")
		)
		(fp_line
			(start 14.915388 19.400012)
			(end 15.649956 19.400012)
			(stroke
				(width 0.1524)
				(type default)
			)
			(layer "F.SilkS")
		)
		(fp_line
			(start 15.649956 19.400012)
			(end 15.649956 16.817848)
			(stroke
				(width 0.1524)
				(type default)
			)
			(layer "F.SilkS")
		)
		(fp_line
			(start 16.439388 22.400006)
			(end 14.762988 22.400006)
			(stroke
				(width 0.1524)
				(type default)
			)
			(layer "F.SilkS")
		)
		(fp_line
			(start 18.64995 16.888968)
			(end 18.64995 18.849848)
			(stroke
				(width 0.1524)
				(type default)
			)
			(layer "F.SilkS")
		)
		(fp_line
			(start 18.64995 20.500848)
			(end 18.64995 22.400006)
			(stroke
				(width 0.1524)
				(type default)
			)
			(layer "F.SilkS")
		)
		(fp_line
			(start 18.64995 22.400006)
			(end 17.836388 22.400006)
			(stroke
				(width 0.1524)
				(type default)
			)
			(layer "F.SilkS")
		)
		(fp_poly
			(pts
				(xy -1.654048 0) (xy -2.670048 0.508) (xy -2.670048 -0.508)
			)
			(stroke
				(width 0)
				(type default)
			)
			(fill yes)
			(layer "F.SilkS")
		)
		(fp_line
			(start -4.249928 -11.999976)
			(end 18.64995 -11.999976)
			(stroke
				(width 0.1524)
				(type default)
			)
			(layer "B.SilkS")
		)
		(fp_line
			(start -4.249928 22.400006)
			(end -4.249928 -11.999976)
			(stroke
				(width 0.1524)
				(type default)
			)
			(layer "B.SilkS")
		)
		(fp_line
			(start -3.550412 22.400006)
			(end -4.249928 22.400006)
			(stroke
				(width 0.1524)
				(type default)
			)
			(layer "B.SilkS")
		)
		(fp_line
			(start -0.502412 22.400006)
			(end -1.874012 22.400006)
			(stroke
				(width 0.1524)
				(type default)
			)
			(layer "B.SilkS")
		)
		(fp_line
			(start 2.596388 22.400006)
			(end 1.173988 22.400006)
			(stroke
				(width 0.1524)
				(type default)
			)
			(layer "B.SilkS")
		)
		(fp_line
			(start 5.669788 22.400006)
			(end 4.145788 22.400006)
			(stroke
				(width 0.1524)
				(type default)
			)
			(layer "B.SilkS")
		)
		(fp_line
			(start 8.666988 22.400006)
			(end 7.295388 22.400006)
			(stroke
				(width 0.1524)
				(type default)
			)
			(layer "B.SilkS")
		)
		(fp_line
			(start 11.537188 22.400006)
			(end 10.292588 22.400006)
			(stroke
				(width 0.1524)
				(type default)
			)
			(layer "B.SilkS")
		)
		(fp_line
			(start 14.889988 22.400006)
			(end 13.416788 22.400006)
			(stroke
				(width 0.1524)
				(type default)
			)
			(layer "B.SilkS")
		)
		(fp_line
			(start 17.937988 22.400006)
			(end 16.286988 22.400006)
			(stroke
				(width 0.1524)
				(type default)
			)
			(layer "B.SilkS")
		)
		(fp_line
			(start 18.64995 -11.999976)
			(end 18.64995 -0.781812)
			(stroke
				(width 0.1524)
				(type default)
			)
			(layer "B.SilkS")
		)
		(fp_line
			(start 18.64995 16.980408)
			(end 18.64995 21.745448)
			(stroke
				(width 0.1524)
				(type default)
			)
			(layer "B.SilkS")
		)
		(fp_line
			(start -4.249928 -11.999976)
			(end 18.64995 -11.999976)
			(stroke
				(width 0.1)
				(type default)
			)
			(layer "B.Fab")
		)
		(fp_line
			(start -4.249928 22.400006)
			(end -4.249928 -11.999976)
			(stroke
				(width 0.1)
				(type default)
			)
			(layer "B.Fab")
		)
		(fp_line
			(start 18.64995 -11.999976)
			(end 18.64995 22.400006)
			(stroke
				(width 0.1)
				(type default)
			)
			(layer "B.Fab")
		)
		(fp_line
			(start 18.64995 22.400006)
			(end -4.249928 22.400006)
			(stroke
				(width 0.1)
				(type default)
			)
			(layer "B.Fab")
		)
		(fp_line
			(start -1.249934 -8.999982)
			(end -1.249934 19.400012)
			(stroke
				(width 0.1)
				(type default)
			)
			(layer "F.Fab")
		)
		(fp_line
			(start -1.249934 19.400012)
			(end 15.649956 19.400012)
			(stroke
				(width 0.1)
				(type default)
			)
			(layer "F.Fab")
		)
		(fp_line
			(start 15.649956 -8.999982)
			(end -1.249934 -8.999982)
			(stroke
				(width 0.1)
				(type default)
			)
			(layer "F.Fab")
		)
		(fp_line
			(start 15.649956 19.400012)
			(end 15.649956 -8.999982)
			(stroke
				(width 0.1)
				(type default)
			)
			(layer "F.Fab")
		)
		(fp_poly
			(pts
				(xy -2.670048 -0.508) (xy -2.670048 0.508) (xy -1.654048 0)
			)
			(stroke
				(width 0)
				(type default)
			)
			(fill yes)
			(layer "F.Fab")
		)
		(fp_text user "PRESS-FIT"
			(at -3.433572 12.943586 90)
			(unlocked yes)
			(layer "F.SilkS")
			(effects
				(font
					(size 0.7874 0.5842)
					(thickness 0.1524)
				)
				(justify left)
			)
		)
		(fp_text user "B"
			(at -2.253742 1.199896 90)
			(unlocked yes)
			(layer "F.SilkS")
			(effects
				(font
					(size 0.7874 0.5842)
					(thickness 0.1524)
				)
			)
		)
		(fp_text user "C"
			(at -2.253742 2.400046 90)
			(unlocked yes)
			(layer "F.SilkS")
			(effects
				(font
					(size 0.7874 0.5842)
					(thickness 0.1524)
				)
			)
		)
		(fp_text user "D"
			(at -2.253742 3.599942 90)
			(unlocked yes)
			(layer "F.SilkS")
			(effects
				(font
					(size 0.7874 0.5842)
					(thickness 0.1524)
				)
			)
		)
		(fp_text user "E"
			(at -2.253742 4.800092 90)
			(unlocked yes)
			(layer "F.SilkS")
			(effects
				(font
					(size 0.7874 0.5842)
					(thickness 0.1524)
				)
			)
		)
		(fp_text user "F"
			(at -2.253742 5.999988 90)
			(unlocked yes)
			(layer "F.SilkS")
			(effects
				(font
					(size 0.7874 0.5842)
					(thickness 0.1524)
				)
			)
		)
		(fp_text user "G"
			(at -2.253742 7.199884 90)
			(unlocked yes)
			(layer "F.SilkS")
			(effects
				(font
					(size 0.7874 0.5842)
					(thickness 0.1524)
				)
			)
		)
		(fp_text user "H"
			(at -2.253742 8.400034 90)
			(unlocked yes)
			(layer "F.SilkS")
			(effects
				(font
					(size 0.7874 0.5842)
					(thickness 0.1524)
				)
			)
		)
		(fp_text user "I"
			(at -2.253742 9.59993 90)
			(unlocked yes)
			(layer "F.SilkS")
			(effects
				(font
					(size 0.7874 0.5842)
					(thickness 0.1524)
				)
			)
		)
		(fp_text user "J"
			(at -2.253742 10.80008 90)
			(unlocked yes)
			(layer "F.SilkS")
			(effects
				(font
					(size 0.7874 0.5842)
					(thickness 0.1524)
				)
			)
		)
		(fp_text user "K"
			(at -2.253742 11.999976 90)
			(unlocked yes)
			(layer "F.SilkS")
			(effects
				(font
					(size 0.7874 0.5842)
					(thickness 0.1524)
				)
			)
		)
		(fp_text user "L"
			(at -2.253742 13.200126 90)
			(unlocked yes)
			(layer "F.SilkS")
			(effects
				(font
					(size 0.7874 0.5842)
					(thickness 0.1524)
				)
			)
		)
		(fp_text user "M"
			(at -2.253742 14.400022 90)
			(unlocked yes)
			(layer "F.SilkS")
			(effects
				(font
					(size 0.7874 0.5842)
					(thickness 0.1524)
				)
			)
		)
		(fp_text user "N"
			(at -2.253742 15.599918 90)
			(unlocked yes)
			(layer "F.SilkS")
			(effects
				(font
					(size 0.7874 0.5842)
					(thickness 0.1524)
				)
			)
		)
		(fp_text user "1"
			(at 0.111252 19.8628 90)
			(unlocked yes)
			(layer "F.SilkS")
			(effects
				(font
					(size 0.7874 0.5842)
					(thickness 0.1524)
				)
			)
		)
		(fp_text user "EDGE OF DAUGHTER CARD"
			(at 2.2479 -0.899668 0)
			(unlocked yes)
			(layer "F.SilkS")
			(effects
				(font
					(size 0.635 0.4064)
					(thickness 0.1524)
				)
				(justify left)
			)
		)
		(fp_text user "2"
			(at 2.975356 19.99361 90)
			(unlocked yes)
			(layer "F.SilkS")
			(effects
				(font
					(size 0.7874 0.5842)
					(thickness 0.1524)
				)
			)
		)
		(fp_text user "3"
			(at 4.06146 20.042378 90)
			(unlocked yes)
			(layer "F.SilkS")
			(effects
				(font
					(size 0.7874 0.5842)
					(thickness 0.1524)
				)
			)
		)
		(fp_text user "4"
			(at 6.11124 19.8628 90)
			(unlocked yes)
			(layer "F.SilkS")
			(effects
				(font
					(size 0.7874 0.5842)
					(thickness 0.1524)
				)
			)
		)
		(fp_text user "5"
			(at 8.887206 20.538186 90)
			(unlocked yes)
			(layer "F.SilkS")
			(effects
				(font
					(size 0.7874 0.5842)
					(thickness 0.1524)
				)
			)
		)
		(fp_text user "6"
			(at 10.111232 19.8628 90)
			(unlocked yes)
			(layer "F.SilkS")
			(effects
				(font
					(size 0.7874 0.5842)
					(thickness 0.1524)
				)
			)
		)
		(fp_text user "7"
			(at 12.111228 19.8628 90)
			(unlocked yes)
			(layer "F.SilkS")
			(effects
				(font
					(size 0.7874 0.5842)
					(thickness 0.1524)
				)
			)
		)
		(fp_text user "8"
			(at 14.876526 20.656296 90)
			(unlocked yes)
			(layer "F.SilkS")
			(effects
				(font
					(size 0.7874 0.5842)
					(thickness 0.1524)
				)
			)
		)
		(fp_text user "PRESS-FIT"
			(at -2.909062 -0.708152 90)
			(unlocked yes)
			(layer "B.SilkS")
			(effects
				(font
					(size 1.905 1.4224)
					(thickness 0.1524)
				)
				(justify left mirror)
			)
		)
		(fp_text user "A"
			(at -1.199134 0 90)
			(unlocked yes)
			(layer "B.SilkS")
			(effects
				(font
					(size 0.7874 0.5842)
					(thickness 0.1524)
				)
				(justify mirror)
			)
		)
		(fp_text user "G"
			(at -1.173734 7.4168 90)
			(unlocked yes)
			(layer "B.SilkS")
			(effects
				(font
					(size 0.7874 0.5842)
					(thickness 0.1524)
				)
				(justify mirror)
			)
		)
		(fp_text user "H"
			(at -1.148334 8.636 90)
			(unlocked yes)
			(layer "B.SilkS")
			(effects
				(font
					(size 0.7874 0.5842)
					(thickness 0.1524)
				)
				(justify mirror)
			)
		)
		(fp_text user "B"
			(at -1.14681 1.326896 90)
			(unlocked yes)
			(layer "B.SilkS")
			(effects
				(font
					(size 0.7874 0.5842)
					(thickness 0.1524)
				)
				(justify mirror)
			)
		)
		(fp_text user "C"
			(at -1.14681 2.527046 90)
			(unlocked yes)
			(layer "B.SilkS")
			(effects
				(font
					(size 0.7874 0.5842)
					(thickness 0.1524)
				)
				(justify mirror)
			)
		)
		(fp_text user "D"
			(at -1.14681 3.726942 90)
			(unlocked yes)
			(layer "B.SilkS")
			(effects
				(font
					(size 0.7874 0.5842)
					(thickness 0.1524)
				)
				(justify mirror)
			)
		)
		(fp_text user "E"
			(at -1.14681 4.927092 90)
			(unlocked yes)
			(layer "B.SilkS")
			(effects
				(font
					(size 0.7874 0.5842)
					(thickness 0.1524)
				)
				(justify mirror)
			)
		)
		(fp_text user "F"
			(at -1.14681 6.126988 90)
			(unlocked yes)
			(layer "B.SilkS")
			(effects
				(font
					(size 0.7874 0.5842)
					(thickness 0.1524)
				)
				(justify mirror)
			)
		)
		(fp_text user "I"
			(at -1.14681 9.72693 90)
			(unlocked yes)
			(layer "B.SilkS")
			(effects
				(font
					(size 0.7874 0.5842)
					(thickness 0.1524)
				)
				(justify mirror)
			)
		)
		(fp_text user "J"
			(at -1.14681 10.92708 90)
			(unlocked yes)
			(layer "B.SilkS")
			(effects
				(font
					(size 0.7874 0.5842)
					(thickness 0.1524)
				)
				(justify mirror)
			)
		)
		(fp_text user "K"
			(at -1.14681 12.126976 90)
			(unlocked yes)
			(layer "B.SilkS")
			(effects
				(font
					(size 0.7874 0.5842)
					(thickness 0.1524)
				)
				(justify mirror)
			)
		)
		(fp_text user "L"
			(at -1.14681 13.327126 90)
			(unlocked yes)
			(layer "B.SilkS")
			(effects
				(font
					(size 0.7874 0.5842)
					(thickness 0.1524)
				)
				(justify mirror)
			)
		)
		(fp_text user "M"
			(at -1.14681 14.527022 90)
			(unlocked yes)
			(layer "B.SilkS")
			(effects
				(font
					(size 0.7874 0.5842)
					(thickness 0.1524)
				)
				(justify mirror)
			)
		)
		(fp_text user "N"
			(at -1.14681 15.726918 90)
			(unlocked yes)
			(layer "B.SilkS")
			(effects
				(font
					(size 0.7874 0.5842)
					(thickness 0.1524)
				)
				(justify mirror)
			)
		)
		(fp_text user "1"
			(at 0.060452 16.764 90)
			(unlocked yes)
			(layer "B.SilkS")
			(effects
				(font
					(size 0.7874 0.5842)
					(thickness 0.1524)
				)
				(justify mirror)
			)
		)
		(fp_text user "2"
			(at 2.060448 16.764 90)
			(unlocked yes)
			(layer "B.SilkS")
			(effects
				(font
					(size 0.7874 0.5842)
					(thickness 0.1524)
				)
				(justify mirror)
			)
		)
		(fp_text user "3"
			(at 4.060444 16.764 90)
			(unlocked yes)
			(layer "B.SilkS")
			(effects
				(font
					(size 0.7874 0.5842)
					(thickness 0.1524)
				)
				(justify mirror)
			)
		)
		(fp_text user "4"
			(at 6.06044 16.764 90)
			(unlocked yes)
			(layer "B.SilkS")
			(effects
				(font
					(size 0.7874 0.5842)
					(thickness 0.1524)
				)
				(justify mirror)
			)
		)
		(fp_text user "5"
			(at 8.060436 16.764 90)
			(unlocked yes)
			(layer "B.SilkS")
			(effects
				(font
					(size 0.7874 0.5842)
					(thickness 0.1524)
				)
				(justify mirror)
			)
		)
		(fp_text user "6"
			(at 10.060432 16.764 90)
			(unlocked yes)
			(layer "B.SilkS")
			(effects
				(font
					(size 0.7874 0.5842)
					(thickness 0.1524)
				)
				(justify mirror)
			)
		)
		(fp_text user "7"
			(at 12.060428 16.764 90)
			(unlocked yes)
			(layer "B.SilkS")
			(effects
				(font
					(size 0.7874 0.5842)
					(thickness 0.1524)
				)
				(justify mirror)
			)
		)
		(fp_text user "8"
			(at 14.060424 16.764 90)
			(unlocked yes)
			(layer "B.SilkS")
			(effects
				(font
					(size 0.7874 0.5842)
					(thickness 0.1524)
				)
				(justify mirror)
			)
		)
		(fp_text user "A"
			(at -1.199134 0 90)
			(unlocked yes)
			(layer "B.Fab")
			(effects
				(font
					(size 0.7874 0.5842)
					(thickness 0.1524)
				)
				(justify mirror)
			)
		)
		(fp_text user "G"
			(at -1.173734 7.4168 90)
			(unlocked yes)
			(layer "B.Fab")
			(effects
				(font
					(size 0.7874 0.5842)
					(thickness 0.1524)
				)
				(justify mirror)
			)
		)
		(fp_text user "H"
			(at -1.148334 8.636 90)
			(unlocked yes)
			(layer "B.Fab")
			(effects
				(font
					(size 0.7874 0.5842)
					(thickness 0.1524)
				)
				(justify mirror)
			)
		)
		(fp_text user "B"
			(at -1.14681 1.326896 90)
			(unlocked yes)
			(layer "B.Fab")
			(effects
				(font
					(size 0.7874 0.5842)
					(thickness 0.1524)
				)
				(justify mirror)
			)
		)
		(fp_text user "C"
			(at -1.14681 2.527046 90)
			(unlocked yes)
			(layer "B.Fab")
			(effects
				(font
					(size 0.7874 0.5842)
					(thickness 0.1524)
				)
				(justify mirror)
			)
		)
		(fp_text user "D"
			(at -1.14681 3.726942 90)
			(unlocked yes)
			(layer "B.Fab")
			(effects
				(font
					(size 0.7874 0.5842)
					(thickness 0.1524)
				)
				(justify mirror)
			)
		)
		(fp_text user "E"
			(at -1.14681 4.927092 90)
			(unlocked yes)
			(layer "B.Fab")
			(effects
				(font
					(size 0.7874 0.5842)
					(thickness 0.1524)
				)
				(justify mirror)
			)
		)
		(fp_text user "F"
			(at -1.14681 6.126988 90)
			(unlocked yes)
			(layer "B.Fab")
			(effects
				(font
					(size 0.7874 0.5842)
					(thickness 0.1524)
				)
				(justify mirror)
			)
		)
		(fp_text user "I"
			(at -1.14681 9.72693 90)
			(unlocked yes)
			(layer "B.Fab")
			(effects
				(font
					(size 0.7874 0.5842)
					(thickness 0.1524)
				)
				(justify mirror)
			)
		)
		(fp_text user "J"
			(at -1.14681 10.92708 90)
			(unlocked yes)
			(layer "B.Fab")
			(effects
				(font
					(size 0.7874 0.5842)
					(thickness 0.1524)
				)
				(justify mirror)
			)
		)
		(fp_text user "K"
			(at -1.14681 12.126976 90)
			(unlocked yes)
			(layer "B.Fab")
			(effects
				(font
					(size 0.7874 0.5842)
					(thickness 0.1524)
				)
				(justify mirror)
			)
		)
		(fp_text user "L"
			(at -1.14681 13.327126 90)
			(unlocked yes)
			(layer "B.Fab")
			(effects
				(font
					(size 0.7874 0.5842)
					(thickness 0.1524)
				)
				(justify mirror)
			)
		)
		(fp_text user "M"
			(at -1.14681 14.527022 90)
			(unlocked yes)
			(layer "B.Fab")
			(effects
				(font
					(size 0.7874 0.5842)
					(thickness 0.1524)
				)
				(justify mirror)
			)
		)
		(fp_text user "N"
			(at -1.14681 15.726918 90)
			(unlocked yes)
			(layer "B.Fab")
			(effects
				(font
					(size 0.7874 0.5842)
					(thickness 0.1524)
				)
				(justify mirror)
			)
		)
		(fp_text user "1"
			(at 0.060452 16.764 90)
			(unlocked yes)
			(layer "B.Fab")
			(effects
				(font
					(size 0.7874 0.5842)
					(thickness 0.1524)
				)
				(justify mirror)
			)
		)
		(fp_text user "2"
			(at 2.060448 16.764 90)
			(unlocked yes)
			(layer "B.Fab")
			(effects
				(font
					(size 0.7874 0.5842)
					(thickness 0.1524)
				)
				(justify mirror)
			)
		)
		(fp_text user "3"
			(at 4.060444 16.764 90)
			(unlocked yes)
			(layer "B.Fab")
			(effects
				(font
					(size 0.7874 0.5842)
					(thickness 0.1524)
				)
				(justify mirror)
			)
		)
		(fp_text user "4"
			(at 6.06044 16.764 90)
			(unlocked yes)
			(layer "B.Fab")
			(effects
				(font
					(size 0.7874 0.5842)
					(thickness 0.1524)
				)
				(justify mirror)
			)
		)
		(fp_text user "5"
			(at 8.060436 16.764 90)
			(unlocked yes)
			(layer "B.Fab")
			(effects
				(font
					(size 0.7874 0.5842)
					(thickness 0.1524)
				)
				(justify mirror)
			)
		)
		(fp_text user "6"
			(at 10.060432 16.764 90)
			(unlocked yes)
			(layer "B.Fab")
			(effects
				(font
					(size 0.7874 0.5842)
					(thickness 0.1524)
				)
				(justify mirror)
			)
		)
		(fp_text user "7"
			(at 12.060428 16.764 90)
			(unlocked yes)
			(layer "B.Fab")
			(effects
				(font
					(size 0.7874 0.5842)
					(thickness 0.1524)
				)
				(justify mirror)
			)
		)
		(fp_text user "8"
			(at 14.060424 16.764 90)
			(unlocked yes)
			(layer "B.Fab")
			(effects
				(font
					(size 0.7874 0.5842)
					(thickness 0.1524)
				)
				(justify mirror)
			)
		)
		(fp_text user "PRESS-FIT"
			(at 17.23771 -0.0762 90)
			(unlocked yes)
			(layer "B.Fab")
			(effects
				(font
					(size 1.905 1.4224)
					(thickness 0.1524)
				)
				(justify left mirror)
			)
		)
		(fp_text user "B"
			(at -2.253742 1.199896 90)
			(unlocked yes)
			(layer "F.Fab")
			(effects
				(font
					(size 0.7874 0.5842)
					(thickness 0.1524)
				)
			)
		)
		(fp_text user "C"
			(at -2.253742 2.400046 90)
			(unlocked yes)
			(layer "F.Fab")
			(effects
				(font
					(size 0.7874 0.5842)
					(thickness 0.1524)
				)
			)
		)
		(fp_text user "D"
			(at -2.253742 3.599942 90)
			(unlocked yes)
			(layer "F.Fab")
			(effects
				(font
					(size 0.7874 0.5842)
					(thickness 0.1524)
				)
			)
		)
		(fp_text user "E"
			(at -2.253742 4.800092 90)
			(unlocked yes)
			(layer "F.Fab")
			(effects
				(font
					(size 0.7874 0.5842)
					(thickness 0.1524)
				)
			)
		)
		(fp_text user "F"
			(at -2.253742 5.999988 90)
			(unlocked yes)
			(layer "F.Fab")
			(effects
				(font
					(size 0.7874 0.5842)
					(thickness 0.1524)
				)
			)
		)
		(fp_text user "G"
			(at -2.253742 7.199884 90)
			(unlocked yes)
			(layer "F.Fab")
			(effects
				(font
					(size 0.7874 0.5842)
					(thickness 0.1524)
				)
			)
		)
		(fp_text user "H"
			(at -2.253742 8.400034 90)
			(unlocked yes)
			(layer "F.Fab")
			(effects
				(font
					(size 0.7874 0.5842)
					(thickness 0.1524)
				)
			)
		)
		(fp_text user "I"
			(at -2.253742 9.59993 90)
			(unlocked yes)
			(layer "F.Fab")
			(effects
				(font
					(size 0.7874 0.5842)
					(thickness 0.1524)
				)
			)
		)
		(fp_text user "J"
			(at -2.253742 10.80008 90)
			(unlocked yes)
			(layer "F.Fab")
			(effects
				(font
					(size 0.7874 0.5842)
					(thickness 0.1524)
				)
			)
		)
		(fp_text user "K"
			(at -2.253742 11.999976 90)
			(unlocked yes)
			(layer "F.Fab")
			(effects
				(font
					(size 0.7874 0.5842)
					(thickness 0.1524)
				)
			)
		)
		(fp_text user "L"
			(at -2.253742 13.200126 90)
			(unlocked yes)
			(layer "F.Fab")
			(effects
				(font
					(size 0.7874 0.5842)
					(thickness 0.1524)
				)
			)
		)
		(fp_text user "M"
			(at -2.253742 14.400022 90)
			(unlocked yes)
			(layer "F.Fab")
			(effects
				(font
					(size 0.7874 0.5842)
					(thickness 0.1524)
				)
			)
		)
		(fp_text user "N"
			(at -2.253742 15.599918 90)
			(unlocked yes)
			(layer "F.Fab")
			(effects
				(font
					(size 0.7874 0.5842)
					(thickness 0.1524)
				)
			)
		)
		(fp_text user "1"
			(at 0.111252 19.8628 90)
			(unlocked yes)
			(layer "F.Fab")
			(effects
				(font
					(size 0.7874 0.5842)
					(thickness 0.1524)
				)
			)
		)
		(fp_text user "2"
			(at 2.111248 19.8628 90)
			(unlocked yes)
			(layer "F.Fab")
			(effects
				(font
					(size 0.7874 0.5842)
					(thickness 0.1524)
				)
			)
		)
		(fp_text user "3"
			(at 4.111244 19.8628 90)
			(unlocked yes)
			(layer "F.Fab")
			(effects
				(font
					(size 0.7874 0.5842)
					(thickness 0.1524)
				)
			)
		)
		(fp_text user "4"
			(at 6.11124 19.8628 90)
			(unlocked yes)
			(layer "F.Fab")
			(effects
				(font
					(size 0.7874 0.5842)
					(thickness 0.1524)
				)
			)
		)
		(fp_text user "5"
			(at 8.111236 19.8628 90)
			(unlocked yes)
			(layer "F.Fab")
			(effects
				(font
					(size 0.7874 0.5842)
					(thickness 0.1524)
				)
			)
		)
		(fp_text user "6"
			(at 10.111232 19.8628 90)
			(unlocked yes)
			(layer "F.Fab")
			(effects
				(font
					(size 0.7874 0.5842)
					(thickness 0.1524)
				)
			)
		)
		(fp_text user "7"
			(at 12.111228 19.8628 90)
			(unlocked yes)
			(layer "F.Fab")
			(effects
				(font
					(size 0.7874 0.5842)
					(thickness 0.1524)
				)
			)
		)
		(fp_text user "8"
			(at 14.111224 19.8628 90)
			(unlocked yes)
			(layer "F.Fab")
			(effects
				(font
					(size 0.7874 0.5842)
					(thickness 0.1524)
				)
			)
		)
		(fp_text user "PRESS-FIT"
			(at 17.240758 16.521684 90)
			(unlocked yes)
			(layer "F.Fab")
			(effects
				(font
					(size 1.905 1.4224)
					(thickness 0.1524)
				)
				(justify left)
			)
		)
		(pad "A1" thru_hole rect
			(at 0 0 180)
			(size 0.766318 0.766318)
			(drill 0.359918)
			(layers "*.Cu" "*.Mask")
			(remove_unused_layers no)
			(net "GPU_3V3IO_RSVD3_FFU")
			(clearance 0.0508)
			(thermal_gap 0.0508)
			(padstack
				(mode front_inner_back)
				(layer "Inner"
					(shape circle)
					(size 0.766318 0.766318)
					(clearance 0.0508)
				)
				(layer "B.Cu"
					(shape rect)
					(size 0.766318 0.766318)
					(clearance 0.0508)
				)
			)
		)
		(pad "A2" thru_hole circle
			(at 1.999996 0.199898 180)
			(size 0.906272 0.906272)
			(drill 0.499872)
			(layers "*.Cu" "*.Mask")
			(remove_unused_layers no)
			(net "GND")
			(clearance 0.0508)
			(thermal_gap 0.0508)
		)
		(pad "A3" thru_hole circle
			(at 3.999992 0 180)
			(size 0.766318 0.766318)
			(drill 0.359918)
			(layers "*.Cu" "*.Mask")
			(remove_unused_layers no)
			(net "PRSNT_CABLE_GPU_A2_N")
			(clearance 0.0508)
			(thermal_gap 0.0508)
		)
		(pad "A4" thru_hole circle
			(at 5.999988 0.199898 180)
			(size 0.906272 0.906272)
			(drill 0.499872)
			(layers "*.Cu" "*.Mask")
			(remove_unused_layers no)
			(net "GND")
			(clearance 0.0508)
			(thermal_gap 0.0508)
		)
		(pad "A5" thru_hole circle
			(at 7.999984 0 180)
			(size 0.766318 0.766318)
			(drill 0.359918)
			(layers "*.Cu" "*.Mask")
			(remove_unused_layers no)
			(net "GPU_3V3IO_RSVD5_FFU")
			(clearance 0.0508)
			(thermal_gap 0.0508)
		)
		(pad "A6" thru_hole circle
			(at 9.99998 0.199898 180)
			(size 0.906272 0.906272)
			(drill 0.499872)
			(layers "*.Cu" "*.Mask")
			(remove_unused_layers no)
			(net "GND")
			(clearance 0.0508)
			(thermal_gap 0.0508)
		)
		(pad "A7" thru_hole circle
			(at 11.999976 0 180)
			(size 0.766318 0.766318)
			(drill 0.359918)
			(layers "*.Cu" "*.Mask")
			(remove_unused_layers no)
			(net "GPU_FPGA_OVERT_N")
			(clearance 0.0508)
			(thermal_gap 0.0508)
		)
		(pad "A8" thru_hole circle
			(at 13.999972 0.199898 180)
			(size 0.906272 0.906272)
			(drill 0.499872)
			(layers "*.Cu" "*.Mask")
			(remove_unused_layers no)
			(net "GND")
			(clearance 0.0508)
			(thermal_gap 0.0508)
		)
		(pad "B1" thru_hole circle
			(at 0 1.199896 180)
			(size 0.906272 0.906272)
			(drill 0.499872)
			(layers "*.Cu" "*.Mask")
			(remove_unused_layers no)
			(net "GND")
			(clearance 0.0508)
			(thermal_gap 0.0508)
		)
		(pad "B3" thru_hole circle
			(at 3.999992 1.199896 180)
			(size 0.906272 0.906272)
			(drill 0.499872)
			(layers "*.Cu" "*.Mask")
			(remove_unused_layers no)
			(net "GND")
			(clearance 0.0508)
			(thermal_gap 0.0508)
		)
		(pad "B5" thru_hole circle
			(at 7.999984 1.199896 180)
			(size 0.906272 0.906272)
			(drill 0.499872)
			(layers "*.Cu" "*.Mask")
			(remove_unused_layers no)
			(net "GND")
			(clearance 0.0508)
			(thermal_gap 0.0508)
		)
		(pad "B7" thru_hole circle
			(at 11.999976 1.199896 180)
			(size 0.906272 0.906272)
			(drill 0.499872)
			(layers "*.Cu" "*.Mask")
			(remove_unused_layers no)
			(net "GND")
			(clearance 0.0508)
			(thermal_gap 0.0508)
		)
		(pad "D2" thru_hole circle
			(at 1.999996 3.800094 180)
			(size 0.906272 0.906272)
			(drill 0.499872)
			(layers "*.Cu" "*.Mask")
			(remove_unused_layers no)
			(net "GND")
			(clearance 0.0508)
			(thermal_gap 0.0508)
		)
		(pad "D4" thru_hole circle
			(at 5.999988 3.800094 180)
			(size 0.906272 0.906272)
			(drill 0.499872)
			(layers "*.Cu" "*.Mask")
			(remove_unused_layers no)
			(net "GND")
			(clearance 0.0508)
			(thermal_gap 0.0508)
		)
		(pad "D6" thru_hole circle
			(at 9.99998 3.800094 180)
			(size 0.906272 0.906272)
			(drill 0.499872)
			(layers "*.Cu" "*.Mask")
			(remove_unused_layers no)
			(net "GND")
			(clearance 0.0508)
			(thermal_gap 0.0508)
		)
		(pad "D8" thru_hole circle
			(at 13.999972 3.800094 180)
			(size 0.906272 0.906272)
			(drill 0.499872)
			(layers "*.Cu" "*.Mask")
			(remove_unused_layers no)
			(net "GND")
			(clearance 0.0508)
			(thermal_gap 0.0508)
		)
		(pad "E1" thru_hole circle
			(at 0 4.800092 180)
			(size 0.906272 0.906272)
			(drill 0.499872)
			(layers "*.Cu" "*.Mask")
			(remove_unused_layers no)
			(net "GND")
			(clearance 0.0508)
			(thermal_gap 0.0508)
		)
		(pad "E3" thru_hole circle
			(at 3.999992 4.800092 180)
			(size 0.906272 0.906272)
			(drill 0.499872)
			(layers "*.Cu" "*.Mask")
			(remove_unused_layers no)
			(net "GND")
			(clearance 0.0508)
			(thermal_gap 0.0508)
		)
		(pad "E5" thru_hole circle
			(at 7.999984 4.800092 180)
			(size 0.906272 0.906272)
			(drill 0.499872)
			(layers "*.Cu" "*.Mask")
			(remove_unused_layers no)
			(net "GND")
			(clearance 0.0508)
			(thermal_gap 0.0508)
		)
		(pad "E7" thru_hole circle
			(at 11.999976 4.800092 180)
			(size 0.906272 0.906272)
			(drill 0.499872)
			(layers "*.Cu" "*.Mask")
			(remove_unused_layers no)
			(net "GND")
			(clearance 0.0508)
			(thermal_gap 0.0508)
		)
		(pad "G2" thru_hole circle
			(at 1.999996 7.400036 180)
			(size 0.906272 0.906272)
			(drill 0.499872)
			(layers "*.Cu" "*.Mask")
			(remove_unused_layers no)
			(net "GND")
			(clearance 0.0508)
			(thermal_gap 0.0508)
		)
		(pad "G4" thru_hole circle
			(at 5.999988 7.400036 180)
			(size 0.906272 0.906272)
			(drill 0.499872)
			(layers "*.Cu" "*.Mask")
			(remove_unused_layers no)
			(net "GND")
			(clearance 0.0508)
			(thermal_gap 0.0508)
		)
		(pad "G6" thru_hole circle
			(at 9.99998 7.400036 180)
			(size 0.906272 0.906272)
			(drill 0.499872)
			(layers "*.Cu" "*.Mask")
			(remove_unused_layers no)
			(net "GND")
			(clearance 0.0508)
			(thermal_gap 0.0508)
		)
		(pad "G8" thru_hole circle
			(at 13.999972 7.400036 180)
			(size 0.906272 0.906272)
			(drill 0.499872)
			(layers "*.Cu" "*.Mask")
			(remove_unused_layers no)
			(net "GND")
			(clearance 0.0508)
			(thermal_gap 0.0508)
		)
		(pad "H1" thru_hole circle
			(at 0 8.400034 180)
			(size 0.906272 0.906272)
			(drill 0.499872)
			(layers "*.Cu" "*.Mask")
			(remove_unused_layers no)
			(net "GND")
			(clearance 0.0508)
			(thermal_gap 0.0508)
		)
		(pad "H3" thru_hole circle
			(at 3.999992 8.400034 180)
			(size 0.906272 0.906272)
			(drill 0.499872)
			(layers "*.Cu" "*.Mask")
			(remove_unused_layers no)
			(net "GND")
			(clearance 0.0508)
			(thermal_gap 0.0508)
		)
		(pad "H5" thru_hole circle
			(at 7.999984 8.400034 180)
			(size 0.906272 0.906272)
			(drill 0.499872)
			(layers "*.Cu" "*.Mask")
			(remove_unused_layers no)
			(net "GND")
			(clearance 0.0508)
			(thermal_gap 0.0508)
		)
		(pad "H7" thru_hole circle
			(at 11.999976 8.400034 180)
			(size 0.906272 0.906272)
			(drill 0.499872)
			(layers "*.Cu" "*.Mask")
			(remove_unused_layers no)
			(net "GND")
			(clearance 0.0508)
			(thermal_gap 0.0508)
		)
		(pad "J2" thru_hole circle
			(at 1.999996 10.999978 180)
			(size 0.906272 0.906272)
			(drill 0.499872)
			(layers "*.Cu" "*.Mask")
			(remove_unused_layers no)
			(net "GND")
			(clearance 0.0508)
			(thermal_gap 0.0508)
		)
		(pad "J4" thru_hole circle
			(at 5.999988 10.999978 180)
			(size 0.906272 0.906272)
			(drill 0.499872)
			(layers "*.Cu" "*.Mask")
			(remove_unused_layers no)
			(net "GND")
			(clearance 0.0508)
			(thermal_gap 0.0508)
		)
		(pad "J6" thru_hole circle
			(at 9.99998 10.999978 180)
			(size 0.906272 0.906272)
			(drill 0.499872)
			(layers "*.Cu" "*.Mask")
			(remove_unused_layers no)
			(net "GND")
			(clearance 0.0508)
			(thermal_gap 0.0508)
		)
		(pad "J8" thru_hole circle
			(at 13.999972 10.999978 180)
			(size 0.906272 0.906272)
			(drill 0.499872)
			(layers "*.Cu" "*.Mask")
			(remove_unused_layers no)
			(net "GND")
			(clearance 0.0508)
			(thermal_gap 0.0508)
		)
		(pad "K1" thru_hole circle
			(at 0 11.999976 180)
			(size 0.906272 0.906272)
			(drill 0.499872)
			(layers "*.Cu" "*.Mask")
			(remove_unused_layers no)
			(net "GND")
			(clearance 0.0508)
			(thermal_gap 0.0508)
		)
		(pad "K3" thru_hole circle
			(at 3.999992 11.999976 180)
			(size 0.906272 0.906272)
			(drill 0.499872)
			(layers "*.Cu" "*.Mask")
			(remove_unused_layers no)
			(net "GND")
			(clearance 0.0508)
			(thermal_gap 0.0508)
		)
		(pad "K5" thru_hole circle
			(at 7.999984 11.999976 180)
			(size 0.906272 0.906272)
			(drill 0.499872)
			(layers "*.Cu" "*.Mask")
			(remove_unused_layers no)
			(net "GND")
			(clearance 0.0508)
			(thermal_gap 0.0508)
		)
		(pad "K7" thru_hole circle
			(at 11.999976 11.999976 180)
			(size 0.906272 0.906272)
			(drill 0.499872)
			(layers "*.Cu" "*.Mask")
			(remove_unused_layers no)
			(net "GND")
			(clearance 0.0508)
			(thermal_gap 0.0508)
		)
		(pad "M2" thru_hole circle
			(at 1.999996 14.59992 180)
			(size 0.906272 0.906272)
			(drill 0.499872)
			(layers "*.Cu" "*.Mask")
			(remove_unused_layers no)
			(net "GND")
			(clearance 0.0508)
			(thermal_gap 0.0508)
		)
		(pad "M4" thru_hole circle
			(at 5.999988 14.59992 180)
			(size 0.906272 0.906272)
			(drill 0.499872)
			(layers "*.Cu" "*.Mask")
			(remove_unused_layers no)
			(net "GND")
			(clearance 0.0508)
			(thermal_gap 0.0508)
		)
		(pad "M6" thru_hole circle
			(at 9.99998 14.59992 180)
			(size 0.906272 0.906272)
			(drill 0.499872)
			(layers "*.Cu" "*.Mask")
			(remove_unused_layers no)
			(net "GND")
			(clearance 0.0508)
			(thermal_gap 0.0508)
		)
		(pad "M8" thru_hole circle
			(at 13.999972 14.59992 180)
			(size 0.906272 0.906272)
			(drill 0.499872)
			(layers "*.Cu" "*.Mask")
			(remove_unused_layers no)
			(net "GND")
			(clearance 0.0508)
			(thermal_gap 0.0508)
		)
		(pad "N1" thru_hole circle
			(at 0 15.599918 180)
			(size 0.906272 0.906272)
			(drill 0.499872)
			(layers "*.Cu" "*.Mask")
			(remove_unused_layers no)
			(net "GND")
			(clearance 0.0508)
			(thermal_gap 0.0508)
		)
		(pad "N2" thru_hole circle
			(at 1.999996 15.80007 180)
			(size 0.766318 0.766318)
			(drill 0.359918)
			(layers "*.Cu" "*.Mask")
			(remove_unused_layers no)
			(net "NC_J108_N2")
			(clearance 0.0508)
			(thermal_gap 0.0508)
		)
		(pad "N3" thru_hole circle
			(at 3.999992 15.599918 180)
			(size 0.906272 0.906272)
			(drill 0.499872)
			(layers "*.Cu" "*.Mask")
			(remove_unused_layers no)
			(net "GND")
			(clearance 0.0508)
			(thermal_gap 0.0508)
		)
		(pad "N4" thru_hole circle
			(at 5.999988 15.80007 180)
			(size 0.766318 0.766318)
			(drill 0.359918)
			(layers "*.Cu" "*.Mask")
			(remove_unused_layers no)
			(net "NC_J108_N4")
			(clearance 0.0508)
			(thermal_gap 0.0508)
		)
		(pad "N5" thru_hole circle
			(at 7.999984 15.599918 180)
			(size 0.906272 0.906272)
			(drill 0.499872)
			(layers "*.Cu" "*.Mask")
			(remove_unused_layers no)
			(net "GND")
			(clearance 0.0508)
			(thermal_gap 0.0508)
		)
		(pad "N6" thru_hole circle
			(at 9.99998 15.80007 180)
			(size 0.766318 0.766318)
			(drill 0.359918)
			(layers "*.Cu" "*.Mask")
			(remove_unused_layers no)
			(net "NC_J108_N6")
			(clearance 0.0508)
			(thermal_gap 0.0508)
		)
		(pad "N7" thru_hole circle
			(at 11.999976 15.599918 180)
			(size 0.906272 0.906272)
			(drill 0.499872)
			(layers "*.Cu" "*.Mask")
			(remove_unused_layers no)
			(net "GND")
			(clearance 0.0508)
			(thermal_gap 0.0508)
		)
		(pad "N8" thru_hole circle
			(at 13.999972 15.80007 180)
			(size 0.766318 0.766318)
			(drill 0.359918)
			(layers "*.Cu" "*.Mask")
			(remove_unused_layers no)
			(net "PRSNT_CABLE_GPU_A3_N")
			(clearance 0.0508)
			(thermal_gap 0.0508)
		)
		(zone
			(layer "B.Cu")
			(hatch none 0.5)
			(connect_pads
				(clearance 0)
			)
			(min_thickness 0.25)
			(keepout
				(tracks allowed)
				(vias not_allowed)
				(pads allowed)
				(copperpour not_allowed)
				(footprints allowed)
			)
			(placement
				(enabled no)
				(sheetname "")
			)
			(fill
				(thermal_gap 0.5)
				(thermal_bridge_width 0.5)
				(island_removal_mode 0)
			)
			(polygon
				(pts
					(xy 314.141612 -424.246548) (xy 329.165712 -424.246548) (xy 329.165712 -440.934348) (xy 314.141612 -440.934348)
				)
			)
		)
	)
	(footprint ""
		(layer "F.Cu")
		(at 254.592836 -117.51945)
		(property "Reference" "R3728"
			(at 0 0 0)
			(layer "F.SilkS")
			(hide yes)
			(effects
				(font
					(size 1.27 1.27)
				)
			)
		)
		(property "Value" ""
			(at 0 0 0)
			(layer "F.Fab")
			(effects
				(font
					(size 1.27 1.27)
				)
			)
		)
		(duplicate_pad_numbers_are_jumpers no)
		(fp_line
			(start -0.7874 -0.4064)
			(end 0.7874 -0.4064)
			(stroke
				(width 0.1524)
				(type default)
			)
			(layer "F.SilkS")
		)
		(fp_line
			(start -0.7874 0.4064)
			(end -0.7874 -0.4064)
			(stroke
				(width 0.1524)
				(type default)
			)
			(layer "F.SilkS")
		)
		(fp_line
			(start 0.7874 -0.4064)
			(end 0.7874 0.4064)
			(stroke
				(width 0.1524)
				(type default)
			)
			(layer "F.SilkS")
		)
		(fp_line
			(start 0.7874 0.4064)
			(end -0.7874 0.4064)
			(stroke
				(width 0.1524)
				(type default)
			)
			(layer "F.SilkS")
		)
		(fp_line
			(start -0.67945 -0.305054)
			(end -0.12065 -0.305054)
			(stroke
				(width 0.1)
				(type default)
			)
			(layer "F.Fab")
		)
		(fp_line
			(start -0.67945 0.3048)
			(end -0.67945 -0.305054)
			(stroke
				(width 0.1)
				(type default)
			)
			(layer "F.Fab")
		)
		(fp_line
			(start -0.12065 -0.305054)
			(end -0.12065 -0.2794)
			(stroke
				(width 0.1)
				(type default)
			)
			(layer "F.Fab")
		)
		(fp_line
			(start -0.12065 -0.2794)
			(end 0.12065 -0.2794)
			(stroke
				(width 0.1)
				(type default)
			)
			(layer "F.Fab")
		)
		(fp_line
			(start -0.12065 0.2794)
			(end -0.12065 0.3048)
			(stroke
				(width 0.1)
				(type default)
			)
			(layer "F.Fab")
		)
		(fp_line
			(start -0.12065 0.3048)
			(end -0.67945 0.3048)
			(stroke
				(width 0.1)
				(type default)
			)
			(layer "F.Fab")
		)
		(fp_line
			(start 0.120396 0.2794)
			(end -0.12065 0.2794)
			(stroke
				(width 0.1)
				(type default)
			)
			(layer "F.Fab")
		)
		(fp_line
			(start 0.120396 0.3048)
			(end 0.120396 0.2794)
			(stroke
				(width 0.1)
				(type default)
			)
			(layer "F.Fab")
		)
		(fp_line
			(start 0.12065 -0.3048)
			(end 0.67945 -0.3048)
			(stroke
				(width 0.1)
				(type default)
			)
			(layer "F.Fab")
		)
		(fp_line
			(start 0.12065 -0.2794)
			(end 0.12065 -0.3048)
			(stroke
				(width 0.1)
				(type default)
			)
			(layer "F.Fab")
		)
		(fp_line
			(start 0.67945 -0.3048)
			(end 0.67945 0.3048)
			(stroke
				(width 0.1)
				(type default)
			)
			(layer "F.Fab")
		)
		(fp_line
			(start 0.67945 0.3048)
			(end 0.120396 0.3048)
			(stroke
				(width 0.1)
				(type default)
			)
			(layer "F.Fab")
		)
		(pad "1" smd circle
			(at -0.40005 0)
			(size 0 0)
			(layers "F.Cu" "F.Mask" "F.Paste")
			(net "P3V3_AUX")
		)
		(pad "2" smd circle
			(at 0.40005 0)
			(size 0 0)
			(layers "F.Cu" "F.Mask" "F.Paste")
			(net "SMB_LM75_1_3V3AUX_SDA")
		)
	)
	(footprint ""
		(layer "F.Cu")
		(at 455.115676 -401.709128 90)
		(property "Reference" "PR6562"
			(at 0 0 90)
			(layer "F.SilkS")
			(hide yes)
			(effects
				(font
					(size 1.27 1.27)
				)
			)
		)
		(property "Value" ""
			(at 0 0 90)
			(layer "F.Fab")
			(effects
				(font
					(size 1.27 1.27)
				)
			)
		)
		(duplicate_pad_numbers_are_jumpers no)
		(fp_line
			(start 0.7874 -0.4064)
			(end 0.7874 0.4064)
			(stroke
				(width 0.1524)
				(type default)
			)
			(layer "F.SilkS")
		)
		(fp_line
			(start -0.7874 -0.4064)
			(end 0.7874 -0.4064)
			(stroke
				(width 0.1524)
				(type default)
			)
			(layer "F.SilkS")
		)
		(fp_line
			(start 0.7874 0.4064)
			(end -0.7874 0.4064)
			(stroke
				(width 0.1524)
				(type default)
			)
			(layer "F.SilkS")
		)
		(fp_line
			(start -0.7874 0.4064)
			(end -0.7874 -0.4064)
			(stroke
				(width 0.1524)
				(type default)
			)
			(layer "F.SilkS")
		)
		(fp_line
			(start -0.12065 -0.305054)
			(end -0.12065 -0.2794)
			(stroke
				(width 0.1)
				(type default)
			)
			(layer "F.Fab")
		)
		(fp_line
			(start -0.67945 -0.305054)
			(end -0.12065 -0.305054)
			(stroke
				(width 0.1)
				(type default)
			)
			(layer "F.Fab")
		)
		(fp_line
			(start 0.67945 -0.3048)
			(end 0.67945 0.3048)
			(stroke
				(width 0.1)
				(type default)
			)
			(layer "F.Fab")
		)
		(fp_line
			(start 0.12065 -0.3048)
			(end 0.67945 -0.3048)
			(stroke
				(width 0.1)
				(type default)
			)
			(layer "F.Fab")
		)
		(fp_line
			(start 0.12065 -0.2794)
			(end 0.12065 -0.3048)
			(stroke
				(width 0.1)
				(type default)
			)
			(layer "F.Fab")
		)
		(fp_line
			(start -0.12065 -0.2794)
			(end 0.12065 -0.2794)
			(stroke
				(width 0.1)
				(type default)
			)
			(layer "F.Fab")
		)
		(fp_line
			(start 0.120396 0.2794)
			(end -0.12065 0.2794)
			(stroke
				(width 0.1)
				(type default)
			)
			(layer "F.Fab")
		)
		(fp_line
			(start -0.12065 0.2794)
			(end -0.12065 0.3048)
			(stroke
				(width 0.1)
				(type default)
			)
			(layer "F.Fab")
		)
		(fp_line
			(start 0.67945 0.3048)
			(end 0.120396 0.3048)
			(stroke
				(width 0.1)
				(type default)
			)
			(layer "F.Fab")
		)
		(fp_line
			(start 0.120396 0.3048)
			(end 0.120396 0.2794)
			(stroke
				(width 0.1)
				(type default)
			)
			(layer "F.Fab")
		)
		(fp_line
			(start -0.12065 0.3048)
			(end -0.67945 0.3048)
			(stroke
				(width 0.1)
				(type default)
			)
			(layer "F.Fab")
		)
		(fp_line
			(start -0.67945 0.3048)
			(end -0.67945 -0.305054)
			(stroke
				(width 0.1)
				(type default)
			)
			(layer "F.Fab")
		)
		(pad "1" smd circle
			(at -0.40005 0 90)
			(size 0 0)
			(layers "F.Cu" "F.Mask" "F.Paste")
			(net "SW_P0V9_RETIMER_CPU0_BOOT2")
		)
		(pad "2" smd circle
			(at 0.40005 0 90)
			(size 0 0)
			(layers "F.Cu" "F.Mask" "F.Paste")
			(net "SW_P0V9_RETIMER_CPU0_BOOT2_RC")
		)
	)
	(footprint ""
		(layer "F.Cu")
		(at 318.262 -364.617 90)
		(property "Reference" "PR76"
			(at 0 0 90)
			(layer "F.SilkS")
			(hide yes)
			(effects
				(font
					(size 1.27 1.27)
				)
			)
		)
		(property "Value" ""
			(at 0 0 90)
			(layer "F.Fab")
			(effects
				(font
					(size 1.27 1.27)
				)
			)
		)
		(duplicate_pad_numbers_are_jumpers no)
		(fp_line
			(start 0.7874 -0.4064)
			(end 0.7874 0.4064)
			(stroke
				(width 0.1524)
				(type default)
			)
			(layer "F.SilkS")
		)
		(fp_line
			(start -0.7874 -0.4064)
			(end 0.7874 -0.4064)
			(stroke
				(width 0.1524)
				(type default)
			)
			(layer "F.SilkS")
		)
		(fp_line
			(start 0.7874 0.4064)
			(end -0.7874 0.4064)
			(stroke
				(width 0.1524)
				(type default)
			)
			(layer "F.SilkS")
		)
		(fp_line
			(start -0.7874 0.4064)
			(end -0.7874 -0.4064)
			(stroke
				(width 0.1524)
				(type default)
			)
			(layer "F.SilkS")
		)
		(fp_line
			(start -0.12065 -0.305054)
			(end -0.12065 -0.2794)
			(stroke
				(width 0.1)
				(type default)
			)
			(layer "F.Fab")
		)
		(fp_line
			(start -0.67945 -0.305054)
			(end -0.12065 -0.305054)
			(stroke
				(width 0.1)
				(type default)
			)
			(layer "F.Fab")
		)
		(fp_line
			(start 0.67945 -0.3048)
			(end 0.67945 0.3048)
			(stroke
				(width 0.1)
				(type default)
			)
			(layer "F.Fab")
		)
		(fp_line
			(start 0.12065 -0.3048)
			(end 0.67945 -0.3048)
			(stroke
				(width 0.1)
				(type default)
			)
			(layer "F.Fab")
		)
		(fp_line
			(start 0.12065 -0.2794)
			(end 0.12065 -0.3048)
			(stroke
				(width 0.1)
				(type default)
			)
			(layer "F.Fab")
		)
		(fp_line
			(start -0.12065 -0.2794)
			(end 0.12065 -0.2794)
			(stroke
				(width 0.1)
				(type default)
			)
			(layer "F.Fab")
		)
		(fp_line
			(start 0.120396 0.2794)
			(end -0.12065 0.2794)
			(stroke
				(width 0.1)
				(type default)
			)
			(layer "F.Fab")
		)
		(fp_line
			(start -0.12065 0.2794)
			(end -0.12065 0.3048)
			(stroke
				(width 0.1)
				(type default)
			)
			(layer "F.Fab")
		)
		(fp_line
			(start 0.67945 0.3048)
			(end 0.120396 0.3048)
			(stroke
				(width 0.1)
				(type default)
			)
			(layer "F.Fab")
		)
		(fp_line
			(start 0.120396 0.3048)
			(end 0.120396 0.2794)
			(stroke
				(width 0.1)
				(type default)
			)
			(layer "F.Fab")
		)
		(fp_line
			(start -0.12065 0.3048)
			(end -0.67945 0.3048)
			(stroke
				(width 0.1)
				(type default)
			)
			(layer "F.Fab")
		)
		(fp_line
			(start -0.67945 0.3048)
			(end -0.67945 -0.305054)
			(stroke
				(width 0.1)
				(type default)
			)
			(layer "F.Fab")
		)
		(pad "1" smd circle
			(at -0.40005 0 90)
			(size 0 0)
			(layers "F.Cu" "F.Mask" "F.Paste")
			(net "PVDDCR_CPU1_P0_VCC")
		)
		(pad "2" smd circle
			(at 0.40005 0 90)
			(size 0 0)
			(layers "F.Cu" "F.Mask" "F.Paste")
			(net "P3V3_AUX")
		)
	)
	(footprint ""
		(layer "F.Cu")
		(at 34.325306 19.444716 -90)
		(property "Reference" "U26_BP"
			(at 0 0 270)
			(layer "F.SilkS")
			(hide yes)
			(effects
				(font
					(size 1.27 1.27)
				)
			)
		)
		(property "Value" ""
			(at 0 0 270)
			(layer "F.Fab")
			(effects
				(font
					(size 1.27 1.27)
				)
			)
		)
		(duplicate_pad_numbers_are_jumpers no)
		(pad "1" smd circle
			(at 0 0 270)
			(size 0.762 0.762)
			(layers "F.Cu" "F.Mask" "F.Paste")
			(net "Net_10787")
		)
	)
	(footprint ""
		(layer "F.Cu")
		(at 109.165136 -123.604274 -90)
		(property "Reference" "Q27"
			(at -0.13208 1.599438 90)
			(unlocked yes)
			(layer "F.SilkS")
			(effects
				(font
					(size 0.7874 0.5842)
					(thickness 0.1524)
				)
			)
		)
		(property "Value" ""
			(at 0 0 270)
			(layer "F.Fab")
			(effects
				(font
					(size 1.27 1.27)
				)
			)
		)
		(duplicate_pad_numbers_are_jumpers no)
		(fp_line
			(start -1.7018 1.100074)
			(end -1.7018 -1.100074)
			(stroke
				(width 0.1524)
				(type default)
			)
			(layer "F.SilkS")
		)
		(fp_line
			(start 1.7018 1.100074)
			(end -1.7018 1.100074)
			(stroke
				(width 0.1524)
				(type default)
			)
			(layer "F.SilkS")
		)
		(fp_line
			(start -1.7018 -1.100074)
			(end 1.7018 -1.100074)
			(stroke
				(width 0.1524)
				(type default)
			)
			(layer "F.SilkS")
		)
		(fp_line
			(start 1.7018 -1.100074)
			(end 1.7018 1.100074)
			(stroke
				(width 0.1524)
				(type default)
			)
			(layer "F.SilkS")
		)
		(fp_poly
			(pts
				(xy -2.313686 -0.705866) (xy -2.867406 -0.409194) (xy -2.867406 -1.034034)
			)
			(stroke
				(width 0)
				(type default)
			)
			(fill yes)
			(layer "F.SilkS")
		)
		(fp_line
			(start -0.670052 1.100074)
			(end -0.670052 0.8001)
			(stroke
				(width 0.1)
				(type default)
			)
			(layer "F.Fab")
		)
		(fp_line
			(start 0.670052 1.100074)
			(end -0.670052 1.100074)
			(stroke
				(width 0.1)
				(type default)
			)
			(layer "F.Fab")
		)
		(fp_line
			(start -1.100074 0.8001)
			(end -1.100074 -0.8001)
			(stroke
				(width 0.1)
				(type default)
			)
			(layer "F.Fab")
		)
		(fp_line
			(start -0.670052 0.8001)
			(end -1.100074 0.8001)
			(stroke
				(width 0.1)
				(type default)
			)
			(layer "F.Fab")
		)
		(fp_line
			(start -0.670052 0.8001)
			(end -0.670052 -0.8001)
			(stroke
				(width 0.1)
				(type default)
			)
			(layer "F.Fab")
		)
		(fp_line
			(start 0.670052 0.8001)
			(end 0.670052 1.100074)
			(stroke
				(width 0.1)
				(type default)
			)
			(layer "F.Fab")
		)
		(fp_line
			(start 1.100074 0.8001)
			(end 0.670052 0.8001)
			(stroke
				(width 0.1)
				(type default)
			)
			(layer "F.Fab")
		)
		(fp_line
			(start -1.100074 -0.8001)
			(end -0.670052 -0.8001)
			(stroke
				(width 0.1)
				(type default)
			)
			(layer "F.Fab")
		)
		(fp_line
			(start -0.670052 -0.8001)
			(end -0.670052 -1.100074)
			(stroke
				(width 0.1)
				(type default)
			)
			(layer "F.Fab")
		)
		(fp_line
			(start 0.670052 -0.8001)
			(end 0.670052 0.8001)
			(stroke
				(width 0.1)
				(type default)
			)
			(layer "F.Fab")
		)
		(fp_line
			(start 0.670052 -0.8001)
			(end 1.100074 -0.8001)
			(stroke
				(width 0.1)
				(type default)
			)
			(layer "F.Fab")
		)
		(fp_line
			(start 1.100074 -0.8001)
			(end 1.100074 0.8001)
			(stroke
				(width 0.1)
				(type default)
			)
			(layer "F.Fab")
		)
		(fp_line
			(start -0.670052 -1.100074)
			(end 0.670052 -1.100074)
			(stroke
				(width 0.1)
				(type default)
			)
			(layer "F.Fab")
		)
		(fp_line
			(start 0.670052 -1.100074)
			(end 0.670052 -0.8001)
			(stroke
				(width 0.1)
				(type default)
			)
			(layer "F.Fab")
		)
		(fp_poly
			(pts
				(xy -2.33172 -0.338328) (xy -2.33172 -0.963168) (xy -1.778 -0.635)
			)
			(stroke
				(width 0)
				(type default)
			)
			(fill yes)
			(layer "F.Fab")
		)
		(pad "1" smd rect
			(at -0.937514 -0.649986)
			(size 0.3048 1.2446)
			(layers "F.Cu" "F.Mask" "F.Paste")
			(net "GND")
		)
		(pad "2" smd rect
			(at -0.937514 0)
			(size 0.3048 1.2446)
			(layers "F.Cu" "F.Mask" "F.Paste")
			(net "PWRGD_P3V3_EN")
		)
		(pad "3" smd rect
			(at -0.937514 0.649986)
			(size 0.3048 1.2446)
			(layers "F.Cu" "F.Mask" "F.Paste")
			(net "PWRGD_P3V3_R1")
		)
		(pad "4" smd rect
			(at 0.937514 0.649986)
			(size 0.3048 1.2446)
			(layers "F.Cu" "F.Mask" "F.Paste")
			(net "GND")
		)
		(pad "5" smd rect
			(at 0.937514 0)
			(size 0.3048 1.2446)
			(layers "F.Cu" "F.Mask" "F.Paste")
			(net "PWRGD_P3V3_EN_N")
		)
		(pad "6" smd rect
			(at 0.937514 -0.649986)
			(size 0.3048 1.2446)
			(layers "F.Cu" "F.Mask" "F.Paste")
			(net "PWRGD_P3V3_EN_N")
		)
	)
	(footprint ""
		(layer "F.Cu")
		(at 123.871736 -59.182)
		(property "Reference" "R1745"
			(at 0 0 0)
			(layer "F.SilkS")
			(hide yes)
			(effects
				(font
					(size 1.27 1.27)
				)
			)
		)
		(property "Value" ""
			(at 0 0 0)
			(layer "F.Fab")
			(effects
				(font
					(size 1.27 1.27)
				)
			)
		)
		(duplicate_pad_numbers_are_jumpers no)
		(fp_line
			(start -0.7874 -0.4064)
			(end 0.7874 -0.4064)
			(stroke
				(width 0.1524)
				(type default)
			)
			(layer "F.SilkS")
		)
		(fp_line
			(start -0.7874 0.4064)
			(end -0.7874 -0.4064)
			(stroke
				(width 0.1524)
				(type default)
			)
			(layer "F.SilkS")
		)
		(fp_line
			(start 0.7874 -0.4064)
			(end 0.7874 0.4064)
			(stroke
				(width 0.1524)
				(type default)
			)
			(layer "F.SilkS")
		)
		(fp_line
			(start 0.7874 0.4064)
			(end -0.7874 0.4064)
			(stroke
				(width 0.1524)
				(type default)
			)
			(layer "F.SilkS")
		)
		(fp_line
			(start -0.67945 -0.305054)
			(end -0.12065 -0.305054)
			(stroke
				(width 0.1)
				(type default)
			)
			(layer "F.Fab")
		)
		(fp_line
			(start -0.67945 0.3048)
			(end -0.67945 -0.305054)
			(stroke
				(width 0.1)
				(type default)
			)
			(layer "F.Fab")
		)
		(fp_line
			(start -0.12065 -0.305054)
			(end -0.12065 -0.2794)
			(stroke
				(width 0.1)
				(type default)
			)
			(layer "F.Fab")
		)
		(fp_line
			(start -0.12065 -0.2794)
			(end 0.12065 -0.2794)
			(stroke
				(width 0.1)
				(type default)
			)
			(layer "F.Fab")
		)
		(fp_line
			(start -0.12065 0.2794)
			(end -0.12065 0.3048)
			(stroke
				(width 0.1)
				(type default)
			)
			(layer "F.Fab")
		)
		(fp_line
			(start -0.12065 0.3048)
			(end -0.67945 0.3048)
			(stroke
				(width 0.1)
				(type default)
			)
			(layer "F.Fab")
		)
		(fp_line
			(start 0.120396 0.2794)
			(end -0.12065 0.2794)
			(stroke
				(width 0.1)
				(type default)
			)
			(layer "F.Fab")
		)
		(fp_line
			(start 0.120396 0.3048)
			(end 0.120396 0.2794)
			(stroke
				(width 0.1)
				(type default)
			)
			(layer "F.Fab")
		)
		(fp_line
			(start 0.12065 -0.3048)
			(end 0.67945 -0.3048)
			(stroke
				(width 0.1)
				(type default)
			)
			(layer "F.Fab")
		)
		(fp_line
			(start 0.12065 -0.2794)
			(end 0.12065 -0.3048)
			(stroke
				(width 0.1)
				(type default)
			)
			(layer "F.Fab")
		)
		(fp_line
			(start 0.67945 -0.3048)
			(end 0.67945 0.3048)
			(stroke
				(width 0.1)
				(type default)
			)
			(layer "F.Fab")
		)
		(fp_line
			(start 0.67945 0.3048)
			(end 0.120396 0.3048)
			(stroke
				(width 0.1)
				(type default)
			)
			(layer "F.Fab")
		)
		(pad "1" smd circle
			(at -0.40005 0)
			(size 0 0)
			(layers "F.Cu" "F.Mask" "F.Paste")
			(net "P3V3_AUX")
		)
		(pad "2" smd circle
			(at 0.40005 0)
			(size 0 0)
			(layers "F.Cu" "F.Mask" "F.Paste")
			(net "JTAG_SCM_MUX_TDO")
		)
	)
	(footprint ""
		(layer "F.Cu")
		(at 57.697878 -181.84241)
		(property "Reference" "TP17"
			(at -2.071878 1.52908 0)
			(unlocked yes)
			(layer "F.SilkS")
			(effects
				(font
					(size 0.7874 0.5842)
					(thickness 0.1524)
				)
				(justify left)
			)
		)
		(property "Value" ""
			(at 0 0 0)
			(layer "F.Fab")
			(effects
				(font
					(size 1.27 1.27)
				)
			)
		)
		(duplicate_pad_numbers_are_jumpers no)
		(pad "1" smd circle
			(at 0 0)
			(size 0.762 0.762)
			(layers "F.Cu" "F.Mask" "F.Paste")
			(net "VSENSE_PVDDCR_CPU0_P1_DP")
		)
	)
	(footprint ""
		(layer "F.Cu")
		(at 40.6527 -102.5525 90)
		(property "Reference" "U57"
			(at -1.4224 -1.844548 90)
			(unlocked yes)
			(layer "F.SilkS")
			(effects
				(font
					(size 0.7874 0.5842)
					(thickness 0.1524)
				)
				(justify left)
			)
		)
		(property "Value" ""
			(at 0 0 90)
			(layer "F.Fab")
			(effects
				(font
					(size 1.27 1.27)
				)
			)
		)
		(duplicate_pad_numbers_are_jumpers no)
		(fp_line
			(start 1.335278 -1.100074)
			(end -1.335278 -1.100074)
			(stroke
				(width 0.1524)
				(type default)
			)
			(layer "F.SilkS")
		)
		(fp_line
			(start -1.335278 -1.100074)
			(end -1.335278 1.100074)
			(stroke
				(width 0.1524)
				(type default)
			)
			(layer "F.SilkS")
		)
		(fp_line
			(start 1.335278 1.100074)
			(end 1.335278 -1.100074)
			(stroke
				(width 0.1524)
				(type default)
			)
			(layer "F.SilkS")
		)
		(fp_line
			(start -1.335278 1.100074)
			(end 1.335278 1.100074)
			(stroke
				(width 0.1524)
				(type default)
			)
			(layer "F.SilkS")
		)
		(fp_line
			(start 0.674878 -1.100074)
			(end -0.674878 -1.100074)
			(stroke
				(width 0.1)
				(type default)
			)
			(layer "F.Fab")
		)
		(fp_line
			(start -0.674878 -1.100074)
			(end -0.674878 1.100074)
			(stroke
				(width 0.1)
				(type default)
			)
			(layer "F.Fab")
		)
		(fp_line
			(start 0.674878 1.100074)
			(end 0.674878 -1.100074)
			(stroke
				(width 0.1)
				(type default)
			)
			(layer "F.Fab")
		)
		(fp_line
			(start -0.674878 1.100074)
			(end 0.674878 1.100074)
			(stroke
				(width 0.1)
				(type default)
			)
			(layer "F.Fab")
		)
		(pad "1" smd rect
			(at -0.8001 0.649986)
			(size 0.6096 0.8128)
			(layers "F.Cu" "F.Mask" "F.Paste")
			(net "P12V_AUX_DSC_VOL")
		)
		(pad "2" smd rect
			(at -0.8001 -0.649986)
			(size 0.6096 0.8128)
			(layers "F.Cu" "F.Mask" "F.Paste")
			(net "Net_10857")
		)
		(pad "3" smd rect
			(at 0.8001 0)
			(size 0.6096 0.8128)
			(layers "F.Cu" "F.Mask" "F.Paste")
			(net "P12V_AUX_DSC_S1")
		)
	)
	(footprint ""
		(layer "F.Cu")
		(at 289.012884 -370.318792 -90)
		(property "Reference" "C8066"
			(at 0 0 270)
			(layer "F.SilkS")
			(hide yes)
			(effects
				(font
					(size 1.27 1.27)
				)
			)
		)
		(property "Value" ""
			(at 0 0 270)
			(layer "F.Fab")
			(effects
				(font
					(size 1.27 1.27)
				)
			)
		)
		(duplicate_pad_numbers_are_jumpers no)
		(fp_line
			(start -0.7874 0.4064)
			(end -0.7874 -0.4064)
			(stroke
				(width 0.1524)
				(type default)
			)
			(layer "F.SilkS")
		)
		(fp_line
			(start 0.7874 0.4064)
			(end -0.7874 0.4064)
			(stroke
				(width 0.1524)
				(type default)
			)
			(layer "F.SilkS")
		)
		(fp_line
			(start -0.7874 -0.4064)
			(end 0.7874 -0.4064)
			(stroke
				(width 0.1524)
				(type default)
			)
			(layer "F.SilkS")
		)
		(fp_line
			(start 0.7874 -0.4064)
			(end 0.7874 0.4064)
			(stroke
				(width 0.1524)
				(type default)
			)
			(layer "F.SilkS")
		)
		(fp_line
			(start -0.67945 0.3048)
			(end -0.67945 -0.305054)
			(stroke
				(width 0.1)
				(type default)
			)
			(layer "F.Fab")
		)
		(fp_line
			(start -0.12065 0.3048)
			(end -0.67945 0.3048)
			(stroke
				(width 0.1)
				(type default)
			)
			(layer "F.Fab")
		)
		(fp_line
			(start 0.120396 0.3048)
			(end 0.120396 0.2794)
			(stroke
				(width 0.1)
				(type default)
			)
			(layer "F.Fab")
		)
		(fp_line
			(start 0.67945 0.3048)
			(end 0.120396 0.3048)
			(stroke
				(width 0.1)
				(type default)
			)
			(layer "F.Fab")
		)
		(fp_line
			(start -0.12065 0.2794)
			(end -0.12065 0.3048)
			(stroke
				(width 0.1)
				(type default)
			)
			(layer "F.Fab")
		)
		(fp_line
			(start 0.120396 0.2794)
			(end -0.12065 0.2794)
			(stroke
				(width 0.1)
				(type default)
			)
			(layer "F.Fab")
		)
		(fp_line
			(start -0.12065 -0.2794)
			(end 0.12065 -0.2794)
			(stroke
				(width 0.1)
				(type default)
			)
			(layer "F.Fab")
		)
		(fp_line
			(start 0.12065 -0.2794)
			(end 0.12065 -0.3048)
			(stroke
				(width 0.1)
				(type default)
			)
			(layer "F.Fab")
		)
		(fp_line
			(start 0.12065 -0.3048)
			(end 0.67945 -0.3048)
			(stroke
				(width 0.1)
				(type default)
			)
			(layer "F.Fab")
		)
		(fp_line
			(start 0.67945 -0.3048)
			(end 0.67945 0.3048)
			(stroke
				(width 0.1)
				(type default)
			)
			(layer "F.Fab")
		)
		(fp_line
			(start -0.67945 -0.305054)
			(end -0.12065 -0.305054)
			(stroke
				(width 0.1)
				(type default)
			)
			(layer "F.Fab")
		)
		(fp_line
			(start -0.12065 -0.305054)
			(end -0.12065 -0.2794)
			(stroke
				(width 0.1)
				(type default)
			)
			(layer "F.Fab")
		)
		(pad "1" smd circle
			(at -0.40005 0 270)
			(size 0 0)
			(layers "F.Cu" "F.Mask" "F.Paste")
			(net "PVDDIO_P0_EN_R")
		)
		(pad "2" smd circle
			(at 0.40005 0 270)
			(size 0 0)
			(layers "F.Cu" "F.Mask" "F.Paste")
			(net "GND")
		)
	)
	(footprint ""
		(layer "F.Cu")
		(at 325.862188 -392.48588 180)
		(property "Reference" "R952"
			(at 0 0 180)
			(layer "F.SilkS")
			(hide yes)
			(effects
				(font
					(size 1.27 1.27)
				)
			)
		)
		(property "Value" ""
			(at 0 0 180)
			(layer "F.Fab")
			(effects
				(font
					(size 1.27 1.27)
				)
			)
		)
		(duplicate_pad_numbers_are_jumpers no)
		(fp_line
			(start 0.7874 0.4064)
			(end -0.7874 0.4064)
			(stroke
				(width 0.1524)
				(type default)
			)
			(layer "F.SilkS")
		)
		(fp_line
			(start 0.7874 -0.4064)
			(end 0.7874 0.4064)
			(stroke
				(width 0.1524)
				(type default)
			)
			(layer "F.SilkS")
		)
		(fp_line
			(start -0.7874 0.4064)
			(end -0.7874 -0.4064)
			(stroke
				(width 0.1524)
				(type default)
			)
			(layer "F.SilkS")
		)
		(fp_line
			(start -0.7874 -0.4064)
			(end 0.7874 -0.4064)
			(stroke
				(width 0.1524)
				(type default)
			)
			(layer "F.SilkS")
		)
		(fp_line
			(start 0.67945 0.3048)
			(end 0.120396 0.3048)
			(stroke
				(width 0.1)
				(type default)
			)
			(layer "F.Fab")
		)
		(fp_line
			(start 0.67945 -0.3048)
			(end 0.67945 0.3048)
			(stroke
				(width 0.1)
				(type default)
			)
			(layer "F.Fab")
		)
		(fp_line
			(start 0.12065 -0.2794)
			(end 0.12065 -0.3048)
			(stroke
				(width 0.1)
				(type default)
			)
			(layer "F.Fab")
		)
		(fp_line
			(start 0.12065 -0.3048)
			(end 0.67945 -0.3048)
			(stroke
				(width 0.1)
				(type default)
			)
			(layer "F.Fab")
		)
		(fp_line
			(start 0.120396 0.3048)
			(end 0.120396 0.2794)
			(stroke
				(width 0.1)
				(type default)
			)
			(layer "F.Fab")
		)
		(fp_line
			(start 0.120396 0.2794)
			(end -0.12065 0.2794)
			(stroke
				(width 0.1)
				(type default)
			)
			(layer "F.Fab")
		)
		(fp_line
			(start -0.12065 0.3048)
			(end -0.67945 0.3048)
			(stroke
				(width 0.1)
				(type default)
			)
			(layer "F.Fab")
		)
		(fp_line
			(start -0.12065 0.2794)
			(end -0.12065 0.3048)
			(stroke
				(width 0.1)
				(type default)
			)
			(layer "F.Fab")
		)
		(fp_line
			(start -0.12065 -0.2794)
			(end 0.12065 -0.2794)
			(stroke
				(width 0.1)
				(type default)
			)
			(layer "F.Fab")
		)
		(fp_line
			(start -0.12065 -0.305054)
			(end -0.12065 -0.2794)
			(stroke
				(width 0.1)
				(type default)
			)
			(layer "F.Fab")
		)
		(fp_line
			(start -0.67945 0.3048)
			(end -0.67945 -0.305054)
			(stroke
				(width 0.1)
				(type default)
			)
			(layer "F.Fab")
		)
		(fp_line
			(start -0.67945 -0.305054)
			(end -0.12065 -0.305054)
			(stroke
				(width 0.1)
				(type default)
			)
			(layer "F.Fab")
		)
		(pad "1" smd rect
			(at -0.40005 0)
			(size 0.4572 0.508)
			(layers "F.Cu" "F.Mask" "F.Paste")
			(net "P1V8_CPU0_RT0_1A_1D")
		)
		(pad "2" smd rect
			(at 0.40005 0)
			(size 0.4572 0.508)
			(layers "F.Cu" "F.Mask" "F.Paste")
			(net "P1V8_CPU0_RT0_1A")
		)
	)
	(footprint ""
		(layer "F.Cu")
		(at 10.066782 -406.119584 180)
		(property "Reference" "PC6544"
			(at 0 0 180)
			(layer "F.SilkS")
			(hide yes)
			(effects
				(font
					(size 1.27 1.27)
				)
			)
		)
		(property "Value" ""
			(at 0 0 180)
			(layer "F.Fab")
			(effects
				(font
					(size 1.27 1.27)
				)
			)
		)
		(duplicate_pad_numbers_are_jumpers no)
		(fp_line
			(start 0.7874 0.4064)
			(end -0.7874 0.4064)
			(stroke
				(width 0.1524)
				(type default)
			)
			(layer "F.SilkS")
		)
		(fp_line
			(start 0.7874 -0.4064)
			(end 0.7874 0.4064)
			(stroke
				(width 0.1524)
				(type default)
			)
			(layer "F.SilkS")
		)
		(fp_line
			(start -0.7874 0.4064)
			(end -0.7874 -0.4064)
			(stroke
				(width 0.1524)
				(type default)
			)
			(layer "F.SilkS")
		)
		(fp_line
			(start -0.7874 -0.4064)
			(end 0.7874 -0.4064)
			(stroke
				(width 0.1524)
				(type default)
			)
			(layer "F.SilkS")
		)
		(fp_line
			(start 0.67945 0.3048)
			(end 0.120396 0.3048)
			(stroke
				(width 0.1)
				(type default)
			)
			(layer "F.Fab")
		)
		(fp_line
			(start 0.67945 -0.3048)
			(end 0.67945 0.3048)
			(stroke
				(width 0.1)
				(type default)
			)
			(layer "F.Fab")
		)
		(fp_line
			(start 0.12065 -0.2794)
			(end 0.12065 -0.3048)
			(stroke
				(width 0.1)
				(type default)
			)
			(layer "F.Fab")
		)
		(fp_line
			(start 0.12065 -0.3048)
			(end 0.67945 -0.3048)
			(stroke
				(width 0.1)
				(type default)
			)
			(layer "F.Fab")
		)
		(fp_line
			(start 0.120396 0.3048)
			(end 0.120396 0.2794)
			(stroke
				(width 0.1)
				(type default)
			)
			(layer "F.Fab")
		)
		(fp_line
			(start 0.120396 0.2794)
			(end -0.12065 0.2794)
			(stroke
				(width 0.1)
				(type default)
			)
			(layer "F.Fab")
		)
		(fp_line
			(start -0.12065 0.3048)
			(end -0.67945 0.3048)
			(stroke
				(width 0.1)
				(type default)
			)
			(layer "F.Fab")
		)
		(fp_line
			(start -0.12065 0.2794)
			(end -0.12065 0.3048)
			(stroke
				(width 0.1)
				(type default)
			)
			(layer "F.Fab")
		)
		(fp_line
			(start -0.12065 -0.2794)
			(end 0.12065 -0.2794)
			(stroke
				(width 0.1)
				(type default)
			)
			(layer "F.Fab")
		)
		(fp_line
			(start -0.12065 -0.305054)
			(end -0.12065 -0.2794)
			(stroke
				(width 0.1)
				(type default)
			)
			(layer "F.Fab")
		)
		(fp_line
			(start -0.67945 0.3048)
			(end -0.67945 -0.305054)
			(stroke
				(width 0.1)
				(type default)
			)
			(layer "F.Fab")
		)
		(fp_line
			(start -0.67945 -0.305054)
			(end -0.12065 -0.305054)
			(stroke
				(width 0.1)
				(type default)
			)
			(layer "F.Fab")
		)
		(pad "1" smd circle
			(at -0.40005 0 180)
			(size 0 0)
			(layers "F.Cu" "F.Mask" "F.Paste")
			(net "P0V9_RETIMER_CPU1_VCC")
		)
		(pad "2" smd circle
			(at 0.40005 0 180)
			(size 0 0)
			(layers "F.Cu" "F.Mask" "F.Paste")
			(net "GND")
		)
	)
	(footprint ""
		(layer "F.Cu")
		(at 59.169808 -71.527416)
		(property "Reference" "ME3"
			(at 0 0 0)
			(layer "F.SilkS")
			(hide yes)
			(effects
				(font
					(size 1.27 1.27)
				)
			)
		)
		(property "Value" ""
			(at 0 0 0)
			(layer "F.Fab")
			(effects
				(font
					(size 1.27 1.27)
				)
			)
		)
		(duplicate_pad_numbers_are_jumpers no)
		(fp_line
			(start -3.1369 2.5527)
			(end -3.1115 2.5019)
			(stroke
				(width 0.1524)
				(type default)
			)
			(layer "F.SilkS")
		)
		(fp_line
			(start -3.1369 3.0861)
			(end -2.8321 3.0861)
			(stroke
				(width 0.1524)
				(type default)
			)
			(layer "F.SilkS")
		)
		(fp_line
			(start -3.1242 2.9972)
			(end -3.1369 3.0861)
			(stroke
				(width 0.1524)
				(type default)
			)
			(layer "F.SilkS")
		)
		(fp_line
			(start -3.1115 2.5019)
			(end -3.0861 2.4765)
			(stroke
				(width 0.1524)
				(type default)
			)
			(layer "F.SilkS")
		)
		(fp_line
			(start -3.0988 2.921)
			(end -3.1242 2.9972)
			(stroke
				(width 0.1524)
				(type default)
			)
			(layer "F.SilkS")
		)
		(fp_line
			(start -3.0861 2.4765)
			(end -3.048 2.4511)
			(stroke
				(width 0.1524)
				(type default)
			)
			(layer "F.SilkS")
		)
		(fp_line
			(start -3.0734 2.8829)
			(end -3.0988 2.921)
			(stroke
				(width 0.1524)
				(type default)
			)
			(layer "F.SilkS")
		)
		(fp_line
			(start -3.048 2.4511)
			(end -2.9972 2.4384)
			(stroke
				(width 0.1524)
				(type default)
			)
			(layer "F.SilkS")
		)
		(fp_line
			(start -3.048 2.8575)
			(end -3.0734 2.8829)
			(stroke
				(width 0.1524)
				(type default)
			)
			(layer "F.SilkS")
		)
		(fp_line
			(start -3.0099 2.8067)
			(end -3.048 2.8575)
			(stroke
				(width 0.1524)
				(type default)
			)
			(layer "F.SilkS")
		)
		(fp_line
			(start -2.9972 2.4384)
			(end -2.9337 2.4511)
			(stroke
				(width 0.1524)
				(type default)
			)
			(layer "F.SilkS")
		)
		(fp_line
			(start -2.9591 2.7686)
			(end -3.0099 2.8067)
			(stroke
				(width 0.1524)
				(type default)
			)
			(layer "F.SilkS")
		)
		(fp_line
			(start -2.9337 2.4511)
			(end -2.8702 2.5146)
			(stroke
				(width 0.1524)
				(type default)
			)
			(layer "F.SilkS")
		)
		(fp_line
			(start -2.921 2.7432)
			(end -2.9591 2.7686)
			(stroke
				(width 0.1524)
				(type default)
			)
			(layer "F.SilkS")
		)
		(fp_line
			(start -2.8956 2.7178)
			(end -2.921 2.7432)
			(stroke
				(width 0.1524)
				(type default)
			)
			(layer "F.SilkS")
		)
		(fp_line
			(start -2.8702 2.5146)
			(end -2.8575 2.5527)
			(stroke
				(width 0.1524)
				(type default)
			)
			(layer "F.SilkS")
		)
		(fp_line
			(start -2.8702 2.6797)
			(end -2.8956 2.7178)
			(stroke
				(width 0.1524)
				(type default)
			)
			(layer "F.SilkS")
		)
		(fp_line
			(start -2.8575 2.5527)
			(end -2.8575 2.6416)
			(stroke
				(width 0.1524)
				(type default)
			)
			(layer "F.SilkS")
		)
		(fp_line
			(start -2.8575 2.6416)
			(end -2.8702 2.6797)
			(stroke
				(width 0.1524)
				(type default)
			)
			(layer "F.SilkS")
		)
		(fp_line
			(start -2.5908 2.6543)
			(end -2.5908 3.0861)
			(stroke
				(width 0.1524)
				(type default)
			)
			(layer "F.SilkS")
		)
		(fp_line
			(start -2.5908 2.7813)
			(end -2.5654 2.7305)
			(stroke
				(width 0.1524)
				(type default)
			)
			(layer "F.SilkS")
		)
		(fp_line
			(start -2.5654 2.7305)
			(end -2.54 2.6924)
			(stroke
				(width 0.1524)
				(type default)
			)
			(layer "F.SilkS")
		)
		(fp_line
			(start -2.54 2.6924)
			(end -2.5146 2.667)
			(stroke
				(width 0.1524)
				(type default)
			)
			(layer "F.SilkS")
		)
		(fp_line
			(start -2.5146 2.667)
			(end -2.4638 2.6543)
			(stroke
				(width 0.1524)
				(type default)
			)
			(layer "F.SilkS")
		)
		(fp_line
			(start -2.4638 2.6543)
			(end -2.4257 2.6543)
			(stroke
				(width 0.1524)
				(type default)
			)
			(layer "F.SilkS")
		)
		(fp_line
			(start -2.4257 2.6543)
			(end -2.3749 2.667)
			(stroke
				(width 0.1524)
				(type default)
			)
			(layer "F.SilkS")
		)
		(fp_line
			(start -2.3749 2.667)
			(end -2.3368 2.7178)
			(stroke
				(width 0.1524)
				(type default)
			)
			(layer "F.SilkS")
		)
		(fp_line
			(start -2.3368 2.7178)
			(end -2.3114 2.7686)
			(stroke
				(width 0.1524)
				(type default)
			)
			(layer "F.SilkS")
		)
		(fp_line
			(start -2.3114 2.7686)
			(end -2.3114 3.0861)
			(stroke
				(width 0.1524)
				(type default)
			)
			(layer "F.SilkS")
		)
		(fp_line
			(start -2.0701 2.8575)
			(end -2.0701 2.9083)
			(stroke
				(width 0.1524)
				(type default)
			)
			(layer "F.SilkS")
		)
		(fp_line
			(start -2.0701 2.9083)
			(end -2.0574 2.9718)
			(stroke
				(width 0.1524)
				(type default)
			)
			(layer "F.SilkS")
		)
		(fp_line
			(start -2.0574 2.8194)
			(end -2.0701 2.8575)
			(stroke
				(width 0.1524)
				(type default)
			)
			(layer "F.SilkS")
		)
		(fp_line
			(start -2.0574 2.9718)
			(end -2.032 3.0099)
			(stroke
				(width 0.1524)
				(type default)
			)
			(layer "F.SilkS")
		)
		(fp_line
			(start -2.0447 2.794)
			(end -2.0574 2.8194)
			(stroke
				(width 0.1524)
				(type default)
			)
			(layer "F.SilkS")
		)
		(fp_line
			(start -2.032 3.0099)
			(end -2.0066 3.0353)
			(stroke
				(width 0.1524)
				(type default)
			)
			(layer "F.SilkS")
		)
		(fp_line
			(start -2.0066 2.7559)
			(end -2.0447 2.794)
			(stroke
				(width 0.1524)
				(type default)
			)
			(layer "F.SilkS")
		)
		(fp_line
			(start -2.0066 3.0353)
			(end -1.9685 3.0607)
			(stroke
				(width 0.1524)
				(type default)
			)
			(layer "F.SilkS")
		)
		(fp_line
			(start -1.9685 2.7305)
			(end -2.0066 2.7559)
			(stroke
				(width 0.1524)
				(type default)
			)
			(layer "F.SilkS")
		)
		(fp_line
			(start -1.9685 3.0607)
			(end -1.9304 3.0734)
			(stroke
				(width 0.1524)
				(type default)
			)
			(layer "F.SilkS")
		)
		(fp_line
			(start -1.9304 3.0734)
			(end -1.8796 3.0734)
			(stroke
				(width 0.1524)
				(type default)
			)
			(layer "F.SilkS")
		)
		(fp_line
			(start -1.9177 2.7178)
			(end -1.9685 2.7305)
			(stroke
				(width 0.1524)
				(type default)
			)
			(layer "F.SilkS")
		)
		(fp_line
			(start -1.8796 3.0734)
			(end -1.8161 3.0607)
			(stroke
				(width 0.1524)
				(type default)
			)
			(layer "F.SilkS")
		)
		(fp_line
			(start -1.8542 2.7178)
			(end -1.9177 2.7178)
			(stroke
				(width 0.1524)
				(type default)
			)
			(layer "F.SilkS")
		)
		(fp_line
			(start -1.8161 2.7305)
			(end -1.8542 2.7178)
			(stroke
				(width 0.1524)
				(type default)
			)
			(layer "F.SilkS")
		)
		(fp_line
			(start -1.8161 3.0607)
			(end -1.778 3.0353)
			(stroke
				(width 0.1524)
				(type default)
			)
			(layer "F.SilkS")
		)
		(fp_line
			(start -1.778 2.7559)
			(end -1.8161 2.7305)
			(stroke
				(width 0.1524)
				(type default)
			)
			(layer "F.SilkS")
		)
		(fp_line
			(start -1.778 3.0353)
			(end -1.7526 3.0099)
			(stroke
				(width 0.1524)
				(type default)
			)
			(layer "F.SilkS")
		)
		(fp_line
			(start -1.7526 2.4384)
			(end -1.7526 3.0861)
			(stroke
				(width 0.1524)
				(type default)
			)
			(layer "F.SilkS")
		)
		(fp_line
			(start -1.7526 2.7813)
			(end -1.778 2.7559)
			(stroke
				(width 0.1524)
				(type default)
			)
			(layer "F.SilkS")
		)
		(fp_line
			(start -1.3208 -1.524)
			(end 1.4732 1.397)
			(stroke
				(width 0.1524)
				(type default)
			)
			(layer "F.SilkS")
		)
		(fp_line
			(start -1.1938 -1.27)
			(end -1.1938 1.2954)
			(stroke
				(width 0.254)
				(type default)
			)
			(layer "F.SilkS")
		)
		(fp_line
			(start -1.1938 -1.27)
			(end -0.5588 -1.27)
			(stroke
				(width 0.254)
				(type default)
			)
			(layer "F.SilkS")
		)
		(fp_line
			(start -1.1557 2.4257)
			(end -1.1557 3.0861)
			(stroke
				(width 0.1524)
				(type default)
			)
			(layer "F.SilkS")
		)
		(fp_line
			(start -1.016 4.7498)
			(end -1.016 4.826)
			(stroke
				(width 0.254)
				(type default)
			)
			(layer "F.SilkS")
		)
		(fp_line
			(start -1.016 4.7752)
			(end 0.3048 4.7752)
			(stroke
				(width 0.254)
				(type default)
			)
			(layer "F.SilkS")
		)
		(fp_line
			(start -1.016 4.826)
			(end -0.9906 4.953)
			(stroke
				(width 0.254)
				(type default)
			)
			(layer "F.SilkS")
		)
		(fp_line
			(start -0.9906 4.5974)
			(end -1.016 4.7498)
			(stroke
				(width 0.254)
				(type default)
			)
			(layer "F.SilkS")
		)
		(fp_line
			(start -0.9906 4.953)
			(end -0.9652 5.0292)
			(stroke
				(width 0.254)
				(type default)
			)
			(layer "F.SilkS")
		)
		(fp_line
			(start -0.9652 4.5212)
			(end -0.9906 4.5974)
			(stroke
				(width 0.254)
				(type default)
			)
			(layer "F.SilkS")
		)
		(fp_line
			(start -0.9652 5.0292)
			(end -0.9144 5.1308)
			(stroke
				(width 0.254)
				(type default)
			)
			(layer "F.SilkS")
		)
		(fp_line
			(start -0.9144 4.4196)
			(end -0.9652 4.5212)
			(stroke
				(width 0.254)
				(type default)
			)
			(layer "F.SilkS")
		)
		(fp_line
			(start -0.9144 5.1308)
			(end -0.8382 5.2324)
			(stroke
				(width 0.254)
				(type default)
			)
			(layer "F.SilkS")
		)
		(fp_line
			(start -0.8382 4.318)
			(end -0.9144 4.4196)
			(stroke
				(width 0.254)
				(type default)
			)
			(layer "F.SilkS")
		)
		(fp_line
			(start -0.8382 5.2324)
			(end -0.7112 5.334)
			(stroke
				(width 0.254)
				(type default)
			)
			(layer "F.SilkS")
		)
		(fp_line
			(start -0.8128 4.2926)
			(end -0.8382 4.318)
			(stroke
				(width 0.254)
				(type default)
			)
			(layer "F.SilkS")
		)
		(fp_line
			(start -0.7747 2.6543)
			(end -0.5969 3.0861)
			(stroke
				(width 0.1524)
				(type default)
			)
			(layer "F.SilkS")
		)
		(fp_line
			(start -0.7112 4.2164)
			(end -0.8128 4.2926)
			(stroke
				(width 0.254)
				(type default)
			)
			(layer "F.SilkS")
		)
		(fp_line
			(start -0.7112 5.334)
			(end -0.6096 5.3848)
			(stroke
				(width 0.254)
				(type default)
			)
			(layer "F.SilkS")
		)
		(fp_line
			(start -0.6096 4.1656)
			(end -0.7112 4.2164)
			(stroke
				(width 0.254)
				(type default)
			)
			(layer "F.SilkS")
		)
		(fp_line
			(start -0.6096 5.3848)
			(end -0.5334 5.4102)
			(stroke
				(width 0.254)
				(type default)
			)
			(layer "F.SilkS")
		)
		(fp_line
			(start -0.5969 3.0861)
			(end -0.4191 2.6543)
			(stroke
				(width 0.1524)
				(type default)
			)
			(layer "F.SilkS")
		)
		(fp_line
			(start -0.5588 0)
			(end -1.1938 0)
			(stroke
				(width 0.254)
				(type default)
			)
			(layer "F.SilkS")
		)
		(fp_line
			(start -0.5334 4.1402)
			(end -0.6096 4.1656)
			(stroke
				(width 0.254)
				(type default)
			)
			(layer "F.SilkS")
		)
		(fp_line
			(start -0.5334 5.4102)
			(end -0.381 5.4356)
			(stroke
				(width 0.254)
				(type default)
			)
			(layer "F.SilkS")
		)
		(fp_line
			(start -0.4064 4.1148)
			(end -0.5334 4.1402)
			(stroke
				(width 0.254)
				(type default)
			)
			(layer "F.SilkS")
		)
		(fp_line
			(start -0.381 5.4356)
			(end -0.3556 5.4356)
			(stroke
				(width 0.254)
				(type default)
			)
			(layer "F.SilkS")
		)
		(fp_line
			(start -0.3556 5.4356)
			(end -0.1778 5.4102)
			(stroke
				(width 0.254)
				(type default)
			)
			(layer "F.SilkS")
		)
		(fp_line
			(start -0.3048 4.1148)
			(end -0.4064 4.1148)
			(stroke
				(width 0.254)
				(type default)
			)
			(layer "F.SilkS")
		)
		(fp_line
			(start -0.1778 4.1402)
			(end -0.3048 4.1148)
			(stroke
				(width 0.254)
				(type default)
			)
			(layer "F.SilkS")
		)
		(fp_line
			(start -0.1778 5.4102)
			(end -0.1016 5.3848)
			(stroke
				(width 0.254)
				(type default)
			)
			(layer "F.SilkS")
		)
		(fp_line
			(start -0.1016 4.1656)
			(end -0.1778 4.1402)
			(stroke
				(width 0.254)
				(type default)
			)
			(layer "F.SilkS")
		)
		(fp_line
			(start -0.1016 5.3848)
			(end -0.0508 5.3594)
			(stroke
				(width 0.254)
				(type default)
			)
			(layer "F.SilkS")
		)
		(fp_line
			(start -0.0508 5.3594)
			(end 0.1016 5.2578)
			(stroke
				(width 0.254)
				(type default)
			)
			(layer "F.SilkS")
		)
		(fp_line
			(start -0.0381 2.4257)
			(end -0.0381 3.0861)
			(stroke
				(width 0.1524)
				(type default)
			)
			(layer "F.SilkS")
		)
		(fp_line
			(start 0 4.2164)
			(end -0.1016 4.1656)
			(stroke
				(width 0.254)
				(type default)
			)
			(layer "F.SilkS")
		)
		(fp_line
			(start 0.1016 5.2578)
			(end 0.2032 5.1308)
			(stroke
				(width 0.254)
				(type default)
			)
			(layer "F.SilkS")
		)
		(fp_line
			(start 0.127 4.318)
			(end 0 4.2164)
			(stroke
				(width 0.254)
				(type default)
			)
			(layer "F.SilkS")
		)
		(fp_line
			(start 0.2032 4.4196)
			(end 0.127 4.318)
			(stroke
				(width 0.254)
				(type default)
			)
			(layer "F.SilkS")
		)
		(fp_line
			(start 0.254 4.5212)
			(end 0.2032 4.4196)
			(stroke
				(width 0.254)
				(type default)
			)
			(layer "F.SilkS")
		)
		(fp_line
			(start 0.2794 4.5974)
			(end 0.254 4.5212)
			(stroke
				(width 0.254)
				(type default)
			)
			(layer "F.SilkS")
		)
		(fp_line
			(start 0.3048 4.7752)
			(end 0.2794 4.5974)
			(stroke
				(width 0.254)
				(type default)
			)
			(layer "F.SilkS")
		)
		(fp_line
			(start 0.3556 -1.27)
			(end 0.3556 1.2954)
			(stroke
				(width 0.254)
				(type default)
			)
			(layer "F.SilkS")
		)
		(fp_line
			(start 0.635 4.3434)
			(end 0.9144 4.191)
			(stroke
				(width 0.254)
				(type default)
			)
			(layer "F.SilkS")
		)
		(fp_line
			(start 0.6731 2.3495)
			(end 0.6731 2.3749)
			(stroke
				(width 0.1524)
				(type default)
			)
			(layer "F.SilkS")
		)
		(fp_line
			(start 0.6731 2.3749)
			(end 0.6985 2.4003)
			(stroke
				(width 0.1524)
				(type default)
			)
			(layer "F.SilkS")
		)
		(fp_line
			(start 0.6985 2.3241)
			(end 0.6731 2.3495)
			(stroke
				(width 0.1524)
				(type default)
			)
			(layer "F.SilkS")
		)
		(fp_line
			(start 0.6985 2.4003)
			(end 0.7239 2.3749)
			(stroke
				(width 0.1524)
				(type default)
			)
			(layer "F.SilkS")
		)
		(fp_line
			(start 0.6985 2.6416)
			(end 0.6985 3.0861)
			(stroke
				(width 0.1524)
				(type default)
			)
			(layer "F.SilkS")
		)
		(fp_line
			(start 0.7239 2.3495)
			(end 0.6985 2.3241)
			(stroke
				(width 0.1524)
				(type default)
			)
			(layer "F.SilkS")
		)
		(fp_line
			(start 0.7239 2.3749)
			(end 0.7239 2.3495)
			(stroke
				(width 0.1524)
				(type default)
			)
			(layer "F.SilkS")
		)
		(fp_line
			(start 0.9144 4.191)
			(end 0.9144 5.461)
			(stroke
				(width 0.254)
				(type default)
			)
			(layer "F.SilkS")
		)
		(fp_line
			(start 1.143 2.6543)
			(end 1.143 3.0861)
			(stroke
				(width 0.1524)
				(type default)
			)
			(layer "F.SilkS")
		)
		(fp_line
			(start 1.143 2.7813)
			(end 1.1684 2.7305)
			(stroke
				(width 0.1524)
				(type default)
			)
			(layer "F.SilkS")
		)
		(fp_line
			(start 1.1684 2.7305)
			(end 1.1938 2.6924)
			(stroke
				(width 0.1524)
				(type default)
			)
			(layer "F.SilkS")
		)
		(fp_line
			(start 1.1938 2.6924)
			(end 1.2192 2.667)
			(stroke
				(width 0.1524)
				(type default)
			)
			(layer "F.SilkS")
		)
		(fp_line
			(start 1.2192 2.667)
			(end 1.27 2.6543)
			(stroke
				(width 0.1524)
				(type default)
			)
			(layer "F.SilkS")
		)
		(fp_line
			(start 1.27 2.6543)
			(end 1.3081 2.6543)
			(stroke
				(width 0.1524)
				(type default)
			)
			(layer "F.SilkS")
		)
		(fp_line
			(start 1.3081 2.6543)
			(end 1.3589 2.667)
			(stroke
				(width 0.1524)
				(type default)
			)
			(layer "F.SilkS")
		)
		(fp_line
			(start 1.3589 2.667)
			(end 1.397 2.7178)
			(stroke
				(width 0.1524)
				(type default)
			)
			(layer "F.SilkS")
		)
		(fp_line
			(start 1.397 2.7178)
			(end 1.4224 2.7686)
			(stroke
				(width 0.1524)
				(type default)
			)
			(layer "F.SilkS")
		)
		(fp_line
			(start 1.4224 2.7686)
			(end 1.4224 3.0861)
			(stroke
				(width 0.1524)
				(type default)
			)
			(layer "F.SilkS")
		)
		(fp_line
			(start 1.7018 2.667)
			(end 1.9304 2.667)
			(stroke
				(width 0.1524)
				(type default)
			)
			(layer "F.SilkS")
		)
		(fp_line
			(start 1.8161 2.4511)
			(end 1.8161 3.0861)
			(stroke
				(width 0.1524)
				(type default)
			)
			(layer "F.SilkS")
		)
		(fp_line
			(start 1.8161 3.0861)
			(end 1.9939 3.0734)
			(stroke
				(width 0.1524)
				(type default)
			)
			(layer "F.SilkS")
		)
		(fp_line
			(start 2.1844 2.8575)
			(end 2.1844 2.8956)
			(stroke
				(width 0.1524)
				(type default)
			)
			(layer "F.SilkS")
		)
		(fp_line
			(start 2.1844 2.8956)
			(end 2.1971 2.9464)
			(stroke
				(width 0.1524)
				(type default)
			)
			(layer "F.SilkS")
		)
		(fp_line
			(start 2.1971 2.794)
			(end 2.1844 2.8575)
			(stroke
				(width 0.1524)
				(type default)
			)
			(layer "F.SilkS")
		)
		(fp_line
			(start 2.1971 2.9464)
			(end 2.2098 2.9718)
			(stroke
				(width 0.1524)
				(type default)
			)
			(layer "F.SilkS")
		)
		(fp_line
			(start 2.2098 2.7686)
			(end 2.1971 2.794)
			(stroke
				(width 0.1524)
				(type default)
			)
			(layer "F.SilkS")
		)
		(fp_line
			(start 2.2098 2.9718)
			(end 2.2352 3.0099)
			(stroke
				(width 0.1524)
				(type default)
			)
			(layer "F.SilkS")
		)
		(fp_line
			(start 2.2352 2.7305)
			(end 2.2098 2.7686)
			(stroke
				(width 0.1524)
				(type default)
			)
			(layer "F.SilkS")
		)
		(fp_line
			(start 2.2352 3.0099)
			(end 2.2606 3.0353)
			(stroke
				(width 0.1524)
				(type default)
			)
			(layer "F.SilkS")
		)
		(fp_line
			(start 2.2606 2.7051)
			(end 2.2352 2.7305)
			(stroke
				(width 0.1524)
				(type default)
			)
			(layer "F.SilkS")
		)
		(fp_line
			(start 2.2606 3.0353)
			(end 2.2987 3.0607)
			(stroke
				(width 0.1524)
				(type default)
			)
			(layer "F.SilkS")
		)
		(fp_line
			(start 2.2987 2.6797)
			(end 2.2606 2.7051)
			(stroke
				(width 0.1524)
				(type default)
			)
			(layer "F.SilkS")
		)
		(fp_line
			(start 2.2987 3.0607)
			(end 2.3241 3.0734)
			(stroke
				(width 0.1524)
				(type default)
			)
			(layer "F.SilkS")
		)
		(fp_line
			(start 2.3241 2.667)
			(end 2.2987 2.6797)
			(stroke
				(width 0.1524)
				(type default)
			)
			(layer "F.SilkS")
		)
		(fp_line
			(start 2.3241 3.0734)
			(end 2.3876 3.0861)
			(stroke
				(width 0.1524)
				(type default)
			)
			(layer "F.SilkS")
		)
		(fp_line
			(start 2.3749 2.6543)
			(end 2.3241 2.667)
			(stroke
				(width 0.1524)
				(type default)
			)
			(layer "F.SilkS")
		)
		(fp_line
			(start 2.3876 3.0861)
			(end 2.4384 3.0861)
			(stroke
				(width 0.1524)
				(type default)
			)
			(layer "F.SilkS")
		)
		(fp_line
			(start 2.413 2.6543)
			(end 2.3749 2.6543)
			(stroke
				(width 0.1524)
				(type default)
			)
			(layer "F.SilkS")
		)
		(fp_line
			(start 2.4384 3.0861)
			(end 2.5019 3.0607)
			(stroke
				(width 0.1524)
				(type default)
			)
			(layer "F.SilkS")
		)
		(fp_line
			(start 2.4638 2.667)
			(end 2.413 2.6543)
			(stroke
				(width 0.1524)
				(type default)
			)
			(layer "F.SilkS")
		)
		(fp_line
			(start 2.5019 2.6797)
			(end 2.4638 2.667)
			(stroke
				(width 0.1524)
				(type default)
			)
			(layer "F.SilkS")
		)
		(fp_line
			(start 2.8194 2.667)
			(end 3.048 2.667)
			(stroke
				(width 0.1524)
				(type default)
			)
			(layer "F.SilkS")
		)
		(fp_line
			(start 2.9337 2.4511)
			(end 2.9337 3.0861)
			(stroke
				(width 0.1524)
				(type default)
			)
			(layer "F.SilkS")
		)
		(fp_line
			(start 2.9337 3.0861)
			(end 3.1115 3.0734)
			(stroke
				(width 0.1524)
				(type default)
			)
			(layer "F.SilkS")
		)
		(fp_arc
			(start -1.5748 4.826)
			(mid -0.985647 3.828332)
			(end 0.127 3.5052)
			(stroke
				(width 0.1524)
				(type default)
			)
			(layer "F.SilkS")
		)
		(fp_arc
			(start -0.5588 -1.27)
			(mid 0.0762 -0.635)
			(end -0.5588 0)
			(stroke
				(width 0.254)
				(type default)
			)
			(layer "F.SilkS")
		)
		(fp_arc
			(start -0.127 3.5052)
			(mid 0.985653 3.828369)
			(end 1.5748 4.826)
			(stroke
				(width 0.1524)
				(type default)
			)
			(layer "F.SilkS")
		)
		(fp_arc
			(start 0.1524 6.096)
			(mid -0.96456 5.805564)
			(end -1.5748 4.826)
			(stroke
				(width 0.1524)
				(type default)
			)
			(layer "F.SilkS")
		)
		(fp_arc
			(start 1.5748 4.826)
			(mid 0.964538 5.805581)
			(end -0.1524 6.096)
			(stroke
				(width 0.1524)
				(type default)
			)
			(layer "F.SilkS")
		)
		(fp_circle
			(center -1.8923 2.8956)
			(end -1.71196 2.8956)
			(stroke
				(width 0.1524)
				(type default)
			)
			(fill no)
			(layer "F.SilkS")
		)
		(fp_circle
			(center 0 0)
			(end 2.03454 0)
			(stroke
				(width 0.1524)
				(type default)
			)
			(fill no)
			(layer "F.SilkS")
		)
		(fp_circle
			(center 0.9652 0.6858)
			(end 1.57734 0.6858)
			(stroke
				(width 0.254)
				(type default)
			)
			(fill no)
			(layer "F.SilkS")
		)
	)
	(footprint ""
		(layer "F.Cu")
		(at 110.525814 -256.012442 90)
		(property "Reference" "C2475"
			(at 0 0 90)
			(layer "F.SilkS")
			(hide yes)
			(effects
				(font
					(size 1.27 1.27)
				)
			)
		)
		(property "Value" ""
			(at 0 0 90)
			(layer "F.Fab")
			(effects
				(font
					(size 1.27 1.27)
				)
			)
		)
		(duplicate_pad_numbers_are_jumpers no)
		(fp_line
			(start 0.7874 -0.4064)
			(end 0.7874 0.4064)
			(stroke
				(width 0.1524)
				(type default)
			)
			(layer "F.SilkS")
		)
		(fp_line
			(start -0.7874 -0.4064)
			(end 0.7874 -0.4064)
			(stroke
				(width 0.1524)
				(type default)
			)
			(layer "F.SilkS")
		)
		(fp_line
			(start 0.7874 0.4064)
			(end -0.7874 0.4064)
			(stroke
				(width 0.1524)
				(type default)
			)
			(layer "F.SilkS")
		)
		(fp_line
			(start -0.7874 0.4064)
			(end -0.7874 -0.4064)
			(stroke
				(width 0.1524)
				(type default)
			)
			(layer "F.SilkS")
		)
		(fp_line
			(start -0.12065 -0.305054)
			(end -0.12065 -0.2794)
			(stroke
				(width 0.1)
				(type default)
			)
			(layer "F.Fab")
		)
		(fp_line
			(start -0.67945 -0.305054)
			(end -0.12065 -0.305054)
			(stroke
				(width 0.1)
				(type default)
			)
			(layer "F.Fab")
		)
		(fp_line
			(start 0.67945 -0.3048)
			(end 0.67945 0.3048)
			(stroke
				(width 0.1)
				(type default)
			)
			(layer "F.Fab")
		)
		(fp_line
			(start 0.12065 -0.3048)
			(end 0.67945 -0.3048)
			(stroke
				(width 0.1)
				(type default)
			)
			(layer "F.Fab")
		)
		(fp_line
			(start 0.12065 -0.2794)
			(end 0.12065 -0.3048)
			(stroke
				(width 0.1)
				(type default)
			)
			(layer "F.Fab")
		)
		(fp_line
			(start -0.12065 -0.2794)
			(end 0.12065 -0.2794)
			(stroke
				(width 0.1)
				(type default)
			)
			(layer "F.Fab")
		)
		(fp_line
			(start 0.120396 0.2794)
			(end -0.12065 0.2794)
			(stroke
				(width 0.1)
				(type default)
			)
			(layer "F.Fab")
		)
		(fp_line
			(start -0.12065 0.2794)
			(end -0.12065 0.3048)
			(stroke
				(width 0.1)
				(type default)
			)
			(layer "F.Fab")
		)
		(fp_line
			(start 0.67945 0.3048)
			(end 0.120396 0.3048)
			(stroke
				(width 0.1)
				(type default)
			)
			(layer "F.Fab")
		)
		(fp_line
			(start 0.120396 0.3048)
			(end 0.120396 0.2794)
			(stroke
				(width 0.1)
				(type default)
			)
			(layer "F.Fab")
		)
		(fp_line
			(start -0.12065 0.3048)
			(end -0.67945 0.3048)
			(stroke
				(width 0.1)
				(type default)
			)
			(layer "F.Fab")
		)
		(fp_line
			(start -0.67945 0.3048)
			(end -0.67945 -0.305054)
			(stroke
				(width 0.1)
				(type default)
			)
			(layer "F.Fab")
		)
		(pad "1" smd circle
			(at -0.40005 0 90)
			(size 0 0)
			(layers "F.Cu" "F.Mask" "F.Paste")
			(net "PVDDCR_SOC_P1")
		)
		(pad "2" smd circle
			(at 0.40005 0 90)
			(size 0 0)
			(layers "F.Cu" "F.Mask" "F.Paste")
			(net "GND")
		)
	)
	(footprint ""
		(layer "F.Cu")
		(at 359.059988 -416.392868 90)
		(property "Reference" "C1803"
			(at 0 0 90)
			(layer "F.SilkS")
			(hide yes)
			(effects
				(font
					(size 1.27 1.27)
				)
			)
		)
		(property "Value" ""
			(at 0 0 90)
			(layer "F.Fab")
			(effects
				(font
					(size 1.27 1.27)
				)
			)
		)
		(duplicate_pad_numbers_are_jumpers no)
		(fp_line
			(start 0.7874 -0.4064)
			(end 0.7874 0.4064)
			(stroke
				(width 0.1524)
				(type default)
			)
			(layer "F.SilkS")
		)
		(fp_line
			(start -0.7874 -0.4064)
			(end 0.7874 -0.4064)
			(stroke
				(width 0.1524)
				(type default)
			)
			(layer "F.SilkS")
		)
		(fp_line
			(start 0.7874 0.4064)
			(end -0.7874 0.4064)
			(stroke
				(width 0.1524)
				(type default)
			)
			(layer "F.SilkS")
		)
		(fp_line
			(start -0.7874 0.4064)
			(end -0.7874 -0.4064)
			(stroke
				(width 0.1524)
				(type default)
			)
			(layer "F.SilkS")
		)
		(fp_line
			(start -0.12065 -0.305054)
			(end -0.12065 -0.2794)
			(stroke
				(width 0.1)
				(type default)
			)
			(layer "F.Fab")
		)
		(fp_line
			(start -0.67945 -0.305054)
			(end -0.12065 -0.305054)
			(stroke
				(width 0.1)
				(type default)
			)
			(layer "F.Fab")
		)
		(fp_line
			(start 0.67945 -0.3048)
			(end 0.67945 0.3048)
			(stroke
				(width 0.1)
				(type default)
			)
			(layer "F.Fab")
		)
		(fp_line
			(start 0.12065 -0.3048)
			(end 0.67945 -0.3048)
			(stroke
				(width 0.1)
				(type default)
			)
			(layer "F.Fab")
		)
		(fp_line
			(start 0.12065 -0.2794)
			(end 0.12065 -0.3048)
			(stroke
				(width 0.1)
				(type default)
			)
			(layer "F.Fab")
		)
		(fp_line
			(start -0.12065 -0.2794)
			(end 0.12065 -0.2794)
			(stroke
				(width 0.1)
				(type default)
			)
			(layer "F.Fab")
		)
		(fp_line
			(start 0.120396 0.2794)
			(end -0.12065 0.2794)
			(stroke
				(width 0.1)
				(type default)
			)
			(layer "F.Fab")
		)
		(fp_line
			(start -0.12065 0.2794)
			(end -0.12065 0.3048)
			(stroke
				(width 0.1)
				(type default)
			)
			(layer "F.Fab")
		)
		(fp_line
			(start 0.67945 0.3048)
			(end 0.120396 0.3048)
			(stroke
				(width 0.1)
				(type default)
			)
			(layer "F.Fab")
		)
		(fp_line
			(start 0.120396 0.3048)
			(end 0.120396 0.2794)
			(stroke
				(width 0.1)
				(type default)
			)
			(layer "F.Fab")
		)
		(fp_line
			(start -0.12065 0.3048)
			(end -0.67945 0.3048)
			(stroke
				(width 0.1)
				(type default)
			)
			(layer "F.Fab")
		)
		(fp_line
			(start -0.67945 0.3048)
			(end -0.67945 -0.305054)
			(stroke
				(width 0.1)
				(type default)
			)
			(layer "F.Fab")
		)
		(pad "1" smd circle
			(at -0.40005 0 90)
			(size 0 0)
			(layers "F.Cu" "F.Mask" "F.Paste")
			(net "P3V3_AUX")
		)
		(pad "2" smd circle
			(at 0.40005 0 90)
			(size 0 0)
			(layers "F.Cu" "F.Mask" "F.Paste")
			(net "GND")
		)
	)
	(footprint ""
		(layer "F.Cu")
		(at 200.952608 -111.593376)
		(property "Reference" "C5001"
			(at 0 0 0)
			(layer "F.SilkS")
			(hide yes)
			(effects
				(font
					(size 1.27 1.27)
				)
			)
		)
		(property "Value" ""
			(at 0 0 0)
			(layer "F.Fab")
			(effects
				(font
					(size 1.27 1.27)
				)
			)
		)
		(duplicate_pad_numbers_are_jumpers no)
		(fp_line
			(start -0.7874 -0.4064)
			(end 0.7874 -0.4064)
			(stroke
				(width 0.1524)
				(type default)
			)
			(layer "F.SilkS")
		)
		(fp_line
			(start -0.7874 0.4064)
			(end -0.7874 -0.4064)
			(stroke
				(width 0.1524)
				(type default)
			)
			(layer "F.SilkS")
		)
		(fp_line
			(start 0.7874 -0.4064)
			(end 0.7874 0.4064)
			(stroke
				(width 0.1524)
				(type default)
			)
			(layer "F.SilkS")
		)
		(fp_line
			(start 0.7874 0.4064)
			(end -0.7874 0.4064)
			(stroke
				(width 0.1524)
				(type default)
			)
			(layer "F.SilkS")
		)
		(fp_line
			(start -0.67945 -0.305054)
			(end -0.12065 -0.305054)
			(stroke
				(width 0.1)
				(type default)
			)
			(layer "F.Fab")
		)
		(fp_line
			(start -0.67945 0.3048)
			(end -0.67945 -0.305054)
			(stroke
				(width 0.1)
				(type default)
			)
			(layer "F.Fab")
		)
		(fp_line
			(start -0.12065 -0.305054)
			(end -0.12065 -0.2794)
			(stroke
				(width 0.1)
				(type default)
			)
			(layer "F.Fab")
		)
		(fp_line
			(start -0.12065 -0.2794)
			(end 0.12065 -0.2794)
			(stroke
				(width 0.1)
				(type default)
			)
			(layer "F.Fab")
		)
		(fp_line
			(start -0.12065 0.2794)
			(end -0.12065 0.3048)
			(stroke
				(width 0.1)
				(type default)
			)
			(layer "F.Fab")
		)
		(fp_line
			(start -0.12065 0.3048)
			(end -0.67945 0.3048)
			(stroke
				(width 0.1)
				(type default)
			)
			(layer "F.Fab")
		)
		(fp_line
			(start 0.120396 0.2794)
			(end -0.12065 0.2794)
			(stroke
				(width 0.1)
				(type default)
			)
			(layer "F.Fab")
		)
		(fp_line
			(start 0.120396 0.3048)
			(end 0.120396 0.2794)
			(stroke
				(width 0.1)
				(type default)
			)
			(layer "F.Fab")
		)
		(fp_line
			(start 0.12065 -0.3048)
			(end 0.67945 -0.3048)
			(stroke
				(width 0.1)
				(type default)
			)
			(layer "F.Fab")
		)
		(fp_line
			(start 0.12065 -0.2794)
			(end 0.12065 -0.3048)
			(stroke
				(width 0.1)
				(type default)
			)
			(layer "F.Fab")
		)
		(fp_line
			(start 0.67945 -0.3048)
			(end 0.67945 0.3048)
			(stroke
				(width 0.1)
				(type default)
			)
			(layer "F.Fab")
		)
		(fp_line
			(start 0.67945 0.3048)
			(end 0.120396 0.3048)
			(stroke
				(width 0.1)
				(type default)
			)
			(layer "F.Fab")
		)
		(pad "1" smd circle
			(at -0.40005 0)
			(size 0 0)
			(layers "F.Cu" "F.Mask" "F.Paste")
			(net "FM_PWRGD_PVDD18_S5_P0")
		)
		(pad "2" smd circle
			(at 0.40005 0)
			(size 0 0)
			(layers "F.Cu" "F.Mask" "F.Paste")
			(net "GND")
		)
	)
	(footprint ""
		(layer "F.Cu")
		(at 191.135 -129.377948 90)
		(property "Reference" "R1359"
			(at 0 0 90)
			(layer "F.SilkS")
			(hide yes)
			(effects
				(font
					(size 1.27 1.27)
				)
			)
		)
		(property "Value" ""
			(at 0 0 90)
			(layer "F.Fab")
			(effects
				(font
					(size 1.27 1.27)
				)
			)
		)
		(duplicate_pad_numbers_are_jumpers no)
		(fp_line
			(start 0.7874 -0.4064)
			(end 0.7874 0.4064)
			(stroke
				(width 0.1524)
				(type default)
			)
			(layer "F.SilkS")
		)
		(fp_line
			(start -0.7874 -0.4064)
			(end 0.7874 -0.4064)
			(stroke
				(width 0.1524)
				(type default)
			)
			(layer "F.SilkS")
		)
		(fp_line
			(start 0.7874 0.4064)
			(end -0.7874 0.4064)
			(stroke
				(width 0.1524)
				(type default)
			)
			(layer "F.SilkS")
		)
		(fp_line
			(start -0.7874 0.4064)
			(end -0.7874 -0.4064)
			(stroke
				(width 0.1524)
				(type default)
			)
			(layer "F.SilkS")
		)
		(fp_line
			(start -0.12065 -0.305054)
			(end -0.12065 -0.2794)
			(stroke
				(width 0.1)
				(type default)
			)
			(layer "F.Fab")
		)
		(fp_line
			(start -0.67945 -0.305054)
			(end -0.12065 -0.305054)
			(stroke
				(width 0.1)
				(type default)
			)
			(layer "F.Fab")
		)
		(fp_line
			(start 0.67945 -0.3048)
			(end 0.67945 0.3048)
			(stroke
				(width 0.1)
				(type default)
			)
			(layer "F.Fab")
		)
		(fp_line
			(start 0.12065 -0.3048)
			(end 0.67945 -0.3048)
			(stroke
				(width 0.1)
				(type default)
			)
			(layer "F.Fab")
		)
		(fp_line
			(start 0.12065 -0.2794)
			(end 0.12065 -0.3048)
			(stroke
				(width 0.1)
				(type default)
			)
			(layer "F.Fab")
		)
		(fp_line
			(start -0.12065 -0.2794)
			(end 0.12065 -0.2794)
			(stroke
				(width 0.1)
				(type default)
			)
			(layer "F.Fab")
		)
		(fp_line
			(start 0.120396 0.2794)
			(end -0.12065 0.2794)
			(stroke
				(width 0.1)
				(type default)
			)
			(layer "F.Fab")
		)
		(fp_line
			(start -0.12065 0.2794)
			(end -0.12065 0.3048)
			(stroke
				(width 0.1)
				(type default)
			)
			(layer "F.Fab")
		)
		(fp_line
			(start 0.67945 0.3048)
			(end 0.120396 0.3048)
			(stroke
				(width 0.1)
				(type default)
			)
			(layer "F.Fab")
		)
		(fp_line
			(start 0.120396 0.3048)
			(end 0.120396 0.2794)
			(stroke
				(width 0.1)
				(type default)
			)
			(layer "F.Fab")
		)
		(fp_line
			(start -0.12065 0.3048)
			(end -0.67945 0.3048)
			(stroke
				(width 0.1)
				(type default)
			)
			(layer "F.Fab")
		)
		(fp_line
			(start -0.67945 0.3048)
			(end -0.67945 -0.305054)
			(stroke
				(width 0.1)
				(type default)
			)
			(layer "F.Fab")
		)
		(pad "1" smd circle
			(at -0.40005 0 90)
			(size 0 0)
			(layers "F.Cu" "F.Mask" "F.Paste")
			(net "BMC_JTAG_SEL_R")
		)
		(pad "2" smd circle
			(at 0.40005 0 90)
			(size 0 0)
			(layers "F.Cu" "F.Mask" "F.Paste")
			(net "BMC_JTAG_SEL")
		)
	)
	(footprint ""
		(layer "F.Cu")
		(at 287.570672 -412.74111 -90)
		(property "Reference" "R4520"
			(at 0 0 270)
			(layer "F.SilkS")
			(hide yes)
			(effects
				(font
					(size 1.27 1.27)
				)
			)
		)
		(property "Value" ""
			(at 0 0 270)
			(layer "F.Fab")
			(effects
				(font
					(size 1.27 1.27)
				)
			)
		)
		(duplicate_pad_numbers_are_jumpers no)
		(fp_line
			(start -0.7874 0.4064)
			(end -0.7874 -0.4064)
			(stroke
				(width 0.1524)
				(type default)
			)
			(layer "F.SilkS")
		)
		(fp_line
			(start 0.7874 0.4064)
			(end -0.7874 0.4064)
			(stroke
				(width 0.1524)
				(type default)
			)
			(layer "F.SilkS")
		)
		(fp_line
			(start -0.7874 -0.4064)
			(end 0.7874 -0.4064)
			(stroke
				(width 0.1524)
				(type default)
			)
			(layer "F.SilkS")
		)
		(fp_line
			(start 0.7874 -0.4064)
			(end 0.7874 0.4064)
			(stroke
				(width 0.1524)
				(type default)
			)
			(layer "F.SilkS")
		)
		(fp_line
			(start -0.67945 0.3048)
			(end -0.67945 -0.305054)
			(stroke
				(width 0.1)
				(type default)
			)
			(layer "F.Fab")
		)
		(fp_line
			(start -0.12065 0.3048)
			(end -0.67945 0.3048)
			(stroke
				(width 0.1)
				(type default)
			)
			(layer "F.Fab")
		)
		(fp_line
			(start 0.120396 0.3048)
			(end 0.120396 0.2794)
			(stroke
				(width 0.1)
				(type default)
			)
			(layer "F.Fab")
		)
		(fp_line
			(start 0.67945 0.3048)
			(end 0.120396 0.3048)
			(stroke
				(width 0.1)
				(type default)
			)
			(layer "F.Fab")
		)
		(fp_line
			(start -0.12065 0.2794)
			(end -0.12065 0.3048)
			(stroke
				(width 0.1)
				(type default)
			)
			(layer "F.Fab")
		)
		(fp_line
			(start 0.120396 0.2794)
			(end -0.12065 0.2794)
			(stroke
				(width 0.1)
				(type default)
			)
			(layer "F.Fab")
		)
		(fp_line
			(start -0.12065 -0.2794)
			(end 0.12065 -0.2794)
			(stroke
				(width 0.1)
				(type default)
			)
			(layer "F.Fab")
		)
		(fp_line
			(start 0.12065 -0.2794)
			(end 0.12065 -0.3048)
			(stroke
				(width 0.1)
				(type default)
			)
			(layer "F.Fab")
		)
		(fp_line
			(start 0.12065 -0.3048)
			(end 0.67945 -0.3048)
			(stroke
				(width 0.1)
				(type default)
			)
			(layer "F.Fab")
		)
		(fp_line
			(start 0.67945 -0.3048)
			(end 0.67945 0.3048)
			(stroke
				(width 0.1)
				(type default)
			)
			(layer "F.Fab")
		)
		(fp_line
			(start -0.67945 -0.305054)
			(end -0.12065 -0.305054)
			(stroke
				(width 0.1)
				(type default)
			)
			(layer "F.Fab")
		)
		(fp_line
			(start -0.12065 -0.305054)
			(end -0.12065 -0.2794)
			(stroke
				(width 0.1)
				(type default)
			)
			(layer "F.Fab")
		)
		(pad "1" smd circle
			(at -0.40005 0 270)
			(size 0 0)
			(layers "F.Cu" "F.Mask" "F.Paste")
			(net "FM_9ZXL045_P0_0_OE_N")
		)
		(pad "2" smd circle
			(at 0.40005 0 270)
			(size 0 0)
			(layers "F.Cu" "F.Mask" "F.Paste")
			(net "GND")
		)
	)
	(footprint ""
		(layer "F.Cu")
		(at 378.916692 -383.88163 -90)
		(property "Reference" "C886"
			(at 0 0 270)
			(layer "F.SilkS")
			(hide yes)
			(effects
				(font
					(size 1.27 1.27)
				)
			)
		)
		(property "Value" ""
			(at 0 0 270)
			(layer "F.Fab")
			(effects
				(font
					(size 1.27 1.27)
				)
			)
		)
		(duplicate_pad_numbers_are_jumpers no)
		(fp_line
			(start -0.299974 0.150114)
			(end -0.299974 -0.150114)
			(stroke
				(width 0.1)
				(type default)
			)
			(layer "F.Fab")
		)
		(fp_line
			(start 0.299974 0.150114)
			(end -0.299974 0.150114)
			(stroke
				(width 0.1)
				(type default)
			)
			(layer "F.Fab")
		)
		(fp_line
			(start -0.299974 -0.150114)
			(end 0.299974 -0.150114)
			(stroke
				(width 0.1)
				(type default)
			)
			(layer "F.Fab")
		)
		(fp_line
			(start 0.299974 -0.150114)
			(end 0.299974 0.150114)
			(stroke
				(width 0.1)
				(type default)
			)
			(layer "F.Fab")
		)
		(pad "1" smd rect
			(at -0.2667 0 270)
			(size 0.3048 0.381)
			(layers "F.Cu" "F.Mask" "F.Paste")
			(net "P5E_CPU0_P3_TX_C_DN<7>")
		)
		(pad "2" smd rect
			(at 0.2667 0 270)
			(size 0.3048 0.381)
			(layers "F.Cu" "F.Mask" "F.Paste")
			(net "P5E_CPU0_P3_TX_DN<7>")
		)
	)
	(footprint ""
		(layer "F.Cu")
		(at 255.45669 -40.498522 -90)
		(property "Reference" "PC2215"
			(at 0 0 270)
			(layer "F.SilkS")
			(hide yes)
			(effects
				(font
					(size 1.27 1.27)
				)
			)
		)
		(property "Value" ""
			(at 0 0 270)
			(layer "F.Fab")
			(effects
				(font
					(size 1.27 1.27)
				)
			)
		)
		(duplicate_pad_numbers_are_jumpers no)
		(fp_line
			(start -0.7874 0.4064)
			(end -0.7874 -0.4064)
			(stroke
				(width 0.1524)
				(type default)
			)
			(layer "F.SilkS")
		)
		(fp_line
			(start 0.7874 0.4064)
			(end -0.7874 0.4064)
			(stroke
				(width 0.1524)
				(type default)
			)
			(layer "F.SilkS")
		)
		(fp_line
			(start -0.7874 -0.4064)
			(end 0.7874 -0.4064)
			(stroke
				(width 0.1524)
				(type default)
			)
			(layer "F.SilkS")
		)
		(fp_line
			(start 0.7874 -0.4064)
			(end 0.7874 0.4064)
			(stroke
				(width 0.1524)
				(type default)
			)
			(layer "F.SilkS")
		)
		(fp_line
			(start -0.67945 0.3048)
			(end -0.67945 -0.305054)
			(stroke
				(width 0.1)
				(type default)
			)
			(layer "F.Fab")
		)
		(fp_line
			(start -0.12065 0.3048)
			(end -0.67945 0.3048)
			(stroke
				(width 0.1)
				(type default)
			)
			(layer "F.Fab")
		)
		(fp_line
			(start 0.120396 0.3048)
			(end 0.120396 0.2794)
			(stroke
				(width 0.1)
				(type default)
			)
			(layer "F.Fab")
		)
		(fp_line
			(start 0.67945 0.3048)
			(end 0.120396 0.3048)
			(stroke
				(width 0.1)
				(type default)
			)
			(layer "F.Fab")
		)
		(fp_line
			(start -0.12065 0.2794)
			(end -0.12065 0.3048)
			(stroke
				(width 0.1)
				(type default)
			)
			(layer "F.Fab")
		)
		(fp_line
			(start 0.120396 0.2794)
			(end -0.12065 0.2794)
			(stroke
				(width 0.1)
				(type default)
			)
			(layer "F.Fab")
		)
		(fp_line
			(start -0.12065 -0.2794)
			(end 0.12065 -0.2794)
			(stroke
				(width 0.1)
				(type default)
			)
			(layer "F.Fab")
		)
		(fp_line
			(start 0.12065 -0.2794)
			(end 0.12065 -0.3048)
			(stroke
				(width 0.1)
				(type default)
			)
			(layer "F.Fab")
		)
		(fp_line
			(start 0.12065 -0.3048)
			(end 0.67945 -0.3048)
			(stroke
				(width 0.1)
				(type default)
			)
			(layer "F.Fab")
		)
		(fp_line
			(start 0.67945 -0.3048)
			(end 0.67945 0.3048)
			(stroke
				(width 0.1)
				(type default)
			)
			(layer "F.Fab")
		)
		(fp_line
			(start -0.67945 -0.305054)
			(end -0.12065 -0.305054)
			(stroke
				(width 0.1)
				(type default)
			)
			(layer "F.Fab")
		)
		(fp_line
			(start -0.12065 -0.305054)
			(end -0.12065 -0.2794)
			(stroke
				(width 0.1)
				(type default)
			)
			(layer "F.Fab")
		)
		(pad "1" smd circle
			(at -0.40005 0 270)
			(size 0 0)
			(layers "F.Cu" "F.Mask" "F.Paste")
			(net "P12V_E1S_GATE_0")
		)
		(pad "2" smd circle
			(at 0.40005 0 270)
			(size 0 0)
			(layers "F.Cu" "F.Mask" "F.Paste")
			(net "GND")
		)
	)
	(footprint ""
		(layer "F.Cu")
		(at 298.967144 -384.32486 180)
		(property "Reference" "C931"
			(at 0 0 180)
			(layer "F.SilkS")
			(hide yes)
			(effects
				(font
					(size 1.27 1.27)
				)
			)
		)
		(property "Value" ""
			(at 0 0 180)
			(layer "F.Fab")
			(effects
				(font
					(size 1.27 1.27)
				)
			)
		)
		(duplicate_pad_numbers_are_jumpers no)
		(fp_line
			(start 0.299974 0.150114)
			(end -0.299974 0.150114)
			(stroke
				(width 0.1)
				(type default)
			)
			(layer "F.Fab")
		)
		(fp_line
			(start 0.299974 -0.150114)
			(end 0.299974 0.150114)
			(stroke
				(width 0.1)
				(type default)
			)
			(layer "F.Fab")
		)
		(fp_line
			(start -0.299974 0.150114)
			(end -0.299974 -0.150114)
			(stroke
				(width 0.1)
				(type default)
			)
			(layer "F.Fab")
		)
		(fp_line
			(start -0.299974 -0.150114)
			(end 0.299974 -0.150114)
			(stroke
				(width 0.1)
				(type default)
			)
			(layer "F.Fab")
		)
		(pad "1" smd rect
			(at -0.2667 0 180)
			(size 0.3048 0.381)
			(layers "F.Cu" "F.Mask" "F.Paste")
			(net "P5E_CPU0_P0_TX_C_DP<1>")
		)
		(pad "2" smd rect
			(at 0.2667 0 180)
			(size 0.3048 0.381)
			(layers "F.Cu" "F.Mask" "F.Paste")
			(net "P5E_CPU0_P0_TX_DP<1>")
		)
	)
	(footprint ""
		(layer "F.Cu")
		(at 216.982548 -133.200902 180)
		(property "Reference" "R6119"
			(at 0 0 180)
			(layer "F.SilkS")
			(hide yes)
			(effects
				(font
					(size 1.27 1.27)
				)
			)
		)
		(property "Value" ""
			(at 0 0 180)
			(layer "F.Fab")
			(effects
				(font
					(size 1.27 1.27)
				)
			)
		)
		(duplicate_pad_numbers_are_jumpers no)
		(fp_line
			(start 0.7874 0.4064)
			(end -0.7874 0.4064)
			(stroke
				(width 0.1524)
				(type default)
			)
			(layer "F.SilkS")
		)
		(fp_line
			(start 0.7874 -0.4064)
			(end 0.7874 0.4064)
			(stroke
				(width 0.1524)
				(type default)
			)
			(layer "F.SilkS")
		)
		(fp_line
			(start -0.7874 0.4064)
			(end -0.7874 -0.4064)
			(stroke
				(width 0.1524)
				(type default)
			)
			(layer "F.SilkS")
		)
		(fp_line
			(start -0.7874 -0.4064)
			(end 0.7874 -0.4064)
			(stroke
				(width 0.1524)
				(type default)
			)
			(layer "F.SilkS")
		)
		(fp_line
			(start 0.67945 0.3048)
			(end 0.120396 0.3048)
			(stroke
				(width 0.1)
				(type default)
			)
			(layer "F.Fab")
		)
		(fp_line
			(start 0.67945 -0.3048)
			(end 0.67945 0.3048)
			(stroke
				(width 0.1)
				(type default)
			)
			(layer "F.Fab")
		)
		(fp_line
			(start 0.12065 -0.2794)
			(end 0.12065 -0.3048)
			(stroke
				(width 0.1)
				(type default)
			)
			(layer "F.Fab")
		)
		(fp_line
			(start 0.12065 -0.3048)
			(end 0.67945 -0.3048)
			(stroke
				(width 0.1)
				(type default)
			)
			(layer "F.Fab")
		)
		(fp_line
			(start 0.120396 0.3048)
			(end 0.120396 0.2794)
			(stroke
				(width 0.1)
				(type default)
			)
			(layer "F.Fab")
		)
		(fp_line
			(start 0.120396 0.2794)
			(end -0.12065 0.2794)
			(stroke
				(width 0.1)
				(type default)
			)
			(layer "F.Fab")
		)
		(fp_line
			(start -0.12065 0.3048)
			(end -0.67945 0.3048)
			(stroke
				(width 0.1)
				(type default)
			)
			(layer "F.Fab")
		)
		(fp_line
			(start -0.12065 0.2794)
			(end -0.12065 0.3048)
			(stroke
				(width 0.1)
				(type default)
			)
			(layer "F.Fab")
		)
		(fp_line
			(start -0.12065 -0.2794)
			(end 0.12065 -0.2794)
			(stroke
				(width 0.1)
				(type default)
			)
			(layer "F.Fab")
		)
		(fp_line
			(start -0.12065 -0.305054)
			(end -0.12065 -0.2794)
			(stroke
				(width 0.1)
				(type default)
			)
			(layer "F.Fab")
		)
		(fp_line
			(start -0.67945 0.3048)
			(end -0.67945 -0.305054)
			(stroke
				(width 0.1)
				(type default)
			)
			(layer "F.Fab")
		)
		(fp_line
			(start -0.67945 -0.305054)
			(end -0.12065 -0.305054)
			(stroke
				(width 0.1)
				(type default)
			)
			(layer "F.Fab")
		)
		(pad "1" smd circle
			(at -0.40005 0 180)
			(size 0 0)
			(layers "F.Cu" "F.Mask" "F.Paste")
			(net "PWRGD_P3V3_AUX")
		)
		(pad "2" smd circle
			(at 0.40005 0 180)
			(size 0 0)
			(layers "F.Cu" "F.Mask" "F.Paste")
			(net "P1V8_AUX_ENABLE")
		)
	)
	(footprint ""
		(layer "F.Cu")
		(at 84.42833 -339.835998 90)
		(property "Reference" "PC374_1"
			(at 0 0 90)
			(layer "F.SilkS")
			(hide yes)
			(effects
				(font
					(size 1.27 1.27)
				)
			)
		)
		(property "Value" ""
			(at 0 0 90)
			(layer "F.Fab")
			(effects
				(font
					(size 1.27 1.27)
				)
			)
		)
		(duplicate_pad_numbers_are_jumpers no)
		(fp_line
			(start 0.7874 -0.4064)
			(end 0.7874 0.4064)
			(stroke
				(width 0.1524)
				(type default)
			)
			(layer "F.SilkS")
		)
		(fp_line
			(start -0.7874 -0.4064)
			(end 0.7874 -0.4064)
			(stroke
				(width 0.1524)
				(type default)
			)
			(layer "F.SilkS")
		)
		(fp_line
			(start 0.7874 0.4064)
			(end -0.7874 0.4064)
			(stroke
				(width 0.1524)
				(type default)
			)
			(layer "F.SilkS")
		)
		(fp_line
			(start -0.7874 0.4064)
			(end -0.7874 -0.4064)
			(stroke
				(width 0.1524)
				(type default)
			)
			(layer "F.SilkS")
		)
		(fp_line
			(start -0.12065 -0.305054)
			(end -0.12065 -0.2794)
			(stroke
				(width 0.1)
				(type default)
			)
			(layer "F.Fab")
		)
		(fp_line
			(start -0.67945 -0.305054)
			(end -0.12065 -0.305054)
			(stroke
				(width 0.1)
				(type default)
			)
			(layer "F.Fab")
		)
		(fp_line
			(start 0.67945 -0.3048)
			(end 0.67945 0.3048)
			(stroke
				(width 0.1)
				(type default)
			)
			(layer "F.Fab")
		)
		(fp_line
			(start 0.12065 -0.3048)
			(end 0.67945 -0.3048)
			(stroke
				(width 0.1)
				(type default)
			)
			(layer "F.Fab")
		)
		(fp_line
			(start 0.12065 -0.2794)
			(end 0.12065 -0.3048)
			(stroke
				(width 0.1)
				(type default)
			)
			(layer "F.Fab")
		)
		(fp_line
			(start -0.12065 -0.2794)
			(end 0.12065 -0.2794)
			(stroke
				(width 0.1)
				(type default)
			)
			(layer "F.Fab")
		)
		(fp_line
			(start 0.120396 0.2794)
			(end -0.12065 0.2794)
			(stroke
				(width 0.1)
				(type default)
			)
			(layer "F.Fab")
		)
		(fp_line
			(start -0.12065 0.2794)
			(end -0.12065 0.3048)
			(stroke
				(width 0.1)
				(type default)
			)
			(layer "F.Fab")
		)
		(fp_line
			(start 0.67945 0.3048)
			(end 0.120396 0.3048)
			(stroke
				(width 0.1)
				(type default)
			)
			(layer "F.Fab")
		)
		(fp_line
			(start 0.120396 0.3048)
			(end 0.120396 0.2794)
			(stroke
				(width 0.1)
				(type default)
			)
			(layer "F.Fab")
		)
		(fp_line
			(start -0.12065 0.3048)
			(end -0.67945 0.3048)
			(stroke
				(width 0.1)
				(type default)
			)
			(layer "F.Fab")
		)
		(fp_line
			(start -0.67945 0.3048)
			(end -0.67945 -0.305054)
			(stroke
				(width 0.1)
				(type default)
			)
			(layer "F.Fab")
		)
		(pad "1" smd circle
			(at -0.40005 0 90)
			(size 0 0)
			(layers "F.Cu" "F.Mask" "F.Paste")
			(net "PVDDCR_CPU1_P1_VCCS")
		)
		(pad "2" smd circle
			(at 0.40005 0 90)
			(size 0 0)
			(layers "F.Cu" "F.Mask" "F.Paste")
			(net "GND")
		)
	)
	(footprint ""
		(layer "F.Cu")
		(at 104.843834 -135.290052 90)
		(property "Reference" "PR152"
			(at 0 0 90)
			(layer "F.SilkS")
			(hide yes)
			(effects
				(font
					(size 1.27 1.27)
				)
			)
		)
		(property "Value" ""
			(at 0 0 90)
			(layer "F.Fab")
			(effects
				(font
					(size 1.27 1.27)
				)
			)
		)
		(duplicate_pad_numbers_are_jumpers no)
		(fp_line
			(start 0.7874 -0.4064)
			(end 0.7874 0.4064)
			(stroke
				(width 0.1524)
				(type default)
			)
			(layer "F.SilkS")
		)
		(fp_line
			(start -0.7874 -0.4064)
			(end 0.7874 -0.4064)
			(stroke
				(width 0.1524)
				(type default)
			)
			(layer "F.SilkS")
		)
		(fp_line
			(start 0.7874 0.4064)
			(end -0.7874 0.4064)
			(stroke
				(width 0.1524)
				(type default)
			)
			(layer "F.SilkS")
		)
		(fp_line
			(start -0.7874 0.4064)
			(end -0.7874 -0.4064)
			(stroke
				(width 0.1524)
				(type default)
			)
			(layer "F.SilkS")
		)
		(fp_line
			(start -0.12065 -0.305054)
			(end -0.12065 -0.2794)
			(stroke
				(width 0.1)
				(type default)
			)
			(layer "F.Fab")
		)
		(fp_line
			(start -0.67945 -0.305054)
			(end -0.12065 -0.305054)
			(stroke
				(width 0.1)
				(type default)
			)
			(layer "F.Fab")
		)
		(fp_line
			(start 0.67945 -0.3048)
			(end 0.67945 0.3048)
			(stroke
				(width 0.1)
				(type default)
			)
			(layer "F.Fab")
		)
		(fp_line
			(start 0.12065 -0.3048)
			(end 0.67945 -0.3048)
			(stroke
				(width 0.1)
				(type default)
			)
			(layer "F.Fab")
		)
		(fp_line
			(start 0.12065 -0.2794)
			(end 0.12065 -0.3048)
			(stroke
				(width 0.1)
				(type default)
			)
			(layer "F.Fab")
		)
		(fp_line
			(start -0.12065 -0.2794)
			(end 0.12065 -0.2794)
			(stroke
				(width 0.1)
				(type default)
			)
			(layer "F.Fab")
		)
		(fp_line
			(start 0.120396 0.2794)
			(end -0.12065 0.2794)
			(stroke
				(width 0.1)
				(type default)
			)
			(layer "F.Fab")
		)
		(fp_line
			(start -0.12065 0.2794)
			(end -0.12065 0.3048)
			(stroke
				(width 0.1)
				(type default)
			)
			(layer "F.Fab")
		)
		(fp_line
			(start 0.67945 0.3048)
			(end 0.120396 0.3048)
			(stroke
				(width 0.1)
				(type default)
			)
			(layer "F.Fab")
		)
		(fp_line
			(start 0.120396 0.3048)
			(end 0.120396 0.2794)
			(stroke
				(width 0.1)
				(type default)
			)
			(layer "F.Fab")
		)
		(fp_line
			(start -0.12065 0.3048)
			(end -0.67945 0.3048)
			(stroke
				(width 0.1)
				(type default)
			)
			(layer "F.Fab")
		)
		(fp_line
			(start -0.67945 0.3048)
			(end -0.67945 -0.305054)
			(stroke
				(width 0.1)
				(type default)
			)
			(layer "F.Fab")
		)
		(pad "1" smd circle
			(at -0.40005 0 90)
			(size 0 0)
			(layers "F.Cu" "F.Mask" "F.Paste")
			(net "P3V3_AUX")
		)
		(pad "2" smd circle
			(at 0.40005 0 90)
			(size 0 0)
			(layers "F.Cu" "F.Mask" "F.Paste")
			(net "PVDDCR_SOC_P1_EN_GD")
		)
	)
	(footprint ""
		(layer "F.Cu")
		(at 113.283238 -39.40175 -90)
		(property "Reference" "R6285"
			(at 0 0 270)
			(layer "F.SilkS")
			(hide yes)
			(effects
				(font
					(size 1.27 1.27)
				)
			)
		)
		(property "Value" ""
			(at 0 0 270)
			(layer "F.Fab")
			(effects
				(font
					(size 1.27 1.27)
				)
			)
		)
		(duplicate_pad_numbers_are_jumpers no)
		(fp_line
			(start -0.7874 0.4064)
			(end -0.7874 -0.4064)
			(stroke
				(width 0.1524)
				(type default)
			)
			(layer "F.SilkS")
		)
		(fp_line
			(start 0.7874 0.4064)
			(end -0.7874 0.4064)
			(stroke
				(width 0.1524)
				(type default)
			)
			(layer "F.SilkS")
		)
		(fp_line
			(start -0.7874 -0.4064)
			(end 0.7874 -0.4064)
			(stroke
				(width 0.1524)
				(type default)
			)
			(layer "F.SilkS")
		)
		(fp_line
			(start 0.7874 -0.4064)
			(end 0.7874 0.4064)
			(stroke
				(width 0.1524)
				(type default)
			)
			(layer "F.SilkS")
		)
		(fp_line
			(start -0.67945 0.3048)
			(end -0.67945 -0.305054)
			(stroke
				(width 0.1)
				(type default)
			)
			(layer "F.Fab")
		)
		(fp_line
			(start -0.12065 0.3048)
			(end -0.67945 0.3048)
			(stroke
				(width 0.1)
				(type default)
			)
			(layer "F.Fab")
		)
		(fp_line
			(start 0.120396 0.3048)
			(end 0.120396 0.2794)
			(stroke
				(width 0.1)
				(type default)
			)
			(layer "F.Fab")
		)
		(fp_line
			(start 0.67945 0.3048)
			(end 0.120396 0.3048)
			(stroke
				(width 0.1)
				(type default)
			)
			(layer "F.Fab")
		)
		(fp_line
			(start -0.12065 0.2794)
			(end -0.12065 0.3048)
			(stroke
				(width 0.1)
				(type default)
			)
			(layer "F.Fab")
		)
		(fp_line
			(start 0.120396 0.2794)
			(end -0.12065 0.2794)
			(stroke
				(width 0.1)
				(type default)
			)
			(layer "F.Fab")
		)
		(fp_line
			(start -0.12065 -0.2794)
			(end 0.12065 -0.2794)
			(stroke
				(width 0.1)
				(type default)
			)
			(layer "F.Fab")
		)
		(fp_line
			(start 0.12065 -0.2794)
			(end 0.12065 -0.3048)
			(stroke
				(width 0.1)
				(type default)
			)
			(layer "F.Fab")
		)
		(fp_line
			(start 0.12065 -0.3048)
			(end 0.67945 -0.3048)
			(stroke
				(width 0.1)
				(type default)
			)
			(layer "F.Fab")
		)
		(fp_line
			(start 0.67945 -0.3048)
			(end 0.67945 0.3048)
			(stroke
				(width 0.1)
				(type default)
			)
			(layer "F.Fab")
		)
		(fp_line
			(start -0.67945 -0.305054)
			(end -0.12065 -0.305054)
			(stroke
				(width 0.1)
				(type default)
			)
			(layer "F.Fab")
		)
		(fp_line
			(start -0.12065 -0.305054)
			(end -0.12065 -0.2794)
			(stroke
				(width 0.1)
				(type default)
			)
			(layer "F.Fab")
		)
		(pad "1" smd circle
			(at -0.40005 0 270)
			(size 0 0)
			(layers "F.Cu" "F.Mask" "F.Paste")
			(net "USB_HUB2_TI_PWRCTL_POL")
		)
		(pad "2" smd circle
			(at 0.40005 0 270)
			(size 0 0)
			(layers "F.Cu" "F.Mask" "F.Paste")
			(net "USB_HUB2_TI_PWRCTL_POL_MRP_VBUS_DET")
		)
	)
	(footprint ""
		(layer "F.Cu")
		(at 208.894426 -114.249708 180)
		(property "Reference" "R4608"
			(at 0 0 180)
			(layer "F.SilkS")
			(hide yes)
			(effects
				(font
					(size 1.27 1.27)
				)
			)
		)
		(property "Value" ""
			(at 0 0 180)
			(layer "F.Fab")
			(effects
				(font
					(size 1.27 1.27)
				)
			)
		)
		(duplicate_pad_numbers_are_jumpers no)
		(fp_line
			(start 0.7874 0.4064)
			(end -0.7874 0.4064)
			(stroke
				(width 0.1524)
				(type default)
			)
			(layer "F.SilkS")
		)
		(fp_line
			(start 0.7874 -0.4064)
			(end 0.7874 0.4064)
			(stroke
				(width 0.1524)
				(type default)
			)
			(layer "F.SilkS")
		)
		(fp_line
			(start -0.7874 0.4064)
			(end -0.7874 -0.4064)
			(stroke
				(width 0.1524)
				(type default)
			)
			(layer "F.SilkS")
		)
		(fp_line
			(start -0.7874 -0.4064)
			(end 0.7874 -0.4064)
			(stroke
				(width 0.1524)
				(type default)
			)
			(layer "F.SilkS")
		)
		(fp_line
			(start 0.67945 0.3048)
			(end 0.120396 0.3048)
			(stroke
				(width 0.1)
				(type default)
			)
			(layer "F.Fab")
		)
		(fp_line
			(start 0.67945 -0.3048)
			(end 0.67945 0.3048)
			(stroke
				(width 0.1)
				(type default)
			)
			(layer "F.Fab")
		)
		(fp_line
			(start 0.12065 -0.2794)
			(end 0.12065 -0.3048)
			(stroke
				(width 0.1)
				(type default)
			)
			(layer "F.Fab")
		)
		(fp_line
			(start 0.12065 -0.3048)
			(end 0.67945 -0.3048)
			(stroke
				(width 0.1)
				(type default)
			)
			(layer "F.Fab")
		)
		(fp_line
			(start 0.120396 0.3048)
			(end 0.120396 0.2794)
			(stroke
				(width 0.1)
				(type default)
			)
			(layer "F.Fab")
		)
		(fp_line
			(start 0.120396 0.2794)
			(end -0.12065 0.2794)
			(stroke
				(width 0.1)
				(type default)
			)
			(layer "F.Fab")
		)
		(fp_line
			(start -0.12065 0.3048)
			(end -0.67945 0.3048)
			(stroke
				(width 0.1)
				(type default)
			)
			(layer "F.Fab")
		)
		(fp_line
			(start -0.12065 0.2794)
			(end -0.12065 0.3048)
			(stroke
				(width 0.1)
				(type default)
			)
			(layer "F.Fab")
		)
		(fp_line
			(start -0.12065 -0.2794)
			(end 0.12065 -0.2794)
			(stroke
				(width 0.1)
				(type default)
			)
			(layer "F.Fab")
		)
		(fp_line
			(start -0.12065 -0.305054)
			(end -0.12065 -0.2794)
			(stroke
				(width 0.1)
				(type default)
			)
			(layer "F.Fab")
		)
		(fp_line
			(start -0.67945 0.3048)
			(end -0.67945 -0.305054)
			(stroke
				(width 0.1)
				(type default)
			)
			(layer "F.Fab")
		)
		(fp_line
			(start -0.67945 -0.305054)
			(end -0.12065 -0.305054)
			(stroke
				(width 0.1)
				(type default)
			)
			(layer "F.Fab")
		)
		(pad "1" smd circle
			(at -0.40005 0 180)
			(size 0 0)
			(layers "F.Cu" "F.Mask" "F.Paste")
			(net "GPU_FPGA_RST_R_N")
		)
		(pad "2" smd circle
			(at 0.40005 0 180)
			(size 0 0)
			(layers "F.Cu" "F.Mask" "F.Paste")
			(net "GPU_FPGA_RST_N")
		)
	)
	(footprint ""
		(layer "F.Cu")
		(at 364.139226 -62.0903)
		(property "Reference" "R8022"
			(at 0 0 0)
			(layer "F.SilkS")
			(hide yes)
			(effects
				(font
					(size 1.27 1.27)
				)
			)
		)
		(property "Value" ""
			(at 0 0 0)
			(layer "F.Fab")
			(effects
				(font
					(size 1.27 1.27)
				)
			)
		)
		(duplicate_pad_numbers_are_jumpers no)
		(fp_line
			(start -0.7874 -0.4064)
			(end 0.7874 -0.4064)
			(stroke
				(width 0.1524)
				(type default)
			)
			(layer "F.SilkS")
		)
		(fp_line
			(start -0.7874 0.4064)
			(end -0.7874 -0.4064)
			(stroke
				(width 0.1524)
				(type default)
			)
			(layer "F.SilkS")
		)
		(fp_line
			(start 0.7874 -0.4064)
			(end 0.7874 0.4064)
			(stroke
				(width 0.1524)
				(type default)
			)
			(layer "F.SilkS")
		)
		(fp_line
			(start 0.7874 0.4064)
			(end -0.7874 0.4064)
			(stroke
				(width 0.1524)
				(type default)
			)
			(layer "F.SilkS")
		)
		(fp_line
			(start -0.67945 -0.305054)
			(end -0.12065 -0.305054)
			(stroke
				(width 0.1)
				(type default)
			)
			(layer "F.Fab")
		)
		(fp_line
			(start -0.67945 0.3048)
			(end -0.67945 -0.305054)
			(stroke
				(width 0.1)
				(type default)
			)
			(layer "F.Fab")
		)
		(fp_line
			(start -0.12065 -0.305054)
			(end -0.12065 -0.2794)
			(stroke
				(width 0.1)
				(type default)
			)
			(layer "F.Fab")
		)
		(fp_line
			(start -0.12065 -0.2794)
			(end 0.12065 -0.2794)
			(stroke
				(width 0.1)
				(type default)
			)
			(layer "F.Fab")
		)
		(fp_line
			(start -0.12065 0.2794)
			(end -0.12065 0.3048)
			(stroke
				(width 0.1)
				(type default)
			)
			(layer "F.Fab")
		)
		(fp_line
			(start -0.12065 0.3048)
			(end -0.67945 0.3048)
			(stroke
				(width 0.1)
				(type default)
			)
			(layer "F.Fab")
		)
		(fp_line
			(start 0.120396 0.2794)
			(end -0.12065 0.2794)
			(stroke
				(width 0.1)
				(type default)
			)
			(layer "F.Fab")
		)
		(fp_line
			(start 0.120396 0.3048)
			(end 0.120396 0.2794)
			(stroke
				(width 0.1)
				(type default)
			)
			(layer "F.Fab")
		)
		(fp_line
			(start 0.12065 -0.3048)
			(end 0.67945 -0.3048)
			(stroke
				(width 0.1)
				(type default)
			)
			(layer "F.Fab")
		)
		(fp_line
			(start 0.12065 -0.2794)
			(end 0.12065 -0.3048)
			(stroke
				(width 0.1)
				(type default)
			)
			(layer "F.Fab")
		)
		(fp_line
			(start 0.67945 -0.3048)
			(end 0.67945 0.3048)
			(stroke
				(width 0.1)
				(type default)
			)
			(layer "F.Fab")
		)
		(fp_line
			(start 0.67945 0.3048)
			(end 0.120396 0.3048)
			(stroke
				(width 0.1)
				(type default)
			)
			(layer "F.Fab")
		)
		(pad "1" smd circle
			(at -0.40005 0)
			(size 0 0)
			(layers "F.Cu" "F.Mask" "F.Paste")
			(net "LED_P12V_AUX_R1")
		)
		(pad "2" smd circle
			(at 0.40005 0)
			(size 0 0)
			(layers "F.Cu" "F.Mask" "F.Paste")
			(net "LED_P12V_AUX_R2")
		)
	)
	(footprint ""
		(layer "F.Cu")
		(at 287.996884 -370.318792 -90)
		(property "Reference" "R6086"
			(at 0 0 270)
			(layer "F.SilkS")
			(hide yes)
			(effects
				(font
					(size 1.27 1.27)
				)
			)
		)
		(property "Value" ""
			(at 0 0 270)
			(layer "F.Fab")
			(effects
				(font
					(size 1.27 1.27)
				)
			)
		)
		(duplicate_pad_numbers_are_jumpers no)
		(fp_line
			(start -0.7874 0.4064)
			(end -0.7874 -0.4064)
			(stroke
				(width 0.1524)
				(type default)
			)
			(layer "F.SilkS")
		)
		(fp_line
			(start 0.7874 0.4064)
			(end -0.7874 0.4064)
			(stroke
				(width 0.1524)
				(type default)
			)
			(layer "F.SilkS")
		)
		(fp_line
			(start -0.7874 -0.4064)
			(end 0.7874 -0.4064)
			(stroke
				(width 0.1524)
				(type default)
			)
			(layer "F.SilkS")
		)
		(fp_line
			(start 0.7874 -0.4064)
			(end 0.7874 0.4064)
			(stroke
				(width 0.1524)
				(type default)
			)
			(layer "F.SilkS")
		)
		(fp_line
			(start -0.67945 0.3048)
			(end -0.67945 -0.305054)
			(stroke
				(width 0.1)
				(type default)
			)
			(layer "F.Fab")
		)
		(fp_line
			(start -0.12065 0.3048)
			(end -0.67945 0.3048)
			(stroke
				(width 0.1)
				(type default)
			)
			(layer "F.Fab")
		)
		(fp_line
			(start 0.120396 0.3048)
			(end 0.120396 0.2794)
			(stroke
				(width 0.1)
				(type default)
			)
			(layer "F.Fab")
		)
		(fp_line
			(start 0.67945 0.3048)
			(end 0.120396 0.3048)
			(stroke
				(width 0.1)
				(type default)
			)
			(layer "F.Fab")
		)
		(fp_line
			(start -0.12065 0.2794)
			(end -0.12065 0.3048)
			(stroke
				(width 0.1)
				(type default)
			)
			(layer "F.Fab")
		)
		(fp_line
			(start 0.120396 0.2794)
			(end -0.12065 0.2794)
			(stroke
				(width 0.1)
				(type default)
			)
			(layer "F.Fab")
		)
		(fp_line
			(start -0.12065 -0.2794)
			(end 0.12065 -0.2794)
			(stroke
				(width 0.1)
				(type default)
			)
			(layer "F.Fab")
		)
		(fp_line
			(start 0.12065 -0.2794)
			(end 0.12065 -0.3048)
			(stroke
				(width 0.1)
				(type default)
			)
			(layer "F.Fab")
		)
		(fp_line
			(start 0.12065 -0.3048)
			(end 0.67945 -0.3048)
			(stroke
				(width 0.1)
				(type default)
			)
			(layer "F.Fab")
		)
		(fp_line
			(start 0.67945 -0.3048)
			(end 0.67945 0.3048)
			(stroke
				(width 0.1)
				(type default)
			)
			(layer "F.Fab")
		)
		(fp_line
			(start -0.67945 -0.305054)
			(end -0.12065 -0.305054)
			(stroke
				(width 0.1)
				(type default)
			)
			(layer "F.Fab")
		)
		(fp_line
			(start -0.12065 -0.305054)
			(end -0.12065 -0.2794)
			(stroke
				(width 0.1)
				(type default)
			)
			(layer "F.Fab")
		)
		(pad "1" smd circle
			(at -0.40005 0 270)
			(size 0 0)
			(layers "F.Cu" "F.Mask" "F.Paste")
			(net "PVDDIO_P0_EN_R")
		)
		(pad "2" smd circle
			(at 0.40005 0 270)
			(size 0 0)
			(layers "F.Cu" "F.Mask" "F.Paste")
			(net "GND")
		)
	)
	(footprint ""
		(layer "F.Cu")
		(at 163.465002 -352.652838 90)
		(property "Reference" "PC96"
			(at 0 0 90)
			(layer "F.SilkS")
			(hide yes)
			(effects
				(font
					(size 1.27 1.27)
				)
			)
		)
		(property "Value" ""
			(at 0 0 90)
			(layer "F.Fab")
			(effects
				(font
					(size 1.27 1.27)
				)
			)
		)
		(duplicate_pad_numbers_are_jumpers no)
		(fp_line
			(start 0.7874 -0.4064)
			(end 0.7874 0.4064)
			(stroke
				(width 0.1524)
				(type default)
			)
			(layer "F.SilkS")
		)
		(fp_line
			(start -0.7874 -0.4064)
			(end 0.7874 -0.4064)
			(stroke
				(width 0.1524)
				(type default)
			)
			(layer "F.SilkS")
		)
		(fp_line
			(start 0.7874 0.4064)
			(end -0.7874 0.4064)
			(stroke
				(width 0.1524)
				(type default)
			)
			(layer "F.SilkS")
		)
		(fp_line
			(start -0.7874 0.4064)
			(end -0.7874 -0.4064)
			(stroke
				(width 0.1524)
				(type default)
			)
			(layer "F.SilkS")
		)
		(fp_line
			(start -0.12065 -0.305054)
			(end -0.12065 -0.2794)
			(stroke
				(width 0.1)
				(type default)
			)
			(layer "F.Fab")
		)
		(fp_line
			(start -0.67945 -0.305054)
			(end -0.12065 -0.305054)
			(stroke
				(width 0.1)
				(type default)
			)
			(layer "F.Fab")
		)
		(fp_line
			(start 0.67945 -0.3048)
			(end 0.67945 0.3048)
			(stroke
				(width 0.1)
				(type default)
			)
			(layer "F.Fab")
		)
		(fp_line
			(start 0.12065 -0.3048)
			(end 0.67945 -0.3048)
			(stroke
				(width 0.1)
				(type default)
			)
			(layer "F.Fab")
		)
		(fp_line
			(start 0.12065 -0.2794)
			(end 0.12065 -0.3048)
			(stroke
				(width 0.1)
				(type default)
			)
			(layer "F.Fab")
		)
		(fp_line
			(start -0.12065 -0.2794)
			(end 0.12065 -0.2794)
			(stroke
				(width 0.1)
				(type default)
			)
			(layer "F.Fab")
		)
		(fp_line
			(start 0.120396 0.2794)
			(end -0.12065 0.2794)
			(stroke
				(width 0.1)
				(type default)
			)
			(layer "F.Fab")
		)
		(fp_line
			(start -0.12065 0.2794)
			(end -0.12065 0.3048)
			(stroke
				(width 0.1)
				(type default)
			)
			(layer "F.Fab")
		)
		(fp_line
			(start 0.67945 0.3048)
			(end 0.120396 0.3048)
			(stroke
				(width 0.1)
				(type default)
			)
			(layer "F.Fab")
		)
		(fp_line
			(start 0.120396 0.3048)
			(end 0.120396 0.2794)
			(stroke
				(width 0.1)
				(type default)
			)
			(layer "F.Fab")
		)
		(fp_line
			(start -0.12065 0.3048)
			(end -0.67945 0.3048)
			(stroke
				(width 0.1)
				(type default)
			)
			(layer "F.Fab")
		)
		(fp_line
			(start -0.67945 0.3048)
			(end -0.67945 -0.305054)
			(stroke
				(width 0.1)
				(type default)
			)
			(layer "F.Fab")
		)
		(pad "1" smd circle
			(at -0.40005 0 90)
			(size 0 0)
			(layers "F.Cu" "F.Mask" "F.Paste")
			(net "PVDD11_S3_P1_VCCS")
		)
		(pad "2" smd circle
			(at 0.40005 0 90)
			(size 0 0)
			(layers "F.Cu" "F.Mask" "F.Paste")
			(net "GND")
		)
	)
	(footprint ""
		(layer "F.Cu")
		(at 275.14169 -97.339404 180)
		(property "Reference" "R1643"
			(at 0 0 180)
			(layer "F.SilkS")
			(hide yes)
			(effects
				(font
					(size 1.27 1.27)
				)
			)
		)
		(property "Value" ""
			(at 0 0 180)
			(layer "F.Fab")
			(effects
				(font
					(size 1.27 1.27)
				)
			)
		)
		(duplicate_pad_numbers_are_jumpers no)
		(fp_line
			(start 0.7874 0.4064)
			(end -0.7874 0.4064)
			(stroke
				(width 0.1524)
				(type default)
			)
			(layer "F.SilkS")
		)
		(fp_line
			(start 0.7874 -0.4064)
			(end 0.7874 0.4064)
			(stroke
				(width 0.1524)
				(type default)
			)
			(layer "F.SilkS")
		)
		(fp_line
			(start -0.7874 0.4064)
			(end -0.7874 -0.4064)
			(stroke
				(width 0.1524)
				(type default)
			)
			(layer "F.SilkS")
		)
		(fp_line
			(start -0.7874 -0.4064)
			(end 0.7874 -0.4064)
			(stroke
				(width 0.1524)
				(type default)
			)
			(layer "F.SilkS")
		)
		(fp_line
			(start 0.67945 0.3048)
			(end 0.120396 0.3048)
			(stroke
				(width 0.1)
				(type default)
			)
			(layer "F.Fab")
		)
		(fp_line
			(start 0.67945 -0.3048)
			(end 0.67945 0.3048)
			(stroke
				(width 0.1)
				(type default)
			)
			(layer "F.Fab")
		)
		(fp_line
			(start 0.12065 -0.2794)
			(end 0.12065 -0.3048)
			(stroke
				(width 0.1)
				(type default)
			)
			(layer "F.Fab")
		)
		(fp_line
			(start 0.12065 -0.3048)
			(end 0.67945 -0.3048)
			(stroke
				(width 0.1)
				(type default)
			)
			(layer "F.Fab")
		)
		(fp_line
			(start 0.120396 0.3048)
			(end 0.120396 0.2794)
			(stroke
				(width 0.1)
				(type default)
			)
			(layer "F.Fab")
		)
		(fp_line
			(start 0.120396 0.2794)
			(end -0.12065 0.2794)
			(stroke
				(width 0.1)
				(type default)
			)
			(layer "F.Fab")
		)
		(fp_line
			(start -0.12065 0.3048)
			(end -0.67945 0.3048)
			(stroke
				(width 0.1)
				(type default)
			)
			(layer "F.Fab")
		)
		(fp_line
			(start -0.12065 0.2794)
			(end -0.12065 0.3048)
			(stroke
				(width 0.1)
				(type default)
			)
			(layer "F.Fab")
		)
		(fp_line
			(start -0.12065 -0.2794)
			(end 0.12065 -0.2794)
			(stroke
				(width 0.1)
				(type default)
			)
			(layer "F.Fab")
		)
		(fp_line
			(start -0.12065 -0.305054)
			(end -0.12065 -0.2794)
			(stroke
				(width 0.1)
				(type default)
			)
			(layer "F.Fab")
		)
		(fp_line
			(start -0.67945 0.3048)
			(end -0.67945 -0.305054)
			(stroke
				(width 0.1)
				(type default)
			)
			(layer "F.Fab")
		)
		(fp_line
			(start -0.67945 -0.305054)
			(end -0.12065 -0.305054)
			(stroke
				(width 0.1)
				(type default)
			)
			(layer "F.Fab")
		)
		(pad "1" smd circle
			(at -0.40005 0 180)
			(size 0 0)
			(layers "F.Cu" "F.Mask" "F.Paste")
			(net "JTAG_P1_R_TMS")
		)
		(pad "2" smd circle
			(at 0.40005 0 180)
			(size 0 0)
			(layers "F.Cu" "F.Mask" "F.Paste")
			(net "JTAG_CPU1_TMS")
		)
	)
	(footprint ""
		(layer "F.Cu")
		(at 366.64392 -396.412974 90)
		(property "Reference" "R636"
			(at 0 0 90)
			(layer "F.SilkS")
			(hide yes)
			(effects
				(font
					(size 1.27 1.27)
				)
			)
		)
		(property "Value" ""
			(at 0 0 90)
			(layer "F.Fab")
			(effects
				(font
					(size 1.27 1.27)
				)
			)
		)
		(duplicate_pad_numbers_are_jumpers no)
		(fp_line
			(start 0.32512 -0.175006)
			(end 0.32512 0.175006)
			(stroke
				(width 0.1)
				(type default)
			)
			(layer "F.Fab")
		)
		(fp_line
			(start -0.32512 -0.175006)
			(end 0.32512 -0.175006)
			(stroke
				(width 0.1)
				(type default)
			)
			(layer "F.Fab")
		)
		(fp_line
			(start 0.32512 0.175006)
			(end -0.32512 0.175006)
			(stroke
				(width 0.1)
				(type default)
			)
			(layer "F.Fab")
		)
		(fp_line
			(start -0.32512 0.175006)
			(end -0.32512 -0.175006)
			(stroke
				(width 0.1)
				(type default)
			)
			(layer "F.Fab")
		)
		(pad "1" smd rect
			(at -0.2667 0 90)
			(size 0.3048 0.381)
			(layers "F.Cu" "F.Mask" "F.Paste")
			(net "CLK_100M_RETIMER_CPU0_P3_DP")
		)
		(pad "2" smd rect
			(at 0.2667 0 270)
			(size 0.3048 0.381)
			(layers "F.Cu" "F.Mask" "F.Paste")
			(net "GND")
		)
	)
	(footprint ""
		(layer "F.Cu")
		(at 398.276318 -76.661264)
		(property "Reference" "C1108"
			(at 0 0 0)
			(layer "F.SilkS")
			(hide yes)
			(effects
				(font
					(size 1.27 1.27)
				)
			)
		)
		(property "Value" ""
			(at 0 0 0)
			(layer "F.Fab")
			(effects
				(font
					(size 1.27 1.27)
				)
			)
		)
		(duplicate_pad_numbers_are_jumpers no)
		(fp_line
			(start -0.7874 -0.4064)
			(end 0.7874 -0.4064)
			(stroke
				(width 0.1524)
				(type default)
			)
			(layer "F.SilkS")
		)
		(fp_line
			(start -0.7874 0.4064)
			(end -0.7874 -0.4064)
			(stroke
				(width 0.1524)
				(type default)
			)
			(layer "F.SilkS")
		)
		(fp_line
			(start 0.7874 -0.4064)
			(end 0.7874 0.4064)
			(stroke
				(width 0.1524)
				(type default)
			)
			(layer "F.SilkS")
		)
		(fp_line
			(start 0.7874 0.4064)
			(end -0.7874 0.4064)
			(stroke
				(width 0.1524)
				(type default)
			)
			(layer "F.SilkS")
		)
		(fp_line
			(start -0.67945 -0.305054)
			(end -0.12065 -0.305054)
			(stroke
				(width 0.1)
				(type default)
			)
			(layer "F.Fab")
		)
		(fp_line
			(start -0.67945 0.3048)
			(end -0.67945 -0.305054)
			(stroke
				(width 0.1)
				(type default)
			)
			(layer "F.Fab")
		)
		(fp_line
			(start -0.12065 -0.305054)
			(end -0.12065 -0.2794)
			(stroke
				(width 0.1)
				(type default)
			)
			(layer "F.Fab")
		)
		(fp_line
			(start -0.12065 -0.2794)
			(end 0.12065 -0.2794)
			(stroke
				(width 0.1)
				(type default)
			)
			(layer "F.Fab")
		)
		(fp_line
			(start -0.12065 0.2794)
			(end -0.12065 0.3048)
			(stroke
				(width 0.1)
				(type default)
			)
			(layer "F.Fab")
		)
		(fp_line
			(start -0.12065 0.3048)
			(end -0.67945 0.3048)
			(stroke
				(width 0.1)
				(type default)
			)
			(layer "F.Fab")
		)
		(fp_line
			(start 0.120396 0.2794)
			(end -0.12065 0.2794)
			(stroke
				(width 0.1)
				(type default)
			)
			(layer "F.Fab")
		)
		(fp_line
			(start 0.120396 0.3048)
			(end 0.120396 0.2794)
			(stroke
				(width 0.1)
				(type default)
			)
			(layer "F.Fab")
		)
		(fp_line
			(start 0.12065 -0.3048)
			(end 0.67945 -0.3048)
			(stroke
				(width 0.1)
				(type default)
			)
			(layer "F.Fab")
		)
		(fp_line
			(start 0.12065 -0.2794)
			(end 0.12065 -0.3048)
			(stroke
				(width 0.1)
				(type default)
			)
			(layer "F.Fab")
		)
		(fp_line
			(start 0.67945 -0.3048)
			(end 0.67945 0.3048)
			(stroke
				(width 0.1)
				(type default)
			)
			(layer "F.Fab")
		)
		(fp_line
			(start 0.67945 0.3048)
			(end 0.120396 0.3048)
			(stroke
				(width 0.1)
				(type default)
			)
			(layer "F.Fab")
		)
		(pad "1" smd circle
			(at -0.40005 0)
			(size 0 0)
			(layers "F.Cu" "F.Mask" "F.Paste")
			(net "P12V_OCP_SFF")
		)
		(pad "2" smd circle
			(at 0.40005 0)
			(size 0 0)
			(layers "F.Cu" "F.Mask" "F.Paste")
			(net "GND")
		)
	)
	(footprint ""
		(layer "F.Cu")
		(at 351.407222 -425.295314)
		(property "Reference" "R4562"
			(at 0 0 0)
			(layer "F.SilkS")
			(hide yes)
			(effects
				(font
					(size 1.27 1.27)
				)
			)
		)
		(property "Value" ""
			(at 0 0 0)
			(layer "F.Fab")
			(effects
				(font
					(size 1.27 1.27)
				)
			)
		)
		(duplicate_pad_numbers_are_jumpers no)
		(fp_line
			(start -0.7874 -0.4064)
			(end 0.7874 -0.4064)
			(stroke
				(width 0.1524)
				(type default)
			)
			(layer "F.SilkS")
		)
		(fp_line
			(start -0.7874 0.4064)
			(end -0.7874 -0.4064)
			(stroke
				(width 0.1524)
				(type default)
			)
			(layer "F.SilkS")
		)
		(fp_line
			(start 0.7874 -0.4064)
			(end 0.7874 0.4064)
			(stroke
				(width 0.1524)
				(type default)
			)
			(layer "F.SilkS")
		)
		(fp_line
			(start 0.7874 0.4064)
			(end -0.7874 0.4064)
			(stroke
				(width 0.1524)
				(type default)
			)
			(layer "F.SilkS")
		)
		(fp_line
			(start -0.67945 -0.305054)
			(end -0.12065 -0.305054)
			(stroke
				(width 0.1)
				(type default)
			)
			(layer "F.Fab")
		)
		(fp_line
			(start -0.67945 0.3048)
			(end -0.67945 -0.305054)
			(stroke
				(width 0.1)
				(type default)
			)
			(layer "F.Fab")
		)
		(fp_line
			(start -0.12065 -0.305054)
			(end -0.12065 -0.2794)
			(stroke
				(width 0.1)
				(type default)
			)
			(layer "F.Fab")
		)
		(fp_line
			(start -0.12065 -0.2794)
			(end 0.12065 -0.2794)
			(stroke
				(width 0.1)
				(type default)
			)
			(layer "F.Fab")
		)
		(fp_line
			(start -0.12065 0.2794)
			(end -0.12065 0.3048)
			(stroke
				(width 0.1)
				(type default)
			)
			(layer "F.Fab")
		)
		(fp_line
			(start -0.12065 0.3048)
			(end -0.67945 0.3048)
			(stroke
				(width 0.1)
				(type default)
			)
			(layer "F.Fab")
		)
		(fp_line
			(start 0.120396 0.2794)
			(end -0.12065 0.2794)
			(stroke
				(width 0.1)
				(type default)
			)
			(layer "F.Fab")
		)
		(fp_line
			(start 0.120396 0.3048)
			(end 0.120396 0.2794)
			(stroke
				(width 0.1)
				(type default)
			)
			(layer "F.Fab")
		)
		(fp_line
			(start 0.12065 -0.3048)
			(end 0.67945 -0.3048)
			(stroke
				(width 0.1)
				(type default)
			)
			(layer "F.Fab")
		)
		(fp_line
			(start 0.12065 -0.2794)
			(end 0.12065 -0.3048)
			(stroke
				(width 0.1)
				(type default)
			)
			(layer "F.Fab")
		)
		(fp_line
			(start 0.67945 -0.3048)
			(end 0.67945 0.3048)
			(stroke
				(width 0.1)
				(type default)
			)
			(layer "F.Fab")
		)
		(fp_line
			(start 0.67945 0.3048)
			(end 0.120396 0.3048)
			(stroke
				(width 0.1)
				(type default)
			)
			(layer "F.Fab")
		)
		(pad "1" smd circle
			(at -0.40005 0)
			(size 0 0)
			(layers "F.Cu" "F.Mask" "F.Paste")
			(net "P3V3_AUX")
		)
		(pad "2" smd circle
			(at 0.40005 0)
			(size 0 0)
			(layers "F.Cu" "F.Mask" "F.Paste")
			(net "SWB_HSC_PWRGD")
		)
	)
	(footprint ""
		(layer "F.Cu")
		(at 169.349166 -416.929316 90)
		(property "Reference" "R812"
			(at 0 0 90)
			(layer "F.SilkS")
			(hide yes)
			(effects
				(font
					(size 1.27 1.27)
				)
			)
		)
		(property "Value" ""
			(at 0 0 90)
			(layer "F.Fab")
			(effects
				(font
					(size 1.27 1.27)
				)
			)
		)
		(duplicate_pad_numbers_are_jumpers no)
		(fp_line
			(start 0.32512 -0.175006)
			(end 0.32512 0.175006)
			(stroke
				(width 0.1)
				(type default)
			)
			(layer "F.Fab")
		)
		(fp_line
			(start -0.32512 -0.175006)
			(end 0.32512 -0.175006)
			(stroke
				(width 0.1)
				(type default)
			)
			(layer "F.Fab")
		)
		(fp_line
			(start 0.32512 0.175006)
			(end -0.32512 0.175006)
			(stroke
				(width 0.1)
				(type default)
			)
			(layer "F.Fab")
		)
		(fp_line
			(start -0.32512 0.175006)
			(end -0.32512 -0.175006)
			(stroke
				(width 0.1)
				(type default)
			)
			(layer "F.Fab")
		)
		(pad "1" smd rect
			(at -0.2667 0 90)
			(size 0.3048 0.381)
			(layers "F.Cu" "F.Mask" "F.Paste")
			(net "P1V8_CPU1_RT_1D")
		)
		(pad "2" smd rect
			(at 0.2667 0 270)
			(size 0.3048 0.381)
			(layers "F.Cu" "F.Mask" "F.Paste")
			(net "SMB_RT_CPU1_P3_ROM_R_SCL")
		)
	)
	(footprint ""
		(layer "F.Cu")
		(at 27.561794 -393.317984 -90)
		(property "Reference" "PC6640"
			(at 0 0 270)
			(layer "F.SilkS")
			(hide yes)
			(effects
				(font
					(size 1.27 1.27)
				)
			)
		)
		(property "Value" ""
			(at 0 0 270)
			(layer "F.Fab")
			(effects
				(font
					(size 1.27 1.27)
				)
			)
		)
		(duplicate_pad_numbers_are_jumpers no)
		(fp_line
			(start -0.7874 0.4064)
			(end -0.7874 -0.4064)
			(stroke
				(width 0.1524)
				(type default)
			)
			(layer "F.SilkS")
		)
		(fp_line
			(start 0.7874 0.4064)
			(end -0.7874 0.4064)
			(stroke
				(width 0.1524)
				(type default)
			)
			(layer "F.SilkS")
		)
		(fp_line
			(start -0.7874 -0.4064)
			(end 0.7874 -0.4064)
			(stroke
				(width 0.1524)
				(type default)
			)
			(layer "F.SilkS")
		)
		(fp_line
			(start 0.7874 -0.4064)
			(end 0.7874 0.4064)
			(stroke
				(width 0.1524)
				(type default)
			)
			(layer "F.SilkS")
		)
		(fp_line
			(start -0.67945 0.3048)
			(end -0.67945 -0.305054)
			(stroke
				(width 0.1)
				(type default)
			)
			(layer "F.Fab")
		)
		(fp_line
			(start -0.12065 0.3048)
			(end -0.67945 0.3048)
			(stroke
				(width 0.1)
				(type default)
			)
			(layer "F.Fab")
		)
		(fp_line
			(start 0.120396 0.3048)
			(end 0.120396 0.2794)
			(stroke
				(width 0.1)
				(type default)
			)
			(layer "F.Fab")
		)
		(fp_line
			(start 0.67945 0.3048)
			(end 0.120396 0.3048)
			(stroke
				(width 0.1)
				(type default)
			)
			(layer "F.Fab")
		)
		(fp_line
			(start -0.12065 0.2794)
			(end -0.12065 0.3048)
			(stroke
				(width 0.1)
				(type default)
			)
			(layer "F.Fab")
		)
		(fp_line
			(start 0.120396 0.2794)
			(end -0.12065 0.2794)
			(stroke
				(width 0.1)
				(type default)
			)
			(layer "F.Fab")
		)
		(fp_line
			(start -0.12065 -0.2794)
			(end 0.12065 -0.2794)
			(stroke
				(width 0.1)
				(type default)
			)
			(layer "F.Fab")
		)
		(fp_line
			(start 0.12065 -0.2794)
			(end 0.12065 -0.3048)
			(stroke
				(width 0.1)
				(type default)
			)
			(layer "F.Fab")
		)
		(fp_line
			(start 0.12065 -0.3048)
			(end 0.67945 -0.3048)
			(stroke
				(width 0.1)
				(type default)
			)
			(layer "F.Fab")
		)
		(fp_line
			(start 0.67945 -0.3048)
			(end 0.67945 0.3048)
			(stroke
				(width 0.1)
				(type default)
			)
			(layer "F.Fab")
		)
		(fp_line
			(start -0.67945 -0.305054)
			(end -0.12065 -0.305054)
			(stroke
				(width 0.1)
				(type default)
			)
			(layer "F.Fab")
		)
		(fp_line
			(start -0.12065 -0.305054)
			(end -0.12065 -0.2794)
			(stroke
				(width 0.1)
				(type default)
			)
			(layer "F.Fab")
		)
		(pad "1" smd circle
			(at -0.40005 0 270)
			(size 0 0)
			(layers "F.Cu" "F.Mask" "F.Paste")
			(net "SW_P0V9_RETIMER_CPU1_BOOT2_RC")
		)
		(pad "2" smd circle
			(at 0.40005 0 270)
			(size 0 0)
			(layers "F.Cu" "F.Mask" "F.Paste")
			(net "SW_P0V9_RETIMER_CPU1_PH2")
		)
	)
	(footprint ""
		(layer "F.Cu")
		(at 419.391084 -423.777664 90)
		(property "Reference" "R683"
			(at 0 0 90)
			(layer "F.SilkS")
			(hide yes)
			(effects
				(font
					(size 1.27 1.27)
				)
			)
		)
		(property "Value" ""
			(at 0 0 90)
			(layer "F.Fab")
			(effects
				(font
					(size 1.27 1.27)
				)
			)
		)
		(duplicate_pad_numbers_are_jumpers no)
		(fp_line
			(start 0.32512 -0.175006)
			(end 0.32512 0.175006)
			(stroke
				(width 0.1)
				(type default)
			)
			(layer "F.Fab")
		)
		(fp_line
			(start -0.32512 -0.175006)
			(end 0.32512 -0.175006)
			(stroke
				(width 0.1)
				(type default)
			)
			(layer "F.Fab")
		)
		(fp_line
			(start 0.32512 0.175006)
			(end -0.32512 0.175006)
			(stroke
				(width 0.1)
				(type default)
			)
			(layer "F.Fab")
		)
		(fp_line
			(start -0.32512 0.175006)
			(end -0.32512 -0.175006)
			(stroke
				(width 0.1)
				(type default)
			)
			(layer "F.Fab")
		)
		(pad "1" smd rect
			(at -0.2667 0 90)
			(size 0.3048 0.381)
			(layers "F.Cu" "F.Mask" "F.Paste")
			(net "SMB_RT_CPU0_P2_ROM_R_SDA")
		)
		(pad "2" smd rect
			(at 0.2667 0 270)
			(size 0.3048 0.381)
			(layers "F.Cu" "F.Mask" "F.Paste")
			(net "SMB_RT_CPU0_P2_ROM_SDA")
		)
	)
	(footprint ""
		(layer "F.Cu")
		(at 413.766 -98.425 90)
		(property "Reference" "R8092"
			(at 0 0 90)
			(layer "F.SilkS")
			(hide yes)
			(effects
				(font
					(size 1.27 1.27)
				)
			)
		)
		(property "Value" ""
			(at 0 0 90)
			(layer "F.Fab")
			(effects
				(font
					(size 1.27 1.27)
				)
			)
		)
		(duplicate_pad_numbers_are_jumpers no)
		(fp_line
			(start 0.7874 -0.4064)
			(end 0.7874 0.4064)
			(stroke
				(width 0.1524)
				(type default)
			)
			(layer "F.SilkS")
		)
		(fp_line
			(start -0.7874 -0.4064)
			(end 0.7874 -0.4064)
			(stroke
				(width 0.1524)
				(type default)
			)
			(layer "F.SilkS")
		)
		(fp_line
			(start 0.7874 0.4064)
			(end -0.7874 0.4064)
			(stroke
				(width 0.1524)
				(type default)
			)
			(layer "F.SilkS")
		)
		(fp_line
			(start -0.7874 0.4064)
			(end -0.7874 -0.4064)
			(stroke
				(width 0.1524)
				(type default)
			)
			(layer "F.SilkS")
		)
		(fp_line
			(start -0.12065 -0.305054)
			(end -0.12065 -0.2794)
			(stroke
				(width 0.1)
				(type default)
			)
			(layer "F.Fab")
		)
		(fp_line
			(start -0.67945 -0.305054)
			(end -0.12065 -0.305054)
			(stroke
				(width 0.1)
				(type default)
			)
			(layer "F.Fab")
		)
		(fp_line
			(start 0.67945 -0.3048)
			(end 0.67945 0.3048)
			(stroke
				(width 0.1)
				(type default)
			)
			(layer "F.Fab")
		)
		(fp_line
			(start 0.12065 -0.3048)
			(end 0.67945 -0.3048)
			(stroke
				(width 0.1)
				(type default)
			)
			(layer "F.Fab")
		)
		(fp_line
			(start 0.12065 -0.2794)
			(end 0.12065 -0.3048)
			(stroke
				(width 0.1)
				(type default)
			)
			(layer "F.Fab")
		)
		(fp_line
			(start -0.12065 -0.2794)
			(end 0.12065 -0.2794)
			(stroke
				(width 0.1)
				(type default)
			)
			(layer "F.Fab")
		)
		(fp_line
			(start 0.120396 0.2794)
			(end -0.12065 0.2794)
			(stroke
				(width 0.1)
				(type default)
			)
			(layer "F.Fab")
		)
		(fp_line
			(start -0.12065 0.2794)
			(end -0.12065 0.3048)
			(stroke
				(width 0.1)
				(type default)
			)
			(layer "F.Fab")
		)
		(fp_line
			(start 0.67945 0.3048)
			(end 0.120396 0.3048)
			(stroke
				(width 0.1)
				(type default)
			)
			(layer "F.Fab")
		)
		(fp_line
			(start 0.120396 0.3048)
			(end 0.120396 0.2794)
			(stroke
				(width 0.1)
				(type default)
			)
			(layer "F.Fab")
		)
		(fp_line
			(start -0.12065 0.3048)
			(end -0.67945 0.3048)
			(stroke
				(width 0.1)
				(type default)
			)
			(layer "F.Fab")
		)
		(fp_line
			(start -0.67945 0.3048)
			(end -0.67945 -0.305054)
			(stroke
				(width 0.1)
				(type default)
			)
			(layer "F.Fab")
		)
		(pad "1" smd circle
			(at -0.40005 0 90)
			(size 0 0)
			(layers "F.Cu" "F.Mask" "F.Paste")
			(net "P3V3_OCP_SFF_R")
		)
		(pad "2" smd circle
			(at 0.40005 0 90)
			(size 0 0)
			(layers "F.Cu" "F.Mask" "F.Paste")
			(net "OCP_V3_1_P3V3_R1_PWRGD")
		)
	)
	(footprint ""
		(layer "F.Cu")
		(at 432.636676 -94.938342)
		(property "Reference" "R3603"
			(at 0 0 0)
			(layer "F.SilkS")
			(hide yes)
			(effects
				(font
					(size 1.27 1.27)
				)
			)
		)
		(property "Value" ""
			(at 0 0 0)
			(layer "F.Fab")
			(effects
				(font
					(size 1.27 1.27)
				)
			)
		)
		(duplicate_pad_numbers_are_jumpers no)
		(fp_line
			(start -0.7874 -0.4064)
			(end 0.7874 -0.4064)
			(stroke
				(width 0.1524)
				(type default)
			)
			(layer "F.SilkS")
		)
		(fp_line
			(start -0.7874 0.4064)
			(end -0.7874 -0.4064)
			(stroke
				(width 0.1524)
				(type default)
			)
			(layer "F.SilkS")
		)
		(fp_line
			(start 0.7874 -0.4064)
			(end 0.7874 0.4064)
			(stroke
				(width 0.1524)
				(type default)
			)
			(layer "F.SilkS")
		)
		(fp_line
			(start 0.7874 0.4064)
			(end -0.7874 0.4064)
			(stroke
				(width 0.1524)
				(type default)
			)
			(layer "F.SilkS")
		)
		(fp_line
			(start -0.67945 -0.305054)
			(end -0.12065 -0.305054)
			(stroke
				(width 0.1)
				(type default)
			)
			(layer "F.Fab")
		)
		(fp_line
			(start -0.67945 0.3048)
			(end -0.67945 -0.305054)
			(stroke
				(width 0.1)
				(type default)
			)
			(layer "F.Fab")
		)
		(fp_line
			(start -0.12065 -0.305054)
			(end -0.12065 -0.2794)
			(stroke
				(width 0.1)
				(type default)
			)
			(layer "F.Fab")
		)
		(fp_line
			(start -0.12065 -0.2794)
			(end 0.12065 -0.2794)
			(stroke
				(width 0.1)
				(type default)
			)
			(layer "F.Fab")
		)
		(fp_line
			(start -0.12065 0.2794)
			(end -0.12065 0.3048)
			(stroke
				(width 0.1)
				(type default)
			)
			(layer "F.Fab")
		)
		(fp_line
			(start -0.12065 0.3048)
			(end -0.67945 0.3048)
			(stroke
				(width 0.1)
				(type default)
			)
			(layer "F.Fab")
		)
		(fp_line
			(start 0.120396 0.2794)
			(end -0.12065 0.2794)
			(stroke
				(width 0.1)
				(type default)
			)
			(layer "F.Fab")
		)
		(fp_line
			(start 0.120396 0.3048)
			(end 0.120396 0.2794)
			(stroke
				(width 0.1)
				(type default)
			)
			(layer "F.Fab")
		)
		(fp_line
			(start 0.12065 -0.3048)
			(end 0.67945 -0.3048)
			(stroke
				(width 0.1)
				(type default)
			)
			(layer "F.Fab")
		)
		(fp_line
			(start 0.12065 -0.2794)
			(end 0.12065 -0.3048)
			(stroke
				(width 0.1)
				(type default)
			)
			(layer "F.Fab")
		)
		(fp_line
			(start 0.67945 -0.3048)
			(end 0.67945 0.3048)
			(stroke
				(width 0.1)
				(type default)
			)
			(layer "F.Fab")
		)
		(fp_line
			(start 0.67945 0.3048)
			(end 0.120396 0.3048)
			(stroke
				(width 0.1)
				(type default)
			)
			(layer "F.Fab")
		)
		(pad "1" smd circle
			(at -0.40005 0)
			(size 0 0)
			(layers "F.Cu" "F.Mask" "F.Paste")
			(net "P3V3_OCP_SFF")
		)
		(pad "2" smd circle
			(at 0.40005 0)
			(size 0 0)
			(layers "F.Cu" "F.Mask" "F.Paste")
			(net "VSENSE_P3V3_INA230_1_INN")
		)
	)
	(footprint ""
		(layer "F.Cu")
		(at 155.605226 -408.517344 -90)
		(property "Reference" "C6719"
			(at 0 0 270)
			(layer "F.SilkS")
			(hide yes)
			(effects
				(font
					(size 1.27 1.27)
				)
			)
		)
		(property "Value" ""
			(at 0 0 270)
			(layer "F.Fab")
			(effects
				(font
					(size 1.27 1.27)
				)
			)
		)
		(duplicate_pad_numbers_are_jumpers no)
		(fp_line
			(start -0.299974 0.150114)
			(end -0.299974 -0.150114)
			(stroke
				(width 0.1)
				(type default)
			)
			(layer "F.Fab")
		)
		(fp_line
			(start 0.299974 0.150114)
			(end -0.299974 0.150114)
			(stroke
				(width 0.1)
				(type default)
			)
			(layer "F.Fab")
		)
		(fp_line
			(start -0.299974 -0.150114)
			(end 0.299974 -0.150114)
			(stroke
				(width 0.1)
				(type default)
			)
			(layer "F.Fab")
		)
		(fp_line
			(start 0.299974 -0.150114)
			(end 0.299974 0.150114)
			(stroke
				(width 0.1)
				(type default)
			)
			(layer "F.Fab")
		)
		(pad "1" smd rect
			(at -0.2667 0 270)
			(size 0.3048 0.381)
			(layers "F.Cu" "F.Mask" "F.Paste")
			(net "P5E_CPU1_P2_TX_BUF_C_DP<13>")
		)
		(pad "2" smd rect
			(at 0.2667 0 270)
			(size 0.3048 0.381)
			(layers "F.Cu" "F.Mask" "F.Paste")
			(net "P5E_CPU1_P2_TX_BUF_DP<13>")
		)
	)
	(footprint ""
		(layer "F.Cu")
		(at 11.665458 -423.821098 180)
		(property "Reference" "R6172"
			(at 0 0 180)
			(layer "F.SilkS")
			(hide yes)
			(effects
				(font
					(size 1.27 1.27)
				)
			)
		)
		(property "Value" ""
			(at 0 0 180)
			(layer "F.Fab")
			(effects
				(font
					(size 1.27 1.27)
				)
			)
		)
		(duplicate_pad_numbers_are_jumpers no)
		(fp_line
			(start 0.7874 0.4064)
			(end -0.7874 0.4064)
			(stroke
				(width 0.1524)
				(type default)
			)
			(layer "F.SilkS")
		)
		(fp_line
			(start 0.7874 -0.4064)
			(end 0.7874 0.4064)
			(stroke
				(width 0.1524)
				(type default)
			)
			(layer "F.SilkS")
		)
		(fp_line
			(start -0.7874 0.4064)
			(end -0.7874 -0.4064)
			(stroke
				(width 0.1524)
				(type default)
			)
			(layer "F.SilkS")
		)
		(fp_line
			(start -0.7874 -0.4064)
			(end 0.7874 -0.4064)
			(stroke
				(width 0.1524)
				(type default)
			)
			(layer "F.SilkS")
		)
		(fp_line
			(start 0.67945 0.3048)
			(end 0.120396 0.3048)
			(stroke
				(width 0.1)
				(type default)
			)
			(layer "F.Fab")
		)
		(fp_line
			(start 0.67945 -0.3048)
			(end 0.67945 0.3048)
			(stroke
				(width 0.1)
				(type default)
			)
			(layer "F.Fab")
		)
		(fp_line
			(start 0.12065 -0.2794)
			(end 0.12065 -0.3048)
			(stroke
				(width 0.1)
				(type default)
			)
			(layer "F.Fab")
		)
		(fp_line
			(start 0.12065 -0.3048)
			(end 0.67945 -0.3048)
			(stroke
				(width 0.1)
				(type default)
			)
			(layer "F.Fab")
		)
		(fp_line
			(start 0.120396 0.3048)
			(end 0.120396 0.2794)
			(stroke
				(width 0.1)
				(type default)
			)
			(layer "F.Fab")
		)
		(fp_line
			(start 0.120396 0.2794)
			(end -0.12065 0.2794)
			(stroke
				(width 0.1)
				(type default)
			)
			(layer "F.Fab")
		)
		(fp_line
			(start -0.12065 0.3048)
			(end -0.67945 0.3048)
			(stroke
				(width 0.1)
				(type default)
			)
			(layer "F.Fab")
		)
		(fp_line
			(start -0.12065 0.2794)
			(end -0.12065 0.3048)
			(stroke
				(width 0.1)
				(type default)
			)
			(layer "F.Fab")
		)
		(fp_line
			(start -0.12065 -0.2794)
			(end 0.12065 -0.2794)
			(stroke
				(width 0.1)
				(type default)
			)
			(layer "F.Fab")
		)
		(fp_line
			(start -0.12065 -0.305054)
			(end -0.12065 -0.2794)
			(stroke
				(width 0.1)
				(type default)
			)
			(layer "F.Fab")
		)
		(fp_line
			(start -0.67945 0.3048)
			(end -0.67945 -0.305054)
			(stroke
				(width 0.1)
				(type default)
			)
			(layer "F.Fab")
		)
		(fp_line
			(start -0.67945 -0.305054)
			(end -0.12065 -0.305054)
			(stroke
				(width 0.1)
				(type default)
			)
			(layer "F.Fab")
		)
		(pad "1" smd circle
			(at -0.40005 0 180)
			(size 0 0)
			(layers "F.Cu" "F.Mask" "F.Paste")
			(net "FM_P2E_BUF2_EQA1")
		)
		(pad "2" smd circle
			(at 0.40005 0 180)
			(size 0 0)
			(layers "F.Cu" "F.Mask" "F.Paste")
			(net "GND")
		)
	)
	(footprint ""
		(layer "F.Cu")
		(at 101.044502 -370.57203 -90)
		(property "Reference" "C715"
			(at 0 0 270)
			(layer "F.SilkS")
			(hide yes)
			(effects
				(font
					(size 1.27 1.27)
				)
			)
		)
		(property "Value" ""
			(at 0 0 270)
			(layer "F.Fab")
			(effects
				(font
					(size 1.27 1.27)
				)
			)
		)
		(duplicate_pad_numbers_are_jumpers no)
		(fp_line
			(start -0.299974 0.150114)
			(end -0.299974 -0.150114)
			(stroke
				(width 0.1)
				(type default)
			)
			(layer "F.Fab")
		)
		(fp_line
			(start 0.299974 0.150114)
			(end -0.299974 0.150114)
			(stroke
				(width 0.1)
				(type default)
			)
			(layer "F.Fab")
		)
		(fp_line
			(start -0.299974 -0.150114)
			(end 0.299974 -0.150114)
			(stroke
				(width 0.1)
				(type default)
			)
			(layer "F.Fab")
		)
		(fp_line
			(start 0.299974 -0.150114)
			(end 0.299974 0.150114)
			(stroke
				(width 0.1)
				(type default)
			)
			(layer "F.Fab")
		)
		(pad "1" smd rect
			(at -0.2667 0 270)
			(size 0.3048 0.381)
			(layers "F.Cu" "F.Mask" "F.Paste")
			(net "P5E_CPU1_P1_TX_C_DP<13>")
		)
		(pad "2" smd rect
			(at 0.2667 0 270)
			(size 0.3048 0.381)
			(layers "F.Cu" "F.Mask" "F.Paste")
			(net "P5E_CPU1_P1_TX_DP<13>")
		)
	)
	(footprint ""
		(layer "F.Cu")
		(at 465.169504 -41.105836 180)
		(property "Reference" "Q123"
			(at 1.585214 2.068068 0)
			(unlocked yes)
			(layer "F.SilkS")
			(effects
				(font
					(size 0.7874 0.5842)
					(thickness 0.1524)
				)
				(justify left)
			)
		)
		(property "Value" ""
			(at 0 0 180)
			(layer "F.Fab")
			(effects
				(font
					(size 1.27 1.27)
				)
			)
		)
		(duplicate_pad_numbers_are_jumpers no)
		(fp_line
			(start 1.332738 1.100074)
			(end -1.332738 1.100074)
			(stroke
				(width 0.1524)
				(type default)
			)
			(layer "F.SilkS")
		)
		(fp_line
			(start 1.332738 -1.100074)
			(end 1.332738 1.100074)
			(stroke
				(width 0.1524)
				(type default)
			)
			(layer "F.SilkS")
		)
		(fp_line
			(start 0.4826 -1.100074)
			(end 1.332738 -1.100074)
			(stroke
				(width 0.1524)
				(type default)
			)
			(layer "F.SilkS")
		)
		(fp_line
			(start 0 -0.541274)
			(end 0.4826 -1.100074)
			(stroke
				(width 0.1524)
				(type default)
			)
			(layer "F.SilkS")
		)
		(fp_line
			(start -0.4826 -1.100074)
			(end 0 -0.541274)
			(stroke
				(width 0.1524)
				(type default)
			)
			(layer "F.SilkS")
		)
		(fp_line
			(start -1.332738 1.100074)
			(end -1.332738 -1.100074)
			(stroke
				(width 0.1524)
				(type default)
			)
			(layer "F.SilkS")
		)
		(fp_line
			(start -1.332738 -1.100074)
			(end -0.4826 -1.100074)
			(stroke
				(width 0.1524)
				(type default)
			)
			(layer "F.SilkS")
		)
		(fp_poly
			(pts
				(xy -1.489456 -1.189482) (xy -2.23393 -1.43764) (xy -1.737614 -1.933956)
			)
			(stroke
				(width 0)
				(type default)
			)
			(fill yes)
			(layer "F.SilkS")
		)
		(fp_line
			(start 0.674878 1.100074)
			(end -0.674878 1.100074)
			(stroke
				(width 0.1)
				(type default)
			)
			(layer "F.Fab")
		)
		(fp_line
			(start 0.674878 -1.100074)
			(end 0.674878 1.100074)
			(stroke
				(width 0.1)
				(type default)
			)
			(layer "F.Fab")
		)
		(fp_line
			(start -0.674878 1.100074)
			(end -0.674878 -1.100074)
			(stroke
				(width 0.1)
				(type default)
			)
			(layer "F.Fab")
		)
		(fp_line
			(start -0.674878 -1.100074)
			(end 0.674878 -1.100074)
			(stroke
				(width 0.1)
				(type default)
			)
			(layer "F.Fab")
		)
		(fp_poly
			(pts
				(xy -2.2352 -0.298958) (xy -2.2352 -1.001014) (xy -1.533144 -0.649986)
			)
			(stroke
				(width 0)
				(type default)
			)
			(fill yes)
			(layer "F.Fab")
		)
		(pad "1" smd rect
			(at -0.94996 -0.649986 270)
			(size 0.4318 0.508)
			(layers "F.Cu" "F.Mask" "F.Paste")
			(net "GND")
		)
		(pad "2" smd rect
			(at -0.94996 0 270)
			(size 0.4318 0.508)
			(layers "F.Cu" "F.Mask" "F.Paste")
			(net "P12V_OCP_EN_1_R")
		)
		(pad "3" smd rect
			(at -0.94996 0.649986 270)
			(size 0.4318 0.508)
			(layers "F.Cu" "F.Mask" "F.Paste")
			(net "P12V_OCP_UV_1_R")
		)
		(pad "4" smd rect
			(at 0.94996 0.649986 270)
			(size 0.4318 0.508)
			(layers "F.Cu" "F.Mask" "F.Paste")
			(net "GND")
		)
		(pad "5" smd rect
			(at 0.94996 0 270)
			(size 0.4318 0.508)
			(layers "F.Cu" "F.Mask" "F.Paste")
			(net "P12V_OCP_1_EN_G")
		)
		(pad "6" smd rect
			(at 0.94996 -0.649986 270)
			(size 0.4318 0.508)
			(layers "F.Cu" "F.Mask" "F.Paste")
			(net "P12V_OCP_1_EN_G")
		)
	)
	(footprint ""
		(layer "F.Cu")
		(at 9.74471 -78.180692)
		(property "Reference" "R3135"
			(at 0 0 0)
			(layer "F.SilkS")
			(hide yes)
			(effects
				(font
					(size 1.27 1.27)
				)
			)
		)
		(property "Value" ""
			(at 0 0 0)
			(layer "F.Fab")
			(effects
				(font
					(size 1.27 1.27)
				)
			)
		)
		(duplicate_pad_numbers_are_jumpers no)
		(fp_line
			(start -0.7874 -0.4064)
			(end 0.7874 -0.4064)
			(stroke
				(width 0.1524)
				(type default)
			)
			(layer "F.SilkS")
		)
		(fp_line
			(start -0.7874 0.4064)
			(end -0.7874 -0.4064)
			(stroke
				(width 0.1524)
				(type default)
			)
			(layer "F.SilkS")
		)
		(fp_line
			(start 0.7874 -0.4064)
			(end 0.7874 0.4064)
			(stroke
				(width 0.1524)
				(type default)
			)
			(layer "F.SilkS")
		)
		(fp_line
			(start 0.7874 0.4064)
			(end -0.7874 0.4064)
			(stroke
				(width 0.1524)
				(type default)
			)
			(layer "F.SilkS")
		)
		(fp_line
			(start -0.67945 -0.305054)
			(end -0.12065 -0.305054)
			(stroke
				(width 0.1)
				(type default)
			)
			(layer "F.Fab")
		)
		(fp_line
			(start -0.67945 0.3048)
			(end -0.67945 -0.305054)
			(stroke
				(width 0.1)
				(type default)
			)
			(layer "F.Fab")
		)
		(fp_line
			(start -0.12065 -0.305054)
			(end -0.12065 -0.2794)
			(stroke
				(width 0.1)
				(type default)
			)
			(layer "F.Fab")
		)
		(fp_line
			(start -0.12065 -0.2794)
			(end 0.12065 -0.2794)
			(stroke
				(width 0.1)
				(type default)
			)
			(layer "F.Fab")
		)
		(fp_line
			(start -0.12065 0.2794)
			(end -0.12065 0.3048)
			(stroke
				(width 0.1)
				(type default)
			)
			(layer "F.Fab")
		)
		(fp_line
			(start -0.12065 0.3048)
			(end -0.67945 0.3048)
			(stroke
				(width 0.1)
				(type default)
			)
			(layer "F.Fab")
		)
		(fp_line
			(start 0.120396 0.2794)
			(end -0.12065 0.2794)
			(stroke
				(width 0.1)
				(type default)
			)
			(layer "F.Fab")
		)
		(fp_line
			(start 0.120396 0.3048)
			(end 0.120396 0.2794)
			(stroke
				(width 0.1)
				(type default)
			)
			(layer "F.Fab")
		)
		(fp_line
			(start 0.12065 -0.3048)
			(end 0.67945 -0.3048)
			(stroke
				(width 0.1)
				(type default)
			)
			(layer "F.Fab")
		)
		(fp_line
			(start 0.12065 -0.2794)
			(end 0.12065 -0.3048)
			(stroke
				(width 0.1)
				(type default)
			)
			(layer "F.Fab")
		)
		(fp_line
			(start 0.67945 -0.3048)
			(end 0.67945 0.3048)
			(stroke
				(width 0.1)
				(type default)
			)
			(layer "F.Fab")
		)
		(fp_line
			(start 0.67945 0.3048)
			(end 0.120396 0.3048)
			(stroke
				(width 0.1)
				(type default)
			)
			(layer "F.Fab")
		)
		(pad "1" smd circle
			(at -0.40005 0)
			(size 0 0)
			(layers "F.Cu" "F.Mask" "F.Paste")
			(net "P3V3_AUX")
		)
		(pad "2" smd circle
			(at 0.40005 0)
			(size 0 0)
			(layers "F.Cu" "F.Mask" "F.Paste")
			(net "OCP_V3_2_PRSNT1_R_N")
		)
	)
	(footprint ""
		(layer "F.Cu")
		(at 105.334054 -25.183592 180)
		(property "Reference" "C6090"
			(at 0 0 180)
			(layer "F.SilkS")
			(hide yes)
			(effects
				(font
					(size 1.27 1.27)
				)
			)
		)
		(property "Value" ""
			(at 0 0 180)
			(layer "F.Fab")
			(effects
				(font
					(size 1.27 1.27)
				)
			)
		)
		(duplicate_pad_numbers_are_jumpers no)
		(fp_line
			(start 0.7874 0.4064)
			(end -0.7874 0.4064)
			(stroke
				(width 0.1524)
				(type default)
			)
			(layer "F.SilkS")
		)
		(fp_line
			(start 0.7874 -0.4064)
			(end 0.7874 0.4064)
			(stroke
				(width 0.1524)
				(type default)
			)
			(layer "F.SilkS")
		)
		(fp_line
			(start -0.7874 0.4064)
			(end -0.7874 -0.4064)
			(stroke
				(width 0.1524)
				(type default)
			)
			(layer "F.SilkS")
		)
		(fp_line
			(start -0.7874 -0.4064)
			(end 0.7874 -0.4064)
			(stroke
				(width 0.1524)
				(type default)
			)
			(layer "F.SilkS")
		)
		(fp_line
			(start 0.67945 0.3048)
			(end 0.120396 0.3048)
			(stroke
				(width 0.1)
				(type default)
			)
			(layer "F.Fab")
		)
		(fp_line
			(start 0.67945 -0.3048)
			(end 0.67945 0.3048)
			(stroke
				(width 0.1)
				(type default)
			)
			(layer "F.Fab")
		)
		(fp_line
			(start 0.12065 -0.2794)
			(end 0.12065 -0.3048)
			(stroke
				(width 0.1)
				(type default)
			)
			(layer "F.Fab")
		)
		(fp_line
			(start 0.12065 -0.3048)
			(end 0.67945 -0.3048)
			(stroke
				(width 0.1)
				(type default)
			)
			(layer "F.Fab")
		)
		(fp_line
			(start 0.120396 0.3048)
			(end 0.120396 0.2794)
			(stroke
				(width 0.1)
				(type default)
			)
			(layer "F.Fab")
		)
		(fp_line
			(start 0.120396 0.2794)
			(end -0.12065 0.2794)
			(stroke
				(width 0.1)
				(type default)
			)
			(layer "F.Fab")
		)
		(fp_line
			(start -0.12065 0.3048)
			(end -0.67945 0.3048)
			(stroke
				(width 0.1)
				(type default)
			)
			(layer "F.Fab")
		)
		(fp_line
			(start -0.12065 0.2794)
			(end -0.12065 0.3048)
			(stroke
				(width 0.1)
				(type default)
			)
			(layer "F.Fab")
		)
		(fp_line
			(start -0.12065 -0.2794)
			(end 0.12065 -0.2794)
			(stroke
				(width 0.1)
				(type default)
			)
			(layer "F.Fab")
		)
		(fp_line
			(start -0.12065 -0.305054)
			(end -0.12065 -0.2794)
			(stroke
				(width 0.1)
				(type default)
			)
			(layer "F.Fab")
		)
		(fp_line
			(start -0.67945 0.3048)
			(end -0.67945 -0.305054)
			(stroke
				(width 0.1)
				(type default)
			)
			(layer "F.Fab")
		)
		(fp_line
			(start -0.67945 -0.305054)
			(end -0.12065 -0.305054)
			(stroke
				(width 0.1)
				(type default)
			)
			(layer "F.Fab")
		)
		(pad "1" smd circle
			(at -0.40005 0 180)
			(size 0 0)
			(layers "F.Cu" "F.Mask" "F.Paste")
			(net "XTAL_USB_CPU0_HUB2_XOUT")
		)
		(pad "2" smd circle
			(at 0.40005 0 180)
			(size 0 0)
			(layers "F.Cu" "F.Mask" "F.Paste")
			(net "GND")
		)
	)
	(footprint ""
		(layer "F.Cu")
		(at 169.058844 -370.57203 -90)
		(property "Reference" "C746"
			(at 0 0 270)
			(layer "F.SilkS")
			(hide yes)
			(effects
				(font
					(size 1.27 1.27)
				)
			)
		)
		(property "Value" ""
			(at 0 0 270)
			(layer "F.Fab")
			(effects
				(font
					(size 1.27 1.27)
				)
			)
		)
		(duplicate_pad_numbers_are_jumpers no)
		(fp_line
			(start -0.299974 0.150114)
			(end -0.299974 -0.150114)
			(stroke
				(width 0.1)
				(type default)
			)
			(layer "F.Fab")
		)
		(fp_line
			(start 0.299974 0.150114)
			(end -0.299974 0.150114)
			(stroke
				(width 0.1)
				(type default)
			)
			(layer "F.Fab")
		)
		(fp_line
			(start -0.299974 -0.150114)
			(end 0.299974 -0.150114)
			(stroke
				(width 0.1)
				(type default)
			)
			(layer "F.Fab")
		)
		(fp_line
			(start 0.299974 -0.150114)
			(end 0.299974 0.150114)
			(stroke
				(width 0.1)
				(type default)
			)
			(layer "F.Fab")
		)
		(pad "1" smd rect
			(at -0.2667 0 270)
			(size 0.3048 0.381)
			(layers "F.Cu" "F.Mask" "F.Paste")
			(net "P5E_CPU1_P2_TX_C_DN<13>")
		)
		(pad "2" smd rect
			(at 0.2667 0 270)
			(size 0.3048 0.381)
			(layers "F.Cu" "F.Mask" "F.Paste")
			(net "P5E_CPU1_P2_TX_DN<13>")
		)
	)
	(footprint ""
		(layer "F.Cu")
		(at 229.87 -282.188666 180)
		(property "Reference" "PC6523"
			(at 0 0 180)
			(layer "F.SilkS")
			(hide yes)
			(effects
				(font
					(size 1.27 1.27)
				)
			)
		)
		(property "Value" ""
			(at 0 0 180)
			(layer "F.Fab")
			(effects
				(font
					(size 1.27 1.27)
				)
			)
		)
		(duplicate_pad_numbers_are_jumpers no)
		(fp_line
			(start 1.524 0.762)
			(end -1.524 0.762)
			(stroke
				(width 0.1524)
				(type default)
			)
			(layer "F.SilkS")
		)
		(fp_line
			(start 1.524 -0.762)
			(end 1.524 0.762)
			(stroke
				(width 0.1524)
				(type default)
			)
			(layer "F.SilkS")
		)
		(fp_line
			(start -1.524 0.762)
			(end -1.524 -0.762)
			(stroke
				(width 0.1524)
				(type default)
			)
			(layer "F.SilkS")
		)
		(fp_line
			(start -1.524 -0.762)
			(end 1.524 -0.762)
			(stroke
				(width 0.1524)
				(type default)
			)
			(layer "F.SilkS")
		)
		(fp_line
			(start 1.1049 0.724916)
			(end 1.1049 -0.724916)
			(stroke
				(width 0.1)
				(type default)
			)
			(layer "F.Fab")
		)
		(fp_line
			(start 1.1049 -0.724916)
			(end -1.1049 -0.724916)
			(stroke
				(width 0.1)
				(type default)
			)
			(layer "F.Fab")
		)
		(fp_line
			(start -1.1049 0.724916)
			(end 1.1049 0.724916)
			(stroke
				(width 0.1)
				(type default)
			)
			(layer "F.Fab")
		)
		(fp_line
			(start -1.1049 -0.724916)
			(end -1.1049 0.724916)
			(stroke
				(width 0.1)
				(type default)
			)
			(layer "F.Fab")
		)
		(pad "1" smd rect
			(at -0.889 0)
			(size 1.016 1.27)
			(layers "F.Cu" "F.Mask" "F.Paste")
			(net "SW_P12V_AUX_P1V8_RETIMER_CPU1_FLT")
		)
		(pad "2" smd rect
			(at 0.889 0)
			(size 1.016 1.27)
			(layers "F.Cu" "F.Mask" "F.Paste")
			(net "GND")
		)
	)
	(footprint ""
		(layer "F.Cu")
		(at 80.925162 -25.358598 180)
		(property "Reference" "PR4522"
			(at 0 0 180)
			(layer "F.SilkS")
			(hide yes)
			(effects
				(font
					(size 1.27 1.27)
				)
			)
		)
		(property "Value" ""
			(at 0 0 180)
			(layer "F.Fab")
			(effects
				(font
					(size 1.27 1.27)
				)
			)
		)
		(duplicate_pad_numbers_are_jumpers no)
		(fp_line
			(start 0.7874 0.4064)
			(end -0.7874 0.4064)
			(stroke
				(width 0.1524)
				(type default)
			)
			(layer "F.SilkS")
		)
		(fp_line
			(start 0.7874 -0.4064)
			(end 0.7874 0.4064)
			(stroke
				(width 0.1524)
				(type default)
			)
			(layer "F.SilkS")
		)
		(fp_line
			(start -0.7874 0.4064)
			(end -0.7874 -0.4064)
			(stroke
				(width 0.1524)
				(type default)
			)
			(layer "F.SilkS")
		)
		(fp_line
			(start -0.7874 -0.4064)
			(end 0.7874 -0.4064)
			(stroke
				(width 0.1524)
				(type default)
			)
			(layer "F.SilkS")
		)
		(fp_line
			(start 0.67945 0.3048)
			(end 0.120396 0.3048)
			(stroke
				(width 0.1)
				(type default)
			)
			(layer "F.Fab")
		)
		(fp_line
			(start 0.67945 -0.3048)
			(end 0.67945 0.3048)
			(stroke
				(width 0.1)
				(type default)
			)
			(layer "F.Fab")
		)
		(fp_line
			(start 0.12065 -0.2794)
			(end 0.12065 -0.3048)
			(stroke
				(width 0.1)
				(type default)
			)
			(layer "F.Fab")
		)
		(fp_line
			(start 0.12065 -0.3048)
			(end 0.67945 -0.3048)
			(stroke
				(width 0.1)
				(type default)
			)
			(layer "F.Fab")
		)
		(fp_line
			(start 0.120396 0.3048)
			(end 0.120396 0.2794)
			(stroke
				(width 0.1)
				(type default)
			)
			(layer "F.Fab")
		)
		(fp_line
			(start 0.120396 0.2794)
			(end -0.12065 0.2794)
			(stroke
				(width 0.1)
				(type default)
			)
			(layer "F.Fab")
		)
		(fp_line
			(start -0.12065 0.3048)
			(end -0.67945 0.3048)
			(stroke
				(width 0.1)
				(type default)
			)
			(layer "F.Fab")
		)
		(fp_line
			(start -0.12065 0.2794)
			(end -0.12065 0.3048)
			(stroke
				(width 0.1)
				(type default)
			)
			(layer "F.Fab")
		)
		(fp_line
			(start -0.12065 -0.2794)
			(end 0.12065 -0.2794)
			(stroke
				(width 0.1)
				(type default)
			)
			(layer "F.Fab")
		)
		(fp_line
			(start -0.12065 -0.305054)
			(end -0.12065 -0.2794)
			(stroke
				(width 0.1)
				(type default)
			)
			(layer "F.Fab")
		)
		(fp_line
			(start -0.67945 0.3048)
			(end -0.67945 -0.305054)
			(stroke
				(width 0.1)
				(type default)
			)
			(layer "F.Fab")
		)
		(fp_line
			(start -0.67945 -0.305054)
			(end -0.12065 -0.305054)
			(stroke
				(width 0.1)
				(type default)
			)
			(layer "F.Fab")
		)
		(pad "1" smd circle
			(at -0.40005 0 180)
			(size 0 0)
			(layers "F.Cu" "F.Mask" "F.Paste")
			(net "P12V_OCP_V3_2")
		)
		(pad "2" smd circle
			(at 0.40005 0 180)
			(size 0 0)
			(layers "F.Cu" "F.Mask" "F.Paste")
			(net "P12V_OCP_GATE_2")
		)
	)
	(footprint ""
		(layer "F.Cu")
		(at 186.577478 -351.383854 -90)
		(property "Reference" "PC511_1"
			(at 0 0 270)
			(layer "F.SilkS")
			(hide yes)
			(effects
				(font
					(size 1.27 1.27)
				)
			)
		)
		(property "Value" ""
			(at 0 0 270)
			(layer "F.Fab")
			(effects
				(font
					(size 1.27 1.27)
				)
			)
		)
		(duplicate_pad_numbers_are_jumpers no)
		(fp_line
			(start -0.7874 0.4064)
			(end -0.7874 -0.4064)
			(stroke
				(width 0.1524)
				(type default)
			)
			(layer "F.SilkS")
		)
		(fp_line
			(start 0.7874 0.4064)
			(end -0.7874 0.4064)
			(stroke
				(width 0.1524)
				(type default)
			)
			(layer "F.SilkS")
		)
		(fp_line
			(start -0.7874 -0.4064)
			(end 0.7874 -0.4064)
			(stroke
				(width 0.1524)
				(type default)
			)
			(layer "F.SilkS")
		)
		(fp_line
			(start 0.7874 -0.4064)
			(end 0.7874 0.4064)
			(stroke
				(width 0.1524)
				(type default)
			)
			(layer "F.SilkS")
		)
		(fp_line
			(start -0.67945 0.3048)
			(end -0.67945 -0.305054)
			(stroke
				(width 0.1)
				(type default)
			)
			(layer "F.Fab")
		)
		(fp_line
			(start -0.12065 0.3048)
			(end -0.67945 0.3048)
			(stroke
				(width 0.1)
				(type default)
			)
			(layer "F.Fab")
		)
		(fp_line
			(start 0.120396 0.3048)
			(end 0.120396 0.2794)
			(stroke
				(width 0.1)
				(type default)
			)
			(layer "F.Fab")
		)
		(fp_line
			(start 0.67945 0.3048)
			(end 0.120396 0.3048)
			(stroke
				(width 0.1)
				(type default)
			)
			(layer "F.Fab")
		)
		(fp_line
			(start -0.12065 0.2794)
			(end -0.12065 0.3048)
			(stroke
				(width 0.1)
				(type default)
			)
			(layer "F.Fab")
		)
		(fp_line
			(start 0.120396 0.2794)
			(end -0.12065 0.2794)
			(stroke
				(width 0.1)
				(type default)
			)
			(layer "F.Fab")
		)
		(fp_line
			(start -0.12065 -0.2794)
			(end 0.12065 -0.2794)
			(stroke
				(width 0.1)
				(type default)
			)
			(layer "F.Fab")
		)
		(fp_line
			(start 0.12065 -0.2794)
			(end 0.12065 -0.3048)
			(stroke
				(width 0.1)
				(type default)
			)
			(layer "F.Fab")
		)
		(fp_line
			(start 0.12065 -0.3048)
			(end 0.67945 -0.3048)
			(stroke
				(width 0.1)
				(type default)
			)
			(layer "F.Fab")
		)
		(fp_line
			(start 0.67945 -0.3048)
			(end 0.67945 0.3048)
			(stroke
				(width 0.1)
				(type default)
			)
			(layer "F.Fab")
		)
		(fp_line
			(start -0.67945 -0.305054)
			(end -0.12065 -0.305054)
			(stroke
				(width 0.1)
				(type default)
			)
			(layer "F.Fab")
		)
		(fp_line
			(start -0.12065 -0.305054)
			(end -0.12065 -0.2794)
			(stroke
				(width 0.1)
				(type default)
			)
			(layer "F.Fab")
		)
		(pad "1" smd circle
			(at -0.40005 0 270)
			(size 0 0)
			(layers "F.Cu" "F.Mask" "F.Paste")
			(net "SW_P12V_AUX_PVDD11_S3_P1_FLT")
		)
		(pad "2" smd circle
			(at 0.40005 0 270)
			(size 0 0)
			(layers "F.Cu" "F.Mask" "F.Paste")
			(net "GND")
		)
	)
	(footprint ""
		(layer "F.Cu")
		(at 115.277138 -261.748016 -90)
		(property "Reference" "C2485"
			(at 0 0 270)
			(layer "F.SilkS")
			(hide yes)
			(effects
				(font
					(size 1.27 1.27)
				)
			)
		)
		(property "Value" ""
			(at 0 0 270)
			(layer "F.Fab")
			(effects
				(font
					(size 1.27 1.27)
				)
			)
		)
		(duplicate_pad_numbers_are_jumpers no)
		(fp_line
			(start -0.7874 0.4064)
			(end -0.7874 -0.4064)
			(stroke
				(width 0.1524)
				(type default)
			)
			(layer "F.SilkS")
		)
		(fp_line
			(start 0.7874 0.4064)
			(end -0.7874 0.4064)
			(stroke
				(width 0.1524)
				(type default)
			)
			(layer "F.SilkS")
		)
		(fp_line
			(start -0.7874 -0.4064)
			(end 0.7874 -0.4064)
			(stroke
				(width 0.1524)
				(type default)
			)
			(layer "F.SilkS")
		)
		(fp_line
			(start 0.7874 -0.4064)
			(end 0.7874 0.4064)
			(stroke
				(width 0.1524)
				(type default)
			)
			(layer "F.SilkS")
		)
		(fp_line
			(start -0.67945 0.3048)
			(end -0.67945 -0.305054)
			(stroke
				(width 0.1)
				(type default)
			)
			(layer "F.Fab")
		)
		(fp_line
			(start -0.12065 0.3048)
			(end -0.67945 0.3048)
			(stroke
				(width 0.1)
				(type default)
			)
			(layer "F.Fab")
		)
		(fp_line
			(start 0.120396 0.3048)
			(end 0.120396 0.2794)
			(stroke
				(width 0.1)
				(type default)
			)
			(layer "F.Fab")
		)
		(fp_line
			(start 0.67945 0.3048)
			(end 0.120396 0.3048)
			(stroke
				(width 0.1)
				(type default)
			)
			(layer "F.Fab")
		)
		(fp_line
			(start -0.12065 0.2794)
			(end -0.12065 0.3048)
			(stroke
				(width 0.1)
				(type default)
			)
			(layer "F.Fab")
		)
		(fp_line
			(start 0.120396 0.2794)
			(end -0.12065 0.2794)
			(stroke
				(width 0.1)
				(type default)
			)
			(layer "F.Fab")
		)
		(fp_line
			(start -0.12065 -0.2794)
			(end 0.12065 -0.2794)
			(stroke
				(width 0.1)
				(type default)
			)
			(layer "F.Fab")
		)
		(fp_line
			(start 0.12065 -0.2794)
			(end 0.12065 -0.3048)
			(stroke
				(width 0.1)
				(type default)
			)
			(layer "F.Fab")
		)
		(fp_line
			(start 0.12065 -0.3048)
			(end 0.67945 -0.3048)
			(stroke
				(width 0.1)
				(type default)
			)
			(layer "F.Fab")
		)
		(fp_line
			(start 0.67945 -0.3048)
			(end 0.67945 0.3048)
			(stroke
				(width 0.1)
				(type default)
			)
			(layer "F.Fab")
		)
		(fp_line
			(start -0.67945 -0.305054)
			(end -0.12065 -0.305054)
			(stroke
				(width 0.1)
				(type default)
			)
			(layer "F.Fab")
		)
		(fp_line
			(start -0.12065 -0.305054)
			(end -0.12065 -0.2794)
			(stroke
				(width 0.1)
				(type default)
			)
			(layer "F.Fab")
		)
		(pad "1" smd circle
			(at -0.40005 0 270)
			(size 0 0)
			(layers "F.Cu" "F.Mask" "F.Paste")
			(net "PVDD11_S3_P1")
		)
		(pad "2" smd circle
			(at 0.40005 0 270)
			(size 0 0)
			(layers "F.Cu" "F.Mask" "F.Paste")
			(net "GND")
		)
	)
	(footprint ""
		(layer "F.Cu")
		(at 118.491 -424.688 180)
		(property "Reference" "R3456"
			(at 0 0 180)
			(layer "F.SilkS")
			(hide yes)
			(effects
				(font
					(size 1.27 1.27)
				)
			)
		)
		(property "Value" ""
			(at 0 0 180)
			(layer "F.Fab")
			(effects
				(font
					(size 1.27 1.27)
				)
			)
		)
		(duplicate_pad_numbers_are_jumpers no)
		(fp_line
			(start 0.7874 0.4064)
			(end -0.7874 0.4064)
			(stroke
				(width 0.1524)
				(type default)
			)
			(layer "F.SilkS")
		)
		(fp_line
			(start 0.7874 -0.4064)
			(end 0.7874 0.4064)
			(stroke
				(width 0.1524)
				(type default)
			)
			(layer "F.SilkS")
		)
		(fp_line
			(start -0.7874 0.4064)
			(end -0.7874 -0.4064)
			(stroke
				(width 0.1524)
				(type default)
			)
			(layer "F.SilkS")
		)
		(fp_line
			(start -0.7874 -0.4064)
			(end 0.7874 -0.4064)
			(stroke
				(width 0.1524)
				(type default)
			)
			(layer "F.SilkS")
		)
		(fp_line
			(start 0.67945 0.3048)
			(end 0.120396 0.3048)
			(stroke
				(width 0.1)
				(type default)
			)
			(layer "F.Fab")
		)
		(fp_line
			(start 0.67945 -0.3048)
			(end 0.67945 0.3048)
			(stroke
				(width 0.1)
				(type default)
			)
			(layer "F.Fab")
		)
		(fp_line
			(start 0.12065 -0.2794)
			(end 0.12065 -0.3048)
			(stroke
				(width 0.1)
				(type default)
			)
			(layer "F.Fab")
		)
		(fp_line
			(start 0.12065 -0.3048)
			(end 0.67945 -0.3048)
			(stroke
				(width 0.1)
				(type default)
			)
			(layer "F.Fab")
		)
		(fp_line
			(start 0.120396 0.3048)
			(end 0.120396 0.2794)
			(stroke
				(width 0.1)
				(type default)
			)
			(layer "F.Fab")
		)
		(fp_line
			(start 0.120396 0.2794)
			(end -0.12065 0.2794)
			(stroke
				(width 0.1)
				(type default)
			)
			(layer "F.Fab")
		)
		(fp_line
			(start -0.12065 0.3048)
			(end -0.67945 0.3048)
			(stroke
				(width 0.1)
				(type default)
			)
			(layer "F.Fab")
		)
		(fp_line
			(start -0.12065 0.2794)
			(end -0.12065 0.3048)
			(stroke
				(width 0.1)
				(type default)
			)
			(layer "F.Fab")
		)
		(fp_line
			(start -0.12065 -0.2794)
			(end 0.12065 -0.2794)
			(stroke
				(width 0.1)
				(type default)
			)
			(layer "F.Fab")
		)
		(fp_line
			(start -0.12065 -0.305054)
			(end -0.12065 -0.2794)
			(stroke
				(width 0.1)
				(type default)
			)
			(layer "F.Fab")
		)
		(fp_line
			(start -0.67945 0.3048)
			(end -0.67945 -0.305054)
			(stroke
				(width 0.1)
				(type default)
			)
			(layer "F.Fab")
		)
		(fp_line
			(start -0.67945 -0.305054)
			(end -0.12065 -0.305054)
			(stroke
				(width 0.1)
				(type default)
			)
			(layer "F.Fab")
		)
		(pad "1" smd circle
			(at -0.40005 0 180)
			(size 0 0)
			(layers "F.Cu" "F.Mask" "F.Paste")
			(net "P3V3_AUX")
		)
		(pad "2" smd circle
			(at 0.40005 0 180)
			(size 0 0)
			(layers "F.Cu" "F.Mask" "F.Paste")
			(net "GPU_BASE_STBY_EN_BUF_R")
		)
	)
	(footprint ""
		(layer "F.Cu")
		(at 151.13 -113.157 180)
		(property "Reference" "R71"
			(at 0 0 180)
			(layer "F.SilkS")
			(hide yes)
			(effects
				(font
					(size 1.27 1.27)
				)
			)
		)
		(property "Value" ""
			(at 0 0 180)
			(layer "F.Fab")
			(effects
				(font
					(size 1.27 1.27)
				)
			)
		)
		(duplicate_pad_numbers_are_jumpers no)
		(fp_line
			(start 0.7874 0.4064)
			(end -0.7874 0.4064)
			(stroke
				(width 0.1524)
				(type default)
			)
			(layer "F.SilkS")
		)
		(fp_line
			(start 0.7874 -0.4064)
			(end 0.7874 0.4064)
			(stroke
				(width 0.1524)
				(type default)
			)
			(layer "F.SilkS")
		)
		(fp_line
			(start -0.7874 0.4064)
			(end -0.7874 -0.4064)
			(stroke
				(width 0.1524)
				(type default)
			)
			(layer "F.SilkS")
		)
		(fp_line
			(start -0.7874 -0.4064)
			(end 0.7874 -0.4064)
			(stroke
				(width 0.1524)
				(type default)
			)
			(layer "F.SilkS")
		)
		(fp_line
			(start 0.67945 0.3048)
			(end 0.120396 0.3048)
			(stroke
				(width 0.1)
				(type default)
			)
			(layer "F.Fab")
		)
		(fp_line
			(start 0.67945 -0.3048)
			(end 0.67945 0.3048)
			(stroke
				(width 0.1)
				(type default)
			)
			(layer "F.Fab")
		)
		(fp_line
			(start 0.12065 -0.2794)
			(end 0.12065 -0.3048)
			(stroke
				(width 0.1)
				(type default)
			)
			(layer "F.Fab")
		)
		(fp_line
			(start 0.12065 -0.3048)
			(end 0.67945 -0.3048)
			(stroke
				(width 0.1)
				(type default)
			)
			(layer "F.Fab")
		)
		(fp_line
			(start 0.120396 0.3048)
			(end 0.120396 0.2794)
			(stroke
				(width 0.1)
				(type default)
			)
			(layer "F.Fab")
		)
		(fp_line
			(start 0.120396 0.2794)
			(end -0.12065 0.2794)
			(stroke
				(width 0.1)
				(type default)
			)
			(layer "F.Fab")
		)
		(fp_line
			(start -0.12065 0.3048)
			(end -0.67945 0.3048)
			(stroke
				(width 0.1)
				(type default)
			)
			(layer "F.Fab")
		)
		(fp_line
			(start -0.12065 0.2794)
			(end -0.12065 0.3048)
			(stroke
				(width 0.1)
				(type default)
			)
			(layer "F.Fab")
		)
		(fp_line
			(start -0.12065 -0.2794)
			(end 0.12065 -0.2794)
			(stroke
				(width 0.1)
				(type default)
			)
			(layer "F.Fab")
		)
		(fp_line
			(start -0.12065 -0.305054)
			(end -0.12065 -0.2794)
			(stroke
				(width 0.1)
				(type default)
			)
			(layer "F.Fab")
		)
		(fp_line
			(start -0.67945 0.3048)
			(end -0.67945 -0.305054)
			(stroke
				(width 0.1)
				(type default)
			)
			(layer "F.Fab")
		)
		(fp_line
			(start -0.67945 -0.305054)
			(end -0.12065 -0.305054)
			(stroke
				(width 0.1)
				(type default)
			)
			(layer "F.Fab")
		)
		(pad "1" smd circle
			(at -0.40005 0 180)
			(size 0 0)
			(layers "F.Cu" "F.Mask" "F.Paste")
			(net "SCM_IRQ_R_N")
		)
		(pad "2" smd circle
			(at 0.40005 0 180)
			(size 0 0)
			(layers "F.Cu" "F.Mask" "F.Paste")
			(net "SCM_IRQ_N")
		)
	)
	(footprint ""
		(layer "F.Cu")
		(at 70.662546 -385.09448 180)
		(property "Reference" "L27"
			(at 0 0 180)
			(layer "F.SilkS")
			(hide yes)
			(effects
				(font
					(size 1.27 1.27)
				)
			)
		)
		(property "Value" ""
			(at 0 0 180)
			(layer "F.Fab")
			(effects
				(font
					(size 1.27 1.27)
				)
			)
		)
		(duplicate_pad_numbers_are_jumpers no)
		(fp_line
			(start 0.762 0.381)
			(end -0.762 0.381)
			(stroke
				(width 0.1524)
				(type default)
			)
			(layer "F.SilkS")
		)
		(fp_line
			(start 0.762 -0.381)
			(end 0.762 0.381)
			(stroke
				(width 0.1524)
				(type default)
			)
			(layer "F.SilkS")
		)
		(fp_line
			(start -0.762 0.381)
			(end -0.762 -0.381)
			(stroke
				(width 0.1524)
				(type default)
			)
			(layer "F.SilkS")
		)
		(fp_line
			(start -0.762 -0.381)
			(end 0.762 -0.381)
			(stroke
				(width 0.1524)
				(type default)
			)
			(layer "F.SilkS")
		)
		(fp_line
			(start 0.680466 0.306324)
			(end 0.118364 0.306324)
			(stroke
				(width 0.1)
				(type default)
			)
			(layer "F.Fab")
		)
		(fp_line
			(start 0.680466 -0.306324)
			(end 0.680466 0.306324)
			(stroke
				(width 0.1)
				(type default)
			)
			(layer "F.Fab")
		)
		(fp_line
			(start 0.118872 -0.2794)
			(end 0.118872 -0.306324)
			(stroke
				(width 0.1)
				(type default)
			)
			(layer "F.Fab")
		)
		(fp_line
			(start 0.118872 -0.306324)
			(end 0.680466 -0.306324)
			(stroke
				(width 0.1)
				(type default)
			)
			(layer "F.Fab")
		)
		(fp_line
			(start 0.118364 0.306324)
			(end 0.118364 0.2794)
			(stroke
				(width 0.1)
				(type default)
			)
			(layer "F.Fab")
		)
		(fp_line
			(start 0.118364 0.2794)
			(end -0.119634 0.2794)
			(stroke
				(width 0.1)
				(type default)
			)
			(layer "F.Fab")
		)
		(fp_line
			(start -0.118364 -0.2794)
			(end 0.118872 -0.2794)
			(stroke
				(width 0.1)
				(type default)
			)
			(layer "F.Fab")
		)
		(fp_line
			(start -0.118364 -0.307086)
			(end -0.118364 -0.2794)
			(stroke
				(width 0.1)
				(type default)
			)
			(layer "F.Fab")
		)
		(fp_line
			(start -0.119634 0.30607)
			(end -0.681736 0.30607)
			(stroke
				(width 0.1)
				(type default)
			)
			(layer "F.Fab")
		)
		(fp_line
			(start -0.119634 0.2794)
			(end -0.119634 0.30607)
			(stroke
				(width 0.1)
				(type default)
			)
			(layer "F.Fab")
		)
		(fp_line
			(start -0.681736 0.30607)
			(end -0.681736 -0.307086)
			(stroke
				(width 0.1)
				(type default)
			)
			(layer "F.Fab")
		)
		(fp_line
			(start -0.681736 -0.307086)
			(end -0.118364 -0.307086)
			(stroke
				(width 0.1)
				(type default)
			)
			(layer "F.Fab")
		)
		(pad "1" smd rect
			(at -0.40005 0)
			(size 0.4572 0.508)
			(layers "F.Cu" "F.Mask" "F.Paste")
			(net "P1V8_CPU1_RT_1D")
		)
		(pad "2" smd rect
			(at 0.40005 0)
			(size 0.4572 0.508)
			(layers "F.Cu" "F.Mask" "F.Paste")
			(net "P1V8_CPU1_RT0_1A_1D")
		)
	)
	(footprint ""
		(layer "F.Cu")
		(at 51.498754 -370.57203 -90)
		(property "Reference" "C825"
			(at 0 0 270)
			(layer "F.SilkS")
			(hide yes)
			(effects
				(font
					(size 1.27 1.27)
				)
			)
		)
		(property "Value" ""
			(at 0 0 270)
			(layer "F.Fab")
			(effects
				(font
					(size 1.27 1.27)
				)
			)
		)
		(duplicate_pad_numbers_are_jumpers no)
		(fp_line
			(start -0.299974 0.150114)
			(end -0.299974 -0.150114)
			(stroke
				(width 0.1)
				(type default)
			)
			(layer "F.Fab")
		)
		(fp_line
			(start 0.299974 0.150114)
			(end -0.299974 0.150114)
			(stroke
				(width 0.1)
				(type default)
			)
			(layer "F.Fab")
		)
		(fp_line
			(start -0.299974 -0.150114)
			(end 0.299974 -0.150114)
			(stroke
				(width 0.1)
				(type default)
			)
			(layer "F.Fab")
		)
		(fp_line
			(start 0.299974 -0.150114)
			(end 0.299974 0.150114)
			(stroke
				(width 0.1)
				(type default)
			)
			(layer "F.Fab")
		)
		(pad "1" smd rect
			(at -0.2667 0 270)
			(size 0.3048 0.381)
			(layers "F.Cu" "F.Mask" "F.Paste")
			(net "P5E_CPU1_P0_TX_C_DP<6>")
		)
		(pad "2" smd rect
			(at 0.2667 0 270)
			(size 0.3048 0.381)
			(layers "F.Cu" "F.Mask" "F.Paste")
			(net "P5E_CPU1_P0_TX_DP<6>")
		)
	)
	(footprint ""
		(layer "F.Cu")
		(at 197.269608 -114.641376 180)
		(property "Reference" "R199"
			(at 0 0 180)
			(layer "F.SilkS")
			(hide yes)
			(effects
				(font
					(size 1.27 1.27)
				)
			)
		)
		(property "Value" ""
			(at 0 0 180)
			(layer "F.Fab")
			(effects
				(font
					(size 1.27 1.27)
				)
			)
		)
		(duplicate_pad_numbers_are_jumpers no)
		(fp_line
			(start 0.7874 0.4064)
			(end -0.7874 0.4064)
			(stroke
				(width 0.1524)
				(type default)
			)
			(layer "F.SilkS")
		)
		(fp_line
			(start 0.7874 -0.4064)
			(end 0.7874 0.4064)
			(stroke
				(width 0.1524)
				(type default)
			)
			(layer "F.SilkS")
		)
		(fp_line
			(start -0.7874 0.4064)
			(end -0.7874 -0.4064)
			(stroke
				(width 0.1524)
				(type default)
			)
			(layer "F.SilkS")
		)
		(fp_line
			(start -0.7874 -0.4064)
			(end 0.7874 -0.4064)
			(stroke
				(width 0.1524)
				(type default)
			)
			(layer "F.SilkS")
		)
		(fp_line
			(start 0.67945 0.3048)
			(end 0.120396 0.3048)
			(stroke
				(width 0.1)
				(type default)
			)
			(layer "F.Fab")
		)
		(fp_line
			(start 0.67945 -0.3048)
			(end 0.67945 0.3048)
			(stroke
				(width 0.1)
				(type default)
			)
			(layer "F.Fab")
		)
		(fp_line
			(start 0.12065 -0.2794)
			(end 0.12065 -0.3048)
			(stroke
				(width 0.1)
				(type default)
			)
			(layer "F.Fab")
		)
		(fp_line
			(start 0.12065 -0.3048)
			(end 0.67945 -0.3048)
			(stroke
				(width 0.1)
				(type default)
			)
			(layer "F.Fab")
		)
		(fp_line
			(start 0.120396 0.3048)
			(end 0.120396 0.2794)
			(stroke
				(width 0.1)
				(type default)
			)
			(layer "F.Fab")
		)
		(fp_line
			(start 0.120396 0.2794)
			(end -0.12065 0.2794)
			(stroke
				(width 0.1)
				(type default)
			)
			(layer "F.Fab")
		)
		(fp_line
			(start -0.12065 0.3048)
			(end -0.67945 0.3048)
			(stroke
				(width 0.1)
				(type default)
			)
			(layer "F.Fab")
		)
		(fp_line
			(start -0.12065 0.2794)
			(end -0.12065 0.3048)
			(stroke
				(width 0.1)
				(type default)
			)
			(layer "F.Fab")
		)
		(fp_line
			(start -0.12065 -0.2794)
			(end 0.12065 -0.2794)
			(stroke
				(width 0.1)
				(type default)
			)
			(layer "F.Fab")
		)
		(fp_line
			(start -0.12065 -0.305054)
			(end -0.12065 -0.2794)
			(stroke
				(width 0.1)
				(type default)
			)
			(layer "F.Fab")
		)
		(fp_line
			(start -0.67945 0.3048)
			(end -0.67945 -0.305054)
			(stroke
				(width 0.1)
				(type default)
			)
			(layer "F.Fab")
		)
		(fp_line
			(start -0.67945 -0.305054)
			(end -0.12065 -0.305054)
			(stroke
				(width 0.1)
				(type default)
			)
			(layer "F.Fab")
		)
		(pad "1" smd circle
			(at -0.40005 0 180)
			(size 0 0)
			(layers "F.Cu" "F.Mask" "F.Paste")
			(net "E1S_0_P12V_EN")
		)
		(pad "2" smd circle
			(at 0.40005 0 180)
			(size 0 0)
			(layers "F.Cu" "F.Mask" "F.Paste")
			(net "P12V_E1S_0_EN")
		)
	)
	(footprint ""
		(layer "F.Cu")
		(at 190.5 -44.577 180)
		(property "Reference" "R8024"
			(at 0 0 180)
			(layer "F.SilkS")
			(hide yes)
			(effects
				(font
					(size 1.27 1.27)
				)
			)
		)
		(property "Value" ""
			(at 0 0 180)
			(layer "F.Fab")
			(effects
				(font
					(size 1.27 1.27)
				)
			)
		)
		(duplicate_pad_numbers_are_jumpers no)
		(fp_line
			(start 0.7874 0.4064)
			(end -0.7874 0.4064)
			(stroke
				(width 0.1524)
				(type default)
			)
			(layer "F.SilkS")
		)
		(fp_line
			(start 0.7874 -0.4064)
			(end 0.7874 0.4064)
			(stroke
				(width 0.1524)
				(type default)
			)
			(layer "F.SilkS")
		)
		(fp_line
			(start -0.7874 0.4064)
			(end -0.7874 -0.4064)
			(stroke
				(width 0.1524)
				(type default)
			)
			(layer "F.SilkS")
		)
		(fp_line
			(start -0.7874 -0.4064)
			(end 0.7874 -0.4064)
			(stroke
				(width 0.1524)
				(type default)
			)
			(layer "F.SilkS")
		)
		(fp_line
			(start 0.67945 0.3048)
			(end 0.120396 0.3048)
			(stroke
				(width 0.1)
				(type default)
			)
			(layer "F.Fab")
		)
		(fp_line
			(start 0.67945 -0.3048)
			(end 0.67945 0.3048)
			(stroke
				(width 0.1)
				(type default)
			)
			(layer "F.Fab")
		)
		(fp_line
			(start 0.12065 -0.2794)
			(end 0.12065 -0.3048)
			(stroke
				(width 0.1)
				(type default)
			)
			(layer "F.Fab")
		)
		(fp_line
			(start 0.12065 -0.3048)
			(end 0.67945 -0.3048)
			(stroke
				(width 0.1)
				(type default)
			)
			(layer "F.Fab")
		)
		(fp_line
			(start 0.120396 0.3048)
			(end 0.120396 0.2794)
			(stroke
				(width 0.1)
				(type default)
			)
			(layer "F.Fab")
		)
		(fp_line
			(start 0.120396 0.2794)
			(end -0.12065 0.2794)
			(stroke
				(width 0.1)
				(type default)
			)
			(layer "F.Fab")
		)
		(fp_line
			(start -0.12065 0.3048)
			(end -0.67945 0.3048)
			(stroke
				(width 0.1)
				(type default)
			)
			(layer "F.Fab")
		)
		(fp_line
			(start -0.12065 0.2794)
			(end -0.12065 0.3048)
			(stroke
				(width 0.1)
				(type default)
			)
			(layer "F.Fab")
		)
		(fp_line
			(start -0.12065 -0.2794)
			(end 0.12065 -0.2794)
			(stroke
				(width 0.1)
				(type default)
			)
			(layer "F.Fab")
		)
		(fp_line
			(start -0.12065 -0.305054)
			(end -0.12065 -0.2794)
			(stroke
				(width 0.1)
				(type default)
			)
			(layer "F.Fab")
		)
		(fp_line
			(start -0.67945 0.3048)
			(end -0.67945 -0.305054)
			(stroke
				(width 0.1)
				(type default)
			)
			(layer "F.Fab")
		)
		(fp_line
			(start -0.67945 -0.305054)
			(end -0.12065 -0.305054)
			(stroke
				(width 0.1)
				(type default)
			)
			(layer "F.Fab")
		)
		(pad "1" smd circle
			(at -0.40005 0 180)
			(size 0 0)
			(layers "F.Cu" "F.Mask" "F.Paste")
			(net "LED_P12V_AUX_R3")
		)
		(pad "2" smd circle
			(at 0.40005 0 180)
			(size 0 0)
			(layers "F.Cu" "F.Mask" "F.Paste")
			(net "P12V_AUX")
		)
	)
	(footprint ""
		(layer "F.Cu")
		(at 208.892394 -107.467146)
		(property "Reference" "C8005"
			(at 0 0 0)
			(layer "F.SilkS")
			(hide yes)
			(effects
				(font
					(size 1.27 1.27)
				)
			)
		)
		(property "Value" ""
			(at 0 0 0)
			(layer "F.Fab")
			(effects
				(font
					(size 1.27 1.27)
				)
			)
		)
		(duplicate_pad_numbers_are_jumpers no)
		(fp_line
			(start -0.7874 -0.4064)
			(end 0.7874 -0.4064)
			(stroke
				(width 0.1524)
				(type default)
			)
			(layer "F.SilkS")
		)
		(fp_line
			(start -0.7874 0.4064)
			(end -0.7874 -0.4064)
			(stroke
				(width 0.1524)
				(type default)
			)
			(layer "F.SilkS")
		)
		(fp_line
			(start 0.7874 -0.4064)
			(end 0.7874 0.4064)
			(stroke
				(width 0.1524)
				(type default)
			)
			(layer "F.SilkS")
		)
		(fp_line
			(start 0.7874 0.4064)
			(end -0.7874 0.4064)
			(stroke
				(width 0.1524)
				(type default)
			)
			(layer "F.SilkS")
		)
		(fp_line
			(start -0.67945 -0.305054)
			(end -0.12065 -0.305054)
			(stroke
				(width 0.1)
				(type default)
			)
			(layer "F.Fab")
		)
		(fp_line
			(start -0.67945 0.3048)
			(end -0.67945 -0.305054)
			(stroke
				(width 0.1)
				(type default)
			)
			(layer "F.Fab")
		)
		(fp_line
			(start -0.12065 -0.305054)
			(end -0.12065 -0.2794)
			(stroke
				(width 0.1)
				(type default)
			)
			(layer "F.Fab")
		)
		(fp_line
			(start -0.12065 -0.2794)
			(end 0.12065 -0.2794)
			(stroke
				(width 0.1)
				(type default)
			)
			(layer "F.Fab")
		)
		(fp_line
			(start -0.12065 0.2794)
			(end -0.12065 0.3048)
			(stroke
				(width 0.1)
				(type default)
			)
			(layer "F.Fab")
		)
		(fp_line
			(start -0.12065 0.3048)
			(end -0.67945 0.3048)
			(stroke
				(width 0.1)
				(type default)
			)
			(layer "F.Fab")
		)
		(fp_line
			(start 0.120396 0.2794)
			(end -0.12065 0.2794)
			(stroke
				(width 0.1)
				(type default)
			)
			(layer "F.Fab")
		)
		(fp_line
			(start 0.120396 0.3048)
			(end 0.120396 0.2794)
			(stroke
				(width 0.1)
				(type default)
			)
			(layer "F.Fab")
		)
		(fp_line
			(start 0.12065 -0.3048)
			(end 0.67945 -0.3048)
			(stroke
				(width 0.1)
				(type default)
			)
			(layer "F.Fab")
		)
		(fp_line
			(start 0.12065 -0.2794)
			(end 0.12065 -0.3048)
			(stroke
				(width 0.1)
				(type default)
			)
			(layer "F.Fab")
		)
		(fp_line
			(start 0.67945 -0.3048)
			(end 0.67945 0.3048)
			(stroke
				(width 0.1)
				(type default)
			)
			(layer "F.Fab")
		)
		(fp_line
			(start 0.67945 0.3048)
			(end 0.120396 0.3048)
			(stroke
				(width 0.1)
				(type default)
			)
			(layer "F.Fab")
		)
		(pad "1" smd circle
			(at -0.40005 0)
			(size 0 0)
			(layers "F.Cu" "F.Mask" "F.Paste")
			(net "PWRGD_P5V_AUX_R3")
		)
		(pad "2" smd circle
			(at 0.40005 0)
			(size 0 0)
			(layers "F.Cu" "F.Mask" "F.Paste")
			(net "GND")
		)
	)
	(footprint ""
		(layer "F.Cu")
		(at 96.0628 -418.0332 180)
		(property "Reference" "R1456"
			(at 0 0 180)
			(layer "F.SilkS")
			(hide yes)
			(effects
				(font
					(size 1.27 1.27)
				)
			)
		)
		(property "Value" ""
			(at 0 0 180)
			(layer "F.Fab")
			(effects
				(font
					(size 1.27 1.27)
				)
			)
		)
		(duplicate_pad_numbers_are_jumpers no)
		(fp_line
			(start 0.32512 0.175006)
			(end -0.32512 0.175006)
			(stroke
				(width 0.1)
				(type default)
			)
			(layer "F.Fab")
		)
		(fp_line
			(start 0.32512 -0.175006)
			(end 0.32512 0.175006)
			(stroke
				(width 0.1)
				(type default)
			)
			(layer "F.Fab")
		)
		(fp_line
			(start -0.32512 0.175006)
			(end -0.32512 -0.175006)
			(stroke
				(width 0.1)
				(type default)
			)
			(layer "F.Fab")
		)
		(fp_line
			(start -0.32512 -0.175006)
			(end 0.32512 -0.175006)
			(stroke
				(width 0.1)
				(type default)
			)
			(layer "F.Fab")
		)
		(pad "1" smd rect
			(at -0.2667 0 180)
			(size 0.3048 0.381)
			(layers "F.Cu" "F.Mask" "F.Paste")
			(net "P1V8_CPU1_RT_1D")
		)
		(pad "2" smd rect
			(at 0.2667 0)
			(size 0.3048 0.381)
			(layers "F.Cu" "F.Mask" "F.Paste")
			(net "JTAG_TDO_RT_CPU1_P1")
		)
	)
	(footprint ""
		(layer "F.Cu")
		(at 149.230334 -191.371982 -90)
		(property "Reference" "R3197"
			(at 0 0 270)
			(layer "F.SilkS")
			(hide yes)
			(effects
				(font
					(size 1.27 1.27)
				)
			)
		)
		(property "Value" ""
			(at 0 0 270)
			(layer "F.Fab")
			(effects
				(font
					(size 1.27 1.27)
				)
			)
		)
		(duplicate_pad_numbers_are_jumpers no)
		(fp_line
			(start -0.7874 0.4064)
			(end -0.7874 0.056134)
			(stroke
				(width 0.1524)
				(type default)
			)
			(layer "F.SilkS")
		)
		(fp_line
			(start 0.7874 0.4064)
			(end -0.7874 0.4064)
			(stroke
				(width 0.1524)
				(type default)
			)
			(layer "F.SilkS")
		)
		(fp_line
			(start 0.7874 -0.045466)
			(end 0.7874 0.4064)
			(stroke
				(width 0.1524)
				(type default)
			)
			(layer "F.SilkS")
		)
		(fp_line
			(start -0.347218 -0.4064)
			(end 0.440182 -0.4064)
			(stroke
				(width 0.1524)
				(type default)
			)
			(layer "F.SilkS")
		)
		(fp_line
			(start -0.67945 0.3048)
			(end -0.67945 -0.305054)
			(stroke
				(width 0.1)
				(type default)
			)
			(layer "F.Fab")
		)
		(fp_line
			(start -0.12065 0.3048)
			(end -0.67945 0.3048)
			(stroke
				(width 0.1)
				(type default)
			)
			(layer "F.Fab")
		)
		(fp_line
			(start 0.120396 0.3048)
			(end 0.120396 0.2794)
			(stroke
				(width 0.1)
				(type default)
			)
			(layer "F.Fab")
		)
		(fp_line
			(start 0.67945 0.3048)
			(end 0.120396 0.3048)
			(stroke
				(width 0.1)
				(type default)
			)
			(layer "F.Fab")
		)
		(fp_line
			(start -0.12065 0.2794)
			(end -0.12065 0.3048)
			(stroke
				(width 0.1)
				(type default)
			)
			(layer "F.Fab")
		)
		(fp_line
			(start 0.120396 0.2794)
			(end -0.12065 0.2794)
			(stroke
				(width 0.1)
				(type default)
			)
			(layer "F.Fab")
		)
		(fp_line
			(start -0.12065 -0.2794)
			(end 0.12065 -0.2794)
			(stroke
				(width 0.1)
				(type default)
			)
			(layer "F.Fab")
		)
		(fp_line
			(start 0.12065 -0.2794)
			(end 0.12065 -0.3048)
			(stroke
				(width 0.1)
				(type default)
			)
			(layer "F.Fab")
		)
		(fp_line
			(start 0.12065 -0.3048)
			(end 0.67945 -0.3048)
			(stroke
				(width 0.1)
				(type default)
			)
			(layer "F.Fab")
		)
		(fp_line
			(start 0.67945 -0.3048)
			(end 0.67945 0.3048)
			(stroke
				(width 0.1)
				(type default)
			)
			(layer "F.Fab")
		)
		(fp_line
			(start -0.67945 -0.305054)
			(end -0.12065 -0.305054)
			(stroke
				(width 0.1)
				(type default)
			)
			(layer "F.Fab")
		)
		(fp_line
			(start -0.12065 -0.305054)
			(end -0.12065 -0.2794)
			(stroke
				(width 0.1)
				(type default)
			)
			(layer "F.Fab")
		)
		(pad "1" smd circle
			(at -0.40005 0 270)
			(size 0 0)
			(layers "F.Cu" "F.Mask" "F.Paste")
			(net "CLK_100M_CPU1_CLK03_R_DN")
		)
		(pad "2" smd circle
			(at 0.40005 0 270)
			(size 0 0)
			(layers "F.Cu" "F.Mask" "F.Paste")
			(net "CLK_100M_CPU1_CLK03_DN")
		)
	)
	(footprint ""
		(layer "F.Cu")
		(at 399.197322 -134.92988)
		(property "Reference" "R2344"
			(at 0 0 0)
			(layer "F.SilkS")
			(hide yes)
			(effects
				(font
					(size 1.27 1.27)
				)
			)
		)
		(property "Value" ""
			(at 0 0 0)
			(layer "F.Fab")
			(effects
				(font
					(size 1.27 1.27)
				)
			)
		)
		(duplicate_pad_numbers_are_jumpers no)
		(fp_line
			(start -0.7874 -0.4064)
			(end 0.7874 -0.4064)
			(stroke
				(width 0.1524)
				(type default)
			)
			(layer "F.SilkS")
		)
		(fp_line
			(start -0.7874 0.4064)
			(end -0.7874 -0.4064)
			(stroke
				(width 0.1524)
				(type default)
			)
			(layer "F.SilkS")
		)
		(fp_line
			(start 0.7874 -0.4064)
			(end 0.7874 0.4064)
			(stroke
				(width 0.1524)
				(type default)
			)
			(layer "F.SilkS")
		)
		(fp_line
			(start 0.7874 0.4064)
			(end -0.7874 0.4064)
			(stroke
				(width 0.1524)
				(type default)
			)
			(layer "F.SilkS")
		)
		(fp_line
			(start -0.67945 -0.305054)
			(end -0.12065 -0.305054)
			(stroke
				(width 0.1)
				(type default)
			)
			(layer "F.Fab")
		)
		(fp_line
			(start -0.67945 0.3048)
			(end -0.67945 -0.305054)
			(stroke
				(width 0.1)
				(type default)
			)
			(layer "F.Fab")
		)
		(fp_line
			(start -0.12065 -0.305054)
			(end -0.12065 -0.2794)
			(stroke
				(width 0.1)
				(type default)
			)
			(layer "F.Fab")
		)
		(fp_line
			(start -0.12065 -0.2794)
			(end 0.12065 -0.2794)
			(stroke
				(width 0.1)
				(type default)
			)
			(layer "F.Fab")
		)
		(fp_line
			(start -0.12065 0.2794)
			(end -0.12065 0.3048)
			(stroke
				(width 0.1)
				(type default)
			)
			(layer "F.Fab")
		)
		(fp_line
			(start -0.12065 0.3048)
			(end -0.67945 0.3048)
			(stroke
				(width 0.1)
				(type default)
			)
			(layer "F.Fab")
		)
		(fp_line
			(start 0.120396 0.2794)
			(end -0.12065 0.2794)
			(stroke
				(width 0.1)
				(type default)
			)
			(layer "F.Fab")
		)
		(fp_line
			(start 0.120396 0.3048)
			(end 0.120396 0.2794)
			(stroke
				(width 0.1)
				(type default)
			)
			(layer "F.Fab")
		)
		(fp_line
			(start 0.12065 -0.3048)
			(end 0.67945 -0.3048)
			(stroke
				(width 0.1)
				(type default)
			)
			(layer "F.Fab")
		)
		(fp_line
			(start 0.12065 -0.2794)
			(end 0.12065 -0.3048)
			(stroke
				(width 0.1)
				(type default)
			)
			(layer "F.Fab")
		)
		(fp_line
			(start 0.67945 -0.3048)
			(end 0.67945 0.3048)
			(stroke
				(width 0.1)
				(type default)
			)
			(layer "F.Fab")
		)
		(fp_line
			(start 0.67945 0.3048)
			(end 0.120396 0.3048)
			(stroke
				(width 0.1)
				(type default)
			)
			(layer "F.Fab")
		)
		(pad "1" smd circle
			(at -0.40005 0)
			(size 0 0)
			(layers "F.Cu" "F.Mask" "F.Paste")
			(net "P3V3_AUX")
		)
		(pad "2" smd circle
			(at 0.40005 0)
			(size 0 0)
			(layers "F.Cu" "F.Mask" "F.Paste")
			(net "PWRGD_P5V_AUX_R1")
		)
	)
	(footprint ""
		(layer "F.Cu")
		(at 423.35704 -439.284872)
		(property "Reference" "Q69"
			(at -1.239266 -1.871726 0)
			(unlocked yes)
			(layer "F.SilkS")
			(effects
				(font
					(size 0.7874 0.5842)
					(thickness 0.1524)
				)
				(justify left)
			)
		)
		(property "Value" ""
			(at 0 0 0)
			(layer "F.Fab")
			(effects
				(font
					(size 1.27 1.27)
				)
			)
		)
		(duplicate_pad_numbers_are_jumpers no)
		(fp_line
			(start -1.332738 -1.100074)
			(end -0.4826 -1.100074)
			(stroke
				(width 0.1524)
				(type default)
			)
			(layer "F.SilkS")
		)
		(fp_line
			(start -1.332738 1.100074)
			(end -1.332738 -1.100074)
			(stroke
				(width 0.1524)
				(type default)
			)
			(layer "F.SilkS")
		)
		(fp_line
			(start -0.4826 -1.100074)
			(end 0 -0.541274)
			(stroke
				(width 0.1524)
				(type default)
			)
			(layer "F.SilkS")
		)
		(fp_line
			(start 0 -0.541274)
			(end 0.4826 -1.100074)
			(stroke
				(width 0.1524)
				(type default)
			)
			(layer "F.SilkS")
		)
		(fp_line
			(start 0.4826 -1.100074)
			(end 1.332738 -1.100074)
			(stroke
				(width 0.1524)
				(type default)
			)
			(layer "F.SilkS")
		)
		(fp_line
			(start 1.332738 -1.100074)
			(end 1.332738 1.100074)
			(stroke
				(width 0.1524)
				(type default)
			)
			(layer "F.SilkS")
		)
		(fp_line
			(start 1.332738 1.100074)
			(end -1.332738 1.100074)
			(stroke
				(width 0.1524)
				(type default)
			)
			(layer "F.SilkS")
		)
		(fp_poly
			(pts
				(xy -1.533144 -0.649986) (xy -2.2352 -0.298958) (xy -2.2352 -1.001014)
			)
			(stroke
				(width 0)
				(type default)
			)
			(fill yes)
			(layer "F.SilkS")
		)
		(fp_line
			(start -0.674878 -1.100074)
			(end 0.674878 -1.100074)
			(stroke
				(width 0.1)
				(type default)
			)
			(layer "F.Fab")
		)
		(fp_line
			(start -0.674878 1.100074)
			(end -0.674878 -1.100074)
			(stroke
				(width 0.1)
				(type default)
			)
			(layer "F.Fab")
		)
		(fp_line
			(start 0.674878 -1.100074)
			(end 0.674878 1.100074)
			(stroke
				(width 0.1)
				(type default)
			)
			(layer "F.Fab")
		)
		(fp_line
			(start 0.674878 1.100074)
			(end -0.674878 1.100074)
			(stroke
				(width 0.1)
				(type default)
			)
			(layer "F.Fab")
		)
		(fp_poly
			(pts
				(xy -2.2352 -0.298958) (xy -2.2352 -1.001014) (xy -1.533144 -0.649986)
			)
			(stroke
				(width 0)
				(type default)
			)
			(fill yes)
			(layer "F.Fab")
		)
		(pad "1" smd rect
			(at -0.94996 -0.649986 90)
			(size 0.4318 0.508)
			(layers "F.Cu" "F.Mask" "F.Paste")
			(net "GND")
		)
		(pad "2" smd rect
			(at -0.94996 0 90)
			(size 0.4318 0.508)
			(layers "F.Cu" "F.Mask" "F.Paste")
			(net "RST_BMC_FROM_SWB_N")
		)
		(pad "3" smd rect
			(at -0.94996 0.649986 90)
			(size 0.4318 0.508)
			(layers "F.Cu" "F.Mask" "F.Paste")
			(net "RST_BMC_FROM_SWB_ISO_N")
		)
		(pad "4" smd rect
			(at 0.94996 0.649986 90)
			(size 0.4318 0.508)
			(layers "F.Cu" "F.Mask" "F.Paste")
			(net "GND")
		)
		(pad "5" smd rect
			(at 0.94996 0 90)
			(size 0.4318 0.508)
			(layers "F.Cu" "F.Mask" "F.Paste")
			(net "RST_BMC_FROM_SWB")
		)
		(pad "6" smd rect
			(at 0.94996 -0.649986 90)
			(size 0.4318 0.508)
			(layers "F.Cu" "F.Mask" "F.Paste")
			(net "RST_BMC_FROM_SWB")
		)
	)
	(footprint ""
		(layer "F.Cu")
		(at 325.211186 -416.899344 -90)
		(property "Reference" "C6516"
			(at 0 0 270)
			(layer "F.SilkS")
			(hide yes)
			(effects
				(font
					(size 1.27 1.27)
				)
			)
		)
		(property "Value" ""
			(at 0 0 270)
			(layer "F.Fab")
			(effects
				(font
					(size 1.27 1.27)
				)
			)
		)
		(duplicate_pad_numbers_are_jumpers no)
		(fp_line
			(start -0.299974 0.150114)
			(end -0.299974 -0.150114)
			(stroke
				(width 0.1)
				(type default)
			)
			(layer "F.Fab")
		)
		(fp_line
			(start 0.299974 0.150114)
			(end -0.299974 0.150114)
			(stroke
				(width 0.1)
				(type default)
			)
			(layer "F.Fab")
		)
		(fp_line
			(start -0.299974 -0.150114)
			(end 0.299974 -0.150114)
			(stroke
				(width 0.1)
				(type default)
			)
			(layer "F.Fab")
		)
		(fp_line
			(start 0.299974 -0.150114)
			(end 0.299974 0.150114)
			(stroke
				(width 0.1)
				(type default)
			)
			(layer "F.Fab")
		)
		(pad "1" smd rect
			(at -0.2667 0 270)
			(size 0.3048 0.381)
			(layers "F.Cu" "F.Mask" "F.Paste")
			(net "P5E_CPU0_P0_TX_BUF_C_DN<7>")
		)
		(pad "2" smd rect
			(at 0.2667 0 270)
			(size 0.3048 0.381)
			(layers "F.Cu" "F.Mask" "F.Paste")
			(net "P5E_CPU0_P0_TX_BUF_DN<7>")
		)
	)
	(footprint ""
		(layer "F.Cu")
		(at 30.075378 -132.788914 -90)
		(property "Reference" "C1882"
			(at 0 0 270)
			(layer "F.SilkS")
			(hide yes)
			(effects
				(font
					(size 1.27 1.27)
				)
			)
		)
		(property "Value" ""
			(at 0 0 270)
			(layer "F.Fab")
			(effects
				(font
					(size 1.27 1.27)
				)
			)
		)
		(duplicate_pad_numbers_are_jumpers no)
		(fp_line
			(start -0.7874 0.4064)
			(end -0.7874 -0.4064)
			(stroke
				(width 0.1524)
				(type default)
			)
			(layer "F.SilkS")
		)
		(fp_line
			(start 0.7874 0.4064)
			(end -0.7874 0.4064)
			(stroke
				(width 0.1524)
				(type default)
			)
			(layer "F.SilkS")
		)
		(fp_line
			(start -0.7874 -0.4064)
			(end 0.7874 -0.4064)
			(stroke
				(width 0.1524)
				(type default)
			)
			(layer "F.SilkS")
		)
		(fp_line
			(start 0.7874 -0.4064)
			(end 0.7874 0.4064)
			(stroke
				(width 0.1524)
				(type default)
			)
			(layer "F.SilkS")
		)
		(fp_line
			(start -0.67945 0.3048)
			(end -0.67945 -0.305054)
			(stroke
				(width 0.1)
				(type default)
			)
			(layer "F.Fab")
		)
		(fp_line
			(start -0.12065 0.3048)
			(end -0.67945 0.3048)
			(stroke
				(width 0.1)
				(type default)
			)
			(layer "F.Fab")
		)
		(fp_line
			(start 0.120396 0.3048)
			(end 0.120396 0.2794)
			(stroke
				(width 0.1)
				(type default)
			)
			(layer "F.Fab")
		)
		(fp_line
			(start 0.67945 0.3048)
			(end 0.120396 0.3048)
			(stroke
				(width 0.1)
				(type default)
			)
			(layer "F.Fab")
		)
		(fp_line
			(start -0.12065 0.2794)
			(end -0.12065 0.3048)
			(stroke
				(width 0.1)
				(type default)
			)
			(layer "F.Fab")
		)
		(fp_line
			(start 0.120396 0.2794)
			(end -0.12065 0.2794)
			(stroke
				(width 0.1)
				(type default)
			)
			(layer "F.Fab")
		)
		(fp_line
			(start -0.12065 -0.2794)
			(end 0.12065 -0.2794)
			(stroke
				(width 0.1)
				(type default)
			)
			(layer "F.Fab")
		)
		(fp_line
			(start 0.12065 -0.2794)
			(end 0.12065 -0.3048)
			(stroke
				(width 0.1)
				(type default)
			)
			(layer "F.Fab")
		)
		(fp_line
			(start 0.12065 -0.3048)
			(end 0.67945 -0.3048)
			(stroke
				(width 0.1)
				(type default)
			)
			(layer "F.Fab")
		)
		(fp_line
			(start 0.67945 -0.3048)
			(end 0.67945 0.3048)
			(stroke
				(width 0.1)
				(type default)
			)
			(layer "F.Fab")
		)
		(fp_line
			(start -0.67945 -0.305054)
			(end -0.12065 -0.305054)
			(stroke
				(width 0.1)
				(type default)
			)
			(layer "F.Fab")
		)
		(fp_line
			(start -0.12065 -0.305054)
			(end -0.12065 -0.2794)
			(stroke
				(width 0.1)
				(type default)
			)
			(layer "F.Fab")
		)
		(pad "1" smd circle
			(at -0.40005 0 270)
			(size 0 0)
			(layers "F.Cu" "F.Mask" "F.Paste")
			(net "P3V3_AUX")
		)
		(pad "2" smd circle
			(at 0.40005 0 270)
			(size 0 0)
			(layers "F.Cu" "F.Mask" "F.Paste")
			(net "GND")
		)
	)
	(footprint ""
		(layer "F.Cu")
		(at 366.288574 -5.077206 180)
		(property "Reference" "J63"
			(at -4.50723 -1.072642 90)
			(unlocked yes)
			(layer "F.SilkS")
			(effects
				(font
					(size 0.7874 0.5842)
					(thickness 0.1524)
				)
				(justify left)
			)
		)
		(property "Value" ""
			(at 0 0 180)
			(layer "F.Fab")
			(effects
				(font
					(size 1.27 1.27)
				)
			)
		)
		(duplicate_pad_numbers_are_jumpers no)
		(fp_line
			(start 1.2192 2.06756)
			(end -1.2192 2.06756)
			(stroke
				(width 0.1524)
				(type default)
			)
			(layer "F.SilkS")
		)
		(fp_line
			(start 1.2192 -2.06756)
			(end 1.2192 2.06756)
			(stroke
				(width 0.1524)
				(type default)
			)
			(layer "F.SilkS")
		)
		(fp_line
			(start -1.2192 2.06756)
			(end -1.2192 -2.06756)
			(stroke
				(width 0.1524)
				(type default)
			)
			(layer "F.SilkS")
		)
		(fp_line
			(start -1.2192 -2.06756)
			(end 1.2192 -2.06756)
			(stroke
				(width 0.1524)
				(type default)
			)
			(layer "F.SilkS")
		)
		(pad "" np_thru_hole circle
			(at -2.8829 -1.27 90)
			(size 1.0414 1.0414)
			(drill 1.0414)
			(layers "*.Cu" "*.Mask")
			(clearance 0.381)
			(thermal_gap 0.381)
		)
		(pad "" np_thru_hole circle
			(at -2.8829 1.27 90)
			(size 1.0414 1.0414)
			(drill 1.0414)
			(layers "*.Cu" "*.Mask")
			(clearance 0.381)
			(thermal_gap 0.381)
		)
		(pad "" np_thru_hole circle
			(at 3.4671 -1.27 90)
			(size 1.0414 1.0414)
			(drill 1.0414)
			(layers "*.Cu" "*.Mask")
			(clearance 0.381)
			(thermal_gap 0.381)
		)
		(pad "" np_thru_hole circle
			(at 3.4671 1.27 90)
			(size 1.0414 1.0414)
			(drill 1.0414)
			(layers "*.Cu" "*.Mask")
			(clearance 0.381)
			(thermal_gap 0.381)
		)
		(pad "1" smd rect
			(at 0.8255 -0.249936 90)
			(size 0.3048 0.508)
			(layers "F.Cu" "F.Mask" "F.Paste")
			(net "DELTA_L_85_5INCH_TOP_DP")
		)
		(pad "2" smd rect
			(at 0.8255 0.249936 90)
			(size 0.3048 0.508)
			(layers "F.Cu" "F.Mask" "F.Paste")
			(net "DELTA_L_85_5INCH_TOP_DN")
		)
		(pad "3" smd circle
			(at 0 0 180)
			(size 0 0)
			(layers "F.Cu" "F.Mask" "F.Paste")
			(net "DELTA_L_GND_1")
		)
		(zone
			(layer "F.Cu")
			(hatch none 0.5)
			(connect_pads
				(clearance 0)
			)
			(min_thickness 0.25)
			(keepout
				(tracks not_allowed)
				(vias allowed)
				(pads allowed)
				(copperpour not_allowed)
				(footprints allowed)
			)
			(placement
				(enabled no)
				(sheetname "")
			)
			(fill
				(thermal_gap 0.5)
				(thermal_bridge_width 0.5)
				(island_removal_mode 0)
			)
			(polygon
				(pts
					(xy 365.170974 -4.528566) (xy 365.170974 -4.62407) (xy 365.767874 -4.62407) (xy 365.767874 -5.03047)
					(xy 365.170974 -5.03047) (xy 365.170974 -5.123942) (xy 365.767874 -5.123942) (xy 365.767874 -5.530342)
					(xy 365.170974 -5.530342) (xy 365.170974 -5.625846) (xy 365.869474 -5.625846) (xy 365.869474 -4.528566)
				)
			)
		)
		(zone
			(layers "F.Cu" "B.Cu" "In1.Cu" "In2.Cu" "In3.Cu" "In4.Cu" "In5.Cu" "In6.Cu"
				"In7.Cu" "In8.Cu" "In9.Cu" "In10.Cu" "In11.Cu" "In12.Cu" "In13.Cu" "In14.Cu"
				"In15.Cu" "In16.Cu"
			)
			(hatch none 0.5)
			(connect_pads
				(clearance 0)
			)
			(min_thickness 0.25)
			(keepout
				(tracks not_allowed)
				(vias allowed)
				(pads allowed)
				(copperpour not_allowed)
				(footprints allowed)
			)
			(placement
				(enabled no)
				(sheetname "")
			)
			(fill
				(thermal_gap 0.5)
				(thermal_bridge_width 0.5)
				(island_removal_mode 0)
			)
			(polygon
				(pts
					(arc
						(start 363.748574 -6.347206)
						(mid 361.894374 -6.347206)
						(end 363.748574 -6.347206)
					)
				)
			)
		)
		(zone
			(layers "F.Cu" "B.Cu" "In1.Cu" "In2.Cu" "In3.Cu" "In4.Cu" "In5.Cu" "In6.Cu"
				"In7.Cu" "In8.Cu" "In9.Cu" "In10.Cu" "In11.Cu" "In12.Cu" "In13.Cu" "In14.Cu"
				"In15.Cu" "In16.Cu"
			)
			(hatch none 0.5)
			(connect_pads
				(clearance 0)
			)
			(min_thickness 0.25)
			(keepout
				(tracks not_allowed)
				(vias allowed)
				(pads allowed)
				(copperpour not_allowed)
				(footprints allowed)
			)
			(placement
				(enabled no)
				(sheetname "")
			)
			(fill
				(thermal_gap 0.5)
				(thermal_bridge_width 0.5)
				(island_removal_mode 0)
			)
			(polygon
				(pts
					(arc
						(start 363.748574 -3.807206)
						(mid 361.894374 -3.807206)
						(end 363.748574 -3.807206)
					)
				)
			)
		)
		(zone
			(layers "F.Cu" "B.Cu" "In1.Cu" "In2.Cu" "In3.Cu" "In4.Cu" "In5.Cu" "In6.Cu"
				"In7.Cu" "In8.Cu" "In9.Cu" "In10.Cu" "In11.Cu" "In12.Cu" "In13.Cu" "In14.Cu"
				"In15.Cu" "In16.Cu"
			)
			(hatch none 0.5)
			(connect_pads
				(clearance 0)
			)
			(min_thickness 0.25)
			(keepout
				(tracks not_allowed)
				(vias allowed)
				(pads allowed)
				(copperpour not_allowed)
				(footprints allowed)
			)
			(placement
				(enabled no)
				(sheetname "")
			)
			(fill
				(thermal_gap 0.5)
				(thermal_bridge_width 0.5)
				(island_removal_mode 0)
			)
			(polygon
				(pts
					(arc
						(start 370.098574 -6.347206)
						(mid 368.244374 -6.347206)
						(end 370.098574 -6.347206)
					)
				)
			)
		)
		(zone
			(layers "F.Cu" "B.Cu" "In1.Cu" "In2.Cu" "In3.Cu" "In4.Cu" "In5.Cu" "In6.Cu"
				"In7.Cu" "In8.Cu" "In9.Cu" "In10.Cu" "In11.Cu" "In12.Cu" "In13.Cu" "In14.Cu"
				"In15.Cu" "In16.Cu"
			)
			(hatch none 0.5)
			(connect_pads
				(clearance 0)
			)
			(min_thickness 0.25)
			(keepout
				(tracks not_allowed)
				(vias allowed)
				(pads allowed)
				(copperpour not_allowed)
				(footprints allowed)
			)
			(placement
				(enabled no)
				(sheetname "")
			)
			(fill
				(thermal_gap 0.5)
				(thermal_bridge_width 0.5)
				(island_removal_mode 0)
			)
			(polygon
				(pts
					(arc
						(start 370.098574 -3.807206)
						(mid 368.244374 -3.807206)
						(end 370.098574 -3.807206)
					)
				)
			)
		)
	)
	(footprint ""
		(layer "F.Cu")
		(at 100.696268 -395.6304 -90)
		(property "Reference" "R731"
			(at 0 0 270)
			(layer "F.SilkS")
			(hide yes)
			(effects
				(font
					(size 1.27 1.27)
				)
			)
		)
		(property "Value" ""
			(at 0 0 270)
			(layer "F.Fab")
			(effects
				(font
					(size 1.27 1.27)
				)
			)
		)
		(duplicate_pad_numbers_are_jumpers no)
		(fp_line
			(start -0.32512 0.175006)
			(end -0.32512 -0.175006)
			(stroke
				(width 0.1)
				(type default)
			)
			(layer "F.Fab")
		)
		(fp_line
			(start 0.32512 0.175006)
			(end -0.32512 0.175006)
			(stroke
				(width 0.1)
				(type default)
			)
			(layer "F.Fab")
		)
		(fp_line
			(start -0.32512 -0.175006)
			(end 0.32512 -0.175006)
			(stroke
				(width 0.1)
				(type default)
			)
			(layer "F.Fab")
		)
		(fp_line
			(start 0.32512 -0.175006)
			(end 0.32512 0.175006)
			(stroke
				(width 0.1)
				(type default)
			)
			(layer "F.Fab")
		)
		(pad "1" smd rect
			(at -0.2667 0 270)
			(size 0.3048 0.381)
			(layers "F.Cu" "F.Mask" "F.Paste")
			(net "RST_RT_CPU1_P1_PERST_N")
		)
		(pad "2" smd rect
			(at 0.2667 0 90)
			(size 0.3048 0.381)
			(layers "F.Cu" "F.Mask" "F.Paste")
			(net "RST_RT_CPU1_P1_PERST_R_N")
		)
	)
	(footprint ""
		(layer "F.Cu")
		(at 308.420516 -435.720744 -90)
		(property "Reference" "R3437"
			(at 0 0 270)
			(layer "F.SilkS")
			(hide yes)
			(effects
				(font
					(size 1.27 1.27)
				)
			)
		)
		(property "Value" ""
			(at 0 0 270)
			(layer "F.Fab")
			(effects
				(font
					(size 1.27 1.27)
				)
			)
		)
		(duplicate_pad_numbers_are_jumpers no)
		(fp_line
			(start -0.7874 0.4064)
			(end -0.7874 -0.4064)
			(stroke
				(width 0.1524)
				(type default)
			)
			(layer "F.SilkS")
		)
		(fp_line
			(start 0.7874 0.4064)
			(end -0.7874 0.4064)
			(stroke
				(width 0.1524)
				(type default)
			)
			(layer "F.SilkS")
		)
		(fp_line
			(start -0.7874 -0.4064)
			(end 0.7874 -0.4064)
			(stroke
				(width 0.1524)
				(type default)
			)
			(layer "F.SilkS")
		)
		(fp_line
			(start 0.7874 -0.4064)
			(end 0.7874 0.4064)
			(stroke
				(width 0.1524)
				(type default)
			)
			(layer "F.SilkS")
		)
		(fp_line
			(start -0.67945 0.3048)
			(end -0.67945 -0.305054)
			(stroke
				(width 0.1)
				(type default)
			)
			(layer "F.Fab")
		)
		(fp_line
			(start -0.12065 0.3048)
			(end -0.67945 0.3048)
			(stroke
				(width 0.1)
				(type default)
			)
			(layer "F.Fab")
		)
		(fp_line
			(start 0.120396 0.3048)
			(end 0.120396 0.2794)
			(stroke
				(width 0.1)
				(type default)
			)
			(layer "F.Fab")
		)
		(fp_line
			(start 0.67945 0.3048)
			(end 0.120396 0.3048)
			(stroke
				(width 0.1)
				(type default)
			)
			(layer "F.Fab")
		)
		(fp_line
			(start -0.12065 0.2794)
			(end -0.12065 0.3048)
			(stroke
				(width 0.1)
				(type default)
			)
			(layer "F.Fab")
		)
		(fp_line
			(start 0.120396 0.2794)
			(end -0.12065 0.2794)
			(stroke
				(width 0.1)
				(type default)
			)
			(layer "F.Fab")
		)
		(fp_line
			(start -0.12065 -0.2794)
			(end 0.12065 -0.2794)
			(stroke
				(width 0.1)
				(type default)
			)
			(layer "F.Fab")
		)
		(fp_line
			(start 0.12065 -0.2794)
			(end 0.12065 -0.3048)
			(stroke
				(width 0.1)
				(type default)
			)
			(layer "F.Fab")
		)
		(fp_line
			(start 0.12065 -0.3048)
			(end 0.67945 -0.3048)
			(stroke
				(width 0.1)
				(type default)
			)
			(layer "F.Fab")
		)
		(fp_line
			(start 0.67945 -0.3048)
			(end 0.67945 0.3048)
			(stroke
				(width 0.1)
				(type default)
			)
			(layer "F.Fab")
		)
		(fp_line
			(start -0.67945 -0.305054)
			(end -0.12065 -0.305054)
			(stroke
				(width 0.1)
				(type default)
			)
			(layer "F.Fab")
		)
		(fp_line
			(start -0.12065 -0.305054)
			(end -0.12065 -0.2794)
			(stroke
				(width 0.1)
				(type default)
			)
			(layer "F.Fab")
		)
		(pad "1" smd circle
			(at -0.40005 0 270)
			(size 0 0)
			(layers "F.Cu" "F.Mask" "F.Paste")
			(net "P3V3_AUX")
		)
		(pad "2" smd circle
			(at 0.40005 0 270)
			(size 0 0)
			(layers "F.Cu" "F.Mask" "F.Paste")
			(net "GPU_FPGA_OVERT_ISO_N")
		)
	)
	(footprint ""
		(layer "F.Cu")
		(at 319.999106 -416.899344 -90)
		(property "Reference" "C6511"
			(at 0 0 270)
			(layer "F.SilkS")
			(hide yes)
			(effects
				(font
					(size 1.27 1.27)
				)
			)
		)
		(property "Value" ""
			(at 0 0 270)
			(layer "F.Fab")
			(effects
				(font
					(size 1.27 1.27)
				)
			)
		)
		(duplicate_pad_numbers_are_jumpers no)
		(fp_line
			(start -0.299974 0.150114)
			(end -0.299974 -0.150114)
			(stroke
				(width 0.1)
				(type default)
			)
			(layer "F.Fab")
		)
		(fp_line
			(start 0.299974 0.150114)
			(end -0.299974 0.150114)
			(stroke
				(width 0.1)
				(type default)
			)
			(layer "F.Fab")
		)
		(fp_line
			(start -0.299974 -0.150114)
			(end 0.299974 -0.150114)
			(stroke
				(width 0.1)
				(type default)
			)
			(layer "F.Fab")
		)
		(fp_line
			(start 0.299974 -0.150114)
			(end 0.299974 0.150114)
			(stroke
				(width 0.1)
				(type default)
			)
			(layer "F.Fab")
		)
		(pad "1" smd rect
			(at -0.2667 0 270)
			(size 0.3048 0.381)
			(layers "F.Cu" "F.Mask" "F.Paste")
			(net "P5E_CPU0_P0_TX_BUF_C_DP<5>")
		)
		(pad "2" smd rect
			(at 0.2667 0 270)
			(size 0.3048 0.381)
			(layers "F.Cu" "F.Mask" "F.Paste")
			(net "P5E_CPU0_P0_TX_BUF_DP<5>")
		)
	)
	(footprint ""
		(layer "F.Cu")
		(at 164.973 -96.012 90)
		(property "Reference" "C1058"
			(at 0 0 90)
			(layer "F.SilkS")
			(hide yes)
			(effects
				(font
					(size 1.27 1.27)
				)
			)
		)
		(property "Value" ""
			(at 0 0 90)
			(layer "F.Fab")
			(effects
				(font
					(size 1.27 1.27)
				)
			)
		)
		(duplicate_pad_numbers_are_jumpers no)
		(fp_line
			(start 0.7874 -0.4064)
			(end 0.7874 0.4064)
			(stroke
				(width 0.1524)
				(type default)
			)
			(layer "F.SilkS")
		)
		(fp_line
			(start -0.7874 -0.4064)
			(end 0.7874 -0.4064)
			(stroke
				(width 0.1524)
				(type default)
			)
			(layer "F.SilkS")
		)
		(fp_line
			(start 0.7874 0.4064)
			(end -0.7874 0.4064)
			(stroke
				(width 0.1524)
				(type default)
			)
			(layer "F.SilkS")
		)
		(fp_line
			(start -0.7874 0.4064)
			(end -0.7874 -0.4064)
			(stroke
				(width 0.1524)
				(type default)
			)
			(layer "F.SilkS")
		)
		(fp_line
			(start -0.12065 -0.305054)
			(end -0.12065 -0.2794)
			(stroke
				(width 0.1)
				(type default)
			)
			(layer "F.Fab")
		)
		(fp_line
			(start -0.67945 -0.305054)
			(end -0.12065 -0.305054)
			(stroke
				(width 0.1)
				(type default)
			)
			(layer "F.Fab")
		)
		(fp_line
			(start 0.67945 -0.3048)
			(end 0.67945 0.3048)
			(stroke
				(width 0.1)
				(type default)
			)
			(layer "F.Fab")
		)
		(fp_line
			(start 0.12065 -0.3048)
			(end 0.67945 -0.3048)
			(stroke
				(width 0.1)
				(type default)
			)
			(layer "F.Fab")
		)
		(fp_line
			(start 0.12065 -0.2794)
			(end 0.12065 -0.3048)
			(stroke
				(width 0.1)
				(type default)
			)
			(layer "F.Fab")
		)
		(fp_line
			(start -0.12065 -0.2794)
			(end 0.12065 -0.2794)
			(stroke
				(width 0.1)
				(type default)
			)
			(layer "F.Fab")
		)
		(fp_line
			(start 0.120396 0.2794)
			(end -0.12065 0.2794)
			(stroke
				(width 0.1)
				(type default)
			)
			(layer "F.Fab")
		)
		(fp_line
			(start -0.12065 0.2794)
			(end -0.12065 0.3048)
			(stroke
				(width 0.1)
				(type default)
			)
			(layer "F.Fab")
		)
		(fp_line
			(start 0.67945 0.3048)
			(end 0.120396 0.3048)
			(stroke
				(width 0.1)
				(type default)
			)
			(layer "F.Fab")
		)
		(fp_line
			(start 0.120396 0.3048)
			(end 0.120396 0.2794)
			(stroke
				(width 0.1)
				(type default)
			)
			(layer "F.Fab")
		)
		(fp_line
			(start -0.12065 0.3048)
			(end -0.67945 0.3048)
			(stroke
				(width 0.1)
				(type default)
			)
			(layer "F.Fab")
		)
		(fp_line
			(start -0.67945 0.3048)
			(end -0.67945 -0.305054)
			(stroke
				(width 0.1)
				(type default)
			)
			(layer "F.Fab")
		)
		(pad "1" smd circle
			(at -0.40005 0 90)
			(size 0 0)
			(layers "F.Cu" "F.Mask" "F.Paste")
			(net "P3V3_AUX")
		)
		(pad "2" smd circle
			(at 0.40005 0 90)
			(size 0 0)
			(layers "F.Cu" "F.Mask" "F.Paste")
			(net "GND")
		)
	)
	(footprint ""
		(layer "F.Cu")
		(at 111.633 -125.73 90)
		(property "Reference" "R6500"
			(at 0 0 90)
			(layer "F.SilkS")
			(hide yes)
			(effects
				(font
					(size 1.27 1.27)
				)
			)
		)
		(property "Value" ""
			(at 0 0 90)
			(layer "F.Fab")
			(effects
				(font
					(size 1.27 1.27)
				)
			)
		)
		(duplicate_pad_numbers_are_jumpers no)
		(fp_line
			(start 0.7874 -0.4064)
			(end 0.7874 0.4064)
			(stroke
				(width 0.1524)
				(type default)
			)
			(layer "F.SilkS")
		)
		(fp_line
			(start -0.7874 -0.4064)
			(end 0.7874 -0.4064)
			(stroke
				(width 0.1524)
				(type default)
			)
			(layer "F.SilkS")
		)
		(fp_line
			(start 0.7874 0.4064)
			(end -0.7874 0.4064)
			(stroke
				(width 0.1524)
				(type default)
			)
			(layer "F.SilkS")
		)
		(fp_line
			(start -0.7874 0.4064)
			(end -0.7874 -0.4064)
			(stroke
				(width 0.1524)
				(type default)
			)
			(layer "F.SilkS")
		)
		(fp_line
			(start -0.12065 -0.305054)
			(end -0.12065 -0.2794)
			(stroke
				(width 0.1)
				(type default)
			)
			(layer "F.Fab")
		)
		(fp_line
			(start -0.67945 -0.305054)
			(end -0.12065 -0.305054)
			(stroke
				(width 0.1)
				(type default)
			)
			(layer "F.Fab")
		)
		(fp_line
			(start 0.67945 -0.3048)
			(end 0.67945 0.3048)
			(stroke
				(width 0.1)
				(type default)
			)
			(layer "F.Fab")
		)
		(fp_line
			(start 0.12065 -0.3048)
			(end 0.67945 -0.3048)
			(stroke
				(width 0.1)
				(type default)
			)
			(layer "F.Fab")
		)
		(fp_line
			(start 0.12065 -0.2794)
			(end 0.12065 -0.3048)
			(stroke
				(width 0.1)
				(type default)
			)
			(layer "F.Fab")
		)
		(fp_line
			(start -0.12065 -0.2794)
			(end 0.12065 -0.2794)
			(stroke
				(width 0.1)
				(type default)
			)
			(layer "F.Fab")
		)
		(fp_line
			(start 0.120396 0.2794)
			(end -0.12065 0.2794)
			(stroke
				(width 0.1)
				(type default)
			)
			(layer "F.Fab")
		)
		(fp_line
			(start -0.12065 0.2794)
			(end -0.12065 0.3048)
			(stroke
				(width 0.1)
				(type default)
			)
			(layer "F.Fab")
		)
		(fp_line
			(start 0.67945 0.3048)
			(end 0.120396 0.3048)
			(stroke
				(width 0.1)
				(type default)
			)
			(layer "F.Fab")
		)
		(fp_line
			(start 0.120396 0.3048)
			(end 0.120396 0.2794)
			(stroke
				(width 0.1)
				(type default)
			)
			(layer "F.Fab")
		)
		(fp_line
			(start -0.12065 0.3048)
			(end -0.67945 0.3048)
			(stroke
				(width 0.1)
				(type default)
			)
			(layer "F.Fab")
		)
		(fp_line
			(start -0.67945 0.3048)
			(end -0.67945 -0.305054)
			(stroke
				(width 0.1)
				(type default)
			)
			(layer "F.Fab")
		)
		(pad "1" smd circle
			(at -0.40005 0 90)
			(size 0 0)
			(layers "F.Cu" "F.Mask" "F.Paste")
			(net "PWRGD_P3V3_EN_R")
		)
		(pad "2" smd circle
			(at 0.40005 0 90)
			(size 0 0)
			(layers "F.Cu" "F.Mask" "F.Paste")
			(net "PWRGD_P3V3_EN")
		)
	)
	(footprint ""
		(layer "F.Cu")
		(at 237.507272 -68.524374 180)
		(property "Reference" "U44"
			(at 1.378204 -2.10566 0)
			(unlocked yes)
			(layer "F.SilkS")
			(effects
				(font
					(size 0.7874 0.5842)
					(thickness 0.1524)
				)
				(justify left)
			)
		)
		(property "Value" ""
			(at 0 0 180)
			(layer "F.Fab")
			(effects
				(font
					(size 1.27 1.27)
				)
			)
		)
		(duplicate_pad_numbers_are_jumpers no)
		(fp_line
			(start 1.695958 1.124966)
			(end -1.695958 1.124966)
			(stroke
				(width 0.1524)
				(type default)
			)
			(layer "F.SilkS")
		)
		(fp_line
			(start 1.695958 -1.124966)
			(end 1.695958 1.124966)
			(stroke
				(width 0.1524)
				(type default)
			)
			(layer "F.SilkS")
		)
		(fp_line
			(start -1.695958 1.124966)
			(end -1.695958 -1.124966)
			(stroke
				(width 0.1524)
				(type default)
			)
			(layer "F.SilkS")
		)
		(fp_line
			(start -1.695958 -1.124966)
			(end 1.695958 -1.124966)
			(stroke
				(width 0.1524)
				(type default)
			)
			(layer "F.SilkS")
		)
		(fp_poly
			(pts
				(xy -2.4892 -0.340106) (xy -2.4892 -0.959866) (xy -1.86944 -0.649986)
			)
			(stroke
				(width 0)
				(type default)
			)
			(fill yes)
			(layer "F.SilkS")
		)
		(fp_line
			(start 0.674878 1.124966)
			(end -0.674878 1.124966)
			(stroke
				(width 0.1)
				(type default)
			)
			(layer "F.Fab")
		)
		(fp_line
			(start 0.674878 -1.124966)
			(end 0.674878 1.124966)
			(stroke
				(width 0.1)
				(type default)
			)
			(layer "F.Fab")
		)
		(fp_line
			(start -0.674878 1.124966)
			(end -0.674878 -1.124966)
			(stroke
				(width 0.1)
				(type default)
			)
			(layer "F.Fab")
		)
		(fp_line
			(start -0.674878 -1.124966)
			(end 0.674878 -1.124966)
			(stroke
				(width 0.1)
				(type default)
			)
			(layer "F.Fab")
		)
		(fp_poly
			(pts
				(xy -2.4892 -0.959866) (xy -1.86944 -0.649986) (xy -2.4892 -0.340106)
			)
			(stroke
				(width 0)
				(type default)
			)
			(fill yes)
			(layer "F.Fab")
		)
		(pad "1" smd rect
			(at -0.94488 -0.649986 270)
			(size 0.3556 1.2446)
			(layers "F.Cu" "F.Mask" "F.Paste")
			(net "Net_10764")
		)
		(pad "2" smd rect
			(at -0.94488 0 270)
			(size 0.3556 1.2446)
			(layers "F.Cu" "F.Mask" "F.Paste")
			(net "FM_LED_ACTIVE_E1S_0_R")
		)
		(pad "3" smd rect
			(at -0.94488 0.649986 270)
			(size 0.3556 1.2446)
			(layers "F.Cu" "F.Mask" "F.Paste")
			(net "GND")
		)
		(pad "4" smd rect
			(at 0.94488 0.649986 270)
			(size 0.3556 1.2446)
			(layers "F.Cu" "F.Mask" "F.Paste")
			(net "FM_LED_ACTIVE_E1S_0_R_BUF")
		)
		(pad "5" smd rect
			(at 0.94488 -0.649986 270)
			(size 0.3556 1.2446)
			(layers "F.Cu" "F.Mask" "F.Paste")
			(net "P3V3_E1S_0")
		)
	)
	(footprint ""
		(layer "F.Cu")
		(at 90.487754 -350.497394 90)
		(property "Reference" "PL42"
			(at -2.671064 3.492246 0)
			(unlocked yes)
			(layer "F.SilkS")
			(effects
				(font
					(size 0.7874 0.5842)
					(thickness 0.1524)
				)
				(justify left)
			)
		)
		(property "Value" ""
			(at 0 0 90)
			(layer "F.Fab")
			(effects
				(font
					(size 1.27 1.27)
				)
			)
		)
		(duplicate_pad_numbers_are_jumpers no)
		(fp_line
			(start 3.050032 -2.999994)
			(end -3.050032 -2.999994)
			(stroke
				(width 0.1524)
				(type default)
			)
			(layer "F.SilkS")
		)
		(fp_line
			(start -3.050032 -2.999994)
			(end -3.050032 -1.4478)
			(stroke
				(width 0.1524)
				(type default)
			)
			(layer "F.SilkS")
		)
		(fp_line
			(start 3.050032 -1.4478)
			(end 3.050032 -2.999994)
			(stroke
				(width 0.1524)
				(type default)
			)
			(layer "F.SilkS")
		)
		(fp_line
			(start -3.050032 1.4478)
			(end -3.050032 2.999994)
			(stroke
				(width 0.1524)
				(type default)
			)
			(layer "F.SilkS")
		)
		(fp_line
			(start 3.050032 2.999994)
			(end 3.050032 1.4478)
			(stroke
				(width 0.1524)
				(type default)
			)
			(layer "F.SilkS")
		)
		(fp_line
			(start -3.050032 2.999994)
			(end 3.050032 2.999994)
			(stroke
				(width 0.1524)
				(type default)
			)
			(layer "F.SilkS")
		)
		(fp_line
			(start 3.050032 -2.999994)
			(end -3.050032 -2.999994)
			(stroke
				(width 0.1)
				(type default)
			)
			(layer "F.Fab")
		)
		(fp_line
			(start -3.050032 -2.999994)
			(end -3.050032 2.999994)
			(stroke
				(width 0.1)
				(type default)
			)
			(layer "F.Fab")
		)
		(fp_line
			(start 3.050032 2.999994)
			(end 3.050032 -2.999994)
			(stroke
				(width 0.1)
				(type default)
			)
			(layer "F.Fab")
		)
		(fp_line
			(start -3.050032 2.999994)
			(end 3.050032 2.999994)
			(stroke
				(width 0.1)
				(type default)
			)
			(layer "F.Fab")
		)
		(pad "1" smd rect
			(at -2.525014 0 90)
			(size 1.651 2.6162)
			(layers "F.Cu" "F.Mask" "F.Paste")
			(net "SW_P12V_AUX_PVDDCR_CPU1_P1_FLT")
		)
		(pad "2" smd rect
			(at 2.525014 0 90)
			(size 1.651 2.6162)
			(layers "F.Cu" "F.Mask" "F.Paste")
			(net "P12V_AUX")
		)
	)
	(footprint ""
		(layer "F.Cu")
		(at 163.743894 -120.37187)
		(property "Reference" "R6031"
			(at 0 0 0)
			(layer "F.SilkS")
			(hide yes)
			(effects
				(font
					(size 1.27 1.27)
				)
			)
		)
		(property "Value" ""
			(at 0 0 0)
			(layer "F.Fab")
			(effects
				(font
					(size 1.27 1.27)
				)
			)
		)
		(duplicate_pad_numbers_are_jumpers no)
		(fp_line
			(start -0.7874 -0.4064)
			(end 0.7874 -0.4064)
			(stroke
				(width 0.1524)
				(type default)
			)
			(layer "F.SilkS")
		)
		(fp_line
			(start -0.7874 0.4064)
			(end -0.7874 -0.4064)
			(stroke
				(width 0.1524)
				(type default)
			)
			(layer "F.SilkS")
		)
		(fp_line
			(start 0.7874 -0.4064)
			(end 0.7874 0.4064)
			(stroke
				(width 0.1524)
				(type default)
			)
			(layer "F.SilkS")
		)
		(fp_line
			(start 0.7874 0.4064)
			(end -0.7874 0.4064)
			(stroke
				(width 0.1524)
				(type default)
			)
			(layer "F.SilkS")
		)
		(fp_line
			(start -0.67945 -0.305054)
			(end -0.12065 -0.305054)
			(stroke
				(width 0.1)
				(type default)
			)
			(layer "F.Fab")
		)
		(fp_line
			(start -0.67945 0.3048)
			(end -0.67945 -0.305054)
			(stroke
				(width 0.1)
				(type default)
			)
			(layer "F.Fab")
		)
		(fp_line
			(start -0.12065 -0.305054)
			(end -0.12065 -0.2794)
			(stroke
				(width 0.1)
				(type default)
			)
			(layer "F.Fab")
		)
		(fp_line
			(start -0.12065 -0.2794)
			(end 0.12065 -0.2794)
			(stroke
				(width 0.1)
				(type default)
			)
			(layer "F.Fab")
		)
		(fp_line
			(start -0.12065 0.2794)
			(end -0.12065 0.3048)
			(stroke
				(width 0.1)
				(type default)
			)
			(layer "F.Fab")
		)
		(fp_line
			(start -0.12065 0.3048)
			(end -0.67945 0.3048)
			(stroke
				(width 0.1)
				(type default)
			)
			(layer "F.Fab")
		)
		(fp_line
			(start 0.120396 0.2794)
			(end -0.12065 0.2794)
			(stroke
				(width 0.1)
				(type default)
			)
			(layer "F.Fab")
		)
		(fp_line
			(start 0.120396 0.3048)
			(end 0.120396 0.2794)
			(stroke
				(width 0.1)
				(type default)
			)
			(layer "F.Fab")
		)
		(fp_line
			(start 0.12065 -0.3048)
			(end 0.67945 -0.3048)
			(stroke
				(width 0.1)
				(type default)
			)
			(layer "F.Fab")
		)
		(fp_line
			(start 0.12065 -0.2794)
			(end 0.12065 -0.3048)
			(stroke
				(width 0.1)
				(type default)
			)
			(layer "F.Fab")
		)
		(fp_line
			(start 0.67945 -0.3048)
			(end 0.67945 0.3048)
			(stroke
				(width 0.1)
				(type default)
			)
			(layer "F.Fab")
		)
		(fp_line
			(start 0.67945 0.3048)
			(end 0.120396 0.3048)
			(stroke
				(width 0.1)
				(type default)
			)
			(layer "F.Fab")
		)
		(pad "1" smd circle
			(at -0.40005 0)
			(size 0 0)
			(layers "F.Cu" "F.Mask" "F.Paste")
			(net "VIRTUAL_RESEAT_FPGA_N")
		)
		(pad "2" smd circle
			(at 0.40005 0)
			(size 0 0)
			(layers "F.Cu" "F.Mask" "F.Paste")
			(net "VIRTUAL_RESEAT_FPGA_R_N")
		)
	)
	(footprint ""
		(layer "F.Cu")
		(at 319.411096 -381.41783 -90)
		(property "Reference" "C911"
			(at 0 0 270)
			(layer "F.SilkS")
			(hide yes)
			(effects
				(font
					(size 1.27 1.27)
				)
			)
		)
		(property "Value" ""
			(at 0 0 270)
			(layer "F.Fab")
			(effects
				(font
					(size 1.27 1.27)
				)
			)
		)
		(duplicate_pad_numbers_are_jumpers no)
		(fp_line
			(start -0.299974 0.150114)
			(end -0.299974 -0.150114)
			(stroke
				(width 0.1)
				(type default)
			)
			(layer "F.Fab")
		)
		(fp_line
			(start 0.299974 0.150114)
			(end -0.299974 0.150114)
			(stroke
				(width 0.1)
				(type default)
			)
			(layer "F.Fab")
		)
		(fp_line
			(start -0.299974 -0.150114)
			(end 0.299974 -0.150114)
			(stroke
				(width 0.1)
				(type default)
			)
			(layer "F.Fab")
		)
		(fp_line
			(start 0.299974 -0.150114)
			(end 0.299974 0.150114)
			(stroke
				(width 0.1)
				(type default)
			)
			(layer "F.Fab")
		)
		(pad "1" smd rect
			(at -0.2667 0 270)
			(size 0.3048 0.381)
			(layers "F.Cu" "F.Mask" "F.Paste")
			(net "P5E_CPU0_P0_TX_C_DP<11>")
		)
		(pad "2" smd rect
			(at 0.2667 0 270)
			(size 0.3048 0.381)
			(layers "F.Cu" "F.Mask" "F.Paste")
			(net "P5E_CPU0_P0_TX_DP<11>")
		)
	)
	(footprint ""
		(layer "F.Cu")
		(at 112.048798 -171.808902 90)
		(property "Reference" "PC323_1"
			(at 0 0 90)
			(layer "F.SilkS")
			(hide yes)
			(effects
				(font
					(size 1.27 1.27)
				)
			)
		)
		(property "Value" ""
			(at 0 0 90)
			(layer "F.Fab")
			(effects
				(font
					(size 1.27 1.27)
				)
			)
		)
		(duplicate_pad_numbers_are_jumpers no)
		(fp_line
			(start 0.7874 -0.4064)
			(end 0.7874 0.4064)
			(stroke
				(width 0.1524)
				(type default)
			)
			(layer "F.SilkS")
		)
		(fp_line
			(start -0.7874 -0.4064)
			(end 0.7874 -0.4064)
			(stroke
				(width 0.1524)
				(type default)
			)
			(layer "F.SilkS")
		)
		(fp_line
			(start 0.7874 0.4064)
			(end -0.7874 0.4064)
			(stroke
				(width 0.1524)
				(type default)
			)
			(layer "F.SilkS")
		)
		(fp_line
			(start -0.7874 0.4064)
			(end -0.7874 -0.4064)
			(stroke
				(width 0.1524)
				(type default)
			)
			(layer "F.SilkS")
		)
		(fp_line
			(start -0.12065 -0.305054)
			(end -0.12065 -0.2794)
			(stroke
				(width 0.1)
				(type default)
			)
			(layer "F.Fab")
		)
		(fp_line
			(start -0.67945 -0.305054)
			(end -0.12065 -0.305054)
			(stroke
				(width 0.1)
				(type default)
			)
			(layer "F.Fab")
		)
		(fp_line
			(start 0.67945 -0.3048)
			(end 0.67945 0.3048)
			(stroke
				(width 0.1)
				(type default)
			)
			(layer "F.Fab")
		)
		(fp_line
			(start 0.12065 -0.3048)
			(end 0.67945 -0.3048)
			(stroke
				(width 0.1)
				(type default)
			)
			(layer "F.Fab")
		)
		(fp_line
			(start 0.12065 -0.2794)
			(end 0.12065 -0.3048)
			(stroke
				(width 0.1)
				(type default)
			)
			(layer "F.Fab")
		)
		(fp_line
			(start -0.12065 -0.2794)
			(end 0.12065 -0.2794)
			(stroke
				(width 0.1)
				(type default)
			)
			(layer "F.Fab")
		)
		(fp_line
			(start 0.120396 0.2794)
			(end -0.12065 0.2794)
			(stroke
				(width 0.1)
				(type default)
			)
			(layer "F.Fab")
		)
		(fp_line
			(start -0.12065 0.2794)
			(end -0.12065 0.3048)
			(stroke
				(width 0.1)
				(type default)
			)
			(layer "F.Fab")
		)
		(fp_line
			(start 0.67945 0.3048)
			(end 0.120396 0.3048)
			(stroke
				(width 0.1)
				(type default)
			)
			(layer "F.Fab")
		)
		(fp_line
			(start 0.120396 0.3048)
			(end 0.120396 0.2794)
			(stroke
				(width 0.1)
				(type default)
			)
			(layer "F.Fab")
		)
		(fp_line
			(start -0.12065 0.3048)
			(end -0.67945 0.3048)
			(stroke
				(width 0.1)
				(type default)
			)
			(layer "F.Fab")
		)
		(fp_line
			(start -0.67945 0.3048)
			(end -0.67945 -0.305054)
			(stroke
				(width 0.1)
				(type default)
			)
			(layer "F.Fab")
		)
		(pad "1" smd circle
			(at -0.40005 0 90)
			(size 0 0)
			(layers "F.Cu" "F.Mask" "F.Paste")
			(net "SW_P12V_AUX_PVDDCR_SOC_P1_FLT")
		)
		(pad "2" smd circle
			(at 0.40005 0 90)
			(size 0 0)
			(layers "F.Cu" "F.Mask" "F.Paste")
			(net "GND")
		)
	)
	(footprint ""
		(layer "F.Cu")
		(at 440.088782 -438.14746 -90)
		(property "Reference" "R4571"
			(at 0 0 270)
			(layer "F.SilkS")
			(hide yes)
			(effects
				(font
					(size 1.27 1.27)
				)
			)
		)
		(property "Value" ""
			(at 0 0 270)
			(layer "F.Fab")
			(effects
				(font
					(size 1.27 1.27)
				)
			)
		)
		(duplicate_pad_numbers_are_jumpers no)
		(fp_line
			(start -0.7874 0.4064)
			(end -0.7874 -0.4064)
			(stroke
				(width 0.1524)
				(type default)
			)
			(layer "F.SilkS")
		)
		(fp_line
			(start 0.7874 0.4064)
			(end -0.7874 0.4064)
			(stroke
				(width 0.1524)
				(type default)
			)
			(layer "F.SilkS")
		)
		(fp_line
			(start -0.7874 -0.4064)
			(end 0.7874 -0.4064)
			(stroke
				(width 0.1524)
				(type default)
			)
			(layer "F.SilkS")
		)
		(fp_line
			(start 0.7874 -0.4064)
			(end 0.7874 0.4064)
			(stroke
				(width 0.1524)
				(type default)
			)
			(layer "F.SilkS")
		)
		(fp_line
			(start -0.67945 0.3048)
			(end -0.67945 -0.305054)
			(stroke
				(width 0.1)
				(type default)
			)
			(layer "F.Fab")
		)
		(fp_line
			(start -0.12065 0.3048)
			(end -0.67945 0.3048)
			(stroke
				(width 0.1)
				(type default)
			)
			(layer "F.Fab")
		)
		(fp_line
			(start 0.120396 0.3048)
			(end 0.120396 0.2794)
			(stroke
				(width 0.1)
				(type default)
			)
			(layer "F.Fab")
		)
		(fp_line
			(start 0.67945 0.3048)
			(end 0.120396 0.3048)
			(stroke
				(width 0.1)
				(type default)
			)
			(layer "F.Fab")
		)
		(fp_line
			(start -0.12065 0.2794)
			(end -0.12065 0.3048)
			(stroke
				(width 0.1)
				(type default)
			)
			(layer "F.Fab")
		)
		(fp_line
			(start 0.120396 0.2794)
			(end -0.12065 0.2794)
			(stroke
				(width 0.1)
				(type default)
			)
			(layer "F.Fab")
		)
		(fp_line
			(start -0.12065 -0.2794)
			(end 0.12065 -0.2794)
			(stroke
				(width 0.1)
				(type default)
			)
			(layer "F.Fab")
		)
		(fp_line
			(start 0.12065 -0.2794)
			(end 0.12065 -0.3048)
			(stroke
				(width 0.1)
				(type default)
			)
			(layer "F.Fab")
		)
		(fp_line
			(start 0.12065 -0.3048)
			(end 0.67945 -0.3048)
			(stroke
				(width 0.1)
				(type default)
			)
			(layer "F.Fab")
		)
		(fp_line
			(start 0.67945 -0.3048)
			(end 0.67945 0.3048)
			(stroke
				(width 0.1)
				(type default)
			)
			(layer "F.Fab")
		)
		(fp_line
			(start -0.67945 -0.305054)
			(end -0.12065 -0.305054)
			(stroke
				(width 0.1)
				(type default)
			)
			(layer "F.Fab")
		)
		(fp_line
			(start -0.12065 -0.305054)
			(end -0.12065 -0.2794)
			(stroke
				(width 0.1)
				(type default)
			)
			(layer "F.Fab")
		)
		(pad "1" smd circle
			(at -0.40005 0 270)
			(size 0 0)
			(layers "F.Cu" "F.Mask" "F.Paste")
			(net "GPU_3V3IO_RSVD4")
		)
		(pad "2" smd circle
			(at 0.40005 0 270)
			(size 0 0)
			(layers "F.Cu" "F.Mask" "F.Paste")
			(net "GPU_3V3IO_RSVD4_ISO")
		)
	)
	(footprint ""
		(layer "F.Cu")
		(at 92.559632 -74.68362 180)
		(property "Reference" "PC2169"
			(at 0 0 180)
			(layer "F.SilkS")
			(hide yes)
			(effects
				(font
					(size 1.27 1.27)
				)
			)
		)
		(property "Value" ""
			(at 0 0 180)
			(layer "F.Fab")
			(effects
				(font
					(size 1.27 1.27)
				)
			)
		)
		(duplicate_pad_numbers_are_jumpers no)
		(fp_line
			(start 0.7874 0.4064)
			(end -0.7874 0.4064)
			(stroke
				(width 0.1524)
				(type default)
			)
			(layer "F.SilkS")
		)
		(fp_line
			(start 0.7874 -0.4064)
			(end 0.7874 0.4064)
			(stroke
				(width 0.1524)
				(type default)
			)
			(layer "F.SilkS")
		)
		(fp_line
			(start -0.7874 0.4064)
			(end -0.7874 -0.4064)
			(stroke
				(width 0.1524)
				(type default)
			)
			(layer "F.SilkS")
		)
		(fp_line
			(start -0.7874 -0.4064)
			(end 0.7874 -0.4064)
			(stroke
				(width 0.1524)
				(type default)
			)
			(layer "F.SilkS")
		)
		(fp_line
			(start 0.67945 0.3048)
			(end 0.120396 0.3048)
			(stroke
				(width 0.1)
				(type default)
			)
			(layer "F.Fab")
		)
		(fp_line
			(start 0.67945 -0.3048)
			(end 0.67945 0.3048)
			(stroke
				(width 0.1)
				(type default)
			)
			(layer "F.Fab")
		)
		(fp_line
			(start 0.12065 -0.2794)
			(end 0.12065 -0.3048)
			(stroke
				(width 0.1)
				(type default)
			)
			(layer "F.Fab")
		)
		(fp_line
			(start 0.12065 -0.3048)
			(end 0.67945 -0.3048)
			(stroke
				(width 0.1)
				(type default)
			)
			(layer "F.Fab")
		)
		(fp_line
			(start 0.120396 0.3048)
			(end 0.120396 0.2794)
			(stroke
				(width 0.1)
				(type default)
			)
			(layer "F.Fab")
		)
		(fp_line
			(start 0.120396 0.2794)
			(end -0.12065 0.2794)
			(stroke
				(width 0.1)
				(type default)
			)
			(layer "F.Fab")
		)
		(fp_line
			(start -0.12065 0.3048)
			(end -0.67945 0.3048)
			(stroke
				(width 0.1)
				(type default)
			)
			(layer "F.Fab")
		)
		(fp_line
			(start -0.12065 0.2794)
			(end -0.12065 0.3048)
			(stroke
				(width 0.1)
				(type default)
			)
			(layer "F.Fab")
		)
		(fp_line
			(start -0.12065 -0.2794)
			(end 0.12065 -0.2794)
			(stroke
				(width 0.1)
				(type default)
			)
			(layer "F.Fab")
		)
		(fp_line
			(start -0.12065 -0.305054)
			(end -0.12065 -0.2794)
			(stroke
				(width 0.1)
				(type default)
			)
			(layer "F.Fab")
		)
		(fp_line
			(start -0.67945 0.3048)
			(end -0.67945 -0.305054)
			(stroke
				(width 0.1)
				(type default)
			)
			(layer "F.Fab")
		)
		(fp_line
			(start -0.67945 -0.305054)
			(end -0.12065 -0.305054)
			(stroke
				(width 0.1)
				(type default)
			)
			(layer "F.Fab")
		)
		(pad "1" smd circle
			(at -0.40005 0 180)
			(size 0 0)
			(layers "F.Cu" "F.Mask" "F.Paste")
			(net "P3V3_AUX")
		)
		(pad "2" smd circle
			(at 0.40005 0 180)
			(size 0 0)
			(layers "F.Cu" "F.Mask" "F.Paste")
			(net "GND")
		)
	)
	(footprint ""
		(layer "F.Cu")
		(at 153.486612 -40.04056 180)
		(property "Reference" "R3228"
			(at 0 0 180)
			(layer "F.SilkS")
			(hide yes)
			(effects
				(font
					(size 1.27 1.27)
				)
			)
		)
		(property "Value" ""
			(at 0 0 180)
			(layer "F.Fab")
			(effects
				(font
					(size 1.27 1.27)
				)
			)
		)
		(duplicate_pad_numbers_are_jumpers no)
		(fp_line
			(start 0.7874 0.4064)
			(end -0.7874 0.4064)
			(stroke
				(width 0.1524)
				(type default)
			)
			(layer "F.SilkS")
		)
		(fp_line
			(start 0.7874 -0.4064)
			(end 0.7874 0.4064)
			(stroke
				(width 0.1524)
				(type default)
			)
			(layer "F.SilkS")
		)
		(fp_line
			(start -0.7874 0.4064)
			(end -0.7874 -0.4064)
			(stroke
				(width 0.1524)
				(type default)
			)
			(layer "F.SilkS")
		)
		(fp_line
			(start -0.7874 -0.4064)
			(end 0.7874 -0.4064)
			(stroke
				(width 0.1524)
				(type default)
			)
			(layer "F.SilkS")
		)
		(fp_line
			(start 0.67945 0.3048)
			(end 0.120396 0.3048)
			(stroke
				(width 0.1)
				(type default)
			)
			(layer "F.Fab")
		)
		(fp_line
			(start 0.67945 -0.3048)
			(end 0.67945 0.3048)
			(stroke
				(width 0.1)
				(type default)
			)
			(layer "F.Fab")
		)
		(fp_line
			(start 0.12065 -0.2794)
			(end 0.12065 -0.3048)
			(stroke
				(width 0.1)
				(type default)
			)
			(layer "F.Fab")
		)
		(fp_line
			(start 0.12065 -0.3048)
			(end 0.67945 -0.3048)
			(stroke
				(width 0.1)
				(type default)
			)
			(layer "F.Fab")
		)
		(fp_line
			(start 0.120396 0.3048)
			(end 0.120396 0.2794)
			(stroke
				(width 0.1)
				(type default)
			)
			(layer "F.Fab")
		)
		(fp_line
			(start 0.120396 0.2794)
			(end -0.12065 0.2794)
			(stroke
				(width 0.1)
				(type default)
			)
			(layer "F.Fab")
		)
		(fp_line
			(start -0.12065 0.3048)
			(end -0.67945 0.3048)
			(stroke
				(width 0.1)
				(type default)
			)
			(layer "F.Fab")
		)
		(fp_line
			(start -0.12065 0.2794)
			(end -0.12065 0.3048)
			(stroke
				(width 0.1)
				(type default)
			)
			(layer "F.Fab")
		)
		(fp_line
			(start -0.12065 -0.2794)
			(end 0.12065 -0.2794)
			(stroke
				(width 0.1)
				(type default)
			)
			(layer "F.Fab")
		)
		(fp_line
			(start -0.12065 -0.305054)
			(end -0.12065 -0.2794)
			(stroke
				(width 0.1)
				(type default)
			)
			(layer "F.Fab")
		)
		(fp_line
			(start -0.67945 0.3048)
			(end -0.67945 -0.305054)
			(stroke
				(width 0.1)
				(type default)
			)
			(layer "F.Fab")
		)
		(fp_line
			(start -0.67945 -0.305054)
			(end -0.12065 -0.305054)
			(stroke
				(width 0.1)
				(type default)
			)
			(layer "F.Fab")
		)
		(pad "1" smd circle
			(at -0.40005 0 180)
			(size 0 0)
			(layers "F.Cu" "F.Mask" "F.Paste")
			(net "SMB_OCP_V3_2_3V3AUX_BUF_R_SCL")
		)
		(pad "2" smd circle
			(at 0.40005 0 180)
			(size 0 0)
			(layers "F.Cu" "F.Mask" "F.Paste")
			(net "SMB_OCP_V3_2_3V3AUX_BUF_SCL")
		)
	)
	(footprint ""
		(layer "F.Cu")
		(at 394.981938 -395.1732 90)
		(property "Reference" "R1098"
			(at 0 0 90)
			(layer "F.SilkS")
			(hide yes)
			(effects
				(font
					(size 1.27 1.27)
				)
			)
		)
		(property "Value" ""
			(at 0 0 90)
			(layer "F.Fab")
			(effects
				(font
					(size 1.27 1.27)
				)
			)
		)
		(duplicate_pad_numbers_are_jumpers no)
		(fp_line
			(start 0.32512 -0.175006)
			(end 0.32512 0.175006)
			(stroke
				(width 0.1)
				(type default)
			)
			(layer "F.Fab")
		)
		(fp_line
			(start -0.32512 -0.175006)
			(end 0.32512 -0.175006)
			(stroke
				(width 0.1)
				(type default)
			)
			(layer "F.Fab")
		)
		(fp_line
			(start 0.32512 0.175006)
			(end -0.32512 0.175006)
			(stroke
				(width 0.1)
				(type default)
			)
			(layer "F.Fab")
		)
		(fp_line
			(start -0.32512 0.175006)
			(end -0.32512 -0.175006)
			(stroke
				(width 0.1)
				(type default)
			)
			(layer "F.Fab")
		)
		(pad "1" smd rect
			(at -0.2667 0 90)
			(size 0.3048 0.381)
			(layers "F.Cu" "F.Mask" "F.Paste")
			(net "RT_CPU0_P3_ADDR3")
		)
		(pad "2" smd rect
			(at 0.2667 0 270)
			(size 0.3048 0.381)
			(layers "F.Cu" "F.Mask" "F.Paste")
			(net "GND")
		)
	)
	(footprint ""
		(layer "F.Cu")
		(at 104.741726 -397.13408 180)
		(property "Reference" "C7501"
			(at 0 0 180)
			(layer "F.SilkS")
			(hide yes)
			(effects
				(font
					(size 1.27 1.27)
				)
			)
		)
		(property "Value" ""
			(at 0 0 180)
			(layer "F.Fab")
			(effects
				(font
					(size 1.27 1.27)
				)
			)
		)
		(duplicate_pad_numbers_are_jumpers no)
		(fp_line
			(start 0.299974 0.150114)
			(end -0.299974 0.150114)
			(stroke
				(width 0.1)
				(type default)
			)
			(layer "F.Fab")
		)
		(fp_line
			(start 0.299974 -0.150114)
			(end 0.299974 0.150114)
			(stroke
				(width 0.1)
				(type default)
			)
			(layer "F.Fab")
		)
		(fp_line
			(start -0.299974 0.150114)
			(end -0.299974 -0.150114)
			(stroke
				(width 0.1)
				(type default)
			)
			(layer "F.Fab")
		)
		(fp_line
			(start -0.299974 -0.150114)
			(end 0.299974 -0.150114)
			(stroke
				(width 0.1)
				(type default)
			)
			(layer "F.Fab")
		)
		(pad "1" smd rect
			(at -0.2667 0 180)
			(size 0.3048 0.381)
			(layers "F.Cu" "F.Mask" "F.Paste")
			(net "P1V8_CPU1_RT_1D")
		)
		(pad "2" smd rect
			(at 0.2667 0 180)
			(size 0.3048 0.381)
			(layers "F.Cu" "F.Mask" "F.Paste")
			(net "GND")
		)
	)
	(footprint ""
		(layer "F.Cu")
		(at 433.1716 -17.624298 90)
		(property "Reference" "C1579"
			(at 0 0 90)
			(layer "F.SilkS")
			(hide yes)
			(effects
				(font
					(size 1.27 1.27)
				)
			)
		)
		(property "Value" ""
			(at 0 0 90)
			(layer "F.Fab")
			(effects
				(font
					(size 1.27 1.27)
				)
			)
		)
		(duplicate_pad_numbers_are_jumpers no)
		(fp_line
			(start 0.299974 -0.150114)
			(end 0.299974 0.150114)
			(stroke
				(width 0.1)
				(type default)
			)
			(layer "F.Fab")
		)
		(fp_line
			(start -0.299974 -0.150114)
			(end 0.299974 -0.150114)
			(stroke
				(width 0.1)
				(type default)
			)
			(layer "F.Fab")
		)
		(fp_line
			(start 0.299974 0.150114)
			(end -0.299974 0.150114)
			(stroke
				(width 0.1)
				(type default)
			)
			(layer "F.Fab")
		)
		(fp_line
			(start -0.299974 0.150114)
			(end -0.299974 -0.150114)
			(stroke
				(width 0.1)
				(type default)
			)
			(layer "F.Fab")
		)
		(pad "1" smd rect
			(at -0.2667 0 90)
			(size 0.3048 0.381)
			(layers "F.Cu" "F.Mask" "F.Paste")
			(net "P5E_CPU0_G3_TX_C_DP<0>")
		)
		(pad "2" smd rect
			(at 0.2667 0 90)
			(size 0.3048 0.381)
			(layers "F.Cu" "F.Mask" "F.Paste")
			(net "P5E_CPU0_G3_TX_DP<0>")
		)
	)
	(footprint ""
		(layer "F.Cu")
		(at 367.685066 -424.002962 90)
		(property "Reference" "R4207"
			(at 0 0 90)
			(layer "F.SilkS")
			(hide yes)
			(effects
				(font
					(size 1.27 1.27)
				)
			)
		)
		(property "Value" ""
			(at 0 0 90)
			(layer "F.Fab")
			(effects
				(font
					(size 1.27 1.27)
				)
			)
		)
		(duplicate_pad_numbers_are_jumpers no)
		(fp_line
			(start 0.7874 -0.4064)
			(end 0.7874 0.4064)
			(stroke
				(width 0.1524)
				(type default)
			)
			(layer "F.SilkS")
		)
		(fp_line
			(start -0.7874 -0.4064)
			(end 0.7874 -0.4064)
			(stroke
				(width 0.1524)
				(type default)
			)
			(layer "F.SilkS")
		)
		(fp_line
			(start 0.7874 0.4064)
			(end -0.7874 0.4064)
			(stroke
				(width 0.1524)
				(type default)
			)
			(layer "F.SilkS")
		)
		(fp_line
			(start -0.7874 0.4064)
			(end -0.7874 -0.4064)
			(stroke
				(width 0.1524)
				(type default)
			)
			(layer "F.SilkS")
		)
		(fp_line
			(start -0.12065 -0.305054)
			(end -0.12065 -0.2794)
			(stroke
				(width 0.1)
				(type default)
			)
			(layer "F.Fab")
		)
		(fp_line
			(start -0.67945 -0.305054)
			(end -0.12065 -0.305054)
			(stroke
				(width 0.1)
				(type default)
			)
			(layer "F.Fab")
		)
		(fp_line
			(start 0.67945 -0.3048)
			(end 0.67945 0.3048)
			(stroke
				(width 0.1)
				(type default)
			)
			(layer "F.Fab")
		)
		(fp_line
			(start 0.12065 -0.3048)
			(end 0.67945 -0.3048)
			(stroke
				(width 0.1)
				(type default)
			)
			(layer "F.Fab")
		)
		(fp_line
			(start 0.12065 -0.2794)
			(end 0.12065 -0.3048)
			(stroke
				(width 0.1)
				(type default)
			)
			(layer "F.Fab")
		)
		(fp_line
			(start -0.12065 -0.2794)
			(end 0.12065 -0.2794)
			(stroke
				(width 0.1)
				(type default)
			)
			(layer "F.Fab")
		)
		(fp_line
			(start 0.120396 0.2794)
			(end -0.12065 0.2794)
			(stroke
				(width 0.1)
				(type default)
			)
			(layer "F.Fab")
		)
		(fp_line
			(start -0.12065 0.2794)
			(end -0.12065 0.3048)
			(stroke
				(width 0.1)
				(type default)
			)
			(layer "F.Fab")
		)
		(fp_line
			(start 0.67945 0.3048)
			(end 0.120396 0.3048)
			(stroke
				(width 0.1)
				(type default)
			)
			(layer "F.Fab")
		)
		(fp_line
			(start 0.120396 0.3048)
			(end 0.120396 0.2794)
			(stroke
				(width 0.1)
				(type default)
			)
			(layer "F.Fab")
		)
		(fp_line
			(start -0.12065 0.3048)
			(end -0.67945 0.3048)
			(stroke
				(width 0.1)
				(type default)
			)
			(layer "F.Fab")
		)
		(fp_line
			(start -0.67945 0.3048)
			(end -0.67945 -0.305054)
			(stroke
				(width 0.1)
				(type default)
			)
			(layer "F.Fab")
		)
		(pad "1" smd circle
			(at -0.40005 0 90)
			(size 0 0)
			(layers "F.Cu" "F.Mask" "F.Paste")
			(net "U270_0_ADD0")
		)
		(pad "2" smd circle
			(at 0.40005 0 90)
			(size 0 0)
			(layers "F.Cu" "F.Mask" "F.Paste")
			(net "GND")
		)
	)
	(footprint ""
		(layer "F.Cu")
		(at 197.269608 -125.817376)
		(property "Reference" "R3479"
			(at 0 0 0)
			(layer "F.SilkS")
			(hide yes)
			(effects
				(font
					(size 1.27 1.27)
				)
			)
		)
		(property "Value" ""
			(at 0 0 0)
			(layer "F.Fab")
			(effects
				(font
					(size 1.27 1.27)
				)
			)
		)
		(duplicate_pad_numbers_are_jumpers no)
		(fp_line
			(start -0.7874 -0.4064)
			(end 0.7874 -0.4064)
			(stroke
				(width 0.1524)
				(type default)
			)
			(layer "F.SilkS")
		)
		(fp_line
			(start -0.7874 0.4064)
			(end -0.7874 -0.4064)
			(stroke
				(width 0.1524)
				(type default)
			)
			(layer "F.SilkS")
		)
		(fp_line
			(start 0.7874 -0.4064)
			(end 0.7874 0.4064)
			(stroke
				(width 0.1524)
				(type default)
			)
			(layer "F.SilkS")
		)
		(fp_line
			(start 0.7874 0.4064)
			(end -0.7874 0.4064)
			(stroke
				(width 0.1524)
				(type default)
			)
			(layer "F.SilkS")
		)
		(fp_line
			(start -0.67945 -0.305054)
			(end -0.12065 -0.305054)
			(stroke
				(width 0.1)
				(type default)
			)
			(layer "F.Fab")
		)
		(fp_line
			(start -0.67945 0.3048)
			(end -0.67945 -0.305054)
			(stroke
				(width 0.1)
				(type default)
			)
			(layer "F.Fab")
		)
		(fp_line
			(start -0.12065 -0.305054)
			(end -0.12065 -0.2794)
			(stroke
				(width 0.1)
				(type default)
			)
			(layer "F.Fab")
		)
		(fp_line
			(start -0.12065 -0.2794)
			(end 0.12065 -0.2794)
			(stroke
				(width 0.1)
				(type default)
			)
			(layer "F.Fab")
		)
		(fp_line
			(start -0.12065 0.2794)
			(end -0.12065 0.3048)
			(stroke
				(width 0.1)
				(type default)
			)
			(layer "F.Fab")
		)
		(fp_line
			(start -0.12065 0.3048)
			(end -0.67945 0.3048)
			(stroke
				(width 0.1)
				(type default)
			)
			(layer "F.Fab")
		)
		(fp_line
			(start 0.120396 0.2794)
			(end -0.12065 0.2794)
			(stroke
				(width 0.1)
				(type default)
			)
			(layer "F.Fab")
		)
		(fp_line
			(start 0.120396 0.3048)
			(end 0.120396 0.2794)
			(stroke
				(width 0.1)
				(type default)
			)
			(layer "F.Fab")
		)
		(fp_line
			(start 0.12065 -0.3048)
			(end 0.67945 -0.3048)
			(stroke
				(width 0.1)
				(type default)
			)
			(layer "F.Fab")
		)
		(fp_line
			(start 0.12065 -0.2794)
			(end 0.12065 -0.3048)
			(stroke
				(width 0.1)
				(type default)
			)
			(layer "F.Fab")
		)
		(fp_line
			(start 0.67945 -0.3048)
			(end 0.67945 0.3048)
			(stroke
				(width 0.1)
				(type default)
			)
			(layer "F.Fab")
		)
		(fp_line
			(start 0.67945 0.3048)
			(end 0.120396 0.3048)
			(stroke
				(width 0.1)
				(type default)
			)
			(layer "F.Fab")
		)
		(pad "1" smd circle
			(at -0.40005 0)
			(size 0 0)
			(layers "F.Cu" "F.Mask" "F.Paste")
			(net "GPU_BASE_STBY_EN_R")
		)
		(pad "2" smd circle
			(at 0.40005 0)
			(size 0 0)
			(layers "F.Cu" "F.Mask" "F.Paste")
			(net "GPU_BASE_STBY_EN")
		)
	)
	(footprint ""
		(layer "F.Cu")
		(at 146.415506 -408.517344 -90)
		(property "Reference" "C6713"
			(at 0 0 270)
			(layer "F.SilkS")
			(hide yes)
			(effects
				(font
					(size 1.27 1.27)
				)
			)
		)
		(property "Value" ""
			(at 0 0 270)
			(layer "F.Fab")
			(effects
				(font
					(size 1.27 1.27)
				)
			)
		)
		(duplicate_pad_numbers_are_jumpers no)
		(fp_line
			(start -0.299974 0.150114)
			(end -0.299974 -0.150114)
			(stroke
				(width 0.1)
				(type default)
			)
			(layer "F.Fab")
		)
		(fp_line
			(start 0.299974 0.150114)
			(end -0.299974 0.150114)
			(stroke
				(width 0.1)
				(type default)
			)
			(layer "F.Fab")
		)
		(fp_line
			(start -0.299974 -0.150114)
			(end 0.299974 -0.150114)
			(stroke
				(width 0.1)
				(type default)
			)
			(layer "F.Fab")
		)
		(fp_line
			(start 0.299974 -0.150114)
			(end 0.299974 0.150114)
			(stroke
				(width 0.1)
				(type default)
			)
			(layer "F.Fab")
		)
		(pad "1" smd rect
			(at -0.2667 0 270)
			(size 0.3048 0.381)
			(layers "F.Cu" "F.Mask" "F.Paste")
			(net "P5E_CPU1_P2_TX_BUF_C_DP<10>")
		)
		(pad "2" smd rect
			(at 0.2667 0 270)
			(size 0.3048 0.381)
			(layers "F.Cu" "F.Mask" "F.Paste")
			(net "P5E_CPU1_P2_TX_BUF_DP<10>")
		)
	)
	(footprint ""
		(layer "F.Cu")
		(at 43.265852 -385.58216)
		(property "Reference" "R707"
			(at 0 0 0)
			(layer "F.SilkS")
			(hide yes)
			(effects
				(font
					(size 1.27 1.27)
				)
			)
		)
		(property "Value" ""
			(at 0 0 0)
			(layer "F.Fab")
			(effects
				(font
					(size 1.27 1.27)
				)
			)
		)
		(duplicate_pad_numbers_are_jumpers no)
		(fp_line
			(start -0.32512 -0.175006)
			(end 0.32512 -0.175006)
			(stroke
				(width 0.1)
				(type default)
			)
			(layer "F.Fab")
		)
		(fp_line
			(start -0.32512 0.175006)
			(end -0.32512 -0.175006)
			(stroke
				(width 0.1)
				(type default)
			)
			(layer "F.Fab")
		)
		(fp_line
			(start 0.32512 -0.175006)
			(end 0.32512 0.175006)
			(stroke
				(width 0.1)
				(type default)
			)
			(layer "F.Fab")
		)
		(fp_line
			(start 0.32512 0.175006)
			(end -0.32512 0.175006)
			(stroke
				(width 0.1)
				(type default)
			)
			(layer "F.Fab")
		)
		(pad "1" smd rect
			(at -0.2667 0)
			(size 0.3048 0.381)
			(layers "F.Cu" "F.Mask" "F.Paste")
			(net "GPIO2_RT_CPU1_P0")
		)
		(pad "2" smd rect
			(at 0.2667 0 180)
			(size 0.3048 0.381)
			(layers "F.Cu" "F.Mask" "F.Paste")
			(net "GND")
		)
	)
	(footprint ""
		(layer "F.Cu")
		(at 89.922604 -178.024028 -90)
		(property "Reference" "PR190"
			(at 0 0 270)
			(layer "F.SilkS")
			(hide yes)
			(effects
				(font
					(size 1.27 1.27)
				)
			)
		)
		(property "Value" ""
			(at 0 0 270)
			(layer "F.Fab")
			(effects
				(font
					(size 1.27 1.27)
				)
			)
		)
		(duplicate_pad_numbers_are_jumpers no)
		(fp_line
			(start -0.7874 0.4064)
			(end -0.7874 -0.4064)
			(stroke
				(width 0.1524)
				(type default)
			)
			(layer "F.SilkS")
		)
		(fp_line
			(start 0.7874 0.4064)
			(end -0.7874 0.4064)
			(stroke
				(width 0.1524)
				(type default)
			)
			(layer "F.SilkS")
		)
		(fp_line
			(start -0.7874 -0.4064)
			(end 0.7874 -0.4064)
			(stroke
				(width 0.1524)
				(type default)
			)
			(layer "F.SilkS")
		)
		(fp_line
			(start 0.7874 -0.4064)
			(end 0.7874 0.4064)
			(stroke
				(width 0.1524)
				(type default)
			)
			(layer "F.SilkS")
		)
		(fp_line
			(start -0.67945 0.3048)
			(end -0.67945 -0.305054)
			(stroke
				(width 0.1)
				(type default)
			)
			(layer "F.Fab")
		)
		(fp_line
			(start -0.12065 0.3048)
			(end -0.67945 0.3048)
			(stroke
				(width 0.1)
				(type default)
			)
			(layer "F.Fab")
		)
		(fp_line
			(start 0.120396 0.3048)
			(end 0.120396 0.2794)
			(stroke
				(width 0.1)
				(type default)
			)
			(layer "F.Fab")
		)
		(fp_line
			(start 0.67945 0.3048)
			(end 0.120396 0.3048)
			(stroke
				(width 0.1)
				(type default)
			)
			(layer "F.Fab")
		)
		(fp_line
			(start -0.12065 0.2794)
			(end -0.12065 0.3048)
			(stroke
				(width 0.1)
				(type default)
			)
			(layer "F.Fab")
		)
		(fp_line
			(start 0.120396 0.2794)
			(end -0.12065 0.2794)
			(stroke
				(width 0.1)
				(type default)
			)
			(layer "F.Fab")
		)
		(fp_line
			(start -0.12065 -0.2794)
			(end 0.12065 -0.2794)
			(stroke
				(width 0.1)
				(type default)
			)
			(layer "F.Fab")
		)
		(fp_line
			(start 0.12065 -0.2794)
			(end 0.12065 -0.3048)
			(stroke
				(width 0.1)
				(type default)
			)
			(layer "F.Fab")
		)
		(fp_line
			(start 0.12065 -0.3048)
			(end 0.67945 -0.3048)
			(stroke
				(width 0.1)
				(type default)
			)
			(layer "F.Fab")
		)
		(fp_line
			(start 0.67945 -0.3048)
			(end 0.67945 0.3048)
			(stroke
				(width 0.1)
				(type default)
			)
			(layer "F.Fab")
		)
		(fp_line
			(start -0.67945 -0.305054)
			(end -0.12065 -0.305054)
			(stroke
				(width 0.1)
				(type default)
			)
			(layer "F.Fab")
		)
		(fp_line
			(start -0.12065 -0.305054)
			(end -0.12065 -0.2794)
			(stroke
				(width 0.1)
				(type default)
			)
			(layer "F.Fab")
		)
		(pad "1" smd circle
			(at -0.40005 0 270)
			(size 0 0)
			(layers "F.Cu" "F.Mask" "F.Paste")
			(net "SW_PVDDCR_CPU0_P1_BOOT2")
		)
		(pad "2" smd circle
			(at 0.40005 0 270)
			(size 0 0)
			(layers "F.Cu" "F.Mask" "F.Paste")
			(net "SW_PVDDCR_CPU0_P1_BOOT2_RC")
		)
	)
	(footprint ""
		(layer "F.Cu")
		(at 69.324728 -170.662854 -90)
		(property "Reference" "PR524"
			(at 0 0 270)
			(layer "F.SilkS")
			(hide yes)
			(effects
				(font
					(size 1.27 1.27)
				)
			)
		)
		(property "Value" ""
			(at 0 0 270)
			(layer "F.Fab")
			(effects
				(font
					(size 1.27 1.27)
				)
			)
		)
		(duplicate_pad_numbers_are_jumpers no)
		(fp_line
			(start -0.7874 0.4064)
			(end -0.7874 -0.4064)
			(stroke
				(width 0.1524)
				(type default)
			)
			(layer "F.SilkS")
		)
		(fp_line
			(start 0.7874 0.4064)
			(end -0.7874 0.4064)
			(stroke
				(width 0.1524)
				(type default)
			)
			(layer "F.SilkS")
		)
		(fp_line
			(start -0.7874 -0.4064)
			(end 0.7874 -0.4064)
			(stroke
				(width 0.1524)
				(type default)
			)
			(layer "F.SilkS")
		)
		(fp_line
			(start 0.7874 -0.4064)
			(end 0.7874 0.4064)
			(stroke
				(width 0.1524)
				(type default)
			)
			(layer "F.SilkS")
		)
		(fp_line
			(start -0.67945 0.3048)
			(end -0.67945 -0.305054)
			(stroke
				(width 0.1)
				(type default)
			)
			(layer "F.Fab")
		)
		(fp_line
			(start -0.12065 0.3048)
			(end -0.67945 0.3048)
			(stroke
				(width 0.1)
				(type default)
			)
			(layer "F.Fab")
		)
		(fp_line
			(start 0.120396 0.3048)
			(end 0.120396 0.2794)
			(stroke
				(width 0.1)
				(type default)
			)
			(layer "F.Fab")
		)
		(fp_line
			(start 0.67945 0.3048)
			(end 0.120396 0.3048)
			(stroke
				(width 0.1)
				(type default)
			)
			(layer "F.Fab")
		)
		(fp_line
			(start -0.12065 0.2794)
			(end -0.12065 0.3048)
			(stroke
				(width 0.1)
				(type default)
			)
			(layer "F.Fab")
		)
		(fp_line
			(start 0.120396 0.2794)
			(end -0.12065 0.2794)
			(stroke
				(width 0.1)
				(type default)
			)
			(layer "F.Fab")
		)
		(fp_line
			(start -0.12065 -0.2794)
			(end 0.12065 -0.2794)
			(stroke
				(width 0.1)
				(type default)
			)
			(layer "F.Fab")
		)
		(fp_line
			(start 0.12065 -0.2794)
			(end 0.12065 -0.3048)
			(stroke
				(width 0.1)
				(type default)
			)
			(layer "F.Fab")
		)
		(fp_line
			(start 0.12065 -0.3048)
			(end 0.67945 -0.3048)
			(stroke
				(width 0.1)
				(type default)
			)
			(layer "F.Fab")
		)
		(fp_line
			(start 0.67945 -0.3048)
			(end 0.67945 0.3048)
			(stroke
				(width 0.1)
				(type default)
			)
			(layer "F.Fab")
		)
		(fp_line
			(start -0.67945 -0.305054)
			(end -0.12065 -0.305054)
			(stroke
				(width 0.1)
				(type default)
			)
			(layer "F.Fab")
		)
		(fp_line
			(start -0.12065 -0.305054)
			(end -0.12065 -0.2794)
			(stroke
				(width 0.1)
				(type default)
			)
			(layer "F.Fab")
		)
		(pad "1" smd circle
			(at -0.40005 0 270)
			(size 0 0)
			(layers "F.Cu" "F.Mask" "F.Paste")
			(net "SW_PVDDCR_CPU0_P1_SW6_RC")
		)
		(pad "2" smd circle
			(at 0.40005 0 270)
			(size 0 0)
			(layers "F.Cu" "F.Mask" "F.Paste")
			(net "GND")
		)
	)
	(footprint ""
		(layer "F.Cu")
		(at 174.78248 -385.578604 90)
		(property "Reference" "C368"
			(at 0 0 90)
			(layer "F.SilkS")
			(hide yes)
			(effects
				(font
					(size 1.27 1.27)
				)
			)
		)
		(property "Value" ""
			(at 0 0 90)
			(layer "F.Fab")
			(effects
				(font
					(size 1.27 1.27)
				)
			)
		)
		(duplicate_pad_numbers_are_jumpers no)
		(fp_line
			(start 0.7874 -0.4064)
			(end 0.7874 0.4064)
			(stroke
				(width 0.1524)
				(type default)
			)
			(layer "F.SilkS")
		)
		(fp_line
			(start -0.7874 -0.4064)
			(end 0.7874 -0.4064)
			(stroke
				(width 0.1524)
				(type default)
			)
			(layer "F.SilkS")
		)
		(fp_line
			(start 0.7874 0.4064)
			(end -0.7874 0.4064)
			(stroke
				(width 0.1524)
				(type default)
			)
			(layer "F.SilkS")
		)
		(fp_line
			(start -0.7874 0.4064)
			(end -0.7874 -0.4064)
			(stroke
				(width 0.1524)
				(type default)
			)
			(layer "F.SilkS")
		)
		(fp_line
			(start -0.12065 -0.305054)
			(end -0.12065 -0.2794)
			(stroke
				(width 0.1)
				(type default)
			)
			(layer "F.Fab")
		)
		(fp_line
			(start -0.67945 -0.305054)
			(end -0.12065 -0.305054)
			(stroke
				(width 0.1)
				(type default)
			)
			(layer "F.Fab")
		)
		(fp_line
			(start 0.67945 -0.3048)
			(end 0.67945 0.3048)
			(stroke
				(width 0.1)
				(type default)
			)
			(layer "F.Fab")
		)
		(fp_line
			(start 0.12065 -0.3048)
			(end 0.67945 -0.3048)
			(stroke
				(width 0.1)
				(type default)
			)
			(layer "F.Fab")
		)
		(fp_line
			(start 0.12065 -0.2794)
			(end 0.12065 -0.3048)
			(stroke
				(width 0.1)
				(type default)
			)
			(layer "F.Fab")
		)
		(fp_line
			(start -0.12065 -0.2794)
			(end 0.12065 -0.2794)
			(stroke
				(width 0.1)
				(type default)
			)
			(layer "F.Fab")
		)
		(fp_line
			(start 0.120396 0.2794)
			(end -0.12065 0.2794)
			(stroke
				(width 0.1)
				(type default)
			)
			(layer "F.Fab")
		)
		(fp_line
			(start -0.12065 0.2794)
			(end -0.12065 0.3048)
			(stroke
				(width 0.1)
				(type default)
			)
			(layer "F.Fab")
		)
		(fp_line
			(start 0.67945 0.3048)
			(end 0.120396 0.3048)
			(stroke
				(width 0.1)
				(type default)
			)
			(layer "F.Fab")
		)
		(fp_line
			(start 0.120396 0.3048)
			(end 0.120396 0.2794)
			(stroke
				(width 0.1)
				(type default)
			)
			(layer "F.Fab")
		)
		(fp_line
			(start -0.12065 0.3048)
			(end -0.67945 0.3048)
			(stroke
				(width 0.1)
				(type default)
			)
			(layer "F.Fab")
		)
		(fp_line
			(start -0.67945 0.3048)
			(end -0.67945 -0.305054)
			(stroke
				(width 0.1)
				(type default)
			)
			(layer "F.Fab")
		)
		(pad "1" smd circle
			(at -0.40005 0 90)
			(size 0 0)
			(layers "F.Cu" "F.Mask" "F.Paste")
			(net "P1V8_CPU1_RT_1D")
		)
		(pad "2" smd circle
			(at 0.40005 0 90)
			(size 0 0)
			(layers "F.Cu" "F.Mask" "F.Paste")
			(net "GND")
		)
	)
	(footprint ""
		(layer "F.Cu")
		(at 196.977 -100.294948 90)
		(property "Reference" "R3477"
			(at 0 0 90)
			(layer "F.SilkS")
			(hide yes)
			(effects
				(font
					(size 1.27 1.27)
				)
			)
		)
		(property "Value" ""
			(at 0 0 90)
			(layer "F.Fab")
			(effects
				(font
					(size 1.27 1.27)
				)
			)
		)
		(duplicate_pad_numbers_are_jumpers no)
		(fp_line
			(start 0.7874 -0.4064)
			(end 0.7874 0.4064)
			(stroke
				(width 0.1524)
				(type default)
			)
			(layer "F.SilkS")
		)
		(fp_line
			(start -0.7874 -0.4064)
			(end 0.7874 -0.4064)
			(stroke
				(width 0.1524)
				(type default)
			)
			(layer "F.SilkS")
		)
		(fp_line
			(start 0.7874 0.4064)
			(end -0.7874 0.4064)
			(stroke
				(width 0.1524)
				(type default)
			)
			(layer "F.SilkS")
		)
		(fp_line
			(start -0.7874 0.4064)
			(end -0.7874 -0.4064)
			(stroke
				(width 0.1524)
				(type default)
			)
			(layer "F.SilkS")
		)
		(fp_line
			(start -0.12065 -0.305054)
			(end -0.12065 -0.2794)
			(stroke
				(width 0.1)
				(type default)
			)
			(layer "F.Fab")
		)
		(fp_line
			(start -0.67945 -0.305054)
			(end -0.12065 -0.305054)
			(stroke
				(width 0.1)
				(type default)
			)
			(layer "F.Fab")
		)
		(fp_line
			(start 0.67945 -0.3048)
			(end 0.67945 0.3048)
			(stroke
				(width 0.1)
				(type default)
			)
			(layer "F.Fab")
		)
		(fp_line
			(start 0.12065 -0.3048)
			(end 0.67945 -0.3048)
			(stroke
				(width 0.1)
				(type default)
			)
			(layer "F.Fab")
		)
		(fp_line
			(start 0.12065 -0.2794)
			(end 0.12065 -0.3048)
			(stroke
				(width 0.1)
				(type default)
			)
			(layer "F.Fab")
		)
		(fp_line
			(start -0.12065 -0.2794)
			(end 0.12065 -0.2794)
			(stroke
				(width 0.1)
				(type default)
			)
			(layer "F.Fab")
		)
		(fp_line
			(start 0.120396 0.2794)
			(end -0.12065 0.2794)
			(stroke
				(width 0.1)
				(type default)
			)
			(layer "F.Fab")
		)
		(fp_line
			(start -0.12065 0.2794)
			(end -0.12065 0.3048)
			(stroke
				(width 0.1)
				(type default)
			)
			(layer "F.Fab")
		)
		(fp_line
			(start 0.67945 0.3048)
			(end 0.120396 0.3048)
			(stroke
				(width 0.1)
				(type default)
			)
			(layer "F.Fab")
		)
		(fp_line
			(start 0.120396 0.3048)
			(end 0.120396 0.2794)
			(stroke
				(width 0.1)
				(type default)
			)
			(layer "F.Fab")
		)
		(fp_line
			(start -0.12065 0.3048)
			(end -0.67945 0.3048)
			(stroke
				(width 0.1)
				(type default)
			)
			(layer "F.Fab")
		)
		(fp_line
			(start -0.67945 0.3048)
			(end -0.67945 -0.305054)
			(stroke
				(width 0.1)
				(type default)
			)
			(layer "F.Fab")
		)
		(pad "1" smd circle
			(at -0.40005 0 90)
			(size 0 0)
			(layers "F.Cu" "F.Mask" "F.Paste")
			(net "GPU_NVS_PWR_BRAKE_N")
		)
		(pad "2" smd circle
			(at 0.40005 0 90)
			(size 0 0)
			(layers "F.Cu" "F.Mask" "F.Paste")
			(net "GPU_NVS_PWR_BRAKE_R_N")
		)
	)
	(footprint ""
		(layer "F.Cu")
		(at 172.593 -132.715 90)
		(property "Reference" "C6122"
			(at 0 0 90)
			(layer "F.SilkS")
			(hide yes)
			(effects
				(font
					(size 1.27 1.27)
				)
			)
		)
		(property "Value" ""
			(at 0 0 90)
			(layer "F.Fab")
			(effects
				(font
					(size 1.27 1.27)
				)
			)
		)
		(duplicate_pad_numbers_are_jumpers no)
		(fp_line
			(start 0.7874 -0.4064)
			(end 0.7874 0.4064)
			(stroke
				(width 0.1524)
				(type default)
			)
			(layer "F.SilkS")
		)
		(fp_line
			(start -0.7874 -0.4064)
			(end 0.7874 -0.4064)
			(stroke
				(width 0.1524)
				(type default)
			)
			(layer "F.SilkS")
		)
		(fp_line
			(start 0.7874 0.4064)
			(end -0.7874 0.4064)
			(stroke
				(width 0.1524)
				(type default)
			)
			(layer "F.SilkS")
		)
		(fp_line
			(start -0.7874 0.4064)
			(end -0.7874 -0.4064)
			(stroke
				(width 0.1524)
				(type default)
			)
			(layer "F.SilkS")
		)
		(fp_line
			(start -0.12065 -0.305054)
			(end -0.12065 -0.2794)
			(stroke
				(width 0.1)
				(type default)
			)
			(layer "F.Fab")
		)
		(fp_line
			(start -0.67945 -0.305054)
			(end -0.12065 -0.305054)
			(stroke
				(width 0.1)
				(type default)
			)
			(layer "F.Fab")
		)
		(fp_line
			(start 0.67945 -0.3048)
			(end 0.67945 0.3048)
			(stroke
				(width 0.1)
				(type default)
			)
			(layer "F.Fab")
		)
		(fp_line
			(start 0.12065 -0.3048)
			(end 0.67945 -0.3048)
			(stroke
				(width 0.1)
				(type default)
			)
			(layer "F.Fab")
		)
		(fp_line
			(start 0.12065 -0.2794)
			(end 0.12065 -0.3048)
			(stroke
				(width 0.1)
				(type default)
			)
			(layer "F.Fab")
		)
		(fp_line
			(start -0.12065 -0.2794)
			(end 0.12065 -0.2794)
			(stroke
				(width 0.1)
				(type default)
			)
			(layer "F.Fab")
		)
		(fp_line
			(start 0.120396 0.2794)
			(end -0.12065 0.2794)
			(stroke
				(width 0.1)
				(type default)
			)
			(layer "F.Fab")
		)
		(fp_line
			(start -0.12065 0.2794)
			(end -0.12065 0.3048)
			(stroke
				(width 0.1)
				(type default)
			)
			(layer "F.Fab")
		)
		(fp_line
			(start 0.67945 0.3048)
			(end 0.120396 0.3048)
			(stroke
				(width 0.1)
				(type default)
			)
			(layer "F.Fab")
		)
		(fp_line
			(start 0.120396 0.3048)
			(end 0.120396 0.2794)
			(stroke
				(width 0.1)
				(type default)
			)
			(layer "F.Fab")
		)
		(fp_line
			(start -0.12065 0.3048)
			(end -0.67945 0.3048)
			(stroke
				(width 0.1)
				(type default)
			)
			(layer "F.Fab")
		)
		(fp_line
			(start -0.67945 0.3048)
			(end -0.67945 -0.305054)
			(stroke
				(width 0.1)
				(type default)
			)
			(layer "F.Fab")
		)
		(pad "1" smd circle
			(at -0.40005 0 90)
			(size 0 0)
			(layers "F.Cu" "F.Mask" "F.Paste")
			(net "P5V")
		)
		(pad "2" smd circle
			(at 0.40005 0 90)
			(size 0 0)
			(layers "F.Cu" "F.Mask" "F.Paste")
			(net "GND")
		)
	)
	(footprint ""
		(layer "F.Cu")
		(at 386.211826 -64.3255 180)
		(property "Reference" "R1632"
			(at 0 0 180)
			(layer "F.SilkS")
			(hide yes)
			(effects
				(font
					(size 1.27 1.27)
				)
			)
		)
		(property "Value" ""
			(at 0 0 180)
			(layer "F.Fab")
			(effects
				(font
					(size 1.27 1.27)
				)
			)
		)
		(duplicate_pad_numbers_are_jumpers no)
		(fp_line
			(start 0.7874 0.4064)
			(end -0.7874 0.4064)
			(stroke
				(width 0.1524)
				(type default)
			)
			(layer "F.SilkS")
		)
		(fp_line
			(start 0.7874 -0.4064)
			(end 0.7874 0.4064)
			(stroke
				(width 0.1524)
				(type default)
			)
			(layer "F.SilkS")
		)
		(fp_line
			(start -0.7874 0.4064)
			(end -0.7874 -0.4064)
			(stroke
				(width 0.1524)
				(type default)
			)
			(layer "F.SilkS")
		)
		(fp_line
			(start -0.7874 -0.4064)
			(end 0.7874 -0.4064)
			(stroke
				(width 0.1524)
				(type default)
			)
			(layer "F.SilkS")
		)
		(fp_line
			(start 0.67945 0.3048)
			(end 0.120396 0.3048)
			(stroke
				(width 0.1)
				(type default)
			)
			(layer "F.Fab")
		)
		(fp_line
			(start 0.67945 -0.3048)
			(end 0.67945 0.3048)
			(stroke
				(width 0.1)
				(type default)
			)
			(layer "F.Fab")
		)
		(fp_line
			(start 0.12065 -0.2794)
			(end 0.12065 -0.3048)
			(stroke
				(width 0.1)
				(type default)
			)
			(layer "F.Fab")
		)
		(fp_line
			(start 0.12065 -0.3048)
			(end 0.67945 -0.3048)
			(stroke
				(width 0.1)
				(type default)
			)
			(layer "F.Fab")
		)
		(fp_line
			(start 0.120396 0.3048)
			(end 0.120396 0.2794)
			(stroke
				(width 0.1)
				(type default)
			)
			(layer "F.Fab")
		)
		(fp_line
			(start 0.120396 0.2794)
			(end -0.12065 0.2794)
			(stroke
				(width 0.1)
				(type default)
			)
			(layer "F.Fab")
		)
		(fp_line
			(start -0.12065 0.3048)
			(end -0.67945 0.3048)
			(stroke
				(width 0.1)
				(type default)
			)
			(layer "F.Fab")
		)
		(fp_line
			(start -0.12065 0.2794)
			(end -0.12065 0.3048)
			(stroke
				(width 0.1)
				(type default)
			)
			(layer "F.Fab")
		)
		(fp_line
			(start -0.12065 -0.2794)
			(end 0.12065 -0.2794)
			(stroke
				(width 0.1)
				(type default)
			)
			(layer "F.Fab")
		)
		(fp_line
			(start -0.12065 -0.305054)
			(end -0.12065 -0.2794)
			(stroke
				(width 0.1)
				(type default)
			)
			(layer "F.Fab")
		)
		(fp_line
			(start -0.67945 0.3048)
			(end -0.67945 -0.305054)
			(stroke
				(width 0.1)
				(type default)
			)
			(layer "F.Fab")
		)
		(fp_line
			(start -0.67945 -0.305054)
			(end -0.12065 -0.305054)
			(stroke
				(width 0.1)
				(type default)
			)
			(layer "F.Fab")
		)
		(pad "1" smd circle
			(at -0.40005 0 180)
			(size 0 0)
			(layers "F.Cu" "F.Mask" "F.Paste")
			(net "HDT_CPU0_HDT_CONN_TESTEN")
		)
		(pad "2" smd circle
			(at 0.40005 0 180)
			(size 0 0)
			(layers "F.Cu" "F.Mask" "F.Paste")
			(net "CPU0_HDT_CONN_TESTEN")
		)
	)
	(footprint ""
		(layer "F.Cu")
		(at 453.892666 -390.076944 -90)
		(property "Reference" "PL6506"
			(at 1.075944 -5.747004 90)
			(unlocked yes)
			(layer "F.SilkS")
			(effects
				(font
					(size 0.7874 0.5842)
					(thickness 0.1524)
				)
				(justify left)
			)
		)
		(property "Value" ""
			(at 0 0 270)
			(layer "F.Fab")
			(effects
				(font
					(size 1.27 1.27)
				)
			)
		)
		(duplicate_pad_numbers_are_jumpers no)
		(fp_line
			(start -3.24993 3.24993)
			(end -3.24993 2.2352)
			(stroke
				(width 0.1524)
				(type default)
			)
			(layer "F.SilkS")
		)
		(fp_line
			(start 3.24993 3.24993)
			(end -3.24993 3.24993)
			(stroke
				(width 0.1524)
				(type default)
			)
			(layer "F.SilkS")
		)
		(fp_line
			(start 3.24993 2.2352)
			(end 3.24993 3.24993)
			(stroke
				(width 0.1524)
				(type default)
			)
			(layer "F.SilkS")
		)
		(fp_line
			(start -3.24993 -2.2352)
			(end -3.24993 -3.24993)
			(stroke
				(width 0.1524)
				(type default)
			)
			(layer "F.SilkS")
		)
		(fp_line
			(start -3.24993 -3.24993)
			(end 3.24993 -3.24993)
			(stroke
				(width 0.1524)
				(type default)
			)
			(layer "F.SilkS")
		)
		(fp_line
			(start 3.24993 -3.24993)
			(end 3.24993 -2.2352)
			(stroke
				(width 0.1524)
				(type default)
			)
			(layer "F.SilkS")
		)
		(fp_line
			(start -3.24993 3.24993)
			(end -3.24993 -3.24993)
			(stroke
				(width 0.1)
				(type default)
			)
			(layer "F.Fab")
		)
		(fp_line
			(start 3.24993 3.24993)
			(end -3.24993 3.24993)
			(stroke
				(width 0.1)
				(type default)
			)
			(layer "F.Fab")
		)
		(fp_line
			(start -3.24993 -3.24993)
			(end 3.24993 -3.24993)
			(stroke
				(width 0.1)
				(type default)
			)
			(layer "F.Fab")
		)
		(fp_line
			(start 3.24993 -3.24993)
			(end 3.24993 3.24993)
			(stroke
				(width 0.1)
				(type default)
			)
			(layer "F.Fab")
		)
		(pad "1" smd rect
			(at -2.29997 0 270)
			(size 2.0066 4.2164)
			(layers "F.Cu" "F.Mask" "F.Paste")
			(net "SW_P0V9_RETIMER_CPU0_SW2")
		)
		(pad "2" smd rect
			(at 2.29997 0 270)
			(size 2.0066 4.2164)
			(layers "F.Cu" "F.Mask" "F.Paste")
			(net "P0V9_CPU0_RT_2D")
		)
	)
	(footprint ""
		(layer "F.Cu")
		(at 160.377886 -119.089424 180)
		(property "Reference" "R2219"
			(at 0 0 180)
			(layer "F.SilkS")
			(hide yes)
			(effects
				(font
					(size 1.27 1.27)
				)
			)
		)
		(property "Value" ""
			(at 0 0 180)
			(layer "F.Fab")
			(effects
				(font
					(size 1.27 1.27)
				)
			)
		)
		(duplicate_pad_numbers_are_jumpers no)
		(fp_line
			(start 0.7874 0.4064)
			(end -0.7874 0.4064)
			(stroke
				(width 0.1524)
				(type default)
			)
			(layer "F.SilkS")
		)
		(fp_line
			(start 0.7874 -0.4064)
			(end 0.7874 0.4064)
			(stroke
				(width 0.1524)
				(type default)
			)
			(layer "F.SilkS")
		)
		(fp_line
			(start -0.7874 0.4064)
			(end -0.7874 -0.4064)
			(stroke
				(width 0.1524)
				(type default)
			)
			(layer "F.SilkS")
		)
		(fp_line
			(start -0.7874 -0.4064)
			(end 0.7874 -0.4064)
			(stroke
				(width 0.1524)
				(type default)
			)
			(layer "F.SilkS")
		)
		(fp_line
			(start 0.67945 0.3048)
			(end 0.120396 0.3048)
			(stroke
				(width 0.1)
				(type default)
			)
			(layer "F.Fab")
		)
		(fp_line
			(start 0.67945 -0.3048)
			(end 0.67945 0.3048)
			(stroke
				(width 0.1)
				(type default)
			)
			(layer "F.Fab")
		)
		(fp_line
			(start 0.12065 -0.2794)
			(end 0.12065 -0.3048)
			(stroke
				(width 0.1)
				(type default)
			)
			(layer "F.Fab")
		)
		(fp_line
			(start 0.12065 -0.3048)
			(end 0.67945 -0.3048)
			(stroke
				(width 0.1)
				(type default)
			)
			(layer "F.Fab")
		)
		(fp_line
			(start 0.120396 0.3048)
			(end 0.120396 0.2794)
			(stroke
				(width 0.1)
				(type default)
			)
			(layer "F.Fab")
		)
		(fp_line
			(start 0.120396 0.2794)
			(end -0.12065 0.2794)
			(stroke
				(width 0.1)
				(type default)
			)
			(layer "F.Fab")
		)
		(fp_line
			(start -0.12065 0.3048)
			(end -0.67945 0.3048)
			(stroke
				(width 0.1)
				(type default)
			)
			(layer "F.Fab")
		)
		(fp_line
			(start -0.12065 0.2794)
			(end -0.12065 0.3048)
			(stroke
				(width 0.1)
				(type default)
			)
			(layer "F.Fab")
		)
		(fp_line
			(start -0.12065 -0.2794)
			(end 0.12065 -0.2794)
			(stroke
				(width 0.1)
				(type default)
			)
			(layer "F.Fab")
		)
		(fp_line
			(start -0.12065 -0.305054)
			(end -0.12065 -0.2794)
			(stroke
				(width 0.1)
				(type default)
			)
			(layer "F.Fab")
		)
		(fp_line
			(start -0.67945 0.3048)
			(end -0.67945 -0.305054)
			(stroke
				(width 0.1)
				(type default)
			)
			(layer "F.Fab")
		)
		(fp_line
			(start -0.67945 -0.305054)
			(end -0.12065 -0.305054)
			(stroke
				(width 0.1)
				(type default)
			)
			(layer "F.Fab")
		)
		(pad "1" smd circle
			(at -0.40005 0 180)
			(size 0 0)
			(layers "F.Cu" "F.Mask" "F.Paste")
			(net "P12V_AUX")
		)
		(pad "2" smd circle
			(at 0.40005 0 180)
			(size 0 0)
			(layers "F.Cu" "F.Mask" "F.Paste")
			(net "A_P12V_STBY_ADR_TRIGGER")
		)
	)
	(footprint ""
		(layer "F.Cu")
		(at 152.84958 -33.59658)
		(property "Reference" "R1522"
			(at 0 0 0)
			(layer "F.SilkS")
			(hide yes)
			(effects
				(font
					(size 1.27 1.27)
				)
			)
		)
		(property "Value" ""
			(at 0 0 0)
			(layer "F.Fab")
			(effects
				(font
					(size 1.27 1.27)
				)
			)
		)
		(duplicate_pad_numbers_are_jumpers no)
		(fp_line
			(start -0.7874 -0.4064)
			(end 0.7874 -0.4064)
			(stroke
				(width 0.1524)
				(type default)
			)
			(layer "F.SilkS")
		)
		(fp_line
			(start -0.7874 0.4064)
			(end -0.7874 -0.4064)
			(stroke
				(width 0.1524)
				(type default)
			)
			(layer "F.SilkS")
		)
		(fp_line
			(start 0.7874 -0.4064)
			(end 0.7874 0.4064)
			(stroke
				(width 0.1524)
				(type default)
			)
			(layer "F.SilkS")
		)
		(fp_line
			(start 0.7874 0.4064)
			(end -0.7874 0.4064)
			(stroke
				(width 0.1524)
				(type default)
			)
			(layer "F.SilkS")
		)
		(fp_line
			(start -0.67945 -0.305054)
			(end -0.12065 -0.305054)
			(stroke
				(width 0.1)
				(type default)
			)
			(layer "F.Fab")
		)
		(fp_line
			(start -0.67945 0.3048)
			(end -0.67945 -0.305054)
			(stroke
				(width 0.1)
				(type default)
			)
			(layer "F.Fab")
		)
		(fp_line
			(start -0.12065 -0.305054)
			(end -0.12065 -0.2794)
			(stroke
				(width 0.1)
				(type default)
			)
			(layer "F.Fab")
		)
		(fp_line
			(start -0.12065 -0.2794)
			(end 0.12065 -0.2794)
			(stroke
				(width 0.1)
				(type default)
			)
			(layer "F.Fab")
		)
		(fp_line
			(start -0.12065 0.2794)
			(end -0.12065 0.3048)
			(stroke
				(width 0.1)
				(type default)
			)
			(layer "F.Fab")
		)
		(fp_line
			(start -0.12065 0.3048)
			(end -0.67945 0.3048)
			(stroke
				(width 0.1)
				(type default)
			)
			(layer "F.Fab")
		)
		(fp_line
			(start 0.120396 0.2794)
			(end -0.12065 0.2794)
			(stroke
				(width 0.1)
				(type default)
			)
			(layer "F.Fab")
		)
		(fp_line
			(start 0.120396 0.3048)
			(end 0.120396 0.2794)
			(stroke
				(width 0.1)
				(type default)
			)
			(layer "F.Fab")
		)
		(fp_line
			(start 0.12065 -0.3048)
			(end 0.67945 -0.3048)
			(stroke
				(width 0.1)
				(type default)
			)
			(layer "F.Fab")
		)
		(fp_line
			(start 0.12065 -0.2794)
			(end 0.12065 -0.3048)
			(stroke
				(width 0.1)
				(type default)
			)
			(layer "F.Fab")
		)
		(fp_line
			(start 0.67945 -0.3048)
			(end 0.67945 0.3048)
			(stroke
				(width 0.1)
				(type default)
			)
			(layer "F.Fab")
		)
		(fp_line
			(start 0.67945 0.3048)
			(end 0.120396 0.3048)
			(stroke
				(width 0.1)
				(type default)
			)
			(layer "F.Fab")
		)
		(pad "1" smd circle
			(at -0.40005 0)
			(size 0 0)
			(layers "F.Cu" "F.Mask" "F.Paste")
			(net "HP_LVC3_OCP_V3_2_R_EN")
		)
		(pad "2" smd circle
			(at 0.40005 0)
			(size 0 0)
			(layers "F.Cu" "F.Mask" "F.Paste")
			(net "P12V_OCP_V3_2_BUF_EN_R")
		)
	)
	(footprint ""
		(layer "F.Cu")
		(at 429.4251 -400.987768 -90)
		(property "Reference" "R1057"
			(at 0 0 270)
			(layer "F.SilkS")
			(hide yes)
			(effects
				(font
					(size 1.27 1.27)
				)
			)
		)
		(property "Value" ""
			(at 0 0 270)
			(layer "F.Fab")
			(effects
				(font
					(size 1.27 1.27)
				)
			)
		)
		(duplicate_pad_numbers_are_jumpers no)
		(fp_line
			(start -0.32512 0.175006)
			(end -0.32512 -0.175006)
			(stroke
				(width 0.1)
				(type default)
			)
			(layer "F.Fab")
		)
		(fp_line
			(start 0.32512 0.175006)
			(end -0.32512 0.175006)
			(stroke
				(width 0.1)
				(type default)
			)
			(layer "F.Fab")
		)
		(fp_line
			(start -0.32512 -0.175006)
			(end 0.32512 -0.175006)
			(stroke
				(width 0.1)
				(type default)
			)
			(layer "F.Fab")
		)
		(fp_line
			(start 0.32512 -0.175006)
			(end 0.32512 0.175006)
			(stroke
				(width 0.1)
				(type default)
			)
			(layer "F.Fab")
		)
		(pad "1" smd rect
			(at -0.2667 0 270)
			(size 0.3048 0.381)
			(layers "F.Cu" "F.Mask" "F.Paste")
			(net "P1V8_CPU0_RT_1D")
		)
		(pad "2" smd rect
			(at 0.2667 0 90)
			(size 0.3048 0.381)
			(layers "F.Cu" "F.Mask" "F.Paste")
			(net "RT_CPU0_P2_ADDR2")
		)
	)
	(footprint ""
		(layer "F.Cu")
		(at 314.965588 0.002794)
		(property "Reference" "J73"
			(at -4.473448 1.284732 90)
			(unlocked yes)
			(layer "F.SilkS")
			(effects
				(font
					(size 0.7874 0.5842)
					(thickness 0.1524)
				)
				(justify left)
			)
		)
		(property "Value" ""
			(at 0 0 0)
			(layer "F.Fab")
			(effects
				(font
					(size 1.27 1.27)
				)
			)
		)
		(duplicate_pad_numbers_are_jumpers no)
		(fp_line
			(start -1.2192 -2.06756)
			(end 1.2192 -2.06756)
			(stroke
				(width 0.1524)
				(type default)
			)
			(layer "F.SilkS")
		)
		(fp_line
			(start -1.2192 2.06756)
			(end -1.2192 -2.06756)
			(stroke
				(width 0.1524)
				(type default)
			)
			(layer "F.SilkS")
		)
		(fp_line
			(start 1.2192 -2.06756)
			(end 1.2192 2.06756)
			(stroke
				(width 0.1524)
				(type default)
			)
			(layer "F.SilkS")
		)
		(fp_line
			(start 1.2192 2.06756)
			(end -1.2192 2.06756)
			(stroke
				(width 0.1524)
				(type default)
			)
			(layer "F.SilkS")
		)
		(pad "" np_thru_hole circle
			(at -2.8829 -1.27 270)
			(size 1.0414 1.0414)
			(drill 1.0414)
			(layers "*.Cu" "*.Mask")
			(clearance 0.381)
			(thermal_gap 0.381)
		)
		(pad "" np_thru_hole circle
			(at -2.8829 1.27 270)
			(size 1.0414 1.0414)
			(drill 1.0414)
			(layers "*.Cu" "*.Mask")
			(clearance 0.381)
			(thermal_gap 0.381)
		)
		(pad "" np_thru_hole circle
			(at 3.4671 -1.27 270)
			(size 1.0414 1.0414)
			(drill 1.0414)
			(layers "*.Cu" "*.Mask")
			(clearance 0.381)
			(thermal_gap 0.381)
		)
		(pad "" np_thru_hole circle
			(at 3.4671 1.27 270)
			(size 1.0414 1.0414)
			(drill 1.0414)
			(layers "*.Cu" "*.Mask")
			(clearance 0.381)
			(thermal_gap 0.381)
		)
		(pad "1" smd rect
			(at 0.8255 -0.249936 270)
			(size 0.3048 0.508)
			(layers "F.Cu" "F.Mask" "F.Paste")
			(net "DELTA_L_85_5INCH_IN3_DN")
		)
		(pad "2" smd rect
			(at 0.8255 0.249936 270)
			(size 0.3048 0.508)
			(layers "F.Cu" "F.Mask" "F.Paste")
			(net "DELTA_L_85_5INCH_IN3_DP")
		)
		(pad "3" smd circle
			(at 0 0)
			(size 0 0)
			(layers "F.Cu" "F.Mask" "F.Paste")
			(net "DELTA_L_GND_1")
		)
		(zone
			(layer "F.Cu")
			(hatch none 0.5)
			(connect_pads
				(clearance 0)
			)
			(min_thickness 0.25)
			(keepout
				(tracks not_allowed)
				(vias allowed)
				(pads allowed)
				(copperpour not_allowed)
				(footprints allowed)
			)
			(placement
				(enabled no)
				(sheetname "")
			)
			(fill
				(thermal_gap 0.5)
				(thermal_bridge_width 0.5)
				(island_removal_mode 0)
			)
			(polygon
				(pts
					(xy 316.083188 -0.545846) (xy 316.083188 -0.450342) (xy 315.486288 -0.450342) (xy 315.486288 -0.043942)
					(xy 316.083188 -0.043942) (xy 316.083188 0.04953) (xy 315.486288 0.04953) (xy 315.486288 0.45593)
					(xy 316.083188 0.45593) (xy 316.083188 0.551434) (xy 315.384688 0.551434) (xy 315.384688 -0.545846)
				)
			)
		)
		(zone
			(layers "F.Cu" "B.Cu" "In1.Cu" "In2.Cu" "In3.Cu" "In4.Cu" "In5.Cu" "In6.Cu"
				"In7.Cu" "In8.Cu" "In9.Cu" "In10.Cu" "In11.Cu" "In12.Cu" "In13.Cu" "In14.Cu"
				"In15.Cu" "In16.Cu"
			)
			(hatch none 0.5)
			(connect_pads
				(clearance 0)
			)
			(min_thickness 0.25)
			(keepout
				(tracks not_allowed)
				(vias allowed)
				(pads allowed)
				(copperpour not_allowed)
				(footprints allowed)
			)
			(placement
				(enabled no)
				(sheetname "")
			)
			(fill
				(thermal_gap 0.5)
				(thermal_bridge_width 0.5)
				(island_removal_mode 0)
			)
			(polygon
				(pts
					(arc
						(start 313.009788 -1.267206)
						(mid 311.155588 -1.267206)
						(end 313.009788 -1.267206)
					)
				)
			)
		)
		(zone
			(layers "F.Cu" "B.Cu" "In1.Cu" "In2.Cu" "In3.Cu" "In4.Cu" "In5.Cu" "In6.Cu"
				"In7.Cu" "In8.Cu" "In9.Cu" "In10.Cu" "In11.Cu" "In12.Cu" "In13.Cu" "In14.Cu"
				"In15.Cu" "In16.Cu"
			)
			(hatch none 0.5)
			(connect_pads
				(clearance 0)
			)
			(min_thickness 0.25)
			(keepout
				(tracks not_allowed)
				(vias allowed)
				(pads allowed)
				(copperpour not_allowed)
				(footprints allowed)
			)
			(placement
				(enabled no)
				(sheetname "")
			)
			(fill
				(thermal_gap 0.5)
				(thermal_bridge_width 0.5)
				(island_removal_mode 0)
			)
			(polygon
				(pts
					(arc
						(start 313.009788 1.272794)
						(mid 311.155588 1.272794)
						(end 313.009788 1.272794)
					)
				)
			)
		)
		(zone
			(layers "F.Cu" "B.Cu" "In1.Cu" "In2.Cu" "In3.Cu" "In4.Cu" "In5.Cu" "In6.Cu"
				"In7.Cu" "In8.Cu" "In9.Cu" "In10.Cu" "In11.Cu" "In12.Cu" "In13.Cu" "In14.Cu"
				"In15.Cu" "In16.Cu"
			)
			(hatch none 0.5)
			(connect_pads
				(clearance 0)
			)
			(min_thickness 0.25)
			(keepout
				(tracks not_allowed)
				(vias allowed)
				(pads allowed)
				(copperpour not_allowed)
				(footprints allowed)
			)
			(placement
				(enabled no)
				(sheetname "")
			)
			(fill
				(thermal_gap 0.5)
				(thermal_bridge_width 0.5)
				(island_removal_mode 0)
			)
			(polygon
				(pts
					(arc
						(start 319.359788 -1.267206)
						(mid 317.505588 -1.267206)
						(end 319.359788 -1.267206)
					)
				)
			)
		)
		(zone
			(layers "F.Cu" "B.Cu" "In1.Cu" "In2.Cu" "In3.Cu" "In4.Cu" "In5.Cu" "In6.Cu"
				"In7.Cu" "In8.Cu" "In9.Cu" "In10.Cu" "In11.Cu" "In12.Cu" "In13.Cu" "In14.Cu"
				"In15.Cu" "In16.Cu"
			)
			(hatch none 0.5)
			(connect_pads
				(clearance 0)
			)
			(min_thickness 0.25)
			(keepout
				(tracks not_allowed)
				(vias allowed)
				(pads allowed)
				(copperpour not_allowed)
				(footprints allowed)
			)
			(placement
				(enabled no)
				(sheetname "")
			)
			(fill
				(thermal_gap 0.5)
				(thermal_bridge_width 0.5)
				(island_removal_mode 0)
			)
			(polygon
				(pts
					(arc
						(start 319.359788 1.272794)
						(mid 317.505588 1.272794)
						(end 319.359788 1.272794)
					)
				)
			)
		)
	)
	(footprint ""
		(layer "F.Cu")
		(at 352.05543 -434.857652 180)
		(property "Reference" "C8"
			(at 0 0 180)
			(layer "F.SilkS")
			(hide yes)
			(effects
				(font
					(size 1.27 1.27)
				)
			)
		)
		(property "Value" ""
			(at 0 0 180)
			(layer "F.Fab")
			(effects
				(font
					(size 1.27 1.27)
				)
			)
		)
		(duplicate_pad_numbers_are_jumpers no)
		(fp_line
			(start 0.7874 0.4064)
			(end -0.7874 0.4064)
			(stroke
				(width 0.1524)
				(type default)
			)
			(layer "F.SilkS")
		)
		(fp_line
			(start 0.7874 -0.4064)
			(end 0.7874 0.4064)
			(stroke
				(width 0.1524)
				(type default)
			)
			(layer "F.SilkS")
		)
		(fp_line
			(start -0.7874 0.4064)
			(end -0.7874 -0.4064)
			(stroke
				(width 0.1524)
				(type default)
			)
			(layer "F.SilkS")
		)
		(fp_line
			(start -0.7874 -0.4064)
			(end 0.7874 -0.4064)
			(stroke
				(width 0.1524)
				(type default)
			)
			(layer "F.SilkS")
		)
		(fp_line
			(start 0.67945 0.3048)
			(end 0.120396 0.3048)
			(stroke
				(width 0.1)
				(type default)
			)
			(layer "F.Fab")
		)
		(fp_line
			(start 0.67945 -0.3048)
			(end 0.67945 0.3048)
			(stroke
				(width 0.1)
				(type default)
			)
			(layer "F.Fab")
		)
		(fp_line
			(start 0.12065 -0.2794)
			(end 0.12065 -0.3048)
			(stroke
				(width 0.1)
				(type default)
			)
			(layer "F.Fab")
		)
		(fp_line
			(start 0.12065 -0.3048)
			(end 0.67945 -0.3048)
			(stroke
				(width 0.1)
				(type default)
			)
			(layer "F.Fab")
		)
		(fp_line
			(start 0.120396 0.3048)
			(end 0.120396 0.2794)
			(stroke
				(width 0.1)
				(type default)
			)
			(layer "F.Fab")
		)
		(fp_line
			(start 0.120396 0.2794)
			(end -0.12065 0.2794)
			(stroke
				(width 0.1)
				(type default)
			)
			(layer "F.Fab")
		)
		(fp_line
			(start -0.12065 0.3048)
			(end -0.67945 0.3048)
			(stroke
				(width 0.1)
				(type default)
			)
			(layer "F.Fab")
		)
		(fp_line
			(start -0.12065 0.2794)
			(end -0.12065 0.3048)
			(stroke
				(width 0.1)
				(type default)
			)
			(layer "F.Fab")
		)
		(fp_line
			(start -0.12065 -0.2794)
			(end 0.12065 -0.2794)
			(stroke
				(width 0.1)
				(type default)
			)
			(layer "F.Fab")
		)
		(fp_line
			(start -0.12065 -0.305054)
			(end -0.12065 -0.2794)
			(stroke
				(width 0.1)
				(type default)
			)
			(layer "F.Fab")
		)
		(fp_line
			(start -0.67945 0.3048)
			(end -0.67945 -0.305054)
			(stroke
				(width 0.1)
				(type default)
			)
			(layer "F.Fab")
		)
		(fp_line
			(start -0.67945 -0.305054)
			(end -0.12065 -0.305054)
			(stroke
				(width 0.1)
				(type default)
			)
			(layer "F.Fab")
		)
		(pad "1" smd circle
			(at -0.40005 0 180)
			(size 0 0)
			(layers "F.Cu" "F.Mask" "F.Paste")
			(net "P3V3_AUX")
		)
		(pad "2" smd circle
			(at 0.40005 0 180)
			(size 0 0)
			(layers "F.Cu" "F.Mask" "F.Paste")
			(net "GND")
		)
	)
	(footprint ""
		(layer "F.Cu")
		(at 39.309294 -423.21734 180)
		(property "Reference" "R6153"
			(at 0 0 180)
			(layer "F.SilkS")
			(hide yes)
			(effects
				(font
					(size 1.27 1.27)
				)
			)
		)
		(property "Value" ""
			(at 0 0 180)
			(layer "F.Fab")
			(effects
				(font
					(size 1.27 1.27)
				)
			)
		)
		(duplicate_pad_numbers_are_jumpers no)
		(fp_line
			(start 0.32512 0.175006)
			(end -0.32512 0.175006)
			(stroke
				(width 0.1)
				(type default)
			)
			(layer "F.Fab")
		)
		(fp_line
			(start 0.32512 -0.175006)
			(end 0.32512 0.175006)
			(stroke
				(width 0.1)
				(type default)
			)
			(layer "F.Fab")
		)
		(fp_line
			(start -0.32512 0.175006)
			(end -0.32512 -0.175006)
			(stroke
				(width 0.1)
				(type default)
			)
			(layer "F.Fab")
		)
		(fp_line
			(start -0.32512 -0.175006)
			(end 0.32512 -0.175006)
			(stroke
				(width 0.1)
				(type default)
			)
			(layer "F.Fab")
		)
		(pad "1" smd rect
			(at -0.2667 0 180)
			(size 0.3048 0.381)
			(layers "F.Cu" "F.Mask" "F.Paste")
			(net "P2E_MB_BMC_TX_C_DN<0>")
		)
		(pad "2" smd rect
			(at 0.2667 0)
			(size 0.3048 0.381)
			(layers "F.Cu" "F.Mask" "F.Paste")
			(net "P2E_MB_BMC_TX_C_R1_DN<0>")
		)
	)
	(footprint ""
		(layer "F.Cu")
		(at 175.895 -129.377948 90)
		(property "Reference" "R249"
			(at 0 0 90)
			(layer "F.SilkS")
			(hide yes)
			(effects
				(font
					(size 1.27 1.27)
				)
			)
		)
		(property "Value" ""
			(at 0 0 90)
			(layer "F.Fab")
			(effects
				(font
					(size 1.27 1.27)
				)
			)
		)
		(duplicate_pad_numbers_are_jumpers no)
		(fp_line
			(start 0.7874 -0.4064)
			(end 0.7874 0.4064)
			(stroke
				(width 0.1524)
				(type default)
			)
			(layer "F.SilkS")
		)
		(fp_line
			(start -0.7874 -0.4064)
			(end 0.7874 -0.4064)
			(stroke
				(width 0.1524)
				(type default)
			)
			(layer "F.SilkS")
		)
		(fp_line
			(start 0.7874 0.4064)
			(end -0.7874 0.4064)
			(stroke
				(width 0.1524)
				(type default)
			)
			(layer "F.SilkS")
		)
		(fp_line
			(start -0.7874 0.4064)
			(end -0.7874 -0.4064)
			(stroke
				(width 0.1524)
				(type default)
			)
			(layer "F.SilkS")
		)
		(fp_line
			(start -0.12065 -0.305054)
			(end -0.12065 -0.2794)
			(stroke
				(width 0.1)
				(type default)
			)
			(layer "F.Fab")
		)
		(fp_line
			(start -0.67945 -0.305054)
			(end -0.12065 -0.305054)
			(stroke
				(width 0.1)
				(type default)
			)
			(layer "F.Fab")
		)
		(fp_line
			(start 0.67945 -0.3048)
			(end 0.67945 0.3048)
			(stroke
				(width 0.1)
				(type default)
			)
			(layer "F.Fab")
		)
		(fp_line
			(start 0.12065 -0.3048)
			(end 0.67945 -0.3048)
			(stroke
				(width 0.1)
				(type default)
			)
			(layer "F.Fab")
		)
		(fp_line
			(start 0.12065 -0.2794)
			(end 0.12065 -0.3048)
			(stroke
				(width 0.1)
				(type default)
			)
			(layer "F.Fab")
		)
		(fp_line
			(start -0.12065 -0.2794)
			(end 0.12065 -0.2794)
			(stroke
				(width 0.1)
				(type default)
			)
			(layer "F.Fab")
		)
		(fp_line
			(start 0.120396 0.2794)
			(end -0.12065 0.2794)
			(stroke
				(width 0.1)
				(type default)
			)
			(layer "F.Fab")
		)
		(fp_line
			(start -0.12065 0.2794)
			(end -0.12065 0.3048)
			(stroke
				(width 0.1)
				(type default)
			)
			(layer "F.Fab")
		)
		(fp_line
			(start 0.67945 0.3048)
			(end 0.120396 0.3048)
			(stroke
				(width 0.1)
				(type default)
			)
			(layer "F.Fab")
		)
		(fp_line
			(start 0.120396 0.3048)
			(end 0.120396 0.2794)
			(stroke
				(width 0.1)
				(type default)
			)
			(layer "F.Fab")
		)
		(fp_line
			(start -0.12065 0.3048)
			(end -0.67945 0.3048)
			(stroke
				(width 0.1)
				(type default)
			)
			(layer "F.Fab")
		)
		(fp_line
			(start -0.67945 0.3048)
			(end -0.67945 -0.305054)
			(stroke
				(width 0.1)
				(type default)
			)
			(layer "F.Fab")
		)
		(pad "1" smd circle
			(at -0.40005 0 90)
			(size 0 0)
			(layers "F.Cu" "F.Mask" "F.Paste")
			(net "FM_CPU0_SLP_S3_N")
		)
		(pad "2" smd circle
			(at 0.40005 0 90)
			(size 0 0)
			(layers "F.Cu" "F.Mask" "F.Paste")
			(net "CPU0_SLP_S3_N")
		)
	)
	(footprint ""
		(layer "F.Cu")
		(at 363.51845 -22.207728 90)
		(property "Reference" "J13"
			(at -3.17754 -2.820924 90)
			(unlocked yes)
			(layer "F.SilkS")
			(effects
				(font
					(size 0.7874 0.5842)
					(thickness 0.1524)
				)
				(justify left)
			)
		)
		(property "Value" ""
			(at 0 0 90)
			(layer "F.Fab")
			(effects
				(font
					(size 1.27 1.27)
				)
			)
		)
		(duplicate_pad_numbers_are_jumpers no)
		(fp_line
			(start 1.700022 -1.999996)
			(end -2.999994 -1.999996)
			(stroke
				(width 0.1524)
				(type default)
			)
			(layer "F.SilkS")
		)
		(fp_line
			(start -2.999994 -1.999996)
			(end -2.999994 7.999984)
			(stroke
				(width 0.1524)
				(type default)
			)
			(layer "F.SilkS")
		)
		(fp_line
			(start 1.199896 -1.500124)
			(end 1.199896 0.999998)
			(stroke
				(width 0.1524)
				(type default)
			)
			(layer "F.SilkS")
		)
		(fp_line
			(start -2.500122 -1.500124)
			(end 1.199896 -1.500124)
			(stroke
				(width 0.1524)
				(type default)
			)
			(layer "F.SilkS")
		)
		(fp_line
			(start 1.199896 0.999998)
			(end 1.700022 0.999998)
			(stroke
				(width 0.1524)
				(type default)
			)
			(layer "F.SilkS")
		)
		(fp_line
			(start 1.700022 4.99999)
			(end 1.199896 4.99999)
			(stroke
				(width 0.1524)
				(type default)
			)
			(layer "F.SilkS")
		)
		(fp_line
			(start 1.199896 4.99999)
			(end 1.199896 7.500112)
			(stroke
				(width 0.1524)
				(type default)
			)
			(layer "F.SilkS")
		)
		(fp_line
			(start -2.500122 5.425694)
			(end -2.500122 -1.500124)
			(stroke
				(width 0.1524)
				(type default)
			)
			(layer "F.SilkS")
		)
		(fp_line
			(start 1.199896 7.500112)
			(end -2.500122 7.500112)
			(stroke
				(width 0.1524)
				(type default)
			)
			(layer "F.SilkS")
		)
		(fp_line
			(start -2.500122 7.500112)
			(end -2.500122 6.568694)
			(stroke
				(width 0.1524)
				(type default)
			)
			(layer "F.SilkS")
		)
		(fp_line
			(start 1.700022 7.999984)
			(end 1.700022 -1.999996)
			(stroke
				(width 0.1524)
				(type default)
			)
			(layer "F.SilkS")
		)
		(fp_line
			(start -0.899922 7.999984)
			(end 1.700022 7.999984)
			(stroke
				(width 0.1524)
				(type default)
			)
			(layer "F.SilkS")
		)
		(fp_line
			(start -2.999994 7.999984)
			(end -0.899922 7.999984)
			(stroke
				(width 0.1524)
				(type default)
			)
			(layer "F.SilkS")
		)
		(fp_poly
			(pts
				(xy 0.762 -3.731006) (xy 0 -2.207006) (xy -0.762 -3.731006)
			)
			(stroke
				(width 0)
				(type default)
			)
			(fill yes)
			(layer "F.SilkS")
		)
		(fp_line
			(start 1.700022 -1.999996)
			(end -2.999994 -1.999996)
			(stroke
				(width 0.1)
				(type default)
			)
			(layer "F.Fab")
		)
		(fp_line
			(start -2.999994 -1.999996)
			(end -2.999994 7.999984)
			(stroke
				(width 0.1)
				(type default)
			)
			(layer "F.Fab")
		)
		(fp_line
			(start 1.199896 -1.500124)
			(end 1.199896 0.999998)
			(stroke
				(width 0.1)
				(type default)
			)
			(layer "F.Fab")
		)
		(fp_line
			(start -2.500122 -1.500124)
			(end 1.199896 -1.500124)
			(stroke
				(width 0.1)
				(type default)
			)
			(layer "F.Fab")
		)
		(fp_line
			(start 1.199896 0.999998)
			(end 1.700022 0.999998)
			(stroke
				(width 0.1)
				(type default)
			)
			(layer "F.Fab")
		)
		(fp_line
			(start 1.700022 4.99999)
			(end 1.199896 4.99999)
			(stroke
				(width 0.1)
				(type default)
			)
			(layer "F.Fab")
		)
		(fp_line
			(start 1.199896 4.99999)
			(end 1.199896 7.500112)
			(stroke
				(width 0.1)
				(type default)
			)
			(layer "F.Fab")
		)
		(fp_line
			(start -2.500122 6.657594)
			(end -2.500122 -1.500124)
			(stroke
				(width 0.1)
				(type default)
			)
			(layer "F.Fab")
		)
		(fp_line
			(start 1.199896 7.500112)
			(end -2.500122 7.500112)
			(stroke
				(width 0.1)
				(type default)
			)
			(layer "F.Fab")
		)
		(fp_line
			(start -2.500122 7.500112)
			(end -2.500122 6.606794)
			(stroke
				(width 0.1)
				(type default)
			)
			(layer "F.Fab")
		)
		(fp_line
			(start 1.700022 7.999984)
			(end 1.700022 -1.999996)
			(stroke
				(width 0.1)
				(type default)
			)
			(layer "F.Fab")
		)
		(fp_line
			(start -0.899922 7.999984)
			(end 1.700022 7.999984)
			(stroke
				(width 0.1)
				(type default)
			)
			(layer "F.Fab")
		)
		(fp_line
			(start -2.999994 7.999984)
			(end -0.899922 7.999984)
			(stroke
				(width 0.1)
				(type default)
			)
			(layer "F.Fab")
		)
		(fp_poly
			(pts
				(xy 0 -2.207006) (xy -0.762 -3.731006) (xy 0.762 -3.731006)
			)
			(stroke
				(width 0)
				(type default)
			)
			(fill yes)
			(layer "F.Fab")
		)
		(pad "" np_thru_hole circle
			(at -1.800098 5.999988 180)
			(size 1.143 1.143)
			(drill 1.143)
			(layers "*.Cu" "*.Mask")
			(clearance 0.381)
			(thermal_gap 0.381)
		)
		(pad "1" thru_hole rect
			(at 0 0 180)
			(size 1.2192 1.2192)
			(drill 0.8128)
			(layers "*.Cu" "*.Mask")
			(remove_unused_layers no)
			(net "UART_VCC_J13")
			(clearance 0.0508)
			(thermal_gap 0.0508)
			(padstack
				(mode front_inner_back)
				(layer "Inner"
					(shape circle)
					(size 1.2192 1.2192)
					(clearance 0.0508)
				)
				(layer "B.Cu"
					(shape rect)
					(size 1.2192 1.2192)
					(clearance 0.0508)
				)
			)
		)
		(pad "2" thru_hole circle
			(at 0 1.999996 180)
			(size 1.2192 1.2192)
			(drill 0.8128)
			(layers "*.Cu" "*.Mask")
			(remove_unused_layers no)
			(net "UART_CPU0_LVC3_UART0_RX")
			(clearance 0.0508)
			(thermal_gap 0.0508)
		)
		(pad "3" thru_hole circle
			(at 0 3.999992 180)
			(size 1.2192 1.2192)
			(drill 0.8128)
			(layers "*.Cu" "*.Mask")
			(remove_unused_layers no)
			(net "UART_CPU0_LVC3_UART0_TX")
			(clearance 0.0508)
			(thermal_gap 0.0508)
		)
		(pad "4" thru_hole circle
			(at 0 5.999988 180)
			(size 1.2192 1.2192)
			(drill 0.8128)
			(layers "*.Cu" "*.Mask")
			(remove_unused_layers no)
			(net "GND")
			(clearance 0.0508)
			(thermal_gap 0.0508)
		)
		(zone
			(layers "F.Cu" "B.Cu" "In1.Cu" "In2.Cu" "In3.Cu" "In4.Cu" "In5.Cu" "In6.Cu"
				"In7.Cu" "In8.Cu" "In9.Cu" "In10.Cu" "In11.Cu" "In12.Cu" "In13.Cu" "In14.Cu"
				"In15.Cu" "In16.Cu"
			)
			(hatch none 0.5)
			(connect_pads
				(clearance 0)
			)
			(min_thickness 0.25)
			(keepout
				(tracks not_allowed)
				(vias allowed)
				(pads allowed)
				(copperpour not_allowed)
				(footprints allowed)
			)
			(placement
				(enabled no)
				(sheetname "")
			)
			(fill
				(thermal_gap 0.5)
				(thermal_bridge_width 0.5)
				(island_removal_mode 0)
			)
			(polygon
				(pts
					(arc
						(start 370.536724 -20.418806)
						(mid 370.237657 -19.696793)
						(end 369.515644 -19.397726)
					)
					(arc
						(start 369.515644 -19.397726)
						(mid 368.507264 -20.406106)
						(end 369.515644 -21.414486)
					)
					(arc
						(start 369.541044 -21.414486)
						(mid 370.245096 -21.122858)
						(end 370.536724 -20.418806)
					)
				)
			)
		)
	)
	(footprint ""
		(layer "F.Cu")
		(at 208.661 -104.013 180)
		(property "Reference" "R8080"
			(at 0 0 180)
			(layer "F.SilkS")
			(hide yes)
			(effects
				(font
					(size 1.27 1.27)
				)
			)
		)
		(property "Value" ""
			(at 0 0 180)
			(layer "F.Fab")
			(effects
				(font
					(size 1.27 1.27)
				)
			)
		)
		(duplicate_pad_numbers_are_jumpers no)
		(fp_line
			(start 0.7874 0.4064)
			(end -0.7874 0.4064)
			(stroke
				(width 0.1524)
				(type default)
			)
			(layer "F.SilkS")
		)
		(fp_line
			(start 0.7874 -0.4064)
			(end 0.7874 0.4064)
			(stroke
				(width 0.1524)
				(type default)
			)
			(layer "F.SilkS")
		)
		(fp_line
			(start -0.7874 0.4064)
			(end -0.7874 -0.4064)
			(stroke
				(width 0.1524)
				(type default)
			)
			(layer "F.SilkS")
		)
		(fp_line
			(start -0.7874 -0.4064)
			(end 0.7874 -0.4064)
			(stroke
				(width 0.1524)
				(type default)
			)
			(layer "F.SilkS")
		)
		(fp_line
			(start 0.67945 0.3048)
			(end 0.120396 0.3048)
			(stroke
				(width 0.1)
				(type default)
			)
			(layer "F.Fab")
		)
		(fp_line
			(start 0.67945 -0.3048)
			(end 0.67945 0.3048)
			(stroke
				(width 0.1)
				(type default)
			)
			(layer "F.Fab")
		)
		(fp_line
			(start 0.12065 -0.2794)
			(end 0.12065 -0.3048)
			(stroke
				(width 0.1)
				(type default)
			)
			(layer "F.Fab")
		)
		(fp_line
			(start 0.12065 -0.3048)
			(end 0.67945 -0.3048)
			(stroke
				(width 0.1)
				(type default)
			)
			(layer "F.Fab")
		)
		(fp_line
			(start 0.120396 0.3048)
			(end 0.120396 0.2794)
			(stroke
				(width 0.1)
				(type default)
			)
			(layer "F.Fab")
		)
		(fp_line
			(start 0.120396 0.2794)
			(end -0.12065 0.2794)
			(stroke
				(width 0.1)
				(type default)
			)
			(layer "F.Fab")
		)
		(fp_line
			(start -0.12065 0.3048)
			(end -0.67945 0.3048)
			(stroke
				(width 0.1)
				(type default)
			)
			(layer "F.Fab")
		)
		(fp_line
			(start -0.12065 0.2794)
			(end -0.12065 0.3048)
			(stroke
				(width 0.1)
				(type default)
			)
			(layer "F.Fab")
		)
		(fp_line
			(start -0.12065 -0.2794)
			(end 0.12065 -0.2794)
			(stroke
				(width 0.1)
				(type default)
			)
			(layer "F.Fab")
		)
		(fp_line
			(start -0.12065 -0.305054)
			(end -0.12065 -0.2794)
			(stroke
				(width 0.1)
				(type default)
			)
			(layer "F.Fab")
		)
		(fp_line
			(start -0.67945 0.3048)
			(end -0.67945 -0.305054)
			(stroke
				(width 0.1)
				(type default)
			)
			(layer "F.Fab")
		)
		(fp_line
			(start -0.67945 -0.305054)
			(end -0.12065 -0.305054)
			(stroke
				(width 0.1)
				(type default)
			)
			(layer "F.Fab")
		)
		(pad "1" smd circle
			(at -0.40005 0 180)
			(size 0 0)
			(layers "F.Cu" "F.Mask" "F.Paste")
			(net "PWRGD_CHAF_CPU0")
		)
		(pad "2" smd circle
			(at 0.40005 0 180)
			(size 0 0)
			(layers "F.Cu" "F.Mask" "F.Paste")
			(net "PWRGD_CHAF_CPU0_R1")
		)
	)
	(footprint ""
		(layer "F.Cu")
		(at 174.022004 -255.560322 180)
		(property "Reference" "J27"
			(at -2.7178 -81.857088 0)
			(unlocked yes)
			(layer "F.SilkS")
			(effects
				(font
					(size 0.7874 0.5842)
					(thickness 0.1524)
				)
			)
		)
		(property "Value" ""
			(at 0 0 180)
			(layer "F.Fab")
			(effects
				(font
					(size 1.27 1.27)
				)
			)
		)
		(duplicate_pad_numbers_are_jumpers no)
		(fp_line
			(start 3.24993 81.000092)
			(end -3.24993 81.000092)
			(stroke
				(width 0.1524)
				(type default)
			)
			(layer "F.SilkS")
		)
		(fp_line
			(start 3.24993 79.016098)
			(end 3.24993 81.000092)
			(stroke
				(width 0.1524)
				(type default)
			)
			(layer "F.SilkS")
		)
		(fp_line
			(start 3.24993 -81.000092)
			(end 3.24993 75.622658)
			(stroke
				(width 0.1524)
				(type default)
			)
			(layer "F.SilkS")
		)
		(fp_line
			(start -3.24993 81.000092)
			(end -3.24993 80.634078)
			(stroke
				(width 0.1524)
				(type default)
			)
			(layer "F.SilkS")
		)
		(fp_line
			(start -3.24993 73.928478)
			(end -3.24993 -81.000092)
			(stroke
				(width 0.1524)
				(type default)
			)
			(layer "F.SilkS")
		)
		(fp_line
			(start -3.24993 72.499982)
			(end 3.24993 72.499982)
			(stroke
				(width 0.1524)
				(type default)
			)
			(layer "F.SilkS")
		)
		(fp_line
			(start -3.24993 -72.499982)
			(end 3.24993 -72.499982)
			(stroke
				(width 0.1524)
				(type default)
			)
			(layer "F.SilkS")
		)
		(fp_line
			(start -3.24993 -81.000092)
			(end 3.24993 -81.000092)
			(stroke
				(width 0.1524)
				(type default)
			)
			(layer "F.SilkS")
		)
		(fp_poly
			(pts
				(xy -3.7465 -64.824864) (xy -3.082036 -63.903352) (xy -4.217924 -63.924688)
			)
			(stroke
				(width 0)
				(type default)
			)
			(fill yes)
			(layer "F.SilkS")
		)
		(fp_line
			(start 3.24993 81.000092)
			(end -3.24993 81.000092)
			(stroke
				(width 0.1)
				(type default)
			)
			(layer "F.Fab")
		)
		(fp_line
			(start 3.24993 -81.000092)
			(end 3.24993 81.000092)
			(stroke
				(width 0.1)
				(type default)
			)
			(layer "F.Fab")
		)
		(fp_line
			(start -3.24993 81.000092)
			(end -3.24993 -81.000092)
			(stroke
				(width 0.1)
				(type default)
			)
			(layer "F.Fab")
		)
		(fp_line
			(start -3.24993 72.499982)
			(end 3.24993 72.499982)
			(stroke
				(width 0.1)
				(type default)
			)
			(layer "F.Fab")
		)
		(fp_line
			(start -3.24993 71.000112)
			(end 3.24993 71.000112)
			(stroke
				(width 0.1)
				(type default)
			)
			(layer "F.Fab")
		)
		(fp_line
			(start -3.24993 -71.000112)
			(end 3.24993 -71.000112)
			(stroke
				(width 0.1)
				(type default)
			)
			(layer "F.Fab")
		)
		(fp_line
			(start -3.24993 -72.499982)
			(end 3.24993 -72.499982)
			(stroke
				(width 0.1)
				(type default)
			)
			(layer "F.Fab")
		)
		(fp_line
			(start -3.24993 -81.000092)
			(end 3.24993 -81.000092)
			(stroke
				(width 0.1)
				(type default)
			)
			(layer "F.Fab")
		)
		(fp_poly
			(pts
				(xy -3.41503 -63.324994) (xy -4.43103 -62.816994) (xy -4.43103 -63.832994)
			)
			(stroke
				(width 0)
				(type default)
			)
			(fill yes)
			(layer "F.Fab")
		)
		(pad "1" smd rect
			(at -2.050034 -63.324994 90)
			(size 0.519938 1.4986)
			(layers "F.Cu" "F.Mask" "F.Paste")
			(net "P12V_MEM_CPU1")
		)
		(pad "2" smd rect
			(at -2.050034 -62.47511 90)
			(size 0.519938 1.4986)
			(layers "F.Cu" "F.Mask" "F.Paste")
			(net "Net_2354")
		)
		(pad "3" smd rect
			(at -2.050034 -61.624972 90)
			(size 0.519938 1.4986)
			(layers "F.Cu" "F.Mask" "F.Paste")
			(net "P3V3_AUX")
		)
		(pad "4" smd rect
			(at -2.050034 -60.775088 90)
			(size 0.519938 1.4986)
			(layers "F.Cu" "F.Mask" "F.Paste")
			(net "I3C_SPD_DDRH_CPU1_SCL")
		)
		(pad "5" smd rect
			(at -2.050034 -59.92495 90)
			(size 0.519938 1.4986)
			(layers "F.Cu" "F.Mask" "F.Paste")
			(net "I3C_SPD_DDRH_CPU1_SDA")
		)
		(pad "6" smd rect
			(at -2.050034 -59.075066 90)
			(size 0.519938 1.4986)
			(layers "F.Cu" "F.Mask" "F.Paste")
			(net "GND")
		)
		(pad "7" smd rect
			(at -2.050034 -58.224928 90)
			(size 0.519938 1.4986)
			(layers "F.Cu" "F.Mask" "F.Paste")
			(net "M_H_CPU1_SA_DQ<0>")
		)
		(pad "8" smd rect
			(at -2.050034 -57.375044 90)
			(size 0.519938 1.4986)
			(layers "F.Cu" "F.Mask" "F.Paste")
			(net "GND")
		)
		(pad "9" smd rect
			(at -2.050034 -56.524906 90)
			(size 0.519938 1.4986)
			(layers "F.Cu" "F.Mask" "F.Paste")
			(net "M_H_CPU1_SA_DQ<1>")
		)
		(pad "10" smd rect
			(at -2.050034 -55.675022 90)
			(size 0.519938 1.4986)
			(layers "F.Cu" "F.Mask" "F.Paste")
			(net "GND")
		)
		(pad "11" smd rect
			(at -2.050034 -54.824884 90)
			(size 0.519938 1.4986)
			(layers "F.Cu" "F.Mask" "F.Paste")
			(net "M_H_CPU1_SA_DQS_DP<0>")
		)
		(pad "12" smd rect
			(at -2.050034 -53.975 90)
			(size 0.519938 1.4986)
			(layers "F.Cu" "F.Mask" "F.Paste")
			(net "M_H_CPU1_SA_DQS_DN<0>")
		)
		(pad "13" smd rect
			(at -2.050034 -53.125116 90)
			(size 0.519938 1.4986)
			(layers "F.Cu" "F.Mask" "F.Paste")
			(net "GND")
		)
		(pad "14" smd rect
			(at -2.050034 -52.274978 90)
			(size 0.519938 1.4986)
			(layers "F.Cu" "F.Mask" "F.Paste")
			(net "M_H_CPU1_SA_DQ<4>")
		)
		(pad "15" smd rect
			(at -2.050034 -51.425094 90)
			(size 0.519938 1.4986)
			(layers "F.Cu" "F.Mask" "F.Paste")
			(net "GND")
		)
		(pad "16" smd rect
			(at -2.050034 -50.574956 90)
			(size 0.519938 1.4986)
			(layers "F.Cu" "F.Mask" "F.Paste")
			(net "M_H_CPU1_SA_DQ<5>")
		)
		(pad "17" smd rect
			(at -2.050034 -49.725072 90)
			(size 0.519938 1.4986)
			(layers "F.Cu" "F.Mask" "F.Paste")
			(net "GND")
		)
		(pad "18" smd rect
			(at -2.050034 -48.874934 90)
			(size 0.519938 1.4986)
			(layers "F.Cu" "F.Mask" "F.Paste")
			(net "M_H_CPU1_SA_DQ<8>")
		)
		(pad "19" smd rect
			(at -2.050034 -48.02505 90)
			(size 0.519938 1.4986)
			(layers "F.Cu" "F.Mask" "F.Paste")
			(net "GND")
		)
		(pad "20" smd rect
			(at -2.050034 -47.174912 90)
			(size 0.519938 1.4986)
			(layers "F.Cu" "F.Mask" "F.Paste")
			(net "M_H_CPU1_SA_DQ<9>")
		)
		(pad "21" smd rect
			(at -2.050034 -46.325028 90)
			(size 0.519938 1.4986)
			(layers "F.Cu" "F.Mask" "F.Paste")
			(net "GND")
		)
		(pad "22" smd rect
			(at -2.050034 -45.47489 90)
			(size 0.519938 1.4986)
			(layers "F.Cu" "F.Mask" "F.Paste")
			(net "M_H_CPU1_SA_DQS_DP<1>")
		)
		(pad "23" smd rect
			(at -2.050034 -44.625006 90)
			(size 0.519938 1.4986)
			(layers "F.Cu" "F.Mask" "F.Paste")
			(net "M_H_CPU1_SA_DQS_DN<1>")
		)
		(pad "24" smd rect
			(at -2.050034 -43.775122 90)
			(size 0.519938 1.4986)
			(layers "F.Cu" "F.Mask" "F.Paste")
			(net "GND")
		)
		(pad "25" smd rect
			(at -2.050034 -42.924984 90)
			(size 0.519938 1.4986)
			(layers "F.Cu" "F.Mask" "F.Paste")
			(net "M_H_CPU1_SA_DQ<12>")
		)
		(pad "26" smd rect
			(at -2.050034 -42.0751 90)
			(size 0.519938 1.4986)
			(layers "F.Cu" "F.Mask" "F.Paste")
			(net "GND")
		)
		(pad "27" smd rect
			(at -2.050034 -41.224962 90)
			(size 0.519938 1.4986)
			(layers "F.Cu" "F.Mask" "F.Paste")
			(net "M_H_CPU1_SA_DQ<13>")
		)
		(pad "28" smd rect
			(at -2.050034 -40.375078 90)
			(size 0.519938 1.4986)
			(layers "F.Cu" "F.Mask" "F.Paste")
			(net "GND")
		)
		(pad "29" smd rect
			(at -2.050034 -39.52494 90)
			(size 0.519938 1.4986)
			(layers "F.Cu" "F.Mask" "F.Paste")
			(net "M_H_CPU1_SA_DQ<16>")
		)
		(pad "30" smd rect
			(at -2.050034 -38.675056 90)
			(size 0.519938 1.4986)
			(layers "F.Cu" "F.Mask" "F.Paste")
			(net "GND")
		)
		(pad "31" smd rect
			(at -2.050034 -37.824918 90)
			(size 0.519938 1.4986)
			(layers "F.Cu" "F.Mask" "F.Paste")
			(net "M_H_CPU1_SA_DQ<17>")
		)
		(pad "32" smd rect
			(at -2.050034 -36.975034 90)
			(size 0.519938 1.4986)
			(layers "F.Cu" "F.Mask" "F.Paste")
			(net "GND")
		)
		(pad "33" smd rect
			(at -2.050034 -36.124896 90)
			(size 0.519938 1.4986)
			(layers "F.Cu" "F.Mask" "F.Paste")
			(net "M_H_CPU1_SA_DQS_DP<2>")
		)
		(pad "34" smd rect
			(at -2.050034 -35.275012 90)
			(size 0.519938 1.4986)
			(layers "F.Cu" "F.Mask" "F.Paste")
			(net "M_H_CPU1_SA_DQS_DN<2>")
		)
		(pad "35" smd rect
			(at -2.050034 -34.425128 90)
			(size 0.519938 1.4986)
			(layers "F.Cu" "F.Mask" "F.Paste")
			(net "GND")
		)
		(pad "36" smd rect
			(at -2.050034 -33.57499 90)
			(size 0.519938 1.4986)
			(layers "F.Cu" "F.Mask" "F.Paste")
			(net "M_H_CPU1_SA_DQ<20>")
		)
		(pad "37" smd rect
			(at -2.050034 -32.725106 90)
			(size 0.519938 1.4986)
			(layers "F.Cu" "F.Mask" "F.Paste")
			(net "GND")
		)
		(pad "38" smd rect
			(at -2.050034 -31.874968 90)
			(size 0.519938 1.4986)
			(layers "F.Cu" "F.Mask" "F.Paste")
			(net "M_H_CPU1_SA_DQ<21>")
		)
		(pad "39" smd rect
			(at -2.050034 -31.025084 90)
			(size 0.519938 1.4986)
			(layers "F.Cu" "F.Mask" "F.Paste")
			(net "GND")
		)
		(pad "40" smd rect
			(at -2.050034 -30.174946 90)
			(size 0.519938 1.4986)
			(layers "F.Cu" "F.Mask" "F.Paste")
			(net "M_H_CPU1_SA_DQ<24>")
		)
		(pad "41" smd rect
			(at -2.050034 -29.325062 90)
			(size 0.519938 1.4986)
			(layers "F.Cu" "F.Mask" "F.Paste")
			(net "GND")
		)
		(pad "42" smd rect
			(at -2.050034 -28.474924 90)
			(size 0.519938 1.4986)
			(layers "F.Cu" "F.Mask" "F.Paste")
			(net "M_H_CPU1_SA_DQ<25>")
		)
		(pad "43" smd rect
			(at -2.050034 -27.62504 90)
			(size 0.519938 1.4986)
			(layers "F.Cu" "F.Mask" "F.Paste")
			(net "GND")
		)
		(pad "44" smd rect
			(at -2.050034 -26.774902 90)
			(size 0.519938 1.4986)
			(layers "F.Cu" "F.Mask" "F.Paste")
			(net "M_H_CPU1_SA_DQS_DP<3>")
		)
		(pad "45" smd rect
			(at -2.050034 -25.925018 90)
			(size 0.519938 1.4986)
			(layers "F.Cu" "F.Mask" "F.Paste")
			(net "M_H_CPU1_SA_DQS_DN<3>")
		)
		(pad "46" smd rect
			(at -2.050034 -25.07488 90)
			(size 0.519938 1.4986)
			(layers "F.Cu" "F.Mask" "F.Paste")
			(net "GND")
		)
		(pad "47" smd rect
			(at -2.050034 -24.224996 90)
			(size 0.519938 1.4986)
			(layers "F.Cu" "F.Mask" "F.Paste")
			(net "M_H_CPU1_SA_DQ<28>")
		)
		(pad "48" smd rect
			(at -2.050034 -23.375112 90)
			(size 0.519938 1.4986)
			(layers "F.Cu" "F.Mask" "F.Paste")
			(net "GND")
		)
		(pad "49" smd rect
			(at -2.050034 -22.524974 90)
			(size 0.519938 1.4986)
			(layers "F.Cu" "F.Mask" "F.Paste")
			(net "M_H_CPU1_SA_DQ<29>")
		)
		(pad "50" smd rect
			(at -2.050034 -21.67509 90)
			(size 0.519938 1.4986)
			(layers "F.Cu" "F.Mask" "F.Paste")
			(net "GND")
		)
		(pad "51" smd rect
			(at -2.050034 -20.824952 90)
			(size 0.519938 1.4986)
			(layers "F.Cu" "F.Mask" "F.Paste")
			(net "M_H_CPU1_SA_CB<0>")
		)
		(pad "52" smd rect
			(at -2.050034 -19.975068 90)
			(size 0.519938 1.4986)
			(layers "F.Cu" "F.Mask" "F.Paste")
			(net "GND")
		)
		(pad "53" smd rect
			(at -2.050034 -19.12493 90)
			(size 0.519938 1.4986)
			(layers "F.Cu" "F.Mask" "F.Paste")
			(net "M_H_CPU1_SA_CB<1>")
		)
		(pad "54" smd rect
			(at -2.050034 -18.275046 90)
			(size 0.519938 1.4986)
			(layers "F.Cu" "F.Mask" "F.Paste")
			(net "GND")
		)
		(pad "55" smd rect
			(at -2.050034 -17.424908 90)
			(size 0.519938 1.4986)
			(layers "F.Cu" "F.Mask" "F.Paste")
			(net "M_H_CPU1_SA_DQS_DP<4>")
		)
		(pad "56" smd rect
			(at -2.050034 -16.575024 90)
			(size 0.519938 1.4986)
			(layers "F.Cu" "F.Mask" "F.Paste")
			(net "M_H_CPU1_SA_DQS_DN<4>")
		)
		(pad "57" smd rect
			(at -2.050034 -15.724886 90)
			(size 0.519938 1.4986)
			(layers "F.Cu" "F.Mask" "F.Paste")
			(net "GND")
		)
		(pad "58" smd rect
			(at -2.050034 -14.875002 90)
			(size 0.519938 1.4986)
			(layers "F.Cu" "F.Mask" "F.Paste")
			(net "M_H_CPU1_SA_CB<4>")
		)
		(pad "59" smd rect
			(at -2.050034 -14.025118 90)
			(size 0.519938 1.4986)
			(layers "F.Cu" "F.Mask" "F.Paste")
			(net "GND")
		)
		(pad "60" smd rect
			(at -2.050034 -13.17498 90)
			(size 0.519938 1.4986)
			(layers "F.Cu" "F.Mask" "F.Paste")
			(net "M_H_CPU1_SA_CB<5>")
		)
		(pad "61" smd rect
			(at -2.050034 -12.325096 90)
			(size 0.519938 1.4986)
			(layers "F.Cu" "F.Mask" "F.Paste")
			(net "GND")
		)
		(pad "62" smd rect
			(at -2.050034 -11.474958 90)
			(size 0.519938 1.4986)
			(layers "F.Cu" "F.Mask" "F.Paste")
			(net "M_H_CPU1_ALERT_N")
		)
		(pad "63" smd rect
			(at -2.050034 -10.625074 90)
			(size 0.519938 1.4986)
			(layers "F.Cu" "F.Mask" "F.Paste")
			(net "GND")
		)
		(pad "64" smd rect
			(at -2.050034 -9.774936 90)
			(size 0.519938 1.4986)
			(layers "F.Cu" "F.Mask" "F.Paste")
			(net "M_H_CPU1_SA_CS_N<0>")
		)
		(pad "65" smd rect
			(at -2.050034 -8.925052 90)
			(size 0.519938 1.4986)
			(layers "F.Cu" "F.Mask" "F.Paste")
			(net "GND")
		)
		(pad "66" smd rect
			(at -2.050034 -8.074914 90)
			(size 0.519938 1.4986)
			(layers "F.Cu" "F.Mask" "F.Paste")
			(net "M_H_CPU1_SA_CA<0>")
		)
		(pad "67" smd rect
			(at -2.050034 -7.22503 90)
			(size 0.519938 1.4986)
			(layers "F.Cu" "F.Mask" "F.Paste")
			(net "GND")
		)
		(pad "68" smd rect
			(at -2.050034 -6.374892 90)
			(size 0.519938 1.4986)
			(layers "F.Cu" "F.Mask" "F.Paste")
			(net "M_H_CPU1_SA_CA<2>")
		)
		(pad "69" smd rect
			(at -2.050034 -5.525008 90)
			(size 0.519938 1.4986)
			(layers "F.Cu" "F.Mask" "F.Paste")
			(net "GND")
		)
		(pad "70" smd rect
			(at -2.050034 -4.675124 90)
			(size 0.519938 1.4986)
			(layers "F.Cu" "F.Mask" "F.Paste")
			(net "M_H_CPU1_SA_CA<4>")
		)
		(pad "71" smd rect
			(at -2.050034 -3.824986 90)
			(size 0.519938 1.4986)
			(layers "F.Cu" "F.Mask" "F.Paste")
			(net "GND")
		)
		(pad "72" smd rect
			(at -2.050034 -2.975102 90)
			(size 0.519938 1.4986)
			(layers "F.Cu" "F.Mask" "F.Paste")
			(net "M_H_CPU1_SA_CA<6>")
		)
		(pad "73" smd rect
			(at -2.050034 -2.124964 90)
			(size 0.519938 1.4986)
			(layers "F.Cu" "F.Mask" "F.Paste")
			(net "GND")
		)
		(pad "74" smd rect
			(at -2.050034 -1.27508 90)
			(size 0.519938 1.4986)
			(layers "F.Cu" "F.Mask" "F.Paste")
			(net "M_H_CPU1_SA_PAR")
		)
		(pad "75" smd rect
			(at -2.050034 -0.424942 90)
			(size 0.519938 1.4986)
			(layers "F.Cu" "F.Mask" "F.Paste")
			(net "GND")
		)
		(pad "76" smd rect
			(at -2.050034 5.525008 90)
			(size 0.519938 1.4986)
			(layers "F.Cu" "F.Mask" "F.Paste")
			(net "M_H_CPU1_SB_CA<0>")
		)
		(pad "77" smd rect
			(at -2.050034 6.374892 90)
			(size 0.519938 1.4986)
			(layers "F.Cu" "F.Mask" "F.Paste")
			(net "GND")
		)
		(pad "78" smd rect
			(at -2.050034 7.22503 90)
			(size 0.519938 1.4986)
			(layers "F.Cu" "F.Mask" "F.Paste")
			(net "M_H_CPU1_SB_CA<2>")
		)
		(pad "79" smd rect
			(at -2.050034 8.074914 90)
			(size 0.519938 1.4986)
			(layers "F.Cu" "F.Mask" "F.Paste")
			(net "GND")
		)
		(pad "80" smd rect
			(at -2.050034 8.925052 90)
			(size 0.519938 1.4986)
			(layers "F.Cu" "F.Mask" "F.Paste")
			(net "M_H_CPU1_SB_CA<4>")
		)
		(pad "81" smd rect
			(at -2.050034 9.774936 90)
			(size 0.519938 1.4986)
			(layers "F.Cu" "F.Mask" "F.Paste")
			(net "GND")
		)
		(pad "82" smd rect
			(at -2.050034 10.625074 90)
			(size 0.519938 1.4986)
			(layers "F.Cu" "F.Mask" "F.Paste")
			(net "M_H_CPU1_SB_CA<6>")
		)
		(pad "83" smd rect
			(at -2.050034 11.474958 90)
			(size 0.519938 1.4986)
			(layers "F.Cu" "F.Mask" "F.Paste")
			(net "GND")
		)
		(pad "84" smd rect
			(at -2.050034 12.325096 90)
			(size 0.519938 1.4986)
			(layers "F.Cu" "F.Mask" "F.Paste")
			(net "M_H_CPU1_SB_CS_N<0>")
		)
		(pad "85" smd rect
			(at -2.050034 13.17498 90)
			(size 0.519938 1.4986)
			(layers "F.Cu" "F.Mask" "F.Paste")
			(net "GND")
		)
		(pad "86" smd rect
			(at -2.050034 14.025118 90)
			(size 0.519938 1.4986)
			(layers "F.Cu" "F.Mask" "F.Paste")
			(net "M_H_CPU1_SA_RSP<0>")
		)
		(pad "87" smd rect
			(at -2.050034 14.875002 90)
			(size 0.519938 1.4986)
			(layers "F.Cu" "F.Mask" "F.Paste")
			(net "M_H_CPU1_SB_RSP<0>")
		)
		(pad "88" smd rect
			(at -2.050034 15.724886 90)
			(size 0.519938 1.4986)
			(layers "F.Cu" "F.Mask" "F.Paste")
			(net "GND")
		)
		(pad "89" smd rect
			(at -2.050034 16.575024 90)
			(size 0.519938 1.4986)
			(layers "F.Cu" "F.Mask" "F.Paste")
			(net "M_H_CPU1_SB_CB<4>")
		)
		(pad "90" smd rect
			(at -2.050034 17.424908 90)
			(size 0.519938 1.4986)
			(layers "F.Cu" "F.Mask" "F.Paste")
			(net "GND")
		)
		(pad "91" smd rect
			(at -2.050034 18.275046 90)
			(size 0.519938 1.4986)
			(layers "F.Cu" "F.Mask" "F.Paste")
			(net "M_H_CPU1_SB_CB<5>")
		)
		(pad "92" smd rect
			(at -2.050034 19.12493 90)
			(size 0.519938 1.4986)
			(layers "F.Cu" "F.Mask" "F.Paste")
			(net "GND")
		)
		(pad "93" smd rect
			(at -2.050034 19.975068 90)
			(size 0.519938 1.4986)
			(layers "F.Cu" "F.Mask" "F.Paste")
			(net "M_H_CPU1_SB_DQS_DP<9>")
		)
		(pad "94" smd rect
			(at -2.050034 20.824952 90)
			(size 0.519938 1.4986)
			(layers "F.Cu" "F.Mask" "F.Paste")
			(net "M_H_CPU1_SB_DQS_DN<9>")
		)
		(pad "95" smd rect
			(at -2.050034 21.67509 90)
			(size 0.519938 1.4986)
			(layers "F.Cu" "F.Mask" "F.Paste")
			(net "GND")
		)
		(pad "96" smd rect
			(at -2.050034 22.524974 90)
			(size 0.519938 1.4986)
			(layers "F.Cu" "F.Mask" "F.Paste")
			(net "M_H_CPU1_SB_CB<0>")
		)
		(pad "97" smd rect
			(at -2.050034 23.375112 90)
			(size 0.519938 1.4986)
			(layers "F.Cu" "F.Mask" "F.Paste")
			(net "GND")
		)
		(pad "98" smd rect
			(at -2.050034 24.224996 90)
			(size 0.519938 1.4986)
			(layers "F.Cu" "F.Mask" "F.Paste")
			(net "M_H_CPU1_SB_CB<1>")
		)
		(pad "99" smd rect
			(at -2.050034 25.07488 90)
			(size 0.519938 1.4986)
			(layers "F.Cu" "F.Mask" "F.Paste")
			(net "GND")
		)
		(pad "100" smd rect
			(at -2.050034 25.925018 90)
			(size 0.519938 1.4986)
			(layers "F.Cu" "F.Mask" "F.Paste")
			(net "M_H_CPU1_SB_DQ<0>")
		)
		(pad "101" smd rect
			(at -2.050034 26.774902 90)
			(size 0.519938 1.4986)
			(layers "F.Cu" "F.Mask" "F.Paste")
			(net "GND")
		)
		(pad "102" smd rect
			(at -2.050034 27.62504 90)
			(size 0.519938 1.4986)
			(layers "F.Cu" "F.Mask" "F.Paste")
			(net "M_H_CPU1_SB_DQ<1>")
		)
		(pad "103" smd rect
			(at -2.050034 28.474924 90)
			(size 0.519938 1.4986)
			(layers "F.Cu" "F.Mask" "F.Paste")
			(net "GND")
		)
		(pad "104" smd rect
			(at -2.050034 29.325062 90)
			(size 0.519938 1.4986)
			(layers "F.Cu" "F.Mask" "F.Paste")
			(net "M_H_CPU1_SB_DQS_DP<0>")
		)
		(pad "105" smd rect
			(at -2.050034 30.174946 90)
			(size 0.519938 1.4986)
			(layers "F.Cu" "F.Mask" "F.Paste")
			(net "M_H_CPU1_SB_DQS_DN<0>")
		)
		(pad "106" smd rect
			(at -2.050034 31.025084 90)
			(size 0.519938 1.4986)
			(layers "F.Cu" "F.Mask" "F.Paste")
			(net "GND")
		)
		(pad "107" smd rect
			(at -2.050034 31.874968 90)
			(size 0.519938 1.4986)
			(layers "F.Cu" "F.Mask" "F.Paste")
			(net "M_H_CPU1_SB_DQ<4>")
		)
		(pad "108" smd rect
			(at -2.050034 32.725106 90)
			(size 0.519938 1.4986)
			(layers "F.Cu" "F.Mask" "F.Paste")
			(net "GND")
		)
		(pad "109" smd rect
			(at -2.050034 33.57499 90)
			(size 0.519938 1.4986)
			(layers "F.Cu" "F.Mask" "F.Paste")
			(net "M_H_CPU1_SB_DQ<5>")
		)
		(pad "110" smd rect
			(at -2.050034 34.425128 90)
			(size 0.519938 1.4986)
			(layers "F.Cu" "F.Mask" "F.Paste")
			(net "GND")
		)
		(pad "111" smd rect
			(at -2.050034 35.275012 90)
			(size 0.519938 1.4986)
			(layers "F.Cu" "F.Mask" "F.Paste")
			(net "M_H_CPU1_SB_DQ<8>")
		)
		(pad "112" smd rect
			(at -2.050034 36.124896 90)
			(size 0.519938 1.4986)
			(layers "F.Cu" "F.Mask" "F.Paste")
			(net "GND")
		)
		(pad "113" smd rect
			(at -2.050034 36.975034 90)
			(size 0.519938 1.4986)
			(layers "F.Cu" "F.Mask" "F.Paste")
			(net "M_H_CPU1_SB_DQ<9>")
		)
		(pad "114" smd rect
			(at -2.050034 37.824918 90)
			(size 0.519938 1.4986)
			(layers "F.Cu" "F.Mask" "F.Paste")
			(net "GND")
		)
		(pad "115" smd rect
			(at -2.050034 38.675056 90)
			(size 0.519938 1.4986)
			(layers "F.Cu" "F.Mask" "F.Paste")
			(net "M_H_CPU1_SB_DQS_DP<1>")
		)
		(pad "116" smd rect
			(at -2.050034 39.52494 90)
			(size 0.519938 1.4986)
			(layers "F.Cu" "F.Mask" "F.Paste")
			(net "M_H_CPU1_SB_DQS_DN<1>")
		)
		(pad "117" smd rect
			(at -2.050034 40.375078 90)
			(size 0.519938 1.4986)
			(layers "F.Cu" "F.Mask" "F.Paste")
			(net "GND")
		)
		(pad "118" smd rect
			(at -2.050034 41.224962 90)
			(size 0.519938 1.4986)
			(layers "F.Cu" "F.Mask" "F.Paste")
			(net "M_H_CPU1_SB_DQ<12>")
		)
		(pad "119" smd rect
			(at -2.050034 42.0751 90)
			(size 0.519938 1.4986)
			(layers "F.Cu" "F.Mask" "F.Paste")
			(net "GND")
		)
		(pad "120" smd rect
			(at -2.050034 42.924984 90)
			(size 0.519938 1.4986)
			(layers "F.Cu" "F.Mask" "F.Paste")
			(net "M_H_CPU1_SB_DQ<13>")
		)
		(pad "121" smd rect
			(at -2.050034 43.775122 90)
			(size 0.519938 1.4986)
			(layers "F.Cu" "F.Mask" "F.Paste")
			(net "GND")
		)
		(pad "122" smd rect
			(at -2.050034 44.625006 90)
			(size 0.519938 1.4986)
			(layers "F.Cu" "F.Mask" "F.Paste")
			(net "M_H_CPU1_SB_DQ<16>")
		)
		(pad "123" smd rect
			(at -2.050034 45.47489 90)
			(size 0.519938 1.4986)
			(layers "F.Cu" "F.Mask" "F.Paste")
			(net "GND")
		)
		(pad "124" smd rect
			(at -2.050034 46.325028 90)
			(size 0.519938 1.4986)
			(layers "F.Cu" "F.Mask" "F.Paste")
			(net "M_H_CPU1_SB_DQ<17>")
		)
		(pad "125" smd rect
			(at -2.050034 47.174912 90)
			(size 0.519938 1.4986)
			(layers "F.Cu" "F.Mask" "F.Paste")
			(net "GND")
		)
		(pad "126" smd rect
			(at -2.050034 48.02505 90)
			(size 0.519938 1.4986)
			(layers "F.Cu" "F.Mask" "F.Paste")
			(net "M_H_CPU1_SB_DQS_DP<2>")
		)
		(pad "127" smd rect
			(at -2.050034 48.874934 90)
			(size 0.519938 1.4986)
			(layers "F.Cu" "F.Mask" "F.Paste")
			(net "M_H_CPU1_SB_DQS_DN<2>")
		)
		(pad "128" smd rect
			(at -2.050034 49.725072 90)
			(size 0.519938 1.4986)
			(layers "F.Cu" "F.Mask" "F.Paste")
			(net "GND")
		)
		(pad "129" smd rect
			(at -2.050034 50.574956 90)
			(size 0.519938 1.4986)
			(layers "F.Cu" "F.Mask" "F.Paste")
			(net "M_H_CPU1_SB_DQ<20>")
		)
		(pad "130" smd rect
			(at -2.050034 51.425094 90)
			(size 0.519938 1.4986)
			(layers "F.Cu" "F.Mask" "F.Paste")
			(net "GND")
		)
		(pad "131" smd rect
			(at -2.050034 52.274978 90)
			(size 0.519938 1.4986)
			(layers "F.Cu" "F.Mask" "F.Paste")
			(net "M_H_CPU1_SB_DQ<21>")
		)
		(pad "132" smd rect
			(at -2.050034 53.125116 90)
			(size 0.519938 1.4986)
			(layers "F.Cu" "F.Mask" "F.Paste")
			(net "GND")
		)
		(pad "133" smd rect
			(at -2.050034 53.975 90)
			(size 0.519938 1.4986)
			(layers "F.Cu" "F.Mask" "F.Paste")
			(net "M_H_CPU1_SB_DQ<24>")
		)
		(pad "134" smd rect
			(at -2.050034 54.824884 90)
			(size 0.519938 1.4986)
			(layers "F.Cu" "F.Mask" "F.Paste")
			(net "GND")
		)
		(pad "135" smd rect
			(at -2.050034 55.675022 90)
			(size 0.519938 1.4986)
			(layers "F.Cu" "F.Mask" "F.Paste")
			(net "M_H_CPU1_SB_DQ<25>")
		)
		(pad "136" smd rect
			(at -2.050034 56.524906 90)
			(size 0.519938 1.4986)
			(layers "F.Cu" "F.Mask" "F.Paste")
			(net "GND")
		)
		(pad "137" smd rect
			(at -2.050034 57.375044 90)
			(size 0.519938 1.4986)
			(layers "F.Cu" "F.Mask" "F.Paste")
			(net "M_H_CPU1_SB_DQS_DP<3>")
		)
		(pad "138" smd rect
			(at -2.050034 58.224928 90)
			(size 0.519938 1.4986)
			(layers "F.Cu" "F.Mask" "F.Paste")
			(net "M_H_CPU1_SB_DQS_DN<3>")
		)
		(pad "139" smd rect
			(at -2.050034 59.075066 90)
			(size 0.519938 1.4986)
			(layers "F.Cu" "F.Mask" "F.Paste")
			(net "GND")
		)
		(pad "140" smd rect
			(at -2.050034 59.92495 90)
			(size 0.519938 1.4986)
			(layers "F.Cu" "F.Mask" "F.Paste")
			(net "M_H_CPU1_SB_DQ<28>")
		)
		(pad "141" smd rect
			(at -2.050034 60.775088 90)
			(size 0.519938 1.4986)
			(layers "F.Cu" "F.Mask" "F.Paste")
			(net "GND")
		)
		(pad "142" smd rect
			(at -2.050034 61.624972 90)
			(size 0.519938 1.4986)
			(layers "F.Cu" "F.Mask" "F.Paste")
			(net "M_H_CPU1_SB_DQ<29>")
		)
		(pad "143" smd rect
			(at -2.050034 62.47511 90)
			(size 0.519938 1.4986)
			(layers "F.Cu" "F.Mask" "F.Paste")
			(net "GND")
		)
		(pad "144" smd rect
			(at -2.050034 63.324994 90)
			(size 0.519938 1.4986)
			(layers "F.Cu" "F.Mask" "F.Paste")
			(net "Net_2355")
		)
		(pad "145" smd rect
			(at 2.050034 -63.324994 90)
			(size 0.519938 1.4986)
			(layers "F.Cu" "F.Mask" "F.Paste")
			(net "P12V_MEM_CPU1")
		)
		(pad "146" smd rect
			(at 2.050034 -62.47511 90)
			(size 0.519938 1.4986)
			(layers "F.Cu" "F.Mask" "F.Paste")
			(net "P12V_MEM_CPU1")
		)
		(pad "147" smd rect
			(at 2.050034 -61.624972 90)
			(size 0.519938 1.4986)
			(layers "F.Cu" "F.Mask" "F.Paste")
			(net "PWRGD_CHH_CPU1_DIMM")
		)
		(pad "148" smd rect
			(at 2.050034 -60.775088 90)
			(size 0.519938 1.4986)
			(layers "F.Cu" "F.Mask" "F.Paste")
			(net "PD_CHH_CPU1_DIMM_SAA")
		)
		(pad "149" smd rect
			(at 2.050034 -59.92495 90)
			(size 0.519938 1.4986)
			(layers "F.Cu" "F.Mask" "F.Paste")
			(net "Net_2356")
		)
		(pad "150" smd rect
			(at 2.050034 -59.075066 90)
			(size 0.519938 1.4986)
			(layers "F.Cu" "F.Mask" "F.Paste")
			(net "Net_2357")
		)
		(pad "151" smd rect
			(at 2.050034 -58.224928 90)
			(size 0.519938 1.4986)
			(layers "F.Cu" "F.Mask" "F.Paste")
			(net "GND")
		)
		(pad "152" smd rect
			(at 2.050034 -57.375044 90)
			(size 0.519938 1.4986)
			(layers "F.Cu" "F.Mask" "F.Paste")
			(net "M_H_CPU1_SA_DQ<2>")
		)
		(pad "153" smd rect
			(at 2.050034 -56.524906 90)
			(size 0.519938 1.4986)
			(layers "F.Cu" "F.Mask" "F.Paste")
			(net "GND")
		)
		(pad "154" smd rect
			(at 2.050034 -55.675022 90)
			(size 0.519938 1.4986)
			(layers "F.Cu" "F.Mask" "F.Paste")
			(net "M_H_CPU1_SA_DQ<3>")
		)
		(pad "155" smd rect
			(at 2.050034 -54.824884 90)
			(size 0.519938 1.4986)
			(layers "F.Cu" "F.Mask" "F.Paste")
			(net "GND")
		)
		(pad "156" smd rect
			(at 2.050034 -53.975 90)
			(size 0.519938 1.4986)
			(layers "F.Cu" "F.Mask" "F.Paste")
			(net "M_H_CPU1_SA_DQS_DN<5>")
		)
		(pad "157" smd rect
			(at 2.050034 -53.125116 90)
			(size 0.519938 1.4986)
			(layers "F.Cu" "F.Mask" "F.Paste")
			(net "M_H_CPU1_SA_DQS_DP<5>")
		)
		(pad "158" smd rect
			(at 2.050034 -52.274978 90)
			(size 0.519938 1.4986)
			(layers "F.Cu" "F.Mask" "F.Paste")
			(net "GND")
		)
		(pad "159" smd rect
			(at 2.050034 -51.425094 90)
			(size 0.519938 1.4986)
			(layers "F.Cu" "F.Mask" "F.Paste")
			(net "M_H_CPU1_SA_DQ<6>")
		)
		(pad "160" smd rect
			(at 2.050034 -50.574956 90)
			(size 0.519938 1.4986)
			(layers "F.Cu" "F.Mask" "F.Paste")
			(net "GND")
		)
		(pad "161" smd rect
			(at 2.050034 -49.725072 90)
			(size 0.519938 1.4986)
			(layers "F.Cu" "F.Mask" "F.Paste")
			(net "M_H_CPU1_SA_DQ<7>")
		)
		(pad "162" smd rect
			(at 2.050034 -48.874934 90)
			(size 0.519938 1.4986)
			(layers "F.Cu" "F.Mask" "F.Paste")
			(net "GND")
		)
		(pad "163" smd rect
			(at 2.050034 -48.02505 90)
			(size 0.519938 1.4986)
			(layers "F.Cu" "F.Mask" "F.Paste")
			(net "M_H_CPU1_SA_DQ<10>")
		)
		(pad "164" smd rect
			(at 2.050034 -47.174912 90)
			(size 0.519938 1.4986)
			(layers "F.Cu" "F.Mask" "F.Paste")
			(net "GND")
		)
		(pad "165" smd rect
			(at 2.050034 -46.325028 90)
			(size 0.519938 1.4986)
			(layers "F.Cu" "F.Mask" "F.Paste")
			(net "M_H_CPU1_SA_DQ<11>")
		)
		(pad "166" smd rect
			(at 2.050034 -45.47489 90)
			(size 0.519938 1.4986)
			(layers "F.Cu" "F.Mask" "F.Paste")
			(net "GND")
		)
		(pad "167" smd rect
			(at 2.050034 -44.625006 90)
			(size 0.519938 1.4986)
			(layers "F.Cu" "F.Mask" "F.Paste")
			(net "M_H_CPU1_SA_DQS_DN<6>")
		)
		(pad "168" smd rect
			(at 2.050034 -43.775122 90)
			(size 0.519938 1.4986)
			(layers "F.Cu" "F.Mask" "F.Paste")
			(net "M_H_CPU1_SA_DQS_DP<6>")
		)
		(pad "169" smd rect
			(at 2.050034 -42.924984 90)
			(size 0.519938 1.4986)
			(layers "F.Cu" "F.Mask" "F.Paste")
			(net "GND")
		)
		(pad "170" smd rect
			(at 2.050034 -42.0751 90)
			(size 0.519938 1.4986)
			(layers "F.Cu" "F.Mask" "F.Paste")
			(net "M_H_CPU1_SA_DQ<14>")
		)
		(pad "171" smd rect
			(at 2.050034 -41.224962 90)
			(size 0.519938 1.4986)
			(layers "F.Cu" "F.Mask" "F.Paste")
			(net "GND")
		)
		(pad "172" smd rect
			(at 2.050034 -40.375078 90)
			(size 0.519938 1.4986)
			(layers "F.Cu" "F.Mask" "F.Paste")
			(net "M_H_CPU1_SA_DQ<15>")
		)
		(pad "173" smd rect
			(at 2.050034 -39.52494 90)
			(size 0.519938 1.4986)
			(layers "F.Cu" "F.Mask" "F.Paste")
			(net "GND")
		)
		(pad "174" smd rect
			(at 2.050034 -38.675056 90)
			(size 0.519938 1.4986)
			(layers "F.Cu" "F.Mask" "F.Paste")
			(net "M_H_CPU1_SA_DQ<18>")
		)
		(pad "175" smd rect
			(at 2.050034 -37.824918 90)
			(size 0.519938 1.4986)
			(layers "F.Cu" "F.Mask" "F.Paste")
			(net "GND")
		)
		(pad "176" smd rect
			(at 2.050034 -36.975034 90)
			(size 0.519938 1.4986)
			(layers "F.Cu" "F.Mask" "F.Paste")
			(net "M_H_CPU1_SA_DQ<19>")
		)
		(pad "177" smd rect
			(at 2.050034 -36.124896 90)
			(size 0.519938 1.4986)
			(layers "F.Cu" "F.Mask" "F.Paste")
			(net "GND")
		)
		(pad "178" smd rect
			(at 2.050034 -35.275012 90)
			(size 0.519938 1.4986)
			(layers "F.Cu" "F.Mask" "F.Paste")
			(net "M_H_CPU1_SA_DQS_DN<7>")
		)
		(pad "179" smd rect
			(at 2.050034 -34.425128 90)
			(size 0.519938 1.4986)
			(layers "F.Cu" "F.Mask" "F.Paste")
			(net "M_H_CPU1_SA_DQS_DP<7>")
		)
		(pad "180" smd rect
			(at 2.050034 -33.57499 90)
			(size 0.519938 1.4986)
			(layers "F.Cu" "F.Mask" "F.Paste")
			(net "GND")
		)
		(pad "181" smd rect
			(at 2.050034 -32.725106 90)
			(size 0.519938 1.4986)
			(layers "F.Cu" "F.Mask" "F.Paste")
			(net "M_H_CPU1_SA_DQ<22>")
		)
		(pad "182" smd rect
			(at 2.050034 -31.874968 90)
			(size 0.519938 1.4986)
			(layers "F.Cu" "F.Mask" "F.Paste")
			(net "GND")
		)
		(pad "183" smd rect
			(at 2.050034 -31.025084 90)
			(size 0.519938 1.4986)
			(layers "F.Cu" "F.Mask" "F.Paste")
			(net "M_H_CPU1_SA_DQ<23>")
		)
		(pad "184" smd rect
			(at 2.050034 -30.174946 90)
			(size 0.519938 1.4986)
			(layers "F.Cu" "F.Mask" "F.Paste")
			(net "GND")
		)
		(pad "185" smd rect
			(at 2.050034 -29.325062 90)
			(size 0.519938 1.4986)
			(layers "F.Cu" "F.Mask" "F.Paste")
			(net "M_H_CPU1_SA_DQ<26>")
		)
		(pad "186" smd rect
			(at 2.050034 -28.474924 90)
			(size 0.519938 1.4986)
			(layers "F.Cu" "F.Mask" "F.Paste")
			(net "GND")
		)
		(pad "187" smd rect
			(at 2.050034 -27.62504 90)
			(size 0.519938 1.4986)
			(layers "F.Cu" "F.Mask" "F.Paste")
			(net "M_H_CPU1_SA_DQ<27>")
		)
		(pad "188" smd rect
			(at 2.050034 -26.774902 90)
			(size 0.519938 1.4986)
			(layers "F.Cu" "F.Mask" "F.Paste")
			(net "GND")
		)
		(pad "189" smd rect
			(at 2.050034 -25.925018 90)
			(size 0.519938 1.4986)
			(layers "F.Cu" "F.Mask" "F.Paste")
			(net "M_H_CPU1_SA_DQS_DN<8>")
		)
		(pad "190" smd rect
			(at 2.050034 -25.07488 90)
			(size 0.519938 1.4986)
			(layers "F.Cu" "F.Mask" "F.Paste")
			(net "M_H_CPU1_SA_DQS_DP<8>")
		)
		(pad "191" smd rect
			(at 2.050034 -24.224996 90)
			(size 0.519938 1.4986)
			(layers "F.Cu" "F.Mask" "F.Paste")
			(net "GND")
		)
		(pad "192" smd rect
			(at 2.050034 -23.375112 90)
			(size 0.519938 1.4986)
			(layers "F.Cu" "F.Mask" "F.Paste")
			(net "M_H_CPU1_SA_DQ<30>")
		)
		(pad "193" smd rect
			(at 2.050034 -22.524974 90)
			(size 0.519938 1.4986)
			(layers "F.Cu" "F.Mask" "F.Paste")
			(net "GND")
		)
		(pad "194" smd rect
			(at 2.050034 -21.67509 90)
			(size 0.519938 1.4986)
			(layers "F.Cu" "F.Mask" "F.Paste")
			(net "M_H_CPU1_SA_DQ<31>")
		)
		(pad "195" smd rect
			(at 2.050034 -20.824952 90)
			(size 0.519938 1.4986)
			(layers "F.Cu" "F.Mask" "F.Paste")
			(net "GND")
		)
		(pad "196" smd rect
			(at 2.050034 -19.975068 90)
			(size 0.519938 1.4986)
			(layers "F.Cu" "F.Mask" "F.Paste")
			(net "M_H_CPU1_SA_CB<2>")
		)
		(pad "197" smd rect
			(at 2.050034 -19.12493 90)
			(size 0.519938 1.4986)
			(layers "F.Cu" "F.Mask" "F.Paste")
			(net "GND")
		)
		(pad "198" smd rect
			(at 2.050034 -18.275046 90)
			(size 0.519938 1.4986)
			(layers "F.Cu" "F.Mask" "F.Paste")
			(net "M_H_CPU1_SA_CB<3>")
		)
		(pad "199" smd rect
			(at 2.050034 -17.424908 90)
			(size 0.519938 1.4986)
			(layers "F.Cu" "F.Mask" "F.Paste")
			(net "GND")
		)
		(pad "200" smd rect
			(at 2.050034 -16.575024 90)
			(size 0.519938 1.4986)
			(layers "F.Cu" "F.Mask" "F.Paste")
			(net "M_H_CPU1_SA_DQS_DN<9>")
		)
		(pad "201" smd rect
			(at 2.050034 -15.724886 90)
			(size 0.519938 1.4986)
			(layers "F.Cu" "F.Mask" "F.Paste")
			(net "M_H_CPU1_SA_DQS_DP<9>")
		)
		(pad "202" smd rect
			(at 2.050034 -14.875002 90)
			(size 0.519938 1.4986)
			(layers "F.Cu" "F.Mask" "F.Paste")
			(net "GND")
		)
		(pad "203" smd rect
			(at 2.050034 -14.025118 90)
			(size 0.519938 1.4986)
			(layers "F.Cu" "F.Mask" "F.Paste")
			(net "M_H_CPU1_SA_CB<6>")
		)
		(pad "204" smd rect
			(at 2.050034 -13.17498 90)
			(size 0.519938 1.4986)
			(layers "F.Cu" "F.Mask" "F.Paste")
			(net "GND")
		)
		(pad "205" smd rect
			(at 2.050034 -12.325096 90)
			(size 0.519938 1.4986)
			(layers "F.Cu" "F.Mask" "F.Paste")
			(net "M_H_CPU1_SA_CB<7>")
		)
		(pad "206" smd rect
			(at 2.050034 -11.474958 90)
			(size 0.519938 1.4986)
			(layers "F.Cu" "F.Mask" "F.Paste")
			(net "GND")
		)
		(pad "207" smd rect
			(at 2.050034 -10.625074 90)
			(size 0.519938 1.4986)
			(layers "F.Cu" "F.Mask" "F.Paste")
			(net "M_H_CPU1_RESET_N")
		)
		(pad "208" smd rect
			(at 2.050034 -9.774936 90)
			(size 0.519938 1.4986)
			(layers "F.Cu" "F.Mask" "F.Paste")
			(net "GND")
		)
		(pad "209" smd rect
			(at 2.050034 -8.925052 90)
			(size 0.519938 1.4986)
			(layers "F.Cu" "F.Mask" "F.Paste")
			(net "M_H_CPU1_SA_CS_N<1>")
		)
		(pad "210" smd rect
			(at 2.050034 -8.074914 90)
			(size 0.519938 1.4986)
			(layers "F.Cu" "F.Mask" "F.Paste")
			(net "GND")
		)
		(pad "211" smd rect
			(at 2.050034 -7.22503 90)
			(size 0.519938 1.4986)
			(layers "F.Cu" "F.Mask" "F.Paste")
			(net "M_H_CPU1_SA_CA<1>")
		)
		(pad "212" smd rect
			(at 2.050034 -6.374892 90)
			(size 0.519938 1.4986)
			(layers "F.Cu" "F.Mask" "F.Paste")
			(net "GND")
		)
		(pad "213" smd rect
			(at 2.050034 -5.525008 90)
			(size 0.519938 1.4986)
			(layers "F.Cu" "F.Mask" "F.Paste")
			(net "M_H_CPU1_SA_CA<3>")
		)
		(pad "214" smd rect
			(at 2.050034 -4.675124 90)
			(size 0.519938 1.4986)
			(layers "F.Cu" "F.Mask" "F.Paste")
			(net "GND")
		)
		(pad "215" smd rect
			(at 2.050034 -3.824986 90)
			(size 0.519938 1.4986)
			(layers "F.Cu" "F.Mask" "F.Paste")
			(net "M_H_CPU1_SA_CA<5>")
		)
		(pad "216" smd rect
			(at 2.050034 -2.975102 90)
			(size 0.519938 1.4986)
			(layers "F.Cu" "F.Mask" "F.Paste")
			(net "GND")
		)
		(pad "217" smd rect
			(at 2.050034 -2.124964 90)
			(size 0.519938 1.4986)
			(layers "F.Cu" "F.Mask" "F.Paste")
			(net "M_H_CPU1_CLK_DP<0>")
		)
		(pad "218" smd rect
			(at 2.050034 -1.27508 90)
			(size 0.519938 1.4986)
			(layers "F.Cu" "F.Mask" "F.Paste")
			(net "M_H_CPU1_CLK_DN<0>")
		)
		(pad "219" smd rect
			(at 2.050034 -0.424942 90)
			(size 0.519938 1.4986)
			(layers "F.Cu" "F.Mask" "F.Paste")
			(net "GND")
		)
		(pad "220" smd rect
			(at 2.050034 5.525008 90)
			(size 0.519938 1.4986)
			(layers "F.Cu" "F.Mask" "F.Paste")
			(net "Net_2358")
		)
		(pad "221" smd rect
			(at 2.050034 6.374892 90)
			(size 0.519938 1.4986)
			(layers "F.Cu" "F.Mask" "F.Paste")
			(net "M_H_CPU1_SB_CA<1>")
		)
		(pad "222" smd rect
			(at 2.050034 7.22503 90)
			(size 0.519938 1.4986)
			(layers "F.Cu" "F.Mask" "F.Paste")
			(net "GND")
		)
		(pad "223" smd rect
			(at 2.050034 8.074914 90)
			(size 0.519938 1.4986)
			(layers "F.Cu" "F.Mask" "F.Paste")
			(net "M_H_CPU1_SB_CA<3>")
		)
		(pad "224" smd rect
			(at 2.050034 8.925052 90)
			(size 0.519938 1.4986)
			(layers "F.Cu" "F.Mask" "F.Paste")
			(net "GND")
		)
		(pad "225" smd rect
			(at 2.050034 9.774936 90)
			(size 0.519938 1.4986)
			(layers "F.Cu" "F.Mask" "F.Paste")
			(net "M_H_CPU1_SB_CA<5>")
		)
		(pad "226" smd rect
			(at 2.050034 10.625074 90)
			(size 0.519938 1.4986)
			(layers "F.Cu" "F.Mask" "F.Paste")
			(net "GND")
		)
		(pad "227" smd rect
			(at 2.050034 11.474958 90)
			(size 0.519938 1.4986)
			(layers "F.Cu" "F.Mask" "F.Paste")
			(net "M_H_CPU1_SB_PAR")
		)
		(pad "228" smd rect
			(at 2.050034 12.325096 90)
			(size 0.519938 1.4986)
			(layers "F.Cu" "F.Mask" "F.Paste")
			(net "GND")
		)
		(pad "229" smd rect
			(at 2.050034 13.17498 90)
			(size 0.519938 1.4986)
			(layers "F.Cu" "F.Mask" "F.Paste")
			(net "M_H_CPU1_SB_CS_N<1>")
		)
		(pad "230" smd rect
			(at 2.050034 14.025118 90)
			(size 0.519938 1.4986)
			(layers "F.Cu" "F.Mask" "F.Paste")
			(net "GND")
		)
		(pad "231" smd rect
			(at 2.050034 14.875002 90)
			(size 0.519938 1.4986)
			(layers "F.Cu" "F.Mask" "F.Paste")
			(net "Net_2359")
		)
		(pad "232" smd rect
			(at 2.050034 15.724886 90)
			(size 0.519938 1.4986)
			(layers "F.Cu" "F.Mask" "F.Paste")
			(net "Net_2360")
		)
		(pad "233" smd rect
			(at 2.050034 16.575024 90)
			(size 0.519938 1.4986)
			(layers "F.Cu" "F.Mask" "F.Paste")
			(net "GND")
		)
		(pad "234" smd rect
			(at 2.050034 17.424908 90)
			(size 0.519938 1.4986)
			(layers "F.Cu" "F.Mask" "F.Paste")
			(net "M_H_CPU1_SB_CB<6>")
		)
		(pad "235" smd rect
			(at 2.050034 18.275046 90)
			(size 0.519938 1.4986)
			(layers "F.Cu" "F.Mask" "F.Paste")
			(net "GND")
		)
		(pad "236" smd rect
			(at 2.050034 19.12493 90)
			(size 0.519938 1.4986)
			(layers "F.Cu" "F.Mask" "F.Paste")
			(net "M_H_CPU1_SB_CB<7>")
		)
		(pad "237" smd rect
			(at 2.050034 19.975068 90)
			(size 0.519938 1.4986)
			(layers "F.Cu" "F.Mask" "F.Paste")
			(net "GND")
		)
		(pad "238" smd rect
			(at 2.050034 20.824952 90)
			(size 0.519938 1.4986)
			(layers "F.Cu" "F.Mask" "F.Paste")
			(net "M_H_CPU1_SB_DQS_DN<4>")
		)
		(pad "239" smd rect
			(at 2.050034 21.67509 90)
			(size 0.519938 1.4986)
			(layers "F.Cu" "F.Mask" "F.Paste")
			(net "M_H_CPU1_SB_DQS_DP<4>")
		)
		(pad "240" smd rect
			(at 2.050034 22.524974 90)
			(size 0.519938 1.4986)
			(layers "F.Cu" "F.Mask" "F.Paste")
			(net "GND")
		)
		(pad "241" smd rect
			(at 2.050034 23.375112 90)
			(size 0.519938 1.4986)
			(layers "F.Cu" "F.Mask" "F.Paste")
			(net "M_H_CPU1_SB_CB<2>")
		)
		(pad "242" smd rect
			(at 2.050034 24.224996 90)
			(size 0.519938 1.4986)
			(layers "F.Cu" "F.Mask" "F.Paste")
			(net "GND")
		)
		(pad "243" smd rect
			(at 2.050034 25.07488 90)
			(size 0.519938 1.4986)
			(layers "F.Cu" "F.Mask" "F.Paste")
			(net "M_H_CPU1_SB_CB<3>")
		)
		(pad "244" smd rect
			(at 2.050034 25.925018 90)
			(size 0.519938 1.4986)
			(layers "F.Cu" "F.Mask" "F.Paste")
			(net "GND")
		)
		(pad "245" smd rect
			(at 2.050034 26.774902 90)
			(size 0.519938 1.4986)
			(layers "F.Cu" "F.Mask" "F.Paste")
			(net "M_H_CPU1_SB_DQ<2>")
		)
		(pad "246" smd rect
			(at 2.050034 27.62504 90)
			(size 0.519938 1.4986)
			(layers "F.Cu" "F.Mask" "F.Paste")
			(net "GND")
		)
		(pad "247" smd rect
			(at 2.050034 28.474924 90)
			(size 0.519938 1.4986)
			(layers "F.Cu" "F.Mask" "F.Paste")
			(net "M_H_CPU1_SB_DQ<3>")
		)
		(pad "248" smd rect
			(at 2.050034 29.325062 90)
			(size 0.519938 1.4986)
			(layers "F.Cu" "F.Mask" "F.Paste")
			(net "GND")
		)
		(pad "249" smd rect
			(at 2.050034 30.174946 90)
			(size 0.519938 1.4986)
			(layers "F.Cu" "F.Mask" "F.Paste")
			(net "M_H_CPU1_SB_DQS_DN<5>")
		)
		(pad "250" smd rect
			(at 2.050034 31.025084 90)
			(size 0.519938 1.4986)
			(layers "F.Cu" "F.Mask" "F.Paste")
			(net "M_H_CPU1_SB_DQS_DP<5>")
		)
		(pad "251" smd rect
			(at 2.050034 31.874968 90)
			(size 0.519938 1.4986)
			(layers "F.Cu" "F.Mask" "F.Paste")
			(net "GND")
		)
		(pad "252" smd rect
			(at 2.050034 32.725106 90)
			(size 0.519938 1.4986)
			(layers "F.Cu" "F.Mask" "F.Paste")
			(net "M_H_CPU1_SB_DQ<6>")
		)
		(pad "253" smd rect
			(at 2.050034 33.57499 90)
			(size 0.519938 1.4986)
			(layers "F.Cu" "F.Mask" "F.Paste")
			(net "GND")
		)
		(pad "254" smd rect
			(at 2.050034 34.425128 90)
			(size 0.519938 1.4986)
			(layers "F.Cu" "F.Mask" "F.Paste")
			(net "M_H_CPU1_SB_DQ<7>")
		)
		(pad "255" smd rect
			(at 2.050034 35.275012 90)
			(size 0.519938 1.4986)
			(layers "F.Cu" "F.Mask" "F.Paste")
			(net "GND")
		)
		(pad "256" smd rect
			(at 2.050034 36.124896 90)
			(size 0.519938 1.4986)
			(layers "F.Cu" "F.Mask" "F.Paste")
			(net "M_H_CPU1_SB_DQ<10>")
		)
		(pad "257" smd rect
			(at 2.050034 36.975034 90)
			(size 0.519938 1.4986)
			(layers "F.Cu" "F.Mask" "F.Paste")
			(net "GND")
		)
		(pad "258" smd rect
			(at 2.050034 37.824918 90)
			(size 0.519938 1.4986)
			(layers "F.Cu" "F.Mask" "F.Paste")
			(net "M_H_CPU1_SB_DQ<11>")
		)
		(pad "259" smd rect
			(at 2.050034 38.675056 90)
			(size 0.519938 1.4986)
			(layers "F.Cu" "F.Mask" "F.Paste")
			(net "GND")
		)
		(pad "260" smd rect
			(at 2.050034 39.52494 90)
			(size 0.519938 1.4986)
			(layers "F.Cu" "F.Mask" "F.Paste")
			(net "M_H_CPU1_SB_DQS_DN<6>")
		)
		(pad "261" smd rect
			(at 2.050034 40.375078 90)
			(size 0.519938 1.4986)
			(layers "F.Cu" "F.Mask" "F.Paste")
			(net "M_H_CPU1_SB_DQS_DP<6>")
		)
		(pad "262" smd rect
			(at 2.050034 41.224962 90)
			(size 0.519938 1.4986)
			(layers "F.Cu" "F.Mask" "F.Paste")
			(net "GND")
		)
		(pad "263" smd rect
			(at 2.050034 42.0751 90)
			(size 0.519938 1.4986)
			(layers "F.Cu" "F.Mask" "F.Paste")
			(net "M_H_CPU1_SB_DQ<14>")
		)
		(pad "264" smd rect
			(at 2.050034 42.924984 90)
			(size 0.519938 1.4986)
			(layers "F.Cu" "F.Mask" "F.Paste")
			(net "GND")
		)
		(pad "265" smd rect
			(at 2.050034 43.775122 90)
			(size 0.519938 1.4986)
			(layers "F.Cu" "F.Mask" "F.Paste")
			(net "M_H_CPU1_SB_DQ<15>")
		)
		(pad "266" smd rect
			(at 2.050034 44.625006 90)
			(size 0.519938 1.4986)
			(layers "F.Cu" "F.Mask" "F.Paste")
			(net "GND")
		)
		(pad "267" smd rect
			(at 2.050034 45.47489 90)
			(size 0.519938 1.4986)
			(layers "F.Cu" "F.Mask" "F.Paste")
			(net "M_H_CPU1_SB_DQ<18>")
		)
		(pad "268" smd rect
			(at 2.050034 46.325028 90)
			(size 0.519938 1.4986)
			(layers "F.Cu" "F.Mask" "F.Paste")
			(net "GND")
		)
		(pad "269" smd rect
			(at 2.050034 47.174912 90)
			(size 0.519938 1.4986)
			(layers "F.Cu" "F.Mask" "F.Paste")
			(net "M_H_CPU1_SB_DQ<19>")
		)
		(pad "270" smd rect
			(at 2.050034 48.02505 90)
			(size 0.519938 1.4986)
			(layers "F.Cu" "F.Mask" "F.Paste")
			(net "GND")
		)
		(pad "271" smd rect
			(at 2.050034 48.874934 90)
			(size 0.519938 1.4986)
			(layers "F.Cu" "F.Mask" "F.Paste")
			(net "M_H_CPU1_SB_DQS_DN<7>")
		)
		(pad "272" smd rect
			(at 2.050034 49.725072 90)
			(size 0.519938 1.4986)
			(layers "F.Cu" "F.Mask" "F.Paste")
			(net "M_H_CPU1_SB_DQS_DP<7>")
		)
		(pad "273" smd rect
			(at 2.050034 50.574956 90)
			(size 0.519938 1.4986)
			(layers "F.Cu" "F.Mask" "F.Paste")
			(net "GND")
		)
		(pad "274" smd rect
			(at 2.050034 51.425094 90)
			(size 0.519938 1.4986)
			(layers "F.Cu" "F.Mask" "F.Paste")
			(net "M_H_CPU1_SB_DQ<22>")
		)
		(pad "275" smd rect
			(at 2.050034 52.274978 90)
			(size 0.519938 1.4986)
			(layers "F.Cu" "F.Mask" "F.Paste")
			(net "GND")
		)
		(pad "276" smd rect
			(at 2.050034 53.125116 90)
			(size 0.519938 1.4986)
			(layers "F.Cu" "F.Mask" "F.Paste")
			(net "M_H_CPU1_SB_DQ<23>")
		)
		(pad "277" smd rect
			(at 2.050034 53.975 90)
			(size 0.519938 1.4986)
			(layers "F.Cu" "F.Mask" "F.Paste")
			(net "GND")
		)
		(pad "278" smd rect
			(at 2.050034 54.824884 90)
			(size 0.519938 1.4986)
			(layers "F.Cu" "F.Mask" "F.Paste")
			(net "M_H_CPU1_SB_DQ<26>")
		)
		(pad "279" smd rect
			(at 2.050034 55.675022 90)
			(size 0.519938 1.4986)
			(layers "F.Cu" "F.Mask" "F.Paste")
			(net "GND")
		)
		(pad "280" smd rect
			(at 2.050034 56.524906 90)
			(size 0.519938 1.4986)
			(layers "F.Cu" "F.Mask" "F.Paste")
			(net "M_H_CPU1_SB_DQ<27>")
		)
		(pad "281" smd rect
			(at 2.050034 57.375044 90)
			(size 0.519938 1.4986)
			(layers "F.Cu" "F.Mask" "F.Paste")
			(net "GND")
		)
		(pad "282" smd rect
			(at 2.050034 58.224928 90)
			(size 0.519938 1.4986)
			(layers "F.Cu" "F.Mask" "F.Paste")
			(net "M_H_CPU1_SB_DQS_DN<8>")
		)
		(pad "283" smd rect
			(at 2.050034 59.075066 90)
			(size 0.519938 1.4986)
			(layers "F.Cu" "F.Mask" "F.Paste")
			(net "M_H_CPU1_SB_DQS_DP<8>")
		)
		(pad "284" smd rect
			(at 2.050034 59.92495 90)
			(size 0.519938 1.4986)
			(layers "F.Cu" "F.Mask" "F.Paste")
			(net "GND")
		)
		(pad "285" smd rect
			(at 2.050034 60.775088 90)
			(size 0.519938 1.4986)
			(layers "F.Cu" "F.Mask" "F.Paste")
			(net "M_H_CPU1_SB_DQ<30>")
		)
		(pad "286" smd rect
			(at 2.050034 61.624972 90)
			(size 0.519938 1.4986)
			(layers "F.Cu" "F.Mask" "F.Paste")
			(net "GND")
		)
		(pad "287" smd rect
			(at 2.050034 62.47511 90)
			(size 0.519938 1.4986)
			(layers "F.Cu" "F.Mask" "F.Paste")
			(net "M_H_CPU1_SB_DQ<31>")
		)
		(pad "288" smd rect
			(at 2.050034 63.324994 90)
			(size 0.519938 1.4986)
			(layers "F.Cu" "F.Mask" "F.Paste")
			(net "GND")
		)
		(pad "G1" thru_hole oval
			(at 0 -68.97497 90)
			(size 1.7272 3.4798)
			(drill oval 1.2192 2.4638)
			(layers "*.Cu" "*.Mask")
			(remove_unused_layers no)
			(net "GND")
			(clearance 0.127)
			(thermal_gap 0.127)
		)
		(pad "G2" thru_hole oval
			(at 0 3.875024 90)
			(size 1.7272 3.4798)
			(drill oval 1.2192 2.4638)
			(layers "*.Cu" "*.Mask")
			(remove_unused_layers no)
			(net "GND")
			(clearance 0.127)
			(thermal_gap 0.127)
		)
		(pad "G3" thru_hole oval
			(at 0 68.97497 90)
			(size 1.7272 3.4798)
			(drill oval 1.2192 2.4638)
			(layers "*.Cu" "*.Mask")
			(remove_unused_layers no)
			(net "GND")
			(clearance 0.127)
			(thermal_gap 0.127)
		)
	)
	(footprint ""
		(layer "F.Cu")
		(at 463.370168 -109.646212 180)
		(property "Reference" "R577"
			(at 0 0 180)
			(layer "F.SilkS")
			(hide yes)
			(effects
				(font
					(size 1.27 1.27)
				)
			)
		)
		(property "Value" ""
			(at 0 0 180)
			(layer "F.Fab")
			(effects
				(font
					(size 1.27 1.27)
				)
			)
		)
		(duplicate_pad_numbers_are_jumpers no)
		(fp_line
			(start 0.7874 0.4064)
			(end -0.7874 0.4064)
			(stroke
				(width 0.1524)
				(type default)
			)
			(layer "F.SilkS")
		)
		(fp_line
			(start 0.7874 -0.4064)
			(end 0.7874 0.4064)
			(stroke
				(width 0.1524)
				(type default)
			)
			(layer "F.SilkS")
		)
		(fp_line
			(start -0.7874 0.4064)
			(end -0.7874 -0.4064)
			(stroke
				(width 0.1524)
				(type default)
			)
			(layer "F.SilkS")
		)
		(fp_line
			(start -0.7874 -0.4064)
			(end 0.7874 -0.4064)
			(stroke
				(width 0.1524)
				(type default)
			)
			(layer "F.SilkS")
		)
		(fp_line
			(start 0.67945 0.3048)
			(end 0.120396 0.3048)
			(stroke
				(width 0.1)
				(type default)
			)
			(layer "F.Fab")
		)
		(fp_line
			(start 0.67945 -0.3048)
			(end 0.67945 0.3048)
			(stroke
				(width 0.1)
				(type default)
			)
			(layer "F.Fab")
		)
		(fp_line
			(start 0.12065 -0.2794)
			(end 0.12065 -0.3048)
			(stroke
				(width 0.1)
				(type default)
			)
			(layer "F.Fab")
		)
		(fp_line
			(start 0.12065 -0.3048)
			(end 0.67945 -0.3048)
			(stroke
				(width 0.1)
				(type default)
			)
			(layer "F.Fab")
		)
		(fp_line
			(start 0.120396 0.3048)
			(end 0.120396 0.2794)
			(stroke
				(width 0.1)
				(type default)
			)
			(layer "F.Fab")
		)
		(fp_line
			(start 0.120396 0.2794)
			(end -0.12065 0.2794)
			(stroke
				(width 0.1)
				(type default)
			)
			(layer "F.Fab")
		)
		(fp_line
			(start -0.12065 0.3048)
			(end -0.67945 0.3048)
			(stroke
				(width 0.1)
				(type default)
			)
			(layer "F.Fab")
		)
		(fp_line
			(start -0.12065 0.2794)
			(end -0.12065 0.3048)
			(stroke
				(width 0.1)
				(type default)
			)
			(layer "F.Fab")
		)
		(fp_line
			(start -0.12065 -0.2794)
			(end 0.12065 -0.2794)
			(stroke
				(width 0.1)
				(type default)
			)
			(layer "F.Fab")
		)
		(fp_line
			(start -0.12065 -0.305054)
			(end -0.12065 -0.2794)
			(stroke
				(width 0.1)
				(type default)
			)
			(layer "F.Fab")
		)
		(fp_line
			(start -0.67945 0.3048)
			(end -0.67945 -0.305054)
			(stroke
				(width 0.1)
				(type default)
			)
			(layer "F.Fab")
		)
		(fp_line
			(start -0.67945 -0.305054)
			(end -0.12065 -0.305054)
			(stroke
				(width 0.1)
				(type default)
			)
			(layer "F.Fab")
		)
		(pad "1" smd circle
			(at -0.40005 0 180)
			(size 0 0)
			(layers "F.Cu" "F.Mask" "F.Paste")
			(net "P3V3_AUX")
		)
		(pad "2" smd circle
			(at 0.40005 0 180)
			(size 0 0)
			(layers "F.Cu" "F.Mask" "F.Paste")
			(net "HP_LVC3_OCP_SFF_PRSNT2_N")
		)
	)
	(footprint ""
		(layer "F.Cu")
		(at 253.506224 -133.622796 180)
		(property "Reference" "R600"
			(at 0 0 180)
			(layer "F.SilkS")
			(hide yes)
			(effects
				(font
					(size 1.27 1.27)
				)
			)
		)
		(property "Value" ""
			(at 0 0 180)
			(layer "F.Fab")
			(effects
				(font
					(size 1.27 1.27)
				)
			)
		)
		(duplicate_pad_numbers_are_jumpers no)
		(fp_line
			(start 0.7874 0.4064)
			(end -0.7874 0.4064)
			(stroke
				(width 0.1524)
				(type default)
			)
			(layer "F.SilkS")
		)
		(fp_line
			(start 0.7874 -0.4064)
			(end 0.7874 0.4064)
			(stroke
				(width 0.1524)
				(type default)
			)
			(layer "F.SilkS")
		)
		(fp_line
			(start -0.7874 0.4064)
			(end -0.7874 -0.4064)
			(stroke
				(width 0.1524)
				(type default)
			)
			(layer "F.SilkS")
		)
		(fp_line
			(start -0.7874 -0.4064)
			(end 0.7874 -0.4064)
			(stroke
				(width 0.1524)
				(type default)
			)
			(layer "F.SilkS")
		)
		(fp_line
			(start 0.67945 0.3048)
			(end 0.120396 0.3048)
			(stroke
				(width 0.1)
				(type default)
			)
			(layer "F.Fab")
		)
		(fp_line
			(start 0.67945 -0.3048)
			(end 0.67945 0.3048)
			(stroke
				(width 0.1)
				(type default)
			)
			(layer "F.Fab")
		)
		(fp_line
			(start 0.12065 -0.2794)
			(end 0.12065 -0.3048)
			(stroke
				(width 0.1)
				(type default)
			)
			(layer "F.Fab")
		)
		(fp_line
			(start 0.12065 -0.3048)
			(end 0.67945 -0.3048)
			(stroke
				(width 0.1)
				(type default)
			)
			(layer "F.Fab")
		)
		(fp_line
			(start 0.120396 0.3048)
			(end 0.120396 0.2794)
			(stroke
				(width 0.1)
				(type default)
			)
			(layer "F.Fab")
		)
		(fp_line
			(start 0.120396 0.2794)
			(end -0.12065 0.2794)
			(stroke
				(width 0.1)
				(type default)
			)
			(layer "F.Fab")
		)
		(fp_line
			(start -0.12065 0.3048)
			(end -0.67945 0.3048)
			(stroke
				(width 0.1)
				(type default)
			)
			(layer "F.Fab")
		)
		(fp_line
			(start -0.12065 0.2794)
			(end -0.12065 0.3048)
			(stroke
				(width 0.1)
				(type default)
			)
			(layer "F.Fab")
		)
		(fp_line
			(start -0.12065 -0.2794)
			(end 0.12065 -0.2794)
			(stroke
				(width 0.1)
				(type default)
			)
			(layer "F.Fab")
		)
		(fp_line
			(start -0.12065 -0.305054)
			(end -0.12065 -0.2794)
			(stroke
				(width 0.1)
				(type default)
			)
			(layer "F.Fab")
		)
		(fp_line
			(start -0.67945 0.3048)
			(end -0.67945 -0.305054)
			(stroke
				(width 0.1)
				(type default)
			)
			(layer "F.Fab")
		)
		(fp_line
			(start -0.67945 -0.305054)
			(end -0.12065 -0.305054)
			(stroke
				(width 0.1)
				(type default)
			)
			(layer "F.Fab")
		)
		(pad "1" smd circle
			(at -0.40005 0 180)
			(size 0 0)
			(layers "F.Cu" "F.Mask" "F.Paste")
			(net "SPI_CPU0_LVC3_CS1_N")
		)
		(pad "2" smd circle
			(at 0.40005 0 180)
			(size 0 0)
			(layers "F.Cu" "F.Mask" "F.Paste")
			(net "SPI_CPU0_LVC3_SCM_CS1_N")
		)
	)
	(footprint ""
		(layer "F.Cu")
		(at 102.021386 -386.44068 90)
		(property "Reference" "C111"
			(at 0 0 90)
			(layer "F.SilkS")
			(hide yes)
			(effects
				(font
					(size 1.27 1.27)
				)
			)
		)
		(property "Value" ""
			(at 0 0 90)
			(layer "F.Fab")
			(effects
				(font
					(size 1.27 1.27)
				)
			)
		)
		(duplicate_pad_numbers_are_jumpers no)
		(fp_line
			(start 0.7874 -0.4064)
			(end 0.7874 0.4064)
			(stroke
				(width 0.1524)
				(type default)
			)
			(layer "F.SilkS")
		)
		(fp_line
			(start -0.7874 -0.4064)
			(end 0.7874 -0.4064)
			(stroke
				(width 0.1524)
				(type default)
			)
			(layer "F.SilkS")
		)
		(fp_line
			(start 0.7874 0.4064)
			(end -0.7874 0.4064)
			(stroke
				(width 0.1524)
				(type default)
			)
			(layer "F.SilkS")
		)
		(fp_line
			(start -0.7874 0.4064)
			(end -0.7874 -0.4064)
			(stroke
				(width 0.1524)
				(type default)
			)
			(layer "F.SilkS")
		)
		(fp_line
			(start -0.12065 -0.305054)
			(end -0.12065 -0.2794)
			(stroke
				(width 0.1)
				(type default)
			)
			(layer "F.Fab")
		)
		(fp_line
			(start -0.67945 -0.305054)
			(end -0.12065 -0.305054)
			(stroke
				(width 0.1)
				(type default)
			)
			(layer "F.Fab")
		)
		(fp_line
			(start 0.67945 -0.3048)
			(end 0.67945 0.3048)
			(stroke
				(width 0.1)
				(type default)
			)
			(layer "F.Fab")
		)
		(fp_line
			(start 0.12065 -0.3048)
			(end 0.67945 -0.3048)
			(stroke
				(width 0.1)
				(type default)
			)
			(layer "F.Fab")
		)
		(fp_line
			(start 0.12065 -0.2794)
			(end 0.12065 -0.3048)
			(stroke
				(width 0.1)
				(type default)
			)
			(layer "F.Fab")
		)
		(fp_line
			(start -0.12065 -0.2794)
			(end 0.12065 -0.2794)
			(stroke
				(width 0.1)
				(type default)
			)
			(layer "F.Fab")
		)
		(fp_line
			(start 0.120396 0.2794)
			(end -0.12065 0.2794)
			(stroke
				(width 0.1)
				(type default)
			)
			(layer "F.Fab")
		)
		(fp_line
			(start -0.12065 0.2794)
			(end -0.12065 0.3048)
			(stroke
				(width 0.1)
				(type default)
			)
			(layer "F.Fab")
		)
		(fp_line
			(start 0.67945 0.3048)
			(end 0.120396 0.3048)
			(stroke
				(width 0.1)
				(type default)
			)
			(layer "F.Fab")
		)
		(fp_line
			(start 0.120396 0.3048)
			(end 0.120396 0.2794)
			(stroke
				(width 0.1)
				(type default)
			)
			(layer "F.Fab")
		)
		(fp_line
			(start -0.12065 0.3048)
			(end -0.67945 0.3048)
			(stroke
				(width 0.1)
				(type default)
			)
			(layer "F.Fab")
		)
		(fp_line
			(start -0.67945 0.3048)
			(end -0.67945 -0.305054)
			(stroke
				(width 0.1)
				(type default)
			)
			(layer "F.Fab")
		)
		(pad "1" smd circle
			(at -0.40005 0 90)
			(size 0 0)
			(layers "F.Cu" "F.Mask" "F.Paste")
			(net "P1V8_CPU1_RT1_1A")
		)
		(pad "2" smd circle
			(at 0.40005 0 90)
			(size 0 0)
			(layers "F.Cu" "F.Mask" "F.Paste")
			(net "GND")
		)
	)
	(footprint ""
		(layer "F.Cu")
		(at 255.447546 -43.902122 90)
		(property "Reference" "PC2209"
			(at 0 0 90)
			(layer "F.SilkS")
			(hide yes)
			(effects
				(font
					(size 1.27 1.27)
				)
			)
		)
		(property "Value" ""
			(at 0 0 90)
			(layer "F.Fab")
			(effects
				(font
					(size 1.27 1.27)
				)
			)
		)
		(duplicate_pad_numbers_are_jumpers no)
		(fp_line
			(start 0.7874 -0.4064)
			(end 0.7874 0.4064)
			(stroke
				(width 0.1524)
				(type default)
			)
			(layer "F.SilkS")
		)
		(fp_line
			(start -0.7874 -0.4064)
			(end 0.7874 -0.4064)
			(stroke
				(width 0.1524)
				(type default)
			)
			(layer "F.SilkS")
		)
		(fp_line
			(start 0.7874 0.4064)
			(end -0.7874 0.4064)
			(stroke
				(width 0.1524)
				(type default)
			)
			(layer "F.SilkS")
		)
		(fp_line
			(start -0.7874 0.4064)
			(end -0.7874 -0.4064)
			(stroke
				(width 0.1524)
				(type default)
			)
			(layer "F.SilkS")
		)
		(fp_line
			(start -0.12065 -0.305054)
			(end -0.12065 -0.2794)
			(stroke
				(width 0.1)
				(type default)
			)
			(layer "F.Fab")
		)
		(fp_line
			(start -0.67945 -0.305054)
			(end -0.12065 -0.305054)
			(stroke
				(width 0.1)
				(type default)
			)
			(layer "F.Fab")
		)
		(fp_line
			(start 0.67945 -0.3048)
			(end 0.67945 0.3048)
			(stroke
				(width 0.1)
				(type default)
			)
			(layer "F.Fab")
		)
		(fp_line
			(start 0.12065 -0.3048)
			(end 0.67945 -0.3048)
			(stroke
				(width 0.1)
				(type default)
			)
			(layer "F.Fab")
		)
		(fp_line
			(start 0.12065 -0.2794)
			(end 0.12065 -0.3048)
			(stroke
				(width 0.1)
				(type default)
			)
			(layer "F.Fab")
		)
		(fp_line
			(start -0.12065 -0.2794)
			(end 0.12065 -0.2794)
			(stroke
				(width 0.1)
				(type default)
			)
			(layer "F.Fab")
		)
		(fp_line
			(start 0.120396 0.2794)
			(end -0.12065 0.2794)
			(stroke
				(width 0.1)
				(type default)
			)
			(layer "F.Fab")
		)
		(fp_line
			(start -0.12065 0.2794)
			(end -0.12065 0.3048)
			(stroke
				(width 0.1)
				(type default)
			)
			(layer "F.Fab")
		)
		(fp_line
			(start 0.67945 0.3048)
			(end 0.120396 0.3048)
			(stroke
				(width 0.1)
				(type default)
			)
			(layer "F.Fab")
		)
		(fp_line
			(start 0.120396 0.3048)
			(end 0.120396 0.2794)
			(stroke
				(width 0.1)
				(type default)
			)
			(layer "F.Fab")
		)
		(fp_line
			(start -0.12065 0.3048)
			(end -0.67945 0.3048)
			(stroke
				(width 0.1)
				(type default)
			)
			(layer "F.Fab")
		)
		(fp_line
			(start -0.67945 0.3048)
			(end -0.67945 -0.305054)
			(stroke
				(width 0.1)
				(type default)
			)
			(layer "F.Fab")
		)
		(pad "1" smd circle
			(at -0.40005 0 90)
			(size 0 0)
			(layers "F.Cu" "F.Mask" "F.Paste")
			(net "P12V_E1S_VCC_0")
		)
		(pad "2" smd circle
			(at 0.40005 0 90)
			(size 0 0)
			(layers "F.Cu" "F.Mask" "F.Paste")
			(net "GND")
		)
	)
	(footprint ""
		(layer "F.Cu")
		(at 205.214982 -123.785376)
		(property "Reference" "R2844"
			(at 0 0 0)
			(layer "F.SilkS")
			(hide yes)
			(effects
				(font
					(size 1.27 1.27)
				)
			)
		)
		(property "Value" ""
			(at 0 0 0)
			(layer "F.Fab")
			(effects
				(font
					(size 1.27 1.27)
				)
			)
		)
		(duplicate_pad_numbers_are_jumpers no)
		(fp_line
			(start -0.7874 -0.4064)
			(end 0.7874 -0.4064)
			(stroke
				(width 0.1524)
				(type default)
			)
			(layer "F.SilkS")
		)
		(fp_line
			(start -0.7874 0.4064)
			(end -0.7874 -0.4064)
			(stroke
				(width 0.1524)
				(type default)
			)
			(layer "F.SilkS")
		)
		(fp_line
			(start 0.7874 -0.4064)
			(end 0.7874 0.4064)
			(stroke
				(width 0.1524)
				(type default)
			)
			(layer "F.SilkS")
		)
		(fp_line
			(start 0.7874 0.4064)
			(end -0.7874 0.4064)
			(stroke
				(width 0.1524)
				(type default)
			)
			(layer "F.SilkS")
		)
		(fp_line
			(start -0.67945 -0.305054)
			(end -0.12065 -0.305054)
			(stroke
				(width 0.1)
				(type default)
			)
			(layer "F.Fab")
		)
		(fp_line
			(start -0.67945 0.3048)
			(end -0.67945 -0.305054)
			(stroke
				(width 0.1)
				(type default)
			)
			(layer "F.Fab")
		)
		(fp_line
			(start -0.12065 -0.305054)
			(end -0.12065 -0.2794)
			(stroke
				(width 0.1)
				(type default)
			)
			(layer "F.Fab")
		)
		(fp_line
			(start -0.12065 -0.2794)
			(end 0.12065 -0.2794)
			(stroke
				(width 0.1)
				(type default)
			)
			(layer "F.Fab")
		)
		(fp_line
			(start -0.12065 0.2794)
			(end -0.12065 0.3048)
			(stroke
				(width 0.1)
				(type default)
			)
			(layer "F.Fab")
		)
		(fp_line
			(start -0.12065 0.3048)
			(end -0.67945 0.3048)
			(stroke
				(width 0.1)
				(type default)
			)
			(layer "F.Fab")
		)
		(fp_line
			(start 0.120396 0.2794)
			(end -0.12065 0.2794)
			(stroke
				(width 0.1)
				(type default)
			)
			(layer "F.Fab")
		)
		(fp_line
			(start 0.120396 0.3048)
			(end 0.120396 0.2794)
			(stroke
				(width 0.1)
				(type default)
			)
			(layer "F.Fab")
		)
		(fp_line
			(start 0.12065 -0.3048)
			(end 0.67945 -0.3048)
			(stroke
				(width 0.1)
				(type default)
			)
			(layer "F.Fab")
		)
		(fp_line
			(start 0.12065 -0.2794)
			(end 0.12065 -0.3048)
			(stroke
				(width 0.1)
				(type default)
			)
			(layer "F.Fab")
		)
		(fp_line
			(start 0.67945 -0.3048)
			(end 0.67945 0.3048)
			(stroke
				(width 0.1)
				(type default)
			)
			(layer "F.Fab")
		)
		(fp_line
			(start 0.67945 0.3048)
			(end 0.120396 0.3048)
			(stroke
				(width 0.1)
				(type default)
			)
			(layer "F.Fab")
		)
		(pad "1" smd circle
			(at -0.40005 0)
			(size 0 0)
			(layers "F.Cu" "F.Mask" "F.Paste")
			(net "FM_SWB_BIC_READY_ISO_R_N")
		)
		(pad "2" smd circle
			(at 0.40005 0)
			(size 0 0)
			(layers "F.Cu" "F.Mask" "F.Paste")
			(net "FM_SWB_BIC_READY_ISO_N")
		)
	)
	(footprint ""
		(layer "F.Cu")
		(at 425.54144 -434.467508 90)
		(property "Reference" "R4164"
			(at 0 0 90)
			(layer "F.SilkS")
			(hide yes)
			(effects
				(font
					(size 1.27 1.27)
				)
			)
		)
		(property "Value" ""
			(at 0 0 90)
			(layer "F.Fab")
			(effects
				(font
					(size 1.27 1.27)
				)
			)
		)
		(duplicate_pad_numbers_are_jumpers no)
		(fp_line
			(start 0.7874 -0.4064)
			(end 0.7874 0.4064)
			(stroke
				(width 0.1524)
				(type default)
			)
			(layer "F.SilkS")
		)
		(fp_line
			(start -0.7874 -0.4064)
			(end 0.7874 -0.4064)
			(stroke
				(width 0.1524)
				(type default)
			)
			(layer "F.SilkS")
		)
		(fp_line
			(start 0.7874 0.4064)
			(end -0.7874 0.4064)
			(stroke
				(width 0.1524)
				(type default)
			)
			(layer "F.SilkS")
		)
		(fp_line
			(start -0.7874 0.4064)
			(end -0.7874 -0.4064)
			(stroke
				(width 0.1524)
				(type default)
			)
			(layer "F.SilkS")
		)
		(fp_line
			(start -0.12065 -0.305054)
			(end -0.12065 -0.2794)
			(stroke
				(width 0.1)
				(type default)
			)
			(layer "F.Fab")
		)
		(fp_line
			(start -0.67945 -0.305054)
			(end -0.12065 -0.305054)
			(stroke
				(width 0.1)
				(type default)
			)
			(layer "F.Fab")
		)
		(fp_line
			(start 0.67945 -0.3048)
			(end 0.67945 0.3048)
			(stroke
				(width 0.1)
				(type default)
			)
			(layer "F.Fab")
		)
		(fp_line
			(start 0.12065 -0.3048)
			(end 0.67945 -0.3048)
			(stroke
				(width 0.1)
				(type default)
			)
			(layer "F.Fab")
		)
		(fp_line
			(start 0.12065 -0.2794)
			(end 0.12065 -0.3048)
			(stroke
				(width 0.1)
				(type default)
			)
			(layer "F.Fab")
		)
		(fp_line
			(start -0.12065 -0.2794)
			(end 0.12065 -0.2794)
			(stroke
				(width 0.1)
				(type default)
			)
			(layer "F.Fab")
		)
		(fp_line
			(start 0.120396 0.2794)
			(end -0.12065 0.2794)
			(stroke
				(width 0.1)
				(type default)
			)
			(layer "F.Fab")
		)
		(fp_line
			(start -0.12065 0.2794)
			(end -0.12065 0.3048)
			(stroke
				(width 0.1)
				(type default)
			)
			(layer "F.Fab")
		)
		(fp_line
			(start 0.67945 0.3048)
			(end 0.120396 0.3048)
			(stroke
				(width 0.1)
				(type default)
			)
			(layer "F.Fab")
		)
		(fp_line
			(start 0.120396 0.3048)
			(end 0.120396 0.2794)
			(stroke
				(width 0.1)
				(type default)
			)
			(layer "F.Fab")
		)
		(fp_line
			(start -0.12065 0.3048)
			(end -0.67945 0.3048)
			(stroke
				(width 0.1)
				(type default)
			)
			(layer "F.Fab")
		)
		(fp_line
			(start -0.67945 0.3048)
			(end -0.67945 -0.305054)
			(stroke
				(width 0.1)
				(type default)
			)
			(layer "F.Fab")
		)
		(pad "1" smd circle
			(at -0.40005 0 90)
			(size 0 0)
			(layers "F.Cu" "F.Mask" "F.Paste")
			(net "P3V3_AUX")
		)
		(pad "2" smd circle
			(at 0.40005 0 90)
			(size 0 0)
			(layers "F.Cu" "F.Mask" "F.Paste")
			(net "GPU_3V3IO_RSVD1_N")
		)
	)
	(footprint ""
		(layer "F.Cu")
		(at 277.608792 -121.37517 -90)
		(property "Reference" "R6212"
			(at 0 0 270)
			(layer "F.SilkS")
			(hide yes)
			(effects
				(font
					(size 1.27 1.27)
				)
			)
		)
		(property "Value" ""
			(at 0 0 270)
			(layer "F.Fab")
			(effects
				(font
					(size 1.27 1.27)
				)
			)
		)
		(duplicate_pad_numbers_are_jumpers no)
		(fp_line
			(start -0.7874 0.4064)
			(end -0.7874 -0.4064)
			(stroke
				(width 0.1524)
				(type default)
			)
			(layer "F.SilkS")
		)
		(fp_line
			(start 0.7874 0.4064)
			(end -0.7874 0.4064)
			(stroke
				(width 0.1524)
				(type default)
			)
			(layer "F.SilkS")
		)
		(fp_line
			(start -0.7874 -0.4064)
			(end 0.7874 -0.4064)
			(stroke
				(width 0.1524)
				(type default)
			)
			(layer "F.SilkS")
		)
		(fp_line
			(start 0.7874 -0.4064)
			(end 0.7874 0.4064)
			(stroke
				(width 0.1524)
				(type default)
			)
			(layer "F.SilkS")
		)
		(fp_line
			(start -0.67945 0.3048)
			(end -0.67945 -0.305054)
			(stroke
				(width 0.1)
				(type default)
			)
			(layer "F.Fab")
		)
		(fp_line
			(start -0.12065 0.3048)
			(end -0.67945 0.3048)
			(stroke
				(width 0.1)
				(type default)
			)
			(layer "F.Fab")
		)
		(fp_line
			(start 0.120396 0.3048)
			(end 0.120396 0.2794)
			(stroke
				(width 0.1)
				(type default)
			)
			(layer "F.Fab")
		)
		(fp_line
			(start 0.67945 0.3048)
			(end 0.120396 0.3048)
			(stroke
				(width 0.1)
				(type default)
			)
			(layer "F.Fab")
		)
		(fp_line
			(start -0.12065 0.2794)
			(end -0.12065 0.3048)
			(stroke
				(width 0.1)
				(type default)
			)
			(layer "F.Fab")
		)
		(fp_line
			(start 0.120396 0.2794)
			(end -0.12065 0.2794)
			(stroke
				(width 0.1)
				(type default)
			)
			(layer "F.Fab")
		)
		(fp_line
			(start -0.12065 -0.2794)
			(end 0.12065 -0.2794)
			(stroke
				(width 0.1)
				(type default)
			)
			(layer "F.Fab")
		)
		(fp_line
			(start 0.12065 -0.2794)
			(end 0.12065 -0.3048)
			(stroke
				(width 0.1)
				(type default)
			)
			(layer "F.Fab")
		)
		(fp_line
			(start 0.12065 -0.3048)
			(end 0.67945 -0.3048)
			(stroke
				(width 0.1)
				(type default)
			)
			(layer "F.Fab")
		)
		(fp_line
			(start 0.67945 -0.3048)
			(end 0.67945 0.3048)
			(stroke
				(width 0.1)
				(type default)
			)
			(layer "F.Fab")
		)
		(fp_line
			(start -0.67945 -0.305054)
			(end -0.12065 -0.305054)
			(stroke
				(width 0.1)
				(type default)
			)
			(layer "F.Fab")
		)
		(fp_line
			(start -0.12065 -0.305054)
			(end -0.12065 -0.2794)
			(stroke
				(width 0.1)
				(type default)
			)
			(layer "F.Fab")
		)
		(pad "1" smd circle
			(at -0.40005 0 270)
			(size 0 0)
			(layers "F.Cu" "F.Mask" "F.Paste")
			(net "P3V3_AUX")
		)
		(pad "2" smd circle
			(at 0.40005 0 270)
			(size 0 0)
			(layers "F.Cu" "F.Mask" "F.Paste")
			(net "SMB_USB_CPU0_HUB1_SDA")
		)
	)
	(footprint ""
		(layer "F.Cu")
		(at 365.09579 -393.86256)
		(property "Reference" "R1111"
			(at 0 0 0)
			(layer "F.SilkS")
			(hide yes)
			(effects
				(font
					(size 1.27 1.27)
				)
			)
		)
		(property "Value" ""
			(at 0 0 0)
			(layer "F.Fab")
			(effects
				(font
					(size 1.27 1.27)
				)
			)
		)
		(duplicate_pad_numbers_are_jumpers no)
		(fp_line
			(start -0.32512 -0.175006)
			(end 0.32512 -0.175006)
			(stroke
				(width 0.1)
				(type default)
			)
			(layer "F.Fab")
		)
		(fp_line
			(start -0.32512 0.175006)
			(end -0.32512 -0.175006)
			(stroke
				(width 0.1)
				(type default)
			)
			(layer "F.Fab")
		)
		(fp_line
			(start 0.32512 -0.175006)
			(end 0.32512 0.175006)
			(stroke
				(width 0.1)
				(type default)
			)
			(layer "F.Fab")
		)
		(fp_line
			(start 0.32512 0.175006)
			(end -0.32512 0.175006)
			(stroke
				(width 0.1)
				(type default)
			)
			(layer "F.Fab")
		)
		(pad "1" smd rect
			(at -0.2667 0)
			(size 0.3048 0.381)
			(layers "F.Cu" "F.Mask" "F.Paste")
			(net "P1V8_CPU0_RT_1D")
		)
		(pad "2" smd rect
			(at 0.2667 0 180)
			(size 0.3048 0.381)
			(layers "F.Cu" "F.Mask" "F.Paste")
			(net "GPIO2_RT_CPU0_P3")
		)
	)
	(footprint ""
		(layer "F.Cu")
		(at 264.478516 -131.067556 180)
		(property "Reference" "R811"
			(at 0 0 180)
			(layer "F.SilkS")
			(hide yes)
			(effects
				(font
					(size 1.27 1.27)
				)
			)
		)
		(property "Value" ""
			(at 0 0 180)
			(layer "F.Fab")
			(effects
				(font
					(size 1.27 1.27)
				)
			)
		)
		(duplicate_pad_numbers_are_jumpers no)
		(fp_line
			(start 0.7874 0.4064)
			(end -0.7874 0.4064)
			(stroke
				(width 0.1524)
				(type default)
			)
			(layer "F.SilkS")
		)
		(fp_line
			(start 0.7874 -0.4064)
			(end 0.7874 0.4064)
			(stroke
				(width 0.1524)
				(type default)
			)
			(layer "F.SilkS")
		)
		(fp_line
			(start -0.7874 0.4064)
			(end -0.7874 -0.4064)
			(stroke
				(width 0.1524)
				(type default)
			)
			(layer "F.SilkS")
		)
		(fp_line
			(start -0.7874 -0.4064)
			(end 0.7874 -0.4064)
			(stroke
				(width 0.1524)
				(type default)
			)
			(layer "F.SilkS")
		)
		(fp_line
			(start 0.67945 0.3048)
			(end 0.120396 0.3048)
			(stroke
				(width 0.1)
				(type default)
			)
			(layer "F.Fab")
		)
		(fp_line
			(start 0.67945 -0.3048)
			(end 0.67945 0.3048)
			(stroke
				(width 0.1)
				(type default)
			)
			(layer "F.Fab")
		)
		(fp_line
			(start 0.12065 -0.2794)
			(end 0.12065 -0.3048)
			(stroke
				(width 0.1)
				(type default)
			)
			(layer "F.Fab")
		)
		(fp_line
			(start 0.12065 -0.3048)
			(end 0.67945 -0.3048)
			(stroke
				(width 0.1)
				(type default)
			)
			(layer "F.Fab")
		)
		(fp_line
			(start 0.120396 0.3048)
			(end 0.120396 0.2794)
			(stroke
				(width 0.1)
				(type default)
			)
			(layer "F.Fab")
		)
		(fp_line
			(start 0.120396 0.2794)
			(end -0.12065 0.2794)
			(stroke
				(width 0.1)
				(type default)
			)
			(layer "F.Fab")
		)
		(fp_line
			(start -0.12065 0.3048)
			(end -0.67945 0.3048)
			(stroke
				(width 0.1)
				(type default)
			)
			(layer "F.Fab")
		)
		(fp_line
			(start -0.12065 0.2794)
			(end -0.12065 0.3048)
			(stroke
				(width 0.1)
				(type default)
			)
			(layer "F.Fab")
		)
		(fp_line
			(start -0.12065 -0.2794)
			(end 0.12065 -0.2794)
			(stroke
				(width 0.1)
				(type default)
			)
			(layer "F.Fab")
		)
		(fp_line
			(start -0.12065 -0.305054)
			(end -0.12065 -0.2794)
			(stroke
				(width 0.1)
				(type default)
			)
			(layer "F.Fab")
		)
		(fp_line
			(start -0.67945 0.3048)
			(end -0.67945 -0.305054)
			(stroke
				(width 0.1)
				(type default)
			)
			(layer "F.Fab")
		)
		(fp_line
			(start -0.67945 -0.305054)
			(end -0.12065 -0.305054)
			(stroke
				(width 0.1)
				(type default)
			)
			(layer "F.Fab")
		)
		(pad "1" smd circle
			(at -0.40005 0 180)
			(size 0 0)
			(layers "F.Cu" "F.Mask" "F.Paste")
			(net "PVDD18_S5_P0")
		)
		(pad "2" smd circle
			(at 0.40005 0 180)
			(size 0 0)
			(layers "F.Cu" "F.Mask" "F.Paste")
			(net "SPI_CPU0_CS0_N")
		)
	)
	(footprint ""
		(layer "F.Cu")
		(at 109.165136 -119.46001 90)
		(property "Reference" "R1492"
			(at 0 0 90)
			(layer "F.SilkS")
			(hide yes)
			(effects
				(font
					(size 1.27 1.27)
				)
			)
		)
		(property "Value" ""
			(at 0 0 90)
			(layer "F.Fab")
			(effects
				(font
					(size 1.27 1.27)
				)
			)
		)
		(duplicate_pad_numbers_are_jumpers no)
		(fp_line
			(start 0.7874 -0.4064)
			(end 0.7874 0.4064)
			(stroke
				(width 0.1524)
				(type default)
			)
			(layer "F.SilkS")
		)
		(fp_line
			(start -0.7874 -0.4064)
			(end 0.7874 -0.4064)
			(stroke
				(width 0.1524)
				(type default)
			)
			(layer "F.SilkS")
		)
		(fp_line
			(start 0.7874 0.4064)
			(end -0.7874 0.4064)
			(stroke
				(width 0.1524)
				(type default)
			)
			(layer "F.SilkS")
		)
		(fp_line
			(start -0.7874 0.4064)
			(end -0.7874 -0.4064)
			(stroke
				(width 0.1524)
				(type default)
			)
			(layer "F.SilkS")
		)
		(fp_line
			(start -0.12065 -0.305054)
			(end -0.12065 -0.2794)
			(stroke
				(width 0.1)
				(type default)
			)
			(layer "F.Fab")
		)
		(fp_line
			(start -0.67945 -0.305054)
			(end -0.12065 -0.305054)
			(stroke
				(width 0.1)
				(type default)
			)
			(layer "F.Fab")
		)
		(fp_line
			(start 0.67945 -0.3048)
			(end 0.67945 0.3048)
			(stroke
				(width 0.1)
				(type default)
			)
			(layer "F.Fab")
		)
		(fp_line
			(start 0.12065 -0.3048)
			(end 0.67945 -0.3048)
			(stroke
				(width 0.1)
				(type default)
			)
			(layer "F.Fab")
		)
		(fp_line
			(start 0.12065 -0.2794)
			(end 0.12065 -0.3048)
			(stroke
				(width 0.1)
				(type default)
			)
			(layer "F.Fab")
		)
		(fp_line
			(start -0.12065 -0.2794)
			(end 0.12065 -0.2794)
			(stroke
				(width 0.1)
				(type default)
			)
			(layer "F.Fab")
		)
		(fp_line
			(start 0.120396 0.2794)
			(end -0.12065 0.2794)
			(stroke
				(width 0.1)
				(type default)
			)
			(layer "F.Fab")
		)
		(fp_line
			(start -0.12065 0.2794)
			(end -0.12065 0.3048)
			(stroke
				(width 0.1)
				(type default)
			)
			(layer "F.Fab")
		)
		(fp_line
			(start 0.67945 0.3048)
			(end 0.120396 0.3048)
			(stroke
				(width 0.1)
				(type default)
			)
			(layer "F.Fab")
		)
		(fp_line
			(start 0.120396 0.3048)
			(end 0.120396 0.2794)
			(stroke
				(width 0.1)
				(type default)
			)
			(layer "F.Fab")
		)
		(fp_line
			(start -0.12065 0.3048)
			(end -0.67945 0.3048)
			(stroke
				(width 0.1)
				(type default)
			)
			(layer "F.Fab")
		)
		(fp_line
			(start -0.67945 0.3048)
			(end -0.67945 -0.305054)
			(stroke
				(width 0.1)
				(type default)
			)
			(layer "F.Fab")
		)
		(pad "1" smd circle
			(at -0.40005 0 90)
			(size 0 0)
			(layers "F.Cu" "F.Mask" "F.Paste")
			(net "P3V3_AUX")
		)
		(pad "2" smd circle
			(at 0.40005 0 90)
			(size 0 0)
			(layers "F.Cu" "F.Mask" "F.Paste")
			(net "PWRGD_P3V3_EN_N")
		)
	)
	(footprint ""
		(layer "F.Cu")
		(at 152.97912 -23.284942 -90)
		(property "Reference" "R6014"
			(at 0 0 270)
			(layer "F.SilkS")
			(hide yes)
			(effects
				(font
					(size 1.27 1.27)
				)
			)
		)
		(property "Value" ""
			(at 0 0 270)
			(layer "F.Fab")
			(effects
				(font
					(size 1.27 1.27)
				)
			)
		)
		(duplicate_pad_numbers_are_jumpers no)
		(fp_line
			(start -0.7874 0.4064)
			(end -0.7874 -0.4064)
			(stroke
				(width 0.1524)
				(type default)
			)
			(layer "F.SilkS")
		)
		(fp_line
			(start 0.7874 0.4064)
			(end -0.7874 0.4064)
			(stroke
				(width 0.1524)
				(type default)
			)
			(layer "F.SilkS")
		)
		(fp_line
			(start -0.7874 -0.4064)
			(end 0.7874 -0.4064)
			(stroke
				(width 0.1524)
				(type default)
			)
			(layer "F.SilkS")
		)
		(fp_line
			(start 0.7874 -0.4064)
			(end 0.7874 0.4064)
			(stroke
				(width 0.1524)
				(type default)
			)
			(layer "F.SilkS")
		)
		(fp_line
			(start -0.67945 0.3048)
			(end -0.67945 -0.305054)
			(stroke
				(width 0.1)
				(type default)
			)
			(layer "F.Fab")
		)
		(fp_line
			(start -0.12065 0.3048)
			(end -0.67945 0.3048)
			(stroke
				(width 0.1)
				(type default)
			)
			(layer "F.Fab")
		)
		(fp_line
			(start 0.120396 0.3048)
			(end 0.120396 0.2794)
			(stroke
				(width 0.1)
				(type default)
			)
			(layer "F.Fab")
		)
		(fp_line
			(start 0.67945 0.3048)
			(end 0.120396 0.3048)
			(stroke
				(width 0.1)
				(type default)
			)
			(layer "F.Fab")
		)
		(fp_line
			(start -0.12065 0.2794)
			(end -0.12065 0.3048)
			(stroke
				(width 0.1)
				(type default)
			)
			(layer "F.Fab")
		)
		(fp_line
			(start 0.120396 0.2794)
			(end -0.12065 0.2794)
			(stroke
				(width 0.1)
				(type default)
			)
			(layer "F.Fab")
		)
		(fp_line
			(start -0.12065 -0.2794)
			(end 0.12065 -0.2794)
			(stroke
				(width 0.1)
				(type default)
			)
			(layer "F.Fab")
		)
		(fp_line
			(start 0.12065 -0.2794)
			(end 0.12065 -0.3048)
			(stroke
				(width 0.1)
				(type default)
			)
			(layer "F.Fab")
		)
		(fp_line
			(start 0.12065 -0.3048)
			(end 0.67945 -0.3048)
			(stroke
				(width 0.1)
				(type default)
			)
			(layer "F.Fab")
		)
		(fp_line
			(start 0.67945 -0.3048)
			(end 0.67945 0.3048)
			(stroke
				(width 0.1)
				(type default)
			)
			(layer "F.Fab")
		)
		(fp_line
			(start -0.67945 -0.305054)
			(end -0.12065 -0.305054)
			(stroke
				(width 0.1)
				(type default)
			)
			(layer "F.Fab")
		)
		(fp_line
			(start -0.12065 -0.305054)
			(end -0.12065 -0.2794)
			(stroke
				(width 0.1)
				(type default)
			)
			(layer "F.Fab")
		)
		(pad "1" smd circle
			(at -0.40005 0 270)
			(size 0 0)
			(layers "F.Cu" "F.Mask" "F.Paste")
			(net "SGPIO_SCM_DI_<1>")
		)
		(pad "2" smd circle
			(at 0.40005 0 270)
			(size 0 0)
			(layers "F.Cu" "F.Mask" "F.Paste")
			(net "SGPIO_SCM_DI_R_<1>")
		)
	)
	(footprint ""
		(layer "F.Cu")
		(at 205.232 -129.032 180)
		(property "Reference" "R496"
			(at 0 0 180)
			(layer "F.SilkS")
			(hide yes)
			(effects
				(font
					(size 1.27 1.27)
				)
			)
		)
		(property "Value" ""
			(at 0 0 180)
			(layer "F.Fab")
			(effects
				(font
					(size 1.27 1.27)
				)
			)
		)
		(duplicate_pad_numbers_are_jumpers no)
		(fp_line
			(start 0.7874 0.4064)
			(end -0.7874 0.4064)
			(stroke
				(width 0.1524)
				(type default)
			)
			(layer "F.SilkS")
		)
		(fp_line
			(start 0.7874 -0.4064)
			(end 0.7874 0.4064)
			(stroke
				(width 0.1524)
				(type default)
			)
			(layer "F.SilkS")
		)
		(fp_line
			(start -0.7874 0.4064)
			(end -0.7874 -0.4064)
			(stroke
				(width 0.1524)
				(type default)
			)
			(layer "F.SilkS")
		)
		(fp_line
			(start -0.7874 -0.4064)
			(end 0.7874 -0.4064)
			(stroke
				(width 0.1524)
				(type default)
			)
			(layer "F.SilkS")
		)
		(fp_line
			(start 0.67945 0.3048)
			(end 0.120396 0.3048)
			(stroke
				(width 0.1)
				(type default)
			)
			(layer "F.Fab")
		)
		(fp_line
			(start 0.67945 -0.3048)
			(end 0.67945 0.3048)
			(stroke
				(width 0.1)
				(type default)
			)
			(layer "F.Fab")
		)
		(fp_line
			(start 0.12065 -0.2794)
			(end 0.12065 -0.3048)
			(stroke
				(width 0.1)
				(type default)
			)
			(layer "F.Fab")
		)
		(fp_line
			(start 0.12065 -0.3048)
			(end 0.67945 -0.3048)
			(stroke
				(width 0.1)
				(type default)
			)
			(layer "F.Fab")
		)
		(fp_line
			(start 0.120396 0.3048)
			(end 0.120396 0.2794)
			(stroke
				(width 0.1)
				(type default)
			)
			(layer "F.Fab")
		)
		(fp_line
			(start 0.120396 0.2794)
			(end -0.12065 0.2794)
			(stroke
				(width 0.1)
				(type default)
			)
			(layer "F.Fab")
		)
		(fp_line
			(start -0.12065 0.3048)
			(end -0.67945 0.3048)
			(stroke
				(width 0.1)
				(type default)
			)
			(layer "F.Fab")
		)
		(fp_line
			(start -0.12065 0.2794)
			(end -0.12065 0.3048)
			(stroke
				(width 0.1)
				(type default)
			)
			(layer "F.Fab")
		)
		(fp_line
			(start -0.12065 -0.2794)
			(end 0.12065 -0.2794)
			(stroke
				(width 0.1)
				(type default)
			)
			(layer "F.Fab")
		)
		(fp_line
			(start -0.12065 -0.305054)
			(end -0.12065 -0.2794)
			(stroke
				(width 0.1)
				(type default)
			)
			(layer "F.Fab")
		)
		(fp_line
			(start -0.67945 0.3048)
			(end -0.67945 -0.305054)
			(stroke
				(width 0.1)
				(type default)
			)
			(layer "F.Fab")
		)
		(fp_line
			(start -0.67945 -0.305054)
			(end -0.12065 -0.305054)
			(stroke
				(width 0.1)
				(type default)
			)
			(layer "F.Fab")
		)
		(pad "1" smd circle
			(at -0.40005 0 180)
			(size 0 0)
			(layers "F.Cu" "F.Mask" "F.Paste")
			(net "P3V3_AUX")
		)
		(pad "2" smd circle
			(at 0.40005 0 180)
			(size 0 0)
			(layers "F.Cu" "F.Mask" "F.Paste")
			(net "SW_P3V3_EN")
		)
	)
	(footprint ""
		(layer "F.Cu")
		(at 137.033762 -151.616664 -90)
		(property "Reference" "PR336"
			(at 0 0 270)
			(layer "F.SilkS")
			(hide yes)
			(effects
				(font
					(size 1.27 1.27)
				)
			)
		)
		(property "Value" ""
			(at 0 0 270)
			(layer "F.Fab")
			(effects
				(font
					(size 1.27 1.27)
				)
			)
		)
		(duplicate_pad_numbers_are_jumpers no)
		(fp_line
			(start -0.7874 0.4064)
			(end -0.7874 -0.4064)
			(stroke
				(width 0.1524)
				(type default)
			)
			(layer "F.SilkS")
		)
		(fp_line
			(start 0.7874 0.4064)
			(end -0.7874 0.4064)
			(stroke
				(width 0.1524)
				(type default)
			)
			(layer "F.SilkS")
		)
		(fp_line
			(start -0.7874 -0.4064)
			(end 0.7874 -0.4064)
			(stroke
				(width 0.1524)
				(type default)
			)
			(layer "F.SilkS")
		)
		(fp_line
			(start 0.7874 -0.4064)
			(end 0.7874 0.4064)
			(stroke
				(width 0.1524)
				(type default)
			)
			(layer "F.SilkS")
		)
		(fp_line
			(start -0.67945 0.3048)
			(end -0.67945 -0.305054)
			(stroke
				(width 0.1)
				(type default)
			)
			(layer "F.Fab")
		)
		(fp_line
			(start -0.12065 0.3048)
			(end -0.67945 0.3048)
			(stroke
				(width 0.1)
				(type default)
			)
			(layer "F.Fab")
		)
		(fp_line
			(start 0.120396 0.3048)
			(end 0.120396 0.2794)
			(stroke
				(width 0.1)
				(type default)
			)
			(layer "F.Fab")
		)
		(fp_line
			(start 0.67945 0.3048)
			(end 0.120396 0.3048)
			(stroke
				(width 0.1)
				(type default)
			)
			(layer "F.Fab")
		)
		(fp_line
			(start -0.12065 0.2794)
			(end -0.12065 0.3048)
			(stroke
				(width 0.1)
				(type default)
			)
			(layer "F.Fab")
		)
		(fp_line
			(start 0.120396 0.2794)
			(end -0.12065 0.2794)
			(stroke
				(width 0.1)
				(type default)
			)
			(layer "F.Fab")
		)
		(fp_line
			(start -0.12065 -0.2794)
			(end 0.12065 -0.2794)
			(stroke
				(width 0.1)
				(type default)
			)
			(layer "F.Fab")
		)
		(fp_line
			(start 0.12065 -0.2794)
			(end 0.12065 -0.3048)
			(stroke
				(width 0.1)
				(type default)
			)
			(layer "F.Fab")
		)
		(fp_line
			(start 0.12065 -0.3048)
			(end 0.67945 -0.3048)
			(stroke
				(width 0.1)
				(type default)
			)
			(layer "F.Fab")
		)
		(fp_line
			(start 0.67945 -0.3048)
			(end 0.67945 0.3048)
			(stroke
				(width 0.1)
				(type default)
			)
			(layer "F.Fab")
		)
		(fp_line
			(start -0.67945 -0.305054)
			(end -0.12065 -0.305054)
			(stroke
				(width 0.1)
				(type default)
			)
			(layer "F.Fab")
		)
		(fp_line
			(start -0.12065 -0.305054)
			(end -0.12065 -0.2794)
			(stroke
				(width 0.1)
				(type default)
			)
			(layer "F.Fab")
		)
		(pad "1" smd circle
			(at -0.40005 0 270)
			(size 0 0)
			(layers "F.Cu" "F.Mask" "F.Paste")
			(net "PVDDCR_CPU0_P1_PVCC")
		)
		(pad "2" smd circle
			(at 0.40005 0 270)
			(size 0 0)
			(layers "F.Cu" "F.Mask" "F.Paste")
			(net "P3V3_AUX")
		)
	)
	(footprint ""
		(layer "F.Cu")
		(at 130.49758 -26.99258 -90)
		(property "Reference" "R6192"
			(at 0 0 270)
			(layer "F.SilkS")
			(hide yes)
			(effects
				(font
					(size 1.27 1.27)
				)
			)
		)
		(property "Value" ""
			(at 0 0 270)
			(layer "F.Fab")
			(effects
				(font
					(size 1.27 1.27)
				)
			)
		)
		(duplicate_pad_numbers_are_jumpers no)
		(fp_line
			(start -0.32512 0.175006)
			(end -0.32512 -0.175006)
			(stroke
				(width 0.1)
				(type default)
			)
			(layer "F.Fab")
		)
		(fp_line
			(start 0.32512 0.175006)
			(end -0.32512 0.175006)
			(stroke
				(width 0.1)
				(type default)
			)
			(layer "F.Fab")
		)
		(fp_line
			(start -0.32512 -0.175006)
			(end 0.32512 -0.175006)
			(stroke
				(width 0.1)
				(type default)
			)
			(layer "F.Fab")
		)
		(fp_line
			(start 0.32512 -0.175006)
			(end 0.32512 0.175006)
			(stroke
				(width 0.1)
				(type default)
			)
			(layer "F.Fab")
		)
		(pad "1" smd rect
			(at -0.2667 0 270)
			(size 0.3048 0.381)
			(layers "F.Cu" "F.Mask" "F.Paste")
			(net "USB2_CPU0_P0_DP")
		)
		(pad "2" smd rect
			(at 0.2667 0 90)
			(size 0.3048 0.381)
			(layers "F.Cu" "F.Mask" "F.Paste")
			(net "USB2_CPU0_P0_R2_DP")
		)
	)
	(footprint ""
		(layer "F.Cu")
		(at 30.392878 -17.623536 90)
		(property "Reference" "C689"
			(at 0 0 90)
			(layer "F.SilkS")
			(hide yes)
			(effects
				(font
					(size 1.27 1.27)
				)
			)
		)
		(property "Value" ""
			(at 0 0 90)
			(layer "F.Fab")
			(effects
				(font
					(size 1.27 1.27)
				)
			)
		)
		(duplicate_pad_numbers_are_jumpers no)
		(fp_line
			(start 0.299974 -0.150114)
			(end 0.299974 0.150114)
			(stroke
				(width 0.1)
				(type default)
			)
			(layer "F.Fab")
		)
		(fp_line
			(start -0.299974 -0.150114)
			(end 0.299974 -0.150114)
			(stroke
				(width 0.1)
				(type default)
			)
			(layer "F.Fab")
		)
		(fp_line
			(start 0.299974 0.150114)
			(end -0.299974 0.150114)
			(stroke
				(width 0.1)
				(type default)
			)
			(layer "F.Fab")
		)
		(fp_line
			(start -0.299974 0.150114)
			(end -0.299974 -0.150114)
			(stroke
				(width 0.1)
				(type default)
			)
			(layer "F.Fab")
		)
		(pad "1" smd rect
			(at -0.2667 0 90)
			(size 0.3048 0.381)
			(layers "F.Cu" "F.Mask" "F.Paste")
			(net "P5E_CPU1_G1_TX_C_DP<10>")
		)
		(pad "2" smd rect
			(at 0.2667 0 90)
			(size 0.3048 0.381)
			(layers "F.Cu" "F.Mask" "F.Paste")
			(net "P5E_CPU1_G1_TX_DP<10>")
		)
	)
	(footprint ""
		(layer "F.Cu")
		(at 388.649972 -178.0921 -90)
		(property "Reference" "PR349"
			(at 0 0 270)
			(layer "F.SilkS")
			(hide yes)
			(effects
				(font
					(size 1.27 1.27)
				)
			)
		)
		(property "Value" ""
			(at 0 0 270)
			(layer "F.Fab")
			(effects
				(font
					(size 1.27 1.27)
				)
			)
		)
		(duplicate_pad_numbers_are_jumpers no)
		(fp_line
			(start -0.7874 0.4064)
			(end -0.7874 -0.4064)
			(stroke
				(width 0.1524)
				(type default)
			)
			(layer "F.SilkS")
		)
		(fp_line
			(start 0.7874 0.4064)
			(end -0.7874 0.4064)
			(stroke
				(width 0.1524)
				(type default)
			)
			(layer "F.SilkS")
		)
		(fp_line
			(start -0.7874 -0.4064)
			(end 0.7874 -0.4064)
			(stroke
				(width 0.1524)
				(type default)
			)
			(layer "F.SilkS")
		)
		(fp_line
			(start 0.7874 -0.4064)
			(end 0.7874 0.4064)
			(stroke
				(width 0.1524)
				(type default)
			)
			(layer "F.SilkS")
		)
		(fp_line
			(start -0.67945 0.3048)
			(end -0.67945 -0.305054)
			(stroke
				(width 0.1)
				(type default)
			)
			(layer "F.Fab")
		)
		(fp_line
			(start -0.12065 0.3048)
			(end -0.67945 0.3048)
			(stroke
				(width 0.1)
				(type default)
			)
			(layer "F.Fab")
		)
		(fp_line
			(start 0.120396 0.3048)
			(end 0.120396 0.2794)
			(stroke
				(width 0.1)
				(type default)
			)
			(layer "F.Fab")
		)
		(fp_line
			(start 0.67945 0.3048)
			(end 0.120396 0.3048)
			(stroke
				(width 0.1)
				(type default)
			)
			(layer "F.Fab")
		)
		(fp_line
			(start -0.12065 0.2794)
			(end -0.12065 0.3048)
			(stroke
				(width 0.1)
				(type default)
			)
			(layer "F.Fab")
		)
		(fp_line
			(start 0.120396 0.2794)
			(end -0.12065 0.2794)
			(stroke
				(width 0.1)
				(type default)
			)
			(layer "F.Fab")
		)
		(fp_line
			(start -0.12065 -0.2794)
			(end 0.12065 -0.2794)
			(stroke
				(width 0.1)
				(type default)
			)
			(layer "F.Fab")
		)
		(fp_line
			(start 0.12065 -0.2794)
			(end 0.12065 -0.3048)
			(stroke
				(width 0.1)
				(type default)
			)
			(layer "F.Fab")
		)
		(fp_line
			(start 0.12065 -0.3048)
			(end 0.67945 -0.3048)
			(stroke
				(width 0.1)
				(type default)
			)
			(layer "F.Fab")
		)
		(fp_line
			(start 0.67945 -0.3048)
			(end 0.67945 0.3048)
			(stroke
				(width 0.1)
				(type default)
			)
			(layer "F.Fab")
		)
		(fp_line
			(start -0.67945 -0.305054)
			(end -0.12065 -0.305054)
			(stroke
				(width 0.1)
				(type default)
			)
			(layer "F.Fab")
		)
		(fp_line
			(start -0.12065 -0.305054)
			(end -0.12065 -0.2794)
			(stroke
				(width 0.1)
				(type default)
			)
			(layer "F.Fab")
		)
		(pad "1" smd circle
			(at -0.40005 0 270)
			(size 0 0)
			(layers "F.Cu" "F.Mask" "F.Paste")
			(net "SW_PVDDCR_CPU0_P0_BOOT4")
		)
		(pad "2" smd circle
			(at 0.40005 0 270)
			(size 0 0)
			(layers "F.Cu" "F.Mask" "F.Paste")
			(net "SW_PVDDCR_CPU0_P0_BOOT4_RC")
		)
	)
	(footprint ""
		(layer "F.Cu")
		(at 297.995594 -393.96416)
		(property "Reference" "R978"
			(at 0 0 0)
			(layer "F.SilkS")
			(hide yes)
			(effects
				(font
					(size 1.27 1.27)
				)
			)
		)
		(property "Value" ""
			(at 0 0 0)
			(layer "F.Fab")
			(effects
				(font
					(size 1.27 1.27)
				)
			)
		)
		(duplicate_pad_numbers_are_jumpers no)
		(fp_line
			(start -0.32512 -0.175006)
			(end 0.32512 -0.175006)
			(stroke
				(width 0.1)
				(type default)
			)
			(layer "F.Fab")
		)
		(fp_line
			(start -0.32512 0.175006)
			(end -0.32512 -0.175006)
			(stroke
				(width 0.1)
				(type default)
			)
			(layer "F.Fab")
		)
		(fp_line
			(start 0.32512 -0.175006)
			(end 0.32512 0.175006)
			(stroke
				(width 0.1)
				(type default)
			)
			(layer "F.Fab")
		)
		(fp_line
			(start 0.32512 0.175006)
			(end -0.32512 0.175006)
			(stroke
				(width 0.1)
				(type default)
			)
			(layer "F.Fab")
		)
		(pad "1" smd rect
			(at -0.2667 0)
			(size 0.3048 0.381)
			(layers "F.Cu" "F.Mask" "F.Paste")
			(net "P1V8_CPU0_RT_1D")
		)
		(pad "2" smd rect
			(at 0.2667 0 180)
			(size 0.3048 0.381)
			(layers "F.Cu" "F.Mask" "F.Paste")
			(net "GPIO2_RT_CPU0_P0")
		)
	)
	(footprint ""
		(layer "F.Cu")
		(at 278.006556 -438.001664 90)
		(property "Reference" "R4552"
			(at 0 0 90)
			(layer "F.SilkS")
			(hide yes)
			(effects
				(font
					(size 1.27 1.27)
				)
			)
		)
		(property "Value" ""
			(at 0 0 90)
			(layer "F.Fab")
			(effects
				(font
					(size 1.27 1.27)
				)
			)
		)
		(duplicate_pad_numbers_are_jumpers no)
		(fp_line
			(start 0.7874 -0.4064)
			(end 0.7874 0.4064)
			(stroke
				(width 0.1524)
				(type default)
			)
			(layer "F.SilkS")
		)
		(fp_line
			(start -0.7874 -0.4064)
			(end 0.7874 -0.4064)
			(stroke
				(width 0.1524)
				(type default)
			)
			(layer "F.SilkS")
		)
		(fp_line
			(start 0.7874 0.4064)
			(end -0.7874 0.4064)
			(stroke
				(width 0.1524)
				(type default)
			)
			(layer "F.SilkS")
		)
		(fp_line
			(start -0.7874 0.4064)
			(end -0.7874 -0.4064)
			(stroke
				(width 0.1524)
				(type default)
			)
			(layer "F.SilkS")
		)
		(fp_line
			(start -0.12065 -0.305054)
			(end -0.12065 -0.2794)
			(stroke
				(width 0.1)
				(type default)
			)
			(layer "F.Fab")
		)
		(fp_line
			(start -0.67945 -0.305054)
			(end -0.12065 -0.305054)
			(stroke
				(width 0.1)
				(type default)
			)
			(layer "F.Fab")
		)
		(fp_line
			(start 0.67945 -0.3048)
			(end 0.67945 0.3048)
			(stroke
				(width 0.1)
				(type default)
			)
			(layer "F.Fab")
		)
		(fp_line
			(start 0.12065 -0.3048)
			(end 0.67945 -0.3048)
			(stroke
				(width 0.1)
				(type default)
			)
			(layer "F.Fab")
		)
		(fp_line
			(start 0.12065 -0.2794)
			(end 0.12065 -0.3048)
			(stroke
				(width 0.1)
				(type default)
			)
			(layer "F.Fab")
		)
		(fp_line
			(start -0.12065 -0.2794)
			(end 0.12065 -0.2794)
			(stroke
				(width 0.1)
				(type default)
			)
			(layer "F.Fab")
		)
		(fp_line
			(start 0.120396 0.2794)
			(end -0.12065 0.2794)
			(stroke
				(width 0.1)
				(type default)
			)
			(layer "F.Fab")
		)
		(fp_line
			(start -0.12065 0.2794)
			(end -0.12065 0.3048)
			(stroke
				(width 0.1)
				(type default)
			)
			(layer "F.Fab")
		)
		(fp_line
			(start 0.67945 0.3048)
			(end 0.120396 0.3048)
			(stroke
				(width 0.1)
				(type default)
			)
			(layer "F.Fab")
		)
		(fp_line
			(start 0.120396 0.3048)
			(end 0.120396 0.2794)
			(stroke
				(width 0.1)
				(type default)
			)
			(layer "F.Fab")
		)
		(fp_line
			(start -0.12065 0.3048)
			(end -0.67945 0.3048)
			(stroke
				(width 0.1)
				(type default)
			)
			(layer "F.Fab")
		)
		(fp_line
			(start -0.67945 0.3048)
			(end -0.67945 -0.305054)
			(stroke
				(width 0.1)
				(type default)
			)
			(layer "F.Fab")
		)
		(pad "1" smd circle
			(at -0.40005 0 90)
			(size 0 0)
			(layers "F.Cu" "F.Mask" "F.Paste")
			(net "HPDB_HSC_PWRGD")
		)
		(pad "2" smd circle
			(at 0.40005 0 90)
			(size 0 0)
			(layers "F.Cu" "F.Mask" "F.Paste")
			(net "GND")
		)
	)
	(footprint ""
		(layer "F.Cu")
		(at 333.65948 -16.178276 90)
		(property "Reference" "D8"
			(at -3.48869 -0.212344 90)
			(unlocked yes)
			(layer "F.SilkS")
			(effects
				(font
					(size 0.7874 0.5842)
					(thickness 0.1524)
				)
				(justify left)
			)
		)
		(property "Value" ""
			(at 0 0 90)
			(layer "F.Fab")
			(effects
				(font
					(size 1.27 1.27)
				)
			)
		)
		(duplicate_pad_numbers_are_jumpers no)
		(fp_line
			(start 1.778 -0.5588)
			(end 1.3208 -0.5588)
			(stroke
				(width 0.1524)
				(type default)
			)
			(layer "F.SilkS")
		)
		(fp_line
			(start 1.778 -0.5588)
			(end 1.778 0.5588)
			(stroke
				(width 0.1524)
				(type default)
			)
			(layer "F.SilkS")
		)
		(fp_line
			(start 1.4732 -0.5588)
			(end 1.4732 0.5588)
			(stroke
				(width 0.1524)
				(type default)
			)
			(layer "F.SilkS")
		)
		(fp_line
			(start 1.3208 -0.5588)
			(end 1.3208 0.5588)
			(stroke
				(width 0.1524)
				(type default)
			)
			(layer "F.SilkS")
		)
		(fp_line
			(start -1.3208 -0.5588)
			(end 1.3208 -0.5588)
			(stroke
				(width 0.1524)
				(type default)
			)
			(layer "F.SilkS")
		)
		(fp_line
			(start 1.778 0.5588)
			(end 1.3208 0.5588)
			(stroke
				(width 0.1524)
				(type default)
			)
			(layer "F.SilkS")
		)
		(fp_line
			(start 1.6256 0.5588)
			(end 1.6256 -0.5588)
			(stroke
				(width 0.1524)
				(type default)
			)
			(layer "F.SilkS")
		)
		(fp_line
			(start 1.3208 0.5588)
			(end -1.3208 0.5588)
			(stroke
				(width 0.1524)
				(type default)
			)
			(layer "F.SilkS")
		)
		(fp_line
			(start -1.3208 0.5588)
			(end -1.3208 -0.5588)
			(stroke
				(width 0.1524)
				(type default)
			)
			(layer "F.SilkS")
		)
		(fp_line
			(start 0.899922 -0.40005)
			(end 0.899922 0.40005)
			(stroke
				(width 0.1)
				(type default)
			)
			(layer "F.Fab")
		)
		(fp_line
			(start -0.899922 -0.40005)
			(end 0.899922 -0.40005)
			(stroke
				(width 0.1)
				(type default)
			)
			(layer "F.Fab")
		)
		(fp_line
			(start 0.899922 0.40005)
			(end -0.899922 0.40005)
			(stroke
				(width 0.1)
				(type default)
			)
			(layer "F.Fab")
		)
		(fp_line
			(start -0.899922 0.40005)
			(end -0.899922 -0.40005)
			(stroke
				(width 0.1)
				(type default)
			)
			(layer "F.Fab")
		)
		(fp_text user "-"
			(at 1.651 -0.86233 90)
			(unlocked yes)
			(layer "F.SilkS")
			(effects
				(font
					(size 1.905 1.4224)
					(thickness 0.1524)
				)
				(justify left)
			)
		)
		(fp_text user "+"
			(at -2.466086 0.324104 90)
			(unlocked yes)
			(layer "F.SilkS")
			(effects
				(font
					(size 1.905 1.4224)
					(thickness 0.1524)
				)
				(justify left)
			)
		)
		(fp_text user "-"
			(at 1.651 -0.22225 90)
			(unlocked yes)
			(layer "F.Fab")
			(effects
				(font
					(size 1.905 1.4224)
					(thickness 0.1524)
				)
				(justify left)
			)
		)
		(fp_text user "+"
			(at -2.6162 -0.22225 90)
			(unlocked yes)
			(layer "F.Fab")
			(effects
				(font
					(size 1.905 1.4224)
					(thickness 0.1524)
				)
				(justify left)
			)
		)
		(pad "A" smd rect
			(at -0.750062 0 90)
			(size 0.8128 0.8128)
			(layers "F.Cu" "F.Mask" "F.Paste")
			(net "BMC_FPGA_LED1_R_N")
		)
		(pad "C" smd rect
			(at 0.750062 0 90)
			(size 0.8128 0.8128)
			(layers "F.Cu" "F.Mask" "F.Paste")
			(net "BMC_FPGA_LED1_N")
		)
	)
	(footprint ""
		(layer "F.Cu")
		(at 215.4301 -398.940782 180)
		(property "Reference" "PC2350"
			(at 0 0 180)
			(layer "F.SilkS")
			(hide yes)
			(effects
				(font
					(size 1.27 1.27)
				)
			)
		)
		(property "Value" ""
			(at 0 0 180)
			(layer "F.Fab")
			(effects
				(font
					(size 1.27 1.27)
				)
			)
		)
		(duplicate_pad_numbers_are_jumpers no)
		(fp_line
			(start 0.7874 0.4064)
			(end -0.7874 0.4064)
			(stroke
				(width 0.1524)
				(type default)
			)
			(layer "F.SilkS")
		)
		(fp_line
			(start 0.7874 -0.4064)
			(end 0.7874 0.4064)
			(stroke
				(width 0.1524)
				(type default)
			)
			(layer "F.SilkS")
		)
		(fp_line
			(start -0.7874 0.4064)
			(end -0.7874 -0.4064)
			(stroke
				(width 0.1524)
				(type default)
			)
			(layer "F.SilkS")
		)
		(fp_line
			(start -0.7874 -0.4064)
			(end 0.7874 -0.4064)
			(stroke
				(width 0.1524)
				(type default)
			)
			(layer "F.SilkS")
		)
		(fp_line
			(start 0.67945 0.3048)
			(end 0.120396 0.3048)
			(stroke
				(width 0.1)
				(type default)
			)
			(layer "F.Fab")
		)
		(fp_line
			(start 0.67945 -0.3048)
			(end 0.67945 0.3048)
			(stroke
				(width 0.1)
				(type default)
			)
			(layer "F.Fab")
		)
		(fp_line
			(start 0.12065 -0.2794)
			(end 0.12065 -0.3048)
			(stroke
				(width 0.1)
				(type default)
			)
			(layer "F.Fab")
		)
		(fp_line
			(start 0.12065 -0.3048)
			(end 0.67945 -0.3048)
			(stroke
				(width 0.1)
				(type default)
			)
			(layer "F.Fab")
		)
		(fp_line
			(start 0.120396 0.3048)
			(end 0.120396 0.2794)
			(stroke
				(width 0.1)
				(type default)
			)
			(layer "F.Fab")
		)
		(fp_line
			(start 0.120396 0.2794)
			(end -0.12065 0.2794)
			(stroke
				(width 0.1)
				(type default)
			)
			(layer "F.Fab")
		)
		(fp_line
			(start -0.12065 0.3048)
			(end -0.67945 0.3048)
			(stroke
				(width 0.1)
				(type default)
			)
			(layer "F.Fab")
		)
		(fp_line
			(start -0.12065 0.2794)
			(end -0.12065 0.3048)
			(stroke
				(width 0.1)
				(type default)
			)
			(layer "F.Fab")
		)
		(fp_line
			(start -0.12065 -0.2794)
			(end 0.12065 -0.2794)
			(stroke
				(width 0.1)
				(type default)
			)
			(layer "F.Fab")
		)
		(fp_line
			(start -0.12065 -0.305054)
			(end -0.12065 -0.2794)
			(stroke
				(width 0.1)
				(type default)
			)
			(layer "F.Fab")
		)
		(fp_line
			(start -0.67945 0.3048)
			(end -0.67945 -0.305054)
			(stroke
				(width 0.1)
				(type default)
			)
			(layer "F.Fab")
		)
		(fp_line
			(start -0.67945 -0.305054)
			(end -0.12065 -0.305054)
			(stroke
				(width 0.1)
				(type default)
			)
			(layer "F.Fab")
		)
		(pad "1" smd circle
			(at -0.40005 0 180)
			(size 0 0)
			(layers "F.Cu" "F.Mask" "F.Paste")
			(net "HSC_OCREF")
		)
		(pad "2" smd circle
			(at 0.40005 0 180)
			(size 0 0)
			(layers "F.Cu" "F.Mask" "F.Paste")
			(net "AGND_HSC")
		)
	)
	(footprint ""
		(layer "F.Cu")
		(at 315.771022 -32.572706 180)
		(property "Reference" "C59"
			(at 0 0 180)
			(layer "F.SilkS")
			(hide yes)
			(effects
				(font
					(size 1.27 1.27)
				)
			)
		)
		(property "Value" ""
			(at 0 0 180)
			(layer "F.Fab")
			(effects
				(font
					(size 1.27 1.27)
				)
			)
		)
		(duplicate_pad_numbers_are_jumpers no)
		(fp_line
			(start 0.7874 0.4064)
			(end -0.7874 0.4064)
			(stroke
				(width 0.1524)
				(type default)
			)
			(layer "F.SilkS")
		)
		(fp_line
			(start 0.7874 -0.4064)
			(end 0.7874 0.4064)
			(stroke
				(width 0.1524)
				(type default)
			)
			(layer "F.SilkS")
		)
		(fp_line
			(start -0.7874 0.4064)
			(end -0.7874 -0.4064)
			(stroke
				(width 0.1524)
				(type default)
			)
			(layer "F.SilkS")
		)
		(fp_line
			(start -0.7874 -0.4064)
			(end 0.7874 -0.4064)
			(stroke
				(width 0.1524)
				(type default)
			)
			(layer "F.SilkS")
		)
		(fp_line
			(start 0.67945 0.3048)
			(end 0.120396 0.3048)
			(stroke
				(width 0.1)
				(type default)
			)
			(layer "F.Fab")
		)
		(fp_line
			(start 0.67945 -0.3048)
			(end 0.67945 0.3048)
			(stroke
				(width 0.1)
				(type default)
			)
			(layer "F.Fab")
		)
		(fp_line
			(start 0.12065 -0.2794)
			(end 0.12065 -0.3048)
			(stroke
				(width 0.1)
				(type default)
			)
			(layer "F.Fab")
		)
		(fp_line
			(start 0.12065 -0.3048)
			(end 0.67945 -0.3048)
			(stroke
				(width 0.1)
				(type default)
			)
			(layer "F.Fab")
		)
		(fp_line
			(start 0.120396 0.3048)
			(end 0.120396 0.2794)
			(stroke
				(width 0.1)
				(type default)
			)
			(layer "F.Fab")
		)
		(fp_line
			(start 0.120396 0.2794)
			(end -0.12065 0.2794)
			(stroke
				(width 0.1)
				(type default)
			)
			(layer "F.Fab")
		)
		(fp_line
			(start -0.12065 0.3048)
			(end -0.67945 0.3048)
			(stroke
				(width 0.1)
				(type default)
			)
			(layer "F.Fab")
		)
		(fp_line
			(start -0.12065 0.2794)
			(end -0.12065 0.3048)
			(stroke
				(width 0.1)
				(type default)
			)
			(layer "F.Fab")
		)
		(fp_line
			(start -0.12065 -0.2794)
			(end 0.12065 -0.2794)
			(stroke
				(width 0.1)
				(type default)
			)
			(layer "F.Fab")
		)
		(fp_line
			(start -0.12065 -0.305054)
			(end -0.12065 -0.2794)
			(stroke
				(width 0.1)
				(type default)
			)
			(layer "F.Fab")
		)
		(fp_line
			(start -0.67945 0.3048)
			(end -0.67945 -0.305054)
			(stroke
				(width 0.1)
				(type default)
			)
			(layer "F.Fab")
		)
		(fp_line
			(start -0.67945 -0.305054)
			(end -0.12065 -0.305054)
			(stroke
				(width 0.1)
				(type default)
			)
			(layer "F.Fab")
		)
		(pad "1" smd circle
			(at -0.40005 0 180)
			(size 0 0)
			(layers "F.Cu" "F.Mask" "F.Paste")
			(net "P12V_OCP_V3_2_ISENSE_MAM")
		)
		(pad "2" smd circle
			(at 0.40005 0 180)
			(size 0 0)
			(layers "F.Cu" "F.Mask" "F.Paste")
			(net "GND")
		)
	)
	(footprint ""
		(layer "F.Cu")
		(at 401.501356 -178.905408 -90)
		(property "Reference" "PR502"
			(at 0 0 270)
			(layer "F.SilkS")
			(hide yes)
			(effects
				(font
					(size 1.27 1.27)
				)
			)
		)
		(property "Value" ""
			(at 0 0 270)
			(layer "F.Fab")
			(effects
				(font
					(size 1.27 1.27)
				)
			)
		)
		(duplicate_pad_numbers_are_jumpers no)
		(fp_line
			(start -0.7874 0.4064)
			(end -0.7874 -0.4064)
			(stroke
				(width 0.1524)
				(type default)
			)
			(layer "F.SilkS")
		)
		(fp_line
			(start 0.7874 0.4064)
			(end -0.7874 0.4064)
			(stroke
				(width 0.1524)
				(type default)
			)
			(layer "F.SilkS")
		)
		(fp_line
			(start -0.7874 -0.4064)
			(end 0.7874 -0.4064)
			(stroke
				(width 0.1524)
				(type default)
			)
			(layer "F.SilkS")
		)
		(fp_line
			(start 0.7874 -0.4064)
			(end 0.7874 0.4064)
			(stroke
				(width 0.1524)
				(type default)
			)
			(layer "F.SilkS")
		)
		(fp_line
			(start -0.67945 0.3048)
			(end -0.67945 -0.305054)
			(stroke
				(width 0.1)
				(type default)
			)
			(layer "F.Fab")
		)
		(fp_line
			(start -0.12065 0.3048)
			(end -0.67945 0.3048)
			(stroke
				(width 0.1)
				(type default)
			)
			(layer "F.Fab")
		)
		(fp_line
			(start 0.120396 0.3048)
			(end 0.120396 0.2794)
			(stroke
				(width 0.1)
				(type default)
			)
			(layer "F.Fab")
		)
		(fp_line
			(start 0.67945 0.3048)
			(end 0.120396 0.3048)
			(stroke
				(width 0.1)
				(type default)
			)
			(layer "F.Fab")
		)
		(fp_line
			(start -0.12065 0.2794)
			(end -0.12065 0.3048)
			(stroke
				(width 0.1)
				(type default)
			)
			(layer "F.Fab")
		)
		(fp_line
			(start 0.120396 0.2794)
			(end -0.12065 0.2794)
			(stroke
				(width 0.1)
				(type default)
			)
			(layer "F.Fab")
		)
		(fp_line
			(start -0.12065 -0.2794)
			(end 0.12065 -0.2794)
			(stroke
				(width 0.1)
				(type default)
			)
			(layer "F.Fab")
		)
		(fp_line
			(start 0.12065 -0.2794)
			(end 0.12065 -0.3048)
			(stroke
				(width 0.1)
				(type default)
			)
			(layer "F.Fab")
		)
		(fp_line
			(start 0.12065 -0.3048)
			(end 0.67945 -0.3048)
			(stroke
				(width 0.1)
				(type default)
			)
			(layer "F.Fab")
		)
		(fp_line
			(start 0.67945 -0.3048)
			(end 0.67945 0.3048)
			(stroke
				(width 0.1)
				(type default)
			)
			(layer "F.Fab")
		)
		(fp_line
			(start -0.67945 -0.305054)
			(end -0.12065 -0.305054)
			(stroke
				(width 0.1)
				(type default)
			)
			(layer "F.Fab")
		)
		(fp_line
			(start -0.12065 -0.305054)
			(end -0.12065 -0.2794)
			(stroke
				(width 0.1)
				(type default)
			)
			(layer "F.Fab")
		)
		(pad "1" smd circle
			(at -0.40005 0 270)
			(size 0 0)
			(layers "F.Cu" "F.Mask" "F.Paste")
			(net "SW_PVDDCR_SOC_P0_SW1_RC")
		)
		(pad "2" smd circle
			(at 0.40005 0 270)
			(size 0 0)
			(layers "F.Cu" "F.Mask" "F.Paste")
			(net "GND")
		)
	)
	(footprint ""
		(layer "F.Cu")
		(at 191.135 -133.568948 90)
		(property "Reference" "R588"
			(at 0 0 90)
			(layer "F.SilkS")
			(hide yes)
			(effects
				(font
					(size 1.27 1.27)
				)
			)
		)
		(property "Value" ""
			(at 0 0 90)
			(layer "F.Fab")
			(effects
				(font
					(size 1.27 1.27)
				)
			)
		)
		(duplicate_pad_numbers_are_jumpers no)
		(fp_line
			(start 0.7874 -0.4064)
			(end 0.7874 0.4064)
			(stroke
				(width 0.1524)
				(type default)
			)
			(layer "F.SilkS")
		)
		(fp_line
			(start -0.7874 -0.4064)
			(end 0.7874 -0.4064)
			(stroke
				(width 0.1524)
				(type default)
			)
			(layer "F.SilkS")
		)
		(fp_line
			(start 0.7874 0.4064)
			(end -0.7874 0.4064)
			(stroke
				(width 0.1524)
				(type default)
			)
			(layer "F.SilkS")
		)
		(fp_line
			(start -0.7874 0.4064)
			(end -0.7874 -0.4064)
			(stroke
				(width 0.1524)
				(type default)
			)
			(layer "F.SilkS")
		)
		(fp_line
			(start -0.12065 -0.305054)
			(end -0.12065 -0.2794)
			(stroke
				(width 0.1)
				(type default)
			)
			(layer "F.Fab")
		)
		(fp_line
			(start -0.67945 -0.305054)
			(end -0.12065 -0.305054)
			(stroke
				(width 0.1)
				(type default)
			)
			(layer "F.Fab")
		)
		(fp_line
			(start 0.67945 -0.3048)
			(end 0.67945 0.3048)
			(stroke
				(width 0.1)
				(type default)
			)
			(layer "F.Fab")
		)
		(fp_line
			(start 0.12065 -0.3048)
			(end 0.67945 -0.3048)
			(stroke
				(width 0.1)
				(type default)
			)
			(layer "F.Fab")
		)
		(fp_line
			(start 0.12065 -0.2794)
			(end 0.12065 -0.3048)
			(stroke
				(width 0.1)
				(type default)
			)
			(layer "F.Fab")
		)
		(fp_line
			(start -0.12065 -0.2794)
			(end 0.12065 -0.2794)
			(stroke
				(width 0.1)
				(type default)
			)
			(layer "F.Fab")
		)
		(fp_line
			(start 0.120396 0.2794)
			(end -0.12065 0.2794)
			(stroke
				(width 0.1)
				(type default)
			)
			(layer "F.Fab")
		)
		(fp_line
			(start -0.12065 0.2794)
			(end -0.12065 0.3048)
			(stroke
				(width 0.1)
				(type default)
			)
			(layer "F.Fab")
		)
		(fp_line
			(start 0.67945 0.3048)
			(end 0.120396 0.3048)
			(stroke
				(width 0.1)
				(type default)
			)
			(layer "F.Fab")
		)
		(fp_line
			(start 0.120396 0.3048)
			(end 0.120396 0.2794)
			(stroke
				(width 0.1)
				(type default)
			)
			(layer "F.Fab")
		)
		(fp_line
			(start -0.12065 0.3048)
			(end -0.67945 0.3048)
			(stroke
				(width 0.1)
				(type default)
			)
			(layer "F.Fab")
		)
		(fp_line
			(start -0.67945 0.3048)
			(end -0.67945 -0.305054)
			(stroke
				(width 0.1)
				(type default)
			)
			(layer "F.Fab")
		)
		(pad "1" smd circle
			(at -0.40005 0 90)
			(size 0 0)
			(layers "F.Cu" "F.Mask" "F.Paste")
			(net "SCM_USB_OC_R_N")
		)
		(pad "2" smd circle
			(at 0.40005 0 90)
			(size 0 0)
			(layers "F.Cu" "F.Mask" "F.Paste")
			(net "SCM_USB_OC_N")
		)
	)
	(footprint ""
		(layer "F.Cu")
		(at 191.246506 -351.320862)
		(property "Reference" "PU45"
			(at -3.032506 -7.935468 0)
			(unlocked yes)
			(layer "F.SilkS")
			(effects
				(font
					(size 0.7874 0.5842)
					(thickness 0.1524)
				)
				(justify left)
			)
		)
		(property "Value" ""
			(at 0 0 0)
			(layer "F.Fab")
			(effects
				(font
					(size 1.27 1.27)
				)
			)
		)
		(duplicate_pad_numbers_are_jumpers no)
		(fp_line
			(start -2.500122 -2.999994)
			(end -2.24409 -2.999994)
			(stroke
				(width 0.1524)
				(type default)
			)
			(layer "F.SilkS")
		)
		(fp_line
			(start -2.500122 -2.529078)
			(end -2.500122 -2.999994)
			(stroke
				(width 0.1524)
				(type default)
			)
			(layer "F.SilkS")
		)
		(fp_line
			(start -2.500122 0.6604)
			(end -2.500122 0.229108)
			(stroke
				(width 0.1524)
				(type default)
			)
			(layer "F.SilkS")
		)
		(fp_line
			(start -2.500122 2.999994)
			(end -2.500122 2.339594)
			(stroke
				(width 0.1524)
				(type default)
			)
			(layer "F.SilkS")
		)
		(fp_line
			(start -2.2987 2.999994)
			(end -2.500122 2.999994)
			(stroke
				(width 0.1524)
				(type default)
			)
			(layer "F.SilkS")
		)
		(fp_line
			(start 2.31394 -2.999994)
			(end 2.500122 -2.999994)
			(stroke
				(width 0.1524)
				(type default)
			)
			(layer "F.SilkS")
		)
		(fp_line
			(start 2.500122 -2.999994)
			(end 2.500122 -2.44348)
			(stroke
				(width 0.1524)
				(type default)
			)
			(layer "F.SilkS")
		)
		(fp_line
			(start 2.500122 2.339594)
			(end 2.500122 2.999994)
			(stroke
				(width 0.1524)
				(type default)
			)
			(layer "F.SilkS")
		)
		(fp_line
			(start 2.500122 2.999994)
			(end 2.2987 2.999994)
			(stroke
				(width 0.1524)
				(type default)
			)
			(layer "F.SilkS")
		)
		(fp_poly
			(pts
				(xy -2.768854 -2.421382) (xy -3.442462 -2.645918) (xy -2.99339 -3.09499)
			)
			(stroke
				(width 0)
				(type default)
			)
			(fill yes)
			(layer "F.SilkS")
		)
		(fp_line
			(start -2.500122 -2.999994)
			(end 2.500122 -2.999994)
			(stroke
				(width 0.1)
				(type default)
			)
			(layer "F.Fab")
		)
		(fp_line
			(start -2.500122 2.999994)
			(end -2.500122 -2.999994)
			(stroke
				(width 0.1)
				(type default)
			)
			(layer "F.Fab")
		)
		(fp_line
			(start 2.500122 -2.999994)
			(end 2.500122 2.999994)
			(stroke
				(width 0.1)
				(type default)
			)
			(layer "F.Fab")
		)
		(fp_line
			(start 2.500122 2.999994)
			(end -2.500122 2.999994)
			(stroke
				(width 0.1)
				(type default)
			)
			(layer "F.Fab")
		)
		(fp_poly
			(pts
				(xy -4.218432 -2.783078) (xy -4.218432 -1.767078) (xy -3.202432 -2.275078)
			)
			(stroke
				(width 0)
				(type default)
			)
			(fill yes)
			(layer "F.Fab")
		)
		(pad "1" smd rect
			(at -2.400046 -2.275078 90)
			(size 0.2286 0.6096)
			(layers "F.Cu" "F.Mask" "F.Paste")
			(net "PVDD11_S3_P1_VOS2")
		)
		(pad "2" smd rect
			(at -2.400046 -1.82499 90)
			(size 0.2286 0.6096)
			(layers "F.Cu" "F.Mask" "F.Paste")
			(net "GND")
		)
		(pad "3" smd rect
			(at -2.400046 -1.374902 90)
			(size 0.2286 0.6096)
			(layers "F.Cu" "F.Mask" "F.Paste")
			(net "PVDD11_S3_P1_VCC2")
		)
		(pad "4" smd rect
			(at -2.400046 -0.925068 90)
			(size 0.2286 0.6096)
			(layers "F.Cu" "F.Mask" "F.Paste")
			(net "PVDD11_S3_P1_PVCC")
		)
		(pad "5" smd rect
			(at -2.400046 -0.47498 90)
			(size 0.2286 0.6096)
			(layers "F.Cu" "F.Mask" "F.Paste")
			(net "GND")
		)
		(pad "6" smd rect
			(at -2.400046 -0.024892 90)
			(size 0.2286 0.6096)
			(layers "F.Cu" "F.Mask" "F.Paste")
			(net "NC_PVDD11_S3_P1_GL1_2")
		)
		(pad "7_9-20_24" smd circle
			(at 0 1.150112 90)
			(size 0 0)
			(layers "F.Cu" "F.Mask" "F.Paste")
			(net "GND")
		)
		(pad "10_19" smd rect
			(at 0 2.899918 90)
			(size 0.6096 4.318)
			(layers "F.Cu" "F.Mask" "F.Paste")
			(net "SW_PVDD11_S3_P1_SW2")
		)
		(pad "25_29" smd rect
			(at 1.549908 -1.279906 270)
			(size 2.0574 2.3114)
			(layers "F.Cu" "F.Mask" "F.Paste")
			(net "SW_P12V_AUX_PVDD11_S3_P1_FLT")
		)
		(pad "30" smd rect
			(at 2.05994 -2.899918)
			(size 0.2286 0.6096)
			(layers "F.Cu" "F.Mask" "F.Paste")
			(net "SW_P12V_AUX_PVDD11_S3_P1_FLT")
		)
		(pad "31" smd rect
			(at 1.610106 -2.899918)
			(size 0.2286 0.6096)
			(layers "F.Cu" "F.Mask" "F.Paste")
			(net "NC_PVDD11_S3_P1_DNC2")
		)
		(pad "32" smd rect
			(at 1.160018 -2.899918)
			(size 0.2286 0.6096)
			(layers "F.Cu" "F.Mask" "F.Paste")
			(net "SW_PVDD11_S3_P1_PH2")
		)
		(pad "33" smd rect
			(at 0.70993 -2.899918)
			(size 0.2286 0.6096)
			(layers "F.Cu" "F.Mask" "F.Paste")
			(net "SW_PVDD11_S3_P1_BOOT2")
		)
		(pad "34" smd rect
			(at 0.260096 -2.899918)
			(size 0.2286 0.6096)
			(layers "F.Cu" "F.Mask" "F.Paste")
			(net "PVDD11_S3_P1_PWM2")
		)
		(pad "35" smd rect
			(at -0.189992 -2.899918)
			(size 0.2286 0.6096)
			(layers "F.Cu" "F.Mask" "F.Paste")
			(net "PVDD11_S3_P1_VCC2")
		)
		(pad "36" smd rect
			(at -0.64008 -2.899918)
			(size 0.2286 0.6096)
			(layers "F.Cu" "F.Mask" "F.Paste")
			(net "PVDD11_S3_P1_TEMP0")
		)
		(pad "37" smd rect
			(at -1.089914 -2.899918)
			(size 0.2286 0.6096)
			(layers "F.Cu" "F.Mask" "F.Paste")
			(net "PVDD11_S3_P1_LSET2")
		)
		(pad "38" smd rect
			(at -1.540002 -2.899918)
			(size 0.2286 0.6096)
			(layers "F.Cu" "F.Mask" "F.Paste")
			(net "PVDD11_S3_P1_IMON2")
		)
		(pad "39" smd rect
			(at -1.99009 -2.899918)
			(size 0.2286 0.6096)
			(layers "F.Cu" "F.Mask" "F.Paste")
			(net "PVDD11_S3_P1_VCCS")
		)
		(pad "40" smd rect
			(at -0.87503 -1.27508)
			(size 1.7526 1.9558)
			(layers "F.Cu" "F.Mask" "F.Paste")
			(net "GND")
		)
		(pad "41" smd rect
			(at -1.525016 0.249936 270)
			(size 0.3048 0.4572)
			(layers "F.Cu" "F.Mask" "F.Paste")
			(net "NC_PVDD11_S3_P1_GL2_2")
		)
		(zone
			(layer "F.Cu")
			(hatch none 0.5)
			(connect_pads
				(clearance 0)
			)
			(min_thickness 0.25)
			(keepout
				(tracks not_allowed)
				(vias allowed)
				(pads allowed)
				(copperpour not_allowed)
				(footprints allowed)
			)
			(placement
				(enabled no)
				(sheetname "")
			)
			(fill
				(thermal_gap 0.5)
				(thermal_bridge_width 0.5)
				(island_removal_mode 0)
			)
			(polygon
				(pts
					(xy 188.746384 -348.774512) (xy 188.746384 -349.070168) (xy 193.746628 -349.070168) (xy 193.746628 -348.320868)
					(xy 193.456306 -348.320868) (xy 193.456306 -348.776544) (xy 189.036706 -348.776544) (xy 189.036706 -348.774512)
				)
			)
		)
		(zone
			(layer "F.Cu")
			(hatch none 0.5)
			(connect_pads
				(clearance 0)
			)
			(min_thickness 0.25)
			(keepout
				(tracks not_allowed)
				(vias allowed)
				(pads allowed)
				(copperpour not_allowed)
				(footprints allowed)
			)
			(placement
				(enabled no)
				(sheetname "")
			)
			(fill
				(thermal_gap 0.5)
				(thermal_bridge_width 0.5)
				(island_removal_mode 0)
			)
			(polygon
				(pts
					(xy 191.298576 -351.57664) (xy 191.298576 -353.624642) (xy 189.444376 -353.624642) (xy 189.444376 -353.383596)
					(xy 189.20206 -353.383596) (xy 189.20206 -353.86518) (xy 193.023744 -353.86518) (xy 193.023744 -353.680268)
					(xy 191.589914 -353.680268) (xy 191.589914 -351.521268) (xy 193.746628 -351.521268) (xy 193.746628 -351.271586)
					(xy 191.60363 -351.271586)
				)
			)
		)
	)
	(footprint ""
		(layer "F.Cu")
		(at 12.987782 -415.263584 90)
		(property "Reference" "PR6543"
			(at 0 0 90)
			(layer "F.SilkS")
			(hide yes)
			(effects
				(font
					(size 1.27 1.27)
				)
			)
		)
		(property "Value" ""
			(at 0 0 90)
			(layer "F.Fab")
			(effects
				(font
					(size 1.27 1.27)
				)
			)
		)
		(duplicate_pad_numbers_are_jumpers no)
		(fp_line
			(start 0.7874 -0.4064)
			(end 0.7874 0.4064)
			(stroke
				(width 0.1524)
				(type default)
			)
			(layer "F.SilkS")
		)
		(fp_line
			(start -0.7874 -0.4064)
			(end 0.7874 -0.4064)
			(stroke
				(width 0.1524)
				(type default)
			)
			(layer "F.SilkS")
		)
		(fp_line
			(start 0.7874 0.4064)
			(end -0.7874 0.4064)
			(stroke
				(width 0.1524)
				(type default)
			)
			(layer "F.SilkS")
		)
		(fp_line
			(start -0.7874 0.4064)
			(end -0.7874 -0.4064)
			(stroke
				(width 0.1524)
				(type default)
			)
			(layer "F.SilkS")
		)
		(fp_line
			(start -0.12065 -0.305054)
			(end -0.12065 -0.2794)
			(stroke
				(width 0.1)
				(type default)
			)
			(layer "F.Fab")
		)
		(fp_line
			(start -0.67945 -0.305054)
			(end -0.12065 -0.305054)
			(stroke
				(width 0.1)
				(type default)
			)
			(layer "F.Fab")
		)
		(fp_line
			(start 0.67945 -0.3048)
			(end 0.67945 0.3048)
			(stroke
				(width 0.1)
				(type default)
			)
			(layer "F.Fab")
		)
		(fp_line
			(start 0.12065 -0.3048)
			(end 0.67945 -0.3048)
			(stroke
				(width 0.1)
				(type default)
			)
			(layer "F.Fab")
		)
		(fp_line
			(start 0.12065 -0.2794)
			(end 0.12065 -0.3048)
			(stroke
				(width 0.1)
				(type default)
			)
			(layer "F.Fab")
		)
		(fp_line
			(start -0.12065 -0.2794)
			(end 0.12065 -0.2794)
			(stroke
				(width 0.1)
				(type default)
			)
			(layer "F.Fab")
		)
		(fp_line
			(start 0.120396 0.2794)
			(end -0.12065 0.2794)
			(stroke
				(width 0.1)
				(type default)
			)
			(layer "F.Fab")
		)
		(fp_line
			(start -0.12065 0.2794)
			(end -0.12065 0.3048)
			(stroke
				(width 0.1)
				(type default)
			)
			(layer "F.Fab")
		)
		(fp_line
			(start 0.67945 0.3048)
			(end 0.120396 0.3048)
			(stroke
				(width 0.1)
				(type default)
			)
			(layer "F.Fab")
		)
		(fp_line
			(start 0.120396 0.3048)
			(end 0.120396 0.2794)
			(stroke
				(width 0.1)
				(type default)
			)
			(layer "F.Fab")
		)
		(fp_line
			(start -0.12065 0.3048)
			(end -0.67945 0.3048)
			(stroke
				(width 0.1)
				(type default)
			)
			(layer "F.Fab")
		)
		(fp_line
			(start -0.67945 0.3048)
			(end -0.67945 -0.305054)
			(stroke
				(width 0.1)
				(type default)
			)
			(layer "F.Fab")
		)
		(pad "1" smd circle
			(at -0.40005 0 90)
			(size 0 0)
			(layers "F.Cu" "F.Mask" "F.Paste")
			(net "NC_P0V9_RETIMER_CPU1_IMON7")
		)
		(pad "2" smd circle
			(at 0.40005 0 90)
			(size 0 0)
			(layers "F.Cu" "F.Mask" "F.Paste")
			(net "GND")
		)
	)
	(footprint ""
		(layer "F.Cu")
		(at 114.629946 -54.882034 90)
		(property "Reference" "R6302"
			(at 0 0 90)
			(layer "F.SilkS")
			(hide yes)
			(effects
				(font
					(size 1.27 1.27)
				)
			)
		)
		(property "Value" ""
			(at 0 0 90)
			(layer "F.Fab")
			(effects
				(font
					(size 1.27 1.27)
				)
			)
		)
		(duplicate_pad_numbers_are_jumpers no)
		(fp_line
			(start 0.7874 -0.4064)
			(end 0.7874 0.4064)
			(stroke
				(width 0.1524)
				(type default)
			)
			(layer "F.SilkS")
		)
		(fp_line
			(start -0.7874 -0.4064)
			(end 0.7874 -0.4064)
			(stroke
				(width 0.1524)
				(type default)
			)
			(layer "F.SilkS")
		)
		(fp_line
			(start 0.7874 0.4064)
			(end -0.7874 0.4064)
			(stroke
				(width 0.1524)
				(type default)
			)
			(layer "F.SilkS")
		)
		(fp_line
			(start -0.7874 0.4064)
			(end -0.7874 -0.4064)
			(stroke
				(width 0.1524)
				(type default)
			)
			(layer "F.SilkS")
		)
		(fp_line
			(start -0.12065 -0.305054)
			(end -0.12065 -0.2794)
			(stroke
				(width 0.1)
				(type default)
			)
			(layer "F.Fab")
		)
		(fp_line
			(start -0.67945 -0.305054)
			(end -0.12065 -0.305054)
			(stroke
				(width 0.1)
				(type default)
			)
			(layer "F.Fab")
		)
		(fp_line
			(start 0.67945 -0.3048)
			(end 0.67945 0.3048)
			(stroke
				(width 0.1)
				(type default)
			)
			(layer "F.Fab")
		)
		(fp_line
			(start 0.12065 -0.3048)
			(end 0.67945 -0.3048)
			(stroke
				(width 0.1)
				(type default)
			)
			(layer "F.Fab")
		)
		(fp_line
			(start 0.12065 -0.2794)
			(end 0.12065 -0.3048)
			(stroke
				(width 0.1)
				(type default)
			)
			(layer "F.Fab")
		)
		(fp_line
			(start -0.12065 -0.2794)
			(end 0.12065 -0.2794)
			(stroke
				(width 0.1)
				(type default)
			)
			(layer "F.Fab")
		)
		(fp_line
			(start 0.120396 0.2794)
			(end -0.12065 0.2794)
			(stroke
				(width 0.1)
				(type default)
			)
			(layer "F.Fab")
		)
		(fp_line
			(start -0.12065 0.2794)
			(end -0.12065 0.3048)
			(stroke
				(width 0.1)
				(type default)
			)
			(layer "F.Fab")
		)
		(fp_line
			(start 0.67945 0.3048)
			(end 0.120396 0.3048)
			(stroke
				(width 0.1)
				(type default)
			)
			(layer "F.Fab")
		)
		(fp_line
			(start 0.120396 0.3048)
			(end 0.120396 0.2794)
			(stroke
				(width 0.1)
				(type default)
			)
			(layer "F.Fab")
		)
		(fp_line
			(start -0.12065 0.3048)
			(end -0.67945 0.3048)
			(stroke
				(width 0.1)
				(type default)
			)
			(layer "F.Fab")
		)
		(fp_line
			(start -0.67945 0.3048)
			(end -0.67945 -0.305054)
			(stroke
				(width 0.1)
				(type default)
			)
			(layer "F.Fab")
		)
		(pad "1" smd circle
			(at -0.40005 0 90)
			(size 0 0)
			(layers "F.Cu" "F.Mask" "F.Paste")
			(net "USB_HUB2_MRP_CFG_BC_EN")
		)
		(pad "2" smd circle
			(at 0.40005 0 90)
			(size 0 0)
			(layers "F.Cu" "F.Mask" "F.Paste")
			(net "GND")
		)
	)
	(footprint ""
		(layer "F.Cu")
		(at 421.174164 -176.864772)
		(property "Reference" "PR296"
			(at 0 0 0)
			(layer "F.SilkS")
			(hide yes)
			(effects
				(font
					(size 1.27 1.27)
				)
			)
		)
		(property "Value" ""
			(at 0 0 0)
			(layer "F.Fab")
			(effects
				(font
					(size 1.27 1.27)
				)
			)
		)
		(duplicate_pad_numbers_are_jumpers no)
		(fp_line
			(start -0.7874 -0.4064)
			(end 0.7874 -0.4064)
			(stroke
				(width 0.1524)
				(type default)
			)
			(layer "F.SilkS")
		)
		(fp_line
			(start -0.7874 0.4064)
			(end -0.7874 -0.4064)
			(stroke
				(width 0.1524)
				(type default)
			)
			(layer "F.SilkS")
		)
		(fp_line
			(start 0.7874 -0.4064)
			(end 0.7874 0.4064)
			(stroke
				(width 0.1524)
				(type default)
			)
			(layer "F.SilkS")
		)
		(fp_line
			(start 0.7874 0.4064)
			(end -0.7874 0.4064)
			(stroke
				(width 0.1524)
				(type default)
			)
			(layer "F.SilkS")
		)
		(fp_line
			(start -0.67945 -0.305054)
			(end -0.12065 -0.305054)
			(stroke
				(width 0.1)
				(type default)
			)
			(layer "F.Fab")
		)
		(fp_line
			(start -0.67945 0.3048)
			(end -0.67945 -0.305054)
			(stroke
				(width 0.1)
				(type default)
			)
			(layer "F.Fab")
		)
		(fp_line
			(start -0.12065 -0.305054)
			(end -0.12065 -0.2794)
			(stroke
				(width 0.1)
				(type default)
			)
			(layer "F.Fab")
		)
		(fp_line
			(start -0.12065 -0.2794)
			(end 0.12065 -0.2794)
			(stroke
				(width 0.1)
				(type default)
			)
			(layer "F.Fab")
		)
		(fp_line
			(start -0.12065 0.2794)
			(end -0.12065 0.3048)
			(stroke
				(width 0.1)
				(type default)
			)
			(layer "F.Fab")
		)
		(fp_line
			(start -0.12065 0.3048)
			(end -0.67945 0.3048)
			(stroke
				(width 0.1)
				(type default)
			)
			(layer "F.Fab")
		)
		(fp_line
			(start 0.120396 0.2794)
			(end -0.12065 0.2794)
			(stroke
				(width 0.1)
				(type default)
			)
			(layer "F.Fab")
		)
		(fp_line
			(start 0.120396 0.3048)
			(end 0.120396 0.2794)
			(stroke
				(width 0.1)
				(type default)
			)
			(layer "F.Fab")
		)
		(fp_line
			(start 0.12065 -0.3048)
			(end 0.67945 -0.3048)
			(stroke
				(width 0.1)
				(type default)
			)
			(layer "F.Fab")
		)
		(fp_line
			(start 0.12065 -0.2794)
			(end 0.12065 -0.3048)
			(stroke
				(width 0.1)
				(type default)
			)
			(layer "F.Fab")
		)
		(fp_line
			(start 0.67945 -0.3048)
			(end 0.67945 0.3048)
			(stroke
				(width 0.1)
				(type default)
			)
			(layer "F.Fab")
		)
		(fp_line
			(start 0.67945 0.3048)
			(end 0.120396 0.3048)
			(stroke
				(width 0.1)
				(type default)
			)
			(layer "F.Fab")
		)
		(pad "1" smd circle
			(at -0.40005 0)
			(size 0 0)
			(layers "F.Cu" "F.Mask" "F.Paste")
			(net "PVDDCR_SOC_P0")
		)
		(pad "2" smd circle
			(at 0.40005 0)
			(size 0 0)
			(layers "F.Cu" "F.Mask" "F.Paste")
			(net "VSENSE_PVDDCR_SOC_P0_DP")
		)
	)
	(footprint ""
		(layer "F.Cu")
		(at 299.060362 -351.927922)
		(property "Reference" "PR98"
			(at 0 0 0)
			(layer "F.SilkS")
			(hide yes)
			(effects
				(font
					(size 1.27 1.27)
				)
			)
		)
		(property "Value" ""
			(at 0 0 0)
			(layer "F.Fab")
			(effects
				(font
					(size 1.27 1.27)
				)
			)
		)
		(duplicate_pad_numbers_are_jumpers no)
		(fp_line
			(start -0.7874 -0.4064)
			(end 0.7874 -0.4064)
			(stroke
				(width 0.1524)
				(type default)
			)
			(layer "F.SilkS")
		)
		(fp_line
			(start -0.7874 0.4064)
			(end -0.7874 -0.4064)
			(stroke
				(width 0.1524)
				(type default)
			)
			(layer "F.SilkS")
		)
		(fp_line
			(start 0.7874 -0.4064)
			(end 0.7874 0.4064)
			(stroke
				(width 0.1524)
				(type default)
			)
			(layer "F.SilkS")
		)
		(fp_line
			(start 0.7874 0.4064)
			(end -0.7874 0.4064)
			(stroke
				(width 0.1524)
				(type default)
			)
			(layer "F.SilkS")
		)
		(fp_line
			(start -0.67945 -0.305054)
			(end -0.12065 -0.305054)
			(stroke
				(width 0.1)
				(type default)
			)
			(layer "F.Fab")
		)
		(fp_line
			(start -0.67945 0.3048)
			(end -0.67945 -0.305054)
			(stroke
				(width 0.1)
				(type default)
			)
			(layer "F.Fab")
		)
		(fp_line
			(start -0.12065 -0.305054)
			(end -0.12065 -0.2794)
			(stroke
				(width 0.1)
				(type default)
			)
			(layer "F.Fab")
		)
		(fp_line
			(start -0.12065 -0.2794)
			(end 0.12065 -0.2794)
			(stroke
				(width 0.1)
				(type default)
			)
			(layer "F.Fab")
		)
		(fp_line
			(start -0.12065 0.2794)
			(end -0.12065 0.3048)
			(stroke
				(width 0.1)
				(type default)
			)
			(layer "F.Fab")
		)
		(fp_line
			(start -0.12065 0.3048)
			(end -0.67945 0.3048)
			(stroke
				(width 0.1)
				(type default)
			)
			(layer "F.Fab")
		)
		(fp_line
			(start 0.120396 0.2794)
			(end -0.12065 0.2794)
			(stroke
				(width 0.1)
				(type default)
			)
			(layer "F.Fab")
		)
		(fp_line
			(start 0.120396 0.3048)
			(end 0.120396 0.2794)
			(stroke
				(width 0.1)
				(type default)
			)
			(layer "F.Fab")
		)
		(fp_line
			(start 0.12065 -0.3048)
			(end 0.67945 -0.3048)
			(stroke
				(width 0.1)
				(type default)
			)
			(layer "F.Fab")
		)
		(fp_line
			(start 0.12065 -0.2794)
			(end 0.12065 -0.3048)
			(stroke
				(width 0.1)
				(type default)
			)
			(layer "F.Fab")
		)
		(fp_line
			(start 0.67945 -0.3048)
			(end 0.67945 0.3048)
			(stroke
				(width 0.1)
				(type default)
			)
			(layer "F.Fab")
		)
		(fp_line
			(start 0.67945 0.3048)
			(end 0.120396 0.3048)
			(stroke
				(width 0.1)
				(type default)
			)
			(layer "F.Fab")
		)
		(pad "1" smd circle
			(at -0.40005 0)
			(size 0 0)
			(layers "F.Cu" "F.Mask" "F.Paste")
			(net "PVDDIO_P0_LSET1")
		)
		(pad "2" smd circle
			(at 0.40005 0)
			(size 0 0)
			(layers "F.Cu" "F.Mask" "F.Paste")
			(net "GND")
		)
	)
	(footprint ""
		(layer "F.Cu")
		(at 390.474708 -409.15082 180)
		(property "Reference" "C7001"
			(at 8.527796 1.740408 0)
			(unlocked yes)
			(layer "F.SilkS")
			(effects
				(font
					(size 0.7874 0.5842)
					(thickness 0.1524)
				)
				(justify left)
			)
		)
		(property "Value" ""
			(at 0 0 180)
			(layer "F.Fab")
			(effects
				(font
					(size 1.27 1.27)
				)
			)
		)
		(duplicate_pad_numbers_are_jumpers no)
		(fp_line
			(start 4.53898 2.15011)
			(end -4.53898 2.15011)
			(stroke
				(width 0.1524)
				(type default)
			)
			(layer "F.SilkS")
		)
		(fp_line
			(start 4.53898 -2.15011)
			(end 4.53898 2.15011)
			(stroke
				(width 0.1524)
				(type default)
			)
			(layer "F.SilkS")
		)
		(fp_line
			(start -4.53898 2.15011)
			(end -4.53898 -2.15011)
			(stroke
				(width 0.1524)
				(type default)
			)
			(layer "F.SilkS")
		)
		(fp_line
			(start -4.53898 -2.15011)
			(end 4.53898 -2.15011)
			(stroke
				(width 0.1524)
				(type default)
			)
			(layer "F.SilkS")
		)
		(fp_line
			(start -4.53898 -2.150618)
			(end -4.539742 2.152142)
			(stroke
				(width 0.1524)
				(type default)
			)
			(layer "F.SilkS")
		)
		(fp_line
			(start -4.69138 -2.150618)
			(end -4.692396 2.161032)
			(stroke
				(width 0.1524)
				(type default)
			)
			(layer "F.SilkS")
		)
		(fp_line
			(start -4.83108 2.150364)
			(end -4.447794 2.149348)
			(stroke
				(width 0.1524)
				(type default)
			)
			(layer "F.SilkS")
		)
		(fp_line
			(start -4.84378 -2.150618)
			(end -4.53898 -2.150618)
			(stroke
				(width 0.1524)
				(type default)
			)
			(layer "F.SilkS")
		)
		(fp_line
			(start -4.84378 -2.150618)
			(end -4.842256 2.163064)
			(stroke
				(width 0.1524)
				(type default)
			)
			(layer "F.SilkS")
		)
		(fp_line
			(start 3.64998 2.15011)
			(end -3.64998 2.15011)
			(stroke
				(width 0.1)
				(type default)
			)
			(layer "F.Fab")
		)
		(fp_line
			(start 3.64998 -2.15011)
			(end 3.64998 2.15011)
			(stroke
				(width 0.1)
				(type default)
			)
			(layer "F.Fab")
		)
		(fp_line
			(start -3.64998 2.15011)
			(end -3.64998 -2.15011)
			(stroke
				(width 0.1)
				(type default)
			)
			(layer "F.Fab")
		)
		(fp_line
			(start -3.64998 -2.15011)
			(end 3.64998 -2.15011)
			(stroke
				(width 0.1)
				(type default)
			)
			(layer "F.Fab")
		)
		(fp_text user "-"
			(at 4.592574 -0.165608 180)
			(unlocked yes)
			(layer "F.SilkS")
			(effects
				(font
					(size 1.905 1.4224)
					(thickness 0.1524)
				)
				(justify left)
			)
		)
		(fp_text user "+"
			(at -6.024372 -1.571498 180)
			(unlocked yes)
			(layer "F.SilkS")
			(effects
				(font
					(size 1.905 1.4224)
					(thickness 0.1524)
				)
				(justify left)
			)
		)
		(fp_text user "-"
			(at 4.313174 -0.094488 180)
			(unlocked yes)
			(layer "F.Fab")
			(effects
				(font
					(size 1.905 1.4224)
					(thickness 0.1524)
				)
				(justify left)
			)
		)
		(fp_text user "+"
			(at -6.214872 -0.337058 180)
			(unlocked yes)
			(layer "F.Fab")
			(effects
				(font
					(size 1.905 1.4224)
					(thickness 0.1524)
				)
				(justify left)
			)
		)
		(pad "1" smd rect
			(at -3.199892 0 180)
			(size 2.413 2.8194)
			(layers "F.Cu" "F.Mask" "F.Paste")
			(net "P0V9_CPU0_RT_2D")
		)
		(pad "2" smd rect
			(at 3.199892 0 180)
			(size 2.413 2.8194)
			(layers "F.Cu" "F.Mask" "F.Paste")
			(net "GND")
		)
	)
	(footprint ""
		(layer "F.Cu")
		(at 110.856014 -258.795266)
		(property "Reference" "C2503"
			(at 0 0 0)
			(layer "F.SilkS")
			(hide yes)
			(effects
				(font
					(size 1.27 1.27)
				)
			)
		)
		(property "Value" ""
			(at 0 0 0)
			(layer "F.Fab")
			(effects
				(font
					(size 1.27 1.27)
				)
			)
		)
		(duplicate_pad_numbers_are_jumpers no)
		(fp_line
			(start -0.7874 -0.4064)
			(end 0.7874 -0.4064)
			(stroke
				(width 0.1524)
				(type default)
			)
			(layer "F.SilkS")
		)
		(fp_line
			(start -0.7874 0.4064)
			(end -0.7874 -0.4064)
			(stroke
				(width 0.1524)
				(type default)
			)
			(layer "F.SilkS")
		)
		(fp_line
			(start 0.7874 -0.4064)
			(end 0.7874 0.4064)
			(stroke
				(width 0.1524)
				(type default)
			)
			(layer "F.SilkS")
		)
		(fp_line
			(start 0.7874 0.4064)
			(end -0.7874 0.4064)
			(stroke
				(width 0.1524)
				(type default)
			)
			(layer "F.SilkS")
		)
		(fp_line
			(start -0.67945 -0.305054)
			(end -0.12065 -0.305054)
			(stroke
				(width 0.1)
				(type default)
			)
			(layer "F.Fab")
		)
		(fp_line
			(start -0.67945 0.3048)
			(end -0.67945 -0.305054)
			(stroke
				(width 0.1)
				(type default)
			)
			(layer "F.Fab")
		)
		(fp_line
			(start -0.12065 -0.305054)
			(end -0.12065 -0.2794)
			(stroke
				(width 0.1)
				(type default)
			)
			(layer "F.Fab")
		)
		(fp_line
			(start -0.12065 -0.2794)
			(end 0.12065 -0.2794)
			(stroke
				(width 0.1)
				(type default)
			)
			(layer "F.Fab")
		)
		(fp_line
			(start -0.12065 0.2794)
			(end -0.12065 0.3048)
			(stroke
				(width 0.1)
				(type default)
			)
			(layer "F.Fab")
		)
		(fp_line
			(start -0.12065 0.3048)
			(end -0.67945 0.3048)
			(stroke
				(width 0.1)
				(type default)
			)
			(layer "F.Fab")
		)
		(fp_line
			(start 0.120396 0.2794)
			(end -0.12065 0.2794)
			(stroke
				(width 0.1)
				(type default)
			)
			(layer "F.Fab")
		)
		(fp_line
			(start 0.120396 0.3048)
			(end 0.120396 0.2794)
			(stroke
				(width 0.1)
				(type default)
			)
			(layer "F.Fab")
		)
		(fp_line
			(start 0.12065 -0.3048)
			(end 0.67945 -0.3048)
			(stroke
				(width 0.1)
				(type default)
			)
			(layer "F.Fab")
		)
		(fp_line
			(start 0.12065 -0.2794)
			(end 0.12065 -0.3048)
			(stroke
				(width 0.1)
				(type default)
			)
			(layer "F.Fab")
		)
		(fp_line
			(start 0.67945 -0.3048)
			(end 0.67945 0.3048)
			(stroke
				(width 0.1)
				(type default)
			)
			(layer "F.Fab")
		)
		(fp_line
			(start 0.67945 0.3048)
			(end 0.120396 0.3048)
			(stroke
				(width 0.1)
				(type default)
			)
			(layer "F.Fab")
		)
		(pad "1" smd circle
			(at -0.40005 0)
			(size 0 0)
			(layers "F.Cu" "F.Mask" "F.Paste")
			(net "PVDD11_S3_P1")
		)
		(pad "2" smd circle
			(at 0.40005 0)
			(size 0 0)
			(layers "F.Cu" "F.Mask" "F.Paste")
			(net "GND")
		)
	)
	(footprint ""
		(layer "F.Cu")
		(at 322.147946 -416.899344 -90)
		(property "Reference" "C6514"
			(at 0 0 270)
			(layer "F.SilkS")
			(hide yes)
			(effects
				(font
					(size 1.27 1.27)
				)
			)
		)
		(property "Value" ""
			(at 0 0 270)
			(layer "F.Fab")
			(effects
				(font
					(size 1.27 1.27)
				)
			)
		)
		(duplicate_pad_numbers_are_jumpers no)
		(fp_line
			(start -0.299974 0.150114)
			(end -0.299974 -0.150114)
			(stroke
				(width 0.1)
				(type default)
			)
			(layer "F.Fab")
		)
		(fp_line
			(start 0.299974 0.150114)
			(end -0.299974 0.150114)
			(stroke
				(width 0.1)
				(type default)
			)
			(layer "F.Fab")
		)
		(fp_line
			(start -0.299974 -0.150114)
			(end 0.299974 -0.150114)
			(stroke
				(width 0.1)
				(type default)
			)
			(layer "F.Fab")
		)
		(fp_line
			(start 0.299974 -0.150114)
			(end 0.299974 0.150114)
			(stroke
				(width 0.1)
				(type default)
			)
			(layer "F.Fab")
		)
		(pad "1" smd rect
			(at -0.2667 0 270)
			(size 0.3048 0.381)
			(layers "F.Cu" "F.Mask" "F.Paste")
			(net "P5E_CPU0_P0_TX_BUF_C_DN<6>")
		)
		(pad "2" smd rect
			(at 0.2667 0 270)
			(size 0.3048 0.381)
			(layers "F.Cu" "F.Mask" "F.Paste")
			(net "P5E_CPU0_P0_TX_BUF_DN<6>")
		)
	)
	(footprint ""
		(layer "F.Cu")
		(at 188.087 -137.632948 -90)
		(property "Reference" "R1551"
			(at 0 0 270)
			(layer "F.SilkS")
			(hide yes)
			(effects
				(font
					(size 1.27 1.27)
				)
			)
		)
		(property "Value" ""
			(at 0 0 270)
			(layer "F.Fab")
			(effects
				(font
					(size 1.27 1.27)
				)
			)
		)
		(duplicate_pad_numbers_are_jumpers no)
		(fp_line
			(start -0.7874 0.4064)
			(end -0.7874 -0.4064)
			(stroke
				(width 0.1524)
				(type default)
			)
			(layer "F.SilkS")
		)
		(fp_line
			(start 0.7874 0.4064)
			(end -0.7874 0.4064)
			(stroke
				(width 0.1524)
				(type default)
			)
			(layer "F.SilkS")
		)
		(fp_line
			(start -0.7874 -0.4064)
			(end 0.7874 -0.4064)
			(stroke
				(width 0.1524)
				(type default)
			)
			(layer "F.SilkS")
		)
		(fp_line
			(start 0.7874 -0.4064)
			(end 0.7874 0.4064)
			(stroke
				(width 0.1524)
				(type default)
			)
			(layer "F.SilkS")
		)
		(fp_line
			(start -0.67945 0.3048)
			(end -0.67945 -0.305054)
			(stroke
				(width 0.1)
				(type default)
			)
			(layer "F.Fab")
		)
		(fp_line
			(start -0.12065 0.3048)
			(end -0.67945 0.3048)
			(stroke
				(width 0.1)
				(type default)
			)
			(layer "F.Fab")
		)
		(fp_line
			(start 0.120396 0.3048)
			(end 0.120396 0.2794)
			(stroke
				(width 0.1)
				(type default)
			)
			(layer "F.Fab")
		)
		(fp_line
			(start 0.67945 0.3048)
			(end 0.120396 0.3048)
			(stroke
				(width 0.1)
				(type default)
			)
			(layer "F.Fab")
		)
		(fp_line
			(start -0.12065 0.2794)
			(end -0.12065 0.3048)
			(stroke
				(width 0.1)
				(type default)
			)
			(layer "F.Fab")
		)
		(fp_line
			(start 0.120396 0.2794)
			(end -0.12065 0.2794)
			(stroke
				(width 0.1)
				(type default)
			)
			(layer "F.Fab")
		)
		(fp_line
			(start -0.12065 -0.2794)
			(end 0.12065 -0.2794)
			(stroke
				(width 0.1)
				(type default)
			)
			(layer "F.Fab")
		)
		(fp_line
			(start 0.12065 -0.2794)
			(end 0.12065 -0.3048)
			(stroke
				(width 0.1)
				(type default)
			)
			(layer "F.Fab")
		)
		(fp_line
			(start 0.12065 -0.3048)
			(end 0.67945 -0.3048)
			(stroke
				(width 0.1)
				(type default)
			)
			(layer "F.Fab")
		)
		(fp_line
			(start 0.67945 -0.3048)
			(end 0.67945 0.3048)
			(stroke
				(width 0.1)
				(type default)
			)
			(layer "F.Fab")
		)
		(fp_line
			(start -0.67945 -0.305054)
			(end -0.12065 -0.305054)
			(stroke
				(width 0.1)
				(type default)
			)
			(layer "F.Fab")
		)
		(fp_line
			(start -0.12065 -0.305054)
			(end -0.12065 -0.2794)
			(stroke
				(width 0.1)
				(type default)
			)
			(layer "F.Fab")
		)
		(pad "1" smd circle
			(at -0.40005 0 270)
			(size 0 0)
			(layers "F.Cu" "F.Mask" "F.Paste")
			(net "ESPI_CPU0_R1_D2")
		)
		(pad "2" smd circle
			(at 0.40005 0 270)
			(size 0 0)
			(layers "F.Cu" "F.Mask" "F.Paste")
			(net "ESPI_CPU0_D2")
		)
	)
	(footprint ""
		(layer "F.Cu")
		(at 271.092676 -118.618)
		(property "Reference" "R1312"
			(at 0 0 0)
			(layer "F.SilkS")
			(hide yes)
			(effects
				(font
					(size 1.27 1.27)
				)
			)
		)
		(property "Value" ""
			(at 0 0 0)
			(layer "F.Fab")
			(effects
				(font
					(size 1.27 1.27)
				)
			)
		)
		(duplicate_pad_numbers_are_jumpers no)
		(fp_line
			(start -0.7874 -0.4064)
			(end 0.7874 -0.4064)
			(stroke
				(width 0.1524)
				(type default)
			)
			(layer "F.SilkS")
		)
		(fp_line
			(start -0.7874 0.4064)
			(end -0.7874 -0.4064)
			(stroke
				(width 0.1524)
				(type default)
			)
			(layer "F.SilkS")
		)
		(fp_line
			(start 0.7874 -0.4064)
			(end 0.7874 0.4064)
			(stroke
				(width 0.1524)
				(type default)
			)
			(layer "F.SilkS")
		)
		(fp_line
			(start 0.7874 0.4064)
			(end -0.7874 0.4064)
			(stroke
				(width 0.1524)
				(type default)
			)
			(layer "F.SilkS")
		)
		(fp_line
			(start -0.67945 -0.305054)
			(end -0.12065 -0.305054)
			(stroke
				(width 0.1)
				(type default)
			)
			(layer "F.Fab")
		)
		(fp_line
			(start -0.67945 0.3048)
			(end -0.67945 -0.305054)
			(stroke
				(width 0.1)
				(type default)
			)
			(layer "F.Fab")
		)
		(fp_line
			(start -0.12065 -0.305054)
			(end -0.12065 -0.2794)
			(stroke
				(width 0.1)
				(type default)
			)
			(layer "F.Fab")
		)
		(fp_line
			(start -0.12065 -0.2794)
			(end 0.12065 -0.2794)
			(stroke
				(width 0.1)
				(type default)
			)
			(layer "F.Fab")
		)
		(fp_line
			(start -0.12065 0.2794)
			(end -0.12065 0.3048)
			(stroke
				(width 0.1)
				(type default)
			)
			(layer "F.Fab")
		)
		(fp_line
			(start -0.12065 0.3048)
			(end -0.67945 0.3048)
			(stroke
				(width 0.1)
				(type default)
			)
			(layer "F.Fab")
		)
		(fp_line
			(start 0.120396 0.2794)
			(end -0.12065 0.2794)
			(stroke
				(width 0.1)
				(type default)
			)
			(layer "F.Fab")
		)
		(fp_line
			(start 0.120396 0.3048)
			(end 0.120396 0.2794)
			(stroke
				(width 0.1)
				(type default)
			)
			(layer "F.Fab")
		)
		(fp_line
			(start 0.12065 -0.3048)
			(end 0.67945 -0.3048)
			(stroke
				(width 0.1)
				(type default)
			)
			(layer "F.Fab")
		)
		(fp_line
			(start 0.12065 -0.2794)
			(end 0.12065 -0.3048)
			(stroke
				(width 0.1)
				(type default)
			)
			(layer "F.Fab")
		)
		(fp_line
			(start 0.67945 -0.3048)
			(end 0.67945 0.3048)
			(stroke
				(width 0.1)
				(type default)
			)
			(layer "F.Fab")
		)
		(fp_line
			(start 0.67945 0.3048)
			(end 0.120396 0.3048)
			(stroke
				(width 0.1)
				(type default)
			)
			(layer "F.Fab")
		)
		(pad "1" smd circle
			(at -0.40005 0)
			(size 0 0)
			(layers "F.Cu" "F.Mask" "F.Paste")
			(net "SMB_ADC_SDA")
		)
		(pad "2" smd circle
			(at 0.40005 0)
			(size 0 0)
			(layers "F.Cu" "F.Mask" "F.Paste")
			(net "SMB_ADC_SDA_R")
		)
	)
	(footprint ""
		(layer "F.Cu")
		(at 254 -38.683946 180)
		(property "Reference" "R3976"
			(at 0 0 180)
			(layer "F.SilkS")
			(hide yes)
			(effects
				(font
					(size 1.27 1.27)
				)
			)
		)
		(property "Value" ""
			(at 0 0 180)
			(layer "F.Fab")
			(effects
				(font
					(size 1.27 1.27)
				)
			)
		)
		(duplicate_pad_numbers_are_jumpers no)
		(fp_line
			(start 0.7874 0.4064)
			(end -0.7874 0.4064)
			(stroke
				(width 0.1524)
				(type default)
			)
			(layer "F.SilkS")
		)
		(fp_line
			(start 0.7874 -0.4064)
			(end 0.7874 0.4064)
			(stroke
				(width 0.1524)
				(type default)
			)
			(layer "F.SilkS")
		)
		(fp_line
			(start -0.7874 0.4064)
			(end -0.7874 -0.4064)
			(stroke
				(width 0.1524)
				(type default)
			)
			(layer "F.SilkS")
		)
		(fp_line
			(start -0.7874 -0.4064)
			(end 0.7874 -0.4064)
			(stroke
				(width 0.1524)
				(type default)
			)
			(layer "F.SilkS")
		)
		(fp_line
			(start 0.67945 0.3048)
			(end 0.120396 0.3048)
			(stroke
				(width 0.1)
				(type default)
			)
			(layer "F.Fab")
		)
		(fp_line
			(start 0.67945 -0.3048)
			(end 0.67945 0.3048)
			(stroke
				(width 0.1)
				(type default)
			)
			(layer "F.Fab")
		)
		(fp_line
			(start 0.12065 -0.2794)
			(end 0.12065 -0.3048)
			(stroke
				(width 0.1)
				(type default)
			)
			(layer "F.Fab")
		)
		(fp_line
			(start 0.12065 -0.3048)
			(end 0.67945 -0.3048)
			(stroke
				(width 0.1)
				(type default)
			)
			(layer "F.Fab")
		)
		(fp_line
			(start 0.120396 0.3048)
			(end 0.120396 0.2794)
			(stroke
				(width 0.1)
				(type default)
			)
			(layer "F.Fab")
		)
		(fp_line
			(start 0.120396 0.2794)
			(end -0.12065 0.2794)
			(stroke
				(width 0.1)
				(type default)
			)
			(layer "F.Fab")
		)
		(fp_line
			(start -0.12065 0.3048)
			(end -0.67945 0.3048)
			(stroke
				(width 0.1)
				(type default)
			)
			(layer "F.Fab")
		)
		(fp_line
			(start -0.12065 0.2794)
			(end -0.12065 0.3048)
			(stroke
				(width 0.1)
				(type default)
			)
			(layer "F.Fab")
		)
		(fp_line
			(start -0.12065 -0.2794)
			(end 0.12065 -0.2794)
			(stroke
				(width 0.1)
				(type default)
			)
			(layer "F.Fab")
		)
		(fp_line
			(start -0.12065 -0.305054)
			(end -0.12065 -0.2794)
			(stroke
				(width 0.1)
				(type default)
			)
			(layer "F.Fab")
		)
		(fp_line
			(start -0.67945 0.3048)
			(end -0.67945 -0.305054)
			(stroke
				(width 0.1)
				(type default)
			)
			(layer "F.Fab")
		)
		(fp_line
			(start -0.67945 -0.305054)
			(end -0.12065 -0.305054)
			(stroke
				(width 0.1)
				(type default)
			)
			(layer "F.Fab")
		)
		(pad "1" smd circle
			(at -0.40005 0 180)
			(size 0 0)
			(layers "F.Cu" "F.Mask" "F.Paste")
			(net "P3V3_AUX")
		)
		(pad "2" smd circle
			(at 0.40005 0 180)
			(size 0 0)
			(layers "F.Cu" "F.Mask" "F.Paste")
			(net "P12V_E1S_FAULT_0")
		)
	)
	(footprint ""
		(layer "F.Cu")
		(at 189.865 -96.103948 90)
		(property "Reference" "R6073"
			(at 0 0 90)
			(layer "F.SilkS")
			(hide yes)
			(effects
				(font
					(size 1.27 1.27)
				)
			)
		)
		(property "Value" ""
			(at 0 0 90)
			(layer "F.Fab")
			(effects
				(font
					(size 1.27 1.27)
				)
			)
		)
		(duplicate_pad_numbers_are_jumpers no)
		(fp_line
			(start 0.7874 -0.4064)
			(end 0.7874 0.4064)
			(stroke
				(width 0.1524)
				(type default)
			)
			(layer "F.SilkS")
		)
		(fp_line
			(start -0.7874 -0.4064)
			(end 0.7874 -0.4064)
			(stroke
				(width 0.1524)
				(type default)
			)
			(layer "F.SilkS")
		)
		(fp_line
			(start 0.7874 0.4064)
			(end -0.7874 0.4064)
			(stroke
				(width 0.1524)
				(type default)
			)
			(layer "F.SilkS")
		)
		(fp_line
			(start -0.7874 0.4064)
			(end -0.7874 -0.4064)
			(stroke
				(width 0.1524)
				(type default)
			)
			(layer "F.SilkS")
		)
		(fp_line
			(start -0.12065 -0.305054)
			(end -0.12065 -0.2794)
			(stroke
				(width 0.1)
				(type default)
			)
			(layer "F.Fab")
		)
		(fp_line
			(start -0.67945 -0.305054)
			(end -0.12065 -0.305054)
			(stroke
				(width 0.1)
				(type default)
			)
			(layer "F.Fab")
		)
		(fp_line
			(start 0.67945 -0.3048)
			(end 0.67945 0.3048)
			(stroke
				(width 0.1)
				(type default)
			)
			(layer "F.Fab")
		)
		(fp_line
			(start 0.12065 -0.3048)
			(end 0.67945 -0.3048)
			(stroke
				(width 0.1)
				(type default)
			)
			(layer "F.Fab")
		)
		(fp_line
			(start 0.12065 -0.2794)
			(end 0.12065 -0.3048)
			(stroke
				(width 0.1)
				(type default)
			)
			(layer "F.Fab")
		)
		(fp_line
			(start -0.12065 -0.2794)
			(end 0.12065 -0.2794)
			(stroke
				(width 0.1)
				(type default)
			)
			(layer "F.Fab")
		)
		(fp_line
			(start 0.120396 0.2794)
			(end -0.12065 0.2794)
			(stroke
				(width 0.1)
				(type default)
			)
			(layer "F.Fab")
		)
		(fp_line
			(start -0.12065 0.2794)
			(end -0.12065 0.3048)
			(stroke
				(width 0.1)
				(type default)
			)
			(layer "F.Fab")
		)
		(fp_line
			(start 0.67945 0.3048)
			(end 0.120396 0.3048)
			(stroke
				(width 0.1)
				(type default)
			)
			(layer "F.Fab")
		)
		(fp_line
			(start 0.120396 0.3048)
			(end 0.120396 0.2794)
			(stroke
				(width 0.1)
				(type default)
			)
			(layer "F.Fab")
		)
		(fp_line
			(start -0.12065 0.3048)
			(end -0.67945 0.3048)
			(stroke
				(width 0.1)
				(type default)
			)
			(layer "F.Fab")
		)
		(fp_line
			(start -0.67945 0.3048)
			(end -0.67945 -0.305054)
			(stroke
				(width 0.1)
				(type default)
			)
			(layer "F.Fab")
		)
		(pad "1" smd circle
			(at -0.40005 0 90)
			(size 0 0)
			(layers "F.Cu" "F.Mask" "F.Paste")
			(net "FM_PDB_BUF_EN_R_N")
		)
		(pad "2" smd circle
			(at 0.40005 0 90)
			(size 0 0)
			(layers "F.Cu" "F.Mask" "F.Paste")
			(net "FM_PDB_BUF_EN_N")
		)
	)
	(footprint ""
		(layer "F.Cu")
		(at 233.2228 -287.0708)
		(property "Reference" "PC6905"
			(at 0 0 0)
			(layer "F.SilkS")
			(hide yes)
			(effects
				(font
					(size 1.27 1.27)
				)
			)
		)
		(property "Value" ""
			(at 0 0 0)
			(layer "F.Fab")
			(effects
				(font
					(size 1.27 1.27)
				)
			)
		)
		(duplicate_pad_numbers_are_jumpers no)
		(fp_line
			(start -1.524 -0.762)
			(end 1.524 -0.762)
			(stroke
				(width 0.1524)
				(type default)
			)
			(layer "F.SilkS")
		)
		(fp_line
			(start -1.524 0.762)
			(end -1.524 -0.762)
			(stroke
				(width 0.1524)
				(type default)
			)
			(layer "F.SilkS")
		)
		(fp_line
			(start 1.524 -0.762)
			(end 1.524 0.762)
			(stroke
				(width 0.1524)
				(type default)
			)
			(layer "F.SilkS")
		)
		(fp_line
			(start 1.524 0.762)
			(end -1.524 0.762)
			(stroke
				(width 0.1524)
				(type default)
			)
			(layer "F.SilkS")
		)
		(fp_line
			(start -1.1049 -0.724916)
			(end -1.1049 0.724916)
			(stroke
				(width 0.1)
				(type default)
			)
			(layer "F.Fab")
		)
		(fp_line
			(start -1.1049 0.724916)
			(end 1.1049 0.724916)
			(stroke
				(width 0.1)
				(type default)
			)
			(layer "F.Fab")
		)
		(fp_line
			(start 1.1049 -0.724916)
			(end -1.1049 -0.724916)
			(stroke
				(width 0.1)
				(type default)
			)
			(layer "F.Fab")
		)
		(fp_line
			(start 1.1049 0.724916)
			(end 1.1049 -0.724916)
			(stroke
				(width 0.1)
				(type default)
			)
			(layer "F.Fab")
		)
		(pad "1" smd rect
			(at -0.889 0 180)
			(size 1.016 1.27)
			(layers "F.Cu" "F.Mask" "F.Paste")
			(net "SW_P12V_AUX_P1V8_RETIMER_CPU1_FLT")
		)
		(pad "2" smd rect
			(at 0.889 0 180)
			(size 1.016 1.27)
			(layers "F.Cu" "F.Mask" "F.Paste")
			(net "GND")
		)
	)
	(footprint ""
		(layer "F.Cu")
		(at 473.635324 -437.43753 180)
		(property "Reference" "DB7"
			(at 3.42519 1.965452 0)
			(unlocked yes)
			(layer "F.SilkS")
			(effects
				(font
					(size 0.7874 0.5842)
					(thickness 0.1524)
				)
				(justify left)
			)
		)
		(property "Value" ""
			(at 0 0 180)
			(layer "F.Fab")
			(effects
				(font
					(size 1.27 1.27)
				)
			)
		)
		(duplicate_pad_numbers_are_jumpers no)
		(fp_line
			(start 3.330702 -4.771136)
			(end 0 4.011168)
			(stroke
				(width 0.1524)
				(type default)
			)
			(layer "F.SilkS")
		)
		(fp_line
			(start 0 4.011168)
			(end -3.330702 -4.771136)
			(stroke
				(width 0.1524)
				(type default)
			)
			(layer "F.SilkS")
		)
		(fp_line
			(start -3.330702 -4.771136)
			(end 3.330702 -4.771136)
			(stroke
				(width 0.1524)
				(type default)
			)
			(layer "F.SilkS")
		)
		(fp_line
			(start 3.330702 -4.771136)
			(end 0 4.011168)
			(stroke
				(width 0.1)
				(type default)
			)
			(layer "F.Fab")
		)
		(fp_line
			(start 0 4.011168)
			(end -3.330702 -4.771136)
			(stroke
				(width 0.1)
				(type default)
			)
			(layer "F.Fab")
		)
		(fp_line
			(start -3.330702 -4.771136)
			(end 3.330702 -4.771136)
			(stroke
				(width 0.1)
				(type default)
			)
			(layer "F.Fab")
		)
		(pad "1" thru_hole circle
			(at 0 0 180)
			(size 2.159 2.159)
			(drill 1.7018)
			(layers "*.Cu" "*.Mask")
			(remove_unused_layers no)
			(net "T1_GND")
			(clearance 0.0254)
			(thermal_gap 0.0254)
		)
		(pad "2" thru_hole circle
			(at -1.27 -3.348736 180)
			(size 2.159 2.159)
			(drill 1.7018)
			(layers "*.Cu" "*.Mask")
			(remove_unused_layers no)
			(net "TDR_SE_50_OHM_TOP")
			(clearance 0.0254)
			(thermal_gap 0.0254)
		)
		(pad "3" thru_hole circle
			(at 1.27 -3.348736 180)
			(size 2.159 2.159)
			(drill 1.7018)
			(layers "*.Cu" "*.Mask")
			(remove_unused_layers no)
			(net "TDR_SE_50_OHM_TOP")
			(clearance 0.0254)
			(thermal_gap 0.0254)
		)
	)
	(footprint ""
		(layer "F.Cu")
		(at 378.85624 -151.393398 -90)
		(property "Reference" "PC583"
			(at 0 0 270)
			(layer "F.SilkS")
			(hide yes)
			(effects
				(font
					(size 1.27 1.27)
				)
			)
		)
		(property "Value" ""
			(at 0 0 270)
			(layer "F.Fab")
			(effects
				(font
					(size 1.27 1.27)
				)
			)
		)
		(duplicate_pad_numbers_are_jumpers no)
		(fp_line
			(start -0.7874 0.4064)
			(end -0.7874 -0.4064)
			(stroke
				(width 0.1524)
				(type default)
			)
			(layer "F.SilkS")
		)
		(fp_line
			(start 0.7874 0.4064)
			(end -0.7874 0.4064)
			(stroke
				(width 0.1524)
				(type default)
			)
			(layer "F.SilkS")
		)
		(fp_line
			(start -0.7874 -0.4064)
			(end 0.7874 -0.4064)
			(stroke
				(width 0.1524)
				(type default)
			)
			(layer "F.SilkS")
		)
		(fp_line
			(start 0.7874 -0.4064)
			(end 0.7874 0.4064)
			(stroke
				(width 0.1524)
				(type default)
			)
			(layer "F.SilkS")
		)
		(fp_line
			(start -0.67945 0.3048)
			(end -0.67945 -0.305054)
			(stroke
				(width 0.1)
				(type default)
			)
			(layer "F.Fab")
		)
		(fp_line
			(start -0.12065 0.3048)
			(end -0.67945 0.3048)
			(stroke
				(width 0.1)
				(type default)
			)
			(layer "F.Fab")
		)
		(fp_line
			(start 0.120396 0.3048)
			(end 0.120396 0.2794)
			(stroke
				(width 0.1)
				(type default)
			)
			(layer "F.Fab")
		)
		(fp_line
			(start 0.67945 0.3048)
			(end 0.120396 0.3048)
			(stroke
				(width 0.1)
				(type default)
			)
			(layer "F.Fab")
		)
		(fp_line
			(start -0.12065 0.2794)
			(end -0.12065 0.3048)
			(stroke
				(width 0.1)
				(type default)
			)
			(layer "F.Fab")
		)
		(fp_line
			(start 0.120396 0.2794)
			(end -0.12065 0.2794)
			(stroke
				(width 0.1)
				(type default)
			)
			(layer "F.Fab")
		)
		(fp_line
			(start -0.12065 -0.2794)
			(end 0.12065 -0.2794)
			(stroke
				(width 0.1)
				(type default)
			)
			(layer "F.Fab")
		)
		(fp_line
			(start 0.12065 -0.2794)
			(end 0.12065 -0.3048)
			(stroke
				(width 0.1)
				(type default)
			)
			(layer "F.Fab")
		)
		(fp_line
			(start 0.12065 -0.3048)
			(end 0.67945 -0.3048)
			(stroke
				(width 0.1)
				(type default)
			)
			(layer "F.Fab")
		)
		(fp_line
			(start 0.67945 -0.3048)
			(end 0.67945 0.3048)
			(stroke
				(width 0.1)
				(type default)
			)
			(layer "F.Fab")
		)
		(fp_line
			(start -0.67945 -0.305054)
			(end -0.12065 -0.305054)
			(stroke
				(width 0.1)
				(type default)
			)
			(layer "F.Fab")
		)
		(fp_line
			(start -0.12065 -0.305054)
			(end -0.12065 -0.2794)
			(stroke
				(width 0.1)
				(type default)
			)
			(layer "F.Fab")
		)
		(pad "1" smd circle
			(at -0.40005 0 270)
			(size 0 0)
			(layers "F.Cu" "F.Mask" "F.Paste")
			(net "P12V_AUX")
		)
		(pad "2" smd circle
			(at 0.40005 0 270)
			(size 0 0)
			(layers "F.Cu" "F.Mask" "F.Paste")
			(net "GND")
		)
	)
	(footprint ""
		(layer "F.Cu")
		(at 25.331166 -73.614788 -90)
		(property "Reference" "JP6000"
			(at 2.451354 6.528054 0)
			(unlocked yes)
			(layer "F.SilkS")
			(effects
				(font
					(size 0.7874 0.5842)
					(thickness 0.1524)
				)
				(justify left)
			)
		)
		(property "Value" ""
			(at 0 0 270)
			(layer "F.Fab")
			(effects
				(font
					(size 1.27 1.27)
				)
			)
		)
		(duplicate_pad_numbers_are_jumpers no)
		(fp_line
			(start -1.249934 6.400038)
			(end -1.249934 -1.320038)
			(stroke
				(width 0.1524)
				(type default)
			)
			(layer "F.SilkS")
		)
		(fp_line
			(start 1.249934 6.400038)
			(end -1.249934 6.400038)
			(stroke
				(width 0.1524)
				(type default)
			)
			(layer "F.SilkS")
		)
		(fp_line
			(start -1.249934 -1.320038)
			(end 1.249934 -1.320038)
			(stroke
				(width 0.1524)
				(type default)
			)
			(layer "F.SilkS")
		)
		(fp_line
			(start 1.249934 -1.320038)
			(end 1.249934 6.400038)
			(stroke
				(width 0.1524)
				(type default)
			)
			(layer "F.SilkS")
		)
		(fp_poly
			(pts
				(xy -2.5654 -0.556514) (xy -1.452372 0) (xy -2.5654 0.556514)
			)
			(stroke
				(width 0)
				(type default)
			)
			(fill yes)
			(layer "F.SilkS")
		)
		(fp_line
			(start -1.249934 6.400038)
			(end -1.249934 -1.320038)
			(stroke
				(width 0.1)
				(type default)
			)
			(layer "F.Fab")
		)
		(fp_line
			(start 1.249934 6.400038)
			(end -1.249934 6.400038)
			(stroke
				(width 0.1)
				(type default)
			)
			(layer "F.Fab")
		)
		(fp_line
			(start -1.249934 -1.320038)
			(end 1.249934 -1.320038)
			(stroke
				(width 0.1)
				(type default)
			)
			(layer "F.Fab")
		)
		(fp_line
			(start 1.249934 -1.320038)
			(end 1.249934 6.400038)
			(stroke
				(width 0.1)
				(type default)
			)
			(layer "F.Fab")
		)
		(fp_poly
			(pts
				(xy -2.5654 -0.556514) (xy -1.452372 0) (xy -2.5654 0.556514)
			)
			(stroke
				(width 0)
				(type default)
			)
			(fill yes)
			(layer "F.Fab")
		)
		(fp_text user "3"
			(at -1.778 5.13207 270)
			(unlocked yes)
			(layer "F.SilkS")
			(effects
				(font
					(size 0.7874 0.5842)
					(thickness 0.1524)
				)
			)
		)
		(fp_text user "3"
			(at -1.1557 5.18287 270)
			(unlocked yes)
			(layer "B.SilkS")
			(effects
				(font
					(size 0.7874 0.5842)
					(thickness 0.1524)
				)
				(justify mirror)
			)
		)
		(fp_text user "1"
			(at -1.143 0.02667 270)
			(unlocked yes)
			(layer "B.SilkS")
			(effects
				(font
					(size 0.7874 0.5842)
					(thickness 0.1524)
				)
				(justify mirror)
			)
		)
		(fp_text user "3"
			(at -1.1557 5.18287 270)
			(unlocked yes)
			(layer "B.Fab")
			(effects
				(font
					(size 0.7874 0.5842)
					(thickness 0.1524)
				)
				(justify mirror)
			)
		)
		(fp_text user "1"
			(at -1.143 0.02667 270)
			(unlocked yes)
			(layer "B.Fab")
			(effects
				(font
					(size 0.7874 0.5842)
					(thickness 0.1524)
				)
				(justify mirror)
			)
		)
		(fp_text user "3"
			(at -1.778 5.13207 270)
			(unlocked yes)
			(layer "F.Fab")
			(effects
				(font
					(size 0.7874 0.5842)
					(thickness 0.1524)
				)
			)
		)
		(pad "1" thru_hole rect
			(at 0 0 270)
			(size 1.5494 1.5494)
			(drill 1.0414)
			(layers "*.Cu" "*.Mask")
			(remove_unused_layers no)
			(net "PU_U212_EN_N")
			(clearance 0)
			(padstack
				(mode front_inner_back)
				(layer "Inner"
					(shape circle)
					(size 1.5494 1.5494)
					(clearance 0)
				)
				(layer "B.Cu"
					(shape rect)
					(size 1.5494 1.5494)
					(clearance 0)
				)
			)
		)
		(pad "2" thru_hole circle
			(at 0 2.54 270)
			(size 1.5494 1.5494)
			(drill 1.0414)
			(layers "*.Cu" "*.Mask")
			(remove_unused_layers no)
			(net "U212_EN_N")
			(clearance 0)
		)
		(pad "3" thru_hole circle
			(at 0 5.08 270)
			(size 1.5494 1.5494)
			(drill 1.0414)
			(layers "*.Cu" "*.Mask")
			(remove_unused_layers no)
			(net "PD_U212_EN_N")
			(clearance 0)
		)
	)
	(footprint ""
		(layer "F.Cu")
		(at 316.23 -364.617 90)
		(property "Reference" "PC14"
			(at 0 0 90)
			(layer "F.SilkS")
			(hide yes)
			(effects
				(font
					(size 1.27 1.27)
				)
			)
		)
		(property "Value" ""
			(at 0 0 90)
			(layer "F.Fab")
			(effects
				(font
					(size 1.27 1.27)
				)
			)
		)
		(duplicate_pad_numbers_are_jumpers no)
		(fp_line
			(start 0.7874 -0.4064)
			(end 0.7874 0.4064)
			(stroke
				(width 0.1524)
				(type default)
			)
			(layer "F.SilkS")
		)
		(fp_line
			(start -0.7874 -0.4064)
			(end 0.7874 -0.4064)
			(stroke
				(width 0.1524)
				(type default)
			)
			(layer "F.SilkS")
		)
		(fp_line
			(start 0.7874 0.4064)
			(end -0.7874 0.4064)
			(stroke
				(width 0.1524)
				(type default)
			)
			(layer "F.SilkS")
		)
		(fp_line
			(start -0.7874 0.4064)
			(end -0.7874 -0.4064)
			(stroke
				(width 0.1524)
				(type default)
			)
			(layer "F.SilkS")
		)
		(fp_line
			(start -0.12065 -0.305054)
			(end -0.12065 -0.2794)
			(stroke
				(width 0.1)
				(type default)
			)
			(layer "F.Fab")
		)
		(fp_line
			(start -0.67945 -0.305054)
			(end -0.12065 -0.305054)
			(stroke
				(width 0.1)
				(type default)
			)
			(layer "F.Fab")
		)
		(fp_line
			(start 0.67945 -0.3048)
			(end 0.67945 0.3048)
			(stroke
				(width 0.1)
				(type default)
			)
			(layer "F.Fab")
		)
		(fp_line
			(start 0.12065 -0.3048)
			(end 0.67945 -0.3048)
			(stroke
				(width 0.1)
				(type default)
			)
			(layer "F.Fab")
		)
		(fp_line
			(start 0.12065 -0.2794)
			(end 0.12065 -0.3048)
			(stroke
				(width 0.1)
				(type default)
			)
			(layer "F.Fab")
		)
		(fp_line
			(start -0.12065 -0.2794)
			(end 0.12065 -0.2794)
			(stroke
				(width 0.1)
				(type default)
			)
			(layer "F.Fab")
		)
		(fp_line
			(start 0.120396 0.2794)
			(end -0.12065 0.2794)
			(stroke
				(width 0.1)
				(type default)
			)
			(layer "F.Fab")
		)
		(fp_line
			(start -0.12065 0.2794)
			(end -0.12065 0.3048)
			(stroke
				(width 0.1)
				(type default)
			)
			(layer "F.Fab")
		)
		(fp_line
			(start 0.67945 0.3048)
			(end 0.120396 0.3048)
			(stroke
				(width 0.1)
				(type default)
			)
			(layer "F.Fab")
		)
		(fp_line
			(start 0.120396 0.3048)
			(end 0.120396 0.2794)
			(stroke
				(width 0.1)
				(type default)
			)
			(layer "F.Fab")
		)
		(fp_line
			(start -0.12065 0.3048)
			(end -0.67945 0.3048)
			(stroke
				(width 0.1)
				(type default)
			)
			(layer "F.Fab")
		)
		(fp_line
			(start -0.67945 0.3048)
			(end -0.67945 -0.305054)
			(stroke
				(width 0.1)
				(type default)
			)
			(layer "F.Fab")
		)
		(pad "1" smd circle
			(at -0.40005 0 90)
			(size 0 0)
			(layers "F.Cu" "F.Mask" "F.Paste")
			(net "PVDDCR_CPU1_P0_VCC")
		)
		(pad "2" smd circle
			(at 0.40005 0 90)
			(size 0 0)
			(layers "F.Cu" "F.Mask" "F.Paste")
			(net "GND")
		)
	)
	(footprint ""
		(layer "F.Cu")
		(at 436.052722 -406.33396)
		(property "Reference" "R1406"
			(at 0 0 0)
			(layer "F.SilkS")
			(hide yes)
			(effects
				(font
					(size 1.27 1.27)
				)
			)
		)
		(property "Value" ""
			(at 0 0 0)
			(layer "F.Fab")
			(effects
				(font
					(size 1.27 1.27)
				)
			)
		)
		(duplicate_pad_numbers_are_jumpers no)
		(fp_line
			(start -0.32512 -0.175006)
			(end 0.32512 -0.175006)
			(stroke
				(width 0.1)
				(type default)
			)
			(layer "F.Fab")
		)
		(fp_line
			(start -0.32512 0.175006)
			(end -0.32512 -0.175006)
			(stroke
				(width 0.1)
				(type default)
			)
			(layer "F.Fab")
		)
		(fp_line
			(start 0.32512 -0.175006)
			(end 0.32512 0.175006)
			(stroke
				(width 0.1)
				(type default)
			)
			(layer "F.Fab")
		)
		(fp_line
			(start 0.32512 0.175006)
			(end -0.32512 0.175006)
			(stroke
				(width 0.1)
				(type default)
			)
			(layer "F.Fab")
		)
		(pad "1" smd rect
			(at -0.2667 0)
			(size 0.3048 0.381)
			(layers "F.Cu" "F.Mask" "F.Paste")
			(net "RXDET_BYP_RT_CPU0_P2")
		)
		(pad "2" smd rect
			(at 0.2667 0 180)
			(size 0.3048 0.381)
			(layers "F.Cu" "F.Mask" "F.Paste")
			(net "GND")
		)
	)
	(footprint ""
		(layer "F.Cu")
		(at 58.64987 -440.489848)
		(property "Reference" "J112"
			(at -4.958842 26.716736 90)
			(unlocked yes)
			(layer "F.SilkS")
			(effects
				(font
					(size 0.7874 0.5842)
					(thickness 0.1524)
				)
				(justify left)
			)
		)
		(property "Value" ""
			(at 0 0 0)
			(layer "F.Fab")
			(effects
				(font
					(size 1.27 1.27)
				)
			)
		)
		(duplicate_pad_numbers_are_jumpers no)
		(fp_line
			(start -4.249928 -0.484124)
			(end -4.249928 4.371848)
			(stroke
				(width 0.1524)
				(type default)
			)
			(layer "F.SilkS")
		)
		(fp_line
			(start -4.249928 6.022848)
			(end -4.249928 27.308048)
			(stroke
				(width 0.1524)
				(type default)
			)
			(layer "F.SilkS")
		)
		(fp_line
			(start -4.249928 29.59989)
			(end -1.90627 29.59989)
			(stroke
				(width 0.1524)
				(type default)
			)
			(layer "F.SilkS")
		)
		(fp_line
			(start -1.249934 -1.500124)
			(end 15.649956 -1.500124)
			(stroke
				(width 0.1524)
				(type default)
			)
			(layer "F.SilkS")
		)
		(fp_line
			(start -1.249934 26.599896)
			(end -1.249934 -0.484124)
			(stroke
				(width 0.1524)
				(type default)
			)
			(layer "F.SilkS")
		)
		(fp_line
			(start -0.63627 29.59989)
			(end 1.19253 29.59989)
			(stroke
				(width 0.1524)
				(type default)
			)
			(layer "F.SilkS")
		)
		(fp_line
			(start 0.2413 -0.9144)
			(end 1.2573 -0.9144)
			(stroke
				(width 0.1524)
				(type default)
			)
			(layer "F.SilkS")
		)
		(fp_line
			(start 0.7493 -1.4224)
			(end 0.2413 -0.9144)
			(stroke
				(width 0.1524)
				(type default)
			)
			(layer "F.SilkS")
		)
		(fp_line
			(start 0.7493 -1.4224)
			(end 0.7493 -0.5588)
			(stroke
				(width 0.1524)
				(type default)
			)
			(layer "F.SilkS")
		)
		(fp_line
			(start 0.7493 -0.5588)
			(end 2.0193 -0.5588)
			(stroke
				(width 0.1524)
				(type default)
			)
			(layer "F.SilkS")
		)
		(fp_line
			(start 1.2573 -0.9144)
			(end 0.7493 -1.4224)
			(stroke
				(width 0.1524)
				(type default)
			)
			(layer "F.SilkS")
		)
		(fp_line
			(start 2.0193 -0.5588)
			(end 2.2479 -0.7874)
			(stroke
				(width 0.1524)
				(type default)
			)
			(layer "F.SilkS")
		)
		(fp_line
			(start 2.46253 29.59989)
			(end 4.21513 29.59989)
			(stroke
				(width 0.1524)
				(type default)
			)
			(layer "F.SilkS")
		)
		(fp_line
			(start 5.53593 29.59989)
			(end 7.31393 29.59989)
			(stroke
				(width 0.1524)
				(type default)
			)
			(layer "F.SilkS")
		)
		(fp_line
			(start 8.60933 29.59989)
			(end 10.41273 29.59989)
			(stroke
				(width 0.1524)
				(type default)
			)
			(layer "F.SilkS")
		)
		(fp_line
			(start 11.68273 29.59989)
			(end 13.48613 29.59989)
			(stroke
				(width 0.1524)
				(type default)
			)
			(layer "F.SilkS")
		)
		(fp_line
			(start 14.70533 29.59989)
			(end 16.55953 29.59989)
			(stroke
				(width 0.1524)
				(type default)
			)
			(layer "F.SilkS")
		)
		(fp_line
			(start 15.649956 18.595848)
			(end 15.649956 26.599896)
			(stroke
				(width 0.1524)
				(type default)
			)
			(layer "F.SilkS")
		)
		(fp_line
			(start 15.649956 26.599896)
			(end -1.249934 26.599896)
			(stroke
				(width 0.1524)
				(type default)
			)
			(layer "F.SilkS")
		)
		(fp_line
			(start 17.80413 29.59989)
			(end 18.64995 29.59989)
			(stroke
				(width 0.1524)
				(type default)
			)
			(layer "F.SilkS")
		)
		(fp_line
			(start 18.64995 23.421848)
			(end 18.64995 16.820388)
			(stroke
				(width 0.1524)
				(type default)
			)
			(layer "F.SilkS")
		)
		(fp_line
			(start 18.64995 29.59989)
			(end 18.64995 26.596848)
			(stroke
				(width 0.1524)
				(type default)
			)
			(layer "F.SilkS")
		)
		(fp_poly
			(pts
				(xy -2.792222 -0.597662) (xy -1.596898 0) (xy -2.792222 0.597662)
			)
			(stroke
				(width 0)
				(type default)
			)
			(fill yes)
			(layer "F.SilkS")
		)
		(fp_line
			(start -4.249928 -11.999976)
			(end -4.249928 4.78028)
			(stroke
				(width 0.1524)
				(type default)
			)
			(layer "B.SilkS")
		)
		(fp_line
			(start -4.249928 5.933186)
			(end -4.249928 24.260048)
			(stroke
				(width 0.1524)
				(type default)
			)
			(layer "B.SilkS")
		)
		(fp_line
			(start -4.249928 26.266648)
			(end -4.249928 28.425648)
			(stroke
				(width 0.1524)
				(type default)
			)
			(layer "B.SilkS")
		)
		(fp_line
			(start -4.249928 29.59989)
			(end 18.64995 29.59989)
			(stroke
				(width 0.1524)
				(type default)
			)
			(layer "B.SilkS")
		)
		(fp_line
			(start 18.64995 -11.999976)
			(end -4.249928 -11.999976)
			(stroke
				(width 0.1524)
				(type default)
			)
			(layer "B.SilkS")
		)
		(fp_line
			(start 18.64995 -0.809752)
			(end 18.64995 -11.999976)
			(stroke
				(width 0.1524)
				(type default)
			)
			(layer "B.SilkS")
		)
		(fp_line
			(start 18.64995 29.59989)
			(end 18.64995 24.437848)
			(stroke
				(width 0.1524)
				(type default)
			)
			(layer "B.SilkS")
		)
		(fp_line
			(start -4.249928 -11.999976)
			(end -4.249928 29.59989)
			(stroke
				(width 0.1)
				(type default)
			)
			(layer "B.Fab")
		)
		(fp_line
			(start -4.249928 29.59989)
			(end 18.64995 29.59989)
			(stroke
				(width 0.1)
				(type default)
			)
			(layer "B.Fab")
		)
		(fp_line
			(start 18.64995 -11.999976)
			(end -4.249928 -11.999976)
			(stroke
				(width 0.1)
				(type default)
			)
			(layer "B.Fab")
		)
		(fp_line
			(start 18.64995 29.59989)
			(end 18.64995 -11.999976)
			(stroke
				(width 0.1)
				(type default)
			)
			(layer "B.Fab")
		)
		(fp_line
			(start -1.249934 -8.999982)
			(end 15.649956 -8.999982)
			(stroke
				(width 0.1)
				(type default)
			)
			(layer "F.Fab")
		)
		(fp_line
			(start -1.249934 26.599896)
			(end -1.249934 -8.999982)
			(stroke
				(width 0.1)
				(type default)
			)
			(layer "F.Fab")
		)
		(fp_line
			(start 15.649956 -8.999982)
			(end 15.649956 26.599896)
			(stroke
				(width 0.1)
				(type default)
			)
			(layer "F.Fab")
		)
		(fp_line
			(start 15.649956 26.599896)
			(end -1.249934 26.599896)
			(stroke
				(width 0.1)
				(type default)
			)
			(layer "F.Fab")
		)
		(fp_poly
			(pts
				(xy -1.596898 0) (xy -2.792222 0.597662) (xy -2.792222 -0.597662)
			)
			(stroke
				(width 0)
				(type default)
			)
			(fill yes)
			(layer "F.Fab")
		)
		(fp_text user "PRESS-FIT"
			(at -3.472942 22.658832 90)
			(unlocked yes)
			(layer "F.SilkS")
			(effects
				(font
					(size 0.7874 0.5842)
					(thickness 0.1524)
				)
				(justify left)
			)
		)
		(fp_text user "B"
			(at -2.1844 1.205484 0)
			(unlocked yes)
			(layer "F.SilkS")
			(effects
				(font
					(size 0.7874 0.5842)
					(thickness 0.1524)
				)
			)
		)
		(fp_text user "C"
			(at -2.1844 2.40538 0)
			(unlocked yes)
			(layer "F.SilkS")
			(effects
				(font
					(size 0.7874 0.5842)
					(thickness 0.1524)
				)
			)
		)
		(fp_text user "D"
			(at -2.1844 3.60553 0)
			(unlocked yes)
			(layer "F.SilkS")
			(effects
				(font
					(size 0.7874 0.5842)
					(thickness 0.1524)
				)
			)
		)
		(fp_text user "E"
			(at -2.1844 4.805426 0)
			(unlocked yes)
			(layer "F.SilkS")
			(effects
				(font
					(size 0.7874 0.5842)
					(thickness 0.1524)
				)
			)
		)
		(fp_text user "F"
			(at -2.1844 6.005576 0)
			(unlocked yes)
			(layer "F.SilkS")
			(effects
				(font
					(size 0.7874 0.5842)
					(thickness 0.1524)
				)
			)
		)
		(fp_text user "G"
			(at -2.1844 7.205472 0)
			(unlocked yes)
			(layer "F.SilkS")
			(effects
				(font
					(size 0.7874 0.5842)
					(thickness 0.1524)
				)
			)
		)
		(fp_text user "H"
			(at -2.1844 8.405622 0)
			(unlocked yes)
			(layer "F.SilkS")
			(effects
				(font
					(size 0.7874 0.5842)
					(thickness 0.1524)
				)
			)
		)
		(fp_text user "I"
			(at -2.1844 9.605518 0)
			(unlocked yes)
			(layer "F.SilkS")
			(effects
				(font
					(size 0.7874 0.5842)
					(thickness 0.1524)
				)
			)
		)
		(fp_text user "J"
			(at -2.1844 10.805414 0)
			(unlocked yes)
			(layer "F.SilkS")
			(effects
				(font
					(size 0.7874 0.5842)
					(thickness 0.1524)
				)
			)
		)
		(fp_text user "K"
			(at -2.1844 12.005564 0)
			(unlocked yes)
			(layer "F.SilkS")
			(effects
				(font
					(size 0.7874 0.5842)
					(thickness 0.1524)
				)
			)
		)
		(fp_text user "L"
			(at -2.1844 13.20546 0)
			(unlocked yes)
			(layer "F.SilkS")
			(effects
				(font
					(size 0.7874 0.5842)
					(thickness 0.1524)
				)
			)
		)
		(fp_text user "M"
			(at -2.1844 14.40561 0)
			(unlocked yes)
			(layer "F.SilkS")
			(effects
				(font
					(size 0.7874 0.5842)
					(thickness 0.1524)
				)
			)
		)
		(fp_text user "N"
			(at -2.1844 15.605506 0)
			(unlocked yes)
			(layer "F.SilkS")
			(effects
				(font
					(size 0.7874 0.5842)
					(thickness 0.1524)
				)
			)
		)
		(fp_text user "O"
			(at -2.1844 16.805402 0)
			(unlocked yes)
			(layer "F.SilkS")
			(effects
				(font
					(size 0.7874 0.5842)
					(thickness 0.1524)
				)
			)
		)
		(fp_text user "P"
			(at -2.1844 18.005552 0)
			(unlocked yes)
			(layer "F.SilkS")
			(effects
				(font
					(size 0.7874 0.5842)
					(thickness 0.1524)
				)
			)
		)
		(fp_text user "Q"
			(at -2.1844 19.205448 0)
			(unlocked yes)
			(layer "F.SilkS")
			(effects
				(font
					(size 0.7874 0.5842)
					(thickness 0.1524)
				)
			)
		)
		(fp_text user "R"
			(at -2.1844 20.405598 0)
			(unlocked yes)
			(layer "F.SilkS")
			(effects
				(font
					(size 0.7874 0.5842)
					(thickness 0.1524)
				)
			)
		)
		(fp_text user "S"
			(at -2.1844 21.605494 0)
			(unlocked yes)
			(layer "F.SilkS")
			(effects
				(font
					(size 0.7874 0.5842)
					(thickness 0.1524)
				)
			)
		)
		(fp_text user "T"
			(at -2.1844 22.80539 0)
			(unlocked yes)
			(layer "F.SilkS")
			(effects
				(font
					(size 0.7874 0.5842)
					(thickness 0.1524)
				)
			)
		)
		(fp_text user "1"
			(at 0 27.277568 0)
			(unlocked yes)
			(layer "F.SilkS")
			(effects
				(font
					(size 0.7874 0.5842)
					(thickness 0.1524)
				)
			)
		)
		(fp_text user "2"
			(at 1.999996 27.294586 0)
			(unlocked yes)
			(layer "F.SilkS")
			(effects
				(font
					(size 0.7874 0.5842)
					(thickness 0.1524)
				)
			)
		)
		(fp_text user "EDGE OF DAUGHTERCARD"
			(at 2.54 -0.886968 0)
			(unlocked yes)
			(layer "F.SilkS")
			(effects
				(font
					(size 0.635 0.4064)
					(thickness 0.1524)
				)
				(justify left)
			)
		)
		(fp_text user "3"
			(at 3.999992 27.277568 0)
			(unlocked yes)
			(layer "F.SilkS")
			(effects
				(font
					(size 0.7874 0.5842)
					(thickness 0.1524)
				)
			)
		)
		(fp_text user "4"
			(at 5.999988 27.294586 0)
			(unlocked yes)
			(layer "F.SilkS")
			(effects
				(font
					(size 0.7874 0.5842)
					(thickness 0.1524)
				)
			)
		)
		(fp_text user "5"
			(at 7.999984 27.277568 0)
			(unlocked yes)
			(layer "F.SilkS")
			(effects
				(font
					(size 0.7874 0.5842)
					(thickness 0.1524)
				)
			)
		)
		(fp_text user "6"
			(at 9.99998 27.294586 0)
			(unlocked yes)
			(layer "F.SilkS")
			(effects
				(font
					(size 0.7874 0.5842)
					(thickness 0.1524)
				)
			)
		)
		(fp_text user "7"
			(at 11.999976 27.277568 0)
			(unlocked yes)
			(layer "F.SilkS")
			(effects
				(font
					(size 0.7874 0.5842)
					(thickness 0.1524)
				)
			)
		)
		(fp_text user "8"
			(at 13.999972 27.294586 0)
			(unlocked yes)
			(layer "F.SilkS")
			(effects
				(font
					(size 0.7874 0.5842)
					(thickness 0.1524)
				)
			)
		)
		(fp_text user "PRESS-FIT"
			(at -2.81432 -0.530352 90)
			(unlocked yes)
			(layer "B.SilkS")
			(effects
				(font
					(size 1.905 1.4224)
					(thickness 0.1524)
				)
				(justify left mirror)
			)
		)
		(fp_text user "A"
			(at -1.13538 0.04953 0)
			(unlocked yes)
			(layer "B.SilkS")
			(effects
				(font
					(size 0.7874 0.5842)
					(thickness 0.1524)
				)
				(justify mirror)
			)
		)
		(fp_text user "B"
			(at -1.13538 1.24968 0)
			(unlocked yes)
			(layer "B.SilkS")
			(effects
				(font
					(size 0.7874 0.5842)
					(thickness 0.1524)
				)
				(justify mirror)
			)
		)
		(fp_text user "C"
			(at -1.13538 2.449576 0)
			(unlocked yes)
			(layer "B.SilkS")
			(effects
				(font
					(size 0.7874 0.5842)
					(thickness 0.1524)
				)
				(justify mirror)
			)
		)
		(fp_text user "D"
			(at -1.13538 3.649726 0)
			(unlocked yes)
			(layer "B.SilkS")
			(effects
				(font
					(size 0.7874 0.5842)
					(thickness 0.1524)
				)
				(justify mirror)
			)
		)
		(fp_text user "E"
			(at -1.13538 4.849622 0)
			(unlocked yes)
			(layer "B.SilkS")
			(effects
				(font
					(size 0.7874 0.5842)
					(thickness 0.1524)
				)
				(justify mirror)
			)
		)
		(fp_text user "F"
			(at -1.13538 6.049518 0)
			(unlocked yes)
			(layer "B.SilkS")
			(effects
				(font
					(size 0.7874 0.5842)
					(thickness 0.1524)
				)
				(justify mirror)
			)
		)
		(fp_text user "G"
			(at -1.13538 7.249668 0)
			(unlocked yes)
			(layer "B.SilkS")
			(effects
				(font
					(size 0.7874 0.5842)
					(thickness 0.1524)
				)
				(justify mirror)
			)
		)
		(fp_text user "H"
			(at -1.13538 8.449564 0)
			(unlocked yes)
			(layer "B.SilkS")
			(effects
				(font
					(size 0.7874 0.5842)
					(thickness 0.1524)
				)
				(justify mirror)
			)
		)
		(fp_text user "I"
			(at -1.13538 9.649714 0)
			(unlocked yes)
			(layer "B.SilkS")
			(effects
				(font
					(size 0.7874 0.5842)
					(thickness 0.1524)
				)
				(justify mirror)
			)
		)
		(fp_text user "J"
			(at -1.13538 10.84961 0)
			(unlocked yes)
			(layer "B.SilkS")
			(effects
				(font
					(size 0.7874 0.5842)
					(thickness 0.1524)
				)
				(justify mirror)
			)
		)
		(fp_text user "K"
			(at -1.13538 12.049506 0)
			(unlocked yes)
			(layer "B.SilkS")
			(effects
				(font
					(size 0.7874 0.5842)
					(thickness 0.1524)
				)
				(justify mirror)
			)
		)
		(fp_text user "L"
			(at -1.13538 13.249656 0)
			(unlocked yes)
			(layer "B.SilkS")
			(effects
				(font
					(size 0.7874 0.5842)
					(thickness 0.1524)
				)
				(justify mirror)
			)
		)
		(fp_text user "M"
			(at -1.13538 14.449552 0)
			(unlocked yes)
			(layer "B.SilkS")
			(effects
				(font
					(size 0.7874 0.5842)
					(thickness 0.1524)
				)
				(justify mirror)
			)
		)
		(fp_text user "N"
			(at -1.13538 15.649702 0)
			(unlocked yes)
			(layer "B.SilkS")
			(effects
				(font
					(size 0.7874 0.5842)
					(thickness 0.1524)
				)
				(justify mirror)
			)
		)
		(fp_text user "O"
			(at -1.13538 16.849598 0)
			(unlocked yes)
			(layer "B.SilkS")
			(effects
				(font
					(size 0.7874 0.5842)
					(thickness 0.1524)
				)
				(justify mirror)
			)
		)
		(fp_text user "P"
			(at -1.13538 18.049494 0)
			(unlocked yes)
			(layer "B.SilkS")
			(effects
				(font
					(size 0.7874 0.5842)
					(thickness 0.1524)
				)
				(justify mirror)
			)
		)
		(fp_text user "Q"
			(at -1.13538 19.249644 0)
			(unlocked yes)
			(layer "B.SilkS")
			(effects
				(font
					(size 0.7874 0.5842)
					(thickness 0.1524)
				)
				(justify mirror)
			)
		)
		(fp_text user "R"
			(at -1.13538 20.44954 0)
			(unlocked yes)
			(layer "B.SilkS")
			(effects
				(font
					(size 0.7874 0.5842)
					(thickness 0.1524)
				)
				(justify mirror)
			)
		)
		(fp_text user "S"
			(at -1.13538 21.64969 0)
			(unlocked yes)
			(layer "B.SilkS")
			(effects
				(font
					(size 0.7874 0.5842)
					(thickness 0.1524)
				)
				(justify mirror)
			)
		)
		(fp_text user "T"
			(at -1.13538 22.849586 0)
			(unlocked yes)
			(layer "B.SilkS")
			(effects
				(font
					(size 0.7874 0.5842)
					(thickness 0.1524)
				)
				(justify mirror)
			)
		)
		(fp_text user "1"
			(at 0.0254 24.127968 0)
			(unlocked yes)
			(layer "B.SilkS")
			(effects
				(font
					(size 0.7874 0.5842)
					(thickness 0.1524)
				)
				(justify mirror)
			)
		)
		(fp_text user "2"
			(at 2.025396 24.144986 0)
			(unlocked yes)
			(layer "B.SilkS")
			(effects
				(font
					(size 0.7874 0.5842)
					(thickness 0.1524)
				)
				(justify mirror)
			)
		)
		(fp_text user "3"
			(at 4.025392 24.127968 0)
			(unlocked yes)
			(layer "B.SilkS")
			(effects
				(font
					(size 0.7874 0.5842)
					(thickness 0.1524)
				)
				(justify mirror)
			)
		)
		(fp_text user "4"
			(at 6.025388 24.144986 0)
			(unlocked yes)
			(layer "B.SilkS")
			(effects
				(font
					(size 0.7874 0.5842)
					(thickness 0.1524)
				)
				(justify mirror)
			)
		)
		(fp_text user "5"
			(at 8.025384 24.127968 0)
			(unlocked yes)
			(layer "B.SilkS")
			(effects
				(font
					(size 0.7874 0.5842)
					(thickness 0.1524)
				)
				(justify mirror)
			)
		)
		(fp_text user "6"
			(at 10.02538 24.144986 0)
			(unlocked yes)
			(layer "B.SilkS")
			(effects
				(font
					(size 0.7874 0.5842)
					(thickness 0.1524)
				)
				(justify mirror)
			)
		)
		(fp_text user "7"
			(at 12.025376 24.127968 0)
			(unlocked yes)
			(layer "B.SilkS")
			(effects
				(font
					(size 0.7874 0.5842)
					(thickness 0.1524)
				)
				(justify mirror)
			)
		)
		(fp_text user "8"
			(at 13.48613 24.058118 0)
			(unlocked yes)
			(layer "B.SilkS")
			(effects
				(font
					(size 0.7874 0.5842)
					(thickness 0.1524)
				)
				(justify mirror)
			)
		)
		(fp_text user "A"
			(at -1.13538 0.04953 0)
			(unlocked yes)
			(layer "B.Fab")
			(effects
				(font
					(size 0.7874 0.5842)
					(thickness 0.1524)
				)
				(justify mirror)
			)
		)
		(fp_text user "B"
			(at -1.13538 1.24968 0)
			(unlocked yes)
			(layer "B.Fab")
			(effects
				(font
					(size 0.7874 0.5842)
					(thickness 0.1524)
				)
				(justify mirror)
			)
		)
		(fp_text user "C"
			(at -1.13538 2.449576 0)
			(unlocked yes)
			(layer "B.Fab")
			(effects
				(font
					(size 0.7874 0.5842)
					(thickness 0.1524)
				)
				(justify mirror)
			)
		)
		(fp_text user "D"
			(at -1.13538 3.649726 0)
			(unlocked yes)
			(layer "B.Fab")
			(effects
				(font
					(size 0.7874 0.5842)
					(thickness 0.1524)
				)
				(justify mirror)
			)
		)
		(fp_text user "E"
			(at -1.13538 4.849622 0)
			(unlocked yes)
			(layer "B.Fab")
			(effects
				(font
					(size 0.7874 0.5842)
					(thickness 0.1524)
				)
				(justify mirror)
			)
		)
		(fp_text user "F"
			(at -1.13538 6.049518 0)
			(unlocked yes)
			(layer "B.Fab")
			(effects
				(font
					(size 0.7874 0.5842)
					(thickness 0.1524)
				)
				(justify mirror)
			)
		)
		(fp_text user "G"
			(at -1.13538 7.249668 0)
			(unlocked yes)
			(layer "B.Fab")
			(effects
				(font
					(size 0.7874 0.5842)
					(thickness 0.1524)
				)
				(justify mirror)
			)
		)
		(fp_text user "H"
			(at -1.13538 8.449564 0)
			(unlocked yes)
			(layer "B.Fab")
			(effects
				(font
					(size 0.7874 0.5842)
					(thickness 0.1524)
				)
				(justify mirror)
			)
		)
		(fp_text user "I"
			(at -1.13538 9.649714 0)
			(unlocked yes)
			(layer "B.Fab")
			(effects
				(font
					(size 0.7874 0.5842)
					(thickness 0.1524)
				)
				(justify mirror)
			)
		)
		(fp_text user "J"
			(at -1.13538 10.84961 0)
			(unlocked yes)
			(layer "B.Fab")
			(effects
				(font
					(size 0.7874 0.5842)
					(thickness 0.1524)
				)
				(justify mirror)
			)
		)
		(fp_text user "K"
			(at -1.13538 12.049506 0)
			(unlocked yes)
			(layer "B.Fab")
			(effects
				(font
					(size 0.7874 0.5842)
					(thickness 0.1524)
				)
				(justify mirror)
			)
		)
		(fp_text user "L"
			(at -1.13538 13.249656 0)
			(unlocked yes)
			(layer "B.Fab")
			(effects
				(font
					(size 0.7874 0.5842)
					(thickness 0.1524)
				)
				(justify mirror)
			)
		)
		(fp_text user "M"
			(at -1.13538 14.449552 0)
			(unlocked yes)
			(layer "B.Fab")
			(effects
				(font
					(size 0.7874 0.5842)
					(thickness 0.1524)
				)
				(justify mirror)
			)
		)
		(fp_text user "N"
			(at -1.13538 15.649702 0)
			(unlocked yes)
			(layer "B.Fab")
			(effects
				(font
					(size 0.7874 0.5842)
					(thickness 0.1524)
				)
				(justify mirror)
			)
		)
		(fp_text user "O"
			(at -1.13538 16.849598 0)
			(unlocked yes)
			(layer "B.Fab")
			(effects
				(font
					(size 0.7874 0.5842)
					(thickness 0.1524)
				)
				(justify mirror)
			)
		)
		(fp_text user "P"
			(at -1.13538 18.049494 0)
			(unlocked yes)
			(layer "B.Fab")
			(effects
				(font
					(size 0.7874 0.5842)
					(thickness 0.1524)
				)
				(justify mirror)
			)
		)
		(fp_text user "Q"
			(at -1.13538 19.249644 0)
			(unlocked yes)
			(layer "B.Fab")
			(effects
				(font
					(size 0.7874 0.5842)
					(thickness 0.1524)
				)
				(justify mirror)
			)
		)
		(fp_text user "R"
			(at -1.13538 20.44954 0)
			(unlocked yes)
			(layer "B.Fab")
			(effects
				(font
					(size 0.7874 0.5842)
					(thickness 0.1524)
				)
				(justify mirror)
			)
		)
		(fp_text user "S"
			(at -1.13538 21.64969 0)
			(unlocked yes)
			(layer "B.Fab")
			(effects
				(font
					(size 0.7874 0.5842)
					(thickness 0.1524)
				)
				(justify mirror)
			)
		)
		(fp_text user "T"
			(at -1.13538 22.849586 0)
			(unlocked yes)
			(layer "B.Fab")
			(effects
				(font
					(size 0.7874 0.5842)
					(thickness 0.1524)
				)
				(justify mirror)
			)
		)
		(fp_text user "1"
			(at 0.0254 24.127968 0)
			(unlocked yes)
			(layer "B.Fab")
			(effects
				(font
					(size 0.7874 0.5842)
					(thickness 0.1524)
				)
				(justify mirror)
			)
		)
		(fp_text user "2"
			(at 2.025396 24.144986 0)
			(unlocked yes)
			(layer "B.Fab")
			(effects
				(font
					(size 0.7874 0.5842)
					(thickness 0.1524)
				)
				(justify mirror)
			)
		)
		(fp_text user "3"
			(at 4.025392 24.127968 0)
			(unlocked yes)
			(layer "B.Fab")
			(effects
				(font
					(size 0.7874 0.5842)
					(thickness 0.1524)
				)
				(justify mirror)
			)
		)
		(fp_text user "4"
			(at 6.025388 24.144986 0)
			(unlocked yes)
			(layer "B.Fab")
			(effects
				(font
					(size 0.7874 0.5842)
					(thickness 0.1524)
				)
				(justify mirror)
			)
		)
		(fp_text user "5"
			(at 8.025384 24.127968 0)
			(unlocked yes)
			(layer "B.Fab")
			(effects
				(font
					(size 0.7874 0.5842)
					(thickness 0.1524)
				)
				(justify mirror)
			)
		)
		(fp_text user "6"
			(at 10.02538 24.144986 0)
			(unlocked yes)
			(layer "B.Fab")
			(effects
				(font
					(size 0.7874 0.5842)
					(thickness 0.1524)
				)
				(justify mirror)
			)
		)
		(fp_text user "7"
			(at 12.025376 24.127968 0)
			(unlocked yes)
			(layer "B.Fab")
			(effects
				(font
					(size 0.7874 0.5842)
					(thickness 0.1524)
				)
				(justify mirror)
			)
		)
		(fp_text user "8"
			(at 14.025372 24.144986 0)
			(unlocked yes)
			(layer "B.Fab")
			(effects
				(font
					(size 0.7874 0.5842)
					(thickness 0.1524)
				)
				(justify mirror)
			)
		)
		(fp_text user "PRESS-FIT"
			(at 17.292828 3.961384 90)
			(unlocked yes)
			(layer "B.Fab")
			(effects
				(font
					(size 1.905 1.4224)
					(thickness 0.1524)
				)
				(justify left mirror)
			)
		)
		(fp_text user "B"
			(at -2.1844 1.205484 0)
			(unlocked yes)
			(layer "F.Fab")
			(effects
				(font
					(size 0.7874 0.5842)
					(thickness 0.1524)
				)
			)
		)
		(fp_text user "C"
			(at -2.1844 2.40538 0)
			(unlocked yes)
			(layer "F.Fab")
			(effects
				(font
					(size 0.7874 0.5842)
					(thickness 0.1524)
				)
			)
		)
		(fp_text user "D"
			(at -2.1844 3.60553 0)
			(unlocked yes)
			(layer "F.Fab")
			(effects
				(font
					(size 0.7874 0.5842)
					(thickness 0.1524)
				)
			)
		)
		(fp_text user "E"
			(at -2.1844 4.805426 0)
			(unlocked yes)
			(layer "F.Fab")
			(effects
				(font
					(size 0.7874 0.5842)
					(thickness 0.1524)
				)
			)
		)
		(fp_text user "F"
			(at -2.1844 6.005576 0)
			(unlocked yes)
			(layer "F.Fab")
			(effects
				(font
					(size 0.7874 0.5842)
					(thickness 0.1524)
				)
			)
		)
		(fp_text user "G"
			(at -2.1844 7.205472 0)
			(unlocked yes)
			(layer "F.Fab")
			(effects
				(font
					(size 0.7874 0.5842)
					(thickness 0.1524)
				)
			)
		)
		(fp_text user "H"
			(at -2.1844 8.405622 0)
			(unlocked yes)
			(layer "F.Fab")
			(effects
				(font
					(size 0.7874 0.5842)
					(thickness 0.1524)
				)
			)
		)
		(fp_text user "I"
			(at -2.1844 9.605518 0)
			(unlocked yes)
			(layer "F.Fab")
			(effects
				(font
					(size 0.7874 0.5842)
					(thickness 0.1524)
				)
			)
		)
		(fp_text user "J"
			(at -2.1844 10.805414 0)
			(unlocked yes)
			(layer "F.Fab")
			(effects
				(font
					(size 0.7874 0.5842)
					(thickness 0.1524)
				)
			)
		)
		(fp_text user "K"
			(at -2.1844 12.005564 0)
			(unlocked yes)
			(layer "F.Fab")
			(effects
				(font
					(size 0.7874 0.5842)
					(thickness 0.1524)
				)
			)
		)
		(fp_text user "L"
			(at -2.1844 13.20546 0)
			(unlocked yes)
			(layer "F.Fab")
			(effects
				(font
					(size 0.7874 0.5842)
					(thickness 0.1524)
				)
			)
		)
		(fp_text user "M"
			(at -2.1844 14.40561 0)
			(unlocked yes)
			(layer "F.Fab")
			(effects
				(font
					(size 0.7874 0.5842)
					(thickness 0.1524)
				)
			)
		)
		(fp_text user "N"
			(at -2.1844 15.605506 0)
			(unlocked yes)
			(layer "F.Fab")
			(effects
				(font
					(size 0.7874 0.5842)
					(thickness 0.1524)
				)
			)
		)
		(fp_text user "O"
			(at -2.1844 16.805402 0)
			(unlocked yes)
			(layer "F.Fab")
			(effects
				(font
					(size 0.7874 0.5842)
					(thickness 0.1524)
				)
			)
		)
		(fp_text user "P"
			(at -2.1844 18.005552 0)
			(unlocked yes)
			(layer "F.Fab")
			(effects
				(font
					(size 0.7874 0.5842)
					(thickness 0.1524)
				)
			)
		)
		(fp_text user "Q"
			(at -2.1844 19.205448 0)
			(unlocked yes)
			(layer "F.Fab")
			(effects
				(font
					(size 0.7874 0.5842)
					(thickness 0.1524)
				)
			)
		)
		(fp_text user "R"
			(at -2.1844 20.405598 0)
			(unlocked yes)
			(layer "F.Fab")
			(effects
				(font
					(size 0.7874 0.5842)
					(thickness 0.1524)
				)
			)
		)
		(fp_text user "S"
			(at -2.1844 21.605494 0)
			(unlocked yes)
			(layer "F.Fab")
			(effects
				(font
					(size 0.7874 0.5842)
					(thickness 0.1524)
				)
			)
		)
		(fp_text user "T"
			(at -2.1844 22.80539 0)
			(unlocked yes)
			(layer "F.Fab")
			(effects
				(font
					(size 0.7874 0.5842)
					(thickness 0.1524)
				)
			)
		)
		(fp_text user "1"
			(at 0 27.277568 0)
			(unlocked yes)
			(layer "F.Fab")
			(effects
				(font
					(size 0.7874 0.5842)
					(thickness 0.1524)
				)
			)
		)
		(fp_text user "2"
			(at 1.999996 27.294586 0)
			(unlocked yes)
			(layer "F.Fab")
			(effects
				(font
					(size 0.7874 0.5842)
					(thickness 0.1524)
				)
			)
		)
		(fp_text user "3"
			(at 3.999992 27.277568 0)
			(unlocked yes)
			(layer "F.Fab")
			(effects
				(font
					(size 0.7874 0.5842)
					(thickness 0.1524)
				)
			)
		)
		(fp_text user "4"
			(at 5.999988 27.294586 0)
			(unlocked yes)
			(layer "F.Fab")
			(effects
				(font
					(size 0.7874 0.5842)
					(thickness 0.1524)
				)
			)
		)
		(fp_text user "5"
			(at 7.999984 27.277568 0)
			(unlocked yes)
			(layer "F.Fab")
			(effects
				(font
					(size 0.7874 0.5842)
					(thickness 0.1524)
				)
			)
		)
		(fp_text user "6"
			(at 9.99998 27.294586 0)
			(unlocked yes)
			(layer "F.Fab")
			(effects
				(font
					(size 0.7874 0.5842)
					(thickness 0.1524)
				)
			)
		)
		(fp_text user "7"
			(at 11.999976 27.277568 0)
			(unlocked yes)
			(layer "F.Fab")
			(effects
				(font
					(size 0.7874 0.5842)
					(thickness 0.1524)
				)
			)
		)
		(fp_text user "8"
			(at 13.999972 27.294586 0)
			(unlocked yes)
			(layer "F.Fab")
			(effects
				(font
					(size 0.7874 0.5842)
					(thickness 0.1524)
				)
			)
		)
		(fp_text user "PRESS-FIT"
			(at 17.229328 20.636484 90)
			(unlocked yes)
			(layer "F.Fab")
			(effects
				(font
					(size 1.905 1.4224)
					(thickness 0.1524)
				)
				(justify left)
			)
		)
		(pad "A1" thru_hole rect
			(at 0 0 180)
			(size 0.766318 0.766318)
			(drill 0.359918)
			(layers "*.Cu" "*.Mask")
			(remove_unused_layers no)
			(net "RST_PERST_2_SWB_BUF_N")
			(clearance 0.0508)
			(thermal_gap 0.0508)
			(padstack
				(mode front_inner_back)
				(layer "Inner"
					(shape circle)
					(size 0.766318 0.766318)
					(clearance 0.0508)
				)
				(layer "B.Cu"
					(shape rect)
					(size 0.766318 0.766318)
					(clearance 0.0508)
				)
			)
		)
		(pad "A2" thru_hole circle
			(at 1.999996 0.199898 180)
			(size 0.906272 0.906272)
			(drill 0.499872)
			(layers "*.Cu" "*.Mask")
			(remove_unused_layers no)
			(net "GND")
			(clearance 0.0508)
			(thermal_gap 0.0508)
		)
		(pad "A3" thru_hole circle
			(at 3.999992 0 180)
			(size 0.766318 0.766318)
			(drill 0.359918)
			(layers "*.Cu" "*.Mask")
			(remove_unused_layers no)
			(net "HGX_DETECT_N_ISO")
			(clearance 0.0508)
			(thermal_gap 0.0508)
		)
		(pad "A4" thru_hole circle
			(at 5.999988 0.199898 180)
			(size 0.906272 0.906272)
			(drill 0.499872)
			(layers "*.Cu" "*.Mask")
			(remove_unused_layers no)
			(net "GND")
			(clearance 0.0508)
			(thermal_gap 0.0508)
		)
		(pad "A5" thru_hole circle
			(at 7.999984 0 180)
			(size 0.766318 0.766318)
			(drill 0.359918)
			(layers "*.Cu" "*.Mask")
			(remove_unused_layers no)
			(net "RST_PERST_1_SWB_BUF_N")
			(clearance 0.0508)
			(thermal_gap 0.0508)
		)
		(pad "A6" thru_hole circle
			(at 9.99998 0.199898 180)
			(size 0.906272 0.906272)
			(drill 0.499872)
			(layers "*.Cu" "*.Mask")
			(remove_unused_layers no)
			(net "GND")
			(clearance 0.0508)
			(thermal_gap 0.0508)
		)
		(pad "A7" thru_hole circle
			(at 11.999976 0 180)
			(size 0.766318 0.766318)
			(drill 0.359918)
			(layers "*.Cu" "*.Mask")
			(remove_unused_layers no)
			(net "PRSNT_SWB_N")
			(clearance 0.0508)
			(thermal_gap 0.0508)
		)
		(pad "A8" thru_hole circle
			(at 13.999972 0.199898 180)
			(size 0.906272 0.906272)
			(drill 0.499872)
			(layers "*.Cu" "*.Mask")
			(remove_unused_layers no)
			(net "GND")
			(clearance 0.0508)
			(thermal_gap 0.0508)
		)
		(pad "B1" thru_hole circle
			(at 0 1.199896 180)
			(size 0.906272 0.906272)
			(drill 0.499872)
			(layers "*.Cu" "*.Mask")
			(remove_unused_layers no)
			(net "GND")
			(clearance 0.0508)
			(thermal_gap 0.0508)
		)
		(pad "B3" thru_hole circle
			(at 3.999992 1.199896 180)
			(size 0.906272 0.906272)
			(drill 0.499872)
			(layers "*.Cu" "*.Mask")
			(remove_unused_layers no)
			(net "GND")
			(clearance 0.0508)
			(thermal_gap 0.0508)
		)
		(pad "B5" thru_hole circle
			(at 7.999984 1.199896 180)
			(size 0.906272 0.906272)
			(drill 0.499872)
			(layers "*.Cu" "*.Mask")
			(remove_unused_layers no)
			(net "GND")
			(clearance 0.0508)
			(thermal_gap 0.0508)
		)
		(pad "B7" thru_hole circle
			(at 11.999976 1.199896 180)
			(size 0.906272 0.906272)
			(drill 0.499872)
			(layers "*.Cu" "*.Mask")
			(remove_unused_layers no)
			(net "GND")
			(clearance 0.0508)
			(thermal_gap 0.0508)
		)
		(pad "D2" thru_hole circle
			(at 1.999996 3.800094 180)
			(size 0.906272 0.906272)
			(drill 0.499872)
			(layers "*.Cu" "*.Mask")
			(remove_unused_layers no)
			(net "GND")
			(clearance 0.0508)
			(thermal_gap 0.0508)
		)
		(pad "D4" thru_hole circle
			(at 5.999988 3.800094 180)
			(size 0.906272 0.906272)
			(drill 0.499872)
			(layers "*.Cu" "*.Mask")
			(remove_unused_layers no)
			(net "GND")
			(clearance 0.0508)
			(thermal_gap 0.0508)
		)
		(pad "D6" thru_hole circle
			(at 9.99998 3.800094 180)
			(size 0.906272 0.906272)
			(drill 0.499872)
			(layers "*.Cu" "*.Mask")
			(remove_unused_layers no)
			(net "GND")
			(clearance 0.0508)
			(thermal_gap 0.0508)
		)
		(pad "D8" thru_hole circle
			(at 13.999972 3.800094 180)
			(size 0.906272 0.906272)
			(drill 0.499872)
			(layers "*.Cu" "*.Mask")
			(remove_unused_layers no)
			(net "GND")
			(clearance 0.0508)
			(thermal_gap 0.0508)
		)
		(pad "E1" thru_hole circle
			(at 0 4.800092 180)
			(size 0.906272 0.906272)
			(drill 0.499872)
			(layers "*.Cu" "*.Mask")
			(remove_unused_layers no)
			(net "GND")
			(clearance 0.0508)
			(thermal_gap 0.0508)
		)
		(pad "E3" thru_hole circle
			(at 3.999992 4.800092 180)
			(size 0.906272 0.906272)
			(drill 0.499872)
			(layers "*.Cu" "*.Mask")
			(remove_unused_layers no)
			(net "GND")
			(clearance 0.0508)
			(thermal_gap 0.0508)
		)
		(pad "E5" thru_hole circle
			(at 7.999984 4.800092 180)
			(size 0.906272 0.906272)
			(drill 0.499872)
			(layers "*.Cu" "*.Mask")
			(remove_unused_layers no)
			(net "GND")
			(clearance 0.0508)
			(thermal_gap 0.0508)
		)
		(pad "E7" thru_hole circle
			(at 11.999976 4.800092 180)
			(size 0.906272 0.906272)
			(drill 0.499872)
			(layers "*.Cu" "*.Mask")
			(remove_unused_layers no)
			(net "GND")
			(clearance 0.0508)
			(thermal_gap 0.0508)
		)
		(pad "G2" thru_hole circle
			(at 1.999996 7.400036 180)
			(size 0.906272 0.906272)
			(drill 0.499872)
			(layers "*.Cu" "*.Mask")
			(remove_unused_layers no)
			(net "GND")
			(clearance 0.0508)
			(thermal_gap 0.0508)
		)
		(pad "G4" thru_hole circle
			(at 5.999988 7.400036 180)
			(size 0.906272 0.906272)
			(drill 0.499872)
			(layers "*.Cu" "*.Mask")
			(remove_unused_layers no)
			(net "GND")
			(clearance 0.0508)
			(thermal_gap 0.0508)
		)
		(pad "G6" thru_hole circle
			(at 9.99998 7.400036 180)
			(size 0.906272 0.906272)
			(drill 0.499872)
			(layers "*.Cu" "*.Mask")
			(remove_unused_layers no)
			(net "GND")
			(clearance 0.0508)
			(thermal_gap 0.0508)
		)
		(pad "G8" thru_hole circle
			(at 13.999972 7.400036 180)
			(size 0.906272 0.906272)
			(drill 0.499872)
			(layers "*.Cu" "*.Mask")
			(remove_unused_layers no)
			(net "GND")
			(clearance 0.0508)
			(thermal_gap 0.0508)
		)
		(pad "H1" thru_hole circle
			(at 0 8.400034 180)
			(size 0.906272 0.906272)
			(drill 0.499872)
			(layers "*.Cu" "*.Mask")
			(remove_unused_layers no)
			(net "GND")
			(clearance 0.0508)
			(thermal_gap 0.0508)
		)
		(pad "H3" thru_hole circle
			(at 3.999992 8.400034 180)
			(size 0.906272 0.906272)
			(drill 0.499872)
			(layers "*.Cu" "*.Mask")
			(remove_unused_layers no)
			(net "GND")
			(clearance 0.0508)
			(thermal_gap 0.0508)
		)
		(pad "H5" thru_hole circle
			(at 7.999984 8.400034 180)
			(size 0.906272 0.906272)
			(drill 0.499872)
			(layers "*.Cu" "*.Mask")
			(remove_unused_layers no)
			(net "GND")
			(clearance 0.0508)
			(thermal_gap 0.0508)
		)
		(pad "H7" thru_hole circle
			(at 11.999976 8.400034 180)
			(size 0.906272 0.906272)
			(drill 0.499872)
			(layers "*.Cu" "*.Mask")
			(remove_unused_layers no)
			(net "GND")
			(clearance 0.0508)
			(thermal_gap 0.0508)
		)
		(pad "J2" thru_hole circle
			(at 1.999996 10.999978 180)
			(size 0.906272 0.906272)
			(drill 0.499872)
			(layers "*.Cu" "*.Mask")
			(remove_unused_layers no)
			(net "GND")
			(clearance 0.0508)
			(thermal_gap 0.0508)
		)
		(pad "J4" thru_hole circle
			(at 5.999988 10.999978 180)
			(size 0.906272 0.906272)
			(drill 0.499872)
			(layers "*.Cu" "*.Mask")
			(remove_unused_layers no)
			(net "GND")
			(clearance 0.0508)
			(thermal_gap 0.0508)
		)
		(pad "J6" thru_hole circle
			(at 9.99998 10.999978 180)
			(size 0.906272 0.906272)
			(drill 0.499872)
			(layers "*.Cu" "*.Mask")
			(remove_unused_layers no)
			(net "GND")
			(clearance 0.0508)
			(thermal_gap 0.0508)
		)
		(pad "J8" thru_hole circle
			(at 13.999972 10.999978 180)
			(size 0.906272 0.906272)
			(drill 0.499872)
			(layers "*.Cu" "*.Mask")
			(remove_unused_layers no)
			(net "GND")
			(clearance 0.0508)
			(thermal_gap 0.0508)
		)
		(pad "K1" thru_hole circle
			(at 0 11.999976 180)
			(size 0.906272 0.906272)
			(drill 0.499872)
			(layers "*.Cu" "*.Mask")
			(remove_unused_layers no)
			(net "GND")
			(clearance 0.0508)
			(thermal_gap 0.0508)
		)
		(pad "K3" thru_hole circle
			(at 3.999992 11.999976 180)
			(size 0.906272 0.906272)
			(drill 0.499872)
			(layers "*.Cu" "*.Mask")
			(remove_unused_layers no)
			(net "GND")
			(clearance 0.0508)
			(thermal_gap 0.0508)
		)
		(pad "K5" thru_hole circle
			(at 7.999984 11.999976 180)
			(size 0.906272 0.906272)
			(drill 0.499872)
			(layers "*.Cu" "*.Mask")
			(remove_unused_layers no)
			(net "GND")
			(clearance 0.0508)
			(thermal_gap 0.0508)
		)
		(pad "K7" thru_hole circle
			(at 11.999976 11.999976 180)
			(size 0.906272 0.906272)
			(drill 0.499872)
			(layers "*.Cu" "*.Mask")
			(remove_unused_layers no)
			(net "GND")
			(clearance 0.0508)
			(thermal_gap 0.0508)
		)
		(pad "M2" thru_hole circle
			(at 1.999996 14.59992 180)
			(size 0.906272 0.906272)
			(drill 0.499872)
			(layers "*.Cu" "*.Mask")
			(remove_unused_layers no)
			(net "GND")
			(clearance 0.0508)
			(thermal_gap 0.0508)
		)
		(pad "M4" thru_hole circle
			(at 5.999988 14.59992 180)
			(size 0.906272 0.906272)
			(drill 0.499872)
			(layers "*.Cu" "*.Mask")
			(remove_unused_layers no)
			(net "GND")
			(clearance 0.0508)
			(thermal_gap 0.0508)
		)
		(pad "M6" thru_hole circle
			(at 9.99998 14.59992 180)
			(size 0.906272 0.906272)
			(drill 0.499872)
			(layers "*.Cu" "*.Mask")
			(remove_unused_layers no)
			(net "GND")
			(clearance 0.0508)
			(thermal_gap 0.0508)
		)
		(pad "M8" thru_hole circle
			(at 13.999972 14.59992 180)
			(size 0.906272 0.906272)
			(drill 0.499872)
			(layers "*.Cu" "*.Mask")
			(remove_unused_layers no)
			(net "GND")
			(clearance 0.0508)
			(thermal_gap 0.0508)
		)
		(pad "N1" thru_hole circle
			(at 0 15.599918 180)
			(size 0.906272 0.906272)
			(drill 0.499872)
			(layers "*.Cu" "*.Mask")
			(remove_unused_layers no)
			(net "GND")
			(clearance 0.0508)
			(thermal_gap 0.0508)
		)
		(pad "N2" thru_hole circle
			(at 1.999996 15.80007 180)
			(size 0.766318 0.766318)
			(drill 0.359918)
			(layers "*.Cu" "*.Mask")
			(remove_unused_layers no)
			(net "NC_J112_N2")
			(clearance 0.0508)
			(thermal_gap 0.0508)
		)
		(pad "N3" thru_hole circle
			(at 3.999992 15.599918 180)
			(size 0.906272 0.906272)
			(drill 0.499872)
			(layers "*.Cu" "*.Mask")
			(remove_unused_layers no)
			(net "GND")
			(clearance 0.0508)
			(thermal_gap 0.0508)
		)
		(pad "N5" thru_hole circle
			(at 7.999984 15.599918 180)
			(size 0.906272 0.906272)
			(drill 0.499872)
			(layers "*.Cu" "*.Mask")
			(remove_unused_layers no)
			(net "GND")
			(clearance 0.0508)
			(thermal_gap 0.0508)
		)
		(pad "N7" thru_hole circle
			(at 11.999976 15.599918 180)
			(size 0.906272 0.906272)
			(drill 0.499872)
			(layers "*.Cu" "*.Mask")
			(remove_unused_layers no)
			(net "GND")
			(clearance 0.0508)
			(thermal_gap 0.0508)
		)
		(pad "O2" thru_hole circle
			(at 1.999996 16.999966 180)
			(size 0.766318 0.766318)
			(drill 0.359918)
			(layers "*.Cu" "*.Mask")
			(remove_unused_layers no)
			(net "NC_J112_O2")
			(clearance 0.0508)
			(thermal_gap 0.0508)
		)
		(pad "O5" thru_hole circle
			(at 7.999984 16.800068 180)
			(size 0.766318 0.766318)
			(drill 0.359918)
			(layers "*.Cu" "*.Mask")
			(remove_unused_layers no)
			(net "NC_J112_O5")
			(clearance 0.0508)
			(thermal_gap 0.0508)
		)
		(pad "P2" thru_hole circle
			(at 1.999996 18.200116 180)
			(size 0.906272 0.906272)
			(drill 0.499872)
			(layers "*.Cu" "*.Mask")
			(remove_unused_layers no)
			(net "GND")
			(clearance 0.0508)
			(thermal_gap 0.0508)
		)
		(pad "P4" thru_hole circle
			(at 5.999988 18.200116 180)
			(size 0.906272 0.906272)
			(drill 0.499872)
			(layers "*.Cu" "*.Mask")
			(remove_unused_layers no)
			(net "GND")
			(clearance 0.0508)
			(thermal_gap 0.0508)
		)
		(pad "P5" thru_hole circle
			(at 7.999984 17.999964 180)
			(size 0.766318 0.766318)
			(drill 0.359918)
			(layers "*.Cu" "*.Mask")
			(remove_unused_layers no)
			(net "NC_J112_P5")
			(clearance 0.0508)
			(thermal_gap 0.0508)
		)
		(pad "P6" thru_hole circle
			(at 9.99998 18.200116 180)
			(size 0.906272 0.906272)
			(drill 0.499872)
			(layers "*.Cu" "*.Mask")
			(remove_unused_layers no)
			(net "GND")
			(clearance 0.0508)
			(thermal_gap 0.0508)
		)
		(pad "P8" thru_hole circle
			(at 13.999972 18.200116 180)
			(size 0.906272 0.906272)
			(drill 0.499872)
			(layers "*.Cu" "*.Mask")
			(remove_unused_layers no)
			(net "GND")
			(clearance 0.0508)
			(thermal_gap 0.0508)
		)
		(pad "Q1" thru_hole circle
			(at 0 19.200114 180)
			(size 0.906272 0.906272)
			(drill 0.499872)
			(layers "*.Cu" "*.Mask")
			(remove_unused_layers no)
			(net "GND")
			(clearance 0.0508)
			(thermal_gap 0.0508)
		)
		(pad "Q3" thru_hole circle
			(at 3.999992 19.200114 180)
			(size 0.906272 0.906272)
			(drill 0.499872)
			(layers "*.Cu" "*.Mask")
			(remove_unused_layers no)
			(net "GND")
			(clearance 0.0508)
			(thermal_gap 0.0508)
		)
		(pad "Q4" thru_hole circle
			(at 5.999988 19.400012 180)
			(size 0.766318 0.766318)
			(drill 0.359918)
			(layers "*.Cu" "*.Mask")
			(remove_unused_layers no)
			(net "SMB_1_BMC_GPU_BUF_SCL")
			(clearance 0.0508)
			(thermal_gap 0.0508)
		)
		(pad "Q5" thru_hole circle
			(at 7.999984 19.200114 180)
			(size 0.906272 0.906272)
			(drill 0.499872)
			(layers "*.Cu" "*.Mask")
			(remove_unused_layers no)
			(net "GND")
			(clearance 0.0508)
			(thermal_gap 0.0508)
		)
		(pad "Q7" thru_hole circle
			(at 11.999976 19.200114 180)
			(size 0.906272 0.906272)
			(drill 0.499872)
			(layers "*.Cu" "*.Mask")
			(remove_unused_layers no)
			(net "GND")
			(clearance 0.0508)
			(thermal_gap 0.0508)
		)
		(pad "R3" thru_hole circle
			(at 3.999992 20.40001 180)
			(size 0.766318 0.766318)
			(drill 0.359918)
			(layers "*.Cu" "*.Mask")
			(remove_unused_layers no)
			(net "SMB_2_BMC_GPU_BUF_SCL")
			(clearance 0.0508)
			(thermal_gap 0.0508)
		)
		(pad "R4" thru_hole circle
			(at 5.999988 20.599908 180)
			(size 0.766318 0.766318)
			(drill 0.359918)
			(layers "*.Cu" "*.Mask")
			(remove_unused_layers no)
			(net "SMB_1_BMC_GPU_BUF_SDA")
			(clearance 0.0508)
			(thermal_gap 0.0508)
		)
		(pad "R5" thru_hole circle
			(at 7.999984 20.40001 180)
			(size 0.766318 0.766318)
			(drill 0.359918)
			(layers "*.Cu" "*.Mask")
			(remove_unused_layers no)
			(net "NC_J112_R5")
			(clearance 0.0508)
			(thermal_gap 0.0508)
		)
		(pad "S2" thru_hole circle
			(at 1.999996 21.800058 180)
			(size 0.906272 0.906272)
			(drill 0.499872)
			(layers "*.Cu" "*.Mask")
			(remove_unused_layers no)
			(net "GND")
			(clearance 0.0508)
			(thermal_gap 0.0508)
		)
		(pad "S3" thru_hole circle
			(at 3.999992 21.599906 180)
			(size 0.766318 0.766318)
			(drill 0.359918)
			(layers "*.Cu" "*.Mask")
			(remove_unused_layers no)
			(net "SMB_2_BMC_GPU_BUF_SDA")
			(clearance 0.0508)
			(thermal_gap 0.0508)
		)
		(pad "S4" thru_hole circle
			(at 5.999988 21.800058 180)
			(size 0.906272 0.906272)
			(drill 0.499872)
			(layers "*.Cu" "*.Mask")
			(remove_unused_layers no)
			(net "GND")
			(clearance 0.0508)
			(thermal_gap 0.0508)
		)
		(pad "S5" thru_hole circle
			(at 7.999984 21.599906 180)
			(size 0.766318 0.766318)
			(drill 0.359918)
			(layers "*.Cu" "*.Mask")
			(remove_unused_layers no)
			(net "NC_J112_S5")
			(clearance 0.0508)
			(thermal_gap 0.0508)
		)
		(pad "S6" thru_hole circle
			(at 9.99998 21.800058 180)
			(size 0.906272 0.906272)
			(drill 0.499872)
			(layers "*.Cu" "*.Mask")
			(remove_unused_layers no)
			(net "GND")
			(clearance 0.0508)
			(thermal_gap 0.0508)
		)
		(pad "S8" thru_hole circle
			(at 13.999972 21.800058 180)
			(size 0.906272 0.906272)
			(drill 0.499872)
			(layers "*.Cu" "*.Mask")
			(remove_unused_layers no)
			(net "GND")
			(clearance 0.0508)
			(thermal_gap 0.0508)
		)
		(pad "T1" thru_hole circle
			(at 0 22.800056 180)
			(size 0.906272 0.906272)
			(drill 0.499872)
			(layers "*.Cu" "*.Mask")
			(remove_unused_layers no)
			(net "GND")
			(clearance 0.0508)
			(thermal_gap 0.0508)
		)
		(pad "T2" thru_hole circle
			(at 1.999996 22.999954 180)
			(size 0.766318 0.766318)
			(drill 0.359918)
			(layers "*.Cu" "*.Mask")
			(remove_unused_layers no)
			(net "GPU_FPGA_READY")
			(clearance 0.0508)
			(thermal_gap 0.0508)
		)
		(pad "T3" thru_hole circle
			(at 3.999992 22.800056 180)
			(size 0.906272 0.906272)
			(drill 0.499872)
			(layers "*.Cu" "*.Mask")
			(remove_unused_layers no)
			(net "GND")
			(clearance 0.0508)
			(thermal_gap 0.0508)
		)
		(pad "T4" thru_hole circle
			(at 5.999988 22.999954 180)
			(size 0.766318 0.766318)
			(drill 0.359918)
			(layers "*.Cu" "*.Mask")
			(remove_unused_layers no)
			(net "GPU_NVS_PWR_BRAKE_N_BUF")
			(clearance 0.0508)
			(thermal_gap 0.0508)
		)
		(pad "T5" thru_hole circle
			(at 7.999984 22.800056 180)
			(size 0.906272 0.906272)
			(drill 0.499872)
			(layers "*.Cu" "*.Mask")
			(remove_unused_layers no)
			(net "GND")
			(clearance 0.0508)
			(thermal_gap 0.0508)
		)
		(pad "T6" thru_hole circle
			(at 9.99998 22.999954 180)
			(size 0.766318 0.766318)
			(drill 0.359918)
			(layers "*.Cu" "*.Mask")
			(remove_unused_layers no)
			(net "GPU_FPGA_THERM_OVERT_N")
			(clearance 0.0508)
			(thermal_gap 0.0508)
		)
		(pad "T7" thru_hole circle
			(at 11.999976 22.800056 180)
			(size 0.906272 0.906272)
			(drill 0.499872)
			(layers "*.Cu" "*.Mask")
			(remove_unused_layers no)
			(net "GND")
			(clearance 0.0508)
			(thermal_gap 0.0508)
		)
		(pad "T8" thru_hole circle
			(at 13.999972 22.999954 180)
			(size 0.766318 0.766318)
			(drill 0.359918)
			(layers "*.Cu" "*.Mask")
			(remove_unused_layers no)
			(net "RST_PERST_0_SWB_BUF_N")
			(clearance 0.0508)
			(thermal_gap 0.0508)
		)
		(zone
			(layer "B.Cu")
			(hatch none 0.5)
			(connect_pads
				(clearance 0)
			)
			(min_thickness 0.25)
			(keepout
				(tracks allowed)
				(vias not_allowed)
				(pads allowed)
				(copperpour not_allowed)
				(footprints allowed)
			)
			(placement
				(enabled no)
				(sheetname "")
			)
			(fill
				(thermal_gap 0.5)
				(thermal_bridge_width 0.5)
				(island_removal_mode 0)
			)
			(polygon
				(pts
					(xy 58.14187 -417.033964) (xy 73.17867 -417.033964) (xy 73.17867 -440.935364) (xy 58.14187 -440.935364)
				)
			)
		)
	)
	(footprint ""
		(layer "F.Cu")
		(at 420.246302 -438.234836 -90)
		(property "Reference" "C1772"
			(at 0 0 270)
			(layer "F.SilkS")
			(hide yes)
			(effects
				(font
					(size 1.27 1.27)
				)
			)
		)
		(property "Value" ""
			(at 0 0 270)
			(layer "F.Fab")
			(effects
				(font
					(size 1.27 1.27)
				)
			)
		)
		(duplicate_pad_numbers_are_jumpers no)
		(fp_line
			(start -0.7874 0.4064)
			(end -0.7874 -0.4064)
			(stroke
				(width 0.1524)
				(type default)
			)
			(layer "F.SilkS")
		)
		(fp_line
			(start 0.7874 0.4064)
			(end -0.7874 0.4064)
			(stroke
				(width 0.1524)
				(type default)
			)
			(layer "F.SilkS")
		)
		(fp_line
			(start -0.7874 -0.4064)
			(end 0.7874 -0.4064)
			(stroke
				(width 0.1524)
				(type default)
			)
			(layer "F.SilkS")
		)
		(fp_line
			(start 0.7874 -0.4064)
			(end 0.7874 0.4064)
			(stroke
				(width 0.1524)
				(type default)
			)
			(layer "F.SilkS")
		)
		(fp_line
			(start -0.67945 0.3048)
			(end -0.67945 -0.305054)
			(stroke
				(width 0.1)
				(type default)
			)
			(layer "F.Fab")
		)
		(fp_line
			(start -0.12065 0.3048)
			(end -0.67945 0.3048)
			(stroke
				(width 0.1)
				(type default)
			)
			(layer "F.Fab")
		)
		(fp_line
			(start 0.120396 0.3048)
			(end 0.120396 0.2794)
			(stroke
				(width 0.1)
				(type default)
			)
			(layer "F.Fab")
		)
		(fp_line
			(start 0.67945 0.3048)
			(end 0.120396 0.3048)
			(stroke
				(width 0.1)
				(type default)
			)
			(layer "F.Fab")
		)
		(fp_line
			(start -0.12065 0.2794)
			(end -0.12065 0.3048)
			(stroke
				(width 0.1)
				(type default)
			)
			(layer "F.Fab")
		)
		(fp_line
			(start 0.120396 0.2794)
			(end -0.12065 0.2794)
			(stroke
				(width 0.1)
				(type default)
			)
			(layer "F.Fab")
		)
		(fp_line
			(start -0.12065 -0.2794)
			(end 0.12065 -0.2794)
			(stroke
				(width 0.1)
				(type default)
			)
			(layer "F.Fab")
		)
		(fp_line
			(start 0.12065 -0.2794)
			(end 0.12065 -0.3048)
			(stroke
				(width 0.1)
				(type default)
			)
			(layer "F.Fab")
		)
		(fp_line
			(start 0.12065 -0.3048)
			(end 0.67945 -0.3048)
			(stroke
				(width 0.1)
				(type default)
			)
			(layer "F.Fab")
		)
		(fp_line
			(start 0.67945 -0.3048)
			(end 0.67945 0.3048)
			(stroke
				(width 0.1)
				(type default)
			)
			(layer "F.Fab")
		)
		(fp_line
			(start -0.67945 -0.305054)
			(end -0.12065 -0.305054)
			(stroke
				(width 0.1)
				(type default)
			)
			(layer "F.Fab")
		)
		(fp_line
			(start -0.12065 -0.305054)
			(end -0.12065 -0.2794)
			(stroke
				(width 0.1)
				(type default)
			)
			(layer "F.Fab")
		)
		(pad "1" smd circle
			(at -0.40005 0 270)
			(size 0 0)
			(layers "F.Cu" "F.Mask" "F.Paste")
			(net "RST_BMC_FROM_SWB_ISO_N")
		)
		(pad "2" smd circle
			(at 0.40005 0 270)
			(size 0 0)
			(layers "F.Cu" "F.Mask" "F.Paste")
			(net "GND")
		)
	)
	(footprint ""
		(layer "F.Cu")
		(at 380.960122 -192.061084 180)
		(property "Reference" "PL59"
			(at -12.840716 3.143758 90)
			(unlocked yes)
			(layer "F.SilkS")
			(effects
				(font
					(size 0.7874 0.5842)
					(thickness 0.1524)
				)
				(justify left)
			)
		)
		(property "Value" ""
			(at 0 0 180)
			(layer "F.Fab")
			(effects
				(font
					(size 1.27 1.27)
				)
			)
		)
		(duplicate_pad_numbers_are_jumpers no)
		(fp_line
			(start 3.750056 5.500116)
			(end 3.750056 -5.500116)
			(stroke
				(width 0.1524)
				(type default)
			)
			(layer "F.SilkS")
		)
		(fp_line
			(start 3.750056 -5.500116)
			(end 2.393442 -5.500116)
			(stroke
				(width 0.1524)
				(type default)
			)
			(layer "F.SilkS")
		)
		(fp_line
			(start 2.393442 5.500116)
			(end 3.750056 5.500116)
			(stroke
				(width 0.1524)
				(type default)
			)
			(layer "F.SilkS")
		)
		(fp_line
			(start -2.393442 5.500116)
			(end -3.750056 5.500116)
			(stroke
				(width 0.1524)
				(type default)
			)
			(layer "F.SilkS")
		)
		(fp_line
			(start -3.750056 5.500116)
			(end -3.750056 -5.500116)
			(stroke
				(width 0.1524)
				(type default)
			)
			(layer "F.SilkS")
		)
		(fp_line
			(start -3.750056 -5.500116)
			(end -2.393442 -5.500116)
			(stroke
				(width 0.1524)
				(type default)
			)
			(layer "F.SilkS")
		)
		(fp_poly
			(pts
				(xy -3.9116 -4.249928) (xy -4.421378 -3.995166) (xy -4.421378 -4.50469)
			)
			(stroke
				(width 0)
				(type default)
			)
			(fill yes)
			(layer "F.SilkS")
		)
		(fp_line
			(start 3.750056 5.500116)
			(end 3.750056 -5.500116)
			(stroke
				(width 0.1)
				(type default)
			)
			(layer "F.Fab")
		)
		(fp_line
			(start 3.750056 -5.500116)
			(end -3.750056 -5.500116)
			(stroke
				(width 0.1)
				(type default)
			)
			(layer "F.Fab")
		)
		(fp_line
			(start -3.750056 5.500116)
			(end 3.750056 5.500116)
			(stroke
				(width 0.1)
				(type default)
			)
			(layer "F.Fab")
		)
		(fp_line
			(start -3.750056 -5.500116)
			(end -3.750056 5.500116)
			(stroke
				(width 0.1)
				(type default)
			)
			(layer "F.Fab")
		)
		(fp_poly
			(pts
				(xy -4.9276 -4.757928) (xy -4.9276 -3.741928) (xy -3.9116 -4.249928)
			)
			(stroke
				(width 0)
				(type default)
			)
			(fill yes)
			(layer "F.Fab")
		)
		(pad "1" smd rect
			(at 0 -4.249928 90)
			(size 2.413 4.5212)
			(layers "F.Cu" "F.Mask" "F.Paste")
			(net "SW_PVDDCR_CPU0_P0_SW3")
		)
		(pad "2" smd rect
			(at 0 -1.175004 90)
			(size 1.3716 4.5212)
			(layers "F.Cu" "F.Mask" "F.Paste")
			(net "IND_CPU0_P0_CPL2")
		)
		(pad "3" smd rect
			(at 0 1.175004 90)
			(size 1.3716 4.5212)
			(layers "F.Cu" "F.Mask" "F.Paste")
			(net "IND_CPU0_P0_CPL3")
		)
		(pad "4" smd rect
			(at 0 4.249928 90)
			(size 2.413 4.5212)
			(layers "F.Cu" "F.Mask" "F.Paste")
			(net "PVDDCR_CPU0_P0")
		)
	)
	(footprint ""
		(layer "F.Cu")
		(at 229.903274 -155.284932 180)
		(property "Reference" "C1522"
			(at 0 0 180)
			(layer "F.SilkS")
			(hide yes)
			(effects
				(font
					(size 1.27 1.27)
				)
			)
		)
		(property "Value" ""
			(at 0 0 180)
			(layer "F.Fab")
			(effects
				(font
					(size 1.27 1.27)
				)
			)
		)
		(duplicate_pad_numbers_are_jumpers no)
		(fp_line
			(start 0.7874 0.4064)
			(end -0.7874 0.4064)
			(stroke
				(width 0.1524)
				(type default)
			)
			(layer "F.SilkS")
		)
		(fp_line
			(start 0.7874 -0.4064)
			(end 0.7874 0.4064)
			(stroke
				(width 0.1524)
				(type default)
			)
			(layer "F.SilkS")
		)
		(fp_line
			(start -0.7874 0.4064)
			(end -0.7874 -0.4064)
			(stroke
				(width 0.1524)
				(type default)
			)
			(layer "F.SilkS")
		)
		(fp_line
			(start -0.7874 -0.4064)
			(end 0.7874 -0.4064)
			(stroke
				(width 0.1524)
				(type default)
			)
			(layer "F.SilkS")
		)
		(fp_line
			(start 0.67945 0.3048)
			(end 0.120396 0.3048)
			(stroke
				(width 0.1)
				(type default)
			)
			(layer "F.Fab")
		)
		(fp_line
			(start 0.67945 -0.3048)
			(end 0.67945 0.3048)
			(stroke
				(width 0.1)
				(type default)
			)
			(layer "F.Fab")
		)
		(fp_line
			(start 0.12065 -0.2794)
			(end 0.12065 -0.3048)
			(stroke
				(width 0.1)
				(type default)
			)
			(layer "F.Fab")
		)
		(fp_line
			(start 0.12065 -0.3048)
			(end 0.67945 -0.3048)
			(stroke
				(width 0.1)
				(type default)
			)
			(layer "F.Fab")
		)
		(fp_line
			(start 0.120396 0.3048)
			(end 0.120396 0.2794)
			(stroke
				(width 0.1)
				(type default)
			)
			(layer "F.Fab")
		)
		(fp_line
			(start 0.120396 0.2794)
			(end -0.12065 0.2794)
			(stroke
				(width 0.1)
				(type default)
			)
			(layer "F.Fab")
		)
		(fp_line
			(start -0.12065 0.3048)
			(end -0.67945 0.3048)
			(stroke
				(width 0.1)
				(type default)
			)
			(layer "F.Fab")
		)
		(fp_line
			(start -0.12065 0.2794)
			(end -0.12065 0.3048)
			(stroke
				(width 0.1)
				(type default)
			)
			(layer "F.Fab")
		)
		(fp_line
			(start -0.12065 -0.2794)
			(end 0.12065 -0.2794)
			(stroke
				(width 0.1)
				(type default)
			)
			(layer "F.Fab")
		)
		(fp_line
			(start -0.12065 -0.305054)
			(end -0.12065 -0.2794)
			(stroke
				(width 0.1)
				(type default)
			)
			(layer "F.Fab")
		)
		(fp_line
			(start -0.67945 0.3048)
			(end -0.67945 -0.305054)
			(stroke
				(width 0.1)
				(type default)
			)
			(layer "F.Fab")
		)
		(fp_line
			(start -0.67945 -0.305054)
			(end -0.12065 -0.305054)
			(stroke
				(width 0.1)
				(type default)
			)
			(layer "F.Fab")
		)
		(pad "1" smd circle
			(at -0.40005 0 180)
			(size 0 0)
			(layers "F.Cu" "F.Mask" "F.Paste")
			(net "PVDD18_S5_P0")
		)
		(pad "2" smd circle
			(at 0.40005 0 180)
			(size 0 0)
			(layers "F.Cu" "F.Mask" "F.Paste")
			(net "GND")
		)
	)
	(footprint ""
		(layer "F.Cu")
		(at 304.419 -354.711)
		(property "Reference" "PR62"
			(at 0 0 0)
			(layer "F.SilkS")
			(hide yes)
			(effects
				(font
					(size 1.27 1.27)
				)
			)
		)
		(property "Value" ""
			(at 0 0 0)
			(layer "F.Fab")
			(effects
				(font
					(size 1.27 1.27)
				)
			)
		)
		(duplicate_pad_numbers_are_jumpers no)
		(fp_line
			(start -0.7874 -0.4064)
			(end 0.7874 -0.4064)
			(stroke
				(width 0.1524)
				(type default)
			)
			(layer "F.SilkS")
		)
		(fp_line
			(start -0.7874 0.4064)
			(end -0.7874 -0.4064)
			(stroke
				(width 0.1524)
				(type default)
			)
			(layer "F.SilkS")
		)
		(fp_line
			(start 0.7874 -0.4064)
			(end 0.7874 0.4064)
			(stroke
				(width 0.1524)
				(type default)
			)
			(layer "F.SilkS")
		)
		(fp_line
			(start 0.7874 0.4064)
			(end -0.7874 0.4064)
			(stroke
				(width 0.1524)
				(type default)
			)
			(layer "F.SilkS")
		)
		(fp_line
			(start -0.67945 -0.305054)
			(end -0.12065 -0.305054)
			(stroke
				(width 0.1)
				(type default)
			)
			(layer "F.Fab")
		)
		(fp_line
			(start -0.67945 0.3048)
			(end -0.67945 -0.305054)
			(stroke
				(width 0.1)
				(type default)
			)
			(layer "F.Fab")
		)
		(fp_line
			(start -0.12065 -0.305054)
			(end -0.12065 -0.2794)
			(stroke
				(width 0.1)
				(type default)
			)
			(layer "F.Fab")
		)
		(fp_line
			(start -0.12065 -0.2794)
			(end 0.12065 -0.2794)
			(stroke
				(width 0.1)
				(type default)
			)
			(layer "F.Fab")
		)
		(fp_line
			(start -0.12065 0.2794)
			(end -0.12065 0.3048)
			(stroke
				(width 0.1)
				(type default)
			)
			(layer "F.Fab")
		)
		(fp_line
			(start -0.12065 0.3048)
			(end -0.67945 0.3048)
			(stroke
				(width 0.1)
				(type default)
			)
			(layer "F.Fab")
		)
		(fp_line
			(start 0.120396 0.2794)
			(end -0.12065 0.2794)
			(stroke
				(width 0.1)
				(type default)
			)
			(layer "F.Fab")
		)
		(fp_line
			(start 0.120396 0.3048)
			(end 0.120396 0.2794)
			(stroke
				(width 0.1)
				(type default)
			)
			(layer "F.Fab")
		)
		(fp_line
			(start 0.12065 -0.3048)
			(end 0.67945 -0.3048)
			(stroke
				(width 0.1)
				(type default)
			)
			(layer "F.Fab")
		)
		(fp_line
			(start 0.12065 -0.2794)
			(end 0.12065 -0.3048)
			(stroke
				(width 0.1)
				(type default)
			)
			(layer "F.Fab")
		)
		(fp_line
			(start 0.67945 -0.3048)
			(end 0.67945 0.3048)
			(stroke
				(width 0.1)
				(type default)
			)
			(layer "F.Fab")
		)
		(fp_line
			(start 0.67945 0.3048)
			(end 0.120396 0.3048)
			(stroke
				(width 0.1)
				(type default)
			)
			(layer "F.Fab")
		)
		(pad "1" smd circle
			(at -0.40005 0)
			(size 0 0)
			(layers "F.Cu" "F.Mask" "F.Paste")
			(net "SVID_PVDDCR_CPU1_P0_SVTI")
		)
		(pad "2" smd circle
			(at 0.40005 0)
			(size 0 0)
			(layers "F.Cu" "F.Mask" "F.Paste")
			(net "SVID_PVDDCR_CPU1_P0_SVTI_R")
		)
	)
	(footprint ""
		(layer "F.Cu")
		(at 108.625894 -256.012442 90)
		(property "Reference" "C2445"
			(at 0 0 90)
			(layer "F.SilkS")
			(hide yes)
			(effects
				(font
					(size 1.27 1.27)
				)
			)
		)
		(property "Value" ""
			(at 0 0 90)
			(layer "F.Fab")
			(effects
				(font
					(size 1.27 1.27)
				)
			)
		)
		(duplicate_pad_numbers_are_jumpers no)
		(fp_line
			(start 0.7874 -0.4064)
			(end 0.7874 0.4064)
			(stroke
				(width 0.1524)
				(type default)
			)
			(layer "F.SilkS")
		)
		(fp_line
			(start -0.7874 -0.4064)
			(end 0.7874 -0.4064)
			(stroke
				(width 0.1524)
				(type default)
			)
			(layer "F.SilkS")
		)
		(fp_line
			(start 0.7874 0.4064)
			(end -0.7874 0.4064)
			(stroke
				(width 0.1524)
				(type default)
			)
			(layer "F.SilkS")
		)
		(fp_line
			(start -0.7874 0.4064)
			(end -0.7874 -0.4064)
			(stroke
				(width 0.1524)
				(type default)
			)
			(layer "F.SilkS")
		)
		(fp_line
			(start -0.12065 -0.305054)
			(end -0.12065 -0.2794)
			(stroke
				(width 0.1)
				(type default)
			)
			(layer "F.Fab")
		)
		(fp_line
			(start -0.67945 -0.305054)
			(end -0.12065 -0.305054)
			(stroke
				(width 0.1)
				(type default)
			)
			(layer "F.Fab")
		)
		(fp_line
			(start 0.67945 -0.3048)
			(end 0.67945 0.3048)
			(stroke
				(width 0.1)
				(type default)
			)
			(layer "F.Fab")
		)
		(fp_line
			(start 0.12065 -0.3048)
			(end 0.67945 -0.3048)
			(stroke
				(width 0.1)
				(type default)
			)
			(layer "F.Fab")
		)
		(fp_line
			(start 0.12065 -0.2794)
			(end 0.12065 -0.3048)
			(stroke
				(width 0.1)
				(type default)
			)
			(layer "F.Fab")
		)
		(fp_line
			(start -0.12065 -0.2794)
			(end 0.12065 -0.2794)
			(stroke
				(width 0.1)
				(type default)
			)
			(layer "F.Fab")
		)
		(fp_line
			(start 0.120396 0.2794)
			(end -0.12065 0.2794)
			(stroke
				(width 0.1)
				(type default)
			)
			(layer "F.Fab")
		)
		(fp_line
			(start -0.12065 0.2794)
			(end -0.12065 0.3048)
			(stroke
				(width 0.1)
				(type default)
			)
			(layer "F.Fab")
		)
		(fp_line
			(start 0.67945 0.3048)
			(end 0.120396 0.3048)
			(stroke
				(width 0.1)
				(type default)
			)
			(layer "F.Fab")
		)
		(fp_line
			(start 0.120396 0.3048)
			(end 0.120396 0.2794)
			(stroke
				(width 0.1)
				(type default)
			)
			(layer "F.Fab")
		)
		(fp_line
			(start -0.12065 0.3048)
			(end -0.67945 0.3048)
			(stroke
				(width 0.1)
				(type default)
			)
			(layer "F.Fab")
		)
		(fp_line
			(start -0.67945 0.3048)
			(end -0.67945 -0.305054)
			(stroke
				(width 0.1)
				(type default)
			)
			(layer "F.Fab")
		)
		(pad "1" smd circle
			(at -0.40005 0 90)
			(size 0 0)
			(layers "F.Cu" "F.Mask" "F.Paste")
			(net "PVDDCR_SOC_P1")
		)
		(pad "2" smd circle
			(at 0.40005 0 90)
			(size 0 0)
			(layers "F.Cu" "F.Mask" "F.Paste")
			(net "GND")
		)
	)
	(footprint ""
		(layer "F.Cu")
		(at 277.224236 -393.899136 -90)
		(property "Reference" "PR6002"
			(at 0.449072 -2.98958 90)
			(unlocked yes)
			(layer "F.SilkS")
			(effects
				(font
					(size 0.7874 0.5842)
					(thickness 0.1524)
				)
				(justify left)
			)
		)
		(property "Value" ""
			(at 0 0 270)
			(layer "F.Fab")
			(effects
				(font
					(size 1.27 1.27)
				)
			)
		)
		(duplicate_pad_numbers_are_jumpers no)
		(fp_line
			(start -4.13258 2.1336)
			(end 4.13258 2.1336)
			(stroke
				(width 0.1524)
				(type default)
			)
			(layer "F.SilkS")
		)
		(fp_line
			(start 4.13258 2.1336)
			(end 4.13258 -2.1336)
			(stroke
				(width 0.1524)
				(type default)
			)
			(layer "F.SilkS")
		)
		(fp_line
			(start -4.13258 -2.1336)
			(end -4.13258 2.1336)
			(stroke
				(width 0.1524)
				(type default)
			)
			(layer "F.SilkS")
		)
		(fp_line
			(start 4.13258 -2.1336)
			(end -4.13258 -2.1336)
			(stroke
				(width 0.1524)
				(type default)
			)
			(layer "F.SilkS")
		)
		(fp_line
			(start -3.350006 1.700022)
			(end 3.350006 1.700022)
			(stroke
				(width 0.1)
				(type default)
			)
			(layer "F.Fab")
		)
		(fp_line
			(start 3.350006 1.700022)
			(end 3.350006 -1.700022)
			(stroke
				(width 0.1)
				(type default)
			)
			(layer "F.Fab")
		)
		(fp_line
			(start -3.350006 -1.700022)
			(end -3.350006 1.700022)
			(stroke
				(width 0.1)
				(type default)
			)
			(layer "F.Fab")
		)
		(fp_line
			(start 3.350006 -1.700022)
			(end -3.350006 -1.700022)
			(stroke
				(width 0.1)
				(type default)
			)
			(layer "F.Fab")
		)
		(pad "1A" smd rect
			(at -3.024886 0 270)
			(size 1.9558 4.0132)
			(layers "F.Cu" "F.Mask" "F.Paste")
			(net "P12V_PSU")
		)
		(pad "1B" smd rect
			(at -2.173986 0 270)
			(size 0.254 0.508)
			(layers "F.Cu" "F.Mask" "F.Paste")
			(net "P12V_HSC_SENSE1_P")
		)
		(pad "2A" smd rect
			(at 3.024886 0 270)
			(size 1.9558 4.0132)
			(layers "F.Cu" "F.Mask" "F.Paste")
			(net "P12V_MAIN_R_0")
		)
		(pad "2B" smd rect
			(at 2.173986 0 270)
			(size 0.254 0.508)
			(layers "F.Cu" "F.Mask" "F.Paste")
			(net "P12V_HSC_SENSE1_N")
		)
	)
	(footprint ""
		(layer "F.Cu")
		(at 109.627924 -386.951474)
		(property "Reference" "R622"
			(at 0 0 0)
			(layer "F.SilkS")
			(hide yes)
			(effects
				(font
					(size 1.27 1.27)
				)
			)
		)
		(property "Value" ""
			(at 0 0 0)
			(layer "F.Fab")
			(effects
				(font
					(size 1.27 1.27)
				)
			)
		)
		(duplicate_pad_numbers_are_jumpers no)
		(fp_line
			(start -0.32512 -0.175006)
			(end 0.32512 -0.175006)
			(stroke
				(width 0.1)
				(type default)
			)
			(layer "F.Fab")
		)
		(fp_line
			(start -0.32512 0.175006)
			(end -0.32512 -0.175006)
			(stroke
				(width 0.1)
				(type default)
			)
			(layer "F.Fab")
		)
		(fp_line
			(start 0.32512 -0.175006)
			(end 0.32512 0.175006)
			(stroke
				(width 0.1)
				(type default)
			)
			(layer "F.Fab")
		)
		(fp_line
			(start 0.32512 0.175006)
			(end -0.32512 0.175006)
			(stroke
				(width 0.1)
				(type default)
			)
			(layer "F.Fab")
		)
		(pad "1" smd rect
			(at -0.2667 0)
			(size 0.3048 0.381)
			(layers "F.Cu" "F.Mask" "F.Paste")
			(net "CLK_100M_RETIMER_CPU1_P3_R_DN")
		)
		(pad "2" smd rect
			(at 0.2667 0 180)
			(size 0.3048 0.381)
			(layers "F.Cu" "F.Mask" "F.Paste")
			(net "CLK_100M_RETIMER_CPU1_P3_DN")
		)
	)
	(footprint ""
		(layer "F.Cu")
		(at 301.393098 -25.322276 180)
		(property "Reference" "R5051"
			(at 0 0 180)
			(layer "F.SilkS")
			(hide yes)
			(effects
				(font
					(size 1.27 1.27)
				)
			)
		)
		(property "Value" ""
			(at 0 0 180)
			(layer "F.Fab")
			(effects
				(font
					(size 1.27 1.27)
				)
			)
		)
		(duplicate_pad_numbers_are_jumpers no)
		(fp_line
			(start 0.7874 0.4064)
			(end -0.7874 0.4064)
			(stroke
				(width 0.1524)
				(type default)
			)
			(layer "F.SilkS")
		)
		(fp_line
			(start 0.7874 -0.4064)
			(end 0.7874 0.4064)
			(stroke
				(width 0.1524)
				(type default)
			)
			(layer "F.SilkS")
		)
		(fp_line
			(start -0.7874 0.4064)
			(end -0.7874 -0.4064)
			(stroke
				(width 0.1524)
				(type default)
			)
			(layer "F.SilkS")
		)
		(fp_line
			(start -0.7874 -0.4064)
			(end 0.7874 -0.4064)
			(stroke
				(width 0.1524)
				(type default)
			)
			(layer "F.SilkS")
		)
		(fp_line
			(start 0.67945 0.3048)
			(end 0.120396 0.3048)
			(stroke
				(width 0.1)
				(type default)
			)
			(layer "F.Fab")
		)
		(fp_line
			(start 0.67945 -0.3048)
			(end 0.67945 0.3048)
			(stroke
				(width 0.1)
				(type default)
			)
			(layer "F.Fab")
		)
		(fp_line
			(start 0.12065 -0.2794)
			(end 0.12065 -0.3048)
			(stroke
				(width 0.1)
				(type default)
			)
			(layer "F.Fab")
		)
		(fp_line
			(start 0.12065 -0.3048)
			(end 0.67945 -0.3048)
			(stroke
				(width 0.1)
				(type default)
			)
			(layer "F.Fab")
		)
		(fp_line
			(start 0.120396 0.3048)
			(end 0.120396 0.2794)
			(stroke
				(width 0.1)
				(type default)
			)
			(layer "F.Fab")
		)
		(fp_line
			(start 0.120396 0.2794)
			(end -0.12065 0.2794)
			(stroke
				(width 0.1)
				(type default)
			)
			(layer "F.Fab")
		)
		(fp_line
			(start -0.12065 0.3048)
			(end -0.67945 0.3048)
			(stroke
				(width 0.1)
				(type default)
			)
			(layer "F.Fab")
		)
		(fp_line
			(start -0.12065 0.2794)
			(end -0.12065 0.3048)
			(stroke
				(width 0.1)
				(type default)
			)
			(layer "F.Fab")
		)
		(fp_line
			(start -0.12065 -0.2794)
			(end 0.12065 -0.2794)
			(stroke
				(width 0.1)
				(type default)
			)
			(layer "F.Fab")
		)
		(fp_line
			(start -0.12065 -0.305054)
			(end -0.12065 -0.2794)
			(stroke
				(width 0.1)
				(type default)
			)
			(layer "F.Fab")
		)
		(fp_line
			(start -0.67945 0.3048)
			(end -0.67945 -0.305054)
			(stroke
				(width 0.1)
				(type default)
			)
			(layer "F.Fab")
		)
		(fp_line
			(start -0.67945 -0.305054)
			(end -0.12065 -0.305054)
			(stroke
				(width 0.1)
				(type default)
			)
			(layer "F.Fab")
		)
		(pad "1" smd circle
			(at -0.40005 0 180)
			(size 0 0)
			(layers "F.Cu" "F.Mask" "F.Paste")
			(net "P3V3_RTC_AUX")
		)
		(pad "2" smd circle
			(at 0.40005 0 180)
			(size 0 0)
			(layers "F.Cu" "F.Mask" "F.Paste")
			(net "P1V5_BAT_IN")
		)
	)
	(footprint ""
		(layer "F.Cu")
		(at 146.186652 -78.537562 90)
		(property "Reference" "PC641"
			(at 0 0 90)
			(layer "F.SilkS")
			(hide yes)
			(effects
				(font
					(size 1.27 1.27)
				)
			)
		)
		(property "Value" ""
			(at 0 0 90)
			(layer "F.Fab")
			(effects
				(font
					(size 1.27 1.27)
				)
			)
		)
		(duplicate_pad_numbers_are_jumpers no)
		(fp_line
			(start 0.7874 -0.4064)
			(end 0.7874 0.4064)
			(stroke
				(width 0.1524)
				(type default)
			)
			(layer "F.SilkS")
		)
		(fp_line
			(start -0.7874 -0.4064)
			(end 0.7874 -0.4064)
			(stroke
				(width 0.1524)
				(type default)
			)
			(layer "F.SilkS")
		)
		(fp_line
			(start 0.7874 0.4064)
			(end -0.7874 0.4064)
			(stroke
				(width 0.1524)
				(type default)
			)
			(layer "F.SilkS")
		)
		(fp_line
			(start -0.7874 0.4064)
			(end -0.7874 -0.4064)
			(stroke
				(width 0.1524)
				(type default)
			)
			(layer "F.SilkS")
		)
		(fp_line
			(start -0.12065 -0.305054)
			(end -0.12065 -0.2794)
			(stroke
				(width 0.1)
				(type default)
			)
			(layer "F.Fab")
		)
		(fp_line
			(start -0.67945 -0.305054)
			(end -0.12065 -0.305054)
			(stroke
				(width 0.1)
				(type default)
			)
			(layer "F.Fab")
		)
		(fp_line
			(start 0.67945 -0.3048)
			(end 0.67945 0.3048)
			(stroke
				(width 0.1)
				(type default)
			)
			(layer "F.Fab")
		)
		(fp_line
			(start 0.12065 -0.3048)
			(end 0.67945 -0.3048)
			(stroke
				(width 0.1)
				(type default)
			)
			(layer "F.Fab")
		)
		(fp_line
			(start 0.12065 -0.2794)
			(end 0.12065 -0.3048)
			(stroke
				(width 0.1)
				(type default)
			)
			(layer "F.Fab")
		)
		(fp_line
			(start -0.12065 -0.2794)
			(end 0.12065 -0.2794)
			(stroke
				(width 0.1)
				(type default)
			)
			(layer "F.Fab")
		)
		(fp_line
			(start 0.120396 0.2794)
			(end -0.12065 0.2794)
			(stroke
				(width 0.1)
				(type default)
			)
			(layer "F.Fab")
		)
		(fp_line
			(start -0.12065 0.2794)
			(end -0.12065 0.3048)
			(stroke
				(width 0.1)
				(type default)
			)
			(layer "F.Fab")
		)
		(fp_line
			(start 0.67945 0.3048)
			(end 0.120396 0.3048)
			(stroke
				(width 0.1)
				(type default)
			)
			(layer "F.Fab")
		)
		(fp_line
			(start 0.120396 0.3048)
			(end 0.120396 0.2794)
			(stroke
				(width 0.1)
				(type default)
			)
			(layer "F.Fab")
		)
		(fp_line
			(start -0.12065 0.3048)
			(end -0.67945 0.3048)
			(stroke
				(width 0.1)
				(type default)
			)
			(layer "F.Fab")
		)
		(fp_line
			(start -0.67945 0.3048)
			(end -0.67945 -0.305054)
			(stroke
				(width 0.1)
				(type default)
			)
			(layer "F.Fab")
		)
		(pad "1" smd circle
			(at -0.40005 0 90)
			(size 0 0)
			(layers "F.Cu" "F.Mask" "F.Paste")
			(net "SW_P1V8_AUX_BT_R")
		)
		(pad "2" smd circle
			(at 0.40005 0 90)
			(size 0 0)
			(layers "F.Cu" "F.Mask" "F.Paste")
			(net "SW_P1V8_AUX_PH")
		)
	)
	(footprint ""
		(layer "F.Cu")
		(at 191.295782 -28.267152)
		(property "Reference" "PC2237"
			(at 0 0 0)
			(layer "F.SilkS")
			(hide yes)
			(effects
				(font
					(size 1.27 1.27)
				)
			)
		)
		(property "Value" ""
			(at 0 0 0)
			(layer "F.Fab")
			(effects
				(font
					(size 1.27 1.27)
				)
			)
		)
		(duplicate_pad_numbers_are_jumpers no)
		(fp_line
			(start -0.7874 -0.4064)
			(end 0.7874 -0.4064)
			(stroke
				(width 0.1524)
				(type default)
			)
			(layer "F.SilkS")
		)
		(fp_line
			(start -0.7874 0.4064)
			(end -0.7874 -0.4064)
			(stroke
				(width 0.1524)
				(type default)
			)
			(layer "F.SilkS")
		)
		(fp_line
			(start 0.7874 -0.4064)
			(end 0.7874 0.4064)
			(stroke
				(width 0.1524)
				(type default)
			)
			(layer "F.SilkS")
		)
		(fp_line
			(start 0.7874 0.4064)
			(end -0.7874 0.4064)
			(stroke
				(width 0.1524)
				(type default)
			)
			(layer "F.SilkS")
		)
		(fp_line
			(start -0.67945 -0.305054)
			(end -0.12065 -0.305054)
			(stroke
				(width 0.1)
				(type default)
			)
			(layer "F.Fab")
		)
		(fp_line
			(start -0.67945 0.3048)
			(end -0.67945 -0.305054)
			(stroke
				(width 0.1)
				(type default)
			)
			(layer "F.Fab")
		)
		(fp_line
			(start -0.12065 -0.305054)
			(end -0.12065 -0.2794)
			(stroke
				(width 0.1)
				(type default)
			)
			(layer "F.Fab")
		)
		(fp_line
			(start -0.12065 -0.2794)
			(end 0.12065 -0.2794)
			(stroke
				(width 0.1)
				(type default)
			)
			(layer "F.Fab")
		)
		(fp_line
			(start -0.12065 0.2794)
			(end -0.12065 0.3048)
			(stroke
				(width 0.1)
				(type default)
			)
			(layer "F.Fab")
		)
		(fp_line
			(start -0.12065 0.3048)
			(end -0.67945 0.3048)
			(stroke
				(width 0.1)
				(type default)
			)
			(layer "F.Fab")
		)
		(fp_line
			(start 0.120396 0.2794)
			(end -0.12065 0.2794)
			(stroke
				(width 0.1)
				(type default)
			)
			(layer "F.Fab")
		)
		(fp_line
			(start 0.120396 0.3048)
			(end 0.120396 0.2794)
			(stroke
				(width 0.1)
				(type default)
			)
			(layer "F.Fab")
		)
		(fp_line
			(start 0.12065 -0.3048)
			(end 0.67945 -0.3048)
			(stroke
				(width 0.1)
				(type default)
			)
			(layer "F.Fab")
		)
		(fp_line
			(start 0.12065 -0.2794)
			(end 0.12065 -0.3048)
			(stroke
				(width 0.1)
				(type default)
			)
			(layer "F.Fab")
		)
		(fp_line
			(start 0.67945 -0.3048)
			(end 0.67945 0.3048)
			(stroke
				(width 0.1)
				(type default)
			)
			(layer "F.Fab")
		)
		(fp_line
			(start 0.67945 0.3048)
			(end 0.120396 0.3048)
			(stroke
				(width 0.1)
				(type default)
			)
			(layer "F.Fab")
		)
		(pad "1" smd circle
			(at -0.40005 0)
			(size 0 0)
			(layers "F.Cu" "F.Mask" "F.Paste")
			(net "P12V_SCM_GATE")
		)
		(pad "2" smd circle
			(at 0.40005 0)
			(size 0 0)
			(layers "F.Cu" "F.Mask" "F.Paste")
			(net "GND")
		)
	)
	(footprint ""
		(layer "F.Cu")
		(at 130.946906 -21.372068 90)
		(property "Reference" "R3254"
			(at 0 0 90)
			(layer "F.SilkS")
			(hide yes)
			(effects
				(font
					(size 1.27 1.27)
				)
			)
		)
		(property "Value" ""
			(at 0 0 90)
			(layer "F.Fab")
			(effects
				(font
					(size 1.27 1.27)
				)
			)
		)
		(duplicate_pad_numbers_are_jumpers no)
		(fp_line
			(start 0.7874 -0.4064)
			(end 0.7874 0.4064)
			(stroke
				(width 0.1524)
				(type default)
			)
			(layer "F.SilkS")
		)
		(fp_line
			(start -0.7874 -0.4064)
			(end 0.7874 -0.4064)
			(stroke
				(width 0.1524)
				(type default)
			)
			(layer "F.SilkS")
		)
		(fp_line
			(start 0.7874 0.4064)
			(end -0.7874 0.4064)
			(stroke
				(width 0.1524)
				(type default)
			)
			(layer "F.SilkS")
		)
		(fp_line
			(start -0.7874 0.4064)
			(end -0.7874 -0.4064)
			(stroke
				(width 0.1524)
				(type default)
			)
			(layer "F.SilkS")
		)
		(fp_line
			(start -0.12065 -0.305054)
			(end -0.12065 -0.2794)
			(stroke
				(width 0.1)
				(type default)
			)
			(layer "F.Fab")
		)
		(fp_line
			(start -0.67945 -0.305054)
			(end -0.12065 -0.305054)
			(stroke
				(width 0.1)
				(type default)
			)
			(layer "F.Fab")
		)
		(fp_line
			(start 0.67945 -0.3048)
			(end 0.67945 0.3048)
			(stroke
				(width 0.1)
				(type default)
			)
			(layer "F.Fab")
		)
		(fp_line
			(start 0.12065 -0.3048)
			(end 0.67945 -0.3048)
			(stroke
				(width 0.1)
				(type default)
			)
			(layer "F.Fab")
		)
		(fp_line
			(start 0.12065 -0.2794)
			(end 0.12065 -0.3048)
			(stroke
				(width 0.1)
				(type default)
			)
			(layer "F.Fab")
		)
		(fp_line
			(start -0.12065 -0.2794)
			(end 0.12065 -0.2794)
			(stroke
				(width 0.1)
				(type default)
			)
			(layer "F.Fab")
		)
		(fp_line
			(start 0.120396 0.2794)
			(end -0.12065 0.2794)
			(stroke
				(width 0.1)
				(type default)
			)
			(layer "F.Fab")
		)
		(fp_line
			(start -0.12065 0.2794)
			(end -0.12065 0.3048)
			(stroke
				(width 0.1)
				(type default)
			)
			(layer "F.Fab")
		)
		(fp_line
			(start 0.67945 0.3048)
			(end 0.120396 0.3048)
			(stroke
				(width 0.1)
				(type default)
			)
			(layer "F.Fab")
		)
		(fp_line
			(start 0.120396 0.3048)
			(end 0.120396 0.2794)
			(stroke
				(width 0.1)
				(type default)
			)
			(layer "F.Fab")
		)
		(fp_line
			(start -0.12065 0.3048)
			(end -0.67945 0.3048)
			(stroke
				(width 0.1)
				(type default)
			)
			(layer "F.Fab")
		)
		(fp_line
			(start -0.67945 0.3048)
			(end -0.67945 -0.305054)
			(stroke
				(width 0.1)
				(type default)
			)
			(layer "F.Fab")
		)
		(pad "1" smd circle
			(at -0.40005 0 90)
			(size 0 0)
			(layers "F.Cu" "F.Mask" "F.Paste")
			(net "TP_PCIE_TXP<3>")
		)
		(pad "2" smd circle
			(at 0.40005 0 90)
			(size 0 0)
			(layers "F.Cu" "F.Mask" "F.Paste")
			(net "LED_HDD_ACTIVITY_B_N")
		)
	)
	(footprint ""
		(layer "F.Cu")
		(at 394.164058 -177.04562 90)
		(property "Reference" "PC585_1"
			(at 0 0 90)
			(layer "F.SilkS")
			(hide yes)
			(effects
				(font
					(size 1.27 1.27)
				)
			)
		)
		(property "Value" ""
			(at 0 0 90)
			(layer "F.Fab")
			(effects
				(font
					(size 1.27 1.27)
				)
			)
		)
		(duplicate_pad_numbers_are_jumpers no)
		(fp_line
			(start 0.7874 -0.4064)
			(end 0.7874 0.4064)
			(stroke
				(width 0.1524)
				(type default)
			)
			(layer "F.SilkS")
		)
		(fp_line
			(start -0.7874 -0.4064)
			(end 0.7874 -0.4064)
			(stroke
				(width 0.1524)
				(type default)
			)
			(layer "F.SilkS")
		)
		(fp_line
			(start 0.7874 0.4064)
			(end -0.7874 0.4064)
			(stroke
				(width 0.1524)
				(type default)
			)
			(layer "F.SilkS")
		)
		(fp_line
			(start -0.7874 0.4064)
			(end -0.7874 -0.4064)
			(stroke
				(width 0.1524)
				(type default)
			)
			(layer "F.SilkS")
		)
		(fp_line
			(start -0.12065 -0.305054)
			(end -0.12065 -0.2794)
			(stroke
				(width 0.1)
				(type default)
			)
			(layer "F.Fab")
		)
		(fp_line
			(start -0.67945 -0.305054)
			(end -0.12065 -0.305054)
			(stroke
				(width 0.1)
				(type default)
			)
			(layer "F.Fab")
		)
		(fp_line
			(start 0.67945 -0.3048)
			(end 0.67945 0.3048)
			(stroke
				(width 0.1)
				(type default)
			)
			(layer "F.Fab")
		)
		(fp_line
			(start 0.12065 -0.3048)
			(end 0.67945 -0.3048)
			(stroke
				(width 0.1)
				(type default)
			)
			(layer "F.Fab")
		)
		(fp_line
			(start 0.12065 -0.2794)
			(end 0.12065 -0.3048)
			(stroke
				(width 0.1)
				(type default)
			)
			(layer "F.Fab")
		)
		(fp_line
			(start -0.12065 -0.2794)
			(end 0.12065 -0.2794)
			(stroke
				(width 0.1)
				(type default)
			)
			(layer "F.Fab")
		)
		(fp_line
			(start 0.120396 0.2794)
			(end -0.12065 0.2794)
			(stroke
				(width 0.1)
				(type default)
			)
			(layer "F.Fab")
		)
		(fp_line
			(start -0.12065 0.2794)
			(end -0.12065 0.3048)
			(stroke
				(width 0.1)
				(type default)
			)
			(layer "F.Fab")
		)
		(fp_line
			(start 0.67945 0.3048)
			(end 0.120396 0.3048)
			(stroke
				(width 0.1)
				(type default)
			)
			(layer "F.Fab")
		)
		(fp_line
			(start 0.120396 0.3048)
			(end 0.120396 0.2794)
			(stroke
				(width 0.1)
				(type default)
			)
			(layer "F.Fab")
		)
		(fp_line
			(start -0.12065 0.3048)
			(end -0.67945 0.3048)
			(stroke
				(width 0.1)
				(type default)
			)
			(layer "F.Fab")
		)
		(fp_line
			(start -0.67945 0.3048)
			(end -0.67945 -0.305054)
			(stroke
				(width 0.1)
				(type default)
			)
			(layer "F.Fab")
		)
		(pad "1" smd circle
			(at -0.40005 0 90)
			(size 0 0)
			(layers "F.Cu" "F.Mask" "F.Paste")
			(net "SW_P12V_AUX_PVDDCR_SOC_P0_FLT")
		)
		(pad "2" smd circle
			(at 0.40005 0 90)
			(size 0 0)
			(layers "F.Cu" "F.Mask" "F.Paste")
			(net "GND")
		)
	)
	(footprint ""
		(layer "F.Cu")
		(at 357.958644 -378.95403 -90)
		(property "Reference" "C938"
			(at 0 0 270)
			(layer "F.SilkS")
			(hide yes)
			(effects
				(font
					(size 1.27 1.27)
				)
			)
		)
		(property "Value" ""
			(at 0 0 270)
			(layer "F.Fab")
			(effects
				(font
					(size 1.27 1.27)
				)
			)
		)
		(duplicate_pad_numbers_are_jumpers no)
		(fp_line
			(start -0.299974 0.150114)
			(end -0.299974 -0.150114)
			(stroke
				(width 0.1)
				(type default)
			)
			(layer "F.Fab")
		)
		(fp_line
			(start 0.299974 0.150114)
			(end -0.299974 0.150114)
			(stroke
				(width 0.1)
				(type default)
			)
			(layer "F.Fab")
		)
		(fp_line
			(start -0.299974 -0.150114)
			(end 0.299974 -0.150114)
			(stroke
				(width 0.1)
				(type default)
			)
			(layer "F.Fab")
		)
		(fp_line
			(start 0.299974 -0.150114)
			(end 0.299974 0.150114)
			(stroke
				(width 0.1)
				(type default)
			)
			(layer "F.Fab")
		)
		(pad "1" smd rect
			(at -0.2667 0 270)
			(size 0.3048 0.381)
			(layers "F.Cu" "F.Mask" "F.Paste")
			(net "P5E_CPU0_P1_TX_C_DN<13>")
		)
		(pad "2" smd rect
			(at 0.2667 0 270)
			(size 0.3048 0.381)
			(layers "F.Cu" "F.Mask" "F.Paste")
			(net "P5E_CPU0_P1_TX_DN<13>")
		)
	)
	(footprint ""
		(layer "F.Cu")
		(at 484.834946 -306.882292 -90)
		(property "Reference" "X9010"
			(at -1.79451 4.909312 0)
			(unlocked yes)
			(layer "F.SilkS")
			(effects
				(font
					(size 0.7874 0.5842)
					(thickness 0.1524)
				)
				(justify left)
			)
		)
		(property "Value" ""
			(at 0 0 270)
			(layer "F.Fab")
			(effects
				(font
					(size 1.27 1.27)
				)
			)
		)
		(property "User Part Number" "N_A"
			(at 1.30175 1.27 0)
			(unlocked yes)
			(layer "Cmts.User")
			(hide yes)
			(effects
				(font
					(size 0.635 0.4064)
					(thickness 0.1524)
				)
			)
		)
		(property "Device Type" "TP_TDR_4P_FTS_TH-TP_TDR_4P_DIP,EMPTY,TP15"
			(at 1.30175 1.27 0)
			(unlocked yes)
			(layer "F.Fab")
			(hide yes)
			(effects
				(font
					(size 0.635 0.4064)
					(thickness 0.1524)
				)
			)
		)
		(duplicate_pad_numbers_are_jumpers no)
		(fp_line
			(start 0 3.81)
			(end 2.54 3.81)
			(stroke
				(width 0.1524)
				(type default)
			)
			(layer "F.SilkS")
		)
		(fp_line
			(start 2.54 3.81)
			(end 2.54 3.6703)
			(stroke
				(width 0.1524)
				(type default)
			)
			(layer "F.SilkS")
		)
		(fp_line
			(start 0 3.175)
			(end 0 3.81)
			(stroke
				(width 0.1524)
				(type default)
			)
			(layer "F.SilkS")
		)
		(fp_line
			(start 2.54 1.4097)
			(end 2.54 1.1303)
			(stroke
				(width 0.1524)
				(type default)
			)
			(layer "F.SilkS")
		)
		(fp_line
			(start 0 0.635)
			(end 0 1.905)
			(stroke
				(width 0.1524)
				(type default)
			)
			(layer "F.SilkS")
		)
		(fp_line
			(start 2.54 -1.1303)
			(end 2.54 -1.27)
			(stroke
				(width 0.1524)
				(type default)
			)
			(layer "F.SilkS")
		)
		(fp_line
			(start 0 -1.27)
			(end 0 -0.635)
			(stroke
				(width 0.1524)
				(type default)
			)
			(layer "F.SilkS")
		)
		(fp_line
			(start 2.54 -1.27)
			(end 0 -1.27)
			(stroke
				(width 0.1524)
				(type default)
			)
			(layer "F.SilkS")
		)
		(fp_poly
			(pts
				(xy -2.285746 -0.762) (xy -0.761746 0) (xy -2.285746 0.762)
			)
			(stroke
				(width 0)
				(type default)
			)
			(fill yes)
			(layer "F.SilkS")
		)
		(fp_line
			(start 0 3.81)
			(end 2.54 3.81)
			(stroke
				(width 0.1)
				(type default)
			)
			(layer "F.Fab")
		)
		(fp_line
			(start 2.54 3.81)
			(end 2.54 -1.27)
			(stroke
				(width 0.1)
				(type default)
			)
			(layer "F.Fab")
		)
		(fp_line
			(start 0 -1.27)
			(end 0 3.81)
			(stroke
				(width 0.1)
				(type default)
			)
			(layer "F.Fab")
		)
		(fp_line
			(start 2.54 -1.27)
			(end 0 -1.27)
			(stroke
				(width 0.1)
				(type default)
			)
			(layer "F.Fab")
		)
		(fp_poly
			(pts
				(xy -0.761746 0) (xy -2.285746 -0.762) (xy -2.285746 0.762)
			)
			(stroke
				(width 0)
				(type default)
			)
			(fill yes)
			(layer "F.Fab")
		)
		(pad "1" thru_hole circle
			(at 0 0 270)
			(size 1.0033 1.0033)
			(drill 0.249936)
			(layers "*.Cu" "*.Mask")
			(remove_unused_layers no)
			(net "TDR_DIFF_85_NECK_IN3_DN")
			(clearance 0.10795)
			(thermal_gap 0.10795)
			(padstack
				(mode front_inner_back)
				(layer "Inner"
					(shape circle)
					(size 0.8001 0.8001)
					(clearance 0.1524)
				)
				(layer "B.Cu"
					(shape circle)
					(size 1.0033 1.0033)
					(clearance 0.10795)
				)
			)
		)
		(pad "2" thru_hole circle
			(at 2.54 0 270)
			(size 1.9939 1.9939)
			(drill 0.249936)
			(layers "*.Cu" "*.Mask")
			(remove_unused_layers no)
			(net "T1_GND")
			(clearance 0.10795)
			(thermal_gap 0.10795)
			(padstack
				(mode front_inner_back)
				(layer "Inner"
					(shape circle)
					(size 0.8001 0.8001)
					(clearance 0.1524)
				)
				(layer "B.Cu"
					(shape circle)
					(size 1.9939 1.9939)
					(clearance 0.10795)
				)
			)
		)
		(pad "3" thru_hole circle
			(at 2.54 2.54 270)
			(size 1.9939 1.9939)
			(drill 0.249936)
			(layers "*.Cu" "*.Mask")
			(remove_unused_layers no)
			(net "T1_GND")
			(clearance 0.10795)
			(thermal_gap 0.10795)
			(padstack
				(mode front_inner_back)
				(layer "Inner"
					(shape circle)
					(size 0.8001 0.8001)
					(clearance 0.1524)
				)
				(layer "B.Cu"
					(shape circle)
					(size 1.9939 1.9939)
					(clearance 0.10795)
				)
			)
		)
		(pad "4" thru_hole circle
			(at 0 2.54 270)
			(size 1.0033 1.0033)
			(drill 0.249936)
			(layers "*.Cu" "*.Mask")
			(remove_unused_layers no)
			(net "TDR_DIFF_85_NECK_IN3_DP")
			(clearance 0.10795)
			(thermal_gap 0.10795)
			(padstack
				(mode front_inner_back)
				(layer "Inner"
					(shape circle)
					(size 0.8001 0.8001)
					(clearance 0.1524)
				)
				(layer "B.Cu"
					(shape circle)
					(size 1.0033 1.0033)
					(clearance 0.10795)
				)
			)
		)
	)
	(footprint ""
		(layer "F.Cu")
		(at 428.322232 -430.892458 180)
		(property "Reference" "C6086"
			(at 0 0 180)
			(layer "F.SilkS")
			(hide yes)
			(effects
				(font
					(size 1.27 1.27)
				)
			)
		)
		(property "Value" ""
			(at 0 0 180)
			(layer "F.Fab")
			(effects
				(font
					(size 1.27 1.27)
				)
			)
		)
		(duplicate_pad_numbers_are_jumpers no)
		(fp_line
			(start 0.7874 0.4064)
			(end -0.7874 0.4064)
			(stroke
				(width 0.1524)
				(type default)
			)
			(layer "F.SilkS")
		)
		(fp_line
			(start 0.7874 -0.4064)
			(end 0.7874 0.4064)
			(stroke
				(width 0.1524)
				(type default)
			)
			(layer "F.SilkS")
		)
		(fp_line
			(start -0.7874 0.4064)
			(end -0.7874 -0.4064)
			(stroke
				(width 0.1524)
				(type default)
			)
			(layer "F.SilkS")
		)
		(fp_line
			(start -0.7874 -0.4064)
			(end 0.7874 -0.4064)
			(stroke
				(width 0.1524)
				(type default)
			)
			(layer "F.SilkS")
		)
		(fp_line
			(start 0.67945 0.3048)
			(end 0.120396 0.3048)
			(stroke
				(width 0.1)
				(type default)
			)
			(layer "F.Fab")
		)
		(fp_line
			(start 0.67945 -0.3048)
			(end 0.67945 0.3048)
			(stroke
				(width 0.1)
				(type default)
			)
			(layer "F.Fab")
		)
		(fp_line
			(start 0.12065 -0.2794)
			(end 0.12065 -0.3048)
			(stroke
				(width 0.1)
				(type default)
			)
			(layer "F.Fab")
		)
		(fp_line
			(start 0.12065 -0.3048)
			(end 0.67945 -0.3048)
			(stroke
				(width 0.1)
				(type default)
			)
			(layer "F.Fab")
		)
		(fp_line
			(start 0.120396 0.3048)
			(end 0.120396 0.2794)
			(stroke
				(width 0.1)
				(type default)
			)
			(layer "F.Fab")
		)
		(fp_line
			(start 0.120396 0.2794)
			(end -0.12065 0.2794)
			(stroke
				(width 0.1)
				(type default)
			)
			(layer "F.Fab")
		)
		(fp_line
			(start -0.12065 0.3048)
			(end -0.67945 0.3048)
			(stroke
				(width 0.1)
				(type default)
			)
			(layer "F.Fab")
		)
		(fp_line
			(start -0.12065 0.2794)
			(end -0.12065 0.3048)
			(stroke
				(width 0.1)
				(type default)
			)
			(layer "F.Fab")
		)
		(fp_line
			(start -0.12065 -0.2794)
			(end 0.12065 -0.2794)
			(stroke
				(width 0.1)
				(type default)
			)
			(layer "F.Fab")
		)
		(fp_line
			(start -0.12065 -0.305054)
			(end -0.12065 -0.2794)
			(stroke
				(width 0.1)
				(type default)
			)
			(layer "F.Fab")
		)
		(fp_line
			(start -0.67945 0.3048)
			(end -0.67945 -0.305054)
			(stroke
				(width 0.1)
				(type default)
			)
			(layer "F.Fab")
		)
		(fp_line
			(start -0.67945 -0.305054)
			(end -0.12065 -0.305054)
			(stroke
				(width 0.1)
				(type default)
			)
			(layer "F.Fab")
		)
		(pad "1" smd circle
			(at -0.40005 0 180)
			(size 0 0)
			(layers "F.Cu" "F.Mask" "F.Paste")
			(net "HSC_TYPE_ADC")
		)
		(pad "2" smd circle
			(at 0.40005 0 180)
			(size 0 0)
			(layers "F.Cu" "F.Mask" "F.Paste")
			(net "GND")
		)
	)
	(footprint ""
		(layer "F.Cu")
		(at 239.94999 -39.420038)
		(property "Reference" "H76"
			(at -0.155702 -3.208274 0)
			(unlocked yes)
			(layer "B.SilkS")
			(effects
				(font
					(size 0.7874 0.5842)
					(thickness 0.1524)
				)
				(justify left mirror)
			)
		)
		(property "Value" ""
			(at 0 0 0)
			(layer "F.Fab")
			(effects
				(font
					(size 1.27 1.27)
				)
			)
		)
		(duplicate_pad_numbers_are_jumpers no)
		(pad "1" thru_hole rect
			(at 0 0)
			(size 4.2164 5.0038)
			(drill 2.0066
				(offset 0.099822 0)
			)
			(layers "*.Cu" "*.Mask")
			(remove_unused_layers no)
			(net "GND")
			(clearance -0.8509)
			(padstack
				(mode front_inner_back)
				(layer "Inner"
					(shape circle)
					(size 4.0132 4.0132)
					(clearance -0.7493)
				)
				(layer "B.Cu"
					(shape circle)
					(size 4.0132 4.0132)
					(clearance -0.7493)
				)
			)
		)
	)
	(footprint ""
		(layer "F.Cu")
		(at 404.564342 -416.899344 -90)
		(property "Reference" "C6588"
			(at 0 0 270)
			(layer "F.SilkS")
			(hide yes)
			(effects
				(font
					(size 1.27 1.27)
				)
			)
		)
		(property "Value" ""
			(at 0 0 270)
			(layer "F.Fab")
			(effects
				(font
					(size 1.27 1.27)
				)
			)
		)
		(duplicate_pad_numbers_are_jumpers no)
		(fp_line
			(start -0.299974 0.150114)
			(end -0.299974 -0.150114)
			(stroke
				(width 0.1)
				(type default)
			)
			(layer "F.Fab")
		)
		(fp_line
			(start 0.299974 0.150114)
			(end -0.299974 0.150114)
			(stroke
				(width 0.1)
				(type default)
			)
			(layer "F.Fab")
		)
		(fp_line
			(start -0.299974 -0.150114)
			(end 0.299974 -0.150114)
			(stroke
				(width 0.1)
				(type default)
			)
			(layer "F.Fab")
		)
		(fp_line
			(start 0.299974 -0.150114)
			(end 0.299974 0.150114)
			(stroke
				(width 0.1)
				(type default)
			)
			(layer "F.Fab")
		)
		(pad "1" smd rect
			(at -0.2667 0 270)
			(size 0.3048 0.381)
			(layers "F.Cu" "F.Mask" "F.Paste")
			(net "P5E_CPU0_P2_TX_BUF_C_DN<11>")
		)
		(pad "2" smd rect
			(at 0.2667 0 270)
			(size 0.3048 0.381)
			(layers "F.Cu" "F.Mask" "F.Paste")
			(net "P5E_CPU0_P2_TX_BUF_DN<11>")
		)
	)
	(footprint ""
		(layer "F.Cu")
		(at 369.687094 -404.873206 -90)
		(property "Reference" "R1108"
			(at 0 0 270)
			(layer "F.SilkS")
			(hide yes)
			(effects
				(font
					(size 1.27 1.27)
				)
			)
		)
		(property "Value" ""
			(at 0 0 270)
			(layer "F.Fab")
			(effects
				(font
					(size 1.27 1.27)
				)
			)
		)
		(duplicate_pad_numbers_are_jumpers no)
		(fp_line
			(start -0.32512 0.175006)
			(end -0.32512 -0.175006)
			(stroke
				(width 0.1)
				(type default)
			)
			(layer "F.Fab")
		)
		(fp_line
			(start 0.32512 0.175006)
			(end -0.32512 0.175006)
			(stroke
				(width 0.1)
				(type default)
			)
			(layer "F.Fab")
		)
		(fp_line
			(start -0.32512 -0.175006)
			(end 0.32512 -0.175006)
			(stroke
				(width 0.1)
				(type default)
			)
			(layer "F.Fab")
		)
		(fp_line
			(start 0.32512 -0.175006)
			(end 0.32512 0.175006)
			(stroke
				(width 0.1)
				(type default)
			)
			(layer "F.Fab")
		)
		(pad "1" smd rect
			(at -0.2667 0 270)
			(size 0.3048 0.381)
			(layers "F.Cu" "F.Mask" "F.Paste")
			(net "P1V8_CPU0_RT_1D")
		)
		(pad "2" smd rect
			(at 0.2667 0 90)
			(size 0.3048 0.381)
			(layers "F.Cu" "F.Mask" "F.Paste")
			(net "JTAG_TEST_MODE_RT_CPU0_P3")
		)
	)
	(footprint ""
		(layer "F.Cu")
		(at 193.167 -129.377948 90)
		(property "Reference" "R1564"
			(at 0 0 90)
			(layer "F.SilkS")
			(hide yes)
			(effects
				(font
					(size 1.27 1.27)
				)
			)
		)
		(property "Value" ""
			(at 0 0 90)
			(layer "F.Fab")
			(effects
				(font
					(size 1.27 1.27)
				)
			)
		)
		(duplicate_pad_numbers_are_jumpers no)
		(fp_line
			(start 0.7874 -0.4064)
			(end 0.7874 0.4064)
			(stroke
				(width 0.1524)
				(type default)
			)
			(layer "F.SilkS")
		)
		(fp_line
			(start -0.7874 -0.4064)
			(end 0.7874 -0.4064)
			(stroke
				(width 0.1524)
				(type default)
			)
			(layer "F.SilkS")
		)
		(fp_line
			(start 0.7874 0.4064)
			(end -0.7874 0.4064)
			(stroke
				(width 0.1524)
				(type default)
			)
			(layer "F.SilkS")
		)
		(fp_line
			(start -0.7874 0.4064)
			(end -0.7874 -0.4064)
			(stroke
				(width 0.1524)
				(type default)
			)
			(layer "F.SilkS")
		)
		(fp_line
			(start -0.12065 -0.305054)
			(end -0.12065 -0.2794)
			(stroke
				(width 0.1)
				(type default)
			)
			(layer "F.Fab")
		)
		(fp_line
			(start -0.67945 -0.305054)
			(end -0.12065 -0.305054)
			(stroke
				(width 0.1)
				(type default)
			)
			(layer "F.Fab")
		)
		(fp_line
			(start 0.67945 -0.3048)
			(end 0.67945 0.3048)
			(stroke
				(width 0.1)
				(type default)
			)
			(layer "F.Fab")
		)
		(fp_line
			(start 0.12065 -0.3048)
			(end 0.67945 -0.3048)
			(stroke
				(width 0.1)
				(type default)
			)
			(layer "F.Fab")
		)
		(fp_line
			(start 0.12065 -0.2794)
			(end 0.12065 -0.3048)
			(stroke
				(width 0.1)
				(type default)
			)
			(layer "F.Fab")
		)
		(fp_line
			(start -0.12065 -0.2794)
			(end 0.12065 -0.2794)
			(stroke
				(width 0.1)
				(type default)
			)
			(layer "F.Fab")
		)
		(fp_line
			(start 0.120396 0.2794)
			(end -0.12065 0.2794)
			(stroke
				(width 0.1)
				(type default)
			)
			(layer "F.Fab")
		)
		(fp_line
			(start -0.12065 0.2794)
			(end -0.12065 0.3048)
			(stroke
				(width 0.1)
				(type default)
			)
			(layer "F.Fab")
		)
		(fp_line
			(start 0.67945 0.3048)
			(end 0.120396 0.3048)
			(stroke
				(width 0.1)
				(type default)
			)
			(layer "F.Fab")
		)
		(fp_line
			(start 0.120396 0.3048)
			(end 0.120396 0.2794)
			(stroke
				(width 0.1)
				(type default)
			)
			(layer "F.Fab")
		)
		(fp_line
			(start -0.12065 0.3048)
			(end -0.67945 0.3048)
			(stroke
				(width 0.1)
				(type default)
			)
			(layer "F.Fab")
		)
		(fp_line
			(start -0.67945 0.3048)
			(end -0.67945 -0.305054)
			(stroke
				(width 0.1)
				(type default)
			)
			(layer "F.Fab")
		)
		(pad "1" smd circle
			(at -0.40005 0 90)
			(size 0 0)
			(layers "F.Cu" "F.Mask" "F.Paste")
			(net "FM_ROM_LS_EN")
		)
		(pad "2" smd circle
			(at 0.40005 0 90)
			(size 0 0)
			(layers "F.Cu" "F.Mask" "F.Paste")
			(net "ROM_LS_EN")
		)
	)
	(footprint ""
		(layer "F.Cu")
		(at 67.71513 -339.857588 90)
		(property "Reference" "PC404_3"
			(at 0 0 90)
			(layer "F.SilkS")
			(hide yes)
			(effects
				(font
					(size 1.27 1.27)
				)
			)
		)
		(property "Value" ""
			(at 0 0 90)
			(layer "F.Fab")
			(effects
				(font
					(size 1.27 1.27)
				)
			)
		)
		(duplicate_pad_numbers_are_jumpers no)
		(fp_line
			(start 0.7874 -0.4064)
			(end 0.7874 0.4064)
			(stroke
				(width 0.1524)
				(type default)
			)
			(layer "F.SilkS")
		)
		(fp_line
			(start -0.7874 -0.4064)
			(end 0.7874 -0.4064)
			(stroke
				(width 0.1524)
				(type default)
			)
			(layer "F.SilkS")
		)
		(fp_line
			(start 0.7874 0.4064)
			(end -0.7874 0.4064)
			(stroke
				(width 0.1524)
				(type default)
			)
			(layer "F.SilkS")
		)
		(fp_line
			(start -0.7874 0.4064)
			(end -0.7874 -0.4064)
			(stroke
				(width 0.1524)
				(type default)
			)
			(layer "F.SilkS")
		)
		(fp_line
			(start -0.12065 -0.305054)
			(end -0.12065 -0.2794)
			(stroke
				(width 0.1)
				(type default)
			)
			(layer "F.Fab")
		)
		(fp_line
			(start -0.67945 -0.305054)
			(end -0.12065 -0.305054)
			(stroke
				(width 0.1)
				(type default)
			)
			(layer "F.Fab")
		)
		(fp_line
			(start 0.67945 -0.3048)
			(end 0.67945 0.3048)
			(stroke
				(width 0.1)
				(type default)
			)
			(layer "F.Fab")
		)
		(fp_line
			(start 0.12065 -0.3048)
			(end 0.67945 -0.3048)
			(stroke
				(width 0.1)
				(type default)
			)
			(layer "F.Fab")
		)
		(fp_line
			(start 0.12065 -0.2794)
			(end 0.12065 -0.3048)
			(stroke
				(width 0.1)
				(type default)
			)
			(layer "F.Fab")
		)
		(fp_line
			(start -0.12065 -0.2794)
			(end 0.12065 -0.2794)
			(stroke
				(width 0.1)
				(type default)
			)
			(layer "F.Fab")
		)
		(fp_line
			(start 0.120396 0.2794)
			(end -0.12065 0.2794)
			(stroke
				(width 0.1)
				(type default)
			)
			(layer "F.Fab")
		)
		(fp_line
			(start -0.12065 0.2794)
			(end -0.12065 0.3048)
			(stroke
				(width 0.1)
				(type default)
			)
			(layer "F.Fab")
		)
		(fp_line
			(start 0.67945 0.3048)
			(end 0.120396 0.3048)
			(stroke
				(width 0.1)
				(type default)
			)
			(layer "F.Fab")
		)
		(fp_line
			(start 0.120396 0.3048)
			(end 0.120396 0.2794)
			(stroke
				(width 0.1)
				(type default)
			)
			(layer "F.Fab")
		)
		(fp_line
			(start -0.12065 0.3048)
			(end -0.67945 0.3048)
			(stroke
				(width 0.1)
				(type default)
			)
			(layer "F.Fab")
		)
		(fp_line
			(start -0.67945 0.3048)
			(end -0.67945 -0.305054)
			(stroke
				(width 0.1)
				(type default)
			)
			(layer "F.Fab")
		)
		(pad "1" smd circle
			(at -0.40005 0 90)
			(size 0 0)
			(layers "F.Cu" "F.Mask" "F.Paste")
			(net "PVDDCR_CPU1_P1_VCCS")
		)
		(pad "2" smd circle
			(at 0.40005 0 90)
			(size 0 0)
			(layers "F.Cu" "F.Mask" "F.Paste")
			(net "GND")
		)
	)
	(footprint ""
		(layer "F.Cu")
		(at 410.53004 -383.88163 -90)
		(property "Reference" "C855"
			(at 0 0 270)
			(layer "F.SilkS")
			(hide yes)
			(effects
				(font
					(size 1.27 1.27)
				)
			)
		)
		(property "Value" ""
			(at 0 0 270)
			(layer "F.Fab")
			(effects
				(font
					(size 1.27 1.27)
				)
			)
		)
		(duplicate_pad_numbers_are_jumpers no)
		(fp_line
			(start -0.299974 0.150114)
			(end -0.299974 -0.150114)
			(stroke
				(width 0.1)
				(type default)
			)
			(layer "F.Fab")
		)
		(fp_line
			(start 0.299974 0.150114)
			(end -0.299974 0.150114)
			(stroke
				(width 0.1)
				(type default)
			)
			(layer "F.Fab")
		)
		(fp_line
			(start -0.299974 -0.150114)
			(end 0.299974 -0.150114)
			(stroke
				(width 0.1)
				(type default)
			)
			(layer "F.Fab")
		)
		(fp_line
			(start 0.299974 -0.150114)
			(end 0.299974 0.150114)
			(stroke
				(width 0.1)
				(type default)
			)
			(layer "F.Fab")
		)
		(pad "1" smd rect
			(at -0.2667 0 270)
			(size 0.3048 0.381)
			(layers "F.Cu" "F.Mask" "F.Paste")
			(net "P5E_CPU0_P2_TX_C_DP<7>")
		)
		(pad "2" smd rect
			(at 0.2667 0 270)
			(size 0.3048 0.381)
			(layers "F.Cu" "F.Mask" "F.Paste")
			(net "P5E_CPU0_P2_TX_DP<7>")
		)
	)
	(footprint ""
		(layer "F.Cu")
		(at 88.23452 -159.029908 -90)
		(property "Reference" "PL30"
			(at -0.049784 -3.804412 90)
			(unlocked yes)
			(layer "F.SilkS")
			(effects
				(font
					(size 0.7874 0.5842)
					(thickness 0.1524)
				)
				(justify left)
			)
		)
		(property "Value" ""
			(at 0 0 270)
			(layer "F.Fab")
			(effects
				(font
					(size 1.27 1.27)
				)
			)
		)
		(duplicate_pad_numbers_are_jumpers no)
		(fp_line
			(start -3.050032 2.999994)
			(end 3.050032 2.999994)
			(stroke
				(width 0.1524)
				(type default)
			)
			(layer "F.SilkS")
		)
		(fp_line
			(start 3.050032 2.999994)
			(end 3.050032 1.4478)
			(stroke
				(width 0.1524)
				(type default)
			)
			(layer "F.SilkS")
		)
		(fp_line
			(start -3.050032 1.4478)
			(end -3.050032 2.999994)
			(stroke
				(width 0.1524)
				(type default)
			)
			(layer "F.SilkS")
		)
		(fp_line
			(start 3.050032 -1.4478)
			(end 3.050032 -2.999994)
			(stroke
				(width 0.1524)
				(type default)
			)
			(layer "F.SilkS")
		)
		(fp_line
			(start -3.050032 -2.999994)
			(end -3.050032 -1.4478)
			(stroke
				(width 0.1524)
				(type default)
			)
			(layer "F.SilkS")
		)
		(fp_line
			(start 3.050032 -2.999994)
			(end -3.050032 -2.999994)
			(stroke
				(width 0.1524)
				(type default)
			)
			(layer "F.SilkS")
		)
		(fp_line
			(start -3.050032 2.999994)
			(end 3.050032 2.999994)
			(stroke
				(width 0.1)
				(type default)
			)
			(layer "F.Fab")
		)
		(fp_line
			(start 3.050032 2.999994)
			(end 3.050032 -2.999994)
			(stroke
				(width 0.1)
				(type default)
			)
			(layer "F.Fab")
		)
		(fp_line
			(start -3.050032 -2.999994)
			(end -3.050032 2.999994)
			(stroke
				(width 0.1)
				(type default)
			)
			(layer "F.Fab")
		)
		(fp_line
			(start 3.050032 -2.999994)
			(end -3.050032 -2.999994)
			(stroke
				(width 0.1)
				(type default)
			)
			(layer "F.Fab")
		)
		(pad "1" smd rect
			(at -2.525014 0 270)
			(size 1.651 2.6162)
			(layers "F.Cu" "F.Mask" "F.Paste")
			(net "SW_P12V_AUX_PVDDCR_CPU0_P1_FLT")
		)
		(pad "2" smd rect
			(at 2.525014 0 270)
			(size 1.651 2.6162)
			(layers "F.Cu" "F.Mask" "F.Paste")
			(net "P12V_AUX")
		)
	)
	(footprint ""
		(layer "F.Cu")
		(at 279.513792 -118.70817 180)
		(property "Reference" "R3394"
			(at 0 0 180)
			(layer "F.SilkS")
			(hide yes)
			(effects
				(font
					(size 1.27 1.27)
				)
			)
		)
		(property "Value" ""
			(at 0 0 180)
			(layer "F.Fab")
			(effects
				(font
					(size 1.27 1.27)
				)
			)
		)
		(duplicate_pad_numbers_are_jumpers no)
		(fp_line
			(start 0.7874 0.4064)
			(end -0.7874 0.4064)
			(stroke
				(width 0.1524)
				(type default)
			)
			(layer "F.SilkS")
		)
		(fp_line
			(start 0.7874 -0.4064)
			(end 0.7874 0.4064)
			(stroke
				(width 0.1524)
				(type default)
			)
			(layer "F.SilkS")
		)
		(fp_line
			(start -0.7874 0.4064)
			(end -0.7874 -0.4064)
			(stroke
				(width 0.1524)
				(type default)
			)
			(layer "F.SilkS")
		)
		(fp_line
			(start -0.7874 -0.4064)
			(end 0.7874 -0.4064)
			(stroke
				(width 0.1524)
				(type default)
			)
			(layer "F.SilkS")
		)
		(fp_line
			(start 0.67945 0.3048)
			(end 0.120396 0.3048)
			(stroke
				(width 0.1)
				(type default)
			)
			(layer "F.Fab")
		)
		(fp_line
			(start 0.67945 -0.3048)
			(end 0.67945 0.3048)
			(stroke
				(width 0.1)
				(type default)
			)
			(layer "F.Fab")
		)
		(fp_line
			(start 0.12065 -0.2794)
			(end 0.12065 -0.3048)
			(stroke
				(width 0.1)
				(type default)
			)
			(layer "F.Fab")
		)
		(fp_line
			(start 0.12065 -0.3048)
			(end 0.67945 -0.3048)
			(stroke
				(width 0.1)
				(type default)
			)
			(layer "F.Fab")
		)
		(fp_line
			(start 0.120396 0.3048)
			(end 0.120396 0.2794)
			(stroke
				(width 0.1)
				(type default)
			)
			(layer "F.Fab")
		)
		(fp_line
			(start 0.120396 0.2794)
			(end -0.12065 0.2794)
			(stroke
				(width 0.1)
				(type default)
			)
			(layer "F.Fab")
		)
		(fp_line
			(start -0.12065 0.3048)
			(end -0.67945 0.3048)
			(stroke
				(width 0.1)
				(type default)
			)
			(layer "F.Fab")
		)
		(fp_line
			(start -0.12065 0.2794)
			(end -0.12065 0.3048)
			(stroke
				(width 0.1)
				(type default)
			)
			(layer "F.Fab")
		)
		(fp_line
			(start -0.12065 -0.2794)
			(end 0.12065 -0.2794)
			(stroke
				(width 0.1)
				(type default)
			)
			(layer "F.Fab")
		)
		(fp_line
			(start -0.12065 -0.305054)
			(end -0.12065 -0.2794)
			(stroke
				(width 0.1)
				(type default)
			)
			(layer "F.Fab")
		)
		(fp_line
			(start -0.67945 0.3048)
			(end -0.67945 -0.305054)
			(stroke
				(width 0.1)
				(type default)
			)
			(layer "F.Fab")
		)
		(fp_line
			(start -0.67945 -0.305054)
			(end -0.12065 -0.305054)
			(stroke
				(width 0.1)
				(type default)
			)
			(layer "F.Fab")
		)
		(pad "1" smd circle
			(at -0.40005 0 180)
			(size 0 0)
			(layers "F.Cu" "F.Mask" "F.Paste")
			(net "SMB_IOEXP_3V3AUX_SDA_R")
		)
		(pad "2" smd circle
			(at 0.40005 0 180)
			(size 0 0)
			(layers "F.Cu" "F.Mask" "F.Paste")
			(net "SMB_IOEXP_3V3AUX_SDA")
		)
	)
	(footprint ""
		(layer "F.Cu")
		(at 136.840976 -380.385828)
		(property "Reference" "C48"
			(at 0 0 0)
			(layer "F.SilkS")
			(hide yes)
			(effects
				(font
					(size 1.27 1.27)
				)
			)
		)
		(property "Value" ""
			(at 0 0 0)
			(layer "F.Fab")
			(effects
				(font
					(size 1.27 1.27)
				)
			)
		)
		(duplicate_pad_numbers_are_jumpers no)
		(fp_line
			(start -0.299974 -0.150114)
			(end 0.299974 -0.150114)
			(stroke
				(width 0.1)
				(type default)
			)
			(layer "F.Fab")
		)
		(fp_line
			(start -0.299974 0.150114)
			(end -0.299974 -0.150114)
			(stroke
				(width 0.1)
				(type default)
			)
			(layer "F.Fab")
		)
		(fp_line
			(start 0.299974 -0.150114)
			(end 0.299974 0.150114)
			(stroke
				(width 0.1)
				(type default)
			)
			(layer "F.Fab")
		)
		(fp_line
			(start 0.299974 0.150114)
			(end -0.299974 0.150114)
			(stroke
				(width 0.1)
				(type default)
			)
			(layer "F.Fab")
		)
		(pad "1" smd rect
			(at -0.2667 0)
			(size 0.3048 0.381)
			(layers "F.Cu" "F.Mask" "F.Paste")
			(net "P5E_CPU1_P3_TX_C_DN<15>")
		)
		(pad "2" smd rect
			(at 0.2667 0)
			(size 0.3048 0.381)
			(layers "F.Cu" "F.Mask" "F.Paste")
			(net "P5E_CPU1_P3_TX_DN<15>")
		)
	)
	(footprint ""
		(layer "F.Cu")
		(at 18.702782 -132.489702)
		(property "Reference" "R3335"
			(at 0 0 0)
			(layer "F.SilkS")
			(hide yes)
			(effects
				(font
					(size 1.27 1.27)
				)
			)
		)
		(property "Value" ""
			(at 0 0 0)
			(layer "F.Fab")
			(effects
				(font
					(size 1.27 1.27)
				)
			)
		)
		(duplicate_pad_numbers_are_jumpers no)
		(fp_line
			(start -0.7874 -0.4064)
			(end 0.7874 -0.4064)
			(stroke
				(width 0.1524)
				(type default)
			)
			(layer "F.SilkS")
		)
		(fp_line
			(start -0.7874 0.4064)
			(end -0.7874 -0.4064)
			(stroke
				(width 0.1524)
				(type default)
			)
			(layer "F.SilkS")
		)
		(fp_line
			(start 0.7874 -0.4064)
			(end 0.7874 0.4064)
			(stroke
				(width 0.1524)
				(type default)
			)
			(layer "F.SilkS")
		)
		(fp_line
			(start 0.7874 0.4064)
			(end -0.7874 0.4064)
			(stroke
				(width 0.1524)
				(type default)
			)
			(layer "F.SilkS")
		)
		(fp_line
			(start -0.67945 -0.305054)
			(end -0.12065 -0.305054)
			(stroke
				(width 0.1)
				(type default)
			)
			(layer "F.Fab")
		)
		(fp_line
			(start -0.67945 0.3048)
			(end -0.67945 -0.305054)
			(stroke
				(width 0.1)
				(type default)
			)
			(layer "F.Fab")
		)
		(fp_line
			(start -0.12065 -0.305054)
			(end -0.12065 -0.2794)
			(stroke
				(width 0.1)
				(type default)
			)
			(layer "F.Fab")
		)
		(fp_line
			(start -0.12065 -0.2794)
			(end 0.12065 -0.2794)
			(stroke
				(width 0.1)
				(type default)
			)
			(layer "F.Fab")
		)
		(fp_line
			(start -0.12065 0.2794)
			(end -0.12065 0.3048)
			(stroke
				(width 0.1)
				(type default)
			)
			(layer "F.Fab")
		)
		(fp_line
			(start -0.12065 0.3048)
			(end -0.67945 0.3048)
			(stroke
				(width 0.1)
				(type default)
			)
			(layer "F.Fab")
		)
		(fp_line
			(start 0.120396 0.2794)
			(end -0.12065 0.2794)
			(stroke
				(width 0.1)
				(type default)
			)
			(layer "F.Fab")
		)
		(fp_line
			(start 0.120396 0.3048)
			(end 0.120396 0.2794)
			(stroke
				(width 0.1)
				(type default)
			)
			(layer "F.Fab")
		)
		(fp_line
			(start 0.12065 -0.3048)
			(end 0.67945 -0.3048)
			(stroke
				(width 0.1)
				(type default)
			)
			(layer "F.Fab")
		)
		(fp_line
			(start 0.12065 -0.2794)
			(end 0.12065 -0.3048)
			(stroke
				(width 0.1)
				(type default)
			)
			(layer "F.Fab")
		)
		(fp_line
			(start 0.67945 -0.3048)
			(end 0.67945 0.3048)
			(stroke
				(width 0.1)
				(type default)
			)
			(layer "F.Fab")
		)
		(fp_line
			(start 0.67945 0.3048)
			(end 0.120396 0.3048)
			(stroke
				(width 0.1)
				(type default)
			)
			(layer "F.Fab")
		)
		(pad "1" smd circle
			(at -0.40005 0)
			(size 0 0)
			(layers "F.Cu" "F.Mask" "F.Paste")
			(net "CLK_100M_BMC_RC_DP_R")
		)
		(pad "2" smd circle
			(at 0.40005 0)
			(size 0 0)
			(layers "F.Cu" "F.Mask" "F.Paste")
			(net "CLK_100M_BMC_RC_DP")
		)
	)
	(footprint ""
		(layer "F.Cu")
		(at 200.952608 -110.577376 180)
		(property "Reference" "R3478"
			(at 0 0 180)
			(layer "F.SilkS")
			(hide yes)
			(effects
				(font
					(size 1.27 1.27)
				)
			)
		)
		(property "Value" ""
			(at 0 0 180)
			(layer "F.Fab")
			(effects
				(font
					(size 1.27 1.27)
				)
			)
		)
		(duplicate_pad_numbers_are_jumpers no)
		(fp_line
			(start 0.7874 0.4064)
			(end -0.7874 0.4064)
			(stroke
				(width 0.1524)
				(type default)
			)
			(layer "F.SilkS")
		)
		(fp_line
			(start 0.7874 -0.4064)
			(end 0.7874 0.4064)
			(stroke
				(width 0.1524)
				(type default)
			)
			(layer "F.SilkS")
		)
		(fp_line
			(start -0.7874 0.4064)
			(end -0.7874 -0.4064)
			(stroke
				(width 0.1524)
				(type default)
			)
			(layer "F.SilkS")
		)
		(fp_line
			(start -0.7874 -0.4064)
			(end 0.7874 -0.4064)
			(stroke
				(width 0.1524)
				(type default)
			)
			(layer "F.SilkS")
		)
		(fp_line
			(start 0.67945 0.3048)
			(end 0.120396 0.3048)
			(stroke
				(width 0.1)
				(type default)
			)
			(layer "F.Fab")
		)
		(fp_line
			(start 0.67945 -0.3048)
			(end 0.67945 0.3048)
			(stroke
				(width 0.1)
				(type default)
			)
			(layer "F.Fab")
		)
		(fp_line
			(start 0.12065 -0.2794)
			(end 0.12065 -0.3048)
			(stroke
				(width 0.1)
				(type default)
			)
			(layer "F.Fab")
		)
		(fp_line
			(start 0.12065 -0.3048)
			(end 0.67945 -0.3048)
			(stroke
				(width 0.1)
				(type default)
			)
			(layer "F.Fab")
		)
		(fp_line
			(start 0.120396 0.3048)
			(end 0.120396 0.2794)
			(stroke
				(width 0.1)
				(type default)
			)
			(layer "F.Fab")
		)
		(fp_line
			(start 0.120396 0.2794)
			(end -0.12065 0.2794)
			(stroke
				(width 0.1)
				(type default)
			)
			(layer "F.Fab")
		)
		(fp_line
			(start -0.12065 0.3048)
			(end -0.67945 0.3048)
			(stroke
				(width 0.1)
				(type default)
			)
			(layer "F.Fab")
		)
		(fp_line
			(start -0.12065 0.2794)
			(end -0.12065 0.3048)
			(stroke
				(width 0.1)
				(type default)
			)
			(layer "F.Fab")
		)
		(fp_line
			(start -0.12065 -0.2794)
			(end 0.12065 -0.2794)
			(stroke
				(width 0.1)
				(type default)
			)
			(layer "F.Fab")
		)
		(fp_line
			(start -0.12065 -0.305054)
			(end -0.12065 -0.2794)
			(stroke
				(width 0.1)
				(type default)
			)
			(layer "F.Fab")
		)
		(fp_line
			(start -0.67945 0.3048)
			(end -0.67945 -0.305054)
			(stroke
				(width 0.1)
				(type default)
			)
			(layer "F.Fab")
		)
		(fp_line
			(start -0.67945 -0.305054)
			(end -0.12065 -0.305054)
			(stroke
				(width 0.1)
				(type default)
			)
			(layer "F.Fab")
		)
		(pad "1" smd circle
			(at -0.40005 0 180)
			(size 0 0)
			(layers "F.Cu" "F.Mask" "F.Paste")
			(net "GPU_FPGA_EROT_RST_N")
		)
		(pad "2" smd circle
			(at 0.40005 0 180)
			(size 0 0)
			(layers "F.Cu" "F.Mask" "F.Paste")
			(net "GPU_FPGA_EROT_RST_R_N")
		)
	)
	(footprint ""
		(layer "F.Cu")
		(at 240.298224 -159.680148)
		(property "Reference" "R6110"
			(at 0 0 0)
			(layer "F.SilkS")
			(hide yes)
			(effects
				(font
					(size 1.27 1.27)
				)
			)
		)
		(property "Value" ""
			(at 0 0 0)
			(layer "F.Fab")
			(effects
				(font
					(size 1.27 1.27)
				)
			)
		)
		(duplicate_pad_numbers_are_jumpers no)
		(fp_line
			(start -0.7874 -0.4064)
			(end 0.7874 -0.4064)
			(stroke
				(width 0.1524)
				(type default)
			)
			(layer "F.SilkS")
		)
		(fp_line
			(start -0.7874 0.4064)
			(end -0.7874 -0.4064)
			(stroke
				(width 0.1524)
				(type default)
			)
			(layer "F.SilkS")
		)
		(fp_line
			(start 0.7874 -0.4064)
			(end 0.7874 0.4064)
			(stroke
				(width 0.1524)
				(type default)
			)
			(layer "F.SilkS")
		)
		(fp_line
			(start 0.7874 0.4064)
			(end -0.7874 0.4064)
			(stroke
				(width 0.1524)
				(type default)
			)
			(layer "F.SilkS")
		)
		(fp_line
			(start -0.67945 -0.305054)
			(end -0.12065 -0.305054)
			(stroke
				(width 0.1)
				(type default)
			)
			(layer "F.Fab")
		)
		(fp_line
			(start -0.67945 0.3048)
			(end -0.67945 -0.305054)
			(stroke
				(width 0.1)
				(type default)
			)
			(layer "F.Fab")
		)
		(fp_line
			(start -0.12065 -0.305054)
			(end -0.12065 -0.2794)
			(stroke
				(width 0.1)
				(type default)
			)
			(layer "F.Fab")
		)
		(fp_line
			(start -0.12065 -0.2794)
			(end 0.12065 -0.2794)
			(stroke
				(width 0.1)
				(type default)
			)
			(layer "F.Fab")
		)
		(fp_line
			(start -0.12065 0.2794)
			(end -0.12065 0.3048)
			(stroke
				(width 0.1)
				(type default)
			)
			(layer "F.Fab")
		)
		(fp_line
			(start -0.12065 0.3048)
			(end -0.67945 0.3048)
			(stroke
				(width 0.1)
				(type default)
			)
			(layer "F.Fab")
		)
		(fp_line
			(start 0.120396 0.2794)
			(end -0.12065 0.2794)
			(stroke
				(width 0.1)
				(type default)
			)
			(layer "F.Fab")
		)
		(fp_line
			(start 0.120396 0.3048)
			(end 0.120396 0.2794)
			(stroke
				(width 0.1)
				(type default)
			)
			(layer "F.Fab")
		)
		(fp_line
			(start 0.12065 -0.3048)
			(end 0.67945 -0.3048)
			(stroke
				(width 0.1)
				(type default)
			)
			(layer "F.Fab")
		)
		(fp_line
			(start 0.12065 -0.2794)
			(end 0.12065 -0.3048)
			(stroke
				(width 0.1)
				(type default)
			)
			(layer "F.Fab")
		)
		(fp_line
			(start 0.67945 -0.3048)
			(end 0.67945 0.3048)
			(stroke
				(width 0.1)
				(type default)
			)
			(layer "F.Fab")
		)
		(fp_line
			(start 0.67945 0.3048)
			(end 0.120396 0.3048)
			(stroke
				(width 0.1)
				(type default)
			)
			(layer "F.Fab")
		)
		(pad "1" smd circle
			(at -0.40005 0)
			(size 0 0)
			(layers "F.Cu" "F.Mask" "F.Paste")
			(net "JTAG_CPUX_TDO_R")
		)
		(pad "2" smd circle
			(at 0.40005 0)
			(size 0 0)
			(layers "F.Cu" "F.Mask" "F.Paste")
			(net "JTAG_CPUX_TDO")
		)
	)
	(footprint ""
		(layer "F.Cu")
		(at 149.478746 -408.517344 -90)
		(property "Reference" "C6715"
			(at 0 0 270)
			(layer "F.SilkS")
			(hide yes)
			(effects
				(font
					(size 1.27 1.27)
				)
			)
		)
		(property "Value" ""
			(at 0 0 270)
			(layer "F.Fab")
			(effects
				(font
					(size 1.27 1.27)
				)
			)
		)
		(duplicate_pad_numbers_are_jumpers no)
		(fp_line
			(start -0.299974 0.150114)
			(end -0.299974 -0.150114)
			(stroke
				(width 0.1)
				(type default)
			)
			(layer "F.Fab")
		)
		(fp_line
			(start 0.299974 0.150114)
			(end -0.299974 0.150114)
			(stroke
				(width 0.1)
				(type default)
			)
			(layer "F.Fab")
		)
		(fp_line
			(start -0.299974 -0.150114)
			(end 0.299974 -0.150114)
			(stroke
				(width 0.1)
				(type default)
			)
			(layer "F.Fab")
		)
		(fp_line
			(start 0.299974 -0.150114)
			(end 0.299974 0.150114)
			(stroke
				(width 0.1)
				(type default)
			)
			(layer "F.Fab")
		)
		(pad "1" smd rect
			(at -0.2667 0 270)
			(size 0.3048 0.381)
			(layers "F.Cu" "F.Mask" "F.Paste")
			(net "P5E_CPU1_P2_TX_BUF_C_DP<11>")
		)
		(pad "2" smd rect
			(at 0.2667 0 270)
			(size 0.3048 0.381)
			(layers "F.Cu" "F.Mask" "F.Paste")
			(net "P5E_CPU1_P2_TX_BUF_DP<11>")
		)
	)
	(footprint ""
		(layer "F.Cu")
		(at 257.242056 -120.94337 180)
		(property "Reference" "R3713"
			(at 0 0 180)
			(layer "F.SilkS")
			(hide yes)
			(effects
				(font
					(size 1.27 1.27)
				)
			)
		)
		(property "Value" ""
			(at 0 0 180)
			(layer "F.Fab")
			(effects
				(font
					(size 1.27 1.27)
				)
			)
		)
		(duplicate_pad_numbers_are_jumpers no)
		(fp_line
			(start 0.7874 0.4064)
			(end -0.7874 0.4064)
			(stroke
				(width 0.1524)
				(type default)
			)
			(layer "F.SilkS")
		)
		(fp_line
			(start 0.7874 -0.4064)
			(end 0.7874 0.4064)
			(stroke
				(width 0.1524)
				(type default)
			)
			(layer "F.SilkS")
		)
		(fp_line
			(start -0.7874 0.4064)
			(end -0.7874 -0.4064)
			(stroke
				(width 0.1524)
				(type default)
			)
			(layer "F.SilkS")
		)
		(fp_line
			(start -0.7874 -0.4064)
			(end 0.7874 -0.4064)
			(stroke
				(width 0.1524)
				(type default)
			)
			(layer "F.SilkS")
		)
		(fp_line
			(start 0.67945 0.3048)
			(end 0.120396 0.3048)
			(stroke
				(width 0.1)
				(type default)
			)
			(layer "F.Fab")
		)
		(fp_line
			(start 0.67945 -0.3048)
			(end 0.67945 0.3048)
			(stroke
				(width 0.1)
				(type default)
			)
			(layer "F.Fab")
		)
		(fp_line
			(start 0.12065 -0.2794)
			(end 0.12065 -0.3048)
			(stroke
				(width 0.1)
				(type default)
			)
			(layer "F.Fab")
		)
		(fp_line
			(start 0.12065 -0.3048)
			(end 0.67945 -0.3048)
			(stroke
				(width 0.1)
				(type default)
			)
			(layer "F.Fab")
		)
		(fp_line
			(start 0.120396 0.3048)
			(end 0.120396 0.2794)
			(stroke
				(width 0.1)
				(type default)
			)
			(layer "F.Fab")
		)
		(fp_line
			(start 0.120396 0.2794)
			(end -0.12065 0.2794)
			(stroke
				(width 0.1)
				(type default)
			)
			(layer "F.Fab")
		)
		(fp_line
			(start -0.12065 0.3048)
			(end -0.67945 0.3048)
			(stroke
				(width 0.1)
				(type default)
			)
			(layer "F.Fab")
		)
		(fp_line
			(start -0.12065 0.2794)
			(end -0.12065 0.3048)
			(stroke
				(width 0.1)
				(type default)
			)
			(layer "F.Fab")
		)
		(fp_line
			(start -0.12065 -0.2794)
			(end 0.12065 -0.2794)
			(stroke
				(width 0.1)
				(type default)
			)
			(layer "F.Fab")
		)
		(fp_line
			(start -0.12065 -0.305054)
			(end -0.12065 -0.2794)
			(stroke
				(width 0.1)
				(type default)
			)
			(layer "F.Fab")
		)
		(fp_line
			(start -0.67945 0.3048)
			(end -0.67945 -0.305054)
			(stroke
				(width 0.1)
				(type default)
			)
			(layer "F.Fab")
		)
		(fp_line
			(start -0.67945 -0.305054)
			(end -0.12065 -0.305054)
			(stroke
				(width 0.1)
				(type default)
			)
			(layer "F.Fab")
		)
		(pad "1" smd circle
			(at -0.40005 0 180)
			(size 0 0)
			(layers "F.Cu" "F.Mask" "F.Paste")
			(net "SMB_VR_3V3AUX_SCL_R6")
		)
		(pad "2" smd circle
			(at 0.40005 0 180)
			(size 0 0)
			(layers "F.Cu" "F.Mask" "F.Paste")
			(net "SMB_VR_3V3AUX_SCL")
		)
	)
	(footprint ""
		(layer "F.Cu")
		(at 379.567948 -395.724634)
		(property "Reference" "U6013"
			(at -8.471916 -7.649972 0)
			(unlocked yes)
			(layer "F.SilkS")
			(effects
				(font
					(size 0.7874 0.5842)
					(thickness 0.1524)
				)
				(justify left)
			)
		)
		(property "Value" ""
			(at 0 0 0)
			(layer "F.Fab")
			(effects
				(font
					(size 1.27 1.27)
				)
			)
		)
		(duplicate_pad_numbers_are_jumpers no)
		(fp_line
			(start -11.400028 -4.45008)
			(end -9.794748 -4.45008)
			(stroke
				(width 0.1524)
				(type default)
			)
			(layer "F.SilkS")
		)
		(fp_line
			(start -11.400028 -0.972566)
			(end -11.400028 -4.45008)
			(stroke
				(width 0.1524)
				(type default)
			)
			(layer "F.SilkS")
		)
		(fp_line
			(start -11.400028 4.45008)
			(end -11.400028 0.145034)
			(stroke
				(width 0.1524)
				(type default)
			)
			(layer "F.SilkS")
		)
		(fp_line
			(start -10.023348 4.45008)
			(end -11.400028 4.45008)
			(stroke
				(width 0.1524)
				(type default)
			)
			(layer "F.SilkS")
		)
		(fp_line
			(start 9.661652 -4.45008)
			(end 11.400028 -4.45008)
			(stroke
				(width 0.1524)
				(type default)
			)
			(layer "F.SilkS")
		)
		(fp_line
			(start 11.400028 -4.45008)
			(end 11.400028 4.45008)
			(stroke
				(width 0.1524)
				(type default)
			)
			(layer "F.SilkS")
		)
		(fp_line
			(start 11.400028 4.45008)
			(end 9.534652 4.45008)
			(stroke
				(width 0.1524)
				(type default)
			)
			(layer "F.SilkS")
		)
		(fp_poly
			(pts
				(xy 10.450068 -4.45008) (xy 10.450068 -5.21208) (xy 12.162028 -5.21208) (xy 12.162028 -3.41884)
				(xy 11.400028 -3.41884) (xy 11.400028 -4.45008)
			)
			(stroke
				(width 0)
				(type default)
			)
			(fill yes)
			(layer "F.SilkS")
		)
		(fp_line
			(start -11.400028 -4.45008)
			(end -11.400028 4.45008)
			(stroke
				(width 0.1)
				(type default)
			)
			(layer "F.Fab")
		)
		(fp_line
			(start -11.400028 4.45008)
			(end 11.400028 4.45008)
			(stroke
				(width 0.1)
				(type default)
			)
			(layer "F.Fab")
		)
		(fp_line
			(start 11.400028 -4.45008)
			(end -11.400028 -4.45008)
			(stroke
				(width 0.1)
				(type default)
			)
			(layer "F.Fab")
		)
		(fp_line
			(start 11.400028 4.45008)
			(end 11.400028 -4.45008)
			(stroke
				(width 0.1)
				(type default)
			)
			(layer "F.Fab")
		)
		(fp_poly
			(pts
				(xy 10.450068 -4.45008) (xy 10.450068 -5.21208) (xy 12.162028 -5.21208) (xy 12.162028 -3.41884)
				(xy 11.400028 -3.41884) (xy 11.400028 -4.45008)
			)
			(stroke
				(width 0)
				(type default)
			)
			(fill yes)
			(layer "F.Fab")
		)
		(pad "A1" smd oval
			(at 11.050016 -3.938524)
			(size 0.254 0.3302)
			(layers "F.Cu" "F.Mask" "F.Paste")
			(net "NCF_A1_CPU0_P3_GND")
		)
		(pad "A35" smd oval
			(at 11.050016 3.940048)
			(size 0.254 0.3302)
			(layers "F.Cu" "F.Mask" "F.Paste")
			(net "NCF_CPU0_P3_GND")
		)
		(pad "AA10" smd circle
			(at 7.602728 -1.431798)
			(size 0.381 0.381)
			(layers "F.Cu" "F.Mask" "F.Paste")
			(net "P5E_CPU0_P3_TX_BUF_DN<14>")
		)
		(pad "AA29" smd circle
			(at 7.602728 2.032254)
			(size 0.381 0.381)
			(layers "F.Cu" "F.Mask" "F.Paste")
			(net "P5E_CPU0_P3_RX_DN<14>")
		)
		(pad "AB1" smd oval
			(at 7.450074 -3.938524)
			(size 0.254 0.3302)
			(layers "F.Cu" "F.Mask" "F.Paste")
			(net "P5E_CPU0_P3_RX_BUF_DP<14>")
		)
		(pad "AB35" smd oval
			(at 7.450074 3.940048)
			(size 0.254 0.3302)
			(layers "F.Cu" "F.Mask" "F.Paste")
			(net "P5E_CPU0_P3_TX_C_DN<14>")
		)
		(pad "AC4" smd circle
			(at 7.202678 -2.817368)
			(size 0.381 0.381)
			(layers "F.Cu" "F.Mask" "F.Paste")
			(net "GND")
		)
		(pad "AC13" smd circle
			(at 7.202678 -0.79629)
			(size 0.3048 0.3048)
			(layers "F.Cu" "F.Mask" "F.Paste")
			(net "GND")
		)
		(pad "AC17" smd circle
			(at 7.202678 -0.296164)
			(size 0.3048 0.3048)
			(layers "F.Cu" "F.Mask" "F.Paste")
			(net "P0V9_CPU0_RT3_2A")
		)
		(pad "AC20" smd circle
			(at 7.202678 0.203708)
			(size 0.3048 0.3048)
			(layers "F.Cu" "F.Mask" "F.Paste")
			(net "P0V9_CPU0_RT3_2A")
		)
		(pad "AC22" smd circle
			(at 7.202678 0.703834)
			(size 0.3048 0.3048)
			(layers "F.Cu" "F.Mask" "F.Paste")
			(net "GND")
		)
		(pad "AC32" smd circle
			(at 7.202678 2.724912)
			(size 0.381 0.381)
			(layers "F.Cu" "F.Mask" "F.Paste")
			(net "GND")
		)
		(pad "AD2" smd circle
			(at 7.1501 -3.41884)
			(size 0.3048 0.3048)
			(layers "F.Cu" "F.Mask" "F.Paste")
			(net "GND")
		)
		(pad "AD34" smd circle
			(at 7.1501 3.420364)
			(size 0.3048 0.3048)
			(layers "F.Cu" "F.Mask" "F.Paste")
			(net "GND")
		)
		(pad "AE1" smd oval
			(at 6.849872 -3.938524)
			(size 0.254 0.3302)
			(layers "F.Cu" "F.Mask" "F.Paste")
			(net "GND")
		)
		(pad "AE35" smd oval
			(at 6.849872 3.940048)
			(size 0.254 0.3302)
			(layers "F.Cu" "F.Mask" "F.Paste")
			(net "GND")
		)
		(pad "AF7" smd circle
			(at 6.802628 -2.12471)
			(size 0.381 0.381)
			(layers "F.Cu" "F.Mask" "F.Paste")
			(net "P5E_CPU0_P3_TX_BUF_DP<13>")
		)
		(pad "AF26" smd circle
			(at 6.802628 1.339342)
			(size 0.381 0.381)
			(layers "F.Cu" "F.Mask" "F.Paste")
			(net "P5E_CPU0_P3_RX_DP<13>")
		)
		(pad "AG2" smd circle
			(at 6.549898 -3.41884)
			(size 0.3048 0.3048)
			(layers "F.Cu" "F.Mask" "F.Paste")
			(net "P5E_CPU0_P3_RX_BUF_DN<13>")
		)
		(pad "AG34" smd circle
			(at 6.549898 3.420364)
			(size 0.3048 0.3048)
			(layers "F.Cu" "F.Mask" "F.Paste")
			(net "P5E_CPU0_P3_TX_C_DN<13>")
		)
		(pad "AH10" smd circle
			(at 6.402578 -1.431798)
			(size 0.381 0.381)
			(layers "F.Cu" "F.Mask" "F.Paste")
			(net "P5E_CPU0_P3_TX_BUF_DN<13>")
		)
		(pad "AH29" smd circle
			(at 6.402578 2.032254)
			(size 0.381 0.381)
			(layers "F.Cu" "F.Mask" "F.Paste")
			(net "P5E_CPU0_P3_RX_DN<13>")
		)
		(pad "AJ1" smd oval
			(at 6.249924 -3.938524)
			(size 0.254 0.3302)
			(layers "F.Cu" "F.Mask" "F.Paste")
			(net "P5E_CPU0_P3_RX_BUF_DP<13>")
		)
		(pad "AJ35" smd oval
			(at 6.249924 3.940048)
			(size 0.254 0.3302)
			(layers "F.Cu" "F.Mask" "F.Paste")
			(net "P5E_CPU0_P3_TX_C_DP<13>")
		)
		(pad "AK4" smd circle
			(at 6.002528 -2.817368)
			(size 0.381 0.381)
			(layers "F.Cu" "F.Mask" "F.Paste")
			(net "GND")
		)
		(pad "AK13" smd circle
			(at 6.002528 -0.79629)
			(size 0.3048 0.3048)
			(layers "F.Cu" "F.Mask" "F.Paste")
			(net "GND")
		)
		(pad "AK17" smd circle
			(at 6.002528 -0.296164)
			(size 0.3048 0.3048)
			(layers "F.Cu" "F.Mask" "F.Paste")
			(net "P0V9_CPU0_RT3_2A")
		)
		(pad "AK20" smd circle
			(at 6.002528 0.203708)
			(size 0.3048 0.3048)
			(layers "F.Cu" "F.Mask" "F.Paste")
			(net "P0V9_CPU0_RT3_2A")
		)
		(pad "AK22" smd circle
			(at 6.002528 0.703834)
			(size 0.3048 0.3048)
			(layers "F.Cu" "F.Mask" "F.Paste")
			(net "GND")
		)
		(pad "AK32" smd circle
			(at 6.002528 2.724912)
			(size 0.381 0.381)
			(layers "F.Cu" "F.Mask" "F.Paste")
			(net "GND")
		)
		(pad "AL2" smd circle
			(at 5.94995 -3.41884)
			(size 0.3048 0.3048)
			(layers "F.Cu" "F.Mask" "F.Paste")
			(net "GND")
		)
		(pad "AL34" smd circle
			(at 5.94995 3.420364)
			(size 0.3048 0.3048)
			(layers "F.Cu" "F.Mask" "F.Paste")
			(net "GND")
		)
		(pad "AM1" smd oval
			(at 5.649976 -3.938524)
			(size 0.254 0.3302)
			(layers "F.Cu" "F.Mask" "F.Paste")
			(net "GND")
		)
		(pad "AM35" smd oval
			(at 5.649976 3.940048)
			(size 0.254 0.3302)
			(layers "F.Cu" "F.Mask" "F.Paste")
			(net "GND")
		)
		(pad "AN7" smd circle
			(at 5.602478 -2.12471)
			(size 0.381 0.381)
			(layers "F.Cu" "F.Mask" "F.Paste")
			(net "P5E_CPU0_P3_TX_BUF_DP<12>")
		)
		(pad "AN26" smd circle
			(at 5.602478 1.339342)
			(size 0.381 0.381)
			(layers "F.Cu" "F.Mask" "F.Paste")
			(net "P5E_CPU0_P3_RX_DP<12>")
		)
		(pad "AP2" smd circle
			(at 5.350002 -3.41884)
			(size 0.3048 0.3048)
			(layers "F.Cu" "F.Mask" "F.Paste")
			(net "P5E_CPU0_P3_RX_BUF_DN<12>")
		)
		(pad "AP34" smd circle
			(at 5.350002 3.420364)
			(size 0.3048 0.3048)
			(layers "F.Cu" "F.Mask" "F.Paste")
			(net "P5E_CPU0_P3_TX_C_DN<12>")
		)
		(pad "AR10" smd circle
			(at 5.202682 -1.431798)
			(size 0.381 0.381)
			(layers "F.Cu" "F.Mask" "F.Paste")
			(net "P5E_CPU0_P3_TX_BUF_DN<12>")
		)
		(pad "AR29" smd circle
			(at 5.202682 2.032254)
			(size 0.381 0.381)
			(layers "F.Cu" "F.Mask" "F.Paste")
			(net "P5E_CPU0_P3_RX_DN<12>")
		)
		(pad "AT1" smd oval
			(at 5.050028 -3.938524)
			(size 0.254 0.3302)
			(layers "F.Cu" "F.Mask" "F.Paste")
			(net "P5E_CPU0_P3_RX_BUF_DP<12>")
		)
		(pad "AT35" smd oval
			(at 5.050028 3.940048)
			(size 0.254 0.3302)
			(layers "F.Cu" "F.Mask" "F.Paste")
			(net "P5E_CPU0_P3_TX_C_DP<12>")
		)
		(pad "AU4" smd circle
			(at 4.802632 -2.817368)
			(size 0.381 0.381)
			(layers "F.Cu" "F.Mask" "F.Paste")
			(net "GND")
		)
		(pad "AU13" smd circle
			(at 4.802632 -0.79629)
			(size 0.3048 0.3048)
			(layers "F.Cu" "F.Mask" "F.Paste")
			(net "GND")
		)
		(pad "AU17" smd circle
			(at 4.802632 -0.296164)
			(size 0.3048 0.3048)
			(layers "F.Cu" "F.Mask" "F.Paste")
			(net "P0V9_CPU0_RT3_2A")
		)
		(pad "AU20" smd circle
			(at 4.802632 0.203708)
			(size 0.3048 0.3048)
			(layers "F.Cu" "F.Mask" "F.Paste")
			(net "P0V9_CPU0_RT3_2A")
		)
		(pad "AU22" smd circle
			(at 4.802632 0.703834)
			(size 0.3048 0.3048)
			(layers "F.Cu" "F.Mask" "F.Paste")
			(net "GND")
		)
		(pad "AU32" smd circle
			(at 4.802632 2.724912)
			(size 0.381 0.381)
			(layers "F.Cu" "F.Mask" "F.Paste")
			(net "GND")
		)
		(pad "AV2" smd circle
			(at 4.750054 -3.41884)
			(size 0.3048 0.3048)
			(layers "F.Cu" "F.Mask" "F.Paste")
			(net "GND")
		)
		(pad "AV34" smd circle
			(at 4.750054 3.420364)
			(size 0.3048 0.3048)
			(layers "F.Cu" "F.Mask" "F.Paste")
			(net "GND")
		)
		(pad "AW1" smd oval
			(at 4.45008 -3.938524)
			(size 0.254 0.3302)
			(layers "F.Cu" "F.Mask" "F.Paste")
			(net "GND")
		)
		(pad "AW35" smd oval
			(at 4.45008 3.940048)
			(size 0.254 0.3302)
			(layers "F.Cu" "F.Mask" "F.Paste")
			(net "GND")
		)
		(pad "AY7" smd circle
			(at 4.402582 -2.12471)
			(size 0.381 0.381)
			(layers "F.Cu" "F.Mask" "F.Paste")
			(net "P5E_CPU0_P3_TX_BUF_DP<11>")
		)
		(pad "AY26" smd circle
			(at 4.402582 1.339342)
			(size 0.381 0.381)
			(layers "F.Cu" "F.Mask" "F.Paste")
			(net "P5E_CPU0_P3_RX_DP<11>")
		)
		(pad "B3" smd oval
			(at 10.885932 -2.888488 90)
			(size 0.254 0.3302)
			(layers "F.Cu" "F.Mask" "F.Paste")
			(net "JTAG_TCK_RT_CPU0_P3")
		)
		(pad "B6" smd oval
			(at 10.885932 -2.288286 90)
			(size 0.254 0.3302)
			(layers "F.Cu" "F.Mask" "F.Paste")
			(net "JTAG_TDI_RT_CPU0_P3")
		)
		(pad "B9" smd oval
			(at 10.885932 -1.688338 90)
			(size 0.254 0.3302)
			(layers "F.Cu" "F.Mask" "F.Paste")
			(net "JTAG_TDO_RT_CPU0_P3")
		)
		(pad "B12" smd oval
			(at 10.885932 -1.08839 90)
			(size 0.254 0.3302)
			(layers "F.Cu" "F.Mask" "F.Paste")
			(net "JTAG_TMS_RT_CPU0_P3")
		)
		(pad "B16" smd oval
			(at 10.885932 -0.488442 90)
			(size 0.254 0.3302)
			(layers "F.Cu" "F.Mask" "F.Paste")
			(net "Net_2215")
		)
		(pad "B19" smd oval
			(at 10.885932 0.111506 90)
			(size 0.254 0.3302)
			(layers "F.Cu" "F.Mask" "F.Paste")
			(net "GND")
		)
		(pad "B23" smd oval
			(at 10.885932 0.711708 90)
			(size 0.254 0.3302)
			(layers "F.Cu" "F.Mask" "F.Paste")
			(net "RT_CPU0_P3_ADDR2")
		)
		(pad "B25" smd oval
			(at 10.885932 1.311656 90)
			(size 0.254 0.3302)
			(layers "F.Cu" "F.Mask" "F.Paste")
			(net "RT_CPU0_P3_ADDR3")
		)
		(pad "B28" smd oval
			(at 10.885932 1.911604 90)
			(size 0.254 0.3302)
			(layers "F.Cu" "F.Mask" "F.Paste")
			(net "SMB_RT_CPU0_P3_R2_SDA")
		)
		(pad "B31" smd oval
			(at 10.885932 2.511552 90)
			(size 0.254 0.3302)
			(layers "F.Cu" "F.Mask" "F.Paste")
			(net "SMB_RT_CPU0_P3_R2_SCL")
		)
		(pad "BA2" smd circle
			(at 4.150106 -3.41884)
			(size 0.3048 0.3048)
			(layers "F.Cu" "F.Mask" "F.Paste")
			(net "P5E_CPU0_P3_RX_BUF_DN<11>")
		)
		(pad "BA34" smd circle
			(at 4.150106 3.420364)
			(size 0.3048 0.3048)
			(layers "F.Cu" "F.Mask" "F.Paste")
			(net "P5E_CPU0_P3_TX_C_DN<11>")
		)
		(pad "BB10" smd circle
			(at 4.002532 -1.431798)
			(size 0.381 0.381)
			(layers "F.Cu" "F.Mask" "F.Paste")
			(net "P5E_CPU0_P3_TX_BUF_DN<11>")
		)
		(pad "BB29" smd circle
			(at 4.002532 2.032254)
			(size 0.381 0.381)
			(layers "F.Cu" "F.Mask" "F.Paste")
			(net "P5E_CPU0_P3_RX_DN<11>")
		)
		(pad "BC1" smd oval
			(at 3.849878 -3.938524)
			(size 0.254 0.3302)
			(layers "F.Cu" "F.Mask" "F.Paste")
			(net "P5E_CPU0_P3_RX_BUF_DP<11>")
		)
		(pad "BC35" smd oval
			(at 3.849878 3.940048)
			(size 0.254 0.3302)
			(layers "F.Cu" "F.Mask" "F.Paste")
			(net "P5E_CPU0_P3_TX_C_DP<11>")
		)
		(pad "BD4" smd circle
			(at 3.602482 -2.817368)
			(size 0.381 0.381)
			(layers "F.Cu" "F.Mask" "F.Paste")
			(net "GND")
		)
		(pad "BD13" smd circle
			(at 3.602482 -0.79629)
			(size 0.3048 0.3048)
			(layers "F.Cu" "F.Mask" "F.Paste")
			(net "GND")
		)
		(pad "BD17" smd circle
			(at 3.602482 -0.296164)
			(size 0.3048 0.3048)
			(layers "F.Cu" "F.Mask" "F.Paste")
			(net "P0V9_CPU0_RT3_2A_2D")
		)
		(pad "BD20" smd circle
			(at 3.602482 0.203708)
			(size 0.3048 0.3048)
			(layers "F.Cu" "F.Mask" "F.Paste")
			(net "P0V9_CPU0_RT3_2A_2D")
		)
		(pad "BD22" smd circle
			(at 3.602482 0.703834)
			(size 0.3048 0.3048)
			(layers "F.Cu" "F.Mask" "F.Paste")
			(net "GND")
		)
		(pad "BD32" smd circle
			(at 3.602482 2.724912)
			(size 0.381 0.381)
			(layers "F.Cu" "F.Mask" "F.Paste")
			(net "GND")
		)
		(pad "BE2" smd circle
			(at 3.549904 -3.41884)
			(size 0.3048 0.3048)
			(layers "F.Cu" "F.Mask" "F.Paste")
			(net "GND")
		)
		(pad "BE34" smd circle
			(at 3.549904 3.420364)
			(size 0.3048 0.3048)
			(layers "F.Cu" "F.Mask" "F.Paste")
			(net "GND")
		)
		(pad "BF1" smd oval
			(at 3.24993 -3.938524)
			(size 0.254 0.3302)
			(layers "F.Cu" "F.Mask" "F.Paste")
			(net "GND")
		)
		(pad "BF35" smd oval
			(at 3.24993 3.940048)
			(size 0.254 0.3302)
			(layers "F.Cu" "F.Mask" "F.Paste")
			(net "GND")
		)
		(pad "BG7" smd circle
			(at 3.202686 -2.12471)
			(size 0.381 0.381)
			(layers "F.Cu" "F.Mask" "F.Paste")
			(net "P5E_CPU0_P3_TX_BUF_DP<10>")
		)
		(pad "BG26" smd circle
			(at 3.202686 1.339342)
			(size 0.381 0.381)
			(layers "F.Cu" "F.Mask" "F.Paste")
			(net "P5E_CPU0_P3_RX_DP<10>")
		)
		(pad "BH2" smd circle
			(at 2.949956 -3.41884)
			(size 0.3048 0.3048)
			(layers "F.Cu" "F.Mask" "F.Paste")
			(net "P5E_CPU0_P3_RX_BUF_DN<10>")
		)
		(pad "BH34" smd circle
			(at 2.949956 3.420364)
			(size 0.3048 0.3048)
			(layers "F.Cu" "F.Mask" "F.Paste")
			(net "P5E_CPU0_P3_TX_C_DN<10>")
		)
		(pad "BJ10" smd circle
			(at 2.802636 -1.431798)
			(size 0.381 0.381)
			(layers "F.Cu" "F.Mask" "F.Paste")
			(net "P5E_CPU0_P3_TX_BUF_DN<10>")
		)
		(pad "BJ29" smd circle
			(at 2.802636 2.032254)
			(size 0.381 0.381)
			(layers "F.Cu" "F.Mask" "F.Paste")
			(net "P5E_CPU0_P3_RX_DN<10>")
		)
		(pad "BK1" smd oval
			(at 2.649982 -3.938524)
			(size 0.254 0.3302)
			(layers "F.Cu" "F.Mask" "F.Paste")
			(net "P5E_CPU0_P3_RX_BUF_DP<10>")
		)
		(pad "BK35" smd oval
			(at 2.649982 3.940048)
			(size 0.254 0.3302)
			(layers "F.Cu" "F.Mask" "F.Paste")
			(net "P5E_CPU0_P3_TX_C_DP<10>")
		)
		(pad "BL4" smd circle
			(at 2.402586 -2.817368)
			(size 0.381 0.381)
			(layers "F.Cu" "F.Mask" "F.Paste")
			(net "GND")
		)
		(pad "BL13" smd circle
			(at 2.402586 -0.79629)
			(size 0.3048 0.3048)
			(layers "F.Cu" "F.Mask" "F.Paste")
			(net "GND")
		)
		(pad "BL17" smd circle
			(at 2.402586 -0.296164)
			(size 0.3048 0.3048)
			(layers "F.Cu" "F.Mask" "F.Paste")
			(net "P0V9_CPU0_RT_2D")
		)
		(pad "BL20" smd circle
			(at 2.402586 0.203708)
			(size 0.3048 0.3048)
			(layers "F.Cu" "F.Mask" "F.Paste")
			(net "P0V9_CPU0_RT_2D")
		)
		(pad "BL22" smd circle
			(at 2.402586 0.703834)
			(size 0.3048 0.3048)
			(layers "F.Cu" "F.Mask" "F.Paste")
			(net "GND")
		)
		(pad "BL32" smd circle
			(at 2.402586 2.724912)
			(size 0.381 0.381)
			(layers "F.Cu" "F.Mask" "F.Paste")
			(net "GND")
		)
		(pad "BM2" smd circle
			(at 2.350008 -3.41884)
			(size 0.3048 0.3048)
			(layers "F.Cu" "F.Mask" "F.Paste")
			(net "GND")
		)
		(pad "BM34" smd circle
			(at 2.350008 3.420364)
			(size 0.3048 0.3048)
			(layers "F.Cu" "F.Mask" "F.Paste")
			(net "GND")
		)
		(pad "BN1" smd oval
			(at 2.050034 -3.938524)
			(size 0.254 0.3302)
			(layers "F.Cu" "F.Mask" "F.Paste")
			(net "GND")
		)
		(pad "BN35" smd oval
			(at 2.050034 3.940048)
			(size 0.254 0.3302)
			(layers "F.Cu" "F.Mask" "F.Paste")
			(net "GND")
		)
		(pad "BP7" smd circle
			(at 2.002536 -2.12471)
			(size 0.381 0.381)
			(layers "F.Cu" "F.Mask" "F.Paste")
			(net "P5E_CPU0_P3_TX_BUF_DP<9>")
		)
		(pad "BP26" smd circle
			(at 2.002536 1.339342)
			(size 0.381 0.381)
			(layers "F.Cu" "F.Mask" "F.Paste")
			(net "P5E_CPU0_P3_RX_DP<9>")
		)
		(pad "BR2" smd circle
			(at 1.75006 -3.41884)
			(size 0.3048 0.3048)
			(layers "F.Cu" "F.Mask" "F.Paste")
			(net "P5E_CPU0_P3_RX_BUF_DN<9>")
		)
		(pad "BR34" smd circle
			(at 1.75006 3.420364)
			(size 0.3048 0.3048)
			(layers "F.Cu" "F.Mask" "F.Paste")
			(net "P5E_CPU0_P3_TX_C_DN<9>")
		)
		(pad "BT10" smd circle
			(at 1.602486 -1.431798)
			(size 0.381 0.381)
			(layers "F.Cu" "F.Mask" "F.Paste")
			(net "P5E_CPU0_P3_TX_BUF_DN<9>")
		)
		(pad "BT29" smd circle
			(at 1.602486 2.032254)
			(size 0.381 0.381)
			(layers "F.Cu" "F.Mask" "F.Paste")
			(net "P5E_CPU0_P3_RX_DN<9>")
		)
		(pad "BU1" smd oval
			(at 1.450086 -3.938524)
			(size 0.254 0.3302)
			(layers "F.Cu" "F.Mask" "F.Paste")
			(net "P5E_CPU0_P3_RX_BUF_DP<9>")
		)
		(pad "BU35" smd oval
			(at 1.450086 3.940048)
			(size 0.254 0.3302)
			(layers "F.Cu" "F.Mask" "F.Paste")
			(net "P5E_CPU0_P3_TX_C_DP<9>")
		)
		(pad "BV4" smd circle
			(at 1.20269 -2.817368)
			(size 0.381 0.381)
			(layers "F.Cu" "F.Mask" "F.Paste")
			(net "GND")
		)
		(pad "BV13" smd circle
			(at 1.20269 -0.79629)
			(size 0.3048 0.3048)
			(layers "F.Cu" "F.Mask" "F.Paste")
			(net "GND")
		)
		(pad "BV17" smd circle
			(at 1.20269 -0.296164)
			(size 0.3048 0.3048)
			(layers "F.Cu" "F.Mask" "F.Paste")
			(net "P1V8_CPU0_RT3_1A_1D")
		)
		(pad "BV20" smd circle
			(at 1.20269 0.203708)
			(size 0.3048 0.3048)
			(layers "F.Cu" "F.Mask" "F.Paste")
			(net "P1V8_CPU0_RT3_1A")
		)
		(pad "BV22" smd circle
			(at 1.20269 0.703834)
			(size 0.3048 0.3048)
			(layers "F.Cu" "F.Mask" "F.Paste")
			(net "GND")
		)
		(pad "BV32" smd circle
			(at 1.20269 2.724912)
			(size 0.381 0.381)
			(layers "F.Cu" "F.Mask" "F.Paste")
			(net "GND")
		)
		(pad "BW2" smd circle
			(at 1.150112 -3.41884)
			(size 0.3048 0.3048)
			(layers "F.Cu" "F.Mask" "F.Paste")
			(net "GND")
		)
		(pad "BW34" smd circle
			(at 1.150112 3.420364)
			(size 0.3048 0.3048)
			(layers "F.Cu" "F.Mask" "F.Paste")
			(net "GND")
		)
		(pad "BY1" smd oval
			(at 0.849884 -3.938524)
			(size 0.254 0.3302)
			(layers "F.Cu" "F.Mask" "F.Paste")
			(net "GND")
		)
		(pad "BY35" smd oval
			(at 0.849884 3.940048)
			(size 0.254 0.3302)
			(layers "F.Cu" "F.Mask" "F.Paste")
			(net "GND")
		)
		(pad "C2" smd circle
			(at 10.750042 -3.41884)
			(size 0.3048 0.3048)
			(layers "F.Cu" "F.Mask" "F.Paste")
			(net "NCF_CPU0_P3_GND")
		)
		(pad "C34" smd circle
			(at 10.750042 3.420364)
			(size 0.3048 0.3048)
			(layers "F.Cu" "F.Mask" "F.Paste")
			(net "NCF_CPU0_P3_GND")
		)
		(pad "CA7" smd circle
			(at 0.80264 -2.12471)
			(size 0.381 0.381)
			(layers "F.Cu" "F.Mask" "F.Paste")
			(net "P5E_CPU0_P3_TX_BUF_DP<8>")
		)
		(pad "CA26" smd circle
			(at 0.80264 1.339342)
			(size 0.381 0.381)
			(layers "F.Cu" "F.Mask" "F.Paste")
			(net "P5E_CPU0_P3_RX_DP<8>")
		)
		(pad "CB2" smd circle
			(at 0.54991 -3.41884)
			(size 0.3048 0.3048)
			(layers "F.Cu" "F.Mask" "F.Paste")
			(net "P5E_CPU0_P3_RX_BUF_DN<8>")
		)
		(pad "CB34" smd circle
			(at 0.54991 3.420364)
			(size 0.3048 0.3048)
			(layers "F.Cu" "F.Mask" "F.Paste")
			(net "P5E_CPU0_P3_TX_C_DN<8>")
		)
		(pad "CC10" smd circle
			(at 0.40259 -1.431798)
			(size 0.381 0.381)
			(layers "F.Cu" "F.Mask" "F.Paste")
			(net "P5E_CPU0_P3_TX_BUF_DN<8>")
		)
		(pad "CC29" smd circle
			(at 0.40259 2.032254)
			(size 0.381 0.381)
			(layers "F.Cu" "F.Mask" "F.Paste")
			(net "P5E_CPU0_P3_RX_DN<8>")
		)
		(pad "CD1" smd oval
			(at 0.249936 -3.938524)
			(size 0.254 0.3302)
			(layers "F.Cu" "F.Mask" "F.Paste")
			(net "P5E_CPU0_P3_RX_BUF_DP<8>")
		)
		(pad "CD35" smd oval
			(at 0.249936 3.940048)
			(size 0.254 0.3302)
			(layers "F.Cu" "F.Mask" "F.Paste")
			(net "P5E_CPU0_P3_TX_C_DP<8>")
		)
		(pad "CE4" smd circle
			(at 0.00254 -2.817368)
			(size 0.381 0.381)
			(layers "F.Cu" "F.Mask" "F.Paste")
			(net "GND")
		)
		(pad "CE13" smd circle
			(at 0.00254 -0.79629)
			(size 0.3048 0.3048)
			(layers "F.Cu" "F.Mask" "F.Paste")
			(net "GND")
		)
		(pad "CE17" smd circle
			(at 0.00254 -0.296164)
			(size 0.3048 0.3048)
			(layers "F.Cu" "F.Mask" "F.Paste")
			(net "P1V8_CPU0_RT3_1A")
		)
		(pad "CE20" smd circle
			(at 0.00254 0.203708)
			(size 0.3048 0.3048)
			(layers "F.Cu" "F.Mask" "F.Paste")
			(net "P1V8_CPU0_RT3_1A")
		)
		(pad "CE22" smd circle
			(at 0.00254 0.703834)
			(size 0.3048 0.3048)
			(layers "F.Cu" "F.Mask" "F.Paste")
			(net "GND")
		)
		(pad "CE32" smd circle
			(at 0.00254 2.724912)
			(size 0.381 0.381)
			(layers "F.Cu" "F.Mask" "F.Paste")
			(net "GND")
		)
		(pad "CF2" smd circle
			(at -0.050038 -3.41884)
			(size 0.3048 0.3048)
			(layers "F.Cu" "F.Mask" "F.Paste")
			(net "GND")
		)
		(pad "CF34" smd circle
			(at -0.050038 3.420364)
			(size 0.3048 0.3048)
			(layers "F.Cu" "F.Mask" "F.Paste")
			(net "GND")
		)
		(pad "CG1" smd oval
			(at -0.350012 -3.938524)
			(size 0.254 0.3302)
			(layers "F.Cu" "F.Mask" "F.Paste")
			(net "GND")
		)
		(pad "CG35" smd oval
			(at -0.350012 3.940048)
			(size 0.254 0.3302)
			(layers "F.Cu" "F.Mask" "F.Paste")
			(net "GND")
		)
		(pad "CH7" smd circle
			(at -0.39751 -2.12471)
			(size 0.381 0.381)
			(layers "F.Cu" "F.Mask" "F.Paste")
			(net "P5E_CPU0_P3_TX_BUF_DP<7>")
		)
		(pad "CH26" smd circle
			(at -0.39751 1.339342)
			(size 0.381 0.381)
			(layers "F.Cu" "F.Mask" "F.Paste")
			(net "P5E_CPU0_P3_RX_DP<7>")
		)
		(pad "CJ2" smd circle
			(at -0.649986 -3.41884)
			(size 0.3048 0.3048)
			(layers "F.Cu" "F.Mask" "F.Paste")
			(net "P5E_CPU0_P3_RX_BUF_DN<7>")
		)
		(pad "CJ34" smd circle
			(at -0.649986 3.420364)
			(size 0.3048 0.3048)
			(layers "F.Cu" "F.Mask" "F.Paste")
			(net "P5E_CPU0_P3_TX_C_DN<7>")
		)
		(pad "CK10" smd circle
			(at -0.797306 -1.431798)
			(size 0.381 0.381)
			(layers "F.Cu" "F.Mask" "F.Paste")
			(net "P5E_CPU0_P3_TX_BUF_DN<7>")
		)
		(pad "CK29" smd circle
			(at -0.797306 2.032254)
			(size 0.381 0.381)
			(layers "F.Cu" "F.Mask" "F.Paste")
			(net "P5E_CPU0_P3_RX_DN<7>")
		)
		(pad "CL1" smd oval
			(at -0.94996 -3.938524)
			(size 0.254 0.3302)
			(layers "F.Cu" "F.Mask" "F.Paste")
			(net "P5E_CPU0_P3_RX_BUF_DP<7>")
		)
		(pad "CL35" smd oval
			(at -0.94996 3.940048)
			(size 0.254 0.3302)
			(layers "F.Cu" "F.Mask" "F.Paste")
			(net "P5E_CPU0_P3_TX_C_DP<7>")
		)
		(pad "CM4" smd circle
			(at -1.197356 -2.817368)
			(size 0.381 0.381)
			(layers "F.Cu" "F.Mask" "F.Paste")
			(net "GND")
		)
		(pad "CM13" smd circle
			(at -1.197356 -0.79629)
			(size 0.3048 0.3048)
			(layers "F.Cu" "F.Mask" "F.Paste")
			(net "GND")
		)
		(pad "CM17" smd circle
			(at -1.197356 -0.296164)
			(size 0.3048 0.3048)
			(layers "F.Cu" "F.Mask" "F.Paste")
			(net "P1V8_CPU0_RT3_1A")
		)
		(pad "CM20" smd circle
			(at -1.197356 0.203708)
			(size 0.3048 0.3048)
			(layers "F.Cu" "F.Mask" "F.Paste")
			(net "P1V8_CPU0_RT3_1A")
		)
		(pad "CM22" smd circle
			(at -1.197356 0.703834)
			(size 0.3048 0.3048)
			(layers "F.Cu" "F.Mask" "F.Paste")
			(net "GND")
		)
		(pad "CM32" smd circle
			(at -1.197356 2.724912)
			(size 0.381 0.381)
			(layers "F.Cu" "F.Mask" "F.Paste")
			(net "GND")
		)
		(pad "CN2" smd circle
			(at -1.249934 -3.41884)
			(size 0.3048 0.3048)
			(layers "F.Cu" "F.Mask" "F.Paste")
			(net "GND")
		)
		(pad "CN34" smd circle
			(at -1.249934 3.420364)
			(size 0.3048 0.3048)
			(layers "F.Cu" "F.Mask" "F.Paste")
			(net "GND")
		)
		(pad "CP1" smd oval
			(at -1.549908 -3.938524)
			(size 0.254 0.3302)
			(layers "F.Cu" "F.Mask" "F.Paste")
			(net "GND")
		)
		(pad "CP35" smd oval
			(at -1.549908 3.940048)
			(size 0.254 0.3302)
			(layers "F.Cu" "F.Mask" "F.Paste")
			(net "GND")
		)
		(pad "CR7" smd circle
			(at -1.597406 -2.12471)
			(size 0.381 0.381)
			(layers "F.Cu" "F.Mask" "F.Paste")
			(net "P5E_CPU0_P3_TX_BUF_DP<6>")
		)
		(pad "CR26" smd circle
			(at -1.597406 1.339342)
			(size 0.381 0.381)
			(layers "F.Cu" "F.Mask" "F.Paste")
			(net "P5E_CPU0_P3_RX_DP<6>")
		)
		(pad "CT2" smd circle
			(at -1.849882 -3.41884)
			(size 0.3048 0.3048)
			(layers "F.Cu" "F.Mask" "F.Paste")
			(net "P5E_CPU0_P3_RX_BUF_DN<6>")
		)
		(pad "CT34" smd circle
			(at -1.849882 3.420364)
			(size 0.3048 0.3048)
			(layers "F.Cu" "F.Mask" "F.Paste")
			(net "P5E_CPU0_P3_TX_C_DN<6>")
		)
		(pad "CU10" smd circle
			(at -1.997456 -1.431798)
			(size 0.381 0.381)
			(layers "F.Cu" "F.Mask" "F.Paste")
			(net "P5E_CPU0_P3_TX_BUF_DN<6>")
		)
		(pad "CU29" smd circle
			(at -1.997456 2.032254)
			(size 0.381 0.381)
			(layers "F.Cu" "F.Mask" "F.Paste")
			(net "P5E_CPU0_P3_RX_DN<6>")
		)
		(pad "CV1" smd oval
			(at -2.15011 -3.938524)
			(size 0.254 0.3302)
			(layers "F.Cu" "F.Mask" "F.Paste")
			(net "P5E_CPU0_P3_RX_BUF_DP<6>")
		)
		(pad "CV35" smd oval
			(at -2.15011 3.940048)
			(size 0.254 0.3302)
			(layers "F.Cu" "F.Mask" "F.Paste")
			(net "P5E_CPU0_P3_TX_C_DP<6>")
		)
		(pad "CW4" smd circle
			(at -2.397506 -2.817368)
			(size 0.381 0.381)
			(layers "F.Cu" "F.Mask" "F.Paste")
			(net "GND")
		)
		(pad "CW13" smd circle
			(at -2.397506 -0.79629)
			(size 0.3048 0.3048)
			(layers "F.Cu" "F.Mask" "F.Paste")
			(net "GND")
		)
		(pad "CW17" smd circle
			(at -2.397506 -0.296164)
			(size 0.3048 0.3048)
			(layers "F.Cu" "F.Mask" "F.Paste")
			(net "P0V9_CPU0_RT_2D")
		)
		(pad "CW20" smd circle
			(at -2.397506 0.203708)
			(size 0.3048 0.3048)
			(layers "F.Cu" "F.Mask" "F.Paste")
			(net "P0V9_CPU0_RT_2D")
		)
		(pad "CW22" smd circle
			(at -2.397506 0.703834)
			(size 0.3048 0.3048)
			(layers "F.Cu" "F.Mask" "F.Paste")
			(net "GND")
		)
		(pad "CW32" smd circle
			(at -2.397506 2.724912)
			(size 0.381 0.381)
			(layers "F.Cu" "F.Mask" "F.Paste")
			(net "GND")
		)
		(pad "CY2" smd circle
			(at -2.450084 -3.41884)
			(size 0.3048 0.3048)
			(layers "F.Cu" "F.Mask" "F.Paste")
			(net "GND")
		)
		(pad "CY34" smd circle
			(at -2.450084 3.420364)
			(size 0.3048 0.3048)
			(layers "F.Cu" "F.Mask" "F.Paste")
			(net "GND")
		)
		(pad "D1" smd oval
			(at 10.450068 -3.938524)
			(size 0.254 0.3302)
			(layers "F.Cu" "F.Mask" "F.Paste")
			(net "NCF_CPU0_P3_GND")
		)
		(pad "D35" smd oval
			(at 10.450068 3.940048)
			(size 0.254 0.3302)
			(layers "F.Cu" "F.Mask" "F.Paste")
			(net "NCF_CPU0_P3_GND")
		)
		(pad "DA1" smd oval
			(at -2.750058 -3.938524)
			(size 0.254 0.3302)
			(layers "F.Cu" "F.Mask" "F.Paste")
			(net "GND")
		)
		(pad "DA35" smd oval
			(at -2.750058 3.940048)
			(size 0.254 0.3302)
			(layers "F.Cu" "F.Mask" "F.Paste")
			(net "GND")
		)
		(pad "DB7" smd circle
			(at -2.797302 -2.12471)
			(size 0.381 0.381)
			(layers "F.Cu" "F.Mask" "F.Paste")
			(net "P5E_CPU0_P3_TX_BUF_DP<5>")
		)
		(pad "DB26" smd circle
			(at -2.797302 1.339342)
			(size 0.381 0.381)
			(layers "F.Cu" "F.Mask" "F.Paste")
			(net "P5E_CPU0_P3_RX_DP<5>")
		)
		(pad "DC2" smd circle
			(at -3.050032 -3.41884)
			(size 0.3048 0.3048)
			(layers "F.Cu" "F.Mask" "F.Paste")
			(net "P5E_CPU0_P3_RX_BUF_DN<5>")
		)
		(pad "DC34" smd circle
			(at -3.050032 3.420364)
			(size 0.3048 0.3048)
			(layers "F.Cu" "F.Mask" "F.Paste")
			(net "P5E_CPU0_P3_TX_C_DN<5>")
		)
		(pad "DD10" smd circle
			(at -3.197352 -1.431798)
			(size 0.381 0.381)
			(layers "F.Cu" "F.Mask" "F.Paste")
			(net "P5E_CPU0_P3_TX_BUF_DN<5>")
		)
		(pad "DD29" smd circle
			(at -3.197352 2.032254)
			(size 0.381 0.381)
			(layers "F.Cu" "F.Mask" "F.Paste")
			(net "P5E_CPU0_P3_RX_DN<5>")
		)
		(pad "DE1" smd oval
			(at -3.350006 -3.938524)
			(size 0.254 0.3302)
			(layers "F.Cu" "F.Mask" "F.Paste")
			(net "P5E_CPU0_P3_RX_BUF_DP<5>")
		)
		(pad "DE35" smd oval
			(at -3.350006 3.940048)
			(size 0.254 0.3302)
			(layers "F.Cu" "F.Mask" "F.Paste")
			(net "P5E_CPU0_P3_TX_C_DP<5>")
		)
		(pad "DF4" smd circle
			(at -3.597402 -2.817368)
			(size 0.381 0.381)
			(layers "F.Cu" "F.Mask" "F.Paste")
			(net "GND")
		)
		(pad "DF13" smd circle
			(at -3.597402 -0.79629)
			(size 0.3048 0.3048)
			(layers "F.Cu" "F.Mask" "F.Paste")
			(net "GND")
		)
		(pad "DF17" smd circle
			(at -3.597402 -0.296164)
			(size 0.3048 0.3048)
			(layers "F.Cu" "F.Mask" "F.Paste")
			(net "P0V9_CPU0_RT3_2A_2D")
		)
		(pad "DF20" smd circle
			(at -3.597402 0.203708)
			(size 0.3048 0.3048)
			(layers "F.Cu" "F.Mask" "F.Paste")
			(net "P0V9_CPU0_RT3_2A_2D")
		)
		(pad "DF22" smd circle
			(at -3.597402 0.703834)
			(size 0.3048 0.3048)
			(layers "F.Cu" "F.Mask" "F.Paste")
			(net "GND")
		)
		(pad "DF32" smd circle
			(at -3.597402 2.724912)
			(size 0.381 0.381)
			(layers "F.Cu" "F.Mask" "F.Paste")
			(net "GND")
		)
		(pad "DG2" smd circle
			(at -3.64998 -3.41884)
			(size 0.3048 0.3048)
			(layers "F.Cu" "F.Mask" "F.Paste")
			(net "GND")
		)
		(pad "DG34" smd circle
			(at -3.64998 3.420364)
			(size 0.3048 0.3048)
			(layers "F.Cu" "F.Mask" "F.Paste")
			(net "GND")
		)
		(pad "DH1" smd oval
			(at -3.949954 -3.938524)
			(size 0.254 0.3302)
			(layers "F.Cu" "F.Mask" "F.Paste")
			(net "GND")
		)
		(pad "DH35" smd oval
			(at -3.949954 3.940048)
			(size 0.254 0.3302)
			(layers "F.Cu" "F.Mask" "F.Paste")
			(net "GND")
		)
		(pad "DJ7" smd circle
			(at -3.997452 -2.12471)
			(size 0.381 0.381)
			(layers "F.Cu" "F.Mask" "F.Paste")
			(net "P5E_CPU0_P3_TX_BUF_DP<4>")
		)
		(pad "DJ26" smd circle
			(at -3.997452 1.339342)
			(size 0.381 0.381)
			(layers "F.Cu" "F.Mask" "F.Paste")
			(net "P5E_CPU0_P3_RX_DP<4>")
		)
		(pad "DK2" smd circle
			(at -4.249928 -3.41884)
			(size 0.3048 0.3048)
			(layers "F.Cu" "F.Mask" "F.Paste")
			(net "P5E_CPU0_P3_RX_BUF_DN<4>")
		)
		(pad "DK34" smd circle
			(at -4.249928 3.420364)
			(size 0.3048 0.3048)
			(layers "F.Cu" "F.Mask" "F.Paste")
			(net "P5E_CPU0_P3_TX_C_DN<4>")
		)
		(pad "DL10" smd circle
			(at -4.397502 -1.431798)
			(size 0.381 0.381)
			(layers "F.Cu" "F.Mask" "F.Paste")
			(net "P5E_CPU0_P3_TX_BUF_DN<4>")
		)
		(pad "DL29" smd circle
			(at -4.397502 2.032254)
			(size 0.381 0.381)
			(layers "F.Cu" "F.Mask" "F.Paste")
			(net "P5E_CPU0_P3_RX_DN<4>")
		)
		(pad "DM1" smd oval
			(at -4.549902 -3.938524)
			(size 0.254 0.3302)
			(layers "F.Cu" "F.Mask" "F.Paste")
			(net "P5E_CPU0_P3_RX_BUF_DP<4>")
		)
		(pad "DM35" smd oval
			(at -4.549902 3.940048)
			(size 0.254 0.3302)
			(layers "F.Cu" "F.Mask" "F.Paste")
			(net "P5E_CPU0_P3_TX_C_DP<4>")
		)
		(pad "DN4" smd circle
			(at -4.797298 -2.817368)
			(size 0.381 0.381)
			(layers "F.Cu" "F.Mask" "F.Paste")
			(net "GND")
		)
		(pad "DN13" smd circle
			(at -4.797298 -0.79629)
			(size 0.3048 0.3048)
			(layers "F.Cu" "F.Mask" "F.Paste")
			(net "GND")
		)
		(pad "DN17" smd circle
			(at -4.797298 -0.296164)
			(size 0.3048 0.3048)
			(layers "F.Cu" "F.Mask" "F.Paste")
			(net "P0V9_CPU0_RT3_2A")
		)
		(pad "DN20" smd circle
			(at -4.797298 0.203708)
			(size 0.3048 0.3048)
			(layers "F.Cu" "F.Mask" "F.Paste")
			(net "P0V9_CPU0_RT3_2A")
		)
		(pad "DN22" smd circle
			(at -4.797298 0.703834)
			(size 0.3048 0.3048)
			(layers "F.Cu" "F.Mask" "F.Paste")
			(net "GND")
		)
		(pad "DN32" smd circle
			(at -4.797298 2.724912)
			(size 0.381 0.381)
			(layers "F.Cu" "F.Mask" "F.Paste")
			(net "GND")
		)
		(pad "DP2" smd circle
			(at -4.849876 -3.41884)
			(size 0.3048 0.3048)
			(layers "F.Cu" "F.Mask" "F.Paste")
			(net "GND")
		)
		(pad "DP34" smd circle
			(at -4.849876 3.420364)
			(size 0.3048 0.3048)
			(layers "F.Cu" "F.Mask" "F.Paste")
			(net "GND")
		)
		(pad "DR1" smd oval
			(at -5.150104 -3.938524)
			(size 0.254 0.3302)
			(layers "F.Cu" "F.Mask" "F.Paste")
			(net "GND")
		)
		(pad "DR35" smd oval
			(at -5.150104 3.940048)
			(size 0.254 0.3302)
			(layers "F.Cu" "F.Mask" "F.Paste")
			(net "GND")
		)
		(pad "DT7" smd circle
			(at -5.197348 -2.12471)
			(size 0.381 0.381)
			(layers "F.Cu" "F.Mask" "F.Paste")
			(net "P5E_CPU0_P3_TX_BUF_DP<3>")
		)
		(pad "DT26" smd circle
			(at -5.197348 1.339342)
			(size 0.381 0.381)
			(layers "F.Cu" "F.Mask" "F.Paste")
			(net "P5E_CPU0_P3_RX_DP<3>")
		)
		(pad "DU2" smd circle
			(at -5.450078 -3.41884)
			(size 0.3048 0.3048)
			(layers "F.Cu" "F.Mask" "F.Paste")
			(net "P5E_CPU0_P3_RX_BUF_DN<3>")
		)
		(pad "DU34" smd circle
			(at -5.450078 3.420364)
			(size 0.3048 0.3048)
			(layers "F.Cu" "F.Mask" "F.Paste")
			(net "P5E_CPU0_P3_TX_C_DN<3>")
		)
		(pad "DV10" smd circle
			(at -5.597398 -1.431798)
			(size 0.381 0.381)
			(layers "F.Cu" "F.Mask" "F.Paste")
			(net "P5E_CPU0_P3_TX_BUF_DN<3>")
		)
		(pad "DV29" smd circle
			(at -5.597398 2.032254)
			(size 0.381 0.381)
			(layers "F.Cu" "F.Mask" "F.Paste")
			(net "P5E_CPU0_P3_RX_DN<3>")
		)
		(pad "DW1" smd oval
			(at -5.750052 -3.938524)
			(size 0.254 0.3302)
			(layers "F.Cu" "F.Mask" "F.Paste")
			(net "P5E_CPU0_P3_RX_BUF_DP<3>")
		)
		(pad "DW35" smd oval
			(at -5.750052 3.940048)
			(size 0.254 0.3302)
			(layers "F.Cu" "F.Mask" "F.Paste")
			(net "P5E_CPU0_P3_TX_C_DP<3>")
		)
		(pad "DY4" smd circle
			(at -5.997448 -2.817368)
			(size 0.381 0.381)
			(layers "F.Cu" "F.Mask" "F.Paste")
			(net "GND")
		)
		(pad "DY13" smd circle
			(at -5.997448 -0.79629)
			(size 0.3048 0.3048)
			(layers "F.Cu" "F.Mask" "F.Paste")
			(net "GND")
		)
		(pad "DY17" smd circle
			(at -5.997448 -0.296164)
			(size 0.3048 0.3048)
			(layers "F.Cu" "F.Mask" "F.Paste")
			(net "P0V9_CPU0_RT3_2A")
		)
		(pad "DY20" smd circle
			(at -5.997448 0.203708)
			(size 0.3048 0.3048)
			(layers "F.Cu" "F.Mask" "F.Paste")
			(net "P0V9_CPU0_RT3_2A")
		)
		(pad "DY22" smd circle
			(at -5.997448 0.703834)
			(size 0.3048 0.3048)
			(layers "F.Cu" "F.Mask" "F.Paste")
			(net "GND")
		)
		(pad "DY32" smd circle
			(at -5.997448 2.724912)
			(size 0.381 0.381)
			(layers "F.Cu" "F.Mask" "F.Paste")
			(net "GND")
		)
		(pad "E8" smd circle
			(at 10.366502 -1.988312)
			(size 0.3048 0.3048)
			(layers "F.Cu" "F.Mask" "F.Paste")
			(net "JTAG_TRST_RT_CPU0_P3_N")
		)
		(pad "E11" smd circle
			(at 10.366502 -1.388364)
			(size 0.3048 0.3048)
			(layers "F.Cu" "F.Mask" "F.Paste")
			(net "RXDET_BYP_RT_CPU0_P3")
		)
		(pad "E14" smd circle
			(at 10.366502 -0.788416)
			(size 0.3048 0.3048)
			(layers "F.Cu" "F.Mask" "F.Paste")
			(net "GND")
		)
		(pad "E18" smd circle
			(at 10.366502 -0.188468)
			(size 0.3048 0.3048)
			(layers "F.Cu" "F.Mask" "F.Paste")
			(net "Net_2214")
		)
		(pad "E27" smd circle
			(at 10.366502 1.61163)
			(size 0.3048 0.3048)
			(layers "F.Cu" "F.Mask" "F.Paste")
			(net "GND")
		)
		(pad "E30" smd circle
			(at 10.366502 2.211578)
			(size 0.3048 0.3048)
			(layers "F.Cu" "F.Mask" "F.Paste")
			(net "GND")
		)
		(pad "E33" smd circle
			(at 10.366502 2.811526)
			(size 0.3048 0.3048)
			(layers "F.Cu" "F.Mask" "F.Paste")
			(net "GND")
		)
		(pad "EA2" smd circle
			(at -6.050026 -3.41884)
			(size 0.3048 0.3048)
			(layers "F.Cu" "F.Mask" "F.Paste")
			(net "GND")
		)
		(pad "EA34" smd circle
			(at -6.050026 3.420364)
			(size 0.3048 0.3048)
			(layers "F.Cu" "F.Mask" "F.Paste")
			(net "GND")
		)
		(pad "EB1" smd oval
			(at -6.35 -3.938524)
			(size 0.254 0.3302)
			(layers "F.Cu" "F.Mask" "F.Paste")
			(net "GND")
		)
		(pad "EB35" smd oval
			(at -6.35 3.940048)
			(size 0.254 0.3302)
			(layers "F.Cu" "F.Mask" "F.Paste")
			(net "GND")
		)
		(pad "EC7" smd circle
			(at -6.397498 -2.12471)
			(size 0.381 0.381)
			(layers "F.Cu" "F.Mask" "F.Paste")
			(net "P5E_CPU0_P3_TX_BUF_DP<2>")
		)
		(pad "EC26" smd circle
			(at -6.397498 1.339342)
			(size 0.381 0.381)
			(layers "F.Cu" "F.Mask" "F.Paste")
			(net "P5E_CPU0_P3_RX_DP<2>")
		)
		(pad "ED2" smd circle
			(at -6.649974 -3.41884)
			(size 0.3048 0.3048)
			(layers "F.Cu" "F.Mask" "F.Paste")
			(net "P5E_CPU0_P3_RX_BUF_DN<2>")
		)
		(pad "ED34" smd circle
			(at -6.649974 3.420364)
			(size 0.3048 0.3048)
			(layers "F.Cu" "F.Mask" "F.Paste")
			(net "P5E_CPU0_P3_TX_C_DN<2>")
		)
		(pad "EE10" smd circle
			(at -6.797294 -1.431798)
			(size 0.381 0.381)
			(layers "F.Cu" "F.Mask" "F.Paste")
			(net "P5E_CPU0_P3_TX_BUF_DN<2>")
		)
		(pad "EE29" smd circle
			(at -6.797294 2.032254)
			(size 0.381 0.381)
			(layers "F.Cu" "F.Mask" "F.Paste")
			(net "P5E_CPU0_P3_RX_DN<2>")
		)
		(pad "EF1" smd oval
			(at -6.949948 -3.938524)
			(size 0.254 0.3302)
			(layers "F.Cu" "F.Mask" "F.Paste")
			(net "P5E_CPU0_P3_RX_BUF_DP<2>")
		)
		(pad "EF35" smd oval
			(at -6.949948 3.940048)
			(size 0.254 0.3302)
			(layers "F.Cu" "F.Mask" "F.Paste")
			(net "P5E_CPU0_P3_TX_C_DP<2>")
		)
		(pad "EG4" smd circle
			(at -7.197344 -2.817368)
			(size 0.381 0.381)
			(layers "F.Cu" "F.Mask" "F.Paste")
			(net "GND")
		)
		(pad "EG13" smd circle
			(at -7.197344 -0.79629)
			(size 0.3048 0.3048)
			(layers "F.Cu" "F.Mask" "F.Paste")
			(net "GND")
		)
		(pad "EG17" smd circle
			(at -7.197344 -0.296164)
			(size 0.3048 0.3048)
			(layers "F.Cu" "F.Mask" "F.Paste")
			(net "P0V9_CPU0_RT3_2A")
		)
		(pad "EG20" smd circle
			(at -7.197344 0.203708)
			(size 0.3048 0.3048)
			(layers "F.Cu" "F.Mask" "F.Paste")
			(net "P0V9_CPU0_RT3_2A")
		)
		(pad "EG22" smd circle
			(at -7.197344 0.703834)
			(size 0.3048 0.3048)
			(layers "F.Cu" "F.Mask" "F.Paste")
			(net "GND")
		)
		(pad "EG32" smd circle
			(at -7.197344 2.724912)
			(size 0.381 0.381)
			(layers "F.Cu" "F.Mask" "F.Paste")
			(net "GND")
		)
		(pad "EH2" smd circle
			(at -7.249922 -3.41884)
			(size 0.3048 0.3048)
			(layers "F.Cu" "F.Mask" "F.Paste")
			(net "GND")
		)
		(pad "EH34" smd circle
			(at -7.249922 3.420364)
			(size 0.3048 0.3048)
			(layers "F.Cu" "F.Mask" "F.Paste")
			(net "GND")
		)
		(pad "EJ1" smd oval
			(at -7.549896 -3.938524)
			(size 0.254 0.3302)
			(layers "F.Cu" "F.Mask" "F.Paste")
			(net "GND")
		)
		(pad "EJ35" smd oval
			(at -7.549896 3.940048)
			(size 0.254 0.3302)
			(layers "F.Cu" "F.Mask" "F.Paste")
			(net "GND")
		)
		(pad "EK7" smd circle
			(at -7.597394 -2.12471)
			(size 0.381 0.381)
			(layers "F.Cu" "F.Mask" "F.Paste")
			(net "P5E_CPU0_P3_TX_BUF_DP<1>")
		)
		(pad "EK26" smd circle
			(at -7.597394 1.339342)
			(size 0.381 0.381)
			(layers "F.Cu" "F.Mask" "F.Paste")
			(net "P5E_CPU0_P3_RX_DP<1>")
		)
		(pad "EL2" smd circle
			(at -7.850124 -3.41884)
			(size 0.3048 0.3048)
			(layers "F.Cu" "F.Mask" "F.Paste")
			(net "P5E_CPU0_P3_RX_BUF_DN<1>")
		)
		(pad "EL34" smd circle
			(at -7.850124 3.420364)
			(size 0.3048 0.3048)
			(layers "F.Cu" "F.Mask" "F.Paste")
			(net "P5E_CPU0_P3_TX_C_DP<1>")
		)
		(pad "EM10" smd circle
			(at -7.997444 -1.431798)
			(size 0.381 0.381)
			(layers "F.Cu" "F.Mask" "F.Paste")
			(net "P5E_CPU0_P3_TX_BUF_DN<1>")
		)
		(pad "EM29" smd circle
			(at -7.997444 2.032254)
			(size 0.381 0.381)
			(layers "F.Cu" "F.Mask" "F.Paste")
			(net "P5E_CPU0_P3_RX_DN<1>")
		)
		(pad "EN1" smd oval
			(at -8.150098 -3.938524)
			(size 0.254 0.3302)
			(layers "F.Cu" "F.Mask" "F.Paste")
			(net "P5E_CPU0_P3_RX_BUF_DP<1>")
		)
		(pad "EN35" smd oval
			(at -8.150098 3.940048)
			(size 0.254 0.3302)
			(layers "F.Cu" "F.Mask" "F.Paste")
			(net "P5E_CPU0_P3_TX_C_DN<1>")
		)
		(pad "EP4" smd circle
			(at -8.397494 -2.817368)
			(size 0.381 0.381)
			(layers "F.Cu" "F.Mask" "F.Paste")
			(net "GND")
		)
		(pad "EP13" smd circle
			(at -8.397494 -0.79629)
			(size 0.3048 0.3048)
			(layers "F.Cu" "F.Mask" "F.Paste")
			(net "GND")
		)
		(pad "EP17" smd circle
			(at -8.397494 -0.296164)
			(size 0.3048 0.3048)
			(layers "F.Cu" "F.Mask" "F.Paste")
			(net "P0V9_CPU0_RT3_2A")
		)
		(pad "EP20" smd circle
			(at -8.397494 0.203708)
			(size 0.3048 0.3048)
			(layers "F.Cu" "F.Mask" "F.Paste")
			(net "P0V9_CPU0_RT3_2A")
		)
		(pad "EP22" smd circle
			(at -8.397494 0.703834)
			(size 0.3048 0.3048)
			(layers "F.Cu" "F.Mask" "F.Paste")
			(net "GND")
		)
		(pad "EP32" smd circle
			(at -8.397494 2.724912)
			(size 0.381 0.381)
			(layers "F.Cu" "F.Mask" "F.Paste")
			(net "GND")
		)
		(pad "ER2" smd circle
			(at -8.450072 -3.41884)
			(size 0.3048 0.3048)
			(layers "F.Cu" "F.Mask" "F.Paste")
			(net "GND")
		)
		(pad "ER34" smd circle
			(at -8.450072 3.420364)
			(size 0.3048 0.3048)
			(layers "F.Cu" "F.Mask" "F.Paste")
			(net "GND")
		)
		(pad "ET1" smd oval
			(at -8.750046 -3.938524)
			(size 0.254 0.3302)
			(layers "F.Cu" "F.Mask" "F.Paste")
			(net "GND")
		)
		(pad "ET35" smd oval
			(at -8.750046 3.940048)
			(size 0.254 0.3302)
			(layers "F.Cu" "F.Mask" "F.Paste")
			(net "GND")
		)
		(pad "EU7" smd circle
			(at -8.79729 -2.12471)
			(size 0.381 0.381)
			(layers "F.Cu" "F.Mask" "F.Paste")
			(net "P5E_CPU0_P3_TX_BUF_DP<0>")
		)
		(pad "EU26" smd circle
			(at -8.79729 1.339342)
			(size 0.381 0.381)
			(layers "F.Cu" "F.Mask" "F.Paste")
			(net "P5E_CPU0_P3_RX_DP<0>")
		)
		(pad "EV2" smd circle
			(at -9.05002 -3.41884)
			(size 0.3048 0.3048)
			(layers "F.Cu" "F.Mask" "F.Paste")
			(net "P5E_CPU0_P3_RX_BUF_DN<0>")
		)
		(pad "EV34" smd circle
			(at -9.05002 3.420364)
			(size 0.3048 0.3048)
			(layers "F.Cu" "F.Mask" "F.Paste")
			(net "P5E_CPU0_P3_TX_C_DN<0>")
		)
		(pad "EW10" smd circle
			(at -9.19734 -1.431798)
			(size 0.381 0.381)
			(layers "F.Cu" "F.Mask" "F.Paste")
			(net "P5E_CPU0_P3_TX_BUF_DN<0>")
		)
		(pad "EW29" smd circle
			(at -9.19734 2.032254)
			(size 0.381 0.381)
			(layers "F.Cu" "F.Mask" "F.Paste")
			(net "P5E_CPU0_P3_RX_DN<0>")
		)
		(pad "EY1" smd oval
			(at -9.349994 -3.938524)
			(size 0.254 0.3302)
			(layers "F.Cu" "F.Mask" "F.Paste")
			(net "P5E_CPU0_P3_RX_BUF_DP<0>")
		)
		(pad "EY35" smd oval
			(at -9.349994 3.940048)
			(size 0.254 0.3302)
			(layers "F.Cu" "F.Mask" "F.Paste")
			(net "P5E_CPU0_P3_TX_C_DP<0>")
		)
		(pad "F2" smd circle
			(at 10.150094 -3.41884)
			(size 0.3048 0.3048)
			(layers "F.Cu" "F.Mask" "F.Paste")
			(net "RST_RT_CPU0_P3_PERST_N")
		)
		(pad "F34" smd circle
			(at 10.150094 3.420364)
			(size 0.3048 0.3048)
			(layers "F.Cu" "F.Mask" "F.Paste")
			(net "RT_CPU0_P3_ADDR1")
		)
		(pad "FA15" smd circle
			(at -9.59739 -0.738886)
			(size 0.381 0.381)
			(layers "F.Cu" "F.Mask" "F.Paste")
			(net "GND")
		)
		(pad "FA32" smd circle
			(at -9.59739 2.724912)
			(size 0.381 0.381)
			(layers "F.Cu" "F.Mask" "F.Paste")
			(net "GND")
		)
		(pad "FB2" smd circle
			(at -9.649968 -3.41884)
			(size 0.3048 0.3048)
			(layers "F.Cu" "F.Mask" "F.Paste")
			(net "GND")
		)
		(pad "FB34" smd circle
			(at -9.649968 3.420364)
			(size 0.3048 0.3048)
			(layers "F.Cu" "F.Mask" "F.Paste")
			(net "GND")
		)
		(pad "FC3" smd circle
			(at -9.846818 -2.888488)
			(size 0.3048 0.3048)
			(layers "F.Cu" "F.Mask" "F.Paste")
			(net "GND")
		)
		(pad "FC6" smd circle
			(at -9.846818 -2.288286)
			(size 0.3048 0.3048)
			(layers "F.Cu" "F.Mask" "F.Paste")
			(net "GND")
		)
		(pad "FC9" smd circle
			(at -9.846818 -1.688338)
			(size 0.3048 0.3048)
			(layers "F.Cu" "F.Mask" "F.Paste")
			(net "GND")
		)
		(pad "FC19" smd circle
			(at -9.846818 0.111506)
			(size 0.3048 0.3048)
			(layers "F.Cu" "F.Mask" "F.Paste")
			(net "GND")
		)
		(pad "FC23" smd circle
			(at -9.846818 0.711708)
			(size 0.3048 0.3048)
			(layers "F.Cu" "F.Mask" "F.Paste")
			(net "GND")
		)
		(pad "FC25" smd circle
			(at -9.846818 1.311656)
			(size 0.3048 0.3048)
			(layers "F.Cu" "F.Mask" "F.Paste")
			(net "GND")
		)
		(pad "FC28" smd circle
			(at -9.846818 1.911604)
			(size 0.3048 0.3048)
			(layers "F.Cu" "F.Mask" "F.Paste")
			(net "GND")
		)
		(pad "FD1" smd oval
			(at -9.949942 -3.938524)
			(size 0.254 0.3302)
			(layers "F.Cu" "F.Mask" "F.Paste")
			(net "GND")
		)
		(pad "FD35" smd oval
			(at -9.949942 3.940048)
			(size 0.254 0.3302)
			(layers "F.Cu" "F.Mask" "F.Paste")
			(net "GND")
		)
		(pad "FE2" smd circle
			(at -10.249916 -3.41884)
			(size 0.3048 0.3048)
			(layers "F.Cu" "F.Mask" "F.Paste")
			(net "NCF_CPU0_P3_GND")
		)
		(pad "FE34" smd circle
			(at -10.249916 3.420364)
			(size 0.3048 0.3048)
			(layers "F.Cu" "F.Mask" "F.Paste")
			(net "NCF_CPU0_P3_GND")
		)
		(pad "FF5" smd circle
			(at -10.366248 -2.588514)
			(size 0.3048 0.3048)
			(layers "F.Cu" "F.Mask" "F.Paste")
			(net "SMB_RT_CPU0_P3_ROM_MUX_1D_R_SCL")
		)
		(pad "FF8" smd circle
			(at -10.366248 -1.988312)
			(size 0.3048 0.3048)
			(layers "F.Cu" "F.Mask" "F.Paste")
			(net "JTAG_TEST_MODE_RT_CPU0_P3")
		)
		(pad "FF11" smd circle
			(at -10.366248 -1.388364)
			(size 0.3048 0.3048)
			(layers "F.Cu" "F.Mask" "F.Paste")
			(net "RST_RT_CPU0_P3_RESET_N")
		)
		(pad "FF14" smd circle
			(at -10.366248 -0.788416)
			(size 0.3048 0.3048)
			(layers "F.Cu" "F.Mask" "F.Paste")
			(net "GND")
		)
		(pad "FF18" smd circle
			(at -10.366248 -0.188468)
			(size 0.3048 0.3048)
			(layers "F.Cu" "F.Mask" "F.Paste")
			(net "CLK_100M_RETIMER_CPU0_P3_DN")
		)
		(pad "FF21" smd circle
			(at -10.366248 0.41148)
			(size 0.3048 0.3048)
			(layers "F.Cu" "F.Mask" "F.Paste")
			(net "GND")
		)
		(pad "FF24" smd circle
			(at -10.366248 1.011682)
			(size 0.3048 0.3048)
			(layers "F.Cu" "F.Mask" "F.Paste")
			(net "TEST0_RT_CPU0_P3")
		)
		(pad "FF27" smd circle
			(at -10.366248 1.61163)
			(size 0.3048 0.3048)
			(layers "F.Cu" "F.Mask" "F.Paste")
			(net "TEST1_RT_CPU0_P3")
		)
		(pad "FF30" smd circle
			(at -10.366248 2.211578)
			(size 0.3048 0.3048)
			(layers "F.Cu" "F.Mask" "F.Paste")
			(net "TEST2_RT_CPU0_P3")
		)
		(pad "FF33" smd circle
			(at -10.366248 2.811526)
			(size 0.3048 0.3048)
			(layers "F.Cu" "F.Mask" "F.Paste")
			(net "RT_CPU0_P3_SCAN_MODE")
		)
		(pad "FG1" smd oval
			(at -10.54989 -3.938524)
			(size 0.254 0.3302)
			(layers "F.Cu" "F.Mask" "F.Paste")
			(net "NCF_CPU0_P3_GND")
		)
		(pad "FG35" smd oval
			(at -10.54989 3.940048)
			(size 0.254 0.3302)
			(layers "F.Cu" "F.Mask" "F.Paste")
			(net "NCF_CPU0_P3_GND")
		)
		(pad "FH2" smd circle
			(at -10.850118 -3.41884)
			(size 0.3048 0.3048)
			(layers "F.Cu" "F.Mask" "F.Paste")
			(net "NCF_CPU0_P3_GND")
		)
		(pad "FH34" smd circle
			(at -10.850118 3.420364)
			(size 0.3048 0.3048)
			(layers "F.Cu" "F.Mask" "F.Paste")
			(net "NCF_CPU0_P3_GND")
		)
		(pad "FJ3" smd oval
			(at -10.885932 -2.888488 90)
			(size 0.254 0.3302)
			(layers "F.Cu" "F.Mask" "F.Paste")
			(net "SMB_RT_CPU0_P3_ROM_MUX_1D_R_SDA")
		)
		(pad "FJ6" smd oval
			(at -10.885932 -2.288286 90)
			(size 0.254 0.3302)
			(layers "F.Cu" "F.Mask" "F.Paste")
			(net "Net_2212")
		)
		(pad "FJ9" smd oval
			(at -10.885932 -1.688338 90)
			(size 0.254 0.3302)
			(layers "F.Cu" "F.Mask" "F.Paste")
			(net "MODE_RT_CPU0_P3")
		)
		(pad "FJ12" smd oval
			(at -10.885932 -1.08839 90)
			(size 0.254 0.3302)
			(layers "F.Cu" "F.Mask" "F.Paste")
			(net "GND")
		)
		(pad "FJ16" smd oval
			(at -10.885932 -0.488442 90)
			(size 0.254 0.3302)
			(layers "F.Cu" "F.Mask" "F.Paste")
			(net "CLK_100M_RETIMER_CPU0_P3_DP")
		)
		(pad "FJ19" smd oval
			(at -10.885932 0.111506 90)
			(size 0.254 0.3302)
			(layers "F.Cu" "F.Mask" "F.Paste")
			(net "GND")
		)
		(pad "FJ23" smd oval
			(at -10.885932 0.711708 90)
			(size 0.254 0.3302)
			(layers "F.Cu" "F.Mask" "F.Paste")
			(net "Net_2213")
		)
		(pad "FJ25" smd oval
			(at -10.885932 1.311656 90)
			(size 0.254 0.3302)
			(layers "F.Cu" "F.Mask" "F.Paste")
			(net "GPIO2_RT_CPU0_P3")
		)
		(pad "FJ28" smd oval
			(at -10.885932 1.911604 90)
			(size 0.254 0.3302)
			(layers "F.Cu" "F.Mask" "F.Paste")
			(net "GPIO3_RT_CPU0_P3")
		)
		(pad "FJ31" smd oval
			(at -10.885932 2.511552 90)
			(size 0.254 0.3302)
			(layers "F.Cu" "F.Mask" "F.Paste")
			(net "Net_53")
		)
		(pad "G1" smd oval
			(at 9.85012 -3.938524)
			(size 0.254 0.3302)
			(layers "F.Cu" "F.Mask" "F.Paste")
			(net "RT_CPU0_P3_VQPS")
		)
		(pad "G35" smd oval
			(at 9.85012 3.940048)
			(size 0.254 0.3302)
			(layers "F.Cu" "F.Mask" "F.Paste")
			(net "CLKREQ_RT_CPU0_P3_N")
		)
		(pad "H12" smd circle
			(at 9.846818 -1.08839)
			(size 0.3048 0.3048)
			(layers "F.Cu" "F.Mask" "F.Paste")
			(net "GND")
		)
		(pad "H16" smd circle
			(at 9.846818 -0.488442)
			(size 0.3048 0.3048)
			(layers "F.Cu" "F.Mask" "F.Paste")
			(net "GND")
		)
		(pad "H19" smd circle
			(at 9.846818 0.111506)
			(size 0.3048 0.3048)
			(layers "F.Cu" "F.Mask" "F.Paste")
			(net "GND")
		)
		(pad "H31" smd circle
			(at 9.846818 2.511552)
			(size 0.3048 0.3048)
			(layers "F.Cu" "F.Mask" "F.Paste")
			(net "GND")
		)
		(pad "J4" smd circle
			(at 9.602724 -2.817368)
			(size 0.381 0.381)
			(layers "F.Cu" "F.Mask" "F.Paste")
			(net "GND")
		)
		(pad "J22" smd circle
			(at 9.602724 0.703834)
			(size 0.3048 0.3048)
			(layers "F.Cu" "F.Mask" "F.Paste")
			(net "GND")
		)
		(pad "K2" smd circle
			(at 9.549892 -3.41884)
			(size 0.3048 0.3048)
			(layers "F.Cu" "F.Mask" "F.Paste")
			(net "GND")
		)
		(pad "K34" smd circle
			(at 9.549892 3.420364)
			(size 0.3048 0.3048)
			(layers "F.Cu" "F.Mask" "F.Paste")
			(net "GND")
		)
		(pad "L1" smd oval
			(at 9.249918 -3.938524)
			(size 0.254 0.3302)
			(layers "F.Cu" "F.Mask" "F.Paste")
			(net "GND")
		)
		(pad "L35" smd oval
			(at 9.249918 3.940048)
			(size 0.254 0.3302)
			(layers "F.Cu" "F.Mask" "F.Paste")
			(net "GND")
		)
		(pad "M7" smd circle
			(at 9.202674 -2.12471)
			(size 0.381 0.381)
			(layers "F.Cu" "F.Mask" "F.Paste")
			(net "P5E_CPU0_P3_TX_BUF_DP<15>")
		)
		(pad "M26" smd circle
			(at 9.202674 1.339342)
			(size 0.381 0.381)
			(layers "F.Cu" "F.Mask" "F.Paste")
			(net "P5E_CPU0_P3_RX_DP<15>")
		)
		(pad "N2" smd circle
			(at 8.949944 -3.41884)
			(size 0.3048 0.3048)
			(layers "F.Cu" "F.Mask" "F.Paste")
			(net "P5E_CPU0_P3_RX_BUF_DN<15>")
		)
		(pad "N34" smd circle
			(at 8.949944 3.420364)
			(size 0.3048 0.3048)
			(layers "F.Cu" "F.Mask" "F.Paste")
			(net "P5E_CPU0_P3_TX_C_DN<15>")
		)
		(pad "P10" smd circle
			(at 8.802624 -1.431798)
			(size 0.381 0.381)
			(layers "F.Cu" "F.Mask" "F.Paste")
			(net "P5E_CPU0_P3_TX_BUF_DN<15>")
		)
		(pad "P29" smd circle
			(at 8.802624 2.032254)
			(size 0.381 0.381)
			(layers "F.Cu" "F.Mask" "F.Paste")
			(net "P5E_CPU0_P3_RX_DN<15>")
		)
		(pad "R1" smd oval
			(at 8.64997 -3.938524)
			(size 0.254 0.3302)
			(layers "F.Cu" "F.Mask" "F.Paste")
			(net "P5E_CPU0_P3_RX_BUF_DP<15>")
		)
		(pad "R35" smd oval
			(at 8.64997 3.940048)
			(size 0.254 0.3302)
			(layers "F.Cu" "F.Mask" "F.Paste")
			(net "P5E_CPU0_P3_TX_C_DP<15>")
		)
		(pad "T4" smd circle
			(at 8.402574 -2.817368)
			(size 0.381 0.381)
			(layers "F.Cu" "F.Mask" "F.Paste")
			(net "GND")
		)
		(pad "T13" smd circle
			(at 8.402574 -0.79629)
			(size 0.3048 0.3048)
			(layers "F.Cu" "F.Mask" "F.Paste")
			(net "GND")
		)
		(pad "T17" smd circle
			(at 8.402574 -0.296164)
			(size 0.3048 0.3048)
			(layers "F.Cu" "F.Mask" "F.Paste")
			(net "P0V9_CPU0_RT3_2A")
		)
		(pad "T20" smd circle
			(at 8.402574 0.203708)
			(size 0.3048 0.3048)
			(layers "F.Cu" "F.Mask" "F.Paste")
			(net "P0V9_CPU0_RT3_2A")
		)
		(pad "T22" smd circle
			(at 8.402574 0.703834)
			(size 0.3048 0.3048)
			(layers "F.Cu" "F.Mask" "F.Paste")
			(net "GND")
		)
		(pad "T32" smd circle
			(at 8.402574 2.724912)
			(size 0.381 0.381)
			(layers "F.Cu" "F.Mask" "F.Paste")
			(net "GND")
		)
		(pad "U2" smd circle
			(at 8.349996 -3.41884)
			(size 0.3048 0.3048)
			(layers "F.Cu" "F.Mask" "F.Paste")
			(net "GND")
		)
		(pad "U34" smd circle
			(at 8.349996 3.420364)
			(size 0.3048 0.3048)
			(layers "F.Cu" "F.Mask" "F.Paste")
			(net "GND")
		)
		(pad "V1" smd oval
			(at 8.050022 -3.938524)
			(size 0.254 0.3302)
			(layers "F.Cu" "F.Mask" "F.Paste")
			(net "GND")
		)
		(pad "V35" smd oval
			(at 8.050022 3.940048)
			(size 0.254 0.3302)
			(layers "F.Cu" "F.Mask" "F.Paste")
			(net "GND")
		)
		(pad "W7" smd circle
			(at 8.002524 -2.12471)
			(size 0.381 0.381)
			(layers "F.Cu" "F.Mask" "F.Paste")
			(net "P5E_CPU0_P3_TX_BUF_DP<14>")
		)
		(pad "W26" smd circle
			(at 8.002524 1.339342)
			(size 0.381 0.381)
			(layers "F.Cu" "F.Mask" "F.Paste")
			(net "P5E_CPU0_P3_RX_DP<14>")
		)
		(pad "Y2" smd circle
			(at 7.750048 -3.41884)
			(size 0.3048 0.3048)
			(layers "F.Cu" "F.Mask" "F.Paste")
			(net "P5E_CPU0_P3_RX_BUF_DN<14>")
		)
		(pad "Y34" smd circle
			(at 7.750048 3.420364)
			(size 0.3048 0.3048)
			(layers "F.Cu" "F.Mask" "F.Paste")
			(net "P5E_CPU0_P3_TX_C_DP<14>")
		)
	)
	(footprint ""
		(layer "F.Cu")
		(at 288.393124 -13.360146)
		(property "Reference" "R4214"
			(at 0 0 0)
			(layer "F.SilkS")
			(hide yes)
			(effects
				(font
					(size 1.27 1.27)
				)
			)
		)
		(property "Value" ""
			(at 0 0 0)
			(layer "F.Fab")
			(effects
				(font
					(size 1.27 1.27)
				)
			)
		)
		(duplicate_pad_numbers_are_jumpers no)
		(fp_line
			(start -0.7874 -0.4064)
			(end 0.7874 -0.4064)
			(stroke
				(width 0.1524)
				(type default)
			)
			(layer "F.SilkS")
		)
		(fp_line
			(start -0.7874 0.4064)
			(end -0.7874 -0.4064)
			(stroke
				(width 0.1524)
				(type default)
			)
			(layer "F.SilkS")
		)
		(fp_line
			(start 0.7874 -0.4064)
			(end 0.7874 0.4064)
			(stroke
				(width 0.1524)
				(type default)
			)
			(layer "F.SilkS")
		)
		(fp_line
			(start 0.7874 0.4064)
			(end -0.7874 0.4064)
			(stroke
				(width 0.1524)
				(type default)
			)
			(layer "F.SilkS")
		)
		(fp_line
			(start -0.67945 -0.305054)
			(end -0.12065 -0.305054)
			(stroke
				(width 0.1)
				(type default)
			)
			(layer "F.Fab")
		)
		(fp_line
			(start -0.67945 0.3048)
			(end -0.67945 -0.305054)
			(stroke
				(width 0.1)
				(type default)
			)
			(layer "F.Fab")
		)
		(fp_line
			(start -0.12065 -0.305054)
			(end -0.12065 -0.2794)
			(stroke
				(width 0.1)
				(type default)
			)
			(layer "F.Fab")
		)
		(fp_line
			(start -0.12065 -0.2794)
			(end 0.12065 -0.2794)
			(stroke
				(width 0.1)
				(type default)
			)
			(layer "F.Fab")
		)
		(fp_line
			(start -0.12065 0.2794)
			(end -0.12065 0.3048)
			(stroke
				(width 0.1)
				(type default)
			)
			(layer "F.Fab")
		)
		(fp_line
			(start -0.12065 0.3048)
			(end -0.67945 0.3048)
			(stroke
				(width 0.1)
				(type default)
			)
			(layer "F.Fab")
		)
		(fp_line
			(start 0.120396 0.2794)
			(end -0.12065 0.2794)
			(stroke
				(width 0.1)
				(type default)
			)
			(layer "F.Fab")
		)
		(fp_line
			(start 0.120396 0.3048)
			(end 0.120396 0.2794)
			(stroke
				(width 0.1)
				(type default)
			)
			(layer "F.Fab")
		)
		(fp_line
			(start 0.12065 -0.3048)
			(end 0.67945 -0.3048)
			(stroke
				(width 0.1)
				(type default)
			)
			(layer "F.Fab")
		)
		(fp_line
			(start 0.12065 -0.2794)
			(end 0.12065 -0.3048)
			(stroke
				(width 0.1)
				(type default)
			)
			(layer "F.Fab")
		)
		(fp_line
			(start 0.67945 -0.3048)
			(end 0.67945 0.3048)
			(stroke
				(width 0.1)
				(type default)
			)
			(layer "F.Fab")
		)
		(fp_line
			(start 0.67945 0.3048)
			(end 0.120396 0.3048)
			(stroke
				(width 0.1)
				(type default)
			)
			(layer "F.Fab")
		)
		(pad "1" smd circle
			(at -0.40005 0)
			(size 0 0)
			(layers "F.Cu" "F.Mask" "F.Paste")
			(net "FM_THERMAL_ALERT_N")
		)
		(pad "2" smd circle
			(at 0.40005 0)
			(size 0 0)
			(layers "F.Cu" "F.Mask" "F.Paste")
			(net "FM_G751_1_ALERT_N")
		)
	)
	(footprint ""
		(layer "F.Cu")
		(at 177.67808 -92.685616 -90)
		(property "Reference" "R6744"
			(at 0 0 270)
			(layer "F.SilkS")
			(hide yes)
			(effects
				(font
					(size 1.27 1.27)
				)
			)
		)
		(property "Value" ""
			(at 0 0 270)
			(layer "F.Fab")
			(effects
				(font
					(size 1.27 1.27)
				)
			)
		)
		(duplicate_pad_numbers_are_jumpers no)
		(fp_line
			(start -0.7874 0.4064)
			(end -0.7874 -0.4064)
			(stroke
				(width 0.1524)
				(type default)
			)
			(layer "F.SilkS")
		)
		(fp_line
			(start 0.7874 0.4064)
			(end -0.7874 0.4064)
			(stroke
				(width 0.1524)
				(type default)
			)
			(layer "F.SilkS")
		)
		(fp_line
			(start -0.7874 -0.4064)
			(end 0.7874 -0.4064)
			(stroke
				(width 0.1524)
				(type default)
			)
			(layer "F.SilkS")
		)
		(fp_line
			(start 0.7874 -0.4064)
			(end 0.7874 0.4064)
			(stroke
				(width 0.1524)
				(type default)
			)
			(layer "F.SilkS")
		)
		(fp_line
			(start -0.67945 0.3048)
			(end -0.67945 -0.305054)
			(stroke
				(width 0.1)
				(type default)
			)
			(layer "F.Fab")
		)
		(fp_line
			(start -0.12065 0.3048)
			(end -0.67945 0.3048)
			(stroke
				(width 0.1)
				(type default)
			)
			(layer "F.Fab")
		)
		(fp_line
			(start 0.120396 0.3048)
			(end 0.120396 0.2794)
			(stroke
				(width 0.1)
				(type default)
			)
			(layer "F.Fab")
		)
		(fp_line
			(start 0.67945 0.3048)
			(end 0.120396 0.3048)
			(stroke
				(width 0.1)
				(type default)
			)
			(layer "F.Fab")
		)
		(fp_line
			(start -0.12065 0.2794)
			(end -0.12065 0.3048)
			(stroke
				(width 0.1)
				(type default)
			)
			(layer "F.Fab")
		)
		(fp_line
			(start 0.120396 0.2794)
			(end -0.12065 0.2794)
			(stroke
				(width 0.1)
				(type default)
			)
			(layer "F.Fab")
		)
		(fp_line
			(start -0.12065 -0.2794)
			(end 0.12065 -0.2794)
			(stroke
				(width 0.1)
				(type default)
			)
			(layer "F.Fab")
		)
		(fp_line
			(start 0.12065 -0.2794)
			(end 0.12065 -0.3048)
			(stroke
				(width 0.1)
				(type default)
			)
			(layer "F.Fab")
		)
		(fp_line
			(start 0.12065 -0.3048)
			(end 0.67945 -0.3048)
			(stroke
				(width 0.1)
				(type default)
			)
			(layer "F.Fab")
		)
		(fp_line
			(start 0.67945 -0.3048)
			(end 0.67945 0.3048)
			(stroke
				(width 0.1)
				(type default)
			)
			(layer "F.Fab")
		)
		(fp_line
			(start -0.67945 -0.305054)
			(end -0.12065 -0.305054)
			(stroke
				(width 0.1)
				(type default)
			)
			(layer "F.Fab")
		)
		(fp_line
			(start -0.12065 -0.305054)
			(end -0.12065 -0.2794)
			(stroke
				(width 0.1)
				(type default)
			)
			(layer "F.Fab")
		)
		(pad "1" smd circle
			(at -0.40005 0 270)
			(size 0 0)
			(layers "F.Cu" "F.Mask" "F.Paste")
			(net "RT_BOARD_ID_ID1")
		)
		(pad "2" smd circle
			(at 0.40005 0 270)
			(size 0 0)
			(layers "F.Cu" "F.Mask" "F.Paste")
			(net "GND")
		)
	)
	(footprint ""
		(layer "F.Cu")
		(at 353.900232 -262.204962 180)
		(property "Reference" "C2627"
			(at 0 0 180)
			(layer "F.SilkS")
			(hide yes)
			(effects
				(font
					(size 1.27 1.27)
				)
			)
		)
		(property "Value" ""
			(at 0 0 180)
			(layer "F.Fab")
			(effects
				(font
					(size 1.27 1.27)
				)
			)
		)
		(duplicate_pad_numbers_are_jumpers no)
		(fp_line
			(start 0.7874 0.4064)
			(end -0.7874 0.4064)
			(stroke
				(width 0.1524)
				(type default)
			)
			(layer "F.SilkS")
		)
		(fp_line
			(start 0.7874 -0.4064)
			(end 0.7874 0.4064)
			(stroke
				(width 0.1524)
				(type default)
			)
			(layer "F.SilkS")
		)
		(fp_line
			(start -0.7874 0.4064)
			(end -0.7874 -0.4064)
			(stroke
				(width 0.1524)
				(type default)
			)
			(layer "F.SilkS")
		)
		(fp_line
			(start -0.7874 -0.4064)
			(end 0.7874 -0.4064)
			(stroke
				(width 0.1524)
				(type default)
			)
			(layer "F.SilkS")
		)
		(fp_line
			(start 0.67945 0.3048)
			(end 0.120396 0.3048)
			(stroke
				(width 0.1)
				(type default)
			)
			(layer "F.Fab")
		)
		(fp_line
			(start 0.67945 -0.3048)
			(end 0.67945 0.3048)
			(stroke
				(width 0.1)
				(type default)
			)
			(layer "F.Fab")
		)
		(fp_line
			(start 0.12065 -0.2794)
			(end 0.12065 -0.3048)
			(stroke
				(width 0.1)
				(type default)
			)
			(layer "F.Fab")
		)
		(fp_line
			(start 0.12065 -0.3048)
			(end 0.67945 -0.3048)
			(stroke
				(width 0.1)
				(type default)
			)
			(layer "F.Fab")
		)
		(fp_line
			(start 0.120396 0.3048)
			(end 0.120396 0.2794)
			(stroke
				(width 0.1)
				(type default)
			)
			(layer "F.Fab")
		)
		(fp_line
			(start 0.120396 0.2794)
			(end -0.12065 0.2794)
			(stroke
				(width 0.1)
				(type default)
			)
			(layer "F.Fab")
		)
		(fp_line
			(start -0.12065 0.3048)
			(end -0.67945 0.3048)
			(stroke
				(width 0.1)
				(type default)
			)
			(layer "F.Fab")
		)
		(fp_line
			(start -0.12065 0.2794)
			(end -0.12065 0.3048)
			(stroke
				(width 0.1)
				(type default)
			)
			(layer "F.Fab")
		)
		(fp_line
			(start -0.12065 -0.2794)
			(end 0.12065 -0.2794)
			(stroke
				(width 0.1)
				(type default)
			)
			(layer "F.Fab")
		)
		(fp_line
			(start -0.12065 -0.305054)
			(end -0.12065 -0.2794)
			(stroke
				(width 0.1)
				(type default)
			)
			(layer "F.Fab")
		)
		(fp_line
			(start -0.67945 0.3048)
			(end -0.67945 -0.305054)
			(stroke
				(width 0.1)
				(type default)
			)
			(layer "F.Fab")
		)
		(fp_line
			(start -0.67945 -0.305054)
			(end -0.12065 -0.305054)
			(stroke
				(width 0.1)
				(type default)
			)
			(layer "F.Fab")
		)
		(pad "1" smd circle
			(at -0.40005 0 180)
			(size 0 0)
			(layers "F.Cu" "F.Mask" "F.Paste")
			(net "PVDD11_S3_P0")
		)
		(pad "2" smd circle
			(at 0.40005 0 180)
			(size 0 0)
			(layers "F.Cu" "F.Mask" "F.Paste")
			(net "GND")
		)
	)
	(footprint ""
		(layer "F.Cu")
		(at 439.029602 -421.37711)
		(property "Reference" "PR6817"
			(at 0 0 0)
			(layer "F.SilkS")
			(hide yes)
			(effects
				(font
					(size 1.27 1.27)
				)
			)
		)
		(property "Value" ""
			(at 0 0 0)
			(layer "F.Fab")
			(effects
				(font
					(size 1.27 1.27)
				)
			)
		)
		(duplicate_pad_numbers_are_jumpers no)
		(fp_line
			(start -0.7874 -0.4064)
			(end 0.7874 -0.4064)
			(stroke
				(width 0.1524)
				(type default)
			)
			(layer "F.SilkS")
		)
		(fp_line
			(start -0.7874 0.4064)
			(end -0.7874 -0.4064)
			(stroke
				(width 0.1524)
				(type default)
			)
			(layer "F.SilkS")
		)
		(fp_line
			(start 0.7874 -0.4064)
			(end 0.7874 0.4064)
			(stroke
				(width 0.1524)
				(type default)
			)
			(layer "F.SilkS")
		)
		(fp_line
			(start 0.7874 0.4064)
			(end -0.7874 0.4064)
			(stroke
				(width 0.1524)
				(type default)
			)
			(layer "F.SilkS")
		)
		(fp_line
			(start -0.67945 -0.305054)
			(end -0.12065 -0.305054)
			(stroke
				(width 0.1)
				(type default)
			)
			(layer "F.Fab")
		)
		(fp_line
			(start -0.67945 0.3048)
			(end -0.67945 -0.305054)
			(stroke
				(width 0.1)
				(type default)
			)
			(layer "F.Fab")
		)
		(fp_line
			(start -0.12065 -0.305054)
			(end -0.12065 -0.2794)
			(stroke
				(width 0.1)
				(type default)
			)
			(layer "F.Fab")
		)
		(fp_line
			(start -0.12065 -0.2794)
			(end 0.12065 -0.2794)
			(stroke
				(width 0.1)
				(type default)
			)
			(layer "F.Fab")
		)
		(fp_line
			(start -0.12065 0.2794)
			(end -0.12065 0.3048)
			(stroke
				(width 0.1)
				(type default)
			)
			(layer "F.Fab")
		)
		(fp_line
			(start -0.12065 0.3048)
			(end -0.67945 0.3048)
			(stroke
				(width 0.1)
				(type default)
			)
			(layer "F.Fab")
		)
		(fp_line
			(start 0.120396 0.2794)
			(end -0.12065 0.2794)
			(stroke
				(width 0.1)
				(type default)
			)
			(layer "F.Fab")
		)
		(fp_line
			(start 0.120396 0.3048)
			(end 0.120396 0.2794)
			(stroke
				(width 0.1)
				(type default)
			)
			(layer "F.Fab")
		)
		(fp_line
			(start 0.12065 -0.3048)
			(end 0.67945 -0.3048)
			(stroke
				(width 0.1)
				(type default)
			)
			(layer "F.Fab")
		)
		(fp_line
			(start 0.12065 -0.2794)
			(end 0.12065 -0.3048)
			(stroke
				(width 0.1)
				(type default)
			)
			(layer "F.Fab")
		)
		(fp_line
			(start 0.67945 -0.3048)
			(end 0.67945 0.3048)
			(stroke
				(width 0.1)
				(type default)
			)
			(layer "F.Fab")
		)
		(fp_line
			(start 0.67945 0.3048)
			(end 0.120396 0.3048)
			(stroke
				(width 0.1)
				(type default)
			)
			(layer "F.Fab")
		)
		(pad "1" smd circle
			(at -0.40005 0)
			(size 0 0)
			(layers "F.Cu" "F.Mask" "F.Paste")
			(net "P3V3_AUX")
		)
		(pad "2" smd circle
			(at 0.40005 0)
			(size 0 0)
			(layers "F.Cu" "F.Mask" "F.Paste")
			(net "TP_P0V9_RETIMER_CPU0_SVID_ALERT_N")
		)
	)
	(footprint ""
		(layer "F.Cu")
		(at 81.424018 -15.177262 180)
		(property "Reference" "PD108"
			(at -5.42798 0.894588 0)
			(unlocked yes)
			(layer "F.SilkS")
			(effects
				(font
					(size 0.7874 0.5842)
					(thickness 0.1524)
				)
				(justify left)
			)
		)
		(property "Value" ""
			(at 0 0 180)
			(layer "F.Fab")
			(effects
				(font
					(size 1.27 1.27)
				)
			)
		)
		(duplicate_pad_numbers_are_jumpers no)
		(fp_line
			(start 4.107942 1.459992)
			(end -3.400044 1.459992)
			(stroke
				(width 0.1524)
				(type default)
			)
			(layer "F.SilkS")
		)
		(fp_line
			(start 4.107942 -1.459992)
			(end 4.107942 1.459992)
			(stroke
				(width 0.1524)
				(type default)
			)
			(layer "F.SilkS")
		)
		(fp_line
			(start -3.400044 1.459992)
			(end -3.400044 -1.459992)
			(stroke
				(width 0.1524)
				(type default)
			)
			(layer "F.SilkS")
		)
		(fp_line
			(start -3.400044 -1.459992)
			(end 4.107942 -1.459992)
			(stroke
				(width 0.1524)
				(type default)
			)
			(layer "F.SilkS")
		)
		(fp_rect
			(start 4.107942 -1.459992)
			(end 3.308096 1.459992)
			(stroke
				(width 0)
				(type default)
			)
			(fill yes)
			(layer "F.SilkS")
		)
		(fp_line
			(start 2.29997 1.459992)
			(end -2.29997 1.459992)
			(stroke
				(width 0.1)
				(type default)
			)
			(layer "F.Fab")
		)
		(fp_line
			(start 2.29997 -1.459992)
			(end 2.29997 1.459992)
			(stroke
				(width 0.1)
				(type default)
			)
			(layer "F.Fab")
		)
		(fp_line
			(start -2.29997 1.459992)
			(end -2.29997 -1.459992)
			(stroke
				(width 0.1)
				(type default)
			)
			(layer "F.Fab")
		)
		(fp_line
			(start -2.29997 -1.459992)
			(end 2.29997 -1.459992)
			(stroke
				(width 0.1)
				(type default)
			)
			(layer "F.Fab")
		)
		(fp_text user "-"
			(at 5.4102 0.29845 0)
			(unlocked yes)
			(layer "F.SilkS")
			(effects
				(font
					(size 1.905 1.4224)
					(thickness 0.1524)
				)
				(justify left)
			)
		)
		(fp_text user "+"
			(at -4.7752 -0.12065 180)
			(unlocked yes)
			(layer "F.SilkS")
			(effects
				(font
					(size 1.905 1.4224)
					(thickness 0.1524)
				)
				(justify left)
			)
		)
		(fp_text user "-"
			(at 5.4102 0.29845 0)
			(unlocked yes)
			(layer "F.Fab")
			(effects
				(font
					(size 1.905 1.4224)
					(thickness 0.1524)
				)
				(justify left)
			)
		)
		(fp_text user "+"
			(at -4.7752 -0.12065 180)
			(unlocked yes)
			(layer "F.Fab")
			(effects
				(font
					(size 1.905 1.4224)
					(thickness 0.1524)
				)
				(justify left)
			)
		)
		(pad "A" smd rect
			(at -1.999996 0 270)
			(size 1.7018 2.5146)
			(layers "F.Cu" "F.Mask" "F.Paste")
			(net "GND")
		)
		(pad "C" smd rect
			(at 1.999996 0 270)
			(size 1.7018 2.5146)
			(layers "F.Cu" "F.Mask" "F.Paste")
			(net "P12V_OCP_V3_2")
		)
	)
	(footprint ""
		(layer "F.Cu")
		(at 336.195416 -20.136612 -90)
		(property "Reference" "Q29"
			(at -0.557276 2.35966 90)
			(unlocked yes)
			(layer "F.SilkS")
			(effects
				(font
					(size 0.7874 0.5842)
					(thickness 0.1524)
				)
			)
		)
		(property "Value" ""
			(at 0 0 270)
			(layer "F.Fab")
			(effects
				(font
					(size 1.27 1.27)
				)
			)
		)
		(duplicate_pad_numbers_are_jumpers no)
		(fp_line
			(start -1.8796 1.651)
			(end -1.8796 -1.651)
			(stroke
				(width 0.1524)
				(type default)
			)
			(layer "F.SilkS")
		)
		(fp_line
			(start 1.8796 1.651)
			(end -1.8796 1.651)
			(stroke
				(width 0.1524)
				(type default)
			)
			(layer "F.SilkS")
		)
		(fp_line
			(start -1.8796 -1.651)
			(end 1.8796 -1.651)
			(stroke
				(width 0.1524)
				(type default)
			)
			(layer "F.SilkS")
		)
		(fp_line
			(start 1.8796 -1.651)
			(end 1.8796 1.651)
			(stroke
				(width 0.1524)
				(type default)
			)
			(layer "F.SilkS")
		)
		(fp_line
			(start -0.700024 1.500124)
			(end -0.700024 -1.500124)
			(stroke
				(width 0.1)
				(type default)
			)
			(layer "F.Fab")
		)
		(fp_line
			(start 0.700024 1.500124)
			(end -0.700024 1.500124)
			(stroke
				(width 0.1)
				(type default)
			)
			(layer "F.Fab")
		)
		(fp_line
			(start -0.700024 -1.500124)
			(end 0.700024 -1.500124)
			(stroke
				(width 0.1)
				(type default)
			)
			(layer "F.Fab")
		)
		(fp_line
			(start 0.700024 -1.500124)
			(end 0.700024 1.500124)
			(stroke
				(width 0.1)
				(type default)
			)
			(layer "F.Fab")
		)
		(pad "D" smd rect
			(at 1.119886 0 180)
			(size 1.016 1.2192)
			(layers "F.Cu" "F.Mask" "F.Paste")
			(net "LED_BIOS_DBG_MODE")
		)
		(pad "G" smd rect
			(at -1.119886 -0.999998 180)
			(size 1.016 1.2192)
			(layers "F.Cu" "F.Mask" "F.Paste")
			(net "LED_BIOS_DBG_MODE_N")
		)
		(pad "S" smd rect
			(at -1.119886 0.999998 180)
			(size 1.016 1.2192)
			(layers "F.Cu" "F.Mask" "F.Paste")
			(net "GND")
		)
	)
	(footprint ""
		(layer "F.Cu")
		(at 291.144452 -124.414026)
		(property "Reference" "C106"
			(at 0 0 0)
			(layer "F.SilkS")
			(hide yes)
			(effects
				(font
					(size 1.27 1.27)
				)
			)
		)
		(property "Value" ""
			(at 0 0 0)
			(layer "F.Fab")
			(effects
				(font
					(size 1.27 1.27)
				)
			)
		)
		(duplicate_pad_numbers_are_jumpers no)
		(fp_line
			(start -0.7874 -0.4064)
			(end 0.7874 -0.4064)
			(stroke
				(width 0.1524)
				(type default)
			)
			(layer "F.SilkS")
		)
		(fp_line
			(start -0.7874 0.4064)
			(end -0.7874 -0.4064)
			(stroke
				(width 0.1524)
				(type default)
			)
			(layer "F.SilkS")
		)
		(fp_line
			(start 0.7874 -0.4064)
			(end 0.7874 0.4064)
			(stroke
				(width 0.1524)
				(type default)
			)
			(layer "F.SilkS")
		)
		(fp_line
			(start 0.7874 0.4064)
			(end -0.7874 0.4064)
			(stroke
				(width 0.1524)
				(type default)
			)
			(layer "F.SilkS")
		)
		(fp_line
			(start -0.67945 -0.305054)
			(end -0.12065 -0.305054)
			(stroke
				(width 0.1)
				(type default)
			)
			(layer "F.Fab")
		)
		(fp_line
			(start -0.67945 0.3048)
			(end -0.67945 -0.305054)
			(stroke
				(width 0.1)
				(type default)
			)
			(layer "F.Fab")
		)
		(fp_line
			(start -0.12065 -0.305054)
			(end -0.12065 -0.2794)
			(stroke
				(width 0.1)
				(type default)
			)
			(layer "F.Fab")
		)
		(fp_line
			(start -0.12065 -0.2794)
			(end 0.12065 -0.2794)
			(stroke
				(width 0.1)
				(type default)
			)
			(layer "F.Fab")
		)
		(fp_line
			(start -0.12065 0.2794)
			(end -0.12065 0.3048)
			(stroke
				(width 0.1)
				(type default)
			)
			(layer "F.Fab")
		)
		(fp_line
			(start -0.12065 0.3048)
			(end -0.67945 0.3048)
			(stroke
				(width 0.1)
				(type default)
			)
			(layer "F.Fab")
		)
		(fp_line
			(start 0.120396 0.2794)
			(end -0.12065 0.2794)
			(stroke
				(width 0.1)
				(type default)
			)
			(layer "F.Fab")
		)
		(fp_line
			(start 0.120396 0.3048)
			(end 0.120396 0.2794)
			(stroke
				(width 0.1)
				(type default)
			)
			(layer "F.Fab")
		)
		(fp_line
			(start 0.12065 -0.3048)
			(end 0.67945 -0.3048)
			(stroke
				(width 0.1)
				(type default)
			)
			(layer "F.Fab")
		)
		(fp_line
			(start 0.12065 -0.2794)
			(end 0.12065 -0.3048)
			(stroke
				(width 0.1)
				(type default)
			)
			(layer "F.Fab")
		)
		(fp_line
			(start 0.67945 -0.3048)
			(end 0.67945 0.3048)
			(stroke
				(width 0.1)
				(type default)
			)
			(layer "F.Fab")
		)
		(fp_line
			(start 0.67945 0.3048)
			(end 0.120396 0.3048)
			(stroke
				(width 0.1)
				(type default)
			)
			(layer "F.Fab")
		)
		(pad "1" smd circle
			(at -0.40005 0)
			(size 0 0)
			(layers "F.Cu" "F.Mask" "F.Paste")
			(net "P3V3_AUX")
		)
		(pad "2" smd circle
			(at 0.40005 0)
			(size 0 0)
			(layers "F.Cu" "F.Mask" "F.Paste")
			(net "GND")
		)
	)
	(footprint ""
		(layer "F.Cu")
		(at 435.102 -171.4881 -90)
		(property "Reference" "R1333"
			(at 0 0 270)
			(layer "F.SilkS")
			(hide yes)
			(effects
				(font
					(size 1.27 1.27)
				)
			)
		)
		(property "Value" ""
			(at 0 0 270)
			(layer "F.Fab")
			(effects
				(font
					(size 1.27 1.27)
				)
			)
		)
		(duplicate_pad_numbers_are_jumpers no)
		(fp_line
			(start -0.7874 0.4064)
			(end -0.7874 -0.4064)
			(stroke
				(width 0.1524)
				(type default)
			)
			(layer "F.SilkS")
		)
		(fp_line
			(start 0.7874 0.4064)
			(end -0.7874 0.4064)
			(stroke
				(width 0.1524)
				(type default)
			)
			(layer "F.SilkS")
		)
		(fp_line
			(start -0.7874 -0.4064)
			(end 0.7874 -0.4064)
			(stroke
				(width 0.1524)
				(type default)
			)
			(layer "F.SilkS")
		)
		(fp_line
			(start 0.7874 -0.4064)
			(end 0.7874 0.4064)
			(stroke
				(width 0.1524)
				(type default)
			)
			(layer "F.SilkS")
		)
		(fp_line
			(start -0.67945 0.3048)
			(end -0.67945 -0.305054)
			(stroke
				(width 0.1)
				(type default)
			)
			(layer "F.Fab")
		)
		(fp_line
			(start -0.12065 0.3048)
			(end -0.67945 0.3048)
			(stroke
				(width 0.1)
				(type default)
			)
			(layer "F.Fab")
		)
		(fp_line
			(start 0.120396 0.3048)
			(end 0.120396 0.2794)
			(stroke
				(width 0.1)
				(type default)
			)
			(layer "F.Fab")
		)
		(fp_line
			(start 0.67945 0.3048)
			(end 0.120396 0.3048)
			(stroke
				(width 0.1)
				(type default)
			)
			(layer "F.Fab")
		)
		(fp_line
			(start -0.12065 0.2794)
			(end -0.12065 0.3048)
			(stroke
				(width 0.1)
				(type default)
			)
			(layer "F.Fab")
		)
		(fp_line
			(start 0.120396 0.2794)
			(end -0.12065 0.2794)
			(stroke
				(width 0.1)
				(type default)
			)
			(layer "F.Fab")
		)
		(fp_line
			(start -0.12065 -0.2794)
			(end 0.12065 -0.2794)
			(stroke
				(width 0.1)
				(type default)
			)
			(layer "F.Fab")
		)
		(fp_line
			(start 0.12065 -0.2794)
			(end 0.12065 -0.3048)
			(stroke
				(width 0.1)
				(type default)
			)
			(layer "F.Fab")
		)
		(fp_line
			(start 0.12065 -0.3048)
			(end 0.67945 -0.3048)
			(stroke
				(width 0.1)
				(type default)
			)
			(layer "F.Fab")
		)
		(fp_line
			(start 0.67945 -0.3048)
			(end 0.67945 0.3048)
			(stroke
				(width 0.1)
				(type default)
			)
			(layer "F.Fab")
		)
		(fp_line
			(start -0.67945 -0.305054)
			(end -0.12065 -0.305054)
			(stroke
				(width 0.1)
				(type default)
			)
			(layer "F.Fab")
		)
		(fp_line
			(start -0.12065 -0.305054)
			(end -0.12065 -0.2794)
			(stroke
				(width 0.1)
				(type default)
			)
			(layer "F.Fab")
		)
		(pad "1" smd rect
			(at -0.40005 0 90)
			(size 0.4572 0.508)
			(layers "F.Cu" "F.Mask" "F.Paste")
			(net "I3C_SPD_DDRGL_CPU0_BYPASS_SDA")
		)
		(pad "2" smd rect
			(at 0.40005 0 90)
			(size 0.4572 0.508)
			(layers "F.Cu" "F.Mask" "F.Paste")
			(net "I3C_SPD_DDRGL_CPU0_SDA")
		)
	)
	(footprint ""
		(layer "F.Cu")
		(at 178.8922 -96.103948 90)
		(property "Reference" "R235"
			(at 0 0 90)
			(layer "F.SilkS")
			(hide yes)
			(effects
				(font
					(size 1.27 1.27)
				)
			)
		)
		(property "Value" ""
			(at 0 0 90)
			(layer "F.Fab")
			(effects
				(font
					(size 1.27 1.27)
				)
			)
		)
		(duplicate_pad_numbers_are_jumpers no)
		(fp_line
			(start 0.7874 -0.4064)
			(end 0.7874 0.4064)
			(stroke
				(width 0.1524)
				(type default)
			)
			(layer "F.SilkS")
		)
		(fp_line
			(start -0.7874 -0.4064)
			(end 0.7874 -0.4064)
			(stroke
				(width 0.1524)
				(type default)
			)
			(layer "F.SilkS")
		)
		(fp_line
			(start 0.7874 0.4064)
			(end -0.7874 0.4064)
			(stroke
				(width 0.1524)
				(type default)
			)
			(layer "F.SilkS")
		)
		(fp_line
			(start -0.7874 0.4064)
			(end -0.7874 -0.4064)
			(stroke
				(width 0.1524)
				(type default)
			)
			(layer "F.SilkS")
		)
		(fp_line
			(start -0.12065 -0.305054)
			(end -0.12065 -0.2794)
			(stroke
				(width 0.1)
				(type default)
			)
			(layer "F.Fab")
		)
		(fp_line
			(start -0.67945 -0.305054)
			(end -0.12065 -0.305054)
			(stroke
				(width 0.1)
				(type default)
			)
			(layer "F.Fab")
		)
		(fp_line
			(start 0.67945 -0.3048)
			(end 0.67945 0.3048)
			(stroke
				(width 0.1)
				(type default)
			)
			(layer "F.Fab")
		)
		(fp_line
			(start 0.12065 -0.3048)
			(end 0.67945 -0.3048)
			(stroke
				(width 0.1)
				(type default)
			)
			(layer "F.Fab")
		)
		(fp_line
			(start 0.12065 -0.2794)
			(end 0.12065 -0.3048)
			(stroke
				(width 0.1)
				(type default)
			)
			(layer "F.Fab")
		)
		(fp_line
			(start -0.12065 -0.2794)
			(end 0.12065 -0.2794)
			(stroke
				(width 0.1)
				(type default)
			)
			(layer "F.Fab")
		)
		(fp_line
			(start 0.120396 0.2794)
			(end -0.12065 0.2794)
			(stroke
				(width 0.1)
				(type default)
			)
			(layer "F.Fab")
		)
		(fp_line
			(start -0.12065 0.2794)
			(end -0.12065 0.3048)
			(stroke
				(width 0.1)
				(type default)
			)
			(layer "F.Fab")
		)
		(fp_line
			(start 0.67945 0.3048)
			(end 0.120396 0.3048)
			(stroke
				(width 0.1)
				(type default)
			)
			(layer "F.Fab")
		)
		(fp_line
			(start 0.120396 0.3048)
			(end 0.120396 0.2794)
			(stroke
				(width 0.1)
				(type default)
			)
			(layer "F.Fab")
		)
		(fp_line
			(start -0.12065 0.3048)
			(end -0.67945 0.3048)
			(stroke
				(width 0.1)
				(type default)
			)
			(layer "F.Fab")
		)
		(fp_line
			(start -0.67945 0.3048)
			(end -0.67945 -0.305054)
			(stroke
				(width 0.1)
				(type default)
			)
			(layer "F.Fab")
		)
		(pad "1" smd circle
			(at -0.40005 0 90)
			(size 0 0)
			(layers "F.Cu" "F.Mask" "F.Paste")
			(net "CPU1_XTRIG_L7")
		)
		(pad "2" smd circle
			(at 0.40005 0 90)
			(size 0 0)
			(layers "F.Cu" "F.Mask" "F.Paste")
			(net "FM_CPU1_XTRIG_L7")
		)
	)
	(footprint ""
		(layer "F.Cu")
		(at 358.268524 -387.853428)
		(property "Reference" "C935"
			(at 0 0 0)
			(layer "F.SilkS")
			(hide yes)
			(effects
				(font
					(size 1.27 1.27)
				)
			)
		)
		(property "Value" ""
			(at 0 0 0)
			(layer "F.Fab")
			(effects
				(font
					(size 1.27 1.27)
				)
			)
		)
		(duplicate_pad_numbers_are_jumpers no)
		(fp_line
			(start -0.299974 -0.150114)
			(end 0.299974 -0.150114)
			(stroke
				(width 0.1)
				(type default)
			)
			(layer "F.Fab")
		)
		(fp_line
			(start -0.299974 0.150114)
			(end -0.299974 -0.150114)
			(stroke
				(width 0.1)
				(type default)
			)
			(layer "F.Fab")
		)
		(fp_line
			(start 0.299974 -0.150114)
			(end 0.299974 0.150114)
			(stroke
				(width 0.1)
				(type default)
			)
			(layer "F.Fab")
		)
		(fp_line
			(start 0.299974 0.150114)
			(end -0.299974 0.150114)
			(stroke
				(width 0.1)
				(type default)
			)
			(layer "F.Fab")
		)
		(pad "1" smd rect
			(at -0.2667 0)
			(size 0.3048 0.381)
			(layers "F.Cu" "F.Mask" "F.Paste")
			(net "P5E_CPU0_P1_TX_C_DP<15>")
		)
		(pad "2" smd rect
			(at 0.2667 0)
			(size 0.3048 0.381)
			(layers "F.Cu" "F.Mask" "F.Paste")
			(net "P5E_CPU0_P1_TX_DP<15>")
		)
	)
	(footprint ""
		(layer "F.Cu")
		(at 179.482242 -422.802304 -90)
		(property "Reference" "C1713"
			(at 0 0 270)
			(layer "F.SilkS")
			(hide yes)
			(effects
				(font
					(size 1.27 1.27)
				)
			)
		)
		(property "Value" ""
			(at 0 0 270)
			(layer "F.Fab")
			(effects
				(font
					(size 1.27 1.27)
				)
			)
		)
		(duplicate_pad_numbers_are_jumpers no)
		(fp_line
			(start -0.7874 0.4064)
			(end -0.7874 -0.4064)
			(stroke
				(width 0.1524)
				(type default)
			)
			(layer "F.SilkS")
		)
		(fp_line
			(start 0.7874 0.4064)
			(end -0.7874 0.4064)
			(stroke
				(width 0.1524)
				(type default)
			)
			(layer "F.SilkS")
		)
		(fp_line
			(start -0.7874 -0.4064)
			(end 0.7874 -0.4064)
			(stroke
				(width 0.1524)
				(type default)
			)
			(layer "F.SilkS")
		)
		(fp_line
			(start 0.7874 -0.4064)
			(end 0.7874 0.4064)
			(stroke
				(width 0.1524)
				(type default)
			)
			(layer "F.SilkS")
		)
		(fp_line
			(start -0.67945 0.3048)
			(end -0.67945 -0.305054)
			(stroke
				(width 0.1)
				(type default)
			)
			(layer "F.Fab")
		)
		(fp_line
			(start -0.12065 0.3048)
			(end -0.67945 0.3048)
			(stroke
				(width 0.1)
				(type default)
			)
			(layer "F.Fab")
		)
		(fp_line
			(start 0.120396 0.3048)
			(end 0.120396 0.2794)
			(stroke
				(width 0.1)
				(type default)
			)
			(layer "F.Fab")
		)
		(fp_line
			(start 0.67945 0.3048)
			(end 0.120396 0.3048)
			(stroke
				(width 0.1)
				(type default)
			)
			(layer "F.Fab")
		)
		(fp_line
			(start -0.12065 0.2794)
			(end -0.12065 0.3048)
			(stroke
				(width 0.1)
				(type default)
			)
			(layer "F.Fab")
		)
		(fp_line
			(start 0.120396 0.2794)
			(end -0.12065 0.2794)
			(stroke
				(width 0.1)
				(type default)
			)
			(layer "F.Fab")
		)
		(fp_line
			(start -0.12065 -0.2794)
			(end 0.12065 -0.2794)
			(stroke
				(width 0.1)
				(type default)
			)
			(layer "F.Fab")
		)
		(fp_line
			(start 0.12065 -0.2794)
			(end 0.12065 -0.3048)
			(stroke
				(width 0.1)
				(type default)
			)
			(layer "F.Fab")
		)
		(fp_line
			(start 0.12065 -0.3048)
			(end 0.67945 -0.3048)
			(stroke
				(width 0.1)
				(type default)
			)
			(layer "F.Fab")
		)
		(fp_line
			(start 0.67945 -0.3048)
			(end 0.67945 0.3048)
			(stroke
				(width 0.1)
				(type default)
			)
			(layer "F.Fab")
		)
		(fp_line
			(start -0.67945 -0.305054)
			(end -0.12065 -0.305054)
			(stroke
				(width 0.1)
				(type default)
			)
			(layer "F.Fab")
		)
		(fp_line
			(start -0.12065 -0.305054)
			(end -0.12065 -0.2794)
			(stroke
				(width 0.1)
				(type default)
			)
			(layer "F.Fab")
		)
		(pad "1" smd circle
			(at -0.40005 0 270)
			(size 0 0)
			(layers "F.Cu" "F.Mask" "F.Paste")
			(net "P3V3_AUX")
		)
		(pad "2" smd circle
			(at 0.40005 0 270)
			(size 0 0)
			(layers "F.Cu" "F.Mask" "F.Paste")
			(net "GND")
		)
	)
	(footprint ""
		(layer "F.Cu")
		(at 356.565962 -256.012188 90)
		(property "Reference" "C3895"
			(at 0 0 90)
			(layer "F.SilkS")
			(hide yes)
			(effects
				(font
					(size 1.27 1.27)
				)
			)
		)
		(property "Value" ""
			(at 0 0 90)
			(layer "F.Fab")
			(effects
				(font
					(size 1.27 1.27)
				)
			)
		)
		(duplicate_pad_numbers_are_jumpers no)
		(fp_line
			(start 0.7874 -0.4064)
			(end 0.7874 0.4064)
			(stroke
				(width 0.1524)
				(type default)
			)
			(layer "F.SilkS")
		)
		(fp_line
			(start -0.7874 -0.4064)
			(end 0.7874 -0.4064)
			(stroke
				(width 0.1524)
				(type default)
			)
			(layer "F.SilkS")
		)
		(fp_line
			(start 0.7874 0.4064)
			(end -0.7874 0.4064)
			(stroke
				(width 0.1524)
				(type default)
			)
			(layer "F.SilkS")
		)
		(fp_line
			(start -0.7874 0.4064)
			(end -0.7874 -0.4064)
			(stroke
				(width 0.1524)
				(type default)
			)
			(layer "F.SilkS")
		)
		(fp_line
			(start -0.12065 -0.305054)
			(end -0.12065 -0.2794)
			(stroke
				(width 0.1)
				(type default)
			)
			(layer "F.Fab")
		)
		(fp_line
			(start -0.67945 -0.305054)
			(end -0.12065 -0.305054)
			(stroke
				(width 0.1)
				(type default)
			)
			(layer "F.Fab")
		)
		(fp_line
			(start 0.67945 -0.3048)
			(end 0.67945 0.3048)
			(stroke
				(width 0.1)
				(type default)
			)
			(layer "F.Fab")
		)
		(fp_line
			(start 0.12065 -0.3048)
			(end 0.67945 -0.3048)
			(stroke
				(width 0.1)
				(type default)
			)
			(layer "F.Fab")
		)
		(fp_line
			(start 0.12065 -0.2794)
			(end 0.12065 -0.3048)
			(stroke
				(width 0.1)
				(type default)
			)
			(layer "F.Fab")
		)
		(fp_line
			(start -0.12065 -0.2794)
			(end 0.12065 -0.2794)
			(stroke
				(width 0.1)
				(type default)
			)
			(layer "F.Fab")
		)
		(fp_line
			(start 0.120396 0.2794)
			(end -0.12065 0.2794)
			(stroke
				(width 0.1)
				(type default)
			)
			(layer "F.Fab")
		)
		(fp_line
			(start -0.12065 0.2794)
			(end -0.12065 0.3048)
			(stroke
				(width 0.1)
				(type default)
			)
			(layer "F.Fab")
		)
		(fp_line
			(start 0.67945 0.3048)
			(end 0.120396 0.3048)
			(stroke
				(width 0.1)
				(type default)
			)
			(layer "F.Fab")
		)
		(fp_line
			(start 0.120396 0.3048)
			(end 0.120396 0.2794)
			(stroke
				(width 0.1)
				(type default)
			)
			(layer "F.Fab")
		)
		(fp_line
			(start -0.12065 0.3048)
			(end -0.67945 0.3048)
			(stroke
				(width 0.1)
				(type default)
			)
			(layer "F.Fab")
		)
		(fp_line
			(start -0.67945 0.3048)
			(end -0.67945 -0.305054)
			(stroke
				(width 0.1)
				(type default)
			)
			(layer "F.Fab")
		)
		(pad "1" smd circle
			(at -0.40005 0 90)
			(size 0 0)
			(layers "F.Cu" "F.Mask" "F.Paste")
			(net "PVDDCR_SOC_P0")
		)
		(pad "2" smd circle
			(at 0.40005 0 90)
			(size 0 0)
			(layers "F.Cu" "F.Mask" "F.Paste")
			(net "GND")
		)
	)
	(footprint ""
		(layer "F.Cu")
		(at 143.88084 -40.403526 90)
		(property "Reference" "C1859"
			(at 0 0 90)
			(layer "F.SilkS")
			(hide yes)
			(effects
				(font
					(size 1.27 1.27)
				)
			)
		)
		(property "Value" ""
			(at 0 0 90)
			(layer "F.Fab")
			(effects
				(font
					(size 1.27 1.27)
				)
			)
		)
		(duplicate_pad_numbers_are_jumpers no)
		(fp_line
			(start 0.7874 -0.4064)
			(end 0.7874 0.4064)
			(stroke
				(width 0.1524)
				(type default)
			)
			(layer "F.SilkS")
		)
		(fp_line
			(start -0.7874 -0.4064)
			(end 0.7874 -0.4064)
			(stroke
				(width 0.1524)
				(type default)
			)
			(layer "F.SilkS")
		)
		(fp_line
			(start 0.7874 0.4064)
			(end -0.7874 0.4064)
			(stroke
				(width 0.1524)
				(type default)
			)
			(layer "F.SilkS")
		)
		(fp_line
			(start -0.7874 0.4064)
			(end -0.7874 -0.4064)
			(stroke
				(width 0.1524)
				(type default)
			)
			(layer "F.SilkS")
		)
		(fp_line
			(start -0.12065 -0.305054)
			(end -0.12065 -0.2794)
			(stroke
				(width 0.1)
				(type default)
			)
			(layer "F.Fab")
		)
		(fp_line
			(start -0.67945 -0.305054)
			(end -0.12065 -0.305054)
			(stroke
				(width 0.1)
				(type default)
			)
			(layer "F.Fab")
		)
		(fp_line
			(start 0.67945 -0.3048)
			(end 0.67945 0.3048)
			(stroke
				(width 0.1)
				(type default)
			)
			(layer "F.Fab")
		)
		(fp_line
			(start 0.12065 -0.3048)
			(end 0.67945 -0.3048)
			(stroke
				(width 0.1)
				(type default)
			)
			(layer "F.Fab")
		)
		(fp_line
			(start 0.12065 -0.2794)
			(end 0.12065 -0.3048)
			(stroke
				(width 0.1)
				(type default)
			)
			(layer "F.Fab")
		)
		(fp_line
			(start -0.12065 -0.2794)
			(end 0.12065 -0.2794)
			(stroke
				(width 0.1)
				(type default)
			)
			(layer "F.Fab")
		)
		(fp_line
			(start 0.120396 0.2794)
			(end -0.12065 0.2794)
			(stroke
				(width 0.1)
				(type default)
			)
			(layer "F.Fab")
		)
		(fp_line
			(start -0.12065 0.2794)
			(end -0.12065 0.3048)
			(stroke
				(width 0.1)
				(type default)
			)
			(layer "F.Fab")
		)
		(fp_line
			(start 0.67945 0.3048)
			(end 0.120396 0.3048)
			(stroke
				(width 0.1)
				(type default)
			)
			(layer "F.Fab")
		)
		(fp_line
			(start 0.120396 0.3048)
			(end 0.120396 0.2794)
			(stroke
				(width 0.1)
				(type default)
			)
			(layer "F.Fab")
		)
		(fp_line
			(start -0.12065 0.3048)
			(end -0.67945 0.3048)
			(stroke
				(width 0.1)
				(type default)
			)
			(layer "F.Fab")
		)
		(fp_line
			(start -0.67945 0.3048)
			(end -0.67945 -0.305054)
			(stroke
				(width 0.1)
				(type default)
			)
			(layer "F.Fab")
		)
		(pad "1" smd circle
			(at -0.40005 0 90)
			(size 0 0)
			(layers "F.Cu" "F.Mask" "F.Paste")
			(net "P3V3_AUX")
		)
		(pad "2" smd circle
			(at 0.40005 0 90)
			(size 0 0)
			(layers "F.Cu" "F.Mask" "F.Paste")
			(net "GND")
		)
	)
	(footprint ""
		(layer "F.Cu")
		(at 91.776296 -333.29499 90)
		(property "Reference" "PR517"
			(at 0 0 90)
			(layer "F.SilkS")
			(hide yes)
			(effects
				(font
					(size 1.27 1.27)
				)
			)
		)
		(property "Value" ""
			(at 0 0 90)
			(layer "F.Fab")
			(effects
				(font
					(size 1.27 1.27)
				)
			)
		)
		(duplicate_pad_numbers_are_jumpers no)
		(fp_line
			(start 0.7874 -0.4064)
			(end 0.7874 0.4064)
			(stroke
				(width 0.1524)
				(type default)
			)
			(layer "F.SilkS")
		)
		(fp_line
			(start -0.7874 -0.4064)
			(end 0.7874 -0.4064)
			(stroke
				(width 0.1524)
				(type default)
			)
			(layer "F.SilkS")
		)
		(fp_line
			(start 0.7874 0.4064)
			(end -0.7874 0.4064)
			(stroke
				(width 0.1524)
				(type default)
			)
			(layer "F.SilkS")
		)
		(fp_line
			(start -0.7874 0.4064)
			(end -0.7874 -0.4064)
			(stroke
				(width 0.1524)
				(type default)
			)
			(layer "F.SilkS")
		)
		(fp_line
			(start -0.12065 -0.305054)
			(end -0.12065 -0.2794)
			(stroke
				(width 0.1)
				(type default)
			)
			(layer "F.Fab")
		)
		(fp_line
			(start -0.67945 -0.305054)
			(end -0.12065 -0.305054)
			(stroke
				(width 0.1)
				(type default)
			)
			(layer "F.Fab")
		)
		(fp_line
			(start 0.67945 -0.3048)
			(end 0.67945 0.3048)
			(stroke
				(width 0.1)
				(type default)
			)
			(layer "F.Fab")
		)
		(fp_line
			(start 0.12065 -0.3048)
			(end 0.67945 -0.3048)
			(stroke
				(width 0.1)
				(type default)
			)
			(layer "F.Fab")
		)
		(fp_line
			(start 0.12065 -0.2794)
			(end 0.12065 -0.3048)
			(stroke
				(width 0.1)
				(type default)
			)
			(layer "F.Fab")
		)
		(fp_line
			(start -0.12065 -0.2794)
			(end 0.12065 -0.2794)
			(stroke
				(width 0.1)
				(type default)
			)
			(layer "F.Fab")
		)
		(fp_line
			(start 0.120396 0.2794)
			(end -0.12065 0.2794)
			(stroke
				(width 0.1)
				(type default)
			)
			(layer "F.Fab")
		)
		(fp_line
			(start -0.12065 0.2794)
			(end -0.12065 0.3048)
			(stroke
				(width 0.1)
				(type default)
			)
			(layer "F.Fab")
		)
		(fp_line
			(start 0.67945 0.3048)
			(end 0.120396 0.3048)
			(stroke
				(width 0.1)
				(type default)
			)
			(layer "F.Fab")
		)
		(fp_line
			(start 0.120396 0.3048)
			(end 0.120396 0.2794)
			(stroke
				(width 0.1)
				(type default)
			)
			(layer "F.Fab")
		)
		(fp_line
			(start -0.12065 0.3048)
			(end -0.67945 0.3048)
			(stroke
				(width 0.1)
				(type default)
			)
			(layer "F.Fab")
		)
		(fp_line
			(start -0.67945 0.3048)
			(end -0.67945 -0.305054)
			(stroke
				(width 0.1)
				(type default)
			)
			(layer "F.Fab")
		)
		(pad "1" smd circle
			(at -0.40005 0 90)
			(size 0 0)
			(layers "F.Cu" "F.Mask" "F.Paste")
			(net "SW_PVDDCR_CPU1_P1_SW5_RC")
		)
		(pad "2" smd circle
			(at 0.40005 0 90)
			(size 0 0)
			(layers "F.Cu" "F.Mask" "F.Paste")
			(net "GND")
		)
	)
	(footprint ""
		(layer "F.Cu")
		(at 97.745296 -412.931102 90)
		(property "Reference" "R4181"
			(at 0 0 90)
			(layer "F.SilkS")
			(hide yes)
			(effects
				(font
					(size 1.27 1.27)
				)
			)
		)
		(property "Value" ""
			(at 0 0 90)
			(layer "F.Fab")
			(effects
				(font
					(size 1.27 1.27)
				)
			)
		)
		(duplicate_pad_numbers_are_jumpers no)
		(fp_line
			(start 0.7874 -0.4064)
			(end 0.7874 0.4064)
			(stroke
				(width 0.1524)
				(type default)
			)
			(layer "F.SilkS")
		)
		(fp_line
			(start -0.7874 -0.4064)
			(end 0.7874 -0.4064)
			(stroke
				(width 0.1524)
				(type default)
			)
			(layer "F.SilkS")
		)
		(fp_line
			(start 0.7874 0.4064)
			(end -0.7874 0.4064)
			(stroke
				(width 0.1524)
				(type default)
			)
			(layer "F.SilkS")
		)
		(fp_line
			(start -0.7874 0.4064)
			(end -0.7874 -0.4064)
			(stroke
				(width 0.1524)
				(type default)
			)
			(layer "F.SilkS")
		)
		(fp_line
			(start -0.12065 -0.305054)
			(end -0.12065 -0.2794)
			(stroke
				(width 0.1)
				(type default)
			)
			(layer "F.Fab")
		)
		(fp_line
			(start -0.67945 -0.305054)
			(end -0.12065 -0.305054)
			(stroke
				(width 0.1)
				(type default)
			)
			(layer "F.Fab")
		)
		(fp_line
			(start 0.67945 -0.3048)
			(end 0.67945 0.3048)
			(stroke
				(width 0.1)
				(type default)
			)
			(layer "F.Fab")
		)
		(fp_line
			(start 0.12065 -0.3048)
			(end 0.67945 -0.3048)
			(stroke
				(width 0.1)
				(type default)
			)
			(layer "F.Fab")
		)
		(fp_line
			(start 0.12065 -0.2794)
			(end 0.12065 -0.3048)
			(stroke
				(width 0.1)
				(type default)
			)
			(layer "F.Fab")
		)
		(fp_line
			(start -0.12065 -0.2794)
			(end 0.12065 -0.2794)
			(stroke
				(width 0.1)
				(type default)
			)
			(layer "F.Fab")
		)
		(fp_line
			(start 0.120396 0.2794)
			(end -0.12065 0.2794)
			(stroke
				(width 0.1)
				(type default)
			)
			(layer "F.Fab")
		)
		(fp_line
			(start -0.12065 0.2794)
			(end -0.12065 0.3048)
			(stroke
				(width 0.1)
				(type default)
			)
			(layer "F.Fab")
		)
		(fp_line
			(start 0.67945 0.3048)
			(end 0.120396 0.3048)
			(stroke
				(width 0.1)
				(type default)
			)
			(layer "F.Fab")
		)
		(fp_line
			(start 0.120396 0.3048)
			(end 0.120396 0.2794)
			(stroke
				(width 0.1)
				(type default)
			)
			(layer "F.Fab")
		)
		(fp_line
			(start -0.12065 0.3048)
			(end -0.67945 0.3048)
			(stroke
				(width 0.1)
				(type default)
			)
			(layer "F.Fab")
		)
		(fp_line
			(start -0.67945 0.3048)
			(end -0.67945 -0.305054)
			(stroke
				(width 0.1)
				(type default)
			)
			(layer "F.Fab")
		)
		(pad "1" smd circle
			(at -0.40005 0 90)
			(size 0 0)
			(layers "F.Cu" "F.Mask" "F.Paste")
			(net "SMB_LM75_2_3V3AUX_SDA")
		)
		(pad "2" smd circle
			(at 0.40005 0 90)
			(size 0 0)
			(layers "F.Cu" "F.Mask" "F.Paste")
			(net "SMB_LM75_2_3V3AUX_SDA_R1")
		)
	)
	(footprint ""
		(layer "F.Cu")
		(at 351.666048 -339.93455)
		(property "Reference" "PU11"
			(at -1.527048 -8.01878 0)
			(unlocked yes)
			(layer "F.SilkS")
			(effects
				(font
					(size 0.7874 0.5842)
					(thickness 0.1524)
				)
				(justify left)
			)
		)
		(property "Value" ""
			(at 0 0 0)
			(layer "F.Fab")
			(effects
				(font
					(size 1.27 1.27)
				)
			)
		)
		(duplicate_pad_numbers_are_jumpers no)
		(fp_line
			(start -2.500122 -2.999994)
			(end -2.24409 -2.999994)
			(stroke
				(width 0.1524)
				(type default)
			)
			(layer "F.SilkS")
		)
		(fp_line
			(start -2.500122 -2.529078)
			(end -2.500122 -2.999994)
			(stroke
				(width 0.1524)
				(type default)
			)
			(layer "F.SilkS")
		)
		(fp_line
			(start -2.500122 0.6604)
			(end -2.500122 0.229108)
			(stroke
				(width 0.1524)
				(type default)
			)
			(layer "F.SilkS")
		)
		(fp_line
			(start -2.500122 2.999994)
			(end -2.500122 2.339594)
			(stroke
				(width 0.1524)
				(type default)
			)
			(layer "F.SilkS")
		)
		(fp_line
			(start -2.2987 2.999994)
			(end -2.500122 2.999994)
			(stroke
				(width 0.1524)
				(type default)
			)
			(layer "F.SilkS")
		)
		(fp_line
			(start 2.31394 -2.999994)
			(end 2.500122 -2.999994)
			(stroke
				(width 0.1524)
				(type default)
			)
			(layer "F.SilkS")
		)
		(fp_line
			(start 2.500122 -2.999994)
			(end 2.500122 -2.44348)
			(stroke
				(width 0.1524)
				(type default)
			)
			(layer "F.SilkS")
		)
		(fp_line
			(start 2.500122 2.339594)
			(end 2.500122 2.999994)
			(stroke
				(width 0.1524)
				(type default)
			)
			(layer "F.SilkS")
		)
		(fp_line
			(start 2.500122 2.999994)
			(end 2.2987 2.999994)
			(stroke
				(width 0.1524)
				(type default)
			)
			(layer "F.SilkS")
		)
		(fp_poly
			(pts
				(xy -2.765298 -2.448814) (xy -3.438906 -2.67335) (xy -2.989834 -3.122422)
			)
			(stroke
				(width 0)
				(type default)
			)
			(fill yes)
			(layer "F.SilkS")
		)
		(fp_line
			(start -2.500122 -2.999994)
			(end 2.500122 -2.999994)
			(stroke
				(width 0.1)
				(type default)
			)
			(layer "F.Fab")
		)
		(fp_line
			(start -2.500122 2.999994)
			(end -2.500122 -2.999994)
			(stroke
				(width 0.1)
				(type default)
			)
			(layer "F.Fab")
		)
		(fp_line
			(start 2.500122 -2.999994)
			(end 2.500122 2.999994)
			(stroke
				(width 0.1)
				(type default)
			)
			(layer "F.Fab")
		)
		(fp_line
			(start 2.500122 2.999994)
			(end -2.500122 2.999994)
			(stroke
				(width 0.1)
				(type default)
			)
			(layer "F.Fab")
		)
		(fp_poly
			(pts
				(xy -4.218432 -2.783078) (xy -4.218432 -1.767078) (xy -3.202432 -2.275078)
			)
			(stroke
				(width 0)
				(type default)
			)
			(fill yes)
			(layer "F.Fab")
		)
		(pad "1" smd rect
			(at -2.400046 -2.275078 90)
			(size 0.2286 0.6096)
			(layers "F.Cu" "F.Mask" "F.Paste")
			(net "PVDDCR_CPU1_P0_VOS6")
		)
		(pad "2" smd rect
			(at -2.400046 -1.82499 90)
			(size 0.2286 0.6096)
			(layers "F.Cu" "F.Mask" "F.Paste")
			(net "GND")
		)
		(pad "3" smd rect
			(at -2.400046 -1.374902 90)
			(size 0.2286 0.6096)
			(layers "F.Cu" "F.Mask" "F.Paste")
			(net "PVDDCR_CPU1_P0_VCC6")
		)
		(pad "4" smd rect
			(at -2.400046 -0.925068 90)
			(size 0.2286 0.6096)
			(layers "F.Cu" "F.Mask" "F.Paste")
			(net "PVDDCR_CPU1_P0_PVCC")
		)
		(pad "5" smd rect
			(at -2.400046 -0.47498 90)
			(size 0.2286 0.6096)
			(layers "F.Cu" "F.Mask" "F.Paste")
			(net "GND")
		)
		(pad "6" smd rect
			(at -2.400046 -0.024892 90)
			(size 0.2286 0.6096)
			(layers "F.Cu" "F.Mask" "F.Paste")
			(net "NC_PVDDCR_CPU1_P0_GL1_6")
		)
		(pad "7_9-20_24" smd circle
			(at 0 1.150112 90)
			(size 0 0)
			(layers "F.Cu" "F.Mask" "F.Paste")
			(net "GND")
		)
		(pad "10_19" smd rect
			(at 0 2.899918 90)
			(size 0.6096 4.318)
			(layers "F.Cu" "F.Mask" "F.Paste")
			(net "SW_PVDDCR_CPU1_P0_SW6")
		)
		(pad "25_29" smd rect
			(at 1.549908 -1.279906 270)
			(size 2.0574 2.3114)
			(layers "F.Cu" "F.Mask" "F.Paste")
			(net "SW_P12V_AUX_PVDDCR_CPU1_P0_FLT")
		)
		(pad "30" smd rect
			(at 2.05994 -2.899918)
			(size 0.2286 0.6096)
			(layers "F.Cu" "F.Mask" "F.Paste")
			(net "SW_P12V_AUX_PVDDCR_CPU1_P0_FLT")
		)
		(pad "31" smd rect
			(at 1.610106 -2.899918)
			(size 0.2286 0.6096)
			(layers "F.Cu" "F.Mask" "F.Paste")
			(net "NC_PVDDCR_CPU1_P0_DNC6")
		)
		(pad "32" smd rect
			(at 1.160018 -2.899918)
			(size 0.2286 0.6096)
			(layers "F.Cu" "F.Mask" "F.Paste")
			(net "SW_PVDDCR_CPU1_P0_BOOTR6")
		)
		(pad "33" smd rect
			(at 0.70993 -2.899918)
			(size 0.2286 0.6096)
			(layers "F.Cu" "F.Mask" "F.Paste")
			(net "SW_PVDDCR_CPU1_P0_BOOT6")
		)
		(pad "34" smd rect
			(at 0.260096 -2.899918)
			(size 0.2286 0.6096)
			(layers "F.Cu" "F.Mask" "F.Paste")
			(net "PVDDCR_CPU1_P0_PWM6")
		)
		(pad "35" smd rect
			(at -0.189992 -2.899918)
			(size 0.2286 0.6096)
			(layers "F.Cu" "F.Mask" "F.Paste")
			(net "PVDDCR_CPU1_P0_VCC6")
		)
		(pad "36" smd rect
			(at -0.64008 -2.899918)
			(size 0.2286 0.6096)
			(layers "F.Cu" "F.Mask" "F.Paste")
			(net "PVDDCR_CPU1_P0_TEMP0")
		)
		(pad "37" smd rect
			(at -1.089914 -2.899918)
			(size 0.2286 0.6096)
			(layers "F.Cu" "F.Mask" "F.Paste")
			(net "PVDDCR_CPU1_P0_LSET6")
		)
		(pad "38" smd rect
			(at -1.540002 -2.899918)
			(size 0.2286 0.6096)
			(layers "F.Cu" "F.Mask" "F.Paste")
			(net "PVDDCR_CPU1_P0_IMON6")
		)
		(pad "39" smd rect
			(at -1.99009 -2.899918)
			(size 0.2286 0.6096)
			(layers "F.Cu" "F.Mask" "F.Paste")
			(net "PVDDCR_CPU1_P0_VCCS")
		)
		(pad "40" smd rect
			(at -0.87503 -1.27508)
			(size 1.7526 1.9558)
			(layers "F.Cu" "F.Mask" "F.Paste")
			(net "GND")
		)
		(pad "41" smd rect
			(at -1.525016 0.249936 270)
			(size 0.3048 0.4572)
			(layers "F.Cu" "F.Mask" "F.Paste")
			(net "NC_PVDDCR_CPU1_P0_GL2_6")
		)
		(zone
			(layer "F.Cu")
			(hatch none 0.5)
			(connect_pads
				(clearance 0)
			)
			(min_thickness 0.25)
			(keepout
				(tracks not_allowed)
				(vias allowed)
				(pads allowed)
				(copperpour not_allowed)
				(footprints allowed)
			)
			(placement
				(enabled no)
				(sheetname "")
			)
			(fill
				(thermal_gap 0.5)
				(thermal_bridge_width 0.5)
				(island_removal_mode 0)
			)
			(polygon
				(pts
					(xy 349.165926 -337.354164) (xy 349.165926 -337.683856) (xy 354.16617 -337.683856) (xy 354.16617 -337.357212)
					(xy 353.875848 -337.357212) (xy 353.875848 -337.390232) (xy 349.456248 -337.390232) (xy 349.456248 -337.354164)
				)
			)
		)
		(zone
			(layer "F.Cu")
			(hatch none 0.5)
			(connect_pads
				(clearance 0)
			)
			(min_thickness 0.25)
			(keepout
				(tracks not_allowed)
				(vias allowed)
				(pads allowed)
				(copperpour not_allowed)
				(footprints allowed)
			)
			(placement
				(enabled no)
				(sheetname "")
			)
			(fill
				(thermal_gap 0.5)
				(thermal_bridge_width 0.5)
				(island_removal_mode 0)
			)
			(polygon
				(pts
					(xy 351.718118 -340.2203) (xy 351.718118 -342.23833) (xy 349.863918 -342.23833) (xy 349.863918 -341.997284)
					(xy 349.621602 -341.997284) (xy 349.621602 -342.478868) (xy 353.40671 -342.478868) (xy 353.40671 -342.293956)
					(xy 352.009456 -342.293956) (xy 352.009456 -340.134956) (xy 354.16617 -340.134956) (xy 354.16617 -339.885274)
					(xy 352.053144 -339.885274)
				)
			)
		)
	)
	(footprint ""
		(layer "F.Cu")
		(at 36.919662 -427.377098)
		(property "Reference" "C1864"
			(at 0 0 0)
			(layer "F.SilkS")
			(hide yes)
			(effects
				(font
					(size 1.27 1.27)
				)
			)
		)
		(property "Value" ""
			(at 0 0 0)
			(layer "F.Fab")
			(effects
				(font
					(size 1.27 1.27)
				)
			)
		)
		(duplicate_pad_numbers_are_jumpers no)
		(fp_line
			(start -0.7874 -0.4064)
			(end 0.7874 -0.4064)
			(stroke
				(width 0.1524)
				(type default)
			)
			(layer "F.SilkS")
		)
		(fp_line
			(start -0.7874 0.4064)
			(end -0.7874 -0.4064)
			(stroke
				(width 0.1524)
				(type default)
			)
			(layer "F.SilkS")
		)
		(fp_line
			(start 0.7874 -0.4064)
			(end 0.7874 0.4064)
			(stroke
				(width 0.1524)
				(type default)
			)
			(layer "F.SilkS")
		)
		(fp_line
			(start 0.7874 0.4064)
			(end -0.7874 0.4064)
			(stroke
				(width 0.1524)
				(type default)
			)
			(layer "F.SilkS")
		)
		(fp_line
			(start -0.67945 -0.305054)
			(end -0.12065 -0.305054)
			(stroke
				(width 0.1)
				(type default)
			)
			(layer "F.Fab")
		)
		(fp_line
			(start -0.67945 0.3048)
			(end -0.67945 -0.305054)
			(stroke
				(width 0.1)
				(type default)
			)
			(layer "F.Fab")
		)
		(fp_line
			(start -0.12065 -0.305054)
			(end -0.12065 -0.2794)
			(stroke
				(width 0.1)
				(type default)
			)
			(layer "F.Fab")
		)
		(fp_line
			(start -0.12065 -0.2794)
			(end 0.12065 -0.2794)
			(stroke
				(width 0.1)
				(type default)
			)
			(layer "F.Fab")
		)
		(fp_line
			(start -0.12065 0.2794)
			(end -0.12065 0.3048)
			(stroke
				(width 0.1)
				(type default)
			)
			(layer "F.Fab")
		)
		(fp_line
			(start -0.12065 0.3048)
			(end -0.67945 0.3048)
			(stroke
				(width 0.1)
				(type default)
			)
			(layer "F.Fab")
		)
		(fp_line
			(start 0.120396 0.2794)
			(end -0.12065 0.2794)
			(stroke
				(width 0.1)
				(type default)
			)
			(layer "F.Fab")
		)
		(fp_line
			(start 0.120396 0.3048)
			(end 0.120396 0.2794)
			(stroke
				(width 0.1)
				(type default)
			)
			(layer "F.Fab")
		)
		(fp_line
			(start 0.12065 -0.3048)
			(end 0.67945 -0.3048)
			(stroke
				(width 0.1)
				(type default)
			)
			(layer "F.Fab")
		)
		(fp_line
			(start 0.12065 -0.2794)
			(end 0.12065 -0.3048)
			(stroke
				(width 0.1)
				(type default)
			)
			(layer "F.Fab")
		)
		(fp_line
			(start 0.67945 -0.3048)
			(end 0.67945 0.3048)
			(stroke
				(width 0.1)
				(type default)
			)
			(layer "F.Fab")
		)
		(fp_line
			(start 0.67945 0.3048)
			(end 0.120396 0.3048)
			(stroke
				(width 0.1)
				(type default)
			)
			(layer "F.Fab")
		)
		(pad "1" smd circle
			(at -0.40005 0)
			(size 0 0)
			(layers "F.Cu" "F.Mask" "F.Paste")
			(net "P3V3_AUX")
		)
		(pad "2" smd circle
			(at 0.40005 0)
			(size 0 0)
			(layers "F.Cu" "F.Mask" "F.Paste")
			(net "GND")
		)
	)
	(footprint ""
		(layer "F.Cu")
		(at 367.996978 -177.773076 90)
		(property "Reference" "PC477_C0P0_1"
			(at 0 0 90)
			(layer "F.SilkS")
			(hide yes)
			(effects
				(font
					(size 1.27 1.27)
				)
			)
		)
		(property "Value" ""
			(at 0 0 90)
			(layer "F.Fab")
			(effects
				(font
					(size 1.27 1.27)
				)
			)
		)
		(duplicate_pad_numbers_are_jumpers no)
		(fp_line
			(start 0.7874 -0.4064)
			(end 0.7874 0.4064)
			(stroke
				(width 0.1524)
				(type default)
			)
			(layer "F.SilkS")
		)
		(fp_line
			(start -0.7874 -0.4064)
			(end 0.7874 -0.4064)
			(stroke
				(width 0.1524)
				(type default)
			)
			(layer "F.SilkS")
		)
		(fp_line
			(start 0.7874 0.4064)
			(end -0.7874 0.4064)
			(stroke
				(width 0.1524)
				(type default)
			)
			(layer "F.SilkS")
		)
		(fp_line
			(start -0.7874 0.4064)
			(end -0.7874 -0.4064)
			(stroke
				(width 0.1524)
				(type default)
			)
			(layer "F.SilkS")
		)
		(fp_line
			(start -0.12065 -0.305054)
			(end -0.12065 -0.2794)
			(stroke
				(width 0.1)
				(type default)
			)
			(layer "F.Fab")
		)
		(fp_line
			(start -0.67945 -0.305054)
			(end -0.12065 -0.305054)
			(stroke
				(width 0.1)
				(type default)
			)
			(layer "F.Fab")
		)
		(fp_line
			(start 0.67945 -0.3048)
			(end 0.67945 0.3048)
			(stroke
				(width 0.1)
				(type default)
			)
			(layer "F.Fab")
		)
		(fp_line
			(start 0.12065 -0.3048)
			(end 0.67945 -0.3048)
			(stroke
				(width 0.1)
				(type default)
			)
			(layer "F.Fab")
		)
		(fp_line
			(start 0.12065 -0.2794)
			(end 0.12065 -0.3048)
			(stroke
				(width 0.1)
				(type default)
			)
			(layer "F.Fab")
		)
		(fp_line
			(start -0.12065 -0.2794)
			(end 0.12065 -0.2794)
			(stroke
				(width 0.1)
				(type default)
			)
			(layer "F.Fab")
		)
		(fp_line
			(start 0.120396 0.2794)
			(end -0.12065 0.2794)
			(stroke
				(width 0.1)
				(type default)
			)
			(layer "F.Fab")
		)
		(fp_line
			(start -0.12065 0.2794)
			(end -0.12065 0.3048)
			(stroke
				(width 0.1)
				(type default)
			)
			(layer "F.Fab")
		)
		(fp_line
			(start 0.67945 0.3048)
			(end 0.120396 0.3048)
			(stroke
				(width 0.1)
				(type default)
			)
			(layer "F.Fab")
		)
		(fp_line
			(start 0.120396 0.3048)
			(end 0.120396 0.2794)
			(stroke
				(width 0.1)
				(type default)
			)
			(layer "F.Fab")
		)
		(fp_line
			(start -0.12065 0.3048)
			(end -0.67945 0.3048)
			(stroke
				(width 0.1)
				(type default)
			)
			(layer "F.Fab")
		)
		(fp_line
			(start -0.67945 0.3048)
			(end -0.67945 -0.305054)
			(stroke
				(width 0.1)
				(type default)
			)
			(layer "F.Fab")
		)
		(pad "1" smd circle
			(at -0.40005 0 90)
			(size 0 0)
			(layers "F.Cu" "F.Mask" "F.Paste")
			(net "PVDDCR_CPU0_P0_PVCC")
		)
		(pad "2" smd circle
			(at 0.40005 0 90)
			(size 0 0)
			(layers "F.Cu" "F.Mask" "F.Paste")
			(net "GND")
		)
	)
	(footprint ""
		(layer "F.Cu")
		(at 184.023 -129.377948 -90)
		(property "Reference" "R215"
			(at 0 0 270)
			(layer "F.SilkS")
			(hide yes)
			(effects
				(font
					(size 1.27 1.27)
				)
			)
		)
		(property "Value" ""
			(at 0 0 270)
			(layer "F.Fab")
			(effects
				(font
					(size 1.27 1.27)
				)
			)
		)
		(duplicate_pad_numbers_are_jumpers no)
		(fp_line
			(start -0.7874 0.4064)
			(end -0.7874 -0.4064)
			(stroke
				(width 0.1524)
				(type default)
			)
			(layer "F.SilkS")
		)
		(fp_line
			(start 0.7874 0.4064)
			(end -0.7874 0.4064)
			(stroke
				(width 0.1524)
				(type default)
			)
			(layer "F.SilkS")
		)
		(fp_line
			(start -0.7874 -0.4064)
			(end 0.7874 -0.4064)
			(stroke
				(width 0.1524)
				(type default)
			)
			(layer "F.SilkS")
		)
		(fp_line
			(start 0.7874 -0.4064)
			(end 0.7874 0.4064)
			(stroke
				(width 0.1524)
				(type default)
			)
			(layer "F.SilkS")
		)
		(fp_line
			(start -0.67945 0.3048)
			(end -0.67945 -0.305054)
			(stroke
				(width 0.1)
				(type default)
			)
			(layer "F.Fab")
		)
		(fp_line
			(start -0.12065 0.3048)
			(end -0.67945 0.3048)
			(stroke
				(width 0.1)
				(type default)
			)
			(layer "F.Fab")
		)
		(fp_line
			(start 0.120396 0.3048)
			(end 0.120396 0.2794)
			(stroke
				(width 0.1)
				(type default)
			)
			(layer "F.Fab")
		)
		(fp_line
			(start 0.67945 0.3048)
			(end 0.120396 0.3048)
			(stroke
				(width 0.1)
				(type default)
			)
			(layer "F.Fab")
		)
		(fp_line
			(start -0.12065 0.2794)
			(end -0.12065 0.3048)
			(stroke
				(width 0.1)
				(type default)
			)
			(layer "F.Fab")
		)
		(fp_line
			(start 0.120396 0.2794)
			(end -0.12065 0.2794)
			(stroke
				(width 0.1)
				(type default)
			)
			(layer "F.Fab")
		)
		(fp_line
			(start -0.12065 -0.2794)
			(end 0.12065 -0.2794)
			(stroke
				(width 0.1)
				(type default)
			)
			(layer "F.Fab")
		)
		(fp_line
			(start 0.12065 -0.2794)
			(end 0.12065 -0.3048)
			(stroke
				(width 0.1)
				(type default)
			)
			(layer "F.Fab")
		)
		(fp_line
			(start 0.12065 -0.3048)
			(end 0.67945 -0.3048)
			(stroke
				(width 0.1)
				(type default)
			)
			(layer "F.Fab")
		)
		(fp_line
			(start 0.67945 -0.3048)
			(end 0.67945 0.3048)
			(stroke
				(width 0.1)
				(type default)
			)
			(layer "F.Fab")
		)
		(fp_line
			(start -0.67945 -0.305054)
			(end -0.12065 -0.305054)
			(stroke
				(width 0.1)
				(type default)
			)
			(layer "F.Fab")
		)
		(fp_line
			(start -0.12065 -0.305054)
			(end -0.12065 -0.2794)
			(stroke
				(width 0.1)
				(type default)
			)
			(layer "F.Fab")
		)
		(pad "1" smd circle
			(at -0.40005 0 270)
			(size 0 0)
			(layers "F.Cu" "F.Mask" "F.Paste")
			(net "CPU0_PWR_BTN_N")
		)
		(pad "2" smd circle
			(at 0.40005 0 270)
			(size 0 0)
			(layers "F.Cu" "F.Mask" "F.Paste")
			(net "FM_CPU0_PWR_BTN_N")
		)
	)
	(footprint ""
		(layer "F.Cu")
		(at 152.329642 -73.589134 180)
		(property "Reference" "PC6021"
			(at 0 0 180)
			(layer "F.SilkS")
			(hide yes)
			(effects
				(font
					(size 1.27 1.27)
				)
			)
		)
		(property "Value" ""
			(at 0 0 180)
			(layer "F.Fab")
			(effects
				(font
					(size 1.27 1.27)
				)
			)
		)
		(duplicate_pad_numbers_are_jumpers no)
		(fp_line
			(start 0.7874 0.4064)
			(end -0.7874 0.4064)
			(stroke
				(width 0.1524)
				(type default)
			)
			(layer "F.SilkS")
		)
		(fp_line
			(start 0.7874 -0.4064)
			(end 0.7874 0.4064)
			(stroke
				(width 0.1524)
				(type default)
			)
			(layer "F.SilkS")
		)
		(fp_line
			(start -0.7874 0.4064)
			(end -0.7874 -0.4064)
			(stroke
				(width 0.1524)
				(type default)
			)
			(layer "F.SilkS")
		)
		(fp_line
			(start -0.7874 -0.4064)
			(end 0.7874 -0.4064)
			(stroke
				(width 0.1524)
				(type default)
			)
			(layer "F.SilkS")
		)
		(fp_line
			(start 0.67945 0.3048)
			(end 0.120396 0.3048)
			(stroke
				(width 0.1)
				(type default)
			)
			(layer "F.Fab")
		)
		(fp_line
			(start 0.67945 -0.3048)
			(end 0.67945 0.3048)
			(stroke
				(width 0.1)
				(type default)
			)
			(layer "F.Fab")
		)
		(fp_line
			(start 0.12065 -0.2794)
			(end 0.12065 -0.3048)
			(stroke
				(width 0.1)
				(type default)
			)
			(layer "F.Fab")
		)
		(fp_line
			(start 0.12065 -0.3048)
			(end 0.67945 -0.3048)
			(stroke
				(width 0.1)
				(type default)
			)
			(layer "F.Fab")
		)
		(fp_line
			(start 0.120396 0.3048)
			(end 0.120396 0.2794)
			(stroke
				(width 0.1)
				(type default)
			)
			(layer "F.Fab")
		)
		(fp_line
			(start 0.120396 0.2794)
			(end -0.12065 0.2794)
			(stroke
				(width 0.1)
				(type default)
			)
			(layer "F.Fab")
		)
		(fp_line
			(start -0.12065 0.3048)
			(end -0.67945 0.3048)
			(stroke
				(width 0.1)
				(type default)
			)
			(layer "F.Fab")
		)
		(fp_line
			(start -0.12065 0.2794)
			(end -0.12065 0.3048)
			(stroke
				(width 0.1)
				(type default)
			)
			(layer "F.Fab")
		)
		(fp_line
			(start -0.12065 -0.2794)
			(end 0.12065 -0.2794)
			(stroke
				(width 0.1)
				(type default)
			)
			(layer "F.Fab")
		)
		(fp_line
			(start -0.12065 -0.305054)
			(end -0.12065 -0.2794)
			(stroke
				(width 0.1)
				(type default)
			)
			(layer "F.Fab")
		)
		(fp_line
			(start -0.67945 0.3048)
			(end -0.67945 -0.305054)
			(stroke
				(width 0.1)
				(type default)
			)
			(layer "F.Fab")
		)
		(fp_line
			(start -0.67945 -0.305054)
			(end -0.12065 -0.305054)
			(stroke
				(width 0.1)
				(type default)
			)
			(layer "F.Fab")
		)
		(pad "1" smd circle
			(at -0.40005 0 180)
			(size 0 0)
			(layers "F.Cu" "F.Mask" "F.Paste")
			(net "P1V8_AUX")
		)
		(pad "2" smd circle
			(at 0.40005 0 180)
			(size 0 0)
			(layers "F.Cu" "F.Mask" "F.Paste")
			(net "GND")
		)
	)
	(footprint ""
		(layer "F.Cu")
		(at 463.462624 -98.564954 180)
		(property "Reference" "R1289"
			(at 0 0 180)
			(layer "F.SilkS")
			(hide yes)
			(effects
				(font
					(size 1.27 1.27)
				)
			)
		)
		(property "Value" ""
			(at 0 0 180)
			(layer "F.Fab")
			(effects
				(font
					(size 1.27 1.27)
				)
			)
		)
		(duplicate_pad_numbers_are_jumpers no)
		(fp_line
			(start 0.7874 0.4064)
			(end -0.7874 0.4064)
			(stroke
				(width 0.1524)
				(type default)
			)
			(layer "F.SilkS")
		)
		(fp_line
			(start 0.7874 -0.4064)
			(end 0.7874 0.4064)
			(stroke
				(width 0.1524)
				(type default)
			)
			(layer "F.SilkS")
		)
		(fp_line
			(start -0.7874 0.4064)
			(end -0.7874 -0.4064)
			(stroke
				(width 0.1524)
				(type default)
			)
			(layer "F.SilkS")
		)
		(fp_line
			(start -0.7874 -0.4064)
			(end 0.7874 -0.4064)
			(stroke
				(width 0.1524)
				(type default)
			)
			(layer "F.SilkS")
		)
		(fp_line
			(start 0.67945 0.3048)
			(end 0.120396 0.3048)
			(stroke
				(width 0.1)
				(type default)
			)
			(layer "F.Fab")
		)
		(fp_line
			(start 0.67945 -0.3048)
			(end 0.67945 0.3048)
			(stroke
				(width 0.1)
				(type default)
			)
			(layer "F.Fab")
		)
		(fp_line
			(start 0.12065 -0.2794)
			(end 0.12065 -0.3048)
			(stroke
				(width 0.1)
				(type default)
			)
			(layer "F.Fab")
		)
		(fp_line
			(start 0.12065 -0.3048)
			(end 0.67945 -0.3048)
			(stroke
				(width 0.1)
				(type default)
			)
			(layer "F.Fab")
		)
		(fp_line
			(start 0.120396 0.3048)
			(end 0.120396 0.2794)
			(stroke
				(width 0.1)
				(type default)
			)
			(layer "F.Fab")
		)
		(fp_line
			(start 0.120396 0.2794)
			(end -0.12065 0.2794)
			(stroke
				(width 0.1)
				(type default)
			)
			(layer "F.Fab")
		)
		(fp_line
			(start -0.12065 0.3048)
			(end -0.67945 0.3048)
			(stroke
				(width 0.1)
				(type default)
			)
			(layer "F.Fab")
		)
		(fp_line
			(start -0.12065 0.2794)
			(end -0.12065 0.3048)
			(stroke
				(width 0.1)
				(type default)
			)
			(layer "F.Fab")
		)
		(fp_line
			(start -0.12065 -0.2794)
			(end 0.12065 -0.2794)
			(stroke
				(width 0.1)
				(type default)
			)
			(layer "F.Fab")
		)
		(fp_line
			(start -0.12065 -0.305054)
			(end -0.12065 -0.2794)
			(stroke
				(width 0.1)
				(type default)
			)
			(layer "F.Fab")
		)
		(fp_line
			(start -0.67945 0.3048)
			(end -0.67945 -0.305054)
			(stroke
				(width 0.1)
				(type default)
			)
			(layer "F.Fab")
		)
		(fp_line
			(start -0.67945 -0.305054)
			(end -0.12065 -0.305054)
			(stroke
				(width 0.1)
				(type default)
			)
			(layer "F.Fab")
		)
		(pad "1" smd circle
			(at -0.40005 0 180)
			(size 0 0)
			(layers "F.Cu" "F.Mask" "F.Paste")
			(net "FB_BMC_ISOLATE")
		)
		(pad "2" smd circle
			(at 0.40005 0 180)
			(size 0 0)
			(layers "F.Cu" "F.Mask" "F.Paste")
			(net "GND")
		)
	)
	(footprint ""
		(layer "F.Cu")
		(at 370.905278 -143.504158)
		(property "Reference" "C5018"
			(at 0 0 0)
			(layer "F.SilkS")
			(hide yes)
			(effects
				(font
					(size 1.27 1.27)
				)
			)
		)
		(property "Value" ""
			(at 0 0 0)
			(layer "F.Fab")
			(effects
				(font
					(size 1.27 1.27)
				)
			)
		)
		(duplicate_pad_numbers_are_jumpers no)
		(fp_line
			(start -0.7874 -0.4064)
			(end 0.7874 -0.4064)
			(stroke
				(width 0.1524)
				(type default)
			)
			(layer "F.SilkS")
		)
		(fp_line
			(start -0.7874 0.4064)
			(end -0.7874 -0.4064)
			(stroke
				(width 0.1524)
				(type default)
			)
			(layer "F.SilkS")
		)
		(fp_line
			(start 0.7874 -0.4064)
			(end 0.7874 0.4064)
			(stroke
				(width 0.1524)
				(type default)
			)
			(layer "F.SilkS")
		)
		(fp_line
			(start 0.7874 0.4064)
			(end -0.7874 0.4064)
			(stroke
				(width 0.1524)
				(type default)
			)
			(layer "F.SilkS")
		)
		(fp_line
			(start -0.67945 -0.305054)
			(end -0.12065 -0.305054)
			(stroke
				(width 0.1)
				(type default)
			)
			(layer "F.Fab")
		)
		(fp_line
			(start -0.67945 0.3048)
			(end -0.67945 -0.305054)
			(stroke
				(width 0.1)
				(type default)
			)
			(layer "F.Fab")
		)
		(fp_line
			(start -0.12065 -0.305054)
			(end -0.12065 -0.2794)
			(stroke
				(width 0.1)
				(type default)
			)
			(layer "F.Fab")
		)
		(fp_line
			(start -0.12065 -0.2794)
			(end 0.12065 -0.2794)
			(stroke
				(width 0.1)
				(type default)
			)
			(layer "F.Fab")
		)
		(fp_line
			(start -0.12065 0.2794)
			(end -0.12065 0.3048)
			(stroke
				(width 0.1)
				(type default)
			)
			(layer "F.Fab")
		)
		(fp_line
			(start -0.12065 0.3048)
			(end -0.67945 0.3048)
			(stroke
				(width 0.1)
				(type default)
			)
			(layer "F.Fab")
		)
		(fp_line
			(start 0.120396 0.2794)
			(end -0.12065 0.2794)
			(stroke
				(width 0.1)
				(type default)
			)
			(layer "F.Fab")
		)
		(fp_line
			(start 0.120396 0.3048)
			(end 0.120396 0.2794)
			(stroke
				(width 0.1)
				(type default)
			)
			(layer "F.Fab")
		)
		(fp_line
			(start 0.12065 -0.3048)
			(end 0.67945 -0.3048)
			(stroke
				(width 0.1)
				(type default)
			)
			(layer "F.Fab")
		)
		(fp_line
			(start 0.12065 -0.2794)
			(end 0.12065 -0.3048)
			(stroke
				(width 0.1)
				(type default)
			)
			(layer "F.Fab")
		)
		(fp_line
			(start 0.67945 -0.3048)
			(end 0.67945 0.3048)
			(stroke
				(width 0.1)
				(type default)
			)
			(layer "F.Fab")
		)
		(fp_line
			(start 0.67945 0.3048)
			(end 0.120396 0.3048)
			(stroke
				(width 0.1)
				(type default)
			)
			(layer "F.Fab")
		)
		(pad "1" smd circle
			(at -0.40005 0)
			(size 0 0)
			(layers "F.Cu" "F.Mask" "F.Paste")
			(net "GND")
		)
		(pad "2" smd circle
			(at 0.40005 0)
			(size 0 0)
			(layers "F.Cu" "F.Mask" "F.Paste")
			(net "PWRGD_PVDDCR_SOC_P0")
		)
	)
	(footprint ""
		(layer "F.Cu")
		(at 365.835692 -261.255002 180)
		(property "Reference" "C2555"
			(at 0 0 180)
			(layer "F.SilkS")
			(hide yes)
			(effects
				(font
					(size 1.27 1.27)
				)
			)
		)
		(property "Value" ""
			(at 0 0 180)
			(layer "F.Fab")
			(effects
				(font
					(size 1.27 1.27)
				)
			)
		)
		(duplicate_pad_numbers_are_jumpers no)
		(fp_line
			(start 0.7874 0.4064)
			(end -0.7874 0.4064)
			(stroke
				(width 0.1524)
				(type default)
			)
			(layer "F.SilkS")
		)
		(fp_line
			(start 0.7874 -0.4064)
			(end 0.7874 0.4064)
			(stroke
				(width 0.1524)
				(type default)
			)
			(layer "F.SilkS")
		)
		(fp_line
			(start -0.7874 0.4064)
			(end -0.7874 -0.4064)
			(stroke
				(width 0.1524)
				(type default)
			)
			(layer "F.SilkS")
		)
		(fp_line
			(start -0.7874 -0.4064)
			(end 0.7874 -0.4064)
			(stroke
				(width 0.1524)
				(type default)
			)
			(layer "F.SilkS")
		)
		(fp_line
			(start 0.67945 0.3048)
			(end 0.120396 0.3048)
			(stroke
				(width 0.1)
				(type default)
			)
			(layer "F.Fab")
		)
		(fp_line
			(start 0.67945 -0.3048)
			(end 0.67945 0.3048)
			(stroke
				(width 0.1)
				(type default)
			)
			(layer "F.Fab")
		)
		(fp_line
			(start 0.12065 -0.2794)
			(end 0.12065 -0.3048)
			(stroke
				(width 0.1)
				(type default)
			)
			(layer "F.Fab")
		)
		(fp_line
			(start 0.12065 -0.3048)
			(end 0.67945 -0.3048)
			(stroke
				(width 0.1)
				(type default)
			)
			(layer "F.Fab")
		)
		(fp_line
			(start 0.120396 0.3048)
			(end 0.120396 0.2794)
			(stroke
				(width 0.1)
				(type default)
			)
			(layer "F.Fab")
		)
		(fp_line
			(start 0.120396 0.2794)
			(end -0.12065 0.2794)
			(stroke
				(width 0.1)
				(type default)
			)
			(layer "F.Fab")
		)
		(fp_line
			(start -0.12065 0.3048)
			(end -0.67945 0.3048)
			(stroke
				(width 0.1)
				(type default)
			)
			(layer "F.Fab")
		)
		(fp_line
			(start -0.12065 0.2794)
			(end -0.12065 0.3048)
			(stroke
				(width 0.1)
				(type default)
			)
			(layer "F.Fab")
		)
		(fp_line
			(start -0.12065 -0.2794)
			(end 0.12065 -0.2794)
			(stroke
				(width 0.1)
				(type default)
			)
			(layer "F.Fab")
		)
		(fp_line
			(start -0.12065 -0.305054)
			(end -0.12065 -0.2794)
			(stroke
				(width 0.1)
				(type default)
			)
			(layer "F.Fab")
		)
		(fp_line
			(start -0.67945 0.3048)
			(end -0.67945 -0.305054)
			(stroke
				(width 0.1)
				(type default)
			)
			(layer "F.Fab")
		)
		(fp_line
			(start -0.67945 -0.305054)
			(end -0.12065 -0.305054)
			(stroke
				(width 0.1)
				(type default)
			)
			(layer "F.Fab")
		)
		(pad "1" smd circle
			(at -0.40005 0 180)
			(size 0 0)
			(layers "F.Cu" "F.Mask" "F.Paste")
			(net "PVDDCR_SOC_P0")
		)
		(pad "2" smd circle
			(at 0.40005 0 180)
			(size 0 0)
			(layers "F.Cu" "F.Mask" "F.Paste")
			(net "GND")
		)
	)
	(footprint ""
		(layer "F.Cu")
		(at 100.457 -77.216)
		(property "Reference" "R1166"
			(at 0 0 0)
			(layer "F.SilkS")
			(hide yes)
			(effects
				(font
					(size 1.27 1.27)
				)
			)
		)
		(property "Value" ""
			(at 0 0 0)
			(layer "F.Fab")
			(effects
				(font
					(size 1.27 1.27)
				)
			)
		)
		(duplicate_pad_numbers_are_jumpers no)
		(fp_line
			(start -0.7874 -0.4064)
			(end 0.7874 -0.4064)
			(stroke
				(width 0.1524)
				(type default)
			)
			(layer "F.SilkS")
		)
		(fp_line
			(start -0.7874 0.4064)
			(end -0.7874 -0.4064)
			(stroke
				(width 0.1524)
				(type default)
			)
			(layer "F.SilkS")
		)
		(fp_line
			(start 0.7874 -0.4064)
			(end 0.7874 0.4064)
			(stroke
				(width 0.1524)
				(type default)
			)
			(layer "F.SilkS")
		)
		(fp_line
			(start 0.7874 0.4064)
			(end -0.7874 0.4064)
			(stroke
				(width 0.1524)
				(type default)
			)
			(layer "F.SilkS")
		)
		(fp_line
			(start -0.67945 -0.305054)
			(end -0.12065 -0.305054)
			(stroke
				(width 0.1)
				(type default)
			)
			(layer "F.Fab")
		)
		(fp_line
			(start -0.67945 0.3048)
			(end -0.67945 -0.305054)
			(stroke
				(width 0.1)
				(type default)
			)
			(layer "F.Fab")
		)
		(fp_line
			(start -0.12065 -0.305054)
			(end -0.12065 -0.2794)
			(stroke
				(width 0.1)
				(type default)
			)
			(layer "F.Fab")
		)
		(fp_line
			(start -0.12065 -0.2794)
			(end 0.12065 -0.2794)
			(stroke
				(width 0.1)
				(type default)
			)
			(layer "F.Fab")
		)
		(fp_line
			(start -0.12065 0.2794)
			(end -0.12065 0.3048)
			(stroke
				(width 0.1)
				(type default)
			)
			(layer "F.Fab")
		)
		(fp_line
			(start -0.12065 0.3048)
			(end -0.67945 0.3048)
			(stroke
				(width 0.1)
				(type default)
			)
			(layer "F.Fab")
		)
		(fp_line
			(start 0.120396 0.2794)
			(end -0.12065 0.2794)
			(stroke
				(width 0.1)
				(type default)
			)
			(layer "F.Fab")
		)
		(fp_line
			(start 0.120396 0.3048)
			(end 0.120396 0.2794)
			(stroke
				(width 0.1)
				(type default)
			)
			(layer "F.Fab")
		)
		(fp_line
			(start 0.12065 -0.3048)
			(end 0.67945 -0.3048)
			(stroke
				(width 0.1)
				(type default)
			)
			(layer "F.Fab")
		)
		(fp_line
			(start 0.12065 -0.2794)
			(end 0.12065 -0.3048)
			(stroke
				(width 0.1)
				(type default)
			)
			(layer "F.Fab")
		)
		(fp_line
			(start 0.67945 -0.3048)
			(end 0.67945 0.3048)
			(stroke
				(width 0.1)
				(type default)
			)
			(layer "F.Fab")
		)
		(fp_line
			(start 0.67945 0.3048)
			(end 0.120396 0.3048)
			(stroke
				(width 0.1)
				(type default)
			)
			(layer "F.Fab")
		)
		(pad "1" smd circle
			(at -0.40005 0)
			(size 0 0)
			(layers "F.Cu" "F.Mask" "F.Paste")
			(net "P12V_OCP_V3_2_PLD_R_PWRGD")
		)
		(pad "2" smd circle
			(at 0.40005 0)
			(size 0 0)
			(layers "F.Cu" "F.Mask" "F.Paste")
			(net "P12V_OCP_V3_2_PLD_PWRGD")
		)
	)
	(footprint ""
		(layer "F.Cu")
		(at 125.405896 -370.57203 -90)
		(property "Reference" "C1529"
			(at 0 0 270)
			(layer "F.SilkS")
			(hide yes)
			(effects
				(font
					(size 1.27 1.27)
				)
			)
		)
		(property "Value" ""
			(at 0 0 270)
			(layer "F.Fab")
			(effects
				(font
					(size 1.27 1.27)
				)
			)
		)
		(duplicate_pad_numbers_are_jumpers no)
		(fp_line
			(start -0.299974 0.150114)
			(end -0.299974 -0.150114)
			(stroke
				(width 0.1)
				(type default)
			)
			(layer "F.Fab")
		)
		(fp_line
			(start 0.299974 0.150114)
			(end -0.299974 0.150114)
			(stroke
				(width 0.1)
				(type default)
			)
			(layer "F.Fab")
		)
		(fp_line
			(start -0.299974 -0.150114)
			(end 0.299974 -0.150114)
			(stroke
				(width 0.1)
				(type default)
			)
			(layer "F.Fab")
		)
		(fp_line
			(start 0.299974 -0.150114)
			(end 0.299974 0.150114)
			(stroke
				(width 0.1)
				(type default)
			)
			(layer "F.Fab")
		)
		(pad "1" smd rect
			(at -0.2667 0 270)
			(size 0.3048 0.381)
			(layers "F.Cu" "F.Mask" "F.Paste")
			(net "P5E_CPU1_P3_TX_C_DP<9>")
		)
		(pad "2" smd rect
			(at 0.2667 0 270)
			(size 0.3048 0.381)
			(layers "F.Cu" "F.Mask" "F.Paste")
			(net "P5E_CPU1_P3_TX_DP<9>")
		)
	)
	(footprint ""
		(layer "F.Cu")
		(at 165.576758 -352.27006 90)
		(property "Reference" "PR393"
			(at 0 0 90)
			(layer "F.SilkS")
			(hide yes)
			(effects
				(font
					(size 1.27 1.27)
				)
			)
		)
		(property "Value" ""
			(at 0 0 90)
			(layer "F.Fab")
			(effects
				(font
					(size 1.27 1.27)
				)
			)
		)
		(duplicate_pad_numbers_are_jumpers no)
		(fp_line
			(start 0.7874 -0.4064)
			(end 0.7874 0.4064)
			(stroke
				(width 0.1524)
				(type default)
			)
			(layer "F.SilkS")
		)
		(fp_line
			(start -0.7874 -0.4064)
			(end 0.7874 -0.4064)
			(stroke
				(width 0.1524)
				(type default)
			)
			(layer "F.SilkS")
		)
		(fp_line
			(start 0.7874 0.4064)
			(end -0.7874 0.4064)
			(stroke
				(width 0.1524)
				(type default)
			)
			(layer "F.SilkS")
		)
		(fp_line
			(start -0.7874 0.4064)
			(end -0.7874 -0.4064)
			(stroke
				(width 0.1524)
				(type default)
			)
			(layer "F.SilkS")
		)
		(fp_line
			(start -0.12065 -0.305054)
			(end -0.12065 -0.2794)
			(stroke
				(width 0.1)
				(type default)
			)
			(layer "F.Fab")
		)
		(fp_line
			(start -0.67945 -0.305054)
			(end -0.12065 -0.305054)
			(stroke
				(width 0.1)
				(type default)
			)
			(layer "F.Fab")
		)
		(fp_line
			(start 0.67945 -0.3048)
			(end 0.67945 0.3048)
			(stroke
				(width 0.1)
				(type default)
			)
			(layer "F.Fab")
		)
		(fp_line
			(start 0.12065 -0.3048)
			(end 0.67945 -0.3048)
			(stroke
				(width 0.1)
				(type default)
			)
			(layer "F.Fab")
		)
		(fp_line
			(start 0.12065 -0.2794)
			(end 0.12065 -0.3048)
			(stroke
				(width 0.1)
				(type default)
			)
			(layer "F.Fab")
		)
		(fp_line
			(start -0.12065 -0.2794)
			(end 0.12065 -0.2794)
			(stroke
				(width 0.1)
				(type default)
			)
			(layer "F.Fab")
		)
		(fp_line
			(start 0.120396 0.2794)
			(end -0.12065 0.2794)
			(stroke
				(width 0.1)
				(type default)
			)
			(layer "F.Fab")
		)
		(fp_line
			(start -0.12065 0.2794)
			(end -0.12065 0.3048)
			(stroke
				(width 0.1)
				(type default)
			)
			(layer "F.Fab")
		)
		(fp_line
			(start 0.67945 0.3048)
			(end 0.120396 0.3048)
			(stroke
				(width 0.1)
				(type default)
			)
			(layer "F.Fab")
		)
		(fp_line
			(start 0.120396 0.3048)
			(end 0.120396 0.2794)
			(stroke
				(width 0.1)
				(type default)
			)
			(layer "F.Fab")
		)
		(fp_line
			(start -0.12065 0.3048)
			(end -0.67945 0.3048)
			(stroke
				(width 0.1)
				(type default)
			)
			(layer "F.Fab")
		)
		(fp_line
			(start -0.67945 0.3048)
			(end -0.67945 -0.305054)
			(stroke
				(width 0.1)
				(type default)
			)
			(layer "F.Fab")
		)
		(pad "1" smd circle
			(at -0.40005 0 90)
			(size 0 0)
			(layers "F.Cu" "F.Mask" "F.Paste")
			(net "PVDD11_S3_P1_VCC")
		)
		(pad "2" smd circle
			(at 0.40005 0 90)
			(size 0 0)
			(layers "F.Cu" "F.Mask" "F.Paste")
			(net "P3V3_AUX")
		)
	)
	(footprint ""
		(layer "F.Cu")
		(at 59.135518 -143.656558 -90)
		(property "Reference" "PR399"
			(at 0 0 270)
			(layer "F.SilkS")
			(hide yes)
			(effects
				(font
					(size 1.27 1.27)
				)
			)
		)
		(property "Value" ""
			(at 0 0 270)
			(layer "F.Fab")
			(effects
				(font
					(size 1.27 1.27)
				)
			)
		)
		(duplicate_pad_numbers_are_jumpers no)
		(fp_line
			(start -0.7874 0.4064)
			(end -0.7874 -0.4064)
			(stroke
				(width 0.1524)
				(type default)
			)
			(layer "F.SilkS")
		)
		(fp_line
			(start 0.7874 0.4064)
			(end -0.7874 0.4064)
			(stroke
				(width 0.1524)
				(type default)
			)
			(layer "F.SilkS")
		)
		(fp_line
			(start -0.7874 -0.4064)
			(end 0.7874 -0.4064)
			(stroke
				(width 0.1524)
				(type default)
			)
			(layer "F.SilkS")
		)
		(fp_line
			(start 0.7874 -0.4064)
			(end 0.7874 0.4064)
			(stroke
				(width 0.1524)
				(type default)
			)
			(layer "F.SilkS")
		)
		(fp_line
			(start -0.67945 0.3048)
			(end -0.67945 -0.305054)
			(stroke
				(width 0.1)
				(type default)
			)
			(layer "F.Fab")
		)
		(fp_line
			(start -0.12065 0.3048)
			(end -0.67945 0.3048)
			(stroke
				(width 0.1)
				(type default)
			)
			(layer "F.Fab")
		)
		(fp_line
			(start 0.120396 0.3048)
			(end 0.120396 0.2794)
			(stroke
				(width 0.1)
				(type default)
			)
			(layer "F.Fab")
		)
		(fp_line
			(start 0.67945 0.3048)
			(end 0.120396 0.3048)
			(stroke
				(width 0.1)
				(type default)
			)
			(layer "F.Fab")
		)
		(fp_line
			(start -0.12065 0.2794)
			(end -0.12065 0.3048)
			(stroke
				(width 0.1)
				(type default)
			)
			(layer "F.Fab")
		)
		(fp_line
			(start 0.120396 0.2794)
			(end -0.12065 0.2794)
			(stroke
				(width 0.1)
				(type default)
			)
			(layer "F.Fab")
		)
		(fp_line
			(start -0.12065 -0.2794)
			(end 0.12065 -0.2794)
			(stroke
				(width 0.1)
				(type default)
			)
			(layer "F.Fab")
		)
		(fp_line
			(start 0.12065 -0.2794)
			(end 0.12065 -0.3048)
			(stroke
				(width 0.1)
				(type default)
			)
			(layer "F.Fab")
		)
		(fp_line
			(start 0.12065 -0.3048)
			(end 0.67945 -0.3048)
			(stroke
				(width 0.1)
				(type default)
			)
			(layer "F.Fab")
		)
		(fp_line
			(start 0.67945 -0.3048)
			(end 0.67945 0.3048)
			(stroke
				(width 0.1)
				(type default)
			)
			(layer "F.Fab")
		)
		(fp_line
			(start -0.67945 -0.305054)
			(end -0.12065 -0.305054)
			(stroke
				(width 0.1)
				(type default)
			)
			(layer "F.Fab")
		)
		(fp_line
			(start -0.12065 -0.305054)
			(end -0.12065 -0.2794)
			(stroke
				(width 0.1)
				(type default)
			)
			(layer "F.Fab")
		)
		(pad "1" smd circle
			(at -0.40005 0 270)
			(size 0 0)
			(layers "F.Cu" "F.Mask" "F.Paste")
			(net "GND")
		)
		(pad "2" smd circle
			(at 0.40005 0 270)
			(size 0 0)
			(layers "F.Cu" "F.Mask" "F.Paste")
			(net "PVDD18_SS_P1_RGND")
		)
	)
	(footprint ""
		(layer "F.Cu")
		(at 307.498496 -378.95403 -90)
		(property "Reference" "C921"
			(at 0 0 270)
			(layer "F.SilkS")
			(hide yes)
			(effects
				(font
					(size 1.27 1.27)
				)
			)
		)
		(property "Value" ""
			(at 0 0 270)
			(layer "F.Fab")
			(effects
				(font
					(size 1.27 1.27)
				)
			)
		)
		(duplicate_pad_numbers_are_jumpers no)
		(fp_line
			(start -0.299974 0.150114)
			(end -0.299974 -0.150114)
			(stroke
				(width 0.1)
				(type default)
			)
			(layer "F.Fab")
		)
		(fp_line
			(start 0.299974 0.150114)
			(end -0.299974 0.150114)
			(stroke
				(width 0.1)
				(type default)
			)
			(layer "F.Fab")
		)
		(fp_line
			(start -0.299974 -0.150114)
			(end 0.299974 -0.150114)
			(stroke
				(width 0.1)
				(type default)
			)
			(layer "F.Fab")
		)
		(fp_line
			(start 0.299974 -0.150114)
			(end 0.299974 0.150114)
			(stroke
				(width 0.1)
				(type default)
			)
			(layer "F.Fab")
		)
		(pad "1" smd rect
			(at -0.2667 0 270)
			(size 0.3048 0.381)
			(layers "F.Cu" "F.Mask" "F.Paste")
			(net "P5E_CPU0_P0_TX_C_DP<6>")
		)
		(pad "2" smd rect
			(at 0.2667 0 270)
			(size 0.3048 0.381)
			(layers "F.Cu" "F.Mask" "F.Paste")
			(net "P5E_CPU0_P0_TX_DP<6>")
		)
	)
	(footprint ""
		(layer "F.Cu")
		(at 307.391562 -351.927922)
		(property "Reference" "PR85"
			(at 0 0 0)
			(layer "F.SilkS")
			(hide yes)
			(effects
				(font
					(size 1.27 1.27)
				)
			)
		)
		(property "Value" ""
			(at 0 0 0)
			(layer "F.Fab")
			(effects
				(font
					(size 1.27 1.27)
				)
			)
		)
		(duplicate_pad_numbers_are_jumpers no)
		(fp_line
			(start -0.7874 -0.4064)
			(end 0.7874 -0.4064)
			(stroke
				(width 0.1524)
				(type default)
			)
			(layer "F.SilkS")
		)
		(fp_line
			(start -0.7874 0.4064)
			(end -0.7874 -0.4064)
			(stroke
				(width 0.1524)
				(type default)
			)
			(layer "F.SilkS")
		)
		(fp_line
			(start 0.7874 -0.4064)
			(end 0.7874 0.4064)
			(stroke
				(width 0.1524)
				(type default)
			)
			(layer "F.SilkS")
		)
		(fp_line
			(start 0.7874 0.4064)
			(end -0.7874 0.4064)
			(stroke
				(width 0.1524)
				(type default)
			)
			(layer "F.SilkS")
		)
		(fp_line
			(start -0.67945 -0.305054)
			(end -0.12065 -0.305054)
			(stroke
				(width 0.1)
				(type default)
			)
			(layer "F.Fab")
		)
		(fp_line
			(start -0.67945 0.3048)
			(end -0.67945 -0.305054)
			(stroke
				(width 0.1)
				(type default)
			)
			(layer "F.Fab")
		)
		(fp_line
			(start -0.12065 -0.305054)
			(end -0.12065 -0.2794)
			(stroke
				(width 0.1)
				(type default)
			)
			(layer "F.Fab")
		)
		(fp_line
			(start -0.12065 -0.2794)
			(end 0.12065 -0.2794)
			(stroke
				(width 0.1)
				(type default)
			)
			(layer "F.Fab")
		)
		(fp_line
			(start -0.12065 0.2794)
			(end -0.12065 0.3048)
			(stroke
				(width 0.1)
				(type default)
			)
			(layer "F.Fab")
		)
		(fp_line
			(start -0.12065 0.3048)
			(end -0.67945 0.3048)
			(stroke
				(width 0.1)
				(type default)
			)
			(layer "F.Fab")
		)
		(fp_line
			(start 0.120396 0.2794)
			(end -0.12065 0.2794)
			(stroke
				(width 0.1)
				(type default)
			)
			(layer "F.Fab")
		)
		(fp_line
			(start 0.120396 0.3048)
			(end 0.120396 0.2794)
			(stroke
				(width 0.1)
				(type default)
			)
			(layer "F.Fab")
		)
		(fp_line
			(start 0.12065 -0.3048)
			(end 0.67945 -0.3048)
			(stroke
				(width 0.1)
				(type default)
			)
			(layer "F.Fab")
		)
		(fp_line
			(start 0.12065 -0.2794)
			(end 0.12065 -0.3048)
			(stroke
				(width 0.1)
				(type default)
			)
			(layer "F.Fab")
		)
		(fp_line
			(start 0.67945 -0.3048)
			(end 0.67945 0.3048)
			(stroke
				(width 0.1)
				(type default)
			)
			(layer "F.Fab")
		)
		(fp_line
			(start 0.67945 0.3048)
			(end 0.120396 0.3048)
			(stroke
				(width 0.1)
				(type default)
			)
			(layer "F.Fab")
		)
		(pad "1" smd circle
			(at -0.40005 0)
			(size 0 0)
			(layers "F.Cu" "F.Mask" "F.Paste")
			(net "PVDDCR_CPU1_P0_LSET4")
		)
		(pad "2" smd circle
			(at 0.40005 0)
			(size 0 0)
			(layers "F.Cu" "F.Mask" "F.Paste")
			(net "GND")
		)
	)
	(footprint ""
		(layer "F.Cu")
		(at 389.522208 -173.314868)
		(property "Reference" "H38"
			(at -5.712206 2.34696 0)
			(unlocked yes)
			(layer "F.SilkS")
			(effects
				(font
					(size 0.7874 0.5842)
					(thickness 0.1524)
				)
				(justify left)
			)
		)
		(property "Value" ""
			(at 0 0 0)
			(layer "F.Fab")
			(effects
				(font
					(size 1.27 1.27)
				)
			)
		)
		(duplicate_pad_numbers_are_jumpers no)
		(pad "1" thru_hole circle
			(at 0 0)
			(size 6.1976 6.1976)
			(drill 3.7338)
			(layers "*.Cu" "*.Mask")
			(remove_unused_layers no)
			(net "GND")
			(clearance -0.9779)
			(padstack
				(mode front_inner_back)
				(layer "Inner"
					(shape circle)
					(size 5.5372 5.5372)
					(clearance -0.6477)
				)
				(layer "B.Cu"
					(shape circle)
					(size 6.1976 6.1976)
					(clearance -0.9779)
				)
			)
		)
	)
	(footprint ""
		(layer "F.Cu")
		(at 185.799222 -23.113492)
		(property "Reference" "PR4000"
			(at 0 0 0)
			(layer "F.SilkS")
			(hide yes)
			(effects
				(font
					(size 1.27 1.27)
				)
			)
		)
		(property "Value" ""
			(at 0 0 0)
			(layer "F.Fab")
			(effects
				(font
					(size 1.27 1.27)
				)
			)
		)
		(duplicate_pad_numbers_are_jumpers no)
		(fp_line
			(start -0.7874 -0.4064)
			(end 0.7874 -0.4064)
			(stroke
				(width 0.1524)
				(type default)
			)
			(layer "F.SilkS")
		)
		(fp_line
			(start -0.7874 0.4064)
			(end -0.7874 -0.4064)
			(stroke
				(width 0.1524)
				(type default)
			)
			(layer "F.SilkS")
		)
		(fp_line
			(start 0.7874 -0.4064)
			(end 0.7874 0.4064)
			(stroke
				(width 0.1524)
				(type default)
			)
			(layer "F.SilkS")
		)
		(fp_line
			(start 0.7874 0.4064)
			(end -0.7874 0.4064)
			(stroke
				(width 0.1524)
				(type default)
			)
			(layer "F.SilkS")
		)
		(fp_line
			(start -0.67945 -0.305054)
			(end -0.12065 -0.305054)
			(stroke
				(width 0.1)
				(type default)
			)
			(layer "F.Fab")
		)
		(fp_line
			(start -0.67945 0.3048)
			(end -0.67945 -0.305054)
			(stroke
				(width 0.1)
				(type default)
			)
			(layer "F.Fab")
		)
		(fp_line
			(start -0.12065 -0.305054)
			(end -0.12065 -0.2794)
			(stroke
				(width 0.1)
				(type default)
			)
			(layer "F.Fab")
		)
		(fp_line
			(start -0.12065 -0.2794)
			(end 0.12065 -0.2794)
			(stroke
				(width 0.1)
				(type default)
			)
			(layer "F.Fab")
		)
		(fp_line
			(start -0.12065 0.2794)
			(end -0.12065 0.3048)
			(stroke
				(width 0.1)
				(type default)
			)
			(layer "F.Fab")
		)
		(fp_line
			(start -0.12065 0.3048)
			(end -0.67945 0.3048)
			(stroke
				(width 0.1)
				(type default)
			)
			(layer "F.Fab")
		)
		(fp_line
			(start 0.120396 0.2794)
			(end -0.12065 0.2794)
			(stroke
				(width 0.1)
				(type default)
			)
			(layer "F.Fab")
		)
		(fp_line
			(start 0.120396 0.3048)
			(end 0.120396 0.2794)
			(stroke
				(width 0.1)
				(type default)
			)
			(layer "F.Fab")
		)
		(fp_line
			(start 0.12065 -0.3048)
			(end 0.67945 -0.3048)
			(stroke
				(width 0.1)
				(type default)
			)
			(layer "F.Fab")
		)
		(fp_line
			(start 0.12065 -0.2794)
			(end 0.12065 -0.3048)
			(stroke
				(width 0.1)
				(type default)
			)
			(layer "F.Fab")
		)
		(fp_line
			(start 0.67945 -0.3048)
			(end 0.67945 0.3048)
			(stroke
				(width 0.1)
				(type default)
			)
			(layer "F.Fab")
		)
		(fp_line
			(start 0.67945 0.3048)
			(end 0.120396 0.3048)
			(stroke
				(width 0.1)
				(type default)
			)
			(layer "F.Fab")
		)
		(pad "1" smd circle
			(at -0.40005 0)
			(size 0 0)
			(layers "F.Cu" "F.Mask" "F.Paste")
			(net "P12V_AUX")
		)
		(pad "2" smd circle
			(at 0.40005 0)
			(size 0 0)
			(layers "F.Cu" "F.Mask" "F.Paste")
			(net "P12V_SCM_UV")
		)
	)
	(footprint ""
		(layer "F.Cu")
		(at 422.180766 -404.0124 -90)
		(property "Reference" "R1081"
			(at 0 0 270)
			(layer "F.SilkS")
			(hide yes)
			(effects
				(font
					(size 1.27 1.27)
				)
			)
		)
		(property "Value" ""
			(at 0 0 270)
			(layer "F.Fab")
			(effects
				(font
					(size 1.27 1.27)
				)
			)
		)
		(duplicate_pad_numbers_are_jumpers no)
		(fp_line
			(start -0.32512 0.175006)
			(end -0.32512 -0.175006)
			(stroke
				(width 0.1)
				(type default)
			)
			(layer "F.Fab")
		)
		(fp_line
			(start 0.32512 0.175006)
			(end -0.32512 0.175006)
			(stroke
				(width 0.1)
				(type default)
			)
			(layer "F.Fab")
		)
		(fp_line
			(start -0.32512 -0.175006)
			(end 0.32512 -0.175006)
			(stroke
				(width 0.1)
				(type default)
			)
			(layer "F.Fab")
		)
		(fp_line
			(start 0.32512 -0.175006)
			(end 0.32512 0.175006)
			(stroke
				(width 0.1)
				(type default)
			)
			(layer "F.Fab")
		)
		(pad "1" smd rect
			(at -0.2667 0 270)
			(size 0.3048 0.381)
			(layers "F.Cu" "F.Mask" "F.Paste")
			(net "P1V8_CPU0_RT_1D")
		)
		(pad "2" smd rect
			(at 0.2667 0 90)
			(size 0.3048 0.381)
			(layers "F.Cu" "F.Mask" "F.Paste")
			(net "RT_CPU0_P2_VQPS")
		)
	)
	(footprint ""
		(layer "F.Cu")
		(at 24.057102 -351.621598 90)
		(property "Reference" "PR340"
			(at 0 0 90)
			(layer "F.SilkS")
			(hide yes)
			(effects
				(font
					(size 1.27 1.27)
				)
			)
		)
		(property "Value" ""
			(at 0 0 90)
			(layer "F.Fab")
			(effects
				(font
					(size 1.27 1.27)
				)
			)
		)
		(duplicate_pad_numbers_are_jumpers no)
		(fp_line
			(start 0.7874 -0.4064)
			(end 0.7874 0.4064)
			(stroke
				(width 0.1524)
				(type default)
			)
			(layer "F.SilkS")
		)
		(fp_line
			(start -0.7874 -0.4064)
			(end 0.7874 -0.4064)
			(stroke
				(width 0.1524)
				(type default)
			)
			(layer "F.SilkS")
		)
		(fp_line
			(start 0.7874 0.4064)
			(end -0.7874 0.4064)
			(stroke
				(width 0.1524)
				(type default)
			)
			(layer "F.SilkS")
		)
		(fp_line
			(start -0.7874 0.4064)
			(end -0.7874 -0.4064)
			(stroke
				(width 0.1524)
				(type default)
			)
			(layer "F.SilkS")
		)
		(fp_line
			(start -0.12065 -0.305054)
			(end -0.12065 -0.2794)
			(stroke
				(width 0.1)
				(type default)
			)
			(layer "F.Fab")
		)
		(fp_line
			(start -0.67945 -0.305054)
			(end -0.12065 -0.305054)
			(stroke
				(width 0.1)
				(type default)
			)
			(layer "F.Fab")
		)
		(fp_line
			(start 0.67945 -0.3048)
			(end 0.67945 0.3048)
			(stroke
				(width 0.1)
				(type default)
			)
			(layer "F.Fab")
		)
		(fp_line
			(start 0.12065 -0.3048)
			(end 0.67945 -0.3048)
			(stroke
				(width 0.1)
				(type default)
			)
			(layer "F.Fab")
		)
		(fp_line
			(start 0.12065 -0.2794)
			(end 0.12065 -0.3048)
			(stroke
				(width 0.1)
				(type default)
			)
			(layer "F.Fab")
		)
		(fp_line
			(start -0.12065 -0.2794)
			(end 0.12065 -0.2794)
			(stroke
				(width 0.1)
				(type default)
			)
			(layer "F.Fab")
		)
		(fp_line
			(start 0.120396 0.2794)
			(end -0.12065 0.2794)
			(stroke
				(width 0.1)
				(type default)
			)
			(layer "F.Fab")
		)
		(fp_line
			(start -0.12065 0.2794)
			(end -0.12065 0.3048)
			(stroke
				(width 0.1)
				(type default)
			)
			(layer "F.Fab")
		)
		(fp_line
			(start 0.67945 0.3048)
			(end 0.120396 0.3048)
			(stroke
				(width 0.1)
				(type default)
			)
			(layer "F.Fab")
		)
		(fp_line
			(start 0.120396 0.3048)
			(end 0.120396 0.2794)
			(stroke
				(width 0.1)
				(type default)
			)
			(layer "F.Fab")
		)
		(fp_line
			(start -0.12065 0.3048)
			(end -0.67945 0.3048)
			(stroke
				(width 0.1)
				(type default)
			)
			(layer "F.Fab")
		)
		(fp_line
			(start -0.67945 0.3048)
			(end -0.67945 -0.305054)
			(stroke
				(width 0.1)
				(type default)
			)
			(layer "F.Fab")
		)
		(pad "1" smd circle
			(at -0.40005 0 90)
			(size 0 0)
			(layers "F.Cu" "F.Mask" "F.Paste")
			(net "PVDDCR_CPU1_P1_PVCC")
		)
		(pad "2" smd circle
			(at 0.40005 0 90)
			(size 0 0)
			(layers "F.Cu" "F.Mask" "F.Paste")
			(net "P5V_AUX")
		)
	)
	(footprint ""
		(layer "F.Cu")
		(at 414.325562 -362.804964 180)
		(property "Reference" "PR128"
			(at 0 0 180)
			(layer "F.SilkS")
			(hide yes)
			(effects
				(font
					(size 1.27 1.27)
				)
			)
		)
		(property "Value" ""
			(at 0 0 180)
			(layer "F.Fab")
			(effects
				(font
					(size 1.27 1.27)
				)
			)
		)
		(duplicate_pad_numbers_are_jumpers no)
		(fp_line
			(start 0.7874 0.4064)
			(end -0.7874 0.4064)
			(stroke
				(width 0.1524)
				(type default)
			)
			(layer "F.SilkS")
		)
		(fp_line
			(start 0.7874 -0.4064)
			(end 0.7874 0.4064)
			(stroke
				(width 0.1524)
				(type default)
			)
			(layer "F.SilkS")
		)
		(fp_line
			(start -0.7874 0.4064)
			(end -0.7874 -0.4064)
			(stroke
				(width 0.1524)
				(type default)
			)
			(layer "F.SilkS")
		)
		(fp_line
			(start -0.7874 -0.4064)
			(end 0.7874 -0.4064)
			(stroke
				(width 0.1524)
				(type default)
			)
			(layer "F.SilkS")
		)
		(fp_line
			(start 0.67945 0.3048)
			(end 0.120396 0.3048)
			(stroke
				(width 0.1)
				(type default)
			)
			(layer "F.Fab")
		)
		(fp_line
			(start 0.67945 -0.3048)
			(end 0.67945 0.3048)
			(stroke
				(width 0.1)
				(type default)
			)
			(layer "F.Fab")
		)
		(fp_line
			(start 0.12065 -0.2794)
			(end 0.12065 -0.3048)
			(stroke
				(width 0.1)
				(type default)
			)
			(layer "F.Fab")
		)
		(fp_line
			(start 0.12065 -0.3048)
			(end 0.67945 -0.3048)
			(stroke
				(width 0.1)
				(type default)
			)
			(layer "F.Fab")
		)
		(fp_line
			(start 0.120396 0.3048)
			(end 0.120396 0.2794)
			(stroke
				(width 0.1)
				(type default)
			)
			(layer "F.Fab")
		)
		(fp_line
			(start 0.120396 0.2794)
			(end -0.12065 0.2794)
			(stroke
				(width 0.1)
				(type default)
			)
			(layer "F.Fab")
		)
		(fp_line
			(start -0.12065 0.3048)
			(end -0.67945 0.3048)
			(stroke
				(width 0.1)
				(type default)
			)
			(layer "F.Fab")
		)
		(fp_line
			(start -0.12065 0.2794)
			(end -0.12065 0.3048)
			(stroke
				(width 0.1)
				(type default)
			)
			(layer "F.Fab")
		)
		(fp_line
			(start -0.12065 -0.2794)
			(end 0.12065 -0.2794)
			(stroke
				(width 0.1)
				(type default)
			)
			(layer "F.Fab")
		)
		(fp_line
			(start -0.12065 -0.305054)
			(end -0.12065 -0.2794)
			(stroke
				(width 0.1)
				(type default)
			)
			(layer "F.Fab")
		)
		(fp_line
			(start -0.67945 0.3048)
			(end -0.67945 -0.305054)
			(stroke
				(width 0.1)
				(type default)
			)
			(layer "F.Fab")
		)
		(fp_line
			(start -0.67945 -0.305054)
			(end -0.12065 -0.305054)
			(stroke
				(width 0.1)
				(type default)
			)
			(layer "F.Fab")
		)
		(pad "1" smd circle
			(at -0.40005 0 180)
			(size 0 0)
			(layers "F.Cu" "F.Mask" "F.Paste")
			(net "PVDD11_S3_P0_RESET_N_R")
		)
		(pad "2" smd circle
			(at 0.40005 0 180)
			(size 0 0)
			(layers "F.Cu" "F.Mask" "F.Paste")
			(net "PVDD18_S5_P0")
		)
	)
	(footprint ""
		(layer "F.Cu")
		(at 137.186924 -167.9702 -90)
		(property "Reference" "PC338"
			(at 0 0 270)
			(layer "F.SilkS")
			(hide yes)
			(effects
				(font
					(size 1.27 1.27)
				)
			)
		)
		(property "Value" ""
			(at 0 0 270)
			(layer "F.Fab")
			(effects
				(font
					(size 1.27 1.27)
				)
			)
		)
		(duplicate_pad_numbers_are_jumpers no)
		(fp_line
			(start -0.7874 0.4064)
			(end -0.7874 -0.4064)
			(stroke
				(width 0.1524)
				(type default)
			)
			(layer "F.SilkS")
		)
		(fp_line
			(start 0.7874 0.4064)
			(end -0.7874 0.4064)
			(stroke
				(width 0.1524)
				(type default)
			)
			(layer "F.SilkS")
		)
		(fp_line
			(start -0.7874 -0.4064)
			(end 0.7874 -0.4064)
			(stroke
				(width 0.1524)
				(type default)
			)
			(layer "F.SilkS")
		)
		(fp_line
			(start 0.7874 -0.4064)
			(end 0.7874 0.4064)
			(stroke
				(width 0.1524)
				(type default)
			)
			(layer "F.SilkS")
		)
		(fp_line
			(start -0.67945 0.3048)
			(end -0.67945 -0.305054)
			(stroke
				(width 0.1)
				(type default)
			)
			(layer "F.Fab")
		)
		(fp_line
			(start -0.12065 0.3048)
			(end -0.67945 0.3048)
			(stroke
				(width 0.1)
				(type default)
			)
			(layer "F.Fab")
		)
		(fp_line
			(start 0.120396 0.3048)
			(end 0.120396 0.2794)
			(stroke
				(width 0.1)
				(type default)
			)
			(layer "F.Fab")
		)
		(fp_line
			(start 0.67945 0.3048)
			(end 0.120396 0.3048)
			(stroke
				(width 0.1)
				(type default)
			)
			(layer "F.Fab")
		)
		(fp_line
			(start -0.12065 0.2794)
			(end -0.12065 0.3048)
			(stroke
				(width 0.1)
				(type default)
			)
			(layer "F.Fab")
		)
		(fp_line
			(start 0.120396 0.2794)
			(end -0.12065 0.2794)
			(stroke
				(width 0.1)
				(type default)
			)
			(layer "F.Fab")
		)
		(fp_line
			(start -0.12065 -0.2794)
			(end 0.12065 -0.2794)
			(stroke
				(width 0.1)
				(type default)
			)
			(layer "F.Fab")
		)
		(fp_line
			(start 0.12065 -0.2794)
			(end 0.12065 -0.3048)
			(stroke
				(width 0.1)
				(type default)
			)
			(layer "F.Fab")
		)
		(fp_line
			(start 0.12065 -0.3048)
			(end 0.67945 -0.3048)
			(stroke
				(width 0.1)
				(type default)
			)
			(layer "F.Fab")
		)
		(fp_line
			(start 0.67945 -0.3048)
			(end 0.67945 0.3048)
			(stroke
				(width 0.1)
				(type default)
			)
			(layer "F.Fab")
		)
		(fp_line
			(start -0.67945 -0.305054)
			(end -0.12065 -0.305054)
			(stroke
				(width 0.1)
				(type default)
			)
			(layer "F.Fab")
		)
		(fp_line
			(start -0.12065 -0.305054)
			(end -0.12065 -0.2794)
			(stroke
				(width 0.1)
				(type default)
			)
			(layer "F.Fab")
		)
		(pad "1" smd circle
			(at -0.40005 0 270)
			(size 0 0)
			(layers "F.Cu" "F.Mask" "F.Paste")
			(net "PVDDCR_SOC_P1")
		)
		(pad "2" smd circle
			(at 0.40005 0 270)
			(size 0 0)
			(layers "F.Cu" "F.Mask" "F.Paste")
			(net "GND")
		)
	)
	(footprint ""
		(layer "F.Cu")
		(at 167.132 -110.200948 180)
		(property "Reference" "R152"
			(at 0 0 180)
			(layer "F.SilkS")
			(hide yes)
			(effects
				(font
					(size 1.27 1.27)
				)
			)
		)
		(property "Value" ""
			(at 0 0 180)
			(layer "F.Fab")
			(effects
				(font
					(size 1.27 1.27)
				)
			)
		)
		(duplicate_pad_numbers_are_jumpers no)
		(fp_line
			(start 0.7874 0.4064)
			(end -0.7874 0.4064)
			(stroke
				(width 0.1524)
				(type default)
			)
			(layer "F.SilkS")
		)
		(fp_line
			(start 0.7874 -0.4064)
			(end 0.7874 0.4064)
			(stroke
				(width 0.1524)
				(type default)
			)
			(layer "F.SilkS")
		)
		(fp_line
			(start -0.7874 0.4064)
			(end -0.7874 -0.4064)
			(stroke
				(width 0.1524)
				(type default)
			)
			(layer "F.SilkS")
		)
		(fp_line
			(start -0.7874 -0.4064)
			(end 0.7874 -0.4064)
			(stroke
				(width 0.1524)
				(type default)
			)
			(layer "F.SilkS")
		)
		(fp_line
			(start 0.67945 0.3048)
			(end 0.120396 0.3048)
			(stroke
				(width 0.1)
				(type default)
			)
			(layer "F.Fab")
		)
		(fp_line
			(start 0.67945 -0.3048)
			(end 0.67945 0.3048)
			(stroke
				(width 0.1)
				(type default)
			)
			(layer "F.Fab")
		)
		(fp_line
			(start 0.12065 -0.2794)
			(end 0.12065 -0.3048)
			(stroke
				(width 0.1)
				(type default)
			)
			(layer "F.Fab")
		)
		(fp_line
			(start 0.12065 -0.3048)
			(end 0.67945 -0.3048)
			(stroke
				(width 0.1)
				(type default)
			)
			(layer "F.Fab")
		)
		(fp_line
			(start 0.120396 0.3048)
			(end 0.120396 0.2794)
			(stroke
				(width 0.1)
				(type default)
			)
			(layer "F.Fab")
		)
		(fp_line
			(start 0.120396 0.2794)
			(end -0.12065 0.2794)
			(stroke
				(width 0.1)
				(type default)
			)
			(layer "F.Fab")
		)
		(fp_line
			(start -0.12065 0.3048)
			(end -0.67945 0.3048)
			(stroke
				(width 0.1)
				(type default)
			)
			(layer "F.Fab")
		)
		(fp_line
			(start -0.12065 0.2794)
			(end -0.12065 0.3048)
			(stroke
				(width 0.1)
				(type default)
			)
			(layer "F.Fab")
		)
		(fp_line
			(start -0.12065 -0.2794)
			(end 0.12065 -0.2794)
			(stroke
				(width 0.1)
				(type default)
			)
			(layer "F.Fab")
		)
		(fp_line
			(start -0.12065 -0.305054)
			(end -0.12065 -0.2794)
			(stroke
				(width 0.1)
				(type default)
			)
			(layer "F.Fab")
		)
		(fp_line
			(start -0.67945 0.3048)
			(end -0.67945 -0.305054)
			(stroke
				(width 0.1)
				(type default)
			)
			(layer "F.Fab")
		)
		(fp_line
			(start -0.67945 -0.305054)
			(end -0.12065 -0.305054)
			(stroke
				(width 0.1)
				(type default)
			)
			(layer "F.Fab")
		)
		(pad "1" smd circle
			(at -0.40005 0 180)
			(size 0 0)
			(layers "F.Cu" "F.Mask" "F.Paste")
			(net "P12V_OCP_SFF_EN")
		)
		(pad "2" smd circle
			(at 0.40005 0 180)
			(size 0 0)
			(layers "F.Cu" "F.Mask" "F.Paste")
			(net "P12V_OCP_SFF_EN_R")
		)
	)
	(footprint ""
		(layer "F.Cu")
		(at 94.237302 -375.49963 -90)
		(property "Reference" "C721"
			(at 0 0 270)
			(layer "F.SilkS")
			(hide yes)
			(effects
				(font
					(size 1.27 1.27)
				)
			)
		)
		(property "Value" ""
			(at 0 0 270)
			(layer "F.Fab")
			(effects
				(font
					(size 1.27 1.27)
				)
			)
		)
		(duplicate_pad_numbers_are_jumpers no)
		(fp_line
			(start -0.299974 0.150114)
			(end -0.299974 -0.150114)
			(stroke
				(width 0.1)
				(type default)
			)
			(layer "F.Fab")
		)
		(fp_line
			(start 0.299974 0.150114)
			(end -0.299974 0.150114)
			(stroke
				(width 0.1)
				(type default)
			)
			(layer "F.Fab")
		)
		(fp_line
			(start -0.299974 -0.150114)
			(end 0.299974 -0.150114)
			(stroke
				(width 0.1)
				(type default)
			)
			(layer "F.Fab")
		)
		(fp_line
			(start 0.299974 -0.150114)
			(end 0.299974 0.150114)
			(stroke
				(width 0.1)
				(type default)
			)
			(layer "F.Fab")
		)
		(pad "1" smd rect
			(at -0.2667 0 270)
			(size 0.3048 0.381)
			(layers "F.Cu" "F.Mask" "F.Paste")
			(net "P5E_CPU1_P1_TX_C_DP<10>")
		)
		(pad "2" smd rect
			(at 0.2667 0 270)
			(size 0.3048 0.381)
			(layers "F.Cu" "F.Mask" "F.Paste")
			(net "P5E_CPU1_P1_TX_DP<10>")
		)
	)
	(footprint ""
		(layer "F.Cu")
		(at 203.2 -99.695)
		(property "Reference" "R8085"
			(at 0 0 0)
			(layer "F.SilkS")
			(hide yes)
			(effects
				(font
					(size 1.27 1.27)
				)
			)
		)
		(property "Value" ""
			(at 0 0 0)
			(layer "F.Fab")
			(effects
				(font
					(size 1.27 1.27)
				)
			)
		)
		(duplicate_pad_numbers_are_jumpers no)
		(fp_line
			(start -0.7874 -0.4064)
			(end 0.7874 -0.4064)
			(stroke
				(width 0.1524)
				(type default)
			)
			(layer "F.SilkS")
		)
		(fp_line
			(start -0.7874 0.4064)
			(end -0.7874 -0.4064)
			(stroke
				(width 0.1524)
				(type default)
			)
			(layer "F.SilkS")
		)
		(fp_line
			(start 0.7874 -0.4064)
			(end 0.7874 0.4064)
			(stroke
				(width 0.1524)
				(type default)
			)
			(layer "F.SilkS")
		)
		(fp_line
			(start 0.7874 0.4064)
			(end -0.7874 0.4064)
			(stroke
				(width 0.1524)
				(type default)
			)
			(layer "F.SilkS")
		)
		(fp_line
			(start -0.67945 -0.305054)
			(end -0.12065 -0.305054)
			(stroke
				(width 0.1)
				(type default)
			)
			(layer "F.Fab")
		)
		(fp_line
			(start -0.67945 0.3048)
			(end -0.67945 -0.305054)
			(stroke
				(width 0.1)
				(type default)
			)
			(layer "F.Fab")
		)
		(fp_line
			(start -0.12065 -0.305054)
			(end -0.12065 -0.2794)
			(stroke
				(width 0.1)
				(type default)
			)
			(layer "F.Fab")
		)
		(fp_line
			(start -0.12065 -0.2794)
			(end 0.12065 -0.2794)
			(stroke
				(width 0.1)
				(type default)
			)
			(layer "F.Fab")
		)
		(fp_line
			(start -0.12065 0.2794)
			(end -0.12065 0.3048)
			(stroke
				(width 0.1)
				(type default)
			)
			(layer "F.Fab")
		)
		(fp_line
			(start -0.12065 0.3048)
			(end -0.67945 0.3048)
			(stroke
				(width 0.1)
				(type default)
			)
			(layer "F.Fab")
		)
		(fp_line
			(start 0.120396 0.2794)
			(end -0.12065 0.2794)
			(stroke
				(width 0.1)
				(type default)
			)
			(layer "F.Fab")
		)
		(fp_line
			(start 0.120396 0.3048)
			(end 0.120396 0.2794)
			(stroke
				(width 0.1)
				(type default)
			)
			(layer "F.Fab")
		)
		(fp_line
			(start 0.12065 -0.3048)
			(end 0.67945 -0.3048)
			(stroke
				(width 0.1)
				(type default)
			)
			(layer "F.Fab")
		)
		(fp_line
			(start 0.12065 -0.2794)
			(end 0.12065 -0.3048)
			(stroke
				(width 0.1)
				(type default)
			)
			(layer "F.Fab")
		)
		(fp_line
			(start 0.67945 -0.3048)
			(end 0.67945 0.3048)
			(stroke
				(width 0.1)
				(type default)
			)
			(layer "F.Fab")
		)
		(fp_line
			(start 0.67945 0.3048)
			(end 0.120396 0.3048)
			(stroke
				(width 0.1)
				(type default)
			)
			(layer "F.Fab")
		)
		(pad "1" smd circle
			(at -0.40005 0)
			(size 0 0)
			(layers "F.Cu" "F.Mask" "F.Paste")
			(net "P3V3_AUX")
		)
		(pad "2" smd circle
			(at 0.40005 0)
			(size 0 0)
			(layers "F.Cu" "F.Mask" "F.Paste")
			(net "PWRGD_CHGL_CPU0_R1")
		)
	)
	(footprint ""
		(layer "F.Cu")
		(at 226.0981 -404.020782)
		(property "Reference" "PC2224"
			(at 0 0 0)
			(layer "F.SilkS")
			(hide yes)
			(effects
				(font
					(size 1.27 1.27)
				)
			)
		)
		(property "Value" ""
			(at 0 0 0)
			(layer "F.Fab")
			(effects
				(font
					(size 1.27 1.27)
				)
			)
		)
		(duplicate_pad_numbers_are_jumpers no)
		(fp_line
			(start -0.7874 -0.4064)
			(end 0.7874 -0.4064)
			(stroke
				(width 0.1524)
				(type default)
			)
			(layer "F.SilkS")
		)
		(fp_line
			(start -0.7874 0.4064)
			(end -0.7874 -0.4064)
			(stroke
				(width 0.1524)
				(type default)
			)
			(layer "F.SilkS")
		)
		(fp_line
			(start 0.7874 -0.4064)
			(end 0.7874 0.4064)
			(stroke
				(width 0.1524)
				(type default)
			)
			(layer "F.SilkS")
		)
		(fp_line
			(start 0.7874 0.4064)
			(end -0.7874 0.4064)
			(stroke
				(width 0.1524)
				(type default)
			)
			(layer "F.SilkS")
		)
		(fp_line
			(start -0.67945 -0.305054)
			(end -0.12065 -0.305054)
			(stroke
				(width 0.1)
				(type default)
			)
			(layer "F.Fab")
		)
		(fp_line
			(start -0.67945 0.3048)
			(end -0.67945 -0.305054)
			(stroke
				(width 0.1)
				(type default)
			)
			(layer "F.Fab")
		)
		(fp_line
			(start -0.12065 -0.305054)
			(end -0.12065 -0.2794)
			(stroke
				(width 0.1)
				(type default)
			)
			(layer "F.Fab")
		)
		(fp_line
			(start -0.12065 -0.2794)
			(end 0.12065 -0.2794)
			(stroke
				(width 0.1)
				(type default)
			)
			(layer "F.Fab")
		)
		(fp_line
			(start -0.12065 0.2794)
			(end -0.12065 0.3048)
			(stroke
				(width 0.1)
				(type default)
			)
			(layer "F.Fab")
		)
		(fp_line
			(start -0.12065 0.3048)
			(end -0.67945 0.3048)
			(stroke
				(width 0.1)
				(type default)
			)
			(layer "F.Fab")
		)
		(fp_line
			(start 0.120396 0.2794)
			(end -0.12065 0.2794)
			(stroke
				(width 0.1)
				(type default)
			)
			(layer "F.Fab")
		)
		(fp_line
			(start 0.120396 0.3048)
			(end 0.120396 0.2794)
			(stroke
				(width 0.1)
				(type default)
			)
			(layer "F.Fab")
		)
		(fp_line
			(start 0.12065 -0.3048)
			(end 0.67945 -0.3048)
			(stroke
				(width 0.1)
				(type default)
			)
			(layer "F.Fab")
		)
		(fp_line
			(start 0.12065 -0.2794)
			(end 0.12065 -0.3048)
			(stroke
				(width 0.1)
				(type default)
			)
			(layer "F.Fab")
		)
		(fp_line
			(start 0.67945 -0.3048)
			(end 0.67945 0.3048)
			(stroke
				(width 0.1)
				(type default)
			)
			(layer "F.Fab")
		)
		(fp_line
			(start 0.67945 0.3048)
			(end 0.120396 0.3048)
			(stroke
				(width 0.1)
				(type default)
			)
			(layer "F.Fab")
		)
		(pad "1" smd circle
			(at -0.40005 0)
			(size 0 0)
			(layers "F.Cu" "F.Mask" "F.Paste")
			(net "HSC_ON")
		)
		(pad "2" smd circle
			(at 0.40005 0)
			(size 0 0)
			(layers "F.Cu" "F.Mask" "F.Paste")
			(net "AGND_HSC")
		)
	)
	(footprint ""
		(layer "F.Cu")
		(at 174.030894 -390.53008 180)
		(property "Reference" "R863"
			(at 0 0 180)
			(layer "F.SilkS")
			(hide yes)
			(effects
				(font
					(size 1.27 1.27)
				)
			)
		)
		(property "Value" ""
			(at 0 0 180)
			(layer "F.Fab")
			(effects
				(font
					(size 1.27 1.27)
				)
			)
		)
		(duplicate_pad_numbers_are_jumpers no)
		(fp_line
			(start 0.32512 0.175006)
			(end -0.32512 0.175006)
			(stroke
				(width 0.1)
				(type default)
			)
			(layer "F.Fab")
		)
		(fp_line
			(start 0.32512 -0.175006)
			(end 0.32512 0.175006)
			(stroke
				(width 0.1)
				(type default)
			)
			(layer "F.Fab")
		)
		(fp_line
			(start -0.32512 0.175006)
			(end -0.32512 -0.175006)
			(stroke
				(width 0.1)
				(type default)
			)
			(layer "F.Fab")
		)
		(fp_line
			(start -0.32512 -0.175006)
			(end 0.32512 -0.175006)
			(stroke
				(width 0.1)
				(type default)
			)
			(layer "F.Fab")
		)
		(pad "1" smd rect
			(at -0.2667 0 180)
			(size 0.3048 0.381)
			(layers "F.Cu" "F.Mask" "F.Paste")
			(net "RT_CPU1_P2_ADDR3")
		)
		(pad "2" smd rect
			(at 0.2667 0)
			(size 0.3048 0.381)
			(layers "F.Cu" "F.Mask" "F.Paste")
			(net "GND")
		)
	)
	(footprint ""
		(layer "F.Cu")
		(at 209.070956 -30.276292 90)
		(property "Reference" "R3624"
			(at 0 0 90)
			(layer "F.SilkS")
			(hide yes)
			(effects
				(font
					(size 1.27 1.27)
				)
			)
		)
		(property "Value" ""
			(at 0 0 90)
			(layer "F.Fab")
			(effects
				(font
					(size 1.27 1.27)
				)
			)
		)
		(duplicate_pad_numbers_are_jumpers no)
		(fp_line
			(start 0.7874 -0.4064)
			(end 0.7874 0.4064)
			(stroke
				(width 0.1524)
				(type default)
			)
			(layer "F.SilkS")
		)
		(fp_line
			(start -0.7874 -0.4064)
			(end 0.7874 -0.4064)
			(stroke
				(width 0.1524)
				(type default)
			)
			(layer "F.SilkS")
		)
		(fp_line
			(start 0.7874 0.4064)
			(end -0.7874 0.4064)
			(stroke
				(width 0.1524)
				(type default)
			)
			(layer "F.SilkS")
		)
		(fp_line
			(start -0.7874 0.4064)
			(end -0.7874 -0.4064)
			(stroke
				(width 0.1524)
				(type default)
			)
			(layer "F.SilkS")
		)
		(fp_line
			(start -0.12065 -0.305054)
			(end -0.12065 -0.2794)
			(stroke
				(width 0.1)
				(type default)
			)
			(layer "F.Fab")
		)
		(fp_line
			(start -0.67945 -0.305054)
			(end -0.12065 -0.305054)
			(stroke
				(width 0.1)
				(type default)
			)
			(layer "F.Fab")
		)
		(fp_line
			(start 0.67945 -0.3048)
			(end 0.67945 0.3048)
			(stroke
				(width 0.1)
				(type default)
			)
			(layer "F.Fab")
		)
		(fp_line
			(start 0.12065 -0.3048)
			(end 0.67945 -0.3048)
			(stroke
				(width 0.1)
				(type default)
			)
			(layer "F.Fab")
		)
		(fp_line
			(start 0.12065 -0.2794)
			(end 0.12065 -0.3048)
			(stroke
				(width 0.1)
				(type default)
			)
			(layer "F.Fab")
		)
		(fp_line
			(start -0.12065 -0.2794)
			(end 0.12065 -0.2794)
			(stroke
				(width 0.1)
				(type default)
			)
			(layer "F.Fab")
		)
		(fp_line
			(start 0.120396 0.2794)
			(end -0.12065 0.2794)
			(stroke
				(width 0.1)
				(type default)
			)
			(layer "F.Fab")
		)
		(fp_line
			(start -0.12065 0.2794)
			(end -0.12065 0.3048)
			(stroke
				(width 0.1)
				(type default)
			)
			(layer "F.Fab")
		)
		(fp_line
			(start 0.67945 0.3048)
			(end 0.120396 0.3048)
			(stroke
				(width 0.1)
				(type default)
			)
			(layer "F.Fab")
		)
		(fp_line
			(start 0.120396 0.3048)
			(end 0.120396 0.2794)
			(stroke
				(width 0.1)
				(type default)
			)
			(layer "F.Fab")
		)
		(fp_line
			(start -0.12065 0.3048)
			(end -0.67945 0.3048)
			(stroke
				(width 0.1)
				(type default)
			)
			(layer "F.Fab")
		)
		(fp_line
			(start -0.67945 0.3048)
			(end -0.67945 -0.305054)
			(stroke
				(width 0.1)
				(type default)
			)
			(layer "F.Fab")
		)
		(pad "1" smd circle
			(at -0.40005 0 90)
			(size 0 0)
			(layers "F.Cu" "F.Mask" "F.Paste")
			(net "P3V3_AUX")
		)
		(pad "2" smd circle
			(at 0.40005 0 90)
			(size 0 0)
			(layers "F.Cu" "F.Mask" "F.Paste")
			(net "INA230_5_A1")
		)
	)
	(footprint ""
		(layer "F.Cu")
		(at 314.66282 -334.993488 -90)
		(property "Reference" "PC112_C1P0_3"
			(at 0 0 270)
			(layer "F.SilkS")
			(hide yes)
			(effects
				(font
					(size 1.27 1.27)
				)
			)
		)
		(property "Value" ""
			(at 0 0 270)
			(layer "F.Fab")
			(effects
				(font
					(size 1.27 1.27)
				)
			)
		)
		(duplicate_pad_numbers_are_jumpers no)
		(fp_line
			(start -0.7874 0.4064)
			(end -0.7874 -0.4064)
			(stroke
				(width 0.1524)
				(type default)
			)
			(layer "F.SilkS")
		)
		(fp_line
			(start 0.7874 0.4064)
			(end -0.7874 0.4064)
			(stroke
				(width 0.1524)
				(type default)
			)
			(layer "F.SilkS")
		)
		(fp_line
			(start -0.7874 -0.4064)
			(end 0.7874 -0.4064)
			(stroke
				(width 0.1524)
				(type default)
			)
			(layer "F.SilkS")
		)
		(fp_line
			(start 0.7874 -0.4064)
			(end 0.7874 0.4064)
			(stroke
				(width 0.1524)
				(type default)
			)
			(layer "F.SilkS")
		)
		(fp_line
			(start -0.67945 0.3048)
			(end -0.67945 -0.305054)
			(stroke
				(width 0.1)
				(type default)
			)
			(layer "F.Fab")
		)
		(fp_line
			(start -0.12065 0.3048)
			(end -0.67945 0.3048)
			(stroke
				(width 0.1)
				(type default)
			)
			(layer "F.Fab")
		)
		(fp_line
			(start 0.120396 0.3048)
			(end 0.120396 0.2794)
			(stroke
				(width 0.1)
				(type default)
			)
			(layer "F.Fab")
		)
		(fp_line
			(start 0.67945 0.3048)
			(end 0.120396 0.3048)
			(stroke
				(width 0.1)
				(type default)
			)
			(layer "F.Fab")
		)
		(fp_line
			(start -0.12065 0.2794)
			(end -0.12065 0.3048)
			(stroke
				(width 0.1)
				(type default)
			)
			(layer "F.Fab")
		)
		(fp_line
			(start 0.120396 0.2794)
			(end -0.12065 0.2794)
			(stroke
				(width 0.1)
				(type default)
			)
			(layer "F.Fab")
		)
		(fp_line
			(start -0.12065 -0.2794)
			(end 0.12065 -0.2794)
			(stroke
				(width 0.1)
				(type default)
			)
			(layer "F.Fab")
		)
		(fp_line
			(start 0.12065 -0.2794)
			(end 0.12065 -0.3048)
			(stroke
				(width 0.1)
				(type default)
			)
			(layer "F.Fab")
		)
		(fp_line
			(start 0.12065 -0.3048)
			(end 0.67945 -0.3048)
			(stroke
				(width 0.1)
				(type default)
			)
			(layer "F.Fab")
		)
		(fp_line
			(start 0.67945 -0.3048)
			(end 0.67945 0.3048)
			(stroke
				(width 0.1)
				(type default)
			)
			(layer "F.Fab")
		)
		(fp_line
			(start -0.67945 -0.305054)
			(end -0.12065 -0.305054)
			(stroke
				(width 0.1)
				(type default)
			)
			(layer "F.Fab")
		)
		(fp_line
			(start -0.12065 -0.305054)
			(end -0.12065 -0.2794)
			(stroke
				(width 0.1)
				(type default)
			)
			(layer "F.Fab")
		)
		(pad "1" smd circle
			(at -0.40005 0 270)
			(size 0 0)
			(layers "F.Cu" "F.Mask" "F.Paste")
			(net "PVDDCR_CPU1_P0_PVCC")
		)
		(pad "2" smd circle
			(at 0.40005 0 270)
			(size 0 0)
			(layers "F.Cu" "F.Mask" "F.Paste")
			(net "GND")
		)
	)
	(footprint ""
		(layer "F.Cu")
		(at 59.18073 -351.578672 90)
		(property "Reference" "PC403_4"
			(at 0 0 90)
			(layer "F.SilkS")
			(hide yes)
			(effects
				(font
					(size 1.27 1.27)
				)
			)
		)
		(property "Value" ""
			(at 0 0 90)
			(layer "F.Fab")
			(effects
				(font
					(size 1.27 1.27)
				)
			)
		)
		(duplicate_pad_numbers_are_jumpers no)
		(fp_line
			(start 0.7874 -0.4064)
			(end 0.7874 0.4064)
			(stroke
				(width 0.1524)
				(type default)
			)
			(layer "F.SilkS")
		)
		(fp_line
			(start -0.7874 -0.4064)
			(end 0.7874 -0.4064)
			(stroke
				(width 0.1524)
				(type default)
			)
			(layer "F.SilkS")
		)
		(fp_line
			(start 0.7874 0.4064)
			(end -0.7874 0.4064)
			(stroke
				(width 0.1524)
				(type default)
			)
			(layer "F.SilkS")
		)
		(fp_line
			(start -0.7874 0.4064)
			(end -0.7874 -0.4064)
			(stroke
				(width 0.1524)
				(type default)
			)
			(layer "F.SilkS")
		)
		(fp_line
			(start -0.12065 -0.305054)
			(end -0.12065 -0.2794)
			(stroke
				(width 0.1)
				(type default)
			)
			(layer "F.Fab")
		)
		(fp_line
			(start -0.67945 -0.305054)
			(end -0.12065 -0.305054)
			(stroke
				(width 0.1)
				(type default)
			)
			(layer "F.Fab")
		)
		(fp_line
			(start 0.67945 -0.3048)
			(end 0.67945 0.3048)
			(stroke
				(width 0.1)
				(type default)
			)
			(layer "F.Fab")
		)
		(fp_line
			(start 0.12065 -0.3048)
			(end 0.67945 -0.3048)
			(stroke
				(width 0.1)
				(type default)
			)
			(layer "F.Fab")
		)
		(fp_line
			(start 0.12065 -0.2794)
			(end 0.12065 -0.3048)
			(stroke
				(width 0.1)
				(type default)
			)
			(layer "F.Fab")
		)
		(fp_line
			(start -0.12065 -0.2794)
			(end 0.12065 -0.2794)
			(stroke
				(width 0.1)
				(type default)
			)
			(layer "F.Fab")
		)
		(fp_line
			(start 0.120396 0.2794)
			(end -0.12065 0.2794)
			(stroke
				(width 0.1)
				(type default)
			)
			(layer "F.Fab")
		)
		(fp_line
			(start -0.12065 0.2794)
			(end -0.12065 0.3048)
			(stroke
				(width 0.1)
				(type default)
			)
			(layer "F.Fab")
		)
		(fp_line
			(start 0.67945 0.3048)
			(end 0.120396 0.3048)
			(stroke
				(width 0.1)
				(type default)
			)
			(layer "F.Fab")
		)
		(fp_line
			(start 0.120396 0.3048)
			(end 0.120396 0.2794)
			(stroke
				(width 0.1)
				(type default)
			)
			(layer "F.Fab")
		)
		(fp_line
			(start -0.12065 0.3048)
			(end -0.67945 0.3048)
			(stroke
				(width 0.1)
				(type default)
			)
			(layer "F.Fab")
		)
		(fp_line
			(start -0.67945 0.3048)
			(end -0.67945 -0.305054)
			(stroke
				(width 0.1)
				(type default)
			)
			(layer "F.Fab")
		)
		(pad "1" smd circle
			(at -0.40005 0 90)
			(size 0 0)
			(layers "F.Cu" "F.Mask" "F.Paste")
			(net "PVDDCR_CPU1_P1_VCCS")
		)
		(pad "2" smd circle
			(at 0.40005 0 90)
			(size 0 0)
			(layers "F.Cu" "F.Mask" "F.Paste")
			(net "GND")
		)
	)
	(footprint ""
		(layer "F.Cu")
		(at 32.272478 -16.099536 90)
		(property "Reference" "C690"
			(at 0 0 90)
			(layer "F.SilkS")
			(hide yes)
			(effects
				(font
					(size 1.27 1.27)
				)
			)
		)
		(property "Value" ""
			(at 0 0 90)
			(layer "F.Fab")
			(effects
				(font
					(size 1.27 1.27)
				)
			)
		)
		(duplicate_pad_numbers_are_jumpers no)
		(fp_line
			(start 0.299974 -0.150114)
			(end 0.299974 0.150114)
			(stroke
				(width 0.1)
				(type default)
			)
			(layer "F.Fab")
		)
		(fp_line
			(start -0.299974 -0.150114)
			(end 0.299974 -0.150114)
			(stroke
				(width 0.1)
				(type default)
			)
			(layer "F.Fab")
		)
		(fp_line
			(start 0.299974 0.150114)
			(end -0.299974 0.150114)
			(stroke
				(width 0.1)
				(type default)
			)
			(layer "F.Fab")
		)
		(fp_line
			(start -0.299974 0.150114)
			(end -0.299974 -0.150114)
			(stroke
				(width 0.1)
				(type default)
			)
			(layer "F.Fab")
		)
		(pad "1" smd rect
			(at -0.2667 0 90)
			(size 0.3048 0.381)
			(layers "F.Cu" "F.Mask" "F.Paste")
			(net "P5E_CPU1_G1_TX_C_DN<9>")
		)
		(pad "2" smd rect
			(at 0.2667 0 90)
			(size 0.3048 0.381)
			(layers "F.Cu" "F.Mask" "F.Paste")
			(net "P5E_CPU1_G1_TX_DN<9>")
		)
	)
	(footprint ""
		(layer "F.Cu")
		(at 220.98508 -106.35488)
		(property "Reference" "R1518"
			(at 0 0 0)
			(layer "F.SilkS")
			(hide yes)
			(effects
				(font
					(size 1.27 1.27)
				)
			)
		)
		(property "Value" ""
			(at 0 0 0)
			(layer "F.Fab")
			(effects
				(font
					(size 1.27 1.27)
				)
			)
		)
		(duplicate_pad_numbers_are_jumpers no)
		(fp_line
			(start -0.7874 -0.4064)
			(end 0.7874 -0.4064)
			(stroke
				(width 0.1524)
				(type default)
			)
			(layer "F.SilkS")
		)
		(fp_line
			(start -0.7874 0.4064)
			(end -0.7874 -0.4064)
			(stroke
				(width 0.1524)
				(type default)
			)
			(layer "F.SilkS")
		)
		(fp_line
			(start 0.7874 -0.4064)
			(end 0.7874 0.4064)
			(stroke
				(width 0.1524)
				(type default)
			)
			(layer "F.SilkS")
		)
		(fp_line
			(start 0.7874 0.4064)
			(end -0.7874 0.4064)
			(stroke
				(width 0.1524)
				(type default)
			)
			(layer "F.SilkS")
		)
		(fp_line
			(start -0.67945 -0.305054)
			(end -0.12065 -0.305054)
			(stroke
				(width 0.1)
				(type default)
			)
			(layer "F.Fab")
		)
		(fp_line
			(start -0.67945 0.3048)
			(end -0.67945 -0.305054)
			(stroke
				(width 0.1)
				(type default)
			)
			(layer "F.Fab")
		)
		(fp_line
			(start -0.12065 -0.305054)
			(end -0.12065 -0.2794)
			(stroke
				(width 0.1)
				(type default)
			)
			(layer "F.Fab")
		)
		(fp_line
			(start -0.12065 -0.2794)
			(end 0.12065 -0.2794)
			(stroke
				(width 0.1)
				(type default)
			)
			(layer "F.Fab")
		)
		(fp_line
			(start -0.12065 0.2794)
			(end -0.12065 0.3048)
			(stroke
				(width 0.1)
				(type default)
			)
			(layer "F.Fab")
		)
		(fp_line
			(start -0.12065 0.3048)
			(end -0.67945 0.3048)
			(stroke
				(width 0.1)
				(type default)
			)
			(layer "F.Fab")
		)
		(fp_line
			(start 0.120396 0.2794)
			(end -0.12065 0.2794)
			(stroke
				(width 0.1)
				(type default)
			)
			(layer "F.Fab")
		)
		(fp_line
			(start 0.120396 0.3048)
			(end 0.120396 0.2794)
			(stroke
				(width 0.1)
				(type default)
			)
			(layer "F.Fab")
		)
		(fp_line
			(start 0.12065 -0.3048)
			(end 0.67945 -0.3048)
			(stroke
				(width 0.1)
				(type default)
			)
			(layer "F.Fab")
		)
		(fp_line
			(start 0.12065 -0.2794)
			(end 0.12065 -0.3048)
			(stroke
				(width 0.1)
				(type default)
			)
			(layer "F.Fab")
		)
		(fp_line
			(start 0.67945 -0.3048)
			(end 0.67945 0.3048)
			(stroke
				(width 0.1)
				(type default)
			)
			(layer "F.Fab")
		)
		(fp_line
			(start 0.67945 0.3048)
			(end 0.120396 0.3048)
			(stroke
				(width 0.1)
				(type default)
			)
			(layer "F.Fab")
		)
		(pad "1" smd circle
			(at -0.40005 0)
			(size 0 0)
			(layers "F.Cu" "F.Mask" "F.Paste")
			(net "HP_LVC3_OCP_V3_1_PWRGD_R2")
		)
		(pad "2" smd circle
			(at 0.40005 0)
			(size 0 0)
			(layers "F.Cu" "F.Mask" "F.Paste")
			(net "OCP_V3_1_P3V3_R3_PWRGD")
		)
	)
	(footprint ""
		(layer "F.Cu")
		(at 279.527 -417.195 180)
		(property "Reference" "R4490"
			(at 0 0 180)
			(layer "F.SilkS")
			(hide yes)
			(effects
				(font
					(size 1.27 1.27)
				)
			)
		)
		(property "Value" ""
			(at 0 0 180)
			(layer "F.Fab")
			(effects
				(font
					(size 1.27 1.27)
				)
			)
		)
		(duplicate_pad_numbers_are_jumpers no)
		(fp_line
			(start 0.7874 0.4064)
			(end -0.7874 0.4064)
			(stroke
				(width 0.1524)
				(type default)
			)
			(layer "F.SilkS")
		)
		(fp_line
			(start 0.7874 -0.4064)
			(end 0.7874 0.4064)
			(stroke
				(width 0.1524)
				(type default)
			)
			(layer "F.SilkS")
		)
		(fp_line
			(start -0.7874 0.4064)
			(end -0.7874 -0.4064)
			(stroke
				(width 0.1524)
				(type default)
			)
			(layer "F.SilkS")
		)
		(fp_line
			(start -0.7874 -0.4064)
			(end 0.7874 -0.4064)
			(stroke
				(width 0.1524)
				(type default)
			)
			(layer "F.SilkS")
		)
		(fp_line
			(start 0.67945 0.3048)
			(end 0.120396 0.3048)
			(stroke
				(width 0.1)
				(type default)
			)
			(layer "F.Fab")
		)
		(fp_line
			(start 0.67945 -0.3048)
			(end 0.67945 0.3048)
			(stroke
				(width 0.1)
				(type default)
			)
			(layer "F.Fab")
		)
		(fp_line
			(start 0.12065 -0.2794)
			(end 0.12065 -0.3048)
			(stroke
				(width 0.1)
				(type default)
			)
			(layer "F.Fab")
		)
		(fp_line
			(start 0.12065 -0.3048)
			(end 0.67945 -0.3048)
			(stroke
				(width 0.1)
				(type default)
			)
			(layer "F.Fab")
		)
		(fp_line
			(start 0.120396 0.3048)
			(end 0.120396 0.2794)
			(stroke
				(width 0.1)
				(type default)
			)
			(layer "F.Fab")
		)
		(fp_line
			(start 0.120396 0.2794)
			(end -0.12065 0.2794)
			(stroke
				(width 0.1)
				(type default)
			)
			(layer "F.Fab")
		)
		(fp_line
			(start -0.12065 0.3048)
			(end -0.67945 0.3048)
			(stroke
				(width 0.1)
				(type default)
			)
			(layer "F.Fab")
		)
		(fp_line
			(start -0.12065 0.2794)
			(end -0.12065 0.3048)
			(stroke
				(width 0.1)
				(type default)
			)
			(layer "F.Fab")
		)
		(fp_line
			(start -0.12065 -0.2794)
			(end 0.12065 -0.2794)
			(stroke
				(width 0.1)
				(type default)
			)
			(layer "F.Fab")
		)
		(fp_line
			(start -0.12065 -0.305054)
			(end -0.12065 -0.2794)
			(stroke
				(width 0.1)
				(type default)
			)
			(layer "F.Fab")
		)
		(fp_line
			(start -0.67945 0.3048)
			(end -0.67945 -0.305054)
			(stroke
				(width 0.1)
				(type default)
			)
			(layer "F.Fab")
		)
		(fp_line
			(start -0.67945 -0.305054)
			(end -0.12065 -0.305054)
			(stroke
				(width 0.1)
				(type default)
			)
			(layer "F.Fab")
		)
		(pad "1" smd circle
			(at -0.40005 0 180)
			(size 0 0)
			(layers "F.Cu" "F.Mask" "F.Paste")
			(net "CLK_9ZXL045_P0_SADR0")
		)
		(pad "2" smd circle
			(at 0.40005 0 180)
			(size 0 0)
			(layers "F.Cu" "F.Mask" "F.Paste")
			(net "GND")
		)
	)
	(footprint ""
		(layer "F.Cu")
		(at 352.853244 -381.41783 -90)
		(property "Reference" "C942"
			(at 0 0 270)
			(layer "F.SilkS")
			(hide yes)
			(effects
				(font
					(size 1.27 1.27)
				)
			)
		)
		(property "Value" ""
			(at 0 0 270)
			(layer "F.Fab")
			(effects
				(font
					(size 1.27 1.27)
				)
			)
		)
		(duplicate_pad_numbers_are_jumpers no)
		(fp_line
			(start -0.299974 0.150114)
			(end -0.299974 -0.150114)
			(stroke
				(width 0.1)
				(type default)
			)
			(layer "F.Fab")
		)
		(fp_line
			(start 0.299974 0.150114)
			(end -0.299974 0.150114)
			(stroke
				(width 0.1)
				(type default)
			)
			(layer "F.Fab")
		)
		(fp_line
			(start -0.299974 -0.150114)
			(end 0.299974 -0.150114)
			(stroke
				(width 0.1)
				(type default)
			)
			(layer "F.Fab")
		)
		(fp_line
			(start 0.299974 -0.150114)
			(end 0.299974 0.150114)
			(stroke
				(width 0.1)
				(type default)
			)
			(layer "F.Fab")
		)
		(pad "1" smd rect
			(at -0.2667 0 270)
			(size 0.3048 0.381)
			(layers "F.Cu" "F.Mask" "F.Paste")
			(net "P5E_CPU0_P1_TX_C_DN<11>")
		)
		(pad "2" smd rect
			(at 0.2667 0 270)
			(size 0.3048 0.381)
			(layers "F.Cu" "F.Mask" "F.Paste")
			(net "P5E_CPU0_P1_TX_DN<11>")
		)
	)
	(footprint ""
		(layer "F.Cu")
		(at 381.749808 -440.489848)
		(property "Reference" "J106"
			(at -7.604506 17.991328 0)
			(unlocked yes)
			(layer "F.SilkS")
			(effects
				(font
					(size 0.7874 0.5842)
					(thickness 0.1524)
				)
				(justify left)
			)
		)
		(property "Value" ""
			(at 0 0 0)
			(layer "F.Fab")
			(effects
				(font
					(size 1.27 1.27)
				)
			)
		)
		(duplicate_pad_numbers_are_jumpers no)
		(fp_line
			(start -4.249928 19.154648)
			(end -4.249928 -0.484124)
			(stroke
				(width 0.1524)
				(type default)
			)
			(layer "F.SilkS")
		)
		(fp_line
			(start -1.918208 22.400006)
			(end -3.797808 22.400006)
			(stroke
				(width 0.1524)
				(type default)
			)
			(layer "F.SilkS")
		)
		(fp_line
			(start -1.249934 -1.500124)
			(end 15.649956 -1.500124)
			(stroke
				(width 0.1524)
				(type default)
			)
			(layer "F.SilkS")
		)
		(fp_line
			(start -1.249934 -0.484124)
			(end -1.249934 19.400012)
			(stroke
				(width 0.1524)
				(type default)
			)
			(layer "F.SilkS")
		)
		(fp_line
			(start -0.343408 19.400012)
			(end 0.926592 19.400012)
			(stroke
				(width 0.1524)
				(type default)
			)
			(layer "F.SilkS")
		)
		(fp_line
			(start 0.0254 -0.9144)
			(end 1.0414 -0.9144)
			(stroke
				(width 0.1524)
				(type default)
			)
			(layer "F.SilkS")
		)
		(fp_line
			(start 0.5334 -1.4224)
			(end 0.0254 -0.9144)
			(stroke
				(width 0.1524)
				(type default)
			)
			(layer "F.SilkS")
		)
		(fp_line
			(start 0.5334 -1.4224)
			(end 0.5334 -0.5588)
			(stroke
				(width 0.1524)
				(type default)
			)
			(layer "F.SilkS")
		)
		(fp_line
			(start 0.5334 -0.5588)
			(end 1.8034 -0.5588)
			(stroke
				(width 0.1524)
				(type default)
			)
			(layer "F.SilkS")
		)
		(fp_line
			(start 1.0414 -0.9144)
			(end 0.5334 -1.4224)
			(stroke
				(width 0.1524)
				(type default)
			)
			(layer "F.SilkS")
		)
		(fp_line
			(start 1.155192 22.400006)
			(end -0.521208 22.400006)
			(stroke
				(width 0.1524)
				(type default)
			)
			(layer "F.SilkS")
		)
		(fp_line
			(start 1.8034 -0.5588)
			(end 2.032 -0.7874)
			(stroke
				(width 0.1524)
				(type default)
			)
			(layer "F.SilkS")
		)
		(fp_line
			(start 2.679192 19.400012)
			(end 3.999992 19.400012)
			(stroke
				(width 0.1524)
				(type default)
			)
			(layer "F.SilkS")
		)
		(fp_line
			(start 4.253992 22.400006)
			(end 2.526792 22.400006)
			(stroke
				(width 0.1524)
				(type default)
			)
			(layer "F.SilkS")
		)
		(fp_line
			(start 5.625592 19.400012)
			(end 7.149592 19.400012)
			(stroke
				(width 0.1524)
				(type default)
			)
			(layer "F.SilkS")
		)
		(fp_line
			(start 7.276592 22.400006)
			(end 5.600192 22.400006)
			(stroke
				(width 0.1524)
				(type default)
			)
			(layer "F.SilkS")
		)
		(fp_line
			(start 8.749792 19.400012)
			(end 10.095992 19.400012)
			(stroke
				(width 0.1524)
				(type default)
			)
			(layer "F.SilkS")
		)
		(fp_line
			(start 10.299192 22.400006)
			(end 8.622792 22.400006)
			(stroke
				(width 0.1524)
				(type default)
			)
			(layer "F.SilkS")
		)
		(fp_line
			(start 11.823192 19.400012)
			(end 13.270992 19.400012)
			(stroke
				(width 0.1524)
				(type default)
			)
			(layer "F.SilkS")
		)
		(fp_line
			(start 13.423392 22.400006)
			(end 11.772392 22.400006)
			(stroke
				(width 0.1524)
				(type default)
			)
			(layer "F.SilkS")
		)
		(fp_line
			(start 14.896592 19.400012)
			(end 15.649956 19.400012)
			(stroke
				(width 0.1524)
				(type default)
			)
			(layer "F.SilkS")
		)
		(fp_line
			(start 15.649956 19.400012)
			(end 15.649956 17.071848)
			(stroke
				(width 0.1524)
				(type default)
			)
			(layer "F.SilkS")
		)
		(fp_line
			(start 16.471392 22.400006)
			(end 14.820392 22.400006)
			(stroke
				(width 0.1524)
				(type default)
			)
			(layer "F.SilkS")
		)
		(fp_line
			(start 18.64995 16.911828)
			(end 18.64995 22.400006)
			(stroke
				(width 0.1524)
				(type default)
			)
			(layer "F.SilkS")
		)
		(fp_line
			(start 18.64995 22.400006)
			(end 17.842992 22.400006)
			(stroke
				(width 0.1524)
				(type default)
			)
			(layer "F.SilkS")
		)
		(fp_poly
			(pts
				(xy -1.654048 0) (xy -2.670048 0.508) (xy -2.670048 -0.508)
			)
			(stroke
				(width 0)
				(type default)
			)
			(fill yes)
			(layer "F.SilkS")
		)
		(fp_line
			(start -4.249928 -11.999976)
			(end 18.64995 -11.999976)
			(stroke
				(width 0.1524)
				(type default)
			)
			(layer "B.SilkS")
		)
		(fp_line
			(start -4.249928 11.483848)
			(end -4.249928 -11.999976)
			(stroke
				(width 0.1524)
				(type default)
			)
			(layer "B.SilkS")
		)
		(fp_line
			(start -4.249928 22.400006)
			(end -4.249928 12.931648)
			(stroke
				(width 0.1524)
				(type default)
			)
			(layer "B.SilkS")
		)
		(fp_line
			(start -3.594608 22.400006)
			(end -4.249928 22.400006)
			(stroke
				(width 0.1524)
				(type default)
			)
			(layer "B.SilkS")
		)
		(fp_line
			(start -0.521208 22.400006)
			(end -1.969008 22.400006)
			(stroke
				(width 0.1524)
				(type default)
			)
			(layer "B.SilkS")
		)
		(fp_line
			(start 2.628392 22.400006)
			(end 1.104392 22.400006)
			(stroke
				(width 0.1524)
				(type default)
			)
			(layer "B.SilkS")
		)
		(fp_line
			(start 5.752592 22.400006)
			(end 4.126992 22.400006)
			(stroke
				(width 0.1524)
				(type default)
			)
			(layer "B.SilkS")
		)
		(fp_line
			(start 8.597392 22.400006)
			(end 7.098792 22.400006)
			(stroke
				(width 0.1524)
				(type default)
			)
			(layer "B.SilkS")
		)
		(fp_line
			(start 11.746992 22.400006)
			(end 10.197592 22.400006)
			(stroke
				(width 0.1524)
				(type default)
			)
			(layer "B.SilkS")
		)
		(fp_line
			(start 14.896592 22.400006)
			(end 13.245592 22.400006)
			(stroke
				(width 0.1524)
				(type default)
			)
			(layer "B.SilkS")
		)
		(fp_line
			(start 17.868392 22.400006)
			(end 16.395192 22.400006)
			(stroke
				(width 0.1524)
				(type default)
			)
			(layer "B.SilkS")
		)
		(fp_line
			(start 18.64995 -11.999976)
			(end 18.64995 -0.990092)
			(stroke
				(width 0.1524)
				(type default)
			)
			(layer "B.SilkS")
		)
		(fp_line
			(start 18.64995 17.064228)
			(end 18.64995 21.821648)
			(stroke
				(width 0.1524)
				(type default)
			)
			(layer "B.SilkS")
		)
		(fp_line
			(start -4.249928 -11.999976)
			(end 18.64995 -11.999976)
			(stroke
				(width 0.1)
				(type default)
			)
			(layer "B.Fab")
		)
		(fp_line
			(start -4.249928 22.400006)
			(end -4.249928 -11.999976)
			(stroke
				(width 0.1)
				(type default)
			)
			(layer "B.Fab")
		)
		(fp_line
			(start 18.64995 -11.999976)
			(end 18.64995 22.400006)
			(stroke
				(width 0.1)
				(type default)
			)
			(layer "B.Fab")
		)
		(fp_line
			(start 18.64995 22.400006)
			(end -4.249928 22.400006)
			(stroke
				(width 0.1)
				(type default)
			)
			(layer "B.Fab")
		)
		(fp_line
			(start -1.249934 -8.999982)
			(end -1.249934 19.400012)
			(stroke
				(width 0.1)
				(type default)
			)
			(layer "F.Fab")
		)
		(fp_line
			(start -1.249934 19.400012)
			(end 15.649956 19.400012)
			(stroke
				(width 0.1)
				(type default)
			)
			(layer "F.Fab")
		)
		(fp_line
			(start 15.649956 -8.999982)
			(end -1.249934 -8.999982)
			(stroke
				(width 0.1)
				(type default)
			)
			(layer "F.Fab")
		)
		(fp_line
			(start 15.649956 19.400012)
			(end 15.649956 -8.999982)
			(stroke
				(width 0.1)
				(type default)
			)
			(layer "F.Fab")
		)
		(fp_poly
			(pts
				(xy -2.670048 -0.508) (xy -2.670048 0.508) (xy -1.654048 0)
			)
			(stroke
				(width 0)
				(type default)
			)
			(fill yes)
			(layer "F.Fab")
		)
		(fp_text user "PRESS-FIT"
			(at -3.618484 10.456418 90)
			(unlocked yes)
			(layer "F.SilkS")
			(effects
				(font
					(size 0.7874 0.5842)
					(thickness 0.1524)
				)
				(justify left)
			)
		)
		(fp_text user "B"
			(at -2.253742 1.199896 90)
			(unlocked yes)
			(layer "F.SilkS")
			(effects
				(font
					(size 0.7874 0.5842)
					(thickness 0.1524)
				)
			)
		)
		(fp_text user "C"
			(at -2.253742 2.400046 90)
			(unlocked yes)
			(layer "F.SilkS")
			(effects
				(font
					(size 0.7874 0.5842)
					(thickness 0.1524)
				)
			)
		)
		(fp_text user "D"
			(at -2.253742 3.599942 90)
			(unlocked yes)
			(layer "F.SilkS")
			(effects
				(font
					(size 0.7874 0.5842)
					(thickness 0.1524)
				)
			)
		)
		(fp_text user "E"
			(at -2.253742 4.800092 90)
			(unlocked yes)
			(layer "F.SilkS")
			(effects
				(font
					(size 0.7874 0.5842)
					(thickness 0.1524)
				)
			)
		)
		(fp_text user "F"
			(at -2.253742 5.999988 90)
			(unlocked yes)
			(layer "F.SilkS")
			(effects
				(font
					(size 0.7874 0.5842)
					(thickness 0.1524)
				)
			)
		)
		(fp_text user "G"
			(at -2.253742 7.199884 90)
			(unlocked yes)
			(layer "F.SilkS")
			(effects
				(font
					(size 0.7874 0.5842)
					(thickness 0.1524)
				)
			)
		)
		(fp_text user "H"
			(at -2.253742 8.400034 90)
			(unlocked yes)
			(layer "F.SilkS")
			(effects
				(font
					(size 0.7874 0.5842)
					(thickness 0.1524)
				)
			)
		)
		(fp_text user "I"
			(at -2.253742 9.59993 90)
			(unlocked yes)
			(layer "F.SilkS")
			(effects
				(font
					(size 0.7874 0.5842)
					(thickness 0.1524)
				)
			)
		)
		(fp_text user "J"
			(at -2.253742 10.80008 90)
			(unlocked yes)
			(layer "F.SilkS")
			(effects
				(font
					(size 0.7874 0.5842)
					(thickness 0.1524)
				)
			)
		)
		(fp_text user "K"
			(at -2.253742 11.999976 90)
			(unlocked yes)
			(layer "F.SilkS")
			(effects
				(font
					(size 0.7874 0.5842)
					(thickness 0.1524)
				)
			)
		)
		(fp_text user "L"
			(at -2.253742 13.200126 90)
			(unlocked yes)
			(layer "F.SilkS")
			(effects
				(font
					(size 0.7874 0.5842)
					(thickness 0.1524)
				)
			)
		)
		(fp_text user "M"
			(at -2.253742 14.400022 90)
			(unlocked yes)
			(layer "F.SilkS")
			(effects
				(font
					(size 0.7874 0.5842)
					(thickness 0.1524)
				)
			)
		)
		(fp_text user "N"
			(at -2.253742 15.599918 90)
			(unlocked yes)
			(layer "F.SilkS")
			(effects
				(font
					(size 0.7874 0.5842)
					(thickness 0.1524)
				)
			)
		)
		(fp_text user "1"
			(at 0.111252 19.8628 90)
			(unlocked yes)
			(layer "F.SilkS")
			(effects
				(font
					(size 0.7874 0.5842)
					(thickness 0.1524)
				)
			)
		)
		(fp_text user "EDGE OF DAUGHTER CARD"
			(at 2.2479 -0.899668 0)
			(unlocked yes)
			(layer "F.SilkS")
			(effects
				(font
					(size 0.635 0.4064)
					(thickness 0.1524)
				)
				(justify left)
			)
		)
		(fp_text user "2"
			(at 2.756662 20.018248 90)
			(unlocked yes)
			(layer "F.SilkS")
			(effects
				(font
					(size 0.7874 0.5842)
					(thickness 0.1524)
				)
			)
		)
		(fp_text user "3"
			(at 3.950462 20.018248 90)
			(unlocked yes)
			(layer "F.SilkS")
			(effects
				(font
					(size 0.7874 0.5842)
					(thickness 0.1524)
				)
			)
		)
		(fp_text user "4"
			(at 5.906262 20.043648 90)
			(unlocked yes)
			(layer "F.SilkS")
			(effects
				(font
					(size 0.7874 0.5842)
					(thickness 0.1524)
				)
			)
		)
		(fp_text user "5"
			(at 9.005062 20.018248 90)
			(unlocked yes)
			(layer "F.SilkS")
			(effects
				(font
					(size 0.7874 0.5842)
					(thickness 0.1524)
				)
			)
		)
		(fp_text user "6"
			(at 10.173462 20.018248 90)
			(unlocked yes)
			(layer "F.SilkS")
			(effects
				(font
					(size 0.7874 0.5842)
					(thickness 0.1524)
				)
			)
		)
		(fp_text user "7"
			(at 12.053062 20.069048 90)
			(unlocked yes)
			(layer "F.SilkS")
			(effects
				(font
					(size 0.7874 0.5842)
					(thickness 0.1524)
				)
			)
		)
		(fp_text user "8"
			(at 14.999462 20.069048 90)
			(unlocked yes)
			(layer "F.SilkS")
			(effects
				(font
					(size 0.7874 0.5842)
					(thickness 0.1524)
				)
			)
		)
		(fp_text user "PRESS-FIT"
			(at -2.927858 -0.581152 90)
			(unlocked yes)
			(layer "B.SilkS")
			(effects
				(font
					(size 1.905 1.4224)
					(thickness 0.1524)
				)
				(justify left mirror)
			)
		)
		(fp_text user "A"
			(at -1.199134 0 90)
			(unlocked yes)
			(layer "B.SilkS")
			(effects
				(font
					(size 0.7874 0.5842)
					(thickness 0.1524)
				)
				(justify mirror)
			)
		)
		(fp_text user "G"
			(at -1.173734 7.4168 90)
			(unlocked yes)
			(layer "B.SilkS")
			(effects
				(font
					(size 0.7874 0.5842)
					(thickness 0.1524)
				)
				(justify mirror)
			)
		)
		(fp_text user "H"
			(at -1.148334 8.636 90)
			(unlocked yes)
			(layer "B.SilkS")
			(effects
				(font
					(size 0.7874 0.5842)
					(thickness 0.1524)
				)
				(justify mirror)
			)
		)
		(fp_text user "B"
			(at -1.14681 1.326896 90)
			(unlocked yes)
			(layer "B.SilkS")
			(effects
				(font
					(size 0.7874 0.5842)
					(thickness 0.1524)
				)
				(justify mirror)
			)
		)
		(fp_text user "C"
			(at -1.14681 2.527046 90)
			(unlocked yes)
			(layer "B.SilkS")
			(effects
				(font
					(size 0.7874 0.5842)
					(thickness 0.1524)
				)
				(justify mirror)
			)
		)
		(fp_text user "D"
			(at -1.14681 3.726942 90)
			(unlocked yes)
			(layer "B.SilkS")
			(effects
				(font
					(size 0.7874 0.5842)
					(thickness 0.1524)
				)
				(justify mirror)
			)
		)
		(fp_text user "E"
			(at -1.14681 4.927092 90)
			(unlocked yes)
			(layer "B.SilkS")
			(effects
				(font
					(size 0.7874 0.5842)
					(thickness 0.1524)
				)
				(justify mirror)
			)
		)
		(fp_text user "F"
			(at -1.14681 6.126988 90)
			(unlocked yes)
			(layer "B.SilkS")
			(effects
				(font
					(size 0.7874 0.5842)
					(thickness 0.1524)
				)
				(justify mirror)
			)
		)
		(fp_text user "I"
			(at -1.14681 9.72693 90)
			(unlocked yes)
			(layer "B.SilkS")
			(effects
				(font
					(size 0.7874 0.5842)
					(thickness 0.1524)
				)
				(justify mirror)
			)
		)
		(fp_text user "J"
			(at -1.14681 10.92708 90)
			(unlocked yes)
			(layer "B.SilkS")
			(effects
				(font
					(size 0.7874 0.5842)
					(thickness 0.1524)
				)
				(justify mirror)
			)
		)
		(fp_text user "K"
			(at -1.14681 12.126976 90)
			(unlocked yes)
			(layer "B.SilkS")
			(effects
				(font
					(size 0.7874 0.5842)
					(thickness 0.1524)
				)
				(justify mirror)
			)
		)
		(fp_text user "L"
			(at -1.14681 13.327126 90)
			(unlocked yes)
			(layer "B.SilkS")
			(effects
				(font
					(size 0.7874 0.5842)
					(thickness 0.1524)
				)
				(justify mirror)
			)
		)
		(fp_text user "M"
			(at -1.14681 14.527022 90)
			(unlocked yes)
			(layer "B.SilkS")
			(effects
				(font
					(size 0.7874 0.5842)
					(thickness 0.1524)
				)
				(justify mirror)
			)
		)
		(fp_text user "N"
			(at -1.14681 15.726918 90)
			(unlocked yes)
			(layer "B.SilkS")
			(effects
				(font
					(size 0.7874 0.5842)
					(thickness 0.1524)
				)
				(justify mirror)
			)
		)
		(fp_text user "1"
			(at 0.060452 16.764 90)
			(unlocked yes)
			(layer "B.SilkS")
			(effects
				(font
					(size 0.7874 0.5842)
					(thickness 0.1524)
				)
				(justify mirror)
			)
		)
		(fp_text user "2"
			(at 2.060448 16.764 90)
			(unlocked yes)
			(layer "B.SilkS")
			(effects
				(font
					(size 0.7874 0.5842)
					(thickness 0.1524)
				)
				(justify mirror)
			)
		)
		(fp_text user "3"
			(at 4.060444 16.764 90)
			(unlocked yes)
			(layer "B.SilkS")
			(effects
				(font
					(size 0.7874 0.5842)
					(thickness 0.1524)
				)
				(justify mirror)
			)
		)
		(fp_text user "4"
			(at 6.06044 16.764 90)
			(unlocked yes)
			(layer "B.SilkS")
			(effects
				(font
					(size 0.7874 0.5842)
					(thickness 0.1524)
				)
				(justify mirror)
			)
		)
		(fp_text user "5"
			(at 8.060436 16.764 90)
			(unlocked yes)
			(layer "B.SilkS")
			(effects
				(font
					(size 0.7874 0.5842)
					(thickness 0.1524)
				)
				(justify mirror)
			)
		)
		(fp_text user "6"
			(at 10.060432 16.764 90)
			(unlocked yes)
			(layer "B.SilkS")
			(effects
				(font
					(size 0.7874 0.5842)
					(thickness 0.1524)
				)
				(justify mirror)
			)
		)
		(fp_text user "7"
			(at 12.060428 16.764 90)
			(unlocked yes)
			(layer "B.SilkS")
			(effects
				(font
					(size 0.7874 0.5842)
					(thickness 0.1524)
				)
				(justify mirror)
			)
		)
		(fp_text user "8"
			(at 14.060424 16.764 90)
			(unlocked yes)
			(layer "B.SilkS")
			(effects
				(font
					(size 0.7874 0.5842)
					(thickness 0.1524)
				)
				(justify mirror)
			)
		)
		(fp_text user "A"
			(at -1.199134 0 90)
			(unlocked yes)
			(layer "B.Fab")
			(effects
				(font
					(size 0.7874 0.5842)
					(thickness 0.1524)
				)
				(justify mirror)
			)
		)
		(fp_text user "G"
			(at -1.173734 7.4168 90)
			(unlocked yes)
			(layer "B.Fab")
			(effects
				(font
					(size 0.7874 0.5842)
					(thickness 0.1524)
				)
				(justify mirror)
			)
		)
		(fp_text user "H"
			(at -1.148334 8.636 90)
			(unlocked yes)
			(layer "B.Fab")
			(effects
				(font
					(size 0.7874 0.5842)
					(thickness 0.1524)
				)
				(justify mirror)
			)
		)
		(fp_text user "B"
			(at -1.14681 1.326896 90)
			(unlocked yes)
			(layer "B.Fab")
			(effects
				(font
					(size 0.7874 0.5842)
					(thickness 0.1524)
				)
				(justify mirror)
			)
		)
		(fp_text user "C"
			(at -1.14681 2.527046 90)
			(unlocked yes)
			(layer "B.Fab")
			(effects
				(font
					(size 0.7874 0.5842)
					(thickness 0.1524)
				)
				(justify mirror)
			)
		)
		(fp_text user "D"
			(at -1.14681 3.726942 90)
			(unlocked yes)
			(layer "B.Fab")
			(effects
				(font
					(size 0.7874 0.5842)
					(thickness 0.1524)
				)
				(justify mirror)
			)
		)
		(fp_text user "E"
			(at -1.14681 4.927092 90)
			(unlocked yes)
			(layer "B.Fab")
			(effects
				(font
					(size 0.7874 0.5842)
					(thickness 0.1524)
				)
				(justify mirror)
			)
		)
		(fp_text user "F"
			(at -1.14681 6.126988 90)
			(unlocked yes)
			(layer "B.Fab")
			(effects
				(font
					(size 0.7874 0.5842)
					(thickness 0.1524)
				)
				(justify mirror)
			)
		)
		(fp_text user "I"
			(at -1.14681 9.72693 90)
			(unlocked yes)
			(layer "B.Fab")
			(effects
				(font
					(size 0.7874 0.5842)
					(thickness 0.1524)
				)
				(justify mirror)
			)
		)
		(fp_text user "J"
			(at -1.14681 10.92708 90)
			(unlocked yes)
			(layer "B.Fab")
			(effects
				(font
					(size 0.7874 0.5842)
					(thickness 0.1524)
				)
				(justify mirror)
			)
		)
		(fp_text user "K"
			(at -1.14681 12.126976 90)
			(unlocked yes)
			(layer "B.Fab")
			(effects
				(font
					(size 0.7874 0.5842)
					(thickness 0.1524)
				)
				(justify mirror)
			)
		)
		(fp_text user "L"
			(at -1.14681 13.327126 90)
			(unlocked yes)
			(layer "B.Fab")
			(effects
				(font
					(size 0.7874 0.5842)
					(thickness 0.1524)
				)
				(justify mirror)
			)
		)
		(fp_text user "M"
			(at -1.14681 14.527022 90)
			(unlocked yes)
			(layer "B.Fab")
			(effects
				(font
					(size 0.7874 0.5842)
					(thickness 0.1524)
				)
				(justify mirror)
			)
		)
		(fp_text user "N"
			(at -1.14681 15.726918 90)
			(unlocked yes)
			(layer "B.Fab")
			(effects
				(font
					(size 0.7874 0.5842)
					(thickness 0.1524)
				)
				(justify mirror)
			)
		)
		(fp_text user "1"
			(at 0.060452 16.764 90)
			(unlocked yes)
			(layer "B.Fab")
			(effects
				(font
					(size 0.7874 0.5842)
					(thickness 0.1524)
				)
				(justify mirror)
			)
		)
		(fp_text user "2"
			(at 2.060448 16.764 90)
			(unlocked yes)
			(layer "B.Fab")
			(effects
				(font
					(size 0.7874 0.5842)
					(thickness 0.1524)
				)
				(justify mirror)
			)
		)
		(fp_text user "3"
			(at 4.060444 16.764 90)
			(unlocked yes)
			(layer "B.Fab")
			(effects
				(font
					(size 0.7874 0.5842)
					(thickness 0.1524)
				)
				(justify mirror)
			)
		)
		(fp_text user "4"
			(at 6.06044 16.764 90)
			(unlocked yes)
			(layer "B.Fab")
			(effects
				(font
					(size 0.7874 0.5842)
					(thickness 0.1524)
				)
				(justify mirror)
			)
		)
		(fp_text user "5"
			(at 8.060436 16.764 90)
			(unlocked yes)
			(layer "B.Fab")
			(effects
				(font
					(size 0.7874 0.5842)
					(thickness 0.1524)
				)
				(justify mirror)
			)
		)
		(fp_text user "6"
			(at 10.060432 16.764 90)
			(unlocked yes)
			(layer "B.Fab")
			(effects
				(font
					(size 0.7874 0.5842)
					(thickness 0.1524)
				)
				(justify mirror)
			)
		)
		(fp_text user "7"
			(at 12.060428 16.764 90)
			(unlocked yes)
			(layer "B.Fab")
			(effects
				(font
					(size 0.7874 0.5842)
					(thickness 0.1524)
				)
				(justify mirror)
			)
		)
		(fp_text user "8"
			(at 14.060424 16.764 90)
			(unlocked yes)
			(layer "B.Fab")
			(effects
				(font
					(size 0.7874 0.5842)
					(thickness 0.1524)
				)
				(justify mirror)
			)
		)
		(fp_text user "PRESS-FIT"
			(at 17.23771 -0.0762 90)
			(unlocked yes)
			(layer "B.Fab")
			(effects
				(font
					(size 1.905 1.4224)
					(thickness 0.1524)
				)
				(justify left mirror)
			)
		)
		(fp_text user "B"
			(at -2.253742 1.199896 90)
			(unlocked yes)
			(layer "F.Fab")
			(effects
				(font
					(size 0.7874 0.5842)
					(thickness 0.1524)
				)
			)
		)
		(fp_text user "C"
			(at -2.253742 2.400046 90)
			(unlocked yes)
			(layer "F.Fab")
			(effects
				(font
					(size 0.7874 0.5842)
					(thickness 0.1524)
				)
			)
		)
		(fp_text user "D"
			(at -2.253742 3.599942 90)
			(unlocked yes)
			(layer "F.Fab")
			(effects
				(font
					(size 0.7874 0.5842)
					(thickness 0.1524)
				)
			)
		)
		(fp_text user "E"
			(at -2.253742 4.800092 90)
			(unlocked yes)
			(layer "F.Fab")
			(effects
				(font
					(size 0.7874 0.5842)
					(thickness 0.1524)
				)
			)
		)
		(fp_text user "F"
			(at -2.253742 5.999988 90)
			(unlocked yes)
			(layer "F.Fab")
			(effects
				(font
					(size 0.7874 0.5842)
					(thickness 0.1524)
				)
			)
		)
		(fp_text user "G"
			(at -2.253742 7.199884 90)
			(unlocked yes)
			(layer "F.Fab")
			(effects
				(font
					(size 0.7874 0.5842)
					(thickness 0.1524)
				)
			)
		)
		(fp_text user "H"
			(at -2.253742 8.400034 90)
			(unlocked yes)
			(layer "F.Fab")
			(effects
				(font
					(size 0.7874 0.5842)
					(thickness 0.1524)
				)
			)
		)
		(fp_text user "I"
			(at -2.253742 9.59993 90)
			(unlocked yes)
			(layer "F.Fab")
			(effects
				(font
					(size 0.7874 0.5842)
					(thickness 0.1524)
				)
			)
		)
		(fp_text user "J"
			(at -2.253742 10.80008 90)
			(unlocked yes)
			(layer "F.Fab")
			(effects
				(font
					(size 0.7874 0.5842)
					(thickness 0.1524)
				)
			)
		)
		(fp_text user "K"
			(at -2.253742 11.999976 90)
			(unlocked yes)
			(layer "F.Fab")
			(effects
				(font
					(size 0.7874 0.5842)
					(thickness 0.1524)
				)
			)
		)
		(fp_text user "L"
			(at -2.253742 13.200126 90)
			(unlocked yes)
			(layer "F.Fab")
			(effects
				(font
					(size 0.7874 0.5842)
					(thickness 0.1524)
				)
			)
		)
		(fp_text user "M"
			(at -2.253742 14.400022 90)
			(unlocked yes)
			(layer "F.Fab")
			(effects
				(font
					(size 0.7874 0.5842)
					(thickness 0.1524)
				)
			)
		)
		(fp_text user "N"
			(at -2.253742 15.599918 90)
			(unlocked yes)
			(layer "F.Fab")
			(effects
				(font
					(size 0.7874 0.5842)
					(thickness 0.1524)
				)
			)
		)
		(fp_text user "1"
			(at 0.111252 19.8628 90)
			(unlocked yes)
			(layer "F.Fab")
			(effects
				(font
					(size 0.7874 0.5842)
					(thickness 0.1524)
				)
			)
		)
		(fp_text user "2"
			(at 2.111248 19.8628 90)
			(unlocked yes)
			(layer "F.Fab")
			(effects
				(font
					(size 0.7874 0.5842)
					(thickness 0.1524)
				)
			)
		)
		(fp_text user "3"
			(at 4.111244 19.8628 90)
			(unlocked yes)
			(layer "F.Fab")
			(effects
				(font
					(size 0.7874 0.5842)
					(thickness 0.1524)
				)
			)
		)
		(fp_text user "4"
			(at 6.11124 19.8628 90)
			(unlocked yes)
			(layer "F.Fab")
			(effects
				(font
					(size 0.7874 0.5842)
					(thickness 0.1524)
				)
			)
		)
		(fp_text user "5"
			(at 8.111236 19.8628 90)
			(unlocked yes)
			(layer "F.Fab")
			(effects
				(font
					(size 0.7874 0.5842)
					(thickness 0.1524)
				)
			)
		)
		(fp_text user "6"
			(at 10.111232 19.8628 90)
			(unlocked yes)
			(layer "F.Fab")
			(effects
				(font
					(size 0.7874 0.5842)
					(thickness 0.1524)
				)
			)
		)
		(fp_text user "7"
			(at 12.111228 19.8628 90)
			(unlocked yes)
			(layer "F.Fab")
			(effects
				(font
					(size 0.7874 0.5842)
					(thickness 0.1524)
				)
			)
		)
		(fp_text user "8"
			(at 14.111224 19.8628 90)
			(unlocked yes)
			(layer "F.Fab")
			(effects
				(font
					(size 0.7874 0.5842)
					(thickness 0.1524)
				)
			)
		)
		(fp_text user "PRESS-FIT"
			(at 17.240758 16.521684 90)
			(unlocked yes)
			(layer "F.Fab")
			(effects
				(font
					(size 1.905 1.4224)
					(thickness 0.1524)
				)
				(justify left)
			)
		)
		(pad "A1" thru_hole rect
			(at 0 0 180)
			(size 0.766318 0.766318)
			(drill 0.359918)
			(layers "*.Cu" "*.Mask")
			(remove_unused_layers no)
			(net "PRSNT_CABLE_SWB_B1_N")
			(clearance 0.0508)
			(thermal_gap 0.0508)
			(padstack
				(mode front_inner_back)
				(layer "Inner"
					(shape circle)
					(size 0.766318 0.766318)
					(clearance 0.0508)
				)
				(layer "B.Cu"
					(shape rect)
					(size 0.766318 0.766318)
					(clearance 0.0508)
				)
			)
		)
		(pad "A2" thru_hole circle
			(at 1.999996 0.199898 180)
			(size 0.906272 0.906272)
			(drill 0.499872)
			(layers "*.Cu" "*.Mask")
			(remove_unused_layers no)
			(net "GND")
			(clearance 0.0508)
			(thermal_gap 0.0508)
		)
		(pad "A3" thru_hole circle
			(at 3.999992 0 180)
			(size 0.766318 0.766318)
			(drill 0.359918)
			(layers "*.Cu" "*.Mask")
			(remove_unused_layers no)
			(net "FM_SWB_PWRGD")
			(clearance 0.0508)
			(thermal_gap 0.0508)
		)
		(pad "A4" thru_hole circle
			(at 5.999988 0.199898 180)
			(size 0.906272 0.906272)
			(drill 0.499872)
			(layers "*.Cu" "*.Mask")
			(remove_unused_layers no)
			(net "GND")
			(clearance 0.0508)
			(thermal_gap 0.0508)
		)
		(pad "A5" thru_hole circle
			(at 7.999984 0 180)
			(size 0.766318 0.766318)
			(drill 0.359918)
			(layers "*.Cu" "*.Mask")
			(remove_unused_layers no)
			(net "NC_J106_A5")
			(clearance 0.0508)
			(thermal_gap 0.0508)
		)
		(pad "A6" thru_hole circle
			(at 9.99998 0.199898 180)
			(size 0.906272 0.906272)
			(drill 0.499872)
			(layers "*.Cu" "*.Mask")
			(remove_unused_layers no)
			(net "GND")
			(clearance 0.0508)
			(thermal_gap 0.0508)
		)
		(pad "A7" thru_hole circle
			(at 11.999976 0 180)
			(size 0.766318 0.766318)
			(drill 0.359918)
			(layers "*.Cu" "*.Mask")
			(remove_unused_layers no)
			(net "PRSNT_CABLE_GPU_A1_N")
			(clearance 0.0508)
			(thermal_gap 0.0508)
		)
		(pad "A8" thru_hole circle
			(at 13.999972 0.199898 180)
			(size 0.906272 0.906272)
			(drill 0.499872)
			(layers "*.Cu" "*.Mask")
			(remove_unused_layers no)
			(net "GND")
			(clearance 0.0508)
			(thermal_gap 0.0508)
		)
		(pad "B1" thru_hole circle
			(at 0 1.199896 180)
			(size 0.906272 0.906272)
			(drill 0.499872)
			(layers "*.Cu" "*.Mask")
			(remove_unused_layers no)
			(net "GND")
			(clearance 0.0508)
			(thermal_gap 0.0508)
		)
		(pad "B3" thru_hole circle
			(at 3.999992 1.199896 180)
			(size 0.906272 0.906272)
			(drill 0.499872)
			(layers "*.Cu" "*.Mask")
			(remove_unused_layers no)
			(net "GND")
			(clearance 0.0508)
			(thermal_gap 0.0508)
		)
		(pad "B5" thru_hole circle
			(at 7.999984 1.199896 180)
			(size 0.906272 0.906272)
			(drill 0.499872)
			(layers "*.Cu" "*.Mask")
			(remove_unused_layers no)
			(net "GND")
			(clearance 0.0508)
			(thermal_gap 0.0508)
		)
		(pad "B7" thru_hole circle
			(at 11.999976 1.199896 180)
			(size 0.906272 0.906272)
			(drill 0.499872)
			(layers "*.Cu" "*.Mask")
			(remove_unused_layers no)
			(net "GND")
			(clearance 0.0508)
			(thermal_gap 0.0508)
		)
		(pad "D2" thru_hole circle
			(at 1.999996 3.800094 180)
			(size 0.906272 0.906272)
			(drill 0.499872)
			(layers "*.Cu" "*.Mask")
			(remove_unused_layers no)
			(net "GND")
			(clearance 0.0508)
			(thermal_gap 0.0508)
		)
		(pad "D4" thru_hole circle
			(at 5.999988 3.800094 180)
			(size 0.906272 0.906272)
			(drill 0.499872)
			(layers "*.Cu" "*.Mask")
			(remove_unused_layers no)
			(net "GND")
			(clearance 0.0508)
			(thermal_gap 0.0508)
		)
		(pad "D6" thru_hole circle
			(at 9.99998 3.800094 180)
			(size 0.906272 0.906272)
			(drill 0.499872)
			(layers "*.Cu" "*.Mask")
			(remove_unused_layers no)
			(net "GND")
			(clearance 0.0508)
			(thermal_gap 0.0508)
		)
		(pad "D8" thru_hole circle
			(at 13.999972 3.800094 180)
			(size 0.906272 0.906272)
			(drill 0.499872)
			(layers "*.Cu" "*.Mask")
			(remove_unused_layers no)
			(net "GND")
			(clearance 0.0508)
			(thermal_gap 0.0508)
		)
		(pad "E1" thru_hole circle
			(at 0 4.800092 180)
			(size 0.906272 0.906272)
			(drill 0.499872)
			(layers "*.Cu" "*.Mask")
			(remove_unused_layers no)
			(net "GND")
			(clearance 0.0508)
			(thermal_gap 0.0508)
		)
		(pad "E3" thru_hole circle
			(at 3.999992 4.800092 180)
			(size 0.906272 0.906272)
			(drill 0.499872)
			(layers "*.Cu" "*.Mask")
			(remove_unused_layers no)
			(net "GND")
			(clearance 0.0508)
			(thermal_gap 0.0508)
		)
		(pad "E5" thru_hole circle
			(at 7.999984 4.800092 180)
			(size 0.906272 0.906272)
			(drill 0.499872)
			(layers "*.Cu" "*.Mask")
			(remove_unused_layers no)
			(net "GND")
			(clearance 0.0508)
			(thermal_gap 0.0508)
		)
		(pad "E7" thru_hole circle
			(at 11.999976 4.800092 180)
			(size 0.906272 0.906272)
			(drill 0.499872)
			(layers "*.Cu" "*.Mask")
			(remove_unused_layers no)
			(net "GND")
			(clearance 0.0508)
			(thermal_gap 0.0508)
		)
		(pad "G2" thru_hole circle
			(at 1.999996 7.400036 180)
			(size 0.906272 0.906272)
			(drill 0.499872)
			(layers "*.Cu" "*.Mask")
			(remove_unused_layers no)
			(net "GND")
			(clearance 0.0508)
			(thermal_gap 0.0508)
		)
		(pad "G4" thru_hole circle
			(at 5.999988 7.400036 180)
			(size 0.906272 0.906272)
			(drill 0.499872)
			(layers "*.Cu" "*.Mask")
			(remove_unused_layers no)
			(net "GND")
			(clearance 0.0508)
			(thermal_gap 0.0508)
		)
		(pad "G6" thru_hole circle
			(at 9.99998 7.400036 180)
			(size 0.906272 0.906272)
			(drill 0.499872)
			(layers "*.Cu" "*.Mask")
			(remove_unused_layers no)
			(net "GND")
			(clearance 0.0508)
			(thermal_gap 0.0508)
		)
		(pad "G8" thru_hole circle
			(at 13.999972 7.400036 180)
			(size 0.906272 0.906272)
			(drill 0.499872)
			(layers "*.Cu" "*.Mask")
			(remove_unused_layers no)
			(net "GND")
			(clearance 0.0508)
			(thermal_gap 0.0508)
		)
		(pad "H1" thru_hole circle
			(at 0 8.400034 180)
			(size 0.906272 0.906272)
			(drill 0.499872)
			(layers "*.Cu" "*.Mask")
			(remove_unused_layers no)
			(net "GND")
			(clearance 0.0508)
			(thermal_gap 0.0508)
		)
		(pad "H3" thru_hole circle
			(at 3.999992 8.400034 180)
			(size 0.906272 0.906272)
			(drill 0.499872)
			(layers "*.Cu" "*.Mask")
			(remove_unused_layers no)
			(net "GND")
			(clearance 0.0508)
			(thermal_gap 0.0508)
		)
		(pad "H5" thru_hole circle
			(at 7.999984 8.400034 180)
			(size 0.906272 0.906272)
			(drill 0.499872)
			(layers "*.Cu" "*.Mask")
			(remove_unused_layers no)
			(net "GND")
			(clearance 0.0508)
			(thermal_gap 0.0508)
		)
		(pad "H7" thru_hole circle
			(at 11.999976 8.400034 180)
			(size 0.906272 0.906272)
			(drill 0.499872)
			(layers "*.Cu" "*.Mask")
			(remove_unused_layers no)
			(net "GND")
			(clearance 0.0508)
			(thermal_gap 0.0508)
		)
		(pad "J2" thru_hole circle
			(at 1.999996 10.999978 180)
			(size 0.906272 0.906272)
			(drill 0.499872)
			(layers "*.Cu" "*.Mask")
			(remove_unused_layers no)
			(net "GND")
			(clearance 0.0508)
			(thermal_gap 0.0508)
		)
		(pad "J4" thru_hole circle
			(at 5.999988 10.999978 180)
			(size 0.906272 0.906272)
			(drill 0.499872)
			(layers "*.Cu" "*.Mask")
			(remove_unused_layers no)
			(net "GND")
			(clearance 0.0508)
			(thermal_gap 0.0508)
		)
		(pad "J6" thru_hole circle
			(at 9.99998 10.999978 180)
			(size 0.906272 0.906272)
			(drill 0.499872)
			(layers "*.Cu" "*.Mask")
			(remove_unused_layers no)
			(net "GND")
			(clearance 0.0508)
			(thermal_gap 0.0508)
		)
		(pad "J8" thru_hole circle
			(at 13.999972 10.999978 180)
			(size 0.906272 0.906272)
			(drill 0.499872)
			(layers "*.Cu" "*.Mask")
			(remove_unused_layers no)
			(net "GND")
			(clearance 0.0508)
			(thermal_gap 0.0508)
		)
		(pad "K1" thru_hole circle
			(at 0 11.999976 180)
			(size 0.906272 0.906272)
			(drill 0.499872)
			(layers "*.Cu" "*.Mask")
			(remove_unused_layers no)
			(net "GND")
			(clearance 0.0508)
			(thermal_gap 0.0508)
		)
		(pad "K3" thru_hole circle
			(at 3.999992 11.999976 180)
			(size 0.906272 0.906272)
			(drill 0.499872)
			(layers "*.Cu" "*.Mask")
			(remove_unused_layers no)
			(net "GND")
			(clearance 0.0508)
			(thermal_gap 0.0508)
		)
		(pad "K5" thru_hole circle
			(at 7.999984 11.999976 180)
			(size 0.906272 0.906272)
			(drill 0.499872)
			(layers "*.Cu" "*.Mask")
			(remove_unused_layers no)
			(net "GND")
			(clearance 0.0508)
			(thermal_gap 0.0508)
		)
		(pad "K7" thru_hole circle
			(at 11.999976 11.999976 180)
			(size 0.906272 0.906272)
			(drill 0.499872)
			(layers "*.Cu" "*.Mask")
			(remove_unused_layers no)
			(net "GND")
			(clearance 0.0508)
			(thermal_gap 0.0508)
		)
		(pad "M2" thru_hole circle
			(at 1.999996 14.59992 180)
			(size 0.906272 0.906272)
			(drill 0.499872)
			(layers "*.Cu" "*.Mask")
			(remove_unused_layers no)
			(net "GND")
			(clearance 0.0508)
			(thermal_gap 0.0508)
		)
		(pad "M4" thru_hole circle
			(at 5.999988 14.59992 180)
			(size 0.906272 0.906272)
			(drill 0.499872)
			(layers "*.Cu" "*.Mask")
			(remove_unused_layers no)
			(net "GND")
			(clearance 0.0508)
			(thermal_gap 0.0508)
		)
		(pad "M6" thru_hole circle
			(at 9.99998 14.59992 180)
			(size 0.906272 0.906272)
			(drill 0.499872)
			(layers "*.Cu" "*.Mask")
			(remove_unused_layers no)
			(net "GND")
			(clearance 0.0508)
			(thermal_gap 0.0508)
		)
		(pad "M8" thru_hole circle
			(at 13.999972 14.59992 180)
			(size 0.906272 0.906272)
			(drill 0.499872)
			(layers "*.Cu" "*.Mask")
			(remove_unused_layers no)
			(net "GND")
			(clearance 0.0508)
			(thermal_gap 0.0508)
		)
		(pad "N1" thru_hole circle
			(at 0 15.599918 180)
			(size 0.906272 0.906272)
			(drill 0.499872)
			(layers "*.Cu" "*.Mask")
			(remove_unused_layers no)
			(net "GND")
			(clearance 0.0508)
			(thermal_gap 0.0508)
		)
		(pad "N2" thru_hole circle
			(at 1.999996 15.80007 180)
			(size 0.766318 0.766318)
			(drill 0.359918)
			(layers "*.Cu" "*.Mask")
			(remove_unused_layers no)
			(net "I3C_BMC_SWB_BUF_SDA")
			(clearance 0.0508)
			(thermal_gap 0.0508)
		)
		(pad "N3" thru_hole circle
			(at 3.999992 15.599918 180)
			(size 0.906272 0.906272)
			(drill 0.499872)
			(layers "*.Cu" "*.Mask")
			(remove_unused_layers no)
			(net "GND")
			(clearance 0.0508)
			(thermal_gap 0.0508)
		)
		(pad "N4" thru_hole circle
			(at 5.999988 15.80007 180)
			(size 0.766318 0.766318)
			(drill 0.359918)
			(layers "*.Cu" "*.Mask")
			(remove_unused_layers no)
			(net "I3C_BMC_SWB_BUF_SCL")
			(clearance 0.0508)
			(thermal_gap 0.0508)
		)
		(pad "N5" thru_hole circle
			(at 7.999984 15.599918 180)
			(size 0.906272 0.906272)
			(drill 0.499872)
			(layers "*.Cu" "*.Mask")
			(remove_unused_layers no)
			(net "GND")
			(clearance 0.0508)
			(thermal_gap 0.0508)
		)
		(pad "N6" thru_hole circle
			(at 9.99998 15.80007 180)
			(size 0.766318 0.766318)
			(drill 0.359918)
			(layers "*.Cu" "*.Mask")
			(remove_unused_layers no)
			(net "UART_BMC_BIC_RX")
			(clearance 0.0508)
			(thermal_gap 0.0508)
		)
		(pad "N7" thru_hole circle
			(at 11.999976 15.599918 180)
			(size 0.906272 0.906272)
			(drill 0.499872)
			(layers "*.Cu" "*.Mask")
			(remove_unused_layers no)
			(net "GND")
			(clearance 0.0508)
			(thermal_gap 0.0508)
		)
		(pad "N8" thru_hole circle
			(at 13.999972 15.80007 180)
			(size 0.766318 0.766318)
			(drill 0.359918)
			(layers "*.Cu" "*.Mask")
			(remove_unused_layers no)
			(net "UART_BMC_BIC_TX")
			(clearance 0.0508)
			(thermal_gap 0.0508)
		)
		(zone
			(layer "B.Cu")
			(hatch none 0.5)
			(connect_pads
				(clearance 0)
			)
			(min_thickness 0.25)
			(keepout
				(tracks allowed)
				(vias not_allowed)
				(pads allowed)
				(copperpour not_allowed)
				(footprints allowed)
			)
			(placement
				(enabled no)
				(sheetname "")
			)
			(fill
				(thermal_gap 0.5)
				(thermal_bridge_width 0.5)
				(island_removal_mode 0)
			)
			(polygon
				(pts
					(xy 381.241808 -424.246548) (xy 396.265908 -424.246548) (xy 396.265908 -440.934348) (xy 381.241808 -440.934348)
				)
			)
		)
	)
	(footprint ""
		(layer "F.Cu")
		(at 146.567398 -49.153064)
		(property "Reference" "R1346"
			(at 0 0 0)
			(layer "F.SilkS")
			(hide yes)
			(effects
				(font
					(size 1.27 1.27)
				)
			)
		)
		(property "Value" ""
			(at 0 0 0)
			(layer "F.Fab")
			(effects
				(font
					(size 1.27 1.27)
				)
			)
		)
		(duplicate_pad_numbers_are_jumpers no)
		(fp_line
			(start -0.7874 -0.4064)
			(end 0.7874 -0.4064)
			(stroke
				(width 0.1524)
				(type default)
			)
			(layer "F.SilkS")
		)
		(fp_line
			(start -0.7874 0.4064)
			(end -0.7874 -0.4064)
			(stroke
				(width 0.1524)
				(type default)
			)
			(layer "F.SilkS")
		)
		(fp_line
			(start 0.7874 -0.4064)
			(end 0.7874 0.4064)
			(stroke
				(width 0.1524)
				(type default)
			)
			(layer "F.SilkS")
		)
		(fp_line
			(start 0.7874 0.4064)
			(end -0.7874 0.4064)
			(stroke
				(width 0.1524)
				(type default)
			)
			(layer "F.SilkS")
		)
		(fp_line
			(start -0.67945 -0.305054)
			(end -0.12065 -0.305054)
			(stroke
				(width 0.1)
				(type default)
			)
			(layer "F.Fab")
		)
		(fp_line
			(start -0.67945 0.3048)
			(end -0.67945 -0.305054)
			(stroke
				(width 0.1)
				(type default)
			)
			(layer "F.Fab")
		)
		(fp_line
			(start -0.12065 -0.305054)
			(end -0.12065 -0.2794)
			(stroke
				(width 0.1)
				(type default)
			)
			(layer "F.Fab")
		)
		(fp_line
			(start -0.12065 -0.2794)
			(end 0.12065 -0.2794)
			(stroke
				(width 0.1)
				(type default)
			)
			(layer "F.Fab")
		)
		(fp_line
			(start -0.12065 0.2794)
			(end -0.12065 0.3048)
			(stroke
				(width 0.1)
				(type default)
			)
			(layer "F.Fab")
		)
		(fp_line
			(start -0.12065 0.3048)
			(end -0.67945 0.3048)
			(stroke
				(width 0.1)
				(type default)
			)
			(layer "F.Fab")
		)
		(fp_line
			(start 0.120396 0.2794)
			(end -0.12065 0.2794)
			(stroke
				(width 0.1)
				(type default)
			)
			(layer "F.Fab")
		)
		(fp_line
			(start 0.120396 0.3048)
			(end 0.120396 0.2794)
			(stroke
				(width 0.1)
				(type default)
			)
			(layer "F.Fab")
		)
		(fp_line
			(start 0.12065 -0.3048)
			(end 0.67945 -0.3048)
			(stroke
				(width 0.1)
				(type default)
			)
			(layer "F.Fab")
		)
		(fp_line
			(start 0.12065 -0.2794)
			(end 0.12065 -0.3048)
			(stroke
				(width 0.1)
				(type default)
			)
			(layer "F.Fab")
		)
		(fp_line
			(start 0.67945 -0.3048)
			(end 0.67945 0.3048)
			(stroke
				(width 0.1)
				(type default)
			)
			(layer "F.Fab")
		)
		(fp_line
			(start 0.67945 0.3048)
			(end 0.120396 0.3048)
			(stroke
				(width 0.1)
				(type default)
			)
			(layer "F.Fab")
		)
		(pad "1" smd circle
			(at -0.40005 0)
			(size 0 0)
			(layers "F.Cu" "F.Mask" "F.Paste")
			(net "SMB_INA230_3V3AUX_SCL")
		)
		(pad "2" smd circle
			(at 0.40005 0)
			(size 0 0)
			(layers "F.Cu" "F.Mask" "F.Paste")
			(net "SMB_INA230_7_3V3AUX_SCL_R")
		)
	)
	(footprint ""
		(layer "F.Cu")
		(at 329.592178 -41.160954 180)
		(property "Reference" "R2907"
			(at 0 0 180)
			(layer "F.SilkS")
			(hide yes)
			(effects
				(font
					(size 1.27 1.27)
				)
			)
		)
		(property "Value" ""
			(at 0 0 180)
			(layer "F.Fab")
			(effects
				(font
					(size 1.27 1.27)
				)
			)
		)
		(duplicate_pad_numbers_are_jumpers no)
		(fp_line
			(start 0.7874 0.4064)
			(end -0.7874 0.4064)
			(stroke
				(width 0.1524)
				(type default)
			)
			(layer "F.SilkS")
		)
		(fp_line
			(start 0.7874 -0.4064)
			(end 0.7874 0.4064)
			(stroke
				(width 0.1524)
				(type default)
			)
			(layer "F.SilkS")
		)
		(fp_line
			(start -0.7874 0.4064)
			(end -0.7874 -0.4064)
			(stroke
				(width 0.1524)
				(type default)
			)
			(layer "F.SilkS")
		)
		(fp_line
			(start -0.7874 -0.4064)
			(end 0.7874 -0.4064)
			(stroke
				(width 0.1524)
				(type default)
			)
			(layer "F.SilkS")
		)
		(fp_line
			(start 0.67945 0.3048)
			(end 0.120396 0.3048)
			(stroke
				(width 0.1)
				(type default)
			)
			(layer "F.Fab")
		)
		(fp_line
			(start 0.67945 -0.3048)
			(end 0.67945 0.3048)
			(stroke
				(width 0.1)
				(type default)
			)
			(layer "F.Fab")
		)
		(fp_line
			(start 0.12065 -0.2794)
			(end 0.12065 -0.3048)
			(stroke
				(width 0.1)
				(type default)
			)
			(layer "F.Fab")
		)
		(fp_line
			(start 0.12065 -0.3048)
			(end 0.67945 -0.3048)
			(stroke
				(width 0.1)
				(type default)
			)
			(layer "F.Fab")
		)
		(fp_line
			(start 0.120396 0.3048)
			(end 0.120396 0.2794)
			(stroke
				(width 0.1)
				(type default)
			)
			(layer "F.Fab")
		)
		(fp_line
			(start 0.120396 0.2794)
			(end -0.12065 0.2794)
			(stroke
				(width 0.1)
				(type default)
			)
			(layer "F.Fab")
		)
		(fp_line
			(start -0.12065 0.3048)
			(end -0.67945 0.3048)
			(stroke
				(width 0.1)
				(type default)
			)
			(layer "F.Fab")
		)
		(fp_line
			(start -0.12065 0.2794)
			(end -0.12065 0.3048)
			(stroke
				(width 0.1)
				(type default)
			)
			(layer "F.Fab")
		)
		(fp_line
			(start -0.12065 -0.2794)
			(end 0.12065 -0.2794)
			(stroke
				(width 0.1)
				(type default)
			)
			(layer "F.Fab")
		)
		(fp_line
			(start -0.12065 -0.305054)
			(end -0.12065 -0.2794)
			(stroke
				(width 0.1)
				(type default)
			)
			(layer "F.Fab")
		)
		(fp_line
			(start -0.67945 0.3048)
			(end -0.67945 -0.305054)
			(stroke
				(width 0.1)
				(type default)
			)
			(layer "F.Fab")
		)
		(fp_line
			(start -0.67945 -0.305054)
			(end -0.12065 -0.305054)
			(stroke
				(width 0.1)
				(type default)
			)
			(layer "F.Fab")
		)
		(pad "1" smd circle
			(at -0.40005 0 180)
			(size 0 0)
			(layers "F.Cu" "F.Mask" "F.Paste")
			(net "P3V3_AUX")
		)
		(pad "2" smd circle
			(at 0.40005 0 180)
			(size 0 0)
			(layers "F.Cu" "F.Mask" "F.Paste")
			(net "P3V3_AUX_ADC")
		)
	)
	(footprint ""
		(layer "F.Cu")
		(at 185.777124 -96.096074 -90)
		(property "Reference" "R1187"
			(at 0 0 270)
			(layer "F.SilkS")
			(hide yes)
			(effects
				(font
					(size 1.27 1.27)
				)
			)
		)
		(property "Value" ""
			(at 0 0 270)
			(layer "F.Fab")
			(effects
				(font
					(size 1.27 1.27)
				)
			)
		)
		(duplicate_pad_numbers_are_jumpers no)
		(fp_line
			(start -0.7874 0.4064)
			(end -0.7874 -0.4064)
			(stroke
				(width 0.1524)
				(type default)
			)
			(layer "F.SilkS")
		)
		(fp_line
			(start 0.7874 0.4064)
			(end -0.7874 0.4064)
			(stroke
				(width 0.1524)
				(type default)
			)
			(layer "F.SilkS")
		)
		(fp_line
			(start -0.7874 -0.4064)
			(end 0.7874 -0.4064)
			(stroke
				(width 0.1524)
				(type default)
			)
			(layer "F.SilkS")
		)
		(fp_line
			(start 0.7874 -0.4064)
			(end 0.7874 0.4064)
			(stroke
				(width 0.1524)
				(type default)
			)
			(layer "F.SilkS")
		)
		(fp_line
			(start -0.67945 0.3048)
			(end -0.67945 -0.305054)
			(stroke
				(width 0.1)
				(type default)
			)
			(layer "F.Fab")
		)
		(fp_line
			(start -0.12065 0.3048)
			(end -0.67945 0.3048)
			(stroke
				(width 0.1)
				(type default)
			)
			(layer "F.Fab")
		)
		(fp_line
			(start 0.120396 0.3048)
			(end 0.120396 0.2794)
			(stroke
				(width 0.1)
				(type default)
			)
			(layer "F.Fab")
		)
		(fp_line
			(start 0.67945 0.3048)
			(end 0.120396 0.3048)
			(stroke
				(width 0.1)
				(type default)
			)
			(layer "F.Fab")
		)
		(fp_line
			(start -0.12065 0.2794)
			(end -0.12065 0.3048)
			(stroke
				(width 0.1)
				(type default)
			)
			(layer "F.Fab")
		)
		(fp_line
			(start 0.120396 0.2794)
			(end -0.12065 0.2794)
			(stroke
				(width 0.1)
				(type default)
			)
			(layer "F.Fab")
		)
		(fp_line
			(start -0.12065 -0.2794)
			(end 0.12065 -0.2794)
			(stroke
				(width 0.1)
				(type default)
			)
			(layer "F.Fab")
		)
		(fp_line
			(start 0.12065 -0.2794)
			(end 0.12065 -0.3048)
			(stroke
				(width 0.1)
				(type default)
			)
			(layer "F.Fab")
		)
		(fp_line
			(start 0.12065 -0.3048)
			(end 0.67945 -0.3048)
			(stroke
				(width 0.1)
				(type default)
			)
			(layer "F.Fab")
		)
		(fp_line
			(start 0.67945 -0.3048)
			(end 0.67945 0.3048)
			(stroke
				(width 0.1)
				(type default)
			)
			(layer "F.Fab")
		)
		(fp_line
			(start -0.67945 -0.305054)
			(end -0.12065 -0.305054)
			(stroke
				(width 0.1)
				(type default)
			)
			(layer "F.Fab")
		)
		(fp_line
			(start -0.12065 -0.305054)
			(end -0.12065 -0.2794)
			(stroke
				(width 0.1)
				(type default)
			)
			(layer "F.Fab")
		)
		(pad "1" smd circle
			(at -0.40005 0 270)
			(size 0 0)
			(layers "F.Cu" "F.Mask" "F.Paste")
			(net "PVDDCR_CPU0_P1_PMALERT")
		)
		(pad "2" smd circle
			(at 0.40005 0 270)
			(size 0 0)
			(layers "F.Cu" "F.Mask" "F.Paste")
			(net "P3V3_AUX")
		)
	)
	(footprint ""
		(layer "F.Cu")
		(at 243.063268 -44.682918)
		(property "Reference" "C1277"
			(at 0 0 0)
			(layer "F.SilkS")
			(hide yes)
			(effects
				(font
					(size 1.27 1.27)
				)
			)
		)
		(property "Value" ""
			(at 0 0 0)
			(layer "F.Fab")
			(effects
				(font
					(size 1.27 1.27)
				)
			)
		)
		(duplicate_pad_numbers_are_jumpers no)
		(fp_line
			(start -1.524 -0.762)
			(end 1.524 -0.762)
			(stroke
				(width 0.1524)
				(type default)
			)
			(layer "F.SilkS")
		)
		(fp_line
			(start -1.524 0.762)
			(end -1.524 -0.762)
			(stroke
				(width 0.1524)
				(type default)
			)
			(layer "F.SilkS")
		)
		(fp_line
			(start 1.524 -0.762)
			(end 1.524 0.762)
			(stroke
				(width 0.1524)
				(type default)
			)
			(layer "F.SilkS")
		)
		(fp_line
			(start 1.524 0.762)
			(end -1.524 0.762)
			(stroke
				(width 0.1524)
				(type default)
			)
			(layer "F.SilkS")
		)
		(fp_line
			(start -1.1049 -0.724916)
			(end -1.1049 0.724916)
			(stroke
				(width 0.1)
				(type default)
			)
			(layer "F.Fab")
		)
		(fp_line
			(start -1.1049 0.724916)
			(end 1.1049 0.724916)
			(stroke
				(width 0.1)
				(type default)
			)
			(layer "F.Fab")
		)
		(fp_line
			(start 1.1049 -0.724916)
			(end -1.1049 -0.724916)
			(stroke
				(width 0.1)
				(type default)
			)
			(layer "F.Fab")
		)
		(fp_line
			(start 1.1049 0.724916)
			(end 1.1049 -0.724916)
			(stroke
				(width 0.1)
				(type default)
			)
			(layer "F.Fab")
		)
		(pad "1" smd rect
			(at -0.889 0 180)
			(size 1.016 1.27)
			(layers "F.Cu" "F.Mask" "F.Paste")
			(net "P12V_E1S_0_R")
		)
		(pad "2" smd rect
			(at 0.889 0 180)
			(size 1.016 1.27)
			(layers "F.Cu" "F.Mask" "F.Paste")
			(net "GND")
		)
	)
	(footprint ""
		(layer "F.Cu")
		(at 19.508724 -405.868378 -90)
		(property "Reference" "C107"
			(at 0 0 270)
			(layer "F.SilkS")
			(hide yes)
			(effects
				(font
					(size 1.27 1.27)
				)
			)
		)
		(property "Value" ""
			(at 0 0 270)
			(layer "F.Fab")
			(effects
				(font
					(size 1.27 1.27)
				)
			)
		)
		(duplicate_pad_numbers_are_jumpers no)
		(fp_line
			(start -0.7874 0.4064)
			(end -0.7874 -0.4064)
			(stroke
				(width 0.1524)
				(type default)
			)
			(layer "F.SilkS")
		)
		(fp_line
			(start 0.7874 0.4064)
			(end -0.7874 0.4064)
			(stroke
				(width 0.1524)
				(type default)
			)
			(layer "F.SilkS")
		)
		(fp_line
			(start -0.7874 -0.4064)
			(end 0.7874 -0.4064)
			(stroke
				(width 0.1524)
				(type default)
			)
			(layer "F.SilkS")
		)
		(fp_line
			(start 0.7874 -0.4064)
			(end 0.7874 0.4064)
			(stroke
				(width 0.1524)
				(type default)
			)
			(layer "F.SilkS")
		)
		(fp_line
			(start -0.67945 0.3048)
			(end -0.67945 -0.305054)
			(stroke
				(width 0.1)
				(type default)
			)
			(layer "F.Fab")
		)
		(fp_line
			(start -0.12065 0.3048)
			(end -0.67945 0.3048)
			(stroke
				(width 0.1)
				(type default)
			)
			(layer "F.Fab")
		)
		(fp_line
			(start 0.120396 0.3048)
			(end 0.120396 0.2794)
			(stroke
				(width 0.1)
				(type default)
			)
			(layer "F.Fab")
		)
		(fp_line
			(start 0.67945 0.3048)
			(end 0.120396 0.3048)
			(stroke
				(width 0.1)
				(type default)
			)
			(layer "F.Fab")
		)
		(fp_line
			(start -0.12065 0.2794)
			(end -0.12065 0.3048)
			(stroke
				(width 0.1)
				(type default)
			)
			(layer "F.Fab")
		)
		(fp_line
			(start 0.120396 0.2794)
			(end -0.12065 0.2794)
			(stroke
				(width 0.1)
				(type default)
			)
			(layer "F.Fab")
		)
		(fp_line
			(start -0.12065 -0.2794)
			(end 0.12065 -0.2794)
			(stroke
				(width 0.1)
				(type default)
			)
			(layer "F.Fab")
		)
		(fp_line
			(start 0.12065 -0.2794)
			(end 0.12065 -0.3048)
			(stroke
				(width 0.1)
				(type default)
			)
			(layer "F.Fab")
		)
		(fp_line
			(start 0.12065 -0.3048)
			(end 0.67945 -0.3048)
			(stroke
				(width 0.1)
				(type default)
			)
			(layer "F.Fab")
		)
		(fp_line
			(start 0.67945 -0.3048)
			(end 0.67945 0.3048)
			(stroke
				(width 0.1)
				(type default)
			)
			(layer "F.Fab")
		)
		(fp_line
			(start -0.67945 -0.305054)
			(end -0.12065 -0.305054)
			(stroke
				(width 0.1)
				(type default)
			)
			(layer "F.Fab")
		)
		(fp_line
			(start -0.12065 -0.305054)
			(end -0.12065 -0.2794)
			(stroke
				(width 0.1)
				(type default)
			)
			(layer "F.Fab")
		)
		(pad "1" smd circle
			(at -0.40005 0 270)
			(size 0 0)
			(layers "F.Cu" "F.Mask" "F.Paste")
			(net "PWRGD_P0V9_RETIMER_CPU1_R")
		)
		(pad "2" smd circle
			(at 0.40005 0 270)
			(size 0 0)
			(layers "F.Cu" "F.Mask" "F.Paste")
			(net "GND")
		)
	)
	(footprint ""
		(layer "F.Cu")
		(at 424.5356 -421.64 90)
		(property "Reference" "R1485"
			(at 0 0 90)
			(layer "F.SilkS")
			(hide yes)
			(effects
				(font
					(size 1.27 1.27)
				)
			)
		)
		(property "Value" ""
			(at 0 0 90)
			(layer "F.Fab")
			(effects
				(font
					(size 1.27 1.27)
				)
			)
		)
		(duplicate_pad_numbers_are_jumpers no)
		(fp_line
			(start 0.32512 -0.175006)
			(end 0.32512 0.175006)
			(stroke
				(width 0.1)
				(type default)
			)
			(layer "F.Fab")
		)
		(fp_line
			(start -0.32512 -0.175006)
			(end 0.32512 -0.175006)
			(stroke
				(width 0.1)
				(type default)
			)
			(layer "F.Fab")
		)
		(fp_line
			(start 0.32512 0.175006)
			(end -0.32512 0.175006)
			(stroke
				(width 0.1)
				(type default)
			)
			(layer "F.Fab")
		)
		(fp_line
			(start -0.32512 0.175006)
			(end -0.32512 -0.175006)
			(stroke
				(width 0.1)
				(type default)
			)
			(layer "F.Fab")
		)
		(pad "1" smd rect
			(at -0.2667 0 90)
			(size 0.3048 0.381)
			(layers "F.Cu" "F.Mask" "F.Paste")
			(net "P1V8_CPU0_RT_1D")
		)
		(pad "2" smd rect
			(at 0.2667 0 270)
			(size 0.3048 0.381)
			(layers "F.Cu" "F.Mask" "F.Paste")
			(net "JTAG_TCK_RT_CPU0_P3")
		)
	)
	(footprint ""
		(layer "F.Cu")
		(at 393.715748 -17.624298 90)
		(property "Reference" "C1792"
			(at 0 0 90)
			(layer "F.SilkS")
			(hide yes)
			(effects
				(font
					(size 1.27 1.27)
				)
			)
		)
		(property "Value" ""
			(at 0 0 90)
			(layer "F.Fab")
			(effects
				(font
					(size 1.27 1.27)
				)
			)
		)
		(duplicate_pad_numbers_are_jumpers no)
		(fp_line
			(start 0.299974 -0.150114)
			(end 0.299974 0.150114)
			(stroke
				(width 0.1)
				(type default)
			)
			(layer "F.Fab")
		)
		(fp_line
			(start -0.299974 -0.150114)
			(end 0.299974 -0.150114)
			(stroke
				(width 0.1)
				(type default)
			)
			(layer "F.Fab")
		)
		(fp_line
			(start 0.299974 0.150114)
			(end -0.299974 0.150114)
			(stroke
				(width 0.1)
				(type default)
			)
			(layer "F.Fab")
		)
		(fp_line
			(start -0.299974 0.150114)
			(end -0.299974 -0.150114)
			(stroke
				(width 0.1)
				(type default)
			)
			(layer "F.Fab")
		)
		(pad "1" smd rect
			(at -0.2667 0 90)
			(size 0.3048 0.381)
			(layers "F.Cu" "F.Mask" "F.Paste")
			(net "P5E_CPU0_G3_TX_C_DP<14>")
		)
		(pad "2" smd rect
			(at 0.2667 0 90)
			(size 0.3048 0.381)
			(layers "F.Cu" "F.Mask" "F.Paste")
			(net "P5E_CPU0_G3_TX_DP<14>")
		)
	)
	(footprint ""
		(layer "F.Cu")
		(at 420.017956 -369.275106 90)
		(property "Reference" "R6856"
			(at 0 0 90)
			(layer "F.SilkS")
			(hide yes)
			(effects
				(font
					(size 1.27 1.27)
				)
			)
		)
		(property "Value" ""
			(at 0 0 90)
			(layer "F.Fab")
			(effects
				(font
					(size 1.27 1.27)
				)
			)
		)
		(duplicate_pad_numbers_are_jumpers no)
		(fp_line
			(start 0.7874 -0.4064)
			(end 0.7874 0.4064)
			(stroke
				(width 0.1524)
				(type default)
			)
			(layer "F.SilkS")
		)
		(fp_line
			(start -0.7874 -0.4064)
			(end 0.7874 -0.4064)
			(stroke
				(width 0.1524)
				(type default)
			)
			(layer "F.SilkS")
		)
		(fp_line
			(start 0.7874 0.4064)
			(end -0.7874 0.4064)
			(stroke
				(width 0.1524)
				(type default)
			)
			(layer "F.SilkS")
		)
		(fp_line
			(start -0.7874 0.4064)
			(end -0.7874 -0.4064)
			(stroke
				(width 0.1524)
				(type default)
			)
			(layer "F.SilkS")
		)
		(fp_line
			(start -0.12065 -0.305054)
			(end -0.12065 -0.2794)
			(stroke
				(width 0.1)
				(type default)
			)
			(layer "F.Fab")
		)
		(fp_line
			(start -0.67945 -0.305054)
			(end -0.12065 -0.305054)
			(stroke
				(width 0.1)
				(type default)
			)
			(layer "F.Fab")
		)
		(fp_line
			(start 0.67945 -0.3048)
			(end 0.67945 0.3048)
			(stroke
				(width 0.1)
				(type default)
			)
			(layer "F.Fab")
		)
		(fp_line
			(start 0.12065 -0.3048)
			(end 0.67945 -0.3048)
			(stroke
				(width 0.1)
				(type default)
			)
			(layer "F.Fab")
		)
		(fp_line
			(start 0.12065 -0.2794)
			(end 0.12065 -0.3048)
			(stroke
				(width 0.1)
				(type default)
			)
			(layer "F.Fab")
		)
		(fp_line
			(start -0.12065 -0.2794)
			(end 0.12065 -0.2794)
			(stroke
				(width 0.1)
				(type default)
			)
			(layer "F.Fab")
		)
		(fp_line
			(start 0.120396 0.2794)
			(end -0.12065 0.2794)
			(stroke
				(width 0.1)
				(type default)
			)
			(layer "F.Fab")
		)
		(fp_line
			(start -0.12065 0.2794)
			(end -0.12065 0.3048)
			(stroke
				(width 0.1)
				(type default)
			)
			(layer "F.Fab")
		)
		(fp_line
			(start 0.67945 0.3048)
			(end 0.120396 0.3048)
			(stroke
				(width 0.1)
				(type default)
			)
			(layer "F.Fab")
		)
		(fp_line
			(start 0.120396 0.3048)
			(end 0.120396 0.2794)
			(stroke
				(width 0.1)
				(type default)
			)
			(layer "F.Fab")
		)
		(fp_line
			(start -0.12065 0.3048)
			(end -0.67945 0.3048)
			(stroke
				(width 0.1)
				(type default)
			)
			(layer "F.Fab")
		)
		(fp_line
			(start -0.67945 0.3048)
			(end -0.67945 -0.305054)
			(stroke
				(width 0.1)
				(type default)
			)
			(layer "F.Fab")
		)
		(pad "1" smd circle
			(at -0.40005 0 90)
			(size 0 0)
			(layers "F.Cu" "F.Mask" "F.Paste")
			(net "SMB_SCM_2_R6_SCL")
		)
		(pad "2" smd circle
			(at 0.40005 0 90)
			(size 0 0)
			(layers "F.Cu" "F.Mask" "F.Paste")
			(net "P0V9_RETIMER_CPU0_PMSCL")
		)
	)
	(footprint ""
		(layer "F.Cu")
		(at 34.665158 -172.53966)
		(property "Reference" "R5011"
			(at 0 0 0)
			(layer "F.SilkS")
			(hide yes)
			(effects
				(font
					(size 1.27 1.27)
				)
			)
		)
		(property "Value" ""
			(at 0 0 0)
			(layer "F.Fab")
			(effects
				(font
					(size 1.27 1.27)
				)
			)
		)
		(duplicate_pad_numbers_are_jumpers no)
		(fp_line
			(start -0.7874 -0.4064)
			(end 0.7874 -0.4064)
			(stroke
				(width 0.1524)
				(type default)
			)
			(layer "F.SilkS")
		)
		(fp_line
			(start -0.7874 0.4064)
			(end -0.7874 -0.4064)
			(stroke
				(width 0.1524)
				(type default)
			)
			(layer "F.SilkS")
		)
		(fp_line
			(start 0.7874 -0.4064)
			(end 0.7874 0.4064)
			(stroke
				(width 0.1524)
				(type default)
			)
			(layer "F.SilkS")
		)
		(fp_line
			(start 0.7874 0.4064)
			(end -0.7874 0.4064)
			(stroke
				(width 0.1524)
				(type default)
			)
			(layer "F.SilkS")
		)
		(fp_line
			(start -0.67945 -0.305054)
			(end -0.12065 -0.305054)
			(stroke
				(width 0.1)
				(type default)
			)
			(layer "F.Fab")
		)
		(fp_line
			(start -0.67945 0.3048)
			(end -0.67945 -0.305054)
			(stroke
				(width 0.1)
				(type default)
			)
			(layer "F.Fab")
		)
		(fp_line
			(start -0.12065 -0.305054)
			(end -0.12065 -0.2794)
			(stroke
				(width 0.1)
				(type default)
			)
			(layer "F.Fab")
		)
		(fp_line
			(start -0.12065 -0.2794)
			(end 0.12065 -0.2794)
			(stroke
				(width 0.1)
				(type default)
			)
			(layer "F.Fab")
		)
		(fp_line
			(start -0.12065 0.2794)
			(end -0.12065 0.3048)
			(stroke
				(width 0.1)
				(type default)
			)
			(layer "F.Fab")
		)
		(fp_line
			(start -0.12065 0.3048)
			(end -0.67945 0.3048)
			(stroke
				(width 0.1)
				(type default)
			)
			(layer "F.Fab")
		)
		(fp_line
			(start 0.120396 0.2794)
			(end -0.12065 0.2794)
			(stroke
				(width 0.1)
				(type default)
			)
			(layer "F.Fab")
		)
		(fp_line
			(start 0.120396 0.3048)
			(end 0.120396 0.2794)
			(stroke
				(width 0.1)
				(type default)
			)
			(layer "F.Fab")
		)
		(fp_line
			(start 0.12065 -0.3048)
			(end 0.67945 -0.3048)
			(stroke
				(width 0.1)
				(type default)
			)
			(layer "F.Fab")
		)
		(fp_line
			(start 0.12065 -0.2794)
			(end 0.12065 -0.3048)
			(stroke
				(width 0.1)
				(type default)
			)
			(layer "F.Fab")
		)
		(fp_line
			(start 0.67945 -0.3048)
			(end 0.67945 0.3048)
			(stroke
				(width 0.1)
				(type default)
			)
			(layer "F.Fab")
		)
		(fp_line
			(start 0.67945 0.3048)
			(end 0.120396 0.3048)
			(stroke
				(width 0.1)
				(type default)
			)
			(layer "F.Fab")
		)
		(pad "1" smd circle
			(at -0.40005 0)
			(size 0 0)
			(layers "F.Cu" "F.Mask" "F.Paste")
			(net "PVDD11_S3_P1")
		)
		(pad "2" smd circle
			(at 0.40005 0)
			(size 0 0)
			(layers "F.Cu" "F.Mask" "F.Paste")
			(net "I3C_SPD_DDRAF_CPU1_LVC1_SDA")
		)
	)
	(footprint ""
		(layer "F.Cu")
		(at 367.996978 -175.106076 -90)
		(property "Reference" "PC475"
			(at 0 0 270)
			(layer "F.SilkS")
			(hide yes)
			(effects
				(font
					(size 1.27 1.27)
				)
			)
		)
		(property "Value" ""
			(at 0 0 270)
			(layer "F.Fab")
			(effects
				(font
					(size 1.27 1.27)
				)
			)
		)
		(duplicate_pad_numbers_are_jumpers no)
		(fp_line
			(start -0.7874 0.4064)
			(end -0.7874 -0.4064)
			(stroke
				(width 0.1524)
				(type default)
			)
			(layer "F.SilkS")
		)
		(fp_line
			(start -0.255524 0.4064)
			(end -0.7874 0.4064)
			(stroke
				(width 0.1524)
				(type default)
			)
			(layer "F.SilkS")
		)
		(fp_line
			(start 0.7874 0.4064)
			(end 0.404876 0.4064)
			(stroke
				(width 0.1524)
				(type default)
			)
			(layer "F.SilkS")
		)
		(fp_line
			(start -0.7874 -0.4064)
			(end 0.7874 -0.4064)
			(stroke
				(width 0.1524)
				(type default)
			)
			(layer "F.SilkS")
		)
		(fp_line
			(start 0.7874 -0.4064)
			(end 0.7874 0.4064)
			(stroke
				(width 0.1524)
				(type default)
			)
			(layer "F.SilkS")
		)
		(fp_line
			(start -0.67945 0.3048)
			(end -0.67945 -0.305054)
			(stroke
				(width 0.1)
				(type default)
			)
			(layer "F.Fab")
		)
		(fp_line
			(start -0.12065 0.3048)
			(end -0.67945 0.3048)
			(stroke
				(width 0.1)
				(type default)
			)
			(layer "F.Fab")
		)
		(fp_line
			(start 0.120396 0.3048)
			(end 0.120396 0.2794)
			(stroke
				(width 0.1)
				(type default)
			)
			(layer "F.Fab")
		)
		(fp_line
			(start 0.67945 0.3048)
			(end 0.120396 0.3048)
			(stroke
				(width 0.1)
				(type default)
			)
			(layer "F.Fab")
		)
		(fp_line
			(start -0.12065 0.2794)
			(end -0.12065 0.3048)
			(stroke
				(width 0.1)
				(type default)
			)
			(layer "F.Fab")
		)
		(fp_line
			(start 0.120396 0.2794)
			(end -0.12065 0.2794)
			(stroke
				(width 0.1)
				(type default)
			)
			(layer "F.Fab")
		)
		(fp_line
			(start -0.12065 -0.2794)
			(end 0.12065 -0.2794)
			(stroke
				(width 0.1)
				(type default)
			)
			(layer "F.Fab")
		)
		(fp_line
			(start 0.12065 -0.2794)
			(end 0.12065 -0.3048)
			(stroke
				(width 0.1)
				(type default)
			)
			(layer "F.Fab")
		)
		(fp_line
			(start 0.12065 -0.3048)
			(end 0.67945 -0.3048)
			(stroke
				(width 0.1)
				(type default)
			)
			(layer "F.Fab")
		)
		(fp_line
			(start 0.67945 -0.3048)
			(end 0.67945 0.3048)
			(stroke
				(width 0.1)
				(type default)
			)
			(layer "F.Fab")
		)
		(fp_line
			(start -0.67945 -0.305054)
			(end -0.12065 -0.305054)
			(stroke
				(width 0.1)
				(type default)
			)
			(layer "F.Fab")
		)
		(fp_line
			(start -0.12065 -0.305054)
			(end -0.12065 -0.2794)
			(stroke
				(width 0.1)
				(type default)
			)
			(layer "F.Fab")
		)
		(pad "1" smd circle
			(at -0.40005 0 270)
			(size 0 0)
			(layers "F.Cu" "F.Mask" "F.Paste")
			(net "PVDDCR_CPU0_P0_VCC1")
		)
		(pad "2" smd circle
			(at 0.40005 0 270)
			(size 0 0)
			(layers "F.Cu" "F.Mask" "F.Paste")
			(net "GND")
		)
	)
	(footprint ""
		(layer "F.Cu")
		(at 178.943 -137.632948 -90)
		(property "Reference" "R198"
			(at 0 0 270)
			(layer "F.SilkS")
			(hide yes)
			(effects
				(font
					(size 1.27 1.27)
				)
			)
		)
		(property "Value" ""
			(at 0 0 270)
			(layer "F.Fab")
			(effects
				(font
					(size 1.27 1.27)
				)
			)
		)
		(duplicate_pad_numbers_are_jumpers no)
		(fp_line
			(start -0.7874 0.4064)
			(end -0.7874 -0.4064)
			(stroke
				(width 0.1524)
				(type default)
			)
			(layer "F.SilkS")
		)
		(fp_line
			(start 0.7874 0.4064)
			(end -0.7874 0.4064)
			(stroke
				(width 0.1524)
				(type default)
			)
			(layer "F.SilkS")
		)
		(fp_line
			(start -0.7874 -0.4064)
			(end 0.7874 -0.4064)
			(stroke
				(width 0.1524)
				(type default)
			)
			(layer "F.SilkS")
		)
		(fp_line
			(start 0.7874 -0.4064)
			(end 0.7874 0.4064)
			(stroke
				(width 0.1524)
				(type default)
			)
			(layer "F.SilkS")
		)
		(fp_line
			(start -0.67945 0.3048)
			(end -0.67945 -0.305054)
			(stroke
				(width 0.1)
				(type default)
			)
			(layer "F.Fab")
		)
		(fp_line
			(start -0.12065 0.3048)
			(end -0.67945 0.3048)
			(stroke
				(width 0.1)
				(type default)
			)
			(layer "F.Fab")
		)
		(fp_line
			(start 0.120396 0.3048)
			(end 0.120396 0.2794)
			(stroke
				(width 0.1)
				(type default)
			)
			(layer "F.Fab")
		)
		(fp_line
			(start 0.67945 0.3048)
			(end 0.120396 0.3048)
			(stroke
				(width 0.1)
				(type default)
			)
			(layer "F.Fab")
		)
		(fp_line
			(start -0.12065 0.2794)
			(end -0.12065 0.3048)
			(stroke
				(width 0.1)
				(type default)
			)
			(layer "F.Fab")
		)
		(fp_line
			(start 0.120396 0.2794)
			(end -0.12065 0.2794)
			(stroke
				(width 0.1)
				(type default)
			)
			(layer "F.Fab")
		)
		(fp_line
			(start -0.12065 -0.2794)
			(end 0.12065 -0.2794)
			(stroke
				(width 0.1)
				(type default)
			)
			(layer "F.Fab")
		)
		(fp_line
			(start 0.12065 -0.2794)
			(end 0.12065 -0.3048)
			(stroke
				(width 0.1)
				(type default)
			)
			(layer "F.Fab")
		)
		(fp_line
			(start 0.12065 -0.3048)
			(end 0.67945 -0.3048)
			(stroke
				(width 0.1)
				(type default)
			)
			(layer "F.Fab")
		)
		(fp_line
			(start 0.67945 -0.3048)
			(end 0.67945 0.3048)
			(stroke
				(width 0.1)
				(type default)
			)
			(layer "F.Fab")
		)
		(fp_line
			(start -0.67945 -0.305054)
			(end -0.12065 -0.305054)
			(stroke
				(width 0.1)
				(type default)
			)
			(layer "F.Fab")
		)
		(fp_line
			(start -0.12065 -0.305054)
			(end -0.12065 -0.2794)
			(stroke
				(width 0.1)
				(type default)
			)
			(layer "F.Fab")
		)
		(pad "1" smd circle
			(at -0.40005 0 270)
			(size 0 0)
			(layers "F.Cu" "F.Mask" "F.Paste")
			(net "RST_CPU1_PERST1_N")
		)
		(pad "2" smd circle
			(at 0.40005 0 270)
			(size 0 0)
			(layers "F.Cu" "F.Mask" "F.Paste")
			(net "RST_CPU1_PERST1_R_N")
		)
	)
	(footprint ""
		(layer "F.Cu")
		(at 42.672 -170.307)
		(property "Reference" "R564"
			(at 0 0 0)
			(layer "F.SilkS")
			(hide yes)
			(effects
				(font
					(size 1.27 1.27)
				)
			)
		)
		(property "Value" ""
			(at 0 0 0)
			(layer "F.Fab")
			(effects
				(font
					(size 1.27 1.27)
				)
			)
		)
		(duplicate_pad_numbers_are_jumpers no)
		(fp_line
			(start -0.7874 -0.4064)
			(end 0.7874 -0.4064)
			(stroke
				(width 0.1524)
				(type default)
			)
			(layer "F.SilkS")
		)
		(fp_line
			(start -0.7874 0.4064)
			(end -0.7874 -0.4064)
			(stroke
				(width 0.1524)
				(type default)
			)
			(layer "F.SilkS")
		)
		(fp_line
			(start 0.7874 -0.4064)
			(end 0.7874 0.4064)
			(stroke
				(width 0.1524)
				(type default)
			)
			(layer "F.SilkS")
		)
		(fp_line
			(start 0.7874 0.4064)
			(end -0.7874 0.4064)
			(stroke
				(width 0.1524)
				(type default)
			)
			(layer "F.SilkS")
		)
		(fp_line
			(start -0.67945 -0.305054)
			(end -0.12065 -0.305054)
			(stroke
				(width 0.1)
				(type default)
			)
			(layer "F.Fab")
		)
		(fp_line
			(start -0.67945 0.3048)
			(end -0.67945 -0.305054)
			(stroke
				(width 0.1)
				(type default)
			)
			(layer "F.Fab")
		)
		(fp_line
			(start -0.12065 -0.305054)
			(end -0.12065 -0.2794)
			(stroke
				(width 0.1)
				(type default)
			)
			(layer "F.Fab")
		)
		(fp_line
			(start -0.12065 -0.2794)
			(end 0.12065 -0.2794)
			(stroke
				(width 0.1)
				(type default)
			)
			(layer "F.Fab")
		)
		(fp_line
			(start -0.12065 0.2794)
			(end -0.12065 0.3048)
			(stroke
				(width 0.1)
				(type default)
			)
			(layer "F.Fab")
		)
		(fp_line
			(start -0.12065 0.3048)
			(end -0.67945 0.3048)
			(stroke
				(width 0.1)
				(type default)
			)
			(layer "F.Fab")
		)
		(fp_line
			(start 0.120396 0.2794)
			(end -0.12065 0.2794)
			(stroke
				(width 0.1)
				(type default)
			)
			(layer "F.Fab")
		)
		(fp_line
			(start 0.120396 0.3048)
			(end 0.120396 0.2794)
			(stroke
				(width 0.1)
				(type default)
			)
			(layer "F.Fab")
		)
		(fp_line
			(start 0.12065 -0.3048)
			(end 0.67945 -0.3048)
			(stroke
				(width 0.1)
				(type default)
			)
			(layer "F.Fab")
		)
		(fp_line
			(start 0.12065 -0.2794)
			(end 0.12065 -0.3048)
			(stroke
				(width 0.1)
				(type default)
			)
			(layer "F.Fab")
		)
		(fp_line
			(start 0.67945 -0.3048)
			(end 0.67945 0.3048)
			(stroke
				(width 0.1)
				(type default)
			)
			(layer "F.Fab")
		)
		(fp_line
			(start 0.67945 0.3048)
			(end 0.120396 0.3048)
			(stroke
				(width 0.1)
				(type default)
			)
			(layer "F.Fab")
		)
		(pad "1" smd rect
			(at -0.40005 0 180)
			(size 0.4572 0.508)
			(layers "F.Cu" "F.Mask" "F.Paste")
			(net "I3C_0_SPD_DDRAF_CPU1_SCL")
		)
		(pad "2" smd rect
			(at 0.40005 0 180)
			(size 0.4572 0.508)
			(layers "F.Cu" "F.Mask" "F.Paste")
			(net "I3C_0_SPD_DDRAF_CPU1_R_SCL")
		)
	)
	(footprint ""
		(layer "F.Cu")
		(at 181.388766 -168.317418 -90)
		(property "Reference" "R1295"
			(at 0 0 270)
			(layer "F.SilkS")
			(hide yes)
			(effects
				(font
					(size 1.27 1.27)
				)
			)
		)
		(property "Value" ""
			(at 0 0 270)
			(layer "F.Fab")
			(effects
				(font
					(size 1.27 1.27)
				)
			)
		)
		(duplicate_pad_numbers_are_jumpers no)
		(fp_line
			(start -0.7874 0.4064)
			(end -0.7874 -0.4064)
			(stroke
				(width 0.1524)
				(type default)
			)
			(layer "F.SilkS")
		)
		(fp_line
			(start 0.7874 0.4064)
			(end -0.7874 0.4064)
			(stroke
				(width 0.1524)
				(type default)
			)
			(layer "F.SilkS")
		)
		(fp_line
			(start -0.7874 -0.4064)
			(end 0.7874 -0.4064)
			(stroke
				(width 0.1524)
				(type default)
			)
			(layer "F.SilkS")
		)
		(fp_line
			(start 0.7874 -0.4064)
			(end 0.7874 0.4064)
			(stroke
				(width 0.1524)
				(type default)
			)
			(layer "F.SilkS")
		)
		(fp_line
			(start -0.67945 0.3048)
			(end -0.67945 -0.305054)
			(stroke
				(width 0.1)
				(type default)
			)
			(layer "F.Fab")
		)
		(fp_line
			(start -0.12065 0.3048)
			(end -0.67945 0.3048)
			(stroke
				(width 0.1)
				(type default)
			)
			(layer "F.Fab")
		)
		(fp_line
			(start 0.120396 0.3048)
			(end 0.120396 0.2794)
			(stroke
				(width 0.1)
				(type default)
			)
			(layer "F.Fab")
		)
		(fp_line
			(start 0.67945 0.3048)
			(end 0.120396 0.3048)
			(stroke
				(width 0.1)
				(type default)
			)
			(layer "F.Fab")
		)
		(fp_line
			(start -0.12065 0.2794)
			(end -0.12065 0.3048)
			(stroke
				(width 0.1)
				(type default)
			)
			(layer "F.Fab")
		)
		(fp_line
			(start 0.120396 0.2794)
			(end -0.12065 0.2794)
			(stroke
				(width 0.1)
				(type default)
			)
			(layer "F.Fab")
		)
		(fp_line
			(start -0.12065 -0.2794)
			(end 0.12065 -0.2794)
			(stroke
				(width 0.1)
				(type default)
			)
			(layer "F.Fab")
		)
		(fp_line
			(start 0.12065 -0.2794)
			(end 0.12065 -0.3048)
			(stroke
				(width 0.1)
				(type default)
			)
			(layer "F.Fab")
		)
		(fp_line
			(start 0.12065 -0.3048)
			(end 0.67945 -0.3048)
			(stroke
				(width 0.1)
				(type default)
			)
			(layer "F.Fab")
		)
		(fp_line
			(start 0.67945 -0.3048)
			(end 0.67945 0.3048)
			(stroke
				(width 0.1)
				(type default)
			)
			(layer "F.Fab")
		)
		(fp_line
			(start -0.67945 -0.305054)
			(end -0.12065 -0.305054)
			(stroke
				(width 0.1)
				(type default)
			)
			(layer "F.Fab")
		)
		(fp_line
			(start -0.12065 -0.305054)
			(end -0.12065 -0.2794)
			(stroke
				(width 0.1)
				(type default)
			)
			(layer "F.Fab")
		)
		(pad "1" smd rect
			(at -0.40005 0 90)
			(size 0.4572 0.508)
			(layers "F.Cu" "F.Mask" "F.Paste")
			(net "I3C_SPD_DDRGL_CPU1_SCL")
		)
		(pad "2" smd rect
			(at 0.40005 0 90)
			(size 0.4572 0.508)
			(layers "F.Cu" "F.Mask" "F.Paste")
			(net "I3C_SPD_DDRGL_CPU1_LVC1_SCL")
		)
	)
	(footprint ""
		(layer "F.Cu")
		(at 157.677358 -353.245928 180)
		(property "Reference" "C5010"
			(at 0 0 180)
			(layer "F.SilkS")
			(hide yes)
			(effects
				(font
					(size 1.27 1.27)
				)
			)
		)
		(property "Value" ""
			(at 0 0 180)
			(layer "F.Fab")
			(effects
				(font
					(size 1.27 1.27)
				)
			)
		)
		(duplicate_pad_numbers_are_jumpers no)
		(fp_line
			(start 0.7874 0.4064)
			(end -0.7874 0.4064)
			(stroke
				(width 0.1524)
				(type default)
			)
			(layer "F.SilkS")
		)
		(fp_line
			(start 0.7874 -0.4064)
			(end 0.7874 0.4064)
			(stroke
				(width 0.1524)
				(type default)
			)
			(layer "F.SilkS")
		)
		(fp_line
			(start -0.7874 0.4064)
			(end -0.7874 -0.4064)
			(stroke
				(width 0.1524)
				(type default)
			)
			(layer "F.SilkS")
		)
		(fp_line
			(start -0.7874 -0.4064)
			(end 0.7874 -0.4064)
			(stroke
				(width 0.1524)
				(type default)
			)
			(layer "F.SilkS")
		)
		(fp_line
			(start 0.67945 0.3048)
			(end 0.120396 0.3048)
			(stroke
				(width 0.1)
				(type default)
			)
			(layer "F.Fab")
		)
		(fp_line
			(start 0.67945 -0.3048)
			(end 0.67945 0.3048)
			(stroke
				(width 0.1)
				(type default)
			)
			(layer "F.Fab")
		)
		(fp_line
			(start 0.12065 -0.2794)
			(end 0.12065 -0.3048)
			(stroke
				(width 0.1)
				(type default)
			)
			(layer "F.Fab")
		)
		(fp_line
			(start 0.12065 -0.3048)
			(end 0.67945 -0.3048)
			(stroke
				(width 0.1)
				(type default)
			)
			(layer "F.Fab")
		)
		(fp_line
			(start 0.120396 0.3048)
			(end 0.120396 0.2794)
			(stroke
				(width 0.1)
				(type default)
			)
			(layer "F.Fab")
		)
		(fp_line
			(start 0.120396 0.2794)
			(end -0.12065 0.2794)
			(stroke
				(width 0.1)
				(type default)
			)
			(layer "F.Fab")
		)
		(fp_line
			(start -0.12065 0.3048)
			(end -0.67945 0.3048)
			(stroke
				(width 0.1)
				(type default)
			)
			(layer "F.Fab")
		)
		(fp_line
			(start -0.12065 0.2794)
			(end -0.12065 0.3048)
			(stroke
				(width 0.1)
				(type default)
			)
			(layer "F.Fab")
		)
		(fp_line
			(start -0.12065 -0.2794)
			(end 0.12065 -0.2794)
			(stroke
				(width 0.1)
				(type default)
			)
			(layer "F.Fab")
		)
		(fp_line
			(start -0.12065 -0.305054)
			(end -0.12065 -0.2794)
			(stroke
				(width 0.1)
				(type default)
			)
			(layer "F.Fab")
		)
		(fp_line
			(start -0.67945 0.3048)
			(end -0.67945 -0.305054)
			(stroke
				(width 0.1)
				(type default)
			)
			(layer "F.Fab")
		)
		(fp_line
			(start -0.67945 -0.305054)
			(end -0.12065 -0.305054)
			(stroke
				(width 0.1)
				(type default)
			)
			(layer "F.Fab")
		)
		(pad "1" smd circle
			(at -0.40005 0 180)
			(size 0 0)
			(layers "F.Cu" "F.Mask" "F.Paste")
			(net "PVDD11_S3_P1_PMALERT")
		)
		(pad "2" smd circle
			(at 0.40005 0 180)
			(size 0 0)
			(layers "F.Cu" "F.Mask" "F.Paste")
			(net "GND")
		)
	)
	(footprint ""
		(layer "F.Cu")
		(at 173.08576 -351.825052)
		(property "Reference" "H22"
			(at -3.9116 -3.96113 0)
			(unlocked yes)
			(layer "F.SilkS")
			(effects
				(font
					(size 0.7874 0.5842)
					(thickness 0.1524)
				)
				(justify left)
			)
		)
		(property "Value" ""
			(at 0 0 0)
			(layer "F.Fab")
			(effects
				(font
					(size 1.27 1.27)
				)
			)
		)
		(duplicate_pad_numbers_are_jumpers no)
		(pad "1" thru_hole circle
			(at 0 0)
			(size 6.1976 6.1976)
			(drill 3.7338)
			(layers "*.Cu" "*.Mask")
			(remove_unused_layers no)
			(net "GND")
			(clearance -0.9779)
			(padstack
				(mode front_inner_back)
				(layer "Inner"
					(shape circle)
					(size 5.5372 5.5372)
					(clearance -0.6477)
				)
				(layer "B.Cu"
					(shape circle)
					(size 6.1976 6.1976)
					(clearance -0.9779)
				)
			)
		)
	)
	(footprint ""
		(layer "F.Cu")
		(at 120.396 -420.497)
		(property "Reference" "R3431"
			(at 0 0 0)
			(layer "F.SilkS")
			(hide yes)
			(effects
				(font
					(size 1.27 1.27)
				)
			)
		)
		(property "Value" ""
			(at 0 0 0)
			(layer "F.Fab")
			(effects
				(font
					(size 1.27 1.27)
				)
			)
		)
		(duplicate_pad_numbers_are_jumpers no)
		(fp_line
			(start -0.7874 -0.4064)
			(end 0.7874 -0.4064)
			(stroke
				(width 0.1524)
				(type default)
			)
			(layer "F.SilkS")
		)
		(fp_line
			(start -0.7874 0.4064)
			(end -0.7874 -0.4064)
			(stroke
				(width 0.1524)
				(type default)
			)
			(layer "F.SilkS")
		)
		(fp_line
			(start 0.7874 -0.4064)
			(end 0.7874 0.4064)
			(stroke
				(width 0.1524)
				(type default)
			)
			(layer "F.SilkS")
		)
		(fp_line
			(start 0.7874 0.4064)
			(end -0.7874 0.4064)
			(stroke
				(width 0.1524)
				(type default)
			)
			(layer "F.SilkS")
		)
		(fp_line
			(start -0.67945 -0.305054)
			(end -0.12065 -0.305054)
			(stroke
				(width 0.1)
				(type default)
			)
			(layer "F.Fab")
		)
		(fp_line
			(start -0.67945 0.3048)
			(end -0.67945 -0.305054)
			(stroke
				(width 0.1)
				(type default)
			)
			(layer "F.Fab")
		)
		(fp_line
			(start -0.12065 -0.305054)
			(end -0.12065 -0.2794)
			(stroke
				(width 0.1)
				(type default)
			)
			(layer "F.Fab")
		)
		(fp_line
			(start -0.12065 -0.2794)
			(end 0.12065 -0.2794)
			(stroke
				(width 0.1)
				(type default)
			)
			(layer "F.Fab")
		)
		(fp_line
			(start -0.12065 0.2794)
			(end -0.12065 0.3048)
			(stroke
				(width 0.1)
				(type default)
			)
			(layer "F.Fab")
		)
		(fp_line
			(start -0.12065 0.3048)
			(end -0.67945 0.3048)
			(stroke
				(width 0.1)
				(type default)
			)
			(layer "F.Fab")
		)
		(fp_line
			(start 0.120396 0.2794)
			(end -0.12065 0.2794)
			(stroke
				(width 0.1)
				(type default)
			)
			(layer "F.Fab")
		)
		(fp_line
			(start 0.120396 0.3048)
			(end 0.120396 0.2794)
			(stroke
				(width 0.1)
				(type default)
			)
			(layer "F.Fab")
		)
		(fp_line
			(start 0.12065 -0.3048)
			(end 0.67945 -0.3048)
			(stroke
				(width 0.1)
				(type default)
			)
			(layer "F.Fab")
		)
		(fp_line
			(start 0.12065 -0.2794)
			(end 0.12065 -0.3048)
			(stroke
				(width 0.1)
				(type default)
			)
			(layer "F.Fab")
		)
		(fp_line
			(start 0.67945 -0.3048)
			(end 0.67945 0.3048)
			(stroke
				(width 0.1)
				(type default)
			)
			(layer "F.Fab")
		)
		(fp_line
			(start 0.67945 0.3048)
			(end 0.120396 0.3048)
			(stroke
				(width 0.1)
				(type default)
			)
			(layer "F.Fab")
		)
		(pad "1" smd circle
			(at -0.40005 0)
			(size 0 0)
			(layers "F.Cu" "F.Mask" "F.Paste")
			(net "GPU_HMC_PRSNT_N")
		)
		(pad "2" smd circle
			(at 0.40005 0)
			(size 0 0)
			(layers "F.Cu" "F.Mask" "F.Paste")
			(net "GND")
		)
	)
	(footprint ""
		(layer "F.Cu")
		(at 313.313064 -346.863924 -90)
		(property "Reference" "PC115_4"
			(at 0 0 270)
			(layer "F.SilkS")
			(hide yes)
			(effects
				(font
					(size 1.27 1.27)
				)
			)
		)
		(property "Value" ""
			(at 0 0 270)
			(layer "F.Fab")
			(effects
				(font
					(size 1.27 1.27)
				)
			)
		)
		(duplicate_pad_numbers_are_jumpers no)
		(fp_line
			(start -0.7874 0.4064)
			(end -0.7874 -0.4064)
			(stroke
				(width 0.1524)
				(type default)
			)
			(layer "F.SilkS")
		)
		(fp_line
			(start 0.7874 0.4064)
			(end -0.7874 0.4064)
			(stroke
				(width 0.1524)
				(type default)
			)
			(layer "F.SilkS")
		)
		(fp_line
			(start -0.7874 -0.4064)
			(end 0.7874 -0.4064)
			(stroke
				(width 0.1524)
				(type default)
			)
			(layer "F.SilkS")
		)
		(fp_line
			(start 0.7874 -0.4064)
			(end 0.7874 0.4064)
			(stroke
				(width 0.1524)
				(type default)
			)
			(layer "F.SilkS")
		)
		(fp_line
			(start -0.67945 0.3048)
			(end -0.67945 -0.305054)
			(stroke
				(width 0.1)
				(type default)
			)
			(layer "F.Fab")
		)
		(fp_line
			(start -0.12065 0.3048)
			(end -0.67945 0.3048)
			(stroke
				(width 0.1)
				(type default)
			)
			(layer "F.Fab")
		)
		(fp_line
			(start 0.120396 0.3048)
			(end 0.120396 0.2794)
			(stroke
				(width 0.1)
				(type default)
			)
			(layer "F.Fab")
		)
		(fp_line
			(start 0.67945 0.3048)
			(end 0.120396 0.3048)
			(stroke
				(width 0.1)
				(type default)
			)
			(layer "F.Fab")
		)
		(fp_line
			(start -0.12065 0.2794)
			(end -0.12065 0.3048)
			(stroke
				(width 0.1)
				(type default)
			)
			(layer "F.Fab")
		)
		(fp_line
			(start 0.120396 0.2794)
			(end -0.12065 0.2794)
			(stroke
				(width 0.1)
				(type default)
			)
			(layer "F.Fab")
		)
		(fp_line
			(start -0.12065 -0.2794)
			(end 0.12065 -0.2794)
			(stroke
				(width 0.1)
				(type default)
			)
			(layer "F.Fab")
		)
		(fp_line
			(start 0.12065 -0.2794)
			(end 0.12065 -0.3048)
			(stroke
				(width 0.1)
				(type default)
			)
			(layer "F.Fab")
		)
		(fp_line
			(start 0.12065 -0.3048)
			(end 0.67945 -0.3048)
			(stroke
				(width 0.1)
				(type default)
			)
			(layer "F.Fab")
		)
		(fp_line
			(start 0.67945 -0.3048)
			(end 0.67945 0.3048)
			(stroke
				(width 0.1)
				(type default)
			)
			(layer "F.Fab")
		)
		(fp_line
			(start -0.67945 -0.305054)
			(end -0.12065 -0.305054)
			(stroke
				(width 0.1)
				(type default)
			)
			(layer "F.Fab")
		)
		(fp_line
			(start -0.12065 -0.305054)
			(end -0.12065 -0.2794)
			(stroke
				(width 0.1)
				(type default)
			)
			(layer "F.Fab")
		)
		(pad "1" smd circle
			(at -0.40005 0 270)
			(size 0 0)
			(layers "F.Cu" "F.Mask" "F.Paste")
			(net "SW_P12V_AUX_PVDDCR_CPU1_P0_FLT")
		)
		(pad "2" smd circle
			(at 0.40005 0 270)
			(size 0 0)
			(layers "F.Cu" "F.Mask" "F.Paste")
			(net "GND")
		)
	)
	(footprint ""
		(layer "F.Cu")
		(at 223.70288 -43.525948)
		(property "Reference" "R3533"
			(at 0 0 0)
			(layer "F.SilkS")
			(hide yes)
			(effects
				(font
					(size 1.27 1.27)
				)
			)
		)
		(property "Value" ""
			(at 0 0 0)
			(layer "F.Fab")
			(effects
				(font
					(size 1.27 1.27)
				)
			)
		)
		(duplicate_pad_numbers_are_jumpers no)
		(fp_line
			(start -0.7874 -0.4064)
			(end 0.7874 -0.4064)
			(stroke
				(width 0.1524)
				(type default)
			)
			(layer "F.SilkS")
		)
		(fp_line
			(start -0.7874 0.4064)
			(end -0.7874 -0.4064)
			(stroke
				(width 0.1524)
				(type default)
			)
			(layer "F.SilkS")
		)
		(fp_line
			(start 0.7874 -0.4064)
			(end 0.7874 0.4064)
			(stroke
				(width 0.1524)
				(type default)
			)
			(layer "F.SilkS")
		)
		(fp_line
			(start 0.7874 0.4064)
			(end -0.7874 0.4064)
			(stroke
				(width 0.1524)
				(type default)
			)
			(layer "F.SilkS")
		)
		(fp_line
			(start -0.67945 -0.305054)
			(end -0.12065 -0.305054)
			(stroke
				(width 0.1)
				(type default)
			)
			(layer "F.Fab")
		)
		(fp_line
			(start -0.67945 0.3048)
			(end -0.67945 -0.305054)
			(stroke
				(width 0.1)
				(type default)
			)
			(layer "F.Fab")
		)
		(fp_line
			(start -0.12065 -0.305054)
			(end -0.12065 -0.2794)
			(stroke
				(width 0.1)
				(type default)
			)
			(layer "F.Fab")
		)
		(fp_line
			(start -0.12065 -0.2794)
			(end 0.12065 -0.2794)
			(stroke
				(width 0.1)
				(type default)
			)
			(layer "F.Fab")
		)
		(fp_line
			(start -0.12065 0.2794)
			(end -0.12065 0.3048)
			(stroke
				(width 0.1)
				(type default)
			)
			(layer "F.Fab")
		)
		(fp_line
			(start -0.12065 0.3048)
			(end -0.67945 0.3048)
			(stroke
				(width 0.1)
				(type default)
			)
			(layer "F.Fab")
		)
		(fp_line
			(start 0.120396 0.2794)
			(end -0.12065 0.2794)
			(stroke
				(width 0.1)
				(type default)
			)
			(layer "F.Fab")
		)
		(fp_line
			(start 0.120396 0.3048)
			(end 0.120396 0.2794)
			(stroke
				(width 0.1)
				(type default)
			)
			(layer "F.Fab")
		)
		(fp_line
			(start 0.12065 -0.3048)
			(end 0.67945 -0.3048)
			(stroke
				(width 0.1)
				(type default)
			)
			(layer "F.Fab")
		)
		(fp_line
			(start 0.12065 -0.2794)
			(end 0.12065 -0.3048)
			(stroke
				(width 0.1)
				(type default)
			)
			(layer "F.Fab")
		)
		(fp_line
			(start 0.67945 -0.3048)
			(end 0.67945 0.3048)
			(stroke
				(width 0.1)
				(type default)
			)
			(layer "F.Fab")
		)
		(fp_line
			(start 0.67945 0.3048)
			(end 0.120396 0.3048)
			(stroke
				(width 0.1)
				(type default)
			)
			(layer "F.Fab")
		)
		(pad "1" smd circle
			(at -0.40005 0)
			(size 0 0)
			(layers "F.Cu" "F.Mask" "F.Paste")
			(net "SMB_E1S_3V3AUX_ISO_SCL_R")
		)
		(pad "2" smd circle
			(at 0.40005 0)
			(size 0 0)
			(layers "F.Cu" "F.Mask" "F.Paste")
			(net "SMB_E1S_3V3AUX_ISO_SCL")
		)
	)
	(footprint ""
		(layer "F.Cu")
		(at 183.364886 -427.449234 -90)
		(property "Reference" "R9019"
			(at 0 0 270)
			(layer "F.SilkS")
			(hide yes)
			(effects
				(font
					(size 1.27 1.27)
				)
			)
		)
		(property "Value" ""
			(at 0 0 270)
			(layer "F.Fab")
			(effects
				(font
					(size 1.27 1.27)
				)
			)
		)
		(duplicate_pad_numbers_are_jumpers no)
		(fp_line
			(start -0.7874 0.4064)
			(end -0.7874 -0.4064)
			(stroke
				(width 0.1524)
				(type default)
			)
			(layer "F.SilkS")
		)
		(fp_line
			(start 0.7874 0.4064)
			(end -0.7874 0.4064)
			(stroke
				(width 0.1524)
				(type default)
			)
			(layer "F.SilkS")
		)
		(fp_line
			(start -0.7874 -0.4064)
			(end 0.7874 -0.4064)
			(stroke
				(width 0.1524)
				(type default)
			)
			(layer "F.SilkS")
		)
		(fp_line
			(start 0.7874 -0.4064)
			(end 0.7874 0.4064)
			(stroke
				(width 0.1524)
				(type default)
			)
			(layer "F.SilkS")
		)
		(fp_line
			(start -0.67945 0.3048)
			(end -0.67945 -0.305054)
			(stroke
				(width 0.1)
				(type default)
			)
			(layer "F.Fab")
		)
		(fp_line
			(start -0.12065 0.3048)
			(end -0.67945 0.3048)
			(stroke
				(width 0.1)
				(type default)
			)
			(layer "F.Fab")
		)
		(fp_line
			(start 0.120396 0.3048)
			(end 0.120396 0.2794)
			(stroke
				(width 0.1)
				(type default)
			)
			(layer "F.Fab")
		)
		(fp_line
			(start 0.67945 0.3048)
			(end 0.120396 0.3048)
			(stroke
				(width 0.1)
				(type default)
			)
			(layer "F.Fab")
		)
		(fp_line
			(start -0.12065 0.2794)
			(end -0.12065 0.3048)
			(stroke
				(width 0.1)
				(type default)
			)
			(layer "F.Fab")
		)
		(fp_line
			(start 0.120396 0.2794)
			(end -0.12065 0.2794)
			(stroke
				(width 0.1)
				(type default)
			)
			(layer "F.Fab")
		)
		(fp_line
			(start -0.12065 -0.2794)
			(end 0.12065 -0.2794)
			(stroke
				(width 0.1)
				(type default)
			)
			(layer "F.Fab")
		)
		(fp_line
			(start 0.12065 -0.2794)
			(end 0.12065 -0.3048)
			(stroke
				(width 0.1)
				(type default)
			)
			(layer "F.Fab")
		)
		(fp_line
			(start 0.12065 -0.3048)
			(end 0.67945 -0.3048)
			(stroke
				(width 0.1)
				(type default)
			)
			(layer "F.Fab")
		)
		(fp_line
			(start 0.67945 -0.3048)
			(end 0.67945 0.3048)
			(stroke
				(width 0.1)
				(type default)
			)
			(layer "F.Fab")
		)
		(fp_line
			(start -0.67945 -0.305054)
			(end -0.12065 -0.305054)
			(stroke
				(width 0.1)
				(type default)
			)
			(layer "F.Fab")
		)
		(fp_line
			(start -0.12065 -0.305054)
			(end -0.12065 -0.2794)
			(stroke
				(width 0.1)
				(type default)
			)
			(layer "F.Fab")
		)
		(pad "1" smd circle
			(at -0.40005 0 270)
			(size 0 0)
			(layers "F.Cu" "F.Mask" "F.Paste")
			(net "PRSNT_CABLE_GPU_A1_ISO_N")
		)
		(pad "2" smd circle
			(at 0.40005 0 270)
			(size 0 0)
			(layers "F.Cu" "F.Mask" "F.Paste")
			(net "PRSNT_CABLE_GPU_A1_ISO_R1_N")
		)
	)
	(footprint ""
		(layer "F.Cu")
		(at 353.9236 -407.8732 90)
		(property "Reference" "R1473"
			(at 0 0 90)
			(layer "F.SilkS")
			(hide yes)
			(effects
				(font
					(size 1.27 1.27)
				)
			)
		)
		(property "Value" ""
			(at 0 0 90)
			(layer "F.Fab")
			(effects
				(font
					(size 1.27 1.27)
				)
			)
		)
		(duplicate_pad_numbers_are_jumpers no)
		(fp_line
			(start 0.32512 -0.175006)
			(end 0.32512 0.175006)
			(stroke
				(width 0.1)
				(type default)
			)
			(layer "F.Fab")
		)
		(fp_line
			(start -0.32512 -0.175006)
			(end 0.32512 -0.175006)
			(stroke
				(width 0.1)
				(type default)
			)
			(layer "F.Fab")
		)
		(fp_line
			(start 0.32512 0.175006)
			(end -0.32512 0.175006)
			(stroke
				(width 0.1)
				(type default)
			)
			(layer "F.Fab")
		)
		(fp_line
			(start -0.32512 0.175006)
			(end -0.32512 -0.175006)
			(stroke
				(width 0.1)
				(type default)
			)
			(layer "F.Fab")
		)
		(pad "1" smd rect
			(at -0.2667 0 90)
			(size 0.3048 0.381)
			(layers "F.Cu" "F.Mask" "F.Paste")
			(net "P1V8_CPU0_RT_1D")
		)
		(pad "2" smd rect
			(at 0.2667 0 270)
			(size 0.3048 0.381)
			(layers "F.Cu" "F.Mask" "F.Paste")
			(net "JTAG_TCK_RT_CPU0_P1")
		)
	)
	(footprint ""
		(layer "F.Cu")
		(at 251.474224 -132.337556)
		(property "Reference" "R20"
			(at 0 0 0)
			(layer "F.SilkS")
			(hide yes)
			(effects
				(font
					(size 1.27 1.27)
				)
			)
		)
		(property "Value" ""
			(at 0 0 0)
			(layer "F.Fab")
			(effects
				(font
					(size 1.27 1.27)
				)
			)
		)
		(duplicate_pad_numbers_are_jumpers no)
		(fp_line
			(start -0.7874 -0.4064)
			(end 0.7874 -0.4064)
			(stroke
				(width 0.1524)
				(type default)
			)
			(layer "F.SilkS")
		)
		(fp_line
			(start -0.7874 0.4064)
			(end -0.7874 -0.4064)
			(stroke
				(width 0.1524)
				(type default)
			)
			(layer "F.SilkS")
		)
		(fp_line
			(start 0.7874 -0.4064)
			(end 0.7874 0.4064)
			(stroke
				(width 0.1524)
				(type default)
			)
			(layer "F.SilkS")
		)
		(fp_line
			(start 0.7874 0.4064)
			(end -0.7874 0.4064)
			(stroke
				(width 0.1524)
				(type default)
			)
			(layer "F.SilkS")
		)
		(fp_line
			(start -0.67945 -0.305054)
			(end -0.12065 -0.305054)
			(stroke
				(width 0.1)
				(type default)
			)
			(layer "F.Fab")
		)
		(fp_line
			(start -0.67945 0.3048)
			(end -0.67945 -0.305054)
			(stroke
				(width 0.1)
				(type default)
			)
			(layer "F.Fab")
		)
		(fp_line
			(start -0.12065 -0.305054)
			(end -0.12065 -0.2794)
			(stroke
				(width 0.1)
				(type default)
			)
			(layer "F.Fab")
		)
		(fp_line
			(start -0.12065 -0.2794)
			(end 0.12065 -0.2794)
			(stroke
				(width 0.1)
				(type default)
			)
			(layer "F.Fab")
		)
		(fp_line
			(start -0.12065 0.2794)
			(end -0.12065 0.3048)
			(stroke
				(width 0.1)
				(type default)
			)
			(layer "F.Fab")
		)
		(fp_line
			(start -0.12065 0.3048)
			(end -0.67945 0.3048)
			(stroke
				(width 0.1)
				(type default)
			)
			(layer "F.Fab")
		)
		(fp_line
			(start 0.120396 0.2794)
			(end -0.12065 0.2794)
			(stroke
				(width 0.1)
				(type default)
			)
			(layer "F.Fab")
		)
		(fp_line
			(start 0.120396 0.3048)
			(end 0.120396 0.2794)
			(stroke
				(width 0.1)
				(type default)
			)
			(layer "F.Fab")
		)
		(fp_line
			(start 0.12065 -0.3048)
			(end 0.67945 -0.3048)
			(stroke
				(width 0.1)
				(type default)
			)
			(layer "F.Fab")
		)
		(fp_line
			(start 0.12065 -0.2794)
			(end 0.12065 -0.3048)
			(stroke
				(width 0.1)
				(type default)
			)
			(layer "F.Fab")
		)
		(fp_line
			(start 0.67945 -0.3048)
			(end 0.67945 0.3048)
			(stroke
				(width 0.1)
				(type default)
			)
			(layer "F.Fab")
		)
		(fp_line
			(start 0.67945 0.3048)
			(end 0.120396 0.3048)
			(stroke
				(width 0.1)
				(type default)
			)
			(layer "F.Fab")
		)
		(pad "1" smd circle
			(at -0.40005 0)
			(size 0 0)
			(layers "F.Cu" "F.Mask" "F.Paste")
			(net "P3V3_AUX")
		)
		(pad "2" smd circle
			(at 0.40005 0)
			(size 0 0)
			(layers "F.Cu" "F.Mask" "F.Paste")
			(net "SPI_CPU0_LVC3_SCM_CLK")
		)
	)
	(footprint ""
		(layer "F.Cu")
		(at 346.968572 -156.487622 -90)
		(property "Reference" "PR432"
			(at 0 0 270)
			(layer "F.SilkS")
			(hide yes)
			(effects
				(font
					(size 1.27 1.27)
				)
			)
		)
		(property "Value" ""
			(at 0 0 270)
			(layer "F.Fab")
			(effects
				(font
					(size 1.27 1.27)
				)
			)
		)
		(duplicate_pad_numbers_are_jumpers no)
		(fp_line
			(start -0.7874 0.4064)
			(end -0.7874 -0.4064)
			(stroke
				(width 0.1524)
				(type default)
			)
			(layer "F.SilkS")
		)
		(fp_line
			(start 0.7874 0.4064)
			(end -0.7874 0.4064)
			(stroke
				(width 0.1524)
				(type default)
			)
			(layer "F.SilkS")
		)
		(fp_line
			(start -0.7874 -0.4064)
			(end 0.7874 -0.4064)
			(stroke
				(width 0.1524)
				(type default)
			)
			(layer "F.SilkS")
		)
		(fp_line
			(start 0.7874 -0.4064)
			(end 0.7874 0.4064)
			(stroke
				(width 0.1524)
				(type default)
			)
			(layer "F.SilkS")
		)
		(fp_line
			(start -0.67945 0.3048)
			(end -0.67945 -0.305054)
			(stroke
				(width 0.1)
				(type default)
			)
			(layer "F.Fab")
		)
		(fp_line
			(start -0.12065 0.3048)
			(end -0.67945 0.3048)
			(stroke
				(width 0.1)
				(type default)
			)
			(layer "F.Fab")
		)
		(fp_line
			(start 0.120396 0.3048)
			(end 0.120396 0.2794)
			(stroke
				(width 0.1)
				(type default)
			)
			(layer "F.Fab")
		)
		(fp_line
			(start 0.67945 0.3048)
			(end 0.120396 0.3048)
			(stroke
				(width 0.1)
				(type default)
			)
			(layer "F.Fab")
		)
		(fp_line
			(start -0.12065 0.2794)
			(end -0.12065 0.3048)
			(stroke
				(width 0.1)
				(type default)
			)
			(layer "F.Fab")
		)
		(fp_line
			(start 0.120396 0.2794)
			(end -0.12065 0.2794)
			(stroke
				(width 0.1)
				(type default)
			)
			(layer "F.Fab")
		)
		(fp_line
			(start -0.12065 -0.2794)
			(end 0.12065 -0.2794)
			(stroke
				(width 0.1)
				(type default)
			)
			(layer "F.Fab")
		)
		(fp_line
			(start 0.12065 -0.2794)
			(end 0.12065 -0.3048)
			(stroke
				(width 0.1)
				(type default)
			)
			(layer "F.Fab")
		)
		(fp_line
			(start 0.12065 -0.3048)
			(end 0.67945 -0.3048)
			(stroke
				(width 0.1)
				(type default)
			)
			(layer "F.Fab")
		)
		(fp_line
			(start 0.67945 -0.3048)
			(end 0.67945 0.3048)
			(stroke
				(width 0.1)
				(type default)
			)
			(layer "F.Fab")
		)
		(fp_line
			(start -0.67945 -0.305054)
			(end -0.12065 -0.305054)
			(stroke
				(width 0.1)
				(type default)
			)
			(layer "F.Fab")
		)
		(fp_line
			(start -0.12065 -0.305054)
			(end -0.12065 -0.2794)
			(stroke
				(width 0.1)
				(type default)
			)
			(layer "F.Fab")
		)
		(pad "1" smd circle
			(at -0.40005 0 270)
			(size 0 0)
			(layers "F.Cu" "F.Mask" "F.Paste")
			(net "SW_PVDDCR_CPU0_P0_BOOT6")
		)
		(pad "2" smd circle
			(at 0.40005 0 270)
			(size 0 0)
			(layers "F.Cu" "F.Mask" "F.Paste")
			(net "SW_PVDDCR_CPU0_P0_BOOT6_RC")
		)
	)
	(footprint ""
		(layer "F.Cu")
		(at 19.558 -366.649 90)
		(property "Reference" "PQ12"
			(at -1.464818 -3.07594 90)
			(unlocked yes)
			(layer "F.SilkS")
			(effects
				(font
					(size 0.7874 0.5842)
					(thickness 0.1524)
				)
				(justify left)
			)
		)
		(property "Value" ""
			(at 0 0 90)
			(layer "F.Fab")
			(effects
				(font
					(size 1.27 1.27)
				)
			)
		)
		(duplicate_pad_numbers_are_jumpers no)
		(fp_line
			(start 1.603248 -1.500124)
			(end 1.603248 1.500124)
			(stroke
				(width 0.1524)
				(type default)
			)
			(layer "F.SilkS")
		)
		(fp_line
			(start -1.603248 -1.500124)
			(end 1.603248 -1.500124)
			(stroke
				(width 0.1524)
				(type default)
			)
			(layer "F.SilkS")
		)
		(fp_line
			(start 1.603248 1.500124)
			(end -1.603248 1.500124)
			(stroke
				(width 0.1524)
				(type default)
			)
			(layer "F.SilkS")
		)
		(fp_line
			(start -1.603248 1.500124)
			(end -1.603248 -1.500124)
			(stroke
				(width 0.1524)
				(type default)
			)
			(layer "F.SilkS")
		)
		(fp_line
			(start 0.700024 -1.500124)
			(end -0.700024 -1.500124)
			(stroke
				(width 0.1)
				(type default)
			)
			(layer "F.Fab")
		)
		(fp_line
			(start -0.700024 -1.500124)
			(end -0.700024 -1.169924)
			(stroke
				(width 0.1)
				(type default)
			)
			(layer "F.Fab")
		)
		(fp_line
			(start -0.700024 -1.169924)
			(end -1.249934 -1.169924)
			(stroke
				(width 0.1)
				(type default)
			)
			(layer "F.Fab")
		)
		(fp_line
			(start -1.249934 -1.169924)
			(end -1.249934 -0.729996)
			(stroke
				(width 0.1)
				(type default)
			)
			(layer "F.Fab")
		)
		(fp_line
			(start -0.6985 -0.729996)
			(end -0.6985 0.729996)
			(stroke
				(width 0.1)
				(type default)
			)
			(layer "F.Fab")
		)
		(fp_line
			(start -1.249934 -0.729996)
			(end -0.6985 -0.729996)
			(stroke
				(width 0.1)
				(type default)
			)
			(layer "F.Fab")
		)
		(fp_line
			(start 1.249934 -0.219964)
			(end 0.700024 -0.219964)
			(stroke
				(width 0.1)
				(type default)
			)
			(layer "F.Fab")
		)
		(fp_line
			(start 0.700024 -0.219964)
			(end 0.700024 -1.500124)
			(stroke
				(width 0.1)
				(type default)
			)
			(layer "F.Fab")
		)
		(fp_line
			(start 1.249934 0.219964)
			(end 1.249934 -0.219964)
			(stroke
				(width 0.1)
				(type default)
			)
			(layer "F.Fab")
		)
		(fp_line
			(start 0.700024 0.219964)
			(end 1.249934 0.219964)
			(stroke
				(width 0.1)
				(type default)
			)
			(layer "F.Fab")
		)
		(fp_line
			(start -0.6985 0.729996)
			(end -1.249934 0.729996)
			(stroke
				(width 0.1)
				(type default)
			)
			(layer "F.Fab")
		)
		(fp_line
			(start -1.249934 0.729996)
			(end -1.249934 1.169924)
			(stroke
				(width 0.1)
				(type default)
			)
			(layer "F.Fab")
		)
		(fp_line
			(start -0.700024 1.169924)
			(end -0.700024 1.500124)
			(stroke
				(width 0.1)
				(type default)
			)
			(layer "F.Fab")
		)
		(fp_line
			(start -1.249934 1.169924)
			(end -0.700024 1.169924)
			(stroke
				(width 0.1)
				(type default)
			)
			(layer "F.Fab")
		)
		(fp_line
			(start 0.700024 1.500124)
			(end 0.700024 0.219964)
			(stroke
				(width 0.1)
				(type default)
			)
			(layer "F.Fab")
		)
		(fp_line
			(start -0.700024 1.500124)
			(end 0.700024 1.500124)
			(stroke
				(width 0.1)
				(type default)
			)
			(layer "F.Fab")
		)
		(fp_rect
			(start -0.700024 1.500124)
			(end 0.700024 -1.500124)
			(stroke
				(width 0)
				(type default)
			)
			(fill no)
			(layer "F.Fab")
		)
		(pad "D" smd rect
			(at 0.999998 0)
			(size 0.8128 0.9144)
			(layers "F.Cu" "F.Mask" "F.Paste")
			(net "PVDDCR_CPU1_P1_EN1_ADDR_CFG")
		)
		(pad "G" smd rect
			(at -0.999998 -0.94996)
			(size 0.8128 0.9144)
			(layers "F.Cu" "F.Mask" "F.Paste")
			(net "PVDDIO_P1_EN_G")
		)
		(pad "S" smd rect
			(at -0.999998 0.94996)
			(size 0.8128 0.9144)
			(layers "F.Cu" "F.Mask" "F.Paste")
			(net "P3V3_AUX")
		)
	)
	(footprint ""
		(layer "F.Cu")
		(at 360.366056 -256.012188 90)
		(property "Reference" "C3927"
			(at 0 0 90)
			(layer "F.SilkS")
			(hide yes)
			(effects
				(font
					(size 1.27 1.27)
				)
			)
		)
		(property "Value" ""
			(at 0 0 90)
			(layer "F.Fab")
			(effects
				(font
					(size 1.27 1.27)
				)
			)
		)
		(duplicate_pad_numbers_are_jumpers no)
		(fp_line
			(start 0.7874 -0.4064)
			(end 0.7874 0.4064)
			(stroke
				(width 0.1524)
				(type default)
			)
			(layer "F.SilkS")
		)
		(fp_line
			(start -0.7874 -0.4064)
			(end 0.7874 -0.4064)
			(stroke
				(width 0.1524)
				(type default)
			)
			(layer "F.SilkS")
		)
		(fp_line
			(start 0.7874 0.4064)
			(end -0.7874 0.4064)
			(stroke
				(width 0.1524)
				(type default)
			)
			(layer "F.SilkS")
		)
		(fp_line
			(start -0.7874 0.4064)
			(end -0.7874 -0.4064)
			(stroke
				(width 0.1524)
				(type default)
			)
			(layer "F.SilkS")
		)
		(fp_line
			(start -0.12065 -0.305054)
			(end -0.12065 -0.2794)
			(stroke
				(width 0.1)
				(type default)
			)
			(layer "F.Fab")
		)
		(fp_line
			(start -0.67945 -0.305054)
			(end -0.12065 -0.305054)
			(stroke
				(width 0.1)
				(type default)
			)
			(layer "F.Fab")
		)
		(fp_line
			(start 0.67945 -0.3048)
			(end 0.67945 0.3048)
			(stroke
				(width 0.1)
				(type default)
			)
			(layer "F.Fab")
		)
		(fp_line
			(start 0.12065 -0.3048)
			(end 0.67945 -0.3048)
			(stroke
				(width 0.1)
				(type default)
			)
			(layer "F.Fab")
		)
		(fp_line
			(start 0.12065 -0.2794)
			(end 0.12065 -0.3048)
			(stroke
				(width 0.1)
				(type default)
			)
			(layer "F.Fab")
		)
		(fp_line
			(start -0.12065 -0.2794)
			(end 0.12065 -0.2794)
			(stroke
				(width 0.1)
				(type default)
			)
			(layer "F.Fab")
		)
		(fp_line
			(start 0.120396 0.2794)
			(end -0.12065 0.2794)
			(stroke
				(width 0.1)
				(type default)
			)
			(layer "F.Fab")
		)
		(fp_line
			(start -0.12065 0.2794)
			(end -0.12065 0.3048)
			(stroke
				(width 0.1)
				(type default)
			)
			(layer "F.Fab")
		)
		(fp_line
			(start 0.67945 0.3048)
			(end 0.120396 0.3048)
			(stroke
				(width 0.1)
				(type default)
			)
			(layer "F.Fab")
		)
		(fp_line
			(start 0.120396 0.3048)
			(end 0.120396 0.2794)
			(stroke
				(width 0.1)
				(type default)
			)
			(layer "F.Fab")
		)
		(fp_line
			(start -0.12065 0.3048)
			(end -0.67945 0.3048)
			(stroke
				(width 0.1)
				(type default)
			)
			(layer "F.Fab")
		)
		(fp_line
			(start -0.67945 0.3048)
			(end -0.67945 -0.305054)
			(stroke
				(width 0.1)
				(type default)
			)
			(layer "F.Fab")
		)
		(pad "1" smd circle
			(at -0.40005 0 90)
			(size 0 0)
			(layers "F.Cu" "F.Mask" "F.Paste")
			(net "PVDDCR_SOC_P0")
		)
		(pad "2" smd circle
			(at 0.40005 0 90)
			(size 0 0)
			(layers "F.Cu" "F.Mask" "F.Paste")
			(net "GND")
		)
	)
	(footprint ""
		(layer "F.Cu")
		(at 58.305954 -370.57203 -90)
		(property "Reference" "C819"
			(at 0 0 270)
			(layer "F.SilkS")
			(hide yes)
			(effects
				(font
					(size 1.27 1.27)
				)
			)
		)
		(property "Value" ""
			(at 0 0 270)
			(layer "F.Fab")
			(effects
				(font
					(size 1.27 1.27)
				)
			)
		)
		(duplicate_pad_numbers_are_jumpers no)
		(fp_line
			(start -0.299974 0.150114)
			(end -0.299974 -0.150114)
			(stroke
				(width 0.1)
				(type default)
			)
			(layer "F.Fab")
		)
		(fp_line
			(start 0.299974 0.150114)
			(end -0.299974 0.150114)
			(stroke
				(width 0.1)
				(type default)
			)
			(layer "F.Fab")
		)
		(fp_line
			(start -0.299974 -0.150114)
			(end 0.299974 -0.150114)
			(stroke
				(width 0.1)
				(type default)
			)
			(layer "F.Fab")
		)
		(fp_line
			(start 0.299974 -0.150114)
			(end 0.299974 0.150114)
			(stroke
				(width 0.1)
				(type default)
			)
			(layer "F.Fab")
		)
		(pad "1" smd rect
			(at -0.2667 0 270)
			(size 0.3048 0.381)
			(layers "F.Cu" "F.Mask" "F.Paste")
			(net "P5E_CPU1_P0_TX_C_DP<9>")
		)
		(pad "2" smd rect
			(at 0.2667 0 270)
			(size 0.3048 0.381)
			(layers "F.Cu" "F.Mask" "F.Paste")
			(net "P5E_CPU1_P0_TX_DP<9>")
		)
	)
	(footprint ""
		(layer "F.Cu")
		(at 218.130882 -57.399682 -90)
		(property "Reference" "C2071"
			(at 0 0 270)
			(layer "F.SilkS")
			(hide yes)
			(effects
				(font
					(size 1.27 1.27)
				)
			)
		)
		(property "Value" ""
			(at 0 0 270)
			(layer "F.Fab")
			(effects
				(font
					(size 1.27 1.27)
				)
			)
		)
		(duplicate_pad_numbers_are_jumpers no)
		(fp_line
			(start -0.7874 0.4064)
			(end -0.7874 -0.4064)
			(stroke
				(width 0.1524)
				(type default)
			)
			(layer "F.SilkS")
		)
		(fp_line
			(start 0.7874 0.4064)
			(end -0.7874 0.4064)
			(stroke
				(width 0.1524)
				(type default)
			)
			(layer "F.SilkS")
		)
		(fp_line
			(start -0.7874 -0.4064)
			(end 0.7874 -0.4064)
			(stroke
				(width 0.1524)
				(type default)
			)
			(layer "F.SilkS")
		)
		(fp_line
			(start 0.7874 -0.4064)
			(end 0.7874 0.4064)
			(stroke
				(width 0.1524)
				(type default)
			)
			(layer "F.SilkS")
		)
		(fp_line
			(start -0.67945 0.3048)
			(end -0.67945 -0.305054)
			(stroke
				(width 0.1)
				(type default)
			)
			(layer "F.Fab")
		)
		(fp_line
			(start -0.12065 0.3048)
			(end -0.67945 0.3048)
			(stroke
				(width 0.1)
				(type default)
			)
			(layer "F.Fab")
		)
		(fp_line
			(start 0.120396 0.3048)
			(end 0.120396 0.2794)
			(stroke
				(width 0.1)
				(type default)
			)
			(layer "F.Fab")
		)
		(fp_line
			(start 0.67945 0.3048)
			(end 0.120396 0.3048)
			(stroke
				(width 0.1)
				(type default)
			)
			(layer "F.Fab")
		)
		(fp_line
			(start -0.12065 0.2794)
			(end -0.12065 0.3048)
			(stroke
				(width 0.1)
				(type default)
			)
			(layer "F.Fab")
		)
		(fp_line
			(start 0.120396 0.2794)
			(end -0.12065 0.2794)
			(stroke
				(width 0.1)
				(type default)
			)
			(layer "F.Fab")
		)
		(fp_line
			(start -0.12065 -0.2794)
			(end 0.12065 -0.2794)
			(stroke
				(width 0.1)
				(type default)
			)
			(layer "F.Fab")
		)
		(fp_line
			(start 0.12065 -0.2794)
			(end 0.12065 -0.3048)
			(stroke
				(width 0.1)
				(type default)
			)
			(layer "F.Fab")
		)
		(fp_line
			(start 0.12065 -0.3048)
			(end 0.67945 -0.3048)
			(stroke
				(width 0.1)
				(type default)
			)
			(layer "F.Fab")
		)
		(fp_line
			(start 0.67945 -0.3048)
			(end 0.67945 0.3048)
			(stroke
				(width 0.1)
				(type default)
			)
			(layer "F.Fab")
		)
		(fp_line
			(start -0.67945 -0.305054)
			(end -0.12065 -0.305054)
			(stroke
				(width 0.1)
				(type default)
			)
			(layer "F.Fab")
		)
		(fp_line
			(start -0.12065 -0.305054)
			(end -0.12065 -0.2794)
			(stroke
				(width 0.1)
				(type default)
			)
			(layer "F.Fab")
		)
		(pad "1" smd circle
			(at -0.40005 0 270)
			(size 0 0)
			(layers "F.Cu" "F.Mask" "F.Paste")
			(net "VSENSE_P3V3_INA230_2_INP")
		)
		(pad "2" smd circle
			(at 0.40005 0 270)
			(size 0 0)
			(layers "F.Cu" "F.Mask" "F.Paste")
			(net "VSENSE_P3V3_INA230_2_INN")
		)
	)
	(footprint ""
		(layer "F.Cu")
		(at 12.982956 -92.687648 90)
		(property "Reference" "R3660"
			(at 0 0 90)
			(layer "F.SilkS")
			(hide yes)
			(effects
				(font
					(size 1.27 1.27)
				)
			)
		)
		(property "Value" ""
			(at 0 0 90)
			(layer "F.Fab")
			(effects
				(font
					(size 1.27 1.27)
				)
			)
		)
		(duplicate_pad_numbers_are_jumpers no)
		(fp_line
			(start 0.7874 -0.4064)
			(end 0.7874 0.4064)
			(stroke
				(width 0.1524)
				(type default)
			)
			(layer "F.SilkS")
		)
		(fp_line
			(start -0.7874 -0.4064)
			(end 0.7874 -0.4064)
			(stroke
				(width 0.1524)
				(type default)
			)
			(layer "F.SilkS")
		)
		(fp_line
			(start 0.7874 0.4064)
			(end -0.7874 0.4064)
			(stroke
				(width 0.1524)
				(type default)
			)
			(layer "F.SilkS")
		)
		(fp_line
			(start -0.7874 0.4064)
			(end -0.7874 -0.4064)
			(stroke
				(width 0.1524)
				(type default)
			)
			(layer "F.SilkS")
		)
		(fp_line
			(start -0.12065 -0.305054)
			(end -0.12065 -0.2794)
			(stroke
				(width 0.1)
				(type default)
			)
			(layer "F.Fab")
		)
		(fp_line
			(start -0.67945 -0.305054)
			(end -0.12065 -0.305054)
			(stroke
				(width 0.1)
				(type default)
			)
			(layer "F.Fab")
		)
		(fp_line
			(start 0.67945 -0.3048)
			(end 0.67945 0.3048)
			(stroke
				(width 0.1)
				(type default)
			)
			(layer "F.Fab")
		)
		(fp_line
			(start 0.12065 -0.3048)
			(end 0.67945 -0.3048)
			(stroke
				(width 0.1)
				(type default)
			)
			(layer "F.Fab")
		)
		(fp_line
			(start 0.12065 -0.2794)
			(end 0.12065 -0.3048)
			(stroke
				(width 0.1)
				(type default)
			)
			(layer "F.Fab")
		)
		(fp_line
			(start -0.12065 -0.2794)
			(end 0.12065 -0.2794)
			(stroke
				(width 0.1)
				(type default)
			)
			(layer "F.Fab")
		)
		(fp_line
			(start 0.120396 0.2794)
			(end -0.12065 0.2794)
			(stroke
				(width 0.1)
				(type default)
			)
			(layer "F.Fab")
		)
		(fp_line
			(start -0.12065 0.2794)
			(end -0.12065 0.3048)
			(stroke
				(width 0.1)
				(type default)
			)
			(layer "F.Fab")
		)
		(fp_line
			(start 0.67945 0.3048)
			(end 0.120396 0.3048)
			(stroke
				(width 0.1)
				(type default)
			)
			(layer "F.Fab")
		)
		(fp_line
			(start 0.120396 0.3048)
			(end 0.120396 0.2794)
			(stroke
				(width 0.1)
				(type default)
			)
			(layer "F.Fab")
		)
		(fp_line
			(start -0.12065 0.3048)
			(end -0.67945 0.3048)
			(stroke
				(width 0.1)
				(type default)
			)
			(layer "F.Fab")
		)
		(fp_line
			(start -0.67945 0.3048)
			(end -0.67945 -0.305054)
			(stroke
				(width 0.1)
				(type default)
			)
			(layer "F.Fab")
		)
		(pad "1" smd circle
			(at -0.40005 0 90)
			(size 0 0)
			(layers "F.Cu" "F.Mask" "F.Paste")
			(net "P3V3_AUX")
		)
		(pad "2" smd circle
			(at 0.40005 0 90)
			(size 0 0)
			(layers "F.Cu" "F.Mask" "F.Paste")
			(net "RST_USB_HUB_R_N")
		)
	)
	(footprint ""
		(layer "F.Cu")
		(at 329.282044 -138.893042 90)
		(property "Reference" "PC259"
			(at 0 0 90)
			(layer "F.SilkS")
			(hide yes)
			(effects
				(font
					(size 1.27 1.27)
				)
			)
		)
		(property "Value" ""
			(at 0 0 90)
			(layer "F.Fab")
			(effects
				(font
					(size 1.27 1.27)
				)
			)
		)
		(duplicate_pad_numbers_are_jumpers no)
		(fp_line
			(start 0.7874 -0.4064)
			(end 0.7874 0.4064)
			(stroke
				(width 0.1524)
				(type default)
			)
			(layer "F.SilkS")
		)
		(fp_line
			(start -0.7874 -0.4064)
			(end 0.7874 -0.4064)
			(stroke
				(width 0.1524)
				(type default)
			)
			(layer "F.SilkS")
		)
		(fp_line
			(start 0.7874 0.4064)
			(end -0.7874 0.4064)
			(stroke
				(width 0.1524)
				(type default)
			)
			(layer "F.SilkS")
		)
		(fp_line
			(start -0.7874 0.4064)
			(end -0.7874 -0.4064)
			(stroke
				(width 0.1524)
				(type default)
			)
			(layer "F.SilkS")
		)
		(fp_line
			(start -0.12065 -0.305054)
			(end -0.12065 -0.2794)
			(stroke
				(width 0.1)
				(type default)
			)
			(layer "F.Fab")
		)
		(fp_line
			(start -0.67945 -0.305054)
			(end -0.12065 -0.305054)
			(stroke
				(width 0.1)
				(type default)
			)
			(layer "F.Fab")
		)
		(fp_line
			(start 0.67945 -0.3048)
			(end 0.67945 0.3048)
			(stroke
				(width 0.1)
				(type default)
			)
			(layer "F.Fab")
		)
		(fp_line
			(start 0.12065 -0.3048)
			(end 0.67945 -0.3048)
			(stroke
				(width 0.1)
				(type default)
			)
			(layer "F.Fab")
		)
		(fp_line
			(start 0.12065 -0.2794)
			(end 0.12065 -0.3048)
			(stroke
				(width 0.1)
				(type default)
			)
			(layer "F.Fab")
		)
		(fp_line
			(start -0.12065 -0.2794)
			(end 0.12065 -0.2794)
			(stroke
				(width 0.1)
				(type default)
			)
			(layer "F.Fab")
		)
		(fp_line
			(start 0.120396 0.2794)
			(end -0.12065 0.2794)
			(stroke
				(width 0.1)
				(type default)
			)
			(layer "F.Fab")
		)
		(fp_line
			(start -0.12065 0.2794)
			(end -0.12065 0.3048)
			(stroke
				(width 0.1)
				(type default)
			)
			(layer "F.Fab")
		)
		(fp_line
			(start 0.67945 0.3048)
			(end 0.120396 0.3048)
			(stroke
				(width 0.1)
				(type default)
			)
			(layer "F.Fab")
		)
		(fp_line
			(start 0.120396 0.3048)
			(end 0.120396 0.2794)
			(stroke
				(width 0.1)
				(type default)
			)
			(layer "F.Fab")
		)
		(fp_line
			(start -0.12065 0.3048)
			(end -0.67945 0.3048)
			(stroke
				(width 0.1)
				(type default)
			)
			(layer "F.Fab")
		)
		(fp_line
			(start -0.67945 0.3048)
			(end -0.67945 -0.305054)
			(stroke
				(width 0.1)
				(type default)
			)
			(layer "F.Fab")
		)
		(pad "1" smd circle
			(at -0.40005 0 90)
			(size 0 0)
			(layers "F.Cu" "F.Mask" "F.Paste")
			(net "PVDD18_S5_P0_FB")
		)
		(pad "2" smd circle
			(at 0.40005 0 90)
			(size 0 0)
			(layers "F.Cu" "F.Mask" "F.Paste")
			(net "PVDD18_S5_P0_FB_RC")
		)
	)
	(footprint ""
		(layer "F.Cu")
		(at 285.75254 -403.961092 -90)
		(property "Reference" "R2625"
			(at 0 0 270)
			(layer "F.SilkS")
			(hide yes)
			(effects
				(font
					(size 1.27 1.27)
				)
			)
		)
		(property "Value" ""
			(at 0 0 270)
			(layer "F.Fab")
			(effects
				(font
					(size 1.27 1.27)
				)
			)
		)
		(duplicate_pad_numbers_are_jumpers no)
		(fp_line
			(start -0.7874 0.4064)
			(end -0.7874 -0.4064)
			(stroke
				(width 0.1524)
				(type default)
			)
			(layer "F.SilkS")
		)
		(fp_line
			(start 0.7874 0.4064)
			(end -0.7874 0.4064)
			(stroke
				(width 0.1524)
				(type default)
			)
			(layer "F.SilkS")
		)
		(fp_line
			(start -0.7874 -0.4064)
			(end 0.7874 -0.4064)
			(stroke
				(width 0.1524)
				(type default)
			)
			(layer "F.SilkS")
		)
		(fp_line
			(start 0.7874 -0.4064)
			(end 0.7874 0.4064)
			(stroke
				(width 0.1524)
				(type default)
			)
			(layer "F.SilkS")
		)
		(fp_line
			(start -0.67945 0.3048)
			(end -0.67945 -0.305054)
			(stroke
				(width 0.1)
				(type default)
			)
			(layer "F.Fab")
		)
		(fp_line
			(start -0.12065 0.3048)
			(end -0.67945 0.3048)
			(stroke
				(width 0.1)
				(type default)
			)
			(layer "F.Fab")
		)
		(fp_line
			(start 0.120396 0.3048)
			(end 0.120396 0.2794)
			(stroke
				(width 0.1)
				(type default)
			)
			(layer "F.Fab")
		)
		(fp_line
			(start 0.67945 0.3048)
			(end 0.120396 0.3048)
			(stroke
				(width 0.1)
				(type default)
			)
			(layer "F.Fab")
		)
		(fp_line
			(start -0.12065 0.2794)
			(end -0.12065 0.3048)
			(stroke
				(width 0.1)
				(type default)
			)
			(layer "F.Fab")
		)
		(fp_line
			(start 0.120396 0.2794)
			(end -0.12065 0.2794)
			(stroke
				(width 0.1)
				(type default)
			)
			(layer "F.Fab")
		)
		(fp_line
			(start -0.12065 -0.2794)
			(end 0.12065 -0.2794)
			(stroke
				(width 0.1)
				(type default)
			)
			(layer "F.Fab")
		)
		(fp_line
			(start 0.12065 -0.2794)
			(end 0.12065 -0.3048)
			(stroke
				(width 0.1)
				(type default)
			)
			(layer "F.Fab")
		)
		(fp_line
			(start 0.12065 -0.3048)
			(end 0.67945 -0.3048)
			(stroke
				(width 0.1)
				(type default)
			)
			(layer "F.Fab")
		)
		(fp_line
			(start 0.67945 -0.3048)
			(end 0.67945 0.3048)
			(stroke
				(width 0.1)
				(type default)
			)
			(layer "F.Fab")
		)
		(fp_line
			(start -0.67945 -0.305054)
			(end -0.12065 -0.305054)
			(stroke
				(width 0.1)
				(type default)
			)
			(layer "F.Fab")
		)
		(fp_line
			(start -0.12065 -0.305054)
			(end -0.12065 -0.2794)
			(stroke
				(width 0.1)
				(type default)
			)
			(layer "F.Fab")
		)
		(pad "1" smd circle
			(at -0.40005 0 270)
			(size 0 0)
			(layers "F.Cu" "F.Mask" "F.Paste")
			(net "P12V_HSC_TEMP_R")
		)
		(pad "2" smd circle
			(at 0.40005 0 270)
			(size 0 0)
			(layers "F.Cu" "F.Mask" "F.Paste")
			(net "P12V_HSC_TEMP_D+")
		)
	)
	(footprint ""
		(layer "F.Cu")
		(at 181.388766 -169.117518 -90)
		(property "Reference" "R1336"
			(at 0 0 270)
			(layer "F.SilkS")
			(hide yes)
			(effects
				(font
					(size 1.27 1.27)
				)
			)
		)
		(property "Value" ""
			(at 0 0 270)
			(layer "F.Fab")
			(effects
				(font
					(size 1.27 1.27)
				)
			)
		)
		(duplicate_pad_numbers_are_jumpers no)
		(fp_line
			(start -0.7874 0.4064)
			(end -0.7874 -0.4064)
			(stroke
				(width 0.1524)
				(type default)
			)
			(layer "F.SilkS")
		)
		(fp_line
			(start 0.7874 0.4064)
			(end -0.7874 0.4064)
			(stroke
				(width 0.1524)
				(type default)
			)
			(layer "F.SilkS")
		)
		(fp_line
			(start -0.7874 -0.4064)
			(end 0.7874 -0.4064)
			(stroke
				(width 0.1524)
				(type default)
			)
			(layer "F.SilkS")
		)
		(fp_line
			(start 0.7874 -0.4064)
			(end 0.7874 0.4064)
			(stroke
				(width 0.1524)
				(type default)
			)
			(layer "F.SilkS")
		)
		(fp_line
			(start -0.67945 0.3048)
			(end -0.67945 -0.305054)
			(stroke
				(width 0.1)
				(type default)
			)
			(layer "F.Fab")
		)
		(fp_line
			(start -0.12065 0.3048)
			(end -0.67945 0.3048)
			(stroke
				(width 0.1)
				(type default)
			)
			(layer "F.Fab")
		)
		(fp_line
			(start 0.120396 0.3048)
			(end 0.120396 0.2794)
			(stroke
				(width 0.1)
				(type default)
			)
			(layer "F.Fab")
		)
		(fp_line
			(start 0.67945 0.3048)
			(end 0.120396 0.3048)
			(stroke
				(width 0.1)
				(type default)
			)
			(layer "F.Fab")
		)
		(fp_line
			(start -0.12065 0.2794)
			(end -0.12065 0.3048)
			(stroke
				(width 0.1)
				(type default)
			)
			(layer "F.Fab")
		)
		(fp_line
			(start 0.120396 0.2794)
			(end -0.12065 0.2794)
			(stroke
				(width 0.1)
				(type default)
			)
			(layer "F.Fab")
		)
		(fp_line
			(start -0.12065 -0.2794)
			(end 0.12065 -0.2794)
			(stroke
				(width 0.1)
				(type default)
			)
			(layer "F.Fab")
		)
		(fp_line
			(start 0.12065 -0.2794)
			(end 0.12065 -0.3048)
			(stroke
				(width 0.1)
				(type default)
			)
			(layer "F.Fab")
		)
		(fp_line
			(start 0.12065 -0.3048)
			(end 0.67945 -0.3048)
			(stroke
				(width 0.1)
				(type default)
			)
			(layer "F.Fab")
		)
		(fp_line
			(start 0.67945 -0.3048)
			(end 0.67945 0.3048)
			(stroke
				(width 0.1)
				(type default)
			)
			(layer "F.Fab")
		)
		(fp_line
			(start -0.67945 -0.305054)
			(end -0.12065 -0.305054)
			(stroke
				(width 0.1)
				(type default)
			)
			(layer "F.Fab")
		)
		(fp_line
			(start -0.12065 -0.305054)
			(end -0.12065 -0.2794)
			(stroke
				(width 0.1)
				(type default)
			)
			(layer "F.Fab")
		)
		(pad "1" smd rect
			(at -0.40005 0 90)
			(size 0.4572 0.508)
			(layers "F.Cu" "F.Mask" "F.Paste")
			(net "I3C_SPD_DDRGL_CPU1_BYPASS_SCL")
		)
		(pad "2" smd rect
			(at 0.40005 0 90)
			(size 0.4572 0.508)
			(layers "F.Cu" "F.Mask" "F.Paste")
			(net "I3C_SPD_DDRGL_CPU1_SCL")
		)
	)
	(footprint ""
		(layer "F.Cu")
		(at 70.9676 -381.7874)
		(property "Reference" "R1387"
			(at 0 0 0)
			(layer "F.SilkS")
			(hide yes)
			(effects
				(font
					(size 1.27 1.27)
				)
			)
		)
		(property "Value" ""
			(at 0 0 0)
			(layer "F.Fab")
			(effects
				(font
					(size 1.27 1.27)
				)
			)
		)
		(duplicate_pad_numbers_are_jumpers no)
		(fp_line
			(start -0.32512 -0.175006)
			(end 0.32512 -0.175006)
			(stroke
				(width 0.1)
				(type default)
			)
			(layer "F.Fab")
		)
		(fp_line
			(start -0.32512 0.175006)
			(end -0.32512 -0.175006)
			(stroke
				(width 0.1)
				(type default)
			)
			(layer "F.Fab")
		)
		(fp_line
			(start 0.32512 -0.175006)
			(end 0.32512 0.175006)
			(stroke
				(width 0.1)
				(type default)
			)
			(layer "F.Fab")
		)
		(fp_line
			(start 0.32512 0.175006)
			(end -0.32512 0.175006)
			(stroke
				(width 0.1)
				(type default)
			)
			(layer "F.Fab")
		)
		(pad "1" smd rect
			(at -0.2667 0)
			(size 0.3048 0.381)
			(layers "F.Cu" "F.Mask" "F.Paste")
			(net "CLKREQ_RT_CPU1_P0_N")
		)
		(pad "2" smd rect
			(at 0.2667 0 180)
			(size 0.3048 0.381)
			(layers "F.Cu" "F.Mask" "F.Paste")
			(net "GND")
		)
	)
	(footprint ""
		(layer "F.Cu")
		(at 399.303748 -17.624298 90)
		(property "Reference" "C1555"
			(at 0 0 90)
			(layer "F.SilkS")
			(hide yes)
			(effects
				(font
					(size 1.27 1.27)
				)
			)
		)
		(property "Value" ""
			(at 0 0 90)
			(layer "F.Fab")
			(effects
				(font
					(size 1.27 1.27)
				)
			)
		)
		(duplicate_pad_numbers_are_jumpers no)
		(fp_line
			(start 0.299974 -0.150114)
			(end 0.299974 0.150114)
			(stroke
				(width 0.1)
				(type default)
			)
			(layer "F.Fab")
		)
		(fp_line
			(start -0.299974 -0.150114)
			(end 0.299974 -0.150114)
			(stroke
				(width 0.1)
				(type default)
			)
			(layer "F.Fab")
		)
		(fp_line
			(start 0.299974 0.150114)
			(end -0.299974 0.150114)
			(stroke
				(width 0.1)
				(type default)
			)
			(layer "F.Fab")
		)
		(fp_line
			(start -0.299974 0.150114)
			(end -0.299974 -0.150114)
			(stroke
				(width 0.1)
				(type default)
			)
			(layer "F.Fab")
		)
		(pad "1" smd rect
			(at -0.2667 0 90)
			(size 0.3048 0.381)
			(layers "F.Cu" "F.Mask" "F.Paste")
			(net "P5E_CPU0_G3_TX_C_DP<12>")
		)
		(pad "2" smd rect
			(at 0.2667 0 90)
			(size 0.3048 0.381)
			(layers "F.Cu" "F.Mask" "F.Paste")
			(net "P5E_CPU0_G3_TX_DP<12>")
		)
	)
	(footprint ""
		(layer "F.Cu")
		(at 85.978492 -185.748168)
		(property "Reference" "PC170"
			(at 0 0 0)
			(layer "F.SilkS")
			(hide yes)
			(effects
				(font
					(size 1.27 1.27)
				)
			)
		)
		(property "Value" ""
			(at 0 0 0)
			(layer "F.Fab")
			(effects
				(font
					(size 1.27 1.27)
				)
			)
		)
		(duplicate_pad_numbers_are_jumpers no)
		(fp_line
			(start -0.7874 -0.4064)
			(end 0.7874 -0.4064)
			(stroke
				(width 0.1524)
				(type default)
			)
			(layer "F.SilkS")
		)
		(fp_line
			(start -0.7874 0.4064)
			(end -0.7874 -0.4064)
			(stroke
				(width 0.1524)
				(type default)
			)
			(layer "F.SilkS")
		)
		(fp_line
			(start 0.7874 -0.4064)
			(end 0.7874 0.4064)
			(stroke
				(width 0.1524)
				(type default)
			)
			(layer "F.SilkS")
		)
		(fp_line
			(start 0.7874 0.4064)
			(end -0.7874 0.4064)
			(stroke
				(width 0.1524)
				(type default)
			)
			(layer "F.SilkS")
		)
		(fp_line
			(start -0.67945 -0.305054)
			(end -0.12065 -0.305054)
			(stroke
				(width 0.1)
				(type default)
			)
			(layer "F.Fab")
		)
		(fp_line
			(start -0.67945 0.3048)
			(end -0.67945 -0.305054)
			(stroke
				(width 0.1)
				(type default)
			)
			(layer "F.Fab")
		)
		(fp_line
			(start -0.12065 -0.305054)
			(end -0.12065 -0.2794)
			(stroke
				(width 0.1)
				(type default)
			)
			(layer "F.Fab")
		)
		(fp_line
			(start -0.12065 -0.2794)
			(end 0.12065 -0.2794)
			(stroke
				(width 0.1)
				(type default)
			)
			(layer "F.Fab")
		)
		(fp_line
			(start -0.12065 0.2794)
			(end -0.12065 0.3048)
			(stroke
				(width 0.1)
				(type default)
			)
			(layer "F.Fab")
		)
		(fp_line
			(start -0.12065 0.3048)
			(end -0.67945 0.3048)
			(stroke
				(width 0.1)
				(type default)
			)
			(layer "F.Fab")
		)
		(fp_line
			(start 0.120396 0.2794)
			(end -0.12065 0.2794)
			(stroke
				(width 0.1)
				(type default)
			)
			(layer "F.Fab")
		)
		(fp_line
			(start 0.120396 0.3048)
			(end 0.120396 0.2794)
			(stroke
				(width 0.1)
				(type default)
			)
			(layer "F.Fab")
		)
		(fp_line
			(start 0.12065 -0.3048)
			(end 0.67945 -0.3048)
			(stroke
				(width 0.1)
				(type default)
			)
			(layer "F.Fab")
		)
		(fp_line
			(start 0.12065 -0.2794)
			(end 0.12065 -0.3048)
			(stroke
				(width 0.1)
				(type default)
			)
			(layer "F.Fab")
		)
		(fp_line
			(start 0.67945 -0.3048)
			(end 0.67945 0.3048)
			(stroke
				(width 0.1)
				(type default)
			)
			(layer "F.Fab")
		)
		(fp_line
			(start 0.67945 0.3048)
			(end 0.120396 0.3048)
			(stroke
				(width 0.1)
				(type default)
			)
			(layer "F.Fab")
		)
		(pad "1" smd circle
			(at -0.40005 0)
			(size 0 0)
			(layers "F.Cu" "F.Mask" "F.Paste")
			(net "SW_PVDDCR_CPU0_P1_SW1")
		)
		(pad "2" smd circle
			(at 0.40005 0)
			(size 0 0)
			(layers "F.Cu" "F.Mask" "F.Paste")
			(net "SW_PVDDCR_CPU0_P1_SW1_RC")
		)
	)
	(footprint ""
		(layer "F.Cu")
		(at 24.765 -362.204 180)
		(property "Reference" "C8362"
			(at 0 0 180)
			(layer "F.SilkS")
			(hide yes)
			(effects
				(font
					(size 1.27 1.27)
				)
			)
		)
		(property "Value" ""
			(at 0 0 180)
			(layer "F.Fab")
			(effects
				(font
					(size 1.27 1.27)
				)
			)
		)
		(duplicate_pad_numbers_are_jumpers no)
		(fp_line
			(start 0.7874 0.4064)
			(end -0.7874 0.4064)
			(stroke
				(width 0.1524)
				(type default)
			)
			(layer "F.SilkS")
		)
		(fp_line
			(start 0.7874 -0.4064)
			(end 0.7874 0.4064)
			(stroke
				(width 0.1524)
				(type default)
			)
			(layer "F.SilkS")
		)
		(fp_line
			(start -0.7874 0.4064)
			(end -0.7874 -0.4064)
			(stroke
				(width 0.1524)
				(type default)
			)
			(layer "F.SilkS")
		)
		(fp_line
			(start -0.7874 -0.4064)
			(end 0.7874 -0.4064)
			(stroke
				(width 0.1524)
				(type default)
			)
			(layer "F.SilkS")
		)
		(fp_line
			(start 0.67945 0.3048)
			(end 0.120396 0.3048)
			(stroke
				(width 0.1)
				(type default)
			)
			(layer "F.Fab")
		)
		(fp_line
			(start 0.67945 -0.3048)
			(end 0.67945 0.3048)
			(stroke
				(width 0.1)
				(type default)
			)
			(layer "F.Fab")
		)
		(fp_line
			(start 0.12065 -0.2794)
			(end 0.12065 -0.3048)
			(stroke
				(width 0.1)
				(type default)
			)
			(layer "F.Fab")
		)
		(fp_line
			(start 0.12065 -0.3048)
			(end 0.67945 -0.3048)
			(stroke
				(width 0.1)
				(type default)
			)
			(layer "F.Fab")
		)
		(fp_line
			(start 0.120396 0.3048)
			(end 0.120396 0.2794)
			(stroke
				(width 0.1)
				(type default)
			)
			(layer "F.Fab")
		)
		(fp_line
			(start 0.120396 0.2794)
			(end -0.12065 0.2794)
			(stroke
				(width 0.1)
				(type default)
			)
			(layer "F.Fab")
		)
		(fp_line
			(start -0.12065 0.3048)
			(end -0.67945 0.3048)
			(stroke
				(width 0.1)
				(type default)
			)
			(layer "F.Fab")
		)
		(fp_line
			(start -0.12065 0.2794)
			(end -0.12065 0.3048)
			(stroke
				(width 0.1)
				(type default)
			)
			(layer "F.Fab")
		)
		(fp_line
			(start -0.12065 -0.2794)
			(end 0.12065 -0.2794)
			(stroke
				(width 0.1)
				(type default)
			)
			(layer "F.Fab")
		)
		(fp_line
			(start -0.12065 -0.305054)
			(end -0.12065 -0.2794)
			(stroke
				(width 0.1)
				(type default)
			)
			(layer "F.Fab")
		)
		(fp_line
			(start -0.67945 0.3048)
			(end -0.67945 -0.305054)
			(stroke
				(width 0.1)
				(type default)
			)
			(layer "F.Fab")
		)
		(fp_line
			(start -0.67945 -0.305054)
			(end -0.12065 -0.305054)
			(stroke
				(width 0.1)
				(type default)
			)
			(layer "F.Fab")
		)
		(pad "1" smd circle
			(at -0.40005 0 180)
			(size 0 0)
			(layers "F.Cu" "F.Mask" "F.Paste")
			(net "PWRGD_PVDDIO_P1_R")
		)
		(pad "2" smd circle
			(at 0.40005 0 180)
			(size 0 0)
			(layers "F.Cu" "F.Mask" "F.Paste")
			(net "GND")
		)
	)
	(footprint ""
		(layer "F.Cu")
		(at 94.605602 -40.139112)
		(property "Reference" "R3184"
			(at 0 0 0)
			(layer "F.SilkS")
			(hide yes)
			(effects
				(font
					(size 1.27 1.27)
				)
			)
		)
		(property "Value" ""
			(at 0 0 0)
			(layer "F.Fab")
			(effects
				(font
					(size 1.27 1.27)
				)
			)
		)
		(duplicate_pad_numbers_are_jumpers no)
		(fp_line
			(start -0.7874 -0.4064)
			(end 0.7874 -0.4064)
			(stroke
				(width 0.1524)
				(type default)
			)
			(layer "F.SilkS")
		)
		(fp_line
			(start -0.7874 0.4064)
			(end -0.7874 -0.4064)
			(stroke
				(width 0.1524)
				(type default)
			)
			(layer "F.SilkS")
		)
		(fp_line
			(start 0.7874 -0.4064)
			(end 0.7874 0.4064)
			(stroke
				(width 0.1524)
				(type default)
			)
			(layer "F.SilkS")
		)
		(fp_line
			(start 0.7874 0.4064)
			(end -0.7874 0.4064)
			(stroke
				(width 0.1524)
				(type default)
			)
			(layer "F.SilkS")
		)
		(fp_line
			(start -0.67945 -0.305054)
			(end -0.12065 -0.305054)
			(stroke
				(width 0.1)
				(type default)
			)
			(layer "F.Fab")
		)
		(fp_line
			(start -0.67945 0.3048)
			(end -0.67945 -0.305054)
			(stroke
				(width 0.1)
				(type default)
			)
			(layer "F.Fab")
		)
		(fp_line
			(start -0.12065 -0.305054)
			(end -0.12065 -0.2794)
			(stroke
				(width 0.1)
				(type default)
			)
			(layer "F.Fab")
		)
		(fp_line
			(start -0.12065 -0.2794)
			(end 0.12065 -0.2794)
			(stroke
				(width 0.1)
				(type default)
			)
			(layer "F.Fab")
		)
		(fp_line
			(start -0.12065 0.2794)
			(end -0.12065 0.3048)
			(stroke
				(width 0.1)
				(type default)
			)
			(layer "F.Fab")
		)
		(fp_line
			(start -0.12065 0.3048)
			(end -0.67945 0.3048)
			(stroke
				(width 0.1)
				(type default)
			)
			(layer "F.Fab")
		)
		(fp_line
			(start 0.120396 0.2794)
			(end -0.12065 0.2794)
			(stroke
				(width 0.1)
				(type default)
			)
			(layer "F.Fab")
		)
		(fp_line
			(start 0.120396 0.3048)
			(end 0.120396 0.2794)
			(stroke
				(width 0.1)
				(type default)
			)
			(layer "F.Fab")
		)
		(fp_line
			(start 0.12065 -0.3048)
			(end 0.67945 -0.3048)
			(stroke
				(width 0.1)
				(type default)
			)
			(layer "F.Fab")
		)
		(fp_line
			(start 0.12065 -0.2794)
			(end 0.12065 -0.3048)
			(stroke
				(width 0.1)
				(type default)
			)
			(layer "F.Fab")
		)
		(fp_line
			(start 0.67945 -0.3048)
			(end 0.67945 0.3048)
			(stroke
				(width 0.1)
				(type default)
			)
			(layer "F.Fab")
		)
		(fp_line
			(start 0.67945 0.3048)
			(end 0.120396 0.3048)
			(stroke
				(width 0.1)
				(type default)
			)
			(layer "F.Fab")
		)
		(pad "1" smd circle
			(at -0.40005 0)
			(size 0 0)
			(layers "F.Cu" "F.Mask" "F.Paste")
			(net "P3V3_AUX")
		)
		(pad "2" smd circle
			(at 0.40005 0)
			(size 0 0)
			(layers "F.Cu" "F.Mask" "F.Paste")
			(net "OCP_V3_2_WAKE_BUFF_N")
		)
	)
	(footprint ""
		(layer "F.Cu")
		(at 340.940644 -378.95403 -90)
		(property "Reference" "C952"
			(at 0 0 270)
			(layer "F.SilkS")
			(hide yes)
			(effects
				(font
					(size 1.27 1.27)
				)
			)
		)
		(property "Value" ""
			(at 0 0 270)
			(layer "F.Fab")
			(effects
				(font
					(size 1.27 1.27)
				)
			)
		)
		(duplicate_pad_numbers_are_jumpers no)
		(fp_line
			(start -0.299974 0.150114)
			(end -0.299974 -0.150114)
			(stroke
				(width 0.1)
				(type default)
			)
			(layer "F.Fab")
		)
		(fp_line
			(start 0.299974 0.150114)
			(end -0.299974 0.150114)
			(stroke
				(width 0.1)
				(type default)
			)
			(layer "F.Fab")
		)
		(fp_line
			(start -0.299974 -0.150114)
			(end 0.299974 -0.150114)
			(stroke
				(width 0.1)
				(type default)
			)
			(layer "F.Fab")
		)
		(fp_line
			(start 0.299974 -0.150114)
			(end 0.299974 0.150114)
			(stroke
				(width 0.1)
				(type default)
			)
			(layer "F.Fab")
		)
		(pad "1" smd rect
			(at -0.2667 0 270)
			(size 0.3048 0.381)
			(layers "F.Cu" "F.Mask" "F.Paste")
			(net "P5E_CPU0_P1_TX_C_DN<6>")
		)
		(pad "2" smd rect
			(at 0.2667 0 270)
			(size 0.3048 0.381)
			(layers "F.Cu" "F.Mask" "F.Paste")
			(net "P5E_CPU0_P1_TX_DN<6>")
		)
	)
	(footprint ""
		(layer "F.Cu")
		(at 239.152684 -58.32729)
		(property "Reference" "C1989"
			(at 0 0 0)
			(layer "F.SilkS")
			(hide yes)
			(effects
				(font
					(size 1.27 1.27)
				)
			)
		)
		(property "Value" ""
			(at 0 0 0)
			(layer "F.Fab")
			(effects
				(font
					(size 1.27 1.27)
				)
			)
		)
		(duplicate_pad_numbers_are_jumpers no)
		(fp_line
			(start -0.299974 -0.150114)
			(end 0.299974 -0.150114)
			(stroke
				(width 0.1)
				(type default)
			)
			(layer "F.Fab")
		)
		(fp_line
			(start -0.299974 0.150114)
			(end -0.299974 -0.150114)
			(stroke
				(width 0.1)
				(type default)
			)
			(layer "F.Fab")
		)
		(fp_line
			(start 0.299974 -0.150114)
			(end 0.299974 0.150114)
			(stroke
				(width 0.1)
				(type default)
			)
			(layer "F.Fab")
		)
		(fp_line
			(start 0.299974 0.150114)
			(end -0.299974 0.150114)
			(stroke
				(width 0.1)
				(type default)
			)
			(layer "F.Fab")
		)
		(pad "1" smd rect
			(at -0.2667 0)
			(size 0.3048 0.381)
			(layers "F.Cu" "F.Mask" "F.Paste")
			(net "P3E_CPU0_P4_TX_C_DP<3>")
		)
		(pad "2" smd rect
			(at 0.2667 0)
			(size 0.3048 0.381)
			(layers "F.Cu" "F.Mask" "F.Paste")
			(net "P3E_CPU0_P4_TX_DP<3>")
		)
	)
	(footprint ""
		(layer "F.Cu")
		(at 35.881818 -438.465214 180)
		(property "Reference" "R3107"
			(at 0 0 180)
			(layer "F.SilkS")
			(hide yes)
			(effects
				(font
					(size 1.27 1.27)
				)
			)
		)
		(property "Value" ""
			(at 0 0 180)
			(layer "F.Fab")
			(effects
				(font
					(size 1.27 1.27)
				)
			)
		)
		(duplicate_pad_numbers_are_jumpers no)
		(fp_line
			(start 0.7874 0.4064)
			(end -0.7874 0.4064)
			(stroke
				(width 0.1524)
				(type default)
			)
			(layer "F.SilkS")
		)
		(fp_line
			(start 0.7874 -0.4064)
			(end 0.7874 0.4064)
			(stroke
				(width 0.1524)
				(type default)
			)
			(layer "F.SilkS")
		)
		(fp_line
			(start -0.7874 0.4064)
			(end -0.7874 -0.4064)
			(stroke
				(width 0.1524)
				(type default)
			)
			(layer "F.SilkS")
		)
		(fp_line
			(start -0.7874 -0.4064)
			(end 0.7874 -0.4064)
			(stroke
				(width 0.1524)
				(type default)
			)
			(layer "F.SilkS")
		)
		(fp_line
			(start 0.67945 0.3048)
			(end 0.120396 0.3048)
			(stroke
				(width 0.1)
				(type default)
			)
			(layer "F.Fab")
		)
		(fp_line
			(start 0.67945 -0.3048)
			(end 0.67945 0.3048)
			(stroke
				(width 0.1)
				(type default)
			)
			(layer "F.Fab")
		)
		(fp_line
			(start 0.12065 -0.2794)
			(end 0.12065 -0.3048)
			(stroke
				(width 0.1)
				(type default)
			)
			(layer "F.Fab")
		)
		(fp_line
			(start 0.12065 -0.3048)
			(end 0.67945 -0.3048)
			(stroke
				(width 0.1)
				(type default)
			)
			(layer "F.Fab")
		)
		(fp_line
			(start 0.120396 0.3048)
			(end 0.120396 0.2794)
			(stroke
				(width 0.1)
				(type default)
			)
			(layer "F.Fab")
		)
		(fp_line
			(start 0.120396 0.2794)
			(end -0.12065 0.2794)
			(stroke
				(width 0.1)
				(type default)
			)
			(layer "F.Fab")
		)
		(fp_line
			(start -0.12065 0.3048)
			(end -0.67945 0.3048)
			(stroke
				(width 0.1)
				(type default)
			)
			(layer "F.Fab")
		)
		(fp_line
			(start -0.12065 0.2794)
			(end -0.12065 0.3048)
			(stroke
				(width 0.1)
				(type default)
			)
			(layer "F.Fab")
		)
		(fp_line
			(start -0.12065 -0.2794)
			(end 0.12065 -0.2794)
			(stroke
				(width 0.1)
				(type default)
			)
			(layer "F.Fab")
		)
		(fp_line
			(start -0.12065 -0.305054)
			(end -0.12065 -0.2794)
			(stroke
				(width 0.1)
				(type default)
			)
			(layer "F.Fab")
		)
		(fp_line
			(start -0.67945 0.3048)
			(end -0.67945 -0.305054)
			(stroke
				(width 0.1)
				(type default)
			)
			(layer "F.Fab")
		)
		(fp_line
			(start -0.67945 -0.305054)
			(end -0.12065 -0.305054)
			(stroke
				(width 0.1)
				(type default)
			)
			(layer "F.Fab")
		)
		(pad "1" smd circle
			(at -0.40005 0 180)
			(size 0 0)
			(layers "F.Cu" "F.Mask" "F.Paste")
			(net "SMB_2_BMC_GPU_SCL")
		)
		(pad "2" smd circle
			(at 0.40005 0 180)
			(size 0 0)
			(layers "F.Cu" "F.Mask" "F.Paste")
			(net "SMB_2_BMC_GPU_R_SCL")
		)
	)
	(footprint ""
		(layer "F.Cu")
		(at 111.633 -123.952 -90)
		(property "Reference" "R6501"
			(at 0 0 270)
			(layer "F.SilkS")
			(hide yes)
			(effects
				(font
					(size 1.27 1.27)
				)
			)
		)
		(property "Value" ""
			(at 0 0 270)
			(layer "F.Fab")
			(effects
				(font
					(size 1.27 1.27)
				)
			)
		)
		(duplicate_pad_numbers_are_jumpers no)
		(fp_line
			(start -0.7874 0.4064)
			(end -0.7874 -0.4064)
			(stroke
				(width 0.1524)
				(type default)
			)
			(layer "F.SilkS")
		)
		(fp_line
			(start 0.7874 0.4064)
			(end -0.7874 0.4064)
			(stroke
				(width 0.1524)
				(type default)
			)
			(layer "F.SilkS")
		)
		(fp_line
			(start -0.7874 -0.4064)
			(end 0.7874 -0.4064)
			(stroke
				(width 0.1524)
				(type default)
			)
			(layer "F.SilkS")
		)
		(fp_line
			(start 0.7874 -0.4064)
			(end 0.7874 0.4064)
			(stroke
				(width 0.1524)
				(type default)
			)
			(layer "F.SilkS")
		)
		(fp_line
			(start -0.67945 0.3048)
			(end -0.67945 -0.305054)
			(stroke
				(width 0.1)
				(type default)
			)
			(layer "F.Fab")
		)
		(fp_line
			(start -0.12065 0.3048)
			(end -0.67945 0.3048)
			(stroke
				(width 0.1)
				(type default)
			)
			(layer "F.Fab")
		)
		(fp_line
			(start 0.120396 0.3048)
			(end 0.120396 0.2794)
			(stroke
				(width 0.1)
				(type default)
			)
			(layer "F.Fab")
		)
		(fp_line
			(start 0.67945 0.3048)
			(end 0.120396 0.3048)
			(stroke
				(width 0.1)
				(type default)
			)
			(layer "F.Fab")
		)
		(fp_line
			(start -0.12065 0.2794)
			(end -0.12065 0.3048)
			(stroke
				(width 0.1)
				(type default)
			)
			(layer "F.Fab")
		)
		(fp_line
			(start 0.120396 0.2794)
			(end -0.12065 0.2794)
			(stroke
				(width 0.1)
				(type default)
			)
			(layer "F.Fab")
		)
		(fp_line
			(start -0.12065 -0.2794)
			(end 0.12065 -0.2794)
			(stroke
				(width 0.1)
				(type default)
			)
			(layer "F.Fab")
		)
		(fp_line
			(start 0.12065 -0.2794)
			(end 0.12065 -0.3048)
			(stroke
				(width 0.1)
				(type default)
			)
			(layer "F.Fab")
		)
		(fp_line
			(start 0.12065 -0.3048)
			(end 0.67945 -0.3048)
			(stroke
				(width 0.1)
				(type default)
			)
			(layer "F.Fab")
		)
		(fp_line
			(start 0.67945 -0.3048)
			(end 0.67945 0.3048)
			(stroke
				(width 0.1)
				(type default)
			)
			(layer "F.Fab")
		)
		(fp_line
			(start -0.67945 -0.305054)
			(end -0.12065 -0.305054)
			(stroke
				(width 0.1)
				(type default)
			)
			(layer "F.Fab")
		)
		(fp_line
			(start -0.12065 -0.305054)
			(end -0.12065 -0.2794)
			(stroke
				(width 0.1)
				(type default)
			)
			(layer "F.Fab")
		)
		(pad "1" smd circle
			(at -0.40005 0 270)
			(size 0 0)
			(layers "F.Cu" "F.Mask" "F.Paste")
			(net "PWRGD_P3V3_EN_R")
		)
		(pad "2" smd circle
			(at 0.40005 0 270)
			(size 0 0)
			(layers "F.Cu" "F.Mask" "F.Paste")
			(net "GND")
		)
	)
	(footprint ""
		(layer "F.Cu")
		(at 227.59162 -292.988238 180)
		(property "Reference" "PR6522"
			(at 0 0 180)
			(layer "F.SilkS")
			(hide yes)
			(effects
				(font
					(size 1.27 1.27)
				)
			)
		)
		(property "Value" ""
			(at 0 0 180)
			(layer "F.Fab")
			(effects
				(font
					(size 1.27 1.27)
				)
			)
		)
		(duplicate_pad_numbers_are_jumpers no)
		(fp_line
			(start 0.7874 0.4064)
			(end -0.7874 0.4064)
			(stroke
				(width 0.1524)
				(type default)
			)
			(layer "F.SilkS")
		)
		(fp_line
			(start 0.7874 -0.4064)
			(end 0.7874 0.4064)
			(stroke
				(width 0.1524)
				(type default)
			)
			(layer "F.SilkS")
		)
		(fp_line
			(start -0.7874 0.4064)
			(end -0.7874 -0.4064)
			(stroke
				(width 0.1524)
				(type default)
			)
			(layer "F.SilkS")
		)
		(fp_line
			(start -0.7874 -0.4064)
			(end 0.7874 -0.4064)
			(stroke
				(width 0.1524)
				(type default)
			)
			(layer "F.SilkS")
		)
		(fp_line
			(start 0.67945 0.3048)
			(end 0.120396 0.3048)
			(stroke
				(width 0.1)
				(type default)
			)
			(layer "F.Fab")
		)
		(fp_line
			(start 0.67945 -0.3048)
			(end 0.67945 0.3048)
			(stroke
				(width 0.1)
				(type default)
			)
			(layer "F.Fab")
		)
		(fp_line
			(start 0.12065 -0.2794)
			(end 0.12065 -0.3048)
			(stroke
				(width 0.1)
				(type default)
			)
			(layer "F.Fab")
		)
		(fp_line
			(start 0.12065 -0.3048)
			(end 0.67945 -0.3048)
			(stroke
				(width 0.1)
				(type default)
			)
			(layer "F.Fab")
		)
		(fp_line
			(start 0.120396 0.3048)
			(end 0.120396 0.2794)
			(stroke
				(width 0.1)
				(type default)
			)
			(layer "F.Fab")
		)
		(fp_line
			(start 0.120396 0.2794)
			(end -0.12065 0.2794)
			(stroke
				(width 0.1)
				(type default)
			)
			(layer "F.Fab")
		)
		(fp_line
			(start -0.12065 0.3048)
			(end -0.67945 0.3048)
			(stroke
				(width 0.1)
				(type default)
			)
			(layer "F.Fab")
		)
		(fp_line
			(start -0.12065 0.2794)
			(end -0.12065 0.3048)
			(stroke
				(width 0.1)
				(type default)
			)
			(layer "F.Fab")
		)
		(fp_line
			(start -0.12065 -0.2794)
			(end 0.12065 -0.2794)
			(stroke
				(width 0.1)
				(type default)
			)
			(layer "F.Fab")
		)
		(fp_line
			(start -0.12065 -0.305054)
			(end -0.12065 -0.2794)
			(stroke
				(width 0.1)
				(type default)
			)
			(layer "F.Fab")
		)
		(fp_line
			(start -0.67945 0.3048)
			(end -0.67945 -0.305054)
			(stroke
				(width 0.1)
				(type default)
			)
			(layer "F.Fab")
		)
		(fp_line
			(start -0.67945 -0.305054)
			(end -0.12065 -0.305054)
			(stroke
				(width 0.1)
				(type default)
			)
			(layer "F.Fab")
		)
		(pad "1" smd circle
			(at -0.40005 0 180)
			(size 0 0)
			(layers "F.Cu" "F.Mask" "F.Paste")
			(net "P1V8_RETIMER_CPU1_CS")
		)
		(pad "2" smd circle
			(at 0.40005 0 180)
			(size 0 0)
			(layers "F.Cu" "F.Mask" "F.Paste")
			(net "GND")
		)
	)
	(footprint ""
		(layer "F.Cu")
		(at 305.754024 -34.001964)
		(property "Reference" "R1775"
			(at 0 0 0)
			(layer "F.SilkS")
			(hide yes)
			(effects
				(font
					(size 1.27 1.27)
				)
			)
		)
		(property "Value" ""
			(at 0 0 0)
			(layer "F.Fab")
			(effects
				(font
					(size 1.27 1.27)
				)
			)
		)
		(duplicate_pad_numbers_are_jumpers no)
		(fp_line
			(start -0.7874 -0.4064)
			(end 0.7874 -0.4064)
			(stroke
				(width 0.1524)
				(type default)
			)
			(layer "F.SilkS")
		)
		(fp_line
			(start -0.7874 0.4064)
			(end -0.7874 -0.4064)
			(stroke
				(width 0.1524)
				(type default)
			)
			(layer "F.SilkS")
		)
		(fp_line
			(start 0.7874 -0.4064)
			(end 0.7874 0.4064)
			(stroke
				(width 0.1524)
				(type default)
			)
			(layer "F.SilkS")
		)
		(fp_line
			(start 0.7874 0.4064)
			(end -0.7874 0.4064)
			(stroke
				(width 0.1524)
				(type default)
			)
			(layer "F.SilkS")
		)
		(fp_line
			(start -0.67945 -0.305054)
			(end -0.12065 -0.305054)
			(stroke
				(width 0.1)
				(type default)
			)
			(layer "F.Fab")
		)
		(fp_line
			(start -0.67945 0.3048)
			(end -0.67945 -0.305054)
			(stroke
				(width 0.1)
				(type default)
			)
			(layer "F.Fab")
		)
		(fp_line
			(start -0.12065 -0.305054)
			(end -0.12065 -0.2794)
			(stroke
				(width 0.1)
				(type default)
			)
			(layer "F.Fab")
		)
		(fp_line
			(start -0.12065 -0.2794)
			(end 0.12065 -0.2794)
			(stroke
				(width 0.1)
				(type default)
			)
			(layer "F.Fab")
		)
		(fp_line
			(start -0.12065 0.2794)
			(end -0.12065 0.3048)
			(stroke
				(width 0.1)
				(type default)
			)
			(layer "F.Fab")
		)
		(fp_line
			(start -0.12065 0.3048)
			(end -0.67945 0.3048)
			(stroke
				(width 0.1)
				(type default)
			)
			(layer "F.Fab")
		)
		(fp_line
			(start 0.120396 0.2794)
			(end -0.12065 0.2794)
			(stroke
				(width 0.1)
				(type default)
			)
			(layer "F.Fab")
		)
		(fp_line
			(start 0.120396 0.3048)
			(end 0.120396 0.2794)
			(stroke
				(width 0.1)
				(type default)
			)
			(layer "F.Fab")
		)
		(fp_line
			(start 0.12065 -0.3048)
			(end 0.67945 -0.3048)
			(stroke
				(width 0.1)
				(type default)
			)
			(layer "F.Fab")
		)
		(fp_line
			(start 0.12065 -0.2794)
			(end 0.12065 -0.3048)
			(stroke
				(width 0.1)
				(type default)
			)
			(layer "F.Fab")
		)
		(fp_line
			(start 0.67945 -0.3048)
			(end 0.67945 0.3048)
			(stroke
				(width 0.1)
				(type default)
			)
			(layer "F.Fab")
		)
		(fp_line
			(start 0.67945 0.3048)
			(end 0.120396 0.3048)
			(stroke
				(width 0.1)
				(type default)
			)
			(layer "F.Fab")
		)
		(pad "1" smd circle
			(at -0.40005 0)
			(size 0 0)
			(layers "F.Cu" "F.Mask" "F.Paste")
			(net "P3V_BAT")
		)
		(pad "2" smd circle
			(at 0.40005 0)
			(size 0 0)
			(layers "F.Cu" "F.Mask" "F.Paste")
			(net "P3V_BAT_R")
		)
	)
	(footprint ""
		(layer "F.Cu")
		(at 422.623742 -97.941892)
		(property "Reference" "PD103"
			(at -2.246376 2.802382 0)
			(unlocked yes)
			(layer "F.SilkS")
			(effects
				(font
					(size 0.7874 0.5842)
					(thickness 0.1524)
				)
				(justify left)
			)
		)
		(property "Value" ""
			(at 0 0 0)
			(layer "F.Fab")
			(effects
				(font
					(size 1.27 1.27)
				)
			)
		)
		(duplicate_pad_numbers_are_jumpers no)
		(fp_line
			(start -3.400044 -1.459992)
			(end 4.107942 -1.459992)
			(stroke
				(width 0.1524)
				(type default)
			)
			(layer "F.SilkS")
		)
		(fp_line
			(start -3.400044 1.459992)
			(end -3.400044 -1.459992)
			(stroke
				(width 0.1524)
				(type default)
			)
			(layer "F.SilkS")
		)
		(fp_line
			(start 4.107942 -1.459992)
			(end 4.107942 1.459992)
			(stroke
				(width 0.1524)
				(type default)
			)
			(layer "F.SilkS")
		)
		(fp_line
			(start 4.107942 1.459992)
			(end -3.400044 1.459992)
			(stroke
				(width 0.1524)
				(type default)
			)
			(layer "F.SilkS")
		)
		(fp_rect
			(start 3.308096 1.459992)
			(end 4.107942 -1.459992)
			(stroke
				(width 0)
				(type default)
			)
			(fill yes)
			(layer "F.SilkS")
		)
		(fp_line
			(start -2.29997 -1.459992)
			(end 2.29997 -1.459992)
			(stroke
				(width 0.1)
				(type default)
			)
			(layer "F.Fab")
		)
		(fp_line
			(start -2.29997 1.459992)
			(end -2.29997 -1.459992)
			(stroke
				(width 0.1)
				(type default)
			)
			(layer "F.Fab")
		)
		(fp_line
			(start 2.29997 -1.459992)
			(end 2.29997 1.459992)
			(stroke
				(width 0.1)
				(type default)
			)
			(layer "F.Fab")
		)
		(fp_line
			(start 2.29997 1.459992)
			(end -2.29997 1.459992)
			(stroke
				(width 0.1)
				(type default)
			)
			(layer "F.Fab")
		)
		(fp_text user "+"
			(at -4.7752 -0.12065 0)
			(unlocked yes)
			(layer "F.SilkS")
			(effects
				(font
					(size 1.905 1.4224)
					(thickness 0.1524)
				)
				(justify left)
			)
		)
		(fp_text user "-"
			(at 4.51358 2.29997 180)
			(unlocked yes)
			(layer "F.SilkS")
			(effects
				(font
					(size 1.905 1.4224)
					(thickness 0.1524)
				)
				(justify left)
			)
		)
		(fp_text user "+"
			(at -4.7752 -0.12065 0)
			(unlocked yes)
			(layer "F.Fab")
			(effects
				(font
					(size 1.905 1.4224)
					(thickness 0.1524)
				)
				(justify left)
			)
		)
		(fp_text user "-"
			(at 5.4102 0.29845 180)
			(unlocked yes)
			(layer "F.Fab")
			(effects
				(font
					(size 1.905 1.4224)
					(thickness 0.1524)
				)
				(justify left)
			)
		)
		(pad "A" smd rect
			(at -1.999996 0 90)
			(size 1.7018 2.5146)
			(layers "F.Cu" "F.Mask" "F.Paste")
			(net "GND")
		)
		(pad "C" smd rect
			(at 1.999996 0 90)
			(size 1.7018 2.5146)
			(layers "F.Cu" "F.Mask" "F.Paste")
			(net "P3V3_OCP_SFF_R")
		)
	)
	(footprint ""
		(layer "F.Cu")
		(at 429.006 -58.42 -90)
		(property "Reference" "R8018"
			(at 0 0 270)
			(layer "F.SilkS")
			(hide yes)
			(effects
				(font
					(size 1.27 1.27)
				)
			)
		)
		(property "Value" ""
			(at 0 0 270)
			(layer "F.Fab")
			(effects
				(font
					(size 1.27 1.27)
				)
			)
		)
		(duplicate_pad_numbers_are_jumpers no)
		(fp_line
			(start -0.7874 0.4064)
			(end -0.7874 -0.4064)
			(stroke
				(width 0.1524)
				(type default)
			)
			(layer "F.SilkS")
		)
		(fp_line
			(start 0.7874 0.4064)
			(end -0.7874 0.4064)
			(stroke
				(width 0.1524)
				(type default)
			)
			(layer "F.SilkS")
		)
		(fp_line
			(start -0.7874 -0.4064)
			(end 0.7874 -0.4064)
			(stroke
				(width 0.1524)
				(type default)
			)
			(layer "F.SilkS")
		)
		(fp_line
			(start 0.7874 -0.4064)
			(end 0.7874 0.4064)
			(stroke
				(width 0.1524)
				(type default)
			)
			(layer "F.SilkS")
		)
		(fp_line
			(start -0.67945 0.3048)
			(end -0.67945 -0.305054)
			(stroke
				(width 0.1)
				(type default)
			)
			(layer "F.Fab")
		)
		(fp_line
			(start -0.12065 0.3048)
			(end -0.67945 0.3048)
			(stroke
				(width 0.1)
				(type default)
			)
			(layer "F.Fab")
		)
		(fp_line
			(start 0.120396 0.3048)
			(end 0.120396 0.2794)
			(stroke
				(width 0.1)
				(type default)
			)
			(layer "F.Fab")
		)
		(fp_line
			(start 0.67945 0.3048)
			(end 0.120396 0.3048)
			(stroke
				(width 0.1)
				(type default)
			)
			(layer "F.Fab")
		)
		(fp_line
			(start -0.12065 0.2794)
			(end -0.12065 0.3048)
			(stroke
				(width 0.1)
				(type default)
			)
			(layer "F.Fab")
		)
		(fp_line
			(start 0.120396 0.2794)
			(end -0.12065 0.2794)
			(stroke
				(width 0.1)
				(type default)
			)
			(layer "F.Fab")
		)
		(fp_line
			(start -0.12065 -0.2794)
			(end 0.12065 -0.2794)
			(stroke
				(width 0.1)
				(type default)
			)
			(layer "F.Fab")
		)
		(fp_line
			(start 0.12065 -0.2794)
			(end 0.12065 -0.3048)
			(stroke
				(width 0.1)
				(type default)
			)
			(layer "F.Fab")
		)
		(fp_line
			(start 0.12065 -0.3048)
			(end 0.67945 -0.3048)
			(stroke
				(width 0.1)
				(type default)
			)
			(layer "F.Fab")
		)
		(fp_line
			(start 0.67945 -0.3048)
			(end 0.67945 0.3048)
			(stroke
				(width 0.1)
				(type default)
			)
			(layer "F.Fab")
		)
		(fp_line
			(start -0.67945 -0.305054)
			(end -0.12065 -0.305054)
			(stroke
				(width 0.1)
				(type default)
			)
			(layer "F.Fab")
		)
		(fp_line
			(start -0.12065 -0.305054)
			(end -0.12065 -0.2794)
			(stroke
				(width 0.1)
				(type default)
			)
			(layer "F.Fab")
		)
		(pad "1" smd circle
			(at -0.40005 0 270)
			(size 0 0)
			(layers "F.Cu" "F.Mask" "F.Paste")
			(net "P1V8_AUX")
		)
		(pad "2" smd circle
			(at 0.40005 0 270)
			(size 0 0)
			(layers "F.Cu" "F.Mask" "F.Paste")
			(net "U124_VCC")
		)
	)
	(footprint ""
		(layer "F.Cu")
		(at 38.78707 -171.980606 180)
		(property "Reference" "U107"
			(at -2.3368 -2.662682 0)
			(unlocked yes)
			(layer "F.SilkS")
			(effects
				(font
					(size 0.7874 0.5842)
					(thickness 0.1524)
				)
			)
		)
		(property "Value" ""
			(at 0 0 180)
			(layer "F.Fab")
			(effects
				(font
					(size 1.27 1.27)
				)
			)
		)
		(duplicate_pad_numbers_are_jumpers no)
		(fp_line
			(start 1.03378 1.284478)
			(end -1.03378 1.284478)
			(stroke
				(width 0.1524)
				(type default)
			)
			(layer "F.SilkS")
		)
		(fp_line
			(start 1.03378 -1.284478)
			(end 1.03378 1.284478)
			(stroke
				(width 0.1524)
				(type default)
			)
			(layer "F.SilkS")
		)
		(fp_line
			(start -1.03378 1.284478)
			(end -1.03378 -1.284478)
			(stroke
				(width 0.1524)
				(type default)
			)
			(layer "F.SilkS")
		)
		(fp_line
			(start -1.03378 -1.284478)
			(end 1.03378 -1.284478)
			(stroke
				(width 0.1524)
				(type default)
			)
			(layer "F.SilkS")
		)
		(fp_poly
			(pts
				(xy -1.663192 -1.558798) (xy -1.327658 -0.971296) (xy -1.99898 -1.05537)
			)
			(stroke
				(width 0)
				(type default)
			)
			(fill yes)
			(layer "F.SilkS")
		)
		(fp_line
			(start 0.774954 1.02489)
			(end -0.774954 1.02489)
			(stroke
				(width 0.1)
				(type default)
			)
			(layer "F.Fab")
		)
		(fp_line
			(start 0.774954 -1.02489)
			(end 0.774954 1.02489)
			(stroke
				(width 0.1)
				(type default)
			)
			(layer "F.Fab")
		)
		(fp_line
			(start -0.774954 1.02489)
			(end -0.774954 -1.02489)
			(stroke
				(width 0.1)
				(type default)
			)
			(layer "F.Fab")
		)
		(fp_line
			(start -0.774954 -1.02489)
			(end 0.774954 -1.02489)
			(stroke
				(width 0.1)
				(type default)
			)
			(layer "F.Fab")
		)
		(fp_poly
			(pts
				(xy -1.201674 -0.750062) (xy -1.806702 -0.447548) (xy -1.806702 -1.052576)
			)
			(stroke
				(width 0)
				(type default)
			)
			(fill yes)
			(layer "F.Fab")
		)
		(pad "1" smd rect
			(at -0.64008 -0.750062 270)
			(size 0.3048 0.5334)
			(layers "F.Cu" "F.Mask" "F.Paste")
			(net "I3C_0_SPD_DDRAF_CPU1_SCL")
		)
		(pad "2" smd rect
			(at -0.64008 -0.249936 270)
			(size 0.254 0.5334)
			(layers "F.Cu" "F.Mask" "F.Paste")
			(net "I3C_0_SPD_DDRAF_CPU1_SDA")
		)
		(pad "3" smd rect
			(at -0.64008 0.249936 270)
			(size 0.254 0.5334)
			(layers "F.Cu" "F.Mask" "F.Paste")
			(net "I3C_SCM_2_R_SCL")
		)
		(pad "4" smd rect
			(at -0.64008 0.750062 270)
			(size 0.3048 0.5334)
			(layers "F.Cu" "F.Mask" "F.Paste")
			(net "I3C_SCM_2_R_SDA")
		)
		(pad "5" smd rect
			(at 0 0.839978 180)
			(size 0.3302 0.635)
			(layers "F.Cu" "F.Mask" "F.Paste")
			(net "GND")
		)
		(pad "6" smd rect
			(at 0.64008 0.750062 270)
			(size 0.3048 0.5334)
			(layers "F.Cu" "F.Mask" "F.Paste")
			(net "FM_I3C_CPU1_MUX0_OE_N")
		)
		(pad "7" smd rect
			(at 0.64008 0.249936 270)
			(size 0.254 0.5334)
			(layers "F.Cu" "F.Mask" "F.Paste")
			(net "I3C_SPD_DDRAF_CPU1_LVC1_SDA")
		)
		(pad "8" smd rect
			(at 0.64008 -0.249936 270)
			(size 0.254 0.5334)
			(layers "F.Cu" "F.Mask" "F.Paste")
			(net "I3C_SPD_DDRAF_CPU1_LVC1_SCL")
		)
		(pad "9" smd rect
			(at 0.64008 -0.750062 270)
			(size 0.3048 0.5334)
			(layers "F.Cu" "F.Mask" "F.Paste")
			(net "FM_I3C_CPU1_MUX0_SEL")
		)
		(pad "10" smd rect
			(at 0 -0.839978 180)
			(size 0.3302 0.635)
			(layers "F.Cu" "F.Mask" "F.Paste")
			(net "P3V3_AUX")
		)
	)
	(footprint ""
		(layer "F.Cu")
		(at 326.662288 -392.48588 180)
		(property "Reference" "R960"
			(at 0 0 180)
			(layer "F.SilkS")
			(hide yes)
			(effects
				(font
					(size 1.27 1.27)
				)
			)
		)
		(property "Value" ""
			(at 0 0 180)
			(layer "F.Fab")
			(effects
				(font
					(size 1.27 1.27)
				)
			)
		)
		(duplicate_pad_numbers_are_jumpers no)
		(fp_line
			(start 0.7874 0.4064)
			(end -0.7874 0.4064)
			(stroke
				(width 0.1524)
				(type default)
			)
			(layer "F.SilkS")
		)
		(fp_line
			(start 0.7874 -0.4064)
			(end 0.7874 0.4064)
			(stroke
				(width 0.1524)
				(type default)
			)
			(layer "F.SilkS")
		)
		(fp_line
			(start -0.7874 0.4064)
			(end -0.7874 -0.4064)
			(stroke
				(width 0.1524)
				(type default)
			)
			(layer "F.SilkS")
		)
		(fp_line
			(start -0.7874 -0.4064)
			(end 0.7874 -0.4064)
			(stroke
				(width 0.1524)
				(type default)
			)
			(layer "F.SilkS")
		)
		(fp_line
			(start 0.67945 0.3048)
			(end 0.120396 0.3048)
			(stroke
				(width 0.1)
				(type default)
			)
			(layer "F.Fab")
		)
		(fp_line
			(start 0.67945 -0.3048)
			(end 0.67945 0.3048)
			(stroke
				(width 0.1)
				(type default)
			)
			(layer "F.Fab")
		)
		(fp_line
			(start 0.12065 -0.2794)
			(end 0.12065 -0.3048)
			(stroke
				(width 0.1)
				(type default)
			)
			(layer "F.Fab")
		)
		(fp_line
			(start 0.12065 -0.3048)
			(end 0.67945 -0.3048)
			(stroke
				(width 0.1)
				(type default)
			)
			(layer "F.Fab")
		)
		(fp_line
			(start 0.120396 0.3048)
			(end 0.120396 0.2794)
			(stroke
				(width 0.1)
				(type default)
			)
			(layer "F.Fab")
		)
		(fp_line
			(start 0.120396 0.2794)
			(end -0.12065 0.2794)
			(stroke
				(width 0.1)
				(type default)
			)
			(layer "F.Fab")
		)
		(fp_line
			(start -0.12065 0.3048)
			(end -0.67945 0.3048)
			(stroke
				(width 0.1)
				(type default)
			)
			(layer "F.Fab")
		)
		(fp_line
			(start -0.12065 0.2794)
			(end -0.12065 0.3048)
			(stroke
				(width 0.1)
				(type default)
			)
			(layer "F.Fab")
		)
		(fp_line
			(start -0.12065 -0.2794)
			(end 0.12065 -0.2794)
			(stroke
				(width 0.1)
				(type default)
			)
			(layer "F.Fab")
		)
		(fp_line
			(start -0.12065 -0.305054)
			(end -0.12065 -0.2794)
			(stroke
				(width 0.1)
				(type default)
			)
			(layer "F.Fab")
		)
		(fp_line
			(start -0.67945 0.3048)
			(end -0.67945 -0.305054)
			(stroke
				(width 0.1)
				(type default)
			)
			(layer "F.Fab")
		)
		(fp_line
			(start -0.67945 -0.305054)
			(end -0.12065 -0.305054)
			(stroke
				(width 0.1)
				(type default)
			)
			(layer "F.Fab")
		)
		(pad "1" smd rect
			(at -0.40005 0)
			(size 0.4572 0.508)
			(layers "F.Cu" "F.Mask" "F.Paste")
			(net "P1V8_CPU0_RT_1D")
		)
		(pad "2" smd rect
			(at 0.40005 0)
			(size 0.4572 0.508)
			(layers "F.Cu" "F.Mask" "F.Paste")
			(net "P1V8_CPU0_RT0_1A_1D")
		)
	)
	(footprint ""
		(layer "F.Cu")
		(at 75.49515 -382.39446 180)
		(property "Reference" "C741"
			(at 0 0 180)
			(layer "F.SilkS")
			(hide yes)
			(effects
				(font
					(size 1.27 1.27)
				)
			)
		)
		(property "Value" ""
			(at 0 0 180)
			(layer "F.Fab")
			(effects
				(font
					(size 1.27 1.27)
				)
			)
		)
		(duplicate_pad_numbers_are_jumpers no)
		(fp_line
			(start 0.299974 0.150114)
			(end -0.299974 0.150114)
			(stroke
				(width 0.1)
				(type default)
			)
			(layer "F.Fab")
		)
		(fp_line
			(start 0.299974 -0.150114)
			(end 0.299974 0.150114)
			(stroke
				(width 0.1)
				(type default)
			)
			(layer "F.Fab")
		)
		(fp_line
			(start -0.299974 0.150114)
			(end -0.299974 -0.150114)
			(stroke
				(width 0.1)
				(type default)
			)
			(layer "F.Fab")
		)
		(fp_line
			(start -0.299974 -0.150114)
			(end 0.299974 -0.150114)
			(stroke
				(width 0.1)
				(type default)
			)
			(layer "F.Fab")
		)
		(pad "1" smd rect
			(at -0.2667 0 180)
			(size 0.3048 0.381)
			(layers "F.Cu" "F.Mask" "F.Paste")
			(net "P5E_CPU1_P1_TX_C_DP<0>")
		)
		(pad "2" smd rect
			(at 0.2667 0 180)
			(size 0.3048 0.381)
			(layers "F.Cu" "F.Mask" "F.Paste")
			(net "P5E_CPU1_P1_TX_DP<0>")
		)
	)
	(footprint ""
		(layer "F.Cu")
		(at 329.17384 -410.248608 90)
		(property "Reference" "C7003"
			(at 0 0 90)
			(layer "F.SilkS")
			(hide yes)
			(effects
				(font
					(size 1.27 1.27)
				)
			)
		)
		(property "Value" ""
			(at 0 0 90)
			(layer "F.Fab")
			(effects
				(font
					(size 1.27 1.27)
				)
			)
		)
		(duplicate_pad_numbers_are_jumpers no)
		(fp_line
			(start 1.524 -0.762)
			(end 1.524 0.762)
			(stroke
				(width 0.1524)
				(type default)
			)
			(layer "F.SilkS")
		)
		(fp_line
			(start -1.524 -0.762)
			(end 1.524 -0.762)
			(stroke
				(width 0.1524)
				(type default)
			)
			(layer "F.SilkS")
		)
		(fp_line
			(start 1.524 0.762)
			(end -1.524 0.762)
			(stroke
				(width 0.1524)
				(type default)
			)
			(layer "F.SilkS")
		)
		(fp_line
			(start -1.524 0.762)
			(end -1.524 -0.762)
			(stroke
				(width 0.1524)
				(type default)
			)
			(layer "F.SilkS")
		)
		(fp_line
			(start 1.1049 -0.724916)
			(end -1.1049 -0.724916)
			(stroke
				(width 0.1)
				(type default)
			)
			(layer "F.Fab")
		)
		(fp_line
			(start -1.1049 -0.724916)
			(end -1.1049 0.724916)
			(stroke
				(width 0.1)
				(type default)
			)
			(layer "F.Fab")
		)
		(fp_line
			(start 1.1049 0.724916)
			(end 1.1049 -0.724916)
			(stroke
				(width 0.1)
				(type default)
			)
			(layer "F.Fab")
		)
		(fp_line
			(start -1.1049 0.724916)
			(end 1.1049 0.724916)
			(stroke
				(width 0.1)
				(type default)
			)
			(layer "F.Fab")
		)
		(pad "1" smd rect
			(at -0.889 0 270)
			(size 1.016 1.27)
			(layers "F.Cu" "F.Mask" "F.Paste")
			(net "P0V9_CPU0_RT_2D")
		)
		(pad "2" smd rect
			(at 0.889 0 270)
			(size 1.016 1.27)
			(layers "F.Cu" "F.Mask" "F.Paste")
			(net "GND")
		)
	)
	(footprint ""
		(layer "F.Cu")
		(at 392.797538 -398.34058)
		(property "Reference" "R1414"
			(at 0 0 0)
			(layer "F.SilkS")
			(hide yes)
			(effects
				(font
					(size 1.27 1.27)
				)
			)
		)
		(property "Value" ""
			(at 0 0 0)
			(layer "F.Fab")
			(effects
				(font
					(size 1.27 1.27)
				)
			)
		)
		(duplicate_pad_numbers_are_jumpers no)
		(fp_line
			(start -0.32512 -0.175006)
			(end 0.32512 -0.175006)
			(stroke
				(width 0.1)
				(type default)
			)
			(layer "F.Fab")
		)
		(fp_line
			(start -0.32512 0.175006)
			(end -0.32512 -0.175006)
			(stroke
				(width 0.1)
				(type default)
			)
			(layer "F.Fab")
		)
		(fp_line
			(start 0.32512 -0.175006)
			(end 0.32512 0.175006)
			(stroke
				(width 0.1)
				(type default)
			)
			(layer "F.Fab")
		)
		(fp_line
			(start 0.32512 0.175006)
			(end -0.32512 0.175006)
			(stroke
				(width 0.1)
				(type default)
			)
			(layer "F.Fab")
		)
		(pad "1" smd rect
			(at -0.2667 0)
			(size 0.3048 0.381)
			(layers "F.Cu" "F.Mask" "F.Paste")
			(net "RXDET_BYP_RT_CPU0_P3")
		)
		(pad "2" smd rect
			(at 0.2667 0 180)
			(size 0.3048 0.381)
			(layers "F.Cu" "F.Mask" "F.Paste")
			(net "GND")
		)
	)
	(footprint ""
		(layer "F.Cu")
		(at 45.186854 -346.721176)
		(property "Reference" "PU40"
			(at -3.022854 -7.709154 0)
			(unlocked yes)
			(layer "F.SilkS")
			(effects
				(font
					(size 0.7874 0.5842)
					(thickness 0.1524)
				)
				(justify left)
			)
		)
		(property "Value" ""
			(at 0 0 0)
			(layer "F.Fab")
			(effects
				(font
					(size 1.27 1.27)
				)
			)
		)
		(duplicate_pad_numbers_are_jumpers no)
		(fp_line
			(start -2.500122 -2.999994)
			(end -2.24409 -2.999994)
			(stroke
				(width 0.1524)
				(type default)
			)
			(layer "F.SilkS")
		)
		(fp_line
			(start -2.500122 -2.529078)
			(end -2.500122 -2.999994)
			(stroke
				(width 0.1524)
				(type default)
			)
			(layer "F.SilkS")
		)
		(fp_line
			(start -2.500122 0.6604)
			(end -2.500122 0.229108)
			(stroke
				(width 0.1524)
				(type default)
			)
			(layer "F.SilkS")
		)
		(fp_line
			(start -2.500122 2.999994)
			(end -2.500122 2.339594)
			(stroke
				(width 0.1524)
				(type default)
			)
			(layer "F.SilkS")
		)
		(fp_line
			(start -2.2987 2.999994)
			(end -2.500122 2.999994)
			(stroke
				(width 0.1524)
				(type default)
			)
			(layer "F.SilkS")
		)
		(fp_line
			(start 2.31394 -2.999994)
			(end 2.500122 -2.999994)
			(stroke
				(width 0.1524)
				(type default)
			)
			(layer "F.SilkS")
		)
		(fp_line
			(start 2.500122 -2.999994)
			(end 2.500122 -2.44348)
			(stroke
				(width 0.1524)
				(type default)
			)
			(layer "F.SilkS")
		)
		(fp_line
			(start 2.500122 2.339594)
			(end 2.500122 2.999994)
			(stroke
				(width 0.1524)
				(type default)
			)
			(layer "F.SilkS")
		)
		(fp_line
			(start 2.500122 2.999994)
			(end 2.2987 2.999994)
			(stroke
				(width 0.1524)
				(type default)
			)
			(layer "F.SilkS")
		)
		(fp_poly
			(pts
				(xy -2.70129 -2.450084) (xy -3.374898 -2.674366) (xy -2.925826 -3.123438)
			)
			(stroke
				(width 0)
				(type default)
			)
			(fill yes)
			(layer "F.SilkS")
		)
		(fp_line
			(start -2.500122 -2.999994)
			(end 2.500122 -2.999994)
			(stroke
				(width 0.1)
				(type default)
			)
			(layer "F.Fab")
		)
		(fp_line
			(start -2.500122 2.999994)
			(end -2.500122 -2.999994)
			(stroke
				(width 0.1)
				(type default)
			)
			(layer "F.Fab")
		)
		(fp_line
			(start 2.500122 -2.999994)
			(end 2.500122 2.999994)
			(stroke
				(width 0.1)
				(type default)
			)
			(layer "F.Fab")
		)
		(fp_line
			(start 2.500122 2.999994)
			(end -2.500122 2.999994)
			(stroke
				(width 0.1)
				(type default)
			)
			(layer "F.Fab")
		)
		(fp_poly
			(pts
				(xy -4.218432 -2.783078) (xy -4.218432 -1.767078) (xy -3.202432 -2.275078)
			)
			(stroke
				(width 0)
				(type default)
			)
			(fill yes)
			(layer "F.Fab")
		)
		(pad "1" smd rect
			(at -2.400046 -2.275078 90)
			(size 0.2286 0.6096)
			(layers "F.Cu" "F.Mask" "F.Paste")
			(net "PVDDIO_P1_VOS2")
		)
		(pad "2" smd rect
			(at -2.400046 -1.82499 90)
			(size 0.2286 0.6096)
			(layers "F.Cu" "F.Mask" "F.Paste")
			(net "GND")
		)
		(pad "3" smd rect
			(at -2.400046 -1.374902 90)
			(size 0.2286 0.6096)
			(layers "F.Cu" "F.Mask" "F.Paste")
			(net "PVDDIO_P1_VCC2")
		)
		(pad "4" smd rect
			(at -2.400046 -0.925068 90)
			(size 0.2286 0.6096)
			(layers "F.Cu" "F.Mask" "F.Paste")
			(net "PVDDCR_CPU1_P1_PVCC")
		)
		(pad "5" smd rect
			(at -2.400046 -0.47498 90)
			(size 0.2286 0.6096)
			(layers "F.Cu" "F.Mask" "F.Paste")
			(net "GND")
		)
		(pad "6" smd rect
			(at -2.400046 -0.024892 90)
			(size 0.2286 0.6096)
			(layers "F.Cu" "F.Mask" "F.Paste")
			(net "NC_PVDDIO_P1_GL1_2")
		)
		(pad "7_9-20_24" smd circle
			(at 0 1.150112 90)
			(size 0 0)
			(layers "F.Cu" "F.Mask" "F.Paste")
			(net "GND")
		)
		(pad "10_19" smd rect
			(at 0 2.899918 90)
			(size 0.6096 4.318)
			(layers "F.Cu" "F.Mask" "F.Paste")
			(net "SW_PVDDIO_P1_SW2")
		)
		(pad "25_29" smd rect
			(at 1.549908 -1.279906 270)
			(size 2.0574 2.3114)
			(layers "F.Cu" "F.Mask" "F.Paste")
			(net "SW_P12V_AUX_PVDDIO_P1_FLT")
		)
		(pad "30" smd rect
			(at 2.05994 -2.899918)
			(size 0.2286 0.6096)
			(layers "F.Cu" "F.Mask" "F.Paste")
			(net "SW_P12V_AUX_PVDDIO_P1_FLT")
		)
		(pad "31" smd rect
			(at 1.610106 -2.899918)
			(size 0.2286 0.6096)
			(layers "F.Cu" "F.Mask" "F.Paste")
			(net "NC_PVDDIO_P1_DNC2")
		)
		(pad "32" smd rect
			(at 1.160018 -2.899918)
			(size 0.2286 0.6096)
			(layers "F.Cu" "F.Mask" "F.Paste")
			(net "SW_PVDDIO_P1_BOOTR2")
		)
		(pad "33" smd rect
			(at 0.70993 -2.899918)
			(size 0.2286 0.6096)
			(layers "F.Cu" "F.Mask" "F.Paste")
			(net "SW_PVDDIO_P1_BOOT2")
		)
		(pad "34" smd rect
			(at 0.260096 -2.899918)
			(size 0.2286 0.6096)
			(layers "F.Cu" "F.Mask" "F.Paste")
			(net "PVDDIO_P1_PWM2")
		)
		(pad "35" smd rect
			(at -0.189992 -2.899918)
			(size 0.2286 0.6096)
			(layers "F.Cu" "F.Mask" "F.Paste")
			(net "PVDDIO_P1_VCC2")
		)
		(pad "36" smd rect
			(at -0.64008 -2.899918)
			(size 0.2286 0.6096)
			(layers "F.Cu" "F.Mask" "F.Paste")
			(net "PVDDIO_P1_TEMP1")
		)
		(pad "37" smd rect
			(at -1.089914 -2.899918)
			(size 0.2286 0.6096)
			(layers "F.Cu" "F.Mask" "F.Paste")
			(net "PVDDIO_P1_LSET2")
		)
		(pad "38" smd rect
			(at -1.540002 -2.899918)
			(size 0.2286 0.6096)
			(layers "F.Cu" "F.Mask" "F.Paste")
			(net "PVDDIO_P1_IMON2")
		)
		(pad "39" smd rect
			(at -1.99009 -2.899918)
			(size 0.2286 0.6096)
			(layers "F.Cu" "F.Mask" "F.Paste")
			(net "PVDDCR_CPU1_P1_VCCS")
		)
		(pad "40" smd rect
			(at -0.87503 -1.27508)
			(size 1.7526 1.9558)
			(layers "F.Cu" "F.Mask" "F.Paste")
			(net "GND")
		)
		(pad "41" smd rect
			(at -1.525016 0.249936 270)
			(size 0.3048 0.4572)
			(layers "F.Cu" "F.Mask" "F.Paste")
			(net "NC_PVDDIO_P1_GL2_2")
		)
		(zone
			(layer "F.Cu")
			(hatch none 0.5)
			(connect_pads
				(clearance 0)
			)
			(min_thickness 0.25)
			(keepout
				(tracks not_allowed)
				(vias allowed)
				(pads allowed)
				(copperpour not_allowed)
				(footprints allowed)
			)
			(placement
				(enabled no)
				(sheetname "")
			)
			(fill
				(thermal_gap 0.5)
				(thermal_bridge_width 0.5)
				(island_removal_mode 0)
			)
			(polygon
				(pts
					(xy 42.686732 -344.1446) (xy 42.686732 -344.470482) (xy 47.686976 -344.470482) (xy 47.686976 -344.148664)
					(xy 47.396654 -344.148664) (xy 47.396654 -344.176858) (xy 42.977054 -344.176858) (xy 42.977054 -344.1446)
				)
			)
		)
		(zone
			(layer "F.Cu")
			(hatch none 0.5)
			(connect_pads
				(clearance 0)
			)
			(min_thickness 0.25)
			(keepout
				(tracks not_allowed)
				(vias allowed)
				(pads allowed)
				(copperpour not_allowed)
				(footprints allowed)
			)
			(placement
				(enabled no)
				(sheetname "")
			)
			(fill
				(thermal_gap 0.5)
				(thermal_bridge_width 0.5)
				(island_removal_mode 0)
			)
			(polygon
				(pts
					(xy 45.2374 -346.967556) (xy 45.238924 -346.967556) (xy 45.238924 -349.024956) (xy 43.384724 -349.024956)
					(xy 43.384724 -348.78391) (xy 43.142408 -348.78391) (xy 43.142408 -349.265494) (xy 46.98238 -349.265494)
					(xy 46.98238 -349.080582) (xy 45.530262 -349.080582) (xy 45.530262 -346.921582) (xy 47.686976 -346.921582)
					(xy 47.686976 -346.6719) (xy 45.456856 -346.6719) (xy 45.2374 -346.891356)
				)
			)
		)
	)
	(footprint ""
		(layer "F.Cu")
		(at 359.774998 -431.360072 180)
		(property "Reference" "J122"
			(at 4.688332 -9.347962 90)
			(unlocked yes)
			(layer "F.SilkS")
			(effects
				(font
					(size 0.7874 0.5842)
					(thickness 0.1524)
				)
				(justify left)
			)
		)
		(property "Value" ""
			(at 0 0 180)
			(layer "F.Fab")
			(effects
				(font
					(size 1.27 1.27)
				)
			)
		)
		(duplicate_pad_numbers_are_jumpers no)
		(fp_line
			(start 3.525012 9.6139)
			(end 3.525012 -10.489946)
			(stroke
				(width 0.1524)
				(type default)
			)
			(layer "F.SilkS")
		)
		(fp_line
			(start 3.525012 -10.489946)
			(end -3.525012 -10.489946)
			(stroke
				(width 0.1524)
				(type default)
			)
			(layer "F.SilkS")
		)
		(fp_line
			(start -3.525012 6.408928)
			(end -3.525012 9.6139)
			(stroke
				(width 0.1524)
				(type default)
			)
			(layer "F.SilkS")
		)
		(fp_line
			(start -3.525012 -10.489946)
			(end -3.525012 1.836928)
			(stroke
				(width 0.1524)
				(type default)
			)
			(layer "F.SilkS")
		)
		(fp_line
			(start 3.525012 21.310092)
			(end 3.525012 -10.489946)
			(stroke
				(width 0.1)
				(type default)
			)
			(layer "F.Fab")
		)
		(fp_line
			(start 3.525012 -10.489946)
			(end -3.525012 -10.489946)
			(stroke
				(width 0.1)
				(type default)
			)
			(layer "F.Fab")
		)
		(fp_line
			(start -3.525012 21.310092)
			(end 3.525012 21.310092)
			(stroke
				(width 0.1)
				(type default)
			)
			(layer "F.Fab")
		)
		(fp_line
			(start -3.525012 -10.489946)
			(end -3.525012 21.310092)
			(stroke
				(width 0.1)
				(type default)
			)
			(layer "F.Fab")
		)
		(pad "" np_thru_hole circle
			(at 0 -6.620002 180)
			(size 3.175 3.175)
			(drill 3.175)
			(layers "*.Cu" "*.Mask")
			(clearance 0.381)
			(thermal_gap 0.381)
		)
		(pad "" np_thru_hole circle
			(at 0 0 180)
			(size 0 0)
			(drill 3.175)
			(layers "*.Cu" "*.Mask")
			(clearance 0)
		)
		(pad "" np_thru_hole circle
			(at 0 5.130038 180)
			(size 3.175 3.175)
			(drill 3.175)
			(layers "*.Cu" "*.Mask")
			(clearance 0.381)
			(thermal_gap 0.381)
		)
		(zone
			(layers "F.Cu" "B.Cu" "In1.Cu" "In2.Cu" "In3.Cu" "In4.Cu" "In5.Cu" "In6.Cu"
				"In7.Cu" "In8.Cu" "In9.Cu" "In10.Cu" "In11.Cu" "In12.Cu" "In13.Cu" "In14.Cu"
				"In15.Cu" "In16.Cu"
			)
			(hatch none 0.5)
			(connect_pads
				(clearance 0)
			)
			(min_thickness 0.25)
			(keepout
				(tracks not_allowed)
				(vias allowed)
				(pads allowed)
				(copperpour not_allowed)
				(footprints allowed)
			)
			(placement
				(enabled no)
				(sheetname "")
			)
			(fill
				(thermal_gap 0.5)
				(thermal_bridge_width 0.5)
				(island_removal_mode 0)
			)
			(polygon
				(pts
					(arc
						(start 361.870498 -436.49011)
						(mid 357.679498 -436.49011)
						(end 361.870498 -436.49011)
					)
				)
			)
		)
		(zone
			(layers "F.Cu" "B.Cu" "In1.Cu" "In2.Cu" "In3.Cu" "In4.Cu" "In5.Cu" "In6.Cu"
				"In7.Cu" "In8.Cu" "In9.Cu" "In10.Cu" "In11.Cu" "In12.Cu" "In13.Cu" "In14.Cu"
				"In15.Cu" "In16.Cu"
			)
			(hatch none 0.5)
			(connect_pads
				(clearance 0)
			)
			(min_thickness 0.25)
			(keepout
				(tracks not_allowed)
				(vias allowed)
				(pads allowed)
				(copperpour not_allowed)
				(footprints allowed)
			)
			(placement
				(enabled no)
				(sheetname "")
			)
			(fill
				(thermal_gap 0.5)
				(thermal_bridge_width 0.5)
				(island_removal_mode 0)
			)
			(polygon
				(pts
					(arc
						(start 361.870498 -424.74007)
						(mid 357.679498 -424.74007)
						(end 361.870498 -424.74007)
					)
				)
			)
		)
		(zone
			(layers "F.Cu" "B.Cu" "In1.Cu" "In2.Cu" "In3.Cu" "In4.Cu" "In5.Cu" "In6.Cu"
				"In7.Cu" "In8.Cu" "In9.Cu" "In10.Cu" "In11.Cu" "In12.Cu" "In13.Cu" "In14.Cu"
				"In15.Cu" "In16.Cu"
			)
			(hatch none 0.5)
			(connect_pads
				(clearance 0)
			)
			(min_thickness 0.25)
			(keepout
				(tracks not_allowed)
				(vias allowed)
				(pads allowed)
				(copperpour not_allowed)
				(footprints allowed)
			)
			(placement
				(enabled no)
				(sheetname "")
			)
			(fill
				(thermal_gap 0.5)
				(thermal_bridge_width 0.5)
				(island_removal_mode 0)
			)
			(polygon
				(pts
					(arc
						(start 363.394498 -431.360072)
						(mid 356.155498 -431.360072)
						(end 363.394498 -431.360072)
					)
				)
			)
		)
	)
	(footprint ""
		(layer "F.Cu")
		(at 131.689094 -59.50712)
		(property "Reference" "U212"
			(at -0.851662 -3.495802 0)
			(unlocked yes)
			(layer "F.SilkS")
			(effects
				(font
					(size 0.7874 0.5842)
					(thickness 0.1524)
				)
				(justify left)
			)
		)
		(property "Value" ""
			(at 0 0 0)
			(layer "F.Fab")
			(effects
				(font
					(size 1.27 1.27)
				)
			)
		)
		(duplicate_pad_numbers_are_jumpers no)
		(fp_line
			(start -2.112264 -2.549906)
			(end -0.704088 -2.549906)
			(stroke
				(width 0.1524)
				(type default)
			)
			(layer "F.SilkS")
		)
		(fp_line
			(start -2.112264 2.549906)
			(end -2.112264 -2.549906)
			(stroke
				(width 0.1524)
				(type default)
			)
			(layer "F.SilkS")
		)
		(fp_line
			(start -0.704088 -2.549906)
			(end 0 -1.845818)
			(stroke
				(width 0.1524)
				(type default)
			)
			(layer "F.SilkS")
		)
		(fp_line
			(start 0 -1.845818)
			(end 0.704088 -2.549906)
			(stroke
				(width 0.1524)
				(type default)
			)
			(layer "F.SilkS")
		)
		(fp_line
			(start 0.704088 -2.549906)
			(end 2.112264 -2.549906)
			(stroke
				(width 0.1524)
				(type default)
			)
			(layer "F.SilkS")
		)
		(fp_line
			(start 2.112264 -2.549906)
			(end 2.112264 2.549906)
			(stroke
				(width 0.1524)
				(type default)
			)
			(layer "F.SilkS")
		)
		(fp_line
			(start 2.112264 2.549906)
			(end -2.112264 2.549906)
			(stroke
				(width 0.1524)
				(type default)
			)
			(layer "F.SilkS")
		)
		(fp_poly
			(pts
				(xy -4.215892 -4.104386) (xy -4.821174 -3.288538) (xy -3.702558 -3.09118)
			)
			(stroke
				(width 0)
				(type default)
			)
			(fill yes)
			(layer "F.SilkS")
		)
		(fp_line
			(start -2.249932 -2.549906)
			(end 2.249932 -2.549906)
			(stroke
				(width 0.1)
				(type default)
			)
			(layer "F.Fab")
		)
		(fp_line
			(start -2.249932 2.549906)
			(end -2.249932 -2.549906)
			(stroke
				(width 0.1)
				(type default)
			)
			(layer "F.Fab")
		)
		(fp_line
			(start 2.249932 -2.549906)
			(end 2.249932 2.549906)
			(stroke
				(width 0.1)
				(type default)
			)
			(layer "F.Fab")
		)
		(fp_line
			(start 2.249932 2.549906)
			(end -2.249932 2.549906)
			(stroke
				(width 0.1)
				(type default)
			)
			(layer "F.Fab")
		)
		(fp_poly
			(pts
				(xy -4.917186 -2.8829) (xy -4.917186 -1.8669) (xy -3.901186 -2.3749)
			)
			(stroke
				(width 0)
				(type default)
			)
			(fill yes)
			(layer "F.Fab")
		)
		(pad "1" smd rect
			(at -2.925064 -2.3749 270)
			(size 0.6096 1.3716)
			(layers "F.Cu" "F.Mask" "F.Paste")
			(net "TP_JTAG_SCM_SLOT3_R_TDO")
		)
		(pad "2" smd rect
			(at -2.925064 -1.625092 270)
			(size 0.4064 1.3716)
			(layers "F.Cu" "F.Mask" "F.Paste")
			(net "JTAG_SCM_PLD_R_TDO")
		)
		(pad "3" smd rect
			(at -2.925064 -0.975106 270)
			(size 0.4064 1.3716)
			(layers "F.Cu" "F.Mask" "F.Paste")
			(net "JTAG_SCM_TDO")
		)
		(pad "4" smd rect
			(at -2.925064 -0.32512 270)
			(size 0.4064 1.3716)
			(layers "F.Cu" "F.Mask" "F.Paste")
			(net "JTAG_SCM_PLD_R_TDO")
		)
		(pad "5" smd rect
			(at -2.925064 0.32512 270)
			(size 0.4064 1.3716)
			(layers "F.Cu" "F.Mask" "F.Paste")
			(net "JTAG_SCM_MUX_R_TDO")
		)
		(pad "6" smd rect
			(at -2.925064 0.975106 270)
			(size 0.4064 1.3716)
			(layers "F.Cu" "F.Mask" "F.Paste")
			(net "U212_EN_N")
		)
		(pad "7" smd rect
			(at -2.925064 1.625092 270)
			(size 0.4064 1.3716)
			(layers "F.Cu" "F.Mask" "F.Paste")
			(net "GND")
		)
		(pad "8" smd rect
			(at -2.925064 2.3749 270)
			(size 0.6096 1.3716)
			(layers "F.Cu" "F.Mask" "F.Paste")
			(net "GND")
		)
		(pad "9" smd rect
			(at 2.925064 2.3749 270)
			(size 0.6096 1.3716)
			(layers "F.Cu" "F.Mask" "F.Paste")
			(net "SCM_JTAG_MUX_S1")
		)
		(pad "10" smd rect
			(at 2.925064 1.625092 270)
			(size 0.4064 1.3716)
			(layers "F.Cu" "F.Mask" "F.Paste")
			(net "SCM_JTAG_MUX_S0_R2")
		)
		(pad "11" smd rect
			(at 2.925064 0.975106 270)
			(size 0.4064 1.3716)
			(layers "F.Cu" "F.Mask" "F.Paste")
			(net "JTAG_SCM_PLD_R_TDI")
		)
		(pad "12" smd rect
			(at 2.925064 0.32512 270)
			(size 0.4064 1.3716)
			(layers "F.Cu" "F.Mask" "F.Paste")
			(net "TP_JTAG_SCM_SLOT3_R_TDI")
		)
		(pad "13" smd rect
			(at 2.925064 -0.32512 270)
			(size 0.4064 1.3716)
			(layers "F.Cu" "F.Mask" "F.Paste")
			(net "JTAG_SCM_TDI")
		)
		(pad "14" smd rect
			(at 2.925064 -0.975106 270)
			(size 0.4064 1.3716)
			(layers "F.Cu" "F.Mask" "F.Paste")
			(net "JTAG_SCM_MUX_R_TDI")
		)
		(pad "15" smd rect
			(at 2.925064 -1.625092 270)
			(size 0.4064 1.3716)
			(layers "F.Cu" "F.Mask" "F.Paste")
			(net "JTAG_SCM_PLD_R_TDI")
		)
		(pad "16" smd rect
			(at 2.925064 -2.3749 270)
			(size 0.6096 1.3716)
			(layers "F.Cu" "F.Mask" "F.Paste")
			(net "P3V3_AUX")
		)
	)
	(footprint ""
		(layer "F.Cu")
		(at 111.422942 -21.7678 -90)
		(property "Reference" "R6261"
			(at 0 0 270)
			(layer "F.SilkS")
			(hide yes)
			(effects
				(font
					(size 1.27 1.27)
				)
			)
		)
		(property "Value" ""
			(at 0 0 270)
			(layer "F.Fab")
			(effects
				(font
					(size 1.27 1.27)
				)
			)
		)
		(duplicate_pad_numbers_are_jumpers no)
		(fp_line
			(start -0.7874 0.4064)
			(end -0.7874 -0.4064)
			(stroke
				(width 0.1524)
				(type default)
			)
			(layer "F.SilkS")
		)
		(fp_line
			(start 0.7874 0.4064)
			(end -0.7874 0.4064)
			(stroke
				(width 0.1524)
				(type default)
			)
			(layer "F.SilkS")
		)
		(fp_line
			(start -0.7874 -0.4064)
			(end 0.7874 -0.4064)
			(stroke
				(width 0.1524)
				(type default)
			)
			(layer "F.SilkS")
		)
		(fp_line
			(start 0.7874 -0.4064)
			(end 0.7874 0.4064)
			(stroke
				(width 0.1524)
				(type default)
			)
			(layer "F.SilkS")
		)
		(fp_line
			(start -0.67945 0.3048)
			(end -0.67945 -0.305054)
			(stroke
				(width 0.1)
				(type default)
			)
			(layer "F.Fab")
		)
		(fp_line
			(start -0.12065 0.3048)
			(end -0.67945 0.3048)
			(stroke
				(width 0.1)
				(type default)
			)
			(layer "F.Fab")
		)
		(fp_line
			(start 0.120396 0.3048)
			(end 0.120396 0.2794)
			(stroke
				(width 0.1)
				(type default)
			)
			(layer "F.Fab")
		)
		(fp_line
			(start 0.67945 0.3048)
			(end 0.120396 0.3048)
			(stroke
				(width 0.1)
				(type default)
			)
			(layer "F.Fab")
		)
		(fp_line
			(start -0.12065 0.2794)
			(end -0.12065 0.3048)
			(stroke
				(width 0.1)
				(type default)
			)
			(layer "F.Fab")
		)
		(fp_line
			(start 0.120396 0.2794)
			(end -0.12065 0.2794)
			(stroke
				(width 0.1)
				(type default)
			)
			(layer "F.Fab")
		)
		(fp_line
			(start -0.12065 -0.2794)
			(end 0.12065 -0.2794)
			(stroke
				(width 0.1)
				(type default)
			)
			(layer "F.Fab")
		)
		(fp_line
			(start 0.12065 -0.2794)
			(end 0.12065 -0.3048)
			(stroke
				(width 0.1)
				(type default)
			)
			(layer "F.Fab")
		)
		(fp_line
			(start 0.12065 -0.3048)
			(end 0.67945 -0.3048)
			(stroke
				(width 0.1)
				(type default)
			)
			(layer "F.Fab")
		)
		(fp_line
			(start 0.67945 -0.3048)
			(end 0.67945 0.3048)
			(stroke
				(width 0.1)
				(type default)
			)
			(layer "F.Fab")
		)
		(fp_line
			(start -0.67945 -0.305054)
			(end -0.12065 -0.305054)
			(stroke
				(width 0.1)
				(type default)
			)
			(layer "F.Fab")
		)
		(fp_line
			(start -0.12065 -0.305054)
			(end -0.12065 -0.2794)
			(stroke
				(width 0.1)
				(type default)
			)
			(layer "F.Fab")
		)
		(pad "1" smd circle
			(at -0.40005 0 270)
			(size 0 0)
			(layers "F.Cu" "F.Mask" "F.Paste")
			(net "USB_HUB2_TI_USB_SSRXP_DN1_MRP_VDD12")
		)
		(pad "2" smd circle
			(at 0.40005 0 270)
			(size 0 0)
			(layers "F.Cu" "F.Mask" "F.Paste")
			(net "P1V2_CPU0_USB2_DVDD12")
		)
	)
	(footprint ""
		(layer "F.Cu")
		(at 72.4662 -34.788348 180)
		(property "Reference" "R3568"
			(at 0 0 180)
			(layer "F.SilkS")
			(hide yes)
			(effects
				(font
					(size 1.27 1.27)
				)
			)
		)
		(property "Value" ""
			(at 0 0 180)
			(layer "F.Fab")
			(effects
				(font
					(size 1.27 1.27)
				)
			)
		)
		(duplicate_pad_numbers_are_jumpers no)
		(fp_line
			(start 0.7874 0.4064)
			(end -0.7874 0.4064)
			(stroke
				(width 0.1524)
				(type default)
			)
			(layer "F.SilkS")
		)
		(fp_line
			(start 0.7874 -0.4064)
			(end 0.7874 0.4064)
			(stroke
				(width 0.1524)
				(type default)
			)
			(layer "F.SilkS")
		)
		(fp_line
			(start -0.7874 0.4064)
			(end -0.7874 -0.4064)
			(stroke
				(width 0.1524)
				(type default)
			)
			(layer "F.SilkS")
		)
		(fp_line
			(start -0.7874 -0.4064)
			(end 0.7874 -0.4064)
			(stroke
				(width 0.1524)
				(type default)
			)
			(layer "F.SilkS")
		)
		(fp_line
			(start 0.67945 0.3048)
			(end 0.120396 0.3048)
			(stroke
				(width 0.1)
				(type default)
			)
			(layer "F.Fab")
		)
		(fp_line
			(start 0.67945 -0.3048)
			(end 0.67945 0.3048)
			(stroke
				(width 0.1)
				(type default)
			)
			(layer "F.Fab")
		)
		(fp_line
			(start 0.12065 -0.2794)
			(end 0.12065 -0.3048)
			(stroke
				(width 0.1)
				(type default)
			)
			(layer "F.Fab")
		)
		(fp_line
			(start 0.12065 -0.3048)
			(end 0.67945 -0.3048)
			(stroke
				(width 0.1)
				(type default)
			)
			(layer "F.Fab")
		)
		(fp_line
			(start 0.120396 0.3048)
			(end 0.120396 0.2794)
			(stroke
				(width 0.1)
				(type default)
			)
			(layer "F.Fab")
		)
		(fp_line
			(start 0.120396 0.2794)
			(end -0.12065 0.2794)
			(stroke
				(width 0.1)
				(type default)
			)
			(layer "F.Fab")
		)
		(fp_line
			(start -0.12065 0.3048)
			(end -0.67945 0.3048)
			(stroke
				(width 0.1)
				(type default)
			)
			(layer "F.Fab")
		)
		(fp_line
			(start -0.12065 0.2794)
			(end -0.12065 0.3048)
			(stroke
				(width 0.1)
				(type default)
			)
			(layer "F.Fab")
		)
		(fp_line
			(start -0.12065 -0.2794)
			(end 0.12065 -0.2794)
			(stroke
				(width 0.1)
				(type default)
			)
			(layer "F.Fab")
		)
		(fp_line
			(start -0.12065 -0.305054)
			(end -0.12065 -0.2794)
			(stroke
				(width 0.1)
				(type default)
			)
			(layer "F.Fab")
		)
		(fp_line
			(start -0.67945 0.3048)
			(end -0.67945 -0.305054)
			(stroke
				(width 0.1)
				(type default)
			)
			(layer "F.Fab")
		)
		(fp_line
			(start -0.67945 -0.305054)
			(end -0.12065 -0.305054)
			(stroke
				(width 0.1)
				(type default)
			)
			(layer "F.Fab")
		)
		(pad "1" smd circle
			(at -0.40005 0 180)
			(size 0 0)
			(layers "F.Cu" "F.Mask" "F.Paste")
			(net "SMB_INA230_3_3V3AUX_SCL_R")
		)
		(pad "2" smd circle
			(at 0.40005 0 180)
			(size 0 0)
			(layers "F.Cu" "F.Mask" "F.Paste")
			(net "SMB_INA230_3_3V3AUX_SCL_R1")
		)
	)
	(footprint ""
		(layer "F.Cu")
		(at 314.965588 -5.077206)
		(property "Reference" "J8069"
			(at -4.58978 1.628648 90)
			(unlocked yes)
			(layer "F.SilkS")
			(effects
				(font
					(size 0.7874 0.5842)
					(thickness 0.1524)
				)
				(justify left)
			)
		)
		(property "Value" ""
			(at 0 0 0)
			(layer "F.Fab")
			(effects
				(font
					(size 1.27 1.27)
				)
			)
		)
		(duplicate_pad_numbers_are_jumpers no)
		(fp_line
			(start -1.2192 -2.06756)
			(end 1.2192 -2.06756)
			(stroke
				(width 0.1524)
				(type default)
			)
			(layer "F.SilkS")
		)
		(fp_line
			(start -1.2192 2.06756)
			(end -1.2192 -2.06756)
			(stroke
				(width 0.1524)
				(type default)
			)
			(layer "F.SilkS")
		)
		(fp_line
			(start 1.2192 -2.06756)
			(end 1.2192 2.06756)
			(stroke
				(width 0.1524)
				(type default)
			)
			(layer "F.SilkS")
		)
		(fp_line
			(start 1.2192 2.06756)
			(end -1.2192 2.06756)
			(stroke
				(width 0.1524)
				(type default)
			)
			(layer "F.SilkS")
		)
		(pad "" np_thru_hole circle
			(at -2.8829 -1.27 270)
			(size 1.0414 1.0414)
			(drill 1.0414)
			(layers "*.Cu" "*.Mask")
			(clearance 0.381)
			(thermal_gap 0.381)
		)
		(pad "" np_thru_hole circle
			(at -2.8829 1.27 270)
			(size 1.0414 1.0414)
			(drill 1.0414)
			(layers "*.Cu" "*.Mask")
			(clearance 0.381)
			(thermal_gap 0.381)
		)
		(pad "" np_thru_hole circle
			(at 3.4671 -1.27 270)
			(size 1.0414 1.0414)
			(drill 1.0414)
			(layers "*.Cu" "*.Mask")
			(clearance 0.381)
			(thermal_gap 0.381)
		)
		(pad "" np_thru_hole circle
			(at 3.4671 1.27 270)
			(size 1.0414 1.0414)
			(drill 1.0414)
			(layers "*.Cu" "*.Mask")
			(clearance 0.381)
			(thermal_gap 0.381)
		)
		(pad "1" smd rect
			(at 0.8255 -0.249936 270)
			(size 0.3048 0.508)
			(layers "F.Cu" "F.Mask" "F.Paste")
			(net "DELTA_L_85_5INCH_TOP_DN")
		)
		(pad "2" smd rect
			(at 0.8255 0.249936 270)
			(size 0.3048 0.508)
			(layers "F.Cu" "F.Mask" "F.Paste")
			(net "DELTA_L_85_5INCH_TOP_DP")
		)
		(pad "3" smd circle
			(at 0 0)
			(size 0 0)
			(layers "F.Cu" "F.Mask" "F.Paste")
			(net "DELTA_L_GND_1")
		)
		(zone
			(layer "F.Cu")
			(hatch none 0.5)
			(connect_pads
				(clearance 0)
			)
			(min_thickness 0.25)
			(keepout
				(tracks not_allowed)
				(vias allowed)
				(pads allowed)
				(copperpour not_allowed)
				(footprints allowed)
			)
			(placement
				(enabled no)
				(sheetname "")
			)
			(fill
				(thermal_gap 0.5)
				(thermal_bridge_width 0.5)
				(island_removal_mode 0)
			)
			(polygon
				(pts
					(xy 316.083188 -5.625846) (xy 316.083188 -5.530342) (xy 315.486288 -5.530342) (xy 315.486288 -5.123942)
					(xy 316.083188 -5.123942) (xy 316.083188 -5.03047) (xy 315.486288 -5.03047) (xy 315.486288 -4.62407)
					(xy 316.083188 -4.62407) (xy 316.083188 -4.528566) (xy 315.384688 -4.528566) (xy 315.384688 -5.625846)
				)
			)
		)
		(zone
			(layers "F.Cu" "B.Cu" "In1.Cu" "In2.Cu" "In3.Cu" "In4.Cu" "In5.Cu" "In6.Cu"
				"In7.Cu" "In8.Cu" "In9.Cu" "In10.Cu" "In11.Cu" "In12.Cu" "In13.Cu" "In14.Cu"
				"In15.Cu" "In16.Cu"
			)
			(hatch none 0.5)
			(connect_pads
				(clearance 0)
			)
			(min_thickness 0.25)
			(keepout
				(tracks not_allowed)
				(vias allowed)
				(pads allowed)
				(copperpour not_allowed)
				(footprints allowed)
			)
			(placement
				(enabled no)
				(sheetname "")
			)
			(fill
				(thermal_gap 0.5)
				(thermal_bridge_width 0.5)
				(island_removal_mode 0)
			)
			(polygon
				(pts
					(arc
						(start 313.009788 -6.347206)
						(mid 311.155588 -6.347206)
						(end 313.009788 -6.347206)
					)
				)
			)
		)
		(zone
			(layers "F.Cu" "B.Cu" "In1.Cu" "In2.Cu" "In3.Cu" "In4.Cu" "In5.Cu" "In6.Cu"
				"In7.Cu" "In8.Cu" "In9.Cu" "In10.Cu" "In11.Cu" "In12.Cu" "In13.Cu" "In14.Cu"
				"In15.Cu" "In16.Cu"
			)
			(hatch none 0.5)
			(connect_pads
				(clearance 0)
			)
			(min_thickness 0.25)
			(keepout
				(tracks not_allowed)
				(vias allowed)
				(pads allowed)
				(copperpour not_allowed)
				(footprints allowed)
			)
			(placement
				(enabled no)
				(sheetname "")
			)
			(fill
				(thermal_gap 0.5)
				(thermal_bridge_width 0.5)
				(island_removal_mode 0)
			)
			(polygon
				(pts
					(arc
						(start 313.009788 -3.807206)
						(mid 311.155588 -3.807206)
						(end 313.009788 -3.807206)
					)
				)
			)
		)
		(zone
			(layers "F.Cu" "B.Cu" "In1.Cu" "In2.Cu" "In3.Cu" "In4.Cu" "In5.Cu" "In6.Cu"
				"In7.Cu" "In8.Cu" "In9.Cu" "In10.Cu" "In11.Cu" "In12.Cu" "In13.Cu" "In14.Cu"
				"In15.Cu" "In16.Cu"
			)
			(hatch none 0.5)
			(connect_pads
				(clearance 0)
			)
			(min_thickness 0.25)
			(keepout
				(tracks not_allowed)
				(vias allowed)
				(pads allowed)
				(copperpour not_allowed)
				(footprints allowed)
			)
			(placement
				(enabled no)
				(sheetname "")
			)
			(fill
				(thermal_gap 0.5)
				(thermal_bridge_width 0.5)
				(island_removal_mode 0)
			)
			(polygon
				(pts
					(arc
						(start 319.359788 -6.347206)
						(mid 317.505588 -6.347206)
						(end 319.359788 -6.347206)
					)
				)
			)
		)
		(zone
			(layers "F.Cu" "B.Cu" "In1.Cu" "In2.Cu" "In3.Cu" "In4.Cu" "In5.Cu" "In6.Cu"
				"In7.Cu" "In8.Cu" "In9.Cu" "In10.Cu" "In11.Cu" "In12.Cu" "In13.Cu" "In14.Cu"
				"In15.Cu" "In16.Cu"
			)
			(hatch none 0.5)
			(connect_pads
				(clearance 0)
			)
			(min_thickness 0.25)
			(keepout
				(tracks not_allowed)
				(vias allowed)
				(pads allowed)
				(copperpour not_allowed)
				(footprints allowed)
			)
			(placement
				(enabled no)
				(sheetname "")
			)
			(fill
				(thermal_gap 0.5)
				(thermal_bridge_width 0.5)
				(island_removal_mode 0)
			)
			(polygon
				(pts
					(arc
						(start 319.359788 -3.807206)
						(mid 317.505588 -3.807206)
						(end 319.359788 -3.807206)
					)
				)
			)
		)
	)
	(footprint ""
		(layer "F.Cu")
		(at 221.67088 -43.525948 180)
		(property "Reference" "R3530"
			(at 0 0 180)
			(layer "F.SilkS")
			(hide yes)
			(effects
				(font
					(size 1.27 1.27)
				)
			)
		)
		(property "Value" ""
			(at 0 0 180)
			(layer "F.Fab")
			(effects
				(font
					(size 1.27 1.27)
				)
			)
		)
		(duplicate_pad_numbers_are_jumpers no)
		(fp_line
			(start 0.7874 0.4064)
			(end -0.7874 0.4064)
			(stroke
				(width 0.1524)
				(type default)
			)
			(layer "F.SilkS")
		)
		(fp_line
			(start 0.7874 -0.4064)
			(end 0.7874 0.4064)
			(stroke
				(width 0.1524)
				(type default)
			)
			(layer "F.SilkS")
		)
		(fp_line
			(start -0.7874 0.4064)
			(end -0.7874 -0.4064)
			(stroke
				(width 0.1524)
				(type default)
			)
			(layer "F.SilkS")
		)
		(fp_line
			(start -0.7874 -0.4064)
			(end 0.7874 -0.4064)
			(stroke
				(width 0.1524)
				(type default)
			)
			(layer "F.SilkS")
		)
		(fp_line
			(start 0.67945 0.3048)
			(end 0.120396 0.3048)
			(stroke
				(width 0.1)
				(type default)
			)
			(layer "F.Fab")
		)
		(fp_line
			(start 0.67945 -0.3048)
			(end 0.67945 0.3048)
			(stroke
				(width 0.1)
				(type default)
			)
			(layer "F.Fab")
		)
		(fp_line
			(start 0.12065 -0.2794)
			(end 0.12065 -0.3048)
			(stroke
				(width 0.1)
				(type default)
			)
			(layer "F.Fab")
		)
		(fp_line
			(start 0.12065 -0.3048)
			(end 0.67945 -0.3048)
			(stroke
				(width 0.1)
				(type default)
			)
			(layer "F.Fab")
		)
		(fp_line
			(start 0.120396 0.3048)
			(end 0.120396 0.2794)
			(stroke
				(width 0.1)
				(type default)
			)
			(layer "F.Fab")
		)
		(fp_line
			(start 0.120396 0.2794)
			(end -0.12065 0.2794)
			(stroke
				(width 0.1)
				(type default)
			)
			(layer "F.Fab")
		)
		(fp_line
			(start -0.12065 0.3048)
			(end -0.67945 0.3048)
			(stroke
				(width 0.1)
				(type default)
			)
			(layer "F.Fab")
		)
		(fp_line
			(start -0.12065 0.2794)
			(end -0.12065 0.3048)
			(stroke
				(width 0.1)
				(type default)
			)
			(layer "F.Fab")
		)
		(fp_line
			(start -0.12065 -0.2794)
			(end 0.12065 -0.2794)
			(stroke
				(width 0.1)
				(type default)
			)
			(layer "F.Fab")
		)
		(fp_line
			(start -0.12065 -0.305054)
			(end -0.12065 -0.2794)
			(stroke
				(width 0.1)
				(type default)
			)
			(layer "F.Fab")
		)
		(fp_line
			(start -0.67945 0.3048)
			(end -0.67945 -0.305054)
			(stroke
				(width 0.1)
				(type default)
			)
			(layer "F.Fab")
		)
		(fp_line
			(start -0.67945 -0.305054)
			(end -0.12065 -0.305054)
			(stroke
				(width 0.1)
				(type default)
			)
			(layer "F.Fab")
		)
		(pad "1" smd circle
			(at -0.40005 0 180)
			(size 0 0)
			(layers "F.Cu" "F.Mask" "F.Paste")
			(net "P3V3_E1S_0")
		)
		(pad "2" smd circle
			(at 0.40005 0 180)
			(size 0 0)
			(layers "F.Cu" "F.Mask" "F.Paste")
			(net "SMB_E1S_3V3AUX_ISO_SCL_R")
		)
	)
	(footprint ""
		(layer "F.Cu")
		(at 312.499248 -23.52929 -90)
		(property "Reference" "R1342"
			(at 0 0 270)
			(layer "F.SilkS")
			(hide yes)
			(effects
				(font
					(size 1.27 1.27)
				)
			)
		)
		(property "Value" ""
			(at 0 0 270)
			(layer "F.Fab")
			(effects
				(font
					(size 1.27 1.27)
				)
			)
		)
		(duplicate_pad_numbers_are_jumpers no)
		(fp_line
			(start -0.7874 0.4064)
			(end -0.7874 -0.4064)
			(stroke
				(width 0.1524)
				(type default)
			)
			(layer "F.SilkS")
		)
		(fp_line
			(start 0.7874 0.4064)
			(end -0.7874 0.4064)
			(stroke
				(width 0.1524)
				(type default)
			)
			(layer "F.SilkS")
		)
		(fp_line
			(start -0.7874 -0.4064)
			(end 0.7874 -0.4064)
			(stroke
				(width 0.1524)
				(type default)
			)
			(layer "F.SilkS")
		)
		(fp_line
			(start 0.7874 -0.4064)
			(end 0.7874 0.4064)
			(stroke
				(width 0.1524)
				(type default)
			)
			(layer "F.SilkS")
		)
		(fp_line
			(start -0.67945 0.3048)
			(end -0.67945 -0.305054)
			(stroke
				(width 0.1)
				(type default)
			)
			(layer "F.Fab")
		)
		(fp_line
			(start -0.12065 0.3048)
			(end -0.67945 0.3048)
			(stroke
				(width 0.1)
				(type default)
			)
			(layer "F.Fab")
		)
		(fp_line
			(start 0.120396 0.3048)
			(end 0.120396 0.2794)
			(stroke
				(width 0.1)
				(type default)
			)
			(layer "F.Fab")
		)
		(fp_line
			(start 0.67945 0.3048)
			(end 0.120396 0.3048)
			(stroke
				(width 0.1)
				(type default)
			)
			(layer "F.Fab")
		)
		(fp_line
			(start -0.12065 0.2794)
			(end -0.12065 0.3048)
			(stroke
				(width 0.1)
				(type default)
			)
			(layer "F.Fab")
		)
		(fp_line
			(start 0.120396 0.2794)
			(end -0.12065 0.2794)
			(stroke
				(width 0.1)
				(type default)
			)
			(layer "F.Fab")
		)
		(fp_line
			(start -0.12065 -0.2794)
			(end 0.12065 -0.2794)
			(stroke
				(width 0.1)
				(type default)
			)
			(layer "F.Fab")
		)
		(fp_line
			(start 0.12065 -0.2794)
			(end 0.12065 -0.3048)
			(stroke
				(width 0.1)
				(type default)
			)
			(layer "F.Fab")
		)
		(fp_line
			(start 0.12065 -0.3048)
			(end 0.67945 -0.3048)
			(stroke
				(width 0.1)
				(type default)
			)
			(layer "F.Fab")
		)
		(fp_line
			(start 0.67945 -0.3048)
			(end 0.67945 0.3048)
			(stroke
				(width 0.1)
				(type default)
			)
			(layer "F.Fab")
		)
		(fp_line
			(start -0.67945 -0.305054)
			(end -0.12065 -0.305054)
			(stroke
				(width 0.1)
				(type default)
			)
			(layer "F.Fab")
		)
		(fp_line
			(start -0.12065 -0.305054)
			(end -0.12065 -0.2794)
			(stroke
				(width 0.1)
				(type default)
			)
			(layer "F.Fab")
		)
		(pad "1" smd circle
			(at -0.40005 0 270)
			(size 0 0)
			(layers "F.Cu" "F.Mask" "F.Paste")
			(net "FW_RECOVERY_R")
		)
		(pad "2" smd circle
			(at 0.40005 0 270)
			(size 0 0)
			(layers "F.Cu" "F.Mask" "F.Paste")
			(net "GND")
		)
	)
	(footprint ""
		(layer "F.Cu")
		(at 109.219238 -41.17975 90)
		(property "Reference" "R6293"
			(at 0 0 90)
			(layer "F.SilkS")
			(hide yes)
			(effects
				(font
					(size 1.27 1.27)
				)
			)
		)
		(property "Value" ""
			(at 0 0 90)
			(layer "F.Fab")
			(effects
				(font
					(size 1.27 1.27)
				)
			)
		)
		(duplicate_pad_numbers_are_jumpers no)
		(fp_line
			(start 0.7874 -0.4064)
			(end 0.7874 0.4064)
			(stroke
				(width 0.1524)
				(type default)
			)
			(layer "F.SilkS")
		)
		(fp_line
			(start -0.7874 -0.4064)
			(end 0.7874 -0.4064)
			(stroke
				(width 0.1524)
				(type default)
			)
			(layer "F.SilkS")
		)
		(fp_line
			(start 0.7874 0.4064)
			(end -0.7874 0.4064)
			(stroke
				(width 0.1524)
				(type default)
			)
			(layer "F.SilkS")
		)
		(fp_line
			(start -0.7874 0.4064)
			(end -0.7874 -0.4064)
			(stroke
				(width 0.1524)
				(type default)
			)
			(layer "F.SilkS")
		)
		(fp_line
			(start -0.12065 -0.305054)
			(end -0.12065 -0.2794)
			(stroke
				(width 0.1)
				(type default)
			)
			(layer "F.Fab")
		)
		(fp_line
			(start -0.67945 -0.305054)
			(end -0.12065 -0.305054)
			(stroke
				(width 0.1)
				(type default)
			)
			(layer "F.Fab")
		)
		(fp_line
			(start 0.67945 -0.3048)
			(end 0.67945 0.3048)
			(stroke
				(width 0.1)
				(type default)
			)
			(layer "F.Fab")
		)
		(fp_line
			(start 0.12065 -0.3048)
			(end 0.67945 -0.3048)
			(stroke
				(width 0.1)
				(type default)
			)
			(layer "F.Fab")
		)
		(fp_line
			(start 0.12065 -0.2794)
			(end 0.12065 -0.3048)
			(stroke
				(width 0.1)
				(type default)
			)
			(layer "F.Fab")
		)
		(fp_line
			(start -0.12065 -0.2794)
			(end 0.12065 -0.2794)
			(stroke
				(width 0.1)
				(type default)
			)
			(layer "F.Fab")
		)
		(fp_line
			(start 0.120396 0.2794)
			(end -0.12065 0.2794)
			(stroke
				(width 0.1)
				(type default)
			)
			(layer "F.Fab")
		)
		(fp_line
			(start -0.12065 0.2794)
			(end -0.12065 0.3048)
			(stroke
				(width 0.1)
				(type default)
			)
			(layer "F.Fab")
		)
		(fp_line
			(start 0.67945 0.3048)
			(end 0.120396 0.3048)
			(stroke
				(width 0.1)
				(type default)
			)
			(layer "F.Fab")
		)
		(fp_line
			(start 0.120396 0.3048)
			(end 0.120396 0.2794)
			(stroke
				(width 0.1)
				(type default)
			)
			(layer "F.Fab")
		)
		(fp_line
			(start -0.12065 0.3048)
			(end -0.67945 0.3048)
			(stroke
				(width 0.1)
				(type default)
			)
			(layer "F.Fab")
		)
		(fp_line
			(start -0.67945 0.3048)
			(end -0.67945 -0.305054)
			(stroke
				(width 0.1)
				(type default)
			)
			(layer "F.Fab")
		)
		(pad "1" smd circle
			(at -0.40005 0 90)
			(size 0 0)
			(layers "F.Cu" "F.Mask" "F.Paste")
			(net "USB_HUB2_TI_GANGED")
		)
		(pad "2" smd circle
			(at 0.40005 0 90)
			(size 0 0)
			(layers "F.Cu" "F.Mask" "F.Paste")
			(net "GND")
		)
	)
	(footprint ""
		(layer "F.Cu")
		(at 402.415502 -416.899344 -90)
		(property "Reference" "C6585"
			(at 0 0 270)
			(layer "F.SilkS")
			(hide yes)
			(effects
				(font
					(size 1.27 1.27)
				)
			)
		)
		(property "Value" ""
			(at 0 0 270)
			(layer "F.Fab")
			(effects
				(font
					(size 1.27 1.27)
				)
			)
		)
		(duplicate_pad_numbers_are_jumpers no)
		(fp_line
			(start -0.299974 0.150114)
			(end -0.299974 -0.150114)
			(stroke
				(width 0.1)
				(type default)
			)
			(layer "F.Fab")
		)
		(fp_line
			(start 0.299974 0.150114)
			(end -0.299974 0.150114)
			(stroke
				(width 0.1)
				(type default)
			)
			(layer "F.Fab")
		)
		(fp_line
			(start -0.299974 -0.150114)
			(end 0.299974 -0.150114)
			(stroke
				(width 0.1)
				(type default)
			)
			(layer "F.Fab")
		)
		(fp_line
			(start 0.299974 -0.150114)
			(end 0.299974 0.150114)
			(stroke
				(width 0.1)
				(type default)
			)
			(layer "F.Fab")
		)
		(pad "1" smd rect
			(at -0.2667 0 270)
			(size 0.3048 0.381)
			(layers "F.Cu" "F.Mask" "F.Paste")
			(net "P5E_CPU0_P2_TX_BUF_C_DP<10>")
		)
		(pad "2" smd rect
			(at 0.2667 0 270)
			(size 0.3048 0.381)
			(layers "F.Cu" "F.Mask" "F.Paste")
			(net "P5E_CPU0_P2_TX_BUF_DP<10>")
		)
	)
	(footprint ""
		(layer "F.Cu")
		(at 44.2087 -116.10086 90)
		(property "Reference" "Q7003"
			(at -2.4384 -3.292348 90)
			(unlocked yes)
			(layer "F.SilkS")
			(effects
				(font
					(size 0.7874 0.5842)
					(thickness 0.1524)
				)
				(justify left)
			)
		)
		(property "Value" ""
			(at 0 0 90)
			(layer "F.Fab")
			(effects
				(font
					(size 1.27 1.27)
				)
			)
		)
		(duplicate_pad_numbers_are_jumpers no)
		(fp_line
			(start 2.350008 -2.649982)
			(end 2.350008 -2.4892)
			(stroke
				(width 0.1524)
				(type default)
			)
			(layer "F.SilkS")
		)
		(fp_line
			(start -2.350008 -2.649982)
			(end 2.350008 -2.649982)
			(stroke
				(width 0.1524)
				(type default)
			)
			(layer "F.SilkS")
		)
		(fp_line
			(start -2.350008 -2.4384)
			(end -2.350008 -2.649982)
			(stroke
				(width 0.1524)
				(type default)
			)
			(layer "F.SilkS")
		)
		(fp_line
			(start 2.350008 2.4892)
			(end 2.350008 2.649982)
			(stroke
				(width 0.1524)
				(type default)
			)
			(layer "F.SilkS")
		)
		(fp_line
			(start 2.350008 2.649982)
			(end -2.350008 2.649982)
			(stroke
				(width 0.1524)
				(type default)
			)
			(layer "F.SilkS")
		)
		(fp_line
			(start -2.350008 2.649982)
			(end -2.350008 2.413)
			(stroke
				(width 0.1524)
				(type default)
			)
			(layer "F.SilkS")
		)
		(fp_poly
			(pts
				(xy -3.717544 -1.905) (xy -4.758944 -2.3241) (xy -4.758944 -1.524)
			)
			(stroke
				(width 0)
				(type default)
			)
			(fill yes)
			(layer "F.SilkS")
		)
		(fp_line
			(start 2.350008 -2.649982)
			(end 2.350008 2.649982)
			(stroke
				(width 0.1)
				(type default)
			)
			(layer "F.Fab")
		)
		(fp_line
			(start -2.350008 -2.649982)
			(end 2.350008 -2.649982)
			(stroke
				(width 0.1)
				(type default)
			)
			(layer "F.Fab")
		)
		(fp_line
			(start 2.350008 2.649982)
			(end -2.350008 2.649982)
			(stroke
				(width 0.1)
				(type default)
			)
			(layer "F.Fab")
		)
		(fp_line
			(start -2.350008 2.649982)
			(end -2.350008 -2.649982)
			(stroke
				(width 0.1)
				(type default)
			)
			(layer "F.Fab")
		)
		(fp_poly
			(pts
				(xy -3.717544 -1.905) (xy -4.758944 -2.3241) (xy -4.758944 -1.524)
			)
			(stroke
				(width 0)
				(type default)
			)
			(fill yes)
			(layer "F.Fab")
		)
		(pad "1" smd rect
			(at -2.999994 -1.905)
			(size 0.7112 1.1684)
			(layers "F.Cu" "F.Mask" "F.Paste")
			(net "GND")
		)
		(pad "2" smd rect
			(at -2.999994 -0.635)
			(size 0.7112 1.1684)
			(layers "F.Cu" "F.Mask" "F.Paste")
			(net "GND")
		)
		(pad "3" smd rect
			(at -2.999994 0.635)
			(size 0.7112 1.1684)
			(layers "F.Cu" "F.Mask" "F.Paste")
			(net "GND")
		)
		(pad "4" smd rect
			(at -2.999994 1.905)
			(size 0.7112 1.1684)
			(layers "F.Cu" "F.Mask" "F.Paste")
			(net "P3V3_AUX_DSC_G2")
		)
		(pad "5" smd circle
			(at 0.925068 0)
			(size 0 0)
			(layers "F.Cu" "F.Mask" "F.Paste")
			(net "P3V3_AUX_DSC")
		)
		(zone
			(layer "F.Cu")
			(hatch none 0.5)
			(connect_pads
				(clearance 0)
			)
			(min_thickness 0.25)
			(keepout
				(tracks not_allowed)
				(vias allowed)
				(pads allowed)
				(copperpour not_allowed)
				(footprints allowed)
			)
			(placement
				(enabled no)
				(sheetname "")
			)
			(fill
				(thermal_gap 0.5)
				(thermal_bridge_width 0.5)
				(island_removal_mode 0)
			)
			(polygon
				(pts
					(xy 41.5671 -118.43766) (xy 41.7957 -118.43766) (xy 41.7957 -117.75186) (xy 42.0497 -117.75186)
					(xy 42.0497 -114.65306) (xy 46.3677 -114.65306) (xy 46.3677 -117.75186) (xy 46.6217 -117.75186)
					(xy 46.6217 -118.43766) (xy 46.8503 -118.43766) (xy 46.8503 -113.75136) (xy 41.5671 -113.75136)
				)
			)
		)
	)
	(footprint ""
		(layer "F.Cu")
		(at 257.85953 -56.495442)
		(property "Reference" "R3956"
			(at 0 0 0)
			(layer "F.SilkS")
			(hide yes)
			(effects
				(font
					(size 1.27 1.27)
				)
			)
		)
		(property "Value" ""
			(at 0 0 0)
			(layer "F.Fab")
			(effects
				(font
					(size 1.27 1.27)
				)
			)
		)
		(duplicate_pad_numbers_are_jumpers no)
		(fp_line
			(start -0.7874 -0.4064)
			(end 0.7874 -0.4064)
			(stroke
				(width 0.1524)
				(type default)
			)
			(layer "F.SilkS")
		)
		(fp_line
			(start -0.7874 0.4064)
			(end -0.7874 -0.4064)
			(stroke
				(width 0.1524)
				(type default)
			)
			(layer "F.SilkS")
		)
		(fp_line
			(start 0.7874 -0.4064)
			(end 0.7874 0.4064)
			(stroke
				(width 0.1524)
				(type default)
			)
			(layer "F.SilkS")
		)
		(fp_line
			(start 0.7874 0.4064)
			(end -0.7874 0.4064)
			(stroke
				(width 0.1524)
				(type default)
			)
			(layer "F.SilkS")
		)
		(fp_line
			(start -0.67945 -0.305054)
			(end -0.12065 -0.305054)
			(stroke
				(width 0.1)
				(type default)
			)
			(layer "F.Fab")
		)
		(fp_line
			(start -0.67945 0.3048)
			(end -0.67945 -0.305054)
			(stroke
				(width 0.1)
				(type default)
			)
			(layer "F.Fab")
		)
		(fp_line
			(start -0.12065 -0.305054)
			(end -0.12065 -0.2794)
			(stroke
				(width 0.1)
				(type default)
			)
			(layer "F.Fab")
		)
		(fp_line
			(start -0.12065 -0.2794)
			(end 0.12065 -0.2794)
			(stroke
				(width 0.1)
				(type default)
			)
			(layer "F.Fab")
		)
		(fp_line
			(start -0.12065 0.2794)
			(end -0.12065 0.3048)
			(stroke
				(width 0.1)
				(type default)
			)
			(layer "F.Fab")
		)
		(fp_line
			(start -0.12065 0.3048)
			(end -0.67945 0.3048)
			(stroke
				(width 0.1)
				(type default)
			)
			(layer "F.Fab")
		)
		(fp_line
			(start 0.120396 0.2794)
			(end -0.12065 0.2794)
			(stroke
				(width 0.1)
				(type default)
			)
			(layer "F.Fab")
		)
		(fp_line
			(start 0.120396 0.3048)
			(end 0.120396 0.2794)
			(stroke
				(width 0.1)
				(type default)
			)
			(layer "F.Fab")
		)
		(fp_line
			(start 0.12065 -0.3048)
			(end 0.67945 -0.3048)
			(stroke
				(width 0.1)
				(type default)
			)
			(layer "F.Fab")
		)
		(fp_line
			(start 0.12065 -0.2794)
			(end 0.12065 -0.3048)
			(stroke
				(width 0.1)
				(type default)
			)
			(layer "F.Fab")
		)
		(fp_line
			(start 0.67945 -0.3048)
			(end 0.67945 0.3048)
			(stroke
				(width 0.1)
				(type default)
			)
			(layer "F.Fab")
		)
		(fp_line
			(start 0.67945 0.3048)
			(end 0.120396 0.3048)
			(stroke
				(width 0.1)
				(type default)
			)
			(layer "F.Fab")
		)
		(pad "1" smd circle
			(at -0.40005 0)
			(size 0 0)
			(layers "F.Cu" "F.Mask" "F.Paste")
			(net "P12V_E1S_IMON_0")
		)
		(pad "2" smd circle
			(at 0.40005 0)
			(size 0 0)
			(layers "F.Cu" "F.Mask" "F.Paste")
			(net "P12V_E1S_0_ISENSE_MPS_TIC")
		)
	)
	(footprint ""
		(layer "F.Cu")
		(at 130.184906 -408.517344 -90)
		(property "Reference" "C6704"
			(at 0 0 270)
			(layer "F.SilkS")
			(hide yes)
			(effects
				(font
					(size 1.27 1.27)
				)
			)
		)
		(property "Value" ""
			(at 0 0 270)
			(layer "F.Fab")
			(effects
				(font
					(size 1.27 1.27)
				)
			)
		)
		(duplicate_pad_numbers_are_jumpers no)
		(fp_line
			(start -0.299974 0.150114)
			(end -0.299974 -0.150114)
			(stroke
				(width 0.1)
				(type default)
			)
			(layer "F.Fab")
		)
		(fp_line
			(start 0.299974 0.150114)
			(end -0.299974 0.150114)
			(stroke
				(width 0.1)
				(type default)
			)
			(layer "F.Fab")
		)
		(fp_line
			(start -0.299974 -0.150114)
			(end 0.299974 -0.150114)
			(stroke
				(width 0.1)
				(type default)
			)
			(layer "F.Fab")
		)
		(fp_line
			(start 0.299974 -0.150114)
			(end 0.299974 0.150114)
			(stroke
				(width 0.1)
				(type default)
			)
			(layer "F.Fab")
		)
		(pad "1" smd rect
			(at -0.2667 0 270)
			(size 0.3048 0.381)
			(layers "F.Cu" "F.Mask" "F.Paste")
			(net "P5E_CPU1_P2_TX_BUF_C_DN<5>")
		)
		(pad "2" smd rect
			(at 0.2667 0 270)
			(size 0.3048 0.381)
			(layers "F.Cu" "F.Mask" "F.Paste")
			(net "P5E_CPU1_P2_TX_BUF_DN<5>")
		)
	)
	(footprint ""
		(layer "F.Cu")
		(at 273.35734 -116.321586)
		(property "Reference" "R6228"
			(at 0 0 0)
			(layer "F.SilkS")
			(hide yes)
			(effects
				(font
					(size 1.27 1.27)
				)
			)
		)
		(property "Value" ""
			(at 0 0 0)
			(layer "F.Fab")
			(effects
				(font
					(size 1.27 1.27)
				)
			)
		)
		(duplicate_pad_numbers_are_jumpers no)
		(fp_line
			(start -0.7874 -0.4064)
			(end 0.7874 -0.4064)
			(stroke
				(width 0.1524)
				(type default)
			)
			(layer "F.SilkS")
		)
		(fp_line
			(start -0.7874 0.4064)
			(end -0.7874 -0.4064)
			(stroke
				(width 0.1524)
				(type default)
			)
			(layer "F.SilkS")
		)
		(fp_line
			(start 0.7874 -0.4064)
			(end 0.7874 0.4064)
			(stroke
				(width 0.1524)
				(type default)
			)
			(layer "F.SilkS")
		)
		(fp_line
			(start 0.7874 0.4064)
			(end -0.7874 0.4064)
			(stroke
				(width 0.1524)
				(type default)
			)
			(layer "F.SilkS")
		)
		(fp_line
			(start -0.67945 -0.305054)
			(end -0.12065 -0.305054)
			(stroke
				(width 0.1)
				(type default)
			)
			(layer "F.Fab")
		)
		(fp_line
			(start -0.67945 0.3048)
			(end -0.67945 -0.305054)
			(stroke
				(width 0.1)
				(type default)
			)
			(layer "F.Fab")
		)
		(fp_line
			(start -0.12065 -0.305054)
			(end -0.12065 -0.2794)
			(stroke
				(width 0.1)
				(type default)
			)
			(layer "F.Fab")
		)
		(fp_line
			(start -0.12065 -0.2794)
			(end 0.12065 -0.2794)
			(stroke
				(width 0.1)
				(type default)
			)
			(layer "F.Fab")
		)
		(fp_line
			(start -0.12065 0.2794)
			(end -0.12065 0.3048)
			(stroke
				(width 0.1)
				(type default)
			)
			(layer "F.Fab")
		)
		(fp_line
			(start -0.12065 0.3048)
			(end -0.67945 0.3048)
			(stroke
				(width 0.1)
				(type default)
			)
			(layer "F.Fab")
		)
		(fp_line
			(start 0.120396 0.2794)
			(end -0.12065 0.2794)
			(stroke
				(width 0.1)
				(type default)
			)
			(layer "F.Fab")
		)
		(fp_line
			(start 0.120396 0.3048)
			(end 0.120396 0.2794)
			(stroke
				(width 0.1)
				(type default)
			)
			(layer "F.Fab")
		)
		(fp_line
			(start 0.12065 -0.3048)
			(end 0.67945 -0.3048)
			(stroke
				(width 0.1)
				(type default)
			)
			(layer "F.Fab")
		)
		(fp_line
			(start 0.12065 -0.2794)
			(end 0.12065 -0.3048)
			(stroke
				(width 0.1)
				(type default)
			)
			(layer "F.Fab")
		)
		(fp_line
			(start 0.67945 -0.3048)
			(end 0.67945 0.3048)
			(stroke
				(width 0.1)
				(type default)
			)
			(layer "F.Fab")
		)
		(fp_line
			(start 0.67945 0.3048)
			(end 0.120396 0.3048)
			(stroke
				(width 0.1)
				(type default)
			)
			(layer "F.Fab")
		)
		(pad "1" smd circle
			(at -0.40005 0)
			(size 0 0)
			(layers "F.Cu" "F.Mask" "F.Paste")
			(net "SMB_P12V_HSC_SDA_R")
		)
		(pad "2" smd circle
			(at 0.40005 0)
			(size 0 0)
			(layers "F.Cu" "F.Mask" "F.Paste")
			(net "SMB_P12V_HSC_SDA")
		)
	)
	(footprint ""
		(layer "F.Cu")
		(at 62.623954 -375.49963 -90)
		(property "Reference" "C816"
			(at 0 0 270)
			(layer "F.SilkS")
			(hide yes)
			(effects
				(font
					(size 1.27 1.27)
				)
			)
		)
		(property "Value" ""
			(at 0 0 270)
			(layer "F.Fab")
			(effects
				(font
					(size 1.27 1.27)
				)
			)
		)
		(duplicate_pad_numbers_are_jumpers no)
		(fp_line
			(start -0.299974 0.150114)
			(end -0.299974 -0.150114)
			(stroke
				(width 0.1)
				(type default)
			)
			(layer "F.Fab")
		)
		(fp_line
			(start 0.299974 0.150114)
			(end -0.299974 0.150114)
			(stroke
				(width 0.1)
				(type default)
			)
			(layer "F.Fab")
		)
		(fp_line
			(start -0.299974 -0.150114)
			(end 0.299974 -0.150114)
			(stroke
				(width 0.1)
				(type default)
			)
			(layer "F.Fab")
		)
		(fp_line
			(start 0.299974 -0.150114)
			(end 0.299974 0.150114)
			(stroke
				(width 0.1)
				(type default)
			)
			(layer "F.Fab")
		)
		(pad "1" smd rect
			(at -0.2667 0 270)
			(size 0.3048 0.381)
			(layers "F.Cu" "F.Mask" "F.Paste")
			(net "P5E_CPU1_P0_TX_C_DN<10>")
		)
		(pad "2" smd rect
			(at 0.2667 0 270)
			(size 0.3048 0.381)
			(layers "F.Cu" "F.Mask" "F.Paste")
			(net "P5E_CPU1_P0_TX_DN<10>")
		)
	)
	(footprint ""
		(layer "F.Cu")
		(at 234.301538 -293.13505 -90)
		(property "Reference" "PC6525"
			(at 0 0 270)
			(layer "F.SilkS")
			(hide yes)
			(effects
				(font
					(size 1.27 1.27)
				)
			)
		)
		(property "Value" ""
			(at 0 0 270)
			(layer "F.Fab")
			(effects
				(font
					(size 1.27 1.27)
				)
			)
		)
		(duplicate_pad_numbers_are_jumpers no)
		(fp_line
			(start -0.7874 0.4064)
			(end -0.7874 -0.4064)
			(stroke
				(width 0.1524)
				(type default)
			)
			(layer "F.SilkS")
		)
		(fp_line
			(start 0.7874 0.4064)
			(end -0.7874 0.4064)
			(stroke
				(width 0.1524)
				(type default)
			)
			(layer "F.SilkS")
		)
		(fp_line
			(start -0.7874 -0.4064)
			(end 0.7874 -0.4064)
			(stroke
				(width 0.1524)
				(type default)
			)
			(layer "F.SilkS")
		)
		(fp_line
			(start 0.7874 -0.4064)
			(end 0.7874 0.4064)
			(stroke
				(width 0.1524)
				(type default)
			)
			(layer "F.SilkS")
		)
		(fp_line
			(start -0.67945 0.3048)
			(end -0.67945 -0.305054)
			(stroke
				(width 0.1)
				(type default)
			)
			(layer "F.Fab")
		)
		(fp_line
			(start -0.12065 0.3048)
			(end -0.67945 0.3048)
			(stroke
				(width 0.1)
				(type default)
			)
			(layer "F.Fab")
		)
		(fp_line
			(start 0.120396 0.3048)
			(end 0.120396 0.2794)
			(stroke
				(width 0.1)
				(type default)
			)
			(layer "F.Fab")
		)
		(fp_line
			(start 0.67945 0.3048)
			(end 0.120396 0.3048)
			(stroke
				(width 0.1)
				(type default)
			)
			(layer "F.Fab")
		)
		(fp_line
			(start -0.12065 0.2794)
			(end -0.12065 0.3048)
			(stroke
				(width 0.1)
				(type default)
			)
			(layer "F.Fab")
		)
		(fp_line
			(start 0.120396 0.2794)
			(end -0.12065 0.2794)
			(stroke
				(width 0.1)
				(type default)
			)
			(layer "F.Fab")
		)
		(fp_line
			(start -0.12065 -0.2794)
			(end 0.12065 -0.2794)
			(stroke
				(width 0.1)
				(type default)
			)
			(layer "F.Fab")
		)
		(fp_line
			(start 0.12065 -0.2794)
			(end 0.12065 -0.3048)
			(stroke
				(width 0.1)
				(type default)
			)
			(layer "F.Fab")
		)
		(fp_line
			(start 0.12065 -0.3048)
			(end 0.67945 -0.3048)
			(stroke
				(width 0.1)
				(type default)
			)
			(layer "F.Fab")
		)
		(fp_line
			(start 0.67945 -0.3048)
			(end 0.67945 0.3048)
			(stroke
				(width 0.1)
				(type default)
			)
			(layer "F.Fab")
		)
		(fp_line
			(start -0.67945 -0.305054)
			(end -0.12065 -0.305054)
			(stroke
				(width 0.1)
				(type default)
			)
			(layer "F.Fab")
		)
		(fp_line
			(start -0.12065 -0.305054)
			(end -0.12065 -0.2794)
			(stroke
				(width 0.1)
				(type default)
			)
			(layer "F.Fab")
		)
		(pad "1" smd circle
			(at -0.40005 0 270)
			(size 0 0)
			(layers "F.Cu" "F.Mask" "F.Paste")
			(net "P1V8_RETIMER_CPU1_VCC")
		)
		(pad "2" smd circle
			(at 0.40005 0 270)
			(size 0 0)
			(layers "F.Cu" "F.Mask" "F.Paste")
			(net "GND")
		)
	)
	(footprint ""
		(layer "F.Cu")
		(at 185.862722 6.063234 180)
		(property "Reference" "J83"
			(at -4.472686 -1.101598 90)
			(unlocked yes)
			(layer "F.SilkS")
			(effects
				(font
					(size 0.7874 0.5842)
					(thickness 0.1524)
				)
				(justify left)
			)
		)
		(property "Value" ""
			(at 0 0 180)
			(layer "F.Fab")
			(effects
				(font
					(size 1.27 1.27)
				)
			)
		)
		(duplicate_pad_numbers_are_jumpers no)
		(fp_line
			(start 1.2192 2.06756)
			(end -1.2192 2.06756)
			(stroke
				(width 0.1524)
				(type default)
			)
			(layer "F.SilkS")
		)
		(fp_line
			(start 1.2192 -2.06756)
			(end 1.2192 2.06756)
			(stroke
				(width 0.1524)
				(type default)
			)
			(layer "F.SilkS")
		)
		(fp_line
			(start -1.2192 2.06756)
			(end -1.2192 -2.06756)
			(stroke
				(width 0.1524)
				(type default)
			)
			(layer "F.SilkS")
		)
		(fp_line
			(start -1.2192 -2.06756)
			(end 1.2192 -2.06756)
			(stroke
				(width 0.1524)
				(type default)
			)
			(layer "F.SilkS")
		)
		(pad "" np_thru_hole circle
			(at -2.8829 -1.27 90)
			(size 1.0414 1.0414)
			(drill 1.0414)
			(layers "*.Cu" "*.Mask")
			(clearance 0.381)
			(thermal_gap 0.381)
		)
		(pad "" np_thru_hole circle
			(at -2.8829 1.27 90)
			(size 1.0414 1.0414)
			(drill 1.0414)
			(layers "*.Cu" "*.Mask")
			(clearance 0.381)
			(thermal_gap 0.381)
		)
		(pad "" np_thru_hole circle
			(at 3.4671 -1.27 90)
			(size 1.0414 1.0414)
			(drill 1.0414)
			(layers "*.Cu" "*.Mask")
			(clearance 0.381)
			(thermal_gap 0.381)
		)
		(pad "" np_thru_hole circle
			(at 3.4671 1.27 90)
			(size 1.0414 1.0414)
			(drill 1.0414)
			(layers "*.Cu" "*.Mask")
			(clearance 0.381)
			(thermal_gap 0.381)
		)
		(pad "1" smd rect
			(at 0.8255 -0.249936 90)
			(size 0.3048 0.508)
			(layers "F.Cu" "F.Mask" "F.Paste")
			(net "DELTA_L_85_10INCH_IN1_DN")
		)
		(pad "2" smd rect
			(at 0.8255 0.249936 90)
			(size 0.3048 0.508)
			(layers "F.Cu" "F.Mask" "F.Paste")
			(net "DELTA_L_85_10INCH_IN1_DP")
		)
		(pad "3" smd circle
			(at 0 0 180)
			(size 0 0)
			(layers "F.Cu" "F.Mask" "F.Paste")
			(net "DELTA_L_GND_1")
		)
		(zone
			(layer "F.Cu")
			(hatch none 0.5)
			(connect_pads
				(clearance 0)
			)
			(min_thickness 0.25)
			(keepout
				(tracks not_allowed)
				(vias allowed)
				(pads allowed)
				(copperpour not_allowed)
				(footprints allowed)
			)
			(placement
				(enabled no)
				(sheetname "")
			)
			(fill
				(thermal_gap 0.5)
				(thermal_bridge_width 0.5)
				(island_removal_mode 0)
			)
			(polygon
				(pts
					(xy 184.745122 6.611874) (xy 184.745122 6.51637) (xy 185.342022 6.51637) (xy 185.342022 6.10997)
					(xy 184.745122 6.10997) (xy 184.745122 6.016498) (xy 185.342022 6.016498) (xy 185.342022 5.610098)
					(xy 184.745122 5.610098) (xy 184.745122 5.514594) (xy 185.443622 5.514594) (xy 185.443622 6.611874)
				)
			)
		)
		(zone
			(layers "F.Cu" "B.Cu" "In1.Cu" "In2.Cu" "In3.Cu" "In4.Cu" "In5.Cu" "In6.Cu"
				"In7.Cu" "In8.Cu" "In9.Cu" "In10.Cu" "In11.Cu" "In12.Cu" "In13.Cu" "In14.Cu"
				"In15.Cu" "In16.Cu"
			)
			(hatch none 0.5)
			(connect_pads
				(clearance 0)
			)
			(min_thickness 0.25)
			(keepout
				(tracks not_allowed)
				(vias allowed)
				(pads allowed)
				(copperpour not_allowed)
				(footprints allowed)
			)
			(placement
				(enabled no)
				(sheetname "")
			)
			(fill
				(thermal_gap 0.5)
				(thermal_bridge_width 0.5)
				(island_removal_mode 0)
			)
			(polygon
				(pts
					(arc
						(start 183.322722 4.793234)
						(mid 181.468522 4.793234)
						(end 183.322722 4.793234)
					)
				)
			)
		)
		(zone
			(layers "F.Cu" "B.Cu" "In1.Cu" "In2.Cu" "In3.Cu" "In4.Cu" "In5.Cu" "In6.Cu"
				"In7.Cu" "In8.Cu" "In9.Cu" "In10.Cu" "In11.Cu" "In12.Cu" "In13.Cu" "In14.Cu"
				"In15.Cu" "In16.Cu"
			)
			(hatch none 0.5)
			(connect_pads
				(clearance 0)
			)
			(min_thickness 0.25)
			(keepout
				(tracks not_allowed)
				(vias allowed)
				(pads allowed)
				(copperpour not_allowed)
				(footprints allowed)
			)
			(placement
				(enabled no)
				(sheetname "")
			)
			(fill
				(thermal_gap 0.5)
				(thermal_bridge_width 0.5)
				(island_removal_mode 0)
			)
			(polygon
				(pts
					(arc
						(start 183.322722 7.333234)
						(mid 181.468522 7.333234)
						(end 183.322722 7.333234)
					)
				)
			)
		)
		(zone
			(layers "F.Cu" "B.Cu" "In1.Cu" "In2.Cu" "In3.Cu" "In4.Cu" "In5.Cu" "In6.Cu"
				"In7.Cu" "In8.Cu" "In9.Cu" "In10.Cu" "In11.Cu" "In12.Cu" "In13.Cu" "In14.Cu"
				"In15.Cu" "In16.Cu"
			)
			(hatch none 0.5)
			(connect_pads
				(clearance 0)
			)
			(min_thickness 0.25)
			(keepout
				(tracks not_allowed)
				(vias allowed)
				(pads allowed)
				(copperpour not_allowed)
				(footprints allowed)
			)
			(placement
				(enabled no)
				(sheetname "")
			)
			(fill
				(thermal_gap 0.5)
				(thermal_bridge_width 0.5)
				(island_removal_mode 0)
			)
			(polygon
				(pts
					(arc
						(start 189.672722 4.793234)
						(mid 187.818522 4.793234)
						(end 189.672722 4.793234)
					)
				)
			)
		)
		(zone
			(layers "F.Cu" "B.Cu" "In1.Cu" "In2.Cu" "In3.Cu" "In4.Cu" "In5.Cu" "In6.Cu"
				"In7.Cu" "In8.Cu" "In9.Cu" "In10.Cu" "In11.Cu" "In12.Cu" "In13.Cu" "In14.Cu"
				"In15.Cu" "In16.Cu"
			)
			(hatch none 0.5)
			(connect_pads
				(clearance 0)
			)
			(min_thickness 0.25)
			(keepout
				(tracks not_allowed)
				(vias allowed)
				(pads allowed)
				(copperpour not_allowed)
				(footprints allowed)
			)
			(placement
				(enabled no)
				(sheetname "")
			)
			(fill
				(thermal_gap 0.5)
				(thermal_bridge_width 0.5)
				(island_removal_mode 0)
			)
			(polygon
				(pts
					(arc
						(start 189.672722 7.333234)
						(mid 187.818522 7.333234)
						(end 189.672722 7.333234)
					)
				)
			)
		)
	)
	(footprint ""
		(layer "F.Cu")
		(at 184.705752 -355.898958 -90)
		(property "Reference" "PC519"
			(at 0 0 270)
			(layer "F.SilkS")
			(hide yes)
			(effects
				(font
					(size 1.27 1.27)
				)
			)
		)
		(property "Value" ""
			(at 0 0 270)
			(layer "F.Fab")
			(effects
				(font
					(size 1.27 1.27)
				)
			)
		)
		(duplicate_pad_numbers_are_jumpers no)
		(fp_line
			(start -0.7874 0.4064)
			(end -0.7874 -0.4064)
			(stroke
				(width 0.1524)
				(type default)
			)
			(layer "F.SilkS")
		)
		(fp_line
			(start 0.7874 0.4064)
			(end -0.7874 0.4064)
			(stroke
				(width 0.1524)
				(type default)
			)
			(layer "F.SilkS")
		)
		(fp_line
			(start -0.7874 -0.4064)
			(end 0.7874 -0.4064)
			(stroke
				(width 0.1524)
				(type default)
			)
			(layer "F.SilkS")
		)
		(fp_line
			(start 0.7874 -0.4064)
			(end 0.7874 0.4064)
			(stroke
				(width 0.1524)
				(type default)
			)
			(layer "F.SilkS")
		)
		(fp_line
			(start -0.67945 0.3048)
			(end -0.67945 -0.305054)
			(stroke
				(width 0.1)
				(type default)
			)
			(layer "F.Fab")
		)
		(fp_line
			(start -0.12065 0.3048)
			(end -0.67945 0.3048)
			(stroke
				(width 0.1)
				(type default)
			)
			(layer "F.Fab")
		)
		(fp_line
			(start 0.120396 0.3048)
			(end 0.120396 0.2794)
			(stroke
				(width 0.1)
				(type default)
			)
			(layer "F.Fab")
		)
		(fp_line
			(start 0.67945 0.3048)
			(end 0.120396 0.3048)
			(stroke
				(width 0.1)
				(type default)
			)
			(layer "F.Fab")
		)
		(fp_line
			(start -0.12065 0.2794)
			(end -0.12065 0.3048)
			(stroke
				(width 0.1)
				(type default)
			)
			(layer "F.Fab")
		)
		(fp_line
			(start 0.120396 0.2794)
			(end -0.12065 0.2794)
			(stroke
				(width 0.1)
				(type default)
			)
			(layer "F.Fab")
		)
		(fp_line
			(start -0.12065 -0.2794)
			(end 0.12065 -0.2794)
			(stroke
				(width 0.1)
				(type default)
			)
			(layer "F.Fab")
		)
		(fp_line
			(start 0.12065 -0.2794)
			(end 0.12065 -0.3048)
			(stroke
				(width 0.1)
				(type default)
			)
			(layer "F.Fab")
		)
		(fp_line
			(start 0.12065 -0.3048)
			(end 0.67945 -0.3048)
			(stroke
				(width 0.1)
				(type default)
			)
			(layer "F.Fab")
		)
		(fp_line
			(start 0.67945 -0.3048)
			(end 0.67945 0.3048)
			(stroke
				(width 0.1)
				(type default)
			)
			(layer "F.Fab")
		)
		(fp_line
			(start -0.67945 -0.305054)
			(end -0.12065 -0.305054)
			(stroke
				(width 0.1)
				(type default)
			)
			(layer "F.Fab")
		)
		(fp_line
			(start -0.12065 -0.305054)
			(end -0.12065 -0.2794)
			(stroke
				(width 0.1)
				(type default)
			)
			(layer "F.Fab")
		)
		(pad "1" smd circle
			(at -0.40005 0 270)
			(size 0 0)
			(layers "F.Cu" "F.Mask" "F.Paste")
			(net "SW_PVDD11_S3_P1_BOOT1_RC")
		)
		(pad "2" smd circle
			(at 0.40005 0 270)
			(size 0 0)
			(layers "F.Cu" "F.Mask" "F.Paste")
			(net "SW_PVDD11_S3_P1_PH1")
		)
	)
	(footprint ""
		(layer "F.Cu")
		(at 79.629 -64.008 -90)
		(property "Reference" "U8002"
			(at 1.048766 -2.816606 90)
			(unlocked yes)
			(layer "F.SilkS")
			(effects
				(font
					(size 0.7874 0.5842)
					(thickness 0.1524)
				)
				(justify left)
			)
		)
		(property "Value" ""
			(at 0 0 270)
			(layer "F.Fab")
			(effects
				(font
					(size 1.27 1.27)
				)
			)
		)
		(duplicate_pad_numbers_are_jumpers no)
		(fp_line
			(start -1.759712 1.500124)
			(end -1.759712 -1.500124)
			(stroke
				(width 0.1524)
				(type default)
			)
			(layer "F.SilkS")
		)
		(fp_line
			(start 1.759712 1.500124)
			(end -1.759712 1.500124)
			(stroke
				(width 0.1524)
				(type default)
			)
			(layer "F.SilkS")
		)
		(fp_line
			(start -1.759712 -1.500124)
			(end 1.759712 -1.500124)
			(stroke
				(width 0.1524)
				(type default)
			)
			(layer "F.SilkS")
		)
		(fp_line
			(start 1.759712 -1.500124)
			(end 1.759712 1.500124)
			(stroke
				(width 0.1524)
				(type default)
			)
			(layer "F.SilkS")
		)
		(fp_line
			(start -0.700024 1.500124)
			(end -0.700024 -1.500124)
			(stroke
				(width 0.1)
				(type default)
			)
			(layer "F.Fab")
		)
		(fp_line
			(start 0.700024 1.500124)
			(end -0.700024 1.500124)
			(stroke
				(width 0.1)
				(type default)
			)
			(layer "F.Fab")
		)
		(fp_line
			(start -0.700024 -1.500124)
			(end 0.700024 -1.500124)
			(stroke
				(width 0.1)
				(type default)
			)
			(layer "F.Fab")
		)
		(fp_line
			(start 0.700024 -1.500124)
			(end 0.700024 1.500124)
			(stroke
				(width 0.1)
				(type default)
			)
			(layer "F.Fab")
		)
		(pad "1" smd rect
			(at -1.150112 -0.94996 180)
			(size 0.6604 0.9652)
			(layers "F.Cu" "F.Mask" "F.Paste")
			(net "GND")
		)
		(pad "2" smd rect
			(at -1.150112 0.94996 180)
			(size 0.6604 0.9652)
			(layers "F.Cu" "F.Mask" "F.Paste")
			(net "OCP_V3_2_P3V3_R1_PWRGD")
		)
		(pad "3" smd rect
			(at 1.150112 0 180)
			(size 0.6604 0.9652)
			(layers "F.Cu" "F.Mask" "F.Paste")
			(net "P3V3_OCP_V3_2_R")
		)
	)
	(footprint ""
		(layer "F.Cu")
		(at 275.574252 -119.91467)
		(property "Reference" "R6211"
			(at 0 0 0)
			(layer "F.SilkS")
			(hide yes)
			(effects
				(font
					(size 1.27 1.27)
				)
			)
		)
		(property "Value" ""
			(at 0 0 0)
			(layer "F.Fab")
			(effects
				(font
					(size 1.27 1.27)
				)
			)
		)
		(duplicate_pad_numbers_are_jumpers no)
		(fp_line
			(start -0.7874 -0.4064)
			(end 0.7874 -0.4064)
			(stroke
				(width 0.1524)
				(type default)
			)
			(layer "F.SilkS")
		)
		(fp_line
			(start -0.7874 0.4064)
			(end -0.7874 -0.4064)
			(stroke
				(width 0.1524)
				(type default)
			)
			(layer "F.SilkS")
		)
		(fp_line
			(start 0.7874 -0.4064)
			(end 0.7874 0.4064)
			(stroke
				(width 0.1524)
				(type default)
			)
			(layer "F.SilkS")
		)
		(fp_line
			(start 0.7874 0.4064)
			(end -0.7874 0.4064)
			(stroke
				(width 0.1524)
				(type default)
			)
			(layer "F.SilkS")
		)
		(fp_line
			(start -0.67945 -0.305054)
			(end -0.12065 -0.305054)
			(stroke
				(width 0.1)
				(type default)
			)
			(layer "F.Fab")
		)
		(fp_line
			(start -0.67945 0.3048)
			(end -0.67945 -0.305054)
			(stroke
				(width 0.1)
				(type default)
			)
			(layer "F.Fab")
		)
		(fp_line
			(start -0.12065 -0.305054)
			(end -0.12065 -0.2794)
			(stroke
				(width 0.1)
				(type default)
			)
			(layer "F.Fab")
		)
		(fp_line
			(start -0.12065 -0.2794)
			(end 0.12065 -0.2794)
			(stroke
				(width 0.1)
				(type default)
			)
			(layer "F.Fab")
		)
		(fp_line
			(start -0.12065 0.2794)
			(end -0.12065 0.3048)
			(stroke
				(width 0.1)
				(type default)
			)
			(layer "F.Fab")
		)
		(fp_line
			(start -0.12065 0.3048)
			(end -0.67945 0.3048)
			(stroke
				(width 0.1)
				(type default)
			)
			(layer "F.Fab")
		)
		(fp_line
			(start 0.120396 0.2794)
			(end -0.12065 0.2794)
			(stroke
				(width 0.1)
				(type default)
			)
			(layer "F.Fab")
		)
		(fp_line
			(start 0.120396 0.3048)
			(end 0.120396 0.2794)
			(stroke
				(width 0.1)
				(type default)
			)
			(layer "F.Fab")
		)
		(fp_line
			(start 0.12065 -0.3048)
			(end 0.67945 -0.3048)
			(stroke
				(width 0.1)
				(type default)
			)
			(layer "F.Fab")
		)
		(fp_line
			(start 0.12065 -0.2794)
			(end 0.12065 -0.3048)
			(stroke
				(width 0.1)
				(type default)
			)
			(layer "F.Fab")
		)
		(fp_line
			(start 0.67945 -0.3048)
			(end 0.67945 0.3048)
			(stroke
				(width 0.1)
				(type default)
			)
			(layer "F.Fab")
		)
		(fp_line
			(start 0.67945 0.3048)
			(end 0.120396 0.3048)
			(stroke
				(width 0.1)
				(type default)
			)
			(layer "F.Fab")
		)
		(pad "1" smd circle
			(at -0.40005 0)
			(size 0 0)
			(layers "F.Cu" "F.Mask" "F.Paste")
			(net "P3V3_AUX")
		)
		(pad "2" smd circle
			(at 0.40005 0)
			(size 0 0)
			(layers "F.Cu" "F.Mask" "F.Paste")
			(net "SMB_USB_CPU0_HUB1_SCL")
		)
	)
	(footprint ""
		(layer "F.Cu")
		(at 180.3908 -394.1318)
		(property "Reference" "R1417"
			(at 0 0 0)
			(layer "F.SilkS")
			(hide yes)
			(effects
				(font
					(size 1.27 1.27)
				)
			)
		)
		(property "Value" ""
			(at 0 0 0)
			(layer "F.Fab")
			(effects
				(font
					(size 1.27 1.27)
				)
			)
		)
		(duplicate_pad_numbers_are_jumpers no)
		(fp_line
			(start -0.32512 -0.175006)
			(end 0.32512 -0.175006)
			(stroke
				(width 0.1)
				(type default)
			)
			(layer "F.Fab")
		)
		(fp_line
			(start -0.32512 0.175006)
			(end -0.32512 -0.175006)
			(stroke
				(width 0.1)
				(type default)
			)
			(layer "F.Fab")
		)
		(fp_line
			(start 0.32512 -0.175006)
			(end 0.32512 0.175006)
			(stroke
				(width 0.1)
				(type default)
			)
			(layer "F.Fab")
		)
		(fp_line
			(start 0.32512 0.175006)
			(end -0.32512 0.175006)
			(stroke
				(width 0.1)
				(type default)
			)
			(layer "F.Fab")
		)
		(pad "1" smd rect
			(at -0.2667 0)
			(size 0.3048 0.381)
			(layers "F.Cu" "F.Mask" "F.Paste")
			(net "JTAG_TCK_RT_CPU1_P2")
		)
		(pad "2" smd rect
			(at 0.2667 0 180)
			(size 0.3048 0.381)
			(layers "F.Cu" "F.Mask" "F.Paste")
			(net "GND")
		)
	)
	(footprint ""
		(layer "F.Cu")
		(at 33.203896 -344.986864 90)
		(property "Reference" "PR492"
			(at 0 0 90)
			(layer "F.SilkS")
			(hide yes)
			(effects
				(font
					(size 1.27 1.27)
				)
			)
		)
		(property "Value" ""
			(at 0 0 90)
			(layer "F.Fab")
			(effects
				(font
					(size 1.27 1.27)
				)
			)
		)
		(duplicate_pad_numbers_are_jumpers no)
		(fp_line
			(start 0.7874 -0.4064)
			(end 0.7874 0.4064)
			(stroke
				(width 0.1524)
				(type default)
			)
			(layer "F.SilkS")
		)
		(fp_line
			(start -0.7874 -0.4064)
			(end 0.7874 -0.4064)
			(stroke
				(width 0.1524)
				(type default)
			)
			(layer "F.SilkS")
		)
		(fp_line
			(start 0.7874 0.4064)
			(end -0.7874 0.4064)
			(stroke
				(width 0.1524)
				(type default)
			)
			(layer "F.SilkS")
		)
		(fp_line
			(start -0.7874 0.4064)
			(end -0.7874 -0.4064)
			(stroke
				(width 0.1524)
				(type default)
			)
			(layer "F.SilkS")
		)
		(fp_line
			(start -0.12065 -0.305054)
			(end -0.12065 -0.2794)
			(stroke
				(width 0.1)
				(type default)
			)
			(layer "F.Fab")
		)
		(fp_line
			(start -0.67945 -0.305054)
			(end -0.12065 -0.305054)
			(stroke
				(width 0.1)
				(type default)
			)
			(layer "F.Fab")
		)
		(fp_line
			(start 0.67945 -0.3048)
			(end 0.67945 0.3048)
			(stroke
				(width 0.1)
				(type default)
			)
			(layer "F.Fab")
		)
		(fp_line
			(start 0.12065 -0.3048)
			(end 0.67945 -0.3048)
			(stroke
				(width 0.1)
				(type default)
			)
			(layer "F.Fab")
		)
		(fp_line
			(start 0.12065 -0.2794)
			(end 0.12065 -0.3048)
			(stroke
				(width 0.1)
				(type default)
			)
			(layer "F.Fab")
		)
		(fp_line
			(start -0.12065 -0.2794)
			(end 0.12065 -0.2794)
			(stroke
				(width 0.1)
				(type default)
			)
			(layer "F.Fab")
		)
		(fp_line
			(start 0.120396 0.2794)
			(end -0.12065 0.2794)
			(stroke
				(width 0.1)
				(type default)
			)
			(layer "F.Fab")
		)
		(fp_line
			(start -0.12065 0.2794)
			(end -0.12065 0.3048)
			(stroke
				(width 0.1)
				(type default)
			)
			(layer "F.Fab")
		)
		(fp_line
			(start 0.67945 0.3048)
			(end 0.120396 0.3048)
			(stroke
				(width 0.1)
				(type default)
			)
			(layer "F.Fab")
		)
		(fp_line
			(start 0.120396 0.3048)
			(end 0.120396 0.2794)
			(stroke
				(width 0.1)
				(type default)
			)
			(layer "F.Fab")
		)
		(fp_line
			(start -0.12065 0.3048)
			(end -0.67945 0.3048)
			(stroke
				(width 0.1)
				(type default)
			)
			(layer "F.Fab")
		)
		(fp_line
			(start -0.67945 0.3048)
			(end -0.67945 -0.305054)
			(stroke
				(width 0.1)
				(type default)
			)
			(layer "F.Fab")
		)
		(pad "1" smd circle
			(at -0.40005 0 90)
			(size 0 0)
			(layers "F.Cu" "F.Mask" "F.Paste")
			(net "SW_PVDDIO_P1_SW3_RC")
		)
		(pad "2" smd circle
			(at 0.40005 0 90)
			(size 0 0)
			(layers "F.Cu" "F.Mask" "F.Paste")
			(net "GND")
		)
	)
	(footprint ""
		(layer "F.Cu")
		(at 365.518446 -30.084522 -90)
		(property "Reference" "R819"
			(at 0 0 270)
			(layer "F.SilkS")
			(hide yes)
			(effects
				(font
					(size 1.27 1.27)
				)
			)
		)
		(property "Value" ""
			(at 0 0 270)
			(layer "F.Fab")
			(effects
				(font
					(size 1.27 1.27)
				)
			)
		)
		(duplicate_pad_numbers_are_jumpers no)
		(fp_line
			(start -0.7874 0.4064)
			(end -0.7874 -0.4064)
			(stroke
				(width 0.1524)
				(type default)
			)
			(layer "F.SilkS")
		)
		(fp_line
			(start 0.7874 0.4064)
			(end -0.7874 0.4064)
			(stroke
				(width 0.1524)
				(type default)
			)
			(layer "F.SilkS")
		)
		(fp_line
			(start -0.7874 -0.4064)
			(end 0.7874 -0.4064)
			(stroke
				(width 0.1524)
				(type default)
			)
			(layer "F.SilkS")
		)
		(fp_line
			(start 0.7874 -0.4064)
			(end 0.7874 0.4064)
			(stroke
				(width 0.1524)
				(type default)
			)
			(layer "F.SilkS")
		)
		(fp_line
			(start -0.67945 0.3048)
			(end -0.67945 -0.305054)
			(stroke
				(width 0.1)
				(type default)
			)
			(layer "F.Fab")
		)
		(fp_line
			(start -0.12065 0.3048)
			(end -0.67945 0.3048)
			(stroke
				(width 0.1)
				(type default)
			)
			(layer "F.Fab")
		)
		(fp_line
			(start 0.120396 0.3048)
			(end 0.120396 0.2794)
			(stroke
				(width 0.1)
				(type default)
			)
			(layer "F.Fab")
		)
		(fp_line
			(start 0.67945 0.3048)
			(end 0.120396 0.3048)
			(stroke
				(width 0.1)
				(type default)
			)
			(layer "F.Fab")
		)
		(fp_line
			(start -0.12065 0.2794)
			(end -0.12065 0.3048)
			(stroke
				(width 0.1)
				(type default)
			)
			(layer "F.Fab")
		)
		(fp_line
			(start 0.120396 0.2794)
			(end -0.12065 0.2794)
			(stroke
				(width 0.1)
				(type default)
			)
			(layer "F.Fab")
		)
		(fp_line
			(start -0.12065 -0.2794)
			(end 0.12065 -0.2794)
			(stroke
				(width 0.1)
				(type default)
			)
			(layer "F.Fab")
		)
		(fp_line
			(start 0.12065 -0.2794)
			(end 0.12065 -0.3048)
			(stroke
				(width 0.1)
				(type default)
			)
			(layer "F.Fab")
		)
		(fp_line
			(start 0.12065 -0.3048)
			(end 0.67945 -0.3048)
			(stroke
				(width 0.1)
				(type default)
			)
			(layer "F.Fab")
		)
		(fp_line
			(start 0.67945 -0.3048)
			(end 0.67945 0.3048)
			(stroke
				(width 0.1)
				(type default)
			)
			(layer "F.Fab")
		)
		(fp_line
			(start -0.67945 -0.305054)
			(end -0.12065 -0.305054)
			(stroke
				(width 0.1)
				(type default)
			)
			(layer "F.Fab")
		)
		(fp_line
			(start -0.12065 -0.305054)
			(end -0.12065 -0.2794)
			(stroke
				(width 0.1)
				(type default)
			)
			(layer "F.Fab")
		)
		(pad "1" smd circle
			(at -0.40005 0 270)
			(size 0 0)
			(layers "F.Cu" "F.Mask" "F.Paste")
			(net "UART_CPU0_LVC3_UART0_R_RX")
		)
		(pad "2" smd circle
			(at 0.40005 0 270)
			(size 0 0)
			(layers "F.Cu" "F.Mask" "F.Paste")
			(net "UART_CPU0_LVC3_UART0_RX")
		)
	)
	(footprint ""
		(layer "F.Cu")
		(at 173.171358 -388.753604)
		(property "Reference" "C373"
			(at 0 0 0)
			(layer "F.SilkS")
			(hide yes)
			(effects
				(font
					(size 1.27 1.27)
				)
			)
		)
		(property "Value" ""
			(at 0 0 0)
			(layer "F.Fab")
			(effects
				(font
					(size 1.27 1.27)
				)
			)
		)
		(duplicate_pad_numbers_are_jumpers no)
		(fp_line
			(start -0.7874 -0.4064)
			(end 0.7874 -0.4064)
			(stroke
				(width 0.1524)
				(type default)
			)
			(layer "F.SilkS")
		)
		(fp_line
			(start -0.7874 0.4064)
			(end -0.7874 -0.4064)
			(stroke
				(width 0.1524)
				(type default)
			)
			(layer "F.SilkS")
		)
		(fp_line
			(start 0.7874 -0.4064)
			(end 0.7874 0.4064)
			(stroke
				(width 0.1524)
				(type default)
			)
			(layer "F.SilkS")
		)
		(fp_line
			(start 0.7874 0.4064)
			(end -0.7874 0.4064)
			(stroke
				(width 0.1524)
				(type default)
			)
			(layer "F.SilkS")
		)
		(fp_line
			(start -0.67945 -0.305054)
			(end -0.12065 -0.305054)
			(stroke
				(width 0.1)
				(type default)
			)
			(layer "F.Fab")
		)
		(fp_line
			(start -0.67945 0.3048)
			(end -0.67945 -0.305054)
			(stroke
				(width 0.1)
				(type default)
			)
			(layer "F.Fab")
		)
		(fp_line
			(start -0.12065 -0.305054)
			(end -0.12065 -0.2794)
			(stroke
				(width 0.1)
				(type default)
			)
			(layer "F.Fab")
		)
		(fp_line
			(start -0.12065 -0.2794)
			(end 0.12065 -0.2794)
			(stroke
				(width 0.1)
				(type default)
			)
			(layer "F.Fab")
		)
		(fp_line
			(start -0.12065 0.2794)
			(end -0.12065 0.3048)
			(stroke
				(width 0.1)
				(type default)
			)
			(layer "F.Fab")
		)
		(fp_line
			(start -0.12065 0.3048)
			(end -0.67945 0.3048)
			(stroke
				(width 0.1)
				(type default)
			)
			(layer "F.Fab")
		)
		(fp_line
			(start 0.120396 0.2794)
			(end -0.12065 0.2794)
			(stroke
				(width 0.1)
				(type default)
			)
			(layer "F.Fab")
		)
		(fp_line
			(start 0.120396 0.3048)
			(end 0.120396 0.2794)
			(stroke
				(width 0.1)
				(type default)
			)
			(layer "F.Fab")
		)
		(fp_line
			(start 0.12065 -0.3048)
			(end 0.67945 -0.3048)
			(stroke
				(width 0.1)
				(type default)
			)
			(layer "F.Fab")
		)
		(fp_line
			(start 0.12065 -0.2794)
			(end 0.12065 -0.3048)
			(stroke
				(width 0.1)
				(type default)
			)
			(layer "F.Fab")
		)
		(fp_line
			(start 0.67945 -0.3048)
			(end 0.67945 0.3048)
			(stroke
				(width 0.1)
				(type default)
			)
			(layer "F.Fab")
		)
		(fp_line
			(start 0.67945 0.3048)
			(end 0.120396 0.3048)
			(stroke
				(width 0.1)
				(type default)
			)
			(layer "F.Fab")
		)
		(pad "1" smd circle
			(at -0.40005 0)
			(size 0 0)
			(layers "F.Cu" "F.Mask" "F.Paste")
			(net "P1V8_CPU1_RT_1D")
		)
		(pad "2" smd circle
			(at 0.40005 0)
			(size 0 0)
			(layers "F.Cu" "F.Mask" "F.Paste")
			(net "GND")
		)
	)
	(footprint ""
		(layer "F.Cu")
		(at 325.430896 -378.95403 -90)
		(property "Reference" "C907"
			(at 0 0 270)
			(layer "F.SilkS")
			(hide yes)
			(effects
				(font
					(size 1.27 1.27)
				)
			)
		)
		(property "Value" ""
			(at 0 0 270)
			(layer "F.Fab")
			(effects
				(font
					(size 1.27 1.27)
				)
			)
		)
		(duplicate_pad_numbers_are_jumpers no)
		(fp_line
			(start -0.299974 0.150114)
			(end -0.299974 -0.150114)
			(stroke
				(width 0.1)
				(type default)
			)
			(layer "F.Fab")
		)
		(fp_line
			(start 0.299974 0.150114)
			(end -0.299974 0.150114)
			(stroke
				(width 0.1)
				(type default)
			)
			(layer "F.Fab")
		)
		(fp_line
			(start -0.299974 -0.150114)
			(end 0.299974 -0.150114)
			(stroke
				(width 0.1)
				(type default)
			)
			(layer "F.Fab")
		)
		(fp_line
			(start 0.299974 -0.150114)
			(end 0.299974 0.150114)
			(stroke
				(width 0.1)
				(type default)
			)
			(layer "F.Fab")
		)
		(pad "1" smd rect
			(at -0.2667 0 270)
			(size 0.3048 0.381)
			(layers "F.Cu" "F.Mask" "F.Paste")
			(net "P5E_CPU0_P0_TX_C_DP<13>")
		)
		(pad "2" smd rect
			(at 0.2667 0 270)
			(size 0.3048 0.381)
			(layers "F.Cu" "F.Mask" "F.Paste")
			(net "P5E_CPU0_P0_TX_DP<13>")
		)
	)
	(footprint ""
		(layer "F.Cu")
		(at 142.06982 -389.344154 180)
		(property "Reference" "R1434"
			(at 0 0 180)
			(layer "F.SilkS")
			(hide yes)
			(effects
				(font
					(size 1.27 1.27)
				)
			)
		)
		(property "Value" ""
			(at 0 0 180)
			(layer "F.Fab")
			(effects
				(font
					(size 1.27 1.27)
				)
			)
		)
		(duplicate_pad_numbers_are_jumpers no)
		(fp_line
			(start 0.32512 0.175006)
			(end -0.32512 0.175006)
			(stroke
				(width 0.1)
				(type default)
			)
			(layer "F.Fab")
		)
		(fp_line
			(start 0.32512 -0.175006)
			(end 0.32512 0.175006)
			(stroke
				(width 0.1)
				(type default)
			)
			(layer "F.Fab")
		)
		(fp_line
			(start -0.32512 0.175006)
			(end -0.32512 -0.175006)
			(stroke
				(width 0.1)
				(type default)
			)
			(layer "F.Fab")
		)
		(fp_line
			(start -0.32512 -0.175006)
			(end 0.32512 -0.175006)
			(stroke
				(width 0.1)
				(type default)
			)
			(layer "F.Fab")
		)
		(pad "1" smd rect
			(at -0.2667 0 180)
			(size 0.3048 0.381)
			(layers "F.Cu" "F.Mask" "F.Paste")
			(net "P1V8_CPU1_RT_1D")
		)
		(pad "2" smd rect
			(at 0.2667 0)
			(size 0.3048 0.381)
			(layers "F.Cu" "F.Mask" "F.Paste")
			(net "RXDET_BYP_RT_CPU1_P3")
		)
	)
	(footprint ""
		(layer "F.Cu")
		(at 281.46629 -97.644204 180)
		(property "Reference" "U151"
			(at 3.44678 -3.32486 0)
			(unlocked yes)
			(layer "F.SilkS")
			(effects
				(font
					(size 0.7874 0.5842)
					(thickness 0.1524)
				)
				(justify left)
			)
		)
		(property "Value" ""
			(at 0 0 180)
			(layer "F.Fab")
			(effects
				(font
					(size 1.27 1.27)
				)
			)
		)
		(duplicate_pad_numbers_are_jumpers no)
		(fp_line
			(start 1.868932 2.549906)
			(end 1.868932 -2.549906)
			(stroke
				(width 0.1524)
				(type default)
			)
			(layer "F.SilkS")
		)
		(fp_line
			(start 1.868932 -2.549906)
			(end 1.025906 -2.549906)
			(stroke
				(width 0.1524)
				(type default)
			)
			(layer "F.SilkS")
		)
		(fp_line
			(start 1.025906 -2.549906)
			(end 0 -1.524)
			(stroke
				(width 0.1524)
				(type default)
			)
			(layer "F.SilkS")
		)
		(fp_line
			(start 0 -1.524)
			(end -1.025906 -2.549906)
			(stroke
				(width 0.1524)
				(type default)
			)
			(layer "F.SilkS")
		)
		(fp_line
			(start -1.025906 -2.549906)
			(end -1.868932 -2.549906)
			(stroke
				(width 0.1524)
				(type default)
			)
			(layer "F.SilkS")
		)
		(fp_line
			(start -1.868932 2.549906)
			(end 1.868932 2.549906)
			(stroke
				(width 0.1524)
				(type default)
			)
			(layer "F.SilkS")
		)
		(fp_line
			(start -1.868932 -2.549906)
			(end -1.868932 2.549906)
			(stroke
				(width 0.1524)
				(type default)
			)
			(layer "F.SilkS")
		)
		(fp_poly
			(pts
				(xy -3.593338 -2.533142) (xy -4.729226 -2.533142) (xy -4.27482 -3.4417)
			)
			(stroke
				(width 0)
				(type default)
			)
			(fill yes)
			(layer "F.SilkS")
		)
		(fp_line
			(start 2.249932 2.549906)
			(end 2.249932 -2.549906)
			(stroke
				(width 0.1)
				(type default)
			)
			(layer "F.Fab")
		)
		(fp_line
			(start 2.249932 -2.549906)
			(end -2.249932 -2.549906)
			(stroke
				(width 0.1)
				(type default)
			)
			(layer "F.Fab")
		)
		(fp_line
			(start -2.249932 2.549906)
			(end 2.249932 2.549906)
			(stroke
				(width 0.1)
				(type default)
			)
			(layer "F.Fab")
		)
		(fp_line
			(start -2.249932 -2.549906)
			(end -2.249932 2.549906)
			(stroke
				(width 0.1)
				(type default)
			)
			(layer "F.Fab")
		)
		(fp_poly
			(pts
				(xy -4.7752 -1.787398) (xy -4.7752 -2.803398) (xy -3.7592 -2.295398)
			)
			(stroke
				(width 0)
				(type default)
			)
			(fill yes)
			(layer "F.Fab")
		)
		(pad "1" smd rect
			(at -2.800096 -2.275078 90)
			(size 0.3556 1.6002)
			(layers "F.Cu" "F.Mask" "F.Paste")
			(net "PVDD18_S5_P0")
		)
		(pad "2" smd rect
			(at -2.800096 -1.625092 90)
			(size 0.3556 1.6002)
			(layers "F.Cu" "F.Mask" "F.Paste")
			(net "PVDD18_S5_P0")
		)
		(pad "3" smd rect
			(at -2.800096 -0.975106 90)
			(size 0.3556 1.6002)
			(layers "F.Cu" "F.Mask" "F.Paste")
			(net "JTAG_TCK")
		)
		(pad "4" smd rect
			(at -2.800096 -0.32512 90)
			(size 0.3556 1.6002)
			(layers "F.Cu" "F.Mask" "F.Paste")
			(net "JTAG_TMS")
		)
		(pad "5" smd rect
			(at -2.800096 0.32512 90)
			(size 0.3556 1.6002)
			(layers "F.Cu" "F.Mask" "F.Paste")
			(net "JTAG_TRST_N")
		)
		(pad "6" smd rect
			(at -2.800096 0.975106 90)
			(size 0.3556 1.6002)
			(layers "F.Cu" "F.Mask" "F.Paste")
			(net "JTAG_DBREQ_N")
		)
		(pad "7" smd rect
			(at -2.800096 1.625092 90)
			(size 0.3556 1.6002)
			(layers "F.Cu" "F.Mask" "F.Paste")
			(net "PVDD18_S5_P0")
		)
		(pad "8" smd rect
			(at -2.800096 2.275078 90)
			(size 0.3556 1.6002)
			(layers "F.Cu" "F.Mask" "F.Paste")
			(net "PVDD18_S5_P0")
		)
		(pad "9" smd rect
			(at 2.800096 2.275078 90)
			(size 0.3556 1.6002)
			(layers "F.Cu" "F.Mask" "F.Paste")
			(net "CPU1_JTAG_BUF_OE")
		)
		(pad "10" smd rect
			(at 2.800096 1.625092 90)
			(size 0.3556 1.6002)
			(layers "F.Cu" "F.Mask" "F.Paste")
			(net "GND")
		)
		(pad "11" smd rect
			(at 2.800096 0.975106 90)
			(size 0.3556 1.6002)
			(layers "F.Cu" "F.Mask" "F.Paste")
			(net "JTAG_P1_R_DBREQ_N")
		)
		(pad "12" smd rect
			(at 2.800096 0.32512 90)
			(size 0.3556 1.6002)
			(layers "F.Cu" "F.Mask" "F.Paste")
			(net "JTAG_P1_R_TRST_N")
		)
		(pad "13" smd rect
			(at 2.800096 -0.32512 90)
			(size 0.3556 1.6002)
			(layers "F.Cu" "F.Mask" "F.Paste")
			(net "JTAG_P1_R_TMS")
		)
		(pad "14" smd rect
			(at 2.800096 -0.975106 90)
			(size 0.3556 1.6002)
			(layers "F.Cu" "F.Mask" "F.Paste")
			(net "JTAG_P1_R_TCK")
		)
		(pad "15" smd rect
			(at 2.800096 -1.625092 90)
			(size 0.3556 1.6002)
			(layers "F.Cu" "F.Mask" "F.Paste")
			(net "PVDD18_S5_P1")
		)
		(pad "16" smd rect
			(at 2.800096 -2.275078 90)
			(size 0.3556 1.6002)
			(layers "F.Cu" "F.Mask" "F.Paste")
			(net "PVDD18_S5_P0")
		)
	)
	(footprint ""
		(layer "F.Cu")
		(at 357.93426 -327.60031 180)
		(property "Reference" "PR51"
			(at 0 0 180)
			(layer "F.SilkS")
			(hide yes)
			(effects
				(font
					(size 1.27 1.27)
				)
			)
		)
		(property "Value" ""
			(at 0 0 180)
			(layer "F.Fab")
			(effects
				(font
					(size 1.27 1.27)
				)
			)
		)
		(duplicate_pad_numbers_are_jumpers no)
		(fp_line
			(start 0.7874 0.4064)
			(end -0.7874 0.4064)
			(stroke
				(width 0.1524)
				(type default)
			)
			(layer "F.SilkS")
		)
		(fp_line
			(start 0.7874 -0.4064)
			(end 0.7874 0.4064)
			(stroke
				(width 0.1524)
				(type default)
			)
			(layer "F.SilkS")
		)
		(fp_line
			(start -0.7874 0.4064)
			(end -0.7874 -0.4064)
			(stroke
				(width 0.1524)
				(type default)
			)
			(layer "F.SilkS")
		)
		(fp_line
			(start -0.7874 -0.4064)
			(end 0.7874 -0.4064)
			(stroke
				(width 0.1524)
				(type default)
			)
			(layer "F.SilkS")
		)
		(fp_line
			(start 0.67945 0.3048)
			(end 0.120396 0.3048)
			(stroke
				(width 0.1)
				(type default)
			)
			(layer "F.Fab")
		)
		(fp_line
			(start 0.67945 -0.3048)
			(end 0.67945 0.3048)
			(stroke
				(width 0.1)
				(type default)
			)
			(layer "F.Fab")
		)
		(fp_line
			(start 0.12065 -0.2794)
			(end 0.12065 -0.3048)
			(stroke
				(width 0.1)
				(type default)
			)
			(layer "F.Fab")
		)
		(fp_line
			(start 0.12065 -0.3048)
			(end 0.67945 -0.3048)
			(stroke
				(width 0.1)
				(type default)
			)
			(layer "F.Fab")
		)
		(fp_line
			(start 0.120396 0.3048)
			(end 0.120396 0.2794)
			(stroke
				(width 0.1)
				(type default)
			)
			(layer "F.Fab")
		)
		(fp_line
			(start 0.120396 0.2794)
			(end -0.12065 0.2794)
			(stroke
				(width 0.1)
				(type default)
			)
			(layer "F.Fab")
		)
		(fp_line
			(start -0.12065 0.3048)
			(end -0.67945 0.3048)
			(stroke
				(width 0.1)
				(type default)
			)
			(layer "F.Fab")
		)
		(fp_line
			(start -0.12065 0.2794)
			(end -0.12065 0.3048)
			(stroke
				(width 0.1)
				(type default)
			)
			(layer "F.Fab")
		)
		(fp_line
			(start -0.12065 -0.2794)
			(end 0.12065 -0.2794)
			(stroke
				(width 0.1)
				(type default)
			)
			(layer "F.Fab")
		)
		(fp_line
			(start -0.12065 -0.305054)
			(end -0.12065 -0.2794)
			(stroke
				(width 0.1)
				(type default)
			)
			(layer "F.Fab")
		)
		(fp_line
			(start -0.67945 0.3048)
			(end -0.67945 -0.305054)
			(stroke
				(width 0.1)
				(type default)
			)
			(layer "F.Fab")
		)
		(fp_line
			(start -0.67945 -0.305054)
			(end -0.12065 -0.305054)
			(stroke
				(width 0.1)
				(type default)
			)
			(layer "F.Fab")
		)
		(pad "1" smd circle
			(at -0.40005 0 180)
			(size 0 0)
			(layers "F.Cu" "F.Mask" "F.Paste")
			(net "VSENSE_PVDDCR_CPU1_P0_DP")
		)
		(pad "2" smd circle
			(at 0.40005 0 180)
			(size 0 0)
			(layers "F.Cu" "F.Mask" "F.Paste")
			(net "PVDDCR_CPU1_P0")
		)
	)
	(footprint ""
		(layer "F.Cu")
		(at 210.74888 -44.795948)
		(property "Reference" "R3531"
			(at 0 0 0)
			(layer "F.SilkS")
			(hide yes)
			(effects
				(font
					(size 1.27 1.27)
				)
			)
		)
		(property "Value" ""
			(at 0 0 0)
			(layer "F.Fab")
			(effects
				(font
					(size 1.27 1.27)
				)
			)
		)
		(duplicate_pad_numbers_are_jumpers no)
		(fp_line
			(start -0.7874 -0.4064)
			(end 0.7874 -0.4064)
			(stroke
				(width 0.1524)
				(type default)
			)
			(layer "F.SilkS")
		)
		(fp_line
			(start -0.7874 0.4064)
			(end -0.7874 -0.4064)
			(stroke
				(width 0.1524)
				(type default)
			)
			(layer "F.SilkS")
		)
		(fp_line
			(start 0.7874 -0.4064)
			(end 0.7874 0.4064)
			(stroke
				(width 0.1524)
				(type default)
			)
			(layer "F.SilkS")
		)
		(fp_line
			(start 0.7874 0.4064)
			(end -0.7874 0.4064)
			(stroke
				(width 0.1524)
				(type default)
			)
			(layer "F.SilkS")
		)
		(fp_line
			(start -0.67945 -0.305054)
			(end -0.12065 -0.305054)
			(stroke
				(width 0.1)
				(type default)
			)
			(layer "F.Fab")
		)
		(fp_line
			(start -0.67945 0.3048)
			(end -0.67945 -0.305054)
			(stroke
				(width 0.1)
				(type default)
			)
			(layer "F.Fab")
		)
		(fp_line
			(start -0.12065 -0.305054)
			(end -0.12065 -0.2794)
			(stroke
				(width 0.1)
				(type default)
			)
			(layer "F.Fab")
		)
		(fp_line
			(start -0.12065 -0.2794)
			(end 0.12065 -0.2794)
			(stroke
				(width 0.1)
				(type default)
			)
			(layer "F.Fab")
		)
		(fp_line
			(start -0.12065 0.2794)
			(end -0.12065 0.3048)
			(stroke
				(width 0.1)
				(type default)
			)
			(layer "F.Fab")
		)
		(fp_line
			(start -0.12065 0.3048)
			(end -0.67945 0.3048)
			(stroke
				(width 0.1)
				(type default)
			)
			(layer "F.Fab")
		)
		(fp_line
			(start 0.120396 0.2794)
			(end -0.12065 0.2794)
			(stroke
				(width 0.1)
				(type default)
			)
			(layer "F.Fab")
		)
		(fp_line
			(start 0.120396 0.3048)
			(end 0.120396 0.2794)
			(stroke
				(width 0.1)
				(type default)
			)
			(layer "F.Fab")
		)
		(fp_line
			(start 0.12065 -0.3048)
			(end 0.67945 -0.3048)
			(stroke
				(width 0.1)
				(type default)
			)
			(layer "F.Fab")
		)
		(fp_line
			(start 0.12065 -0.2794)
			(end 0.12065 -0.3048)
			(stroke
				(width 0.1)
				(type default)
			)
			(layer "F.Fab")
		)
		(fp_line
			(start 0.67945 -0.3048)
			(end 0.67945 0.3048)
			(stroke
				(width 0.1)
				(type default)
			)
			(layer "F.Fab")
		)
		(fp_line
			(start 0.67945 0.3048)
			(end 0.120396 0.3048)
			(stroke
				(width 0.1)
				(type default)
			)
			(layer "F.Fab")
		)
		(pad "1" smd circle
			(at -0.40005 0)
			(size 0 0)
			(layers "F.Cu" "F.Mask" "F.Paste")
			(net "SMB_PCIE_E1S_ISO_EN")
		)
		(pad "2" smd circle
			(at 0.40005 0)
			(size 0 0)
			(layers "F.Cu" "F.Mask" "F.Paste")
			(net "SMB_PCIE_E1S_ISO_EN_R")
		)
	)
	(footprint ""
		(layer "F.Cu")
		(at 258.12496 -360.764074)
		(property "Reference" "H112"
			(at -4.58216 -9.007856 0)
			(unlocked yes)
			(layer "F.SilkS")
			(effects
				(font
					(size 0.7874 0.5842)
					(thickness 0.1524)
				)
				(justify left)
			)
		)
		(property "Value" ""
			(at 0 0 0)
			(layer "F.Fab")
			(effects
				(font
					(size 1.27 1.27)
				)
			)
		)
		(duplicate_pad_numbers_are_jumpers no)
		(fp_circle
			(center 0 0)
			(end 7.999984 0)
			(stroke
				(width 0.1524)
				(type default)
			)
			(fill no)
			(layer "F.SilkS")
		)
		(fp_circle
			(center 0 0)
			(end 7.999984 0)
			(stroke
				(width 0.1524)
				(type default)
			)
			(fill no)
			(layer "B.SilkS")
		)
		(fp_circle
			(center 0 0)
			(end 7.999984 0)
			(stroke
				(width 0.1)
				(type default)
			)
			(fill no)
			(layer "B.Fab")
		)
		(fp_circle
			(center 0 0)
			(end 7.999984 0)
			(stroke
				(width 0.1)
				(type default)
			)
			(fill no)
			(layer "F.Fab")
		)
		(pad "" np_thru_hole circle
			(at 0 0)
			(size 4.0132 4.0132)
			(drill 4.0132)
			(layers "*.Cu" "*.Mask")
			(clearance 0.381)
			(thermal_gap 0.381)
		)
		(pad "2" thru_hole circle
			(at 3.2639 0)
			(size 0.9144 0.9144)
			(drill 0.5588)
			(layers "*.Cu" "*.Mask")
			(remove_unused_layers no)
			(net "GND")
			(clearance 0.0762)
			(thermal_gap 0.0762)
		)
		(pad "3" thru_hole circle
			(at 2.307844 -2.307844)
			(size 0.9144 0.9144)
			(drill 0.5588)
			(layers "*.Cu" "*.Mask")
			(remove_unused_layers no)
			(net "GND")
			(clearance 0.0762)
			(thermal_gap 0.0762)
		)
		(pad "4" thru_hole circle
			(at 0 -3.2639)
			(size 0.9144 0.9144)
			(drill 0.5588)
			(layers "*.Cu" "*.Mask")
			(remove_unused_layers no)
			(net "GND")
			(clearance 0.0762)
			(thermal_gap 0.0762)
		)
		(pad "5" thru_hole circle
			(at -2.307844 -2.307844)
			(size 0.9144 0.9144)
			(drill 0.5588)
			(layers "*.Cu" "*.Mask")
			(remove_unused_layers no)
			(net "GND")
			(clearance 0.0762)
			(thermal_gap 0.0762)
		)
		(pad "6" thru_hole circle
			(at -3.2639 0)
			(size 0.9144 0.9144)
			(drill 0.5588)
			(layers "*.Cu" "*.Mask")
			(remove_unused_layers no)
			(net "GND")
			(clearance 0.0762)
			(thermal_gap 0.0762)
		)
		(pad "7" thru_hole circle
			(at -2.307844 2.307844)
			(size 0.9144 0.9144)
			(drill 0.5588)
			(layers "*.Cu" "*.Mask")
			(remove_unused_layers no)
			(net "GND")
			(clearance 0.0762)
			(thermal_gap 0.0762)
		)
		(pad "8" thru_hole circle
			(at 0 3.2639)
			(size 0.9144 0.9144)
			(drill 0.5588)
			(layers "*.Cu" "*.Mask")
			(remove_unused_layers no)
			(net "GND")
			(clearance 0.0762)
			(thermal_gap 0.0762)
		)
		(pad "9" thru_hole circle
			(at 2.307844 2.307844)
			(size 0.9144 0.9144)
			(drill 0.5588)
			(layers "*.Cu" "*.Mask")
			(remove_unused_layers no)
			(net "GND")
			(clearance 0.0762)
			(thermal_gap 0.0762)
		)
		(zone
			(layer "F.Cu")
			(hatch none 0.5)
			(connect_pads
				(clearance 0)
			)
			(min_thickness 0.25)
			(keepout
				(tracks not_allowed)
				(vias allowed)
				(pads allowed)
				(copperpour not_allowed)
				(footprints allowed)
			)
			(placement
				(enabled no)
				(sheetname "")
			)
			(fill
				(thermal_gap 0.5)
				(thermal_bridge_width 0.5)
				(island_removal_mode 0)
			)
			(polygon
				(pts
					(arc
						(start 258.12496 -356.496874)
						(mid 253.85776 -360.764074)
						(end 258.12496 -365.031274)
					)
					(arc
						(start 258.12496 -368.764058)
						(mid 252.468117 -366.420917)
						(end 250.124976 -360.764074)
					)
					(arc
						(start 250.124976 -360.764074)
						(mid 252.468117 -355.107231)
						(end 258.12496 -352.76409)
					)
				)
			)
		)
		(zone
			(layer "F.Cu")
			(hatch none 0.5)
			(connect_pads
				(clearance 0)
			)
			(min_thickness 0.25)
			(keepout
				(tracks not_allowed)
				(vias allowed)
				(pads allowed)
				(copperpour not_allowed)
				(footprints allowed)
			)
			(placement
				(enabled no)
				(sheetname "")
			)
			(fill
				(thermal_gap 0.5)
				(thermal_bridge_width 0.5)
				(island_removal_mode 0)
			)
			(polygon
				(pts
					(arc
						(start 258.12496 -356.496874)
						(mid 262.39216 -360.764074)
						(end 258.12496 -365.031274)
					)
					(arc
						(start 258.12496 -368.764058)
						(mid 263.781803 -366.420917)
						(end 266.124944 -360.764074)
					)
					(arc
						(start 266.124944 -360.764074)
						(mid 263.781803 -355.107231)
						(end 258.12496 -352.76409)
					)
				)
			)
		)
		(zone
			(layers "F.Cu" "B.Cu" "In1.Cu" "In2.Cu" "In3.Cu" "In4.Cu" "In5.Cu" "In6.Cu"
				"In7.Cu" "In8.Cu" "In9.Cu" "In10.Cu" "In11.Cu" "In12.Cu" "In13.Cu" "In14.Cu"
				"In15.Cu" "In16.Cu"
			)
			(hatch none 0.5)
			(connect_pads
				(clearance 0)
			)
			(min_thickness 0.25)
			(keepout
				(tracks not_allowed)
				(vias allowed)
				(pads allowed)
				(copperpour not_allowed)
				(footprints allowed)
			)
			(placement
				(enabled no)
				(sheetname "")
			)
			(fill
				(thermal_gap 0.5)
				(thermal_bridge_width 0.5)
				(island_removal_mode 0)
			)
			(polygon
				(pts
					(arc
						(start 260.63702 -360.764074)
						(mid 255.6129 -360.764074)
						(end 260.63702 -360.764074)
					)
				)
			)
		)
	)
	(footprint ""
		(layer "F.Cu")
		(at 395.751558 -323.796152 90)
		(property "Reference" "R1503"
			(at 0 0 90)
			(layer "F.SilkS")
			(hide yes)
			(effects
				(font
					(size 1.27 1.27)
				)
			)
		)
		(property "Value" ""
			(at 0 0 90)
			(layer "F.Fab")
			(effects
				(font
					(size 1.27 1.27)
				)
			)
		)
		(duplicate_pad_numbers_are_jumpers no)
		(fp_line
			(start 0.7874 -0.4064)
			(end 0.7874 0.4064)
			(stroke
				(width 0.1524)
				(type default)
			)
			(layer "F.SilkS")
		)
		(fp_line
			(start -0.7874 -0.4064)
			(end 0.7874 -0.4064)
			(stroke
				(width 0.1524)
				(type default)
			)
			(layer "F.SilkS")
		)
		(fp_line
			(start 0.7874 0.4064)
			(end -0.7874 0.4064)
			(stroke
				(width 0.1524)
				(type default)
			)
			(layer "F.SilkS")
		)
		(fp_line
			(start -0.7874 0.4064)
			(end -0.7874 -0.4064)
			(stroke
				(width 0.1524)
				(type default)
			)
			(layer "F.SilkS")
		)
		(fp_line
			(start -0.12065 -0.305054)
			(end -0.12065 -0.2794)
			(stroke
				(width 0.1)
				(type default)
			)
			(layer "F.Fab")
		)
		(fp_line
			(start -0.67945 -0.305054)
			(end -0.12065 -0.305054)
			(stroke
				(width 0.1)
				(type default)
			)
			(layer "F.Fab")
		)
		(fp_line
			(start 0.67945 -0.3048)
			(end 0.67945 0.3048)
			(stroke
				(width 0.1)
				(type default)
			)
			(layer "F.Fab")
		)
		(fp_line
			(start 0.12065 -0.3048)
			(end 0.67945 -0.3048)
			(stroke
				(width 0.1)
				(type default)
			)
			(layer "F.Fab")
		)
		(fp_line
			(start 0.12065 -0.2794)
			(end 0.12065 -0.3048)
			(stroke
				(width 0.1)
				(type default)
			)
			(layer "F.Fab")
		)
		(fp_line
			(start -0.12065 -0.2794)
			(end 0.12065 -0.2794)
			(stroke
				(width 0.1)
				(type default)
			)
			(layer "F.Fab")
		)
		(fp_line
			(start 0.120396 0.2794)
			(end -0.12065 0.2794)
			(stroke
				(width 0.1)
				(type default)
			)
			(layer "F.Fab")
		)
		(fp_line
			(start -0.12065 0.2794)
			(end -0.12065 0.3048)
			(stroke
				(width 0.1)
				(type default)
			)
			(layer "F.Fab")
		)
		(fp_line
			(start 0.67945 0.3048)
			(end 0.120396 0.3048)
			(stroke
				(width 0.1)
				(type default)
			)
			(layer "F.Fab")
		)
		(fp_line
			(start 0.120396 0.3048)
			(end 0.120396 0.2794)
			(stroke
				(width 0.1)
				(type default)
			)
			(layer "F.Fab")
		)
		(fp_line
			(start -0.12065 0.3048)
			(end -0.67945 0.3048)
			(stroke
				(width 0.1)
				(type default)
			)
			(layer "F.Fab")
		)
		(fp_line
			(start -0.67945 0.3048)
			(end -0.67945 -0.305054)
			(stroke
				(width 0.1)
				(type default)
			)
			(layer "F.Fab")
		)
		(pad "1" smd circle
			(at -0.40005 0 90)
			(size 0 0)
			(layers "F.Cu" "F.Mask" "F.Paste")
			(net "PVDD18_S5_P0")
		)
		(pad "2" smd circle
			(at 0.40005 0 90)
			(size 0 0)
			(layers "F.Cu" "F.Mask" "F.Paste")
			(net "ESPI_CPU0_D0")
		)
	)
	(footprint ""
		(layer "F.Cu")
		(at 30.936692 -397.396462)
		(property "Reference" "PC6637_2"
			(at 0 0 0)
			(layer "F.SilkS")
			(hide yes)
			(effects
				(font
					(size 1.27 1.27)
				)
			)
		)
		(property "Value" ""
			(at 0 0 0)
			(layer "F.Fab")
			(effects
				(font
					(size 1.27 1.27)
				)
			)
		)
		(duplicate_pad_numbers_are_jumpers no)
		(fp_line
			(start -1.524 -0.762)
			(end 1.524 -0.762)
			(stroke
				(width 0.1524)
				(type default)
			)
			(layer "F.SilkS")
		)
		(fp_line
			(start -1.524 0.762)
			(end -1.524 -0.762)
			(stroke
				(width 0.1524)
				(type default)
			)
			(layer "F.SilkS")
		)
		(fp_line
			(start 1.524 -0.762)
			(end 1.524 0.762)
			(stroke
				(width 0.1524)
				(type default)
			)
			(layer "F.SilkS")
		)
		(fp_line
			(start 1.524 0.762)
			(end -1.524 0.762)
			(stroke
				(width 0.1524)
				(type default)
			)
			(layer "F.SilkS")
		)
		(fp_line
			(start -1.1049 -0.724916)
			(end -1.1049 0.724916)
			(stroke
				(width 0.1)
				(type default)
			)
			(layer "F.Fab")
		)
		(fp_line
			(start -1.1049 0.724916)
			(end 1.1049 0.724916)
			(stroke
				(width 0.1)
				(type default)
			)
			(layer "F.Fab")
		)
		(fp_line
			(start 1.1049 -0.724916)
			(end -1.1049 -0.724916)
			(stroke
				(width 0.1)
				(type default)
			)
			(layer "F.Fab")
		)
		(fp_line
			(start 1.1049 0.724916)
			(end 1.1049 -0.724916)
			(stroke
				(width 0.1)
				(type default)
			)
			(layer "F.Fab")
		)
		(pad "1" smd rect
			(at -0.889 0 180)
			(size 1.016 1.27)
			(layers "F.Cu" "F.Mask" "F.Paste")
			(net "SW_P12V_AUX_P0V9_RETIMER_CPU1_FLT")
		)
		(pad "2" smd rect
			(at 0.889 0 180)
			(size 1.016 1.27)
			(layers "F.Cu" "F.Mask" "F.Paste")
			(net "GND")
		)
	)
	(footprint ""
		(layer "F.Cu")
		(at 140.886942 -105.225596)
		(property "Reference" "R3296"
			(at 0 0 0)
			(layer "F.SilkS")
			(hide yes)
			(effects
				(font
					(size 1.27 1.27)
				)
			)
		)
		(property "Value" ""
			(at 0 0 0)
			(layer "F.Fab")
			(effects
				(font
					(size 1.27 1.27)
				)
			)
		)
		(duplicate_pad_numbers_are_jumpers no)
		(fp_line
			(start -0.7874 -0.4064)
			(end 0.7874 -0.4064)
			(stroke
				(width 0.1524)
				(type default)
			)
			(layer "F.SilkS")
		)
		(fp_line
			(start -0.7874 0.4064)
			(end -0.7874 -0.4064)
			(stroke
				(width 0.1524)
				(type default)
			)
			(layer "F.SilkS")
		)
		(fp_line
			(start 0.7874 -0.4064)
			(end 0.7874 0.4064)
			(stroke
				(width 0.1524)
				(type default)
			)
			(layer "F.SilkS")
		)
		(fp_line
			(start 0.7874 0.4064)
			(end -0.7874 0.4064)
			(stroke
				(width 0.1524)
				(type default)
			)
			(layer "F.SilkS")
		)
		(fp_line
			(start -0.67945 -0.305054)
			(end -0.12065 -0.305054)
			(stroke
				(width 0.1)
				(type default)
			)
			(layer "F.Fab")
		)
		(fp_line
			(start -0.67945 0.3048)
			(end -0.67945 -0.305054)
			(stroke
				(width 0.1)
				(type default)
			)
			(layer "F.Fab")
		)
		(fp_line
			(start -0.12065 -0.305054)
			(end -0.12065 -0.2794)
			(stroke
				(width 0.1)
				(type default)
			)
			(layer "F.Fab")
		)
		(fp_line
			(start -0.12065 -0.2794)
			(end 0.12065 -0.2794)
			(stroke
				(width 0.1)
				(type default)
			)
			(layer "F.Fab")
		)
		(fp_line
			(start -0.12065 0.2794)
			(end -0.12065 0.3048)
			(stroke
				(width 0.1)
				(type default)
			)
			(layer "F.Fab")
		)
		(fp_line
			(start -0.12065 0.3048)
			(end -0.67945 0.3048)
			(stroke
				(width 0.1)
				(type default)
			)
			(layer "F.Fab")
		)
		(fp_line
			(start 0.120396 0.2794)
			(end -0.12065 0.2794)
			(stroke
				(width 0.1)
				(type default)
			)
			(layer "F.Fab")
		)
		(fp_line
			(start 0.120396 0.3048)
			(end 0.120396 0.2794)
			(stroke
				(width 0.1)
				(type default)
			)
			(layer "F.Fab")
		)
		(fp_line
			(start 0.12065 -0.3048)
			(end 0.67945 -0.3048)
			(stroke
				(width 0.1)
				(type default)
			)
			(layer "F.Fab")
		)
		(fp_line
			(start 0.12065 -0.2794)
			(end 0.12065 -0.3048)
			(stroke
				(width 0.1)
				(type default)
			)
			(layer "F.Fab")
		)
		(fp_line
			(start 0.67945 -0.3048)
			(end 0.67945 0.3048)
			(stroke
				(width 0.1)
				(type default)
			)
			(layer "F.Fab")
		)
		(fp_line
			(start 0.67945 0.3048)
			(end 0.120396 0.3048)
			(stroke
				(width 0.1)
				(type default)
			)
			(layer "F.Fab")
		)
		(pad "1" smd circle
			(at -0.40005 0)
			(size 0 0)
			(layers "F.Cu" "F.Mask" "F.Paste")
			(net "P3V3_AUX")
		)
		(pad "2" smd circle
			(at 0.40005 0)
			(size 0 0)
			(layers "F.Cu" "F.Mask" "F.Paste")
			(net "HDD_ACTIVITY_BUF")
		)
	)
	(footprint ""
		(layer "F.Cu")
		(at 393.363958 -326.691752)
		(property "Reference" "R212"
			(at 0 0 0)
			(layer "F.SilkS")
			(hide yes)
			(effects
				(font
					(size 1.27 1.27)
				)
			)
		)
		(property "Value" ""
			(at 0 0 0)
			(layer "F.Fab")
			(effects
				(font
					(size 1.27 1.27)
				)
			)
		)
		(duplicate_pad_numbers_are_jumpers no)
		(fp_line
			(start -0.7874 -0.4064)
			(end 0.7874 -0.4064)
			(stroke
				(width 0.1524)
				(type default)
			)
			(layer "F.SilkS")
		)
		(fp_line
			(start -0.7874 0.4064)
			(end -0.7874 -0.4064)
			(stroke
				(width 0.1524)
				(type default)
			)
			(layer "F.SilkS")
		)
		(fp_line
			(start 0.7874 -0.4064)
			(end 0.7874 0.4064)
			(stroke
				(width 0.1524)
				(type default)
			)
			(layer "F.SilkS")
		)
		(fp_line
			(start 0.7874 0.4064)
			(end -0.7874 0.4064)
			(stroke
				(width 0.1524)
				(type default)
			)
			(layer "F.SilkS")
		)
		(fp_line
			(start -0.67945 -0.305054)
			(end -0.12065 -0.305054)
			(stroke
				(width 0.1)
				(type default)
			)
			(layer "F.Fab")
		)
		(fp_line
			(start -0.67945 0.3048)
			(end -0.67945 -0.305054)
			(stroke
				(width 0.1)
				(type default)
			)
			(layer "F.Fab")
		)
		(fp_line
			(start -0.12065 -0.305054)
			(end -0.12065 -0.2794)
			(stroke
				(width 0.1)
				(type default)
			)
			(layer "F.Fab")
		)
		(fp_line
			(start -0.12065 -0.2794)
			(end 0.12065 -0.2794)
			(stroke
				(width 0.1)
				(type default)
			)
			(layer "F.Fab")
		)
		(fp_line
			(start -0.12065 0.2794)
			(end -0.12065 0.3048)
			(stroke
				(width 0.1)
				(type default)
			)
			(layer "F.Fab")
		)
		(fp_line
			(start -0.12065 0.3048)
			(end -0.67945 0.3048)
			(stroke
				(width 0.1)
				(type default)
			)
			(layer "F.Fab")
		)
		(fp_line
			(start 0.120396 0.2794)
			(end -0.12065 0.2794)
			(stroke
				(width 0.1)
				(type default)
			)
			(layer "F.Fab")
		)
		(fp_line
			(start 0.120396 0.3048)
			(end 0.120396 0.2794)
			(stroke
				(width 0.1)
				(type default)
			)
			(layer "F.Fab")
		)
		(fp_line
			(start 0.12065 -0.3048)
			(end 0.67945 -0.3048)
			(stroke
				(width 0.1)
				(type default)
			)
			(layer "F.Fab")
		)
		(fp_line
			(start 0.12065 -0.2794)
			(end 0.12065 -0.3048)
			(stroke
				(width 0.1)
				(type default)
			)
			(layer "F.Fab")
		)
		(fp_line
			(start 0.67945 -0.3048)
			(end 0.67945 0.3048)
			(stroke
				(width 0.1)
				(type default)
			)
			(layer "F.Fab")
		)
		(fp_line
			(start 0.67945 0.3048)
			(end 0.120396 0.3048)
			(stroke
				(width 0.1)
				(type default)
			)
			(layer "F.Fab")
		)
		(pad "1" smd circle
			(at -0.40005 0)
			(size 0 0)
			(layers "F.Cu" "F.Mask" "F.Paste")
			(net "SMB_CPU_5_R_SCL")
		)
		(pad "2" smd circle
			(at 0.40005 0)
			(size 0 0)
			(layers "F.Cu" "F.Mask" "F.Paste")
			(net "SMB_CPU_5_SCL")
		)
	)
	(footprint ""
		(layer "F.Cu")
		(at 106.71175 -166.626032)
		(property "Reference" "H43"
			(at -5.286502 -3.414776 0)
			(unlocked yes)
			(layer "F.SilkS")
			(effects
				(font
					(size 0.7874 0.5842)
					(thickness 0.1524)
				)
				(justify left)
			)
		)
		(property "Value" ""
			(at 0 0 0)
			(layer "F.Fab")
			(effects
				(font
					(size 1.27 1.27)
				)
			)
		)
		(duplicate_pad_numbers_are_jumpers no)
		(pad "1" thru_hole circle
			(at 0 0)
			(size 6.1976 6.1976)
			(drill 3.7338)
			(layers "*.Cu" "*.Mask")
			(remove_unused_layers no)
			(net "GND")
			(clearance -0.9779)
			(padstack
				(mode front_inner_back)
				(layer "Inner"
					(shape circle)
					(size 5.5372 5.5372)
					(clearance -0.6477)
				)
				(layer "B.Cu"
					(shape circle)
					(size 6.1976 6.1976)
					(clearance -0.9779)
				)
			)
		)
	)
	(footprint ""
		(layer "F.Cu")
		(at 145.63344 -31.58744 90)
		(property "Reference" "C6003"
			(at 0 0 90)
			(layer "F.SilkS")
			(hide yes)
			(effects
				(font
					(size 1.27 1.27)
				)
			)
		)
		(property "Value" ""
			(at 0 0 90)
			(layer "F.Fab")
			(effects
				(font
					(size 1.27 1.27)
				)
			)
		)
		(duplicate_pad_numbers_are_jumpers no)
		(fp_line
			(start 0.7874 -0.4064)
			(end 0.7874 0.4064)
			(stroke
				(width 0.1524)
				(type default)
			)
			(layer "F.SilkS")
		)
		(fp_line
			(start -0.7874 -0.4064)
			(end 0.7874 -0.4064)
			(stroke
				(width 0.1524)
				(type default)
			)
			(layer "F.SilkS")
		)
		(fp_line
			(start 0.7874 0.4064)
			(end -0.7874 0.4064)
			(stroke
				(width 0.1524)
				(type default)
			)
			(layer "F.SilkS")
		)
		(fp_line
			(start -0.7874 0.4064)
			(end -0.7874 -0.4064)
			(stroke
				(width 0.1524)
				(type default)
			)
			(layer "F.SilkS")
		)
		(fp_line
			(start 0.6858 -0.3048)
			(end 0.6858 0.3048)
			(stroke
				(width 0.1)
				(type default)
			)
			(layer "F.Fab")
		)
		(fp_line
			(start 0.1016 -0.3048)
			(end 0.6858 -0.3048)
			(stroke
				(width 0.1)
				(type default)
			)
			(layer "F.Fab")
		)
		(fp_line
			(start -0.1016 -0.3048)
			(end -0.1016 -0.2794)
			(stroke
				(width 0.1)
				(type default)
			)
			(layer "F.Fab")
		)
		(fp_line
			(start -0.6858 -0.3048)
			(end -0.1016 -0.3048)
			(stroke
				(width 0.1)
				(type default)
			)
			(layer "F.Fab")
		)
		(fp_line
			(start 0.1016 -0.2794)
			(end 0.1016 -0.3048)
			(stroke
				(width 0.1)
				(type default)
			)
			(layer "F.Fab")
		)
		(fp_line
			(start -0.1016 -0.2794)
			(end 0.1016 -0.2794)
			(stroke
				(width 0.1)
				(type default)
			)
			(layer "F.Fab")
		)
		(fp_line
			(start 0.1016 0.2794)
			(end -0.1016 0.2794)
			(stroke
				(width 0.1)
				(type default)
			)
			(layer "F.Fab")
		)
		(fp_line
			(start -0.1016 0.2794)
			(end -0.1016 0.3048)
			(stroke
				(width 0.1)
				(type default)
			)
			(layer "F.Fab")
		)
		(fp_line
			(start 0.6858 0.3048)
			(end 0.1016 0.3048)
			(stroke
				(width 0.1)
				(type default)
			)
			(layer "F.Fab")
		)
		(fp_line
			(start 0.1016 0.3048)
			(end 0.1016 0.2794)
			(stroke
				(width 0.1)
				(type default)
			)
			(layer "F.Fab")
		)
		(fp_line
			(start -0.1016 0.3048)
			(end -0.6858 0.3048)
			(stroke
				(width 0.1)
				(type default)
			)
			(layer "F.Fab")
		)
		(fp_line
			(start -0.6858 0.3048)
			(end -0.6858 -0.3048)
			(stroke
				(width 0.1)
				(type default)
			)
			(layer "F.Fab")
		)
		(pad "1" smd rect
			(at -0.40005 0 270)
			(size 0.4572 0.508)
			(layers "F.Cu" "F.Mask" "F.Paste")
			(net "USB3_CPU0_BMC_TX_DP")
		)
		(pad "2" smd rect
			(at 0.40005 0 270)
			(size 0.4572 0.508)
			(layers "F.Cu" "F.Mask" "F.Paste")
			(net "USB3_CPU0_BMC_TX_C1_DP")
		)
	)
	(footprint ""
		(layer "F.Cu")
		(at 204.7621 -404.020782)
		(property "Reference" "PC2182"
			(at 0 0 0)
			(layer "F.SilkS")
			(hide yes)
			(effects
				(font
					(size 1.27 1.27)
				)
			)
		)
		(property "Value" ""
			(at 0 0 0)
			(layer "F.Fab")
			(effects
				(font
					(size 1.27 1.27)
				)
			)
		)
		(duplicate_pad_numbers_are_jumpers no)
		(fp_line
			(start -0.7874 -0.4064)
			(end 0.7874 -0.4064)
			(stroke
				(width 0.1524)
				(type default)
			)
			(layer "F.SilkS")
		)
		(fp_line
			(start -0.7874 0.4064)
			(end -0.7874 -0.4064)
			(stroke
				(width 0.1524)
				(type default)
			)
			(layer "F.SilkS")
		)
		(fp_line
			(start 0.7874 -0.4064)
			(end 0.7874 0.4064)
			(stroke
				(width 0.1524)
				(type default)
			)
			(layer "F.SilkS")
		)
		(fp_line
			(start 0.7874 0.4064)
			(end -0.7874 0.4064)
			(stroke
				(width 0.1524)
				(type default)
			)
			(layer "F.SilkS")
		)
		(fp_line
			(start -0.67945 -0.305054)
			(end -0.12065 -0.305054)
			(stroke
				(width 0.1)
				(type default)
			)
			(layer "F.Fab")
		)
		(fp_line
			(start -0.67945 0.3048)
			(end -0.67945 -0.305054)
			(stroke
				(width 0.1)
				(type default)
			)
			(layer "F.Fab")
		)
		(fp_line
			(start -0.12065 -0.305054)
			(end -0.12065 -0.2794)
			(stroke
				(width 0.1)
				(type default)
			)
			(layer "F.Fab")
		)
		(fp_line
			(start -0.12065 -0.2794)
			(end 0.12065 -0.2794)
			(stroke
				(width 0.1)
				(type default)
			)
			(layer "F.Fab")
		)
		(fp_line
			(start -0.12065 0.2794)
			(end -0.12065 0.3048)
			(stroke
				(width 0.1)
				(type default)
			)
			(layer "F.Fab")
		)
		(fp_line
			(start -0.12065 0.3048)
			(end -0.67945 0.3048)
			(stroke
				(width 0.1)
				(type default)
			)
			(layer "F.Fab")
		)
		(fp_line
			(start 0.120396 0.2794)
			(end -0.12065 0.2794)
			(stroke
				(width 0.1)
				(type default)
			)
			(layer "F.Fab")
		)
		(fp_line
			(start 0.120396 0.3048)
			(end 0.120396 0.2794)
			(stroke
				(width 0.1)
				(type default)
			)
			(layer "F.Fab")
		)
		(fp_line
			(start 0.12065 -0.3048)
			(end 0.67945 -0.3048)
			(stroke
				(width 0.1)
				(type default)
			)
			(layer "F.Fab")
		)
		(fp_line
			(start 0.12065 -0.2794)
			(end 0.12065 -0.3048)
			(stroke
				(width 0.1)
				(type default)
			)
			(layer "F.Fab")
		)
		(fp_line
			(start 0.67945 -0.3048)
			(end 0.67945 0.3048)
			(stroke
				(width 0.1)
				(type default)
			)
			(layer "F.Fab")
		)
		(fp_line
			(start 0.67945 0.3048)
			(end 0.120396 0.3048)
			(stroke
				(width 0.1)
				(type default)
			)
			(layer "F.Fab")
		)
		(pad "1" smd circle
			(at -0.40005 0)
			(size 0 0)
			(layers "F.Cu" "F.Mask" "F.Paste")
			(net "HSC_ON")
		)
		(pad "2" smd circle
			(at 0.40005 0)
			(size 0 0)
			(layers "F.Cu" "F.Mask" "F.Paste")
			(net "AGND_HSC")
		)
	)
	(footprint ""
		(layer "F.Cu")
		(at 296.215562 -19.247358 -90)
		(property "Reference" "C1564"
			(at 0 0 270)
			(layer "F.SilkS")
			(hide yes)
			(effects
				(font
					(size 1.27 1.27)
				)
			)
		)
		(property "Value" ""
			(at 0 0 270)
			(layer "F.Fab")
			(effects
				(font
					(size 1.27 1.27)
				)
			)
		)
		(duplicate_pad_numbers_are_jumpers no)
		(fp_line
			(start -0.7874 0.4064)
			(end -0.7874 -0.4064)
			(stroke
				(width 0.1524)
				(type default)
			)
			(layer "F.SilkS")
		)
		(fp_line
			(start 0.7874 0.4064)
			(end -0.7874 0.4064)
			(stroke
				(width 0.1524)
				(type default)
			)
			(layer "F.SilkS")
		)
		(fp_line
			(start -0.7874 -0.4064)
			(end 0.7874 -0.4064)
			(stroke
				(width 0.1524)
				(type default)
			)
			(layer "F.SilkS")
		)
		(fp_line
			(start 0.7874 -0.4064)
			(end 0.7874 0.4064)
			(stroke
				(width 0.1524)
				(type default)
			)
			(layer "F.SilkS")
		)
		(fp_line
			(start -0.67945 0.3048)
			(end -0.67945 -0.305054)
			(stroke
				(width 0.1)
				(type default)
			)
			(layer "F.Fab")
		)
		(fp_line
			(start -0.12065 0.3048)
			(end -0.67945 0.3048)
			(stroke
				(width 0.1)
				(type default)
			)
			(layer "F.Fab")
		)
		(fp_line
			(start 0.120396 0.3048)
			(end 0.120396 0.2794)
			(stroke
				(width 0.1)
				(type default)
			)
			(layer "F.Fab")
		)
		(fp_line
			(start 0.67945 0.3048)
			(end 0.120396 0.3048)
			(stroke
				(width 0.1)
				(type default)
			)
			(layer "F.Fab")
		)
		(fp_line
			(start -0.12065 0.2794)
			(end -0.12065 0.3048)
			(stroke
				(width 0.1)
				(type default)
			)
			(layer "F.Fab")
		)
		(fp_line
			(start 0.120396 0.2794)
			(end -0.12065 0.2794)
			(stroke
				(width 0.1)
				(type default)
			)
			(layer "F.Fab")
		)
		(fp_line
			(start -0.12065 -0.2794)
			(end 0.12065 -0.2794)
			(stroke
				(width 0.1)
				(type default)
			)
			(layer "F.Fab")
		)
		(fp_line
			(start 0.12065 -0.2794)
			(end 0.12065 -0.3048)
			(stroke
				(width 0.1)
				(type default)
			)
			(layer "F.Fab")
		)
		(fp_line
			(start 0.12065 -0.3048)
			(end 0.67945 -0.3048)
			(stroke
				(width 0.1)
				(type default)
			)
			(layer "F.Fab")
		)
		(fp_line
			(start 0.67945 -0.3048)
			(end 0.67945 0.3048)
			(stroke
				(width 0.1)
				(type default)
			)
			(layer "F.Fab")
		)
		(fp_line
			(start -0.67945 -0.305054)
			(end -0.12065 -0.305054)
			(stroke
				(width 0.1)
				(type default)
			)
			(layer "F.Fab")
		)
		(fp_line
			(start -0.12065 -0.305054)
			(end -0.12065 -0.2794)
			(stroke
				(width 0.1)
				(type default)
			)
			(layer "F.Fab")
		)
		(pad "1" smd circle
			(at -0.40005 0 270)
			(size 0 0)
			(layers "F.Cu" "F.Mask" "F.Paste")
			(net "P1V5_BAT_OUT")
		)
		(pad "2" smd circle
			(at 0.40005 0 270)
			(size 0 0)
			(layers "F.Cu" "F.Mask" "F.Paste")
			(net "GND")
		)
	)
	(footprint ""
		(layer "F.Cu")
		(at 116.331238 -41.17975 90)
		(property "Reference" "R6284"
			(at 0 0 90)
			(layer "F.SilkS")
			(hide yes)
			(effects
				(font
					(size 1.27 1.27)
				)
			)
		)
		(property "Value" ""
			(at 0 0 90)
			(layer "F.Fab")
			(effects
				(font
					(size 1.27 1.27)
				)
			)
		)
		(duplicate_pad_numbers_are_jumpers no)
		(fp_line
			(start 0.7874 -0.4064)
			(end 0.7874 0.4064)
			(stroke
				(width 0.1524)
				(type default)
			)
			(layer "F.SilkS")
		)
		(fp_line
			(start -0.7874 -0.4064)
			(end 0.7874 -0.4064)
			(stroke
				(width 0.1524)
				(type default)
			)
			(layer "F.SilkS")
		)
		(fp_line
			(start 0.7874 0.4064)
			(end -0.7874 0.4064)
			(stroke
				(width 0.1524)
				(type default)
			)
			(layer "F.SilkS")
		)
		(fp_line
			(start -0.7874 0.4064)
			(end -0.7874 -0.4064)
			(stroke
				(width 0.1524)
				(type default)
			)
			(layer "F.SilkS")
		)
		(fp_line
			(start -0.12065 -0.305054)
			(end -0.12065 -0.2794)
			(stroke
				(width 0.1)
				(type default)
			)
			(layer "F.Fab")
		)
		(fp_line
			(start -0.67945 -0.305054)
			(end -0.12065 -0.305054)
			(stroke
				(width 0.1)
				(type default)
			)
			(layer "F.Fab")
		)
		(fp_line
			(start 0.67945 -0.3048)
			(end 0.67945 0.3048)
			(stroke
				(width 0.1)
				(type default)
			)
			(layer "F.Fab")
		)
		(fp_line
			(start 0.12065 -0.3048)
			(end 0.67945 -0.3048)
			(stroke
				(width 0.1)
				(type default)
			)
			(layer "F.Fab")
		)
		(fp_line
			(start 0.12065 -0.2794)
			(end 0.12065 -0.3048)
			(stroke
				(width 0.1)
				(type default)
			)
			(layer "F.Fab")
		)
		(fp_line
			(start -0.12065 -0.2794)
			(end 0.12065 -0.2794)
			(stroke
				(width 0.1)
				(type default)
			)
			(layer "F.Fab")
		)
		(fp_line
			(start 0.120396 0.2794)
			(end -0.12065 0.2794)
			(stroke
				(width 0.1)
				(type default)
			)
			(layer "F.Fab")
		)
		(fp_line
			(start -0.12065 0.2794)
			(end -0.12065 0.3048)
			(stroke
				(width 0.1)
				(type default)
			)
			(layer "F.Fab")
		)
		(fp_line
			(start 0.67945 0.3048)
			(end 0.120396 0.3048)
			(stroke
				(width 0.1)
				(type default)
			)
			(layer "F.Fab")
		)
		(fp_line
			(start 0.120396 0.3048)
			(end 0.120396 0.2794)
			(stroke
				(width 0.1)
				(type default)
			)
			(layer "F.Fab")
		)
		(fp_line
			(start -0.12065 0.3048)
			(end -0.67945 0.3048)
			(stroke
				(width 0.1)
				(type default)
			)
			(layer "F.Fab")
		)
		(fp_line
			(start -0.67945 0.3048)
			(end -0.67945 -0.305054)
			(stroke
				(width 0.1)
				(type default)
			)
			(layer "F.Fab")
		)
		(pad "1" smd circle
			(at -0.40005 0 90)
			(size 0 0)
			(layers "F.Cu" "F.Mask" "F.Paste")
			(net "USB_HUB2_TI_FULLPWRMGMTZ_MRP_PROG_FUNC3")
		)
		(pad "2" smd circle
			(at 0.40005 0 90)
			(size 0 0)
			(layers "F.Cu" "F.Mask" "F.Paste")
			(net "GND")
		)
	)
	(footprint ""
		(layer "F.Cu")
		(at 254.592836 -123.10745)
		(property "Reference" "R3724"
			(at 0 0 0)
			(layer "F.SilkS")
			(hide yes)
			(effects
				(font
					(size 1.27 1.27)
				)
			)
		)
		(property "Value" ""
			(at 0 0 0)
			(layer "F.Fab")
			(effects
				(font
					(size 1.27 1.27)
				)
			)
		)
		(duplicate_pad_numbers_are_jumpers no)
		(fp_line
			(start -0.7874 -0.4064)
			(end 0.7874 -0.4064)
			(stroke
				(width 0.1524)
				(type default)
			)
			(layer "F.SilkS")
		)
		(fp_line
			(start -0.7874 0.4064)
			(end -0.7874 -0.4064)
			(stroke
				(width 0.1524)
				(type default)
			)
			(layer "F.SilkS")
		)
		(fp_line
			(start 0.7874 -0.4064)
			(end 0.7874 0.4064)
			(stroke
				(width 0.1524)
				(type default)
			)
			(layer "F.SilkS")
		)
		(fp_line
			(start 0.7874 0.4064)
			(end -0.7874 0.4064)
			(stroke
				(width 0.1524)
				(type default)
			)
			(layer "F.SilkS")
		)
		(fp_line
			(start -0.67945 -0.305054)
			(end -0.12065 -0.305054)
			(stroke
				(width 0.1)
				(type default)
			)
			(layer "F.Fab")
		)
		(fp_line
			(start -0.67945 0.3048)
			(end -0.67945 -0.305054)
			(stroke
				(width 0.1)
				(type default)
			)
			(layer "F.Fab")
		)
		(fp_line
			(start -0.12065 -0.305054)
			(end -0.12065 -0.2794)
			(stroke
				(width 0.1)
				(type default)
			)
			(layer "F.Fab")
		)
		(fp_line
			(start -0.12065 -0.2794)
			(end 0.12065 -0.2794)
			(stroke
				(width 0.1)
				(type default)
			)
			(layer "F.Fab")
		)
		(fp_line
			(start -0.12065 0.2794)
			(end -0.12065 0.3048)
			(stroke
				(width 0.1)
				(type default)
			)
			(layer "F.Fab")
		)
		(fp_line
			(start -0.12065 0.3048)
			(end -0.67945 0.3048)
			(stroke
				(width 0.1)
				(type default)
			)
			(layer "F.Fab")
		)
		(fp_line
			(start 0.120396 0.2794)
			(end -0.12065 0.2794)
			(stroke
				(width 0.1)
				(type default)
			)
			(layer "F.Fab")
		)
		(fp_line
			(start 0.120396 0.3048)
			(end 0.120396 0.2794)
			(stroke
				(width 0.1)
				(type default)
			)
			(layer "F.Fab")
		)
		(fp_line
			(start 0.12065 -0.3048)
			(end 0.67945 -0.3048)
			(stroke
				(width 0.1)
				(type default)
			)
			(layer "F.Fab")
		)
		(fp_line
			(start 0.12065 -0.2794)
			(end 0.12065 -0.3048)
			(stroke
				(width 0.1)
				(type default)
			)
			(layer "F.Fab")
		)
		(fp_line
			(start 0.67945 -0.3048)
			(end 0.67945 0.3048)
			(stroke
				(width 0.1)
				(type default)
			)
			(layer "F.Fab")
		)
		(fp_line
			(start 0.67945 0.3048)
			(end 0.120396 0.3048)
			(stroke
				(width 0.1)
				(type default)
			)
			(layer "F.Fab")
		)
		(pad "1" smd circle
			(at -0.40005 0)
			(size 0 0)
			(layers "F.Cu" "F.Mask" "F.Paste")
			(net "P3V3_AUX")
		)
		(pad "2" smd circle
			(at 0.40005 0)
			(size 0 0)
			(layers "F.Cu" "F.Mask" "F.Paste")
			(net "SMB_VR_3V3AUX_SDA")
		)
	)
	(footprint ""
		(layer "F.Cu")
		(at 118.11 -401.1676)
		(property "Reference" "R1448"
			(at 0 0 0)
			(layer "F.SilkS")
			(hide yes)
			(effects
				(font
					(size 1.27 1.27)
				)
			)
		)
		(property "Value" ""
			(at 0 0 0)
			(layer "F.Fab")
			(effects
				(font
					(size 1.27 1.27)
				)
			)
		)
		(duplicate_pad_numbers_are_jumpers no)
		(fp_line
			(start -0.32512 -0.175006)
			(end 0.32512 -0.175006)
			(stroke
				(width 0.1)
				(type default)
			)
			(layer "F.Fab")
		)
		(fp_line
			(start -0.32512 0.175006)
			(end -0.32512 -0.175006)
			(stroke
				(width 0.1)
				(type default)
			)
			(layer "F.Fab")
		)
		(fp_line
			(start 0.32512 -0.175006)
			(end 0.32512 0.175006)
			(stroke
				(width 0.1)
				(type default)
			)
			(layer "F.Fab")
		)
		(fp_line
			(start 0.32512 0.175006)
			(end -0.32512 0.175006)
			(stroke
				(width 0.1)
				(type default)
			)
			(layer "F.Fab")
		)
		(pad "1" smd rect
			(at -0.2667 0)
			(size 0.3048 0.381)
			(layers "F.Cu" "F.Mask" "F.Paste")
			(net "P1V8_CPU1_RT_1D")
		)
		(pad "2" smd rect
			(at 0.2667 0 180)
			(size 0.3048 0.381)
			(layers "F.Cu" "F.Mask" "F.Paste")
			(net "SMB_RT_CPU1_P1_ROM_MUX_1D_SDA")
		)
	)
	(footprint ""
		(layer "F.Cu")
		(at 185.801 -100.294948 -90)
		(property "Reference" "R1190"
			(at 0 0 270)
			(layer "F.SilkS")
			(hide yes)
			(effects
				(font
					(size 1.27 1.27)
				)
			)
		)
		(property "Value" ""
			(at 0 0 270)
			(layer "F.Fab")
			(effects
				(font
					(size 1.27 1.27)
				)
			)
		)
		(duplicate_pad_numbers_are_jumpers no)
		(fp_line
			(start -0.7874 0.4064)
			(end -0.7874 -0.4064)
			(stroke
				(width 0.1524)
				(type default)
			)
			(layer "F.SilkS")
		)
		(fp_line
			(start 0.7874 0.4064)
			(end -0.7874 0.4064)
			(stroke
				(width 0.1524)
				(type default)
			)
			(layer "F.SilkS")
		)
		(fp_line
			(start -0.7874 -0.4064)
			(end 0.7874 -0.4064)
			(stroke
				(width 0.1524)
				(type default)
			)
			(layer "F.SilkS")
		)
		(fp_line
			(start 0.7874 -0.4064)
			(end 0.7874 0.4064)
			(stroke
				(width 0.1524)
				(type default)
			)
			(layer "F.SilkS")
		)
		(fp_line
			(start -0.67945 0.3048)
			(end -0.67945 -0.305054)
			(stroke
				(width 0.1)
				(type default)
			)
			(layer "F.Fab")
		)
		(fp_line
			(start -0.12065 0.3048)
			(end -0.67945 0.3048)
			(stroke
				(width 0.1)
				(type default)
			)
			(layer "F.Fab")
		)
		(fp_line
			(start 0.120396 0.3048)
			(end 0.120396 0.2794)
			(stroke
				(width 0.1)
				(type default)
			)
			(layer "F.Fab")
		)
		(fp_line
			(start 0.67945 0.3048)
			(end 0.120396 0.3048)
			(stroke
				(width 0.1)
				(type default)
			)
			(layer "F.Fab")
		)
		(fp_line
			(start -0.12065 0.2794)
			(end -0.12065 0.3048)
			(stroke
				(width 0.1)
				(type default)
			)
			(layer "F.Fab")
		)
		(fp_line
			(start 0.120396 0.2794)
			(end -0.12065 0.2794)
			(stroke
				(width 0.1)
				(type default)
			)
			(layer "F.Fab")
		)
		(fp_line
			(start -0.12065 -0.2794)
			(end 0.12065 -0.2794)
			(stroke
				(width 0.1)
				(type default)
			)
			(layer "F.Fab")
		)
		(fp_line
			(start 0.12065 -0.2794)
			(end 0.12065 -0.3048)
			(stroke
				(width 0.1)
				(type default)
			)
			(layer "F.Fab")
		)
		(fp_line
			(start 0.12065 -0.3048)
			(end 0.67945 -0.3048)
			(stroke
				(width 0.1)
				(type default)
			)
			(layer "F.Fab")
		)
		(fp_line
			(start 0.67945 -0.3048)
			(end 0.67945 0.3048)
			(stroke
				(width 0.1)
				(type default)
			)
			(layer "F.Fab")
		)
		(fp_line
			(start -0.67945 -0.305054)
			(end -0.12065 -0.305054)
			(stroke
				(width 0.1)
				(type default)
			)
			(layer "F.Fab")
		)
		(fp_line
			(start -0.12065 -0.305054)
			(end -0.12065 -0.2794)
			(stroke
				(width 0.1)
				(type default)
			)
			(layer "F.Fab")
		)
		(pad "1" smd circle
			(at -0.40005 0 270)
			(size 0 0)
			(layers "F.Cu" "F.Mask" "F.Paste")
			(net "PVDD11_S3_P1_PMALERT")
		)
		(pad "2" smd circle
			(at 0.40005 0 270)
			(size 0 0)
			(layers "F.Cu" "F.Mask" "F.Paste")
			(net "P3V3_AUX")
		)
	)
	(footprint ""
		(layer "F.Cu")
		(at 167.112442 -116.26977)
		(property "Reference" "R6136"
			(at 0 0 0)
			(layer "F.SilkS")
			(hide yes)
			(effects
				(font
					(size 1.27 1.27)
				)
			)
		)
		(property "Value" ""
			(at 0 0 0)
			(layer "F.Fab")
			(effects
				(font
					(size 1.27 1.27)
				)
			)
		)
		(duplicate_pad_numbers_are_jumpers no)
		(fp_line
			(start -0.7874 -0.4064)
			(end 0.7874 -0.4064)
			(stroke
				(width 0.1524)
				(type default)
			)
			(layer "F.SilkS")
		)
		(fp_line
			(start -0.7874 0.4064)
			(end -0.7874 -0.4064)
			(stroke
				(width 0.1524)
				(type default)
			)
			(layer "F.SilkS")
		)
		(fp_line
			(start 0.7874 -0.4064)
			(end 0.7874 0.4064)
			(stroke
				(width 0.1524)
				(type default)
			)
			(layer "F.SilkS")
		)
		(fp_line
			(start 0.7874 0.4064)
			(end -0.7874 0.4064)
			(stroke
				(width 0.1524)
				(type default)
			)
			(layer "F.SilkS")
		)
		(fp_line
			(start -0.67945 -0.305054)
			(end -0.12065 -0.305054)
			(stroke
				(width 0.1)
				(type default)
			)
			(layer "F.Fab")
		)
		(fp_line
			(start -0.67945 0.3048)
			(end -0.67945 -0.305054)
			(stroke
				(width 0.1)
				(type default)
			)
			(layer "F.Fab")
		)
		(fp_line
			(start -0.12065 -0.305054)
			(end -0.12065 -0.2794)
			(stroke
				(width 0.1)
				(type default)
			)
			(layer "F.Fab")
		)
		(fp_line
			(start -0.12065 -0.2794)
			(end 0.12065 -0.2794)
			(stroke
				(width 0.1)
				(type default)
			)
			(layer "F.Fab")
		)
		(fp_line
			(start -0.12065 0.2794)
			(end -0.12065 0.3048)
			(stroke
				(width 0.1)
				(type default)
			)
			(layer "F.Fab")
		)
		(fp_line
			(start -0.12065 0.3048)
			(end -0.67945 0.3048)
			(stroke
				(width 0.1)
				(type default)
			)
			(layer "F.Fab")
		)
		(fp_line
			(start 0.120396 0.2794)
			(end -0.12065 0.2794)
			(stroke
				(width 0.1)
				(type default)
			)
			(layer "F.Fab")
		)
		(fp_line
			(start 0.120396 0.3048)
			(end 0.120396 0.2794)
			(stroke
				(width 0.1)
				(type default)
			)
			(layer "F.Fab")
		)
		(fp_line
			(start 0.12065 -0.3048)
			(end 0.67945 -0.3048)
			(stroke
				(width 0.1)
				(type default)
			)
			(layer "F.Fab")
		)
		(fp_line
			(start 0.12065 -0.2794)
			(end 0.12065 -0.3048)
			(stroke
				(width 0.1)
				(type default)
			)
			(layer "F.Fab")
		)
		(fp_line
			(start 0.67945 -0.3048)
			(end 0.67945 0.3048)
			(stroke
				(width 0.1)
				(type default)
			)
			(layer "F.Fab")
		)
		(fp_line
			(start 0.67945 0.3048)
			(end 0.120396 0.3048)
			(stroke
				(width 0.1)
				(type default)
			)
			(layer "F.Fab")
		)
		(pad "1" smd circle
			(at -0.40005 0)
			(size 0 0)
			(layers "F.Cu" "F.Mask" "F.Paste")
			(net "P3V3_AUX")
		)
		(pad "2" smd circle
			(at 0.40005 0)
			(size 0 0)
			(layers "F.Cu" "F.Mask" "F.Paste")
			(net "FM_BOARD_BMC_SKU_ID4")
		)
	)
	(footprint ""
		(layer "F.Cu")
		(at 118.617746 -53.49748 180)
		(property "Reference" "R6298"
			(at 0 0 180)
			(layer "F.SilkS")
			(hide yes)
			(effects
				(font
					(size 1.27 1.27)
				)
			)
		)
		(property "Value" ""
			(at 0 0 180)
			(layer "F.Fab")
			(effects
				(font
					(size 1.27 1.27)
				)
			)
		)
		(duplicate_pad_numbers_are_jumpers no)
		(fp_line
			(start 0.7874 0.4064)
			(end -0.7874 0.4064)
			(stroke
				(width 0.1524)
				(type default)
			)
			(layer "F.SilkS")
		)
		(fp_line
			(start 0.7874 -0.4064)
			(end 0.7874 0.4064)
			(stroke
				(width 0.1524)
				(type default)
			)
			(layer "F.SilkS")
		)
		(fp_line
			(start -0.7874 0.4064)
			(end -0.7874 -0.4064)
			(stroke
				(width 0.1524)
				(type default)
			)
			(layer "F.SilkS")
		)
		(fp_line
			(start -0.7874 -0.4064)
			(end 0.7874 -0.4064)
			(stroke
				(width 0.1524)
				(type default)
			)
			(layer "F.SilkS")
		)
		(fp_line
			(start 0.67945 0.3048)
			(end 0.120396 0.3048)
			(stroke
				(width 0.1)
				(type default)
			)
			(layer "F.Fab")
		)
		(fp_line
			(start 0.67945 -0.3048)
			(end 0.67945 0.3048)
			(stroke
				(width 0.1)
				(type default)
			)
			(layer "F.Fab")
		)
		(fp_line
			(start 0.12065 -0.2794)
			(end 0.12065 -0.3048)
			(stroke
				(width 0.1)
				(type default)
			)
			(layer "F.Fab")
		)
		(fp_line
			(start 0.12065 -0.3048)
			(end 0.67945 -0.3048)
			(stroke
				(width 0.1)
				(type default)
			)
			(layer "F.Fab")
		)
		(fp_line
			(start 0.120396 0.3048)
			(end 0.120396 0.2794)
			(stroke
				(width 0.1)
				(type default)
			)
			(layer "F.Fab")
		)
		(fp_line
			(start 0.120396 0.2794)
			(end -0.12065 0.2794)
			(stroke
				(width 0.1)
				(type default)
			)
			(layer "F.Fab")
		)
		(fp_line
			(start -0.12065 0.3048)
			(end -0.67945 0.3048)
			(stroke
				(width 0.1)
				(type default)
			)
			(layer "F.Fab")
		)
		(fp_line
			(start -0.12065 0.2794)
			(end -0.12065 0.3048)
			(stroke
				(width 0.1)
				(type default)
			)
			(layer "F.Fab")
		)
		(fp_line
			(start -0.12065 -0.2794)
			(end 0.12065 -0.2794)
			(stroke
				(width 0.1)
				(type default)
			)
			(layer "F.Fab")
		)
		(fp_line
			(start -0.12065 -0.305054)
			(end -0.12065 -0.2794)
			(stroke
				(width 0.1)
				(type default)
			)
			(layer "F.Fab")
		)
		(fp_line
			(start -0.67945 0.3048)
			(end -0.67945 -0.305054)
			(stroke
				(width 0.1)
				(type default)
			)
			(layer "F.Fab")
		)
		(fp_line
			(start -0.67945 -0.305054)
			(end -0.12065 -0.305054)
			(stroke
				(width 0.1)
				(type default)
			)
			(layer "F.Fab")
		)
		(pad "1" smd circle
			(at -0.40005 0 180)
			(size 0 0)
			(layers "F.Cu" "F.Mask" "F.Paste")
			(net "P3V3_AUX")
		)
		(pad "2" smd circle
			(at 0.40005 0 180)
			(size 0 0)
			(layers "F.Cu" "F.Mask" "F.Paste")
			(net "USB_HUB2_MRP_I2C_SLV_CFG1")
		)
	)
	(footprint ""
		(layer "F.Cu")
		(at 124.633228 -50.169064 180)
		(property "Reference" "R4453"
			(at 0 0 180)
			(layer "F.SilkS")
			(hide yes)
			(effects
				(font
					(size 1.27 1.27)
				)
			)
		)
		(property "Value" ""
			(at 0 0 180)
			(layer "F.Fab")
			(effects
				(font
					(size 1.27 1.27)
				)
			)
		)
		(duplicate_pad_numbers_are_jumpers no)
		(fp_line
			(start 0.7874 0.4064)
			(end -0.7874 0.4064)
			(stroke
				(width 0.1524)
				(type default)
			)
			(layer "F.SilkS")
		)
		(fp_line
			(start 0.7874 -0.4064)
			(end 0.7874 0.4064)
			(stroke
				(width 0.1524)
				(type default)
			)
			(layer "F.SilkS")
		)
		(fp_line
			(start -0.7874 0.4064)
			(end -0.7874 -0.4064)
			(stroke
				(width 0.1524)
				(type default)
			)
			(layer "F.SilkS")
		)
		(fp_line
			(start -0.7874 -0.4064)
			(end 0.7874 -0.4064)
			(stroke
				(width 0.1524)
				(type default)
			)
			(layer "F.SilkS")
		)
		(fp_line
			(start 0.67945 0.3048)
			(end 0.120396 0.3048)
			(stroke
				(width 0.1)
				(type default)
			)
			(layer "F.Fab")
		)
		(fp_line
			(start 0.67945 -0.3048)
			(end 0.67945 0.3048)
			(stroke
				(width 0.1)
				(type default)
			)
			(layer "F.Fab")
		)
		(fp_line
			(start 0.12065 -0.2794)
			(end 0.12065 -0.3048)
			(stroke
				(width 0.1)
				(type default)
			)
			(layer "F.Fab")
		)
		(fp_line
			(start 0.12065 -0.3048)
			(end 0.67945 -0.3048)
			(stroke
				(width 0.1)
				(type default)
			)
			(layer "F.Fab")
		)
		(fp_line
			(start 0.120396 0.3048)
			(end 0.120396 0.2794)
			(stroke
				(width 0.1)
				(type default)
			)
			(layer "F.Fab")
		)
		(fp_line
			(start 0.120396 0.2794)
			(end -0.12065 0.2794)
			(stroke
				(width 0.1)
				(type default)
			)
			(layer "F.Fab")
		)
		(fp_line
			(start -0.12065 0.3048)
			(end -0.67945 0.3048)
			(stroke
				(width 0.1)
				(type default)
			)
			(layer "F.Fab")
		)
		(fp_line
			(start -0.12065 0.2794)
			(end -0.12065 0.3048)
			(stroke
				(width 0.1)
				(type default)
			)
			(layer "F.Fab")
		)
		(fp_line
			(start -0.12065 -0.2794)
			(end 0.12065 -0.2794)
			(stroke
				(width 0.1)
				(type default)
			)
			(layer "F.Fab")
		)
		(fp_line
			(start -0.12065 -0.305054)
			(end -0.12065 -0.2794)
			(stroke
				(width 0.1)
				(type default)
			)
			(layer "F.Fab")
		)
		(fp_line
			(start -0.67945 0.3048)
			(end -0.67945 -0.305054)
			(stroke
				(width 0.1)
				(type default)
			)
			(layer "F.Fab")
		)
		(fp_line
			(start -0.67945 -0.305054)
			(end -0.12065 -0.305054)
			(stroke
				(width 0.1)
				(type default)
			)
			(layer "F.Fab")
		)
		(pad "1" smd circle
			(at -0.40005 0 180)
			(size 0 0)
			(layers "F.Cu" "F.Mask" "F.Paste")
			(net "RST_USB_CPU0_HUB1_R_N")
		)
		(pad "2" smd circle
			(at 0.40005 0 180)
			(size 0 0)
			(layers "F.Cu" "F.Mask" "F.Paste")
			(net "GND")
		)
	)
	(footprint ""
		(layer "F.Cu")
		(at 389.497316 -22.789134 90)
		(property "Reference" "R42"
			(at 0 0 90)
			(layer "F.SilkS")
			(hide yes)
			(effects
				(font
					(size 1.27 1.27)
				)
			)
		)
		(property "Value" ""
			(at 0 0 90)
			(layer "F.Fab")
			(effects
				(font
					(size 1.27 1.27)
				)
			)
		)
		(duplicate_pad_numbers_are_jumpers no)
		(fp_line
			(start 0.7874 -0.4064)
			(end 0.7874 0.011684)
			(stroke
				(width 0.1524)
				(type default)
			)
			(layer "F.SilkS")
		)
		(fp_line
			(start -0.7874 -0.4064)
			(end 0.7874 -0.4064)
			(stroke
				(width 0.1524)
				(type default)
			)
			(layer "F.SilkS")
		)
		(fp_line
			(start -0.7874 0.011684)
			(end -0.7874 -0.4064)
			(stroke
				(width 0.1524)
				(type default)
			)
			(layer "F.SilkS")
		)
		(fp_line
			(start -0.12065 -0.305054)
			(end -0.12065 -0.2794)
			(stroke
				(width 0.1)
				(type default)
			)
			(layer "F.Fab")
		)
		(fp_line
			(start -0.67945 -0.305054)
			(end -0.12065 -0.305054)
			(stroke
				(width 0.1)
				(type default)
			)
			(layer "F.Fab")
		)
		(fp_line
			(start 0.67945 -0.3048)
			(end 0.67945 0.3048)
			(stroke
				(width 0.1)
				(type default)
			)
			(layer "F.Fab")
		)
		(fp_line
			(start 0.12065 -0.3048)
			(end 0.67945 -0.3048)
			(stroke
				(width 0.1)
				(type default)
			)
			(layer "F.Fab")
		)
		(fp_line
			(start 0.12065 -0.2794)
			(end 0.12065 -0.3048)
			(stroke
				(width 0.1)
				(type default)
			)
			(layer "F.Fab")
		)
		(fp_line
			(start -0.12065 -0.2794)
			(end 0.12065 -0.2794)
			(stroke
				(width 0.1)
				(type default)
			)
			(layer "F.Fab")
		)
		(fp_line
			(start 0.120396 0.2794)
			(end -0.12065 0.2794)
			(stroke
				(width 0.1)
				(type default)
			)
			(layer "F.Fab")
		)
		(fp_line
			(start -0.12065 0.2794)
			(end -0.12065 0.3048)
			(stroke
				(width 0.1)
				(type default)
			)
			(layer "F.Fab")
		)
		(fp_line
			(start 0.67945 0.3048)
			(end 0.120396 0.3048)
			(stroke
				(width 0.1)
				(type default)
			)
			(layer "F.Fab")
		)
		(fp_line
			(start 0.120396 0.3048)
			(end 0.120396 0.2794)
			(stroke
				(width 0.1)
				(type default)
			)
			(layer "F.Fab")
		)
		(fp_line
			(start -0.12065 0.3048)
			(end -0.67945 0.3048)
			(stroke
				(width 0.1)
				(type default)
			)
			(layer "F.Fab")
		)
		(fp_line
			(start -0.67945 0.3048)
			(end -0.67945 -0.305054)
			(stroke
				(width 0.1)
				(type default)
			)
			(layer "F.Fab")
		)
		(pad "1" smd circle
			(at -0.40005 0 90)
			(size 0 0)
			(layers "F.Cu" "F.Mask" "F.Paste")
			(net "USB2_P11_DN")
		)
		(pad "2" smd circle
			(at 0.40005 0 90)
			(size 0 0)
			(layers "F.Cu" "F.Mask" "F.Paste")
			(net "USB2_CPU0_P11_DN")
		)
	)
	(footprint ""
		(layer "F.Cu")
		(at 158.82874 -44.985686 90)
		(property "Reference" "R2476"
			(at 0 0 90)
			(layer "F.SilkS")
			(hide yes)
			(effects
				(font
					(size 1.27 1.27)
				)
			)
		)
		(property "Value" ""
			(at 0 0 90)
			(layer "F.Fab")
			(effects
				(font
					(size 1.27 1.27)
				)
			)
		)
		(duplicate_pad_numbers_are_jumpers no)
		(fp_line
			(start 0.7874 -0.4064)
			(end 0.7874 0.4064)
			(stroke
				(width 0.1524)
				(type default)
			)
			(layer "F.SilkS")
		)
		(fp_line
			(start -0.7874 -0.4064)
			(end 0.7874 -0.4064)
			(stroke
				(width 0.1524)
				(type default)
			)
			(layer "F.SilkS")
		)
		(fp_line
			(start 0.7874 0.4064)
			(end -0.7874 0.4064)
			(stroke
				(width 0.1524)
				(type default)
			)
			(layer "F.SilkS")
		)
		(fp_line
			(start -0.7874 0.4064)
			(end -0.7874 -0.4064)
			(stroke
				(width 0.1524)
				(type default)
			)
			(layer "F.SilkS")
		)
		(fp_line
			(start -0.12065 -0.305054)
			(end -0.12065 -0.2794)
			(stroke
				(width 0.1)
				(type default)
			)
			(layer "F.Fab")
		)
		(fp_line
			(start -0.67945 -0.305054)
			(end -0.12065 -0.305054)
			(stroke
				(width 0.1)
				(type default)
			)
			(layer "F.Fab")
		)
		(fp_line
			(start 0.67945 -0.3048)
			(end 0.67945 0.3048)
			(stroke
				(width 0.1)
				(type default)
			)
			(layer "F.Fab")
		)
		(fp_line
			(start 0.12065 -0.3048)
			(end 0.67945 -0.3048)
			(stroke
				(width 0.1)
				(type default)
			)
			(layer "F.Fab")
		)
		(fp_line
			(start 0.12065 -0.2794)
			(end 0.12065 -0.3048)
			(stroke
				(width 0.1)
				(type default)
			)
			(layer "F.Fab")
		)
		(fp_line
			(start -0.12065 -0.2794)
			(end 0.12065 -0.2794)
			(stroke
				(width 0.1)
				(type default)
			)
			(layer "F.Fab")
		)
		(fp_line
			(start 0.120396 0.2794)
			(end -0.12065 0.2794)
			(stroke
				(width 0.1)
				(type default)
			)
			(layer "F.Fab")
		)
		(fp_line
			(start -0.12065 0.2794)
			(end -0.12065 0.3048)
			(stroke
				(width 0.1)
				(type default)
			)
			(layer "F.Fab")
		)
		(fp_line
			(start 0.67945 0.3048)
			(end 0.120396 0.3048)
			(stroke
				(width 0.1)
				(type default)
			)
			(layer "F.Fab")
		)
		(fp_line
			(start 0.120396 0.3048)
			(end 0.120396 0.2794)
			(stroke
				(width 0.1)
				(type default)
			)
			(layer "F.Fab")
		)
		(fp_line
			(start -0.12065 0.3048)
			(end -0.67945 0.3048)
			(stroke
				(width 0.1)
				(type default)
			)
			(layer "F.Fab")
		)
		(fp_line
			(start -0.67945 0.3048)
			(end -0.67945 -0.305054)
			(stroke
				(width 0.1)
				(type default)
			)
			(layer "F.Fab")
		)
		(pad "1" smd circle
			(at -0.40005 0 90)
			(size 0 0)
			(layers "F.Cu" "F.Mask" "F.Paste")
			(net "SMB_PCIE_M2_0_EN")
		)
		(pad "2" smd circle
			(at 0.40005 0 90)
			(size 0 0)
			(layers "F.Cu" "F.Mask" "F.Paste")
			(net "PWRGD_P1V8_AUX_R")
		)
	)
	(footprint ""
		(layer "F.Cu")
		(at 353.900232 -259.355082)
		(property "Reference" "C2136"
			(at 0 0 0)
			(layer "F.SilkS")
			(hide yes)
			(effects
				(font
					(size 1.27 1.27)
				)
			)
		)
		(property "Value" ""
			(at 0 0 0)
			(layer "F.Fab")
			(effects
				(font
					(size 1.27 1.27)
				)
			)
		)
		(duplicate_pad_numbers_are_jumpers no)
		(fp_line
			(start -0.7874 -0.4064)
			(end 0.7874 -0.4064)
			(stroke
				(width 0.1524)
				(type default)
			)
			(layer "F.SilkS")
		)
		(fp_line
			(start -0.7874 0.4064)
			(end -0.7874 -0.4064)
			(stroke
				(width 0.1524)
				(type default)
			)
			(layer "F.SilkS")
		)
		(fp_line
			(start 0.7874 -0.4064)
			(end 0.7874 0.4064)
			(stroke
				(width 0.1524)
				(type default)
			)
			(layer "F.SilkS")
		)
		(fp_line
			(start 0.7874 0.4064)
			(end -0.7874 0.4064)
			(stroke
				(width 0.1524)
				(type default)
			)
			(layer "F.SilkS")
		)
		(fp_line
			(start -0.67945 -0.305054)
			(end -0.12065 -0.305054)
			(stroke
				(width 0.1)
				(type default)
			)
			(layer "F.Fab")
		)
		(fp_line
			(start -0.67945 0.3048)
			(end -0.67945 -0.305054)
			(stroke
				(width 0.1)
				(type default)
			)
			(layer "F.Fab")
		)
		(fp_line
			(start -0.12065 -0.305054)
			(end -0.12065 -0.2794)
			(stroke
				(width 0.1)
				(type default)
			)
			(layer "F.Fab")
		)
		(fp_line
			(start -0.12065 -0.2794)
			(end 0.12065 -0.2794)
			(stroke
				(width 0.1)
				(type default)
			)
			(layer "F.Fab")
		)
		(fp_line
			(start -0.12065 0.2794)
			(end -0.12065 0.3048)
			(stroke
				(width 0.1)
				(type default)
			)
			(layer "F.Fab")
		)
		(fp_line
			(start -0.12065 0.3048)
			(end -0.67945 0.3048)
			(stroke
				(width 0.1)
				(type default)
			)
			(layer "F.Fab")
		)
		(fp_line
			(start 0.120396 0.2794)
			(end -0.12065 0.2794)
			(stroke
				(width 0.1)
				(type default)
			)
			(layer "F.Fab")
		)
		(fp_line
			(start 0.120396 0.3048)
			(end 0.120396 0.2794)
			(stroke
				(width 0.1)
				(type default)
			)
			(layer "F.Fab")
		)
		(fp_line
			(start 0.12065 -0.3048)
			(end 0.67945 -0.3048)
			(stroke
				(width 0.1)
				(type default)
			)
			(layer "F.Fab")
		)
		(fp_line
			(start 0.12065 -0.2794)
			(end 0.12065 -0.3048)
			(stroke
				(width 0.1)
				(type default)
			)
			(layer "F.Fab")
		)
		(fp_line
			(start 0.67945 -0.3048)
			(end 0.67945 0.3048)
			(stroke
				(width 0.1)
				(type default)
			)
			(layer "F.Fab")
		)
		(fp_line
			(start 0.67945 0.3048)
			(end 0.120396 0.3048)
			(stroke
				(width 0.1)
				(type default)
			)
			(layer "F.Fab")
		)
		(pad "1" smd circle
			(at -0.40005 0)
			(size 0 0)
			(layers "F.Cu" "F.Mask" "F.Paste")
			(net "PVDDIO_P0")
		)
		(pad "2" smd circle
			(at 0.40005 0)
			(size 0 0)
			(layers "F.Cu" "F.Mask" "F.Paste")
			(net "GND")
		)
	)
	(footprint ""
		(layer "F.Cu")
		(at 322.837048 -43.573954 180)
		(property "Reference" "R3686"
			(at 0 0 180)
			(layer "F.SilkS")
			(hide yes)
			(effects
				(font
					(size 1.27 1.27)
				)
			)
		)
		(property "Value" ""
			(at 0 0 180)
			(layer "F.Fab")
			(effects
				(font
					(size 1.27 1.27)
				)
			)
		)
		(duplicate_pad_numbers_are_jumpers no)
		(fp_line
			(start 0.7874 0.4064)
			(end -0.7874 0.4064)
			(stroke
				(width 0.1524)
				(type default)
			)
			(layer "F.SilkS")
		)
		(fp_line
			(start 0.7874 -0.4064)
			(end 0.7874 0.4064)
			(stroke
				(width 0.1524)
				(type default)
			)
			(layer "F.SilkS")
		)
		(fp_line
			(start -0.7874 0.4064)
			(end -0.7874 -0.4064)
			(stroke
				(width 0.1524)
				(type default)
			)
			(layer "F.SilkS")
		)
		(fp_line
			(start -0.7874 -0.4064)
			(end 0.7874 -0.4064)
			(stroke
				(width 0.1524)
				(type default)
			)
			(layer "F.SilkS")
		)
		(fp_line
			(start 0.67945 0.3048)
			(end 0.120396 0.3048)
			(stroke
				(width 0.1)
				(type default)
			)
			(layer "F.Fab")
		)
		(fp_line
			(start 0.67945 -0.3048)
			(end 0.67945 0.3048)
			(stroke
				(width 0.1)
				(type default)
			)
			(layer "F.Fab")
		)
		(fp_line
			(start 0.12065 -0.2794)
			(end 0.12065 -0.3048)
			(stroke
				(width 0.1)
				(type default)
			)
			(layer "F.Fab")
		)
		(fp_line
			(start 0.12065 -0.3048)
			(end 0.67945 -0.3048)
			(stroke
				(width 0.1)
				(type default)
			)
			(layer "F.Fab")
		)
		(fp_line
			(start 0.120396 0.3048)
			(end 0.120396 0.2794)
			(stroke
				(width 0.1)
				(type default)
			)
			(layer "F.Fab")
		)
		(fp_line
			(start 0.120396 0.2794)
			(end -0.12065 0.2794)
			(stroke
				(width 0.1)
				(type default)
			)
			(layer "F.Fab")
		)
		(fp_line
			(start -0.12065 0.3048)
			(end -0.67945 0.3048)
			(stroke
				(width 0.1)
				(type default)
			)
			(layer "F.Fab")
		)
		(fp_line
			(start -0.12065 0.2794)
			(end -0.12065 0.3048)
			(stroke
				(width 0.1)
				(type default)
			)
			(layer "F.Fab")
		)
		(fp_line
			(start -0.12065 -0.2794)
			(end 0.12065 -0.2794)
			(stroke
				(width 0.1)
				(type default)
			)
			(layer "F.Fab")
		)
		(fp_line
			(start -0.12065 -0.305054)
			(end -0.12065 -0.2794)
			(stroke
				(width 0.1)
				(type default)
			)
			(layer "F.Fab")
		)
		(fp_line
			(start -0.67945 0.3048)
			(end -0.67945 -0.305054)
			(stroke
				(width 0.1)
				(type default)
			)
			(layer "F.Fab")
		)
		(fp_line
			(start -0.67945 -0.305054)
			(end -0.12065 -0.305054)
			(stroke
				(width 0.1)
				(type default)
			)
			(layer "F.Fab")
		)
		(pad "1" smd rect
			(at -0.40005 0)
			(size 0.4572 0.508)
			(layers "F.Cu" "F.Mask" "F.Paste")
			(net "P5V_ADC")
		)
		(pad "2" smd rect
			(at 0.40005 0)
			(size 0.4572 0.508)
			(layers "F.Cu" "F.Mask" "F.Paste")
			(net "P5V_ADC_TIC")
		)
	)
	(footprint ""
		(layer "F.Cu")
		(at 38.9128 -111.45774 180)
		(property "Reference" "R1474"
			(at 0 0 180)
			(layer "F.SilkS")
			(hide yes)
			(effects
				(font
					(size 1.27 1.27)
				)
			)
		)
		(property "Value" ""
			(at 0 0 180)
			(layer "F.Fab")
			(effects
				(font
					(size 1.27 1.27)
				)
			)
		)
		(duplicate_pad_numbers_are_jumpers no)
		(fp_line
			(start 0.7874 0.4064)
			(end -0.7874 0.4064)
			(stroke
				(width 0.1524)
				(type default)
			)
			(layer "F.SilkS")
		)
		(fp_line
			(start 0.7874 -0.4064)
			(end 0.7874 0.4064)
			(stroke
				(width 0.1524)
				(type default)
			)
			(layer "F.SilkS")
		)
		(fp_line
			(start -0.7874 0.4064)
			(end -0.7874 -0.4064)
			(stroke
				(width 0.1524)
				(type default)
			)
			(layer "F.SilkS")
		)
		(fp_line
			(start -0.7874 -0.4064)
			(end 0.7874 -0.4064)
			(stroke
				(width 0.1524)
				(type default)
			)
			(layer "F.SilkS")
		)
		(fp_line
			(start 0.67945 0.3048)
			(end 0.120396 0.3048)
			(stroke
				(width 0.1)
				(type default)
			)
			(layer "F.Fab")
		)
		(fp_line
			(start 0.67945 -0.3048)
			(end 0.67945 0.3048)
			(stroke
				(width 0.1)
				(type default)
			)
			(layer "F.Fab")
		)
		(fp_line
			(start 0.12065 -0.2794)
			(end 0.12065 -0.3048)
			(stroke
				(width 0.1)
				(type default)
			)
			(layer "F.Fab")
		)
		(fp_line
			(start 0.12065 -0.3048)
			(end 0.67945 -0.3048)
			(stroke
				(width 0.1)
				(type default)
			)
			(layer "F.Fab")
		)
		(fp_line
			(start 0.120396 0.3048)
			(end 0.120396 0.2794)
			(stroke
				(width 0.1)
				(type default)
			)
			(layer "F.Fab")
		)
		(fp_line
			(start 0.120396 0.2794)
			(end -0.12065 0.2794)
			(stroke
				(width 0.1)
				(type default)
			)
			(layer "F.Fab")
		)
		(fp_line
			(start -0.12065 0.3048)
			(end -0.67945 0.3048)
			(stroke
				(width 0.1)
				(type default)
			)
			(layer "F.Fab")
		)
		(fp_line
			(start -0.12065 0.2794)
			(end -0.12065 0.3048)
			(stroke
				(width 0.1)
				(type default)
			)
			(layer "F.Fab")
		)
		(fp_line
			(start -0.12065 -0.2794)
			(end 0.12065 -0.2794)
			(stroke
				(width 0.1)
				(type default)
			)
			(layer "F.Fab")
		)
		(fp_line
			(start -0.12065 -0.305054)
			(end -0.12065 -0.2794)
			(stroke
				(width 0.1)
				(type default)
			)
			(layer "F.Fab")
		)
		(fp_line
			(start -0.67945 0.3048)
			(end -0.67945 -0.305054)
			(stroke
				(width 0.1)
				(type default)
			)
			(layer "F.Fab")
		)
		(fp_line
			(start -0.67945 -0.305054)
			(end -0.12065 -0.305054)
			(stroke
				(width 0.1)
				(type default)
			)
			(layer "F.Fab")
		)
		(pad "1" smd circle
			(at -0.40005 0 180)
			(size 0 0)
			(layers "F.Cu" "F.Mask" "F.Paste")
			(net "P12V_AUX_DSC_G2")
		)
		(pad "2" smd circle
			(at 0.40005 0 180)
			(size 0 0)
			(layers "F.Cu" "F.Mask" "F.Paste")
			(net "GND")
		)
	)
	(footprint ""
		(layer "F.Cu")
		(at 437.05018 -255.560068 180)
		(property "Reference" "J68"
			(at 1.32334 -81.844388 0)
			(unlocked yes)
			(layer "F.SilkS")
			(effects
				(font
					(size 0.7874 0.5842)
					(thickness 0.1524)
				)
			)
		)
		(property "Value" ""
			(at 0 0 180)
			(layer "F.Fab")
			(effects
				(font
					(size 1.27 1.27)
				)
			)
		)
		(duplicate_pad_numbers_are_jumpers no)
		(fp_line
			(start 3.24993 -81.000092)
			(end 3.24993 72.861932)
			(stroke
				(width 0.1524)
				(type default)
			)
			(layer "F.SilkS")
		)
		(fp_line
			(start 1.94818 81.000092)
			(end -3.24993 81.000092)
			(stroke
				(width 0.1524)
				(type default)
			)
			(layer "F.SilkS")
		)
		(fp_line
			(start -3.24993 81.000092)
			(end -3.24993 80.608932)
			(stroke
				(width 0.1524)
				(type default)
			)
			(layer "F.SilkS")
		)
		(fp_line
			(start -3.24993 72.861932)
			(end -3.24993 -81.000092)
			(stroke
				(width 0.1524)
				(type default)
			)
			(layer "F.SilkS")
		)
		(fp_line
			(start -3.24993 72.499982)
			(end 3.24993 72.499982)
			(stroke
				(width 0.1524)
				(type default)
			)
			(layer "F.SilkS")
		)
		(fp_line
			(start -3.24993 -72.499982)
			(end 3.24993 -72.499982)
			(stroke
				(width 0.1524)
				(type default)
			)
			(layer "F.SilkS")
		)
		(fp_line
			(start -3.24993 -81.000092)
			(end 3.24993 -81.000092)
			(stroke
				(width 0.1524)
				(type default)
			)
			(layer "F.SilkS")
		)
		(fp_poly
			(pts
				(xy -3.792728 -64.502538) (xy -3.374136 -63.929006) (xy -4.084066 -63.938404)
			)
			(stroke
				(width 0)
				(type default)
			)
			(fill yes)
			(layer "F.SilkS")
		)
		(fp_line
			(start 3.24993 81.000092)
			(end -3.24993 81.000092)
			(stroke
				(width 0.1)
				(type default)
			)
			(layer "F.Fab")
		)
		(fp_line
			(start 3.24993 -81.000092)
			(end 3.24993 81.000092)
			(stroke
				(width 0.1)
				(type default)
			)
			(layer "F.Fab")
		)
		(fp_line
			(start -3.24993 81.000092)
			(end -3.24993 -81.000092)
			(stroke
				(width 0.1)
				(type default)
			)
			(layer "F.Fab")
		)
		(fp_line
			(start -3.24993 72.499982)
			(end 3.24993 72.499982)
			(stroke
				(width 0.1)
				(type default)
			)
			(layer "F.Fab")
		)
		(fp_line
			(start -3.24993 71.000112)
			(end 3.24993 71.000112)
			(stroke
				(width 0.1)
				(type default)
			)
			(layer "F.Fab")
		)
		(fp_line
			(start -3.24993 -71.000112)
			(end 3.24993 -71.000112)
			(stroke
				(width 0.1)
				(type default)
			)
			(layer "F.Fab")
		)
		(fp_line
			(start -3.24993 -72.499982)
			(end 3.24993 -72.499982)
			(stroke
				(width 0.1)
				(type default)
			)
			(layer "F.Fab")
		)
		(fp_line
			(start -3.24993 -81.000092)
			(end 3.24993 -81.000092)
			(stroke
				(width 0.1)
				(type default)
			)
			(layer "F.Fab")
		)
		(fp_poly
			(pts
				(xy -3.41503 -63.324994) (xy -4.43103 -62.816994) (xy -4.43103 -63.832994)
			)
			(stroke
				(width 0)
				(type default)
			)
			(fill yes)
			(layer "F.Fab")
		)
		(pad "1" smd rect
			(at -2.050034 -63.324994 90)
			(size 0.519938 1.4986)
			(layers "F.Cu" "F.Mask" "F.Paste")
			(net "P12V_MEM_CPU0")
		)
		(pad "2" smd rect
			(at -2.050034 -62.47511 90)
			(size 0.519938 1.4986)
			(layers "F.Cu" "F.Mask" "F.Paste")
			(net "Net_2375")
		)
		(pad "3" smd rect
			(at -2.050034 -61.624972 90)
			(size 0.519938 1.4986)
			(layers "F.Cu" "F.Mask" "F.Paste")
			(net "P3V3_AUX")
		)
		(pad "4" smd rect
			(at -2.050034 -60.775088 90)
			(size 0.519938 1.4986)
			(layers "F.Cu" "F.Mask" "F.Paste")
			(net "I3C_SPD_DDRJ_CPU0_SCL")
		)
		(pad "5" smd rect
			(at -2.050034 -59.92495 90)
			(size 0.519938 1.4986)
			(layers "F.Cu" "F.Mask" "F.Paste")
			(net "I3C_SPD_DDRJ_CPU0_SDA")
		)
		(pad "6" smd rect
			(at -2.050034 -59.075066 90)
			(size 0.519938 1.4986)
			(layers "F.Cu" "F.Mask" "F.Paste")
			(net "GND")
		)
		(pad "7" smd rect
			(at -2.050034 -58.224928 90)
			(size 0.519938 1.4986)
			(layers "F.Cu" "F.Mask" "F.Paste")
			(net "M_J_CPU0_SA_DQ<0>")
		)
		(pad "8" smd rect
			(at -2.050034 -57.375044 90)
			(size 0.519938 1.4986)
			(layers "F.Cu" "F.Mask" "F.Paste")
			(net "GND")
		)
		(pad "9" smd rect
			(at -2.050034 -56.524906 90)
			(size 0.519938 1.4986)
			(layers "F.Cu" "F.Mask" "F.Paste")
			(net "M_J_CPU0_SA_DQ<1>")
		)
		(pad "10" smd rect
			(at -2.050034 -55.675022 90)
			(size 0.519938 1.4986)
			(layers "F.Cu" "F.Mask" "F.Paste")
			(net "GND")
		)
		(pad "11" smd rect
			(at -2.050034 -54.824884 90)
			(size 0.519938 1.4986)
			(layers "F.Cu" "F.Mask" "F.Paste")
			(net "M_J_CPU0_SA_DQS_DP<0>")
		)
		(pad "12" smd rect
			(at -2.050034 -53.975 90)
			(size 0.519938 1.4986)
			(layers "F.Cu" "F.Mask" "F.Paste")
			(net "M_J_CPU0_SA_DQS_DN<0>")
		)
		(pad "13" smd rect
			(at -2.050034 -53.125116 90)
			(size 0.519938 1.4986)
			(layers "F.Cu" "F.Mask" "F.Paste")
			(net "GND")
		)
		(pad "14" smd rect
			(at -2.050034 -52.274978 90)
			(size 0.519938 1.4986)
			(layers "F.Cu" "F.Mask" "F.Paste")
			(net "M_J_CPU0_SA_DQ<4>")
		)
		(pad "15" smd rect
			(at -2.050034 -51.425094 90)
			(size 0.519938 1.4986)
			(layers "F.Cu" "F.Mask" "F.Paste")
			(net "GND")
		)
		(pad "16" smd rect
			(at -2.050034 -50.574956 90)
			(size 0.519938 1.4986)
			(layers "F.Cu" "F.Mask" "F.Paste")
			(net "M_J_CPU0_SA_DQ<5>")
		)
		(pad "17" smd rect
			(at -2.050034 -49.725072 90)
			(size 0.519938 1.4986)
			(layers "F.Cu" "F.Mask" "F.Paste")
			(net "GND")
		)
		(pad "18" smd rect
			(at -2.050034 -48.874934 90)
			(size 0.519938 1.4986)
			(layers "F.Cu" "F.Mask" "F.Paste")
			(net "M_J_CPU0_SA_DQ<8>")
		)
		(pad "19" smd rect
			(at -2.050034 -48.02505 90)
			(size 0.519938 1.4986)
			(layers "F.Cu" "F.Mask" "F.Paste")
			(net "GND")
		)
		(pad "20" smd rect
			(at -2.050034 -47.174912 90)
			(size 0.519938 1.4986)
			(layers "F.Cu" "F.Mask" "F.Paste")
			(net "M_J_CPU0_SA_DQ<9>")
		)
		(pad "21" smd rect
			(at -2.050034 -46.325028 90)
			(size 0.519938 1.4986)
			(layers "F.Cu" "F.Mask" "F.Paste")
			(net "GND")
		)
		(pad "22" smd rect
			(at -2.050034 -45.47489 90)
			(size 0.519938 1.4986)
			(layers "F.Cu" "F.Mask" "F.Paste")
			(net "M_J_CPU0_SA_DQS_DP<1>")
		)
		(pad "23" smd rect
			(at -2.050034 -44.625006 90)
			(size 0.519938 1.4986)
			(layers "F.Cu" "F.Mask" "F.Paste")
			(net "M_J_CPU0_SA_DQS_DN<1>")
		)
		(pad "24" smd rect
			(at -2.050034 -43.775122 90)
			(size 0.519938 1.4986)
			(layers "F.Cu" "F.Mask" "F.Paste")
			(net "GND")
		)
		(pad "25" smd rect
			(at -2.050034 -42.924984 90)
			(size 0.519938 1.4986)
			(layers "F.Cu" "F.Mask" "F.Paste")
			(net "M_J_CPU0_SA_DQ<12>")
		)
		(pad "26" smd rect
			(at -2.050034 -42.0751 90)
			(size 0.519938 1.4986)
			(layers "F.Cu" "F.Mask" "F.Paste")
			(net "GND")
		)
		(pad "27" smd rect
			(at -2.050034 -41.224962 90)
			(size 0.519938 1.4986)
			(layers "F.Cu" "F.Mask" "F.Paste")
			(net "M_J_CPU0_SA_DQ<13>")
		)
		(pad "28" smd rect
			(at -2.050034 -40.375078 90)
			(size 0.519938 1.4986)
			(layers "F.Cu" "F.Mask" "F.Paste")
			(net "GND")
		)
		(pad "29" smd rect
			(at -2.050034 -39.52494 90)
			(size 0.519938 1.4986)
			(layers "F.Cu" "F.Mask" "F.Paste")
			(net "M_J_CPU0_SA_DQ<16>")
		)
		(pad "30" smd rect
			(at -2.050034 -38.675056 90)
			(size 0.519938 1.4986)
			(layers "F.Cu" "F.Mask" "F.Paste")
			(net "GND")
		)
		(pad "31" smd rect
			(at -2.050034 -37.824918 90)
			(size 0.519938 1.4986)
			(layers "F.Cu" "F.Mask" "F.Paste")
			(net "M_J_CPU0_SA_DQ<17>")
		)
		(pad "32" smd rect
			(at -2.050034 -36.975034 90)
			(size 0.519938 1.4986)
			(layers "F.Cu" "F.Mask" "F.Paste")
			(net "GND")
		)
		(pad "33" smd rect
			(at -2.050034 -36.124896 90)
			(size 0.519938 1.4986)
			(layers "F.Cu" "F.Mask" "F.Paste")
			(net "M_J_CPU0_SA_DQS_DP<2>")
		)
		(pad "34" smd rect
			(at -2.050034 -35.275012 90)
			(size 0.519938 1.4986)
			(layers "F.Cu" "F.Mask" "F.Paste")
			(net "M_J_CPU0_SA_DQS_DN<2>")
		)
		(pad "35" smd rect
			(at -2.050034 -34.425128 90)
			(size 0.519938 1.4986)
			(layers "F.Cu" "F.Mask" "F.Paste")
			(net "GND")
		)
		(pad "36" smd rect
			(at -2.050034 -33.57499 90)
			(size 0.519938 1.4986)
			(layers "F.Cu" "F.Mask" "F.Paste")
			(net "M_J_CPU0_SA_DQ<20>")
		)
		(pad "37" smd rect
			(at -2.050034 -32.725106 90)
			(size 0.519938 1.4986)
			(layers "F.Cu" "F.Mask" "F.Paste")
			(net "GND")
		)
		(pad "38" smd rect
			(at -2.050034 -31.874968 90)
			(size 0.519938 1.4986)
			(layers "F.Cu" "F.Mask" "F.Paste")
			(net "M_J_CPU0_SA_DQ<21>")
		)
		(pad "39" smd rect
			(at -2.050034 -31.025084 90)
			(size 0.519938 1.4986)
			(layers "F.Cu" "F.Mask" "F.Paste")
			(net "GND")
		)
		(pad "40" smd rect
			(at -2.050034 -30.174946 90)
			(size 0.519938 1.4986)
			(layers "F.Cu" "F.Mask" "F.Paste")
			(net "M_J_CPU0_SA_DQ<24>")
		)
		(pad "41" smd rect
			(at -2.050034 -29.325062 90)
			(size 0.519938 1.4986)
			(layers "F.Cu" "F.Mask" "F.Paste")
			(net "GND")
		)
		(pad "42" smd rect
			(at -2.050034 -28.474924 90)
			(size 0.519938 1.4986)
			(layers "F.Cu" "F.Mask" "F.Paste")
			(net "M_J_CPU0_SA_DQ<25>")
		)
		(pad "43" smd rect
			(at -2.050034 -27.62504 90)
			(size 0.519938 1.4986)
			(layers "F.Cu" "F.Mask" "F.Paste")
			(net "GND")
		)
		(pad "44" smd rect
			(at -2.050034 -26.774902 90)
			(size 0.519938 1.4986)
			(layers "F.Cu" "F.Mask" "F.Paste")
			(net "M_J_CPU0_SA_DQS_DP<3>")
		)
		(pad "45" smd rect
			(at -2.050034 -25.925018 90)
			(size 0.519938 1.4986)
			(layers "F.Cu" "F.Mask" "F.Paste")
			(net "M_J_CPU0_SA_DQS_DN<3>")
		)
		(pad "46" smd rect
			(at -2.050034 -25.07488 90)
			(size 0.519938 1.4986)
			(layers "F.Cu" "F.Mask" "F.Paste")
			(net "GND")
		)
		(pad "47" smd rect
			(at -2.050034 -24.224996 90)
			(size 0.519938 1.4986)
			(layers "F.Cu" "F.Mask" "F.Paste")
			(net "M_J_CPU0_SA_DQ<28>")
		)
		(pad "48" smd rect
			(at -2.050034 -23.375112 90)
			(size 0.519938 1.4986)
			(layers "F.Cu" "F.Mask" "F.Paste")
			(net "GND")
		)
		(pad "49" smd rect
			(at -2.050034 -22.524974 90)
			(size 0.519938 1.4986)
			(layers "F.Cu" "F.Mask" "F.Paste")
			(net "M_J_CPU0_SA_DQ<29>")
		)
		(pad "50" smd rect
			(at -2.050034 -21.67509 90)
			(size 0.519938 1.4986)
			(layers "F.Cu" "F.Mask" "F.Paste")
			(net "GND")
		)
		(pad "51" smd rect
			(at -2.050034 -20.824952 90)
			(size 0.519938 1.4986)
			(layers "F.Cu" "F.Mask" "F.Paste")
			(net "M_J_CPU0_SA_CB<0>")
		)
		(pad "52" smd rect
			(at -2.050034 -19.975068 90)
			(size 0.519938 1.4986)
			(layers "F.Cu" "F.Mask" "F.Paste")
			(net "GND")
		)
		(pad "53" smd rect
			(at -2.050034 -19.12493 90)
			(size 0.519938 1.4986)
			(layers "F.Cu" "F.Mask" "F.Paste")
			(net "M_J_CPU0_SA_CB<1>")
		)
		(pad "54" smd rect
			(at -2.050034 -18.275046 90)
			(size 0.519938 1.4986)
			(layers "F.Cu" "F.Mask" "F.Paste")
			(net "GND")
		)
		(pad "55" smd rect
			(at -2.050034 -17.424908 90)
			(size 0.519938 1.4986)
			(layers "F.Cu" "F.Mask" "F.Paste")
			(net "M_J_CPU0_SA_DQS_DP<4>")
		)
		(pad "56" smd rect
			(at -2.050034 -16.575024 90)
			(size 0.519938 1.4986)
			(layers "F.Cu" "F.Mask" "F.Paste")
			(net "M_J_CPU0_SA_DQS_DN<4>")
		)
		(pad "57" smd rect
			(at -2.050034 -15.724886 90)
			(size 0.519938 1.4986)
			(layers "F.Cu" "F.Mask" "F.Paste")
			(net "GND")
		)
		(pad "58" smd rect
			(at -2.050034 -14.875002 90)
			(size 0.519938 1.4986)
			(layers "F.Cu" "F.Mask" "F.Paste")
			(net "M_J_CPU0_SA_CB<4>")
		)
		(pad "59" smd rect
			(at -2.050034 -14.025118 90)
			(size 0.519938 1.4986)
			(layers "F.Cu" "F.Mask" "F.Paste")
			(net "GND")
		)
		(pad "60" smd rect
			(at -2.050034 -13.17498 90)
			(size 0.519938 1.4986)
			(layers "F.Cu" "F.Mask" "F.Paste")
			(net "M_J_CPU0_SA_CB<5>")
		)
		(pad "61" smd rect
			(at -2.050034 -12.325096 90)
			(size 0.519938 1.4986)
			(layers "F.Cu" "F.Mask" "F.Paste")
			(net "GND")
		)
		(pad "62" smd rect
			(at -2.050034 -11.474958 90)
			(size 0.519938 1.4986)
			(layers "F.Cu" "F.Mask" "F.Paste")
			(net "M_J_CPU0_ALERT_N")
		)
		(pad "63" smd rect
			(at -2.050034 -10.625074 90)
			(size 0.519938 1.4986)
			(layers "F.Cu" "F.Mask" "F.Paste")
			(net "GND")
		)
		(pad "64" smd rect
			(at -2.050034 -9.774936 90)
			(size 0.519938 1.4986)
			(layers "F.Cu" "F.Mask" "F.Paste")
			(net "M_J_CPU0_SA_CS_N<0>")
		)
		(pad "65" smd rect
			(at -2.050034 -8.925052 90)
			(size 0.519938 1.4986)
			(layers "F.Cu" "F.Mask" "F.Paste")
			(net "GND")
		)
		(pad "66" smd rect
			(at -2.050034 -8.074914 90)
			(size 0.519938 1.4986)
			(layers "F.Cu" "F.Mask" "F.Paste")
			(net "M_J_CPU0_SA_CA<0>")
		)
		(pad "67" smd rect
			(at -2.050034 -7.22503 90)
			(size 0.519938 1.4986)
			(layers "F.Cu" "F.Mask" "F.Paste")
			(net "GND")
		)
		(pad "68" smd rect
			(at -2.050034 -6.374892 90)
			(size 0.519938 1.4986)
			(layers "F.Cu" "F.Mask" "F.Paste")
			(net "M_J_CPU0_SA_CA<2>")
		)
		(pad "69" smd rect
			(at -2.050034 -5.525008 90)
			(size 0.519938 1.4986)
			(layers "F.Cu" "F.Mask" "F.Paste")
			(net "GND")
		)
		(pad "70" smd rect
			(at -2.050034 -4.675124 90)
			(size 0.519938 1.4986)
			(layers "F.Cu" "F.Mask" "F.Paste")
			(net "M_J_CPU0_SA_CA<4>")
		)
		(pad "71" smd rect
			(at -2.050034 -3.824986 90)
			(size 0.519938 1.4986)
			(layers "F.Cu" "F.Mask" "F.Paste")
			(net "GND")
		)
		(pad "72" smd rect
			(at -2.050034 -2.975102 90)
			(size 0.519938 1.4986)
			(layers "F.Cu" "F.Mask" "F.Paste")
			(net "M_J_CPU0_SA_CA<6>")
		)
		(pad "73" smd rect
			(at -2.050034 -2.124964 90)
			(size 0.519938 1.4986)
			(layers "F.Cu" "F.Mask" "F.Paste")
			(net "GND")
		)
		(pad "74" smd rect
			(at -2.050034 -1.27508 90)
			(size 0.519938 1.4986)
			(layers "F.Cu" "F.Mask" "F.Paste")
			(net "M_J_CPU0_SA_PAR")
		)
		(pad "75" smd rect
			(at -2.050034 -0.424942 90)
			(size 0.519938 1.4986)
			(layers "F.Cu" "F.Mask" "F.Paste")
			(net "GND")
		)
		(pad "76" smd rect
			(at -2.050034 5.525008 90)
			(size 0.519938 1.4986)
			(layers "F.Cu" "F.Mask" "F.Paste")
			(net "M_J_CPU0_SB_CA<0>")
		)
		(pad "77" smd rect
			(at -2.050034 6.374892 90)
			(size 0.519938 1.4986)
			(layers "F.Cu" "F.Mask" "F.Paste")
			(net "GND")
		)
		(pad "78" smd rect
			(at -2.050034 7.22503 90)
			(size 0.519938 1.4986)
			(layers "F.Cu" "F.Mask" "F.Paste")
			(net "M_J_CPU0_SB_CA<2>")
		)
		(pad "79" smd rect
			(at -2.050034 8.074914 90)
			(size 0.519938 1.4986)
			(layers "F.Cu" "F.Mask" "F.Paste")
			(net "GND")
		)
		(pad "80" smd rect
			(at -2.050034 8.925052 90)
			(size 0.519938 1.4986)
			(layers "F.Cu" "F.Mask" "F.Paste")
			(net "M_J_CPU0_SB_CA<4>")
		)
		(pad "81" smd rect
			(at -2.050034 9.774936 90)
			(size 0.519938 1.4986)
			(layers "F.Cu" "F.Mask" "F.Paste")
			(net "GND")
		)
		(pad "82" smd rect
			(at -2.050034 10.625074 90)
			(size 0.519938 1.4986)
			(layers "F.Cu" "F.Mask" "F.Paste")
			(net "M_J_CPU0_SB_CA<6>")
		)
		(pad "83" smd rect
			(at -2.050034 11.474958 90)
			(size 0.519938 1.4986)
			(layers "F.Cu" "F.Mask" "F.Paste")
			(net "GND")
		)
		(pad "84" smd rect
			(at -2.050034 12.325096 90)
			(size 0.519938 1.4986)
			(layers "F.Cu" "F.Mask" "F.Paste")
			(net "M_J_CPU0_SB_CS_N<0>")
		)
		(pad "85" smd rect
			(at -2.050034 13.17498 90)
			(size 0.519938 1.4986)
			(layers "F.Cu" "F.Mask" "F.Paste")
			(net "GND")
		)
		(pad "86" smd rect
			(at -2.050034 14.025118 90)
			(size 0.519938 1.4986)
			(layers "F.Cu" "F.Mask" "F.Paste")
			(net "M_J_CPU0_SA_RSP<0>")
		)
		(pad "87" smd rect
			(at -2.050034 14.875002 90)
			(size 0.519938 1.4986)
			(layers "F.Cu" "F.Mask" "F.Paste")
			(net "M_J_CPU0_SB_RSP<0>")
		)
		(pad "88" smd rect
			(at -2.050034 15.724886 90)
			(size 0.519938 1.4986)
			(layers "F.Cu" "F.Mask" "F.Paste")
			(net "GND")
		)
		(pad "89" smd rect
			(at -2.050034 16.575024 90)
			(size 0.519938 1.4986)
			(layers "F.Cu" "F.Mask" "F.Paste")
			(net "M_J_CPU0_SB_CB<4>")
		)
		(pad "90" smd rect
			(at -2.050034 17.424908 90)
			(size 0.519938 1.4986)
			(layers "F.Cu" "F.Mask" "F.Paste")
			(net "GND")
		)
		(pad "91" smd rect
			(at -2.050034 18.275046 90)
			(size 0.519938 1.4986)
			(layers "F.Cu" "F.Mask" "F.Paste")
			(net "M_J_CPU0_SB_CB<5>")
		)
		(pad "92" smd rect
			(at -2.050034 19.12493 90)
			(size 0.519938 1.4986)
			(layers "F.Cu" "F.Mask" "F.Paste")
			(net "GND")
		)
		(pad "93" smd rect
			(at -2.050034 19.975068 90)
			(size 0.519938 1.4986)
			(layers "F.Cu" "F.Mask" "F.Paste")
			(net "M_J_CPU0_SB_DQS_DP<9>")
		)
		(pad "94" smd rect
			(at -2.050034 20.824952 90)
			(size 0.519938 1.4986)
			(layers "F.Cu" "F.Mask" "F.Paste")
			(net "M_J_CPU0_SB_DQS_DN<9>")
		)
		(pad "95" smd rect
			(at -2.050034 21.67509 90)
			(size 0.519938 1.4986)
			(layers "F.Cu" "F.Mask" "F.Paste")
			(net "GND")
		)
		(pad "96" smd rect
			(at -2.050034 22.524974 90)
			(size 0.519938 1.4986)
			(layers "F.Cu" "F.Mask" "F.Paste")
			(net "M_J_CPU0_SB_CB<0>")
		)
		(pad "97" smd rect
			(at -2.050034 23.375112 90)
			(size 0.519938 1.4986)
			(layers "F.Cu" "F.Mask" "F.Paste")
			(net "GND")
		)
		(pad "98" smd rect
			(at -2.050034 24.224996 90)
			(size 0.519938 1.4986)
			(layers "F.Cu" "F.Mask" "F.Paste")
			(net "M_J_CPU0_SB_CB<1>")
		)
		(pad "99" smd rect
			(at -2.050034 25.07488 90)
			(size 0.519938 1.4986)
			(layers "F.Cu" "F.Mask" "F.Paste")
			(net "GND")
		)
		(pad "100" smd rect
			(at -2.050034 25.925018 90)
			(size 0.519938 1.4986)
			(layers "F.Cu" "F.Mask" "F.Paste")
			(net "M_J_CPU0_SB_DQ<0>")
		)
		(pad "101" smd rect
			(at -2.050034 26.774902 90)
			(size 0.519938 1.4986)
			(layers "F.Cu" "F.Mask" "F.Paste")
			(net "GND")
		)
		(pad "102" smd rect
			(at -2.050034 27.62504 90)
			(size 0.519938 1.4986)
			(layers "F.Cu" "F.Mask" "F.Paste")
			(net "M_J_CPU0_SB_DQ<1>")
		)
		(pad "103" smd rect
			(at -2.050034 28.474924 90)
			(size 0.519938 1.4986)
			(layers "F.Cu" "F.Mask" "F.Paste")
			(net "GND")
		)
		(pad "104" smd rect
			(at -2.050034 29.325062 90)
			(size 0.519938 1.4986)
			(layers "F.Cu" "F.Mask" "F.Paste")
			(net "M_J_CPU0_SB_DQS_DP<0>")
		)
		(pad "105" smd rect
			(at -2.050034 30.174946 90)
			(size 0.519938 1.4986)
			(layers "F.Cu" "F.Mask" "F.Paste")
			(net "M_J_CPU0_SB_DQS_DN<0>")
		)
		(pad "106" smd rect
			(at -2.050034 31.025084 90)
			(size 0.519938 1.4986)
			(layers "F.Cu" "F.Mask" "F.Paste")
			(net "GND")
		)
		(pad "107" smd rect
			(at -2.050034 31.874968 90)
			(size 0.519938 1.4986)
			(layers "F.Cu" "F.Mask" "F.Paste")
			(net "M_J_CPU0_SB_DQ<4>")
		)
		(pad "108" smd rect
			(at -2.050034 32.725106 90)
			(size 0.519938 1.4986)
			(layers "F.Cu" "F.Mask" "F.Paste")
			(net "GND")
		)
		(pad "109" smd rect
			(at -2.050034 33.57499 90)
			(size 0.519938 1.4986)
			(layers "F.Cu" "F.Mask" "F.Paste")
			(net "M_J_CPU0_SB_DQ<5>")
		)
		(pad "110" smd rect
			(at -2.050034 34.425128 90)
			(size 0.519938 1.4986)
			(layers "F.Cu" "F.Mask" "F.Paste")
			(net "GND")
		)
		(pad "111" smd rect
			(at -2.050034 35.275012 90)
			(size 0.519938 1.4986)
			(layers "F.Cu" "F.Mask" "F.Paste")
			(net "M_J_CPU0_SB_DQ<8>")
		)
		(pad "112" smd rect
			(at -2.050034 36.124896 90)
			(size 0.519938 1.4986)
			(layers "F.Cu" "F.Mask" "F.Paste")
			(net "GND")
		)
		(pad "113" smd rect
			(at -2.050034 36.975034 90)
			(size 0.519938 1.4986)
			(layers "F.Cu" "F.Mask" "F.Paste")
			(net "M_J_CPU0_SB_DQ<9>")
		)
		(pad "114" smd rect
			(at -2.050034 37.824918 90)
			(size 0.519938 1.4986)
			(layers "F.Cu" "F.Mask" "F.Paste")
			(net "GND")
		)
		(pad "115" smd rect
			(at -2.050034 38.675056 90)
			(size 0.519938 1.4986)
			(layers "F.Cu" "F.Mask" "F.Paste")
			(net "M_J_CPU0_SB_DQS_DP<1>")
		)
		(pad "116" smd rect
			(at -2.050034 39.52494 90)
			(size 0.519938 1.4986)
			(layers "F.Cu" "F.Mask" "F.Paste")
			(net "M_J_CPU0_SB_DQS_DN<1>")
		)
		(pad "117" smd rect
			(at -2.050034 40.375078 90)
			(size 0.519938 1.4986)
			(layers "F.Cu" "F.Mask" "F.Paste")
			(net "GND")
		)
		(pad "118" smd rect
			(at -2.050034 41.224962 90)
			(size 0.519938 1.4986)
			(layers "F.Cu" "F.Mask" "F.Paste")
			(net "M_J_CPU0_SB_DQ<12>")
		)
		(pad "119" smd rect
			(at -2.050034 42.0751 90)
			(size 0.519938 1.4986)
			(layers "F.Cu" "F.Mask" "F.Paste")
			(net "GND")
		)
		(pad "120" smd rect
			(at -2.050034 42.924984 90)
			(size 0.519938 1.4986)
			(layers "F.Cu" "F.Mask" "F.Paste")
			(net "M_J_CPU0_SB_DQ<13>")
		)
		(pad "121" smd rect
			(at -2.050034 43.775122 90)
			(size 0.519938 1.4986)
			(layers "F.Cu" "F.Mask" "F.Paste")
			(net "GND")
		)
		(pad "122" smd rect
			(at -2.050034 44.625006 90)
			(size 0.519938 1.4986)
			(layers "F.Cu" "F.Mask" "F.Paste")
			(net "M_J_CPU0_SB_DQ<16>")
		)
		(pad "123" smd rect
			(at -2.050034 45.47489 90)
			(size 0.519938 1.4986)
			(layers "F.Cu" "F.Mask" "F.Paste")
			(net "GND")
		)
		(pad "124" smd rect
			(at -2.050034 46.325028 90)
			(size 0.519938 1.4986)
			(layers "F.Cu" "F.Mask" "F.Paste")
			(net "M_J_CPU0_SB_DQ<17>")
		)
		(pad "125" smd rect
			(at -2.050034 47.174912 90)
			(size 0.519938 1.4986)
			(layers "F.Cu" "F.Mask" "F.Paste")
			(net "GND")
		)
		(pad "126" smd rect
			(at -2.050034 48.02505 90)
			(size 0.519938 1.4986)
			(layers "F.Cu" "F.Mask" "F.Paste")
			(net "M_J_CPU0_SB_DQS_DP<2>")
		)
		(pad "127" smd rect
			(at -2.050034 48.874934 90)
			(size 0.519938 1.4986)
			(layers "F.Cu" "F.Mask" "F.Paste")
			(net "M_J_CPU0_SB_DQS_DN<2>")
		)
		(pad "128" smd rect
			(at -2.050034 49.725072 90)
			(size 0.519938 1.4986)
			(layers "F.Cu" "F.Mask" "F.Paste")
			(net "GND")
		)
		(pad "129" smd rect
			(at -2.050034 50.574956 90)
			(size 0.519938 1.4986)
			(layers "F.Cu" "F.Mask" "F.Paste")
			(net "M_J_CPU0_SB_DQ<20>")
		)
		(pad "130" smd rect
			(at -2.050034 51.425094 90)
			(size 0.519938 1.4986)
			(layers "F.Cu" "F.Mask" "F.Paste")
			(net "GND")
		)
		(pad "131" smd rect
			(at -2.050034 52.274978 90)
			(size 0.519938 1.4986)
			(layers "F.Cu" "F.Mask" "F.Paste")
			(net "M_J_CPU0_SB_DQ<21>")
		)
		(pad "132" smd rect
			(at -2.050034 53.125116 90)
			(size 0.519938 1.4986)
			(layers "F.Cu" "F.Mask" "F.Paste")
			(net "GND")
		)
		(pad "133" smd rect
			(at -2.050034 53.975 90)
			(size 0.519938 1.4986)
			(layers "F.Cu" "F.Mask" "F.Paste")
			(net "M_J_CPU0_SB_DQ<24>")
		)
		(pad "134" smd rect
			(at -2.050034 54.824884 90)
			(size 0.519938 1.4986)
			(layers "F.Cu" "F.Mask" "F.Paste")
			(net "GND")
		)
		(pad "135" smd rect
			(at -2.050034 55.675022 90)
			(size 0.519938 1.4986)
			(layers "F.Cu" "F.Mask" "F.Paste")
			(net "M_J_CPU0_SB_DQ<25>")
		)
		(pad "136" smd rect
			(at -2.050034 56.524906 90)
			(size 0.519938 1.4986)
			(layers "F.Cu" "F.Mask" "F.Paste")
			(net "GND")
		)
		(pad "137" smd rect
			(at -2.050034 57.375044 90)
			(size 0.519938 1.4986)
			(layers "F.Cu" "F.Mask" "F.Paste")
			(net "M_J_CPU0_SB_DQS_DP<3>")
		)
		(pad "138" smd rect
			(at -2.050034 58.224928 90)
			(size 0.519938 1.4986)
			(layers "F.Cu" "F.Mask" "F.Paste")
			(net "M_J_CPU0_SB_DQS_DN<3>")
		)
		(pad "139" smd rect
			(at -2.050034 59.075066 90)
			(size 0.519938 1.4986)
			(layers "F.Cu" "F.Mask" "F.Paste")
			(net "GND")
		)
		(pad "140" smd rect
			(at -2.050034 59.92495 90)
			(size 0.519938 1.4986)
			(layers "F.Cu" "F.Mask" "F.Paste")
			(net "M_J_CPU0_SB_DQ<28>")
		)
		(pad "141" smd rect
			(at -2.050034 60.775088 90)
			(size 0.519938 1.4986)
			(layers "F.Cu" "F.Mask" "F.Paste")
			(net "GND")
		)
		(pad "142" smd rect
			(at -2.050034 61.624972 90)
			(size 0.519938 1.4986)
			(layers "F.Cu" "F.Mask" "F.Paste")
			(net "M_J_CPU0_SB_DQ<29>")
		)
		(pad "143" smd rect
			(at -2.050034 62.47511 90)
			(size 0.519938 1.4986)
			(layers "F.Cu" "F.Mask" "F.Paste")
			(net "GND")
		)
		(pad "144" smd rect
			(at -2.050034 63.324994 90)
			(size 0.519938 1.4986)
			(layers "F.Cu" "F.Mask" "F.Paste")
			(net "Net_2376")
		)
		(pad "145" smd rect
			(at 2.050034 -63.324994 90)
			(size 0.519938 1.4986)
			(layers "F.Cu" "F.Mask" "F.Paste")
			(net "P12V_MEM_CPU0")
		)
		(pad "146" smd rect
			(at 2.050034 -62.47511 90)
			(size 0.519938 1.4986)
			(layers "F.Cu" "F.Mask" "F.Paste")
			(net "P12V_MEM_CPU0")
		)
		(pad "147" smd rect
			(at 2.050034 -61.624972 90)
			(size 0.519938 1.4986)
			(layers "F.Cu" "F.Mask" "F.Paste")
			(net "PWRGD_CHJ_CPU0_DIMM")
		)
		(pad "148" smd rect
			(at 2.050034 -60.775088 90)
			(size 0.519938 1.4986)
			(layers "F.Cu" "F.Mask" "F.Paste")
			(net "PD_CHJ_CPU0_DIMM_SAA")
		)
		(pad "149" smd rect
			(at 2.050034 -59.92495 90)
			(size 0.519938 1.4986)
			(layers "F.Cu" "F.Mask" "F.Paste")
			(net "Net_2377")
		)
		(pad "150" smd rect
			(at 2.050034 -59.075066 90)
			(size 0.519938 1.4986)
			(layers "F.Cu" "F.Mask" "F.Paste")
			(net "Net_2378")
		)
		(pad "151" smd rect
			(at 2.050034 -58.224928 90)
			(size 0.519938 1.4986)
			(layers "F.Cu" "F.Mask" "F.Paste")
			(net "GND")
		)
		(pad "152" smd rect
			(at 2.050034 -57.375044 90)
			(size 0.519938 1.4986)
			(layers "F.Cu" "F.Mask" "F.Paste")
			(net "M_J_CPU0_SA_DQ<2>")
		)
		(pad "153" smd rect
			(at 2.050034 -56.524906 90)
			(size 0.519938 1.4986)
			(layers "F.Cu" "F.Mask" "F.Paste")
			(net "GND")
		)
		(pad "154" smd rect
			(at 2.050034 -55.675022 90)
			(size 0.519938 1.4986)
			(layers "F.Cu" "F.Mask" "F.Paste")
			(net "M_J_CPU0_SA_DQ<3>")
		)
		(pad "155" smd rect
			(at 2.050034 -54.824884 90)
			(size 0.519938 1.4986)
			(layers "F.Cu" "F.Mask" "F.Paste")
			(net "GND")
		)
		(pad "156" smd rect
			(at 2.050034 -53.975 90)
			(size 0.519938 1.4986)
			(layers "F.Cu" "F.Mask" "F.Paste")
			(net "M_J_CPU0_SA_DQS_DN<5>")
		)
		(pad "157" smd rect
			(at 2.050034 -53.125116 90)
			(size 0.519938 1.4986)
			(layers "F.Cu" "F.Mask" "F.Paste")
			(net "M_J_CPU0_SA_DQS_DP<5>")
		)
		(pad "158" smd rect
			(at 2.050034 -52.274978 90)
			(size 0.519938 1.4986)
			(layers "F.Cu" "F.Mask" "F.Paste")
			(net "GND")
		)
		(pad "159" smd rect
			(at 2.050034 -51.425094 90)
			(size 0.519938 1.4986)
			(layers "F.Cu" "F.Mask" "F.Paste")
			(net "M_J_CPU0_SA_DQ<6>")
		)
		(pad "160" smd rect
			(at 2.050034 -50.574956 90)
			(size 0.519938 1.4986)
			(layers "F.Cu" "F.Mask" "F.Paste")
			(net "GND")
		)
		(pad "161" smd rect
			(at 2.050034 -49.725072 90)
			(size 0.519938 1.4986)
			(layers "F.Cu" "F.Mask" "F.Paste")
			(net "M_J_CPU0_SA_DQ<7>")
		)
		(pad "162" smd rect
			(at 2.050034 -48.874934 90)
			(size 0.519938 1.4986)
			(layers "F.Cu" "F.Mask" "F.Paste")
			(net "GND")
		)
		(pad "163" smd rect
			(at 2.050034 -48.02505 90)
			(size 0.519938 1.4986)
			(layers "F.Cu" "F.Mask" "F.Paste")
			(net "M_J_CPU0_SA_DQ<10>")
		)
		(pad "164" smd rect
			(at 2.050034 -47.174912 90)
			(size 0.519938 1.4986)
			(layers "F.Cu" "F.Mask" "F.Paste")
			(net "GND")
		)
		(pad "165" smd rect
			(at 2.050034 -46.325028 90)
			(size 0.519938 1.4986)
			(layers "F.Cu" "F.Mask" "F.Paste")
			(net "M_J_CPU0_SA_DQ<11>")
		)
		(pad "166" smd rect
			(at 2.050034 -45.47489 90)
			(size 0.519938 1.4986)
			(layers "F.Cu" "F.Mask" "F.Paste")
			(net "GND")
		)
		(pad "167" smd rect
			(at 2.050034 -44.625006 90)
			(size 0.519938 1.4986)
			(layers "F.Cu" "F.Mask" "F.Paste")
			(net "M_J_CPU0_SA_DQS_DN<6>")
		)
		(pad "168" smd rect
			(at 2.050034 -43.775122 90)
			(size 0.519938 1.4986)
			(layers "F.Cu" "F.Mask" "F.Paste")
			(net "M_J_CPU0_SA_DQS_DP<6>")
		)
		(pad "169" smd rect
			(at 2.050034 -42.924984 90)
			(size 0.519938 1.4986)
			(layers "F.Cu" "F.Mask" "F.Paste")
			(net "GND")
		)
		(pad "170" smd rect
			(at 2.050034 -42.0751 90)
			(size 0.519938 1.4986)
			(layers "F.Cu" "F.Mask" "F.Paste")
			(net "M_J_CPU0_SA_DQ<14>")
		)
		(pad "171" smd rect
			(at 2.050034 -41.224962 90)
			(size 0.519938 1.4986)
			(layers "F.Cu" "F.Mask" "F.Paste")
			(net "GND")
		)
		(pad "172" smd rect
			(at 2.050034 -40.375078 90)
			(size 0.519938 1.4986)
			(layers "F.Cu" "F.Mask" "F.Paste")
			(net "M_J_CPU0_SA_DQ<15>")
		)
		(pad "173" smd rect
			(at 2.050034 -39.52494 90)
			(size 0.519938 1.4986)
			(layers "F.Cu" "F.Mask" "F.Paste")
			(net "GND")
		)
		(pad "174" smd rect
			(at 2.050034 -38.675056 90)
			(size 0.519938 1.4986)
			(layers "F.Cu" "F.Mask" "F.Paste")
			(net "M_J_CPU0_SA_DQ<18>")
		)
		(pad "175" smd rect
			(at 2.050034 -37.824918 90)
			(size 0.519938 1.4986)
			(layers "F.Cu" "F.Mask" "F.Paste")
			(net "GND")
		)
		(pad "176" smd rect
			(at 2.050034 -36.975034 90)
			(size 0.519938 1.4986)
			(layers "F.Cu" "F.Mask" "F.Paste")
			(net "M_J_CPU0_SA_DQ<19>")
		)
		(pad "177" smd rect
			(at 2.050034 -36.124896 90)
			(size 0.519938 1.4986)
			(layers "F.Cu" "F.Mask" "F.Paste")
			(net "GND")
		)
		(pad "178" smd rect
			(at 2.050034 -35.275012 90)
			(size 0.519938 1.4986)
			(layers "F.Cu" "F.Mask" "F.Paste")
			(net "M_J_CPU0_SA_DQS_DN<7>")
		)
		(pad "179" smd rect
			(at 2.050034 -34.425128 90)
			(size 0.519938 1.4986)
			(layers "F.Cu" "F.Mask" "F.Paste")
			(net "M_J_CPU0_SA_DQS_DP<7>")
		)
		(pad "180" smd rect
			(at 2.050034 -33.57499 90)
			(size 0.519938 1.4986)
			(layers "F.Cu" "F.Mask" "F.Paste")
			(net "GND")
		)
		(pad "181" smd rect
			(at 2.050034 -32.725106 90)
			(size 0.519938 1.4986)
			(layers "F.Cu" "F.Mask" "F.Paste")
			(net "M_J_CPU0_SA_DQ<22>")
		)
		(pad "182" smd rect
			(at 2.050034 -31.874968 90)
			(size 0.519938 1.4986)
			(layers "F.Cu" "F.Mask" "F.Paste")
			(net "GND")
		)
		(pad "183" smd rect
			(at 2.050034 -31.025084 90)
			(size 0.519938 1.4986)
			(layers "F.Cu" "F.Mask" "F.Paste")
			(net "M_J_CPU0_SA_DQ<23>")
		)
		(pad "184" smd rect
			(at 2.050034 -30.174946 90)
			(size 0.519938 1.4986)
			(layers "F.Cu" "F.Mask" "F.Paste")
			(net "GND")
		)
		(pad "185" smd rect
			(at 2.050034 -29.325062 90)
			(size 0.519938 1.4986)
			(layers "F.Cu" "F.Mask" "F.Paste")
			(net "M_J_CPU0_SA_DQ<26>")
		)
		(pad "186" smd rect
			(at 2.050034 -28.474924 90)
			(size 0.519938 1.4986)
			(layers "F.Cu" "F.Mask" "F.Paste")
			(net "GND")
		)
		(pad "187" smd rect
			(at 2.050034 -27.62504 90)
			(size 0.519938 1.4986)
			(layers "F.Cu" "F.Mask" "F.Paste")
			(net "M_J_CPU0_SA_DQ<27>")
		)
		(pad "188" smd rect
			(at 2.050034 -26.774902 90)
			(size 0.519938 1.4986)
			(layers "F.Cu" "F.Mask" "F.Paste")
			(net "GND")
		)
		(pad "189" smd rect
			(at 2.050034 -25.925018 90)
			(size 0.519938 1.4986)
			(layers "F.Cu" "F.Mask" "F.Paste")
			(net "M_J_CPU0_SA_DQS_DN<8>")
		)
		(pad "190" smd rect
			(at 2.050034 -25.07488 90)
			(size 0.519938 1.4986)
			(layers "F.Cu" "F.Mask" "F.Paste")
			(net "M_J_CPU0_SA_DQS_DP<8>")
		)
		(pad "191" smd rect
			(at 2.050034 -24.224996 90)
			(size 0.519938 1.4986)
			(layers "F.Cu" "F.Mask" "F.Paste")
			(net "GND")
		)
		(pad "192" smd rect
			(at 2.050034 -23.375112 90)
			(size 0.519938 1.4986)
			(layers "F.Cu" "F.Mask" "F.Paste")
			(net "M_J_CPU0_SA_DQ<30>")
		)
		(pad "193" smd rect
			(at 2.050034 -22.524974 90)
			(size 0.519938 1.4986)
			(layers "F.Cu" "F.Mask" "F.Paste")
			(net "GND")
		)
		(pad "194" smd rect
			(at 2.050034 -21.67509 90)
			(size 0.519938 1.4986)
			(layers "F.Cu" "F.Mask" "F.Paste")
			(net "M_J_CPU0_SA_DQ<31>")
		)
		(pad "195" smd rect
			(at 2.050034 -20.824952 90)
			(size 0.519938 1.4986)
			(layers "F.Cu" "F.Mask" "F.Paste")
			(net "GND")
		)
		(pad "196" smd rect
			(at 2.050034 -19.975068 90)
			(size 0.519938 1.4986)
			(layers "F.Cu" "F.Mask" "F.Paste")
			(net "M_J_CPU0_SA_CB<2>")
		)
		(pad "197" smd rect
			(at 2.050034 -19.12493 90)
			(size 0.519938 1.4986)
			(layers "F.Cu" "F.Mask" "F.Paste")
			(net "GND")
		)
		(pad "198" smd rect
			(at 2.050034 -18.275046 90)
			(size 0.519938 1.4986)
			(layers "F.Cu" "F.Mask" "F.Paste")
			(net "M_J_CPU0_SA_CB<3>")
		)
		(pad "199" smd rect
			(at 2.050034 -17.424908 90)
			(size 0.519938 1.4986)
			(layers "F.Cu" "F.Mask" "F.Paste")
			(net "GND")
		)
		(pad "200" smd rect
			(at 2.050034 -16.575024 90)
			(size 0.519938 1.4986)
			(layers "F.Cu" "F.Mask" "F.Paste")
			(net "M_J_CPU0_SA_DQS_DN<9>")
		)
		(pad "201" smd rect
			(at 2.050034 -15.724886 90)
			(size 0.519938 1.4986)
			(layers "F.Cu" "F.Mask" "F.Paste")
			(net "M_J_CPU0_SA_DQS_DP<9>")
		)
		(pad "202" smd rect
			(at 2.050034 -14.875002 90)
			(size 0.519938 1.4986)
			(layers "F.Cu" "F.Mask" "F.Paste")
			(net "GND")
		)
		(pad "203" smd rect
			(at 2.050034 -14.025118 90)
			(size 0.519938 1.4986)
			(layers "F.Cu" "F.Mask" "F.Paste")
			(net "M_J_CPU0_SA_CB<6>")
		)
		(pad "204" smd rect
			(at 2.050034 -13.17498 90)
			(size 0.519938 1.4986)
			(layers "F.Cu" "F.Mask" "F.Paste")
			(net "GND")
		)
		(pad "205" smd rect
			(at 2.050034 -12.325096 90)
			(size 0.519938 1.4986)
			(layers "F.Cu" "F.Mask" "F.Paste")
			(net "M_J_CPU0_SA_CB<7>")
		)
		(pad "206" smd rect
			(at 2.050034 -11.474958 90)
			(size 0.519938 1.4986)
			(layers "F.Cu" "F.Mask" "F.Paste")
			(net "GND")
		)
		(pad "207" smd rect
			(at 2.050034 -10.625074 90)
			(size 0.519938 1.4986)
			(layers "F.Cu" "F.Mask" "F.Paste")
			(net "M_J_CPU0_RESET_N")
		)
		(pad "208" smd rect
			(at 2.050034 -9.774936 90)
			(size 0.519938 1.4986)
			(layers "F.Cu" "F.Mask" "F.Paste")
			(net "GND")
		)
		(pad "209" smd rect
			(at 2.050034 -8.925052 90)
			(size 0.519938 1.4986)
			(layers "F.Cu" "F.Mask" "F.Paste")
			(net "M_J_CPU0_SA_CS_N<1>")
		)
		(pad "210" smd rect
			(at 2.050034 -8.074914 90)
			(size 0.519938 1.4986)
			(layers "F.Cu" "F.Mask" "F.Paste")
			(net "GND")
		)
		(pad "211" smd rect
			(at 2.050034 -7.22503 90)
			(size 0.519938 1.4986)
			(layers "F.Cu" "F.Mask" "F.Paste")
			(net "M_J_CPU0_SA_CA<1>")
		)
		(pad "212" smd rect
			(at 2.050034 -6.374892 90)
			(size 0.519938 1.4986)
			(layers "F.Cu" "F.Mask" "F.Paste")
			(net "GND")
		)
		(pad "213" smd rect
			(at 2.050034 -5.525008 90)
			(size 0.519938 1.4986)
			(layers "F.Cu" "F.Mask" "F.Paste")
			(net "M_J_CPU0_SA_CA<3>")
		)
		(pad "214" smd rect
			(at 2.050034 -4.675124 90)
			(size 0.519938 1.4986)
			(layers "F.Cu" "F.Mask" "F.Paste")
			(net "GND")
		)
		(pad "215" smd rect
			(at 2.050034 -3.824986 90)
			(size 0.519938 1.4986)
			(layers "F.Cu" "F.Mask" "F.Paste")
			(net "M_J_CPU0_SA_CA<5>")
		)
		(pad "216" smd rect
			(at 2.050034 -2.975102 90)
			(size 0.519938 1.4986)
			(layers "F.Cu" "F.Mask" "F.Paste")
			(net "GND")
		)
		(pad "217" smd rect
			(at 2.050034 -2.124964 90)
			(size 0.519938 1.4986)
			(layers "F.Cu" "F.Mask" "F.Paste")
			(net "M_J_CPU0_CLK_DP<0>")
		)
		(pad "218" smd rect
			(at 2.050034 -1.27508 90)
			(size 0.519938 1.4986)
			(layers "F.Cu" "F.Mask" "F.Paste")
			(net "M_J_CPU0_CLK_DN<0>")
		)
		(pad "219" smd rect
			(at 2.050034 -0.424942 90)
			(size 0.519938 1.4986)
			(layers "F.Cu" "F.Mask" "F.Paste")
			(net "GND")
		)
		(pad "220" smd rect
			(at 2.050034 5.525008 90)
			(size 0.519938 1.4986)
			(layers "F.Cu" "F.Mask" "F.Paste")
			(net "Net_2379")
		)
		(pad "221" smd rect
			(at 2.050034 6.374892 90)
			(size 0.519938 1.4986)
			(layers "F.Cu" "F.Mask" "F.Paste")
			(net "M_J_CPU0_SB_CA<1>")
		)
		(pad "222" smd rect
			(at 2.050034 7.22503 90)
			(size 0.519938 1.4986)
			(layers "F.Cu" "F.Mask" "F.Paste")
			(net "GND")
		)
		(pad "223" smd rect
			(at 2.050034 8.074914 90)
			(size 0.519938 1.4986)
			(layers "F.Cu" "F.Mask" "F.Paste")
			(net "M_J_CPU0_SB_CA<3>")
		)
		(pad "224" smd rect
			(at 2.050034 8.925052 90)
			(size 0.519938 1.4986)
			(layers "F.Cu" "F.Mask" "F.Paste")
			(net "GND")
		)
		(pad "225" smd rect
			(at 2.050034 9.774936 90)
			(size 0.519938 1.4986)
			(layers "F.Cu" "F.Mask" "F.Paste")
			(net "M_J_CPU0_SB_CA<5>")
		)
		(pad "226" smd rect
			(at 2.050034 10.625074 90)
			(size 0.519938 1.4986)
			(layers "F.Cu" "F.Mask" "F.Paste")
			(net "GND")
		)
		(pad "227" smd rect
			(at 2.050034 11.474958 90)
			(size 0.519938 1.4986)
			(layers "F.Cu" "F.Mask" "F.Paste")
			(net "M_J_CPU0_SB_PAR")
		)
		(pad "228" smd rect
			(at 2.050034 12.325096 90)
			(size 0.519938 1.4986)
			(layers "F.Cu" "F.Mask" "F.Paste")
			(net "GND")
		)
		(pad "229" smd rect
			(at 2.050034 13.17498 90)
			(size 0.519938 1.4986)
			(layers "F.Cu" "F.Mask" "F.Paste")
			(net "M_J_CPU0_SB_CS_N<1>")
		)
		(pad "230" smd rect
			(at 2.050034 14.025118 90)
			(size 0.519938 1.4986)
			(layers "F.Cu" "F.Mask" "F.Paste")
			(net "GND")
		)
		(pad "231" smd rect
			(at 2.050034 14.875002 90)
			(size 0.519938 1.4986)
			(layers "F.Cu" "F.Mask" "F.Paste")
			(net "Net_2380")
		)
		(pad "232" smd rect
			(at 2.050034 15.724886 90)
			(size 0.519938 1.4986)
			(layers "F.Cu" "F.Mask" "F.Paste")
			(net "Net_2381")
		)
		(pad "233" smd rect
			(at 2.050034 16.575024 90)
			(size 0.519938 1.4986)
			(layers "F.Cu" "F.Mask" "F.Paste")
			(net "GND")
		)
		(pad "234" smd rect
			(at 2.050034 17.424908 90)
			(size 0.519938 1.4986)
			(layers "F.Cu" "F.Mask" "F.Paste")
			(net "M_J_CPU0_SB_CB<6>")
		)
		(pad "235" smd rect
			(at 2.050034 18.275046 90)
			(size 0.519938 1.4986)
			(layers "F.Cu" "F.Mask" "F.Paste")
			(net "GND")
		)
		(pad "236" smd rect
			(at 2.050034 19.12493 90)
			(size 0.519938 1.4986)
			(layers "F.Cu" "F.Mask" "F.Paste")
			(net "M_J_CPU0_SB_CB<7>")
		)
		(pad "237" smd rect
			(at 2.050034 19.975068 90)
			(size 0.519938 1.4986)
			(layers "F.Cu" "F.Mask" "F.Paste")
			(net "GND")
		)
		(pad "238" smd rect
			(at 2.050034 20.824952 90)
			(size 0.519938 1.4986)
			(layers "F.Cu" "F.Mask" "F.Paste")
			(net "M_J_CPU0_SB_DQS_DN<4>")
		)
		(pad "239" smd rect
			(at 2.050034 21.67509 90)
			(size 0.519938 1.4986)
			(layers "F.Cu" "F.Mask" "F.Paste")
			(net "M_J_CPU0_SB_DQS_DP<4>")
		)
		(pad "240" smd rect
			(at 2.050034 22.524974 90)
			(size 0.519938 1.4986)
			(layers "F.Cu" "F.Mask" "F.Paste")
			(net "GND")
		)
		(pad "241" smd rect
			(at 2.050034 23.375112 90)
			(size 0.519938 1.4986)
			(layers "F.Cu" "F.Mask" "F.Paste")
			(net "M_J_CPU0_SB_CB<2>")
		)
		(pad "242" smd rect
			(at 2.050034 24.224996 90)
			(size 0.519938 1.4986)
			(layers "F.Cu" "F.Mask" "F.Paste")
			(net "GND")
		)
		(pad "243" smd rect
			(at 2.050034 25.07488 90)
			(size 0.519938 1.4986)
			(layers "F.Cu" "F.Mask" "F.Paste")
			(net "M_J_CPU0_SB_CB<3>")
		)
		(pad "244" smd rect
			(at 2.050034 25.925018 90)
			(size 0.519938 1.4986)
			(layers "F.Cu" "F.Mask" "F.Paste")
			(net "GND")
		)
		(pad "245" smd rect
			(at 2.050034 26.774902 90)
			(size 0.519938 1.4986)
			(layers "F.Cu" "F.Mask" "F.Paste")
			(net "M_J_CPU0_SB_DQ<2>")
		)
		(pad "246" smd rect
			(at 2.050034 27.62504 90)
			(size 0.519938 1.4986)
			(layers "F.Cu" "F.Mask" "F.Paste")
			(net "GND")
		)
		(pad "247" smd rect
			(at 2.050034 28.474924 90)
			(size 0.519938 1.4986)
			(layers "F.Cu" "F.Mask" "F.Paste")
			(net "M_J_CPU0_SB_DQ<3>")
		)
		(pad "248" smd rect
			(at 2.050034 29.325062 90)
			(size 0.519938 1.4986)
			(layers "F.Cu" "F.Mask" "F.Paste")
			(net "GND")
		)
		(pad "249" smd rect
			(at 2.050034 30.174946 90)
			(size 0.519938 1.4986)
			(layers "F.Cu" "F.Mask" "F.Paste")
			(net "M_J_CPU0_SB_DQS_DN<5>")
		)
		(pad "250" smd rect
			(at 2.050034 31.025084 90)
			(size 0.519938 1.4986)
			(layers "F.Cu" "F.Mask" "F.Paste")
			(net "M_J_CPU0_SB_DQS_DP<5>")
		)
		(pad "251" smd rect
			(at 2.050034 31.874968 90)
			(size 0.519938 1.4986)
			(layers "F.Cu" "F.Mask" "F.Paste")
			(net "GND")
		)
		(pad "252" smd rect
			(at 2.050034 32.725106 90)
			(size 0.519938 1.4986)
			(layers "F.Cu" "F.Mask" "F.Paste")
			(net "M_J_CPU0_SB_DQ<6>")
		)
		(pad "253" smd rect
			(at 2.050034 33.57499 90)
			(size 0.519938 1.4986)
			(layers "F.Cu" "F.Mask" "F.Paste")
			(net "GND")
		)
		(pad "254" smd rect
			(at 2.050034 34.425128 90)
			(size 0.519938 1.4986)
			(layers "F.Cu" "F.Mask" "F.Paste")
			(net "M_J_CPU0_SB_DQ<7>")
		)
		(pad "255" smd rect
			(at 2.050034 35.275012 90)
			(size 0.519938 1.4986)
			(layers "F.Cu" "F.Mask" "F.Paste")
			(net "GND")
		)
		(pad "256" smd rect
			(at 2.050034 36.124896 90)
			(size 0.519938 1.4986)
			(layers "F.Cu" "F.Mask" "F.Paste")
			(net "M_J_CPU0_SB_DQ<10>")
		)
		(pad "257" smd rect
			(at 2.050034 36.975034 90)
			(size 0.519938 1.4986)
			(layers "F.Cu" "F.Mask" "F.Paste")
			(net "GND")
		)
		(pad "258" smd rect
			(at 2.050034 37.824918 90)
			(size 0.519938 1.4986)
			(layers "F.Cu" "F.Mask" "F.Paste")
			(net "M_J_CPU0_SB_DQ<11>")
		)
		(pad "259" smd rect
			(at 2.050034 38.675056 90)
			(size 0.519938 1.4986)
			(layers "F.Cu" "F.Mask" "F.Paste")
			(net "GND")
		)
		(pad "260" smd rect
			(at 2.050034 39.52494 90)
			(size 0.519938 1.4986)
			(layers "F.Cu" "F.Mask" "F.Paste")
			(net "M_J_CPU0_SB_DQS_DN<6>")
		)
		(pad "261" smd rect
			(at 2.050034 40.375078 90)
			(size 0.519938 1.4986)
			(layers "F.Cu" "F.Mask" "F.Paste")
			(net "M_J_CPU0_SB_DQS_DP<6>")
		)
		(pad "262" smd rect
			(at 2.050034 41.224962 90)
			(size 0.519938 1.4986)
			(layers "F.Cu" "F.Mask" "F.Paste")
			(net "GND")
		)
		(pad "263" smd rect
			(at 2.050034 42.0751 90)
			(size 0.519938 1.4986)
			(layers "F.Cu" "F.Mask" "F.Paste")
			(net "M_J_CPU0_SB_DQ<14>")
		)
		(pad "264" smd rect
			(at 2.050034 42.924984 90)
			(size 0.519938 1.4986)
			(layers "F.Cu" "F.Mask" "F.Paste")
			(net "GND")
		)
		(pad "265" smd rect
			(at 2.050034 43.775122 90)
			(size 0.519938 1.4986)
			(layers "F.Cu" "F.Mask" "F.Paste")
			(net "M_J_CPU0_SB_DQ<15>")
		)
		(pad "266" smd rect
			(at 2.050034 44.625006 90)
			(size 0.519938 1.4986)
			(layers "F.Cu" "F.Mask" "F.Paste")
			(net "GND")
		)
		(pad "267" smd rect
			(at 2.050034 45.47489 90)
			(size 0.519938 1.4986)
			(layers "F.Cu" "F.Mask" "F.Paste")
			(net "M_J_CPU0_SB_DQ<18>")
		)
		(pad "268" smd rect
			(at 2.050034 46.325028 90)
			(size 0.519938 1.4986)
			(layers "F.Cu" "F.Mask" "F.Paste")
			(net "GND")
		)
		(pad "269" smd rect
			(at 2.050034 47.174912 90)
			(size 0.519938 1.4986)
			(layers "F.Cu" "F.Mask" "F.Paste")
			(net "M_J_CPU0_SB_DQ<19>")
		)
		(pad "270" smd rect
			(at 2.050034 48.02505 90)
			(size 0.519938 1.4986)
			(layers "F.Cu" "F.Mask" "F.Paste")
			(net "GND")
		)
		(pad "271" smd rect
			(at 2.050034 48.874934 90)
			(size 0.519938 1.4986)
			(layers "F.Cu" "F.Mask" "F.Paste")
			(net "M_J_CPU0_SB_DQS_DN<7>")
		)
		(pad "272" smd rect
			(at 2.050034 49.725072 90)
			(size 0.519938 1.4986)
			(layers "F.Cu" "F.Mask" "F.Paste")
			(net "M_J_CPU0_SB_DQS_DP<7>")
		)
		(pad "273" smd rect
			(at 2.050034 50.574956 90)
			(size 0.519938 1.4986)
			(layers "F.Cu" "F.Mask" "F.Paste")
			(net "GND")
		)
		(pad "274" smd rect
			(at 2.050034 51.425094 90)
			(size 0.519938 1.4986)
			(layers "F.Cu" "F.Mask" "F.Paste")
			(net "M_J_CPU0_SB_DQ<22>")
		)
		(pad "275" smd rect
			(at 2.050034 52.274978 90)
			(size 0.519938 1.4986)
			(layers "F.Cu" "F.Mask" "F.Paste")
			(net "GND")
		)
		(pad "276" smd rect
			(at 2.050034 53.125116 90)
			(size 0.519938 1.4986)
			(layers "F.Cu" "F.Mask" "F.Paste")
			(net "M_J_CPU0_SB_DQ<23>")
		)
		(pad "277" smd rect
			(at 2.050034 53.975 90)
			(size 0.519938 1.4986)
			(layers "F.Cu" "F.Mask" "F.Paste")
			(net "GND")
		)
		(pad "278" smd rect
			(at 2.050034 54.824884 90)
			(size 0.519938 1.4986)
			(layers "F.Cu" "F.Mask" "F.Paste")
			(net "M_J_CPU0_SB_DQ<26>")
		)
		(pad "279" smd rect
			(at 2.050034 55.675022 90)
			(size 0.519938 1.4986)
			(layers "F.Cu" "F.Mask" "F.Paste")
			(net "GND")
		)
		(pad "280" smd rect
			(at 2.050034 56.524906 90)
			(size 0.519938 1.4986)
			(layers "F.Cu" "F.Mask" "F.Paste")
			(net "M_J_CPU0_SB_DQ<27>")
		)
		(pad "281" smd rect
			(at 2.050034 57.375044 90)
			(size 0.519938 1.4986)
			(layers "F.Cu" "F.Mask" "F.Paste")
			(net "GND")
		)
		(pad "282" smd rect
			(at 2.050034 58.224928 90)
			(size 0.519938 1.4986)
			(layers "F.Cu" "F.Mask" "F.Paste")
			(net "M_J_CPU0_SB_DQS_DN<8>")
		)
		(pad "283" smd rect
			(at 2.050034 59.075066 90)
			(size 0.519938 1.4986)
			(layers "F.Cu" "F.Mask" "F.Paste")
			(net "M_J_CPU0_SB_DQS_DP<8>")
		)
		(pad "284" smd rect
			(at 2.050034 59.92495 90)
			(size 0.519938 1.4986)
			(layers "F.Cu" "F.Mask" "F.Paste")
			(net "GND")
		)
		(pad "285" smd rect
			(at 2.050034 60.775088 90)
			(size 0.519938 1.4986)
			(layers "F.Cu" "F.Mask" "F.Paste")
			(net "M_J_CPU0_SB_DQ<30>")
		)
		(pad "286" smd rect
			(at 2.050034 61.624972 90)
			(size 0.519938 1.4986)
			(layers "F.Cu" "F.Mask" "F.Paste")
			(net "GND")
		)
		(pad "287" smd rect
			(at 2.050034 62.47511 90)
			(size 0.519938 1.4986)
			(layers "F.Cu" "F.Mask" "F.Paste")
			(net "M_J_CPU0_SB_DQ<31>")
		)
		(pad "288" smd rect
			(at 2.050034 63.324994 90)
			(size 0.519938 1.4986)
			(layers "F.Cu" "F.Mask" "F.Paste")
			(net "GND")
		)
		(pad "G1" thru_hole oval
			(at 0 -68.97497 90)
			(size 1.7272 3.4798)
			(drill oval 1.2192 2.4638)
			(layers "*.Cu" "*.Mask")
			(remove_unused_layers no)
			(net "GND")
			(clearance 0.127)
			(thermal_gap 0.127)
		)
		(pad "G2" thru_hole oval
			(at 0 3.875024 90)
			(size 1.7272 3.4798)
			(drill oval 1.2192 2.4638)
			(layers "*.Cu" "*.Mask")
			(remove_unused_layers no)
			(net "GND")
			(clearance 0.127)
			(thermal_gap 0.127)
		)
		(pad "G3" thru_hole oval
			(at 0 68.97497 90)
			(size 1.7272 3.4798)
			(drill oval 1.2192 2.4638)
			(layers "*.Cu" "*.Mask")
			(remove_unused_layers no)
			(net "GND")
			(clearance 0.127)
			(thermal_gap 0.127)
		)
	)
	(footprint ""
		(layer "F.Cu")
		(at 61.90488 -18.252948)
		(property "Reference" "R3217"
			(at 0 0 0)
			(layer "F.SilkS")
			(hide yes)
			(effects
				(font
					(size 1.27 1.27)
				)
			)
		)
		(property "Value" ""
			(at 0 0 0)
			(layer "F.Fab")
			(effects
				(font
					(size 1.27 1.27)
				)
			)
		)
		(duplicate_pad_numbers_are_jumpers no)
		(fp_line
			(start -0.7874 -0.4064)
			(end 0.7874 -0.4064)
			(stroke
				(width 0.1524)
				(type default)
			)
			(layer "F.SilkS")
		)
		(fp_line
			(start -0.7874 0.4064)
			(end -0.7874 -0.4064)
			(stroke
				(width 0.1524)
				(type default)
			)
			(layer "F.SilkS")
		)
		(fp_line
			(start 0.7874 -0.4064)
			(end 0.7874 0.4064)
			(stroke
				(width 0.1524)
				(type default)
			)
			(layer "F.SilkS")
		)
		(fp_line
			(start 0.7874 0.4064)
			(end -0.7874 0.4064)
			(stroke
				(width 0.1524)
				(type default)
			)
			(layer "F.SilkS")
		)
		(fp_line
			(start -0.67945 -0.305054)
			(end -0.12065 -0.305054)
			(stroke
				(width 0.1)
				(type default)
			)
			(layer "F.Fab")
		)
		(fp_line
			(start -0.67945 0.3048)
			(end -0.67945 -0.305054)
			(stroke
				(width 0.1)
				(type default)
			)
			(layer "F.Fab")
		)
		(fp_line
			(start -0.12065 -0.305054)
			(end -0.12065 -0.2794)
			(stroke
				(width 0.1)
				(type default)
			)
			(layer "F.Fab")
		)
		(fp_line
			(start -0.12065 -0.2794)
			(end 0.12065 -0.2794)
			(stroke
				(width 0.1)
				(type default)
			)
			(layer "F.Fab")
		)
		(fp_line
			(start -0.12065 0.2794)
			(end -0.12065 0.3048)
			(stroke
				(width 0.1)
				(type default)
			)
			(layer "F.Fab")
		)
		(fp_line
			(start -0.12065 0.3048)
			(end -0.67945 0.3048)
			(stroke
				(width 0.1)
				(type default)
			)
			(layer "F.Fab")
		)
		(fp_line
			(start 0.120396 0.2794)
			(end -0.12065 0.2794)
			(stroke
				(width 0.1)
				(type default)
			)
			(layer "F.Fab")
		)
		(fp_line
			(start 0.120396 0.3048)
			(end 0.120396 0.2794)
			(stroke
				(width 0.1)
				(type default)
			)
			(layer "F.Fab")
		)
		(fp_line
			(start 0.12065 -0.3048)
			(end 0.67945 -0.3048)
			(stroke
				(width 0.1)
				(type default)
			)
			(layer "F.Fab")
		)
		(fp_line
			(start 0.12065 -0.2794)
			(end 0.12065 -0.3048)
			(stroke
				(width 0.1)
				(type default)
			)
			(layer "F.Fab")
		)
		(fp_line
			(start 0.67945 -0.3048)
			(end 0.67945 0.3048)
			(stroke
				(width 0.1)
				(type default)
			)
			(layer "F.Fab")
		)
		(fp_line
			(start 0.67945 0.3048)
			(end 0.120396 0.3048)
			(stroke
				(width 0.1)
				(type default)
			)
			(layer "F.Fab")
		)
		(pad "1" smd circle
			(at -0.40005 0)
			(size 0 0)
			(layers "F.Cu" "F.Mask" "F.Paste")
			(net "OCP_V3_2_ISO_BIF2_EN")
		)
		(pad "2" smd circle
			(at 0.40005 0)
			(size 0 0)
			(layers "F.Cu" "F.Mask" "F.Paste")
			(net "GND")
		)
	)
	(footprint ""
		(layer "F.Cu")
		(at 143.350488 -394.903452 90)
		(property "Reference" "R860"
			(at 0 0 90)
			(layer "F.SilkS")
			(hide yes)
			(effects
				(font
					(size 1.27 1.27)
				)
			)
		)
		(property "Value" ""
			(at 0 0 90)
			(layer "F.Fab")
			(effects
				(font
					(size 1.27 1.27)
				)
			)
		)
		(duplicate_pad_numbers_are_jumpers no)
		(fp_line
			(start 0.32512 -0.175006)
			(end 0.32512 0.175006)
			(stroke
				(width 0.1)
				(type default)
			)
			(layer "F.Fab")
		)
		(fp_line
			(start -0.32512 -0.175006)
			(end 0.32512 -0.175006)
			(stroke
				(width 0.1)
				(type default)
			)
			(layer "F.Fab")
		)
		(fp_line
			(start 0.32512 0.175006)
			(end -0.32512 0.175006)
			(stroke
				(width 0.1)
				(type default)
			)
			(layer "F.Fab")
		)
		(fp_line
			(start -0.32512 0.175006)
			(end -0.32512 -0.175006)
			(stroke
				(width 0.1)
				(type default)
			)
			(layer "F.Fab")
		)
		(pad "1" smd rect
			(at -0.2667 0 90)
			(size 0.3048 0.381)
			(layers "F.Cu" "F.Mask" "F.Paste")
			(net "RST_RT_CPU1_P2_RESET_N")
		)
		(pad "2" smd rect
			(at 0.2667 0 270)
			(size 0.3048 0.381)
			(layers "F.Cu" "F.Mask" "F.Paste")
			(net "RST_RT_CPU1_P2_RESET_R_N")
		)
	)
	(footprint ""
		(layer "F.Cu")
		(at 424.755564 -16.100298 90)
		(property "Reference" "C1573"
			(at 0 0 90)
			(layer "F.SilkS")
			(hide yes)
			(effects
				(font
					(size 1.27 1.27)
				)
			)
		)
		(property "Value" ""
			(at 0 0 90)
			(layer "F.Fab")
			(effects
				(font
					(size 1.27 1.27)
				)
			)
		)
		(duplicate_pad_numbers_are_jumpers no)
		(fp_line
			(start 0.299974 -0.150114)
			(end 0.299974 0.150114)
			(stroke
				(width 0.1)
				(type default)
			)
			(layer "F.Fab")
		)
		(fp_line
			(start -0.299974 -0.150114)
			(end 0.299974 -0.150114)
			(stroke
				(width 0.1)
				(type default)
			)
			(layer "F.Fab")
		)
		(fp_line
			(start 0.299974 0.150114)
			(end -0.299974 0.150114)
			(stroke
				(width 0.1)
				(type default)
			)
			(layer "F.Fab")
		)
		(fp_line
			(start -0.299974 0.150114)
			(end -0.299974 -0.150114)
			(stroke
				(width 0.1)
				(type default)
			)
			(layer "F.Fab")
		)
		(pad "1" smd rect
			(at -0.2667 0 90)
			(size 0.3048 0.381)
			(layers "F.Cu" "F.Mask" "F.Paste")
			(net "P5E_CPU0_G3_TX_C_DP<3>")
		)
		(pad "2" smd rect
			(at 0.2667 0 90)
			(size 0.3048 0.381)
			(layers "F.Cu" "F.Mask" "F.Paste")
			(net "P5E_CPU0_G3_TX_DP<3>")
		)
	)
	(footprint ""
		(layer "F.Cu")
		(at 106.934 -13.909548 180)
		(property "Reference" "R4208"
			(at 0 0 180)
			(layer "F.SilkS")
			(hide yes)
			(effects
				(font
					(size 1.27 1.27)
				)
			)
		)
		(property "Value" ""
			(at 0 0 180)
			(layer "F.Fab")
			(effects
				(font
					(size 1.27 1.27)
				)
			)
		)
		(duplicate_pad_numbers_are_jumpers no)
		(fp_line
			(start 0.7874 0.4064)
			(end -0.7874 0.4064)
			(stroke
				(width 0.1524)
				(type default)
			)
			(layer "F.SilkS")
		)
		(fp_line
			(start 0.7874 -0.4064)
			(end 0.7874 0.4064)
			(stroke
				(width 0.1524)
				(type default)
			)
			(layer "F.SilkS")
		)
		(fp_line
			(start -0.7874 0.4064)
			(end -0.7874 -0.4064)
			(stroke
				(width 0.1524)
				(type default)
			)
			(layer "F.SilkS")
		)
		(fp_line
			(start -0.7874 -0.4064)
			(end 0.7874 -0.4064)
			(stroke
				(width 0.1524)
				(type default)
			)
			(layer "F.SilkS")
		)
		(fp_line
			(start 0.67945 0.3048)
			(end 0.120396 0.3048)
			(stroke
				(width 0.1)
				(type default)
			)
			(layer "F.Fab")
		)
		(fp_line
			(start 0.67945 -0.3048)
			(end 0.67945 0.3048)
			(stroke
				(width 0.1)
				(type default)
			)
			(layer "F.Fab")
		)
		(fp_line
			(start 0.12065 -0.2794)
			(end 0.12065 -0.3048)
			(stroke
				(width 0.1)
				(type default)
			)
			(layer "F.Fab")
		)
		(fp_line
			(start 0.12065 -0.3048)
			(end 0.67945 -0.3048)
			(stroke
				(width 0.1)
				(type default)
			)
			(layer "F.Fab")
		)
		(fp_line
			(start 0.120396 0.3048)
			(end 0.120396 0.2794)
			(stroke
				(width 0.1)
				(type default)
			)
			(layer "F.Fab")
		)
		(fp_line
			(start 0.120396 0.2794)
			(end -0.12065 0.2794)
			(stroke
				(width 0.1)
				(type default)
			)
			(layer "F.Fab")
		)
		(fp_line
			(start -0.12065 0.3048)
			(end -0.67945 0.3048)
			(stroke
				(width 0.1)
				(type default)
			)
			(layer "F.Fab")
		)
		(fp_line
			(start -0.12065 0.2794)
			(end -0.12065 0.3048)
			(stroke
				(width 0.1)
				(type default)
			)
			(layer "F.Fab")
		)
		(fp_line
			(start -0.12065 -0.2794)
			(end 0.12065 -0.2794)
			(stroke
				(width 0.1)
				(type default)
			)
			(layer "F.Fab")
		)
		(fp_line
			(start -0.12065 -0.305054)
			(end -0.12065 -0.2794)
			(stroke
				(width 0.1)
				(type default)
			)
			(layer "F.Fab")
		)
		(fp_line
			(start -0.67945 0.3048)
			(end -0.67945 -0.305054)
			(stroke
				(width 0.1)
				(type default)
			)
			(layer "F.Fab")
		)
		(fp_line
			(start -0.67945 -0.305054)
			(end -0.12065 -0.305054)
			(stroke
				(width 0.1)
				(type default)
			)
			(layer "F.Fab")
		)
		(pad "1" smd circle
			(at -0.40005 0 180)
			(size 0 0)
			(layers "F.Cu" "F.Mask" "F.Paste")
			(net "P3V3_AUX")
		)
		(pad "2" smd circle
			(at 0.40005 0 180)
			(size 0 0)
			(layers "F.Cu" "F.Mask" "F.Paste")
			(net "FM_THERMAL_ALERT_N")
		)
	)
	(footprint ""
		(layer "F.Cu")
		(at 331.337666 -416.899344 -90)
		(property "Reference" "C6520"
			(at 0 0 270)
			(layer "F.SilkS")
			(hide yes)
			(effects
				(font
					(size 1.27 1.27)
				)
			)
		)
		(property "Value" ""
			(at 0 0 270)
			(layer "F.Fab")
			(effects
				(font
					(size 1.27 1.27)
				)
			)
		)
		(duplicate_pad_numbers_are_jumpers no)
		(fp_line
			(start -0.299974 0.150114)
			(end -0.299974 -0.150114)
			(stroke
				(width 0.1)
				(type default)
			)
			(layer "F.Fab")
		)
		(fp_line
			(start 0.299974 0.150114)
			(end -0.299974 0.150114)
			(stroke
				(width 0.1)
				(type default)
			)
			(layer "F.Fab")
		)
		(fp_line
			(start -0.299974 -0.150114)
			(end 0.299974 -0.150114)
			(stroke
				(width 0.1)
				(type default)
			)
			(layer "F.Fab")
		)
		(fp_line
			(start 0.299974 -0.150114)
			(end 0.299974 0.150114)
			(stroke
				(width 0.1)
				(type default)
			)
			(layer "F.Fab")
		)
		(pad "1" smd rect
			(at -0.2667 0 270)
			(size 0.3048 0.381)
			(layers "F.Cu" "F.Mask" "F.Paste")
			(net "P5E_CPU0_P0_TX_BUF_C_DN<9>")
		)
		(pad "2" smd rect
			(at 0.2667 0 270)
			(size 0.3048 0.381)
			(layers "F.Cu" "F.Mask" "F.Paste")
			(net "P5E_CPU0_P0_TX_BUF_DN<9>")
		)
	)
	(footprint ""
		(layer "F.Cu")
		(at 305.177698 -118.179088)
		(property "Reference" "R717"
			(at 0 0 0)
			(layer "F.SilkS")
			(hide yes)
			(effects
				(font
					(size 1.27 1.27)
				)
			)
		)
		(property "Value" ""
			(at 0 0 0)
			(layer "F.Fab")
			(effects
				(font
					(size 1.27 1.27)
				)
			)
		)
		(duplicate_pad_numbers_are_jumpers no)
		(fp_line
			(start -0.7874 -0.4064)
			(end 0.7874 -0.4064)
			(stroke
				(width 0.1524)
				(type default)
			)
			(layer "F.SilkS")
		)
		(fp_line
			(start -0.7874 0.4064)
			(end -0.7874 -0.4064)
			(stroke
				(width 0.1524)
				(type default)
			)
			(layer "F.SilkS")
		)
		(fp_line
			(start 0.7874 -0.4064)
			(end 0.7874 0.4064)
			(stroke
				(width 0.1524)
				(type default)
			)
			(layer "F.SilkS")
		)
		(fp_line
			(start 0.7874 0.4064)
			(end -0.7874 0.4064)
			(stroke
				(width 0.1524)
				(type default)
			)
			(layer "F.SilkS")
		)
		(fp_line
			(start -0.67945 -0.305054)
			(end -0.12065 -0.305054)
			(stroke
				(width 0.1)
				(type default)
			)
			(layer "F.Fab")
		)
		(fp_line
			(start -0.67945 0.3048)
			(end -0.67945 -0.305054)
			(stroke
				(width 0.1)
				(type default)
			)
			(layer "F.Fab")
		)
		(fp_line
			(start -0.12065 -0.305054)
			(end -0.12065 -0.2794)
			(stroke
				(width 0.1)
				(type default)
			)
			(layer "F.Fab")
		)
		(fp_line
			(start -0.12065 -0.2794)
			(end 0.12065 -0.2794)
			(stroke
				(width 0.1)
				(type default)
			)
			(layer "F.Fab")
		)
		(fp_line
			(start -0.12065 0.2794)
			(end -0.12065 0.3048)
			(stroke
				(width 0.1)
				(type default)
			)
			(layer "F.Fab")
		)
		(fp_line
			(start -0.12065 0.3048)
			(end -0.67945 0.3048)
			(stroke
				(width 0.1)
				(type default)
			)
			(layer "F.Fab")
		)
		(fp_line
			(start 0.120396 0.2794)
			(end -0.12065 0.2794)
			(stroke
				(width 0.1)
				(type default)
			)
			(layer "F.Fab")
		)
		(fp_line
			(start 0.120396 0.3048)
			(end 0.120396 0.2794)
			(stroke
				(width 0.1)
				(type default)
			)
			(layer "F.Fab")
		)
		(fp_line
			(start 0.12065 -0.3048)
			(end 0.67945 -0.3048)
			(stroke
				(width 0.1)
				(type default)
			)
			(layer "F.Fab")
		)
		(fp_line
			(start 0.12065 -0.2794)
			(end 0.12065 -0.3048)
			(stroke
				(width 0.1)
				(type default)
			)
			(layer "F.Fab")
		)
		(fp_line
			(start 0.67945 -0.3048)
			(end 0.67945 0.3048)
			(stroke
				(width 0.1)
				(type default)
			)
			(layer "F.Fab")
		)
		(fp_line
			(start 0.67945 0.3048)
			(end 0.120396 0.3048)
			(stroke
				(width 0.1)
				(type default)
			)
			(layer "F.Fab")
		)
		(pad "1" smd circle
			(at -0.40005 0)
			(size 0 0)
			(layers "F.Cu" "F.Mask" "F.Paste")
			(net "P3V3_AUX")
		)
		(pad "2" smd circle
			(at 0.40005 0)
			(size 0 0)
			(layers "F.Cu" "F.Mask" "F.Paste")
			(net "MB_FRU_ADDR1")
		)
	)
	(footprint ""
		(layer "F.Cu")
		(at 200.952608 -113.625376 180)
		(property "Reference" "R1314"
			(at 0 0 180)
			(layer "F.SilkS")
			(hide yes)
			(effects
				(font
					(size 1.27 1.27)
				)
			)
		)
		(property "Value" ""
			(at 0 0 180)
			(layer "F.Fab")
			(effects
				(font
					(size 1.27 1.27)
				)
			)
		)
		(duplicate_pad_numbers_are_jumpers no)
		(fp_line
			(start 0.7874 0.4064)
			(end -0.7874 0.4064)
			(stroke
				(width 0.1524)
				(type default)
			)
			(layer "F.SilkS")
		)
		(fp_line
			(start 0.7874 -0.4064)
			(end 0.7874 0.4064)
			(stroke
				(width 0.1524)
				(type default)
			)
			(layer "F.SilkS")
		)
		(fp_line
			(start -0.7874 0.4064)
			(end -0.7874 -0.4064)
			(stroke
				(width 0.1524)
				(type default)
			)
			(layer "F.SilkS")
		)
		(fp_line
			(start -0.7874 -0.4064)
			(end 0.7874 -0.4064)
			(stroke
				(width 0.1524)
				(type default)
			)
			(layer "F.SilkS")
		)
		(fp_line
			(start 0.67945 0.3048)
			(end 0.120396 0.3048)
			(stroke
				(width 0.1)
				(type default)
			)
			(layer "F.Fab")
		)
		(fp_line
			(start 0.67945 -0.3048)
			(end 0.67945 0.3048)
			(stroke
				(width 0.1)
				(type default)
			)
			(layer "F.Fab")
		)
		(fp_line
			(start 0.12065 -0.2794)
			(end 0.12065 -0.3048)
			(stroke
				(width 0.1)
				(type default)
			)
			(layer "F.Fab")
		)
		(fp_line
			(start 0.12065 -0.3048)
			(end 0.67945 -0.3048)
			(stroke
				(width 0.1)
				(type default)
			)
			(layer "F.Fab")
		)
		(fp_line
			(start 0.120396 0.3048)
			(end 0.120396 0.2794)
			(stroke
				(width 0.1)
				(type default)
			)
			(layer "F.Fab")
		)
		(fp_line
			(start 0.120396 0.2794)
			(end -0.12065 0.2794)
			(stroke
				(width 0.1)
				(type default)
			)
			(layer "F.Fab")
		)
		(fp_line
			(start -0.12065 0.3048)
			(end -0.67945 0.3048)
			(stroke
				(width 0.1)
				(type default)
			)
			(layer "F.Fab")
		)
		(fp_line
			(start -0.12065 0.2794)
			(end -0.12065 0.3048)
			(stroke
				(width 0.1)
				(type default)
			)
			(layer "F.Fab")
		)
		(fp_line
			(start -0.12065 -0.2794)
			(end 0.12065 -0.2794)
			(stroke
				(width 0.1)
				(type default)
			)
			(layer "F.Fab")
		)
		(fp_line
			(start -0.12065 -0.305054)
			(end -0.12065 -0.2794)
			(stroke
				(width 0.1)
				(type default)
			)
			(layer "F.Fab")
		)
		(fp_line
			(start -0.67945 0.3048)
			(end -0.67945 -0.305054)
			(stroke
				(width 0.1)
				(type default)
			)
			(layer "F.Fab")
		)
		(fp_line
			(start -0.67945 -0.305054)
			(end -0.12065 -0.305054)
			(stroke
				(width 0.1)
				(type default)
			)
			(layer "F.Fab")
		)
		(pad "1" smd circle
			(at -0.40005 0 180)
			(size 0 0)
			(layers "F.Cu" "F.Mask" "F.Paste")
			(net "E1S_0_P12V_EN")
		)
		(pad "2" smd circle
			(at 0.40005 0 180)
			(size 0 0)
			(layers "F.Cu" "F.Mask" "F.Paste")
			(net "P3V3_AUX")
		)
	)
	(footprint ""
		(layer "F.Cu")
		(at 72.466454 -148.635212 179.946)
		(property "Reference" "PR147"
			(at 0 0 179.946)
			(layer "F.SilkS")
			(hide yes)
			(effects
				(font
					(size 1.27 1.27)
				)
			)
		)
		(property "Value" ""
			(at 0 0 179.946)
			(layer "F.Fab")
			(effects
				(font
					(size 1.27 1.27)
				)
			)
		)
		(duplicate_pad_numbers_are_jumpers no)
		(fp_line
			(start 0.787525 -0.40638)
			(end 0.787275 0.40642)
			(stroke
				(width 0.1524)
				(type default)
			)
			(layer "F.SilkS")
		)
		(fp_line
			(start 0.787275 0.40642)
			(end -0.787525 0.40638)
			(stroke
				(width 0.1524)
				(type default)
			)
			(layer "F.SilkS")
		)
		(fp_line
			(start -0.787275 -0.40642)
			(end 0.787525 -0.40638)
			(stroke
				(width 0.1524)
				(type default)
			)
			(layer "F.SilkS")
		)
		(fp_line
			(start -0.787525 0.40638)
			(end -0.787275 -0.40642)
			(stroke
				(width 0.1524)
				(type default)
			)
			(layer "F.SilkS")
		)
		(fp_line
			(start 0.679417 -0.304678)
			(end 0.679484 0.304922)
			(stroke
				(width 0.1)
				(type default)
			)
			(layer "F.Fab")
		)
		(fp_line
			(start 0.679484 0.304922)
			(end 0.120429 0.304687)
			(stroke
				(width 0.1)
				(type default)
			)
			(layer "F.Fab")
		)
		(fp_line
			(start 0.120641 -0.279514)
			(end 0.120617 -0.304914)
			(stroke
				(width 0.1)
				(type default)
			)
			(layer "F.Fab")
		)
		(fp_line
			(start 0.120617 -0.304914)
			(end 0.679417 -0.304678)
			(stroke
				(width 0.1)
				(type default)
			)
			(layer "F.Fab")
		)
		(fp_line
			(start 0.120429 0.304687)
			(end 0.120405 0.279287)
			(stroke
				(width 0.1)
				(type default)
			)
			(layer "F.Fab")
		)
		(fp_line
			(start 0.120405 0.279287)
			(end -0.120641 0.279514)
			(stroke
				(width 0.1)
				(type default)
			)
			(layer "F.Fab")
		)
		(fp_line
			(start -0.120659 -0.279286)
			(end 0.120641 -0.279514)
			(stroke
				(width 0.1)
				(type default)
			)
			(layer "F.Fab")
		)
		(fp_line
			(start -0.120683 -0.30494)
			(end -0.120659 -0.279286)
			(stroke
				(width 0.1)
				(type default)
			)
			(layer "F.Fab")
		)
		(fp_line
			(start -0.120617 0.304914)
			(end -0.679417 0.304678)
			(stroke
				(width 0.1)
				(type default)
			)
			(layer "F.Fab")
		)
		(fp_line
			(start -0.120641 0.279514)
			(end -0.120617 0.304914)
			(stroke
				(width 0.1)
				(type default)
			)
			(layer "F.Fab")
		)
		(fp_line
			(start -0.679484 -0.305176)
			(end -0.120683 -0.30494)
			(stroke
				(width 0.1)
				(type default)
			)
			(layer "F.Fab")
		)
		(fp_line
			(start -0.679417 0.304678)
			(end -0.679484 -0.305176)
			(stroke
				(width 0.1)
				(type default)
			)
			(layer "F.Fab")
		)
		(pad "1" smd circle
			(at -0.40005 0 179.946)
			(size 0 0)
			(layers "F.Cu" "F.Mask" "F.Paste")
			(net "PVDD18_S5_P1_FB")
		)
		(pad "2" smd circle
			(at 0.40005 0 179.946)
			(size 0 0)
			(layers "F.Cu" "F.Mask" "F.Paste")
			(net "PVDD18_SS_P1_RGND")
		)
	)
	(footprint ""
		(layer "F.Cu")
		(at 368.600736 -403.818852 -90)
		(property "Reference" "R1122"
			(at 0 0 270)
			(layer "F.SilkS")
			(hide yes)
			(effects
				(font
					(size 1.27 1.27)
				)
			)
		)
		(property "Value" ""
			(at 0 0 270)
			(layer "F.Fab")
			(effects
				(font
					(size 1.27 1.27)
				)
			)
		)
		(duplicate_pad_numbers_are_jumpers no)
		(fp_line
			(start -0.32512 0.175006)
			(end -0.32512 -0.175006)
			(stroke
				(width 0.1)
				(type default)
			)
			(layer "F.Fab")
		)
		(fp_line
			(start 0.32512 0.175006)
			(end -0.32512 0.175006)
			(stroke
				(width 0.1)
				(type default)
			)
			(layer "F.Fab")
		)
		(fp_line
			(start -0.32512 -0.175006)
			(end 0.32512 -0.175006)
			(stroke
				(width 0.1)
				(type default)
			)
			(layer "F.Fab")
		)
		(fp_line
			(start 0.32512 -0.175006)
			(end 0.32512 0.175006)
			(stroke
				(width 0.1)
				(type default)
			)
			(layer "F.Fab")
		)
		(pad "1" smd rect
			(at -0.2667 0 270)
			(size 0.3048 0.381)
			(layers "F.Cu" "F.Mask" "F.Paste")
			(net "P1V8_CPU0_RT_1D")
		)
		(pad "2" smd rect
			(at 0.2667 0 90)
			(size 0.3048 0.381)
			(layers "F.Cu" "F.Mask" "F.Paste")
			(net "MODE_RT_CPU0_P3")
		)
	)
	(footprint ""
		(layer "F.Cu")
		(at 147.16379 -102.294182 90)
		(property "Reference" "C2007"
			(at 0 0 90)
			(layer "F.SilkS")
			(hide yes)
			(effects
				(font
					(size 1.27 1.27)
				)
			)
		)
		(property "Value" ""
			(at 0 0 90)
			(layer "F.Fab")
			(effects
				(font
					(size 1.27 1.27)
				)
			)
		)
		(duplicate_pad_numbers_are_jumpers no)
		(fp_line
			(start 0.7874 -0.4064)
			(end 0.7874 0.4064)
			(stroke
				(width 0.1524)
				(type default)
			)
			(layer "F.SilkS")
		)
		(fp_line
			(start -0.7874 -0.4064)
			(end 0.7874 -0.4064)
			(stroke
				(width 0.1524)
				(type default)
			)
			(layer "F.SilkS")
		)
		(fp_line
			(start 0.7874 0.4064)
			(end -0.7874 0.4064)
			(stroke
				(width 0.1524)
				(type default)
			)
			(layer "F.SilkS")
		)
		(fp_line
			(start -0.7874 0.4064)
			(end -0.7874 -0.4064)
			(stroke
				(width 0.1524)
				(type default)
			)
			(layer "F.SilkS")
		)
		(fp_line
			(start -0.12065 -0.305054)
			(end -0.12065 -0.2794)
			(stroke
				(width 0.1)
				(type default)
			)
			(layer "F.Fab")
		)
		(fp_line
			(start -0.67945 -0.305054)
			(end -0.12065 -0.305054)
			(stroke
				(width 0.1)
				(type default)
			)
			(layer "F.Fab")
		)
		(fp_line
			(start 0.67945 -0.3048)
			(end 0.67945 0.3048)
			(stroke
				(width 0.1)
				(type default)
			)
			(layer "F.Fab")
		)
		(fp_line
			(start 0.12065 -0.3048)
			(end 0.67945 -0.3048)
			(stroke
				(width 0.1)
				(type default)
			)
			(layer "F.Fab")
		)
		(fp_line
			(start 0.12065 -0.2794)
			(end 0.12065 -0.3048)
			(stroke
				(width 0.1)
				(type default)
			)
			(layer "F.Fab")
		)
		(fp_line
			(start -0.12065 -0.2794)
			(end 0.12065 -0.2794)
			(stroke
				(width 0.1)
				(type default)
			)
			(layer "F.Fab")
		)
		(fp_line
			(start 0.120396 0.2794)
			(end -0.12065 0.2794)
			(stroke
				(width 0.1)
				(type default)
			)
			(layer "F.Fab")
		)
		(fp_line
			(start -0.12065 0.2794)
			(end -0.12065 0.3048)
			(stroke
				(width 0.1)
				(type default)
			)
			(layer "F.Fab")
		)
		(fp_line
			(start 0.67945 0.3048)
			(end 0.120396 0.3048)
			(stroke
				(width 0.1)
				(type default)
			)
			(layer "F.Fab")
		)
		(fp_line
			(start 0.120396 0.3048)
			(end 0.120396 0.2794)
			(stroke
				(width 0.1)
				(type default)
			)
			(layer "F.Fab")
		)
		(fp_line
			(start -0.12065 0.3048)
			(end -0.67945 0.3048)
			(stroke
				(width 0.1)
				(type default)
			)
			(layer "F.Fab")
		)
		(fp_line
			(start -0.67945 0.3048)
			(end -0.67945 -0.305054)
			(stroke
				(width 0.1)
				(type default)
			)
			(layer "F.Fab")
		)
		(pad "1" smd circle
			(at -0.40005 0 90)
			(size 0 0)
			(layers "F.Cu" "F.Mask" "F.Paste")
			(net "P3V3_AUX")
		)
		(pad "2" smd circle
			(at 0.40005 0 90)
			(size 0 0)
			(layers "F.Cu" "F.Mask" "F.Paste")
			(net "GND")
		)
	)
	(footprint ""
		(layer "F.Cu")
		(at 90.209878 -142.85341)
		(property "Reference" "R8179"
			(at 0 0 0)
			(layer "F.SilkS")
			(hide yes)
			(effects
				(font
					(size 1.27 1.27)
				)
			)
		)
		(property "Value" ""
			(at 0 0 0)
			(layer "F.Fab")
			(effects
				(font
					(size 1.27 1.27)
				)
			)
		)
		(duplicate_pad_numbers_are_jumpers no)
		(fp_line
			(start -0.7874 -0.4064)
			(end 0.7874 -0.4064)
			(stroke
				(width 0.1524)
				(type default)
			)
			(layer "F.SilkS")
		)
		(fp_line
			(start -0.7874 0.4064)
			(end -0.7874 -0.4064)
			(stroke
				(width 0.1524)
				(type default)
			)
			(layer "F.SilkS")
		)
		(fp_line
			(start 0.7874 -0.4064)
			(end 0.7874 0.4064)
			(stroke
				(width 0.1524)
				(type default)
			)
			(layer "F.SilkS")
		)
		(fp_line
			(start 0.7874 0.4064)
			(end -0.7874 0.4064)
			(stroke
				(width 0.1524)
				(type default)
			)
			(layer "F.SilkS")
		)
		(fp_line
			(start -0.67945 -0.305054)
			(end -0.12065 -0.305054)
			(stroke
				(width 0.1)
				(type default)
			)
			(layer "F.Fab")
		)
		(fp_line
			(start -0.67945 0.3048)
			(end -0.67945 -0.305054)
			(stroke
				(width 0.1)
				(type default)
			)
			(layer "F.Fab")
		)
		(fp_line
			(start -0.12065 -0.305054)
			(end -0.12065 -0.2794)
			(stroke
				(width 0.1)
				(type default)
			)
			(layer "F.Fab")
		)
		(fp_line
			(start -0.12065 -0.2794)
			(end 0.12065 -0.2794)
			(stroke
				(width 0.1)
				(type default)
			)
			(layer "F.Fab")
		)
		(fp_line
			(start -0.12065 0.2794)
			(end -0.12065 0.3048)
			(stroke
				(width 0.1)
				(type default)
			)
			(layer "F.Fab")
		)
		(fp_line
			(start -0.12065 0.3048)
			(end -0.67945 0.3048)
			(stroke
				(width 0.1)
				(type default)
			)
			(layer "F.Fab")
		)
		(fp_line
			(start 0.120396 0.2794)
			(end -0.12065 0.2794)
			(stroke
				(width 0.1)
				(type default)
			)
			(layer "F.Fab")
		)
		(fp_line
			(start 0.120396 0.3048)
			(end 0.120396 0.2794)
			(stroke
				(width 0.1)
				(type default)
			)
			(layer "F.Fab")
		)
		(fp_line
			(start 0.12065 -0.3048)
			(end 0.67945 -0.3048)
			(stroke
				(width 0.1)
				(type default)
			)
			(layer "F.Fab")
		)
		(fp_line
			(start 0.12065 -0.2794)
			(end 0.12065 -0.3048)
			(stroke
				(width 0.1)
				(type default)
			)
			(layer "F.Fab")
		)
		(fp_line
			(start 0.67945 -0.3048)
			(end 0.67945 0.3048)
			(stroke
				(width 0.1)
				(type default)
			)
			(layer "F.Fab")
		)
		(fp_line
			(start 0.67945 0.3048)
			(end 0.120396 0.3048)
			(stroke
				(width 0.1)
				(type default)
			)
			(layer "F.Fab")
		)
		(pad "1" smd circle
			(at -0.40005 0)
			(size 0 0)
			(layers "F.Cu" "F.Mask" "F.Paste")
			(net "PVDDCR_CPU0_P1_EN")
		)
		(pad "2" smd circle
			(at 0.40005 0)
			(size 0 0)
			(layers "F.Cu" "F.Mask" "F.Paste")
			(net "PVDDCR_CPU0_P1_EN_R")
		)
	)
	(footprint ""
		(layer "F.Cu")
		(at 11.421618 -106.28249 -90)
		(property "Reference" "R2788"
			(at 0 0 270)
			(layer "F.SilkS")
			(hide yes)
			(effects
				(font
					(size 1.27 1.27)
				)
			)
		)
		(property "Value" ""
			(at 0 0 270)
			(layer "F.Fab")
			(effects
				(font
					(size 1.27 1.27)
				)
			)
		)
		(duplicate_pad_numbers_are_jumpers no)
		(fp_line
			(start -0.7874 0.4064)
			(end -0.7874 -0.4064)
			(stroke
				(width 0.1524)
				(type default)
			)
			(layer "F.SilkS")
		)
		(fp_line
			(start 0.7874 0.4064)
			(end -0.7874 0.4064)
			(stroke
				(width 0.1524)
				(type default)
			)
			(layer "F.SilkS")
		)
		(fp_line
			(start -0.7874 -0.4064)
			(end 0.7874 -0.4064)
			(stroke
				(width 0.1524)
				(type default)
			)
			(layer "F.SilkS")
		)
		(fp_line
			(start 0.7874 -0.4064)
			(end 0.7874 0.4064)
			(stroke
				(width 0.1524)
				(type default)
			)
			(layer "F.SilkS")
		)
		(fp_line
			(start -0.67945 0.3048)
			(end -0.67945 -0.305054)
			(stroke
				(width 0.1)
				(type default)
			)
			(layer "F.Fab")
		)
		(fp_line
			(start -0.12065 0.3048)
			(end -0.67945 0.3048)
			(stroke
				(width 0.1)
				(type default)
			)
			(layer "F.Fab")
		)
		(fp_line
			(start 0.120396 0.3048)
			(end 0.120396 0.2794)
			(stroke
				(width 0.1)
				(type default)
			)
			(layer "F.Fab")
		)
		(fp_line
			(start 0.67945 0.3048)
			(end 0.120396 0.3048)
			(stroke
				(width 0.1)
				(type default)
			)
			(layer "F.Fab")
		)
		(fp_line
			(start -0.12065 0.2794)
			(end -0.12065 0.3048)
			(stroke
				(width 0.1)
				(type default)
			)
			(layer "F.Fab")
		)
		(fp_line
			(start 0.120396 0.2794)
			(end -0.12065 0.2794)
			(stroke
				(width 0.1)
				(type default)
			)
			(layer "F.Fab")
		)
		(fp_line
			(start -0.12065 -0.2794)
			(end 0.12065 -0.2794)
			(stroke
				(width 0.1)
				(type default)
			)
			(layer "F.Fab")
		)
		(fp_line
			(start 0.12065 -0.2794)
			(end 0.12065 -0.3048)
			(stroke
				(width 0.1)
				(type default)
			)
			(layer "F.Fab")
		)
		(fp_line
			(start 0.12065 -0.3048)
			(end 0.67945 -0.3048)
			(stroke
				(width 0.1)
				(type default)
			)
			(layer "F.Fab")
		)
		(fp_line
			(start 0.67945 -0.3048)
			(end 0.67945 0.3048)
			(stroke
				(width 0.1)
				(type default)
			)
			(layer "F.Fab")
		)
		(fp_line
			(start -0.67945 -0.305054)
			(end -0.12065 -0.305054)
			(stroke
				(width 0.1)
				(type default)
			)
			(layer "F.Fab")
		)
		(fp_line
			(start -0.12065 -0.305054)
			(end -0.12065 -0.2794)
			(stroke
				(width 0.1)
				(type default)
			)
			(layer "F.Fab")
		)
		(pad "1" smd rect
			(at -0.40005 0 90)
			(size 0.4572 0.508)
			(layers "F.Cu" "F.Mask" "F.Paste")
			(net "USB2_HOST_BMC_B_BUF_DP")
		)
		(pad "2" smd rect
			(at 0.40005 0 90)
			(size 0.4572 0.508)
			(layers "F.Cu" "F.Mask" "F.Paste")
			(net "USB2_HUB_BUF_SWB_R_DP")
		)
	)
	(footprint ""
		(layer "F.Cu")
		(at 1.551686 -424.956732)
		(property "Reference" "BIOS_LABEL"
			(at -2.487168 2.245106 90)
			(unlocked yes)
			(layer "F.SilkS")
			(effects
				(font
					(size 0.7874 0.5842)
					(thickness 0.1524)
				)
				(justify left)
			)
		)
		(property "Value" ""
			(at 0 0 0)
			(layer "F.Fab")
			(effects
				(font
					(size 1.27 1.27)
				)
			)
		)
		(duplicate_pad_numbers_are_jumpers no)
		(pad "1" smd circle
			(at 0 0)
			(size 0.762 0.762)
			(layers "F.Cu" "F.Mask" "F.Paste")
			(net "Net_2230")
		)
	)
	(footprint ""
		(layer "F.Cu")
		(at 9.908032 -92.687648 90)
		(property "Reference" "R3654"
			(at 0 0 90)
			(layer "F.SilkS")
			(hide yes)
			(effects
				(font
					(size 1.27 1.27)
				)
			)
		)
		(property "Value" ""
			(at 0 0 90)
			(layer "F.Fab")
			(effects
				(font
					(size 1.27 1.27)
				)
			)
		)
		(duplicate_pad_numbers_are_jumpers no)
		(fp_line
			(start 0.7874 -0.4064)
			(end 0.7874 0.4064)
			(stroke
				(width 0.1524)
				(type default)
			)
			(layer "F.SilkS")
		)
		(fp_line
			(start -0.7874 -0.4064)
			(end 0.7874 -0.4064)
			(stroke
				(width 0.1524)
				(type default)
			)
			(layer "F.SilkS")
		)
		(fp_line
			(start 0.7874 0.4064)
			(end -0.7874 0.4064)
			(stroke
				(width 0.1524)
				(type default)
			)
			(layer "F.SilkS")
		)
		(fp_line
			(start -0.7874 0.4064)
			(end -0.7874 -0.4064)
			(stroke
				(width 0.1524)
				(type default)
			)
			(layer "F.SilkS")
		)
		(fp_line
			(start -0.12065 -0.305054)
			(end -0.12065 -0.2794)
			(stroke
				(width 0.1)
				(type default)
			)
			(layer "F.Fab")
		)
		(fp_line
			(start -0.67945 -0.305054)
			(end -0.12065 -0.305054)
			(stroke
				(width 0.1)
				(type default)
			)
			(layer "F.Fab")
		)
		(fp_line
			(start 0.67945 -0.3048)
			(end 0.67945 0.3048)
			(stroke
				(width 0.1)
				(type default)
			)
			(layer "F.Fab")
		)
		(fp_line
			(start 0.12065 -0.3048)
			(end 0.67945 -0.3048)
			(stroke
				(width 0.1)
				(type default)
			)
			(layer "F.Fab")
		)
		(fp_line
			(start 0.12065 -0.2794)
			(end 0.12065 -0.3048)
			(stroke
				(width 0.1)
				(type default)
			)
			(layer "F.Fab")
		)
		(fp_line
			(start -0.12065 -0.2794)
			(end 0.12065 -0.2794)
			(stroke
				(width 0.1)
				(type default)
			)
			(layer "F.Fab")
		)
		(fp_line
			(start 0.120396 0.2794)
			(end -0.12065 0.2794)
			(stroke
				(width 0.1)
				(type default)
			)
			(layer "F.Fab")
		)
		(fp_line
			(start -0.12065 0.2794)
			(end -0.12065 0.3048)
			(stroke
				(width 0.1)
				(type default)
			)
			(layer "F.Fab")
		)
		(fp_line
			(start 0.67945 0.3048)
			(end 0.120396 0.3048)
			(stroke
				(width 0.1)
				(type default)
			)
			(layer "F.Fab")
		)
		(fp_line
			(start 0.120396 0.3048)
			(end 0.120396 0.2794)
			(stroke
				(width 0.1)
				(type default)
			)
			(layer "F.Fab")
		)
		(fp_line
			(start -0.12065 0.3048)
			(end -0.67945 0.3048)
			(stroke
				(width 0.1)
				(type default)
			)
			(layer "F.Fab")
		)
		(fp_line
			(start -0.67945 0.3048)
			(end -0.67945 -0.305054)
			(stroke
				(width 0.1)
				(type default)
			)
			(layer "F.Fab")
		)
		(pad "1" smd circle
			(at -0.40005 0 90)
			(size 0 0)
			(layers "F.Cu" "F.Mask" "F.Paste")
			(net "RST_USB_HUB_N")
		)
		(pad "2" smd circle
			(at 0.40005 0 90)
			(size 0 0)
			(layers "F.Cu" "F.Mask" "F.Paste")
			(net "RST_USB_HUB_R_N")
		)
	)
	(footprint ""
		(layer "F.Cu")
		(at 111.477044 -261.748016 -90)
		(property "Reference" "C2113"
			(at 0 0 270)
			(layer "F.SilkS")
			(hide yes)
			(effects
				(font
					(size 1.27 1.27)
				)
			)
		)
		(property "Value" ""
			(at 0 0 270)
			(layer "F.Fab")
			(effects
				(font
					(size 1.27 1.27)
				)
			)
		)
		(duplicate_pad_numbers_are_jumpers no)
		(fp_line
			(start -0.7874 0.4064)
			(end -0.7874 -0.4064)
			(stroke
				(width 0.1524)
				(type default)
			)
			(layer "F.SilkS")
		)
		(fp_line
			(start 0.7874 0.4064)
			(end -0.7874 0.4064)
			(stroke
				(width 0.1524)
				(type default)
			)
			(layer "F.SilkS")
		)
		(fp_line
			(start -0.7874 -0.4064)
			(end 0.7874 -0.4064)
			(stroke
				(width 0.1524)
				(type default)
			)
			(layer "F.SilkS")
		)
		(fp_line
			(start 0.7874 -0.4064)
			(end 0.7874 0.4064)
			(stroke
				(width 0.1524)
				(type default)
			)
			(layer "F.SilkS")
		)
		(fp_line
			(start -0.67945 0.3048)
			(end -0.67945 -0.305054)
			(stroke
				(width 0.1)
				(type default)
			)
			(layer "F.Fab")
		)
		(fp_line
			(start -0.12065 0.3048)
			(end -0.67945 0.3048)
			(stroke
				(width 0.1)
				(type default)
			)
			(layer "F.Fab")
		)
		(fp_line
			(start 0.120396 0.3048)
			(end 0.120396 0.2794)
			(stroke
				(width 0.1)
				(type default)
			)
			(layer "F.Fab")
		)
		(fp_line
			(start 0.67945 0.3048)
			(end 0.120396 0.3048)
			(stroke
				(width 0.1)
				(type default)
			)
			(layer "F.Fab")
		)
		(fp_line
			(start -0.12065 0.2794)
			(end -0.12065 0.3048)
			(stroke
				(width 0.1)
				(type default)
			)
			(layer "F.Fab")
		)
		(fp_line
			(start 0.120396 0.2794)
			(end -0.12065 0.2794)
			(stroke
				(width 0.1)
				(type default)
			)
			(layer "F.Fab")
		)
		(fp_line
			(start -0.12065 -0.2794)
			(end 0.12065 -0.2794)
			(stroke
				(width 0.1)
				(type default)
			)
			(layer "F.Fab")
		)
		(fp_line
			(start 0.12065 -0.2794)
			(end 0.12065 -0.3048)
			(stroke
				(width 0.1)
				(type default)
			)
			(layer "F.Fab")
		)
		(fp_line
			(start 0.12065 -0.3048)
			(end 0.67945 -0.3048)
			(stroke
				(width 0.1)
				(type default)
			)
			(layer "F.Fab")
		)
		(fp_line
			(start 0.67945 -0.3048)
			(end 0.67945 0.3048)
			(stroke
				(width 0.1)
				(type default)
			)
			(layer "F.Fab")
		)
		(fp_line
			(start -0.67945 -0.305054)
			(end -0.12065 -0.305054)
			(stroke
				(width 0.1)
				(type default)
			)
			(layer "F.Fab")
		)
		(fp_line
			(start -0.12065 -0.305054)
			(end -0.12065 -0.2794)
			(stroke
				(width 0.1)
				(type default)
			)
			(layer "F.Fab")
		)
		(pad "1" smd circle
			(at -0.40005 0 270)
			(size 0 0)
			(layers "F.Cu" "F.Mask" "F.Paste")
			(net "PVDD11_S3_P1")
		)
		(pad "2" smd circle
			(at 0.40005 0 270)
			(size 0 0)
			(layers "F.Cu" "F.Mask" "F.Paste")
			(net "GND")
		)
	)
	(footprint ""
		(layer "F.Cu")
		(at 458.80147 -41.105836)
		(property "Reference" "Q124"
			(at -2.899664 -2.731262 0)
			(unlocked yes)
			(layer "F.SilkS")
			(effects
				(font
					(size 0.7874 0.5842)
					(thickness 0.1524)
				)
				(justify left)
			)
		)
		(property "Value" ""
			(at 0 0 0)
			(layer "F.Fab")
			(effects
				(font
					(size 1.27 1.27)
				)
			)
		)
		(duplicate_pad_numbers_are_jumpers no)
		(fp_line
			(start -1.332738 -1.100074)
			(end -0.4826 -1.100074)
			(stroke
				(width 0.1524)
				(type default)
			)
			(layer "F.SilkS")
		)
		(fp_line
			(start -1.332738 1.100074)
			(end -1.332738 -1.100074)
			(stroke
				(width 0.1524)
				(type default)
			)
			(layer "F.SilkS")
		)
		(fp_line
			(start -0.4826 -1.100074)
			(end 0 -0.541274)
			(stroke
				(width 0.1524)
				(type default)
			)
			(layer "F.SilkS")
		)
		(fp_line
			(start 0 -0.541274)
			(end 0.4826 -1.100074)
			(stroke
				(width 0.1524)
				(type default)
			)
			(layer "F.SilkS")
		)
		(fp_line
			(start 0.4826 -1.100074)
			(end 1.332738 -1.100074)
			(stroke
				(width 0.1524)
				(type default)
			)
			(layer "F.SilkS")
		)
		(fp_line
			(start 1.332738 -1.100074)
			(end 1.332738 1.100074)
			(stroke
				(width 0.1524)
				(type default)
			)
			(layer "F.SilkS")
		)
		(fp_line
			(start 1.332738 1.100074)
			(end -1.332738 1.100074)
			(stroke
				(width 0.1524)
				(type default)
			)
			(layer "F.SilkS")
		)
		(fp_poly
			(pts
				(xy -1.489456 -1.189482) (xy -2.23393 -1.43764) (xy -1.737614 -1.933956)
			)
			(stroke
				(width 0)
				(type default)
			)
			(fill yes)
			(layer "F.SilkS")
		)
		(fp_line
			(start -0.674878 -1.100074)
			(end 0.674878 -1.100074)
			(stroke
				(width 0.1)
				(type default)
			)
			(layer "F.Fab")
		)
		(fp_line
			(start -0.674878 1.100074)
			(end -0.674878 -1.100074)
			(stroke
				(width 0.1)
				(type default)
			)
			(layer "F.Fab")
		)
		(fp_line
			(start 0.674878 -1.100074)
			(end 0.674878 1.100074)
			(stroke
				(width 0.1)
				(type default)
			)
			(layer "F.Fab")
		)
		(fp_line
			(start 0.674878 1.100074)
			(end -0.674878 1.100074)
			(stroke
				(width 0.1)
				(type default)
			)
			(layer "F.Fab")
		)
		(fp_poly
			(pts
				(xy -2.2352 -0.298958) (xy -2.2352 -1.001014) (xy -1.533144 -0.649986)
			)
			(stroke
				(width 0)
				(type default)
			)
			(fill yes)
			(layer "F.Fab")
		)
		(pad "1" smd rect
			(at -0.94996 -0.649986 90)
			(size 0.4318 0.508)
			(layers "F.Cu" "F.Mask" "F.Paste")
			(net "GND")
		)
		(pad "2" smd rect
			(at -0.94996 0 90)
			(size 0.4318 0.508)
			(layers "F.Cu" "F.Mask" "F.Paste")
			(net "P3V3_OCP_EN_1_R")
		)
		(pad "3" smd rect
			(at -0.94996 0.649986 90)
			(size 0.4318 0.508)
			(layers "F.Cu" "F.Mask" "F.Paste")
			(net "P3V3_OCP_UV_1_R1")
		)
		(pad "4" smd rect
			(at 0.94996 0.649986 90)
			(size 0.4318 0.508)
			(layers "F.Cu" "F.Mask" "F.Paste")
			(net "GND")
		)
		(pad "5" smd rect
			(at 0.94996 0 90)
			(size 0.4318 0.508)
			(layers "F.Cu" "F.Mask" "F.Paste")
			(net "P3V3_OCP_1_EN_G")
		)
		(pad "6" smd rect
			(at 0.94996 -0.649986 90)
			(size 0.4318 0.508)
			(layers "F.Cu" "F.Mask" "F.Paste")
			(net "P3V3_OCP_1_EN_G")
		)
	)
	(footprint ""
		(layer "F.Cu")
		(at 432.729894 -355.743764 90)
		(property "Reference" "PR136"
			(at 0 0 90)
			(layer "F.SilkS")
			(hide yes)
			(effects
				(font
					(size 1.27 1.27)
				)
			)
		)
		(property "Value" ""
			(at 0 0 90)
			(layer "F.Fab")
			(effects
				(font
					(size 1.27 1.27)
				)
			)
		)
		(duplicate_pad_numbers_are_jumpers no)
		(fp_line
			(start 0.7874 -0.4064)
			(end 0.7874 0.4064)
			(stroke
				(width 0.1524)
				(type default)
			)
			(layer "F.SilkS")
		)
		(fp_line
			(start -0.7874 -0.4064)
			(end 0.7874 -0.4064)
			(stroke
				(width 0.1524)
				(type default)
			)
			(layer "F.SilkS")
		)
		(fp_line
			(start 0.7874 0.4064)
			(end -0.7874 0.4064)
			(stroke
				(width 0.1524)
				(type default)
			)
			(layer "F.SilkS")
		)
		(fp_line
			(start -0.7874 0.4064)
			(end -0.7874 -0.4064)
			(stroke
				(width 0.1524)
				(type default)
			)
			(layer "F.SilkS")
		)
		(fp_line
			(start -0.12065 -0.305054)
			(end -0.12065 -0.2794)
			(stroke
				(width 0.1)
				(type default)
			)
			(layer "F.Fab")
		)
		(fp_line
			(start -0.67945 -0.305054)
			(end -0.12065 -0.305054)
			(stroke
				(width 0.1)
				(type default)
			)
			(layer "F.Fab")
		)
		(fp_line
			(start 0.67945 -0.3048)
			(end 0.67945 0.3048)
			(stroke
				(width 0.1)
				(type default)
			)
			(layer "F.Fab")
		)
		(fp_line
			(start 0.12065 -0.3048)
			(end 0.67945 -0.3048)
			(stroke
				(width 0.1)
				(type default)
			)
			(layer "F.Fab")
		)
		(fp_line
			(start 0.12065 -0.2794)
			(end 0.12065 -0.3048)
			(stroke
				(width 0.1)
				(type default)
			)
			(layer "F.Fab")
		)
		(fp_line
			(start -0.12065 -0.2794)
			(end 0.12065 -0.2794)
			(stroke
				(width 0.1)
				(type default)
			)
			(layer "F.Fab")
		)
		(fp_line
			(start 0.120396 0.2794)
			(end -0.12065 0.2794)
			(stroke
				(width 0.1)
				(type default)
			)
			(layer "F.Fab")
		)
		(fp_line
			(start -0.12065 0.2794)
			(end -0.12065 0.3048)
			(stroke
				(width 0.1)
				(type default)
			)
			(layer "F.Fab")
		)
		(fp_line
			(start 0.67945 0.3048)
			(end 0.120396 0.3048)
			(stroke
				(width 0.1)
				(type default)
			)
			(layer "F.Fab")
		)
		(fp_line
			(start 0.120396 0.3048)
			(end 0.120396 0.2794)
			(stroke
				(width 0.1)
				(type default)
			)
			(layer "F.Fab")
		)
		(fp_line
			(start -0.12065 0.3048)
			(end -0.67945 0.3048)
			(stroke
				(width 0.1)
				(type default)
			)
			(layer "F.Fab")
		)
		(fp_line
			(start -0.67945 0.3048)
			(end -0.67945 -0.305054)
			(stroke
				(width 0.1)
				(type default)
			)
			(layer "F.Fab")
		)
		(pad "1" smd circle
			(at -0.40005 0 90)
			(size 0 0)
			(layers "F.Cu" "F.Mask" "F.Paste")
			(net "SW_PVDD11_S3_P0_BOOT2")
		)
		(pad "2" smd circle
			(at 0.40005 0 90)
			(size 0 0)
			(layers "F.Cu" "F.Mask" "F.Paste")
			(net "SW_PVDD11_S3_P0_BOOT2_RC")
		)
	)
	(footprint ""
		(layer "F.Cu")
		(at 15.399258 -427.232064 180)
		(property "Reference" "R6167"
			(at 0 0 180)
			(layer "F.SilkS")
			(hide yes)
			(effects
				(font
					(size 1.27 1.27)
				)
			)
		)
		(property "Value" ""
			(at 0 0 180)
			(layer "F.Fab")
			(effects
				(font
					(size 1.27 1.27)
				)
			)
		)
		(duplicate_pad_numbers_are_jumpers no)
		(fp_line
			(start 0.7874 0.4064)
			(end -0.7874 0.4064)
			(stroke
				(width 0.1524)
				(type default)
			)
			(layer "F.SilkS")
		)
		(fp_line
			(start 0.7874 -0.4064)
			(end 0.7874 0.4064)
			(stroke
				(width 0.1524)
				(type default)
			)
			(layer "F.SilkS")
		)
		(fp_line
			(start -0.7874 0.4064)
			(end -0.7874 -0.4064)
			(stroke
				(width 0.1524)
				(type default)
			)
			(layer "F.SilkS")
		)
		(fp_line
			(start -0.7874 -0.4064)
			(end 0.7874 -0.4064)
			(stroke
				(width 0.1524)
				(type default)
			)
			(layer "F.SilkS")
		)
		(fp_line
			(start 0.67945 0.3048)
			(end 0.120396 0.3048)
			(stroke
				(width 0.1)
				(type default)
			)
			(layer "F.Fab")
		)
		(fp_line
			(start 0.67945 -0.3048)
			(end 0.67945 0.3048)
			(stroke
				(width 0.1)
				(type default)
			)
			(layer "F.Fab")
		)
		(fp_line
			(start 0.12065 -0.2794)
			(end 0.12065 -0.3048)
			(stroke
				(width 0.1)
				(type default)
			)
			(layer "F.Fab")
		)
		(fp_line
			(start 0.12065 -0.3048)
			(end 0.67945 -0.3048)
			(stroke
				(width 0.1)
				(type default)
			)
			(layer "F.Fab")
		)
		(fp_line
			(start 0.120396 0.3048)
			(end 0.120396 0.2794)
			(stroke
				(width 0.1)
				(type default)
			)
			(layer "F.Fab")
		)
		(fp_line
			(start 0.120396 0.2794)
			(end -0.12065 0.2794)
			(stroke
				(width 0.1)
				(type default)
			)
			(layer "F.Fab")
		)
		(fp_line
			(start -0.12065 0.3048)
			(end -0.67945 0.3048)
			(stroke
				(width 0.1)
				(type default)
			)
			(layer "F.Fab")
		)
		(fp_line
			(start -0.12065 0.2794)
			(end -0.12065 0.3048)
			(stroke
				(width 0.1)
				(type default)
			)
			(layer "F.Fab")
		)
		(fp_line
			(start -0.12065 -0.2794)
			(end 0.12065 -0.2794)
			(stroke
				(width 0.1)
				(type default)
			)
			(layer "F.Fab")
		)
		(fp_line
			(start -0.12065 -0.305054)
			(end -0.12065 -0.2794)
			(stroke
				(width 0.1)
				(type default)
			)
			(layer "F.Fab")
		)
		(fp_line
			(start -0.67945 0.3048)
			(end -0.67945 -0.305054)
			(stroke
				(width 0.1)
				(type default)
			)
			(layer "F.Fab")
		)
		(fp_line
			(start -0.67945 -0.305054)
			(end -0.12065 -0.305054)
			(stroke
				(width 0.1)
				(type default)
			)
			(layer "F.Fab")
		)
		(pad "1" smd circle
			(at -0.40005 0 180)
			(size 0 0)
			(layers "F.Cu" "F.Mask" "F.Paste")
			(net "P3V3_AUX")
		)
		(pad "2" smd circle
			(at 0.40005 0 180)
			(size 0 0)
			(layers "F.Cu" "F.Mask" "F.Paste")
			(net "FM_P2E_BUF2_VODB_DB")
		)
	)
	(footprint ""
		(layer "F.Cu")
		(at 163.17087 -428.23638 180)
		(property "Reference" "R6790"
			(at 0 0 180)
			(layer "F.SilkS")
			(hide yes)
			(effects
				(font
					(size 1.27 1.27)
				)
			)
		)
		(property "Value" ""
			(at 0 0 180)
			(layer "F.Fab")
			(effects
				(font
					(size 1.27 1.27)
				)
			)
		)
		(duplicate_pad_numbers_are_jumpers no)
		(fp_line
			(start 0.32512 0.175006)
			(end -0.32512 0.175006)
			(stroke
				(width 0.1)
				(type default)
			)
			(layer "F.Fab")
		)
		(fp_line
			(start 0.32512 -0.175006)
			(end 0.32512 0.175006)
			(stroke
				(width 0.1)
				(type default)
			)
			(layer "F.Fab")
		)
		(fp_line
			(start -0.32512 0.175006)
			(end -0.32512 -0.175006)
			(stroke
				(width 0.1)
				(type default)
			)
			(layer "F.Fab")
		)
		(fp_line
			(start -0.32512 -0.175006)
			(end 0.32512 -0.175006)
			(stroke
				(width 0.1)
				(type default)
			)
			(layer "F.Fab")
		)
		(pad "1" smd rect
			(at -0.2667 0 180)
			(size 0.3048 0.381)
			(layers "F.Cu" "F.Mask" "F.Paste")
			(net "U20_E2")
		)
		(pad "2" smd rect
			(at 0.2667 0)
			(size 0.3048 0.381)
			(layers "F.Cu" "F.Mask" "F.Paste")
			(net "GND")
		)
	)
	(footprint ""
		(layer "F.Cu")
		(at 118.999 -124.841 -90)
		(property "Reference" "C6500"
			(at 0 0 270)
			(layer "F.SilkS")
			(hide yes)
			(effects
				(font
					(size 1.27 1.27)
				)
			)
		)
		(property "Value" ""
			(at 0 0 270)
			(layer "F.Fab")
			(effects
				(font
					(size 1.27 1.27)
				)
			)
		)
		(duplicate_pad_numbers_are_jumpers no)
		(fp_line
			(start -0.7874 0.4064)
			(end -0.7874 -0.4064)
			(stroke
				(width 0.1524)
				(type default)
			)
			(layer "F.SilkS")
		)
		(fp_line
			(start 0.7874 0.4064)
			(end -0.7874 0.4064)
			(stroke
				(width 0.1524)
				(type default)
			)
			(layer "F.SilkS")
		)
		(fp_line
			(start -0.7874 -0.4064)
			(end 0.7874 -0.4064)
			(stroke
				(width 0.1524)
				(type default)
			)
			(layer "F.SilkS")
		)
		(fp_line
			(start 0.7874 -0.4064)
			(end 0.7874 0.4064)
			(stroke
				(width 0.1524)
				(type default)
			)
			(layer "F.SilkS")
		)
		(fp_line
			(start -0.67945 0.3048)
			(end -0.67945 -0.305054)
			(stroke
				(width 0.1)
				(type default)
			)
			(layer "F.Fab")
		)
		(fp_line
			(start -0.12065 0.3048)
			(end -0.67945 0.3048)
			(stroke
				(width 0.1)
				(type default)
			)
			(layer "F.Fab")
		)
		(fp_line
			(start 0.120396 0.3048)
			(end 0.120396 0.2794)
			(stroke
				(width 0.1)
				(type default)
			)
			(layer "F.Fab")
		)
		(fp_line
			(start 0.67945 0.3048)
			(end 0.120396 0.3048)
			(stroke
				(width 0.1)
				(type default)
			)
			(layer "F.Fab")
		)
		(fp_line
			(start -0.12065 0.2794)
			(end -0.12065 0.3048)
			(stroke
				(width 0.1)
				(type default)
			)
			(layer "F.Fab")
		)
		(fp_line
			(start 0.120396 0.2794)
			(end -0.12065 0.2794)
			(stroke
				(width 0.1)
				(type default)
			)
			(layer "F.Fab")
		)
		(fp_line
			(start -0.12065 -0.2794)
			(end 0.12065 -0.2794)
			(stroke
				(width 0.1)
				(type default)
			)
			(layer "F.Fab")
		)
		(fp_line
			(start 0.12065 -0.2794)
			(end 0.12065 -0.3048)
			(stroke
				(width 0.1)
				(type default)
			)
			(layer "F.Fab")
		)
		(fp_line
			(start 0.12065 -0.3048)
			(end 0.67945 -0.3048)
			(stroke
				(width 0.1)
				(type default)
			)
			(layer "F.Fab")
		)
		(fp_line
			(start 0.67945 -0.3048)
			(end 0.67945 0.3048)
			(stroke
				(width 0.1)
				(type default)
			)
			(layer "F.Fab")
		)
		(fp_line
			(start -0.67945 -0.305054)
			(end -0.12065 -0.305054)
			(stroke
				(width 0.1)
				(type default)
			)
			(layer "F.Fab")
		)
		(fp_line
			(start -0.12065 -0.305054)
			(end -0.12065 -0.2794)
			(stroke
				(width 0.1)
				(type default)
			)
			(layer "F.Fab")
		)
		(pad "1" smd circle
			(at -0.40005 0 270)
			(size 0 0)
			(layers "F.Cu" "F.Mask" "F.Paste")
			(net "P3V3")
		)
		(pad "2" smd circle
			(at 0.40005 0 270)
			(size 0 0)
			(layers "F.Cu" "F.Mask" "F.Paste")
			(net "GND")
		)
	)
	(footprint ""
		(layer "F.Cu")
		(at 432.308 -406.7048)
		(property "Reference" "R1478"
			(at 0 0 0)
			(layer "F.SilkS")
			(hide yes)
			(effects
				(font
					(size 1.27 1.27)
				)
			)
		)
		(property "Value" ""
			(at 0 0 0)
			(layer "F.Fab")
			(effects
				(font
					(size 1.27 1.27)
				)
			)
		)
		(duplicate_pad_numbers_are_jumpers no)
		(fp_line
			(start -0.32512 -0.175006)
			(end 0.32512 -0.175006)
			(stroke
				(width 0.1)
				(type default)
			)
			(layer "F.Fab")
		)
		(fp_line
			(start -0.32512 0.175006)
			(end -0.32512 -0.175006)
			(stroke
				(width 0.1)
				(type default)
			)
			(layer "F.Fab")
		)
		(fp_line
			(start 0.32512 -0.175006)
			(end 0.32512 0.175006)
			(stroke
				(width 0.1)
				(type default)
			)
			(layer "F.Fab")
		)
		(fp_line
			(start 0.32512 0.175006)
			(end -0.32512 0.175006)
			(stroke
				(width 0.1)
				(type default)
			)
			(layer "F.Fab")
		)
		(pad "1" smd rect
			(at -0.2667 0)
			(size 0.3048 0.381)
			(layers "F.Cu" "F.Mask" "F.Paste")
			(net "P1V8_CPU0_RT_1D")
		)
		(pad "2" smd rect
			(at 0.2667 0 180)
			(size 0.3048 0.381)
			(layers "F.Cu" "F.Mask" "F.Paste")
			(net "JTAG_TDO_RT_CPU0_P2")
		)
	)
	(footprint ""
		(layer "F.Cu")
		(at 404.361904 -163.942014 90)
		(property "Reference" "PC594"
			(at 0 0 90)
			(layer "F.SilkS")
			(hide yes)
			(effects
				(font
					(size 1.27 1.27)
				)
			)
		)
		(property "Value" ""
			(at 0 0 90)
			(layer "F.Fab")
			(effects
				(font
					(size 1.27 1.27)
				)
			)
		)
		(duplicate_pad_numbers_are_jumpers no)
		(fp_line
			(start 0.7874 -0.4064)
			(end 0.7874 0.4064)
			(stroke
				(width 0.1524)
				(type default)
			)
			(layer "F.SilkS")
		)
		(fp_line
			(start -0.7874 -0.4064)
			(end 0.7874 -0.4064)
			(stroke
				(width 0.1524)
				(type default)
			)
			(layer "F.SilkS")
		)
		(fp_line
			(start 0.7874 0.4064)
			(end -0.7874 0.4064)
			(stroke
				(width 0.1524)
				(type default)
			)
			(layer "F.SilkS")
		)
		(fp_line
			(start -0.7874 0.4064)
			(end -0.7874 -0.4064)
			(stroke
				(width 0.1524)
				(type default)
			)
			(layer "F.SilkS")
		)
		(fp_line
			(start -0.12065 -0.305054)
			(end -0.12065 -0.2794)
			(stroke
				(width 0.1)
				(type default)
			)
			(layer "F.Fab")
		)
		(fp_line
			(start -0.67945 -0.305054)
			(end -0.12065 -0.305054)
			(stroke
				(width 0.1)
				(type default)
			)
			(layer "F.Fab")
		)
		(fp_line
			(start 0.67945 -0.3048)
			(end 0.67945 0.3048)
			(stroke
				(width 0.1)
				(type default)
			)
			(layer "F.Fab")
		)
		(fp_line
			(start 0.12065 -0.3048)
			(end 0.67945 -0.3048)
			(stroke
				(width 0.1)
				(type default)
			)
			(layer "F.Fab")
		)
		(fp_line
			(start 0.12065 -0.2794)
			(end 0.12065 -0.3048)
			(stroke
				(width 0.1)
				(type default)
			)
			(layer "F.Fab")
		)
		(fp_line
			(start -0.12065 -0.2794)
			(end 0.12065 -0.2794)
			(stroke
				(width 0.1)
				(type default)
			)
			(layer "F.Fab")
		)
		(fp_line
			(start 0.120396 0.2794)
			(end -0.12065 0.2794)
			(stroke
				(width 0.1)
				(type default)
			)
			(layer "F.Fab")
		)
		(fp_line
			(start -0.12065 0.2794)
			(end -0.12065 0.3048)
			(stroke
				(width 0.1)
				(type default)
			)
			(layer "F.Fab")
		)
		(fp_line
			(start 0.67945 0.3048)
			(end 0.120396 0.3048)
			(stroke
				(width 0.1)
				(type default)
			)
			(layer "F.Fab")
		)
		(fp_line
			(start 0.120396 0.3048)
			(end 0.120396 0.2794)
			(stroke
				(width 0.1)
				(type default)
			)
			(layer "F.Fab")
		)
		(fp_line
			(start -0.12065 0.3048)
			(end -0.67945 0.3048)
			(stroke
				(width 0.1)
				(type default)
			)
			(layer "F.Fab")
		)
		(fp_line
			(start -0.67945 0.3048)
			(end -0.67945 -0.305054)
			(stroke
				(width 0.1)
				(type default)
			)
			(layer "F.Fab")
		)
		(pad "1" smd circle
			(at -0.40005 0 90)
			(size 0 0)
			(layers "F.Cu" "F.Mask" "F.Paste")
			(net "SW_PVDDCR_SOC_P0_BOOT2_RC")
		)
		(pad "2" smd circle
			(at 0.40005 0 90)
			(size 0 0)
			(layers "F.Cu" "F.Mask" "F.Paste")
			(net "SW_PVDDCR_SOC_P0_PH2")
		)
	)
	(footprint ""
		(layer "F.Cu")
		(at 180.528468 -44.091098)
		(property "Reference" "C9104"
			(at 0 0 0)
			(layer "F.SilkS")
			(hide yes)
			(effects
				(font
					(size 1.27 1.27)
				)
			)
		)
		(property "Value" ""
			(at 0 0 0)
			(layer "F.Fab")
			(effects
				(font
					(size 1.27 1.27)
				)
			)
		)
		(duplicate_pad_numbers_are_jumpers no)
		(fp_line
			(start -0.299974 -0.150114)
			(end 0.299974 -0.150114)
			(stroke
				(width 0.1)
				(type default)
			)
			(layer "F.Fab")
		)
		(fp_line
			(start -0.299974 0.150114)
			(end -0.299974 -0.150114)
			(stroke
				(width 0.1)
				(type default)
			)
			(layer "F.Fab")
		)
		(fp_line
			(start 0.299974 -0.150114)
			(end 0.299974 0.150114)
			(stroke
				(width 0.1)
				(type default)
			)
			(layer "F.Fab")
		)
		(fp_line
			(start 0.299974 0.150114)
			(end -0.299974 0.150114)
			(stroke
				(width 0.1)
				(type default)
			)
			(layer "F.Fab")
		)
		(pad "1" smd rect
			(at -0.2667 0)
			(size 0.3048 0.381)
			(layers "F.Cu" "F.Mask" "F.Paste")
			(net "P3E_CPU1_P4_TX_C_DP<0>")
		)
		(pad "2" smd rect
			(at 0.2667 0)
			(size 0.3048 0.381)
			(layers "F.Cu" "F.Mask" "F.Paste")
			(net "P3E_CPU1_P4_TX_DP<0>")
		)
	)
	(footprint ""
		(layer "F.Cu")
		(at 48.82134 -346.87129 -90)
		(property "Reference" "PC441_2"
			(at 0 0 270)
			(layer "F.SilkS")
			(hide yes)
			(effects
				(font
					(size 1.27 1.27)
				)
			)
		)
		(property "Value" ""
			(at 0 0 270)
			(layer "F.Fab")
			(effects
				(font
					(size 1.27 1.27)
				)
			)
		)
		(duplicate_pad_numbers_are_jumpers no)
		(fp_line
			(start -0.7874 0.4064)
			(end -0.7874 -0.4064)
			(stroke
				(width 0.1524)
				(type default)
			)
			(layer "F.SilkS")
		)
		(fp_line
			(start 0.7874 0.4064)
			(end -0.7874 0.4064)
			(stroke
				(width 0.1524)
				(type default)
			)
			(layer "F.SilkS")
		)
		(fp_line
			(start -0.7874 -0.4064)
			(end 0.7874 -0.4064)
			(stroke
				(width 0.1524)
				(type default)
			)
			(layer "F.SilkS")
		)
		(fp_line
			(start 0.7874 -0.4064)
			(end 0.7874 0.4064)
			(stroke
				(width 0.1524)
				(type default)
			)
			(layer "F.SilkS")
		)
		(fp_line
			(start -0.67945 0.3048)
			(end -0.67945 -0.305054)
			(stroke
				(width 0.1)
				(type default)
			)
			(layer "F.Fab")
		)
		(fp_line
			(start -0.12065 0.3048)
			(end -0.67945 0.3048)
			(stroke
				(width 0.1)
				(type default)
			)
			(layer "F.Fab")
		)
		(fp_line
			(start 0.120396 0.3048)
			(end 0.120396 0.2794)
			(stroke
				(width 0.1)
				(type default)
			)
			(layer "F.Fab")
		)
		(fp_line
			(start 0.67945 0.3048)
			(end 0.120396 0.3048)
			(stroke
				(width 0.1)
				(type default)
			)
			(layer "F.Fab")
		)
		(fp_line
			(start -0.12065 0.2794)
			(end -0.12065 0.3048)
			(stroke
				(width 0.1)
				(type default)
			)
			(layer "F.Fab")
		)
		(fp_line
			(start 0.120396 0.2794)
			(end -0.12065 0.2794)
			(stroke
				(width 0.1)
				(type default)
			)
			(layer "F.Fab")
		)
		(fp_line
			(start -0.12065 -0.2794)
			(end 0.12065 -0.2794)
			(stroke
				(width 0.1)
				(type default)
			)
			(layer "F.Fab")
		)
		(fp_line
			(start 0.12065 -0.2794)
			(end 0.12065 -0.3048)
			(stroke
				(width 0.1)
				(type default)
			)
			(layer "F.Fab")
		)
		(fp_line
			(start 0.12065 -0.3048)
			(end 0.67945 -0.3048)
			(stroke
				(width 0.1)
				(type default)
			)
			(layer "F.Fab")
		)
		(fp_line
			(start 0.67945 -0.3048)
			(end 0.67945 0.3048)
			(stroke
				(width 0.1)
				(type default)
			)
			(layer "F.Fab")
		)
		(fp_line
			(start -0.67945 -0.305054)
			(end -0.12065 -0.305054)
			(stroke
				(width 0.1)
				(type default)
			)
			(layer "F.Fab")
		)
		(fp_line
			(start -0.12065 -0.305054)
			(end -0.12065 -0.2794)
			(stroke
				(width 0.1)
				(type default)
			)
			(layer "F.Fab")
		)
		(pad "1" smd circle
			(at -0.40005 0 270)
			(size 0 0)
			(layers "F.Cu" "F.Mask" "F.Paste")
			(net "SW_P12V_AUX_PVDDIO_P1_FLT")
		)
		(pad "2" smd circle
			(at 0.40005 0 270)
			(size 0 0)
			(layers "F.Cu" "F.Mask" "F.Paste")
			(net "GND")
		)
	)
	(footprint ""
		(layer "F.Cu")
		(at 123.567952 -387.342634)
		(property "Reference" "U6017"
			(at -6.180074 -7.979664 0)
			(unlocked yes)
			(layer "F.SilkS")
			(effects
				(font
					(size 0.7874 0.5842)
					(thickness 0.1524)
				)
				(justify left)
			)
		)
		(property "Value" ""
			(at 0 0 0)
			(layer "F.Fab")
			(effects
				(font
					(size 1.27 1.27)
				)
			)
		)
		(duplicate_pad_numbers_are_jumpers no)
		(fp_line
			(start -11.400028 -4.45008)
			(end -9.775952 -4.45008)
			(stroke
				(width 0.1524)
				(type default)
			)
			(layer "F.SilkS")
		)
		(fp_line
			(start -11.400028 -0.820166)
			(end -11.400028 -4.45008)
			(stroke
				(width 0.1524)
				(type default)
			)
			(layer "F.SilkS")
		)
		(fp_line
			(start -11.400028 4.45008)
			(end -11.400028 0.170434)
			(stroke
				(width 0.1524)
				(type default)
			)
			(layer "F.SilkS")
		)
		(fp_line
			(start -10.207752 4.45008)
			(end -11.400028 4.45008)
			(stroke
				(width 0.1524)
				(type default)
			)
			(layer "F.SilkS")
		)
		(fp_line
			(start 9.578848 -4.45008)
			(end 11.400028 -4.45008)
			(stroke
				(width 0.1524)
				(type default)
			)
			(layer "F.SilkS")
		)
		(fp_line
			(start 11.400028 -4.45008)
			(end 11.400028 4.45008)
			(stroke
				(width 0.1524)
				(type default)
			)
			(layer "F.SilkS")
		)
		(fp_line
			(start 11.400028 4.45008)
			(end 9.578848 4.45008)
			(stroke
				(width 0.1524)
				(type default)
			)
			(layer "F.SilkS")
		)
		(fp_poly
			(pts
				(xy 10.450068 -4.45008) (xy 10.450068 -5.21208) (xy 12.162028 -5.21208) (xy 12.162028 -3.41884)
				(xy 11.400028 -3.41884) (xy 11.400028 -4.45008)
			)
			(stroke
				(width 0)
				(type default)
			)
			(fill yes)
			(layer "F.SilkS")
		)
		(fp_line
			(start -11.400028 -4.45008)
			(end -11.400028 4.45008)
			(stroke
				(width 0.1)
				(type default)
			)
			(layer "F.Fab")
		)
		(fp_line
			(start -11.400028 4.45008)
			(end 11.400028 4.45008)
			(stroke
				(width 0.1)
				(type default)
			)
			(layer "F.Fab")
		)
		(fp_line
			(start 11.400028 -4.45008)
			(end -11.400028 -4.45008)
			(stroke
				(width 0.1)
				(type default)
			)
			(layer "F.Fab")
		)
		(fp_line
			(start 11.400028 4.45008)
			(end 11.400028 -4.45008)
			(stroke
				(width 0.1)
				(type default)
			)
			(layer "F.Fab")
		)
		(fp_poly
			(pts
				(xy 10.450068 -4.45008) (xy 10.450068 -5.21208) (xy 12.162028 -5.21208) (xy 12.162028 -3.41884)
				(xy 11.400028 -3.41884) (xy 11.400028 -4.45008)
			)
			(stroke
				(width 0)
				(type default)
			)
			(fill yes)
			(layer "F.Fab")
		)
		(pad "A1" smd oval
			(at 11.050016 -3.938524)
			(size 0.254 0.3302)
			(layers "F.Cu" "F.Mask" "F.Paste")
			(net "NCF_A1_CPU1_P3_GND")
		)
		(pad "A35" smd oval
			(at 11.050016 3.940048)
			(size 0.254 0.3302)
			(layers "F.Cu" "F.Mask" "F.Paste")
			(net "NCF_CPU1_P3_GND")
		)
		(pad "AA10" smd circle
			(at 7.602728 -1.431798)
			(size 0.381 0.381)
			(layers "F.Cu" "F.Mask" "F.Paste")
			(net "P5E_CPU1_P3_TX_BUF_DN<14>")
		)
		(pad "AA29" smd circle
			(at 7.602728 2.032254)
			(size 0.381 0.381)
			(layers "F.Cu" "F.Mask" "F.Paste")
			(net "P5E_CPU1_P3_RX_DN<14>")
		)
		(pad "AB1" smd oval
			(at 7.450074 -3.938524)
			(size 0.254 0.3302)
			(layers "F.Cu" "F.Mask" "F.Paste")
			(net "P5E_CPU1_P3_RX_BUF_DP<14>")
		)
		(pad "AB35" smd oval
			(at 7.450074 3.940048)
			(size 0.254 0.3302)
			(layers "F.Cu" "F.Mask" "F.Paste")
			(net "P5E_CPU1_P3_TX_C_DN<14>")
		)
		(pad "AC4" smd circle
			(at 7.202678 -2.817368)
			(size 0.381 0.381)
			(layers "F.Cu" "F.Mask" "F.Paste")
			(net "GND")
		)
		(pad "AC13" smd circle
			(at 7.202678 -0.79629)
			(size 0.3048 0.3048)
			(layers "F.Cu" "F.Mask" "F.Paste")
			(net "GND")
		)
		(pad "AC17" smd circle
			(at 7.202678 -0.296164)
			(size 0.3048 0.3048)
			(layers "F.Cu" "F.Mask" "F.Paste")
			(net "P0V9_CPU1_RT3_2A")
		)
		(pad "AC20" smd circle
			(at 7.202678 0.203708)
			(size 0.3048 0.3048)
			(layers "F.Cu" "F.Mask" "F.Paste")
			(net "P0V9_CPU1_RT3_2A")
		)
		(pad "AC22" smd circle
			(at 7.202678 0.703834)
			(size 0.3048 0.3048)
			(layers "F.Cu" "F.Mask" "F.Paste")
			(net "GND")
		)
		(pad "AC32" smd circle
			(at 7.202678 2.724912)
			(size 0.381 0.381)
			(layers "F.Cu" "F.Mask" "F.Paste")
			(net "GND")
		)
		(pad "AD2" smd circle
			(at 7.1501 -3.41884)
			(size 0.3048 0.3048)
			(layers "F.Cu" "F.Mask" "F.Paste")
			(net "GND")
		)
		(pad "AD34" smd circle
			(at 7.1501 3.420364)
			(size 0.3048 0.3048)
			(layers "F.Cu" "F.Mask" "F.Paste")
			(net "GND")
		)
		(pad "AE1" smd oval
			(at 6.849872 -3.938524)
			(size 0.254 0.3302)
			(layers "F.Cu" "F.Mask" "F.Paste")
			(net "GND")
		)
		(pad "AE35" smd oval
			(at 6.849872 3.940048)
			(size 0.254 0.3302)
			(layers "F.Cu" "F.Mask" "F.Paste")
			(net "GND")
		)
		(pad "AF7" smd circle
			(at 6.802628 -2.12471)
			(size 0.381 0.381)
			(layers "F.Cu" "F.Mask" "F.Paste")
			(net "P5E_CPU1_P3_TX_BUF_DP<13>")
		)
		(pad "AF26" smd circle
			(at 6.802628 1.339342)
			(size 0.381 0.381)
			(layers "F.Cu" "F.Mask" "F.Paste")
			(net "P5E_CPU1_P3_RX_DP<13>")
		)
		(pad "AG2" smd circle
			(at 6.549898 -3.41884)
			(size 0.3048 0.3048)
			(layers "F.Cu" "F.Mask" "F.Paste")
			(net "P5E_CPU1_P3_RX_BUF_DN<13>")
		)
		(pad "AG34" smd circle
			(at 6.549898 3.420364)
			(size 0.3048 0.3048)
			(layers "F.Cu" "F.Mask" "F.Paste")
			(net "P5E_CPU1_P3_TX_C_DN<13>")
		)
		(pad "AH10" smd circle
			(at 6.402578 -1.431798)
			(size 0.381 0.381)
			(layers "F.Cu" "F.Mask" "F.Paste")
			(net "P5E_CPU1_P3_TX_BUF_DN<13>")
		)
		(pad "AH29" smd circle
			(at 6.402578 2.032254)
			(size 0.381 0.381)
			(layers "F.Cu" "F.Mask" "F.Paste")
			(net "P5E_CPU1_P3_RX_DN<13>")
		)
		(pad "AJ1" smd oval
			(at 6.249924 -3.938524)
			(size 0.254 0.3302)
			(layers "F.Cu" "F.Mask" "F.Paste")
			(net "P5E_CPU1_P3_RX_BUF_DP<13>")
		)
		(pad "AJ35" smd oval
			(at 6.249924 3.940048)
			(size 0.254 0.3302)
			(layers "F.Cu" "F.Mask" "F.Paste")
			(net "P5E_CPU1_P3_TX_C_DP<13>")
		)
		(pad "AK4" smd circle
			(at 6.002528 -2.817368)
			(size 0.381 0.381)
			(layers "F.Cu" "F.Mask" "F.Paste")
			(net "GND")
		)
		(pad "AK13" smd circle
			(at 6.002528 -0.79629)
			(size 0.3048 0.3048)
			(layers "F.Cu" "F.Mask" "F.Paste")
			(net "GND")
		)
		(pad "AK17" smd circle
			(at 6.002528 -0.296164)
			(size 0.3048 0.3048)
			(layers "F.Cu" "F.Mask" "F.Paste")
			(net "P0V9_CPU1_RT3_2A")
		)
		(pad "AK20" smd circle
			(at 6.002528 0.203708)
			(size 0.3048 0.3048)
			(layers "F.Cu" "F.Mask" "F.Paste")
			(net "P0V9_CPU1_RT3_2A")
		)
		(pad "AK22" smd circle
			(at 6.002528 0.703834)
			(size 0.3048 0.3048)
			(layers "F.Cu" "F.Mask" "F.Paste")
			(net "GND")
		)
		(pad "AK32" smd circle
			(at 6.002528 2.724912)
			(size 0.381 0.381)
			(layers "F.Cu" "F.Mask" "F.Paste")
			(net "GND")
		)
		(pad "AL2" smd circle
			(at 5.94995 -3.41884)
			(size 0.3048 0.3048)
			(layers "F.Cu" "F.Mask" "F.Paste")
			(net "GND")
		)
		(pad "AL34" smd circle
			(at 5.94995 3.420364)
			(size 0.3048 0.3048)
			(layers "F.Cu" "F.Mask" "F.Paste")
			(net "GND")
		)
		(pad "AM1" smd oval
			(at 5.649976 -3.938524)
			(size 0.254 0.3302)
			(layers "F.Cu" "F.Mask" "F.Paste")
			(net "GND")
		)
		(pad "AM35" smd oval
			(at 5.649976 3.940048)
			(size 0.254 0.3302)
			(layers "F.Cu" "F.Mask" "F.Paste")
			(net "GND")
		)
		(pad "AN7" smd circle
			(at 5.602478 -2.12471)
			(size 0.381 0.381)
			(layers "F.Cu" "F.Mask" "F.Paste")
			(net "P5E_CPU1_P3_TX_BUF_DP<12>")
		)
		(pad "AN26" smd circle
			(at 5.602478 1.339342)
			(size 0.381 0.381)
			(layers "F.Cu" "F.Mask" "F.Paste")
			(net "P5E_CPU1_P3_RX_DP<12>")
		)
		(pad "AP2" smd circle
			(at 5.350002 -3.41884)
			(size 0.3048 0.3048)
			(layers "F.Cu" "F.Mask" "F.Paste")
			(net "P5E_CPU1_P3_RX_BUF_DN<12>")
		)
		(pad "AP34" smd circle
			(at 5.350002 3.420364)
			(size 0.3048 0.3048)
			(layers "F.Cu" "F.Mask" "F.Paste")
			(net "P5E_CPU1_P3_TX_C_DN<12>")
		)
		(pad "AR10" smd circle
			(at 5.202682 -1.431798)
			(size 0.381 0.381)
			(layers "F.Cu" "F.Mask" "F.Paste")
			(net "P5E_CPU1_P3_TX_BUF_DN<12>")
		)
		(pad "AR29" smd circle
			(at 5.202682 2.032254)
			(size 0.381 0.381)
			(layers "F.Cu" "F.Mask" "F.Paste")
			(net "P5E_CPU1_P3_RX_DN<12>")
		)
		(pad "AT1" smd oval
			(at 5.050028 -3.938524)
			(size 0.254 0.3302)
			(layers "F.Cu" "F.Mask" "F.Paste")
			(net "P5E_CPU1_P3_RX_BUF_DP<12>")
		)
		(pad "AT35" smd oval
			(at 5.050028 3.940048)
			(size 0.254 0.3302)
			(layers "F.Cu" "F.Mask" "F.Paste")
			(net "P5E_CPU1_P3_TX_C_DP<12>")
		)
		(pad "AU4" smd circle
			(at 4.802632 -2.817368)
			(size 0.381 0.381)
			(layers "F.Cu" "F.Mask" "F.Paste")
			(net "GND")
		)
		(pad "AU13" smd circle
			(at 4.802632 -0.79629)
			(size 0.3048 0.3048)
			(layers "F.Cu" "F.Mask" "F.Paste")
			(net "GND")
		)
		(pad "AU17" smd circle
			(at 4.802632 -0.296164)
			(size 0.3048 0.3048)
			(layers "F.Cu" "F.Mask" "F.Paste")
			(net "P0V9_CPU1_RT3_2A")
		)
		(pad "AU20" smd circle
			(at 4.802632 0.203708)
			(size 0.3048 0.3048)
			(layers "F.Cu" "F.Mask" "F.Paste")
			(net "P0V9_CPU1_RT3_2A")
		)
		(pad "AU22" smd circle
			(at 4.802632 0.703834)
			(size 0.3048 0.3048)
			(layers "F.Cu" "F.Mask" "F.Paste")
			(net "GND")
		)
		(pad "AU32" smd circle
			(at 4.802632 2.724912)
			(size 0.381 0.381)
			(layers "F.Cu" "F.Mask" "F.Paste")
			(net "GND")
		)
		(pad "AV2" smd circle
			(at 4.750054 -3.41884)
			(size 0.3048 0.3048)
			(layers "F.Cu" "F.Mask" "F.Paste")
			(net "GND")
		)
		(pad "AV34" smd circle
			(at 4.750054 3.420364)
			(size 0.3048 0.3048)
			(layers "F.Cu" "F.Mask" "F.Paste")
			(net "GND")
		)
		(pad "AW1" smd oval
			(at 4.45008 -3.938524)
			(size 0.254 0.3302)
			(layers "F.Cu" "F.Mask" "F.Paste")
			(net "GND")
		)
		(pad "AW35" smd oval
			(at 4.45008 3.940048)
			(size 0.254 0.3302)
			(layers "F.Cu" "F.Mask" "F.Paste")
			(net "GND")
		)
		(pad "AY7" smd circle
			(at 4.402582 -2.12471)
			(size 0.381 0.381)
			(layers "F.Cu" "F.Mask" "F.Paste")
			(net "P5E_CPU1_P3_TX_BUF_DP<11>")
		)
		(pad "AY26" smd circle
			(at 4.402582 1.339342)
			(size 0.381 0.381)
			(layers "F.Cu" "F.Mask" "F.Paste")
			(net "P5E_CPU1_P3_RX_DP<11>")
		)
		(pad "B3" smd oval
			(at 10.885932 -2.888488 90)
			(size 0.254 0.3302)
			(layers "F.Cu" "F.Mask" "F.Paste")
			(net "JTAG_TCK_RT_CPU1_P3")
		)
		(pad "B6" smd oval
			(at 10.885932 -2.288286 90)
			(size 0.254 0.3302)
			(layers "F.Cu" "F.Mask" "F.Paste")
			(net "JTAG_TDI_RT_CPU1_P3")
		)
		(pad "B9" smd oval
			(at 10.885932 -1.688338 90)
			(size 0.254 0.3302)
			(layers "F.Cu" "F.Mask" "F.Paste")
			(net "JTAG_TDO_RT_CPU1_P3")
		)
		(pad "B12" smd oval
			(at 10.885932 -1.08839 90)
			(size 0.254 0.3302)
			(layers "F.Cu" "F.Mask" "F.Paste")
			(net "JTAG_TMS_RT_CPU1_P3")
		)
		(pad "B16" smd oval
			(at 10.885932 -0.488442 90)
			(size 0.254 0.3302)
			(layers "F.Cu" "F.Mask" "F.Paste")
			(net "Net_2229")
		)
		(pad "B19" smd oval
			(at 10.885932 0.111506 90)
			(size 0.254 0.3302)
			(layers "F.Cu" "F.Mask" "F.Paste")
			(net "GND")
		)
		(pad "B23" smd oval
			(at 10.885932 0.711708 90)
			(size 0.254 0.3302)
			(layers "F.Cu" "F.Mask" "F.Paste")
			(net "RT_CPU1_P3_ADDR2")
		)
		(pad "B25" smd oval
			(at 10.885932 1.311656 90)
			(size 0.254 0.3302)
			(layers "F.Cu" "F.Mask" "F.Paste")
			(net "RT_CPU1_P3_ADDR3")
		)
		(pad "B28" smd oval
			(at 10.885932 1.911604 90)
			(size 0.254 0.3302)
			(layers "F.Cu" "F.Mask" "F.Paste")
			(net "SMB_RT_CPU1_P3_R2_SDA")
		)
		(pad "B31" smd oval
			(at 10.885932 2.511552 90)
			(size 0.254 0.3302)
			(layers "F.Cu" "F.Mask" "F.Paste")
			(net "SMB_RT_CPU1_P3_R2_SCL")
		)
		(pad "BA2" smd circle
			(at 4.150106 -3.41884)
			(size 0.3048 0.3048)
			(layers "F.Cu" "F.Mask" "F.Paste")
			(net "P5E_CPU1_P3_RX_BUF_DN<11>")
		)
		(pad "BA34" smd circle
			(at 4.150106 3.420364)
			(size 0.3048 0.3048)
			(layers "F.Cu" "F.Mask" "F.Paste")
			(net "P5E_CPU1_P3_TX_C_DN<11>")
		)
		(pad "BB10" smd circle
			(at 4.002532 -1.431798)
			(size 0.381 0.381)
			(layers "F.Cu" "F.Mask" "F.Paste")
			(net "P5E_CPU1_P3_TX_BUF_DN<11>")
		)
		(pad "BB29" smd circle
			(at 4.002532 2.032254)
			(size 0.381 0.381)
			(layers "F.Cu" "F.Mask" "F.Paste")
			(net "P5E_CPU1_P3_RX_DN<11>")
		)
		(pad "BC1" smd oval
			(at 3.849878 -3.938524)
			(size 0.254 0.3302)
			(layers "F.Cu" "F.Mask" "F.Paste")
			(net "P5E_CPU1_P3_RX_BUF_DP<11>")
		)
		(pad "BC35" smd oval
			(at 3.849878 3.940048)
			(size 0.254 0.3302)
			(layers "F.Cu" "F.Mask" "F.Paste")
			(net "P5E_CPU1_P3_TX_C_DP<11>")
		)
		(pad "BD4" smd circle
			(at 3.602482 -2.817368)
			(size 0.381 0.381)
			(layers "F.Cu" "F.Mask" "F.Paste")
			(net "GND")
		)
		(pad "BD13" smd circle
			(at 3.602482 -0.79629)
			(size 0.3048 0.3048)
			(layers "F.Cu" "F.Mask" "F.Paste")
			(net "GND")
		)
		(pad "BD17" smd circle
			(at 3.602482 -0.296164)
			(size 0.3048 0.3048)
			(layers "F.Cu" "F.Mask" "F.Paste")
			(net "P0V9_CPU1_RT3_2A_2D")
		)
		(pad "BD20" smd circle
			(at 3.602482 0.203708)
			(size 0.3048 0.3048)
			(layers "F.Cu" "F.Mask" "F.Paste")
			(net "P0V9_CPU1_RT3_2A_2D")
		)
		(pad "BD22" smd circle
			(at 3.602482 0.703834)
			(size 0.3048 0.3048)
			(layers "F.Cu" "F.Mask" "F.Paste")
			(net "GND")
		)
		(pad "BD32" smd circle
			(at 3.602482 2.724912)
			(size 0.381 0.381)
			(layers "F.Cu" "F.Mask" "F.Paste")
			(net "GND")
		)
		(pad "BE2" smd circle
			(at 3.549904 -3.41884)
			(size 0.3048 0.3048)
			(layers "F.Cu" "F.Mask" "F.Paste")
			(net "GND")
		)
		(pad "BE34" smd circle
			(at 3.549904 3.420364)
			(size 0.3048 0.3048)
			(layers "F.Cu" "F.Mask" "F.Paste")
			(net "GND")
		)
		(pad "BF1" smd oval
			(at 3.24993 -3.938524)
			(size 0.254 0.3302)
			(layers "F.Cu" "F.Mask" "F.Paste")
			(net "GND")
		)
		(pad "BF35" smd oval
			(at 3.24993 3.940048)
			(size 0.254 0.3302)
			(layers "F.Cu" "F.Mask" "F.Paste")
			(net "GND")
		)
		(pad "BG7" smd circle
			(at 3.202686 -2.12471)
			(size 0.381 0.381)
			(layers "F.Cu" "F.Mask" "F.Paste")
			(net "P5E_CPU1_P3_TX_BUF_DP<10>")
		)
		(pad "BG26" smd circle
			(at 3.202686 1.339342)
			(size 0.381 0.381)
			(layers "F.Cu" "F.Mask" "F.Paste")
			(net "P5E_CPU1_P3_RX_DP<10>")
		)
		(pad "BH2" smd circle
			(at 2.949956 -3.41884)
			(size 0.3048 0.3048)
			(layers "F.Cu" "F.Mask" "F.Paste")
			(net "P5E_CPU1_P3_RX_BUF_DN<10>")
		)
		(pad "BH34" smd circle
			(at 2.949956 3.420364)
			(size 0.3048 0.3048)
			(layers "F.Cu" "F.Mask" "F.Paste")
			(net "P5E_CPU1_P3_TX_C_DN<10>")
		)
		(pad "BJ10" smd circle
			(at 2.802636 -1.431798)
			(size 0.381 0.381)
			(layers "F.Cu" "F.Mask" "F.Paste")
			(net "P5E_CPU1_P3_TX_BUF_DN<10>")
		)
		(pad "BJ29" smd circle
			(at 2.802636 2.032254)
			(size 0.381 0.381)
			(layers "F.Cu" "F.Mask" "F.Paste")
			(net "P5E_CPU1_P3_RX_DN<10>")
		)
		(pad "BK1" smd oval
			(at 2.649982 -3.938524)
			(size 0.254 0.3302)
			(layers "F.Cu" "F.Mask" "F.Paste")
			(net "P5E_CPU1_P3_RX_BUF_DP<10>")
		)
		(pad "BK35" smd oval
			(at 2.649982 3.940048)
			(size 0.254 0.3302)
			(layers "F.Cu" "F.Mask" "F.Paste")
			(net "P5E_CPU1_P3_TX_C_DP<10>")
		)
		(pad "BL4" smd circle
			(at 2.402586 -2.817368)
			(size 0.381 0.381)
			(layers "F.Cu" "F.Mask" "F.Paste")
			(net "GND")
		)
		(pad "BL13" smd circle
			(at 2.402586 -0.79629)
			(size 0.3048 0.3048)
			(layers "F.Cu" "F.Mask" "F.Paste")
			(net "GND")
		)
		(pad "BL17" smd circle
			(at 2.402586 -0.296164)
			(size 0.3048 0.3048)
			(layers "F.Cu" "F.Mask" "F.Paste")
			(net "P0V9_CPU1_RT_2D")
		)
		(pad "BL20" smd circle
			(at 2.402586 0.203708)
			(size 0.3048 0.3048)
			(layers "F.Cu" "F.Mask" "F.Paste")
			(net "P0V9_CPU1_RT_2D")
		)
		(pad "BL22" smd circle
			(at 2.402586 0.703834)
			(size 0.3048 0.3048)
			(layers "F.Cu" "F.Mask" "F.Paste")
			(net "GND")
		)
		(pad "BL32" smd circle
			(at 2.402586 2.724912)
			(size 0.381 0.381)
			(layers "F.Cu" "F.Mask" "F.Paste")
			(net "GND")
		)
		(pad "BM2" smd circle
			(at 2.350008 -3.41884)
			(size 0.3048 0.3048)
			(layers "F.Cu" "F.Mask" "F.Paste")
			(net "GND")
		)
		(pad "BM34" smd circle
			(at 2.350008 3.420364)
			(size 0.3048 0.3048)
			(layers "F.Cu" "F.Mask" "F.Paste")
			(net "GND")
		)
		(pad "BN1" smd oval
			(at 2.050034 -3.938524)
			(size 0.254 0.3302)
			(layers "F.Cu" "F.Mask" "F.Paste")
			(net "GND")
		)
		(pad "BN35" smd oval
			(at 2.050034 3.940048)
			(size 0.254 0.3302)
			(layers "F.Cu" "F.Mask" "F.Paste")
			(net "GND")
		)
		(pad "BP7" smd circle
			(at 2.002536 -2.12471)
			(size 0.381 0.381)
			(layers "F.Cu" "F.Mask" "F.Paste")
			(net "P5E_CPU1_P3_TX_BUF_DP<9>")
		)
		(pad "BP26" smd circle
			(at 2.002536 1.339342)
			(size 0.381 0.381)
			(layers "F.Cu" "F.Mask" "F.Paste")
			(net "P5E_CPU1_P3_RX_DP<9>")
		)
		(pad "BR2" smd circle
			(at 1.75006 -3.41884)
			(size 0.3048 0.3048)
			(layers "F.Cu" "F.Mask" "F.Paste")
			(net "P5E_CPU1_P3_RX_BUF_DN<9>")
		)
		(pad "BR34" smd circle
			(at 1.75006 3.420364)
			(size 0.3048 0.3048)
			(layers "F.Cu" "F.Mask" "F.Paste")
			(net "P5E_CPU1_P3_TX_C_DN<9>")
		)
		(pad "BT10" smd circle
			(at 1.602486 -1.431798)
			(size 0.381 0.381)
			(layers "F.Cu" "F.Mask" "F.Paste")
			(net "P5E_CPU1_P3_TX_BUF_DN<9>")
		)
		(pad "BT29" smd circle
			(at 1.602486 2.032254)
			(size 0.381 0.381)
			(layers "F.Cu" "F.Mask" "F.Paste")
			(net "P5E_CPU1_P3_RX_DN<9>")
		)
		(pad "BU1" smd oval
			(at 1.450086 -3.938524)
			(size 0.254 0.3302)
			(layers "F.Cu" "F.Mask" "F.Paste")
			(net "P5E_CPU1_P3_RX_BUF_DP<9>")
		)
		(pad "BU35" smd oval
			(at 1.450086 3.940048)
			(size 0.254 0.3302)
			(layers "F.Cu" "F.Mask" "F.Paste")
			(net "P5E_CPU1_P3_TX_C_DP<9>")
		)
		(pad "BV4" smd circle
			(at 1.20269 -2.817368)
			(size 0.381 0.381)
			(layers "F.Cu" "F.Mask" "F.Paste")
			(net "GND")
		)
		(pad "BV13" smd circle
			(at 1.20269 -0.79629)
			(size 0.3048 0.3048)
			(layers "F.Cu" "F.Mask" "F.Paste")
			(net "GND")
		)
		(pad "BV17" smd circle
			(at 1.20269 -0.296164)
			(size 0.3048 0.3048)
			(layers "F.Cu" "F.Mask" "F.Paste")
			(net "P1V8_CPU1_RT3_1A_1D")
		)
		(pad "BV20" smd circle
			(at 1.20269 0.203708)
			(size 0.3048 0.3048)
			(layers "F.Cu" "F.Mask" "F.Paste")
			(net "P1V8_CPU1_RT3_1A")
		)
		(pad "BV22" smd circle
			(at 1.20269 0.703834)
			(size 0.3048 0.3048)
			(layers "F.Cu" "F.Mask" "F.Paste")
			(net "GND")
		)
		(pad "BV32" smd circle
			(at 1.20269 2.724912)
			(size 0.381 0.381)
			(layers "F.Cu" "F.Mask" "F.Paste")
			(net "GND")
		)
		(pad "BW2" smd circle
			(at 1.150112 -3.41884)
			(size 0.3048 0.3048)
			(layers "F.Cu" "F.Mask" "F.Paste")
			(net "GND")
		)
		(pad "BW34" smd circle
			(at 1.150112 3.420364)
			(size 0.3048 0.3048)
			(layers "F.Cu" "F.Mask" "F.Paste")
			(net "GND")
		)
		(pad "BY1" smd oval
			(at 0.849884 -3.938524)
			(size 0.254 0.3302)
			(layers "F.Cu" "F.Mask" "F.Paste")
			(net "GND")
		)
		(pad "BY35" smd oval
			(at 0.849884 3.940048)
			(size 0.254 0.3302)
			(layers "F.Cu" "F.Mask" "F.Paste")
			(net "GND")
		)
		(pad "C2" smd circle
			(at 10.750042 -3.41884)
			(size 0.3048 0.3048)
			(layers "F.Cu" "F.Mask" "F.Paste")
			(net "NCF_CPU1_P3_GND")
		)
		(pad "C34" smd circle
			(at 10.750042 3.420364)
			(size 0.3048 0.3048)
			(layers "F.Cu" "F.Mask" "F.Paste")
			(net "NCF_CPU1_P3_GND")
		)
		(pad "CA7" smd circle
			(at 0.80264 -2.12471)
			(size 0.381 0.381)
			(layers "F.Cu" "F.Mask" "F.Paste")
			(net "P5E_CPU1_P3_TX_BUF_DP<8>")
		)
		(pad "CA26" smd circle
			(at 0.80264 1.339342)
			(size 0.381 0.381)
			(layers "F.Cu" "F.Mask" "F.Paste")
			(net "P5E_CPU1_P3_RX_DP<8>")
		)
		(pad "CB2" smd circle
			(at 0.54991 -3.41884)
			(size 0.3048 0.3048)
			(layers "F.Cu" "F.Mask" "F.Paste")
			(net "P5E_CPU1_P3_RX_BUF_DN<8>")
		)
		(pad "CB34" smd circle
			(at 0.54991 3.420364)
			(size 0.3048 0.3048)
			(layers "F.Cu" "F.Mask" "F.Paste")
			(net "P5E_CPU1_P3_TX_C_DN<8>")
		)
		(pad "CC10" smd circle
			(at 0.40259 -1.431798)
			(size 0.381 0.381)
			(layers "F.Cu" "F.Mask" "F.Paste")
			(net "P5E_CPU1_P3_TX_BUF_DN<8>")
		)
		(pad "CC29" smd circle
			(at 0.40259 2.032254)
			(size 0.381 0.381)
			(layers "F.Cu" "F.Mask" "F.Paste")
			(net "P5E_CPU1_P3_RX_DN<8>")
		)
		(pad "CD1" smd oval
			(at 0.249936 -3.938524)
			(size 0.254 0.3302)
			(layers "F.Cu" "F.Mask" "F.Paste")
			(net "P5E_CPU1_P3_RX_BUF_DP<8>")
		)
		(pad "CD35" smd oval
			(at 0.249936 3.940048)
			(size 0.254 0.3302)
			(layers "F.Cu" "F.Mask" "F.Paste")
			(net "P5E_CPU1_P3_TX_C_DP<8>")
		)
		(pad "CE4" smd circle
			(at 0.00254 -2.817368)
			(size 0.381 0.381)
			(layers "F.Cu" "F.Mask" "F.Paste")
			(net "GND")
		)
		(pad "CE13" smd circle
			(at 0.00254 -0.79629)
			(size 0.3048 0.3048)
			(layers "F.Cu" "F.Mask" "F.Paste")
			(net "GND")
		)
		(pad "CE17" smd circle
			(at 0.00254 -0.296164)
			(size 0.3048 0.3048)
			(layers "F.Cu" "F.Mask" "F.Paste")
			(net "P1V8_CPU1_RT3_1A")
		)
		(pad "CE20" smd circle
			(at 0.00254 0.203708)
			(size 0.3048 0.3048)
			(layers "F.Cu" "F.Mask" "F.Paste")
			(net "P1V8_CPU1_RT3_1A")
		)
		(pad "CE22" smd circle
			(at 0.00254 0.703834)
			(size 0.3048 0.3048)
			(layers "F.Cu" "F.Mask" "F.Paste")
			(net "GND")
		)
		(pad "CE32" smd circle
			(at 0.00254 2.724912)
			(size 0.381 0.381)
			(layers "F.Cu" "F.Mask" "F.Paste")
			(net "GND")
		)
		(pad "CF2" smd circle
			(at -0.050038 -3.41884)
			(size 0.3048 0.3048)
			(layers "F.Cu" "F.Mask" "F.Paste")
			(net "GND")
		)
		(pad "CF34" smd circle
			(at -0.050038 3.420364)
			(size 0.3048 0.3048)
			(layers "F.Cu" "F.Mask" "F.Paste")
			(net "GND")
		)
		(pad "CG1" smd oval
			(at -0.350012 -3.938524)
			(size 0.254 0.3302)
			(layers "F.Cu" "F.Mask" "F.Paste")
			(net "GND")
		)
		(pad "CG35" smd oval
			(at -0.350012 3.940048)
			(size 0.254 0.3302)
			(layers "F.Cu" "F.Mask" "F.Paste")
			(net "GND")
		)
		(pad "CH7" smd circle
			(at -0.39751 -2.12471)
			(size 0.381 0.381)
			(layers "F.Cu" "F.Mask" "F.Paste")
			(net "P5E_CPU1_P3_TX_BUF_DP<7>")
		)
		(pad "CH26" smd circle
			(at -0.39751 1.339342)
			(size 0.381 0.381)
			(layers "F.Cu" "F.Mask" "F.Paste")
			(net "P5E_CPU1_P3_RX_DP<7>")
		)
		(pad "CJ2" smd circle
			(at -0.649986 -3.41884)
			(size 0.3048 0.3048)
			(layers "F.Cu" "F.Mask" "F.Paste")
			(net "P5E_CPU1_P3_RX_BUF_DN<7>")
		)
		(pad "CJ34" smd circle
			(at -0.649986 3.420364)
			(size 0.3048 0.3048)
			(layers "F.Cu" "F.Mask" "F.Paste")
			(net "P5E_CPU1_P3_TX_C_DN<7>")
		)
		(pad "CK10" smd circle
			(at -0.797306 -1.431798)
			(size 0.381 0.381)
			(layers "F.Cu" "F.Mask" "F.Paste")
			(net "P5E_CPU1_P3_TX_BUF_DN<7>")
		)
		(pad "CK29" smd circle
			(at -0.797306 2.032254)
			(size 0.381 0.381)
			(layers "F.Cu" "F.Mask" "F.Paste")
			(net "P5E_CPU1_P3_RX_DN<7>")
		)
		(pad "CL1" smd oval
			(at -0.94996 -3.938524)
			(size 0.254 0.3302)
			(layers "F.Cu" "F.Mask" "F.Paste")
			(net "P5E_CPU1_P3_RX_BUF_DP<7>")
		)
		(pad "CL35" smd oval
			(at -0.94996 3.940048)
			(size 0.254 0.3302)
			(layers "F.Cu" "F.Mask" "F.Paste")
			(net "P5E_CPU1_P3_TX_C_DP<7>")
		)
		(pad "CM4" smd circle
			(at -1.197356 -2.817368)
			(size 0.381 0.381)
			(layers "F.Cu" "F.Mask" "F.Paste")
			(net "GND")
		)
		(pad "CM13" smd circle
			(at -1.197356 -0.79629)
			(size 0.3048 0.3048)
			(layers "F.Cu" "F.Mask" "F.Paste")
			(net "GND")
		)
		(pad "CM17" smd circle
			(at -1.197356 -0.296164)
			(size 0.3048 0.3048)
			(layers "F.Cu" "F.Mask" "F.Paste")
			(net "P1V8_CPU1_RT3_1A")
		)
		(pad "CM20" smd circle
			(at -1.197356 0.203708)
			(size 0.3048 0.3048)
			(layers "F.Cu" "F.Mask" "F.Paste")
			(net "P1V8_CPU1_RT3_1A")
		)
		(pad "CM22" smd circle
			(at -1.197356 0.703834)
			(size 0.3048 0.3048)
			(layers "F.Cu" "F.Mask" "F.Paste")
			(net "GND")
		)
		(pad "CM32" smd circle
			(at -1.197356 2.724912)
			(size 0.381 0.381)
			(layers "F.Cu" "F.Mask" "F.Paste")
			(net "GND")
		)
		(pad "CN2" smd circle
			(at -1.249934 -3.41884)
			(size 0.3048 0.3048)
			(layers "F.Cu" "F.Mask" "F.Paste")
			(net "GND")
		)
		(pad "CN34" smd circle
			(at -1.249934 3.420364)
			(size 0.3048 0.3048)
			(layers "F.Cu" "F.Mask" "F.Paste")
			(net "GND")
		)
		(pad "CP1" smd oval
			(at -1.549908 -3.938524)
			(size 0.254 0.3302)
			(layers "F.Cu" "F.Mask" "F.Paste")
			(net "GND")
		)
		(pad "CP35" smd oval
			(at -1.549908 3.940048)
			(size 0.254 0.3302)
			(layers "F.Cu" "F.Mask" "F.Paste")
			(net "GND")
		)
		(pad "CR7" smd circle
			(at -1.597406 -2.12471)
			(size 0.381 0.381)
			(layers "F.Cu" "F.Mask" "F.Paste")
			(net "P5E_CPU1_P3_TX_BUF_DP<6>")
		)
		(pad "CR26" smd circle
			(at -1.597406 1.339342)
			(size 0.381 0.381)
			(layers "F.Cu" "F.Mask" "F.Paste")
			(net "P5E_CPU1_P3_RX_DP<6>")
		)
		(pad "CT2" smd circle
			(at -1.849882 -3.41884)
			(size 0.3048 0.3048)
			(layers "F.Cu" "F.Mask" "F.Paste")
			(net "P5E_CPU1_P3_RX_BUF_DN<6>")
		)
		(pad "CT34" smd circle
			(at -1.849882 3.420364)
			(size 0.3048 0.3048)
			(layers "F.Cu" "F.Mask" "F.Paste")
			(net "P5E_CPU1_P3_TX_C_DN<6>")
		)
		(pad "CU10" smd circle
			(at -1.997456 -1.431798)
			(size 0.381 0.381)
			(layers "F.Cu" "F.Mask" "F.Paste")
			(net "P5E_CPU1_P3_TX_BUF_DN<6>")
		)
		(pad "CU29" smd circle
			(at -1.997456 2.032254)
			(size 0.381 0.381)
			(layers "F.Cu" "F.Mask" "F.Paste")
			(net "P5E_CPU1_P3_RX_DN<6>")
		)
		(pad "CV1" smd oval
			(at -2.15011 -3.938524)
			(size 0.254 0.3302)
			(layers "F.Cu" "F.Mask" "F.Paste")
			(net "P5E_CPU1_P3_RX_BUF_DP<6>")
		)
		(pad "CV35" smd oval
			(at -2.15011 3.940048)
			(size 0.254 0.3302)
			(layers "F.Cu" "F.Mask" "F.Paste")
			(net "P5E_CPU1_P3_TX_C_DP<6>")
		)
		(pad "CW4" smd circle
			(at -2.397506 -2.817368)
			(size 0.381 0.381)
			(layers "F.Cu" "F.Mask" "F.Paste")
			(net "GND")
		)
		(pad "CW13" smd circle
			(at -2.397506 -0.79629)
			(size 0.3048 0.3048)
			(layers "F.Cu" "F.Mask" "F.Paste")
			(net "GND")
		)
		(pad "CW17" smd circle
			(at -2.397506 -0.296164)
			(size 0.3048 0.3048)
			(layers "F.Cu" "F.Mask" "F.Paste")
			(net "P0V9_CPU1_RT_2D")
		)
		(pad "CW20" smd circle
			(at -2.397506 0.203708)
			(size 0.3048 0.3048)
			(layers "F.Cu" "F.Mask" "F.Paste")
			(net "P0V9_CPU1_RT_2D")
		)
		(pad "CW22" smd circle
			(at -2.397506 0.703834)
			(size 0.3048 0.3048)
			(layers "F.Cu" "F.Mask" "F.Paste")
			(net "GND")
		)
		(pad "CW32" smd circle
			(at -2.397506 2.724912)
			(size 0.381 0.381)
			(layers "F.Cu" "F.Mask" "F.Paste")
			(net "GND")
		)
		(pad "CY2" smd circle
			(at -2.450084 -3.41884)
			(size 0.3048 0.3048)
			(layers "F.Cu" "F.Mask" "F.Paste")
			(net "GND")
		)
		(pad "CY34" smd circle
			(at -2.450084 3.420364)
			(size 0.3048 0.3048)
			(layers "F.Cu" "F.Mask" "F.Paste")
			(net "GND")
		)
		(pad "D1" smd oval
			(at 10.450068 -3.938524)
			(size 0.254 0.3302)
			(layers "F.Cu" "F.Mask" "F.Paste")
			(net "NCF_CPU1_P3_GND")
		)
		(pad "D35" smd oval
			(at 10.450068 3.940048)
			(size 0.254 0.3302)
			(layers "F.Cu" "F.Mask" "F.Paste")
			(net "NCF_CPU1_P3_GND")
		)
		(pad "DA1" smd oval
			(at -2.750058 -3.938524)
			(size 0.254 0.3302)
			(layers "F.Cu" "F.Mask" "F.Paste")
			(net "GND")
		)
		(pad "DA35" smd oval
			(at -2.750058 3.940048)
			(size 0.254 0.3302)
			(layers "F.Cu" "F.Mask" "F.Paste")
			(net "GND")
		)
		(pad "DB7" smd circle
			(at -2.797302 -2.12471)
			(size 0.381 0.381)
			(layers "F.Cu" "F.Mask" "F.Paste")
			(net "P5E_CPU1_P3_TX_BUF_DP<5>")
		)
		(pad "DB26" smd circle
			(at -2.797302 1.339342)
			(size 0.381 0.381)
			(layers "F.Cu" "F.Mask" "F.Paste")
			(net "P5E_CPU1_P3_RX_DP<5>")
		)
		(pad "DC2" smd circle
			(at -3.050032 -3.41884)
			(size 0.3048 0.3048)
			(layers "F.Cu" "F.Mask" "F.Paste")
			(net "P5E_CPU1_P3_RX_BUF_DN<5>")
		)
		(pad "DC34" smd circle
			(at -3.050032 3.420364)
			(size 0.3048 0.3048)
			(layers "F.Cu" "F.Mask" "F.Paste")
			(net "P5E_CPU1_P3_TX_C_DN<5>")
		)
		(pad "DD10" smd circle
			(at -3.197352 -1.431798)
			(size 0.381 0.381)
			(layers "F.Cu" "F.Mask" "F.Paste")
			(net "P5E_CPU1_P3_TX_BUF_DN<5>")
		)
		(pad "DD29" smd circle
			(at -3.197352 2.032254)
			(size 0.381 0.381)
			(layers "F.Cu" "F.Mask" "F.Paste")
			(net "P5E_CPU1_P3_RX_DN<5>")
		)
		(pad "DE1" smd oval
			(at -3.350006 -3.938524)
			(size 0.254 0.3302)
			(layers "F.Cu" "F.Mask" "F.Paste")
			(net "P5E_CPU1_P3_RX_BUF_DP<5>")
		)
		(pad "DE35" smd oval
			(at -3.350006 3.940048)
			(size 0.254 0.3302)
			(layers "F.Cu" "F.Mask" "F.Paste")
			(net "P5E_CPU1_P3_TX_C_DP<5>")
		)
		(pad "DF4" smd circle
			(at -3.597402 -2.817368)
			(size 0.381 0.381)
			(layers "F.Cu" "F.Mask" "F.Paste")
			(net "GND")
		)
		(pad "DF13" smd circle
			(at -3.597402 -0.79629)
			(size 0.3048 0.3048)
			(layers "F.Cu" "F.Mask" "F.Paste")
			(net "GND")
		)
		(pad "DF17" smd circle
			(at -3.597402 -0.296164)
			(size 0.3048 0.3048)
			(layers "F.Cu" "F.Mask" "F.Paste")
			(net "P0V9_CPU1_RT3_2A_2D")
		)
		(pad "DF20" smd circle
			(at -3.597402 0.203708)
			(size 0.3048 0.3048)
			(layers "F.Cu" "F.Mask" "F.Paste")
			(net "P0V9_CPU1_RT3_2A_2D")
		)
		(pad "DF22" smd circle
			(at -3.597402 0.703834)
			(size 0.3048 0.3048)
			(layers "F.Cu" "F.Mask" "F.Paste")
			(net "GND")
		)
		(pad "DF32" smd circle
			(at -3.597402 2.724912)
			(size 0.381 0.381)
			(layers "F.Cu" "F.Mask" "F.Paste")
			(net "GND")
		)
		(pad "DG2" smd circle
			(at -3.64998 -3.41884)
			(size 0.3048 0.3048)
			(layers "F.Cu" "F.Mask" "F.Paste")
			(net "GND")
		)
		(pad "DG34" smd circle
			(at -3.64998 3.420364)
			(size 0.3048 0.3048)
			(layers "F.Cu" "F.Mask" "F.Paste")
			(net "GND")
		)
		(pad "DH1" smd oval
			(at -3.949954 -3.938524)
			(size 0.254 0.3302)
			(layers "F.Cu" "F.Mask" "F.Paste")
			(net "GND")
		)
		(pad "DH35" smd oval
			(at -3.949954 3.940048)
			(size 0.254 0.3302)
			(layers "F.Cu" "F.Mask" "F.Paste")
			(net "GND")
		)
		(pad "DJ7" smd circle
			(at -3.997452 -2.12471)
			(size 0.381 0.381)
			(layers "F.Cu" "F.Mask" "F.Paste")
			(net "P5E_CPU1_P3_TX_BUF_DP<4>")
		)
		(pad "DJ26" smd circle
			(at -3.997452 1.339342)
			(size 0.381 0.381)
			(layers "F.Cu" "F.Mask" "F.Paste")
			(net "P5E_CPU1_P3_RX_DP<4>")
		)
		(pad "DK2" smd circle
			(at -4.249928 -3.41884)
			(size 0.3048 0.3048)
			(layers "F.Cu" "F.Mask" "F.Paste")
			(net "P5E_CPU1_P3_RX_BUF_DN<4>")
		)
		(pad "DK34" smd circle
			(at -4.249928 3.420364)
			(size 0.3048 0.3048)
			(layers "F.Cu" "F.Mask" "F.Paste")
			(net "P5E_CPU1_P3_TX_C_DN<4>")
		)
		(pad "DL10" smd circle
			(at -4.397502 -1.431798)
			(size 0.381 0.381)
			(layers "F.Cu" "F.Mask" "F.Paste")
			(net "P5E_CPU1_P3_TX_BUF_DN<4>")
		)
		(pad "DL29" smd circle
			(at -4.397502 2.032254)
			(size 0.381 0.381)
			(layers "F.Cu" "F.Mask" "F.Paste")
			(net "P5E_CPU1_P3_RX_DN<4>")
		)
		(pad "DM1" smd oval
			(at -4.549902 -3.938524)
			(size 0.254 0.3302)
			(layers "F.Cu" "F.Mask" "F.Paste")
			(net "P5E_CPU1_P3_RX_BUF_DP<4>")
		)
		(pad "DM35" smd oval
			(at -4.549902 3.940048)
			(size 0.254 0.3302)
			(layers "F.Cu" "F.Mask" "F.Paste")
			(net "P5E_CPU1_P3_TX_C_DP<4>")
		)
		(pad "DN4" smd circle
			(at -4.797298 -2.817368)
			(size 0.381 0.381)
			(layers "F.Cu" "F.Mask" "F.Paste")
			(net "GND")
		)
		(pad "DN13" smd circle
			(at -4.797298 -0.79629)
			(size 0.3048 0.3048)
			(layers "F.Cu" "F.Mask" "F.Paste")
			(net "GND")
		)
		(pad "DN17" smd circle
			(at -4.797298 -0.296164)
			(size 0.3048 0.3048)
			(layers "F.Cu" "F.Mask" "F.Paste")
			(net "P0V9_CPU1_RT3_2A")
		)
		(pad "DN20" smd circle
			(at -4.797298 0.203708)
			(size 0.3048 0.3048)
			(layers "F.Cu" "F.Mask" "F.Paste")
			(net "P0V9_CPU1_RT3_2A")
		)
		(pad "DN22" smd circle
			(at -4.797298 0.703834)
			(size 0.3048 0.3048)
			(layers "F.Cu" "F.Mask" "F.Paste")
			(net "GND")
		)
		(pad "DN32" smd circle
			(at -4.797298 2.724912)
			(size 0.381 0.381)
			(layers "F.Cu" "F.Mask" "F.Paste")
			(net "GND")
		)
		(pad "DP2" smd circle
			(at -4.849876 -3.41884)
			(size 0.3048 0.3048)
			(layers "F.Cu" "F.Mask" "F.Paste")
			(net "GND")
		)
		(pad "DP34" smd circle
			(at -4.849876 3.420364)
			(size 0.3048 0.3048)
			(layers "F.Cu" "F.Mask" "F.Paste")
			(net "GND")
		)
		(pad "DR1" smd oval
			(at -5.150104 -3.938524)
			(size 0.254 0.3302)
			(layers "F.Cu" "F.Mask" "F.Paste")
			(net "GND")
		)
		(pad "DR35" smd oval
			(at -5.150104 3.940048)
			(size 0.254 0.3302)
			(layers "F.Cu" "F.Mask" "F.Paste")
			(net "GND")
		)
		(pad "DT7" smd circle
			(at -5.197348 -2.12471)
			(size 0.381 0.381)
			(layers "F.Cu" "F.Mask" "F.Paste")
			(net "P5E_CPU1_P3_TX_BUF_DP<3>")
		)
		(pad "DT26" smd circle
			(at -5.197348 1.339342)
			(size 0.381 0.381)
			(layers "F.Cu" "F.Mask" "F.Paste")
			(net "P5E_CPU1_P3_RX_DP<3>")
		)
		(pad "DU2" smd circle
			(at -5.450078 -3.41884)
			(size 0.3048 0.3048)
			(layers "F.Cu" "F.Mask" "F.Paste")
			(net "P5E_CPU1_P3_RX_BUF_DN<3>")
		)
		(pad "DU34" smd circle
			(at -5.450078 3.420364)
			(size 0.3048 0.3048)
			(layers "F.Cu" "F.Mask" "F.Paste")
			(net "P5E_CPU1_P3_TX_C_DN<3>")
		)
		(pad "DV10" smd circle
			(at -5.597398 -1.431798)
			(size 0.381 0.381)
			(layers "F.Cu" "F.Mask" "F.Paste")
			(net "P5E_CPU1_P3_TX_BUF_DN<3>")
		)
		(pad "DV29" smd circle
			(at -5.597398 2.032254)
			(size 0.381 0.381)
			(layers "F.Cu" "F.Mask" "F.Paste")
			(net "P5E_CPU1_P3_RX_DN<3>")
		)
		(pad "DW1" smd oval
			(at -5.750052 -3.938524)
			(size 0.254 0.3302)
			(layers "F.Cu" "F.Mask" "F.Paste")
			(net "P5E_CPU1_P3_RX_BUF_DP<3>")
		)
		(pad "DW35" smd oval
			(at -5.750052 3.940048)
			(size 0.254 0.3302)
			(layers "F.Cu" "F.Mask" "F.Paste")
			(net "P5E_CPU1_P3_TX_C_DP<3>")
		)
		(pad "DY4" smd circle
			(at -5.997448 -2.817368)
			(size 0.381 0.381)
			(layers "F.Cu" "F.Mask" "F.Paste")
			(net "GND")
		)
		(pad "DY13" smd circle
			(at -5.997448 -0.79629)
			(size 0.3048 0.3048)
			(layers "F.Cu" "F.Mask" "F.Paste")
			(net "GND")
		)
		(pad "DY17" smd circle
			(at -5.997448 -0.296164)
			(size 0.3048 0.3048)
			(layers "F.Cu" "F.Mask" "F.Paste")
			(net "P0V9_CPU1_RT3_2A")
		)
		(pad "DY20" smd circle
			(at -5.997448 0.203708)
			(size 0.3048 0.3048)
			(layers "F.Cu" "F.Mask" "F.Paste")
			(net "P0V9_CPU1_RT3_2A")
		)
		(pad "DY22" smd circle
			(at -5.997448 0.703834)
			(size 0.3048 0.3048)
			(layers "F.Cu" "F.Mask" "F.Paste")
			(net "GND")
		)
		(pad "DY32" smd circle
			(at -5.997448 2.724912)
			(size 0.381 0.381)
			(layers "F.Cu" "F.Mask" "F.Paste")
			(net "GND")
		)
		(pad "E8" smd circle
			(at 10.366502 -1.988312)
			(size 0.3048 0.3048)
			(layers "F.Cu" "F.Mask" "F.Paste")
			(net "JTAG_TRST_RT_CPU1_P3_N")
		)
		(pad "E11" smd circle
			(at 10.366502 -1.388364)
			(size 0.3048 0.3048)
			(layers "F.Cu" "F.Mask" "F.Paste")
			(net "RXDET_BYP_RT_CPU1_P3")
		)
		(pad "E14" smd circle
			(at 10.366502 -0.788416)
			(size 0.3048 0.3048)
			(layers "F.Cu" "F.Mask" "F.Paste")
			(net "GND")
		)
		(pad "E18" smd circle
			(at 10.366502 -0.188468)
			(size 0.3048 0.3048)
			(layers "F.Cu" "F.Mask" "F.Paste")
			(net "Net_2228")
		)
		(pad "E27" smd circle
			(at 10.366502 1.61163)
			(size 0.3048 0.3048)
			(layers "F.Cu" "F.Mask" "F.Paste")
			(net "GND")
		)
		(pad "E30" smd circle
			(at 10.366502 2.211578)
			(size 0.3048 0.3048)
			(layers "F.Cu" "F.Mask" "F.Paste")
			(net "GND")
		)
		(pad "E33" smd circle
			(at 10.366502 2.811526)
			(size 0.3048 0.3048)
			(layers "F.Cu" "F.Mask" "F.Paste")
			(net "GND")
		)
		(pad "EA2" smd circle
			(at -6.050026 -3.41884)
			(size 0.3048 0.3048)
			(layers "F.Cu" "F.Mask" "F.Paste")
			(net "GND")
		)
		(pad "EA34" smd circle
			(at -6.050026 3.420364)
			(size 0.3048 0.3048)
			(layers "F.Cu" "F.Mask" "F.Paste")
			(net "GND")
		)
		(pad "EB1" smd oval
			(at -6.35 -3.938524)
			(size 0.254 0.3302)
			(layers "F.Cu" "F.Mask" "F.Paste")
			(net "GND")
		)
		(pad "EB35" smd oval
			(at -6.35 3.940048)
			(size 0.254 0.3302)
			(layers "F.Cu" "F.Mask" "F.Paste")
			(net "GND")
		)
		(pad "EC7" smd circle
			(at -6.397498 -2.12471)
			(size 0.381 0.381)
			(layers "F.Cu" "F.Mask" "F.Paste")
			(net "P5E_CPU1_P3_TX_BUF_DP<2>")
		)
		(pad "EC26" smd circle
			(at -6.397498 1.339342)
			(size 0.381 0.381)
			(layers "F.Cu" "F.Mask" "F.Paste")
			(net "P5E_CPU1_P3_RX_DP<2>")
		)
		(pad "ED2" smd circle
			(at -6.649974 -3.41884)
			(size 0.3048 0.3048)
			(layers "F.Cu" "F.Mask" "F.Paste")
			(net "P5E_CPU1_P3_RX_BUF_DN<2>")
		)
		(pad "ED34" smd circle
			(at -6.649974 3.420364)
			(size 0.3048 0.3048)
			(layers "F.Cu" "F.Mask" "F.Paste")
			(net "P5E_CPU1_P3_TX_C_DN<2>")
		)
		(pad "EE10" smd circle
			(at -6.797294 -1.431798)
			(size 0.381 0.381)
			(layers "F.Cu" "F.Mask" "F.Paste")
			(net "P5E_CPU1_P3_TX_BUF_DN<2>")
		)
		(pad "EE29" smd circle
			(at -6.797294 2.032254)
			(size 0.381 0.381)
			(layers "F.Cu" "F.Mask" "F.Paste")
			(net "P5E_CPU1_P3_RX_DN<2>")
		)
		(pad "EF1" smd oval
			(at -6.949948 -3.938524)
			(size 0.254 0.3302)
			(layers "F.Cu" "F.Mask" "F.Paste")
			(net "P5E_CPU1_P3_RX_BUF_DP<2>")
		)
		(pad "EF35" smd oval
			(at -6.949948 3.940048)
			(size 0.254 0.3302)
			(layers "F.Cu" "F.Mask" "F.Paste")
			(net "P5E_CPU1_P3_TX_C_DP<2>")
		)
		(pad "EG4" smd circle
			(at -7.197344 -2.817368)
			(size 0.381 0.381)
			(layers "F.Cu" "F.Mask" "F.Paste")
			(net "GND")
		)
		(pad "EG13" smd circle
			(at -7.197344 -0.79629)
			(size 0.3048 0.3048)
			(layers "F.Cu" "F.Mask" "F.Paste")
			(net "GND")
		)
		(pad "EG17" smd circle
			(at -7.197344 -0.296164)
			(size 0.3048 0.3048)
			(layers "F.Cu" "F.Mask" "F.Paste")
			(net "P0V9_CPU1_RT3_2A")
		)
		(pad "EG20" smd circle
			(at -7.197344 0.203708)
			(size 0.3048 0.3048)
			(layers "F.Cu" "F.Mask" "F.Paste")
			(net "P0V9_CPU1_RT3_2A")
		)
		(pad "EG22" smd circle
			(at -7.197344 0.703834)
			(size 0.3048 0.3048)
			(layers "F.Cu" "F.Mask" "F.Paste")
			(net "GND")
		)
		(pad "EG32" smd circle
			(at -7.197344 2.724912)
			(size 0.381 0.381)
			(layers "F.Cu" "F.Mask" "F.Paste")
			(net "GND")
		)
		(pad "EH2" smd circle
			(at -7.249922 -3.41884)
			(size 0.3048 0.3048)
			(layers "F.Cu" "F.Mask" "F.Paste")
			(net "GND")
		)
		(pad "EH34" smd circle
			(at -7.249922 3.420364)
			(size 0.3048 0.3048)
			(layers "F.Cu" "F.Mask" "F.Paste")
			(net "GND")
		)
		(pad "EJ1" smd oval
			(at -7.549896 -3.938524)
			(size 0.254 0.3302)
			(layers "F.Cu" "F.Mask" "F.Paste")
			(net "GND")
		)
		(pad "EJ35" smd oval
			(at -7.549896 3.940048)
			(size 0.254 0.3302)
			(layers "F.Cu" "F.Mask" "F.Paste")
			(net "GND")
		)
		(pad "EK7" smd circle
			(at -7.597394 -2.12471)
			(size 0.381 0.381)
			(layers "F.Cu" "F.Mask" "F.Paste")
			(net "P5E_CPU1_P3_TX_BUF_DP<1>")
		)
		(pad "EK26" smd circle
			(at -7.597394 1.339342)
			(size 0.381 0.381)
			(layers "F.Cu" "F.Mask" "F.Paste")
			(net "P5E_CPU1_P3_RX_DP<1>")
		)
		(pad "EL2" smd circle
			(at -7.850124 -3.41884)
			(size 0.3048 0.3048)
			(layers "F.Cu" "F.Mask" "F.Paste")
			(net "P5E_CPU1_P3_RX_BUF_DN<1>")
		)
		(pad "EL34" smd circle
			(at -7.850124 3.420364)
			(size 0.3048 0.3048)
			(layers "F.Cu" "F.Mask" "F.Paste")
			(net "P5E_CPU1_P3_TX_C_DP<1>")
		)
		(pad "EM10" smd circle
			(at -7.997444 -1.431798)
			(size 0.381 0.381)
			(layers "F.Cu" "F.Mask" "F.Paste")
			(net "P5E_CPU1_P3_TX_BUF_DN<1>")
		)
		(pad "EM29" smd circle
			(at -7.997444 2.032254)
			(size 0.381 0.381)
			(layers "F.Cu" "F.Mask" "F.Paste")
			(net "P5E_CPU1_P3_RX_DN<1>")
		)
		(pad "EN1" smd oval
			(at -8.150098 -3.938524)
			(size 0.254 0.3302)
			(layers "F.Cu" "F.Mask" "F.Paste")
			(net "P5E_CPU1_P3_RX_BUF_DP<1>")
		)
		(pad "EN35" smd oval
			(at -8.150098 3.940048)
			(size 0.254 0.3302)
			(layers "F.Cu" "F.Mask" "F.Paste")
			(net "P5E_CPU1_P3_TX_C_DN<1>")
		)
		(pad "EP4" smd circle
			(at -8.397494 -2.817368)
			(size 0.381 0.381)
			(layers "F.Cu" "F.Mask" "F.Paste")
			(net "GND")
		)
		(pad "EP13" smd circle
			(at -8.397494 -0.79629)
			(size 0.3048 0.3048)
			(layers "F.Cu" "F.Mask" "F.Paste")
			(net "GND")
		)
		(pad "EP17" smd circle
			(at -8.397494 -0.296164)
			(size 0.3048 0.3048)
			(layers "F.Cu" "F.Mask" "F.Paste")
			(net "P0V9_CPU1_RT3_2A")
		)
		(pad "EP20" smd circle
			(at -8.397494 0.203708)
			(size 0.3048 0.3048)
			(layers "F.Cu" "F.Mask" "F.Paste")
			(net "P0V9_CPU1_RT3_2A")
		)
		(pad "EP22" smd circle
			(at -8.397494 0.703834)
			(size 0.3048 0.3048)
			(layers "F.Cu" "F.Mask" "F.Paste")
			(net "GND")
		)
		(pad "EP32" smd circle
			(at -8.397494 2.724912)
			(size 0.381 0.381)
			(layers "F.Cu" "F.Mask" "F.Paste")
			(net "GND")
		)
		(pad "ER2" smd circle
			(at -8.450072 -3.41884)
			(size 0.3048 0.3048)
			(layers "F.Cu" "F.Mask" "F.Paste")
			(net "GND")
		)
		(pad "ER34" smd circle
			(at -8.450072 3.420364)
			(size 0.3048 0.3048)
			(layers "F.Cu" "F.Mask" "F.Paste")
			(net "GND")
		)
		(pad "ET1" smd oval
			(at -8.750046 -3.938524)
			(size 0.254 0.3302)
			(layers "F.Cu" "F.Mask" "F.Paste")
			(net "GND")
		)
		(pad "ET35" smd oval
			(at -8.750046 3.940048)
			(size 0.254 0.3302)
			(layers "F.Cu" "F.Mask" "F.Paste")
			(net "GND")
		)
		(pad "EU7" smd circle
			(at -8.79729 -2.12471)
			(size 0.381 0.381)
			(layers "F.Cu" "F.Mask" "F.Paste")
			(net "P5E_CPU1_P3_TX_BUF_DP<0>")
		)
		(pad "EU26" smd circle
			(at -8.79729 1.339342)
			(size 0.381 0.381)
			(layers "F.Cu" "F.Mask" "F.Paste")
			(net "P5E_CPU1_P3_RX_DP<0>")
		)
		(pad "EV2" smd circle
			(at -9.05002 -3.41884)
			(size 0.3048 0.3048)
			(layers "F.Cu" "F.Mask" "F.Paste")
			(net "P5E_CPU1_P3_RX_BUF_DN<0>")
		)
		(pad "EV34" smd circle
			(at -9.05002 3.420364)
			(size 0.3048 0.3048)
			(layers "F.Cu" "F.Mask" "F.Paste")
			(net "P5E_CPU1_P3_TX_C_DN<0>")
		)
		(pad "EW10" smd circle
			(at -9.19734 -1.431798)
			(size 0.381 0.381)
			(layers "F.Cu" "F.Mask" "F.Paste")
			(net "P5E_CPU1_P3_TX_BUF_DN<0>")
		)
		(pad "EW29" smd circle
			(at -9.19734 2.032254)
			(size 0.381 0.381)
			(layers "F.Cu" "F.Mask" "F.Paste")
			(net "P5E_CPU1_P3_RX_DN<0>")
		)
		(pad "EY1" smd oval
			(at -9.349994 -3.938524)
			(size 0.254 0.3302)
			(layers "F.Cu" "F.Mask" "F.Paste")
			(net "P5E_CPU1_P3_RX_BUF_DP<0>")
		)
		(pad "EY35" smd oval
			(at -9.349994 3.940048)
			(size 0.254 0.3302)
			(layers "F.Cu" "F.Mask" "F.Paste")
			(net "P5E_CPU1_P3_TX_C_DP<0>")
		)
		(pad "F2" smd circle
			(at 10.150094 -3.41884)
			(size 0.3048 0.3048)
			(layers "F.Cu" "F.Mask" "F.Paste")
			(net "RST_RT_CPU1_P3_PERST_N")
		)
		(pad "F34" smd circle
			(at 10.150094 3.420364)
			(size 0.3048 0.3048)
			(layers "F.Cu" "F.Mask" "F.Paste")
			(net "RT_CPU1_P3_ADDR1")
		)
		(pad "FA15" smd circle
			(at -9.59739 -0.738886)
			(size 0.381 0.381)
			(layers "F.Cu" "F.Mask" "F.Paste")
			(net "GND")
		)
		(pad "FA32" smd circle
			(at -9.59739 2.724912)
			(size 0.381 0.381)
			(layers "F.Cu" "F.Mask" "F.Paste")
			(net "GND")
		)
		(pad "FB2" smd circle
			(at -9.649968 -3.41884)
			(size 0.3048 0.3048)
			(layers "F.Cu" "F.Mask" "F.Paste")
			(net "GND")
		)
		(pad "FB34" smd circle
			(at -9.649968 3.420364)
			(size 0.3048 0.3048)
			(layers "F.Cu" "F.Mask" "F.Paste")
			(net "GND")
		)
		(pad "FC3" smd circle
			(at -9.846818 -2.888488)
			(size 0.3048 0.3048)
			(layers "F.Cu" "F.Mask" "F.Paste")
			(net "GND")
		)
		(pad "FC6" smd circle
			(at -9.846818 -2.288286)
			(size 0.3048 0.3048)
			(layers "F.Cu" "F.Mask" "F.Paste")
			(net "GND")
		)
		(pad "FC9" smd circle
			(at -9.846818 -1.688338)
			(size 0.3048 0.3048)
			(layers "F.Cu" "F.Mask" "F.Paste")
			(net "GND")
		)
		(pad "FC19" smd circle
			(at -9.846818 0.111506)
			(size 0.3048 0.3048)
			(layers "F.Cu" "F.Mask" "F.Paste")
			(net "GND")
		)
		(pad "FC23" smd circle
			(at -9.846818 0.711708)
			(size 0.3048 0.3048)
			(layers "F.Cu" "F.Mask" "F.Paste")
			(net "GND")
		)
		(pad "FC25" smd circle
			(at -9.846818 1.311656)
			(size 0.3048 0.3048)
			(layers "F.Cu" "F.Mask" "F.Paste")
			(net "GND")
		)
		(pad "FC28" smd circle
			(at -9.846818 1.911604)
			(size 0.3048 0.3048)
			(layers "F.Cu" "F.Mask" "F.Paste")
			(net "GND")
		)
		(pad "FD1" smd oval
			(at -9.949942 -3.938524)
			(size 0.254 0.3302)
			(layers "F.Cu" "F.Mask" "F.Paste")
			(net "GND")
		)
		(pad "FD35" smd oval
			(at -9.949942 3.940048)
			(size 0.254 0.3302)
			(layers "F.Cu" "F.Mask" "F.Paste")
			(net "GND")
		)
		(pad "FE2" smd circle
			(at -10.249916 -3.41884)
			(size 0.3048 0.3048)
			(layers "F.Cu" "F.Mask" "F.Paste")
			(net "NCF_CPU1_P3_GND")
		)
		(pad "FE34" smd circle
			(at -10.249916 3.420364)
			(size 0.3048 0.3048)
			(layers "F.Cu" "F.Mask" "F.Paste")
			(net "NCF_CPU1_P3_GND")
		)
		(pad "FF5" smd circle
			(at -10.366248 -2.588514)
			(size 0.3048 0.3048)
			(layers "F.Cu" "F.Mask" "F.Paste")
			(net "SMB_RT_CPU1_P3_ROM_MUX_1D_R_SCL")
		)
		(pad "FF8" smd circle
			(at -10.366248 -1.988312)
			(size 0.3048 0.3048)
			(layers "F.Cu" "F.Mask" "F.Paste")
			(net "JTAG_TEST_MODE_RT_CPU1_P3")
		)
		(pad "FF11" smd circle
			(at -10.366248 -1.388364)
			(size 0.3048 0.3048)
			(layers "F.Cu" "F.Mask" "F.Paste")
			(net "RST_RT_CPU1_P3_RESET_N")
		)
		(pad "FF14" smd circle
			(at -10.366248 -0.788416)
			(size 0.3048 0.3048)
			(layers "F.Cu" "F.Mask" "F.Paste")
			(net "GND")
		)
		(pad "FF18" smd circle
			(at -10.366248 -0.188468)
			(size 0.3048 0.3048)
			(layers "F.Cu" "F.Mask" "F.Paste")
			(net "CLK_100M_RETIMER_CPU1_P3_DN")
		)
		(pad "FF21" smd circle
			(at -10.366248 0.41148)
			(size 0.3048 0.3048)
			(layers "F.Cu" "F.Mask" "F.Paste")
			(net "GND")
		)
		(pad "FF24" smd circle
			(at -10.366248 1.011682)
			(size 0.3048 0.3048)
			(layers "F.Cu" "F.Mask" "F.Paste")
			(net "TEST0_RT_CPU1_P3")
		)
		(pad "FF27" smd circle
			(at -10.366248 1.61163)
			(size 0.3048 0.3048)
			(layers "F.Cu" "F.Mask" "F.Paste")
			(net "TEST1_RT_CPU1_P3")
		)
		(pad "FF30" smd circle
			(at -10.366248 2.211578)
			(size 0.3048 0.3048)
			(layers "F.Cu" "F.Mask" "F.Paste")
			(net "TEST2_RT_CPU1_P3")
		)
		(pad "FF33" smd circle
			(at -10.366248 2.811526)
			(size 0.3048 0.3048)
			(layers "F.Cu" "F.Mask" "F.Paste")
			(net "RT_CPU1_P3_SCAN_MODE")
		)
		(pad "FG1" smd oval
			(at -10.54989 -3.938524)
			(size 0.254 0.3302)
			(layers "F.Cu" "F.Mask" "F.Paste")
			(net "NCF_CPU1_P3_GND")
		)
		(pad "FG35" smd oval
			(at -10.54989 3.940048)
			(size 0.254 0.3302)
			(layers "F.Cu" "F.Mask" "F.Paste")
			(net "NCF_CPU1_P3_GND")
		)
		(pad "FH2" smd circle
			(at -10.850118 -3.41884)
			(size 0.3048 0.3048)
			(layers "F.Cu" "F.Mask" "F.Paste")
			(net "NCF_CPU1_P3_GND")
		)
		(pad "FH34" smd circle
			(at -10.850118 3.420364)
			(size 0.3048 0.3048)
			(layers "F.Cu" "F.Mask" "F.Paste")
			(net "NCF_CPU1_P3_GND")
		)
		(pad "FJ3" smd oval
			(at -10.885932 -2.888488 90)
			(size 0.254 0.3302)
			(layers "F.Cu" "F.Mask" "F.Paste")
			(net "SMB_RT_CPU1_P3_ROM_MUX_1D_R_SDA")
		)
		(pad "FJ6" smd oval
			(at -10.885932 -2.288286 90)
			(size 0.254 0.3302)
			(layers "F.Cu" "F.Mask" "F.Paste")
			(net "Net_2226")
		)
		(pad "FJ9" smd oval
			(at -10.885932 -1.688338 90)
			(size 0.254 0.3302)
			(layers "F.Cu" "F.Mask" "F.Paste")
			(net "MODE_RT_CPU1_P3")
		)
		(pad "FJ12" smd oval
			(at -10.885932 -1.08839 90)
			(size 0.254 0.3302)
			(layers "F.Cu" "F.Mask" "F.Paste")
			(net "GND")
		)
		(pad "FJ16" smd oval
			(at -10.885932 -0.488442 90)
			(size 0.254 0.3302)
			(layers "F.Cu" "F.Mask" "F.Paste")
			(net "CLK_100M_RETIMER_CPU1_P3_DP")
		)
		(pad "FJ19" smd oval
			(at -10.885932 0.111506 90)
			(size 0.254 0.3302)
			(layers "F.Cu" "F.Mask" "F.Paste")
			(net "GND")
		)
		(pad "FJ23" smd oval
			(at -10.885932 0.711708 90)
			(size 0.254 0.3302)
			(layers "F.Cu" "F.Mask" "F.Paste")
			(net "Net_2227")
		)
		(pad "FJ25" smd oval
			(at -10.885932 1.311656 90)
			(size 0.254 0.3302)
			(layers "F.Cu" "F.Mask" "F.Paste")
			(net "GPIO2_RT_CPU1_P3")
		)
		(pad "FJ28" smd oval
			(at -10.885932 1.911604 90)
			(size 0.254 0.3302)
			(layers "F.Cu" "F.Mask" "F.Paste")
			(net "GPIO3_RT_CPU1_P3")
		)
		(pad "FJ31" smd oval
			(at -10.885932 2.511552 90)
			(size 0.254 0.3302)
			(layers "F.Cu" "F.Mask" "F.Paste")
			(net "Net_57")
		)
		(pad "G1" smd oval
			(at 9.85012 -3.938524)
			(size 0.254 0.3302)
			(layers "F.Cu" "F.Mask" "F.Paste")
			(net "RT_CPU1_P3_VQPS")
		)
		(pad "G35" smd oval
			(at 9.85012 3.940048)
			(size 0.254 0.3302)
			(layers "F.Cu" "F.Mask" "F.Paste")
			(net "CLKREQ_RT_CPU1_P3_N")
		)
		(pad "H12" smd circle
			(at 9.846818 -1.08839)
			(size 0.3048 0.3048)
			(layers "F.Cu" "F.Mask" "F.Paste")
			(net "GND")
		)
		(pad "H16" smd circle
			(at 9.846818 -0.488442)
			(size 0.3048 0.3048)
			(layers "F.Cu" "F.Mask" "F.Paste")
			(net "GND")
		)
		(pad "H19" smd circle
			(at 9.846818 0.111506)
			(size 0.3048 0.3048)
			(layers "F.Cu" "F.Mask" "F.Paste")
			(net "GND")
		)
		(pad "H31" smd circle
			(at 9.846818 2.511552)
			(size 0.3048 0.3048)
			(layers "F.Cu" "F.Mask" "F.Paste")
			(net "GND")
		)
		(pad "J4" smd circle
			(at 9.602724 -2.817368)
			(size 0.381 0.381)
			(layers "F.Cu" "F.Mask" "F.Paste")
			(net "GND")
		)
		(pad "J22" smd circle
			(at 9.602724 0.703834)
			(size 0.3048 0.3048)
			(layers "F.Cu" "F.Mask" "F.Paste")
			(net "GND")
		)
		(pad "K2" smd circle
			(at 9.549892 -3.41884)
			(size 0.3048 0.3048)
			(layers "F.Cu" "F.Mask" "F.Paste")
			(net "GND")
		)
		(pad "K34" smd circle
			(at 9.549892 3.420364)
			(size 0.3048 0.3048)
			(layers "F.Cu" "F.Mask" "F.Paste")
			(net "GND")
		)
		(pad "L1" smd oval
			(at 9.249918 -3.938524)
			(size 0.254 0.3302)
			(layers "F.Cu" "F.Mask" "F.Paste")
			(net "GND")
		)
		(pad "L35" smd oval
			(at 9.249918 3.940048)
			(size 0.254 0.3302)
			(layers "F.Cu" "F.Mask" "F.Paste")
			(net "GND")
		)
		(pad "M7" smd circle
			(at 9.202674 -2.12471)
			(size 0.381 0.381)
			(layers "F.Cu" "F.Mask" "F.Paste")
			(net "P5E_CPU1_P3_TX_BUF_DP<15>")
		)
		(pad "M26" smd circle
			(at 9.202674 1.339342)
			(size 0.381 0.381)
			(layers "F.Cu" "F.Mask" "F.Paste")
			(net "P5E_CPU1_P3_RX_DP<15>")
		)
		(pad "N2" smd circle
			(at 8.949944 -3.41884)
			(size 0.3048 0.3048)
			(layers "F.Cu" "F.Mask" "F.Paste")
			(net "P5E_CPU1_P3_RX_BUF_DN<15>")
		)
		(pad "N34" smd circle
			(at 8.949944 3.420364)
			(size 0.3048 0.3048)
			(layers "F.Cu" "F.Mask" "F.Paste")
			(net "P5E_CPU1_P3_TX_C_DN<15>")
		)
		(pad "P10" smd circle
			(at 8.802624 -1.431798)
			(size 0.381 0.381)
			(layers "F.Cu" "F.Mask" "F.Paste")
			(net "P5E_CPU1_P3_TX_BUF_DN<15>")
		)
		(pad "P29" smd circle
			(at 8.802624 2.032254)
			(size 0.381 0.381)
			(layers "F.Cu" "F.Mask" "F.Paste")
			(net "P5E_CPU1_P3_RX_DN<15>")
		)
		(pad "R1" smd oval
			(at 8.64997 -3.938524)
			(size 0.254 0.3302)
			(layers "F.Cu" "F.Mask" "F.Paste")
			(net "P5E_CPU1_P3_RX_BUF_DP<15>")
		)
		(pad "R35" smd oval
			(at 8.64997 3.940048)
			(size 0.254 0.3302)
			(layers "F.Cu" "F.Mask" "F.Paste")
			(net "P5E_CPU1_P3_TX_C_DP<15>")
		)
		(pad "T4" smd circle
			(at 8.402574 -2.817368)
			(size 0.381 0.381)
			(layers "F.Cu" "F.Mask" "F.Paste")
			(net "GND")
		)
		(pad "T13" smd circle
			(at 8.402574 -0.79629)
			(size 0.3048 0.3048)
			(layers "F.Cu" "F.Mask" "F.Paste")
			(net "GND")
		)
		(pad "T17" smd circle
			(at 8.402574 -0.296164)
			(size 0.3048 0.3048)
			(layers "F.Cu" "F.Mask" "F.Paste")
			(net "P0V9_CPU1_RT3_2A")
		)
		(pad "T20" smd circle
			(at 8.402574 0.203708)
			(size 0.3048 0.3048)
			(layers "F.Cu" "F.Mask" "F.Paste")
			(net "P0V9_CPU1_RT3_2A")
		)
		(pad "T22" smd circle
			(at 8.402574 0.703834)
			(size 0.3048 0.3048)
			(layers "F.Cu" "F.Mask" "F.Paste")
			(net "GND")
		)
		(pad "T32" smd circle
			(at 8.402574 2.724912)
			(size 0.381 0.381)
			(layers "F.Cu" "F.Mask" "F.Paste")
			(net "GND")
		)
		(pad "U2" smd circle
			(at 8.349996 -3.41884)
			(size 0.3048 0.3048)
			(layers "F.Cu" "F.Mask" "F.Paste")
			(net "GND")
		)
		(pad "U34" smd circle
			(at 8.349996 3.420364)
			(size 0.3048 0.3048)
			(layers "F.Cu" "F.Mask" "F.Paste")
			(net "GND")
		)
		(pad "V1" smd oval
			(at 8.050022 -3.938524)
			(size 0.254 0.3302)
			(layers "F.Cu" "F.Mask" "F.Paste")
			(net "GND")
		)
		(pad "V35" smd oval
			(at 8.050022 3.940048)
			(size 0.254 0.3302)
			(layers "F.Cu" "F.Mask" "F.Paste")
			(net "GND")
		)
		(pad "W7" smd circle
			(at 8.002524 -2.12471)
			(size 0.381 0.381)
			(layers "F.Cu" "F.Mask" "F.Paste")
			(net "P5E_CPU1_P3_TX_BUF_DP<14>")
		)
		(pad "W26" smd circle
			(at 8.002524 1.339342)
			(size 0.381 0.381)
			(layers "F.Cu" "F.Mask" "F.Paste")
			(net "P5E_CPU1_P3_RX_DP<14>")
		)
		(pad "Y2" smd circle
			(at 7.750048 -3.41884)
			(size 0.3048 0.3048)
			(layers "F.Cu" "F.Mask" "F.Paste")
			(net "P5E_CPU1_P3_RX_BUF_DN<14>")
		)
		(pad "Y34" smd circle
			(at 7.750048 3.420364)
			(size 0.3048 0.3048)
			(layers "F.Cu" "F.Mask" "F.Paste")
			(net "P5E_CPU1_P3_TX_C_DP<14>")
		)
	)
	(footprint ""
		(layer "F.Cu")
		(at 217.889582 -69.397118)
		(property "Reference" "PC2212"
			(at 0 0 0)
			(layer "F.SilkS")
			(hide yes)
			(effects
				(font
					(size 1.27 1.27)
				)
			)
		)
		(property "Value" ""
			(at 0 0 0)
			(layer "F.Fab")
			(effects
				(font
					(size 1.27 1.27)
				)
			)
		)
		(duplicate_pad_numbers_are_jumpers no)
		(fp_line
			(start -0.7874 -0.4064)
			(end 0.7874 -0.4064)
			(stroke
				(width 0.1524)
				(type default)
			)
			(layer "F.SilkS")
		)
		(fp_line
			(start -0.7874 0.4064)
			(end -0.7874 -0.4064)
			(stroke
				(width 0.1524)
				(type default)
			)
			(layer "F.SilkS")
		)
		(fp_line
			(start 0.7874 -0.4064)
			(end 0.7874 0.4064)
			(stroke
				(width 0.1524)
				(type default)
			)
			(layer "F.SilkS")
		)
		(fp_line
			(start 0.7874 0.4064)
			(end -0.7874 0.4064)
			(stroke
				(width 0.1524)
				(type default)
			)
			(layer "F.SilkS")
		)
		(fp_line
			(start -0.67945 -0.305054)
			(end -0.12065 -0.305054)
			(stroke
				(width 0.1)
				(type default)
			)
			(layer "F.Fab")
		)
		(fp_line
			(start -0.67945 0.3048)
			(end -0.67945 -0.305054)
			(stroke
				(width 0.1)
				(type default)
			)
			(layer "F.Fab")
		)
		(fp_line
			(start -0.12065 -0.305054)
			(end -0.12065 -0.2794)
			(stroke
				(width 0.1)
				(type default)
			)
			(layer "F.Fab")
		)
		(fp_line
			(start -0.12065 -0.2794)
			(end 0.12065 -0.2794)
			(stroke
				(width 0.1)
				(type default)
			)
			(layer "F.Fab")
		)
		(fp_line
			(start -0.12065 0.2794)
			(end -0.12065 0.3048)
			(stroke
				(width 0.1)
				(type default)
			)
			(layer "F.Fab")
		)
		(fp_line
			(start -0.12065 0.3048)
			(end -0.67945 0.3048)
			(stroke
				(width 0.1)
				(type default)
			)
			(layer "F.Fab")
		)
		(fp_line
			(start 0.120396 0.2794)
			(end -0.12065 0.2794)
			(stroke
				(width 0.1)
				(type default)
			)
			(layer "F.Fab")
		)
		(fp_line
			(start 0.120396 0.3048)
			(end 0.120396 0.2794)
			(stroke
				(width 0.1)
				(type default)
			)
			(layer "F.Fab")
		)
		(fp_line
			(start 0.12065 -0.3048)
			(end 0.67945 -0.3048)
			(stroke
				(width 0.1)
				(type default)
			)
			(layer "F.Fab")
		)
		(fp_line
			(start 0.12065 -0.2794)
			(end 0.12065 -0.3048)
			(stroke
				(width 0.1)
				(type default)
			)
			(layer "F.Fab")
		)
		(fp_line
			(start 0.67945 -0.3048)
			(end 0.67945 0.3048)
			(stroke
				(width 0.1)
				(type default)
			)
			(layer "F.Fab")
		)
		(fp_line
			(start 0.67945 0.3048)
			(end 0.120396 0.3048)
			(stroke
				(width 0.1)
				(type default)
			)
			(layer "F.Fab")
		)
		(pad "1" smd circle
			(at -0.40005 0)
			(size 0 0)
			(layers "F.Cu" "F.Mask" "F.Paste")
			(net "GND")
		)
		(pad "2" smd circle
			(at 0.40005 0)
			(size 0 0)
			(layers "F.Cu" "F.Mask" "F.Paste")
			(net "P3V3_E1S_REG_0")
		)
	)
	(footprint ""
		(layer "F.Cu")
		(at 259.834126 -100.016056 180)
		(property "Reference" "R1636"
			(at 0 0 180)
			(layer "F.SilkS")
			(hide yes)
			(effects
				(font
					(size 1.27 1.27)
				)
			)
		)
		(property "Value" ""
			(at 0 0 180)
			(layer "F.Fab")
			(effects
				(font
					(size 1.27 1.27)
				)
			)
		)
		(duplicate_pad_numbers_are_jumpers no)
		(fp_line
			(start 0.7874 0.4064)
			(end -0.7874 0.4064)
			(stroke
				(width 0.1524)
				(type default)
			)
			(layer "F.SilkS")
		)
		(fp_line
			(start 0.7874 -0.4064)
			(end 0.7874 0.4064)
			(stroke
				(width 0.1524)
				(type default)
			)
			(layer "F.SilkS")
		)
		(fp_line
			(start -0.7874 0.4064)
			(end -0.7874 -0.4064)
			(stroke
				(width 0.1524)
				(type default)
			)
			(layer "F.SilkS")
		)
		(fp_line
			(start -0.7874 -0.4064)
			(end 0.7874 -0.4064)
			(stroke
				(width 0.1524)
				(type default)
			)
			(layer "F.SilkS")
		)
		(fp_line
			(start 0.67945 0.3048)
			(end 0.120396 0.3048)
			(stroke
				(width 0.1)
				(type default)
			)
			(layer "F.Fab")
		)
		(fp_line
			(start 0.67945 -0.3048)
			(end 0.67945 0.3048)
			(stroke
				(width 0.1)
				(type default)
			)
			(layer "F.Fab")
		)
		(fp_line
			(start 0.12065 -0.2794)
			(end 0.12065 -0.3048)
			(stroke
				(width 0.1)
				(type default)
			)
			(layer "F.Fab")
		)
		(fp_line
			(start 0.12065 -0.3048)
			(end 0.67945 -0.3048)
			(stroke
				(width 0.1)
				(type default)
			)
			(layer "F.Fab")
		)
		(fp_line
			(start 0.120396 0.3048)
			(end 0.120396 0.2794)
			(stroke
				(width 0.1)
				(type default)
			)
			(layer "F.Fab")
		)
		(fp_line
			(start 0.120396 0.2794)
			(end -0.12065 0.2794)
			(stroke
				(width 0.1)
				(type default)
			)
			(layer "F.Fab")
		)
		(fp_line
			(start -0.12065 0.3048)
			(end -0.67945 0.3048)
			(stroke
				(width 0.1)
				(type default)
			)
			(layer "F.Fab")
		)
		(fp_line
			(start -0.12065 0.2794)
			(end -0.12065 0.3048)
			(stroke
				(width 0.1)
				(type default)
			)
			(layer "F.Fab")
		)
		(fp_line
			(start -0.12065 -0.2794)
			(end 0.12065 -0.2794)
			(stroke
				(width 0.1)
				(type default)
			)
			(layer "F.Fab")
		)
		(fp_line
			(start -0.12065 -0.305054)
			(end -0.12065 -0.2794)
			(stroke
				(width 0.1)
				(type default)
			)
			(layer "F.Fab")
		)
		(fp_line
			(start -0.67945 0.3048)
			(end -0.67945 -0.305054)
			(stroke
				(width 0.1)
				(type default)
			)
			(layer "F.Fab")
		)
		(fp_line
			(start -0.67945 -0.305054)
			(end -0.12065 -0.305054)
			(stroke
				(width 0.1)
				(type default)
			)
			(layer "F.Fab")
		)
		(pad "1" smd circle
			(at -0.40005 0 180)
			(size 0 0)
			(layers "F.Cu" "F.Mask" "F.Paste")
			(net "JTAG_DBREQ_R_N")
		)
		(pad "2" smd circle
			(at 0.40005 0 180)
			(size 0 0)
			(layers "F.Cu" "F.Mask" "F.Paste")
			(net "JTAG_DBREQ_N")
		)
	)
	(footprint ""
		(layer "F.Cu")
		(at 357.20401 -418.329618 180)
		(property "Reference" "R4155"
			(at 0 0 180)
			(layer "F.SilkS")
			(hide yes)
			(effects
				(font
					(size 1.27 1.27)
				)
			)
		)
		(property "Value" ""
			(at 0 0 180)
			(layer "F.Fab")
			(effects
				(font
					(size 1.27 1.27)
				)
			)
		)
		(duplicate_pad_numbers_are_jumpers no)
		(fp_line
			(start 0.7874 0.4064)
			(end -0.7874 0.4064)
			(stroke
				(width 0.1524)
				(type default)
			)
			(layer "F.SilkS")
		)
		(fp_line
			(start 0.7874 -0.4064)
			(end 0.7874 0.4064)
			(stroke
				(width 0.1524)
				(type default)
			)
			(layer "F.SilkS")
		)
		(fp_line
			(start -0.7874 0.4064)
			(end -0.7874 -0.4064)
			(stroke
				(width 0.1524)
				(type default)
			)
			(layer "F.SilkS")
		)
		(fp_line
			(start -0.7874 -0.4064)
			(end 0.7874 -0.4064)
			(stroke
				(width 0.1524)
				(type default)
			)
			(layer "F.SilkS")
		)
		(fp_line
			(start 0.67945 0.3048)
			(end 0.120396 0.3048)
			(stroke
				(width 0.1)
				(type default)
			)
			(layer "F.Fab")
		)
		(fp_line
			(start 0.67945 -0.3048)
			(end 0.67945 0.3048)
			(stroke
				(width 0.1)
				(type default)
			)
			(layer "F.Fab")
		)
		(fp_line
			(start 0.12065 -0.2794)
			(end 0.12065 -0.3048)
			(stroke
				(width 0.1)
				(type default)
			)
			(layer "F.Fab")
		)
		(fp_line
			(start 0.12065 -0.3048)
			(end 0.67945 -0.3048)
			(stroke
				(width 0.1)
				(type default)
			)
			(layer "F.Fab")
		)
		(fp_line
			(start 0.120396 0.3048)
			(end 0.120396 0.2794)
			(stroke
				(width 0.1)
				(type default)
			)
			(layer "F.Fab")
		)
		(fp_line
			(start 0.120396 0.2794)
			(end -0.12065 0.2794)
			(stroke
				(width 0.1)
				(type default)
			)
			(layer "F.Fab")
		)
		(fp_line
			(start -0.12065 0.3048)
			(end -0.67945 0.3048)
			(stroke
				(width 0.1)
				(type default)
			)
			(layer "F.Fab")
		)
		(fp_line
			(start -0.12065 0.2794)
			(end -0.12065 0.3048)
			(stroke
				(width 0.1)
				(type default)
			)
			(layer "F.Fab")
		)
		(fp_line
			(start -0.12065 -0.2794)
			(end 0.12065 -0.2794)
			(stroke
				(width 0.1)
				(type default)
			)
			(layer "F.Fab")
		)
		(fp_line
			(start -0.12065 -0.305054)
			(end -0.12065 -0.2794)
			(stroke
				(width 0.1)
				(type default)
			)
			(layer "F.Fab")
		)
		(fp_line
			(start -0.67945 0.3048)
			(end -0.67945 -0.305054)
			(stroke
				(width 0.1)
				(type default)
			)
			(layer "F.Fab")
		)
		(fp_line
			(start -0.67945 -0.305054)
			(end -0.12065 -0.305054)
			(stroke
				(width 0.1)
				(type default)
			)
			(layer "F.Fab")
		)
		(pad "1" smd circle
			(at -0.40005 0 180)
			(size 0 0)
			(layers "F.Cu" "F.Mask" "F.Paste")
			(net "P3V3_AUX")
		)
		(pad "2" smd circle
			(at 0.40005 0 180)
			(size 0 0)
			(layers "F.Cu" "F.Mask" "F.Paste")
			(net "PRSNT_CABLE_GPU_A1")
		)
	)
	(footprint ""
		(layer "F.Cu")
		(at 304.301398 -430.2379 180)
		(property "Reference" "R4131"
			(at 0 0 180)
			(layer "F.SilkS")
			(hide yes)
			(effects
				(font
					(size 1.27 1.27)
				)
			)
		)
		(property "Value" ""
			(at 0 0 180)
			(layer "F.Fab")
			(effects
				(font
					(size 1.27 1.27)
				)
			)
		)
		(duplicate_pad_numbers_are_jumpers no)
		(fp_line
			(start 0.7874 0.4064)
			(end -0.7874 0.4064)
			(stroke
				(width 0.1524)
				(type default)
			)
			(layer "F.SilkS")
		)
		(fp_line
			(start 0.7874 -0.4064)
			(end 0.7874 0.4064)
			(stroke
				(width 0.1524)
				(type default)
			)
			(layer "F.SilkS")
		)
		(fp_line
			(start -0.7874 0.4064)
			(end -0.7874 -0.4064)
			(stroke
				(width 0.1524)
				(type default)
			)
			(layer "F.SilkS")
		)
		(fp_line
			(start -0.7874 -0.4064)
			(end 0.7874 -0.4064)
			(stroke
				(width 0.1524)
				(type default)
			)
			(layer "F.SilkS")
		)
		(fp_line
			(start 0.67945 0.3048)
			(end 0.120396 0.3048)
			(stroke
				(width 0.1)
				(type default)
			)
			(layer "F.Fab")
		)
		(fp_line
			(start 0.67945 -0.3048)
			(end 0.67945 0.3048)
			(stroke
				(width 0.1)
				(type default)
			)
			(layer "F.Fab")
		)
		(fp_line
			(start 0.12065 -0.2794)
			(end 0.12065 -0.3048)
			(stroke
				(width 0.1)
				(type default)
			)
			(layer "F.Fab")
		)
		(fp_line
			(start 0.12065 -0.3048)
			(end 0.67945 -0.3048)
			(stroke
				(width 0.1)
				(type default)
			)
			(layer "F.Fab")
		)
		(fp_line
			(start 0.120396 0.3048)
			(end 0.120396 0.2794)
			(stroke
				(width 0.1)
				(type default)
			)
			(layer "F.Fab")
		)
		(fp_line
			(start 0.120396 0.2794)
			(end -0.12065 0.2794)
			(stroke
				(width 0.1)
				(type default)
			)
			(layer "F.Fab")
		)
		(fp_line
			(start -0.12065 0.3048)
			(end -0.67945 0.3048)
			(stroke
				(width 0.1)
				(type default)
			)
			(layer "F.Fab")
		)
		(fp_line
			(start -0.12065 0.2794)
			(end -0.12065 0.3048)
			(stroke
				(width 0.1)
				(type default)
			)
			(layer "F.Fab")
		)
		(fp_line
			(start -0.12065 -0.2794)
			(end 0.12065 -0.2794)
			(stroke
				(width 0.1)
				(type default)
			)
			(layer "F.Fab")
		)
		(fp_line
			(start -0.12065 -0.305054)
			(end -0.12065 -0.2794)
			(stroke
				(width 0.1)
				(type default)
			)
			(layer "F.Fab")
		)
		(fp_line
			(start -0.67945 0.3048)
			(end -0.67945 -0.305054)
			(stroke
				(width 0.1)
				(type default)
			)
			(layer "F.Fab")
		)
		(fp_line
			(start -0.67945 -0.305054)
			(end -0.12065 -0.305054)
			(stroke
				(width 0.1)
				(type default)
			)
			(layer "F.Fab")
		)
		(pad "1" smd circle
			(at -0.40005 0 180)
			(size 0 0)
			(layers "F.Cu" "F.Mask" "F.Paste")
			(net "P3V3_AUX")
		)
		(pad "2" smd circle
			(at 0.40005 0 180)
			(size 0 0)
			(layers "F.Cu" "F.Mask" "F.Paste")
			(net "GPU_3V3IO_RSVD3_FFU")
		)
	)
	(footprint ""
		(layer "F.Cu")
		(at 122.55627 -36.675568)
		(property "Reference" "C6025"
			(at 0 0 0)
			(layer "F.SilkS")
			(hide yes)
			(effects
				(font
					(size 1.27 1.27)
				)
			)
		)
		(property "Value" ""
			(at 0 0 0)
			(layer "F.Fab")
			(effects
				(font
					(size 1.27 1.27)
				)
			)
		)
		(duplicate_pad_numbers_are_jumpers no)
		(fp_line
			(start -0.7874 -0.4064)
			(end 0.7874 -0.4064)
			(stroke
				(width 0.1524)
				(type default)
			)
			(layer "F.SilkS")
		)
		(fp_line
			(start -0.7874 0.4064)
			(end -0.7874 -0.4064)
			(stroke
				(width 0.1524)
				(type default)
			)
			(layer "F.SilkS")
		)
		(fp_line
			(start 0.7874 -0.4064)
			(end 0.7874 0.4064)
			(stroke
				(width 0.1524)
				(type default)
			)
			(layer "F.SilkS")
		)
		(fp_line
			(start 0.7874 0.4064)
			(end -0.7874 0.4064)
			(stroke
				(width 0.1524)
				(type default)
			)
			(layer "F.SilkS")
		)
		(fp_line
			(start -0.6858 -0.3048)
			(end -0.1016 -0.3048)
			(stroke
				(width 0.1)
				(type default)
			)
			(layer "F.Fab")
		)
		(fp_line
			(start -0.6858 0.3048)
			(end -0.6858 -0.3048)
			(stroke
				(width 0.1)
				(type default)
			)
			(layer "F.Fab")
		)
		(fp_line
			(start -0.1016 -0.3048)
			(end -0.1016 -0.2794)
			(stroke
				(width 0.1)
				(type default)
			)
			(layer "F.Fab")
		)
		(fp_line
			(start -0.1016 -0.2794)
			(end 0.1016 -0.2794)
			(stroke
				(width 0.1)
				(type default)
			)
			(layer "F.Fab")
		)
		(fp_line
			(start -0.1016 0.2794)
			(end -0.1016 0.3048)
			(stroke
				(width 0.1)
				(type default)
			)
			(layer "F.Fab")
		)
		(fp_line
			(start -0.1016 0.3048)
			(end -0.6858 0.3048)
			(stroke
				(width 0.1)
				(type default)
			)
			(layer "F.Fab")
		)
		(fp_line
			(start 0.1016 -0.3048)
			(end 0.6858 -0.3048)
			(stroke
				(width 0.1)
				(type default)
			)
			(layer "F.Fab")
		)
		(fp_line
			(start 0.1016 -0.2794)
			(end 0.1016 -0.3048)
			(stroke
				(width 0.1)
				(type default)
			)
			(layer "F.Fab")
		)
		(fp_line
			(start 0.1016 0.2794)
			(end -0.1016 0.2794)
			(stroke
				(width 0.1)
				(type default)
			)
			(layer "F.Fab")
		)
		(fp_line
			(start 0.1016 0.3048)
			(end 0.1016 0.2794)
			(stroke
				(width 0.1)
				(type default)
			)
			(layer "F.Fab")
		)
		(fp_line
			(start 0.6858 -0.3048)
			(end 0.6858 0.3048)
			(stroke
				(width 0.1)
				(type default)
			)
			(layer "F.Fab")
		)
		(fp_line
			(start 0.6858 0.3048)
			(end 0.1016 0.3048)
			(stroke
				(width 0.1)
				(type default)
			)
			(layer "F.Fab")
		)
		(pad "1" smd rect
			(at -0.40005 0 180)
			(size 0.4572 0.508)
			(layers "F.Cu" "F.Mask" "F.Paste")
			(net "USB3_CPU0_BMC_HUB2_TX_DP")
		)
		(pad "2" smd rect
			(at 0.40005 0 180)
			(size 0.4572 0.508)
			(layers "F.Cu" "F.Mask" "F.Paste")
			(net "USB3_CPU0_BMC_TX_BUF_C_DP")
		)
	)
	(footprint ""
		(layer "F.Cu")
		(at 199.941942 -344.270584 180)
		(property "Reference" "PC120"
			(at 0 0 180)
			(layer "F.SilkS")
			(hide yes)
			(effects
				(font
					(size 1.27 1.27)
				)
			)
		)
		(property "Value" ""
			(at 0 0 180)
			(layer "F.Fab")
			(effects
				(font
					(size 1.27 1.27)
				)
			)
		)
		(duplicate_pad_numbers_are_jumpers no)
		(fp_line
			(start 1.524 0.762)
			(end -1.524 0.762)
			(stroke
				(width 0.1524)
				(type default)
			)
			(layer "F.SilkS")
		)
		(fp_line
			(start 1.524 -0.762)
			(end 1.524 0.762)
			(stroke
				(width 0.1524)
				(type default)
			)
			(layer "F.SilkS")
		)
		(fp_line
			(start -1.524 0.762)
			(end -1.524 -0.762)
			(stroke
				(width 0.1524)
				(type default)
			)
			(layer "F.SilkS")
		)
		(fp_line
			(start -1.524 -0.762)
			(end 1.524 -0.762)
			(stroke
				(width 0.1524)
				(type default)
			)
			(layer "F.SilkS")
		)
		(fp_line
			(start 1.1049 0.724916)
			(end 1.1049 -0.724916)
			(stroke
				(width 0.1)
				(type default)
			)
			(layer "F.Fab")
		)
		(fp_line
			(start 1.1049 -0.724916)
			(end -1.1049 -0.724916)
			(stroke
				(width 0.1)
				(type default)
			)
			(layer "F.Fab")
		)
		(fp_line
			(start -1.1049 0.724916)
			(end 1.1049 0.724916)
			(stroke
				(width 0.1)
				(type default)
			)
			(layer "F.Fab")
		)
		(fp_line
			(start -1.1049 -0.724916)
			(end -1.1049 0.724916)
			(stroke
				(width 0.1)
				(type default)
			)
			(layer "F.Fab")
		)
		(pad "1" smd rect
			(at -0.889 0)
			(size 1.016 1.27)
			(layers "F.Cu" "F.Mask" "F.Paste")
			(net "SW_P12V_AUX_PVDD_33_S5_FLT")
		)
		(pad "2" smd rect
			(at 0.889 0)
			(size 1.016 1.27)
			(layers "F.Cu" "F.Mask" "F.Paste")
			(net "GND")
		)
	)
	(footprint ""
		(layer "F.Cu")
		(at 176.911 -129.377948 90)
		(property "Reference" "R192"
			(at 0 0 90)
			(layer "F.SilkS")
			(hide yes)
			(effects
				(font
					(size 1.27 1.27)
				)
			)
		)
		(property "Value" ""
			(at 0 0 90)
			(layer "F.Fab")
			(effects
				(font
					(size 1.27 1.27)
				)
			)
		)
		(duplicate_pad_numbers_are_jumpers no)
		(fp_line
			(start 0.7874 -0.4064)
			(end 0.7874 0.4064)
			(stroke
				(width 0.1524)
				(type default)
			)
			(layer "F.SilkS")
		)
		(fp_line
			(start -0.7874 -0.4064)
			(end 0.7874 -0.4064)
			(stroke
				(width 0.1524)
				(type default)
			)
			(layer "F.SilkS")
		)
		(fp_line
			(start 0.7874 0.4064)
			(end -0.7874 0.4064)
			(stroke
				(width 0.1524)
				(type default)
			)
			(layer "F.SilkS")
		)
		(fp_line
			(start -0.7874 0.4064)
			(end -0.7874 -0.4064)
			(stroke
				(width 0.1524)
				(type default)
			)
			(layer "F.SilkS")
		)
		(fp_line
			(start -0.12065 -0.305054)
			(end -0.12065 -0.2794)
			(stroke
				(width 0.1)
				(type default)
			)
			(layer "F.Fab")
		)
		(fp_line
			(start -0.67945 -0.305054)
			(end -0.12065 -0.305054)
			(stroke
				(width 0.1)
				(type default)
			)
			(layer "F.Fab")
		)
		(fp_line
			(start 0.67945 -0.3048)
			(end 0.67945 0.3048)
			(stroke
				(width 0.1)
				(type default)
			)
			(layer "F.Fab")
		)
		(fp_line
			(start 0.12065 -0.3048)
			(end 0.67945 -0.3048)
			(stroke
				(width 0.1)
				(type default)
			)
			(layer "F.Fab")
		)
		(fp_line
			(start 0.12065 -0.2794)
			(end 0.12065 -0.3048)
			(stroke
				(width 0.1)
				(type default)
			)
			(layer "F.Fab")
		)
		(fp_line
			(start -0.12065 -0.2794)
			(end 0.12065 -0.2794)
			(stroke
				(width 0.1)
				(type default)
			)
			(layer "F.Fab")
		)
		(fp_line
			(start 0.120396 0.2794)
			(end -0.12065 0.2794)
			(stroke
				(width 0.1)
				(type default)
			)
			(layer "F.Fab")
		)
		(fp_line
			(start -0.12065 0.2794)
			(end -0.12065 0.3048)
			(stroke
				(width 0.1)
				(type default)
			)
			(layer "F.Fab")
		)
		(fp_line
			(start 0.67945 0.3048)
			(end 0.120396 0.3048)
			(stroke
				(width 0.1)
				(type default)
			)
			(layer "F.Fab")
		)
		(fp_line
			(start 0.120396 0.3048)
			(end 0.120396 0.2794)
			(stroke
				(width 0.1)
				(type default)
			)
			(layer "F.Fab")
		)
		(fp_line
			(start -0.12065 0.3048)
			(end -0.67945 0.3048)
			(stroke
				(width 0.1)
				(type default)
			)
			(layer "F.Fab")
		)
		(fp_line
			(start -0.67945 0.3048)
			(end -0.67945 -0.305054)
			(stroke
				(width 0.1)
				(type default)
			)
			(layer "F.Fab")
		)
		(pad "1" smd circle
			(at -0.40005 0 90)
			(size 0 0)
			(layers "F.Cu" "F.Mask" "F.Paste")
			(net "FM_CPU1_SLP_S3_N")
		)
		(pad "2" smd circle
			(at 0.40005 0 90)
			(size 0 0)
			(layers "F.Cu" "F.Mask" "F.Paste")
			(net "CPU1_SLP_S3_N")
		)
	)
	(footprint ""
		(layer "F.Cu")
		(at 324.853046 -99.284536 180)
		(property "Reference" "R1272"
			(at 0 0 180)
			(layer "F.SilkS")
			(hide yes)
			(effects
				(font
					(size 1.27 1.27)
				)
			)
		)
		(property "Value" ""
			(at 0 0 180)
			(layer "F.Fab")
			(effects
				(font
					(size 1.27 1.27)
				)
			)
		)
		(duplicate_pad_numbers_are_jumpers no)
		(fp_line
			(start 0.7874 0.4064)
			(end -0.7874 0.4064)
			(stroke
				(width 0.1524)
				(type default)
			)
			(layer "F.SilkS")
		)
		(fp_line
			(start 0.7874 -0.4064)
			(end 0.7874 0.4064)
			(stroke
				(width 0.1524)
				(type default)
			)
			(layer "F.SilkS")
		)
		(fp_line
			(start -0.7874 0.4064)
			(end -0.7874 -0.4064)
			(stroke
				(width 0.1524)
				(type default)
			)
			(layer "F.SilkS")
		)
		(fp_line
			(start -0.7874 -0.4064)
			(end 0.7874 -0.4064)
			(stroke
				(width 0.1524)
				(type default)
			)
			(layer "F.SilkS")
		)
		(fp_line
			(start 0.67945 0.3048)
			(end 0.120396 0.3048)
			(stroke
				(width 0.1)
				(type default)
			)
			(layer "F.Fab")
		)
		(fp_line
			(start 0.67945 -0.3048)
			(end 0.67945 0.3048)
			(stroke
				(width 0.1)
				(type default)
			)
			(layer "F.Fab")
		)
		(fp_line
			(start 0.12065 -0.2794)
			(end 0.12065 -0.3048)
			(stroke
				(width 0.1)
				(type default)
			)
			(layer "F.Fab")
		)
		(fp_line
			(start 0.12065 -0.3048)
			(end 0.67945 -0.3048)
			(stroke
				(width 0.1)
				(type default)
			)
			(layer "F.Fab")
		)
		(fp_line
			(start 0.120396 0.3048)
			(end 0.120396 0.2794)
			(stroke
				(width 0.1)
				(type default)
			)
			(layer "F.Fab")
		)
		(fp_line
			(start 0.120396 0.2794)
			(end -0.12065 0.2794)
			(stroke
				(width 0.1)
				(type default)
			)
			(layer "F.Fab")
		)
		(fp_line
			(start -0.12065 0.3048)
			(end -0.67945 0.3048)
			(stroke
				(width 0.1)
				(type default)
			)
			(layer "F.Fab")
		)
		(fp_line
			(start -0.12065 0.2794)
			(end -0.12065 0.3048)
			(stroke
				(width 0.1)
				(type default)
			)
			(layer "F.Fab")
		)
		(fp_line
			(start -0.12065 -0.2794)
			(end 0.12065 -0.2794)
			(stroke
				(width 0.1)
				(type default)
			)
			(layer "F.Fab")
		)
		(fp_line
			(start -0.12065 -0.305054)
			(end -0.12065 -0.2794)
			(stroke
				(width 0.1)
				(type default)
			)
			(layer "F.Fab")
		)
		(fp_line
			(start -0.67945 0.3048)
			(end -0.67945 -0.305054)
			(stroke
				(width 0.1)
				(type default)
			)
			(layer "F.Fab")
		)
		(fp_line
			(start -0.67945 -0.305054)
			(end -0.12065 -0.305054)
			(stroke
				(width 0.1)
				(type default)
			)
			(layer "F.Fab")
		)
		(pad "1" smd circle
			(at -0.40005 0 180)
			(size 0 0)
			(layers "F.Cu" "F.Mask" "F.Paste")
			(net "SMB_INA230_8_3V3AUX_SCL_R")
		)
		(pad "2" smd circle
			(at 0.40005 0 180)
			(size 0 0)
			(layers "F.Cu" "F.Mask" "F.Paste")
			(net "SMB_INA230_8_3V3AUX_SCL_R1")
		)
	)
	(footprint ""
		(layer "F.Cu")
		(at 138.617198 -168.577006)
		(property "Reference" "PR163"
			(at 0 0 0)
			(layer "F.SilkS")
			(hide yes)
			(effects
				(font
					(size 1.27 1.27)
				)
			)
		)
		(property "Value" ""
			(at 0 0 0)
			(layer "F.Fab")
			(effects
				(font
					(size 1.27 1.27)
				)
			)
		)
		(duplicate_pad_numbers_are_jumpers no)
		(fp_line
			(start -0.7874 -0.4064)
			(end 0.7874 -0.4064)
			(stroke
				(width 0.1524)
				(type default)
			)
			(layer "F.SilkS")
		)
		(fp_line
			(start -0.7874 0.4064)
			(end -0.7874 -0.4064)
			(stroke
				(width 0.1524)
				(type default)
			)
			(layer "F.SilkS")
		)
		(fp_line
			(start 0.7874 -0.4064)
			(end 0.7874 0.4064)
			(stroke
				(width 0.1524)
				(type default)
			)
			(layer "F.SilkS")
		)
		(fp_line
			(start 0.7874 0.4064)
			(end -0.7874 0.4064)
			(stroke
				(width 0.1524)
				(type default)
			)
			(layer "F.SilkS")
		)
		(fp_line
			(start -0.67945 -0.305054)
			(end -0.12065 -0.305054)
			(stroke
				(width 0.1)
				(type default)
			)
			(layer "F.Fab")
		)
		(fp_line
			(start -0.67945 0.3048)
			(end -0.67945 -0.305054)
			(stroke
				(width 0.1)
				(type default)
			)
			(layer "F.Fab")
		)
		(fp_line
			(start -0.12065 -0.305054)
			(end -0.12065 -0.2794)
			(stroke
				(width 0.1)
				(type default)
			)
			(layer "F.Fab")
		)
		(fp_line
			(start -0.12065 -0.2794)
			(end 0.12065 -0.2794)
			(stroke
				(width 0.1)
				(type default)
			)
			(layer "F.Fab")
		)
		(fp_line
			(start -0.12065 0.2794)
			(end -0.12065 0.3048)
			(stroke
				(width 0.1)
				(type default)
			)
			(layer "F.Fab")
		)
		(fp_line
			(start -0.12065 0.3048)
			(end -0.67945 0.3048)
			(stroke
				(width 0.1)
				(type default)
			)
			(layer "F.Fab")
		)
		(fp_line
			(start 0.120396 0.2794)
			(end -0.12065 0.2794)
			(stroke
				(width 0.1)
				(type default)
			)
			(layer "F.Fab")
		)
		(fp_line
			(start 0.120396 0.3048)
			(end 0.120396 0.2794)
			(stroke
				(width 0.1)
				(type default)
			)
			(layer "F.Fab")
		)
		(fp_line
			(start 0.12065 -0.3048)
			(end 0.67945 -0.3048)
			(stroke
				(width 0.1)
				(type default)
			)
			(layer "F.Fab")
		)
		(fp_line
			(start 0.12065 -0.2794)
			(end 0.12065 -0.3048)
			(stroke
				(width 0.1)
				(type default)
			)
			(layer "F.Fab")
		)
		(fp_line
			(start 0.67945 -0.3048)
			(end 0.67945 0.3048)
			(stroke
				(width 0.1)
				(type default)
			)
			(layer "F.Fab")
		)
		(fp_line
			(start 0.67945 0.3048)
			(end 0.120396 0.3048)
			(stroke
				(width 0.1)
				(type default)
			)
			(layer "F.Fab")
		)
		(pad "1" smd circle
			(at -0.40005 0)
			(size 0 0)
			(layers "F.Cu" "F.Mask" "F.Paste")
			(net "PVDDCR_SOC_P1")
		)
		(pad "2" smd circle
			(at 0.40005 0)
			(size 0 0)
			(layers "F.Cu" "F.Mask" "F.Paste")
			(net "VSENSE_PVDDCR_SOC_P1_DP")
		)
	)
	(footprint ""
		(layer "F.Cu")
		(at 196.708268 -78.42377 180)
		(property "Reference" "R80"
			(at 0 0 180)
			(layer "F.SilkS")
			(hide yes)
			(effects
				(font
					(size 1.27 1.27)
				)
			)
		)
		(property "Value" ""
			(at 0 0 180)
			(layer "F.Fab")
			(effects
				(font
					(size 1.27 1.27)
				)
			)
		)
		(duplicate_pad_numbers_are_jumpers no)
		(fp_line
			(start 0.7874 0.4064)
			(end -0.7874 0.4064)
			(stroke
				(width 0.1524)
				(type default)
			)
			(layer "F.SilkS")
		)
		(fp_line
			(start 0.7874 -0.4064)
			(end 0.7874 0.4064)
			(stroke
				(width 0.1524)
				(type default)
			)
			(layer "F.SilkS")
		)
		(fp_line
			(start -0.7874 0.4064)
			(end -0.7874 -0.4064)
			(stroke
				(width 0.1524)
				(type default)
			)
			(layer "F.SilkS")
		)
		(fp_line
			(start -0.7874 -0.4064)
			(end 0.7874 -0.4064)
			(stroke
				(width 0.1524)
				(type default)
			)
			(layer "F.SilkS")
		)
		(fp_line
			(start 0.67945 0.3048)
			(end 0.120396 0.3048)
			(stroke
				(width 0.1)
				(type default)
			)
			(layer "F.Fab")
		)
		(fp_line
			(start 0.67945 -0.3048)
			(end 0.67945 0.3048)
			(stroke
				(width 0.1)
				(type default)
			)
			(layer "F.Fab")
		)
		(fp_line
			(start 0.12065 -0.2794)
			(end 0.12065 -0.3048)
			(stroke
				(width 0.1)
				(type default)
			)
			(layer "F.Fab")
		)
		(fp_line
			(start 0.12065 -0.3048)
			(end 0.67945 -0.3048)
			(stroke
				(width 0.1)
				(type default)
			)
			(layer "F.Fab")
		)
		(fp_line
			(start 0.120396 0.3048)
			(end 0.120396 0.2794)
			(stroke
				(width 0.1)
				(type default)
			)
			(layer "F.Fab")
		)
		(fp_line
			(start 0.120396 0.2794)
			(end -0.12065 0.2794)
			(stroke
				(width 0.1)
				(type default)
			)
			(layer "F.Fab")
		)
		(fp_line
			(start -0.12065 0.3048)
			(end -0.67945 0.3048)
			(stroke
				(width 0.1)
				(type default)
			)
			(layer "F.Fab")
		)
		(fp_line
			(start -0.12065 0.2794)
			(end -0.12065 0.3048)
			(stroke
				(width 0.1)
				(type default)
			)
			(layer "F.Fab")
		)
		(fp_line
			(start -0.12065 -0.2794)
			(end 0.12065 -0.2794)
			(stroke
				(width 0.1)
				(type default)
			)
			(layer "F.Fab")
		)
		(fp_line
			(start -0.12065 -0.305054)
			(end -0.12065 -0.2794)
			(stroke
				(width 0.1)
				(type default)
			)
			(layer "F.Fab")
		)
		(fp_line
			(start -0.67945 0.3048)
			(end -0.67945 -0.305054)
			(stroke
				(width 0.1)
				(type default)
			)
			(layer "F.Fab")
		)
		(fp_line
			(start -0.67945 -0.305054)
			(end -0.12065 -0.305054)
			(stroke
				(width 0.1)
				(type default)
			)
			(layer "F.Fab")
		)
		(pad "1" smd circle
			(at -0.40005 0 180)
			(size 0 0)
			(layers "F.Cu" "F.Mask" "F.Paste")
			(net "RMII_OCP_BMC_RXD_1")
		)
		(pad "2" smd circle
			(at 0.40005 0 180)
			(size 0 0)
			(layers "F.Cu" "F.Mask" "F.Paste")
			(net "GND")
		)
	)
	(footprint ""
		(layer "F.Cu")
		(at 302.1584 -362.839)
		(property "Reference" "R8056"
			(at 0 0 0)
			(layer "F.SilkS")
			(hide yes)
			(effects
				(font
					(size 1.27 1.27)
				)
			)
		)
		(property "Value" ""
			(at 0 0 0)
			(layer "F.Fab")
			(effects
				(font
					(size 1.27 1.27)
				)
			)
		)
		(duplicate_pad_numbers_are_jumpers no)
		(fp_line
			(start -0.7874 -0.4064)
			(end 0.7874 -0.4064)
			(stroke
				(width 0.1524)
				(type default)
			)
			(layer "F.SilkS")
		)
		(fp_line
			(start -0.7874 0.4064)
			(end -0.7874 -0.4064)
			(stroke
				(width 0.1524)
				(type default)
			)
			(layer "F.SilkS")
		)
		(fp_line
			(start 0.7874 -0.4064)
			(end 0.7874 0.4064)
			(stroke
				(width 0.1524)
				(type default)
			)
			(layer "F.SilkS")
		)
		(fp_line
			(start 0.7874 0.4064)
			(end -0.7874 0.4064)
			(stroke
				(width 0.1524)
				(type default)
			)
			(layer "F.SilkS")
		)
		(fp_line
			(start -0.67945 -0.305054)
			(end -0.12065 -0.305054)
			(stroke
				(width 0.1)
				(type default)
			)
			(layer "F.Fab")
		)
		(fp_line
			(start -0.67945 0.3048)
			(end -0.67945 -0.305054)
			(stroke
				(width 0.1)
				(type default)
			)
			(layer "F.Fab")
		)
		(fp_line
			(start -0.12065 -0.305054)
			(end -0.12065 -0.2794)
			(stroke
				(width 0.1)
				(type default)
			)
			(layer "F.Fab")
		)
		(fp_line
			(start -0.12065 -0.2794)
			(end 0.12065 -0.2794)
			(stroke
				(width 0.1)
				(type default)
			)
			(layer "F.Fab")
		)
		(fp_line
			(start -0.12065 0.2794)
			(end -0.12065 0.3048)
			(stroke
				(width 0.1)
				(type default)
			)
			(layer "F.Fab")
		)
		(fp_line
			(start -0.12065 0.3048)
			(end -0.67945 0.3048)
			(stroke
				(width 0.1)
				(type default)
			)
			(layer "F.Fab")
		)
		(fp_line
			(start 0.120396 0.2794)
			(end -0.12065 0.2794)
			(stroke
				(width 0.1)
				(type default)
			)
			(layer "F.Fab")
		)
		(fp_line
			(start 0.120396 0.3048)
			(end 0.120396 0.2794)
			(stroke
				(width 0.1)
				(type default)
			)
			(layer "F.Fab")
		)
		(fp_line
			(start 0.12065 -0.3048)
			(end 0.67945 -0.3048)
			(stroke
				(width 0.1)
				(type default)
			)
			(layer "F.Fab")
		)
		(fp_line
			(start 0.12065 -0.2794)
			(end 0.12065 -0.3048)
			(stroke
				(width 0.1)
				(type default)
			)
			(layer "F.Fab")
		)
		(fp_line
			(start 0.67945 -0.3048)
			(end 0.67945 0.3048)
			(stroke
				(width 0.1)
				(type default)
			)
			(layer "F.Fab")
		)
		(fp_line
			(start 0.67945 0.3048)
			(end 0.120396 0.3048)
			(stroke
				(width 0.1)
				(type default)
			)
			(layer "F.Fab")
		)
		(pad "1" smd circle
			(at -0.40005 0)
			(size 0 0)
			(layers "F.Cu" "F.Mask" "F.Paste")
			(net "P3V3_AUX")
		)
		(pad "2" smd circle
			(at 0.40005 0)
			(size 0 0)
			(layers "F.Cu" "F.Mask" "F.Paste")
			(net "PWRGD_PVDDCR_CPU1_P0_R")
		)
	)
	(footprint ""
		(layer "F.Cu")
		(at 165.2016 -436.153052)
		(property "Reference" "C1973"
			(at 0 0 0)
			(layer "F.SilkS")
			(hide yes)
			(effects
				(font
					(size 1.27 1.27)
				)
			)
		)
		(property "Value" ""
			(at 0 0 0)
			(layer "F.Fab")
			(effects
				(font
					(size 1.27 1.27)
				)
			)
		)
		(duplicate_pad_numbers_are_jumpers no)
		(fp_line
			(start -0.7874 -0.4064)
			(end 0.7874 -0.4064)
			(stroke
				(width 0.1524)
				(type default)
			)
			(layer "F.SilkS")
		)
		(fp_line
			(start -0.7874 0.4064)
			(end -0.7874 -0.4064)
			(stroke
				(width 0.1524)
				(type default)
			)
			(layer "F.SilkS")
		)
		(fp_line
			(start 0.7874 -0.4064)
			(end 0.7874 0.4064)
			(stroke
				(width 0.1524)
				(type default)
			)
			(layer "F.SilkS")
		)
		(fp_line
			(start 0.7874 0.4064)
			(end -0.7874 0.4064)
			(stroke
				(width 0.1524)
				(type default)
			)
			(layer "F.SilkS")
		)
		(fp_line
			(start -0.67945 -0.305054)
			(end -0.12065 -0.305054)
			(stroke
				(width 0.1)
				(type default)
			)
			(layer "F.Fab")
		)
		(fp_line
			(start -0.67945 0.3048)
			(end -0.67945 -0.305054)
			(stroke
				(width 0.1)
				(type default)
			)
			(layer "F.Fab")
		)
		(fp_line
			(start -0.12065 -0.305054)
			(end -0.12065 -0.2794)
			(stroke
				(width 0.1)
				(type default)
			)
			(layer "F.Fab")
		)
		(fp_line
			(start -0.12065 -0.2794)
			(end 0.12065 -0.2794)
			(stroke
				(width 0.1)
				(type default)
			)
			(layer "F.Fab")
		)
		(fp_line
			(start -0.12065 0.2794)
			(end -0.12065 0.3048)
			(stroke
				(width 0.1)
				(type default)
			)
			(layer "F.Fab")
		)
		(fp_line
			(start -0.12065 0.3048)
			(end -0.67945 0.3048)
			(stroke
				(width 0.1)
				(type default)
			)
			(layer "F.Fab")
		)
		(fp_line
			(start 0.120396 0.2794)
			(end -0.12065 0.2794)
			(stroke
				(width 0.1)
				(type default)
			)
			(layer "F.Fab")
		)
		(fp_line
			(start 0.120396 0.3048)
			(end 0.120396 0.2794)
			(stroke
				(width 0.1)
				(type default)
			)
			(layer "F.Fab")
		)
		(fp_line
			(start 0.12065 -0.3048)
			(end 0.67945 -0.3048)
			(stroke
				(width 0.1)
				(type default)
			)
			(layer "F.Fab")
		)
		(fp_line
			(start 0.12065 -0.2794)
			(end 0.12065 -0.3048)
			(stroke
				(width 0.1)
				(type default)
			)
			(layer "F.Fab")
		)
		(fp_line
			(start 0.67945 -0.3048)
			(end 0.67945 0.3048)
			(stroke
				(width 0.1)
				(type default)
			)
			(layer "F.Fab")
		)
		(fp_line
			(start 0.67945 0.3048)
			(end 0.120396 0.3048)
			(stroke
				(width 0.1)
				(type default)
			)
			(layer "F.Fab")
		)
		(pad "1" smd circle
			(at -0.40005 0)
			(size 0 0)
			(layers "F.Cu" "F.Mask" "F.Paste")
			(net "GPU_BASE_HMC_READY_ISO")
		)
		(pad "2" smd circle
			(at 0.40005 0)
			(size 0 0)
			(layers "F.Cu" "F.Mask" "F.Paste")
			(net "GND")
		)
	)
	(footprint ""
		(layer "F.Cu")
		(at 21.876258 -427.580298 90)
		(property "Reference" "R6166"
			(at 0 0 90)
			(layer "F.SilkS")
			(hide yes)
			(effects
				(font
					(size 1.27 1.27)
				)
			)
		)
		(property "Value" ""
			(at 0 0 90)
			(layer "F.Fab")
			(effects
				(font
					(size 1.27 1.27)
				)
			)
		)
		(duplicate_pad_numbers_are_jumpers no)
		(fp_line
			(start 0.7874 -0.4064)
			(end 0.7874 0.4064)
			(stroke
				(width 0.1524)
				(type default)
			)
			(layer "F.SilkS")
		)
		(fp_line
			(start -0.7874 -0.4064)
			(end 0.7874 -0.4064)
			(stroke
				(width 0.1524)
				(type default)
			)
			(layer "F.SilkS")
		)
		(fp_line
			(start 0.7874 0.4064)
			(end -0.7874 0.4064)
			(stroke
				(width 0.1524)
				(type default)
			)
			(layer "F.SilkS")
		)
		(fp_line
			(start -0.7874 0.4064)
			(end -0.7874 -0.4064)
			(stroke
				(width 0.1524)
				(type default)
			)
			(layer "F.SilkS")
		)
		(fp_line
			(start -0.12065 -0.305054)
			(end -0.12065 -0.2794)
			(stroke
				(width 0.1)
				(type default)
			)
			(layer "F.Fab")
		)
		(fp_line
			(start -0.67945 -0.305054)
			(end -0.12065 -0.305054)
			(stroke
				(width 0.1)
				(type default)
			)
			(layer "F.Fab")
		)
		(fp_line
			(start 0.67945 -0.3048)
			(end 0.67945 0.3048)
			(stroke
				(width 0.1)
				(type default)
			)
			(layer "F.Fab")
		)
		(fp_line
			(start 0.12065 -0.3048)
			(end 0.67945 -0.3048)
			(stroke
				(width 0.1)
				(type default)
			)
			(layer "F.Fab")
		)
		(fp_line
			(start 0.12065 -0.2794)
			(end 0.12065 -0.3048)
			(stroke
				(width 0.1)
				(type default)
			)
			(layer "F.Fab")
		)
		(fp_line
			(start -0.12065 -0.2794)
			(end 0.12065 -0.2794)
			(stroke
				(width 0.1)
				(type default)
			)
			(layer "F.Fab")
		)
		(fp_line
			(start 0.120396 0.2794)
			(end -0.12065 0.2794)
			(stroke
				(width 0.1)
				(type default)
			)
			(layer "F.Fab")
		)
		(fp_line
			(start -0.12065 0.2794)
			(end -0.12065 0.3048)
			(stroke
				(width 0.1)
				(type default)
			)
			(layer "F.Fab")
		)
		(fp_line
			(start 0.67945 0.3048)
			(end 0.120396 0.3048)
			(stroke
				(width 0.1)
				(type default)
			)
			(layer "F.Fab")
		)
		(fp_line
			(start 0.120396 0.3048)
			(end 0.120396 0.2794)
			(stroke
				(width 0.1)
				(type default)
			)
			(layer "F.Fab")
		)
		(fp_line
			(start -0.12065 0.3048)
			(end -0.67945 0.3048)
			(stroke
				(width 0.1)
				(type default)
			)
			(layer "F.Fab")
		)
		(fp_line
			(start -0.67945 0.3048)
			(end -0.67945 -0.305054)
			(stroke
				(width 0.1)
				(type default)
			)
			(layer "F.Fab")
		)
		(pad "1" smd circle
			(at -0.40005 0 90)
			(size 0 0)
			(layers "F.Cu" "F.Mask" "F.Paste")
			(net "FM_P2E_BUF2_EQB0")
		)
		(pad "2" smd circle
			(at 0.40005 0 90)
			(size 0 0)
			(layers "F.Cu" "F.Mask" "F.Paste")
			(net "GND")
		)
	)
	(footprint ""
		(layer "F.Cu")
		(at 315.214 -366.395 90)
		(property "Reference" "PC15"
			(at 0 0 90)
			(layer "F.SilkS")
			(hide yes)
			(effects
				(font
					(size 1.27 1.27)
				)
			)
		)
		(property "Value" ""
			(at 0 0 90)
			(layer "F.Fab")
			(effects
				(font
					(size 1.27 1.27)
				)
			)
		)
		(duplicate_pad_numbers_are_jumpers no)
		(fp_line
			(start 0.7874 -0.4064)
			(end 0.7874 0.4064)
			(stroke
				(width 0.1524)
				(type default)
			)
			(layer "F.SilkS")
		)
		(fp_line
			(start -0.7874 -0.4064)
			(end 0.7874 -0.4064)
			(stroke
				(width 0.1524)
				(type default)
			)
			(layer "F.SilkS")
		)
		(fp_line
			(start 0.7874 0.4064)
			(end -0.7874 0.4064)
			(stroke
				(width 0.1524)
				(type default)
			)
			(layer "F.SilkS")
		)
		(fp_line
			(start -0.7874 0.4064)
			(end -0.7874 -0.4064)
			(stroke
				(width 0.1524)
				(type default)
			)
			(layer "F.SilkS")
		)
		(fp_line
			(start -0.12065 -0.305054)
			(end -0.12065 -0.2794)
			(stroke
				(width 0.1)
				(type default)
			)
			(layer "F.Fab")
		)
		(fp_line
			(start -0.67945 -0.305054)
			(end -0.12065 -0.305054)
			(stroke
				(width 0.1)
				(type default)
			)
			(layer "F.Fab")
		)
		(fp_line
			(start 0.67945 -0.3048)
			(end 0.67945 0.3048)
			(stroke
				(width 0.1)
				(type default)
			)
			(layer "F.Fab")
		)
		(fp_line
			(start 0.12065 -0.3048)
			(end 0.67945 -0.3048)
			(stroke
				(width 0.1)
				(type default)
			)
			(layer "F.Fab")
		)
		(fp_line
			(start 0.12065 -0.2794)
			(end 0.12065 -0.3048)
			(stroke
				(width 0.1)
				(type default)
			)
			(layer "F.Fab")
		)
		(fp_line
			(start -0.12065 -0.2794)
			(end 0.12065 -0.2794)
			(stroke
				(width 0.1)
				(type default)
			)
			(layer "F.Fab")
		)
		(fp_line
			(start 0.120396 0.2794)
			(end -0.12065 0.2794)
			(stroke
				(width 0.1)
				(type default)
			)
			(layer "F.Fab")
		)
		(fp_line
			(start -0.12065 0.2794)
			(end -0.12065 0.3048)
			(stroke
				(width 0.1)
				(type default)
			)
			(layer "F.Fab")
		)
		(fp_line
			(start 0.67945 0.3048)
			(end 0.120396 0.3048)
			(stroke
				(width 0.1)
				(type default)
			)
			(layer "F.Fab")
		)
		(fp_line
			(start 0.120396 0.3048)
			(end 0.120396 0.2794)
			(stroke
				(width 0.1)
				(type default)
			)
			(layer "F.Fab")
		)
		(fp_line
			(start -0.12065 0.3048)
			(end -0.67945 0.3048)
			(stroke
				(width 0.1)
				(type default)
			)
			(layer "F.Fab")
		)
		(fp_line
			(start -0.67945 0.3048)
			(end -0.67945 -0.305054)
			(stroke
				(width 0.1)
				(type default)
			)
			(layer "F.Fab")
		)
		(pad "1" smd circle
			(at -0.40005 0 90)
			(size 0 0)
			(layers "F.Cu" "F.Mask" "F.Paste")
			(net "PVDDCR_CPU1_P0_VCCS")
		)
		(pad "2" smd circle
			(at 0.40005 0 90)
			(size 0 0)
			(layers "F.Cu" "F.Mask" "F.Paste")
			(net "GND")
		)
	)
	(footprint ""
		(layer "F.Cu")
		(at 42.690034 -361.212892 90)
		(property "Reference" "PC454"
			(at 5.155438 -0.780034 0)
			(unlocked yes)
			(layer "F.SilkS")
			(effects
				(font
					(size 0.7874 0.5842)
					(thickness 0.1524)
				)
				(justify left)
			)
		)
		(property "Value" ""
			(at 0 0 90)
			(layer "F.Fab")
			(effects
				(font
					(size 1.27 1.27)
				)
			)
		)
		(duplicate_pad_numbers_are_jumpers no)
		(fp_line
			(start 3.400044 -3.400044)
			(end -2.146046 -3.400044)
			(stroke
				(width 0.1524)
				(type default)
			)
			(layer "F.SilkS")
		)
		(fp_line
			(start -2.146046 -3.400044)
			(end -3.400044 -2.146046)
			(stroke
				(width 0.1524)
				(type default)
			)
			(layer "F.SilkS")
		)
		(fp_line
			(start -3.400044 -2.146046)
			(end -3.400044 -0.9398)
			(stroke
				(width 0.1524)
				(type default)
			)
			(layer "F.SilkS")
		)
		(fp_line
			(start 3.400044 -0.9398)
			(end 3.400044 -3.400044)
			(stroke
				(width 0.1524)
				(type default)
			)
			(layer "F.SilkS")
		)
		(fp_line
			(start 3.400044 0.9398)
			(end 3.400044 3.400044)
			(stroke
				(width 0.1524)
				(type default)
			)
			(layer "F.SilkS")
		)
		(fp_line
			(start -3.400044 2.146046)
			(end -3.400044 0.9398)
			(stroke
				(width 0.1524)
				(type default)
			)
			(layer "F.SilkS")
		)
		(fp_line
			(start 3.400044 3.400044)
			(end -2.146046 3.400044)
			(stroke
				(width 0.1524)
				(type default)
			)
			(layer "F.SilkS")
		)
		(fp_line
			(start -2.146046 3.400044)
			(end -3.400044 2.146046)
			(stroke
				(width 0.1524)
				(type default)
			)
			(layer "F.SilkS")
		)
		(fp_line
			(start 3.400044 -3.400044)
			(end -3.400044 -3.400044)
			(stroke
				(width 0.1)
				(type default)
			)
			(layer "F.Fab")
		)
		(fp_line
			(start -3.400044 -3.400044)
			(end -3.400044 3.400044)
			(stroke
				(width 0.1)
				(type default)
			)
			(layer "F.Fab")
		)
		(fp_line
			(start 3.400044 3.400044)
			(end 3.400044 -3.400044)
			(stroke
				(width 0.1)
				(type default)
			)
			(layer "F.Fab")
		)
		(fp_line
			(start -3.400044 3.400044)
			(end 3.400044 3.400044)
			(stroke
				(width 0.1)
				(type default)
			)
			(layer "F.Fab")
		)
		(pad "1" smd rect
			(at -2.70002 0)
			(size 1.6002 3.5052)
			(layers "F.Cu" "F.Mask" "F.Paste")
			(net "SW_P12V_AUX_PVDDIO_P1_FLT")
		)
		(pad "2" smd rect
			(at 2.70002 0)
			(size 1.6002 3.5052)
			(layers "F.Cu" "F.Mask" "F.Paste")
			(net "GND")
		)
	)
	(footprint ""
		(layer "F.Cu")
		(at 24.961088 -373.44985 -90)
		(property "Reference" "PC6631"
			(at 4.54152 2.228088 0)
			(unlocked yes)
			(layer "F.SilkS")
			(effects
				(font
					(size 0.7874 0.5842)
					(thickness 0.1524)
				)
				(justify left)
			)
		)
		(property "Value" ""
			(at 0 0 270)
			(layer "F.Fab")
			(effects
				(font
					(size 1.27 1.27)
				)
			)
		)
		(duplicate_pad_numbers_are_jumpers no)
		(fp_line
			(start -1.988058 2.750058)
			(end 2.750058 2.750058)
			(stroke
				(width 0.1524)
				(type default)
			)
			(layer "F.SilkS")
		)
		(fp_line
			(start 2.750058 2.750058)
			(end 2.750058 0.9398)
			(stroke
				(width 0.1524)
				(type default)
			)
			(layer "F.SilkS")
		)
		(fp_line
			(start -2.750058 1.988058)
			(end -1.988058 2.750058)
			(stroke
				(width 0.1524)
				(type default)
			)
			(layer "F.SilkS")
		)
		(fp_line
			(start -2.750058 0.9398)
			(end -2.750058 1.988058)
			(stroke
				(width 0.1524)
				(type default)
			)
			(layer "F.SilkS")
		)
		(fp_line
			(start 2.750058 -0.9398)
			(end 2.750058 -2.750058)
			(stroke
				(width 0.1524)
				(type default)
			)
			(layer "F.SilkS")
		)
		(fp_line
			(start -2.750058 -1.988058)
			(end -2.750058 -0.9398)
			(stroke
				(width 0.1524)
				(type default)
			)
			(layer "F.SilkS")
		)
		(fp_line
			(start -1.988058 -2.750058)
			(end -2.750058 -1.988058)
			(stroke
				(width 0.1524)
				(type default)
			)
			(layer "F.SilkS")
		)
		(fp_line
			(start 2.750058 -2.750058)
			(end -1.988058 -2.750058)
			(stroke
				(width 0.1524)
				(type default)
			)
			(layer "F.SilkS")
		)
		(fp_line
			(start -2.750058 2.750058)
			(end 2.750058 2.750058)
			(stroke
				(width 0.1)
				(type default)
			)
			(layer "F.Fab")
		)
		(fp_line
			(start 2.750058 2.750058)
			(end 2.750058 -2.750058)
			(stroke
				(width 0.1)
				(type default)
			)
			(layer "F.Fab")
		)
		(fp_line
			(start -2.750058 -2.750058)
			(end -2.750058 2.750058)
			(stroke
				(width 0.1)
				(type default)
			)
			(layer "F.Fab")
		)
		(fp_line
			(start 2.750058 -2.750058)
			(end -2.750058 -2.750058)
			(stroke
				(width 0.1)
				(type default)
			)
			(layer "F.Fab")
		)
		(pad "1" smd rect
			(at -2.199894 0)
			(size 1.6002 3.0226)
			(layers "F.Cu" "F.Mask" "F.Paste")
			(net "P0V9_CPU1_RT_2D")
		)
		(pad "2" smd rect
			(at 2.199894 0)
			(size 1.6002 3.0226)
			(layers "F.Cu" "F.Mask" "F.Paste")
			(net "GND")
		)
	)
	(footprint ""
		(layer "F.Cu")
		(at 225.420428 -268.232382)
		(property "Reference" "PC6519"
			(at 0 0 0)
			(layer "F.SilkS")
			(hide yes)
			(effects
				(font
					(size 1.27 1.27)
				)
			)
		)
		(property "Value" ""
			(at 0 0 0)
			(layer "F.Fab")
			(effects
				(font
					(size 1.27 1.27)
				)
			)
		)
		(duplicate_pad_numbers_are_jumpers no)
		(fp_line
			(start -0.7874 -0.4064)
			(end 0.7874 -0.4064)
			(stroke
				(width 0.1524)
				(type default)
			)
			(layer "F.SilkS")
		)
		(fp_line
			(start -0.7874 0.4064)
			(end -0.7874 -0.4064)
			(stroke
				(width 0.1524)
				(type default)
			)
			(layer "F.SilkS")
		)
		(fp_line
			(start 0.7874 -0.4064)
			(end 0.7874 0.4064)
			(stroke
				(width 0.1524)
				(type default)
			)
			(layer "F.SilkS")
		)
		(fp_line
			(start 0.7874 0.4064)
			(end -0.7874 0.4064)
			(stroke
				(width 0.1524)
				(type default)
			)
			(layer "F.SilkS")
		)
		(fp_line
			(start -0.67945 -0.305054)
			(end -0.12065 -0.305054)
			(stroke
				(width 0.1)
				(type default)
			)
			(layer "F.Fab")
		)
		(fp_line
			(start -0.67945 0.3048)
			(end -0.67945 -0.305054)
			(stroke
				(width 0.1)
				(type default)
			)
			(layer "F.Fab")
		)
		(fp_line
			(start -0.12065 -0.305054)
			(end -0.12065 -0.2794)
			(stroke
				(width 0.1)
				(type default)
			)
			(layer "F.Fab")
		)
		(fp_line
			(start -0.12065 -0.2794)
			(end 0.12065 -0.2794)
			(stroke
				(width 0.1)
				(type default)
			)
			(layer "F.Fab")
		)
		(fp_line
			(start -0.12065 0.2794)
			(end -0.12065 0.3048)
			(stroke
				(width 0.1)
				(type default)
			)
			(layer "F.Fab")
		)
		(fp_line
			(start -0.12065 0.3048)
			(end -0.67945 0.3048)
			(stroke
				(width 0.1)
				(type default)
			)
			(layer "F.Fab")
		)
		(fp_line
			(start 0.120396 0.2794)
			(end -0.12065 0.2794)
			(stroke
				(width 0.1)
				(type default)
			)
			(layer "F.Fab")
		)
		(fp_line
			(start 0.120396 0.3048)
			(end 0.120396 0.2794)
			(stroke
				(width 0.1)
				(type default)
			)
			(layer "F.Fab")
		)
		(fp_line
			(start 0.12065 -0.3048)
			(end 0.67945 -0.3048)
			(stroke
				(width 0.1)
				(type default)
			)
			(layer "F.Fab")
		)
		(fp_line
			(start 0.12065 -0.2794)
			(end 0.12065 -0.3048)
			(stroke
				(width 0.1)
				(type default)
			)
			(layer "F.Fab")
		)
		(fp_line
			(start 0.67945 -0.3048)
			(end 0.67945 0.3048)
			(stroke
				(width 0.1)
				(type default)
			)
			(layer "F.Fab")
		)
		(fp_line
			(start 0.67945 0.3048)
			(end 0.120396 0.3048)
			(stroke
				(width 0.1)
				(type default)
			)
			(layer "F.Fab")
		)
		(pad "1" smd circle
			(at -0.40005 0)
			(size 0 0)
			(layers "F.Cu" "F.Mask" "F.Paste")
			(net "P12V_AUX")
		)
		(pad "2" smd circle
			(at 0.40005 0)
			(size 0 0)
			(layers "F.Cu" "F.Mask" "F.Paste")
			(net "GND")
		)
	)
	(footprint ""
		(layer "F.Cu")
		(at 141.624812 -49.159414)
		(property "Reference" "C6028"
			(at 0 0 0)
			(layer "F.SilkS")
			(hide yes)
			(effects
				(font
					(size 1.27 1.27)
				)
			)
		)
		(property "Value" ""
			(at 0 0 0)
			(layer "F.Fab")
			(effects
				(font
					(size 1.27 1.27)
				)
			)
		)
		(duplicate_pad_numbers_are_jumpers no)
		(fp_line
			(start -0.7874 -0.4064)
			(end 0.7874 -0.4064)
			(stroke
				(width 0.1524)
				(type default)
			)
			(layer "F.SilkS")
		)
		(fp_line
			(start -0.7874 0.4064)
			(end -0.7874 -0.4064)
			(stroke
				(width 0.1524)
				(type default)
			)
			(layer "F.SilkS")
		)
		(fp_line
			(start 0.7874 -0.4064)
			(end 0.7874 0.4064)
			(stroke
				(width 0.1524)
				(type default)
			)
			(layer "F.SilkS")
		)
		(fp_line
			(start 0.7874 0.4064)
			(end -0.7874 0.4064)
			(stroke
				(width 0.1524)
				(type default)
			)
			(layer "F.SilkS")
		)
		(fp_line
			(start -0.67945 -0.305054)
			(end -0.12065 -0.305054)
			(stroke
				(width 0.1)
				(type default)
			)
			(layer "F.Fab")
		)
		(fp_line
			(start -0.67945 0.3048)
			(end -0.67945 -0.305054)
			(stroke
				(width 0.1)
				(type default)
			)
			(layer "F.Fab")
		)
		(fp_line
			(start -0.12065 -0.305054)
			(end -0.12065 -0.2794)
			(stroke
				(width 0.1)
				(type default)
			)
			(layer "F.Fab")
		)
		(fp_line
			(start -0.12065 -0.2794)
			(end 0.12065 -0.2794)
			(stroke
				(width 0.1)
				(type default)
			)
			(layer "F.Fab")
		)
		(fp_line
			(start -0.12065 0.2794)
			(end -0.12065 0.3048)
			(stroke
				(width 0.1)
				(type default)
			)
			(layer "F.Fab")
		)
		(fp_line
			(start -0.12065 0.3048)
			(end -0.67945 0.3048)
			(stroke
				(width 0.1)
				(type default)
			)
			(layer "F.Fab")
		)
		(fp_line
			(start 0.120396 0.2794)
			(end -0.12065 0.2794)
			(stroke
				(width 0.1)
				(type default)
			)
			(layer "F.Fab")
		)
		(fp_line
			(start 0.120396 0.3048)
			(end 0.120396 0.2794)
			(stroke
				(width 0.1)
				(type default)
			)
			(layer "F.Fab")
		)
		(fp_line
			(start 0.12065 -0.3048)
			(end 0.67945 -0.3048)
			(stroke
				(width 0.1)
				(type default)
			)
			(layer "F.Fab")
		)
		(fp_line
			(start 0.12065 -0.2794)
			(end 0.12065 -0.3048)
			(stroke
				(width 0.1)
				(type default)
			)
			(layer "F.Fab")
		)
		(fp_line
			(start 0.67945 -0.3048)
			(end 0.67945 0.3048)
			(stroke
				(width 0.1)
				(type default)
			)
			(layer "F.Fab")
		)
		(fp_line
			(start 0.67945 0.3048)
			(end 0.120396 0.3048)
			(stroke
				(width 0.1)
				(type default)
			)
			(layer "F.Fab")
		)
		(pad "1" smd circle
			(at -0.40005 0)
			(size 0 0)
			(layers "F.Cu" "F.Mask" "F.Paste")
			(net "P5V_AUX")
		)
		(pad "2" smd circle
			(at 0.40005 0)
			(size 0 0)
			(layers "F.Cu" "F.Mask" "F.Paste")
			(net "GND")
		)
	)
	(footprint ""
		(layer "F.Cu")
		(at 171.204128 -123.683268 180)
		(property "Reference" "R6143"
			(at 0 0 180)
			(layer "F.SilkS")
			(hide yes)
			(effects
				(font
					(size 1.27 1.27)
				)
			)
		)
		(property "Value" ""
			(at 0 0 180)
			(layer "F.Fab")
			(effects
				(font
					(size 1.27 1.27)
				)
			)
		)
		(duplicate_pad_numbers_are_jumpers no)
		(fp_line
			(start 0.7874 0.4064)
			(end -0.7874 0.4064)
			(stroke
				(width 0.1524)
				(type default)
			)
			(layer "F.SilkS")
		)
		(fp_line
			(start 0.7874 -0.4064)
			(end 0.7874 0.4064)
			(stroke
				(width 0.1524)
				(type default)
			)
			(layer "F.SilkS")
		)
		(fp_line
			(start -0.7874 0.4064)
			(end -0.7874 -0.4064)
			(stroke
				(width 0.1524)
				(type default)
			)
			(layer "F.SilkS")
		)
		(fp_line
			(start -0.7874 -0.4064)
			(end 0.7874 -0.4064)
			(stroke
				(width 0.1524)
				(type default)
			)
			(layer "F.SilkS")
		)
		(fp_line
			(start 0.67945 0.3048)
			(end 0.120396 0.3048)
			(stroke
				(width 0.1)
				(type default)
			)
			(layer "F.Fab")
		)
		(fp_line
			(start 0.67945 -0.3048)
			(end 0.67945 0.3048)
			(stroke
				(width 0.1)
				(type default)
			)
			(layer "F.Fab")
		)
		(fp_line
			(start 0.12065 -0.2794)
			(end 0.12065 -0.3048)
			(stroke
				(width 0.1)
				(type default)
			)
			(layer "F.Fab")
		)
		(fp_line
			(start 0.12065 -0.3048)
			(end 0.67945 -0.3048)
			(stroke
				(width 0.1)
				(type default)
			)
			(layer "F.Fab")
		)
		(fp_line
			(start 0.120396 0.3048)
			(end 0.120396 0.2794)
			(stroke
				(width 0.1)
				(type default)
			)
			(layer "F.Fab")
		)
		(fp_line
			(start 0.120396 0.2794)
			(end -0.12065 0.2794)
			(stroke
				(width 0.1)
				(type default)
			)
			(layer "F.Fab")
		)
		(fp_line
			(start -0.12065 0.3048)
			(end -0.67945 0.3048)
			(stroke
				(width 0.1)
				(type default)
			)
			(layer "F.Fab")
		)
		(fp_line
			(start -0.12065 0.2794)
			(end -0.12065 0.3048)
			(stroke
				(width 0.1)
				(type default)
			)
			(layer "F.Fab")
		)
		(fp_line
			(start -0.12065 -0.2794)
			(end 0.12065 -0.2794)
			(stroke
				(width 0.1)
				(type default)
			)
			(layer "F.Fab")
		)
		(fp_line
			(start -0.12065 -0.305054)
			(end -0.12065 -0.2794)
			(stroke
				(width 0.1)
				(type default)
			)
			(layer "F.Fab")
		)
		(fp_line
			(start -0.67945 0.3048)
			(end -0.67945 -0.305054)
			(stroke
				(width 0.1)
				(type default)
			)
			(layer "F.Fab")
		)
		(fp_line
			(start -0.67945 -0.305054)
			(end -0.12065 -0.305054)
			(stroke
				(width 0.1)
				(type default)
			)
			(layer "F.Fab")
		)
		(pad "1" smd circle
			(at -0.40005 0 180)
			(size 0 0)
			(layers "F.Cu" "F.Mask" "F.Paste")
			(net "FM_BOARD_BMC_SKU_ID2")
		)
		(pad "2" smd circle
			(at 0.40005 0 180)
			(size 0 0)
			(layers "F.Cu" "F.Mask" "F.Paste")
			(net "GND")
		)
	)
	(footprint ""
		(layer "F.Cu")
		(at 115.70589 -258.795266)
		(property "Reference" "C2428"
			(at 0 0 0)
			(layer "F.SilkS")
			(hide yes)
			(effects
				(font
					(size 1.27 1.27)
				)
			)
		)
		(property "Value" ""
			(at 0 0 0)
			(layer "F.Fab")
			(effects
				(font
					(size 1.27 1.27)
				)
			)
		)
		(duplicate_pad_numbers_are_jumpers no)
		(fp_line
			(start -0.7874 -0.4064)
			(end 0.7874 -0.4064)
			(stroke
				(width 0.1524)
				(type default)
			)
			(layer "F.SilkS")
		)
		(fp_line
			(start -0.7874 0.4064)
			(end -0.7874 -0.4064)
			(stroke
				(width 0.1524)
				(type default)
			)
			(layer "F.SilkS")
		)
		(fp_line
			(start 0.7874 -0.4064)
			(end 0.7874 0.4064)
			(stroke
				(width 0.1524)
				(type default)
			)
			(layer "F.SilkS")
		)
		(fp_line
			(start 0.7874 0.4064)
			(end -0.7874 0.4064)
			(stroke
				(width 0.1524)
				(type default)
			)
			(layer "F.SilkS")
		)
		(fp_line
			(start -0.67945 -0.305054)
			(end -0.12065 -0.305054)
			(stroke
				(width 0.1)
				(type default)
			)
			(layer "F.Fab")
		)
		(fp_line
			(start -0.67945 0.3048)
			(end -0.67945 -0.305054)
			(stroke
				(width 0.1)
				(type default)
			)
			(layer "F.Fab")
		)
		(fp_line
			(start -0.12065 -0.305054)
			(end -0.12065 -0.2794)
			(stroke
				(width 0.1)
				(type default)
			)
			(layer "F.Fab")
		)
		(fp_line
			(start -0.12065 -0.2794)
			(end 0.12065 -0.2794)
			(stroke
				(width 0.1)
				(type default)
			)
			(layer "F.Fab")
		)
		(fp_line
			(start -0.12065 0.2794)
			(end -0.12065 0.3048)
			(stroke
				(width 0.1)
				(type default)
			)
			(layer "F.Fab")
		)
		(fp_line
			(start -0.12065 0.3048)
			(end -0.67945 0.3048)
			(stroke
				(width 0.1)
				(type default)
			)
			(layer "F.Fab")
		)
		(fp_line
			(start 0.120396 0.2794)
			(end -0.12065 0.2794)
			(stroke
				(width 0.1)
				(type default)
			)
			(layer "F.Fab")
		)
		(fp_line
			(start 0.120396 0.3048)
			(end 0.120396 0.2794)
			(stroke
				(width 0.1)
				(type default)
			)
			(layer "F.Fab")
		)
		(fp_line
			(start 0.12065 -0.3048)
			(end 0.67945 -0.3048)
			(stroke
				(width 0.1)
				(type default)
			)
			(layer "F.Fab")
		)
		(fp_line
			(start 0.12065 -0.2794)
			(end 0.12065 -0.3048)
			(stroke
				(width 0.1)
				(type default)
			)
			(layer "F.Fab")
		)
		(fp_line
			(start 0.67945 -0.3048)
			(end 0.67945 0.3048)
			(stroke
				(width 0.1)
				(type default)
			)
			(layer "F.Fab")
		)
		(fp_line
			(start 0.67945 0.3048)
			(end 0.120396 0.3048)
			(stroke
				(width 0.1)
				(type default)
			)
			(layer "F.Fab")
		)
		(pad "1" smd circle
			(at -0.40005 0)
			(size 0 0)
			(layers "F.Cu" "F.Mask" "F.Paste")
			(net "PVDDCR_SOC_P1")
		)
		(pad "2" smd circle
			(at 0.40005 0)
			(size 0 0)
			(layers "F.Cu" "F.Mask" "F.Paste")
			(net "GND")
		)
	)
	(footprint ""
		(layer "F.Cu")
		(at 197.610476 -358.027478)
		(property "Reference" "PC8007"
			(at 0 0 0)
			(layer "F.SilkS")
			(hide yes)
			(effects
				(font
					(size 1.27 1.27)
				)
			)
		)
		(property "Value" ""
			(at 0 0 0)
			(layer "F.Fab")
			(effects
				(font
					(size 1.27 1.27)
				)
			)
		)
		(duplicate_pad_numbers_are_jumpers no)
		(fp_line
			(start -1.524 -0.762)
			(end 1.524 -0.762)
			(stroke
				(width 0.1524)
				(type default)
			)
			(layer "F.SilkS")
		)
		(fp_line
			(start -1.524 0.762)
			(end -1.524 -0.762)
			(stroke
				(width 0.1524)
				(type default)
			)
			(layer "F.SilkS")
		)
		(fp_line
			(start 1.524 -0.762)
			(end 1.524 0.762)
			(stroke
				(width 0.1524)
				(type default)
			)
			(layer "F.SilkS")
		)
		(fp_line
			(start 1.524 0.762)
			(end -1.524 0.762)
			(stroke
				(width 0.1524)
				(type default)
			)
			(layer "F.SilkS")
		)
		(fp_line
			(start -1.1049 -0.724916)
			(end -1.1049 0.724916)
			(stroke
				(width 0.1)
				(type default)
			)
			(layer "F.Fab")
		)
		(fp_line
			(start -1.1049 0.724916)
			(end 1.1049 0.724916)
			(stroke
				(width 0.1)
				(type default)
			)
			(layer "F.Fab")
		)
		(fp_line
			(start 1.1049 -0.724916)
			(end -1.1049 -0.724916)
			(stroke
				(width 0.1)
				(type default)
			)
			(layer "F.Fab")
		)
		(fp_line
			(start 1.1049 0.724916)
			(end 1.1049 -0.724916)
			(stroke
				(width 0.1)
				(type default)
			)
			(layer "F.Fab")
		)
		(pad "1" smd rect
			(at -0.889 0 180)
			(size 1.016 1.27)
			(layers "F.Cu" "F.Mask" "F.Paste")
			(net "SW_P12V_AUX_PVDD11_S3_P1_FLT")
		)
		(pad "2" smd rect
			(at 0.889 0 180)
			(size 1.016 1.27)
			(layers "F.Cu" "F.Mask" "F.Paste")
			(net "GND")
		)
	)
	(footprint ""
		(layer "F.Cu")
		(at 330.938632 -410.251656 90)
		(property "Reference" "C7035"
			(at 0 0 90)
			(layer "F.SilkS")
			(hide yes)
			(effects
				(font
					(size 1.27 1.27)
				)
			)
		)
		(property "Value" ""
			(at 0 0 90)
			(layer "F.Fab")
			(effects
				(font
					(size 1.27 1.27)
				)
			)
		)
		(duplicate_pad_numbers_are_jumpers no)
		(fp_line
			(start 1.524 -0.762)
			(end 1.524 0.762)
			(stroke
				(width 0.1524)
				(type default)
			)
			(layer "F.SilkS")
		)
		(fp_line
			(start -1.524 -0.762)
			(end 1.524 -0.762)
			(stroke
				(width 0.1524)
				(type default)
			)
			(layer "F.SilkS")
		)
		(fp_line
			(start 1.524 0.762)
			(end -1.524 0.762)
			(stroke
				(width 0.1524)
				(type default)
			)
			(layer "F.SilkS")
		)
		(fp_line
			(start -1.524 0.762)
			(end -1.524 -0.762)
			(stroke
				(width 0.1524)
				(type default)
			)
			(layer "F.SilkS")
		)
		(fp_line
			(start 1.1049 -0.724916)
			(end -1.1049 -0.724916)
			(stroke
				(width 0.1)
				(type default)
			)
			(layer "F.Fab")
		)
		(fp_line
			(start -1.1049 -0.724916)
			(end -1.1049 0.724916)
			(stroke
				(width 0.1)
				(type default)
			)
			(layer "F.Fab")
		)
		(fp_line
			(start 1.1049 0.724916)
			(end 1.1049 -0.724916)
			(stroke
				(width 0.1)
				(type default)
			)
			(layer "F.Fab")
		)
		(fp_line
			(start -1.1049 0.724916)
			(end 1.1049 0.724916)
			(stroke
				(width 0.1)
				(type default)
			)
			(layer "F.Fab")
		)
		(pad "1" smd rect
			(at -0.889 0 270)
			(size 1.016 1.27)
			(layers "F.Cu" "F.Mask" "F.Paste")
			(net "P0V9_CPU0_RT_2D")
		)
		(pad "2" smd rect
			(at 0.889 0 270)
			(size 1.016 1.27)
			(layers "F.Cu" "F.Mask" "F.Paste")
			(net "GND")
		)
	)
	(footprint ""
		(layer "F.Cu")
		(at 495.525044 -306.87518 -90)
		(property "Reference" "X9003"
			(at -1.82372 4.797298 0)
			(unlocked yes)
			(layer "F.SilkS")
			(effects
				(font
					(size 0.7874 0.5842)
					(thickness 0.1524)
				)
				(justify left)
			)
		)
		(property "Value" ""
			(at 0 0 270)
			(layer "F.Fab")
			(effects
				(font
					(size 1.27 1.27)
				)
			)
		)
		(property "User Part Number" "N_A"
			(at 1.30175 1.27 0)
			(unlocked yes)
			(layer "Cmts.User")
			(hide yes)
			(effects
				(font
					(size 0.635 0.4064)
					(thickness 0.1524)
				)
			)
		)
		(property "Device Type" "TP_TDR_4P_FTS_TH-TP_TDR_4P_DIP,EMPTY,TP15"
			(at 1.30175 1.27 0)
			(unlocked yes)
			(layer "F.Fab")
			(hide yes)
			(effects
				(font
					(size 0.635 0.4064)
					(thickness 0.1524)
				)
			)
		)
		(duplicate_pad_numbers_are_jumpers no)
		(fp_line
			(start 0 3.81)
			(end 2.54 3.81)
			(stroke
				(width 0.1524)
				(type default)
			)
			(layer "F.SilkS")
		)
		(fp_line
			(start 2.54 3.81)
			(end 2.54 3.6703)
			(stroke
				(width 0.1524)
				(type default)
			)
			(layer "F.SilkS")
		)
		(fp_line
			(start 0 3.175)
			(end 0 3.81)
			(stroke
				(width 0.1524)
				(type default)
			)
			(layer "F.SilkS")
		)
		(fp_line
			(start 2.54 1.4097)
			(end 2.54 1.1303)
			(stroke
				(width 0.1524)
				(type default)
			)
			(layer "F.SilkS")
		)
		(fp_line
			(start 0 0.635)
			(end 0 1.905)
			(stroke
				(width 0.1524)
				(type default)
			)
			(layer "F.SilkS")
		)
		(fp_line
			(start 2.54 -1.1303)
			(end 2.54 -1.27)
			(stroke
				(width 0.1524)
				(type default)
			)
			(layer "F.SilkS")
		)
		(fp_line
			(start 0 -1.27)
			(end 0 -0.635)
			(stroke
				(width 0.1524)
				(type default)
			)
			(layer "F.SilkS")
		)
		(fp_line
			(start 2.54 -1.27)
			(end 0 -1.27)
			(stroke
				(width 0.1524)
				(type default)
			)
			(layer "F.SilkS")
		)
		(fp_poly
			(pts
				(xy -2.285746 -0.762) (xy -0.761746 0) (xy -2.285746 0.762)
			)
			(stroke
				(width 0)
				(type default)
			)
			(fill yes)
			(layer "F.SilkS")
		)
		(fp_line
			(start 0 3.81)
			(end 2.54 3.81)
			(stroke
				(width 0.1)
				(type default)
			)
			(layer "F.Fab")
		)
		(fp_line
			(start 2.54 3.81)
			(end 2.54 -1.27)
			(stroke
				(width 0.1)
				(type default)
			)
			(layer "F.Fab")
		)
		(fp_line
			(start 0 -1.27)
			(end 0 3.81)
			(stroke
				(width 0.1)
				(type default)
			)
			(layer "F.Fab")
		)
		(fp_line
			(start 2.54 -1.27)
			(end 0 -1.27)
			(stroke
				(width 0.1)
				(type default)
			)
			(layer "F.Fab")
		)
		(fp_poly
			(pts
				(xy -0.761746 0) (xy -2.285746 -0.762) (xy -2.285746 0.762)
			)
			(stroke
				(width 0)
				(type default)
			)
			(fill yes)
			(layer "F.Fab")
		)
		(pad "1" thru_hole circle
			(at 0 0 270)
			(size 1.0033 1.0033)
			(drill 0.249936)
			(layers "*.Cu" "*.Mask")
			(remove_unused_layers no)
			(net "TDR_DIFF_85_NECK_IN2_DP")
			(clearance 0.10795)
			(thermal_gap 0.10795)
			(padstack
				(mode front_inner_back)
				(layer "Inner"
					(shape circle)
					(size 0.8001 0.8001)
					(clearance 0.1524)
				)
				(layer "B.Cu"
					(shape circle)
					(size 1.0033 1.0033)
					(clearance 0.10795)
				)
			)
		)
		(pad "2" thru_hole circle
			(at 2.54 0 270)
			(size 1.9939 1.9939)
			(drill 0.249936)
			(layers "*.Cu" "*.Mask")
			(remove_unused_layers no)
			(net "T1_GND")
			(clearance 0.10795)
			(thermal_gap 0.10795)
			(padstack
				(mode front_inner_back)
				(layer "Inner"
					(shape circle)
					(size 0.8001 0.8001)
					(clearance 0.1524)
				)
				(layer "B.Cu"
					(shape circle)
					(size 1.9939 1.9939)
					(clearance 0.10795)
				)
			)
		)
		(pad "3" thru_hole circle
			(at 2.54 2.54 270)
			(size 1.9939 1.9939)
			(drill 0.249936)
			(layers "*.Cu" "*.Mask")
			(remove_unused_layers no)
			(net "T1_GND")
			(clearance 0.10795)
			(thermal_gap 0.10795)
			(padstack
				(mode front_inner_back)
				(layer "Inner"
					(shape circle)
					(size 0.8001 0.8001)
					(clearance 0.1524)
				)
				(layer "B.Cu"
					(shape circle)
					(size 1.9939 1.9939)
					(clearance 0.10795)
				)
			)
		)
		(pad "4" thru_hole circle
			(at 0 2.54 270)
			(size 1.0033 1.0033)
			(drill 0.249936)
			(layers "*.Cu" "*.Mask")
			(remove_unused_layers no)
			(net "TDR_DIFF_85_NECK_IN2_DN")
			(clearance 0.10795)
			(thermal_gap 0.10795)
			(padstack
				(mode front_inner_back)
				(layer "Inner"
					(shape circle)
					(size 0.8001 0.8001)
					(clearance 0.1524)
				)
				(layer "B.Cu"
					(shape circle)
					(size 1.0033 1.0033)
					(clearance 0.10795)
				)
			)
		)
	)
	(footprint ""
		(layer "F.Cu")
		(at 236.7661 -403.919182 180)
		(property "Reference" "PR3984"
			(at 0 0 180)
			(layer "F.SilkS")
			(hide yes)
			(effects
				(font
					(size 1.27 1.27)
				)
			)
		)
		(property "Value" ""
			(at 0 0 180)
			(layer "F.Fab")
			(effects
				(font
					(size 1.27 1.27)
				)
			)
		)
		(duplicate_pad_numbers_are_jumpers no)
		(fp_line
			(start 0.7874 0.4064)
			(end -0.7874 0.4064)
			(stroke
				(width 0.1524)
				(type default)
			)
			(layer "F.SilkS")
		)
		(fp_line
			(start 0.7874 -0.4064)
			(end 0.7874 0.4064)
			(stroke
				(width 0.1524)
				(type default)
			)
			(layer "F.SilkS")
		)
		(fp_line
			(start -0.7874 0.4064)
			(end -0.7874 -0.4064)
			(stroke
				(width 0.1524)
				(type default)
			)
			(layer "F.SilkS")
		)
		(fp_line
			(start -0.7874 -0.4064)
			(end 0.7874 -0.4064)
			(stroke
				(width 0.1524)
				(type default)
			)
			(layer "F.SilkS")
		)
		(fp_line
			(start 0.67945 0.3048)
			(end 0.120396 0.3048)
			(stroke
				(width 0.1)
				(type default)
			)
			(layer "F.Fab")
		)
		(fp_line
			(start 0.67945 -0.3048)
			(end 0.67945 0.3048)
			(stroke
				(width 0.1)
				(type default)
			)
			(layer "F.Fab")
		)
		(fp_line
			(start 0.12065 -0.2794)
			(end 0.12065 -0.3048)
			(stroke
				(width 0.1)
				(type default)
			)
			(layer "F.Fab")
		)
		(fp_line
			(start 0.12065 -0.3048)
			(end 0.67945 -0.3048)
			(stroke
				(width 0.1)
				(type default)
			)
			(layer "F.Fab")
		)
		(fp_line
			(start 0.120396 0.3048)
			(end 0.120396 0.2794)
			(stroke
				(width 0.1)
				(type default)
			)
			(layer "F.Fab")
		)
		(fp_line
			(start 0.120396 0.2794)
			(end -0.12065 0.2794)
			(stroke
				(width 0.1)
				(type default)
			)
			(layer "F.Fab")
		)
		(fp_line
			(start -0.12065 0.3048)
			(end -0.67945 0.3048)
			(stroke
				(width 0.1)
				(type default)
			)
			(layer "F.Fab")
		)
		(fp_line
			(start -0.12065 0.2794)
			(end -0.12065 0.3048)
			(stroke
				(width 0.1)
				(type default)
			)
			(layer "F.Fab")
		)
		(fp_line
			(start -0.12065 -0.2794)
			(end 0.12065 -0.2794)
			(stroke
				(width 0.1)
				(type default)
			)
			(layer "F.Fab")
		)
		(fp_line
			(start -0.12065 -0.305054)
			(end -0.12065 -0.2794)
			(stroke
				(width 0.1)
				(type default)
			)
			(layer "F.Fab")
		)
		(fp_line
			(start -0.67945 0.3048)
			(end -0.67945 -0.305054)
			(stroke
				(width 0.1)
				(type default)
			)
			(layer "F.Fab")
		)
		(fp_line
			(start -0.67945 -0.305054)
			(end -0.12065 -0.305054)
			(stroke
				(width 0.1)
				(type default)
			)
			(layer "F.Fab")
		)
		(pad "1" smd circle
			(at -0.40005 0 180)
			(size 0 0)
			(layers "F.Cu" "F.Mask" "F.Paste")
			(net "AGND_HSC")
		)
		(pad "2" smd circle
			(at 0.40005 0 180)
			(size 0 0)
			(layers "F.Cu" "F.Mask" "F.Paste")
			(net "HSC_MODE_4")
		)
	)
	(footprint ""
		(layer "F.Cu")
		(at 257.86588 -50.545746)
		(property "Reference" "PC2196"
			(at 0 0 0)
			(layer "F.SilkS")
			(hide yes)
			(effects
				(font
					(size 1.27 1.27)
				)
			)
		)
		(property "Value" ""
			(at 0 0 0)
			(layer "F.Fab")
			(effects
				(font
					(size 1.27 1.27)
				)
			)
		)
		(duplicate_pad_numbers_are_jumpers no)
		(fp_line
			(start -0.7874 -0.4064)
			(end 0.7874 -0.4064)
			(stroke
				(width 0.1524)
				(type default)
			)
			(layer "F.SilkS")
		)
		(fp_line
			(start -0.7874 0.4064)
			(end -0.7874 -0.4064)
			(stroke
				(width 0.1524)
				(type default)
			)
			(layer "F.SilkS")
		)
		(fp_line
			(start 0.7874 -0.4064)
			(end 0.7874 0.4064)
			(stroke
				(width 0.1524)
				(type default)
			)
			(layer "F.SilkS")
		)
		(fp_line
			(start 0.7874 0.4064)
			(end -0.7874 0.4064)
			(stroke
				(width 0.1524)
				(type default)
			)
			(layer "F.SilkS")
		)
		(fp_line
			(start -0.67945 -0.305054)
			(end -0.12065 -0.305054)
			(stroke
				(width 0.1)
				(type default)
			)
			(layer "F.Fab")
		)
		(fp_line
			(start -0.67945 0.3048)
			(end -0.67945 -0.305054)
			(stroke
				(width 0.1)
				(type default)
			)
			(layer "F.Fab")
		)
		(fp_line
			(start -0.12065 -0.305054)
			(end -0.12065 -0.2794)
			(stroke
				(width 0.1)
				(type default)
			)
			(layer "F.Fab")
		)
		(fp_line
			(start -0.12065 -0.2794)
			(end 0.12065 -0.2794)
			(stroke
				(width 0.1)
				(type default)
			)
			(layer "F.Fab")
		)
		(fp_line
			(start -0.12065 0.2794)
			(end -0.12065 0.3048)
			(stroke
				(width 0.1)
				(type default)
			)
			(layer "F.Fab")
		)
		(fp_line
			(start -0.12065 0.3048)
			(end -0.67945 0.3048)
			(stroke
				(width 0.1)
				(type default)
			)
			(layer "F.Fab")
		)
		(fp_line
			(start 0.120396 0.2794)
			(end -0.12065 0.2794)
			(stroke
				(width 0.1)
				(type default)
			)
			(layer "F.Fab")
		)
		(fp_line
			(start 0.120396 0.3048)
			(end 0.120396 0.2794)
			(stroke
				(width 0.1)
				(type default)
			)
			(layer "F.Fab")
		)
		(fp_line
			(start 0.12065 -0.3048)
			(end 0.67945 -0.3048)
			(stroke
				(width 0.1)
				(type default)
			)
			(layer "F.Fab")
		)
		(fp_line
			(start 0.12065 -0.2794)
			(end 0.12065 -0.3048)
			(stroke
				(width 0.1)
				(type default)
			)
			(layer "F.Fab")
		)
		(fp_line
			(start 0.67945 -0.3048)
			(end 0.67945 0.3048)
			(stroke
				(width 0.1)
				(type default)
			)
			(layer "F.Fab")
		)
		(fp_line
			(start 0.67945 0.3048)
			(end 0.120396 0.3048)
			(stroke
				(width 0.1)
				(type default)
			)
			(layer "F.Fab")
		)
		(pad "1" smd circle
			(at -0.40005 0)
			(size 0 0)
			(layers "F.Cu" "F.Mask" "F.Paste")
			(net "P12V_E1S_TIMER_0")
		)
		(pad "2" smd circle
			(at 0.40005 0)
			(size 0 0)
			(layers "F.Cu" "F.Mask" "F.Paste")
			(net "GND")
		)
	)
	(footprint ""
		(layer "F.Cu")
		(at 362.025438 -409.947364)
		(property "Reference" "R9014"
			(at 0 0 0)
			(layer "F.SilkS")
			(hide yes)
			(effects
				(font
					(size 1.27 1.27)
				)
			)
		)
		(property "Value" ""
			(at 0 0 0)
			(layer "F.Fab")
			(effects
				(font
					(size 1.27 1.27)
				)
			)
		)
		(duplicate_pad_numbers_are_jumpers no)
		(fp_line
			(start -0.7874 -0.4064)
			(end 0.7874 -0.4064)
			(stroke
				(width 0.1524)
				(type default)
			)
			(layer "F.SilkS")
		)
		(fp_line
			(start -0.7874 0.4064)
			(end -0.7874 -0.4064)
			(stroke
				(width 0.1524)
				(type default)
			)
			(layer "F.SilkS")
		)
		(fp_line
			(start 0.7874 -0.4064)
			(end 0.7874 0.4064)
			(stroke
				(width 0.1524)
				(type default)
			)
			(layer "F.SilkS")
		)
		(fp_line
			(start 0.7874 0.4064)
			(end -0.7874 0.4064)
			(stroke
				(width 0.1524)
				(type default)
			)
			(layer "F.SilkS")
		)
		(fp_line
			(start -0.67945 -0.305054)
			(end -0.12065 -0.305054)
			(stroke
				(width 0.1)
				(type default)
			)
			(layer "F.Fab")
		)
		(fp_line
			(start -0.67945 0.3048)
			(end -0.67945 -0.305054)
			(stroke
				(width 0.1)
				(type default)
			)
			(layer "F.Fab")
		)
		(fp_line
			(start -0.12065 -0.305054)
			(end -0.12065 -0.2794)
			(stroke
				(width 0.1)
				(type default)
			)
			(layer "F.Fab")
		)
		(fp_line
			(start -0.12065 -0.2794)
			(end 0.12065 -0.2794)
			(stroke
				(width 0.1)
				(type default)
			)
			(layer "F.Fab")
		)
		(fp_line
			(start -0.12065 0.2794)
			(end -0.12065 0.3048)
			(stroke
				(width 0.1)
				(type default)
			)
			(layer "F.Fab")
		)
		(fp_line
			(start -0.12065 0.3048)
			(end -0.67945 0.3048)
			(stroke
				(width 0.1)
				(type default)
			)
			(layer "F.Fab")
		)
		(fp_line
			(start 0.120396 0.2794)
			(end -0.12065 0.2794)
			(stroke
				(width 0.1)
				(type default)
			)
			(layer "F.Fab")
		)
		(fp_line
			(start 0.120396 0.3048)
			(end 0.120396 0.2794)
			(stroke
				(width 0.1)
				(type default)
			)
			(layer "F.Fab")
		)
		(fp_line
			(start 0.12065 -0.3048)
			(end 0.67945 -0.3048)
			(stroke
				(width 0.1)
				(type default)
			)
			(layer "F.Fab")
		)
		(fp_line
			(start 0.12065 -0.2794)
			(end 0.12065 -0.3048)
			(stroke
				(width 0.1)
				(type default)
			)
			(layer "F.Fab")
		)
		(fp_line
			(start 0.67945 -0.3048)
			(end 0.67945 0.3048)
			(stroke
				(width 0.1)
				(type default)
			)
			(layer "F.Fab")
		)
		(fp_line
			(start 0.67945 0.3048)
			(end 0.120396 0.3048)
			(stroke
				(width 0.1)
				(type default)
			)
			(layer "F.Fab")
		)
		(pad "1" smd circle
			(at -0.40005 0)
			(size 0 0)
			(layers "F.Cu" "F.Mask" "F.Paste")
			(net "P3V3_AUX")
		)
		(pad "2" smd circle
			(at 0.40005 0)
			(size 0 0)
			(layers "F.Cu" "F.Mask" "F.Paste")
			(net "PRSNT_CABLE_GPU_A3_N")
		)
	)
	(footprint ""
		(layer "F.Cu")
		(at 392.840972 -384.449828)
		(property "Reference" "C872"
			(at 0 0 0)
			(layer "F.SilkS")
			(hide yes)
			(effects
				(font
					(size 1.27 1.27)
				)
			)
		)
		(property "Value" ""
			(at 0 0 0)
			(layer "F.Fab")
			(effects
				(font
					(size 1.27 1.27)
				)
			)
		)
		(duplicate_pad_numbers_are_jumpers no)
		(fp_line
			(start -0.299974 -0.150114)
			(end 0.299974 -0.150114)
			(stroke
				(width 0.1)
				(type default)
			)
			(layer "F.Fab")
		)
		(fp_line
			(start -0.299974 0.150114)
			(end -0.299974 -0.150114)
			(stroke
				(width 0.1)
				(type default)
			)
			(layer "F.Fab")
		)
		(fp_line
			(start 0.299974 -0.150114)
			(end 0.299974 0.150114)
			(stroke
				(width 0.1)
				(type default)
			)
			(layer "F.Fab")
		)
		(fp_line
			(start 0.299974 0.150114)
			(end -0.299974 0.150114)
			(stroke
				(width 0.1)
				(type default)
			)
			(layer "F.Fab")
		)
		(pad "1" smd rect
			(at -0.2667 0)
			(size 0.3048 0.381)
			(layers "F.Cu" "F.Mask" "F.Paste")
			(net "P5E_CPU0_P3_TX_C_DN<14>")
		)
		(pad "2" smd rect
			(at 0.2667 0)
			(size 0.3048 0.381)
			(layers "F.Cu" "F.Mask" "F.Paste")
			(net "P5E_CPU0_P3_TX_DN<14>")
		)
	)
	(footprint ""
		(layer "F.Cu")
		(at 19.241516 -41.958514)
		(property "Reference" "R1322"
			(at 0 0 0)
			(layer "F.SilkS")
			(hide yes)
			(effects
				(font
					(size 1.27 1.27)
				)
			)
		)
		(property "Value" ""
			(at 0 0 0)
			(layer "F.Fab")
			(effects
				(font
					(size 1.27 1.27)
				)
			)
		)
		(duplicate_pad_numbers_are_jumpers no)
		(fp_line
			(start -0.7874 -0.4064)
			(end 0.7874 -0.4064)
			(stroke
				(width 0.1524)
				(type default)
			)
			(layer "F.SilkS")
		)
		(fp_line
			(start -0.7874 0.4064)
			(end -0.7874 -0.4064)
			(stroke
				(width 0.1524)
				(type default)
			)
			(layer "F.SilkS")
		)
		(fp_line
			(start 0.7874 -0.4064)
			(end 0.7874 0.4064)
			(stroke
				(width 0.1524)
				(type default)
			)
			(layer "F.SilkS")
		)
		(fp_line
			(start 0.7874 0.4064)
			(end -0.7874 0.4064)
			(stroke
				(width 0.1524)
				(type default)
			)
			(layer "F.SilkS")
		)
		(fp_line
			(start -0.67945 -0.305054)
			(end -0.12065 -0.305054)
			(stroke
				(width 0.1)
				(type default)
			)
			(layer "F.Fab")
		)
		(fp_line
			(start -0.67945 0.3048)
			(end -0.67945 -0.305054)
			(stroke
				(width 0.1)
				(type default)
			)
			(layer "F.Fab")
		)
		(fp_line
			(start -0.12065 -0.305054)
			(end -0.12065 -0.2794)
			(stroke
				(width 0.1)
				(type default)
			)
			(layer "F.Fab")
		)
		(fp_line
			(start -0.12065 -0.2794)
			(end 0.12065 -0.2794)
			(stroke
				(width 0.1)
				(type default)
			)
			(layer "F.Fab")
		)
		(fp_line
			(start -0.12065 0.2794)
			(end -0.12065 0.3048)
			(stroke
				(width 0.1)
				(type default)
			)
			(layer "F.Fab")
		)
		(fp_line
			(start -0.12065 0.3048)
			(end -0.67945 0.3048)
			(stroke
				(width 0.1)
				(type default)
			)
			(layer "F.Fab")
		)
		(fp_line
			(start 0.120396 0.2794)
			(end -0.12065 0.2794)
			(stroke
				(width 0.1)
				(type default)
			)
			(layer "F.Fab")
		)
		(fp_line
			(start 0.120396 0.3048)
			(end 0.120396 0.2794)
			(stroke
				(width 0.1)
				(type default)
			)
			(layer "F.Fab")
		)
		(fp_line
			(start 0.12065 -0.3048)
			(end 0.67945 -0.3048)
			(stroke
				(width 0.1)
				(type default)
			)
			(layer "F.Fab")
		)
		(fp_line
			(start 0.12065 -0.2794)
			(end 0.12065 -0.3048)
			(stroke
				(width 0.1)
				(type default)
			)
			(layer "F.Fab")
		)
		(fp_line
			(start 0.67945 -0.3048)
			(end 0.67945 0.3048)
			(stroke
				(width 0.1)
				(type default)
			)
			(layer "F.Fab")
		)
		(fp_line
			(start 0.67945 0.3048)
			(end 0.120396 0.3048)
			(stroke
				(width 0.1)
				(type default)
			)
			(layer "F.Fab")
		)
		(pad "1" smd circle
			(at -0.40005 0)
			(size 0 0)
			(layers "F.Cu" "F.Mask" "F.Paste")
			(net "P3V3_AUX")
		)
		(pad "2" smd circle
			(at 0.40005 0)
			(size 0 0)
			(layers "F.Cu" "F.Mask" "F.Paste")
			(net "INA230_7_A1")
		)
	)
	(footprint ""
		(layer "F.Cu")
		(at 117.895624 -257.455416 180)
		(property "Reference" "C2422"
			(at 0 0 180)
			(layer "F.SilkS")
			(hide yes)
			(effects
				(font
					(size 1.27 1.27)
				)
			)
		)
		(property "Value" ""
			(at 0 0 180)
			(layer "F.Fab")
			(effects
				(font
					(size 1.27 1.27)
				)
			)
		)
		(duplicate_pad_numbers_are_jumpers no)
		(fp_line
			(start 0.7874 0.4064)
			(end -0.7874 0.4064)
			(stroke
				(width 0.1524)
				(type default)
			)
			(layer "F.SilkS")
		)
		(fp_line
			(start 0.7874 -0.4064)
			(end 0.7874 0.4064)
			(stroke
				(width 0.1524)
				(type default)
			)
			(layer "F.SilkS")
		)
		(fp_line
			(start -0.7874 0.4064)
			(end -0.7874 -0.4064)
			(stroke
				(width 0.1524)
				(type default)
			)
			(layer "F.SilkS")
		)
		(fp_line
			(start -0.7874 -0.4064)
			(end 0.7874 -0.4064)
			(stroke
				(width 0.1524)
				(type default)
			)
			(layer "F.SilkS")
		)
		(fp_line
			(start 0.67945 0.3048)
			(end 0.120396 0.3048)
			(stroke
				(width 0.1)
				(type default)
			)
			(layer "F.Fab")
		)
		(fp_line
			(start 0.67945 -0.3048)
			(end 0.67945 0.3048)
			(stroke
				(width 0.1)
				(type default)
			)
			(layer "F.Fab")
		)
		(fp_line
			(start 0.12065 -0.2794)
			(end 0.12065 -0.3048)
			(stroke
				(width 0.1)
				(type default)
			)
			(layer "F.Fab")
		)
		(fp_line
			(start 0.12065 -0.3048)
			(end 0.67945 -0.3048)
			(stroke
				(width 0.1)
				(type default)
			)
			(layer "F.Fab")
		)
		(fp_line
			(start 0.120396 0.3048)
			(end 0.120396 0.2794)
			(stroke
				(width 0.1)
				(type default)
			)
			(layer "F.Fab")
		)
		(fp_line
			(start 0.120396 0.2794)
			(end -0.12065 0.2794)
			(stroke
				(width 0.1)
				(type default)
			)
			(layer "F.Fab")
		)
		(fp_line
			(start -0.12065 0.3048)
			(end -0.67945 0.3048)
			(stroke
				(width 0.1)
				(type default)
			)
			(layer "F.Fab")
		)
		(fp_line
			(start -0.12065 0.2794)
			(end -0.12065 0.3048)
			(stroke
				(width 0.1)
				(type default)
			)
			(layer "F.Fab")
		)
		(fp_line
			(start -0.12065 -0.2794)
			(end 0.12065 -0.2794)
			(stroke
				(width 0.1)
				(type default)
			)
			(layer "F.Fab")
		)
		(fp_line
			(start -0.12065 -0.305054)
			(end -0.12065 -0.2794)
			(stroke
				(width 0.1)
				(type default)
			)
			(layer "F.Fab")
		)
		(fp_line
			(start -0.67945 0.3048)
			(end -0.67945 -0.305054)
			(stroke
				(width 0.1)
				(type default)
			)
			(layer "F.Fab")
		)
		(fp_line
			(start -0.67945 -0.305054)
			(end -0.12065 -0.305054)
			(stroke
				(width 0.1)
				(type default)
			)
			(layer "F.Fab")
		)
		(pad "1" smd circle
			(at -0.40005 0 180)
			(size 0 0)
			(layers "F.Cu" "F.Mask" "F.Paste")
			(net "PVDDCR_SOC_P1")
		)
		(pad "2" smd circle
			(at 0.40005 0 180)
			(size 0 0)
			(layers "F.Cu" "F.Mask" "F.Paste")
			(net "GND")
		)
	)
	(footprint ""
		(layer "F.Cu")
		(at 165.8112 -429.9712 90)
		(property "Reference" "R2705"
			(at 0 0 90)
			(layer "F.SilkS")
			(hide yes)
			(effects
				(font
					(size 1.27 1.27)
				)
			)
		)
		(property "Value" ""
			(at 0 0 90)
			(layer "F.Fab")
			(effects
				(font
					(size 1.27 1.27)
				)
			)
		)
		(duplicate_pad_numbers_are_jumpers no)
		(fp_line
			(start 0.7874 -0.4064)
			(end 0.7874 0.4064)
			(stroke
				(width 0.1524)
				(type default)
			)
			(layer "F.SilkS")
		)
		(fp_line
			(start -0.7874 -0.4064)
			(end 0.7874 -0.4064)
			(stroke
				(width 0.1524)
				(type default)
			)
			(layer "F.SilkS")
		)
		(fp_line
			(start 0.7874 0.4064)
			(end -0.7874 0.4064)
			(stroke
				(width 0.1524)
				(type default)
			)
			(layer "F.SilkS")
		)
		(fp_line
			(start -0.7874 0.4064)
			(end -0.7874 -0.4064)
			(stroke
				(width 0.1524)
				(type default)
			)
			(layer "F.SilkS")
		)
		(fp_line
			(start -0.12065 -0.305054)
			(end -0.12065 -0.2794)
			(stroke
				(width 0.1)
				(type default)
			)
			(layer "F.Fab")
		)
		(fp_line
			(start -0.67945 -0.305054)
			(end -0.12065 -0.305054)
			(stroke
				(width 0.1)
				(type default)
			)
			(layer "F.Fab")
		)
		(fp_line
			(start 0.67945 -0.3048)
			(end 0.67945 0.3048)
			(stroke
				(width 0.1)
				(type default)
			)
			(layer "F.Fab")
		)
		(fp_line
			(start 0.12065 -0.3048)
			(end 0.67945 -0.3048)
			(stroke
				(width 0.1)
				(type default)
			)
			(layer "F.Fab")
		)
		(fp_line
			(start 0.12065 -0.2794)
			(end 0.12065 -0.3048)
			(stroke
				(width 0.1)
				(type default)
			)
			(layer "F.Fab")
		)
		(fp_line
			(start -0.12065 -0.2794)
			(end 0.12065 -0.2794)
			(stroke
				(width 0.1)
				(type default)
			)
			(layer "F.Fab")
		)
		(fp_line
			(start 0.120396 0.2794)
			(end -0.12065 0.2794)
			(stroke
				(width 0.1)
				(type default)
			)
			(layer "F.Fab")
		)
		(fp_line
			(start -0.12065 0.2794)
			(end -0.12065 0.3048)
			(stroke
				(width 0.1)
				(type default)
			)
			(layer "F.Fab")
		)
		(fp_line
			(start 0.67945 0.3048)
			(end 0.120396 0.3048)
			(stroke
				(width 0.1)
				(type default)
			)
			(layer "F.Fab")
		)
		(fp_line
			(start 0.120396 0.3048)
			(end 0.120396 0.2794)
			(stroke
				(width 0.1)
				(type default)
			)
			(layer "F.Fab")
		)
		(fp_line
			(start -0.12065 0.3048)
			(end -0.67945 0.3048)
			(stroke
				(width 0.1)
				(type default)
			)
			(layer "F.Fab")
		)
		(fp_line
			(start -0.67945 0.3048)
			(end -0.67945 -0.305054)
			(stroke
				(width 0.1)
				(type default)
			)
			(layer "F.Fab")
		)
		(pad "1" smd circle
			(at -0.40005 0 90)
			(size 0 0)
			(layers "F.Cu" "F.Mask" "F.Paste")
			(net "SMB_BMC_SWB_R_SCL")
		)
		(pad "2" smd circle
			(at 0.40005 0 90)
			(size 0 0)
			(layers "F.Cu" "F.Mask" "F.Paste")
			(net "SMB_BMC_SWB_BUF_R_SCL")
		)
	)
	(footprint ""
		(layer "F.Cu")
		(at 294.421052 -119.301514)
		(property "Reference" "R3580"
			(at 0 0 0)
			(layer "F.SilkS")
			(hide yes)
			(effects
				(font
					(size 1.27 1.27)
				)
			)
		)
		(property "Value" ""
			(at 0 0 0)
			(layer "F.Fab")
			(effects
				(font
					(size 1.27 1.27)
				)
			)
		)
		(duplicate_pad_numbers_are_jumpers no)
		(fp_line
			(start -0.7874 -0.4064)
			(end 0.7874 -0.4064)
			(stroke
				(width 0.1524)
				(type default)
			)
			(layer "F.SilkS")
		)
		(fp_line
			(start -0.7874 0.4064)
			(end -0.7874 -0.4064)
			(stroke
				(width 0.1524)
				(type default)
			)
			(layer "F.SilkS")
		)
		(fp_line
			(start 0.7874 -0.4064)
			(end 0.7874 0.4064)
			(stroke
				(width 0.1524)
				(type default)
			)
			(layer "F.SilkS")
		)
		(fp_line
			(start 0.7874 0.4064)
			(end -0.7874 0.4064)
			(stroke
				(width 0.1524)
				(type default)
			)
			(layer "F.SilkS")
		)
		(fp_line
			(start -0.67945 -0.305054)
			(end -0.12065 -0.305054)
			(stroke
				(width 0.1)
				(type default)
			)
			(layer "F.Fab")
		)
		(fp_line
			(start -0.67945 0.3048)
			(end -0.67945 -0.305054)
			(stroke
				(width 0.1)
				(type default)
			)
			(layer "F.Fab")
		)
		(fp_line
			(start -0.12065 -0.305054)
			(end -0.12065 -0.2794)
			(stroke
				(width 0.1)
				(type default)
			)
			(layer "F.Fab")
		)
		(fp_line
			(start -0.12065 -0.2794)
			(end 0.12065 -0.2794)
			(stroke
				(width 0.1)
				(type default)
			)
			(layer "F.Fab")
		)
		(fp_line
			(start -0.12065 0.2794)
			(end -0.12065 0.3048)
			(stroke
				(width 0.1)
				(type default)
			)
			(layer "F.Fab")
		)
		(fp_line
			(start -0.12065 0.3048)
			(end -0.67945 0.3048)
			(stroke
				(width 0.1)
				(type default)
			)
			(layer "F.Fab")
		)
		(fp_line
			(start 0.120396 0.2794)
			(end -0.12065 0.2794)
			(stroke
				(width 0.1)
				(type default)
			)
			(layer "F.Fab")
		)
		(fp_line
			(start 0.120396 0.3048)
			(end 0.120396 0.2794)
			(stroke
				(width 0.1)
				(type default)
			)
			(layer "F.Fab")
		)
		(fp_line
			(start 0.12065 -0.3048)
			(end 0.67945 -0.3048)
			(stroke
				(width 0.1)
				(type default)
			)
			(layer "F.Fab")
		)
		(fp_line
			(start 0.12065 -0.2794)
			(end 0.12065 -0.3048)
			(stroke
				(width 0.1)
				(type default)
			)
			(layer "F.Fab")
		)
		(fp_line
			(start 0.67945 -0.3048)
			(end 0.67945 0.3048)
			(stroke
				(width 0.1)
				(type default)
			)
			(layer "F.Fab")
		)
		(fp_line
			(start 0.67945 0.3048)
			(end 0.120396 0.3048)
			(stroke
				(width 0.1)
				(type default)
			)
			(layer "F.Fab")
		)
		(pad "1" smd circle
			(at -0.40005 0)
			(size 0 0)
			(layers "F.Cu" "F.Mask" "F.Paste")
			(net "SMB_INA230_3V3AUX_SCL_R")
		)
		(pad "2" smd circle
			(at 0.40005 0)
			(size 0 0)
			(layers "F.Cu" "F.Mask" "F.Paste")
			(net "SMB_INA230_3V3AUX_SCL")
		)
	)
	(footprint ""
		(layer "F.Cu")
		(at 176.528984 -147.086574 90)
		(property "Reference" "R493"
			(at 0 0 90)
			(layer "F.SilkS")
			(hide yes)
			(effects
				(font
					(size 1.27 1.27)
				)
			)
		)
		(property "Value" ""
			(at 0 0 90)
			(layer "F.Fab")
			(effects
				(font
					(size 1.27 1.27)
				)
			)
		)
		(duplicate_pad_numbers_are_jumpers no)
		(fp_line
			(start 0.7874 -0.4064)
			(end 0.7874 0.4064)
			(stroke
				(width 0.1524)
				(type default)
			)
			(layer "F.SilkS")
		)
		(fp_line
			(start -0.7874 -0.4064)
			(end 0.7874 -0.4064)
			(stroke
				(width 0.1524)
				(type default)
			)
			(layer "F.SilkS")
		)
		(fp_line
			(start 0.7874 0.4064)
			(end -0.7874 0.4064)
			(stroke
				(width 0.1524)
				(type default)
			)
			(layer "F.SilkS")
		)
		(fp_line
			(start -0.7874 0.4064)
			(end -0.7874 -0.4064)
			(stroke
				(width 0.1524)
				(type default)
			)
			(layer "F.SilkS")
		)
		(fp_line
			(start -0.12065 -0.305054)
			(end -0.12065 -0.2794)
			(stroke
				(width 0.1)
				(type default)
			)
			(layer "F.Fab")
		)
		(fp_line
			(start -0.67945 -0.305054)
			(end -0.12065 -0.305054)
			(stroke
				(width 0.1)
				(type default)
			)
			(layer "F.Fab")
		)
		(fp_line
			(start 0.67945 -0.3048)
			(end 0.67945 0.3048)
			(stroke
				(width 0.1)
				(type default)
			)
			(layer "F.Fab")
		)
		(fp_line
			(start 0.12065 -0.3048)
			(end 0.67945 -0.3048)
			(stroke
				(width 0.1)
				(type default)
			)
			(layer "F.Fab")
		)
		(fp_line
			(start 0.12065 -0.2794)
			(end 0.12065 -0.3048)
			(stroke
				(width 0.1)
				(type default)
			)
			(layer "F.Fab")
		)
		(fp_line
			(start -0.12065 -0.2794)
			(end 0.12065 -0.2794)
			(stroke
				(width 0.1)
				(type default)
			)
			(layer "F.Fab")
		)
		(fp_line
			(start 0.120396 0.2794)
			(end -0.12065 0.2794)
			(stroke
				(width 0.1)
				(type default)
			)
			(layer "F.Fab")
		)
		(fp_line
			(start -0.12065 0.2794)
			(end -0.12065 0.3048)
			(stroke
				(width 0.1)
				(type default)
			)
			(layer "F.Fab")
		)
		(fp_line
			(start 0.67945 0.3048)
			(end 0.120396 0.3048)
			(stroke
				(width 0.1)
				(type default)
			)
			(layer "F.Fab")
		)
		(fp_line
			(start 0.120396 0.3048)
			(end 0.120396 0.2794)
			(stroke
				(width 0.1)
				(type default)
			)
			(layer "F.Fab")
		)
		(fp_line
			(start -0.12065 0.3048)
			(end -0.67945 0.3048)
			(stroke
				(width 0.1)
				(type default)
			)
			(layer "F.Fab")
		)
		(fp_line
			(start -0.67945 0.3048)
			(end -0.67945 -0.305054)
			(stroke
				(width 0.1)
				(type default)
			)
			(layer "F.Fab")
		)
		(pad "1" smd circle
			(at -0.40005 0 90)
			(size 0 0)
			(layers "F.Cu" "F.Mask" "F.Paste")
			(net "SMB_CPU0_4_XLTR_R_SDA")
		)
		(pad "2" smd circle
			(at 0.40005 0 90)
			(size 0 0)
			(layers "F.Cu" "F.Mask" "F.Paste")
			(net "SMB_CPU0_4_XLTR_SDA")
		)
	)
	(footprint ""
		(layer "F.Cu")
		(at 178.71694 -401.452842)
		(property "Reference" "PR3002"
			(at 0 0 0)
			(layer "F.SilkS")
			(hide yes)
			(effects
				(font
					(size 1.27 1.27)
				)
			)
		)
		(property "Value" ""
			(at 0 0 0)
			(layer "F.Fab")
			(effects
				(font
					(size 1.27 1.27)
				)
			)
		)
		(duplicate_pad_numbers_are_jumpers no)
		(fp_line
			(start -0.7874 -0.4064)
			(end 0.7874 -0.4064)
			(stroke
				(width 0.1524)
				(type default)
			)
			(layer "F.SilkS")
		)
		(fp_line
			(start -0.7874 0.4064)
			(end -0.7874 -0.4064)
			(stroke
				(width 0.1524)
				(type default)
			)
			(layer "F.SilkS")
		)
		(fp_line
			(start 0.7874 -0.4064)
			(end 0.7874 0.4064)
			(stroke
				(width 0.1524)
				(type default)
			)
			(layer "F.SilkS")
		)
		(fp_line
			(start 0.7874 0.4064)
			(end -0.7874 0.4064)
			(stroke
				(width 0.1524)
				(type default)
			)
			(layer "F.SilkS")
		)
		(fp_line
			(start -0.67945 -0.305054)
			(end -0.12065 -0.305054)
			(stroke
				(width 0.1)
				(type default)
			)
			(layer "F.Fab")
		)
		(fp_line
			(start -0.67945 0.3048)
			(end -0.67945 -0.305054)
			(stroke
				(width 0.1)
				(type default)
			)
			(layer "F.Fab")
		)
		(fp_line
			(start -0.12065 -0.305054)
			(end -0.12065 -0.2794)
			(stroke
				(width 0.1)
				(type default)
			)
			(layer "F.Fab")
		)
		(fp_line
			(start -0.12065 -0.2794)
			(end 0.12065 -0.2794)
			(stroke
				(width 0.1)
				(type default)
			)
			(layer "F.Fab")
		)
		(fp_line
			(start -0.12065 0.2794)
			(end -0.12065 0.3048)
			(stroke
				(width 0.1)
				(type default)
			)
			(layer "F.Fab")
		)
		(fp_line
			(start -0.12065 0.3048)
			(end -0.67945 0.3048)
			(stroke
				(width 0.1)
				(type default)
			)
			(layer "F.Fab")
		)
		(fp_line
			(start 0.120396 0.2794)
			(end -0.12065 0.2794)
			(stroke
				(width 0.1)
				(type default)
			)
			(layer "F.Fab")
		)
		(fp_line
			(start 0.120396 0.3048)
			(end 0.120396 0.2794)
			(stroke
				(width 0.1)
				(type default)
			)
			(layer "F.Fab")
		)
		(fp_line
			(start 0.12065 -0.3048)
			(end 0.67945 -0.3048)
			(stroke
				(width 0.1)
				(type default)
			)
			(layer "F.Fab")
		)
		(fp_line
			(start 0.12065 -0.2794)
			(end 0.12065 -0.3048)
			(stroke
				(width 0.1)
				(type default)
			)
			(layer "F.Fab")
		)
		(fp_line
			(start 0.67945 -0.3048)
			(end 0.67945 0.3048)
			(stroke
				(width 0.1)
				(type default)
			)
			(layer "F.Fab")
		)
		(fp_line
			(start 0.67945 0.3048)
			(end 0.120396 0.3048)
			(stroke
				(width 0.1)
				(type default)
			)
			(layer "F.Fab")
		)
		(pad "1" smd circle
			(at -0.40005 0)
			(size 0 0)
			(layers "F.Cu" "F.Mask" "F.Paste")
			(net "GND")
		)
		(pad "2" smd circle
			(at 0.40005 0)
			(size 0 0)
			(layers "F.Cu" "F.Mask" "F.Paste")
			(net "AGND_HSC")
		)
	)
	(footprint ""
		(layer "F.Cu")
		(at 29.35986 -351.372932 90)
		(property "Reference" "PR372"
			(at 0 0 90)
			(layer "F.SilkS")
			(hide yes)
			(effects
				(font
					(size 1.27 1.27)
				)
			)
		)
		(property "Value" ""
			(at 0 0 90)
			(layer "F.Fab")
			(effects
				(font
					(size 1.27 1.27)
				)
			)
		)
		(duplicate_pad_numbers_are_jumpers no)
		(fp_line
			(start 0.7874 -0.4064)
			(end 0.7874 0.4064)
			(stroke
				(width 0.1524)
				(type default)
			)
			(layer "F.SilkS")
		)
		(fp_line
			(start -0.7874 -0.4064)
			(end 0.7874 -0.4064)
			(stroke
				(width 0.1524)
				(type default)
			)
			(layer "F.SilkS")
		)
		(fp_line
			(start 0.7874 0.4064)
			(end -0.7874 0.4064)
			(stroke
				(width 0.1524)
				(type default)
			)
			(layer "F.SilkS")
		)
		(fp_line
			(start -0.7874 0.4064)
			(end -0.7874 -0.4064)
			(stroke
				(width 0.1524)
				(type default)
			)
			(layer "F.SilkS")
		)
		(fp_line
			(start -0.12065 -0.305054)
			(end -0.12065 -0.2794)
			(stroke
				(width 0.1)
				(type default)
			)
			(layer "F.Fab")
		)
		(fp_line
			(start -0.67945 -0.305054)
			(end -0.12065 -0.305054)
			(stroke
				(width 0.1)
				(type default)
			)
			(layer "F.Fab")
		)
		(fp_line
			(start 0.67945 -0.3048)
			(end 0.67945 0.3048)
			(stroke
				(width 0.1)
				(type default)
			)
			(layer "F.Fab")
		)
		(fp_line
			(start 0.12065 -0.3048)
			(end 0.67945 -0.3048)
			(stroke
				(width 0.1)
				(type default)
			)
			(layer "F.Fab")
		)
		(fp_line
			(start 0.12065 -0.2794)
			(end 0.12065 -0.3048)
			(stroke
				(width 0.1)
				(type default)
			)
			(layer "F.Fab")
		)
		(fp_line
			(start -0.12065 -0.2794)
			(end 0.12065 -0.2794)
			(stroke
				(width 0.1)
				(type default)
			)
			(layer "F.Fab")
		)
		(fp_line
			(start 0.120396 0.2794)
			(end -0.12065 0.2794)
			(stroke
				(width 0.1)
				(type default)
			)
			(layer "F.Fab")
		)
		(fp_line
			(start -0.12065 0.2794)
			(end -0.12065 0.3048)
			(stroke
				(width 0.1)
				(type default)
			)
			(layer "F.Fab")
		)
		(fp_line
			(start 0.67945 0.3048)
			(end 0.120396 0.3048)
			(stroke
				(width 0.1)
				(type default)
			)
			(layer "F.Fab")
		)
		(fp_line
			(start 0.120396 0.3048)
			(end 0.120396 0.2794)
			(stroke
				(width 0.1)
				(type default)
			)
			(layer "F.Fab")
		)
		(fp_line
			(start -0.12065 0.3048)
			(end -0.67945 0.3048)
			(stroke
				(width 0.1)
				(type default)
			)
			(layer "F.Fab")
		)
		(fp_line
			(start -0.67945 0.3048)
			(end -0.67945 -0.305054)
			(stroke
				(width 0.1)
				(type default)
			)
			(layer "F.Fab")
		)
		(pad "1" smd circle
			(at -0.40005 0 90)
			(size 0 0)
			(layers "F.Cu" "F.Mask" "F.Paste")
			(net "SW_PVDDIO_P1_BOOT4")
		)
		(pad "2" smd circle
			(at 0.40005 0 90)
			(size 0 0)
			(layers "F.Cu" "F.Mask" "F.Paste")
			(net "SW_PVDDIO_P1_BOOT4_R")
		)
	)
	(footprint ""
		(layer "F.Cu")
		(at 109.095794 -385.48056)
		(property "Reference" "R915"
			(at 0 0 0)
			(layer "F.SilkS")
			(hide yes)
			(effects
				(font
					(size 1.27 1.27)
				)
			)
		)
		(property "Value" ""
			(at 0 0 0)
			(layer "F.Fab")
			(effects
				(font
					(size 1.27 1.27)
				)
			)
		)
		(duplicate_pad_numbers_are_jumpers no)
		(fp_line
			(start -0.32512 -0.175006)
			(end 0.32512 -0.175006)
			(stroke
				(width 0.1)
				(type default)
			)
			(layer "F.Fab")
		)
		(fp_line
			(start -0.32512 0.175006)
			(end -0.32512 -0.175006)
			(stroke
				(width 0.1)
				(type default)
			)
			(layer "F.Fab")
		)
		(fp_line
			(start 0.32512 -0.175006)
			(end 0.32512 0.175006)
			(stroke
				(width 0.1)
				(type default)
			)
			(layer "F.Fab")
		)
		(fp_line
			(start 0.32512 0.175006)
			(end -0.32512 0.175006)
			(stroke
				(width 0.1)
				(type default)
			)
			(layer "F.Fab")
		)
		(pad "1" smd rect
			(at -0.2667 0)
			(size 0.3048 0.381)
			(layers "F.Cu" "F.Mask" "F.Paste")
			(net "P1V8_CPU1_RT_1D")
		)
		(pad "2" smd rect
			(at 0.2667 0 180)
			(size 0.3048 0.381)
			(layers "F.Cu" "F.Mask" "F.Paste")
			(net "GPIO2_RT_CPU1_P3")
		)
	)
	(footprint ""
		(layer "F.Cu")
		(at 112.597946 -52.86248 -90)
		(property "Reference" "R6299"
			(at 0 0 270)
			(layer "F.SilkS")
			(hide yes)
			(effects
				(font
					(size 1.27 1.27)
				)
			)
		)
		(property "Value" ""
			(at 0 0 270)
			(layer "F.Fab")
			(effects
				(font
					(size 1.27 1.27)
				)
			)
		)
		(duplicate_pad_numbers_are_jumpers no)
		(fp_line
			(start -0.7874 0.4064)
			(end -0.7874 -0.4064)
			(stroke
				(width 0.1524)
				(type default)
			)
			(layer "F.SilkS")
		)
		(fp_line
			(start 0.7874 0.4064)
			(end -0.7874 0.4064)
			(stroke
				(width 0.1524)
				(type default)
			)
			(layer "F.SilkS")
		)
		(fp_line
			(start -0.7874 -0.4064)
			(end 0.7874 -0.4064)
			(stroke
				(width 0.1524)
				(type default)
			)
			(layer "F.SilkS")
		)
		(fp_line
			(start 0.7874 -0.4064)
			(end 0.7874 0.4064)
			(stroke
				(width 0.1524)
				(type default)
			)
			(layer "F.SilkS")
		)
		(fp_line
			(start -0.67945 0.3048)
			(end -0.67945 -0.305054)
			(stroke
				(width 0.1)
				(type default)
			)
			(layer "F.Fab")
		)
		(fp_line
			(start -0.12065 0.3048)
			(end -0.67945 0.3048)
			(stroke
				(width 0.1)
				(type default)
			)
			(layer "F.Fab")
		)
		(fp_line
			(start 0.120396 0.3048)
			(end 0.120396 0.2794)
			(stroke
				(width 0.1)
				(type default)
			)
			(layer "F.Fab")
		)
		(fp_line
			(start 0.67945 0.3048)
			(end 0.120396 0.3048)
			(stroke
				(width 0.1)
				(type default)
			)
			(layer "F.Fab")
		)
		(fp_line
			(start -0.12065 0.2794)
			(end -0.12065 0.3048)
			(stroke
				(width 0.1)
				(type default)
			)
			(layer "F.Fab")
		)
		(fp_line
			(start 0.120396 0.2794)
			(end -0.12065 0.2794)
			(stroke
				(width 0.1)
				(type default)
			)
			(layer "F.Fab")
		)
		(fp_line
			(start -0.12065 -0.2794)
			(end 0.12065 -0.2794)
			(stroke
				(width 0.1)
				(type default)
			)
			(layer "F.Fab")
		)
		(fp_line
			(start 0.12065 -0.2794)
			(end 0.12065 -0.3048)
			(stroke
				(width 0.1)
				(type default)
			)
			(layer "F.Fab")
		)
		(fp_line
			(start 0.12065 -0.3048)
			(end 0.67945 -0.3048)
			(stroke
				(width 0.1)
				(type default)
			)
			(layer "F.Fab")
		)
		(fp_line
			(start 0.67945 -0.3048)
			(end 0.67945 0.3048)
			(stroke
				(width 0.1)
				(type default)
			)
			(layer "F.Fab")
		)
		(fp_line
			(start -0.67945 -0.305054)
			(end -0.12065 -0.305054)
			(stroke
				(width 0.1)
				(type default)
			)
			(layer "F.Fab")
		)
		(fp_line
			(start -0.12065 -0.305054)
			(end -0.12065 -0.2794)
			(stroke
				(width 0.1)
				(type default)
			)
			(layer "F.Fab")
		)
		(pad "1" smd circle
			(at -0.40005 0 270)
			(size 0 0)
			(layers "F.Cu" "F.Mask" "F.Paste")
			(net "USB_HUB2_TI_OVERCUR3")
		)
		(pad "2" smd circle
			(at 0.40005 0 270)
			(size 0 0)
			(layers "F.Cu" "F.Mask" "F.Paste")
			(net "USB_HUB2_TI_OVERCUR3_MRP_CFG_BC_EN")
		)
	)
	(footprint ""
		(layer "F.Cu")
		(at 353.38004 -44.250102 -90)
		(property "Reference" "J212"
			(at -3.273298 4.965192 0)
			(unlocked yes)
			(layer "F.SilkS")
			(effects
				(font
					(size 0.7874 0.5842)
					(thickness 0.1524)
				)
				(justify left)
			)
		)
		(property "Value" ""
			(at 0 0 270)
			(layer "F.Fab")
			(effects
				(font
					(size 1.27 1.27)
				)
			)
		)
		(duplicate_pad_numbers_are_jumpers no)
		(fp_line
			(start -1.219962 11.495024)
			(end 3.759962 11.495024)
			(stroke
				(width 0.1524)
				(type default)
			)
			(layer "F.SilkS")
		)
		(fp_line
			(start 3.759962 11.495024)
			(end 3.759962 -1.335024)
			(stroke
				(width 0.1524)
				(type default)
			)
			(layer "F.SilkS")
		)
		(fp_line
			(start -1.219962 -1.335024)
			(end -1.219962 11.495024)
			(stroke
				(width 0.1524)
				(type default)
			)
			(layer "F.SilkS")
		)
		(fp_line
			(start 3.759962 -1.335024)
			(end -1.219962 -1.335024)
			(stroke
				(width 0.1524)
				(type default)
			)
			(layer "F.SilkS")
		)
		(fp_poly
			(pts
				(xy -2.5146 -0.508) (xy -2.5146 0.508) (xy -1.4986 0)
			)
			(stroke
				(width 0)
				(type default)
			)
			(fill yes)
			(layer "F.SilkS")
		)
		(fp_line
			(start -1.219962 11.495024)
			(end 3.759962 11.495024)
			(stroke
				(width 0.1)
				(type default)
			)
			(layer "F.Fab")
		)
		(fp_line
			(start 3.759962 11.495024)
			(end 3.759962 -1.335024)
			(stroke
				(width 0.1)
				(type default)
			)
			(layer "F.Fab")
		)
		(fp_line
			(start -1.219962 -1.335024)
			(end -1.219962 11.495024)
			(stroke
				(width 0.1)
				(type default)
			)
			(layer "F.Fab")
		)
		(fp_line
			(start 3.759962 -1.335024)
			(end -1.219962 -1.335024)
			(stroke
				(width 0.1)
				(type default)
			)
			(layer "F.Fab")
		)
		(fp_poly
			(pts
				(xy -2.5146 -0.508) (xy -2.5146 0.508) (xy -1.4986 0)
			)
			(stroke
				(width 0)
				(type default)
			)
			(fill yes)
			(layer "F.Fab")
		)
		(pad "1" thru_hole rect
			(at 0 0 270)
			(size 1.6256 1.6256)
			(drill 1.1176)
			(layers "*.Cu" "*.Mask")
			(remove_unused_layers no)
			(net "CPU0_XTRIG_L4")
			(clearance 0)
			(padstack
				(mode front_inner_back)
				(layer "Inner"
					(shape circle)
					(size 1.6256 1.6256)
					(clearance 0)
				)
				(layer "B.Cu"
					(shape rect)
					(size 1.6256 1.6256)
					(clearance 0)
				)
			)
		)
		(pad "2" thru_hole circle
			(at 2.54 0 270)
			(size 1.6256 1.6256)
			(drill 1.1176)
			(layers "*.Cu" "*.Mask")
			(remove_unused_layers no)
			(net "CPU1_XTRIG_L4")
			(clearance 0)
		)
		(pad "3" thru_hole circle
			(at 0 2.54 270)
			(size 1.6256 1.6256)
			(drill 1.1176)
			(layers "*.Cu" "*.Mask")
			(remove_unused_layers no)
			(net "CPU0_XTRIG_L5")
			(clearance 0)
		)
		(pad "4" thru_hole circle
			(at 2.54 2.54 270)
			(size 1.6256 1.6256)
			(drill 1.1176)
			(layers "*.Cu" "*.Mask")
			(remove_unused_layers no)
			(net "CPU1_XTRIG_L5")
			(clearance 0)
		)
		(pad "5" thru_hole circle
			(at 0 5.08 270)
			(size 1.6256 1.6256)
			(drill 1.1176)
			(layers "*.Cu" "*.Mask")
			(remove_unused_layers no)
			(net "CPU0_XTRIG_L6")
			(clearance 0)
		)
		(pad "6" thru_hole circle
			(at 2.54 5.08 270)
			(size 1.6256 1.6256)
			(drill 1.1176)
			(layers "*.Cu" "*.Mask")
			(remove_unused_layers no)
			(net "CPU1_XTRIG_L6")
			(clearance 0)
		)
		(pad "7" thru_hole circle
			(at 0 7.62 270)
			(size 1.6256 1.6256)
			(drill 1.1176)
			(layers "*.Cu" "*.Mask")
			(remove_unused_layers no)
			(net "CPU0_XTRIG_L7")
			(clearance 0)
		)
		(pad "8" thru_hole circle
			(at 2.54 7.62 270)
			(size 1.6256 1.6256)
			(drill 1.1176)
			(layers "*.Cu" "*.Mask")
			(remove_unused_layers no)
			(net "CPU1_XTRIG_L7")
			(clearance 0)
		)
		(pad "9" thru_hole circle
			(at 0 10.16 270)
			(size 1.6256 1.6256)
			(drill 1.1176)
			(layers "*.Cu" "*.Mask")
			(remove_unused_layers no)
			(net "Net_1766")
			(clearance 0)
		)
		(pad "10" thru_hole circle
			(at 2.54 10.16 270)
			(size 1.6256 1.6256)
			(drill 1.1176)
			(layers "*.Cu" "*.Mask")
			(remove_unused_layers no)
			(net "Net_1765")
			(clearance 0)
		)
	)
	(footprint ""
		(layer "F.Cu")
		(at 32.336994 -133.83895 180)
		(property "Reference" "U248"
			(at 1.415288 -2.52349 0)
			(unlocked yes)
			(layer "F.SilkS")
			(effects
				(font
					(size 0.7874 0.5842)
					(thickness 0.1524)
				)
				(justify left)
			)
		)
		(property "Value" ""
			(at 0 0 180)
			(layer "F.Fab")
			(effects
				(font
					(size 1.27 1.27)
				)
			)
		)
		(duplicate_pad_numbers_are_jumpers no)
		(fp_line
			(start 1.4986 1.100074)
			(end -1.4986 1.100074)
			(stroke
				(width 0.1524)
				(type default)
			)
			(layer "F.SilkS")
		)
		(fp_line
			(start 1.4986 -1.100074)
			(end 1.4986 1.100074)
			(stroke
				(width 0.1524)
				(type default)
			)
			(layer "F.SilkS")
		)
		(fp_line
			(start -1.4986 1.100074)
			(end -1.4986 -1.100074)
			(stroke
				(width 0.1524)
				(type default)
			)
			(layer "F.SilkS")
		)
		(fp_line
			(start -1.4986 -1.100074)
			(end 1.4986 -1.100074)
			(stroke
				(width 0.1524)
				(type default)
			)
			(layer "F.SilkS")
		)
		(fp_poly
			(pts
				(xy -0.956056 -1.274064) (xy -1.252728 -1.827784) (xy -0.627888 -1.827784)
			)
			(stroke
				(width 0)
				(type default)
			)
			(fill yes)
			(layer "F.SilkS")
		)
		(fp_line
			(start 0.67437 1.100074)
			(end -0.67437 1.100074)
			(stroke
				(width 0.1)
				(type default)
			)
			(layer "F.Fab")
		)
		(fp_line
			(start 0.67437 -1.100074)
			(end 0.67437 1.100074)
			(stroke
				(width 0.1)
				(type default)
			)
			(layer "F.Fab")
		)
		(fp_line
			(start -0.67437 1.100074)
			(end -0.67437 -1.100074)
			(stroke
				(width 0.1)
				(type default)
			)
			(layer "F.Fab")
		)
		(fp_line
			(start -0.67437 -1.100074)
			(end 0.67437 -1.100074)
			(stroke
				(width 0.1)
				(type default)
			)
			(layer "F.Fab")
		)
		(fp_poly
			(pts
				(xy -2.20472 -0.338328) (xy -2.20472 -0.963168) (xy -1.651 -0.635)
			)
			(stroke
				(width 0)
				(type default)
			)
			(fill yes)
			(layer "F.Fab")
		)
		(pad "1" smd rect
			(at -0.889 -0.649986 180)
			(size 1.016 0.381)
			(layers "F.Cu" "F.Mask" "F.Paste")
			(net "GPU_FPGA_READY_R_N")
		)
		(pad "2" smd rect
			(at -0.889 0 180)
			(size 1.016 0.381)
			(layers "F.Cu" "F.Mask" "F.Paste")
			(net "CLK_GEN2_GPU_FPGA_OE_R2_N")
		)
		(pad "3" smd rect
			(at -0.889 0.649986 180)
			(size 1.016 0.381)
			(layers "F.Cu" "F.Mask" "F.Paste")
			(net "GND")
		)
		(pad "4" smd rect
			(at 0.889 0.649986 180)
			(size 1.016 0.381)
			(layers "F.Cu" "F.Mask" "F.Paste")
			(net "CLK_GEN2_GPU_FPGA_OE_OR_N")
		)
		(pad "5" smd rect
			(at 0.889 -0.649986 180)
			(size 1.016 0.381)
			(layers "F.Cu" "F.Mask" "F.Paste")
			(net "P3V3_AUX")
		)
	)
	(footprint ""
		(layer "F.Cu")
		(at 103.170736 -127.787654 -90)
		(property "Reference" "R1442"
			(at 0 0 270)
			(layer "F.SilkS")
			(hide yes)
			(effects
				(font
					(size 1.27 1.27)
				)
			)
		)
		(property "Value" ""
			(at 0 0 270)
			(layer "F.Fab")
			(effects
				(font
					(size 1.27 1.27)
				)
			)
		)
		(duplicate_pad_numbers_are_jumpers no)
		(fp_line
			(start -0.7874 0.4064)
			(end -0.7874 -0.4064)
			(stroke
				(width 0.1524)
				(type default)
			)
			(layer "F.SilkS")
		)
		(fp_line
			(start 0.7874 0.4064)
			(end -0.7874 0.4064)
			(stroke
				(width 0.1524)
				(type default)
			)
			(layer "F.SilkS")
		)
		(fp_line
			(start -0.7874 -0.4064)
			(end 0.7874 -0.4064)
			(stroke
				(width 0.1524)
				(type default)
			)
			(layer "F.SilkS")
		)
		(fp_line
			(start 0.7874 -0.4064)
			(end 0.7874 0.4064)
			(stroke
				(width 0.1524)
				(type default)
			)
			(layer "F.SilkS")
		)
		(fp_line
			(start -0.67945 0.3048)
			(end -0.67945 -0.305054)
			(stroke
				(width 0.1)
				(type default)
			)
			(layer "F.Fab")
		)
		(fp_line
			(start -0.12065 0.3048)
			(end -0.67945 0.3048)
			(stroke
				(width 0.1)
				(type default)
			)
			(layer "F.Fab")
		)
		(fp_line
			(start 0.120396 0.3048)
			(end 0.120396 0.2794)
			(stroke
				(width 0.1)
				(type default)
			)
			(layer "F.Fab")
		)
		(fp_line
			(start 0.67945 0.3048)
			(end 0.120396 0.3048)
			(stroke
				(width 0.1)
				(type default)
			)
			(layer "F.Fab")
		)
		(fp_line
			(start -0.12065 0.2794)
			(end -0.12065 0.3048)
			(stroke
				(width 0.1)
				(type default)
			)
			(layer "F.Fab")
		)
		(fp_line
			(start 0.120396 0.2794)
			(end -0.12065 0.2794)
			(stroke
				(width 0.1)
				(type default)
			)
			(layer "F.Fab")
		)
		(fp_line
			(start -0.12065 -0.2794)
			(end 0.12065 -0.2794)
			(stroke
				(width 0.1)
				(type default)
			)
			(layer "F.Fab")
		)
		(fp_line
			(start 0.12065 -0.2794)
			(end 0.12065 -0.3048)
			(stroke
				(width 0.1)
				(type default)
			)
			(layer "F.Fab")
		)
		(fp_line
			(start 0.12065 -0.3048)
			(end 0.67945 -0.3048)
			(stroke
				(width 0.1)
				(type default)
			)
			(layer "F.Fab")
		)
		(fp_line
			(start 0.67945 -0.3048)
			(end 0.67945 0.3048)
			(stroke
				(width 0.1)
				(type default)
			)
			(layer "F.Fab")
		)
		(fp_line
			(start -0.67945 -0.305054)
			(end -0.12065 -0.305054)
			(stroke
				(width 0.1)
				(type default)
			)
			(layer "F.Fab")
		)
		(fp_line
			(start -0.12065 -0.305054)
			(end -0.12065 -0.2794)
			(stroke
				(width 0.1)
				(type default)
			)
			(layer "F.Fab")
		)
		(pad "1" smd circle
			(at -0.40005 0 270)
			(size 0 0)
			(layers "F.Cu" "F.Mask" "F.Paste")
			(net "P12V_MEM_CPU0")
		)
		(pad "2" smd circle
			(at 0.40005 0 270)
			(size 0 0)
			(layers "F.Cu" "F.Mask" "F.Paste")
			(net "PWRGD_P12V_MEM_CPU0_EN")
		)
	)
	(footprint ""
		(layer "F.Cu")
		(at 34.665158 -173.55566)
		(property "Reference" "R1294"
			(at 0 0 0)
			(layer "F.SilkS")
			(hide yes)
			(effects
				(font
					(size 1.27 1.27)
				)
			)
		)
		(property "Value" ""
			(at 0 0 0)
			(layer "F.Fab")
			(effects
				(font
					(size 1.27 1.27)
				)
			)
		)
		(duplicate_pad_numbers_are_jumpers no)
		(fp_line
			(start -0.7874 -0.4064)
			(end 0.7874 -0.4064)
			(stroke
				(width 0.1524)
				(type default)
			)
			(layer "F.SilkS")
		)
		(fp_line
			(start -0.7874 0.4064)
			(end -0.7874 -0.4064)
			(stroke
				(width 0.1524)
				(type default)
			)
			(layer "F.SilkS")
		)
		(fp_line
			(start 0.7874 -0.4064)
			(end 0.7874 0.4064)
			(stroke
				(width 0.1524)
				(type default)
			)
			(layer "F.SilkS")
		)
		(fp_line
			(start 0.7874 0.4064)
			(end -0.7874 0.4064)
			(stroke
				(width 0.1524)
				(type default)
			)
			(layer "F.SilkS")
		)
		(fp_line
			(start -0.67945 -0.305054)
			(end -0.12065 -0.305054)
			(stroke
				(width 0.1)
				(type default)
			)
			(layer "F.Fab")
		)
		(fp_line
			(start -0.67945 0.3048)
			(end -0.67945 -0.305054)
			(stroke
				(width 0.1)
				(type default)
			)
			(layer "F.Fab")
		)
		(fp_line
			(start -0.12065 -0.305054)
			(end -0.12065 -0.2794)
			(stroke
				(width 0.1)
				(type default)
			)
			(layer "F.Fab")
		)
		(fp_line
			(start -0.12065 -0.2794)
			(end 0.12065 -0.2794)
			(stroke
				(width 0.1)
				(type default)
			)
			(layer "F.Fab")
		)
		(fp_line
			(start -0.12065 0.2794)
			(end -0.12065 0.3048)
			(stroke
				(width 0.1)
				(type default)
			)
			(layer "F.Fab")
		)
		(fp_line
			(start -0.12065 0.3048)
			(end -0.67945 0.3048)
			(stroke
				(width 0.1)
				(type default)
			)
			(layer "F.Fab")
		)
		(fp_line
			(start 0.120396 0.2794)
			(end -0.12065 0.2794)
			(stroke
				(width 0.1)
				(type default)
			)
			(layer "F.Fab")
		)
		(fp_line
			(start 0.120396 0.3048)
			(end 0.120396 0.2794)
			(stroke
				(width 0.1)
				(type default)
			)
			(layer "F.Fab")
		)
		(fp_line
			(start 0.12065 -0.3048)
			(end 0.67945 -0.3048)
			(stroke
				(width 0.1)
				(type default)
			)
			(layer "F.Fab")
		)
		(fp_line
			(start 0.12065 -0.2794)
			(end 0.12065 -0.3048)
			(stroke
				(width 0.1)
				(type default)
			)
			(layer "F.Fab")
		)
		(fp_line
			(start 0.67945 -0.3048)
			(end 0.67945 0.3048)
			(stroke
				(width 0.1)
				(type default)
			)
			(layer "F.Fab")
		)
		(fp_line
			(start 0.67945 0.3048)
			(end 0.120396 0.3048)
			(stroke
				(width 0.1)
				(type default)
			)
			(layer "F.Fab")
		)
		(pad "1" smd rect
			(at -0.40005 0 180)
			(size 0.4572 0.508)
			(layers "F.Cu" "F.Mask" "F.Paste")
			(net "I3C_SPD_DDRAF_CPU1_SDA")
		)
		(pad "2" smd rect
			(at 0.40005 0 180)
			(size 0.4572 0.508)
			(layers "F.Cu" "F.Mask" "F.Paste")
			(net "I3C_SPD_DDRAF_CPU1_LVC1_SDA")
		)
	)
	(footprint ""
		(layer "F.Cu")
		(at 69.457824 -18.932144)
		(property "Reference" "R1302"
			(at 0 0 0)
			(layer "F.SilkS")
			(hide yes)
			(effects
				(font
					(size 1.27 1.27)
				)
			)
		)
		(property "Value" ""
			(at 0 0 0)
			(layer "F.Fab")
			(effects
				(font
					(size 1.27 1.27)
				)
			)
		)
		(duplicate_pad_numbers_are_jumpers no)
		(fp_line
			(start -0.7874 -0.4064)
			(end 0.7874 -0.4064)
			(stroke
				(width 0.1524)
				(type default)
			)
			(layer "F.SilkS")
		)
		(fp_line
			(start -0.7874 0.4064)
			(end -0.7874 -0.4064)
			(stroke
				(width 0.1524)
				(type default)
			)
			(layer "F.SilkS")
		)
		(fp_line
			(start 0.7874 -0.4064)
			(end 0.7874 0.4064)
			(stroke
				(width 0.1524)
				(type default)
			)
			(layer "F.SilkS")
		)
		(fp_line
			(start 0.7874 0.4064)
			(end -0.7874 0.4064)
			(stroke
				(width 0.1524)
				(type default)
			)
			(layer "F.SilkS")
		)
		(fp_line
			(start -0.67945 -0.305054)
			(end -0.12065 -0.305054)
			(stroke
				(width 0.1)
				(type default)
			)
			(layer "F.Fab")
		)
		(fp_line
			(start -0.67945 0.3048)
			(end -0.67945 -0.305054)
			(stroke
				(width 0.1)
				(type default)
			)
			(layer "F.Fab")
		)
		(fp_line
			(start -0.12065 -0.305054)
			(end -0.12065 -0.2794)
			(stroke
				(width 0.1)
				(type default)
			)
			(layer "F.Fab")
		)
		(fp_line
			(start -0.12065 -0.2794)
			(end 0.12065 -0.2794)
			(stroke
				(width 0.1)
				(type default)
			)
			(layer "F.Fab")
		)
		(fp_line
			(start -0.12065 0.2794)
			(end -0.12065 0.3048)
			(stroke
				(width 0.1)
				(type default)
			)
			(layer "F.Fab")
		)
		(fp_line
			(start -0.12065 0.3048)
			(end -0.67945 0.3048)
			(stroke
				(width 0.1)
				(type default)
			)
			(layer "F.Fab")
		)
		(fp_line
			(start 0.120396 0.2794)
			(end -0.12065 0.2794)
			(stroke
				(width 0.1)
				(type default)
			)
			(layer "F.Fab")
		)
		(fp_line
			(start 0.120396 0.3048)
			(end 0.120396 0.2794)
			(stroke
				(width 0.1)
				(type default)
			)
			(layer "F.Fab")
		)
		(fp_line
			(start 0.12065 -0.3048)
			(end 0.67945 -0.3048)
			(stroke
				(width 0.1)
				(type default)
			)
			(layer "F.Fab")
		)
		(fp_line
			(start 0.12065 -0.2794)
			(end 0.12065 -0.3048)
			(stroke
				(width 0.1)
				(type default)
			)
			(layer "F.Fab")
		)
		(fp_line
			(start 0.67945 -0.3048)
			(end 0.67945 0.3048)
			(stroke
				(width 0.1)
				(type default)
			)
			(layer "F.Fab")
		)
		(fp_line
			(start 0.67945 0.3048)
			(end 0.120396 0.3048)
			(stroke
				(width 0.1)
				(type default)
			)
			(layer "F.Fab")
		)
		(pad "1" smd circle
			(at -0.40005 0)
			(size 0 0)
			(layers "F.Cu" "F.Mask" "F.Paste")
			(net "P12V_OCP_V3_2_R")
		)
		(pad "2" smd circle
			(at 0.40005 0)
			(size 0 0)
			(layers "F.Cu" "F.Mask" "F.Paste")
			(net "VSENSE_P12V_INA230_7_INN")
		)
	)
	(footprint ""
		(layer "F.Cu")
		(at 277.352252 -114.70767)
		(property "Reference" "R1089"
			(at 0 0 0)
			(layer "F.SilkS")
			(hide yes)
			(effects
				(font
					(size 1.27 1.27)
				)
			)
		)
		(property "Value" ""
			(at 0 0 0)
			(layer "F.Fab")
			(effects
				(font
					(size 1.27 1.27)
				)
			)
		)
		(duplicate_pad_numbers_are_jumpers no)
		(fp_line
			(start -0.7874 -0.4064)
			(end 0.7874 -0.4064)
			(stroke
				(width 0.1524)
				(type default)
			)
			(layer "F.SilkS")
		)
		(fp_line
			(start -0.7874 0.4064)
			(end -0.7874 -0.4064)
			(stroke
				(width 0.1524)
				(type default)
			)
			(layer "F.SilkS")
		)
		(fp_line
			(start 0.7874 -0.4064)
			(end 0.7874 0.4064)
			(stroke
				(width 0.1524)
				(type default)
			)
			(layer "F.SilkS")
		)
		(fp_line
			(start 0.7874 0.4064)
			(end -0.7874 0.4064)
			(stroke
				(width 0.1524)
				(type default)
			)
			(layer "F.SilkS")
		)
		(fp_line
			(start -0.67945 -0.305054)
			(end -0.12065 -0.305054)
			(stroke
				(width 0.1)
				(type default)
			)
			(layer "F.Fab")
		)
		(fp_line
			(start -0.67945 0.3048)
			(end -0.67945 -0.305054)
			(stroke
				(width 0.1)
				(type default)
			)
			(layer "F.Fab")
		)
		(fp_line
			(start -0.12065 -0.305054)
			(end -0.12065 -0.2794)
			(stroke
				(width 0.1)
				(type default)
			)
			(layer "F.Fab")
		)
		(fp_line
			(start -0.12065 -0.2794)
			(end 0.12065 -0.2794)
			(stroke
				(width 0.1)
				(type default)
			)
			(layer "F.Fab")
		)
		(fp_line
			(start -0.12065 0.2794)
			(end -0.12065 0.3048)
			(stroke
				(width 0.1)
				(type default)
			)
			(layer "F.Fab")
		)
		(fp_line
			(start -0.12065 0.3048)
			(end -0.67945 0.3048)
			(stroke
				(width 0.1)
				(type default)
			)
			(layer "F.Fab")
		)
		(fp_line
			(start 0.120396 0.2794)
			(end -0.12065 0.2794)
			(stroke
				(width 0.1)
				(type default)
			)
			(layer "F.Fab")
		)
		(fp_line
			(start 0.120396 0.3048)
			(end 0.120396 0.2794)
			(stroke
				(width 0.1)
				(type default)
			)
			(layer "F.Fab")
		)
		(fp_line
			(start 0.12065 -0.3048)
			(end 0.67945 -0.3048)
			(stroke
				(width 0.1)
				(type default)
			)
			(layer "F.Fab")
		)
		(fp_line
			(start 0.12065 -0.2794)
			(end 0.12065 -0.3048)
			(stroke
				(width 0.1)
				(type default)
			)
			(layer "F.Fab")
		)
		(fp_line
			(start 0.67945 -0.3048)
			(end 0.67945 0.3048)
			(stroke
				(width 0.1)
				(type default)
			)
			(layer "F.Fab")
		)
		(fp_line
			(start 0.67945 0.3048)
			(end 0.120396 0.3048)
			(stroke
				(width 0.1)
				(type default)
			)
			(layer "F.Fab")
		)
		(pad "1" smd circle
			(at -0.40005 0)
			(size 0 0)
			(layers "F.Cu" "F.Mask" "F.Paste")
			(net "P3V3_AUX")
		)
		(pad "2" smd circle
			(at 0.40005 0)
			(size 0 0)
			(layers "F.Cu" "F.Mask" "F.Paste")
			(net "SMB_SENSOR_M2_P1_3V3AUX_SCL")
		)
	)
	(footprint ""
		(layer "F.Cu")
		(at 390.007348 -16.100298 90)
		(property "Reference" "C1548"
			(at 0 0 90)
			(layer "F.SilkS")
			(hide yes)
			(effects
				(font
					(size 1.27 1.27)
				)
			)
		)
		(property "Value" ""
			(at 0 0 90)
			(layer "F.Fab")
			(effects
				(font
					(size 1.27 1.27)
				)
			)
		)
		(duplicate_pad_numbers_are_jumpers no)
		(fp_line
			(start 0.299974 -0.150114)
			(end 0.299974 0.150114)
			(stroke
				(width 0.1)
				(type default)
			)
			(layer "F.Fab")
		)
		(fp_line
			(start -0.299974 -0.150114)
			(end 0.299974 -0.150114)
			(stroke
				(width 0.1)
				(type default)
			)
			(layer "F.Fab")
		)
		(fp_line
			(start 0.299974 0.150114)
			(end -0.299974 0.150114)
			(stroke
				(width 0.1)
				(type default)
			)
			(layer "F.Fab")
		)
		(fp_line
			(start -0.299974 0.150114)
			(end -0.299974 -0.150114)
			(stroke
				(width 0.1)
				(type default)
			)
			(layer "F.Fab")
		)
		(pad "1" smd rect
			(at -0.2667 0 90)
			(size 0.3048 0.381)
			(layers "F.Cu" "F.Mask" "F.Paste")
			(net "P5E_CPU0_G3_TX_C_DN<15>")
		)
		(pad "2" smd rect
			(at 0.2667 0 90)
			(size 0.3048 0.381)
			(layers "F.Cu" "F.Mask" "F.Paste")
			(net "P5E_CPU0_G3_TX_DN<15>")
		)
	)
	(footprint ""
		(layer "F.Cu")
		(at 84.27212 -44.42206 -90)
		(property "Reference" "U207"
			(at 1.57734 -2.028952 90)
			(unlocked yes)
			(layer "F.SilkS")
			(effects
				(font
					(size 0.7874 0.5842)
					(thickness 0.1524)
				)
				(justify left)
			)
		)
		(property "Value" ""
			(at 0 0 270)
			(layer "F.Fab")
			(effects
				(font
					(size 1.27 1.27)
				)
			)
		)
		(duplicate_pad_numbers_are_jumpers no)
		(fp_line
			(start -1.695958 1.124966)
			(end -1.695958 -1.124966)
			(stroke
				(width 0.1524)
				(type default)
			)
			(layer "F.SilkS")
		)
		(fp_line
			(start 1.695958 1.124966)
			(end -1.695958 1.124966)
			(stroke
				(width 0.1524)
				(type default)
			)
			(layer "F.SilkS")
		)
		(fp_line
			(start -1.695958 -1.124966)
			(end 1.695958 -1.124966)
			(stroke
				(width 0.1524)
				(type default)
			)
			(layer "F.SilkS")
		)
		(fp_line
			(start 1.695958 -1.124966)
			(end 1.695958 1.124966)
			(stroke
				(width 0.1524)
				(type default)
			)
			(layer "F.SilkS")
		)
		(fp_poly
			(pts
				(xy -2.43332 -0.484886) (xy -2.43332 -1.104646) (xy -1.81356 -0.794766)
			)
			(stroke
				(width 0)
				(type default)
			)
			(fill yes)
			(layer "F.SilkS")
		)
		(fp_line
			(start -0.674878 1.124966)
			(end -0.674878 -1.124966)
			(stroke
				(width 0.1)
				(type default)
			)
			(layer "F.Fab")
		)
		(fp_line
			(start 0.674878 1.124966)
			(end -0.674878 1.124966)
			(stroke
				(width 0.1)
				(type default)
			)
			(layer "F.Fab")
		)
		(fp_line
			(start -0.674878 -1.124966)
			(end 0.674878 -1.124966)
			(stroke
				(width 0.1)
				(type default)
			)
			(layer "F.Fab")
		)
		(fp_line
			(start 0.674878 -1.124966)
			(end 0.674878 1.124966)
			(stroke
				(width 0.1)
				(type default)
			)
			(layer "F.Fab")
		)
		(fp_poly
			(pts
				(xy -2.4892 -0.959866) (xy -1.86944 -0.649986) (xy -2.4892 -0.340106)
			)
			(stroke
				(width 0)
				(type default)
			)
			(fill yes)
			(layer "F.Fab")
		)
		(pad "1" smd rect
			(at -0.94488 -0.649986)
			(size 0.3556 1.2446)
			(layers "F.Cu" "F.Mask" "F.Paste")
			(net "Net_10784")
		)
		(pad "2" smd rect
			(at -0.94488 0)
			(size 0.3556 1.2446)
			(layers "F.Cu" "F.Mask" "F.Paste")
			(net "RST_PERST_OCP_V3_2_BUF_N")
		)
		(pad "3" smd rect
			(at -0.94488 0.649986)
			(size 0.3556 1.2446)
			(layers "F.Cu" "F.Mask" "F.Paste")
			(net "GND")
		)
		(pad "4" smd rect
			(at 0.94488 0.649986)
			(size 0.3556 1.2446)
			(layers "F.Cu" "F.Mask" "F.Paste")
			(net "RST_PERST_OCP_V3_2_BUF2_N")
		)
		(pad "5" smd rect
			(at 0.94488 -0.649986)
			(size 0.3556 1.2446)
			(layers "F.Cu" "F.Mask" "F.Paste")
			(net "P3V3_AUX")
		)
	)
	(footprint ""
		(layer "F.Cu")
		(at 234.739688 -152.631648 180)
		(property "Reference" "U13"
			(at -4.649724 -0.803148 0)
			(unlocked yes)
			(layer "F.SilkS")
			(effects
				(font
					(size 0.7874 0.5842)
					(thickness 0.1524)
				)
				(justify left)
			)
		)
		(property "Value" ""
			(at 0 0 180)
			(layer "F.Fab")
			(effects
				(font
					(size 1.27 1.27)
				)
			)
		)
		(duplicate_pad_numbers_are_jumpers no)
		(fp_line
			(start 1.0414 1.575054)
			(end -1.0414 1.575054)
			(stroke
				(width 0.1524)
				(type default)
			)
			(layer "F.SilkS")
		)
		(fp_line
			(start 1.0414 -1.575054)
			(end 1.0414 1.575054)
			(stroke
				(width 0.1524)
				(type default)
			)
			(layer "F.SilkS")
		)
		(fp_line
			(start 0.254 -1.575054)
			(end 1.0414 -1.575054)
			(stroke
				(width 0.1524)
				(type default)
			)
			(layer "F.SilkS")
		)
		(fp_line
			(start 0.2286 -1.575054)
			(end 0 -1.272032)
			(stroke
				(width 0.1524)
				(type default)
			)
			(layer "F.SilkS")
		)
		(fp_line
			(start 0 -1.272032)
			(end -0.254 -1.575054)
			(stroke
				(width 0.1524)
				(type default)
			)
			(layer "F.SilkS")
		)
		(fp_line
			(start -1.0414 1.575054)
			(end -1.0414 -1.575054)
			(stroke
				(width 0.1524)
				(type default)
			)
			(layer "F.SilkS")
		)
		(fp_line
			(start -1.0414 -1.575054)
			(end -0.254 -1.575054)
			(stroke
				(width 0.1524)
				(type default)
			)
			(layer "F.SilkS")
		)
		(fp_poly
			(pts
				(xy -3.600704 -0.436118) (xy -3.600704 -1.452118) (xy -2.584704 -0.944118)
			)
			(stroke
				(width 0)
				(type default)
			)
			(fill yes)
			(layer "F.SilkS")
		)
		(fp_line
			(start 2.5654 1.2192)
			(end 1.4478 1.2192)
			(stroke
				(width 0.1)
				(type default)
			)
			(layer "F.Fab")
		)
		(fp_line
			(start 2.5654 -1.2192)
			(end 2.5654 1.2192)
			(stroke
				(width 0.1)
				(type default)
			)
			(layer "F.Fab")
		)
		(fp_line
			(start 1.4478 1.5748)
			(end -1.4478 1.5748)
			(stroke
				(width 0.1)
				(type default)
			)
			(layer "F.Fab")
		)
		(fp_line
			(start 1.4478 1.2192)
			(end 1.4478 1.5748)
			(stroke
				(width 0.1)
				(type default)
			)
			(layer "F.Fab")
		)
		(fp_line
			(start 1.4478 -1.2192)
			(end 2.5654 -1.2192)
			(stroke
				(width 0.1)
				(type default)
			)
			(layer "F.Fab")
		)
		(fp_line
			(start 1.4478 -1.5748)
			(end 1.4478 -1.2192)
			(stroke
				(width 0.1)
				(type default)
			)
			(layer "F.Fab")
		)
		(fp_line
			(start -1.4478 1.5748)
			(end -1.4478 1.2192)
			(stroke
				(width 0.1)
				(type default)
			)
			(layer "F.Fab")
		)
		(fp_line
			(start -1.4478 1.2192)
			(end -2.5654 1.2192)
			(stroke
				(width 0.1)
				(type default)
			)
			(layer "F.Fab")
		)
		(fp_line
			(start -1.4478 -1.2192)
			(end -1.4478 -1.5748)
			(stroke
				(width 0.1)
				(type default)
			)
			(layer "F.Fab")
		)
		(fp_line
			(start -1.4478 -1.5748)
			(end 1.4478 -1.5748)
			(stroke
				(width 0.1)
				(type default)
			)
			(layer "F.Fab")
		)
		(fp_line
			(start -2.5654 1.2192)
			(end -2.5654 -1.2192)
			(stroke
				(width 0.1)
				(type default)
			)
			(layer "F.Fab")
		)
		(fp_line
			(start -2.5654 -1.2192)
			(end -1.4478 -1.2192)
			(stroke
				(width 0.1)
				(type default)
			)
			(layer "F.Fab")
		)
		(fp_poly
			(pts
				(xy -2.710688 -0.975106) (xy -3.726688 -1.483106) (xy -3.726688 -0.467106)
			)
			(stroke
				(width 0)
				(type default)
			)
			(fill yes)
			(layer "F.Fab")
		)
		(pad "1" smd rect
			(at -1.849882 -0.975106 90)
			(size 0.3556 1.3208)
			(layers "F.Cu" "F.Mask" "F.Paste")
			(net "JTAG_CPU0_TDO")
		)
		(pad "2" smd rect
			(at -1.849882 -0.32512 90)
			(size 0.3556 1.3208)
			(layers "F.Cu" "F.Mask" "F.Paste")
			(net "JTAG_CPU0_TDO_CPU1_TDI")
		)
		(pad "3" smd rect
			(at -1.849882 0.32512 90)
			(size 0.3556 1.3208)
			(layers "F.Cu" "F.Mask" "F.Paste")
			(net "FM_PLD_CPU0_PRSNT_HDT_N")
		)
		(pad "4" smd rect
			(at -1.849882 0.975106 90)
			(size 0.3556 1.3208)
			(layers "F.Cu" "F.Mask" "F.Paste")
			(net "GND")
		)
		(pad "5" smd rect
			(at 1.849882 0.975106 90)
			(size 0.3556 1.3208)
			(layers "F.Cu" "F.Mask" "F.Paste")
			(net "JTAG_CPU0_BYPASS_R1")
		)
		(pad "6" smd rect
			(at 1.849882 0.32512 90)
			(size 0.3556 1.3208)
			(layers "F.Cu" "F.Mask" "F.Paste")
			(net "JTAG_CPU0_TDO_CPU1_TDI_R1")
		)
		(pad "7" smd rect
			(at 1.849882 -0.32512 90)
			(size 0.3556 1.3208)
			(layers "F.Cu" "F.Mask" "F.Paste")
			(net "CPU0_HDT_BYPASS_SEL")
		)
		(pad "8" smd rect
			(at 1.849882 -0.975106 90)
			(size 0.3556 1.3208)
			(layers "F.Cu" "F.Mask" "F.Paste")
			(net "PVDD18_S5_P0")
		)
	)
	(footprint ""
		(layer "F.Cu")
		(at 40.386 -436.499)
		(property "Reference" "U256"
			(at -0.413004 -3.526282 0)
			(unlocked yes)
			(layer "F.SilkS")
			(effects
				(font
					(size 0.7874 0.5842)
					(thickness 0.1524)
				)
				(justify left)
			)
		)
		(property "Value" ""
			(at 0 0 0)
			(layer "F.Fab")
			(effects
				(font
					(size 1.27 1.27)
				)
			)
		)
		(duplicate_pad_numbers_are_jumpers no)
		(fp_line
			(start -1.3462 -1.100074)
			(end -0.670052 -1.100074)
			(stroke
				(width 0.1524)
				(type default)
			)
			(layer "F.SilkS")
		)
		(fp_line
			(start -1.3462 1.100074)
			(end -1.3462 -1.100074)
			(stroke
				(width 0.1524)
				(type default)
			)
			(layer "F.SilkS")
		)
		(fp_line
			(start -0.670052 -1.100074)
			(end 0 -0.381)
			(stroke
				(width 0.1524)
				(type default)
			)
			(layer "F.SilkS")
		)
		(fp_line
			(start 0 -0.381)
			(end 0.670052 -1.100074)
			(stroke
				(width 0.1524)
				(type default)
			)
			(layer "F.SilkS")
		)
		(fp_line
			(start 0.670052 -1.100074)
			(end 1.3462 -1.100074)
			(stroke
				(width 0.1524)
				(type default)
			)
			(layer "F.SilkS")
		)
		(fp_line
			(start 1.3462 -1.100074)
			(end 1.3462 1.100074)
			(stroke
				(width 0.1524)
				(type default)
			)
			(layer "F.SilkS")
		)
		(fp_line
			(start 1.3462 1.100074)
			(end -1.3462 1.100074)
			(stroke
				(width 0.1524)
				(type default)
			)
			(layer "F.SilkS")
		)
		(fp_poly
			(pts
				(xy -2.620518 -1.867408) (xy -2.160778 -2.474976) (xy -1.78308 -1.711198)
			)
			(stroke
				(width 0)
				(type default)
			)
			(fill yes)
			(layer "F.SilkS")
		)
		(fp_line
			(start -1.100074 -0.8001)
			(end -0.670052 -0.8001)
			(stroke
				(width 0.1)
				(type default)
			)
			(layer "F.Fab")
		)
		(fp_line
			(start -1.100074 0.8001)
			(end -1.100074 -0.8001)
			(stroke
				(width 0.1)
				(type default)
			)
			(layer "F.Fab")
		)
		(fp_line
			(start -0.670052 -1.100074)
			(end 0.670052 -1.100074)
			(stroke
				(width 0.1)
				(type default)
			)
			(layer "F.Fab")
		)
		(fp_line
			(start -0.670052 -0.8001)
			(end -0.670052 -1.100074)
			(stroke
				(width 0.1)
				(type default)
			)
			(layer "F.Fab")
		)
		(fp_line
			(start -0.670052 0.8001)
			(end -1.100074 0.8001)
			(stroke
				(width 0.1)
				(type default)
			)
			(layer "F.Fab")
		)
		(fp_line
			(start -0.670052 0.8001)
			(end -0.670052 -0.8001)
			(stroke
				(width 0.1)
				(type default)
			)
			(layer "F.Fab")
		)
		(fp_line
			(start -0.670052 1.100074)
			(end -0.670052 0.8001)
			(stroke
				(width 0.1)
				(type default)
			)
			(layer "F.Fab")
		)
		(fp_line
			(start 0.670052 -1.100074)
			(end 0.670052 -0.8001)
			(stroke
				(width 0.1)
				(type default)
			)
			(layer "F.Fab")
		)
		(fp_line
			(start 0.670052 -0.8001)
			(end 0.670052 0.8001)
			(stroke
				(width 0.1)
				(type default)
			)
			(layer "F.Fab")
		)
		(fp_line
			(start 0.670052 -0.8001)
			(end 1.100074 -0.8001)
			(stroke
				(width 0.1)
				(type default)
			)
			(layer "F.Fab")
		)
		(fp_line
			(start 0.670052 0.8001)
			(end 0.670052 1.100074)
			(stroke
				(width 0.1)
				(type default)
			)
			(layer "F.Fab")
		)
		(fp_line
			(start 0.670052 1.100074)
			(end -0.670052 1.100074)
			(stroke
				(width 0.1)
				(type default)
			)
			(layer "F.Fab")
		)
		(fp_line
			(start 1.100074 -0.8001)
			(end 1.100074 0.8001)
			(stroke
				(width 0.1)
				(type default)
			)
			(layer "F.Fab")
		)
		(fp_line
			(start 1.100074 0.8001)
			(end 0.670052 0.8001)
			(stroke
				(width 0.1)
				(type default)
			)
			(layer "F.Fab")
		)
		(fp_poly
			(pts
				(xy -1.524 -0.649986) (xy -2.286 -1.030986) (xy -2.286 -0.268986)
			)
			(stroke
				(width 0)
				(type default)
			)
			(fill yes)
			(layer "F.Fab")
		)
		(pad "1" smd rect
			(at -0.94996 -0.649986 270)
			(size 0.4064 0.508)
			(layers "F.Cu" "F.Mask" "F.Paste")
			(net "RST_PERST_CPU0_SWB_R_N")
		)
		(pad "2" smd rect
			(at -0.94996 0 270)
			(size 0.4064 0.508)
			(layers "F.Cu" "F.Mask" "F.Paste")
			(net "GND")
		)
		(pad "3" smd rect
			(at -0.94996 0.649986 270)
			(size 0.4064 0.508)
			(layers "F.Cu" "F.Mask" "F.Paste")
			(net "FM_SWB_PWR_EN_R")
		)
		(pad "4" smd rect
			(at 0.94996 0.649986 270)
			(size 0.4064 0.508)
			(layers "F.Cu" "F.Mask" "F.Paste")
			(net "FM_SWB_PWR_EN_R1_BUF")
		)
		(pad "5" smd rect
			(at 0.94996 0 270)
			(size 0.4064 0.508)
			(layers "F.Cu" "F.Mask" "F.Paste")
			(net "P3V3_AUX")
		)
		(pad "6" smd rect
			(at 0.94996 -0.649986 270)
			(size 0.4064 0.508)
			(layers "F.Cu" "F.Mask" "F.Paste")
			(net "RST_PERST_1_SWB_BUF_R_N")
		)
	)
	(footprint ""
		(layer "F.Cu")
		(at 393.1031 -185.748168)
		(property "Reference" "PC181"
			(at 0 0 0)
			(layer "F.SilkS")
			(hide yes)
			(effects
				(font
					(size 1.27 1.27)
				)
			)
		)
		(property "Value" ""
			(at 0 0 0)
			(layer "F.Fab")
			(effects
				(font
					(size 1.27 1.27)
				)
			)
		)
		(duplicate_pad_numbers_are_jumpers no)
		(fp_line
			(start -0.7874 -0.4064)
			(end 0.7874 -0.4064)
			(stroke
				(width 0.1524)
				(type default)
			)
			(layer "F.SilkS")
		)
		(fp_line
			(start -0.7874 0.4064)
			(end -0.7874 -0.4064)
			(stroke
				(width 0.1524)
				(type default)
			)
			(layer "F.SilkS")
		)
		(fp_line
			(start 0.7874 -0.4064)
			(end 0.7874 0.4064)
			(stroke
				(width 0.1524)
				(type default)
			)
			(layer "F.SilkS")
		)
		(fp_line
			(start 0.7874 0.4064)
			(end -0.7874 0.4064)
			(stroke
				(width 0.1524)
				(type default)
			)
			(layer "F.SilkS")
		)
		(fp_line
			(start -0.67945 -0.305054)
			(end -0.12065 -0.305054)
			(stroke
				(width 0.1)
				(type default)
			)
			(layer "F.Fab")
		)
		(fp_line
			(start -0.67945 0.3048)
			(end -0.67945 -0.305054)
			(stroke
				(width 0.1)
				(type default)
			)
			(layer "F.Fab")
		)
		(fp_line
			(start -0.12065 -0.305054)
			(end -0.12065 -0.2794)
			(stroke
				(width 0.1)
				(type default)
			)
			(layer "F.Fab")
		)
		(fp_line
			(start -0.12065 -0.2794)
			(end 0.12065 -0.2794)
			(stroke
				(width 0.1)
				(type default)
			)
			(layer "F.Fab")
		)
		(fp_line
			(start -0.12065 0.2794)
			(end -0.12065 0.3048)
			(stroke
				(width 0.1)
				(type default)
			)
			(layer "F.Fab")
		)
		(fp_line
			(start -0.12065 0.3048)
			(end -0.67945 0.3048)
			(stroke
				(width 0.1)
				(type default)
			)
			(layer "F.Fab")
		)
		(fp_line
			(start 0.120396 0.2794)
			(end -0.12065 0.2794)
			(stroke
				(width 0.1)
				(type default)
			)
			(layer "F.Fab")
		)
		(fp_line
			(start 0.120396 0.3048)
			(end 0.120396 0.2794)
			(stroke
				(width 0.1)
				(type default)
			)
			(layer "F.Fab")
		)
		(fp_line
			(start 0.12065 -0.3048)
			(end 0.67945 -0.3048)
			(stroke
				(width 0.1)
				(type default)
			)
			(layer "F.Fab")
		)
		(fp_line
			(start 0.12065 -0.2794)
			(end 0.12065 -0.3048)
			(stroke
				(width 0.1)
				(type default)
			)
			(layer "F.Fab")
		)
		(fp_line
			(start 0.67945 -0.3048)
			(end 0.67945 0.3048)
			(stroke
				(width 0.1)
				(type default)
			)
			(layer "F.Fab")
		)
		(fp_line
			(start 0.67945 0.3048)
			(end 0.120396 0.3048)
			(stroke
				(width 0.1)
				(type default)
			)
			(layer "F.Fab")
		)
		(pad "1" smd circle
			(at -0.40005 0)
			(size 0 0)
			(layers "F.Cu" "F.Mask" "F.Paste")
			(net "SW_PVDDCR_CPU0_P0_SW4")
		)
		(pad "2" smd circle
			(at 0.40005 0)
			(size 0 0)
			(layers "F.Cu" "F.Mask" "F.Paste")
			(net "SW_PVDDCR_CPU0_P0_SW4_RC")
		)
	)
	(footprint ""
		(layer "F.Cu")
		(at 416.373564 -17.624298 90)
		(property "Reference" "C47"
			(at 0 0 90)
			(layer "F.SilkS")
			(hide yes)
			(effects
				(font
					(size 1.27 1.27)
				)
			)
		)
		(property "Value" ""
			(at 0 0 90)
			(layer "F.Fab")
			(effects
				(font
					(size 1.27 1.27)
				)
			)
		)
		(duplicate_pad_numbers_are_jumpers no)
		(fp_line
			(start 0.299974 -0.150114)
			(end 0.299974 0.150114)
			(stroke
				(width 0.1)
				(type default)
			)
			(layer "F.Fab")
		)
		(fp_line
			(start -0.299974 -0.150114)
			(end 0.299974 -0.150114)
			(stroke
				(width 0.1)
				(type default)
			)
			(layer "F.Fab")
		)
		(fp_line
			(start 0.299974 0.150114)
			(end -0.299974 0.150114)
			(stroke
				(width 0.1)
				(type default)
			)
			(layer "F.Fab")
		)
		(fp_line
			(start -0.299974 0.150114)
			(end -0.299974 -0.150114)
			(stroke
				(width 0.1)
				(type default)
			)
			(layer "F.Fab")
		)
		(pad "1" smd rect
			(at -0.2667 0 90)
			(size 0.3048 0.381)
			(layers "F.Cu" "F.Mask" "F.Paste")
			(net "P5E_CPU0_G3_TX_C_DP<6>")
		)
		(pad "2" smd rect
			(at 0.2667 0 90)
			(size 0.3048 0.381)
			(layers "F.Cu" "F.Mask" "F.Paste")
			(net "P5E_CPU0_G3_TX_DP<6>")
		)
	)
	(footprint ""
		(layer "F.Cu")
		(at 336.172556 -135.50265)
		(property "Reference" "PC111"
			(at 0 0 0)
			(layer "F.SilkS")
			(hide yes)
			(effects
				(font
					(size 1.27 1.27)
				)
			)
		)
		(property "Value" ""
			(at 0 0 0)
			(layer "F.Fab")
			(effects
				(font
					(size 1.27 1.27)
				)
			)
		)
		(duplicate_pad_numbers_are_jumpers no)
		(fp_line
			(start -1.524 -0.762)
			(end 1.524 -0.762)
			(stroke
				(width 0.1524)
				(type default)
			)
			(layer "F.SilkS")
		)
		(fp_line
			(start -1.524 0.762)
			(end -1.524 -0.762)
			(stroke
				(width 0.1524)
				(type default)
			)
			(layer "F.SilkS")
		)
		(fp_line
			(start 1.524 -0.762)
			(end 1.524 0.762)
			(stroke
				(width 0.1524)
				(type default)
			)
			(layer "F.SilkS")
		)
		(fp_line
			(start 1.524 0.762)
			(end -1.524 0.762)
			(stroke
				(width 0.1524)
				(type default)
			)
			(layer "F.SilkS")
		)
		(fp_line
			(start -1.1049 -0.724916)
			(end -1.1049 0.724916)
			(stroke
				(width 0.1)
				(type default)
			)
			(layer "F.Fab")
		)
		(fp_line
			(start -1.1049 0.724916)
			(end 1.1049 0.724916)
			(stroke
				(width 0.1)
				(type default)
			)
			(layer "F.Fab")
		)
		(fp_line
			(start 1.1049 -0.724916)
			(end -1.1049 -0.724916)
			(stroke
				(width 0.1)
				(type default)
			)
			(layer "F.Fab")
		)
		(fp_line
			(start 1.1049 0.724916)
			(end 1.1049 -0.724916)
			(stroke
				(width 0.1)
				(type default)
			)
			(layer "F.Fab")
		)
		(pad "1" smd rect
			(at -0.889 0 180)
			(size 1.016 1.27)
			(layers "F.Cu" "F.Mask" "F.Paste")
			(net "SW_P12V_AUX_PVDD18_S5_P0_FLT")
		)
		(pad "2" smd rect
			(at 0.889 0 180)
			(size 1.016 1.27)
			(layers "F.Cu" "F.Mask" "F.Paste")
			(net "GND")
		)
	)
	(footprint ""
		(layer "F.Cu")
		(at 303.768506 -416.899344 -90)
		(property "Reference" "C6502"
			(at 0 0 270)
			(layer "F.SilkS")
			(hide yes)
			(effects
				(font
					(size 1.27 1.27)
				)
			)
		)
		(property "Value" ""
			(at 0 0 270)
			(layer "F.Fab")
			(effects
				(font
					(size 1.27 1.27)
				)
			)
		)
		(duplicate_pad_numbers_are_jumpers no)
		(fp_line
			(start -0.299974 0.150114)
			(end -0.299974 -0.150114)
			(stroke
				(width 0.1)
				(type default)
			)
			(layer "F.Fab")
		)
		(fp_line
			(start 0.299974 0.150114)
			(end -0.299974 0.150114)
			(stroke
				(width 0.1)
				(type default)
			)
			(layer "F.Fab")
		)
		(fp_line
			(start -0.299974 -0.150114)
			(end 0.299974 -0.150114)
			(stroke
				(width 0.1)
				(type default)
			)
			(layer "F.Fab")
		)
		(fp_line
			(start 0.299974 -0.150114)
			(end 0.299974 0.150114)
			(stroke
				(width 0.1)
				(type default)
			)
			(layer "F.Fab")
		)
		(pad "1" smd rect
			(at -0.2667 0 270)
			(size 0.3048 0.381)
			(layers "F.Cu" "F.Mask" "F.Paste")
			(net "P5E_CPU0_P0_TX_BUF_C_DN<0>")
		)
		(pad "2" smd rect
			(at 0.2667 0 270)
			(size 0.3048 0.381)
			(layers "F.Cu" "F.Mask" "F.Paste")
			(net "P5E_CPU0_P0_TX_BUF_DN<0>")
		)
	)
	(footprint ""
		(layer "F.Cu")
		(at 257.501644 -139.718796 180)
		(property "Reference" "R606"
			(at 0 0 180)
			(layer "F.SilkS")
			(hide yes)
			(effects
				(font
					(size 1.27 1.27)
				)
			)
		)
		(property "Value" ""
			(at 0 0 180)
			(layer "F.Fab")
			(effects
				(font
					(size 1.27 1.27)
				)
			)
		)
		(duplicate_pad_numbers_are_jumpers no)
		(fp_line
			(start 0.7874 0.4064)
			(end -0.7874 0.4064)
			(stroke
				(width 0.1524)
				(type default)
			)
			(layer "F.SilkS")
		)
		(fp_line
			(start 0.7874 -0.4064)
			(end 0.7874 0.4064)
			(stroke
				(width 0.1524)
				(type default)
			)
			(layer "F.SilkS")
		)
		(fp_line
			(start -0.7874 0.4064)
			(end -0.7874 -0.4064)
			(stroke
				(width 0.1524)
				(type default)
			)
			(layer "F.SilkS")
		)
		(fp_line
			(start -0.7874 -0.4064)
			(end 0.7874 -0.4064)
			(stroke
				(width 0.1524)
				(type default)
			)
			(layer "F.SilkS")
		)
		(fp_line
			(start 0.67945 0.3048)
			(end 0.120396 0.3048)
			(stroke
				(width 0.1)
				(type default)
			)
			(layer "F.Fab")
		)
		(fp_line
			(start 0.67945 -0.3048)
			(end 0.67945 0.3048)
			(stroke
				(width 0.1)
				(type default)
			)
			(layer "F.Fab")
		)
		(fp_line
			(start 0.12065 -0.2794)
			(end 0.12065 -0.3048)
			(stroke
				(width 0.1)
				(type default)
			)
			(layer "F.Fab")
		)
		(fp_line
			(start 0.12065 -0.3048)
			(end 0.67945 -0.3048)
			(stroke
				(width 0.1)
				(type default)
			)
			(layer "F.Fab")
		)
		(fp_line
			(start 0.120396 0.3048)
			(end 0.120396 0.2794)
			(stroke
				(width 0.1)
				(type default)
			)
			(layer "F.Fab")
		)
		(fp_line
			(start 0.120396 0.2794)
			(end -0.12065 0.2794)
			(stroke
				(width 0.1)
				(type default)
			)
			(layer "F.Fab")
		)
		(fp_line
			(start -0.12065 0.3048)
			(end -0.67945 0.3048)
			(stroke
				(width 0.1)
				(type default)
			)
			(layer "F.Fab")
		)
		(fp_line
			(start -0.12065 0.2794)
			(end -0.12065 0.3048)
			(stroke
				(width 0.1)
				(type default)
			)
			(layer "F.Fab")
		)
		(fp_line
			(start -0.12065 -0.2794)
			(end 0.12065 -0.2794)
			(stroke
				(width 0.1)
				(type default)
			)
			(layer "F.Fab")
		)
		(fp_line
			(start -0.12065 -0.305054)
			(end -0.12065 -0.2794)
			(stroke
				(width 0.1)
				(type default)
			)
			(layer "F.Fab")
		)
		(fp_line
			(start -0.67945 0.3048)
			(end -0.67945 -0.305054)
			(stroke
				(width 0.1)
				(type default)
			)
			(layer "F.Fab")
		)
		(fp_line
			(start -0.67945 -0.305054)
			(end -0.12065 -0.305054)
			(stroke
				(width 0.1)
				(type default)
			)
			(layer "F.Fab")
		)
		(pad "1" smd circle
			(at -0.40005 0 180)
			(size 0 0)
			(layers "F.Cu" "F.Mask" "F.Paste")
			(net "SPI_CPU0_LVC3_D2")
		)
		(pad "2" smd circle
			(at 0.40005 0 180)
			(size 0 0)
			(layers "F.Cu" "F.Mask" "F.Paste")
			(net "SPI_CPU0_LVC3_SCM_D2")
		)
	)
	(footprint ""
		(layer "F.Cu")
		(at 236.649768 -272.50009)
		(property "Reference" "H100"
			(at -4.274566 -5.764276 0)
			(unlocked yes)
			(layer "F.SilkS")
			(effects
				(font
					(size 0.7874 0.5842)
					(thickness 0.1524)
				)
				(justify left)
			)
		)
		(property "Value" ""
			(at 0 0 0)
			(layer "F.Fab")
			(effects
				(font
					(size 1.27 1.27)
				)
			)
		)
		(duplicate_pad_numbers_are_jumpers no)
		(pad "1" thru_hole circle
			(at 0 0)
			(size 10.0076 10.0076)
			(drill 5.6134)
			(layers "*.Cu" "*.Mask")
			(remove_unused_layers no)
			(net "GND")
			(clearance -1.9431)
		)
	)
	(footprint ""
		(layer "F.Cu")
		(at 87.430102 -375.49963 -90)
		(property "Reference" "C727"
			(at 0 0 270)
			(layer "F.SilkS")
			(hide yes)
			(effects
				(font
					(size 1.27 1.27)
				)
			)
		)
		(property "Value" ""
			(at 0 0 270)
			(layer "F.Fab")
			(effects
				(font
					(size 1.27 1.27)
				)
			)
		)
		(duplicate_pad_numbers_are_jumpers no)
		(fp_line
			(start -0.299974 0.150114)
			(end -0.299974 -0.150114)
			(stroke
				(width 0.1)
				(type default)
			)
			(layer "F.Fab")
		)
		(fp_line
			(start 0.299974 0.150114)
			(end -0.299974 0.150114)
			(stroke
				(width 0.1)
				(type default)
			)
			(layer "F.Fab")
		)
		(fp_line
			(start -0.299974 -0.150114)
			(end 0.299974 -0.150114)
			(stroke
				(width 0.1)
				(type default)
			)
			(layer "F.Fab")
		)
		(fp_line
			(start 0.299974 -0.150114)
			(end 0.299974 0.150114)
			(stroke
				(width 0.1)
				(type default)
			)
			(layer "F.Fab")
		)
		(pad "1" smd rect
			(at -0.2667 0 270)
			(size 0.3048 0.381)
			(layers "F.Cu" "F.Mask" "F.Paste")
			(net "P5E_CPU1_P1_TX_C_DP<7>")
		)
		(pad "2" smd rect
			(at 0.2667 0 270)
			(size 0.3048 0.381)
			(layers "F.Cu" "F.Mask" "F.Paste")
			(net "P5E_CPU1_P1_TX_DP<7>")
		)
	)
	(footprint ""
		(layer "F.Cu")
		(at 109.549946 -54.882034 -90)
		(property "Reference" "R6306"
			(at 0 0 270)
			(layer "F.SilkS")
			(hide yes)
			(effects
				(font
					(size 1.27 1.27)
				)
			)
		)
		(property "Value" ""
			(at 0 0 270)
			(layer "F.Fab")
			(effects
				(font
					(size 1.27 1.27)
				)
			)
		)
		(duplicate_pad_numbers_are_jumpers no)
		(fp_line
			(start -0.7874 0.4064)
			(end -0.7874 -0.4064)
			(stroke
				(width 0.1524)
				(type default)
			)
			(layer "F.SilkS")
		)
		(fp_line
			(start 0.7874 0.4064)
			(end -0.7874 0.4064)
			(stroke
				(width 0.1524)
				(type default)
			)
			(layer "F.SilkS")
		)
		(fp_line
			(start -0.7874 -0.4064)
			(end 0.7874 -0.4064)
			(stroke
				(width 0.1524)
				(type default)
			)
			(layer "F.SilkS")
		)
		(fp_line
			(start 0.7874 -0.4064)
			(end 0.7874 0.4064)
			(stroke
				(width 0.1524)
				(type default)
			)
			(layer "F.SilkS")
		)
		(fp_line
			(start -0.67945 0.3048)
			(end -0.67945 -0.305054)
			(stroke
				(width 0.1)
				(type default)
			)
			(layer "F.Fab")
		)
		(fp_line
			(start -0.12065 0.3048)
			(end -0.67945 0.3048)
			(stroke
				(width 0.1)
				(type default)
			)
			(layer "F.Fab")
		)
		(fp_line
			(start 0.120396 0.3048)
			(end 0.120396 0.2794)
			(stroke
				(width 0.1)
				(type default)
			)
			(layer "F.Fab")
		)
		(fp_line
			(start 0.67945 0.3048)
			(end 0.120396 0.3048)
			(stroke
				(width 0.1)
				(type default)
			)
			(layer "F.Fab")
		)
		(fp_line
			(start -0.12065 0.2794)
			(end -0.12065 0.3048)
			(stroke
				(width 0.1)
				(type default)
			)
			(layer "F.Fab")
		)
		(fp_line
			(start 0.120396 0.2794)
			(end -0.12065 0.2794)
			(stroke
				(width 0.1)
				(type default)
			)
			(layer "F.Fab")
		)
		(fp_line
			(start -0.12065 -0.2794)
			(end 0.12065 -0.2794)
			(stroke
				(width 0.1)
				(type default)
			)
			(layer "F.Fab")
		)
		(fp_line
			(start 0.12065 -0.2794)
			(end 0.12065 -0.3048)
			(stroke
				(width 0.1)
				(type default)
			)
			(layer "F.Fab")
		)
		(fp_line
			(start 0.12065 -0.3048)
			(end 0.67945 -0.3048)
			(stroke
				(width 0.1)
				(type default)
			)
			(layer "F.Fab")
		)
		(fp_line
			(start 0.67945 -0.3048)
			(end 0.67945 0.3048)
			(stroke
				(width 0.1)
				(type default)
			)
			(layer "F.Fab")
		)
		(fp_line
			(start -0.67945 -0.305054)
			(end -0.12065 -0.305054)
			(stroke
				(width 0.1)
				(type default)
			)
			(layer "F.Fab")
		)
		(fp_line
			(start -0.12065 -0.305054)
			(end -0.12065 -0.2794)
			(stroke
				(width 0.1)
				(type default)
			)
			(layer "F.Fab")
		)
		(pad "1" smd circle
			(at -0.40005 0 270)
			(size 0 0)
			(layers "F.Cu" "F.Mask" "F.Paste")
			(net "P3V3_AUX")
		)
		(pad "2" smd circle
			(at 0.40005 0 270)
			(size 0 0)
			(layers "F.Cu" "F.Mask" "F.Paste")
			(net "USB_HUB2_TI_HS_SUSPEND")
		)
	)
	(footprint ""
		(layer "F.Cu")
		(at 401.183348 -16.100298 90)
		(property "Reference" "C1556"
			(at 0 0 90)
			(layer "F.SilkS")
			(hide yes)
			(effects
				(font
					(size 1.27 1.27)
				)
			)
		)
		(property "Value" ""
			(at 0 0 90)
			(layer "F.Fab")
			(effects
				(font
					(size 1.27 1.27)
				)
			)
		)
		(duplicate_pad_numbers_are_jumpers no)
		(fp_line
			(start 0.299974 -0.150114)
			(end 0.299974 0.150114)
			(stroke
				(width 0.1)
				(type default)
			)
			(layer "F.Fab")
		)
		(fp_line
			(start -0.299974 -0.150114)
			(end 0.299974 -0.150114)
			(stroke
				(width 0.1)
				(type default)
			)
			(layer "F.Fab")
		)
		(fp_line
			(start 0.299974 0.150114)
			(end -0.299974 0.150114)
			(stroke
				(width 0.1)
				(type default)
			)
			(layer "F.Fab")
		)
		(fp_line
			(start -0.299974 0.150114)
			(end -0.299974 -0.150114)
			(stroke
				(width 0.1)
				(type default)
			)
			(layer "F.Fab")
		)
		(pad "1" smd rect
			(at -0.2667 0 90)
			(size 0.3048 0.381)
			(layers "F.Cu" "F.Mask" "F.Paste")
			(net "P5E_CPU0_G3_TX_C_DN<11>")
		)
		(pad "2" smd rect
			(at 0.2667 0 90)
			(size 0.3048 0.381)
			(layers "F.Cu" "F.Mask" "F.Paste")
			(net "P5E_CPU0_G3_TX_DN<11>")
		)
	)
	(footprint ""
		(layer "F.Cu")
		(at 445.467994 -411.8991 180)
		(property "Reference" "PC6561"
			(at 2.745994 3.49123 0)
			(unlocked yes)
			(layer "F.SilkS")
			(effects
				(font
					(size 0.7874 0.5842)
					(thickness 0.1524)
				)
				(justify left)
			)
		)
		(property "Value" ""
			(at 0 0 180)
			(layer "F.Fab")
			(effects
				(font
					(size 1.27 1.27)
				)
			)
		)
		(duplicate_pad_numbers_are_jumpers no)
		(fp_line
			(start 2.750058 2.750058)
			(end 2.750058 0.9398)
			(stroke
				(width 0.1524)
				(type default)
			)
			(layer "F.SilkS")
		)
		(fp_line
			(start 2.750058 -0.9398)
			(end 2.750058 -2.750058)
			(stroke
				(width 0.1524)
				(type default)
			)
			(layer "F.SilkS")
		)
		(fp_line
			(start 2.750058 -2.750058)
			(end -1.988058 -2.750058)
			(stroke
				(width 0.1524)
				(type default)
			)
			(layer "F.SilkS")
		)
		(fp_line
			(start -1.988058 2.750058)
			(end 2.750058 2.750058)
			(stroke
				(width 0.1524)
				(type default)
			)
			(layer "F.SilkS")
		)
		(fp_line
			(start -1.988058 -2.750058)
			(end -2.750058 -1.988058)
			(stroke
				(width 0.1524)
				(type default)
			)
			(layer "F.SilkS")
		)
		(fp_line
			(start -2.750058 1.988058)
			(end -1.988058 2.750058)
			(stroke
				(width 0.1524)
				(type default)
			)
			(layer "F.SilkS")
		)
		(fp_line
			(start -2.750058 0.9398)
			(end -2.750058 1.988058)
			(stroke
				(width 0.1524)
				(type default)
			)
			(layer "F.SilkS")
		)
		(fp_line
			(start -2.750058 -1.988058)
			(end -2.750058 -0.9398)
			(stroke
				(width 0.1524)
				(type default)
			)
			(layer "F.SilkS")
		)
		(fp_line
			(start 2.750058 2.750058)
			(end 2.750058 -2.750058)
			(stroke
				(width 0.1)
				(type default)
			)
			(layer "F.Fab")
		)
		(fp_line
			(start 2.750058 -2.750058)
			(end -2.750058 -2.750058)
			(stroke
				(width 0.1)
				(type default)
			)
			(layer "F.Fab")
		)
		(fp_line
			(start -2.750058 2.750058)
			(end 2.750058 2.750058)
			(stroke
				(width 0.1)
				(type default)
			)
			(layer "F.Fab")
		)
		(fp_line
			(start -2.750058 -2.750058)
			(end -2.750058 2.750058)
			(stroke
				(width 0.1)
				(type default)
			)
			(layer "F.Fab")
		)
		(pad "1" smd rect
			(at -2.199894 0 270)
			(size 1.6002 3.0226)
			(layers "F.Cu" "F.Mask" "F.Paste")
			(net "SW_P12V_AUX_P0V9_RETIMER_CPU0_FLT")
		)
		(pad "2" smd rect
			(at 2.199894 0 270)
			(size 1.6002 3.0226)
			(layers "F.Cu" "F.Mask" "F.Paste")
			(net "GND")
		)
	)
	(footprint ""
		(layer "F.Cu")
		(at 319.940178 -39.55542)
		(property "Reference" "C2194"
			(at 0 0 0)
			(layer "F.SilkS")
			(hide yes)
			(effects
				(font
					(size 1.27 1.27)
				)
			)
		)
		(property "Value" ""
			(at 0 0 0)
			(layer "F.Fab")
			(effects
				(font
					(size 1.27 1.27)
				)
			)
		)
		(duplicate_pad_numbers_are_jumpers no)
		(fp_line
			(start -0.7874 -0.4064)
			(end 0.7874 -0.4064)
			(stroke
				(width 0.1524)
				(type default)
			)
			(layer "F.SilkS")
		)
		(fp_line
			(start -0.7874 0.4064)
			(end -0.7874 -0.4064)
			(stroke
				(width 0.1524)
				(type default)
			)
			(layer "F.SilkS")
		)
		(fp_line
			(start 0.7874 -0.4064)
			(end 0.7874 0.4064)
			(stroke
				(width 0.1524)
				(type default)
			)
			(layer "F.SilkS")
		)
		(fp_line
			(start 0.7874 0.4064)
			(end -0.7874 0.4064)
			(stroke
				(width 0.1524)
				(type default)
			)
			(layer "F.SilkS")
		)
		(fp_line
			(start -0.67945 -0.305054)
			(end -0.12065 -0.305054)
			(stroke
				(width 0.1)
				(type default)
			)
			(layer "F.Fab")
		)
		(fp_line
			(start -0.67945 0.3048)
			(end -0.67945 -0.305054)
			(stroke
				(width 0.1)
				(type default)
			)
			(layer "F.Fab")
		)
		(fp_line
			(start -0.12065 -0.305054)
			(end -0.12065 -0.2794)
			(stroke
				(width 0.1)
				(type default)
			)
			(layer "F.Fab")
		)
		(fp_line
			(start -0.12065 -0.2794)
			(end 0.12065 -0.2794)
			(stroke
				(width 0.1)
				(type default)
			)
			(layer "F.Fab")
		)
		(fp_line
			(start -0.12065 0.2794)
			(end -0.12065 0.3048)
			(stroke
				(width 0.1)
				(type default)
			)
			(layer "F.Fab")
		)
		(fp_line
			(start -0.12065 0.3048)
			(end -0.67945 0.3048)
			(stroke
				(width 0.1)
				(type default)
			)
			(layer "F.Fab")
		)
		(fp_line
			(start 0.120396 0.2794)
			(end -0.12065 0.2794)
			(stroke
				(width 0.1)
				(type default)
			)
			(layer "F.Fab")
		)
		(fp_line
			(start 0.120396 0.3048)
			(end 0.120396 0.2794)
			(stroke
				(width 0.1)
				(type default)
			)
			(layer "F.Fab")
		)
		(fp_line
			(start 0.12065 -0.3048)
			(end 0.67945 -0.3048)
			(stroke
				(width 0.1)
				(type default)
			)
			(layer "F.Fab")
		)
		(fp_line
			(start 0.12065 -0.2794)
			(end 0.12065 -0.3048)
			(stroke
				(width 0.1)
				(type default)
			)
			(layer "F.Fab")
		)
		(fp_line
			(start 0.67945 -0.3048)
			(end 0.67945 0.3048)
			(stroke
				(width 0.1)
				(type default)
			)
			(layer "F.Fab")
		)
		(fp_line
			(start 0.67945 0.3048)
			(end 0.120396 0.3048)
			(stroke
				(width 0.1)
				(type default)
			)
			(layer "F.Fab")
		)
		(pad "1" smd circle
			(at -0.40005 0)
			(size 0 0)
			(layers "F.Cu" "F.Mask" "F.Paste")
			(net "P12V_E1S_0_ISENSE_TIC")
		)
		(pad "2" smd circle
			(at 0.40005 0)
			(size 0 0)
			(layers "F.Cu" "F.Mask" "F.Paste")
			(net "GND")
		)
	)
	(footprint ""
		(layer "F.Cu")
		(at 164.142674 -38.493954 90)
		(property "Reference" "R2489"
			(at 0 0 90)
			(layer "F.SilkS")
			(hide yes)
			(effects
				(font
					(size 1.27 1.27)
				)
			)
		)
		(property "Value" ""
			(at 0 0 90)
			(layer "F.Fab")
			(effects
				(font
					(size 1.27 1.27)
				)
			)
		)
		(duplicate_pad_numbers_are_jumpers no)
		(fp_line
			(start 0.7874 -0.4064)
			(end 0.7874 0.4064)
			(stroke
				(width 0.1524)
				(type default)
			)
			(layer "F.SilkS")
		)
		(fp_line
			(start -0.7874 -0.4064)
			(end 0.7874 -0.4064)
			(stroke
				(width 0.1524)
				(type default)
			)
			(layer "F.SilkS")
		)
		(fp_line
			(start 0.7874 0.4064)
			(end -0.7874 0.4064)
			(stroke
				(width 0.1524)
				(type default)
			)
			(layer "F.SilkS")
		)
		(fp_line
			(start -0.7874 0.4064)
			(end -0.7874 -0.4064)
			(stroke
				(width 0.1524)
				(type default)
			)
			(layer "F.SilkS")
		)
		(fp_line
			(start -0.12065 -0.305054)
			(end -0.12065 -0.2794)
			(stroke
				(width 0.1)
				(type default)
			)
			(layer "F.Fab")
		)
		(fp_line
			(start -0.67945 -0.305054)
			(end -0.12065 -0.305054)
			(stroke
				(width 0.1)
				(type default)
			)
			(layer "F.Fab")
		)
		(fp_line
			(start 0.67945 -0.3048)
			(end 0.67945 0.3048)
			(stroke
				(width 0.1)
				(type default)
			)
			(layer "F.Fab")
		)
		(fp_line
			(start 0.12065 -0.3048)
			(end 0.67945 -0.3048)
			(stroke
				(width 0.1)
				(type default)
			)
			(layer "F.Fab")
		)
		(fp_line
			(start 0.12065 -0.2794)
			(end 0.12065 -0.3048)
			(stroke
				(width 0.1)
				(type default)
			)
			(layer "F.Fab")
		)
		(fp_line
			(start -0.12065 -0.2794)
			(end 0.12065 -0.2794)
			(stroke
				(width 0.1)
				(type default)
			)
			(layer "F.Fab")
		)
		(fp_line
			(start 0.120396 0.2794)
			(end -0.12065 0.2794)
			(stroke
				(width 0.1)
				(type default)
			)
			(layer "F.Fab")
		)
		(fp_line
			(start -0.12065 0.2794)
			(end -0.12065 0.3048)
			(stroke
				(width 0.1)
				(type default)
			)
			(layer "F.Fab")
		)
		(fp_line
			(start 0.67945 0.3048)
			(end 0.120396 0.3048)
			(stroke
				(width 0.1)
				(type default)
			)
			(layer "F.Fab")
		)
		(fp_line
			(start 0.120396 0.3048)
			(end 0.120396 0.2794)
			(stroke
				(width 0.1)
				(type default)
			)
			(layer "F.Fab")
		)
		(fp_line
			(start -0.12065 0.3048)
			(end -0.67945 0.3048)
			(stroke
				(width 0.1)
				(type default)
			)
			(layer "F.Fab")
		)
		(fp_line
			(start -0.67945 0.3048)
			(end -0.67945 -0.305054)
			(stroke
				(width 0.1)
				(type default)
			)
			(layer "F.Fab")
		)
		(pad "1" smd circle
			(at -0.40005 0 90)
			(size 0 0)
			(layers "F.Cu" "F.Mask" "F.Paste")
			(net "IRQ_LVC3_WAKE_BUF_N")
		)
		(pad "2" smd circle
			(at 0.40005 0 90)
			(size 0 0)
			(layers "F.Cu" "F.Mask" "F.Paste")
			(net "IRQ_OCP_SFF_WAKE_BUF_N")
		)
	)
	(footprint ""
		(layer "F.Cu")
		(at 140.02512 -30.82671 90)
		(property "Reference" "C6018"
			(at 0 0 90)
			(layer "F.SilkS")
			(hide yes)
			(effects
				(font
					(size 1.27 1.27)
				)
			)
		)
		(property "Value" ""
			(at 0 0 90)
			(layer "F.Fab")
			(effects
				(font
					(size 1.27 1.27)
				)
			)
		)
		(duplicate_pad_numbers_are_jumpers no)
		(fp_line
			(start 0.7874 -0.4064)
			(end 0.7874 0.4064)
			(stroke
				(width 0.1524)
				(type default)
			)
			(layer "F.SilkS")
		)
		(fp_line
			(start -0.7874 -0.4064)
			(end 0.7874 -0.4064)
			(stroke
				(width 0.1524)
				(type default)
			)
			(layer "F.SilkS")
		)
		(fp_line
			(start 0.7874 0.4064)
			(end -0.7874 0.4064)
			(stroke
				(width 0.1524)
				(type default)
			)
			(layer "F.SilkS")
		)
		(fp_line
			(start -0.7874 0.4064)
			(end -0.7874 -0.4064)
			(stroke
				(width 0.1524)
				(type default)
			)
			(layer "F.SilkS")
		)
		(fp_line
			(start 0.6858 -0.3048)
			(end 0.6858 0.3048)
			(stroke
				(width 0.1)
				(type default)
			)
			(layer "F.Fab")
		)
		(fp_line
			(start 0.1016 -0.3048)
			(end 0.6858 -0.3048)
			(stroke
				(width 0.1)
				(type default)
			)
			(layer "F.Fab")
		)
		(fp_line
			(start -0.1016 -0.3048)
			(end -0.1016 -0.2794)
			(stroke
				(width 0.1)
				(type default)
			)
			(layer "F.Fab")
		)
		(fp_line
			(start -0.6858 -0.3048)
			(end -0.1016 -0.3048)
			(stroke
				(width 0.1)
				(type default)
			)
			(layer "F.Fab")
		)
		(fp_line
			(start 0.1016 -0.2794)
			(end 0.1016 -0.3048)
			(stroke
				(width 0.1)
				(type default)
			)
			(layer "F.Fab")
		)
		(fp_line
			(start -0.1016 -0.2794)
			(end 0.1016 -0.2794)
			(stroke
				(width 0.1)
				(type default)
			)
			(layer "F.Fab")
		)
		(fp_line
			(start 0.1016 0.2794)
			(end -0.1016 0.2794)
			(stroke
				(width 0.1)
				(type default)
			)
			(layer "F.Fab")
		)
		(fp_line
			(start -0.1016 0.2794)
			(end -0.1016 0.3048)
			(stroke
				(width 0.1)
				(type default)
			)
			(layer "F.Fab")
		)
		(fp_line
			(start 0.6858 0.3048)
			(end 0.1016 0.3048)
			(stroke
				(width 0.1)
				(type default)
			)
			(layer "F.Fab")
		)
		(fp_line
			(start 0.1016 0.3048)
			(end 0.1016 0.2794)
			(stroke
				(width 0.1)
				(type default)
			)
			(layer "F.Fab")
		)
		(fp_line
			(start -0.1016 0.3048)
			(end -0.6858 0.3048)
			(stroke
				(width 0.1)
				(type default)
			)
			(layer "F.Fab")
		)
		(fp_line
			(start -0.6858 0.3048)
			(end -0.6858 -0.3048)
			(stroke
				(width 0.1)
				(type default)
			)
			(layer "F.Fab")
		)
		(pad "1" smd rect
			(at -0.40005 0 270)
			(size 0.4572 0.508)
			(layers "F.Cu" "F.Mask" "F.Paste")
			(net "USB3_CPU0_BMC_RX_HUB2_DN")
		)
		(pad "2" smd rect
			(at 0.40005 0 270)
			(size 0.4572 0.508)
			(layers "F.Cu" "F.Mask" "F.Paste")
			(net "USB3_CPU0_BMC_RX_HUB_C_DN")
		)
	)
	(footprint ""
		(layer "F.Cu")
		(at 277.352252 -123.08967)
		(property "Reference" "R1822"
			(at 0 0 0)
			(layer "F.SilkS")
			(hide yes)
			(effects
				(font
					(size 1.27 1.27)
				)
			)
		)
		(property "Value" ""
			(at 0 0 0)
			(layer "F.Fab")
			(effects
				(font
					(size 1.27 1.27)
				)
			)
		)
		(duplicate_pad_numbers_are_jumpers no)
		(fp_line
			(start -0.7874 -0.4064)
			(end 0.7874 -0.4064)
			(stroke
				(width 0.1524)
				(type default)
			)
			(layer "F.SilkS")
		)
		(fp_line
			(start -0.7874 0.4064)
			(end -0.7874 -0.4064)
			(stroke
				(width 0.1524)
				(type default)
			)
			(layer "F.SilkS")
		)
		(fp_line
			(start 0.7874 -0.4064)
			(end 0.7874 0.4064)
			(stroke
				(width 0.1524)
				(type default)
			)
			(layer "F.SilkS")
		)
		(fp_line
			(start 0.7874 0.4064)
			(end -0.7874 0.4064)
			(stroke
				(width 0.1524)
				(type default)
			)
			(layer "F.SilkS")
		)
		(fp_line
			(start -0.67945 -0.305054)
			(end -0.12065 -0.305054)
			(stroke
				(width 0.1)
				(type default)
			)
			(layer "F.Fab")
		)
		(fp_line
			(start -0.67945 0.3048)
			(end -0.67945 -0.305054)
			(stroke
				(width 0.1)
				(type default)
			)
			(layer "F.Fab")
		)
		(fp_line
			(start -0.12065 -0.305054)
			(end -0.12065 -0.2794)
			(stroke
				(width 0.1)
				(type default)
			)
			(layer "F.Fab")
		)
		(fp_line
			(start -0.12065 -0.2794)
			(end 0.12065 -0.2794)
			(stroke
				(width 0.1)
				(type default)
			)
			(layer "F.Fab")
		)
		(fp_line
			(start -0.12065 0.2794)
			(end -0.12065 0.3048)
			(stroke
				(width 0.1)
				(type default)
			)
			(layer "F.Fab")
		)
		(fp_line
			(start -0.12065 0.3048)
			(end -0.67945 0.3048)
			(stroke
				(width 0.1)
				(type default)
			)
			(layer "F.Fab")
		)
		(fp_line
			(start 0.120396 0.2794)
			(end -0.12065 0.2794)
			(stroke
				(width 0.1)
				(type default)
			)
			(layer "F.Fab")
		)
		(fp_line
			(start 0.120396 0.3048)
			(end 0.120396 0.2794)
			(stroke
				(width 0.1)
				(type default)
			)
			(layer "F.Fab")
		)
		(fp_line
			(start 0.12065 -0.3048)
			(end 0.67945 -0.3048)
			(stroke
				(width 0.1)
				(type default)
			)
			(layer "F.Fab")
		)
		(fp_line
			(start 0.12065 -0.2794)
			(end 0.12065 -0.3048)
			(stroke
				(width 0.1)
				(type default)
			)
			(layer "F.Fab")
		)
		(fp_line
			(start 0.67945 -0.3048)
			(end 0.67945 0.3048)
			(stroke
				(width 0.1)
				(type default)
			)
			(layer "F.Fab")
		)
		(fp_line
			(start 0.67945 0.3048)
			(end 0.120396 0.3048)
			(stroke
				(width 0.1)
				(type default)
			)
			(layer "F.Fab")
		)
		(pad "1" smd circle
			(at -0.40005 0)
			(size 0 0)
			(layers "F.Cu" "F.Mask" "F.Paste")
			(net "P3V3_AUX")
		)
		(pad "2" smd circle
			(at 0.40005 0)
			(size 0 0)
			(layers "F.Cu" "F.Mask" "F.Paste")
			(net "RST_SMB_SWITCH_N")
		)
	)
	(footprint ""
		(layer "F.Cu")
		(at 148.11375 -191.35471 -90)
		(property "Reference" "R3199"
			(at 0 0 270)
			(layer "F.SilkS")
			(hide yes)
			(effects
				(font
					(size 1.27 1.27)
				)
			)
		)
		(property "Value" ""
			(at 0 0 270)
			(layer "F.Fab")
			(effects
				(font
					(size 1.27 1.27)
				)
			)
		)
		(duplicate_pad_numbers_are_jumpers no)
		(fp_line
			(start 0.42291 0.4064)
			(end -0.33909 0.4064)
			(stroke
				(width 0.1524)
				(type default)
			)
			(layer "F.SilkS")
		)
		(fp_line
			(start -0.7874 -0.04445)
			(end -0.7874 -0.4064)
			(stroke
				(width 0.1524)
				(type default)
			)
			(layer "F.SilkS")
		)
		(fp_line
			(start -0.7874 -0.4064)
			(end 0.7874 -0.4064)
			(stroke
				(width 0.1524)
				(type default)
			)
			(layer "F.SilkS")
		)
		(fp_line
			(start 0.7874 -0.4064)
			(end 0.7874 -0.01905)
			(stroke
				(width 0.1524)
				(type default)
			)
			(layer "F.SilkS")
		)
		(fp_line
			(start -0.67945 0.3048)
			(end -0.67945 -0.305054)
			(stroke
				(width 0.1)
				(type default)
			)
			(layer "F.Fab")
		)
		(fp_line
			(start -0.12065 0.3048)
			(end -0.67945 0.3048)
			(stroke
				(width 0.1)
				(type default)
			)
			(layer "F.Fab")
		)
		(fp_line
			(start 0.120396 0.3048)
			(end 0.120396 0.2794)
			(stroke
				(width 0.1)
				(type default)
			)
			(layer "F.Fab")
		)
		(fp_line
			(start 0.67945 0.3048)
			(end 0.120396 0.3048)
			(stroke
				(width 0.1)
				(type default)
			)
			(layer "F.Fab")
		)
		(fp_line
			(start -0.12065 0.2794)
			(end -0.12065 0.3048)
			(stroke
				(width 0.1)
				(type default)
			)
			(layer "F.Fab")
		)
		(fp_line
			(start 0.120396 0.2794)
			(end -0.12065 0.2794)
			(stroke
				(width 0.1)
				(type default)
			)
			(layer "F.Fab")
		)
		(fp_line
			(start -0.12065 -0.2794)
			(end 0.12065 -0.2794)
			(stroke
				(width 0.1)
				(type default)
			)
			(layer "F.Fab")
		)
		(fp_line
			(start 0.12065 -0.2794)
			(end 0.12065 -0.3048)
			(stroke
				(width 0.1)
				(type default)
			)
			(layer "F.Fab")
		)
		(fp_line
			(start 0.12065 -0.3048)
			(end 0.67945 -0.3048)
			(stroke
				(width 0.1)
				(type default)
			)
			(layer "F.Fab")
		)
		(fp_line
			(start 0.67945 -0.3048)
			(end 0.67945 0.3048)
			(stroke
				(width 0.1)
				(type default)
			)
			(layer "F.Fab")
		)
		(fp_line
			(start -0.67945 -0.305054)
			(end -0.12065 -0.305054)
			(stroke
				(width 0.1)
				(type default)
			)
			(layer "F.Fab")
		)
		(fp_line
			(start -0.12065 -0.305054)
			(end -0.12065 -0.2794)
			(stroke
				(width 0.1)
				(type default)
			)
			(layer "F.Fab")
		)
		(pad "1" smd circle
			(at -0.40005 0 270)
			(size 0 0)
			(layers "F.Cu" "F.Mask" "F.Paste")
			(net "CLK_100M_CPU1_CLK04_R_DN")
		)
		(pad "2" smd circle
			(at 0.40005 0 270)
			(size 0 0)
			(layers "F.Cu" "F.Mask" "F.Paste")
			(net "CLK_100M_CPU1_CLK04_DN")
		)
	)
	(footprint ""
		(layer "F.Cu")
		(at 422.180766 -402.7424 -90)
		(property "Reference" "R1082"
			(at 0 0 270)
			(layer "F.SilkS")
			(hide yes)
			(effects
				(font
					(size 1.27 1.27)
				)
			)
		)
		(property "Value" ""
			(at 0 0 270)
			(layer "F.Fab")
			(effects
				(font
					(size 1.27 1.27)
				)
			)
		)
		(duplicate_pad_numbers_are_jumpers no)
		(fp_line
			(start -0.32512 0.175006)
			(end -0.32512 -0.175006)
			(stroke
				(width 0.1)
				(type default)
			)
			(layer "F.Fab")
		)
		(fp_line
			(start 0.32512 0.175006)
			(end -0.32512 0.175006)
			(stroke
				(width 0.1)
				(type default)
			)
			(layer "F.Fab")
		)
		(fp_line
			(start -0.32512 -0.175006)
			(end 0.32512 -0.175006)
			(stroke
				(width 0.1)
				(type default)
			)
			(layer "F.Fab")
		)
		(fp_line
			(start 0.32512 -0.175006)
			(end 0.32512 0.175006)
			(stroke
				(width 0.1)
				(type default)
			)
			(layer "F.Fab")
		)
		(pad "1" smd rect
			(at -0.2667 0 270)
			(size 0.3048 0.381)
			(layers "F.Cu" "F.Mask" "F.Paste")
			(net "RT_CPU0_P2_VQPS")
		)
		(pad "2" smd rect
			(at 0.2667 0 90)
			(size 0.3048 0.381)
			(layers "F.Cu" "F.Mask" "F.Paste")
			(net "GND")
		)
	)
	(footprint ""
		(layer "F.Cu")
		(at 72.635618 -341.04707 180)
		(property "Reference" "PC408_3"
			(at 0 0 180)
			(layer "F.SilkS")
			(hide yes)
			(effects
				(font
					(size 1.27 1.27)
				)
			)
		)
		(property "Value" ""
			(at 0 0 180)
			(layer "F.Fab")
			(effects
				(font
					(size 1.27 1.27)
				)
			)
		)
		(duplicate_pad_numbers_are_jumpers no)
		(fp_line
			(start 0.7874 0.4064)
			(end -0.7874 0.4064)
			(stroke
				(width 0.1524)
				(type default)
			)
			(layer "F.SilkS")
		)
		(fp_line
			(start 0.7874 -0.4064)
			(end 0.7874 0.4064)
			(stroke
				(width 0.1524)
				(type default)
			)
			(layer "F.SilkS")
		)
		(fp_line
			(start -0.7874 0.4064)
			(end -0.7874 -0.4064)
			(stroke
				(width 0.1524)
				(type default)
			)
			(layer "F.SilkS")
		)
		(fp_line
			(start -0.7874 -0.4064)
			(end 0.7874 -0.4064)
			(stroke
				(width 0.1524)
				(type default)
			)
			(layer "F.SilkS")
		)
		(fp_line
			(start 0.67945 0.3048)
			(end 0.120396 0.3048)
			(stroke
				(width 0.1)
				(type default)
			)
			(layer "F.Fab")
		)
		(fp_line
			(start 0.67945 -0.3048)
			(end 0.67945 0.3048)
			(stroke
				(width 0.1)
				(type default)
			)
			(layer "F.Fab")
		)
		(fp_line
			(start 0.12065 -0.2794)
			(end 0.12065 -0.3048)
			(stroke
				(width 0.1)
				(type default)
			)
			(layer "F.Fab")
		)
		(fp_line
			(start 0.12065 -0.3048)
			(end 0.67945 -0.3048)
			(stroke
				(width 0.1)
				(type default)
			)
			(layer "F.Fab")
		)
		(fp_line
			(start 0.120396 0.3048)
			(end 0.120396 0.2794)
			(stroke
				(width 0.1)
				(type default)
			)
			(layer "F.Fab")
		)
		(fp_line
			(start 0.120396 0.2794)
			(end -0.12065 0.2794)
			(stroke
				(width 0.1)
				(type default)
			)
			(layer "F.Fab")
		)
		(fp_line
			(start -0.12065 0.3048)
			(end -0.67945 0.3048)
			(stroke
				(width 0.1)
				(type default)
			)
			(layer "F.Fab")
		)
		(fp_line
			(start -0.12065 0.2794)
			(end -0.12065 0.3048)
			(stroke
				(width 0.1)
				(type default)
			)
			(layer "F.Fab")
		)
		(fp_line
			(start -0.12065 -0.2794)
			(end 0.12065 -0.2794)
			(stroke
				(width 0.1)
				(type default)
			)
			(layer "F.Fab")
		)
		(fp_line
			(start -0.12065 -0.305054)
			(end -0.12065 -0.2794)
			(stroke
				(width 0.1)
				(type default)
			)
			(layer "F.Fab")
		)
		(fp_line
			(start -0.67945 0.3048)
			(end -0.67945 -0.305054)
			(stroke
				(width 0.1)
				(type default)
			)
			(layer "F.Fab")
		)
		(fp_line
			(start -0.67945 -0.305054)
			(end -0.12065 -0.305054)
			(stroke
				(width 0.1)
				(type default)
			)
			(layer "F.Fab")
		)
		(pad "1" smd circle
			(at -0.40005 0 180)
			(size 0 0)
			(layers "F.Cu" "F.Mask" "F.Paste")
			(net "SW_P12V_AUX_PVDDCR_CPU1_P1_FLT")
		)
		(pad "2" smd circle
			(at 0.40005 0 180)
			(size 0 0)
			(layers "F.Cu" "F.Mask" "F.Paste")
			(net "GND")
		)
	)
	(footprint ""
		(layer "F.Cu")
		(at 18.384012 -358.30637 -90)
		(property "Reference" "R6088"
			(at 0 0 270)
			(layer "F.SilkS")
			(hide yes)
			(effects
				(font
					(size 1.27 1.27)
				)
			)
		)
		(property "Value" ""
			(at 0 0 270)
			(layer "F.Fab")
			(effects
				(font
					(size 1.27 1.27)
				)
			)
		)
		(duplicate_pad_numbers_are_jumpers no)
		(fp_line
			(start -0.7874 0.4064)
			(end -0.7874 -0.4064)
			(stroke
				(width 0.1524)
				(type default)
			)
			(layer "F.SilkS")
		)
		(fp_line
			(start 0.7874 0.4064)
			(end -0.7874 0.4064)
			(stroke
				(width 0.1524)
				(type default)
			)
			(layer "F.SilkS")
		)
		(fp_line
			(start -0.7874 -0.4064)
			(end 0.7874 -0.4064)
			(stroke
				(width 0.1524)
				(type default)
			)
			(layer "F.SilkS")
		)
		(fp_line
			(start 0.7874 -0.4064)
			(end 0.7874 0.4064)
			(stroke
				(width 0.1524)
				(type default)
			)
			(layer "F.SilkS")
		)
		(fp_line
			(start -0.67945 0.3048)
			(end -0.67945 -0.305054)
			(stroke
				(width 0.1)
				(type default)
			)
			(layer "F.Fab")
		)
		(fp_line
			(start -0.12065 0.3048)
			(end -0.67945 0.3048)
			(stroke
				(width 0.1)
				(type default)
			)
			(layer "F.Fab")
		)
		(fp_line
			(start 0.120396 0.3048)
			(end 0.120396 0.2794)
			(stroke
				(width 0.1)
				(type default)
			)
			(layer "F.Fab")
		)
		(fp_line
			(start 0.67945 0.3048)
			(end 0.120396 0.3048)
			(stroke
				(width 0.1)
				(type default)
			)
			(layer "F.Fab")
		)
		(fp_line
			(start -0.12065 0.2794)
			(end -0.12065 0.3048)
			(stroke
				(width 0.1)
				(type default)
			)
			(layer "F.Fab")
		)
		(fp_line
			(start 0.120396 0.2794)
			(end -0.12065 0.2794)
			(stroke
				(width 0.1)
				(type default)
			)
			(layer "F.Fab")
		)
		(fp_line
			(start -0.12065 -0.2794)
			(end 0.12065 -0.2794)
			(stroke
				(width 0.1)
				(type default)
			)
			(layer "F.Fab")
		)
		(fp_line
			(start 0.12065 -0.2794)
			(end 0.12065 -0.3048)
			(stroke
				(width 0.1)
				(type default)
			)
			(layer "F.Fab")
		)
		(fp_line
			(start 0.12065 -0.3048)
			(end 0.67945 -0.3048)
			(stroke
				(width 0.1)
				(type default)
			)
			(layer "F.Fab")
		)
		(fp_line
			(start 0.67945 -0.3048)
			(end 0.67945 0.3048)
			(stroke
				(width 0.1)
				(type default)
			)
			(layer "F.Fab")
		)
		(fp_line
			(start -0.67945 -0.305054)
			(end -0.12065 -0.305054)
			(stroke
				(width 0.1)
				(type default)
			)
			(layer "F.Fab")
		)
		(fp_line
			(start -0.12065 -0.305054)
			(end -0.12065 -0.2794)
			(stroke
				(width 0.1)
				(type default)
			)
			(layer "F.Fab")
		)
		(pad "1" smd circle
			(at -0.40005 0 270)
			(size 0 0)
			(layers "F.Cu" "F.Mask" "F.Paste")
			(net "PVDDIO_P1_EN_R")
		)
		(pad "2" smd circle
			(at 0.40005 0 270)
			(size 0 0)
			(layers "F.Cu" "F.Mask" "F.Paste")
			(net "GND")
		)
	)
	(footprint ""
		(layer "F.Cu")
		(at 143.531844 -373.03583 -90)
		(property "Reference" "C768"
			(at 0 0 270)
			(layer "F.SilkS")
			(hide yes)
			(effects
				(font
					(size 1.27 1.27)
				)
			)
		)
		(property "Value" ""
			(at 0 0 270)
			(layer "F.Fab")
			(effects
				(font
					(size 1.27 1.27)
				)
			)
		)
		(duplicate_pad_numbers_are_jumpers no)
		(fp_line
			(start -0.299974 0.150114)
			(end -0.299974 -0.150114)
			(stroke
				(width 0.1)
				(type default)
			)
			(layer "F.Fab")
		)
		(fp_line
			(start 0.299974 0.150114)
			(end -0.299974 0.150114)
			(stroke
				(width 0.1)
				(type default)
			)
			(layer "F.Fab")
		)
		(fp_line
			(start -0.299974 -0.150114)
			(end 0.299974 -0.150114)
			(stroke
				(width 0.1)
				(type default)
			)
			(layer "F.Fab")
		)
		(fp_line
			(start 0.299974 -0.150114)
			(end 0.299974 0.150114)
			(stroke
				(width 0.1)
				(type default)
			)
			(layer "F.Fab")
		)
		(pad "1" smd rect
			(at -0.2667 0 270)
			(size 0.3048 0.381)
			(layers "F.Cu" "F.Mask" "F.Paste")
			(net "P5E_CPU1_P2_TX_C_DN<2>")
		)
		(pad "2" smd rect
			(at 0.2667 0 270)
			(size 0.3048 0.381)
			(layers "F.Cu" "F.Mask" "F.Paste")
			(net "P5E_CPU1_P2_TX_DN<2>")
		)
	)
	(footprint ""
		(layer "F.Cu")
		(at 236.003338 -416.997642)
		(property "Reference" "FS1"
			(at -6.4262 -2.64033 0)
			(unlocked yes)
			(layer "F.SilkS")
			(effects
				(font
					(size 0.7874 0.5842)
					(thickness 0.1524)
				)
				(justify left)
			)
		)
		(property "Value" ""
			(at 0 0 0)
			(layer "F.Fab")
			(effects
				(font
					(size 1.27 1.27)
				)
			)
		)
		(duplicate_pad_numbers_are_jumpers no)
		(fp_line
			(start -6.427724 -1.8415)
			(end -6.427724 1.8415)
			(stroke
				(width 0.1524)
				(type default)
			)
			(layer "F.SilkS")
		)
		(fp_line
			(start -6.427724 1.8415)
			(end 6.427724 1.8415)
			(stroke
				(width 0.1524)
				(type default)
			)
			(layer "F.SilkS")
		)
		(fp_line
			(start 6.427724 -1.8415)
			(end -6.427724 -1.8415)
			(stroke
				(width 0.1524)
				(type default)
			)
			(layer "F.SilkS")
		)
		(fp_line
			(start 6.427724 1.8415)
			(end 6.427724 -1.8415)
			(stroke
				(width 0.1524)
				(type default)
			)
			(layer "F.SilkS")
		)
		(fp_line
			(start -5.225034 -1.610106)
			(end 5.225034 -1.610106)
			(stroke
				(width 0.1)
				(type default)
			)
			(layer "F.Fab")
		)
		(fp_line
			(start -5.225034 1.610106)
			(end -5.225034 -1.610106)
			(stroke
				(width 0.1)
				(type default)
			)
			(layer "F.Fab")
		)
		(fp_line
			(start 5.225034 -1.610106)
			(end 5.225034 1.610106)
			(stroke
				(width 0.1)
				(type default)
			)
			(layer "F.Fab")
		)
		(fp_line
			(start 5.225034 1.610106)
			(end -5.225034 1.610106)
			(stroke
				(width 0.1)
				(type default)
			)
			(layer "F.Fab")
		)
		(pad "1" smd rect
			(at -4.675124 0)
			(size 3.2512 3.429)
			(layers "F.Cu" "F.Mask" "F.Paste")
			(net "P12V_PSU")
		)
		(pad "2" smd rect
			(at 4.675124 0)
			(size 3.2512 3.429)
			(layers "F.Cu" "F.Mask" "F.Paste")
			(net "P12V_PSU_FUSE")
		)
	)
	(footprint ""
		(layer "F.Cu")
		(at 61.845698 -26.99004 90)
		(property "Reference" "PR3852"
			(at 0 0 90)
			(layer "F.SilkS")
			(hide yes)
			(effects
				(font
					(size 1.27 1.27)
				)
			)
		)
		(property "Value" ""
			(at 0 0 90)
			(layer "F.Fab")
			(effects
				(font
					(size 1.27 1.27)
				)
			)
		)
		(duplicate_pad_numbers_are_jumpers no)
		(fp_line
			(start 0.7874 -0.4064)
			(end 0.7874 0.4064)
			(stroke
				(width 0.1524)
				(type default)
			)
			(layer "F.SilkS")
		)
		(fp_line
			(start -0.7874 -0.4064)
			(end 0.7874 -0.4064)
			(stroke
				(width 0.1524)
				(type default)
			)
			(layer "F.SilkS")
		)
		(fp_line
			(start 0.7874 0.4064)
			(end -0.7874 0.4064)
			(stroke
				(width 0.1524)
				(type default)
			)
			(layer "F.SilkS")
		)
		(fp_line
			(start -0.7874 0.4064)
			(end -0.7874 -0.4064)
			(stroke
				(width 0.1524)
				(type default)
			)
			(layer "F.SilkS")
		)
		(fp_line
			(start -0.12065 -0.305054)
			(end -0.12065 -0.2794)
			(stroke
				(width 0.1)
				(type default)
			)
			(layer "F.Fab")
		)
		(fp_line
			(start -0.67945 -0.305054)
			(end -0.12065 -0.305054)
			(stroke
				(width 0.1)
				(type default)
			)
			(layer "F.Fab")
		)
		(fp_line
			(start 0.67945 -0.3048)
			(end 0.67945 0.3048)
			(stroke
				(width 0.1)
				(type default)
			)
			(layer "F.Fab")
		)
		(fp_line
			(start 0.12065 -0.3048)
			(end 0.67945 -0.3048)
			(stroke
				(width 0.1)
				(type default)
			)
			(layer "F.Fab")
		)
		(fp_line
			(start 0.12065 -0.2794)
			(end 0.12065 -0.3048)
			(stroke
				(width 0.1)
				(type default)
			)
			(layer "F.Fab")
		)
		(fp_line
			(start -0.12065 -0.2794)
			(end 0.12065 -0.2794)
			(stroke
				(width 0.1)
				(type default)
			)
			(layer "F.Fab")
		)
		(fp_line
			(start 0.120396 0.2794)
			(end -0.12065 0.2794)
			(stroke
				(width 0.1)
				(type default)
			)
			(layer "F.Fab")
		)
		(fp_line
			(start -0.12065 0.2794)
			(end -0.12065 0.3048)
			(stroke
				(width 0.1)
				(type default)
			)
			(layer "F.Fab")
		)
		(fp_line
			(start 0.67945 0.3048)
			(end 0.120396 0.3048)
			(stroke
				(width 0.1)
				(type default)
			)
			(layer "F.Fab")
		)
		(fp_line
			(start 0.120396 0.3048)
			(end 0.120396 0.2794)
			(stroke
				(width 0.1)
				(type default)
			)
			(layer "F.Fab")
		)
		(fp_line
			(start -0.12065 0.3048)
			(end -0.67945 0.3048)
			(stroke
				(width 0.1)
				(type default)
			)
			(layer "F.Fab")
		)
		(fp_line
			(start -0.67945 0.3048)
			(end -0.67945 -0.305054)
			(stroke
				(width 0.1)
				(type default)
			)
			(layer "F.Fab")
		)
		(pad "1" smd circle
			(at -0.40005 0 90)
			(size 0 0)
			(layers "F.Cu" "F.Mask" "F.Paste")
			(net "P12V_OCP_V3_2")
		)
		(pad "2" smd circle
			(at 0.40005 0 90)
			(size 0 0)
			(layers "F.Cu" "F.Mask" "F.Paste")
			(net "P12V_OCP_OV_FB_2")
		)
	)
	(footprint ""
		(layer "F.Cu")
		(at 204.7621 -406.052782)
		(property "Reference" "PR3920"
			(at 0 0 0)
			(layer "F.SilkS")
			(hide yes)
			(effects
				(font
					(size 1.27 1.27)
				)
			)
		)
		(property "Value" ""
			(at 0 0 0)
			(layer "F.Fab")
			(effects
				(font
					(size 1.27 1.27)
				)
			)
		)
		(duplicate_pad_numbers_are_jumpers no)
		(fp_line
			(start -0.7874 -0.4064)
			(end 0.7874 -0.4064)
			(stroke
				(width 0.1524)
				(type default)
			)
			(layer "F.SilkS")
		)
		(fp_line
			(start -0.7874 0.4064)
			(end -0.7874 -0.4064)
			(stroke
				(width 0.1524)
				(type default)
			)
			(layer "F.SilkS")
		)
		(fp_line
			(start 0.7874 -0.4064)
			(end 0.7874 0.4064)
			(stroke
				(width 0.1524)
				(type default)
			)
			(layer "F.SilkS")
		)
		(fp_line
			(start 0.7874 0.4064)
			(end -0.7874 0.4064)
			(stroke
				(width 0.1524)
				(type default)
			)
			(layer "F.SilkS")
		)
		(fp_line
			(start -0.67945 -0.305054)
			(end -0.12065 -0.305054)
			(stroke
				(width 0.1)
				(type default)
			)
			(layer "F.Fab")
		)
		(fp_line
			(start -0.67945 0.3048)
			(end -0.67945 -0.305054)
			(stroke
				(width 0.1)
				(type default)
			)
			(layer "F.Fab")
		)
		(fp_line
			(start -0.12065 -0.305054)
			(end -0.12065 -0.2794)
			(stroke
				(width 0.1)
				(type default)
			)
			(layer "F.Fab")
		)
		(fp_line
			(start -0.12065 -0.2794)
			(end 0.12065 -0.2794)
			(stroke
				(width 0.1)
				(type default)
			)
			(layer "F.Fab")
		)
		(fp_line
			(start -0.12065 0.2794)
			(end -0.12065 0.3048)
			(stroke
				(width 0.1)
				(type default)
			)
			(layer "F.Fab")
		)
		(fp_line
			(start -0.12065 0.3048)
			(end -0.67945 0.3048)
			(stroke
				(width 0.1)
				(type default)
			)
			(layer "F.Fab")
		)
		(fp_line
			(start 0.120396 0.2794)
			(end -0.12065 0.2794)
			(stroke
				(width 0.1)
				(type default)
			)
			(layer "F.Fab")
		)
		(fp_line
			(start 0.120396 0.3048)
			(end 0.120396 0.2794)
			(stroke
				(width 0.1)
				(type default)
			)
			(layer "F.Fab")
		)
		(fp_line
			(start 0.12065 -0.3048)
			(end 0.67945 -0.3048)
			(stroke
				(width 0.1)
				(type default)
			)
			(layer "F.Fab")
		)
		(fp_line
			(start 0.12065 -0.2794)
			(end 0.12065 -0.3048)
			(stroke
				(width 0.1)
				(type default)
			)
			(layer "F.Fab")
		)
		(fp_line
			(start 0.67945 -0.3048)
			(end 0.67945 0.3048)
			(stroke
				(width 0.1)
				(type default)
			)
			(layer "F.Fab")
		)
		(fp_line
			(start 0.67945 0.3048)
			(end 0.120396 0.3048)
			(stroke
				(width 0.1)
				(type default)
			)
			(layer "F.Fab")
		)
		(pad "1" smd circle
			(at -0.40005 0)
			(size 0 0)
			(layers "F.Cu" "F.Mask" "F.Paste")
			(net "HSC_FLT_TYPE_1")
		)
		(pad "2" smd circle
			(at 0.40005 0)
			(size 0 0)
			(layers "F.Cu" "F.Mask" "F.Paste")
			(net "HSC_FLT_TYPE")
		)
	)
	(footprint ""
		(layer "F.Cu")
		(at 279.659842 -415.1376)
		(property "Reference" "R6865"
			(at 0 0 0)
			(layer "F.SilkS")
			(hide yes)
			(effects
				(font
					(size 1.27 1.27)
				)
			)
		)
		(property "Value" ""
			(at 0 0 0)
			(layer "F.Fab")
			(effects
				(font
					(size 1.27 1.27)
				)
			)
		)
		(duplicate_pad_numbers_are_jumpers no)
		(fp_line
			(start -0.7874 -0.4064)
			(end 0.7874 -0.4064)
			(stroke
				(width 0.1524)
				(type default)
			)
			(layer "F.SilkS")
		)
		(fp_line
			(start -0.7874 0.4064)
			(end -0.7874 -0.4064)
			(stroke
				(width 0.1524)
				(type default)
			)
			(layer "F.SilkS")
		)
		(fp_line
			(start 0.7874 -0.4064)
			(end 0.7874 0.4064)
			(stroke
				(width 0.1524)
				(type default)
			)
			(layer "F.SilkS")
		)
		(fp_line
			(start 0.7874 0.4064)
			(end -0.7874 0.4064)
			(stroke
				(width 0.1524)
				(type default)
			)
			(layer "F.SilkS")
		)
		(fp_line
			(start -0.67945 -0.305054)
			(end -0.12065 -0.305054)
			(stroke
				(width 0.1)
				(type default)
			)
			(layer "F.Fab")
		)
		(fp_line
			(start -0.67945 0.3048)
			(end -0.67945 -0.305054)
			(stroke
				(width 0.1)
				(type default)
			)
			(layer "F.Fab")
		)
		(fp_line
			(start -0.12065 -0.305054)
			(end -0.12065 -0.2794)
			(stroke
				(width 0.1)
				(type default)
			)
			(layer "F.Fab")
		)
		(fp_line
			(start -0.12065 -0.2794)
			(end 0.12065 -0.2794)
			(stroke
				(width 0.1)
				(type default)
			)
			(layer "F.Fab")
		)
		(fp_line
			(start -0.12065 0.2794)
			(end -0.12065 0.3048)
			(stroke
				(width 0.1)
				(type default)
			)
			(layer "F.Fab")
		)
		(fp_line
			(start -0.12065 0.3048)
			(end -0.67945 0.3048)
			(stroke
				(width 0.1)
				(type default)
			)
			(layer "F.Fab")
		)
		(fp_line
			(start 0.120396 0.2794)
			(end -0.12065 0.2794)
			(stroke
				(width 0.1)
				(type default)
			)
			(layer "F.Fab")
		)
		(fp_line
			(start 0.120396 0.3048)
			(end 0.120396 0.2794)
			(stroke
				(width 0.1)
				(type default)
			)
			(layer "F.Fab")
		)
		(fp_line
			(start 0.12065 -0.3048)
			(end 0.67945 -0.3048)
			(stroke
				(width 0.1)
				(type default)
			)
			(layer "F.Fab")
		)
		(fp_line
			(start 0.12065 -0.2794)
			(end 0.12065 -0.3048)
			(stroke
				(width 0.1)
				(type default)
			)
			(layer "F.Fab")
		)
		(fp_line
			(start 0.67945 -0.3048)
			(end 0.67945 0.3048)
			(stroke
				(width 0.1)
				(type default)
			)
			(layer "F.Fab")
		)
		(fp_line
			(start 0.67945 0.3048)
			(end 0.120396 0.3048)
			(stroke
				(width 0.1)
				(type default)
			)
			(layer "F.Fab")
		)
		(pad "1" smd circle
			(at -0.40005 0)
			(size 0 0)
			(layers "F.Cu" "F.Mask" "F.Paste")
			(net "SMB_HOST_CLK_3V3AUX_SDA_R1")
		)
		(pad "2" smd circle
			(at 0.40005 0)
			(size 0 0)
			(layers "F.Cu" "F.Mask" "F.Paste")
			(net "SMB_9ZXL045_P0_SDA")
		)
	)
	(footprint ""
		(layer "F.Cu")
		(at 257.242056 -114.84737 180)
		(property "Reference" "R3719"
			(at 0 0 180)
			(layer "F.SilkS")
			(hide yes)
			(effects
				(font
					(size 1.27 1.27)
				)
			)
		)
		(property "Value" ""
			(at 0 0 180)
			(layer "F.Fab")
			(effects
				(font
					(size 1.27 1.27)
				)
			)
		)
		(duplicate_pad_numbers_are_jumpers no)
		(fp_line
			(start 0.7874 0.4064)
			(end -0.7874 0.4064)
			(stroke
				(width 0.1524)
				(type default)
			)
			(layer "F.SilkS")
		)
		(fp_line
			(start 0.7874 -0.4064)
			(end 0.7874 0.4064)
			(stroke
				(width 0.1524)
				(type default)
			)
			(layer "F.SilkS")
		)
		(fp_line
			(start -0.7874 0.4064)
			(end -0.7874 -0.4064)
			(stroke
				(width 0.1524)
				(type default)
			)
			(layer "F.SilkS")
		)
		(fp_line
			(start -0.7874 -0.4064)
			(end 0.7874 -0.4064)
			(stroke
				(width 0.1524)
				(type default)
			)
			(layer "F.SilkS")
		)
		(fp_line
			(start 0.67945 0.3048)
			(end 0.120396 0.3048)
			(stroke
				(width 0.1)
				(type default)
			)
			(layer "F.Fab")
		)
		(fp_line
			(start 0.67945 -0.3048)
			(end 0.67945 0.3048)
			(stroke
				(width 0.1)
				(type default)
			)
			(layer "F.Fab")
		)
		(fp_line
			(start 0.12065 -0.2794)
			(end 0.12065 -0.3048)
			(stroke
				(width 0.1)
				(type default)
			)
			(layer "F.Fab")
		)
		(fp_line
			(start 0.12065 -0.3048)
			(end 0.67945 -0.3048)
			(stroke
				(width 0.1)
				(type default)
			)
			(layer "F.Fab")
		)
		(fp_line
			(start 0.120396 0.3048)
			(end 0.120396 0.2794)
			(stroke
				(width 0.1)
				(type default)
			)
			(layer "F.Fab")
		)
		(fp_line
			(start 0.120396 0.2794)
			(end -0.12065 0.2794)
			(stroke
				(width 0.1)
				(type default)
			)
			(layer "F.Fab")
		)
		(fp_line
			(start -0.12065 0.3048)
			(end -0.67945 0.3048)
			(stroke
				(width 0.1)
				(type default)
			)
			(layer "F.Fab")
		)
		(fp_line
			(start -0.12065 0.2794)
			(end -0.12065 0.3048)
			(stroke
				(width 0.1)
				(type default)
			)
			(layer "F.Fab")
		)
		(fp_line
			(start -0.12065 -0.2794)
			(end 0.12065 -0.2794)
			(stroke
				(width 0.1)
				(type default)
			)
			(layer "F.Fab")
		)
		(fp_line
			(start -0.12065 -0.305054)
			(end -0.12065 -0.2794)
			(stroke
				(width 0.1)
				(type default)
			)
			(layer "F.Fab")
		)
		(fp_line
			(start -0.67945 0.3048)
			(end -0.67945 -0.305054)
			(stroke
				(width 0.1)
				(type default)
			)
			(layer "F.Fab")
		)
		(fp_line
			(start -0.67945 -0.305054)
			(end -0.12065 -0.305054)
			(stroke
				(width 0.1)
				(type default)
			)
			(layer "F.Fab")
		)
		(pad "1" smd circle
			(at -0.40005 0 180)
			(size 0 0)
			(layers "F.Cu" "F.Mask" "F.Paste")
			(net "SMB_LM75_2_3V3AUX_SCL_R")
		)
		(pad "2" smd circle
			(at 0.40005 0 180)
			(size 0 0)
			(layers "F.Cu" "F.Mask" "F.Paste")
			(net "SMB_LM75_2_3V3AUX_SCL")
		)
	)
	(footprint ""
		(layer "F.Cu")
		(at 49.38268 -35.804348 180)
		(property "Reference" "R3206"
			(at 0 0 180)
			(layer "F.SilkS")
			(hide yes)
			(effects
				(font
					(size 1.27 1.27)
				)
			)
		)
		(property "Value" ""
			(at 0 0 180)
			(layer "F.Fab")
			(effects
				(font
					(size 1.27 1.27)
				)
			)
		)
		(duplicate_pad_numbers_are_jumpers no)
		(fp_line
			(start 0.7874 0.4064)
			(end -0.7874 0.4064)
			(stroke
				(width 0.1524)
				(type default)
			)
			(layer "F.SilkS")
		)
		(fp_line
			(start 0.7874 -0.4064)
			(end 0.7874 0.4064)
			(stroke
				(width 0.1524)
				(type default)
			)
			(layer "F.SilkS")
		)
		(fp_line
			(start -0.7874 0.4064)
			(end -0.7874 -0.4064)
			(stroke
				(width 0.1524)
				(type default)
			)
			(layer "F.SilkS")
		)
		(fp_line
			(start -0.7874 -0.4064)
			(end 0.7874 -0.4064)
			(stroke
				(width 0.1524)
				(type default)
			)
			(layer "F.SilkS")
		)
		(fp_line
			(start 0.67945 0.3048)
			(end 0.120396 0.3048)
			(stroke
				(width 0.1)
				(type default)
			)
			(layer "F.Fab")
		)
		(fp_line
			(start 0.67945 -0.3048)
			(end 0.67945 0.3048)
			(stroke
				(width 0.1)
				(type default)
			)
			(layer "F.Fab")
		)
		(fp_line
			(start 0.12065 -0.2794)
			(end 0.12065 -0.3048)
			(stroke
				(width 0.1)
				(type default)
			)
			(layer "F.Fab")
		)
		(fp_line
			(start 0.12065 -0.3048)
			(end 0.67945 -0.3048)
			(stroke
				(width 0.1)
				(type default)
			)
			(layer "F.Fab")
		)
		(fp_line
			(start 0.120396 0.3048)
			(end 0.120396 0.2794)
			(stroke
				(width 0.1)
				(type default)
			)
			(layer "F.Fab")
		)
		(fp_line
			(start 0.120396 0.2794)
			(end -0.12065 0.2794)
			(stroke
				(width 0.1)
				(type default)
			)
			(layer "F.Fab")
		)
		(fp_line
			(start -0.12065 0.3048)
			(end -0.67945 0.3048)
			(stroke
				(width 0.1)
				(type default)
			)
			(layer "F.Fab")
		)
		(fp_line
			(start -0.12065 0.2794)
			(end -0.12065 0.3048)
			(stroke
				(width 0.1)
				(type default)
			)
			(layer "F.Fab")
		)
		(fp_line
			(start -0.12065 -0.2794)
			(end 0.12065 -0.2794)
			(stroke
				(width 0.1)
				(type default)
			)
			(layer "F.Fab")
		)
		(fp_line
			(start -0.12065 -0.305054)
			(end -0.12065 -0.2794)
			(stroke
				(width 0.1)
				(type default)
			)
			(layer "F.Fab")
		)
		(fp_line
			(start -0.67945 0.3048)
			(end -0.67945 -0.305054)
			(stroke
				(width 0.1)
				(type default)
			)
			(layer "F.Fab")
		)
		(fp_line
			(start -0.67945 -0.305054)
			(end -0.12065 -0.305054)
			(stroke
				(width 0.1)
				(type default)
			)
			(layer "F.Fab")
		)
		(pad "1" smd circle
			(at -0.40005 0 180)
			(size 0 0)
			(layers "F.Cu" "F.Mask" "F.Paste")
			(net "FM_NCSI_OCP_V3_2_R_OE")
		)
		(pad "2" smd circle
			(at 0.40005 0 180)
			(size 0 0)
			(layers "F.Cu" "F.Mask" "F.Paste")
			(net "FB_BMC_ISOLATE1")
		)
	)
	(footprint ""
		(layer "F.Cu")
		(at 151.966676 -50.739294 90)
		(property "Reference" "R3591"
			(at 0 0 90)
			(layer "F.SilkS")
			(hide yes)
			(effects
				(font
					(size 1.27 1.27)
				)
			)
		)
		(property "Value" ""
			(at 0 0 90)
			(layer "F.Fab")
			(effects
				(font
					(size 1.27 1.27)
				)
			)
		)
		(duplicate_pad_numbers_are_jumpers no)
		(fp_line
			(start 0.7874 -0.4064)
			(end 0.7874 0.4064)
			(stroke
				(width 0.1524)
				(type default)
			)
			(layer "F.SilkS")
		)
		(fp_line
			(start -0.7874 -0.4064)
			(end 0.7874 -0.4064)
			(stroke
				(width 0.1524)
				(type default)
			)
			(layer "F.SilkS")
		)
		(fp_line
			(start 0.7874 0.4064)
			(end -0.7874 0.4064)
			(stroke
				(width 0.1524)
				(type default)
			)
			(layer "F.SilkS")
		)
		(fp_line
			(start -0.7874 0.4064)
			(end -0.7874 -0.4064)
			(stroke
				(width 0.1524)
				(type default)
			)
			(layer "F.SilkS")
		)
		(fp_line
			(start -0.12065 -0.305054)
			(end -0.12065 -0.2794)
			(stroke
				(width 0.1)
				(type default)
			)
			(layer "F.Fab")
		)
		(fp_line
			(start -0.67945 -0.305054)
			(end -0.12065 -0.305054)
			(stroke
				(width 0.1)
				(type default)
			)
			(layer "F.Fab")
		)
		(fp_line
			(start 0.67945 -0.3048)
			(end 0.67945 0.3048)
			(stroke
				(width 0.1)
				(type default)
			)
			(layer "F.Fab")
		)
		(fp_line
			(start 0.12065 -0.3048)
			(end 0.67945 -0.3048)
			(stroke
				(width 0.1)
				(type default)
			)
			(layer "F.Fab")
		)
		(fp_line
			(start 0.12065 -0.2794)
			(end 0.12065 -0.3048)
			(stroke
				(width 0.1)
				(type default)
			)
			(layer "F.Fab")
		)
		(fp_line
			(start -0.12065 -0.2794)
			(end 0.12065 -0.2794)
			(stroke
				(width 0.1)
				(type default)
			)
			(layer "F.Fab")
		)
		(fp_line
			(start 0.120396 0.2794)
			(end -0.12065 0.2794)
			(stroke
				(width 0.1)
				(type default)
			)
			(layer "F.Fab")
		)
		(fp_line
			(start -0.12065 0.2794)
			(end -0.12065 0.3048)
			(stroke
				(width 0.1)
				(type default)
			)
			(layer "F.Fab")
		)
		(fp_line
			(start 0.67945 0.3048)
			(end 0.120396 0.3048)
			(stroke
				(width 0.1)
				(type default)
			)
			(layer "F.Fab")
		)
		(fp_line
			(start 0.120396 0.3048)
			(end 0.120396 0.2794)
			(stroke
				(width 0.1)
				(type default)
			)
			(layer "F.Fab")
		)
		(fp_line
			(start -0.12065 0.3048)
			(end -0.67945 0.3048)
			(stroke
				(width 0.1)
				(type default)
			)
			(layer "F.Fab")
		)
		(fp_line
			(start -0.67945 0.3048)
			(end -0.67945 -0.305054)
			(stroke
				(width 0.1)
				(type default)
			)
			(layer "F.Fab")
		)
		(pad "1" smd circle
			(at -0.40005 0 90)
			(size 0 0)
			(layers "F.Cu" "F.Mask" "F.Paste")
			(net "SMB_INA230_3V3AUX_SDA")
		)
		(pad "2" smd circle
			(at 0.40005 0 90)
			(size 0 0)
			(layers "F.Cu" "F.Mask" "F.Paste")
			(net "SMB_INA230_3_3V3AUX_SDA_R")
		)
	)
	(footprint ""
		(layer "F.Cu")
		(at 437.221376 -16.244824 -90)
		(property "Reference" "R39"
			(at 0 0 270)
			(layer "F.SilkS")
			(hide yes)
			(effects
				(font
					(size 1.27 1.27)
				)
			)
		)
		(property "Value" ""
			(at 0 0 270)
			(layer "F.Fab")
			(effects
				(font
					(size 1.27 1.27)
				)
			)
		)
		(duplicate_pad_numbers_are_jumpers no)
		(fp_line
			(start -0.7874 0.4064)
			(end -0.7874 -0.4064)
			(stroke
				(width 0.1524)
				(type default)
			)
			(layer "F.SilkS")
		)
		(fp_line
			(start 0.7874 0.4064)
			(end -0.7874 0.4064)
			(stroke
				(width 0.1524)
				(type default)
			)
			(layer "F.SilkS")
		)
		(fp_line
			(start -0.7874 -0.4064)
			(end 0.7874 -0.4064)
			(stroke
				(width 0.1524)
				(type default)
			)
			(layer "F.SilkS")
		)
		(fp_line
			(start 0.7874 -0.4064)
			(end 0.7874 0.4064)
			(stroke
				(width 0.1524)
				(type default)
			)
			(layer "F.SilkS")
		)
		(fp_line
			(start -0.67945 0.3048)
			(end -0.67945 -0.305054)
			(stroke
				(width 0.1)
				(type default)
			)
			(layer "F.Fab")
		)
		(fp_line
			(start -0.12065 0.3048)
			(end -0.67945 0.3048)
			(stroke
				(width 0.1)
				(type default)
			)
			(layer "F.Fab")
		)
		(fp_line
			(start 0.120396 0.3048)
			(end 0.120396 0.2794)
			(stroke
				(width 0.1)
				(type default)
			)
			(layer "F.Fab")
		)
		(fp_line
			(start 0.67945 0.3048)
			(end 0.120396 0.3048)
			(stroke
				(width 0.1)
				(type default)
			)
			(layer "F.Fab")
		)
		(fp_line
			(start -0.12065 0.2794)
			(end -0.12065 0.3048)
			(stroke
				(width 0.1)
				(type default)
			)
			(layer "F.Fab")
		)
		(fp_line
			(start 0.120396 0.2794)
			(end -0.12065 0.2794)
			(stroke
				(width 0.1)
				(type default)
			)
			(layer "F.Fab")
		)
		(fp_line
			(start -0.12065 -0.2794)
			(end 0.12065 -0.2794)
			(stroke
				(width 0.1)
				(type default)
			)
			(layer "F.Fab")
		)
		(fp_line
			(start 0.12065 -0.2794)
			(end 0.12065 -0.3048)
			(stroke
				(width 0.1)
				(type default)
			)
			(layer "F.Fab")
		)
		(fp_line
			(start 0.12065 -0.3048)
			(end 0.67945 -0.3048)
			(stroke
				(width 0.1)
				(type default)
			)
			(layer "F.Fab")
		)
		(fp_line
			(start 0.67945 -0.3048)
			(end 0.67945 0.3048)
			(stroke
				(width 0.1)
				(type default)
			)
			(layer "F.Fab")
		)
		(fp_line
			(start -0.67945 -0.305054)
			(end -0.12065 -0.305054)
			(stroke
				(width 0.1)
				(type default)
			)
			(layer "F.Fab")
		)
		(fp_line
			(start -0.12065 -0.305054)
			(end -0.12065 -0.2794)
			(stroke
				(width 0.1)
				(type default)
			)
			(layer "F.Fab")
		)
		(pad "1" smd circle
			(at -0.40005 0 270)
			(size 0 0)
			(layers "F.Cu" "F.Mask" "F.Paste")
			(net "OCP_SFF_ISO_BIF0_EN")
		)
		(pad "2" smd circle
			(at 0.40005 0 270)
			(size 0 0)
			(layers "F.Cu" "F.Mask" "F.Paste")
			(net "OCP_SFF_BIF0_R_N")
		)
	)
	(footprint ""
		(layer "F.Cu")
		(at 329.360022 -36.001706 180)
		(property "Reference" "R1792"
			(at 0 0 180)
			(layer "F.SilkS")
			(hide yes)
			(effects
				(font
					(size 1.27 1.27)
				)
			)
		)
		(property "Value" ""
			(at 0 0 180)
			(layer "F.Fab")
			(effects
				(font
					(size 1.27 1.27)
				)
			)
		)
		(duplicate_pad_numbers_are_jumpers no)
		(fp_line
			(start 0.7874 0.4064)
			(end -0.7874 0.4064)
			(stroke
				(width 0.1524)
				(type default)
			)
			(layer "F.SilkS")
		)
		(fp_line
			(start 0.7874 -0.4064)
			(end 0.7874 0.4064)
			(stroke
				(width 0.1524)
				(type default)
			)
			(layer "F.SilkS")
		)
		(fp_line
			(start -0.7874 0.4064)
			(end -0.7874 -0.4064)
			(stroke
				(width 0.1524)
				(type default)
			)
			(layer "F.SilkS")
		)
		(fp_line
			(start -0.7874 -0.4064)
			(end 0.7874 -0.4064)
			(stroke
				(width 0.1524)
				(type default)
			)
			(layer "F.SilkS")
		)
		(fp_line
			(start 0.67945 0.3048)
			(end 0.120396 0.3048)
			(stroke
				(width 0.1)
				(type default)
			)
			(layer "F.Fab")
		)
		(fp_line
			(start 0.67945 -0.3048)
			(end 0.67945 0.3048)
			(stroke
				(width 0.1)
				(type default)
			)
			(layer "F.Fab")
		)
		(fp_line
			(start 0.12065 -0.2794)
			(end 0.12065 -0.3048)
			(stroke
				(width 0.1)
				(type default)
			)
			(layer "F.Fab")
		)
		(fp_line
			(start 0.12065 -0.3048)
			(end 0.67945 -0.3048)
			(stroke
				(width 0.1)
				(type default)
			)
			(layer "F.Fab")
		)
		(fp_line
			(start 0.120396 0.3048)
			(end 0.120396 0.2794)
			(stroke
				(width 0.1)
				(type default)
			)
			(layer "F.Fab")
		)
		(fp_line
			(start 0.120396 0.2794)
			(end -0.12065 0.2794)
			(stroke
				(width 0.1)
				(type default)
			)
			(layer "F.Fab")
		)
		(fp_line
			(start -0.12065 0.3048)
			(end -0.67945 0.3048)
			(stroke
				(width 0.1)
				(type default)
			)
			(layer "F.Fab")
		)
		(fp_line
			(start -0.12065 0.2794)
			(end -0.12065 0.3048)
			(stroke
				(width 0.1)
				(type default)
			)
			(layer "F.Fab")
		)
		(fp_line
			(start -0.12065 -0.2794)
			(end 0.12065 -0.2794)
			(stroke
				(width 0.1)
				(type default)
			)
			(layer "F.Fab")
		)
		(fp_line
			(start -0.12065 -0.305054)
			(end -0.12065 -0.2794)
			(stroke
				(width 0.1)
				(type default)
			)
			(layer "F.Fab")
		)
		(fp_line
			(start -0.67945 0.3048)
			(end -0.67945 -0.305054)
			(stroke
				(width 0.1)
				(type default)
			)
			(layer "F.Fab")
		)
		(fp_line
			(start -0.67945 -0.305054)
			(end -0.12065 -0.305054)
			(stroke
				(width 0.1)
				(type default)
			)
			(layer "F.Fab")
		)
		(pad "1" smd circle
			(at -0.40005 0 180)
			(size 0 0)
			(layers "F.Cu" "F.Mask" "F.Paste")
			(net "SMB_SCM_2_R4_SDA")
		)
		(pad "2" smd circle
			(at 0.40005 0 180)
			(size 0 0)
			(layers "F.Cu" "F.Mask" "F.Paste")
			(net "SMB_SEN_MAM_3V3AUX_SDA")
		)
	)
	(footprint ""
		(layer "F.Cu")
		(at 371.272308 -424.024552 -90)
		(property "Reference" "R4190"
			(at 0 0 270)
			(layer "F.SilkS")
			(hide yes)
			(effects
				(font
					(size 1.27 1.27)
				)
			)
		)
		(property "Value" ""
			(at 0 0 270)
			(layer "F.Fab")
			(effects
				(font
					(size 1.27 1.27)
				)
			)
		)
		(duplicate_pad_numbers_are_jumpers no)
		(fp_line
			(start -0.7874 0.4064)
			(end -0.7874 -0.4064)
			(stroke
				(width 0.1524)
				(type default)
			)
			(layer "F.SilkS")
		)
		(fp_line
			(start 0.7874 0.4064)
			(end -0.7874 0.4064)
			(stroke
				(width 0.1524)
				(type default)
			)
			(layer "F.SilkS")
		)
		(fp_line
			(start -0.7874 -0.4064)
			(end 0.7874 -0.4064)
			(stroke
				(width 0.1524)
				(type default)
			)
			(layer "F.SilkS")
		)
		(fp_line
			(start 0.7874 -0.4064)
			(end 0.7874 0.4064)
			(stroke
				(width 0.1524)
				(type default)
			)
			(layer "F.SilkS")
		)
		(fp_line
			(start -0.67945 0.3048)
			(end -0.67945 -0.305054)
			(stroke
				(width 0.1)
				(type default)
			)
			(layer "F.Fab")
		)
		(fp_line
			(start -0.12065 0.3048)
			(end -0.67945 0.3048)
			(stroke
				(width 0.1)
				(type default)
			)
			(layer "F.Fab")
		)
		(fp_line
			(start 0.120396 0.3048)
			(end 0.120396 0.2794)
			(stroke
				(width 0.1)
				(type default)
			)
			(layer "F.Fab")
		)
		(fp_line
			(start 0.67945 0.3048)
			(end 0.120396 0.3048)
			(stroke
				(width 0.1)
				(type default)
			)
			(layer "F.Fab")
		)
		(fp_line
			(start -0.12065 0.2794)
			(end -0.12065 0.3048)
			(stroke
				(width 0.1)
				(type default)
			)
			(layer "F.Fab")
		)
		(fp_line
			(start 0.120396 0.2794)
			(end -0.12065 0.2794)
			(stroke
				(width 0.1)
				(type default)
			)
			(layer "F.Fab")
		)
		(fp_line
			(start -0.12065 -0.2794)
			(end 0.12065 -0.2794)
			(stroke
				(width 0.1)
				(type default)
			)
			(layer "F.Fab")
		)
		(fp_line
			(start 0.12065 -0.2794)
			(end 0.12065 -0.3048)
			(stroke
				(width 0.1)
				(type default)
			)
			(layer "F.Fab")
		)
		(fp_line
			(start 0.12065 -0.3048)
			(end 0.67945 -0.3048)
			(stroke
				(width 0.1)
				(type default)
			)
			(layer "F.Fab")
		)
		(fp_line
			(start 0.67945 -0.3048)
			(end 0.67945 0.3048)
			(stroke
				(width 0.1)
				(type default)
			)
			(layer "F.Fab")
		)
		(fp_line
			(start -0.67945 -0.305054)
			(end -0.12065 -0.305054)
			(stroke
				(width 0.1)
				(type default)
			)
			(layer "F.Fab")
		)
		(fp_line
			(start -0.12065 -0.305054)
			(end -0.12065 -0.2794)
			(stroke
				(width 0.1)
				(type default)
			)
			(layer "F.Fab")
		)
		(pad "1" smd circle
			(at -0.40005 0 270)
			(size 0 0)
			(layers "F.Cu" "F.Mask" "F.Paste")
			(net "P3V3_AUX")
		)
		(pad "2" smd circle
			(at 0.40005 0 270)
			(size 0 0)
			(layers "F.Cu" "F.Mask" "F.Paste")
			(net "U270_0_ADD2")
		)
	)
	(footprint ""
		(layer "F.Cu")
		(at 366.534446 -28.306522 90)
		(property "Reference" "R824"
			(at 0 0 90)
			(layer "F.SilkS")
			(hide yes)
			(effects
				(font
					(size 1.27 1.27)
				)
			)
		)
		(property "Value" ""
			(at 0 0 90)
			(layer "F.Fab")
			(effects
				(font
					(size 1.27 1.27)
				)
			)
		)
		(duplicate_pad_numbers_are_jumpers no)
		(fp_line
			(start 0.7874 -0.4064)
			(end 0.7874 0.4064)
			(stroke
				(width 0.1524)
				(type default)
			)
			(layer "F.SilkS")
		)
		(fp_line
			(start -0.7874 -0.4064)
			(end 0.7874 -0.4064)
			(stroke
				(width 0.1524)
				(type default)
			)
			(layer "F.SilkS")
		)
		(fp_line
			(start 0.7874 0.4064)
			(end -0.7874 0.4064)
			(stroke
				(width 0.1524)
				(type default)
			)
			(layer "F.SilkS")
		)
		(fp_line
			(start -0.7874 0.4064)
			(end -0.7874 -0.4064)
			(stroke
				(width 0.1524)
				(type default)
			)
			(layer "F.SilkS")
		)
		(fp_line
			(start -0.12065 -0.305054)
			(end -0.12065 -0.2794)
			(stroke
				(width 0.1)
				(type default)
			)
			(layer "F.Fab")
		)
		(fp_line
			(start -0.67945 -0.305054)
			(end -0.12065 -0.305054)
			(stroke
				(width 0.1)
				(type default)
			)
			(layer "F.Fab")
		)
		(fp_line
			(start 0.67945 -0.3048)
			(end 0.67945 0.3048)
			(stroke
				(width 0.1)
				(type default)
			)
			(layer "F.Fab")
		)
		(fp_line
			(start 0.12065 -0.3048)
			(end 0.67945 -0.3048)
			(stroke
				(width 0.1)
				(type default)
			)
			(layer "F.Fab")
		)
		(fp_line
			(start 0.12065 -0.2794)
			(end 0.12065 -0.3048)
			(stroke
				(width 0.1)
				(type default)
			)
			(layer "F.Fab")
		)
		(fp_line
			(start -0.12065 -0.2794)
			(end 0.12065 -0.2794)
			(stroke
				(width 0.1)
				(type default)
			)
			(layer "F.Fab")
		)
		(fp_line
			(start 0.120396 0.2794)
			(end -0.12065 0.2794)
			(stroke
				(width 0.1)
				(type default)
			)
			(layer "F.Fab")
		)
		(fp_line
			(start -0.12065 0.2794)
			(end -0.12065 0.3048)
			(stroke
				(width 0.1)
				(type default)
			)
			(layer "F.Fab")
		)
		(fp_line
			(start 0.67945 0.3048)
			(end 0.120396 0.3048)
			(stroke
				(width 0.1)
				(type default)
			)
			(layer "F.Fab")
		)
		(fp_line
			(start 0.120396 0.3048)
			(end 0.120396 0.2794)
			(stroke
				(width 0.1)
				(type default)
			)
			(layer "F.Fab")
		)
		(fp_line
			(start -0.12065 0.3048)
			(end -0.67945 0.3048)
			(stroke
				(width 0.1)
				(type default)
			)
			(layer "F.Fab")
		)
		(fp_line
			(start -0.67945 0.3048)
			(end -0.67945 -0.305054)
			(stroke
				(width 0.1)
				(type default)
			)
			(layer "F.Fab")
		)
		(pad "1" smd circle
			(at -0.40005 0 90)
			(size 0 0)
			(layers "F.Cu" "F.Mask" "F.Paste")
			(net "P3V3_AUX")
		)
		(pad "2" smd circle
			(at 0.40005 0 90)
			(size 0 0)
			(layers "F.Cu" "F.Mask" "F.Paste")
			(net "UART_CPU0_LVC3_UART0_TX")
		)
	)
	(footprint ""
		(layer "F.Cu")
		(at 435.628288 -351.22866 -90)
		(property "Reference" "PC210_2"
			(at 0 0 270)
			(layer "F.SilkS")
			(hide yes)
			(effects
				(font
					(size 1.27 1.27)
				)
			)
		)
		(property "Value" ""
			(at 0 0 270)
			(layer "F.Fab")
			(effects
				(font
					(size 1.27 1.27)
				)
			)
		)
		(duplicate_pad_numbers_are_jumpers no)
		(fp_line
			(start -0.7874 0.4064)
			(end -0.7874 -0.4064)
			(stroke
				(width 0.1524)
				(type default)
			)
			(layer "F.SilkS")
		)
		(fp_line
			(start 0.7874 0.4064)
			(end -0.7874 0.4064)
			(stroke
				(width 0.1524)
				(type default)
			)
			(layer "F.SilkS")
		)
		(fp_line
			(start -0.7874 -0.4064)
			(end 0.7874 -0.4064)
			(stroke
				(width 0.1524)
				(type default)
			)
			(layer "F.SilkS")
		)
		(fp_line
			(start 0.7874 -0.4064)
			(end 0.7874 0.4064)
			(stroke
				(width 0.1524)
				(type default)
			)
			(layer "F.SilkS")
		)
		(fp_line
			(start -0.67945 0.3048)
			(end -0.67945 -0.305054)
			(stroke
				(width 0.1)
				(type default)
			)
			(layer "F.Fab")
		)
		(fp_line
			(start -0.12065 0.3048)
			(end -0.67945 0.3048)
			(stroke
				(width 0.1)
				(type default)
			)
			(layer "F.Fab")
		)
		(fp_line
			(start 0.120396 0.3048)
			(end 0.120396 0.2794)
			(stroke
				(width 0.1)
				(type default)
			)
			(layer "F.Fab")
		)
		(fp_line
			(start 0.67945 0.3048)
			(end 0.120396 0.3048)
			(stroke
				(width 0.1)
				(type default)
			)
			(layer "F.Fab")
		)
		(fp_line
			(start -0.12065 0.2794)
			(end -0.12065 0.3048)
			(stroke
				(width 0.1)
				(type default)
			)
			(layer "F.Fab")
		)
		(fp_line
			(start 0.120396 0.2794)
			(end -0.12065 0.2794)
			(stroke
				(width 0.1)
				(type default)
			)
			(layer "F.Fab")
		)
		(fp_line
			(start -0.12065 -0.2794)
			(end 0.12065 -0.2794)
			(stroke
				(width 0.1)
				(type default)
			)
			(layer "F.Fab")
		)
		(fp_line
			(start 0.12065 -0.2794)
			(end 0.12065 -0.3048)
			(stroke
				(width 0.1)
				(type default)
			)
			(layer "F.Fab")
		)
		(fp_line
			(start 0.12065 -0.3048)
			(end 0.67945 -0.3048)
			(stroke
				(width 0.1)
				(type default)
			)
			(layer "F.Fab")
		)
		(fp_line
			(start 0.67945 -0.3048)
			(end 0.67945 0.3048)
			(stroke
				(width 0.1)
				(type default)
			)
			(layer "F.Fab")
		)
		(fp_line
			(start -0.67945 -0.305054)
			(end -0.12065 -0.305054)
			(stroke
				(width 0.1)
				(type default)
			)
			(layer "F.Fab")
		)
		(fp_line
			(start -0.12065 -0.305054)
			(end -0.12065 -0.2794)
			(stroke
				(width 0.1)
				(type default)
			)
			(layer "F.Fab")
		)
		(pad "1" smd circle
			(at -0.40005 0 270)
			(size 0 0)
			(layers "F.Cu" "F.Mask" "F.Paste")
			(net "SW_P12V_AUX_PVDD11_S3_P0_FLT")
		)
		(pad "2" smd circle
			(at 0.40005 0 270)
			(size 0 0)
			(layers "F.Cu" "F.Mask" "F.Paste")
			(net "GND")
		)
	)
	(footprint ""
		(layer "F.Cu")
		(at 449.531232 -425.210478)
		(property "Reference" "PC6601"
			(at 0 0 0)
			(layer "F.SilkS")
			(hide yes)
			(effects
				(font
					(size 1.27 1.27)
				)
			)
		)
		(property "Value" ""
			(at 0 0 0)
			(layer "F.Fab")
			(effects
				(font
					(size 1.27 1.27)
				)
			)
		)
		(duplicate_pad_numbers_are_jumpers no)
		(fp_line
			(start -0.7874 -0.4064)
			(end 0.7874 -0.4064)
			(stroke
				(width 0.1524)
				(type default)
			)
			(layer "F.SilkS")
		)
		(fp_line
			(start -0.7874 0.4064)
			(end -0.7874 -0.4064)
			(stroke
				(width 0.1524)
				(type default)
			)
			(layer "F.SilkS")
		)
		(fp_line
			(start 0.7874 -0.4064)
			(end 0.7874 0.4064)
			(stroke
				(width 0.1524)
				(type default)
			)
			(layer "F.SilkS")
		)
		(fp_line
			(start 0.7874 0.4064)
			(end -0.7874 0.4064)
			(stroke
				(width 0.1524)
				(type default)
			)
			(layer "F.SilkS")
		)
		(fp_line
			(start -0.67945 -0.305054)
			(end -0.12065 -0.305054)
			(stroke
				(width 0.1)
				(type default)
			)
			(layer "F.Fab")
		)
		(fp_line
			(start -0.67945 0.3048)
			(end -0.67945 -0.305054)
			(stroke
				(width 0.1)
				(type default)
			)
			(layer "F.Fab")
		)
		(fp_line
			(start -0.12065 -0.305054)
			(end -0.12065 -0.2794)
			(stroke
				(width 0.1)
				(type default)
			)
			(layer "F.Fab")
		)
		(fp_line
			(start -0.12065 -0.2794)
			(end 0.12065 -0.2794)
			(stroke
				(width 0.1)
				(type default)
			)
			(layer "F.Fab")
		)
		(fp_line
			(start -0.12065 0.2794)
			(end -0.12065 0.3048)
			(stroke
				(width 0.1)
				(type default)
			)
			(layer "F.Fab")
		)
		(fp_line
			(start -0.12065 0.3048)
			(end -0.67945 0.3048)
			(stroke
				(width 0.1)
				(type default)
			)
			(layer "F.Fab")
		)
		(fp_line
			(start 0.120396 0.2794)
			(end -0.12065 0.2794)
			(stroke
				(width 0.1)
				(type default)
			)
			(layer "F.Fab")
		)
		(fp_line
			(start 0.120396 0.3048)
			(end 0.120396 0.2794)
			(stroke
				(width 0.1)
				(type default)
			)
			(layer "F.Fab")
		)
		(fp_line
			(start 0.12065 -0.3048)
			(end 0.67945 -0.3048)
			(stroke
				(width 0.1)
				(type default)
			)
			(layer "F.Fab")
		)
		(fp_line
			(start 0.12065 -0.2794)
			(end 0.12065 -0.3048)
			(stroke
				(width 0.1)
				(type default)
			)
			(layer "F.Fab")
		)
		(fp_line
			(start 0.67945 -0.3048)
			(end 0.67945 0.3048)
			(stroke
				(width 0.1)
				(type default)
			)
			(layer "F.Fab")
		)
		(fp_line
			(start 0.67945 0.3048)
			(end 0.120396 0.3048)
			(stroke
				(width 0.1)
				(type default)
			)
			(layer "F.Fab")
		)
		(pad "1" smd circle
			(at -0.40005 0)
			(size 0 0)
			(layers "F.Cu" "F.Mask" "F.Paste")
			(net "P0V9_RETIMER_CPU0_VMON")
		)
		(pad "2" smd circle
			(at 0.40005 0)
			(size 0 0)
			(layers "F.Cu" "F.Mask" "F.Paste")
			(net "GND")
		)
	)
	(footprint ""
		(layer "F.Cu")
		(at 71.16826 -339.651848 90)
		(property "Reference" "PR267"
			(at 0 0 90)
			(layer "F.SilkS")
			(hide yes)
			(effects
				(font
					(size 1.27 1.27)
				)
			)
		)
		(property "Value" ""
			(at 0 0 90)
			(layer "F.Fab")
			(effects
				(font
					(size 1.27 1.27)
				)
			)
		)
		(duplicate_pad_numbers_are_jumpers no)
		(fp_line
			(start 0.7874 -0.4064)
			(end 0.7874 0.4064)
			(stroke
				(width 0.1524)
				(type default)
			)
			(layer "F.SilkS")
		)
		(fp_line
			(start -0.7874 -0.4064)
			(end 0.7874 -0.4064)
			(stroke
				(width 0.1524)
				(type default)
			)
			(layer "F.SilkS")
		)
		(fp_line
			(start 0.7874 0.4064)
			(end -0.7874 0.4064)
			(stroke
				(width 0.1524)
				(type default)
			)
			(layer "F.SilkS")
		)
		(fp_line
			(start -0.7874 0.4064)
			(end -0.7874 -0.4064)
			(stroke
				(width 0.1524)
				(type default)
			)
			(layer "F.SilkS")
		)
		(fp_line
			(start -0.12065 -0.305054)
			(end -0.12065 -0.2794)
			(stroke
				(width 0.1)
				(type default)
			)
			(layer "F.Fab")
		)
		(fp_line
			(start -0.67945 -0.305054)
			(end -0.12065 -0.305054)
			(stroke
				(width 0.1)
				(type default)
			)
			(layer "F.Fab")
		)
		(fp_line
			(start 0.67945 -0.3048)
			(end 0.67945 0.3048)
			(stroke
				(width 0.1)
				(type default)
			)
			(layer "F.Fab")
		)
		(fp_line
			(start 0.12065 -0.3048)
			(end 0.67945 -0.3048)
			(stroke
				(width 0.1)
				(type default)
			)
			(layer "F.Fab")
		)
		(fp_line
			(start 0.12065 -0.2794)
			(end 0.12065 -0.3048)
			(stroke
				(width 0.1)
				(type default)
			)
			(layer "F.Fab")
		)
		(fp_line
			(start -0.12065 -0.2794)
			(end 0.12065 -0.2794)
			(stroke
				(width 0.1)
				(type default)
			)
			(layer "F.Fab")
		)
		(fp_line
			(start 0.120396 0.2794)
			(end -0.12065 0.2794)
			(stroke
				(width 0.1)
				(type default)
			)
			(layer "F.Fab")
		)
		(fp_line
			(start -0.12065 0.2794)
			(end -0.12065 0.3048)
			(stroke
				(width 0.1)
				(type default)
			)
			(layer "F.Fab")
		)
		(fp_line
			(start 0.67945 0.3048)
			(end 0.120396 0.3048)
			(stroke
				(width 0.1)
				(type default)
			)
			(layer "F.Fab")
		)
		(fp_line
			(start 0.120396 0.3048)
			(end 0.120396 0.2794)
			(stroke
				(width 0.1)
				(type default)
			)
			(layer "F.Fab")
		)
		(fp_line
			(start -0.12065 0.3048)
			(end -0.67945 0.3048)
			(stroke
				(width 0.1)
				(type default)
			)
			(layer "F.Fab")
		)
		(fp_line
			(start -0.67945 0.3048)
			(end -0.67945 -0.305054)
			(stroke
				(width 0.1)
				(type default)
			)
			(layer "F.Fab")
		)
		(pad "1" smd circle
			(at -0.40005 0 90)
			(size 0 0)
			(layers "F.Cu" "F.Mask" "F.Paste")
			(net "SW_PVDDCR_CPU1_P1_BOOT3")
		)
		(pad "2" smd circle
			(at 0.40005 0 90)
			(size 0 0)
			(layers "F.Cu" "F.Mask" "F.Paste")
			(net "SW_PVDDCR_CPU1_P1_BOOT3_R")
		)
	)
	(footprint ""
		(layer "F.Cu")
		(at 455.524616 -403.12467 180)
		(property "Reference" "PC6578_2"
			(at 0 0 180)
			(layer "F.SilkS")
			(hide yes)
			(effects
				(font
					(size 1.27 1.27)
				)
			)
		)
		(property "Value" ""
			(at 0 0 180)
			(layer "F.Fab")
			(effects
				(font
					(size 1.27 1.27)
				)
			)
		)
		(duplicate_pad_numbers_are_jumpers no)
		(fp_line
			(start 0.7874 0.4064)
			(end -0.7874 0.4064)
			(stroke
				(width 0.1524)
				(type default)
			)
			(layer "F.SilkS")
		)
		(fp_line
			(start 0.7874 -0.4064)
			(end 0.7874 0.4064)
			(stroke
				(width 0.1524)
				(type default)
			)
			(layer "F.SilkS")
		)
		(fp_line
			(start -0.7874 0.4064)
			(end -0.7874 -0.4064)
			(stroke
				(width 0.1524)
				(type default)
			)
			(layer "F.SilkS")
		)
		(fp_line
			(start -0.7874 -0.4064)
			(end 0.7874 -0.4064)
			(stroke
				(width 0.1524)
				(type default)
			)
			(layer "F.SilkS")
		)
		(fp_line
			(start 0.67945 0.3048)
			(end 0.120396 0.3048)
			(stroke
				(width 0.1)
				(type default)
			)
			(layer "F.Fab")
		)
		(fp_line
			(start 0.67945 -0.3048)
			(end 0.67945 0.3048)
			(stroke
				(width 0.1)
				(type default)
			)
			(layer "F.Fab")
		)
		(fp_line
			(start 0.12065 -0.2794)
			(end 0.12065 -0.3048)
			(stroke
				(width 0.1)
				(type default)
			)
			(layer "F.Fab")
		)
		(fp_line
			(start 0.12065 -0.3048)
			(end 0.67945 -0.3048)
			(stroke
				(width 0.1)
				(type default)
			)
			(layer "F.Fab")
		)
		(fp_line
			(start 0.120396 0.3048)
			(end 0.120396 0.2794)
			(stroke
				(width 0.1)
				(type default)
			)
			(layer "F.Fab")
		)
		(fp_line
			(start 0.120396 0.2794)
			(end -0.12065 0.2794)
			(stroke
				(width 0.1)
				(type default)
			)
			(layer "F.Fab")
		)
		(fp_line
			(start -0.12065 0.3048)
			(end -0.67945 0.3048)
			(stroke
				(width 0.1)
				(type default)
			)
			(layer "F.Fab")
		)
		(fp_line
			(start -0.12065 0.2794)
			(end -0.12065 0.3048)
			(stroke
				(width 0.1)
				(type default)
			)
			(layer "F.Fab")
		)
		(fp_line
			(start -0.12065 -0.2794)
			(end 0.12065 -0.2794)
			(stroke
				(width 0.1)
				(type default)
			)
			(layer "F.Fab")
		)
		(fp_line
			(start -0.12065 -0.305054)
			(end -0.12065 -0.2794)
			(stroke
				(width 0.1)
				(type default)
			)
			(layer "F.Fab")
		)
		(fp_line
			(start -0.67945 0.3048)
			(end -0.67945 -0.305054)
			(stroke
				(width 0.1)
				(type default)
			)
			(layer "F.Fab")
		)
		(fp_line
			(start -0.67945 -0.305054)
			(end -0.12065 -0.305054)
			(stroke
				(width 0.1)
				(type default)
			)
			(layer "F.Fab")
		)
		(pad "1" smd circle
			(at -0.40005 0 180)
			(size 0 0)
			(layers "F.Cu" "F.Mask" "F.Paste")
			(net "SW_P12V_AUX_P0V9_RETIMER_CPU0_FLT")
		)
		(pad "2" smd circle
			(at 0.40005 0 180)
			(size 0 0)
			(layers "F.Cu" "F.Mask" "F.Paste")
			(net "GND")
		)
	)
	(footprint ""
		(layer "F.Cu")
		(at 164.719 -106.299 180)
		(property "Reference" "R9024"
			(at 0 0 180)
			(layer "F.SilkS")
			(hide yes)
			(effects
				(font
					(size 1.27 1.27)
				)
			)
		)
		(property "Value" ""
			(at 0 0 180)
			(layer "F.Fab")
			(effects
				(font
					(size 1.27 1.27)
				)
			)
		)
		(duplicate_pad_numbers_are_jumpers no)
		(fp_line
			(start 0.7874 0.4064)
			(end -0.7874 0.4064)
			(stroke
				(width 0.1524)
				(type default)
			)
			(layer "F.SilkS")
		)
		(fp_line
			(start 0.7874 -0.4064)
			(end 0.7874 0.4064)
			(stroke
				(width 0.1524)
				(type default)
			)
			(layer "F.SilkS")
		)
		(fp_line
			(start -0.7874 0.4064)
			(end -0.7874 -0.4064)
			(stroke
				(width 0.1524)
				(type default)
			)
			(layer "F.SilkS")
		)
		(fp_line
			(start -0.7874 -0.4064)
			(end 0.7874 -0.4064)
			(stroke
				(width 0.1524)
				(type default)
			)
			(layer "F.SilkS")
		)
		(fp_line
			(start 0.67945 0.3048)
			(end 0.120396 0.3048)
			(stroke
				(width 0.1)
				(type default)
			)
			(layer "F.Fab")
		)
		(fp_line
			(start 0.67945 -0.3048)
			(end 0.67945 0.3048)
			(stroke
				(width 0.1)
				(type default)
			)
			(layer "F.Fab")
		)
		(fp_line
			(start 0.12065 -0.2794)
			(end 0.12065 -0.3048)
			(stroke
				(width 0.1)
				(type default)
			)
			(layer "F.Fab")
		)
		(fp_line
			(start 0.12065 -0.3048)
			(end 0.67945 -0.3048)
			(stroke
				(width 0.1)
				(type default)
			)
			(layer "F.Fab")
		)
		(fp_line
			(start 0.120396 0.3048)
			(end 0.120396 0.2794)
			(stroke
				(width 0.1)
				(type default)
			)
			(layer "F.Fab")
		)
		(fp_line
			(start 0.120396 0.2794)
			(end -0.12065 0.2794)
			(stroke
				(width 0.1)
				(type default)
			)
			(layer "F.Fab")
		)
		(fp_line
			(start -0.12065 0.3048)
			(end -0.67945 0.3048)
			(stroke
				(width 0.1)
				(type default)
			)
			(layer "F.Fab")
		)
		(fp_line
			(start -0.12065 0.2794)
			(end -0.12065 0.3048)
			(stroke
				(width 0.1)
				(type default)
			)
			(layer "F.Fab")
		)
		(fp_line
			(start -0.12065 -0.2794)
			(end 0.12065 -0.2794)
			(stroke
				(width 0.1)
				(type default)
			)
			(layer "F.Fab")
		)
		(fp_line
			(start -0.12065 -0.305054)
			(end -0.12065 -0.2794)
			(stroke
				(width 0.1)
				(type default)
			)
			(layer "F.Fab")
		)
		(fp_line
			(start -0.67945 0.3048)
			(end -0.67945 -0.305054)
			(stroke
				(width 0.1)
				(type default)
			)
			(layer "F.Fab")
		)
		(fp_line
			(start -0.67945 -0.305054)
			(end -0.12065 -0.305054)
			(stroke
				(width 0.1)
				(type default)
			)
			(layer "F.Fab")
		)
		(pad "1" smd circle
			(at -0.40005 0 180)
			(size 0 0)
			(layers "F.Cu" "F.Mask" "F.Paste")
			(net "P3V3_AUX")
		)
		(pad "2" smd circle
			(at 0.40005 0 180)
			(size 0 0)
			(layers "F.Cu" "F.Mask" "F.Paste")
			(net "IRQ_HSC_FAULT_N")
		)
	)
	(footprint ""
		(layer "F.Cu")
		(at 317.452248 -344.814906)
		(property "Reference" "H37"
			(at 0.040132 -4.391914 0)
			(unlocked yes)
			(layer "F.SilkS")
			(effects
				(font
					(size 0.7874 0.5842)
					(thickness 0.1524)
				)
				(justify left)
			)
		)
		(property "Value" ""
			(at 0 0 0)
			(layer "F.Fab")
			(effects
				(font
					(size 1.27 1.27)
				)
			)
		)
		(duplicate_pad_numbers_are_jumpers no)
		(pad "1" thru_hole circle
			(at 0 0)
			(size 6.1976 6.1976)
			(drill 3.7338)
			(layers "*.Cu" "*.Mask")
			(remove_unused_layers no)
			(net "GND")
			(clearance -0.9779)
			(padstack
				(mode front_inner_back)
				(layer "Inner"
					(shape circle)
					(size 5.5372 5.5372)
					(clearance -0.6477)
				)
				(layer "B.Cu"
					(shape circle)
					(size 6.1976 6.1976)
					(clearance -0.9779)
				)
			)
		)
	)
	(footprint ""
		(layer "F.Cu")
		(at 347.575124 -344.35161)
		(property "Reference" "PC114_6"
			(at 0 0 0)
			(layer "F.SilkS")
			(hide yes)
			(effects
				(font
					(size 1.27 1.27)
				)
			)
		)
		(property "Value" ""
			(at 0 0 0)
			(layer "F.Fab")
			(effects
				(font
					(size 1.27 1.27)
				)
			)
		)
		(duplicate_pad_numbers_are_jumpers no)
		(fp_line
			(start -0.7874 -0.4064)
			(end 0.7874 -0.4064)
			(stroke
				(width 0.1524)
				(type default)
			)
			(layer "F.SilkS")
		)
		(fp_line
			(start -0.7874 0.4064)
			(end -0.7874 -0.4064)
			(stroke
				(width 0.1524)
				(type default)
			)
			(layer "F.SilkS")
		)
		(fp_line
			(start 0.7874 -0.4064)
			(end 0.7874 0.4064)
			(stroke
				(width 0.1524)
				(type default)
			)
			(layer "F.SilkS")
		)
		(fp_line
			(start 0.7874 0.4064)
			(end -0.7874 0.4064)
			(stroke
				(width 0.1524)
				(type default)
			)
			(layer "F.SilkS")
		)
		(fp_line
			(start -0.67945 -0.305054)
			(end -0.12065 -0.305054)
			(stroke
				(width 0.1)
				(type default)
			)
			(layer "F.Fab")
		)
		(fp_line
			(start -0.67945 0.3048)
			(end -0.67945 -0.305054)
			(stroke
				(width 0.1)
				(type default)
			)
			(layer "F.Fab")
		)
		(fp_line
			(start -0.12065 -0.305054)
			(end -0.12065 -0.2794)
			(stroke
				(width 0.1)
				(type default)
			)
			(layer "F.Fab")
		)
		(fp_line
			(start -0.12065 -0.2794)
			(end 0.12065 -0.2794)
			(stroke
				(width 0.1)
				(type default)
			)
			(layer "F.Fab")
		)
		(fp_line
			(start -0.12065 0.2794)
			(end -0.12065 0.3048)
			(stroke
				(width 0.1)
				(type default)
			)
			(layer "F.Fab")
		)
		(fp_line
			(start -0.12065 0.3048)
			(end -0.67945 0.3048)
			(stroke
				(width 0.1)
				(type default)
			)
			(layer "F.Fab")
		)
		(fp_line
			(start 0.120396 0.2794)
			(end -0.12065 0.2794)
			(stroke
				(width 0.1)
				(type default)
			)
			(layer "F.Fab")
		)
		(fp_line
			(start 0.120396 0.3048)
			(end 0.120396 0.2794)
			(stroke
				(width 0.1)
				(type default)
			)
			(layer "F.Fab")
		)
		(fp_line
			(start 0.12065 -0.3048)
			(end 0.67945 -0.3048)
			(stroke
				(width 0.1)
				(type default)
			)
			(layer "F.Fab")
		)
		(fp_line
			(start 0.12065 -0.2794)
			(end 0.12065 -0.3048)
			(stroke
				(width 0.1)
				(type default)
			)
			(layer "F.Fab")
		)
		(fp_line
			(start 0.67945 -0.3048)
			(end 0.67945 0.3048)
			(stroke
				(width 0.1)
				(type default)
			)
			(layer "F.Fab")
		)
		(fp_line
			(start 0.67945 0.3048)
			(end 0.120396 0.3048)
			(stroke
				(width 0.1)
				(type default)
			)
			(layer "F.Fab")
		)
		(pad "1" smd circle
			(at -0.40005 0)
			(size 0 0)
			(layers "F.Cu" "F.Mask" "F.Paste")
			(net "SW_P12V_AUX_PVDDCR_CPU1_P0_FLT")
		)
		(pad "2" smd circle
			(at 0.40005 0)
			(size 0 0)
			(layers "F.Cu" "F.Mask" "F.Paste")
			(net "GND")
		)
	)
	(footprint ""
		(layer "F.Cu")
		(at 113.613946 -52.86248 -90)
		(property "Reference" "R6300"
			(at 0 0 270)
			(layer "F.SilkS")
			(hide yes)
			(effects
				(font
					(size 1.27 1.27)
				)
			)
		)
		(property "Value" ""
			(at 0 0 270)
			(layer "F.Fab")
			(effects
				(font
					(size 1.27 1.27)
				)
			)
		)
		(duplicate_pad_numbers_are_jumpers no)
		(fp_line
			(start -0.7874 0.4064)
			(end -0.7874 -0.4064)
			(stroke
				(width 0.1524)
				(type default)
			)
			(layer "F.SilkS")
		)
		(fp_line
			(start 0.7874 0.4064)
			(end -0.7874 0.4064)
			(stroke
				(width 0.1524)
				(type default)
			)
			(layer "F.SilkS")
		)
		(fp_line
			(start -0.7874 -0.4064)
			(end 0.7874 -0.4064)
			(stroke
				(width 0.1524)
				(type default)
			)
			(layer "F.SilkS")
		)
		(fp_line
			(start 0.7874 -0.4064)
			(end 0.7874 0.4064)
			(stroke
				(width 0.1524)
				(type default)
			)
			(layer "F.SilkS")
		)
		(fp_line
			(start -0.67945 0.3048)
			(end -0.67945 -0.305054)
			(stroke
				(width 0.1)
				(type default)
			)
			(layer "F.Fab")
		)
		(fp_line
			(start -0.12065 0.3048)
			(end -0.67945 0.3048)
			(stroke
				(width 0.1)
				(type default)
			)
			(layer "F.Fab")
		)
		(fp_line
			(start 0.120396 0.3048)
			(end 0.120396 0.2794)
			(stroke
				(width 0.1)
				(type default)
			)
			(layer "F.Fab")
		)
		(fp_line
			(start 0.67945 0.3048)
			(end 0.120396 0.3048)
			(stroke
				(width 0.1)
				(type default)
			)
			(layer "F.Fab")
		)
		(fp_line
			(start -0.12065 0.2794)
			(end -0.12065 0.3048)
			(stroke
				(width 0.1)
				(type default)
			)
			(layer "F.Fab")
		)
		(fp_line
			(start 0.120396 0.2794)
			(end -0.12065 0.2794)
			(stroke
				(width 0.1)
				(type default)
			)
			(layer "F.Fab")
		)
		(fp_line
			(start -0.12065 -0.2794)
			(end 0.12065 -0.2794)
			(stroke
				(width 0.1)
				(type default)
			)
			(layer "F.Fab")
		)
		(fp_line
			(start 0.12065 -0.2794)
			(end 0.12065 -0.3048)
			(stroke
				(width 0.1)
				(type default)
			)
			(layer "F.Fab")
		)
		(fp_line
			(start 0.12065 -0.3048)
			(end 0.67945 -0.3048)
			(stroke
				(width 0.1)
				(type default)
			)
			(layer "F.Fab")
		)
		(fp_line
			(start 0.67945 -0.3048)
			(end 0.67945 0.3048)
			(stroke
				(width 0.1)
				(type default)
			)
			(layer "F.Fab")
		)
		(fp_line
			(start -0.67945 -0.305054)
			(end -0.12065 -0.305054)
			(stroke
				(width 0.1)
				(type default)
			)
			(layer "F.Fab")
		)
		(fp_line
			(start -0.12065 -0.305054)
			(end -0.12065 -0.2794)
			(stroke
				(width 0.1)
				(type default)
			)
			(layer "F.Fab")
		)
		(pad "1" smd circle
			(at -0.40005 0 270)
			(size 0 0)
			(layers "F.Cu" "F.Mask" "F.Paste")
			(net "USB_HUB2_MRP_CFG_BC_EN")
		)
		(pad "2" smd circle
			(at 0.40005 0 270)
			(size 0 0)
			(layers "F.Cu" "F.Mask" "F.Paste")
			(net "USB_HUB2_TI_OVERCUR3_MRP_CFG_BC_EN")
		)
	)
	(footprint ""
		(layer "F.Cu")
		(at 261.62 -141.986 -90)
		(property "Reference" "R8008"
			(at 0 0 270)
			(layer "F.SilkS")
			(hide yes)
			(effects
				(font
					(size 1.27 1.27)
				)
			)
		)
		(property "Value" ""
			(at 0 0 270)
			(layer "F.Fab")
			(effects
				(font
					(size 1.27 1.27)
				)
			)
		)
		(duplicate_pad_numbers_are_jumpers no)
		(fp_line
			(start -0.7874 0.4064)
			(end -0.7874 -0.4064)
			(stroke
				(width 0.1524)
				(type default)
			)
			(layer "F.SilkS")
		)
		(fp_line
			(start 0.7874 0.4064)
			(end -0.7874 0.4064)
			(stroke
				(width 0.1524)
				(type default)
			)
			(layer "F.SilkS")
		)
		(fp_line
			(start -0.7874 -0.4064)
			(end 0.7874 -0.4064)
			(stroke
				(width 0.1524)
				(type default)
			)
			(layer "F.SilkS")
		)
		(fp_line
			(start 0.7874 -0.4064)
			(end 0.7874 0.4064)
			(stroke
				(width 0.1524)
				(type default)
			)
			(layer "F.SilkS")
		)
		(fp_line
			(start -0.67945 0.3048)
			(end -0.67945 -0.305054)
			(stroke
				(width 0.1)
				(type default)
			)
			(layer "F.Fab")
		)
		(fp_line
			(start -0.12065 0.3048)
			(end -0.67945 0.3048)
			(stroke
				(width 0.1)
				(type default)
			)
			(layer "F.Fab")
		)
		(fp_line
			(start 0.120396 0.3048)
			(end 0.120396 0.2794)
			(stroke
				(width 0.1)
				(type default)
			)
			(layer "F.Fab")
		)
		(fp_line
			(start 0.67945 0.3048)
			(end 0.120396 0.3048)
			(stroke
				(width 0.1)
				(type default)
			)
			(layer "F.Fab")
		)
		(fp_line
			(start -0.12065 0.2794)
			(end -0.12065 0.3048)
			(stroke
				(width 0.1)
				(type default)
			)
			(layer "F.Fab")
		)
		(fp_line
			(start 0.120396 0.2794)
			(end -0.12065 0.2794)
			(stroke
				(width 0.1)
				(type default)
			)
			(layer "F.Fab")
		)
		(fp_line
			(start -0.12065 -0.2794)
			(end 0.12065 -0.2794)
			(stroke
				(width 0.1)
				(type default)
			)
			(layer "F.Fab")
		)
		(fp_line
			(start 0.12065 -0.2794)
			(end 0.12065 -0.3048)
			(stroke
				(width 0.1)
				(type default)
			)
			(layer "F.Fab")
		)
		(fp_line
			(start 0.12065 -0.3048)
			(end 0.67945 -0.3048)
			(stroke
				(width 0.1)
				(type default)
			)
			(layer "F.Fab")
		)
		(fp_line
			(start 0.67945 -0.3048)
			(end 0.67945 0.3048)
			(stroke
				(width 0.1)
				(type default)
			)
			(layer "F.Fab")
		)
		(fp_line
			(start -0.67945 -0.305054)
			(end -0.12065 -0.305054)
			(stroke
				(width 0.1)
				(type default)
			)
			(layer "F.Fab")
		)
		(fp_line
			(start -0.12065 -0.305054)
			(end -0.12065 -0.2794)
			(stroke
				(width 0.1)
				(type default)
			)
			(layer "F.Fab")
		)
		(pad "1" smd circle
			(at -0.40005 0 270)
			(size 0 0)
			(layers "F.Cu" "F.Mask" "F.Paste")
			(net "SPI_CPU0_D1")
		)
		(pad "2" smd circle
			(at 0.40005 0 270)
			(size 0 0)
			(layers "F.Cu" "F.Mask" "F.Paste")
			(net "SPI_CPU0_R1_D1")
		)
	)
	(footprint ""
		(layer "F.Cu")
		(at 110.089696 -373.03583 -90)
		(property "Reference" "C1543"
			(at 0 0 270)
			(layer "F.SilkS")
			(hide yes)
			(effects
				(font
					(size 1.27 1.27)
				)
			)
		)
		(property "Value" ""
			(at 0 0 270)
			(layer "F.Fab")
			(effects
				(font
					(size 1.27 1.27)
				)
			)
		)
		(duplicate_pad_numbers_are_jumpers no)
		(fp_line
			(start -0.299974 0.150114)
			(end -0.299974 -0.150114)
			(stroke
				(width 0.1)
				(type default)
			)
			(layer "F.Fab")
		)
		(fp_line
			(start 0.299974 0.150114)
			(end -0.299974 0.150114)
			(stroke
				(width 0.1)
				(type default)
			)
			(layer "F.Fab")
		)
		(fp_line
			(start -0.299974 -0.150114)
			(end 0.299974 -0.150114)
			(stroke
				(width 0.1)
				(type default)
			)
			(layer "F.Fab")
		)
		(fp_line
			(start 0.299974 -0.150114)
			(end 0.299974 0.150114)
			(stroke
				(width 0.1)
				(type default)
			)
			(layer "F.Fab")
		)
		(pad "1" smd rect
			(at -0.2667 0 270)
			(size 0.3048 0.381)
			(layers "F.Cu" "F.Mask" "F.Paste")
			(net "P5E_CPU1_P3_TX_C_DP<2>")
		)
		(pad "2" smd rect
			(at 0.2667 0 270)
			(size 0.3048 0.381)
			(layers "F.Cu" "F.Mask" "F.Paste")
			(net "P5E_CPU1_P3_TX_DP<2>")
		)
	)
	(footprint ""
		(layer "F.Cu")
		(at 26.226516 -40.180514)
		(property "Reference" "C1109"
			(at 0 0 0)
			(layer "F.SilkS")
			(hide yes)
			(effects
				(font
					(size 1.27 1.27)
				)
			)
		)
		(property "Value" ""
			(at 0 0 0)
			(layer "F.Fab")
			(effects
				(font
					(size 1.27 1.27)
				)
			)
		)
		(duplicate_pad_numbers_are_jumpers no)
		(fp_line
			(start -0.7874 -0.4064)
			(end 0.7874 -0.4064)
			(stroke
				(width 0.1524)
				(type default)
			)
			(layer "F.SilkS")
		)
		(fp_line
			(start -0.7874 0.4064)
			(end -0.7874 -0.4064)
			(stroke
				(width 0.1524)
				(type default)
			)
			(layer "F.SilkS")
		)
		(fp_line
			(start 0.7874 -0.4064)
			(end 0.7874 0.4064)
			(stroke
				(width 0.1524)
				(type default)
			)
			(layer "F.SilkS")
		)
		(fp_line
			(start 0.7874 0.4064)
			(end -0.7874 0.4064)
			(stroke
				(width 0.1524)
				(type default)
			)
			(layer "F.SilkS")
		)
		(fp_line
			(start -0.67945 -0.305054)
			(end -0.12065 -0.305054)
			(stroke
				(width 0.1)
				(type default)
			)
			(layer "F.Fab")
		)
		(fp_line
			(start -0.67945 0.3048)
			(end -0.67945 -0.305054)
			(stroke
				(width 0.1)
				(type default)
			)
			(layer "F.Fab")
		)
		(fp_line
			(start -0.12065 -0.305054)
			(end -0.12065 -0.2794)
			(stroke
				(width 0.1)
				(type default)
			)
			(layer "F.Fab")
		)
		(fp_line
			(start -0.12065 -0.2794)
			(end 0.12065 -0.2794)
			(stroke
				(width 0.1)
				(type default)
			)
			(layer "F.Fab")
		)
		(fp_line
			(start -0.12065 0.2794)
			(end -0.12065 0.3048)
			(stroke
				(width 0.1)
				(type default)
			)
			(layer "F.Fab")
		)
		(fp_line
			(start -0.12065 0.3048)
			(end -0.67945 0.3048)
			(stroke
				(width 0.1)
				(type default)
			)
			(layer "F.Fab")
		)
		(fp_line
			(start 0.120396 0.2794)
			(end -0.12065 0.2794)
			(stroke
				(width 0.1)
				(type default)
			)
			(layer "F.Fab")
		)
		(fp_line
			(start 0.120396 0.3048)
			(end 0.120396 0.2794)
			(stroke
				(width 0.1)
				(type default)
			)
			(layer "F.Fab")
		)
		(fp_line
			(start 0.12065 -0.3048)
			(end 0.67945 -0.3048)
			(stroke
				(width 0.1)
				(type default)
			)
			(layer "F.Fab")
		)
		(fp_line
			(start 0.12065 -0.2794)
			(end 0.12065 -0.3048)
			(stroke
				(width 0.1)
				(type default)
			)
			(layer "F.Fab")
		)
		(fp_line
			(start 0.67945 -0.3048)
			(end 0.67945 0.3048)
			(stroke
				(width 0.1)
				(type default)
			)
			(layer "F.Fab")
		)
		(fp_line
			(start 0.67945 0.3048)
			(end 0.120396 0.3048)
			(stroke
				(width 0.1)
				(type default)
			)
			(layer "F.Fab")
		)
		(pad "1" smd circle
			(at -0.40005 0)
			(size 0 0)
			(layers "F.Cu" "F.Mask" "F.Paste")
			(net "P12V_OCP_V3_2")
		)
		(pad "2" smd circle
			(at 0.40005 0)
			(size 0 0)
			(layers "F.Cu" "F.Mask" "F.Paste")
			(net "GND")
		)
	)
	(footprint ""
		(layer "F.Cu")
		(at 120.327928 -165.109906 90)
		(property "Reference" "PC324_2"
			(at 0 0 90)
			(layer "F.SilkS")
			(hide yes)
			(effects
				(font
					(size 1.27 1.27)
				)
			)
		)
		(property "Value" ""
			(at 0 0 90)
			(layer "F.Fab")
			(effects
				(font
					(size 1.27 1.27)
				)
			)
		)
		(duplicate_pad_numbers_are_jumpers no)
		(fp_line
			(start 0.7874 -0.4064)
			(end 0.7874 0.4064)
			(stroke
				(width 0.1524)
				(type default)
			)
			(layer "F.SilkS")
		)
		(fp_line
			(start -0.7874 -0.4064)
			(end 0.7874 -0.4064)
			(stroke
				(width 0.1524)
				(type default)
			)
			(layer "F.SilkS")
		)
		(fp_line
			(start 0.7874 0.4064)
			(end -0.7874 0.4064)
			(stroke
				(width 0.1524)
				(type default)
			)
			(layer "F.SilkS")
		)
		(fp_line
			(start -0.7874 0.4064)
			(end -0.7874 -0.4064)
			(stroke
				(width 0.1524)
				(type default)
			)
			(layer "F.SilkS")
		)
		(fp_line
			(start -0.12065 -0.305054)
			(end -0.12065 -0.2794)
			(stroke
				(width 0.1)
				(type default)
			)
			(layer "F.Fab")
		)
		(fp_line
			(start -0.67945 -0.305054)
			(end -0.12065 -0.305054)
			(stroke
				(width 0.1)
				(type default)
			)
			(layer "F.Fab")
		)
		(fp_line
			(start 0.67945 -0.3048)
			(end 0.67945 0.3048)
			(stroke
				(width 0.1)
				(type default)
			)
			(layer "F.Fab")
		)
		(fp_line
			(start 0.12065 -0.3048)
			(end 0.67945 -0.3048)
			(stroke
				(width 0.1)
				(type default)
			)
			(layer "F.Fab")
		)
		(fp_line
			(start 0.12065 -0.2794)
			(end 0.12065 -0.3048)
			(stroke
				(width 0.1)
				(type default)
			)
			(layer "F.Fab")
		)
		(fp_line
			(start -0.12065 -0.2794)
			(end 0.12065 -0.2794)
			(stroke
				(width 0.1)
				(type default)
			)
			(layer "F.Fab")
		)
		(fp_line
			(start 0.120396 0.2794)
			(end -0.12065 0.2794)
			(stroke
				(width 0.1)
				(type default)
			)
			(layer "F.Fab")
		)
		(fp_line
			(start -0.12065 0.2794)
			(end -0.12065 0.3048)
			(stroke
				(width 0.1)
				(type default)
			)
			(layer "F.Fab")
		)
		(fp_line
			(start 0.67945 0.3048)
			(end 0.120396 0.3048)
			(stroke
				(width 0.1)
				(type default)
			)
			(layer "F.Fab")
		)
		(fp_line
			(start 0.120396 0.3048)
			(end 0.120396 0.2794)
			(stroke
				(width 0.1)
				(type default)
			)
			(layer "F.Fab")
		)
		(fp_line
			(start -0.12065 0.3048)
			(end -0.67945 0.3048)
			(stroke
				(width 0.1)
				(type default)
			)
			(layer "F.Fab")
		)
		(fp_line
			(start -0.67945 0.3048)
			(end -0.67945 -0.305054)
			(stroke
				(width 0.1)
				(type default)
			)
			(layer "F.Fab")
		)
		(pad "1" smd circle
			(at -0.40005 0 90)
			(size 0 0)
			(layers "F.Cu" "F.Mask" "F.Paste")
			(net "SW_P12V_AUX_PVDDCR_SOC_P1_FLT")
		)
		(pad "2" smd circle
			(at 0.40005 0 90)
			(size 0 0)
			(layers "F.Cu" "F.Mask" "F.Paste")
			(net "GND")
		)
	)
	(footprint ""
		(layer "F.Cu")
		(at 421.798496 -357.688134 -90)
		(property "Reference" "PR35"
			(at 0 0 270)
			(layer "F.SilkS")
			(hide yes)
			(effects
				(font
					(size 1.27 1.27)
				)
			)
		)
		(property "Value" ""
			(at 0 0 270)
			(layer "F.Fab")
			(effects
				(font
					(size 1.27 1.27)
				)
			)
		)
		(duplicate_pad_numbers_are_jumpers no)
		(fp_line
			(start -0.7874 0.4064)
			(end -0.7874 -0.4064)
			(stroke
				(width 0.1524)
				(type default)
			)
			(layer "F.SilkS")
		)
		(fp_line
			(start 0.7874 0.4064)
			(end -0.7874 0.4064)
			(stroke
				(width 0.1524)
				(type default)
			)
			(layer "F.SilkS")
		)
		(fp_line
			(start -0.7874 -0.4064)
			(end 0.7874 -0.4064)
			(stroke
				(width 0.1524)
				(type default)
			)
			(layer "F.SilkS")
		)
		(fp_line
			(start 0.7874 -0.4064)
			(end 0.7874 0.4064)
			(stroke
				(width 0.1524)
				(type default)
			)
			(layer "F.SilkS")
		)
		(fp_line
			(start -0.67945 0.3048)
			(end -0.67945 -0.305054)
			(stroke
				(width 0.1)
				(type default)
			)
			(layer "F.Fab")
		)
		(fp_line
			(start -0.12065 0.3048)
			(end -0.67945 0.3048)
			(stroke
				(width 0.1)
				(type default)
			)
			(layer "F.Fab")
		)
		(fp_line
			(start 0.120396 0.3048)
			(end 0.120396 0.2794)
			(stroke
				(width 0.1)
				(type default)
			)
			(layer "F.Fab")
		)
		(fp_line
			(start 0.67945 0.3048)
			(end 0.120396 0.3048)
			(stroke
				(width 0.1)
				(type default)
			)
			(layer "F.Fab")
		)
		(fp_line
			(start -0.12065 0.2794)
			(end -0.12065 0.3048)
			(stroke
				(width 0.1)
				(type default)
			)
			(layer "F.Fab")
		)
		(fp_line
			(start 0.120396 0.2794)
			(end -0.12065 0.2794)
			(stroke
				(width 0.1)
				(type default)
			)
			(layer "F.Fab")
		)
		(fp_line
			(start -0.12065 -0.2794)
			(end 0.12065 -0.2794)
			(stroke
				(width 0.1)
				(type default)
			)
			(layer "F.Fab")
		)
		(fp_line
			(start 0.12065 -0.2794)
			(end 0.12065 -0.3048)
			(stroke
				(width 0.1)
				(type default)
			)
			(layer "F.Fab")
		)
		(fp_line
			(start 0.12065 -0.3048)
			(end 0.67945 -0.3048)
			(stroke
				(width 0.1)
				(type default)
			)
			(layer "F.Fab")
		)
		(fp_line
			(start 0.67945 -0.3048)
			(end 0.67945 0.3048)
			(stroke
				(width 0.1)
				(type default)
			)
			(layer "F.Fab")
		)
		(fp_line
			(start -0.67945 -0.305054)
			(end -0.12065 -0.305054)
			(stroke
				(width 0.1)
				(type default)
			)
			(layer "F.Fab")
		)
		(fp_line
			(start -0.12065 -0.305054)
			(end -0.12065 -0.2794)
			(stroke
				(width 0.1)
				(type default)
			)
			(layer "F.Fab")
		)
		(pad "1" smd circle
			(at -0.40005 0 270)
			(size 0 0)
			(layers "F.Cu" "F.Mask" "F.Paste")
			(net "NC_PVDD11_S3_P0_IMON6")
		)
		(pad "2" smd circle
			(at 0.40005 0 270)
			(size 0 0)
			(layers "F.Cu" "F.Mask" "F.Paste")
			(net "GND")
		)
	)
	(footprint ""
		(layer "F.Cu")
		(at 455.01306 -39.835836 180)
		(property "Reference" "R3784"
			(at 0 0 180)
			(layer "F.SilkS")
			(hide yes)
			(effects
				(font
					(size 1.27 1.27)
				)
			)
		)
		(property "Value" ""
			(at 0 0 180)
			(layer "F.Fab")
			(effects
				(font
					(size 1.27 1.27)
				)
			)
		)
		(duplicate_pad_numbers_are_jumpers no)
		(fp_line
			(start 0.7874 0.4064)
			(end -0.7874 0.4064)
			(stroke
				(width 0.1524)
				(type default)
			)
			(layer "F.SilkS")
		)
		(fp_line
			(start 0.7874 -0.4064)
			(end 0.7874 0.4064)
			(stroke
				(width 0.1524)
				(type default)
			)
			(layer "F.SilkS")
		)
		(fp_line
			(start -0.7874 0.4064)
			(end -0.7874 -0.4064)
			(stroke
				(width 0.1524)
				(type default)
			)
			(layer "F.SilkS")
		)
		(fp_line
			(start -0.7874 -0.4064)
			(end 0.7874 -0.4064)
			(stroke
				(width 0.1524)
				(type default)
			)
			(layer "F.SilkS")
		)
		(fp_line
			(start 0.67945 0.3048)
			(end 0.120396 0.3048)
			(stroke
				(width 0.1)
				(type default)
			)
			(layer "F.Fab")
		)
		(fp_line
			(start 0.67945 -0.3048)
			(end 0.67945 0.3048)
			(stroke
				(width 0.1)
				(type default)
			)
			(layer "F.Fab")
		)
		(fp_line
			(start 0.12065 -0.2794)
			(end 0.12065 -0.3048)
			(stroke
				(width 0.1)
				(type default)
			)
			(layer "F.Fab")
		)
		(fp_line
			(start 0.12065 -0.3048)
			(end 0.67945 -0.3048)
			(stroke
				(width 0.1)
				(type default)
			)
			(layer "F.Fab")
		)
		(fp_line
			(start 0.120396 0.3048)
			(end 0.120396 0.2794)
			(stroke
				(width 0.1)
				(type default)
			)
			(layer "F.Fab")
		)
		(fp_line
			(start 0.120396 0.2794)
			(end -0.12065 0.2794)
			(stroke
				(width 0.1)
				(type default)
			)
			(layer "F.Fab")
		)
		(fp_line
			(start -0.12065 0.3048)
			(end -0.67945 0.3048)
			(stroke
				(width 0.1)
				(type default)
			)
			(layer "F.Fab")
		)
		(fp_line
			(start -0.12065 0.2794)
			(end -0.12065 0.3048)
			(stroke
				(width 0.1)
				(type default)
			)
			(layer "F.Fab")
		)
		(fp_line
			(start -0.12065 -0.2794)
			(end 0.12065 -0.2794)
			(stroke
				(width 0.1)
				(type default)
			)
			(layer "F.Fab")
		)
		(fp_line
			(start -0.12065 -0.305054)
			(end -0.12065 -0.2794)
			(stroke
				(width 0.1)
				(type default)
			)
			(layer "F.Fab")
		)
		(fp_line
			(start -0.67945 0.3048)
			(end -0.67945 -0.305054)
			(stroke
				(width 0.1)
				(type default)
			)
			(layer "F.Fab")
		)
		(fp_line
			(start -0.67945 -0.305054)
			(end -0.12065 -0.305054)
			(stroke
				(width 0.1)
				(type default)
			)
			(layer "F.Fab")
		)
		(pad "1" smd circle
			(at -0.40005 0 180)
			(size 0 0)
			(layers "F.Cu" "F.Mask" "F.Paste")
			(net "P12V_OCP_UV_1_R")
		)
		(pad "2" smd circle
			(at 0.40005 0 180)
			(size 0 0)
			(layers "F.Cu" "F.Mask" "F.Paste")
			(net "P12V_OCP_UV_1")
		)
	)
	(footprint ""
		(layer "F.Cu")
		(at 449.692268 -72.373236 180)
		(property "Reference" "PC1867"
			(at 4.842256 -2.972562 0)
			(unlocked yes)
			(layer "F.SilkS")
			(effects
				(font
					(size 0.7874 0.5842)
					(thickness 0.1524)
				)
				(justify left)
			)
		)
		(property "Value" ""
			(at 0 0 180)
			(layer "F.Fab")
			(effects
				(font
					(size 1.27 1.27)
				)
			)
		)
		(duplicate_pad_numbers_are_jumpers no)
		(fp_line
			(start -3.400044 1.249934)
			(end 3.400044 1.249934)
			(stroke
				(width 0.1524)
				(type default)
			)
			(layer "F.SilkS")
		)
		(fp_circle
			(center 0 1.249934)
			(end -3.400044 1.249934)
			(stroke
				(width 0.1524)
				(type default)
			)
			(fill no)
			(layer "F.SilkS")
		)
		(fp_poly
			(pts
				(arc
					(start 3.400044 1.249934)
					(mid 0 4.649978)
					(end -3.400044 1.249934)
				)
			)
			(stroke
				(width 0)
				(type default)
			)
			(fill yes)
			(layer "F.SilkS")
		)
		(fp_circle
			(center 0 1.249934)
			(end -3.400044 1.249934)
			(stroke
				(width 0.1)
				(type default)
			)
			(fill no)
			(layer "F.Fab")
		)
		(pad "1" thru_hole rect
			(at 0 0 180)
			(size 1.524 1.524)
			(drill 1.016)
			(layers "*.Cu" "*.Mask")
			(remove_unused_layers no)
			(net "P3V3_AUX")
			(clearance 0)
			(padstack
				(mode front_inner_back)
				(layer "Inner"
					(shape circle)
					(size 1.524 1.524)
					(clearance 0)
				)
				(layer "B.Cu"
					(shape rect)
					(size 1.524 1.524)
					(clearance 0)
				)
			)
		)
		(pad "2" thru_hole circle
			(at 0 2.500122 180)
			(size 1.524 1.524)
			(drill 1.016)
			(layers "*.Cu" "*.Mask")
			(remove_unused_layers no)
			(net "GND")
			(clearance 0)
		)
	)
	(footprint ""
		(layer "F.Cu")
		(at 331.633068 -136.473946)
		(property "Reference" "R8465"
			(at 0 0 0)
			(layer "F.SilkS")
			(hide yes)
			(effects
				(font
					(size 1.27 1.27)
				)
			)
		)
		(property "Value" ""
			(at 0 0 0)
			(layer "F.Fab")
			(effects
				(font
					(size 1.27 1.27)
				)
			)
		)
		(duplicate_pad_numbers_are_jumpers no)
		(fp_line
			(start -0.7874 -0.4064)
			(end 0.7874 -0.4064)
			(stroke
				(width 0.1524)
				(type default)
			)
			(layer "F.SilkS")
		)
		(fp_line
			(start -0.7874 0.4064)
			(end -0.7874 -0.4064)
			(stroke
				(width 0.1524)
				(type default)
			)
			(layer "F.SilkS")
		)
		(fp_line
			(start 0.7874 -0.4064)
			(end 0.7874 0.4064)
			(stroke
				(width 0.1524)
				(type default)
			)
			(layer "F.SilkS")
		)
		(fp_line
			(start 0.7874 0.4064)
			(end -0.7874 0.4064)
			(stroke
				(width 0.1524)
				(type default)
			)
			(layer "F.SilkS")
		)
		(fp_line
			(start -0.67945 -0.305054)
			(end -0.12065 -0.305054)
			(stroke
				(width 0.1)
				(type default)
			)
			(layer "F.Fab")
		)
		(fp_line
			(start -0.67945 0.3048)
			(end -0.67945 -0.305054)
			(stroke
				(width 0.1)
				(type default)
			)
			(layer "F.Fab")
		)
		(fp_line
			(start -0.12065 -0.305054)
			(end -0.12065 -0.2794)
			(stroke
				(width 0.1)
				(type default)
			)
			(layer "F.Fab")
		)
		(fp_line
			(start -0.12065 -0.2794)
			(end 0.12065 -0.2794)
			(stroke
				(width 0.1)
				(type default)
			)
			(layer "F.Fab")
		)
		(fp_line
			(start -0.12065 0.2794)
			(end -0.12065 0.3048)
			(stroke
				(width 0.1)
				(type default)
			)
			(layer "F.Fab")
		)
		(fp_line
			(start -0.12065 0.3048)
			(end -0.67945 0.3048)
			(stroke
				(width 0.1)
				(type default)
			)
			(layer "F.Fab")
		)
		(fp_line
			(start 0.120396 0.2794)
			(end -0.12065 0.2794)
			(stroke
				(width 0.1)
				(type default)
			)
			(layer "F.Fab")
		)
		(fp_line
			(start 0.120396 0.3048)
			(end 0.120396 0.2794)
			(stroke
				(width 0.1)
				(type default)
			)
			(layer "F.Fab")
		)
		(fp_line
			(start 0.12065 -0.3048)
			(end 0.67945 -0.3048)
			(stroke
				(width 0.1)
				(type default)
			)
			(layer "F.Fab")
		)
		(fp_line
			(start 0.12065 -0.2794)
			(end 0.12065 -0.3048)
			(stroke
				(width 0.1)
				(type default)
			)
			(layer "F.Fab")
		)
		(fp_line
			(start 0.67945 -0.3048)
			(end 0.67945 0.3048)
			(stroke
				(width 0.1)
				(type default)
			)
			(layer "F.Fab")
		)
		(fp_line
			(start 0.67945 0.3048)
			(end 0.120396 0.3048)
			(stroke
				(width 0.1)
				(type default)
			)
			(layer "F.Fab")
		)
		(pad "1" smd circle
			(at -0.40005 0)
			(size 0 0)
			(layers "F.Cu" "F.Mask" "F.Paste")
			(net "P3V3_AUX")
		)
		(pad "2" smd circle
			(at 0.40005 0)
			(size 0 0)
			(layers "F.Cu" "F.Mask" "F.Paste")
			(net "PWRGD_PVDD18_S5_P0")
		)
	)
	(footprint ""
		(layer "F.Cu")
		(at 319.940178 -47.002954)
		(property "Reference" "C2046"
			(at 0 0 0)
			(layer "F.SilkS")
			(hide yes)
			(effects
				(font
					(size 1.27 1.27)
				)
			)
		)
		(property "Value" ""
			(at 0 0 0)
			(layer "F.Fab")
			(effects
				(font
					(size 1.27 1.27)
				)
			)
		)
		(duplicate_pad_numbers_are_jumpers no)
		(fp_line
			(start -0.7874 -0.4064)
			(end 0.7874 -0.4064)
			(stroke
				(width 0.1524)
				(type default)
			)
			(layer "F.SilkS")
		)
		(fp_line
			(start -0.7874 0.4064)
			(end -0.7874 -0.4064)
			(stroke
				(width 0.1524)
				(type default)
			)
			(layer "F.SilkS")
		)
		(fp_line
			(start 0.7874 -0.4064)
			(end 0.7874 0.4064)
			(stroke
				(width 0.1524)
				(type default)
			)
			(layer "F.SilkS")
		)
		(fp_line
			(start 0.7874 0.4064)
			(end -0.7874 0.4064)
			(stroke
				(width 0.1524)
				(type default)
			)
			(layer "F.SilkS")
		)
		(fp_line
			(start -0.67945 -0.305054)
			(end -0.12065 -0.305054)
			(stroke
				(width 0.1)
				(type default)
			)
			(layer "F.Fab")
		)
		(fp_line
			(start -0.67945 0.3048)
			(end -0.67945 -0.305054)
			(stroke
				(width 0.1)
				(type default)
			)
			(layer "F.Fab")
		)
		(fp_line
			(start -0.12065 -0.305054)
			(end -0.12065 -0.2794)
			(stroke
				(width 0.1)
				(type default)
			)
			(layer "F.Fab")
		)
		(fp_line
			(start -0.12065 -0.2794)
			(end 0.12065 -0.2794)
			(stroke
				(width 0.1)
				(type default)
			)
			(layer "F.Fab")
		)
		(fp_line
			(start -0.12065 0.2794)
			(end -0.12065 0.3048)
			(stroke
				(width 0.1)
				(type default)
			)
			(layer "F.Fab")
		)
		(fp_line
			(start -0.12065 0.3048)
			(end -0.67945 0.3048)
			(stroke
				(width 0.1)
				(type default)
			)
			(layer "F.Fab")
		)
		(fp_line
			(start 0.120396 0.2794)
			(end -0.12065 0.2794)
			(stroke
				(width 0.1)
				(type default)
			)
			(layer "F.Fab")
		)
		(fp_line
			(start 0.120396 0.3048)
			(end 0.120396 0.2794)
			(stroke
				(width 0.1)
				(type default)
			)
			(layer "F.Fab")
		)
		(fp_line
			(start 0.12065 -0.3048)
			(end 0.67945 -0.3048)
			(stroke
				(width 0.1)
				(type default)
			)
			(layer "F.Fab")
		)
		(fp_line
			(start 0.12065 -0.2794)
			(end 0.12065 -0.3048)
			(stroke
				(width 0.1)
				(type default)
			)
			(layer "F.Fab")
		)
		(fp_line
			(start 0.67945 -0.3048)
			(end 0.67945 0.3048)
			(stroke
				(width 0.1)
				(type default)
			)
			(layer "F.Fab")
		)
		(fp_line
			(start 0.67945 0.3048)
			(end 0.120396 0.3048)
			(stroke
				(width 0.1)
				(type default)
			)
			(layer "F.Fab")
		)
		(pad "1" smd circle
			(at -0.40005 0)
			(size 0 0)
			(layers "F.Cu" "F.Mask" "F.Paste")
			(net "P12V_AUX_ADC_TIC")
		)
		(pad "2" smd circle
			(at 0.40005 0)
			(size 0 0)
			(layers "F.Cu" "F.Mask" "F.Paste")
			(net "GND")
		)
	)
	(footprint ""
		(layer "F.Cu")
		(at 31.712662 -421.916098 180)
		(property "Reference" "C1863"
			(at 0 0 180)
			(layer "F.SilkS")
			(hide yes)
			(effects
				(font
					(size 1.27 1.27)
				)
			)
		)
		(property "Value" ""
			(at 0 0 180)
			(layer "F.Fab")
			(effects
				(font
					(size 1.27 1.27)
				)
			)
		)
		(duplicate_pad_numbers_are_jumpers no)
		(fp_line
			(start 0.7874 0.4064)
			(end -0.7874 0.4064)
			(stroke
				(width 0.1524)
				(type default)
			)
			(layer "F.SilkS")
		)
		(fp_line
			(start 0.7874 -0.4064)
			(end 0.7874 0.4064)
			(stroke
				(width 0.1524)
				(type default)
			)
			(layer "F.SilkS")
		)
		(fp_line
			(start -0.7874 0.4064)
			(end -0.7874 -0.4064)
			(stroke
				(width 0.1524)
				(type default)
			)
			(layer "F.SilkS")
		)
		(fp_line
			(start -0.7874 -0.4064)
			(end 0.7874 -0.4064)
			(stroke
				(width 0.1524)
				(type default)
			)
			(layer "F.SilkS")
		)
		(fp_line
			(start 0.67945 0.3048)
			(end 0.120396 0.3048)
			(stroke
				(width 0.1)
				(type default)
			)
			(layer "F.Fab")
		)
		(fp_line
			(start 0.67945 -0.3048)
			(end 0.67945 0.3048)
			(stroke
				(width 0.1)
				(type default)
			)
			(layer "F.Fab")
		)
		(fp_line
			(start 0.12065 -0.2794)
			(end 0.12065 -0.3048)
			(stroke
				(width 0.1)
				(type default)
			)
			(layer "F.Fab")
		)
		(fp_line
			(start 0.12065 -0.3048)
			(end 0.67945 -0.3048)
			(stroke
				(width 0.1)
				(type default)
			)
			(layer "F.Fab")
		)
		(fp_line
			(start 0.120396 0.3048)
			(end 0.120396 0.2794)
			(stroke
				(width 0.1)
				(type default)
			)
			(layer "F.Fab")
		)
		(fp_line
			(start 0.120396 0.2794)
			(end -0.12065 0.2794)
			(stroke
				(width 0.1)
				(type default)
			)
			(layer "F.Fab")
		)
		(fp_line
			(start -0.12065 0.3048)
			(end -0.67945 0.3048)
			(stroke
				(width 0.1)
				(type default)
			)
			(layer "F.Fab")
		)
		(fp_line
			(start -0.12065 0.2794)
			(end -0.12065 0.3048)
			(stroke
				(width 0.1)
				(type default)
			)
			(layer "F.Fab")
		)
		(fp_line
			(start -0.12065 -0.2794)
			(end 0.12065 -0.2794)
			(stroke
				(width 0.1)
				(type default)
			)
			(layer "F.Fab")
		)
		(fp_line
			(start -0.12065 -0.305054)
			(end -0.12065 -0.2794)
			(stroke
				(width 0.1)
				(type default)
			)
			(layer "F.Fab")
		)
		(fp_line
			(start -0.67945 0.3048)
			(end -0.67945 -0.305054)
			(stroke
				(width 0.1)
				(type default)
			)
			(layer "F.Fab")
		)
		(fp_line
			(start -0.67945 -0.305054)
			(end -0.12065 -0.305054)
			(stroke
				(width 0.1)
				(type default)
			)
			(layer "F.Fab")
		)
		(pad "1" smd circle
			(at -0.40005 0 180)
			(size 0 0)
			(layers "F.Cu" "F.Mask" "F.Paste")
			(net "P3V3_AUX")
		)
		(pad "2" smd circle
			(at 0.40005 0 180)
			(size 0 0)
			(layers "F.Cu" "F.Mask" "F.Paste")
			(net "GND")
		)
	)
	(footprint ""
		(layer "F.Cu")
		(at 84.026502 -370.57203 -90)
		(property "Reference" "C729"
			(at 0 0 270)
			(layer "F.SilkS")
			(hide yes)
			(effects
				(font
					(size 1.27 1.27)
				)
			)
		)
		(property "Value" ""
			(at 0 0 270)
			(layer "F.Fab")
			(effects
				(font
					(size 1.27 1.27)
				)
			)
		)
		(duplicate_pad_numbers_are_jumpers no)
		(fp_line
			(start -0.299974 0.150114)
			(end -0.299974 -0.150114)
			(stroke
				(width 0.1)
				(type default)
			)
			(layer "F.Fab")
		)
		(fp_line
			(start 0.299974 0.150114)
			(end -0.299974 0.150114)
			(stroke
				(width 0.1)
				(type default)
			)
			(layer "F.Fab")
		)
		(fp_line
			(start -0.299974 -0.150114)
			(end 0.299974 -0.150114)
			(stroke
				(width 0.1)
				(type default)
			)
			(layer "F.Fab")
		)
		(fp_line
			(start 0.299974 -0.150114)
			(end 0.299974 0.150114)
			(stroke
				(width 0.1)
				(type default)
			)
			(layer "F.Fab")
		)
		(pad "1" smd rect
			(at -0.2667 0 270)
			(size 0.3048 0.381)
			(layers "F.Cu" "F.Mask" "F.Paste")
			(net "P5E_CPU1_P1_TX_C_DP<6>")
		)
		(pad "2" smd rect
			(at 0.2667 0 270)
			(size 0.3048 0.381)
			(layers "F.Cu" "F.Mask" "F.Paste")
			(net "P5E_CPU1_P1_TX_DP<6>")
		)
	)
	(footprint ""
		(layer "F.Cu")
		(at 104.389936 -127.768096 -90)
		(property "Reference" "R1452"
			(at 0 0 270)
			(layer "F.SilkS")
			(hide yes)
			(effects
				(font
					(size 1.27 1.27)
				)
			)
		)
		(property "Value" ""
			(at 0 0 270)
			(layer "F.Fab")
			(effects
				(font
					(size 1.27 1.27)
				)
			)
		)
		(duplicate_pad_numbers_are_jumpers no)
		(fp_line
			(start -0.7874 0.4064)
			(end -0.7874 -0.4064)
			(stroke
				(width 0.1524)
				(type default)
			)
			(layer "F.SilkS")
		)
		(fp_line
			(start 0.7874 0.4064)
			(end -0.7874 0.4064)
			(stroke
				(width 0.1524)
				(type default)
			)
			(layer "F.SilkS")
		)
		(fp_line
			(start -0.7874 -0.4064)
			(end 0.7874 -0.4064)
			(stroke
				(width 0.1524)
				(type default)
			)
			(layer "F.SilkS")
		)
		(fp_line
			(start 0.7874 -0.4064)
			(end 0.7874 0.4064)
			(stroke
				(width 0.1524)
				(type default)
			)
			(layer "F.SilkS")
		)
		(fp_line
			(start -0.67945 0.3048)
			(end -0.67945 -0.305054)
			(stroke
				(width 0.1)
				(type default)
			)
			(layer "F.Fab")
		)
		(fp_line
			(start -0.12065 0.3048)
			(end -0.67945 0.3048)
			(stroke
				(width 0.1)
				(type default)
			)
			(layer "F.Fab")
		)
		(fp_line
			(start 0.120396 0.3048)
			(end 0.120396 0.2794)
			(stroke
				(width 0.1)
				(type default)
			)
			(layer "F.Fab")
		)
		(fp_line
			(start 0.67945 0.3048)
			(end 0.120396 0.3048)
			(stroke
				(width 0.1)
				(type default)
			)
			(layer "F.Fab")
		)
		(fp_line
			(start -0.12065 0.2794)
			(end -0.12065 0.3048)
			(stroke
				(width 0.1)
				(type default)
			)
			(layer "F.Fab")
		)
		(fp_line
			(start 0.120396 0.2794)
			(end -0.12065 0.2794)
			(stroke
				(width 0.1)
				(type default)
			)
			(layer "F.Fab")
		)
		(fp_line
			(start -0.12065 -0.2794)
			(end 0.12065 -0.2794)
			(stroke
				(width 0.1)
				(type default)
			)
			(layer "F.Fab")
		)
		(fp_line
			(start 0.12065 -0.2794)
			(end 0.12065 -0.3048)
			(stroke
				(width 0.1)
				(type default)
			)
			(layer "F.Fab")
		)
		(fp_line
			(start 0.12065 -0.3048)
			(end 0.67945 -0.3048)
			(stroke
				(width 0.1)
				(type default)
			)
			(layer "F.Fab")
		)
		(fp_line
			(start 0.67945 -0.3048)
			(end 0.67945 0.3048)
			(stroke
				(width 0.1)
				(type default)
			)
			(layer "F.Fab")
		)
		(fp_line
			(start -0.67945 -0.305054)
			(end -0.12065 -0.305054)
			(stroke
				(width 0.1)
				(type default)
			)
			(layer "F.Fab")
		)
		(fp_line
			(start -0.12065 -0.305054)
			(end -0.12065 -0.2794)
			(stroke
				(width 0.1)
				(type default)
			)
			(layer "F.Fab")
		)
		(pad "1" smd circle
			(at -0.40005 0 270)
			(size 0 0)
			(layers "F.Cu" "F.Mask" "F.Paste")
			(net "P1V8_AUX")
		)
		(pad "2" smd circle
			(at 0.40005 0 270)
			(size 0 0)
			(layers "F.Cu" "F.Mask" "F.Paste")
			(net "PWRGD_P12V_MEM_CPU1")
		)
	)
	(footprint ""
		(layer "F.Cu")
		(at 226.421442 -315.82868 90)
		(property "Reference" "PC6804"
			(at -1.75768 -4.906772 90)
			(unlocked yes)
			(layer "F.SilkS")
			(effects
				(font
					(size 0.7874 0.5842)
					(thickness 0.1524)
				)
				(justify left)
			)
		)
		(property "Value" ""
			(at 0 0 90)
			(layer "F.Fab")
			(effects
				(font
					(size 1.27 1.27)
				)
			)
		)
		(duplicate_pad_numbers_are_jumpers no)
		(fp_line
			(start 2.750058 -2.750058)
			(end -1.988058 -2.750058)
			(stroke
				(width 0.1524)
				(type default)
			)
			(layer "F.SilkS")
		)
		(fp_line
			(start -1.988058 -2.750058)
			(end -2.750058 -1.988058)
			(stroke
				(width 0.1524)
				(type default)
			)
			(layer "F.SilkS")
		)
		(fp_line
			(start -2.750058 -1.988058)
			(end -2.750058 -0.9398)
			(stroke
				(width 0.1524)
				(type default)
			)
			(layer "F.SilkS")
		)
		(fp_line
			(start 2.750058 -0.9398)
			(end 2.750058 -2.750058)
			(stroke
				(width 0.1524)
				(type default)
			)
			(layer "F.SilkS")
		)
		(fp_line
			(start -2.750058 0.9398)
			(end -2.750058 1.988058)
			(stroke
				(width 0.1524)
				(type default)
			)
			(layer "F.SilkS")
		)
		(fp_line
			(start -2.750058 1.988058)
			(end -1.988058 2.750058)
			(stroke
				(width 0.1524)
				(type default)
			)
			(layer "F.SilkS")
		)
		(fp_line
			(start 2.750058 2.750058)
			(end 2.750058 0.9398)
			(stroke
				(width 0.1524)
				(type default)
			)
			(layer "F.SilkS")
		)
		(fp_line
			(start -1.988058 2.750058)
			(end 2.750058 2.750058)
			(stroke
				(width 0.1524)
				(type default)
			)
			(layer "F.SilkS")
		)
		(fp_line
			(start 2.750058 -2.750058)
			(end -2.750058 -2.750058)
			(stroke
				(width 0.1)
				(type default)
			)
			(layer "F.Fab")
		)
		(fp_line
			(start -2.750058 -2.750058)
			(end -2.750058 2.750058)
			(stroke
				(width 0.1)
				(type default)
			)
			(layer "F.Fab")
		)
		(fp_line
			(start 2.750058 2.750058)
			(end 2.750058 -2.750058)
			(stroke
				(width 0.1)
				(type default)
			)
			(layer "F.Fab")
		)
		(fp_line
			(start -2.750058 2.750058)
			(end 2.750058 2.750058)
			(stroke
				(width 0.1)
				(type default)
			)
			(layer "F.Fab")
		)
		(pad "1" smd rect
			(at -2.199894 0 180)
			(size 1.6002 3.0226)
			(layers "F.Cu" "F.Mask" "F.Paste")
			(net "P1V8_CPU1_RT_1D")
		)
		(pad "2" smd rect
			(at 2.199894 0 180)
			(size 1.6002 3.0226)
			(layers "F.Cu" "F.Mask" "F.Paste")
			(net "GND")
		)
	)
	(footprint ""
		(layer "F.Cu")
		(at 72.274684 -408.517344 -90)
		(property "Reference" "C6646"
			(at 0 0 270)
			(layer "F.SilkS")
			(hide yes)
			(effects
				(font
					(size 1.27 1.27)
				)
			)
		)
		(property "Value" ""
			(at 0 0 270)
			(layer "F.Fab")
			(effects
				(font
					(size 1.27 1.27)
				)
			)
		)
		(duplicate_pad_numbers_are_jumpers no)
		(fp_line
			(start -0.299974 0.150114)
			(end -0.299974 -0.150114)
			(stroke
				(width 0.1)
				(type default)
			)
			(layer "F.Fab")
		)
		(fp_line
			(start 0.299974 0.150114)
			(end -0.299974 0.150114)
			(stroke
				(width 0.1)
				(type default)
			)
			(layer "F.Fab")
		)
		(fp_line
			(start -0.299974 -0.150114)
			(end 0.299974 -0.150114)
			(stroke
				(width 0.1)
				(type default)
			)
			(layer "F.Fab")
		)
		(fp_line
			(start 0.299974 -0.150114)
			(end 0.299974 0.150114)
			(stroke
				(width 0.1)
				(type default)
			)
			(layer "F.Fab")
		)
		(pad "1" smd rect
			(at -0.2667 0 270)
			(size 0.3048 0.381)
			(layers "F.Cu" "F.Mask" "F.Paste")
			(net "P5E_CPU1_P0_TX_BUF_C_DN<8>")
		)
		(pad "2" smd rect
			(at 0.2667 0 270)
			(size 0.3048 0.381)
			(layers "F.Cu" "F.Mask" "F.Paste")
			(net "P5E_CPU1_P0_TX_BUF_DN<8>")
		)
	)
	(footprint ""
		(layer "F.Cu")
		(at 57.17794 -346.87129 -90)
		(property "Reference" "PC440_1"
			(at 0 0 270)
			(layer "F.SilkS")
			(hide yes)
			(effects
				(font
					(size 1.27 1.27)
				)
			)
		)
		(property "Value" ""
			(at 0 0 270)
			(layer "F.Fab")
			(effects
				(font
					(size 1.27 1.27)
				)
			)
		)
		(duplicate_pad_numbers_are_jumpers no)
		(fp_line
			(start -0.7874 0.4064)
			(end -0.7874 -0.4064)
			(stroke
				(width 0.1524)
				(type default)
			)
			(layer "F.SilkS")
		)
		(fp_line
			(start 0.7874 0.4064)
			(end -0.7874 0.4064)
			(stroke
				(width 0.1524)
				(type default)
			)
			(layer "F.SilkS")
		)
		(fp_line
			(start -0.7874 -0.4064)
			(end 0.7874 -0.4064)
			(stroke
				(width 0.1524)
				(type default)
			)
			(layer "F.SilkS")
		)
		(fp_line
			(start 0.7874 -0.4064)
			(end 0.7874 0.4064)
			(stroke
				(width 0.1524)
				(type default)
			)
			(layer "F.SilkS")
		)
		(fp_line
			(start -0.67945 0.3048)
			(end -0.67945 -0.305054)
			(stroke
				(width 0.1)
				(type default)
			)
			(layer "F.Fab")
		)
		(fp_line
			(start -0.12065 0.3048)
			(end -0.67945 0.3048)
			(stroke
				(width 0.1)
				(type default)
			)
			(layer "F.Fab")
		)
		(fp_line
			(start 0.120396 0.3048)
			(end 0.120396 0.2794)
			(stroke
				(width 0.1)
				(type default)
			)
			(layer "F.Fab")
		)
		(fp_line
			(start 0.67945 0.3048)
			(end 0.120396 0.3048)
			(stroke
				(width 0.1)
				(type default)
			)
			(layer "F.Fab")
		)
		(fp_line
			(start -0.12065 0.2794)
			(end -0.12065 0.3048)
			(stroke
				(width 0.1)
				(type default)
			)
			(layer "F.Fab")
		)
		(fp_line
			(start 0.120396 0.2794)
			(end -0.12065 0.2794)
			(stroke
				(width 0.1)
				(type default)
			)
			(layer "F.Fab")
		)
		(fp_line
			(start -0.12065 -0.2794)
			(end 0.12065 -0.2794)
			(stroke
				(width 0.1)
				(type default)
			)
			(layer "F.Fab")
		)
		(fp_line
			(start 0.12065 -0.2794)
			(end 0.12065 -0.3048)
			(stroke
				(width 0.1)
				(type default)
			)
			(layer "F.Fab")
		)
		(fp_line
			(start 0.12065 -0.3048)
			(end 0.67945 -0.3048)
			(stroke
				(width 0.1)
				(type default)
			)
			(layer "F.Fab")
		)
		(fp_line
			(start 0.67945 -0.3048)
			(end 0.67945 0.3048)
			(stroke
				(width 0.1)
				(type default)
			)
			(layer "F.Fab")
		)
		(fp_line
			(start -0.67945 -0.305054)
			(end -0.12065 -0.305054)
			(stroke
				(width 0.1)
				(type default)
			)
			(layer "F.Fab")
		)
		(fp_line
			(start -0.12065 -0.305054)
			(end -0.12065 -0.2794)
			(stroke
				(width 0.1)
				(type default)
			)
			(layer "F.Fab")
		)
		(pad "1" smd circle
			(at -0.40005 0 270)
			(size 0 0)
			(layers "F.Cu" "F.Mask" "F.Paste")
			(net "SW_P12V_AUX_PVDDIO_P1_FLT")
		)
		(pad "2" smd circle
			(at 0.40005 0 270)
			(size 0 0)
			(layers "F.Cu" "F.Mask" "F.Paste")
			(net "GND")
		)
	)
	(footprint ""
		(layer "F.Cu")
		(at 18.702782 -133.480302)
		(property "Reference" "R3336"
			(at 0 0 0)
			(layer "F.SilkS")
			(hide yes)
			(effects
				(font
					(size 1.27 1.27)
				)
			)
		)
		(property "Value" ""
			(at 0 0 0)
			(layer "F.Fab")
			(effects
				(font
					(size 1.27 1.27)
				)
			)
		)
		(duplicate_pad_numbers_are_jumpers no)
		(fp_line
			(start -0.7874 -0.4064)
			(end 0.7874 -0.4064)
			(stroke
				(width 0.1524)
				(type default)
			)
			(layer "F.SilkS")
		)
		(fp_line
			(start -0.7874 0.4064)
			(end -0.7874 -0.4064)
			(stroke
				(width 0.1524)
				(type default)
			)
			(layer "F.SilkS")
		)
		(fp_line
			(start 0.7874 -0.4064)
			(end 0.7874 0.4064)
			(stroke
				(width 0.1524)
				(type default)
			)
			(layer "F.SilkS")
		)
		(fp_line
			(start 0.7874 0.4064)
			(end -0.7874 0.4064)
			(stroke
				(width 0.1524)
				(type default)
			)
			(layer "F.SilkS")
		)
		(fp_line
			(start -0.67945 -0.305054)
			(end -0.12065 -0.305054)
			(stroke
				(width 0.1)
				(type default)
			)
			(layer "F.Fab")
		)
		(fp_line
			(start -0.67945 0.3048)
			(end -0.67945 -0.305054)
			(stroke
				(width 0.1)
				(type default)
			)
			(layer "F.Fab")
		)
		(fp_line
			(start -0.12065 -0.305054)
			(end -0.12065 -0.2794)
			(stroke
				(width 0.1)
				(type default)
			)
			(layer "F.Fab")
		)
		(fp_line
			(start -0.12065 -0.2794)
			(end 0.12065 -0.2794)
			(stroke
				(width 0.1)
				(type default)
			)
			(layer "F.Fab")
		)
		(fp_line
			(start -0.12065 0.2794)
			(end -0.12065 0.3048)
			(stroke
				(width 0.1)
				(type default)
			)
			(layer "F.Fab")
		)
		(fp_line
			(start -0.12065 0.3048)
			(end -0.67945 0.3048)
			(stroke
				(width 0.1)
				(type default)
			)
			(layer "F.Fab")
		)
		(fp_line
			(start 0.120396 0.2794)
			(end -0.12065 0.2794)
			(stroke
				(width 0.1)
				(type default)
			)
			(layer "F.Fab")
		)
		(fp_line
			(start 0.120396 0.3048)
			(end 0.120396 0.2794)
			(stroke
				(width 0.1)
				(type default)
			)
			(layer "F.Fab")
		)
		(fp_line
			(start 0.12065 -0.3048)
			(end 0.67945 -0.3048)
			(stroke
				(width 0.1)
				(type default)
			)
			(layer "F.Fab")
		)
		(fp_line
			(start 0.12065 -0.2794)
			(end 0.12065 -0.3048)
			(stroke
				(width 0.1)
				(type default)
			)
			(layer "F.Fab")
		)
		(fp_line
			(start 0.67945 -0.3048)
			(end 0.67945 0.3048)
			(stroke
				(width 0.1)
				(type default)
			)
			(layer "F.Fab")
		)
		(fp_line
			(start 0.67945 0.3048)
			(end 0.120396 0.3048)
			(stroke
				(width 0.1)
				(type default)
			)
			(layer "F.Fab")
		)
		(pad "1" smd circle
			(at -0.40005 0)
			(size 0 0)
			(layers "F.Cu" "F.Mask" "F.Paste")
			(net "CLK_100M_BMC_RC_DN_R")
		)
		(pad "2" smd circle
			(at 0.40005 0)
			(size 0 0)
			(layers "F.Cu" "F.Mask" "F.Paste")
			(net "CLK_100M_BMC_RC_DN")
		)
	)
	(footprint ""
		(layer "F.Cu")
		(at 118.718584 -57.852056)
		(property "Reference" "R1740"
			(at 0 0 0)
			(layer "F.SilkS")
			(hide yes)
			(effects
				(font
					(size 1.27 1.27)
				)
			)
		)
		(property "Value" ""
			(at 0 0 0)
			(layer "F.Fab")
			(effects
				(font
					(size 1.27 1.27)
				)
			)
		)
		(duplicate_pad_numbers_are_jumpers no)
		(fp_line
			(start -0.7874 -0.4064)
			(end 0.7874 -0.4064)
			(stroke
				(width 0.1524)
				(type default)
			)
			(layer "F.SilkS")
		)
		(fp_line
			(start -0.7874 0.4064)
			(end -0.7874 -0.4064)
			(stroke
				(width 0.1524)
				(type default)
			)
			(layer "F.SilkS")
		)
		(fp_line
			(start 0.7874 -0.4064)
			(end 0.7874 0.4064)
			(stroke
				(width 0.1524)
				(type default)
			)
			(layer "F.SilkS")
		)
		(fp_line
			(start 0.7874 0.4064)
			(end -0.7874 0.4064)
			(stroke
				(width 0.1524)
				(type default)
			)
			(layer "F.SilkS")
		)
		(fp_line
			(start -0.67945 -0.305054)
			(end -0.12065 -0.305054)
			(stroke
				(width 0.1)
				(type default)
			)
			(layer "F.Fab")
		)
		(fp_line
			(start -0.67945 0.3048)
			(end -0.67945 -0.305054)
			(stroke
				(width 0.1)
				(type default)
			)
			(layer "F.Fab")
		)
		(fp_line
			(start -0.12065 -0.305054)
			(end -0.12065 -0.2794)
			(stroke
				(width 0.1)
				(type default)
			)
			(layer "F.Fab")
		)
		(fp_line
			(start -0.12065 -0.2794)
			(end 0.12065 -0.2794)
			(stroke
				(width 0.1)
				(type default)
			)
			(layer "F.Fab")
		)
		(fp_line
			(start -0.12065 0.2794)
			(end -0.12065 0.3048)
			(stroke
				(width 0.1)
				(type default)
			)
			(layer "F.Fab")
		)
		(fp_line
			(start -0.12065 0.3048)
			(end -0.67945 0.3048)
			(stroke
				(width 0.1)
				(type default)
			)
			(layer "F.Fab")
		)
		(fp_line
			(start 0.120396 0.2794)
			(end -0.12065 0.2794)
			(stroke
				(width 0.1)
				(type default)
			)
			(layer "F.Fab")
		)
		(fp_line
			(start 0.120396 0.3048)
			(end 0.120396 0.2794)
			(stroke
				(width 0.1)
				(type default)
			)
			(layer "F.Fab")
		)
		(fp_line
			(start 0.12065 -0.3048)
			(end 0.67945 -0.3048)
			(stroke
				(width 0.1)
				(type default)
			)
			(layer "F.Fab")
		)
		(fp_line
			(start 0.12065 -0.2794)
			(end 0.12065 -0.3048)
			(stroke
				(width 0.1)
				(type default)
			)
			(layer "F.Fab")
		)
		(fp_line
			(start 0.67945 -0.3048)
			(end 0.67945 0.3048)
			(stroke
				(width 0.1)
				(type default)
			)
			(layer "F.Fab")
		)
		(fp_line
			(start 0.67945 0.3048)
			(end 0.120396 0.3048)
			(stroke
				(width 0.1)
				(type default)
			)
			(layer "F.Fab")
		)
		(pad "1" smd circle
			(at -0.40005 0)
			(size 0 0)
			(layers "F.Cu" "F.Mask" "F.Paste")
			(net "JTAG_SCM_PLD_R_TCK")
		)
		(pad "2" smd circle
			(at 0.40005 0)
			(size 0 0)
			(layers "F.Cu" "F.Mask" "F.Paste")
			(net "JTAG_SCM_PLD_TCK")
		)
	)
	(footprint ""
		(layer "F.Cu")
		(at 120.631712 -73.296272 -0.054)
		(property "Reference" "PR6011"
			(at 0 0 359.946)
			(layer "F.SilkS")
			(hide yes)
			(effects
				(font
					(size 1.27 1.27)
				)
			)
		)
		(property "Value" ""
			(at 0 0 359.946)
			(layer "F.Fab")
			(effects
				(font
					(size 1.27 1.27)
				)
			)
		)
		(duplicate_pad_numbers_are_jumpers no)
		(fp_line
			(start -0.787525 0.40638)
			(end -0.787275 -0.40642)
			(stroke
				(width 0.1524)
				(type default)
			)
			(layer "F.SilkS")
		)
		(fp_line
			(start -0.787275 -0.40642)
			(end 0.787525 -0.40638)
			(stroke
				(width 0.1524)
				(type default)
			)
			(layer "F.SilkS")
		)
		(fp_line
			(start 0.787275 0.40642)
			(end -0.787525 0.40638)
			(stroke
				(width 0.1524)
				(type default)
			)
			(layer "F.SilkS")
		)
		(fp_line
			(start 0.787525 -0.40638)
			(end 0.787275 0.40642)
			(stroke
				(width 0.1524)
				(type default)
			)
			(layer "F.SilkS")
		)
		(fp_line
			(start -0.679417 0.304678)
			(end -0.679484 -0.305176)
			(stroke
				(width 0.1)
				(type default)
			)
			(layer "F.Fab")
		)
		(fp_line
			(start -0.679484 -0.305176)
			(end -0.120683 -0.30494)
			(stroke
				(width 0.1)
				(type default)
			)
			(layer "F.Fab")
		)
		(fp_line
			(start -0.120641 0.279514)
			(end -0.120617 0.304914)
			(stroke
				(width 0.1)
				(type default)
			)
			(layer "F.Fab")
		)
		(fp_line
			(start -0.120617 0.304914)
			(end -0.679417 0.304678)
			(stroke
				(width 0.1)
				(type default)
			)
			(layer "F.Fab")
		)
		(fp_line
			(start -0.120683 -0.30494)
			(end -0.120659 -0.279286)
			(stroke
				(width 0.1)
				(type default)
			)
			(layer "F.Fab")
		)
		(fp_line
			(start -0.120659 -0.279286)
			(end 0.120641 -0.279514)
			(stroke
				(width 0.1)
				(type default)
			)
			(layer "F.Fab")
		)
		(fp_line
			(start 0.120405 0.279287)
			(end -0.120641 0.279514)
			(stroke
				(width 0.1)
				(type default)
			)
			(layer "F.Fab")
		)
		(fp_line
			(start 0.120429 0.304687)
			(end 0.120405 0.279287)
			(stroke
				(width 0.1)
				(type default)
			)
			(layer "F.Fab")
		)
		(fp_line
			(start 0.120617 -0.304914)
			(end 0.679417 -0.304678)
			(stroke
				(width 0.1)
				(type default)
			)
			(layer "F.Fab")
		)
		(fp_line
			(start 0.120641 -0.279514)
			(end 0.120617 -0.304914)
			(stroke
				(width 0.1)
				(type default)
			)
			(layer "F.Fab")
		)
		(fp_line
			(start 0.679484 0.304922)
			(end 0.120429 0.304687)
			(stroke
				(width 0.1)
				(type default)
			)
			(layer "F.Fab")
		)
		(fp_line
			(start 0.679417 -0.304678)
			(end 0.679484 0.304922)
			(stroke
				(width 0.1)
				(type default)
			)
			(layer "F.Fab")
		)
		(pad "1" smd circle
			(at -0.40005 0 359.946)
			(size 0 0)
			(layers "F.Cu" "F.Mask" "F.Paste")
			(net "P1V2_AUX_FB")
		)
		(pad "2" smd circle
			(at 0.40005 0 359.946)
			(size 0 0)
			(layers "F.Cu" "F.Mask" "F.Paste")
			(net "GND")
		)
	)
	(footprint ""
		(layer "F.Cu")
		(at 218.567 -99.441 180)
		(property "Reference" "R9034"
			(at 0 0 180)
			(layer "F.SilkS")
			(hide yes)
			(effects
				(font
					(size 1.27 1.27)
				)
			)
		)
		(property "Value" ""
			(at 0 0 180)
			(layer "F.Fab")
			(effects
				(font
					(size 1.27 1.27)
				)
			)
		)
		(duplicate_pad_numbers_are_jumpers no)
		(fp_line
			(start 0.7874 0.4064)
			(end -0.7874 0.4064)
			(stroke
				(width 0.1524)
				(type default)
			)
			(layer "F.SilkS")
		)
		(fp_line
			(start 0.7874 -0.4064)
			(end 0.7874 0.4064)
			(stroke
				(width 0.1524)
				(type default)
			)
			(layer "F.SilkS")
		)
		(fp_line
			(start -0.7874 0.4064)
			(end -0.7874 -0.4064)
			(stroke
				(width 0.1524)
				(type default)
			)
			(layer "F.SilkS")
		)
		(fp_line
			(start -0.7874 -0.4064)
			(end 0.7874 -0.4064)
			(stroke
				(width 0.1524)
				(type default)
			)
			(layer "F.SilkS")
		)
		(fp_line
			(start 0.67945 0.3048)
			(end 0.120396 0.3048)
			(stroke
				(width 0.1)
				(type default)
			)
			(layer "F.Fab")
		)
		(fp_line
			(start 0.67945 -0.3048)
			(end 0.67945 0.3048)
			(stroke
				(width 0.1)
				(type default)
			)
			(layer "F.Fab")
		)
		(fp_line
			(start 0.12065 -0.2794)
			(end 0.12065 -0.3048)
			(stroke
				(width 0.1)
				(type default)
			)
			(layer "F.Fab")
		)
		(fp_line
			(start 0.12065 -0.3048)
			(end 0.67945 -0.3048)
			(stroke
				(width 0.1)
				(type default)
			)
			(layer "F.Fab")
		)
		(fp_line
			(start 0.120396 0.3048)
			(end 0.120396 0.2794)
			(stroke
				(width 0.1)
				(type default)
			)
			(layer "F.Fab")
		)
		(fp_line
			(start 0.120396 0.2794)
			(end -0.12065 0.2794)
			(stroke
				(width 0.1)
				(type default)
			)
			(layer "F.Fab")
		)
		(fp_line
			(start -0.12065 0.3048)
			(end -0.67945 0.3048)
			(stroke
				(width 0.1)
				(type default)
			)
			(layer "F.Fab")
		)
		(fp_line
			(start -0.12065 0.2794)
			(end -0.12065 0.3048)
			(stroke
				(width 0.1)
				(type default)
			)
			(layer "F.Fab")
		)
		(fp_line
			(start -0.12065 -0.2794)
			(end 0.12065 -0.2794)
			(stroke
				(width 0.1)
				(type default)
			)
			(layer "F.Fab")
		)
		(fp_line
			(start -0.12065 -0.305054)
			(end -0.12065 -0.2794)
			(stroke
				(width 0.1)
				(type default)
			)
			(layer "F.Fab")
		)
		(fp_line
			(start -0.67945 0.3048)
			(end -0.67945 -0.305054)
			(stroke
				(width 0.1)
				(type default)
			)
			(layer "F.Fab")
		)
		(fp_line
			(start -0.67945 -0.305054)
			(end -0.12065 -0.305054)
			(stroke
				(width 0.1)
				(type default)
			)
			(layer "F.Fab")
		)
		(pad "1" smd circle
			(at -0.40005 0 180)
			(size 0 0)
			(layers "F.Cu" "F.Mask" "F.Paste")
			(net "OCP_V3_1_P3V3_R3_PWRGD")
		)
		(pad "2" smd circle
			(at 0.40005 0 180)
			(size 0 0)
			(layers "F.Cu" "F.Mask" "F.Paste")
			(net "HP_LVC3_OCP_V3_1_PWRGD_R1")
		)
	)
	(footprint ""
		(layer "F.Cu")
		(at 345.941904 -156.487622 90)
		(property "Reference" "PC161"
			(at 0 0 90)
			(layer "F.SilkS")
			(hide yes)
			(effects
				(font
					(size 1.27 1.27)
				)
			)
		)
		(property "Value" ""
			(at 0 0 90)
			(layer "F.Fab")
			(effects
				(font
					(size 1.27 1.27)
				)
			)
		)
		(duplicate_pad_numbers_are_jumpers no)
		(fp_line
			(start 0.7874 -0.4064)
			(end 0.7874 0.4064)
			(stroke
				(width 0.1524)
				(type default)
			)
			(layer "F.SilkS")
		)
		(fp_line
			(start -0.7874 -0.4064)
			(end 0.7874 -0.4064)
			(stroke
				(width 0.1524)
				(type default)
			)
			(layer "F.SilkS")
		)
		(fp_line
			(start 0.7874 0.4064)
			(end -0.7874 0.4064)
			(stroke
				(width 0.1524)
				(type default)
			)
			(layer "F.SilkS")
		)
		(fp_line
			(start -0.7874 0.4064)
			(end -0.7874 -0.4064)
			(stroke
				(width 0.1524)
				(type default)
			)
			(layer "F.SilkS")
		)
		(fp_line
			(start -0.12065 -0.305054)
			(end -0.12065 -0.2794)
			(stroke
				(width 0.1)
				(type default)
			)
			(layer "F.Fab")
		)
		(fp_line
			(start -0.67945 -0.305054)
			(end -0.12065 -0.305054)
			(stroke
				(width 0.1)
				(type default)
			)
			(layer "F.Fab")
		)
		(fp_line
			(start 0.67945 -0.3048)
			(end 0.67945 0.3048)
			(stroke
				(width 0.1)
				(type default)
			)
			(layer "F.Fab")
		)
		(fp_line
			(start 0.12065 -0.3048)
			(end 0.67945 -0.3048)
			(stroke
				(width 0.1)
				(type default)
			)
			(layer "F.Fab")
		)
		(fp_line
			(start 0.12065 -0.2794)
			(end 0.12065 -0.3048)
			(stroke
				(width 0.1)
				(type default)
			)
			(layer "F.Fab")
		)
		(fp_line
			(start -0.12065 -0.2794)
			(end 0.12065 -0.2794)
			(stroke
				(width 0.1)
				(type default)
			)
			(layer "F.Fab")
		)
		(fp_line
			(start 0.120396 0.2794)
			(end -0.12065 0.2794)
			(stroke
				(width 0.1)
				(type default)
			)
			(layer "F.Fab")
		)
		(fp_line
			(start -0.12065 0.2794)
			(end -0.12065 0.3048)
			(stroke
				(width 0.1)
				(type default)
			)
			(layer "F.Fab")
		)
		(fp_line
			(start 0.67945 0.3048)
			(end 0.120396 0.3048)
			(stroke
				(width 0.1)
				(type default)
			)
			(layer "F.Fab")
		)
		(fp_line
			(start 0.120396 0.3048)
			(end 0.120396 0.2794)
			(stroke
				(width 0.1)
				(type default)
			)
			(layer "F.Fab")
		)
		(fp_line
			(start -0.12065 0.3048)
			(end -0.67945 0.3048)
			(stroke
				(width 0.1)
				(type default)
			)
			(layer "F.Fab")
		)
		(fp_line
			(start -0.67945 0.3048)
			(end -0.67945 -0.305054)
			(stroke
				(width 0.1)
				(type default)
			)
			(layer "F.Fab")
		)
		(pad "1" smd circle
			(at -0.40005 0 90)
			(size 0 0)
			(layers "F.Cu" "F.Mask" "F.Paste")
			(net "SW_PVDDCR_CPU0_P0_BOOT6_RC")
		)
		(pad "2" smd circle
			(at 0.40005 0 90)
			(size 0 0)
			(layers "F.Cu" "F.Mask" "F.Paste")
			(net "SW_PVDDCR_CPU0_P0_PH6")
		)
	)
	(footprint ""
		(layer "F.Cu")
		(at 319.905888 -22.571456 -90)
		(property "Reference" "R131"
			(at 0 0 270)
			(layer "F.SilkS")
			(hide yes)
			(effects
				(font
					(size 1.27 1.27)
				)
			)
		)
		(property "Value" ""
			(at 0 0 270)
			(layer "F.Fab")
			(effects
				(font
					(size 1.27 1.27)
				)
			)
		)
		(duplicate_pad_numbers_are_jumpers no)
		(fp_line
			(start -0.7874 0.4064)
			(end -0.7874 -0.4064)
			(stroke
				(width 0.1524)
				(type default)
			)
			(layer "F.SilkS")
		)
		(fp_line
			(start 0.7874 0.4064)
			(end -0.7874 0.4064)
			(stroke
				(width 0.1524)
				(type default)
			)
			(layer "F.SilkS")
		)
		(fp_line
			(start -0.7874 -0.4064)
			(end 0.7874 -0.4064)
			(stroke
				(width 0.1524)
				(type default)
			)
			(layer "F.SilkS")
		)
		(fp_line
			(start 0.7874 -0.4064)
			(end 0.7874 0.4064)
			(stroke
				(width 0.1524)
				(type default)
			)
			(layer "F.SilkS")
		)
		(fp_line
			(start -0.67945 0.3048)
			(end -0.67945 -0.305054)
			(stroke
				(width 0.1)
				(type default)
			)
			(layer "F.Fab")
		)
		(fp_line
			(start -0.12065 0.3048)
			(end -0.67945 0.3048)
			(stroke
				(width 0.1)
				(type default)
			)
			(layer "F.Fab")
		)
		(fp_line
			(start 0.120396 0.3048)
			(end 0.120396 0.2794)
			(stroke
				(width 0.1)
				(type default)
			)
			(layer "F.Fab")
		)
		(fp_line
			(start 0.67945 0.3048)
			(end 0.120396 0.3048)
			(stroke
				(width 0.1)
				(type default)
			)
			(layer "F.Fab")
		)
		(fp_line
			(start -0.12065 0.2794)
			(end -0.12065 0.3048)
			(stroke
				(width 0.1)
				(type default)
			)
			(layer "F.Fab")
		)
		(fp_line
			(start 0.120396 0.2794)
			(end -0.12065 0.2794)
			(stroke
				(width 0.1)
				(type default)
			)
			(layer "F.Fab")
		)
		(fp_line
			(start -0.12065 -0.2794)
			(end 0.12065 -0.2794)
			(stroke
				(width 0.1)
				(type default)
			)
			(layer "F.Fab")
		)
		(fp_line
			(start 0.12065 -0.2794)
			(end 0.12065 -0.3048)
			(stroke
				(width 0.1)
				(type default)
			)
			(layer "F.Fab")
		)
		(fp_line
			(start 0.12065 -0.3048)
			(end 0.67945 -0.3048)
			(stroke
				(width 0.1)
				(type default)
			)
			(layer "F.Fab")
		)
		(fp_line
			(start 0.67945 -0.3048)
			(end 0.67945 0.3048)
			(stroke
				(width 0.1)
				(type default)
			)
			(layer "F.Fab")
		)
		(fp_line
			(start -0.67945 -0.305054)
			(end -0.12065 -0.305054)
			(stroke
				(width 0.1)
				(type default)
			)
			(layer "F.Fab")
		)
		(fp_line
			(start -0.12065 -0.305054)
			(end -0.12065 -0.2794)
			(stroke
				(width 0.1)
				(type default)
			)
			(layer "F.Fab")
		)
		(pad "1" smd circle
			(at -0.40005 0 270)
			(size 0 0)
			(layers "F.Cu" "F.Mask" "F.Paste")
			(net "P3V3_AUX")
		)
		(pad "2" smd circle
			(at 0.40005 0 270)
			(size 0 0)
			(layers "F.Cu" "F.Mask" "F.Paste")
			(net "UART_VCC_J8")
		)
	)
	(footprint ""
		(layer "F.Cu")
		(at 110.565946 -54.882034 -90)
		(property "Reference" "R6308"
			(at 0 0 270)
			(layer "F.SilkS")
			(hide yes)
			(effects
				(font
					(size 1.27 1.27)
				)
			)
		)
		(property "Value" ""
			(at 0 0 270)
			(layer "F.Fab")
			(effects
				(font
					(size 1.27 1.27)
				)
			)
		)
		(duplicate_pad_numbers_are_jumpers no)
		(fp_line
			(start -0.7874 0.4064)
			(end -0.7874 -0.4064)
			(stroke
				(width 0.1524)
				(type default)
			)
			(layer "F.SilkS")
		)
		(fp_line
			(start 0.7874 0.4064)
			(end -0.7874 0.4064)
			(stroke
				(width 0.1524)
				(type default)
			)
			(layer "F.SilkS")
		)
		(fp_line
			(start -0.7874 -0.4064)
			(end 0.7874 -0.4064)
			(stroke
				(width 0.1524)
				(type default)
			)
			(layer "F.SilkS")
		)
		(fp_line
			(start 0.7874 -0.4064)
			(end 0.7874 0.4064)
			(stroke
				(width 0.1524)
				(type default)
			)
			(layer "F.SilkS")
		)
		(fp_line
			(start -0.67945 0.3048)
			(end -0.67945 -0.305054)
			(stroke
				(width 0.1)
				(type default)
			)
			(layer "F.Fab")
		)
		(fp_line
			(start -0.12065 0.3048)
			(end -0.67945 0.3048)
			(stroke
				(width 0.1)
				(type default)
			)
			(layer "F.Fab")
		)
		(fp_line
			(start 0.120396 0.3048)
			(end 0.120396 0.2794)
			(stroke
				(width 0.1)
				(type default)
			)
			(layer "F.Fab")
		)
		(fp_line
			(start 0.67945 0.3048)
			(end 0.120396 0.3048)
			(stroke
				(width 0.1)
				(type default)
			)
			(layer "F.Fab")
		)
		(fp_line
			(start -0.12065 0.2794)
			(end -0.12065 0.3048)
			(stroke
				(width 0.1)
				(type default)
			)
			(layer "F.Fab")
		)
		(fp_line
			(start 0.120396 0.2794)
			(end -0.12065 0.2794)
			(stroke
				(width 0.1)
				(type default)
			)
			(layer "F.Fab")
		)
		(fp_line
			(start -0.12065 -0.2794)
			(end 0.12065 -0.2794)
			(stroke
				(width 0.1)
				(type default)
			)
			(layer "F.Fab")
		)
		(fp_line
			(start 0.12065 -0.2794)
			(end 0.12065 -0.3048)
			(stroke
				(width 0.1)
				(type default)
			)
			(layer "F.Fab")
		)
		(fp_line
			(start 0.12065 -0.3048)
			(end 0.67945 -0.3048)
			(stroke
				(width 0.1)
				(type default)
			)
			(layer "F.Fab")
		)
		(fp_line
			(start 0.67945 -0.3048)
			(end 0.67945 0.3048)
			(stroke
				(width 0.1)
				(type default)
			)
			(layer "F.Fab")
		)
		(fp_line
			(start -0.67945 -0.305054)
			(end -0.12065 -0.305054)
			(stroke
				(width 0.1)
				(type default)
			)
			(layer "F.Fab")
		)
		(fp_line
			(start -0.12065 -0.305054)
			(end -0.12065 -0.2794)
			(stroke
				(width 0.1)
				(type default)
			)
			(layer "F.Fab")
		)
		(pad "1" smd circle
			(at -0.40005 0 270)
			(size 0 0)
			(layers "F.Cu" "F.Mask" "F.Paste")
			(net "P3V3_AUX")
		)
		(pad "2" smd circle
			(at 0.40005 0 270)
			(size 0 0)
			(layers "F.Cu" "F.Mask" "F.Paste")
			(net "USB_HUB2_MRP_CFG_NON_REM")
		)
	)
	(footprint ""
		(layer "F.Cu")
		(at 427.739048 -423.606214 -90)
		(property "Reference" "R6254"
			(at 0 0 270)
			(layer "F.SilkS")
			(hide yes)
			(effects
				(font
					(size 1.27 1.27)
				)
			)
		)
		(property "Value" ""
			(at 0 0 270)
			(layer "F.Fab")
			(effects
				(font
					(size 1.27 1.27)
				)
			)
		)
		(duplicate_pad_numbers_are_jumpers no)
		(fp_line
			(start -0.7874 0.4064)
			(end -0.7874 -0.4064)
			(stroke
				(width 0.1524)
				(type default)
			)
			(layer "F.SilkS")
		)
		(fp_line
			(start 0.7874 0.4064)
			(end -0.7874 0.4064)
			(stroke
				(width 0.1524)
				(type default)
			)
			(layer "F.SilkS")
		)
		(fp_line
			(start -0.7874 -0.4064)
			(end 0.7874 -0.4064)
			(stroke
				(width 0.1524)
				(type default)
			)
			(layer "F.SilkS")
		)
		(fp_line
			(start 0.7874 -0.4064)
			(end 0.7874 0.4064)
			(stroke
				(width 0.1524)
				(type default)
			)
			(layer "F.SilkS")
		)
		(fp_line
			(start -0.67945 0.3048)
			(end -0.67945 -0.305054)
			(stroke
				(width 0.1)
				(type default)
			)
			(layer "F.Fab")
		)
		(fp_line
			(start -0.12065 0.3048)
			(end -0.67945 0.3048)
			(stroke
				(width 0.1)
				(type default)
			)
			(layer "F.Fab")
		)
		(fp_line
			(start 0.120396 0.3048)
			(end 0.120396 0.2794)
			(stroke
				(width 0.1)
				(type default)
			)
			(layer "F.Fab")
		)
		(fp_line
			(start 0.67945 0.3048)
			(end 0.120396 0.3048)
			(stroke
				(width 0.1)
				(type default)
			)
			(layer "F.Fab")
		)
		(fp_line
			(start -0.12065 0.2794)
			(end -0.12065 0.3048)
			(stroke
				(width 0.1)
				(type default)
			)
			(layer "F.Fab")
		)
		(fp_line
			(start 0.120396 0.2794)
			(end -0.12065 0.2794)
			(stroke
				(width 0.1)
				(type default)
			)
			(layer "F.Fab")
		)
		(fp_line
			(start -0.12065 -0.2794)
			(end 0.12065 -0.2794)
			(stroke
				(width 0.1)
				(type default)
			)
			(layer "F.Fab")
		)
		(fp_line
			(start 0.12065 -0.2794)
			(end 0.12065 -0.3048)
			(stroke
				(width 0.1)
				(type default)
			)
			(layer "F.Fab")
		)
		(fp_line
			(start 0.12065 -0.3048)
			(end 0.67945 -0.3048)
			(stroke
				(width 0.1)
				(type default)
			)
			(layer "F.Fab")
		)
		(fp_line
			(start 0.67945 -0.3048)
			(end 0.67945 0.3048)
			(stroke
				(width 0.1)
				(type default)
			)
			(layer "F.Fab")
		)
		(fp_line
			(start -0.67945 -0.305054)
			(end -0.12065 -0.305054)
			(stroke
				(width 0.1)
				(type default)
			)
			(layer "F.Fab")
		)
		(fp_line
			(start -0.12065 -0.305054)
			(end -0.12065 -0.2794)
			(stroke
				(width 0.1)
				(type default)
			)
			(layer "F.Fab")
		)
		(pad "1" smd circle
			(at -0.40005 0 270)
			(size 0 0)
			(layers "F.Cu" "F.Mask" "F.Paste")
			(net "HSC_TYPE_ADC_A0")
		)
		(pad "2" smd circle
			(at 0.40005 0 270)
			(size 0 0)
			(layers "F.Cu" "F.Mask" "F.Paste")
			(net "SMB_HSC_TYPE_ADC_SDA")
		)
	)
	(footprint ""
		(layer "F.Cu")
		(at 412.487364 -143.967962 180)
		(property "Reference" "PC1846"
			(at 0 0 180)
			(layer "F.SilkS")
			(hide yes)
			(effects
				(font
					(size 1.27 1.27)
				)
			)
		)
		(property "Value" ""
			(at 0 0 180)
			(layer "F.Fab")
			(effects
				(font
					(size 1.27 1.27)
				)
			)
		)
		(duplicate_pad_numbers_are_jumpers no)
		(fp_line
			(start 0.7874 0.4064)
			(end -0.7874 0.4064)
			(stroke
				(width 0.1524)
				(type default)
			)
			(layer "F.SilkS")
		)
		(fp_line
			(start 0.7874 -0.4064)
			(end 0.7874 0.4064)
			(stroke
				(width 0.1524)
				(type default)
			)
			(layer "F.SilkS")
		)
		(fp_line
			(start -0.7874 0.4064)
			(end -0.7874 -0.4064)
			(stroke
				(width 0.1524)
				(type default)
			)
			(layer "F.SilkS")
		)
		(fp_line
			(start -0.7874 -0.4064)
			(end 0.7874 -0.4064)
			(stroke
				(width 0.1524)
				(type default)
			)
			(layer "F.SilkS")
		)
		(fp_line
			(start 0.67945 0.3048)
			(end 0.120396 0.3048)
			(stroke
				(width 0.1)
				(type default)
			)
			(layer "F.Fab")
		)
		(fp_line
			(start 0.67945 -0.3048)
			(end 0.67945 0.3048)
			(stroke
				(width 0.1)
				(type default)
			)
			(layer "F.Fab")
		)
		(fp_line
			(start 0.12065 -0.2794)
			(end 0.12065 -0.3048)
			(stroke
				(width 0.1)
				(type default)
			)
			(layer "F.Fab")
		)
		(fp_line
			(start 0.12065 -0.3048)
			(end 0.67945 -0.3048)
			(stroke
				(width 0.1)
				(type default)
			)
			(layer "F.Fab")
		)
		(fp_line
			(start 0.120396 0.3048)
			(end 0.120396 0.2794)
			(stroke
				(width 0.1)
				(type default)
			)
			(layer "F.Fab")
		)
		(fp_line
			(start 0.120396 0.2794)
			(end -0.12065 0.2794)
			(stroke
				(width 0.1)
				(type default)
			)
			(layer "F.Fab")
		)
		(fp_line
			(start -0.12065 0.3048)
			(end -0.67945 0.3048)
			(stroke
				(width 0.1)
				(type default)
			)
			(layer "F.Fab")
		)
		(fp_line
			(start -0.12065 0.2794)
			(end -0.12065 0.3048)
			(stroke
				(width 0.1)
				(type default)
			)
			(layer "F.Fab")
		)
		(fp_line
			(start -0.12065 -0.2794)
			(end 0.12065 -0.2794)
			(stroke
				(width 0.1)
				(type default)
			)
			(layer "F.Fab")
		)
		(fp_line
			(start -0.12065 -0.305054)
			(end -0.12065 -0.2794)
			(stroke
				(width 0.1)
				(type default)
			)
			(layer "F.Fab")
		)
		(fp_line
			(start -0.67945 0.3048)
			(end -0.67945 -0.305054)
			(stroke
				(width 0.1)
				(type default)
			)
			(layer "F.Fab")
		)
		(fp_line
			(start -0.67945 -0.305054)
			(end -0.12065 -0.305054)
			(stroke
				(width 0.1)
				(type default)
			)
			(layer "F.Fab")
		)
		(pad "1" smd circle
			(at -0.40005 0 180)
			(size 0 0)
			(layers "F.Cu" "F.Mask" "F.Paste")
			(net "SW_P5V_AUX_FLT")
		)
		(pad "2" smd circle
			(at 0.40005 0 180)
			(size 0 0)
			(layers "F.Cu" "F.Mask" "F.Paste")
			(net "GND")
		)
	)
	(footprint ""
		(layer "F.Cu")
		(at 223.774 -80.137 -90)
		(property "Reference" "U8003"
			(at 1.93294 -2.871978 90)
			(unlocked yes)
			(layer "F.SilkS")
			(effects
				(font
					(size 0.7874 0.5842)
					(thickness 0.1524)
				)
				(justify left)
			)
		)
		(property "Value" ""
			(at 0 0 270)
			(layer "F.Fab")
			(effects
				(font
					(size 1.27 1.27)
				)
			)
		)
		(duplicate_pad_numbers_are_jumpers no)
		(fp_line
			(start -1.759712 1.500124)
			(end -1.759712 -1.500124)
			(stroke
				(width 0.1524)
				(type default)
			)
			(layer "F.SilkS")
		)
		(fp_line
			(start 1.759712 1.500124)
			(end -1.759712 1.500124)
			(stroke
				(width 0.1524)
				(type default)
			)
			(layer "F.SilkS")
		)
		(fp_line
			(start -1.759712 -1.500124)
			(end 1.759712 -1.500124)
			(stroke
				(width 0.1524)
				(type default)
			)
			(layer "F.SilkS")
		)
		(fp_line
			(start 1.759712 -1.500124)
			(end 1.759712 1.500124)
			(stroke
				(width 0.1524)
				(type default)
			)
			(layer "F.SilkS")
		)
		(fp_line
			(start -0.700024 1.500124)
			(end -0.700024 -1.500124)
			(stroke
				(width 0.1)
				(type default)
			)
			(layer "F.Fab")
		)
		(fp_line
			(start 0.700024 1.500124)
			(end -0.700024 1.500124)
			(stroke
				(width 0.1)
				(type default)
			)
			(layer "F.Fab")
		)
		(fp_line
			(start -0.700024 -1.500124)
			(end 0.700024 -1.500124)
			(stroke
				(width 0.1)
				(type default)
			)
			(layer "F.Fab")
		)
		(fp_line
			(start 0.700024 -1.500124)
			(end 0.700024 1.500124)
			(stroke
				(width 0.1)
				(type default)
			)
			(layer "F.Fab")
		)
		(pad "1" smd rect
			(at -1.150112 -0.94996 180)
			(size 0.6604 0.9652)
			(layers "F.Cu" "F.Mask" "F.Paste")
			(net "GND")
		)
		(pad "2" smd rect
			(at -1.150112 0.94996 180)
			(size 0.6604 0.9652)
			(layers "F.Cu" "F.Mask" "F.Paste")
			(net "P3V3_E1S_PWRGD_0_R1")
		)
		(pad "3" smd rect
			(at 1.150112 0 180)
			(size 0.6604 0.9652)
			(layers "F.Cu" "F.Mask" "F.Paste")
			(net "P3V3_E1S_0_R")
		)
	)
	(footprint ""
		(layer "F.Cu")
		(at 328.487278 -339.63991 -90)
		(property "Reference" "PC94"
			(at 0 0 270)
			(layer "F.SilkS")
			(hide yes)
			(effects
				(font
					(size 1.27 1.27)
				)
			)
		)
		(property "Value" ""
			(at 0 0 270)
			(layer "F.Fab")
			(effects
				(font
					(size 1.27 1.27)
				)
			)
		)
		(duplicate_pad_numbers_are_jumpers no)
		(fp_line
			(start -0.7874 0.4064)
			(end -0.7874 -0.4064)
			(stroke
				(width 0.1524)
				(type default)
			)
			(layer "F.SilkS")
		)
		(fp_line
			(start 0.7874 0.4064)
			(end -0.7874 0.4064)
			(stroke
				(width 0.1524)
				(type default)
			)
			(layer "F.SilkS")
		)
		(fp_line
			(start -0.7874 -0.4064)
			(end 0.7874 -0.4064)
			(stroke
				(width 0.1524)
				(type default)
			)
			(layer "F.SilkS")
		)
		(fp_line
			(start 0.7874 -0.4064)
			(end 0.7874 0.4064)
			(stroke
				(width 0.1524)
				(type default)
			)
			(layer "F.SilkS")
		)
		(fp_line
			(start -0.67945 0.3048)
			(end -0.67945 -0.305054)
			(stroke
				(width 0.1)
				(type default)
			)
			(layer "F.Fab")
		)
		(fp_line
			(start -0.12065 0.3048)
			(end -0.67945 0.3048)
			(stroke
				(width 0.1)
				(type default)
			)
			(layer "F.Fab")
		)
		(fp_line
			(start 0.120396 0.3048)
			(end 0.120396 0.2794)
			(stroke
				(width 0.1)
				(type default)
			)
			(layer "F.Fab")
		)
		(fp_line
			(start 0.67945 0.3048)
			(end 0.120396 0.3048)
			(stroke
				(width 0.1)
				(type default)
			)
			(layer "F.Fab")
		)
		(fp_line
			(start -0.12065 0.2794)
			(end -0.12065 0.3048)
			(stroke
				(width 0.1)
				(type default)
			)
			(layer "F.Fab")
		)
		(fp_line
			(start 0.120396 0.2794)
			(end -0.12065 0.2794)
			(stroke
				(width 0.1)
				(type default)
			)
			(layer "F.Fab")
		)
		(fp_line
			(start -0.12065 -0.2794)
			(end 0.12065 -0.2794)
			(stroke
				(width 0.1)
				(type default)
			)
			(layer "F.Fab")
		)
		(fp_line
			(start 0.12065 -0.2794)
			(end 0.12065 -0.3048)
			(stroke
				(width 0.1)
				(type default)
			)
			(layer "F.Fab")
		)
		(fp_line
			(start 0.12065 -0.3048)
			(end 0.67945 -0.3048)
			(stroke
				(width 0.1)
				(type default)
			)
			(layer "F.Fab")
		)
		(fp_line
			(start 0.67945 -0.3048)
			(end 0.67945 0.3048)
			(stroke
				(width 0.1)
				(type default)
			)
			(layer "F.Fab")
		)
		(fp_line
			(start -0.67945 -0.305054)
			(end -0.12065 -0.305054)
			(stroke
				(width 0.1)
				(type default)
			)
			(layer "F.Fab")
		)
		(fp_line
			(start -0.12065 -0.305054)
			(end -0.12065 -0.2794)
			(stroke
				(width 0.1)
				(type default)
			)
			(layer "F.Fab")
		)
		(pad "1" smd circle
			(at -0.40005 0 270)
			(size 0 0)
			(layers "F.Cu" "F.Mask" "F.Paste")
			(net "SW_PVDDCR_CPU1_P0_BOOT2_R")
		)
		(pad "2" smd circle
			(at 0.40005 0 270)
			(size 0 0)
			(layers "F.Cu" "F.Mask" "F.Paste")
			(net "SW_PVDDCR_CPU1_P0_BOOTR2")
		)
	)
	(footprint ""
		(layer "F.Cu")
		(at 104.409748 -386.7912 90)
		(property "Reference" "R741"
			(at 0 0 90)
			(layer "F.SilkS")
			(hide yes)
			(effects
				(font
					(size 1.27 1.27)
				)
			)
		)
		(property "Value" ""
			(at 0 0 90)
			(layer "F.Fab")
			(effects
				(font
					(size 1.27 1.27)
				)
			)
		)
		(duplicate_pad_numbers_are_jumpers no)
		(fp_line
			(start 0.32512 -0.175006)
			(end 0.32512 0.175006)
			(stroke
				(width 0.1)
				(type default)
			)
			(layer "F.Fab")
		)
		(fp_line
			(start -0.32512 -0.175006)
			(end 0.32512 -0.175006)
			(stroke
				(width 0.1)
				(type default)
			)
			(layer "F.Fab")
		)
		(fp_line
			(start 0.32512 0.175006)
			(end -0.32512 0.175006)
			(stroke
				(width 0.1)
				(type default)
			)
			(layer "F.Fab")
		)
		(fp_line
			(start -0.32512 0.175006)
			(end -0.32512 -0.175006)
			(stroke
				(width 0.1)
				(type default)
			)
			(layer "F.Fab")
		)
		(pad "1" smd rect
			(at -0.2667 0 90)
			(size 0.3048 0.381)
			(layers "F.Cu" "F.Mask" "F.Paste")
			(net "RT_CPU1_P1_ADDR3")
		)
		(pad "2" smd rect
			(at 0.2667 0 270)
			(size 0.3048 0.381)
			(layers "F.Cu" "F.Mask" "F.Paste")
			(net "GND")
		)
	)
	(footprint ""
		(layer "F.Cu")
		(at 83.439254 -334.976724 -90)
		(property "Reference" "PC371_C1P1_1"
			(at 0 0 270)
			(layer "F.SilkS")
			(hide yes)
			(effects
				(font
					(size 1.27 1.27)
				)
			)
		)
		(property "Value" ""
			(at 0 0 270)
			(layer "F.Fab")
			(effects
				(font
					(size 1.27 1.27)
				)
			)
		)
		(duplicate_pad_numbers_are_jumpers no)
		(fp_line
			(start -0.7874 0.4064)
			(end -0.7874 -0.4064)
			(stroke
				(width 0.1524)
				(type default)
			)
			(layer "F.SilkS")
		)
		(fp_line
			(start 0.7874 0.4064)
			(end -0.7874 0.4064)
			(stroke
				(width 0.1524)
				(type default)
			)
			(layer "F.SilkS")
		)
		(fp_line
			(start -0.7874 -0.4064)
			(end 0.7874 -0.4064)
			(stroke
				(width 0.1524)
				(type default)
			)
			(layer "F.SilkS")
		)
		(fp_line
			(start 0.7874 -0.4064)
			(end 0.7874 0.4064)
			(stroke
				(width 0.1524)
				(type default)
			)
			(layer "F.SilkS")
		)
		(fp_line
			(start -0.67945 0.3048)
			(end -0.67945 -0.305054)
			(stroke
				(width 0.1)
				(type default)
			)
			(layer "F.Fab")
		)
		(fp_line
			(start -0.12065 0.3048)
			(end -0.67945 0.3048)
			(stroke
				(width 0.1)
				(type default)
			)
			(layer "F.Fab")
		)
		(fp_line
			(start 0.120396 0.3048)
			(end 0.120396 0.2794)
			(stroke
				(width 0.1)
				(type default)
			)
			(layer "F.Fab")
		)
		(fp_line
			(start 0.67945 0.3048)
			(end 0.120396 0.3048)
			(stroke
				(width 0.1)
				(type default)
			)
			(layer "F.Fab")
		)
		(fp_line
			(start -0.12065 0.2794)
			(end -0.12065 0.3048)
			(stroke
				(width 0.1)
				(type default)
			)
			(layer "F.Fab")
		)
		(fp_line
			(start 0.120396 0.2794)
			(end -0.12065 0.2794)
			(stroke
				(width 0.1)
				(type default)
			)
			(layer "F.Fab")
		)
		(fp_line
			(start -0.12065 -0.2794)
			(end 0.12065 -0.2794)
			(stroke
				(width 0.1)
				(type default)
			)
			(layer "F.Fab")
		)
		(fp_line
			(start 0.12065 -0.2794)
			(end 0.12065 -0.3048)
			(stroke
				(width 0.1)
				(type default)
			)
			(layer "F.Fab")
		)
		(fp_line
			(start 0.12065 -0.3048)
			(end 0.67945 -0.3048)
			(stroke
				(width 0.1)
				(type default)
			)
			(layer "F.Fab")
		)
		(fp_line
			(start 0.67945 -0.3048)
			(end 0.67945 0.3048)
			(stroke
				(width 0.1)
				(type default)
			)
			(layer "F.Fab")
		)
		(fp_line
			(start -0.67945 -0.305054)
			(end -0.12065 -0.305054)
			(stroke
				(width 0.1)
				(type default)
			)
			(layer "F.Fab")
		)
		(fp_line
			(start -0.12065 -0.305054)
			(end -0.12065 -0.2794)
			(stroke
				(width 0.1)
				(type default)
			)
			(layer "F.Fab")
		)
		(pad "1" smd circle
			(at -0.40005 0 270)
			(size 0 0)
			(layers "F.Cu" "F.Mask" "F.Paste")
			(net "PVDDCR_CPU1_P1_PVCC")
		)
		(pad "2" smd circle
			(at 0.40005 0 270)
			(size 0 0)
			(layers "F.Cu" "F.Mask" "F.Paste")
			(net "GND")
		)
	)
	(footprint ""
		(layer "F.Cu")
		(at 392.103102 -177.88636 -90)
		(property "Reference" "PC545_4"
			(at 0 0 270)
			(layer "F.SilkS")
			(hide yes)
			(effects
				(font
					(size 1.27 1.27)
				)
			)
		)
		(property "Value" ""
			(at 0 0 270)
			(layer "F.Fab")
			(effects
				(font
					(size 1.27 1.27)
				)
			)
		)
		(duplicate_pad_numbers_are_jumpers no)
		(fp_line
			(start -0.7874 0.4064)
			(end -0.7874 -0.4064)
			(stroke
				(width 0.1524)
				(type default)
			)
			(layer "F.SilkS")
		)
		(fp_line
			(start 0.7874 0.4064)
			(end -0.7874 0.4064)
			(stroke
				(width 0.1524)
				(type default)
			)
			(layer "F.SilkS")
		)
		(fp_line
			(start -0.7874 -0.4064)
			(end 0.7874 -0.4064)
			(stroke
				(width 0.1524)
				(type default)
			)
			(layer "F.SilkS")
		)
		(fp_line
			(start 0.7874 -0.4064)
			(end 0.7874 0.4064)
			(stroke
				(width 0.1524)
				(type default)
			)
			(layer "F.SilkS")
		)
		(fp_line
			(start -0.67945 0.3048)
			(end -0.67945 -0.305054)
			(stroke
				(width 0.1)
				(type default)
			)
			(layer "F.Fab")
		)
		(fp_line
			(start -0.12065 0.3048)
			(end -0.67945 0.3048)
			(stroke
				(width 0.1)
				(type default)
			)
			(layer "F.Fab")
		)
		(fp_line
			(start 0.120396 0.3048)
			(end 0.120396 0.2794)
			(stroke
				(width 0.1)
				(type default)
			)
			(layer "F.Fab")
		)
		(fp_line
			(start 0.67945 0.3048)
			(end 0.120396 0.3048)
			(stroke
				(width 0.1)
				(type default)
			)
			(layer "F.Fab")
		)
		(fp_line
			(start -0.12065 0.2794)
			(end -0.12065 0.3048)
			(stroke
				(width 0.1)
				(type default)
			)
			(layer "F.Fab")
		)
		(fp_line
			(start 0.120396 0.2794)
			(end -0.12065 0.2794)
			(stroke
				(width 0.1)
				(type default)
			)
			(layer "F.Fab")
		)
		(fp_line
			(start -0.12065 -0.2794)
			(end 0.12065 -0.2794)
			(stroke
				(width 0.1)
				(type default)
			)
			(layer "F.Fab")
		)
		(fp_line
			(start 0.12065 -0.2794)
			(end 0.12065 -0.3048)
			(stroke
				(width 0.1)
				(type default)
			)
			(layer "F.Fab")
		)
		(fp_line
			(start 0.12065 -0.3048)
			(end 0.67945 -0.3048)
			(stroke
				(width 0.1)
				(type default)
			)
			(layer "F.Fab")
		)
		(fp_line
			(start 0.67945 -0.3048)
			(end 0.67945 0.3048)
			(stroke
				(width 0.1)
				(type default)
			)
			(layer "F.Fab")
		)
		(fp_line
			(start -0.67945 -0.305054)
			(end -0.12065 -0.305054)
			(stroke
				(width 0.1)
				(type default)
			)
			(layer "F.Fab")
		)
		(fp_line
			(start -0.12065 -0.305054)
			(end -0.12065 -0.2794)
			(stroke
				(width 0.1)
				(type default)
			)
			(layer "F.Fab")
		)
		(pad "1" smd circle
			(at -0.40005 0 270)
			(size 0 0)
			(layers "F.Cu" "F.Mask" "F.Paste")
			(net "PVDDCR_CPU0_P0_VCCS")
		)
		(pad "2" smd circle
			(at 0.40005 0 270)
			(size 0 0)
			(layers "F.Cu" "F.Mask" "F.Paste")
			(net "GND")
		)
	)
	(footprint ""
		(layer "F.Cu")
		(at 331.494892 -385.23926 180)
		(property "Reference" "C962"
			(at 0 0 180)
			(layer "F.SilkS")
			(hide yes)
			(effects
				(font
					(size 1.27 1.27)
				)
			)
		)
		(property "Value" ""
			(at 0 0 180)
			(layer "F.Fab")
			(effects
				(font
					(size 1.27 1.27)
				)
			)
		)
		(duplicate_pad_numbers_are_jumpers no)
		(fp_line
			(start 0.299974 0.150114)
			(end -0.299974 0.150114)
			(stroke
				(width 0.1)
				(type default)
			)
			(layer "F.Fab")
		)
		(fp_line
			(start 0.299974 -0.150114)
			(end 0.299974 0.150114)
			(stroke
				(width 0.1)
				(type default)
			)
			(layer "F.Fab")
		)
		(fp_line
			(start -0.299974 0.150114)
			(end -0.299974 -0.150114)
			(stroke
				(width 0.1)
				(type default)
			)
			(layer "F.Fab")
		)
		(fp_line
			(start -0.299974 -0.150114)
			(end 0.299974 -0.150114)
			(stroke
				(width 0.1)
				(type default)
			)
			(layer "F.Fab")
		)
		(pad "1" smd rect
			(at -0.2667 0 180)
			(size 0.3048 0.381)
			(layers "F.Cu" "F.Mask" "F.Paste")
			(net "P5E_CPU0_P1_TX_C_DN<1>")
		)
		(pad "2" smd rect
			(at 0.2667 0 180)
			(size 0.3048 0.381)
			(layers "F.Cu" "F.Mask" "F.Paste")
			(net "P5E_CPU0_P1_TX_DN<1>")
		)
	)
	(footprint ""
		(layer "F.Cu")
		(at 315.771022 -33.715706 180)
		(property "Reference" "C2176"
			(at 0 0 180)
			(layer "F.SilkS")
			(hide yes)
			(effects
				(font
					(size 1.27 1.27)
				)
			)
		)
		(property "Value" ""
			(at 0 0 180)
			(layer "F.Fab")
			(effects
				(font
					(size 1.27 1.27)
				)
			)
		)
		(duplicate_pad_numbers_are_jumpers no)
		(fp_line
			(start 0.7874 0.4064)
			(end -0.7874 0.4064)
			(stroke
				(width 0.1524)
				(type default)
			)
			(layer "F.SilkS")
		)
		(fp_line
			(start 0.7874 -0.4064)
			(end 0.7874 0.4064)
			(stroke
				(width 0.1524)
				(type default)
			)
			(layer "F.SilkS")
		)
		(fp_line
			(start -0.7874 0.4064)
			(end -0.7874 -0.4064)
			(stroke
				(width 0.1524)
				(type default)
			)
			(layer "F.SilkS")
		)
		(fp_line
			(start -0.7874 -0.4064)
			(end 0.7874 -0.4064)
			(stroke
				(width 0.1524)
				(type default)
			)
			(layer "F.SilkS")
		)
		(fp_line
			(start 0.67945 0.3048)
			(end 0.120396 0.3048)
			(stroke
				(width 0.1)
				(type default)
			)
			(layer "F.Fab")
		)
		(fp_line
			(start 0.67945 -0.3048)
			(end 0.67945 0.3048)
			(stroke
				(width 0.1)
				(type default)
			)
			(layer "F.Fab")
		)
		(fp_line
			(start 0.12065 -0.2794)
			(end 0.12065 -0.3048)
			(stroke
				(width 0.1)
				(type default)
			)
			(layer "F.Fab")
		)
		(fp_line
			(start 0.12065 -0.3048)
			(end 0.67945 -0.3048)
			(stroke
				(width 0.1)
				(type default)
			)
			(layer "F.Fab")
		)
		(fp_line
			(start 0.120396 0.3048)
			(end 0.120396 0.2794)
			(stroke
				(width 0.1)
				(type default)
			)
			(layer "F.Fab")
		)
		(fp_line
			(start 0.120396 0.2794)
			(end -0.12065 0.2794)
			(stroke
				(width 0.1)
				(type default)
			)
			(layer "F.Fab")
		)
		(fp_line
			(start -0.12065 0.3048)
			(end -0.67945 0.3048)
			(stroke
				(width 0.1)
				(type default)
			)
			(layer "F.Fab")
		)
		(fp_line
			(start -0.12065 0.2794)
			(end -0.12065 0.3048)
			(stroke
				(width 0.1)
				(type default)
			)
			(layer "F.Fab")
		)
		(fp_line
			(start -0.12065 -0.2794)
			(end 0.12065 -0.2794)
			(stroke
				(width 0.1)
				(type default)
			)
			(layer "F.Fab")
		)
		(fp_line
			(start -0.12065 -0.305054)
			(end -0.12065 -0.2794)
			(stroke
				(width 0.1)
				(type default)
			)
			(layer "F.Fab")
		)
		(fp_line
			(start -0.67945 0.3048)
			(end -0.67945 -0.305054)
			(stroke
				(width 0.1)
				(type default)
			)
			(layer "F.Fab")
		)
		(fp_line
			(start -0.67945 -0.305054)
			(end -0.12065 -0.305054)
			(stroke
				(width 0.1)
				(type default)
			)
			(layer "F.Fab")
		)
		(pad "1" smd circle
			(at -0.40005 0 180)
			(size 0 0)
			(layers "F.Cu" "F.Mask" "F.Paste")
			(net "P12V_OCP_SFF_ISENSE_MAM")
		)
		(pad "2" smd circle
			(at 0.40005 0 180)
			(size 0 0)
			(layers "F.Cu" "F.Mask" "F.Paste")
			(net "GND")
		)
	)
	(footprint ""
		(layer "F.Cu")
		(at 403.904958 -324.862952 180)
		(property "Reference" "R743"
			(at 0 0 180)
			(layer "F.SilkS")
			(hide yes)
			(effects
				(font
					(size 1.27 1.27)
				)
			)
		)
		(property "Value" ""
			(at 0 0 180)
			(layer "F.Fab")
			(effects
				(font
					(size 1.27 1.27)
				)
			)
		)
		(duplicate_pad_numbers_are_jumpers no)
		(fp_line
			(start 0.7874 0.4064)
			(end -0.7874 0.4064)
			(stroke
				(width 0.1524)
				(type default)
			)
			(layer "F.SilkS")
		)
		(fp_line
			(start 0.7874 -0.4064)
			(end 0.7874 0.4064)
			(stroke
				(width 0.1524)
				(type default)
			)
			(layer "F.SilkS")
		)
		(fp_line
			(start -0.7874 0.4064)
			(end -0.7874 -0.4064)
			(stroke
				(width 0.1524)
				(type default)
			)
			(layer "F.SilkS")
		)
		(fp_line
			(start -0.7874 -0.4064)
			(end 0.7874 -0.4064)
			(stroke
				(width 0.1524)
				(type default)
			)
			(layer "F.SilkS")
		)
		(fp_line
			(start 0.67945 0.3048)
			(end 0.120396 0.3048)
			(stroke
				(width 0.1)
				(type default)
			)
			(layer "F.Fab")
		)
		(fp_line
			(start 0.67945 -0.3048)
			(end 0.67945 0.3048)
			(stroke
				(width 0.1)
				(type default)
			)
			(layer "F.Fab")
		)
		(fp_line
			(start 0.12065 -0.2794)
			(end 0.12065 -0.3048)
			(stroke
				(width 0.1)
				(type default)
			)
			(layer "F.Fab")
		)
		(fp_line
			(start 0.12065 -0.3048)
			(end 0.67945 -0.3048)
			(stroke
				(width 0.1)
				(type default)
			)
			(layer "F.Fab")
		)
		(fp_line
			(start 0.120396 0.3048)
			(end 0.120396 0.2794)
			(stroke
				(width 0.1)
				(type default)
			)
			(layer "F.Fab")
		)
		(fp_line
			(start 0.120396 0.2794)
			(end -0.12065 0.2794)
			(stroke
				(width 0.1)
				(type default)
			)
			(layer "F.Fab")
		)
		(fp_line
			(start -0.12065 0.3048)
			(end -0.67945 0.3048)
			(stroke
				(width 0.1)
				(type default)
			)
			(layer "F.Fab")
		)
		(fp_line
			(start -0.12065 0.2794)
			(end -0.12065 0.3048)
			(stroke
				(width 0.1)
				(type default)
			)
			(layer "F.Fab")
		)
		(fp_line
			(start -0.12065 -0.2794)
			(end 0.12065 -0.2794)
			(stroke
				(width 0.1)
				(type default)
			)
			(layer "F.Fab")
		)
		(fp_line
			(start -0.12065 -0.305054)
			(end -0.12065 -0.2794)
			(stroke
				(width 0.1)
				(type default)
			)
			(layer "F.Fab")
		)
		(fp_line
			(start -0.67945 0.3048)
			(end -0.67945 -0.305054)
			(stroke
				(width 0.1)
				(type default)
			)
			(layer "F.Fab")
		)
		(fp_line
			(start -0.67945 -0.305054)
			(end -0.12065 -0.305054)
			(stroke
				(width 0.1)
				(type default)
			)
			(layer "F.Fab")
		)
		(pad "1" smd circle
			(at -0.40005 0 180)
			(size 0 0)
			(layers "F.Cu" "F.Mask" "F.Paste")
			(net "PVDD18_S5_P0")
		)
		(pad "2" smd circle
			(at 0.40005 0 180)
			(size 0 0)
			(layers "F.Cu" "F.Mask" "F.Paste")
			(net "SPI_CPU0_CLK")
		)
	)
	(footprint ""
		(layer "F.Cu")
		(at 257.242056 -116.87937 180)
		(property "Reference" "R3717"
			(at 0 0 180)
			(layer "F.SilkS")
			(hide yes)
			(effects
				(font
					(size 1.27 1.27)
				)
			)
		)
		(property "Value" ""
			(at 0 0 180)
			(layer "F.Fab")
			(effects
				(font
					(size 1.27 1.27)
				)
			)
		)
		(duplicate_pad_numbers_are_jumpers no)
		(fp_line
			(start 0.7874 0.4064)
			(end -0.7874 0.4064)
			(stroke
				(width 0.1524)
				(type default)
			)
			(layer "F.SilkS")
		)
		(fp_line
			(start 0.7874 -0.4064)
			(end 0.7874 0.4064)
			(stroke
				(width 0.1524)
				(type default)
			)
			(layer "F.SilkS")
		)
		(fp_line
			(start -0.7874 0.4064)
			(end -0.7874 -0.4064)
			(stroke
				(width 0.1524)
				(type default)
			)
			(layer "F.SilkS")
		)
		(fp_line
			(start -0.7874 -0.4064)
			(end 0.7874 -0.4064)
			(stroke
				(width 0.1524)
				(type default)
			)
			(layer "F.SilkS")
		)
		(fp_line
			(start 0.67945 0.3048)
			(end 0.120396 0.3048)
			(stroke
				(width 0.1)
				(type default)
			)
			(layer "F.Fab")
		)
		(fp_line
			(start 0.67945 -0.3048)
			(end 0.67945 0.3048)
			(stroke
				(width 0.1)
				(type default)
			)
			(layer "F.Fab")
		)
		(fp_line
			(start 0.12065 -0.2794)
			(end 0.12065 -0.3048)
			(stroke
				(width 0.1)
				(type default)
			)
			(layer "F.Fab")
		)
		(fp_line
			(start 0.12065 -0.3048)
			(end 0.67945 -0.3048)
			(stroke
				(width 0.1)
				(type default)
			)
			(layer "F.Fab")
		)
		(fp_line
			(start 0.120396 0.3048)
			(end 0.120396 0.2794)
			(stroke
				(width 0.1)
				(type default)
			)
			(layer "F.Fab")
		)
		(fp_line
			(start 0.120396 0.2794)
			(end -0.12065 0.2794)
			(stroke
				(width 0.1)
				(type default)
			)
			(layer "F.Fab")
		)
		(fp_line
			(start -0.12065 0.3048)
			(end -0.67945 0.3048)
			(stroke
				(width 0.1)
				(type default)
			)
			(layer "F.Fab")
		)
		(fp_line
			(start -0.12065 0.2794)
			(end -0.12065 0.3048)
			(stroke
				(width 0.1)
				(type default)
			)
			(layer "F.Fab")
		)
		(fp_line
			(start -0.12065 -0.2794)
			(end 0.12065 -0.2794)
			(stroke
				(width 0.1)
				(type default)
			)
			(layer "F.Fab")
		)
		(fp_line
			(start -0.12065 -0.305054)
			(end -0.12065 -0.2794)
			(stroke
				(width 0.1)
				(type default)
			)
			(layer "F.Fab")
		)
		(fp_line
			(start -0.67945 0.3048)
			(end -0.67945 -0.305054)
			(stroke
				(width 0.1)
				(type default)
			)
			(layer "F.Fab")
		)
		(fp_line
			(start -0.67945 -0.305054)
			(end -0.12065 -0.305054)
			(stroke
				(width 0.1)
				(type default)
			)
			(layer "F.Fab")
		)
		(pad "1" smd circle
			(at -0.40005 0 180)
			(size 0 0)
			(layers "F.Cu" "F.Mask" "F.Paste")
			(net "SMB_LM75_1_3V3AUX_SCL_R")
		)
		(pad "2" smd circle
			(at 0.40005 0 180)
			(size 0 0)
			(layers "F.Cu" "F.Mask" "F.Paste")
			(net "SMB_LM75_1_3V3AUX_SCL")
		)
	)
	(footprint ""
		(layer "F.Cu")
		(at 264.478516 -135.654796 180)
		(property "Reference" "R659"
			(at 0 0 180)
			(layer "F.SilkS")
			(hide yes)
			(effects
				(font
					(size 1.27 1.27)
				)
			)
		)
		(property "Value" ""
			(at 0 0 180)
			(layer "F.Fab")
			(effects
				(font
					(size 1.27 1.27)
				)
			)
		)
		(duplicate_pad_numbers_are_jumpers no)
		(fp_line
			(start 0.7874 0.4064)
			(end -0.7874 0.4064)
			(stroke
				(width 0.1524)
				(type default)
			)
			(layer "F.SilkS")
		)
		(fp_line
			(start 0.7874 -0.4064)
			(end 0.7874 0.4064)
			(stroke
				(width 0.1524)
				(type default)
			)
			(layer "F.SilkS")
		)
		(fp_line
			(start -0.7874 0.4064)
			(end -0.7874 -0.4064)
			(stroke
				(width 0.1524)
				(type default)
			)
			(layer "F.SilkS")
		)
		(fp_line
			(start -0.7874 -0.4064)
			(end 0.7874 -0.4064)
			(stroke
				(width 0.1524)
				(type default)
			)
			(layer "F.SilkS")
		)
		(fp_line
			(start 0.67945 0.3048)
			(end 0.120396 0.3048)
			(stroke
				(width 0.1)
				(type default)
			)
			(layer "F.Fab")
		)
		(fp_line
			(start 0.67945 -0.3048)
			(end 0.67945 0.3048)
			(stroke
				(width 0.1)
				(type default)
			)
			(layer "F.Fab")
		)
		(fp_line
			(start 0.12065 -0.2794)
			(end 0.12065 -0.3048)
			(stroke
				(width 0.1)
				(type default)
			)
			(layer "F.Fab")
		)
		(fp_line
			(start 0.12065 -0.3048)
			(end 0.67945 -0.3048)
			(stroke
				(width 0.1)
				(type default)
			)
			(layer "F.Fab")
		)
		(fp_line
			(start 0.120396 0.3048)
			(end 0.120396 0.2794)
			(stroke
				(width 0.1)
				(type default)
			)
			(layer "F.Fab")
		)
		(fp_line
			(start 0.120396 0.2794)
			(end -0.12065 0.2794)
			(stroke
				(width 0.1)
				(type default)
			)
			(layer "F.Fab")
		)
		(fp_line
			(start -0.12065 0.3048)
			(end -0.67945 0.3048)
			(stroke
				(width 0.1)
				(type default)
			)
			(layer "F.Fab")
		)
		(fp_line
			(start -0.12065 0.2794)
			(end -0.12065 0.3048)
			(stroke
				(width 0.1)
				(type default)
			)
			(layer "F.Fab")
		)
		(fp_line
			(start -0.12065 -0.2794)
			(end 0.12065 -0.2794)
			(stroke
				(width 0.1)
				(type default)
			)
			(layer "F.Fab")
		)
		(fp_line
			(start -0.12065 -0.305054)
			(end -0.12065 -0.2794)
			(stroke
				(width 0.1)
				(type default)
			)
			(layer "F.Fab")
		)
		(fp_line
			(start -0.67945 0.3048)
			(end -0.67945 -0.305054)
			(stroke
				(width 0.1)
				(type default)
			)
			(layer "F.Fab")
		)
		(fp_line
			(start -0.67945 -0.305054)
			(end -0.12065 -0.305054)
			(stroke
				(width 0.1)
				(type default)
			)
			(layer "F.Fab")
		)
		(pad "1" smd circle
			(at -0.40005 0 180)
			(size 0 0)
			(layers "F.Cu" "F.Mask" "F.Paste")
			(net "PVDD18_S5_P0")
		)
		(pad "2" smd circle
			(at 0.40005 0 180)
			(size 0 0)
			(layers "F.Cu" "F.Mask" "F.Paste")
			(net "SPI_CPU0_TPM_CS_N")
		)
	)
	(footprint ""
		(layer "F.Cu")
		(at 183.420766 -168.317418 -90)
		(property "Reference" "R5013"
			(at 0 0 270)
			(layer "F.SilkS")
			(hide yes)
			(effects
				(font
					(size 1.27 1.27)
				)
			)
		)
		(property "Value" ""
			(at 0 0 270)
			(layer "F.Fab")
			(effects
				(font
					(size 1.27 1.27)
				)
			)
		)
		(duplicate_pad_numbers_are_jumpers no)
		(fp_line
			(start -0.7874 0.4064)
			(end -0.7874 -0.4064)
			(stroke
				(width 0.1524)
				(type default)
			)
			(layer "F.SilkS")
		)
		(fp_line
			(start 0.7874 0.4064)
			(end -0.7874 0.4064)
			(stroke
				(width 0.1524)
				(type default)
			)
			(layer "F.SilkS")
		)
		(fp_line
			(start -0.7874 -0.4064)
			(end 0.7874 -0.4064)
			(stroke
				(width 0.1524)
				(type default)
			)
			(layer "F.SilkS")
		)
		(fp_line
			(start 0.7874 -0.4064)
			(end 0.7874 0.4064)
			(stroke
				(width 0.1524)
				(type default)
			)
			(layer "F.SilkS")
		)
		(fp_line
			(start -0.67945 0.3048)
			(end -0.67945 -0.305054)
			(stroke
				(width 0.1)
				(type default)
			)
			(layer "F.Fab")
		)
		(fp_line
			(start -0.12065 0.3048)
			(end -0.67945 0.3048)
			(stroke
				(width 0.1)
				(type default)
			)
			(layer "F.Fab")
		)
		(fp_line
			(start 0.120396 0.3048)
			(end 0.120396 0.2794)
			(stroke
				(width 0.1)
				(type default)
			)
			(layer "F.Fab")
		)
		(fp_line
			(start 0.67945 0.3048)
			(end 0.120396 0.3048)
			(stroke
				(width 0.1)
				(type default)
			)
			(layer "F.Fab")
		)
		(fp_line
			(start -0.12065 0.2794)
			(end -0.12065 0.3048)
			(stroke
				(width 0.1)
				(type default)
			)
			(layer "F.Fab")
		)
		(fp_line
			(start 0.120396 0.2794)
			(end -0.12065 0.2794)
			(stroke
				(width 0.1)
				(type default)
			)
			(layer "F.Fab")
		)
		(fp_line
			(start -0.12065 -0.2794)
			(end 0.12065 -0.2794)
			(stroke
				(width 0.1)
				(type default)
			)
			(layer "F.Fab")
		)
		(fp_line
			(start 0.12065 -0.2794)
			(end 0.12065 -0.3048)
			(stroke
				(width 0.1)
				(type default)
			)
			(layer "F.Fab")
		)
		(fp_line
			(start 0.12065 -0.3048)
			(end 0.67945 -0.3048)
			(stroke
				(width 0.1)
				(type default)
			)
			(layer "F.Fab")
		)
		(fp_line
			(start 0.67945 -0.3048)
			(end 0.67945 0.3048)
			(stroke
				(width 0.1)
				(type default)
			)
			(layer "F.Fab")
		)
		(fp_line
			(start -0.67945 -0.305054)
			(end -0.12065 -0.305054)
			(stroke
				(width 0.1)
				(type default)
			)
			(layer "F.Fab")
		)
		(fp_line
			(start -0.12065 -0.305054)
			(end -0.12065 -0.2794)
			(stroke
				(width 0.1)
				(type default)
			)
			(layer "F.Fab")
		)
		(pad "1" smd circle
			(at -0.40005 0 270)
			(size 0 0)
			(layers "F.Cu" "F.Mask" "F.Paste")
			(net "PVDD11_S3_P1")
		)
		(pad "2" smd circle
			(at 0.40005 0 270)
			(size 0 0)
			(layers "F.Cu" "F.Mask" "F.Paste")
			(net "I3C_SPD_DDRGL_CPU1_LVC1_SDA")
		)
	)
	(footprint ""
		(layer "F.Cu")
		(at 88.06053 -59.83097 -90)
		(property "Reference" "R3832"
			(at 0 0 270)
			(layer "F.SilkS")
			(hide yes)
			(effects
				(font
					(size 1.27 1.27)
				)
			)
		)
		(property "Value" ""
			(at 0 0 270)
			(layer "F.Fab")
			(effects
				(font
					(size 1.27 1.27)
				)
			)
		)
		(duplicate_pad_numbers_are_jumpers no)
		(fp_line
			(start -0.7874 0.4064)
			(end -0.7874 -0.4064)
			(stroke
				(width 0.1524)
				(type default)
			)
			(layer "F.SilkS")
		)
		(fp_line
			(start 0.7874 0.4064)
			(end -0.7874 0.4064)
			(stroke
				(width 0.1524)
				(type default)
			)
			(layer "F.SilkS")
		)
		(fp_line
			(start -0.7874 -0.4064)
			(end 0.7874 -0.4064)
			(stroke
				(width 0.1524)
				(type default)
			)
			(layer "F.SilkS")
		)
		(fp_line
			(start 0.7874 -0.4064)
			(end 0.7874 0.4064)
			(stroke
				(width 0.1524)
				(type default)
			)
			(layer "F.SilkS")
		)
		(fp_line
			(start -0.67945 0.3048)
			(end -0.67945 -0.305054)
			(stroke
				(width 0.1)
				(type default)
			)
			(layer "F.Fab")
		)
		(fp_line
			(start -0.12065 0.3048)
			(end -0.67945 0.3048)
			(stroke
				(width 0.1)
				(type default)
			)
			(layer "F.Fab")
		)
		(fp_line
			(start 0.120396 0.3048)
			(end 0.120396 0.2794)
			(stroke
				(width 0.1)
				(type default)
			)
			(layer "F.Fab")
		)
		(fp_line
			(start 0.67945 0.3048)
			(end 0.120396 0.3048)
			(stroke
				(width 0.1)
				(type default)
			)
			(layer "F.Fab")
		)
		(fp_line
			(start -0.12065 0.2794)
			(end -0.12065 0.3048)
			(stroke
				(width 0.1)
				(type default)
			)
			(layer "F.Fab")
		)
		(fp_line
			(start 0.120396 0.2794)
			(end -0.12065 0.2794)
			(stroke
				(width 0.1)
				(type default)
			)
			(layer "F.Fab")
		)
		(fp_line
			(start -0.12065 -0.2794)
			(end 0.12065 -0.2794)
			(stroke
				(width 0.1)
				(type default)
			)
			(layer "F.Fab")
		)
		(fp_line
			(start 0.12065 -0.2794)
			(end 0.12065 -0.3048)
			(stroke
				(width 0.1)
				(type default)
			)
			(layer "F.Fab")
		)
		(fp_line
			(start 0.12065 -0.3048)
			(end 0.67945 -0.3048)
			(stroke
				(width 0.1)
				(type default)
			)
			(layer "F.Fab")
		)
		(fp_line
			(start 0.67945 -0.3048)
			(end 0.67945 0.3048)
			(stroke
				(width 0.1)
				(type default)
			)
			(layer "F.Fab")
		)
		(fp_line
			(start -0.67945 -0.305054)
			(end -0.12065 -0.305054)
			(stroke
				(width 0.1)
				(type default)
			)
			(layer "F.Fab")
		)
		(fp_line
			(start -0.12065 -0.305054)
			(end -0.12065 -0.2794)
			(stroke
				(width 0.1)
				(type default)
			)
			(layer "F.Fab")
		)
		(pad "1" smd circle
			(at -0.40005 0 270)
			(size 0 0)
			(layers "F.Cu" "F.Mask" "F.Paste")
			(net "P3V3_OCP_PWRGD_2")
		)
		(pad "2" smd circle
			(at 0.40005 0 270)
			(size 0 0)
			(layers "F.Cu" "F.Mask" "F.Paste")
			(net "OCP_V3_2_P3V3_PWRGD")
		)
	)
	(footprint ""
		(layer "F.Cu")
		(at 223.37141 -73.517506)
		(property "Reference" "PC2216"
			(at 0 0 0)
			(layer "F.SilkS")
			(hide yes)
			(effects
				(font
					(size 1.27 1.27)
				)
			)
		)
		(property "Value" ""
			(at 0 0 0)
			(layer "F.Fab")
			(effects
				(font
					(size 1.27 1.27)
				)
			)
		)
		(duplicate_pad_numbers_are_jumpers no)
		(fp_line
			(start -0.7874 -0.4064)
			(end 0.7874 -0.4064)
			(stroke
				(width 0.1524)
				(type default)
			)
			(layer "F.SilkS")
		)
		(fp_line
			(start -0.7874 0.4064)
			(end -0.7874 -0.4064)
			(stroke
				(width 0.1524)
				(type default)
			)
			(layer "F.SilkS")
		)
		(fp_line
			(start 0.7874 -0.4064)
			(end 0.7874 0.4064)
			(stroke
				(width 0.1524)
				(type default)
			)
			(layer "F.SilkS")
		)
		(fp_line
			(start 0.7874 0.4064)
			(end -0.7874 0.4064)
			(stroke
				(width 0.1524)
				(type default)
			)
			(layer "F.SilkS")
		)
		(fp_line
			(start -0.67945 -0.305054)
			(end -0.12065 -0.305054)
			(stroke
				(width 0.1)
				(type default)
			)
			(layer "F.Fab")
		)
		(fp_line
			(start -0.67945 0.3048)
			(end -0.67945 -0.305054)
			(stroke
				(width 0.1)
				(type default)
			)
			(layer "F.Fab")
		)
		(fp_line
			(start -0.12065 -0.305054)
			(end -0.12065 -0.2794)
			(stroke
				(width 0.1)
				(type default)
			)
			(layer "F.Fab")
		)
		(fp_line
			(start -0.12065 -0.2794)
			(end 0.12065 -0.2794)
			(stroke
				(width 0.1)
				(type default)
			)
			(layer "F.Fab")
		)
		(fp_line
			(start -0.12065 0.2794)
			(end -0.12065 0.3048)
			(stroke
				(width 0.1)
				(type default)
			)
			(layer "F.Fab")
		)
		(fp_line
			(start -0.12065 0.3048)
			(end -0.67945 0.3048)
			(stroke
				(width 0.1)
				(type default)
			)
			(layer "F.Fab")
		)
		(fp_line
			(start 0.120396 0.2794)
			(end -0.12065 0.2794)
			(stroke
				(width 0.1)
				(type default)
			)
			(layer "F.Fab")
		)
		(fp_line
			(start 0.120396 0.3048)
			(end 0.120396 0.2794)
			(stroke
				(width 0.1)
				(type default)
			)
			(layer "F.Fab")
		)
		(fp_line
			(start 0.12065 -0.3048)
			(end 0.67945 -0.3048)
			(stroke
				(width 0.1)
				(type default)
			)
			(layer "F.Fab")
		)
		(fp_line
			(start 0.12065 -0.2794)
			(end 0.12065 -0.3048)
			(stroke
				(width 0.1)
				(type default)
			)
			(layer "F.Fab")
		)
		(fp_line
			(start 0.67945 -0.3048)
			(end 0.67945 0.3048)
			(stroke
				(width 0.1)
				(type default)
			)
			(layer "F.Fab")
		)
		(fp_line
			(start 0.67945 0.3048)
			(end 0.120396 0.3048)
			(stroke
				(width 0.1)
				(type default)
			)
			(layer "F.Fab")
		)
		(pad "1" smd circle
			(at -0.40005 0)
			(size 0 0)
			(layers "F.Cu" "F.Mask" "F.Paste")
			(net "P3V3_E1S_GATE_0")
		)
		(pad "2" smd circle
			(at 0.40005 0)
			(size 0 0)
			(layers "F.Cu" "F.Mask" "F.Paste")
			(net "GND")
		)
	)
	(footprint ""
		(layer "F.Cu")
		(at 13.12672 -74.719688)
		(property "Reference" "U242"
			(at 1.629156 2.268982 0)
			(unlocked yes)
			(layer "F.SilkS")
			(effects
				(font
					(size 0.7874 0.5842)
					(thickness 0.1524)
				)
				(justify left)
			)
		)
		(property "Value" ""
			(at 0 0 0)
			(layer "F.Fab")
			(effects
				(font
					(size 1.27 1.27)
				)
			)
		)
		(duplicate_pad_numbers_are_jumpers no)
		(fp_line
			(start -1.207008 -1.549908)
			(end -1.207008 1.549908)
			(stroke
				(width 0.1524)
				(type default)
			)
			(layer "F.SilkS")
		)
		(fp_line
			(start -1.207008 1.549908)
			(end 1.207008 1.549908)
			(stroke
				(width 0.1524)
				(type default)
			)
			(layer "F.SilkS")
		)
		(fp_line
			(start -0.762508 -1.549908)
			(end -1.207008 -1.549908)
			(stroke
				(width 0.1524)
				(type default)
			)
			(layer "F.SilkS")
		)
		(fp_line
			(start 0 -0.635)
			(end -0.762508 -1.549908)
			(stroke
				(width 0.1524)
				(type default)
			)
			(layer "F.SilkS")
		)
		(fp_line
			(start 0.762508 -1.549908)
			(end 0 -0.635)
			(stroke
				(width 0.1524)
				(type default)
			)
			(layer "F.SilkS")
		)
		(fp_line
			(start 1.207008 -1.549908)
			(end 0.762508 -1.549908)
			(stroke
				(width 0.1524)
				(type default)
			)
			(layer "F.SilkS")
		)
		(fp_line
			(start 1.207008 1.549908)
			(end 1.207008 -1.549908)
			(stroke
				(width 0.1524)
				(type default)
			)
			(layer "F.SilkS")
		)
		(fp_poly
			(pts
				(xy -2.608326 -0.655828) (xy -3.524758 0.015494) (xy -3.695192 -0.986028)
			)
			(stroke
				(width 0)
				(type default)
			)
			(fill yes)
			(layer "F.SilkS")
		)
		(fp_line
			(start -1.549908 -1.549908)
			(end -1.549908 1.549908)
			(stroke
				(width 0.1)
				(type default)
			)
			(layer "F.Fab")
		)
		(fp_line
			(start -1.549908 1.549908)
			(end 1.549908 1.549908)
			(stroke
				(width 0.1)
				(type default)
			)
			(layer "F.Fab")
		)
		(fp_line
			(start 1.549908 -1.549908)
			(end -1.549908 -1.549908)
			(stroke
				(width 0.1)
				(type default)
			)
			(layer "F.Fab")
		)
		(fp_line
			(start 1.549908 1.549908)
			(end 1.549908 -1.549908)
			(stroke
				(width 0.1)
				(type default)
			)
			(layer "F.Fab")
		)
		(fp_poly
			(pts
				(xy -3.4036 -1.53289) (xy -3.4036 -0.51689) (xy -2.3876 -1.02489)
			)
			(stroke
				(width 0)
				(type default)
			)
			(fill yes)
			(layer "F.Fab")
		)
		(pad "1" smd rect
			(at -1.774952 -1.02489 270)
			(size 0.508 0.8636)
			(layers "F.Cu" "F.Mask" "F.Paste")
			(net "OCP_SFF_PRSNT01_R1_N")
		)
		(pad "2" smd rect
			(at -1.774952 -0.32512 270)
			(size 0.4064 0.8636)
			(layers "F.Cu" "F.Mask" "F.Paste")
			(net "OCP_SFF_PRSNT23_R1_N")
		)
		(pad "3" smd rect
			(at -1.774952 0.32512 270)
			(size 0.4064 0.8636)
			(layers "F.Cu" "F.Mask" "F.Paste")
			(net "OCP_V3_2_PRSNT_ALL_R_N")
		)
		(pad "4" smd rect
			(at -1.774952 1.02489 270)
			(size 0.508 0.8636)
			(layers "F.Cu" "F.Mask" "F.Paste")
			(net "GND")
		)
		(pad "5" smd rect
			(at 1.774952 1.02489 270)
			(size 0.508 0.8636)
			(layers "F.Cu" "F.Mask" "F.Paste")
			(net "OCP_V3_2_PRSNT01_R1_N")
		)
		(pad "6" smd rect
			(at 1.774952 0.32512 270)
			(size 0.4064 0.8636)
			(layers "F.Cu" "F.Mask" "F.Paste")
			(net "OCP_V3_2_PRSNT23_R1_N")
		)
		(pad "7" smd rect
			(at 1.774952 -0.32512 270)
			(size 0.4064 0.8636)
			(layers "F.Cu" "F.Mask" "F.Paste")
			(net "OCP_SFF_PRSNT_ALL_R_N")
		)
		(pad "8" smd rect
			(at 1.774952 -1.02489 270)
			(size 0.508 0.8636)
			(layers "F.Cu" "F.Mask" "F.Paste")
			(net "P3V3_AUX")
		)
	)
	(footprint ""
		(layer "F.Cu")
		(at 283.21127 -401.586954 90)
		(property "Reference" "R353"
			(at 0 0 90)
			(layer "F.SilkS")
			(hide yes)
			(effects
				(font
					(size 1.27 1.27)
				)
			)
		)
		(property "Value" ""
			(at 0 0 90)
			(layer "F.Fab")
			(effects
				(font
					(size 1.27 1.27)
				)
			)
		)
		(duplicate_pad_numbers_are_jumpers no)
		(fp_line
			(start 0.7874 -0.4064)
			(end 0.7874 0.4064)
			(stroke
				(width 0.1524)
				(type default)
			)
			(layer "F.SilkS")
		)
		(fp_line
			(start -0.7874 -0.4064)
			(end 0.7874 -0.4064)
			(stroke
				(width 0.1524)
				(type default)
			)
			(layer "F.SilkS")
		)
		(fp_line
			(start 0.7874 0.4064)
			(end -0.7874 0.4064)
			(stroke
				(width 0.1524)
				(type default)
			)
			(layer "F.SilkS")
		)
		(fp_line
			(start -0.7874 0.4064)
			(end -0.7874 -0.4064)
			(stroke
				(width 0.1524)
				(type default)
			)
			(layer "F.SilkS")
		)
		(fp_line
			(start -0.12065 -0.305054)
			(end -0.12065 -0.2794)
			(stroke
				(width 0.1)
				(type default)
			)
			(layer "F.Fab")
		)
		(fp_line
			(start -0.67945 -0.305054)
			(end -0.12065 -0.305054)
			(stroke
				(width 0.1)
				(type default)
			)
			(layer "F.Fab")
		)
		(fp_line
			(start 0.67945 -0.3048)
			(end 0.67945 0.3048)
			(stroke
				(width 0.1)
				(type default)
			)
			(layer "F.Fab")
		)
		(fp_line
			(start 0.12065 -0.3048)
			(end 0.67945 -0.3048)
			(stroke
				(width 0.1)
				(type default)
			)
			(layer "F.Fab")
		)
		(fp_line
			(start 0.12065 -0.2794)
			(end 0.12065 -0.3048)
			(stroke
				(width 0.1)
				(type default)
			)
			(layer "F.Fab")
		)
		(fp_line
			(start -0.12065 -0.2794)
			(end 0.12065 -0.2794)
			(stroke
				(width 0.1)
				(type default)
			)
			(layer "F.Fab")
		)
		(fp_line
			(start 0.120396 0.2794)
			(end -0.12065 0.2794)
			(stroke
				(width 0.1)
				(type default)
			)
			(layer "F.Fab")
		)
		(fp_line
			(start -0.12065 0.2794)
			(end -0.12065 0.3048)
			(stroke
				(width 0.1)
				(type default)
			)
			(layer "F.Fab")
		)
		(fp_line
			(start 0.67945 0.3048)
			(end 0.120396 0.3048)
			(stroke
				(width 0.1)
				(type default)
			)
			(layer "F.Fab")
		)
		(fp_line
			(start 0.120396 0.3048)
			(end 0.120396 0.2794)
			(stroke
				(width 0.1)
				(type default)
			)
			(layer "F.Fab")
		)
		(fp_line
			(start -0.12065 0.3048)
			(end -0.67945 0.3048)
			(stroke
				(width 0.1)
				(type default)
			)
			(layer "F.Fab")
		)
		(fp_line
			(start -0.67945 0.3048)
			(end -0.67945 -0.305054)
			(stroke
				(width 0.1)
				(type default)
			)
			(layer "F.Fab")
		)
		(pad "1" smd circle
			(at -0.40005 0 90)
			(size 0 0)
			(layers "F.Cu" "F.Mask" "F.Paste")
			(net "P12V_HSC_T_CRIT_N")
		)
		(pad "2" smd circle
			(at 0.40005 0 90)
			(size 0 0)
			(layers "F.Cu" "F.Mask" "F.Paste")
			(net "P12V_HSC_T_CRIT_R_N")
		)
	)
	(footprint ""
		(layer "F.Cu")
		(at 427.269656 -397.135604 180)
		(property "Reference" "L29"
			(at 0 0 180)
			(layer "F.SilkS")
			(hide yes)
			(effects
				(font
					(size 1.27 1.27)
				)
			)
		)
		(property "Value" ""
			(at 0 0 180)
			(layer "F.Fab")
			(effects
				(font
					(size 1.27 1.27)
				)
			)
		)
		(duplicate_pad_numbers_are_jumpers no)
		(fp_line
			(start 0.762 0.381)
			(end -0.762 0.381)
			(stroke
				(width 0.1524)
				(type default)
			)
			(layer "F.SilkS")
		)
		(fp_line
			(start 0.762 -0.381)
			(end 0.762 0.381)
			(stroke
				(width 0.1524)
				(type default)
			)
			(layer "F.SilkS")
		)
		(fp_line
			(start -0.762 0.381)
			(end -0.762 -0.381)
			(stroke
				(width 0.1524)
				(type default)
			)
			(layer "F.SilkS")
		)
		(fp_line
			(start -0.762 -0.381)
			(end 0.762 -0.381)
			(stroke
				(width 0.1524)
				(type default)
			)
			(layer "F.SilkS")
		)
		(fp_line
			(start 0.680466 0.306324)
			(end 0.118364 0.306324)
			(stroke
				(width 0.1)
				(type default)
			)
			(layer "F.Fab")
		)
		(fp_line
			(start 0.680466 -0.306324)
			(end 0.680466 0.306324)
			(stroke
				(width 0.1)
				(type default)
			)
			(layer "F.Fab")
		)
		(fp_line
			(start 0.118872 -0.2794)
			(end 0.118872 -0.306324)
			(stroke
				(width 0.1)
				(type default)
			)
			(layer "F.Fab")
		)
		(fp_line
			(start 0.118872 -0.306324)
			(end 0.680466 -0.306324)
			(stroke
				(width 0.1)
				(type default)
			)
			(layer "F.Fab")
		)
		(fp_line
			(start 0.118364 0.306324)
			(end 0.118364 0.2794)
			(stroke
				(width 0.1)
				(type default)
			)
			(layer "F.Fab")
		)
		(fp_line
			(start 0.118364 0.2794)
			(end -0.119634 0.2794)
			(stroke
				(width 0.1)
				(type default)
			)
			(layer "F.Fab")
		)
		(fp_line
			(start -0.118364 -0.2794)
			(end 0.118872 -0.2794)
			(stroke
				(width 0.1)
				(type default)
			)
			(layer "F.Fab")
		)
		(fp_line
			(start -0.118364 -0.307086)
			(end -0.118364 -0.2794)
			(stroke
				(width 0.1)
				(type default)
			)
			(layer "F.Fab")
		)
		(fp_line
			(start -0.119634 0.30607)
			(end -0.681736 0.30607)
			(stroke
				(width 0.1)
				(type default)
			)
			(layer "F.Fab")
		)
		(fp_line
			(start -0.119634 0.2794)
			(end -0.119634 0.30607)
			(stroke
				(width 0.1)
				(type default)
			)
			(layer "F.Fab")
		)
		(fp_line
			(start -0.681736 0.30607)
			(end -0.681736 -0.307086)
			(stroke
				(width 0.1)
				(type default)
			)
			(layer "F.Fab")
		)
		(fp_line
			(start -0.681736 -0.307086)
			(end -0.118364 -0.307086)
			(stroke
				(width 0.1)
				(type default)
			)
			(layer "F.Fab")
		)
		(pad "1" smd rect
			(at -0.40005 0)
			(size 0.4572 0.508)
			(layers "F.Cu" "F.Mask" "F.Paste")
			(net "P1V8_CPU0_RT_1D")
		)
		(pad "2" smd rect
			(at 0.40005 0)
			(size 0.4572 0.508)
			(layers "F.Cu" "F.Mask" "F.Paste")
			(net "P1V8_CPU0_RT2_1A_1D")
		)
	)
	(footprint ""
		(layer "F.Cu")
		(at 100.48367 -406.151588 180)
		(property "Reference" "R593"
			(at 0 0 180)
			(layer "F.SilkS")
			(hide yes)
			(effects
				(font
					(size 1.27 1.27)
				)
			)
		)
		(property "Value" ""
			(at 0 0 180)
			(layer "F.Fab")
			(effects
				(font
					(size 1.27 1.27)
				)
			)
		)
		(duplicate_pad_numbers_are_jumpers no)
		(fp_line
			(start 0.7874 0.4064)
			(end -0.7874 0.4064)
			(stroke
				(width 0.1524)
				(type default)
			)
			(layer "F.SilkS")
		)
		(fp_line
			(start 0.7874 -0.4064)
			(end 0.7874 0.4064)
			(stroke
				(width 0.1524)
				(type default)
			)
			(layer "F.SilkS")
		)
		(fp_line
			(start -0.7874 0.4064)
			(end -0.7874 -0.4064)
			(stroke
				(width 0.1524)
				(type default)
			)
			(layer "F.SilkS")
		)
		(fp_line
			(start -0.7874 -0.4064)
			(end 0.7874 -0.4064)
			(stroke
				(width 0.1524)
				(type default)
			)
			(layer "F.SilkS")
		)
		(fp_line
			(start 0.67945 0.3048)
			(end 0.120396 0.3048)
			(stroke
				(width 0.1)
				(type default)
			)
			(layer "F.Fab")
		)
		(fp_line
			(start 0.67945 -0.3048)
			(end 0.67945 0.3048)
			(stroke
				(width 0.1)
				(type default)
			)
			(layer "F.Fab")
		)
		(fp_line
			(start 0.12065 -0.2794)
			(end 0.12065 -0.3048)
			(stroke
				(width 0.1)
				(type default)
			)
			(layer "F.Fab")
		)
		(fp_line
			(start 0.12065 -0.3048)
			(end 0.67945 -0.3048)
			(stroke
				(width 0.1)
				(type default)
			)
			(layer "F.Fab")
		)
		(fp_line
			(start 0.120396 0.3048)
			(end 0.120396 0.2794)
			(stroke
				(width 0.1)
				(type default)
			)
			(layer "F.Fab")
		)
		(fp_line
			(start 0.120396 0.2794)
			(end -0.12065 0.2794)
			(stroke
				(width 0.1)
				(type default)
			)
			(layer "F.Fab")
		)
		(fp_line
			(start -0.12065 0.3048)
			(end -0.67945 0.3048)
			(stroke
				(width 0.1)
				(type default)
			)
			(layer "F.Fab")
		)
		(fp_line
			(start -0.12065 0.2794)
			(end -0.12065 0.3048)
			(stroke
				(width 0.1)
				(type default)
			)
			(layer "F.Fab")
		)
		(fp_line
			(start -0.12065 -0.2794)
			(end 0.12065 -0.2794)
			(stroke
				(width 0.1)
				(type default)
			)
			(layer "F.Fab")
		)
		(fp_line
			(start -0.12065 -0.305054)
			(end -0.12065 -0.2794)
			(stroke
				(width 0.1)
				(type default)
			)
			(layer "F.Fab")
		)
		(fp_line
			(start -0.67945 0.3048)
			(end -0.67945 -0.305054)
			(stroke
				(width 0.1)
				(type default)
			)
			(layer "F.Fab")
		)
		(fp_line
			(start -0.67945 -0.305054)
			(end -0.12065 -0.305054)
			(stroke
				(width 0.1)
				(type default)
			)
			(layer "F.Fab")
		)
		(pad "1" smd circle
			(at -0.40005 0 180)
			(size 0 0)
			(layers "F.Cu" "F.Mask" "F.Paste")
			(net "FM_9ZXL045_P1_1_OE_N")
		)
		(pad "2" smd circle
			(at 0.40005 0 180)
			(size 0 0)
			(layers "F.Cu" "F.Mask" "F.Paste")
			(net "GND")
		)
	)
	(footprint ""
		(layer "F.Cu")
		(at 318.300608 -25.27935 90)
		(property "Reference" "C553"
			(at 0 0 90)
			(layer "F.SilkS")
			(hide yes)
			(effects
				(font
					(size 1.27 1.27)
				)
			)
		)
		(property "Value" ""
			(at 0 0 90)
			(layer "F.Fab")
			(effects
				(font
					(size 1.27 1.27)
				)
			)
		)
		(duplicate_pad_numbers_are_jumpers no)
		(fp_line
			(start 0.7874 -0.4064)
			(end 0.7874 0.4064)
			(stroke
				(width 0.1524)
				(type default)
			)
			(layer "F.SilkS")
		)
		(fp_line
			(start -0.7874 -0.4064)
			(end 0.7874 -0.4064)
			(stroke
				(width 0.1524)
				(type default)
			)
			(layer "F.SilkS")
		)
		(fp_line
			(start 0.7874 0.4064)
			(end -0.7874 0.4064)
			(stroke
				(width 0.1524)
				(type default)
			)
			(layer "F.SilkS")
		)
		(fp_line
			(start -0.7874 0.4064)
			(end -0.7874 -0.4064)
			(stroke
				(width 0.1524)
				(type default)
			)
			(layer "F.SilkS")
		)
		(fp_line
			(start -0.12065 -0.305054)
			(end -0.12065 -0.2794)
			(stroke
				(width 0.1)
				(type default)
			)
			(layer "F.Fab")
		)
		(fp_line
			(start -0.67945 -0.305054)
			(end -0.12065 -0.305054)
			(stroke
				(width 0.1)
				(type default)
			)
			(layer "F.Fab")
		)
		(fp_line
			(start 0.67945 -0.3048)
			(end 0.67945 0.3048)
			(stroke
				(width 0.1)
				(type default)
			)
			(layer "F.Fab")
		)
		(fp_line
			(start 0.12065 -0.3048)
			(end 0.67945 -0.3048)
			(stroke
				(width 0.1)
				(type default)
			)
			(layer "F.Fab")
		)
		(fp_line
			(start 0.12065 -0.2794)
			(end 0.12065 -0.3048)
			(stroke
				(width 0.1)
				(type default)
			)
			(layer "F.Fab")
		)
		(fp_line
			(start -0.12065 -0.2794)
			(end 0.12065 -0.2794)
			(stroke
				(width 0.1)
				(type default)
			)
			(layer "F.Fab")
		)
		(fp_line
			(start 0.120396 0.2794)
			(end -0.12065 0.2794)
			(stroke
				(width 0.1)
				(type default)
			)
			(layer "F.Fab")
		)
		(fp_line
			(start -0.12065 0.2794)
			(end -0.12065 0.3048)
			(stroke
				(width 0.1)
				(type default)
			)
			(layer "F.Fab")
		)
		(fp_line
			(start 0.67945 0.3048)
			(end 0.120396 0.3048)
			(stroke
				(width 0.1)
				(type default)
			)
			(layer "F.Fab")
		)
		(fp_line
			(start 0.120396 0.3048)
			(end 0.120396 0.2794)
			(stroke
				(width 0.1)
				(type default)
			)
			(layer "F.Fab")
		)
		(fp_line
			(start -0.12065 0.3048)
			(end -0.67945 0.3048)
			(stroke
				(width 0.1)
				(type default)
			)
			(layer "F.Fab")
		)
		(fp_line
			(start -0.67945 0.3048)
			(end -0.67945 -0.305054)
			(stroke
				(width 0.1)
				(type default)
			)
			(layer "F.Fab")
		)
		(pad "1" smd circle
			(at -0.40005 0 90)
			(size 0 0)
			(layers "F.Cu" "F.Mask" "F.Paste")
			(net "P3V3_AUX")
		)
		(pad "2" smd circle
			(at 0.40005 0 90)
			(size 0 0)
			(layers "F.Cu" "F.Mask" "F.Paste")
			(net "GND")
		)
	)
	(footprint ""
		(layer "F.Cu")
		(at 74.34707 -148.451316 -90)
		(property "Reference" "C675"
			(at 0 0 270)
			(layer "F.SilkS")
			(hide yes)
			(effects
				(font
					(size 1.27 1.27)
				)
			)
		)
		(property "Value" ""
			(at 0 0 270)
			(layer "F.Fab")
			(effects
				(font
					(size 1.27 1.27)
				)
			)
		)
		(duplicate_pad_numbers_are_jumpers no)
		(fp_line
			(start -0.7874 0.4064)
			(end -0.7874 -0.4064)
			(stroke
				(width 0.1524)
				(type default)
			)
			(layer "F.SilkS")
		)
		(fp_line
			(start 0.7874 0.4064)
			(end -0.7874 0.4064)
			(stroke
				(width 0.1524)
				(type default)
			)
			(layer "F.SilkS")
		)
		(fp_line
			(start -0.7874 -0.4064)
			(end 0.7874 -0.4064)
			(stroke
				(width 0.1524)
				(type default)
			)
			(layer "F.SilkS")
		)
		(fp_line
			(start 0.7874 -0.4064)
			(end 0.7874 0.4064)
			(stroke
				(width 0.1524)
				(type default)
			)
			(layer "F.SilkS")
		)
		(fp_line
			(start -0.67945 0.3048)
			(end -0.67945 -0.305054)
			(stroke
				(width 0.1)
				(type default)
			)
			(layer "F.Fab")
		)
		(fp_line
			(start -0.12065 0.3048)
			(end -0.67945 0.3048)
			(stroke
				(width 0.1)
				(type default)
			)
			(layer "F.Fab")
		)
		(fp_line
			(start 0.120396 0.3048)
			(end 0.120396 0.2794)
			(stroke
				(width 0.1)
				(type default)
			)
			(layer "F.Fab")
		)
		(fp_line
			(start 0.67945 0.3048)
			(end 0.120396 0.3048)
			(stroke
				(width 0.1)
				(type default)
			)
			(layer "F.Fab")
		)
		(fp_line
			(start -0.12065 0.2794)
			(end -0.12065 0.3048)
			(stroke
				(width 0.1)
				(type default)
			)
			(layer "F.Fab")
		)
		(fp_line
			(start 0.120396 0.2794)
			(end -0.12065 0.2794)
			(stroke
				(width 0.1)
				(type default)
			)
			(layer "F.Fab")
		)
		(fp_line
			(start -0.12065 -0.2794)
			(end 0.12065 -0.2794)
			(stroke
				(width 0.1)
				(type default)
			)
			(layer "F.Fab")
		)
		(fp_line
			(start 0.12065 -0.2794)
			(end 0.12065 -0.3048)
			(stroke
				(width 0.1)
				(type default)
			)
			(layer "F.Fab")
		)
		(fp_line
			(start 0.12065 -0.3048)
			(end 0.67945 -0.3048)
			(stroke
				(width 0.1)
				(type default)
			)
			(layer "F.Fab")
		)
		(fp_line
			(start 0.67945 -0.3048)
			(end 0.67945 0.3048)
			(stroke
				(width 0.1)
				(type default)
			)
			(layer "F.Fab")
		)
		(fp_line
			(start -0.67945 -0.305054)
			(end -0.12065 -0.305054)
			(stroke
				(width 0.1)
				(type default)
			)
			(layer "F.Fab")
		)
		(fp_line
			(start -0.12065 -0.305054)
			(end -0.12065 -0.2794)
			(stroke
				(width 0.1)
				(type default)
			)
			(layer "F.Fab")
		)
		(pad "1" smd circle
			(at -0.40005 0 270)
			(size 0 0)
			(layers "F.Cu" "F.Mask" "F.Paste")
			(net "PVDD18_S5_P1_EN")
		)
		(pad "2" smd circle
			(at 0.40005 0 270)
			(size 0 0)
			(layers "F.Cu" "F.Mask" "F.Paste")
			(net "GND")
		)
	)
	(footprint ""
		(layer "F.Cu")
		(at 111.506 -413.385)
		(property "Reference" "R586"
			(at 0 0 0)
			(layer "F.SilkS")
			(hide yes)
			(effects
				(font
					(size 1.27 1.27)
				)
			)
		)
		(property "Value" ""
			(at 0 0 0)
			(layer "F.Fab")
			(effects
				(font
					(size 1.27 1.27)
				)
			)
		)
		(duplicate_pad_numbers_are_jumpers no)
		(fp_line
			(start -1.2954 -0.5842)
			(end 1.2954 -0.5842)
			(stroke
				(width 0.1524)
				(type default)
			)
			(layer "F.SilkS")
		)
		(fp_line
			(start -1.2954 0.5842)
			(end -1.2954 -0.5842)
			(stroke
				(width 0.1524)
				(type default)
			)
			(layer "F.SilkS")
		)
		(fp_line
			(start 1.2954 -0.5842)
			(end 1.2954 0.5842)
			(stroke
				(width 0.1524)
				(type default)
			)
			(layer "F.SilkS")
		)
		(fp_line
			(start 1.2954 0.5842)
			(end -1.2954 0.5842)
			(stroke
				(width 0.1524)
				(type default)
			)
			(layer "F.SilkS")
		)
		(fp_line
			(start -1.1938 -0.406654)
			(end -0.8636 -0.406654)
			(stroke
				(width 0.1)
				(type default)
			)
			(layer "F.Fab")
		)
		(fp_line
			(start -1.1938 0.4064)
			(end -1.1938 -0.406654)
			(stroke
				(width 0.1)
				(type default)
			)
			(layer "F.Fab")
		)
		(fp_line
			(start -0.8636 -0.4572)
			(end 0.8636 -0.4572)
			(stroke
				(width 0.1)
				(type default)
			)
			(layer "F.Fab")
		)
		(fp_line
			(start -0.8636 -0.406654)
			(end -0.8636 -0.4572)
			(stroke
				(width 0.1)
				(type default)
			)
			(layer "F.Fab")
		)
		(fp_line
			(start -0.8636 0.4064)
			(end -1.1938 0.4064)
			(stroke
				(width 0.1)
				(type default)
			)
			(layer "F.Fab")
		)
		(fp_line
			(start -0.8636 0.4318)
			(end -0.8636 0.4064)
			(stroke
				(width 0.1)
				(type default)
			)
			(layer "F.Fab")
		)
		(fp_line
			(start -0.8636 0.4572)
			(end -0.8636 0.4318)
			(stroke
				(width 0.1)
				(type default)
			)
			(layer "F.Fab")
		)
		(fp_line
			(start 0.8636 -0.4572)
			(end 0.8636 -0.406654)
			(stroke
				(width 0.1)
				(type default)
			)
			(layer "F.Fab")
		)
		(fp_line
			(start 0.8636 -0.406654)
			(end 1.1938 -0.406654)
			(stroke
				(width 0.1)
				(type default)
			)
			(layer "F.Fab")
		)
		(fp_line
			(start 0.8636 0.4064)
			(end 0.8636 0.4572)
			(stroke
				(width 0.1)
				(type default)
			)
			(layer "F.Fab")
		)
		(fp_line
			(start 0.8636 0.4572)
			(end -0.8636 0.4572)
			(stroke
				(width 0.1)
				(type default)
			)
			(layer "F.Fab")
		)
		(fp_line
			(start 1.1938 -0.406654)
			(end 1.1938 0.4064)
			(stroke
				(width 0.1)
				(type default)
			)
			(layer "F.Fab")
		)
		(fp_line
			(start 1.1938 0.4064)
			(end 0.8636 0.4064)
			(stroke
				(width 0.1)
				(type default)
			)
			(layer "F.Fab")
		)
		(pad "1" smd rect
			(at -0.7366 0 270)
			(size 0.7112 0.8128)
			(layers "F.Cu" "F.Mask" "F.Paste")
			(net "P3V3_9ZXL045_P1")
		)
		(pad "2" smd rect
			(at 0.7366 0 270)
			(size 0.7112 0.8128)
			(layers "F.Cu" "F.Mask" "F.Paste")
			(net "P3V3_9ZXL045_P1_VDDA")
		)
	)
	(footprint ""
		(layer "F.Cu")
		(at 319.242186 -361.061 90)
		(property "Reference" "PR53"
			(at 0 0 90)
			(layer "F.SilkS")
			(hide yes)
			(effects
				(font
					(size 1.27 1.27)
				)
			)
		)
		(property "Value" ""
			(at 0 0 90)
			(layer "F.Fab")
			(effects
				(font
					(size 1.27 1.27)
				)
			)
		)
		(duplicate_pad_numbers_are_jumpers no)
		(fp_line
			(start 0.7874 -0.4064)
			(end 0.7874 0.4064)
			(stroke
				(width 0.1524)
				(type default)
			)
			(layer "F.SilkS")
		)
		(fp_line
			(start -0.7874 -0.4064)
			(end 0.7874 -0.4064)
			(stroke
				(width 0.1524)
				(type default)
			)
			(layer "F.SilkS")
		)
		(fp_line
			(start 0.7874 0.4064)
			(end -0.7874 0.4064)
			(stroke
				(width 0.1524)
				(type default)
			)
			(layer "F.SilkS")
		)
		(fp_line
			(start -0.7874 0.4064)
			(end -0.7874 -0.4064)
			(stroke
				(width 0.1524)
				(type default)
			)
			(layer "F.SilkS")
		)
		(fp_line
			(start -0.12065 -0.305054)
			(end -0.12065 -0.2794)
			(stroke
				(width 0.1)
				(type default)
			)
			(layer "F.Fab")
		)
		(fp_line
			(start -0.67945 -0.305054)
			(end -0.12065 -0.305054)
			(stroke
				(width 0.1)
				(type default)
			)
			(layer "F.Fab")
		)
		(fp_line
			(start 0.67945 -0.3048)
			(end 0.67945 0.3048)
			(stroke
				(width 0.1)
				(type default)
			)
			(layer "F.Fab")
		)
		(fp_line
			(start 0.12065 -0.3048)
			(end 0.67945 -0.3048)
			(stroke
				(width 0.1)
				(type default)
			)
			(layer "F.Fab")
		)
		(fp_line
			(start 0.12065 -0.2794)
			(end 0.12065 -0.3048)
			(stroke
				(width 0.1)
				(type default)
			)
			(layer "F.Fab")
		)
		(fp_line
			(start -0.12065 -0.2794)
			(end 0.12065 -0.2794)
			(stroke
				(width 0.1)
				(type default)
			)
			(layer "F.Fab")
		)
		(fp_line
			(start 0.120396 0.2794)
			(end -0.12065 0.2794)
			(stroke
				(width 0.1)
				(type default)
			)
			(layer "F.Fab")
		)
		(fp_line
			(start -0.12065 0.2794)
			(end -0.12065 0.3048)
			(stroke
				(width 0.1)
				(type default)
			)
			(layer "F.Fab")
		)
		(fp_line
			(start 0.67945 0.3048)
			(end 0.120396 0.3048)
			(stroke
				(width 0.1)
				(type default)
			)
			(layer "F.Fab")
		)
		(fp_line
			(start 0.120396 0.3048)
			(end 0.120396 0.2794)
			(stroke
				(width 0.1)
				(type default)
			)
			(layer "F.Fab")
		)
		(fp_line
			(start -0.12065 0.3048)
			(end -0.67945 0.3048)
			(stroke
				(width 0.1)
				(type default)
			)
			(layer "F.Fab")
		)
		(fp_line
			(start -0.67945 0.3048)
			(end -0.67945 -0.305054)
			(stroke
				(width 0.1)
				(type default)
			)
			(layer "F.Fab")
		)
		(pad "1" smd circle
			(at -0.40005 0 90)
			(size 0 0)
			(layers "F.Cu" "F.Mask" "F.Paste")
			(net "P5V_AUX")
		)
		(pad "2" smd circle
			(at 0.40005 0 90)
			(size 0 0)
			(layers "F.Cu" "F.Mask" "F.Paste")
			(net "PVDDCR_CPU1_P0_VMON")
		)
	)
	(footprint ""
		(layer "F.Cu")
		(at 453.719946 -106.408728)
		(property "Reference" "R1907"
			(at 0 0 0)
			(layer "F.SilkS")
			(hide yes)
			(effects
				(font
					(size 1.27 1.27)
				)
			)
		)
		(property "Value" ""
			(at 0 0 0)
			(layer "F.Fab")
			(effects
				(font
					(size 1.27 1.27)
				)
			)
		)
		(duplicate_pad_numbers_are_jumpers no)
		(fp_line
			(start -0.7874 -0.4064)
			(end 0.7874 -0.4064)
			(stroke
				(width 0.1524)
				(type default)
			)
			(layer "F.SilkS")
		)
		(fp_line
			(start -0.7874 0.4064)
			(end -0.7874 -0.4064)
			(stroke
				(width 0.1524)
				(type default)
			)
			(layer "F.SilkS")
		)
		(fp_line
			(start 0.7874 -0.4064)
			(end 0.7874 0.4064)
			(stroke
				(width 0.1524)
				(type default)
			)
			(layer "F.SilkS")
		)
		(fp_line
			(start 0.7874 0.4064)
			(end -0.7874 0.4064)
			(stroke
				(width 0.1524)
				(type default)
			)
			(layer "F.SilkS")
		)
		(fp_line
			(start -0.67945 -0.305054)
			(end -0.12065 -0.305054)
			(stroke
				(width 0.1)
				(type default)
			)
			(layer "F.Fab")
		)
		(fp_line
			(start -0.67945 0.3048)
			(end -0.67945 -0.305054)
			(stroke
				(width 0.1)
				(type default)
			)
			(layer "F.Fab")
		)
		(fp_line
			(start -0.12065 -0.305054)
			(end -0.12065 -0.2794)
			(stroke
				(width 0.1)
				(type default)
			)
			(layer "F.Fab")
		)
		(fp_line
			(start -0.12065 -0.2794)
			(end 0.12065 -0.2794)
			(stroke
				(width 0.1)
				(type default)
			)
			(layer "F.Fab")
		)
		(fp_line
			(start -0.12065 0.2794)
			(end -0.12065 0.3048)
			(stroke
				(width 0.1)
				(type default)
			)
			(layer "F.Fab")
		)
		(fp_line
			(start -0.12065 0.3048)
			(end -0.67945 0.3048)
			(stroke
				(width 0.1)
				(type default)
			)
			(layer "F.Fab")
		)
		(fp_line
			(start 0.120396 0.2794)
			(end -0.12065 0.2794)
			(stroke
				(width 0.1)
				(type default)
			)
			(layer "F.Fab")
		)
		(fp_line
			(start 0.120396 0.3048)
			(end 0.120396 0.2794)
			(stroke
				(width 0.1)
				(type default)
			)
			(layer "F.Fab")
		)
		(fp_line
			(start 0.12065 -0.3048)
			(end 0.67945 -0.3048)
			(stroke
				(width 0.1)
				(type default)
			)
			(layer "F.Fab")
		)
		(fp_line
			(start 0.12065 -0.2794)
			(end 0.12065 -0.3048)
			(stroke
				(width 0.1)
				(type default)
			)
			(layer "F.Fab")
		)
		(fp_line
			(start 0.67945 -0.3048)
			(end 0.67945 0.3048)
			(stroke
				(width 0.1)
				(type default)
			)
			(layer "F.Fab")
		)
		(fp_line
			(start 0.67945 0.3048)
			(end 0.120396 0.3048)
			(stroke
				(width 0.1)
				(type default)
			)
			(layer "F.Fab")
		)
		(pad "1" smd circle
			(at -0.40005 0)
			(size 0 0)
			(layers "F.Cu" "F.Mask" "F.Paste")
			(net "P3V3_AUX")
		)
		(pad "2" smd circle
			(at 0.40005 0)
			(size 0 0)
			(layers "F.Cu" "F.Mask" "F.Paste")
			(net "OCP_SFF_PRSNT1_R_N")
		)
	)
	(footprint ""
		(layer "F.Cu")
		(at 447.052954 -401.785328 -90)
		(property "Reference" "PC6563"
			(at 0 0 270)
			(layer "F.SilkS")
			(hide yes)
			(effects
				(font
					(size 1.27 1.27)
				)
			)
		)
		(property "Value" ""
			(at 0 0 270)
			(layer "F.Fab")
			(effects
				(font
					(size 1.27 1.27)
				)
			)
		)
		(duplicate_pad_numbers_are_jumpers no)
		(fp_line
			(start -0.7874 0.4064)
			(end -0.7874 -0.4064)
			(stroke
				(width 0.1524)
				(type default)
			)
			(layer "F.SilkS")
		)
		(fp_line
			(start 0.7874 0.4064)
			(end -0.7874 0.4064)
			(stroke
				(width 0.1524)
				(type default)
			)
			(layer "F.SilkS")
		)
		(fp_line
			(start -0.7874 -0.4064)
			(end 0.7874 -0.4064)
			(stroke
				(width 0.1524)
				(type default)
			)
			(layer "F.SilkS")
		)
		(fp_line
			(start 0.7874 -0.4064)
			(end 0.7874 0.4064)
			(stroke
				(width 0.1524)
				(type default)
			)
			(layer "F.SilkS")
		)
		(fp_line
			(start -0.67945 0.3048)
			(end -0.67945 -0.305054)
			(stroke
				(width 0.1)
				(type default)
			)
			(layer "F.Fab")
		)
		(fp_line
			(start -0.12065 0.3048)
			(end -0.67945 0.3048)
			(stroke
				(width 0.1)
				(type default)
			)
			(layer "F.Fab")
		)
		(fp_line
			(start 0.120396 0.3048)
			(end 0.120396 0.2794)
			(stroke
				(width 0.1)
				(type default)
			)
			(layer "F.Fab")
		)
		(fp_line
			(start 0.67945 0.3048)
			(end 0.120396 0.3048)
			(stroke
				(width 0.1)
				(type default)
			)
			(layer "F.Fab")
		)
		(fp_line
			(start -0.12065 0.2794)
			(end -0.12065 0.3048)
			(stroke
				(width 0.1)
				(type default)
			)
			(layer "F.Fab")
		)
		(fp_line
			(start 0.120396 0.2794)
			(end -0.12065 0.2794)
			(stroke
				(width 0.1)
				(type default)
			)
			(layer "F.Fab")
		)
		(fp_line
			(start -0.12065 -0.2794)
			(end 0.12065 -0.2794)
			(stroke
				(width 0.1)
				(type default)
			)
			(layer "F.Fab")
		)
		(fp_line
			(start 0.12065 -0.2794)
			(end 0.12065 -0.3048)
			(stroke
				(width 0.1)
				(type default)
			)
			(layer "F.Fab")
		)
		(fp_line
			(start 0.12065 -0.3048)
			(end 0.67945 -0.3048)
			(stroke
				(width 0.1)
				(type default)
			)
			(layer "F.Fab")
		)
		(fp_line
			(start 0.67945 -0.3048)
			(end 0.67945 0.3048)
			(stroke
				(width 0.1)
				(type default)
			)
			(layer "F.Fab")
		)
		(fp_line
			(start -0.67945 -0.305054)
			(end -0.12065 -0.305054)
			(stroke
				(width 0.1)
				(type default)
			)
			(layer "F.Fab")
		)
		(fp_line
			(start -0.12065 -0.305054)
			(end -0.12065 -0.2794)
			(stroke
				(width 0.1)
				(type default)
			)
			(layer "F.Fab")
		)
		(pad "1" smd circle
			(at -0.40005 0 270)
			(size 0 0)
			(layers "F.Cu" "F.Mask" "F.Paste")
			(net "SW_P0V9_RETIMER_CPU0_BOOT1_RC")
		)
		(pad "2" smd circle
			(at 0.40005 0 270)
			(size 0 0)
			(layers "F.Cu" "F.Mask" "F.Paste")
			(net "SW_P0V9_RETIMER_CPU0_PH1")
		)
	)
	(footprint ""
		(layer "F.Cu")
		(at 219.61475 -347.604588 180)
		(property "Reference" ""
			(at 0 0 180)
			(layer "F.SilkS")
			(hide yes)
			(effects
				(font
					(size 1.27 1.27)
				)
			)
		)
		(property "Value" ""
			(at 0 0 180)
			(layer "F.Fab")
			(effects
				(font
					(size 1.27 1.27)
				)
			)
		)
		(duplicate_pad_numbers_are_jumpers no)
		(pad "1" smd circle
			(at 0 0 180)
			(size 0.9906 0.9906)
			(layers "F.Cu" "F.Mask" "F.Paste")
			(net "Net_48")
		)
		(zone
			(layer "F.Cu")
			(hatch none 0.5)
			(connect_pads
				(clearance 0)
			)
			(min_thickness 0.25)
			(keepout
				(tracks not_allowed)
				(vias allowed)
				(pads allowed)
				(copperpour not_allowed)
				(footprints allowed)
			)
			(placement
				(enabled no)
				(sheetname "")
			)
			(fill
				(thermal_gap 0.5)
				(thermal_bridge_width 0.5)
				(island_removal_mode 0)
			)
			(polygon
				(pts
					(arc
						(start 221.24035 -347.604588)
						(mid 217.98915 -347.604588)
						(end 221.24035 -347.604588)
					)
				)
			)
		)
	)
	(footprint ""
		(layer "F.Cu")
		(at 192.599818 -70.185788)
		(property "Reference" "PR3947"
			(at 0 0 0)
			(layer "F.SilkS")
			(hide yes)
			(effects
				(font
					(size 1.27 1.27)
				)
			)
		)
		(property "Value" ""
			(at 0 0 0)
			(layer "F.Fab")
			(effects
				(font
					(size 1.27 1.27)
				)
			)
		)
		(duplicate_pad_numbers_are_jumpers no)
		(fp_line
			(start -0.7874 -0.4064)
			(end 0.7874 -0.4064)
			(stroke
				(width 0.1524)
				(type default)
			)
			(layer "F.SilkS")
		)
		(fp_line
			(start -0.7874 0.4064)
			(end -0.7874 -0.4064)
			(stroke
				(width 0.1524)
				(type default)
			)
			(layer "F.SilkS")
		)
		(fp_line
			(start 0.7874 -0.4064)
			(end 0.7874 0.4064)
			(stroke
				(width 0.1524)
				(type default)
			)
			(layer "F.SilkS")
		)
		(fp_line
			(start 0.7874 0.4064)
			(end -0.7874 0.4064)
			(stroke
				(width 0.1524)
				(type default)
			)
			(layer "F.SilkS")
		)
		(fp_line
			(start -0.67945 -0.305054)
			(end -0.12065 -0.305054)
			(stroke
				(width 0.1)
				(type default)
			)
			(layer "F.Fab")
		)
		(fp_line
			(start -0.67945 0.3048)
			(end -0.67945 -0.305054)
			(stroke
				(width 0.1)
				(type default)
			)
			(layer "F.Fab")
		)
		(fp_line
			(start -0.12065 -0.305054)
			(end -0.12065 -0.2794)
			(stroke
				(width 0.1)
				(type default)
			)
			(layer "F.Fab")
		)
		(fp_line
			(start -0.12065 -0.2794)
			(end 0.12065 -0.2794)
			(stroke
				(width 0.1)
				(type default)
			)
			(layer "F.Fab")
		)
		(fp_line
			(start -0.12065 0.2794)
			(end -0.12065 0.3048)
			(stroke
				(width 0.1)
				(type default)
			)
			(layer "F.Fab")
		)
		(fp_line
			(start -0.12065 0.3048)
			(end -0.67945 0.3048)
			(stroke
				(width 0.1)
				(type default)
			)
			(layer "F.Fab")
		)
		(fp_line
			(start 0.120396 0.2794)
			(end -0.12065 0.2794)
			(stroke
				(width 0.1)
				(type default)
			)
			(layer "F.Fab")
		)
		(fp_line
			(start 0.120396 0.3048)
			(end 0.120396 0.2794)
			(stroke
				(width 0.1)
				(type default)
			)
			(layer "F.Fab")
		)
		(fp_line
			(start 0.12065 -0.3048)
			(end 0.67945 -0.3048)
			(stroke
				(width 0.1)
				(type default)
			)
			(layer "F.Fab")
		)
		(fp_line
			(start 0.12065 -0.2794)
			(end 0.12065 -0.3048)
			(stroke
				(width 0.1)
				(type default)
			)
			(layer "F.Fab")
		)
		(fp_line
			(start 0.67945 -0.3048)
			(end 0.67945 0.3048)
			(stroke
				(width 0.1)
				(type default)
			)
			(layer "F.Fab")
		)
		(fp_line
			(start 0.67945 0.3048)
			(end 0.120396 0.3048)
			(stroke
				(width 0.1)
				(type default)
			)
			(layer "F.Fab")
		)
		(pad "1" smd circle
			(at -0.40005 0)
			(size 0 0)
			(layers "F.Cu" "F.Mask" "F.Paste")
			(net "GND")
		)
		(pad "2" smd circle
			(at 0.40005 0)
			(size 0 0)
			(layers "F.Cu" "F.Mask" "F.Paste")
			(net "P3V3_E1S_ILIMIT_0")
		)
	)
	(footprint ""
		(layer "F.Cu")
		(at 197.269608 -111.593376 180)
		(property "Reference" "R177"
			(at 0 0 180)
			(layer "F.SilkS")
			(hide yes)
			(effects
				(font
					(size 1.27 1.27)
				)
			)
		)
		(property "Value" ""
			(at 0 0 180)
			(layer "F.Fab")
			(effects
				(font
					(size 1.27 1.27)
				)
			)
		)
		(duplicate_pad_numbers_are_jumpers no)
		(fp_line
			(start 0.7874 0.4064)
			(end -0.7874 0.4064)
			(stroke
				(width 0.1524)
				(type default)
			)
			(layer "F.SilkS")
		)
		(fp_line
			(start 0.7874 -0.4064)
			(end 0.7874 0.4064)
			(stroke
				(width 0.1524)
				(type default)
			)
			(layer "F.SilkS")
		)
		(fp_line
			(start -0.7874 0.4064)
			(end -0.7874 -0.4064)
			(stroke
				(width 0.1524)
				(type default)
			)
			(layer "F.SilkS")
		)
		(fp_line
			(start -0.7874 -0.4064)
			(end 0.7874 -0.4064)
			(stroke
				(width 0.1524)
				(type default)
			)
			(layer "F.SilkS")
		)
		(fp_line
			(start 0.67945 0.3048)
			(end 0.120396 0.3048)
			(stroke
				(width 0.1)
				(type default)
			)
			(layer "F.Fab")
		)
		(fp_line
			(start 0.67945 -0.3048)
			(end 0.67945 0.3048)
			(stroke
				(width 0.1)
				(type default)
			)
			(layer "F.Fab")
		)
		(fp_line
			(start 0.12065 -0.2794)
			(end 0.12065 -0.3048)
			(stroke
				(width 0.1)
				(type default)
			)
			(layer "F.Fab")
		)
		(fp_line
			(start 0.12065 -0.3048)
			(end 0.67945 -0.3048)
			(stroke
				(width 0.1)
				(type default)
			)
			(layer "F.Fab")
		)
		(fp_line
			(start 0.120396 0.3048)
			(end 0.120396 0.2794)
			(stroke
				(width 0.1)
				(type default)
			)
			(layer "F.Fab")
		)
		(fp_line
			(start 0.120396 0.2794)
			(end -0.12065 0.2794)
			(stroke
				(width 0.1)
				(type default)
			)
			(layer "F.Fab")
		)
		(fp_line
			(start -0.12065 0.3048)
			(end -0.67945 0.3048)
			(stroke
				(width 0.1)
				(type default)
			)
			(layer "F.Fab")
		)
		(fp_line
			(start -0.12065 0.2794)
			(end -0.12065 0.3048)
			(stroke
				(width 0.1)
				(type default)
			)
			(layer "F.Fab")
		)
		(fp_line
			(start -0.12065 -0.2794)
			(end 0.12065 -0.2794)
			(stroke
				(width 0.1)
				(type default)
			)
			(layer "F.Fab")
		)
		(fp_line
			(start -0.12065 -0.305054)
			(end -0.12065 -0.2794)
			(stroke
				(width 0.1)
				(type default)
			)
			(layer "F.Fab")
		)
		(fp_line
			(start -0.67945 0.3048)
			(end -0.67945 -0.305054)
			(stroke
				(width 0.1)
				(type default)
			)
			(layer "F.Fab")
		)
		(fp_line
			(start -0.67945 -0.305054)
			(end -0.12065 -0.305054)
			(stroke
				(width 0.1)
				(type default)
			)
			(layer "F.Fab")
		)
		(pad "1" smd circle
			(at -0.40005 0 180)
			(size 0 0)
			(layers "F.Cu" "F.Mask" "F.Paste")
			(net "PWRGD_PVDD18_S5_P0")
		)
		(pad "2" smd circle
			(at 0.40005 0 180)
			(size 0 0)
			(layers "F.Cu" "F.Mask" "F.Paste")
			(net "FM_PWRGD_PVDD18_S5_P0")
		)
	)
	(footprint ""
		(layer "F.Cu")
		(at 77.915262 -30.112462 -90)
		(property "Reference" "PD107"
			(at 2.145792 -2.517648 90)
			(unlocked yes)
			(layer "F.SilkS")
			(effects
				(font
					(size 0.7874 0.5842)
					(thickness 0.1524)
				)
				(justify left)
			)
		)
		(property "Value" ""
			(at 0 0 270)
			(layer "F.Fab")
			(effects
				(font
					(size 1.27 1.27)
				)
			)
		)
		(duplicate_pad_numbers_are_jumpers no)
		(fp_line
			(start -2.250186 0.999998)
			(end 2.631186 0.999998)
			(stroke
				(width 0.1524)
				(type default)
			)
			(layer "F.SilkS")
		)
		(fp_line
			(start 2.631186 0.999998)
			(end 2.631186 -0.999998)
			(stroke
				(width 0.1524)
				(type default)
			)
			(layer "F.SilkS")
		)
		(fp_line
			(start -0.381 0.3302)
			(end -0.381 -0.4318)
			(stroke
				(width 0.1524)
				(type default)
			)
			(layer "F.SilkS")
		)
		(fp_line
			(start -0.381 -0.0508)
			(end -0.6604 -0.0508)
			(stroke
				(width 0.1524)
				(type default)
			)
			(layer "F.SilkS")
		)
		(fp_line
			(start 0.381 -0.0508)
			(end -0.381 0.3302)
			(stroke
				(width 0.1524)
				(type default)
			)
			(layer "F.SilkS")
		)
		(fp_line
			(start 0.381 -0.0508)
			(end 0.635 -0.0508)
			(stroke
				(width 0.1524)
				(type default)
			)
			(layer "F.SilkS")
		)
		(fp_line
			(start -0.381 -0.4318)
			(end 0.381 -0.0508)
			(stroke
				(width 0.1524)
				(type default)
			)
			(layer "F.SilkS")
		)
		(fp_line
			(start 0.381 -0.4318)
			(end 0.381 0.3302)
			(stroke
				(width 0.1524)
				(type default)
			)
			(layer "F.SilkS")
		)
		(fp_line
			(start -2.250186 -0.999998)
			(end -2.250186 0.999998)
			(stroke
				(width 0.1524)
				(type default)
			)
			(layer "F.SilkS")
		)
		(fp_line
			(start 2.631186 -0.999998)
			(end -2.250186 -0.999998)
			(stroke
				(width 0.1524)
				(type default)
			)
			(layer "F.SilkS")
		)
		(fp_rect
			(start 2.6162 1.016)
			(end 2.1844 -0.9652)
			(stroke
				(width 0)
				(type default)
			)
			(fill yes)
			(layer "F.SilkS")
		)
		(fp_line
			(start -1.450086 0.999998)
			(end 1.450086 0.999998)
			(stroke
				(width 0.1)
				(type default)
			)
			(layer "F.Fab")
		)
		(fp_line
			(start 1.450086 0.999998)
			(end 1.450086 -0.999998)
			(stroke
				(width 0.1)
				(type default)
			)
			(layer "F.Fab")
		)
		(fp_line
			(start -1.450086 -0.999998)
			(end -1.450086 0.999998)
			(stroke
				(width 0.1)
				(type default)
			)
			(layer "F.Fab")
		)
		(fp_line
			(start 1.450086 -0.999998)
			(end -1.450086 -0.999998)
			(stroke
				(width 0.1)
				(type default)
			)
			(layer "F.Fab")
		)
		(fp_text user "+"
			(at -3.849878 -0.100584 270)
			(unlocked yes)
			(layer "F.SilkS")
			(effects
				(font
					(size 1.905 1.4224)
					(thickness 0.1524)
				)
				(justify left)
			)
		)
		(fp_text user "-"
			(at 2.4384 -0.22225 270)
			(unlocked yes)
			(layer "F.SilkS")
			(effects
				(font
					(size 1.905 1.4224)
					(thickness 0.1524)
				)
				(justify left)
			)
		)
		(fp_text user "+"
			(at -3.4798 -0.22225 270)
			(unlocked yes)
			(layer "F.Fab")
			(effects
				(font
					(size 1.905 1.4224)
					(thickness 0.1524)
				)
				(justify left)
			)
		)
		(fp_text user "-"
			(at 2.4384 -0.22225 270)
			(unlocked yes)
			(layer "F.Fab")
			(effects
				(font
					(size 1.905 1.4224)
					(thickness 0.1524)
				)
				(justify left)
			)
		)
		(pad "A" smd rect
			(at -1.450086 0 270)
			(size 1.3208 1.4224)
			(layers "F.Cu" "F.Mask" "F.Paste")
			(net "GND")
		)
		(pad "C" smd rect
			(at 1.450086 0 270)
			(size 1.3208 1.4224)
			(layers "F.Cu" "F.Mask" "F.Paste")
			(net "P12V_AUX")
		)
	)
	(footprint ""
		(layer "F.Cu")
		(at 381.762 -103.378)
		(property "Reference" "ME15"
			(at 0 0 0)
			(layer "F.SilkS")
			(hide yes)
			(effects
				(font
					(size 1.27 1.27)
				)
			)
		)
		(property "Value" ""
			(at 0 0 0)
			(layer "F.Fab")
			(effects
				(font
					(size 1.27 1.27)
				)
			)
		)
		(duplicate_pad_numbers_are_jumpers no)
		(zone
			(layer "F.Cu")
			(hatch none 0.5)
			(connect_pads
				(clearance 0)
			)
			(min_thickness 0.25)
			(keepout
				(tracks allowed)
				(vias allowed)
				(pads allowed)
				(copperpour allowed)
				(footprints not_allowed)
			)
			(placement
				(enabled no)
				(sheetname "")
			)
			(fill
				(thermal_gap 0.5)
				(thermal_bridge_width 0.5)
				(island_removal_mode 0)
			)
			(polygon
				(pts
					(arc
						(start 391.76198 -103.378)
						(mid 371.76202 -103.378)
						(end 391.76198 -103.378)
					)
				)
			)
		)
	)
	(footprint ""
		(layer "F.Cu")
		(at 448.980052 -18.063464 -90)
		(property "Reference" "PR3787"
			(at 0 0 270)
			(layer "F.SilkS")
			(hide yes)
			(effects
				(font
					(size 1.27 1.27)
				)
			)
		)
		(property "Value" ""
			(at 0 0 270)
			(layer "F.Fab")
			(effects
				(font
					(size 1.27 1.27)
				)
			)
		)
		(duplicate_pad_numbers_are_jumpers no)
		(fp_line
			(start -0.7874 0.4064)
			(end -0.7874 -0.4064)
			(stroke
				(width 0.1524)
				(type default)
			)
			(layer "F.SilkS")
		)
		(fp_line
			(start 0.7874 0.4064)
			(end -0.7874 0.4064)
			(stroke
				(width 0.1524)
				(type default)
			)
			(layer "F.SilkS")
		)
		(fp_line
			(start -0.7874 -0.4064)
			(end 0.7874 -0.4064)
			(stroke
				(width 0.1524)
				(type default)
			)
			(layer "F.SilkS")
		)
		(fp_line
			(start 0.7874 -0.4064)
			(end 0.7874 0.4064)
			(stroke
				(width 0.1524)
				(type default)
			)
			(layer "F.SilkS")
		)
		(fp_line
			(start -0.67945 0.3048)
			(end -0.67945 -0.305054)
			(stroke
				(width 0.1)
				(type default)
			)
			(layer "F.Fab")
		)
		(fp_line
			(start -0.12065 0.3048)
			(end -0.67945 0.3048)
			(stroke
				(width 0.1)
				(type default)
			)
			(layer "F.Fab")
		)
		(fp_line
			(start 0.120396 0.3048)
			(end 0.120396 0.2794)
			(stroke
				(width 0.1)
				(type default)
			)
			(layer "F.Fab")
		)
		(fp_line
			(start 0.67945 0.3048)
			(end 0.120396 0.3048)
			(stroke
				(width 0.1)
				(type default)
			)
			(layer "F.Fab")
		)
		(fp_line
			(start -0.12065 0.2794)
			(end -0.12065 0.3048)
			(stroke
				(width 0.1)
				(type default)
			)
			(layer "F.Fab")
		)
		(fp_line
			(start 0.120396 0.2794)
			(end -0.12065 0.2794)
			(stroke
				(width 0.1)
				(type default)
			)
			(layer "F.Fab")
		)
		(fp_line
			(start -0.12065 -0.2794)
			(end 0.12065 -0.2794)
			(stroke
				(width 0.1)
				(type default)
			)
			(layer "F.Fab")
		)
		(fp_line
			(start 0.12065 -0.2794)
			(end 0.12065 -0.3048)
			(stroke
				(width 0.1)
				(type default)
			)
			(layer "F.Fab")
		)
		(fp_line
			(start 0.12065 -0.3048)
			(end 0.67945 -0.3048)
			(stroke
				(width 0.1)
				(type default)
			)
			(layer "F.Fab")
		)
		(fp_line
			(start 0.67945 -0.3048)
			(end 0.67945 0.3048)
			(stroke
				(width 0.1)
				(type default)
			)
			(layer "F.Fab")
		)
		(fp_line
			(start -0.67945 -0.305054)
			(end -0.12065 -0.305054)
			(stroke
				(width 0.1)
				(type default)
			)
			(layer "F.Fab")
		)
		(fp_line
			(start -0.12065 -0.305054)
			(end -0.12065 -0.2794)
			(stroke
				(width 0.1)
				(type default)
			)
			(layer "F.Fab")
		)
		(pad "1" smd circle
			(at -0.40005 0 270)
			(size 0 0)
			(layers "F.Cu" "F.Mask" "F.Paste")
			(net "P12V_OCP_UV_1")
		)
		(pad "2" smd circle
			(at 0.40005 0 270)
			(size 0 0)
			(layers "F.Cu" "F.Mask" "F.Paste")
			(net "P12V_OCP_OV_1")
		)
	)
	(footprint ""
		(layer "F.Cu")
		(at 364.84179 -392.1252)
		(property "Reference" "R1119"
			(at 0 0 0)
			(layer "F.SilkS")
			(hide yes)
			(effects
				(font
					(size 1.27 1.27)
				)
			)
		)
		(property "Value" ""
			(at 0 0 0)
			(layer "F.Fab")
			(effects
				(font
					(size 1.27 1.27)
				)
			)
		)
		(duplicate_pad_numbers_are_jumpers no)
		(fp_line
			(start -0.32512 -0.175006)
			(end 0.32512 -0.175006)
			(stroke
				(width 0.1)
				(type default)
			)
			(layer "F.Fab")
		)
		(fp_line
			(start -0.32512 0.175006)
			(end -0.32512 -0.175006)
			(stroke
				(width 0.1)
				(type default)
			)
			(layer "F.Fab")
		)
		(fp_line
			(start 0.32512 -0.175006)
			(end 0.32512 0.175006)
			(stroke
				(width 0.1)
				(type default)
			)
			(layer "F.Fab")
		)
		(fp_line
			(start 0.32512 0.175006)
			(end -0.32512 0.175006)
			(stroke
				(width 0.1)
				(type default)
			)
			(layer "F.Fab")
		)
		(pad "1" smd rect
			(at -0.2667 0)
			(size 0.3048 0.381)
			(layers "F.Cu" "F.Mask" "F.Paste")
			(net "P1V8_CPU0_RT_1D")
		)
		(pad "2" smd rect
			(at 0.2667 0 180)
			(size 0.3048 0.381)
			(layers "F.Cu" "F.Mask" "F.Paste")
			(net "TEST2_RT_CPU0_P3")
		)
	)
	(footprint ""
		(layer "F.Cu")
		(at 369.687094 -403.603206 -90)
		(property "Reference" "R1121"
			(at 0 0 270)
			(layer "F.SilkS")
			(hide yes)
			(effects
				(font
					(size 1.27 1.27)
				)
			)
		)
		(property "Value" ""
			(at 0 0 270)
			(layer "F.Fab")
			(effects
				(font
					(size 1.27 1.27)
				)
			)
		)
		(duplicate_pad_numbers_are_jumpers no)
		(fp_line
			(start -0.32512 0.175006)
			(end -0.32512 -0.175006)
			(stroke
				(width 0.1)
				(type default)
			)
			(layer "F.Fab")
		)
		(fp_line
			(start 0.32512 0.175006)
			(end -0.32512 0.175006)
			(stroke
				(width 0.1)
				(type default)
			)
			(layer "F.Fab")
		)
		(fp_line
			(start -0.32512 -0.175006)
			(end 0.32512 -0.175006)
			(stroke
				(width 0.1)
				(type default)
			)
			(layer "F.Fab")
		)
		(fp_line
			(start 0.32512 -0.175006)
			(end 0.32512 0.175006)
			(stroke
				(width 0.1)
				(type default)
			)
			(layer "F.Fab")
		)
		(pad "1" smd rect
			(at -0.2667 0 270)
			(size 0.3048 0.381)
			(layers "F.Cu" "F.Mask" "F.Paste")
			(net "JTAG_TEST_MODE_RT_CPU0_P3")
		)
		(pad "2" smd rect
			(at 0.2667 0 90)
			(size 0.3048 0.381)
			(layers "F.Cu" "F.Mask" "F.Paste")
			(net "GND")
		)
	)
	(footprint ""
		(layer "F.Cu")
		(at 311.541922 -32.572706)
		(property "Reference" "R3859"
			(at 0 0 0)
			(layer "F.SilkS")
			(hide yes)
			(effects
				(font
					(size 1.27 1.27)
				)
			)
		)
		(property "Value" ""
			(at 0 0 0)
			(layer "F.Fab")
			(effects
				(font
					(size 1.27 1.27)
				)
			)
		)
		(duplicate_pad_numbers_are_jumpers no)
		(fp_line
			(start -0.7874 -0.4064)
			(end 0.7874 -0.4064)
			(stroke
				(width 0.1524)
				(type default)
			)
			(layer "F.SilkS")
		)
		(fp_line
			(start -0.7874 0.4064)
			(end -0.7874 -0.4064)
			(stroke
				(width 0.1524)
				(type default)
			)
			(layer "F.SilkS")
		)
		(fp_line
			(start 0.7874 -0.4064)
			(end 0.7874 0.4064)
			(stroke
				(width 0.1524)
				(type default)
			)
			(layer "F.SilkS")
		)
		(fp_line
			(start 0.7874 0.4064)
			(end -0.7874 0.4064)
			(stroke
				(width 0.1524)
				(type default)
			)
			(layer "F.SilkS")
		)
		(fp_line
			(start -0.67945 -0.305054)
			(end -0.12065 -0.305054)
			(stroke
				(width 0.1)
				(type default)
			)
			(layer "F.Fab")
		)
		(fp_line
			(start -0.67945 0.3048)
			(end -0.67945 -0.305054)
			(stroke
				(width 0.1)
				(type default)
			)
			(layer "F.Fab")
		)
		(fp_line
			(start -0.12065 -0.305054)
			(end -0.12065 -0.2794)
			(stroke
				(width 0.1)
				(type default)
			)
			(layer "F.Fab")
		)
		(fp_line
			(start -0.12065 -0.2794)
			(end 0.12065 -0.2794)
			(stroke
				(width 0.1)
				(type default)
			)
			(layer "F.Fab")
		)
		(fp_line
			(start -0.12065 0.2794)
			(end -0.12065 0.3048)
			(stroke
				(width 0.1)
				(type default)
			)
			(layer "F.Fab")
		)
		(fp_line
			(start -0.12065 0.3048)
			(end -0.67945 0.3048)
			(stroke
				(width 0.1)
				(type default)
			)
			(layer "F.Fab")
		)
		(fp_line
			(start 0.120396 0.2794)
			(end -0.12065 0.2794)
			(stroke
				(width 0.1)
				(type default)
			)
			(layer "F.Fab")
		)
		(fp_line
			(start 0.120396 0.3048)
			(end 0.120396 0.2794)
			(stroke
				(width 0.1)
				(type default)
			)
			(layer "F.Fab")
		)
		(fp_line
			(start 0.12065 -0.3048)
			(end 0.67945 -0.3048)
			(stroke
				(width 0.1)
				(type default)
			)
			(layer "F.Fab")
		)
		(fp_line
			(start 0.12065 -0.2794)
			(end 0.12065 -0.3048)
			(stroke
				(width 0.1)
				(type default)
			)
			(layer "F.Fab")
		)
		(fp_line
			(start 0.67945 -0.3048)
			(end 0.67945 0.3048)
			(stroke
				(width 0.1)
				(type default)
			)
			(layer "F.Fab")
		)
		(fp_line
			(start 0.67945 0.3048)
			(end 0.120396 0.3048)
			(stroke
				(width 0.1)
				(type default)
			)
			(layer "F.Fab")
		)
		(pad "1" smd rect
			(at -0.40005 0 180)
			(size 0.4572 0.508)
			(layers "F.Cu" "F.Mask" "F.Paste")
			(net "P12V_OCP_V3_2_ISENSE_MAM_MAM")
		)
		(pad "2" smd rect
			(at 0.40005 0 180)
			(size 0.4572 0.508)
			(layers "F.Cu" "F.Mask" "F.Paste")
			(net "P12V_OCP_V3_2_ISENSE_MAM")
		)
	)
	(footprint ""
		(layer "F.Cu")
		(at 165.655244 -370.57203 -90)
		(property "Reference" "C748"
			(at 0 0 270)
			(layer "F.SilkS")
			(hide yes)
			(effects
				(font
					(size 1.27 1.27)
				)
			)
		)
		(property "Value" ""
			(at 0 0 270)
			(layer "F.Fab")
			(effects
				(font
					(size 1.27 1.27)
				)
			)
		)
		(duplicate_pad_numbers_are_jumpers no)
		(fp_line
			(start -0.299974 0.150114)
			(end -0.299974 -0.150114)
			(stroke
				(width 0.1)
				(type default)
			)
			(layer "F.Fab")
		)
		(fp_line
			(start 0.299974 0.150114)
			(end -0.299974 0.150114)
			(stroke
				(width 0.1)
				(type default)
			)
			(layer "F.Fab")
		)
		(fp_line
			(start -0.299974 -0.150114)
			(end 0.299974 -0.150114)
			(stroke
				(width 0.1)
				(type default)
			)
			(layer "F.Fab")
		)
		(fp_line
			(start 0.299974 -0.150114)
			(end 0.299974 0.150114)
			(stroke
				(width 0.1)
				(type default)
			)
			(layer "F.Fab")
		)
		(pad "1" smd rect
			(at -0.2667 0 270)
			(size 0.3048 0.381)
			(layers "F.Cu" "F.Mask" "F.Paste")
			(net "P5E_CPU1_P2_TX_C_DN<12>")
		)
		(pad "2" smd rect
			(at 0.2667 0 270)
			(size 0.3048 0.381)
			(layers "F.Cu" "F.Mask" "F.Paste")
			(net "P5E_CPU1_P2_TX_DN<12>")
		)
	)
	(footprint ""
		(layer "F.Cu")
		(at 70.992746 -386.44068 90)
		(property "Reference" "C115"
			(at 0 0 90)
			(layer "F.SilkS")
			(hide yes)
			(effects
				(font
					(size 1.27 1.27)
				)
			)
		)
		(property "Value" ""
			(at 0 0 90)
			(layer "F.Fab")
			(effects
				(font
					(size 1.27 1.27)
				)
			)
		)
		(duplicate_pad_numbers_are_jumpers no)
		(fp_line
			(start 0.7874 -0.4064)
			(end 0.7874 0.4064)
			(stroke
				(width 0.1524)
				(type default)
			)
			(layer "F.SilkS")
		)
		(fp_line
			(start -0.7874 -0.4064)
			(end 0.7874 -0.4064)
			(stroke
				(width 0.1524)
				(type default)
			)
			(layer "F.SilkS")
		)
		(fp_line
			(start 0.7874 0.4064)
			(end -0.7874 0.4064)
			(stroke
				(width 0.1524)
				(type default)
			)
			(layer "F.SilkS")
		)
		(fp_line
			(start -0.7874 0.4064)
			(end -0.7874 -0.4064)
			(stroke
				(width 0.1524)
				(type default)
			)
			(layer "F.SilkS")
		)
		(fp_line
			(start -0.12065 -0.305054)
			(end -0.12065 -0.2794)
			(stroke
				(width 0.1)
				(type default)
			)
			(layer "F.Fab")
		)
		(fp_line
			(start -0.67945 -0.305054)
			(end -0.12065 -0.305054)
			(stroke
				(width 0.1)
				(type default)
			)
			(layer "F.Fab")
		)
		(fp_line
			(start 0.67945 -0.3048)
			(end 0.67945 0.3048)
			(stroke
				(width 0.1)
				(type default)
			)
			(layer "F.Fab")
		)
		(fp_line
			(start 0.12065 -0.3048)
			(end 0.67945 -0.3048)
			(stroke
				(width 0.1)
				(type default)
			)
			(layer "F.Fab")
		)
		(fp_line
			(start 0.12065 -0.2794)
			(end 0.12065 -0.3048)
			(stroke
				(width 0.1)
				(type default)
			)
			(layer "F.Fab")
		)
		(fp_line
			(start -0.12065 -0.2794)
			(end 0.12065 -0.2794)
			(stroke
				(width 0.1)
				(type default)
			)
			(layer "F.Fab")
		)
		(fp_line
			(start 0.120396 0.2794)
			(end -0.12065 0.2794)
			(stroke
				(width 0.1)
				(type default)
			)
			(layer "F.Fab")
		)
		(fp_line
			(start -0.12065 0.2794)
			(end -0.12065 0.3048)
			(stroke
				(width 0.1)
				(type default)
			)
			(layer "F.Fab")
		)
		(fp_line
			(start 0.67945 0.3048)
			(end 0.120396 0.3048)
			(stroke
				(width 0.1)
				(type default)
			)
			(layer "F.Fab")
		)
		(fp_line
			(start 0.120396 0.3048)
			(end 0.120396 0.2794)
			(stroke
				(width 0.1)
				(type default)
			)
			(layer "F.Fab")
		)
		(fp_line
			(start -0.12065 0.3048)
			(end -0.67945 0.3048)
			(stroke
				(width 0.1)
				(type default)
			)
			(layer "F.Fab")
		)
		(fp_line
			(start -0.67945 0.3048)
			(end -0.67945 -0.305054)
			(stroke
				(width 0.1)
				(type default)
			)
			(layer "F.Fab")
		)
		(pad "1" smd circle
			(at -0.40005 0 90)
			(size 0 0)
			(layers "F.Cu" "F.Mask" "F.Paste")
			(net "P1V8_CPU1_RT_1D")
		)
		(pad "2" smd circle
			(at 0.40005 0 90)
			(size 0 0)
			(layers "F.Cu" "F.Mask" "F.Paste")
			(net "GND")
		)
	)
	(footprint ""
		(layer "F.Cu")
		(at 344.067638 -161.056574 90)
		(property "Reference" "PC154_6"
			(at 0 0 90)
			(layer "F.SilkS")
			(hide yes)
			(effects
				(font
					(size 1.27 1.27)
				)
			)
		)
		(property "Value" ""
			(at 0 0 90)
			(layer "F.Fab")
			(effects
				(font
					(size 1.27 1.27)
				)
			)
		)
		(duplicate_pad_numbers_are_jumpers no)
		(fp_line
			(start 0.7874 -0.4064)
			(end 0.7874 0.4064)
			(stroke
				(width 0.1524)
				(type default)
			)
			(layer "F.SilkS")
		)
		(fp_line
			(start -0.7874 -0.4064)
			(end 0.7874 -0.4064)
			(stroke
				(width 0.1524)
				(type default)
			)
			(layer "F.SilkS")
		)
		(fp_line
			(start 0.7874 0.4064)
			(end -0.7874 0.4064)
			(stroke
				(width 0.1524)
				(type default)
			)
			(layer "F.SilkS")
		)
		(fp_line
			(start -0.7874 0.4064)
			(end -0.7874 -0.4064)
			(stroke
				(width 0.1524)
				(type default)
			)
			(layer "F.SilkS")
		)
		(fp_line
			(start -0.12065 -0.305054)
			(end -0.12065 -0.2794)
			(stroke
				(width 0.1)
				(type default)
			)
			(layer "F.Fab")
		)
		(fp_line
			(start -0.67945 -0.305054)
			(end -0.12065 -0.305054)
			(stroke
				(width 0.1)
				(type default)
			)
			(layer "F.Fab")
		)
		(fp_line
			(start 0.67945 -0.3048)
			(end 0.67945 0.3048)
			(stroke
				(width 0.1)
				(type default)
			)
			(layer "F.Fab")
		)
		(fp_line
			(start 0.12065 -0.3048)
			(end 0.67945 -0.3048)
			(stroke
				(width 0.1)
				(type default)
			)
			(layer "F.Fab")
		)
		(fp_line
			(start 0.12065 -0.2794)
			(end 0.12065 -0.3048)
			(stroke
				(width 0.1)
				(type default)
			)
			(layer "F.Fab")
		)
		(fp_line
			(start -0.12065 -0.2794)
			(end 0.12065 -0.2794)
			(stroke
				(width 0.1)
				(type default)
			)
			(layer "F.Fab")
		)
		(fp_line
			(start 0.120396 0.2794)
			(end -0.12065 0.2794)
			(stroke
				(width 0.1)
				(type default)
			)
			(layer "F.Fab")
		)
		(fp_line
			(start -0.12065 0.2794)
			(end -0.12065 0.3048)
			(stroke
				(width 0.1)
				(type default)
			)
			(layer "F.Fab")
		)
		(fp_line
			(start 0.67945 0.3048)
			(end 0.120396 0.3048)
			(stroke
				(width 0.1)
				(type default)
			)
			(layer "F.Fab")
		)
		(fp_line
			(start 0.120396 0.3048)
			(end 0.120396 0.2794)
			(stroke
				(width 0.1)
				(type default)
			)
			(layer "F.Fab")
		)
		(fp_line
			(start -0.12065 0.3048)
			(end -0.67945 0.3048)
			(stroke
				(width 0.1)
				(type default)
			)
			(layer "F.Fab")
		)
		(fp_line
			(start -0.67945 0.3048)
			(end -0.67945 -0.305054)
			(stroke
				(width 0.1)
				(type default)
			)
			(layer "F.Fab")
		)
		(pad "1" smd circle
			(at -0.40005 0 90)
			(size 0 0)
			(layers "F.Cu" "F.Mask" "F.Paste")
			(net "SW_P12V_AUX_PVDDCR_CPU0_P0_FLT")
		)
		(pad "2" smd circle
			(at 0.40005 0 90)
			(size 0 0)
			(layers "F.Cu" "F.Mask" "F.Paste")
			(net "GND")
		)
	)
	(footprint ""
		(layer "F.Cu")
		(at 36.99891 -337.403948)
		(property "Reference" "PL68"
			(at -3.115056 -15.887446 0)
			(unlocked yes)
			(layer "F.SilkS")
			(effects
				(font
					(size 0.7874 0.5842)
					(thickness 0.1524)
				)
				(justify left)
			)
		)
		(property "Value" ""
			(at 0 0 0)
			(layer "F.Fab")
			(effects
				(font
					(size 1.27 1.27)
				)
			)
		)
		(duplicate_pad_numbers_are_jumpers no)
		(fp_line
			(start -3.750056 -5.500116)
			(end -2.393442 -5.500116)
			(stroke
				(width 0.1524)
				(type default)
			)
			(layer "F.SilkS")
		)
		(fp_line
			(start -3.750056 5.500116)
			(end -3.750056 -5.500116)
			(stroke
				(width 0.1524)
				(type default)
			)
			(layer "F.SilkS")
		)
		(fp_line
			(start -2.393442 5.500116)
			(end -3.750056 5.500116)
			(stroke
				(width 0.1524)
				(type default)
			)
			(layer "F.SilkS")
		)
		(fp_line
			(start 2.393442 5.500116)
			(end 3.750056 5.500116)
			(stroke
				(width 0.1524)
				(type default)
			)
			(layer "F.SilkS")
		)
		(fp_line
			(start 3.750056 -5.500116)
			(end 2.393442 -5.500116)
			(stroke
				(width 0.1524)
				(type default)
			)
			(layer "F.SilkS")
		)
		(fp_line
			(start 3.750056 5.500116)
			(end 3.750056 -5.500116)
			(stroke
				(width 0.1524)
				(type default)
			)
			(layer "F.SilkS")
		)
		(fp_poly
			(pts
				(xy -3.9116 -4.249928) (xy -4.35991 -4.0259) (xy -4.35991 -4.473956)
			)
			(stroke
				(width 0)
				(type default)
			)
			(fill yes)
			(layer "F.SilkS")
		)
		(fp_line
			(start -3.750056 -5.500116)
			(end -3.750056 5.500116)
			(stroke
				(width 0.1)
				(type default)
			)
			(layer "F.Fab")
		)
		(fp_line
			(start -3.750056 5.500116)
			(end 3.750056 5.500116)
			(stroke
				(width 0.1)
				(type default)
			)
			(layer "F.Fab")
		)
		(fp_line
			(start 3.750056 -5.500116)
			(end -3.750056 -5.500116)
			(stroke
				(width 0.1)
				(type default)
			)
			(layer "F.Fab")
		)
		(fp_line
			(start 3.750056 5.500116)
			(end 3.750056 -5.500116)
			(stroke
				(width 0.1)
				(type default)
			)
			(layer "F.Fab")
		)
		(fp_poly
			(pts
				(xy -4.9276 -4.757928) (xy -4.9276 -3.741928) (xy -3.9116 -4.249928)
			)
			(stroke
				(width 0)
				(type default)
			)
			(fill yes)
			(layer "F.Fab")
		)
		(pad "1" smd rect
			(at 0 -4.249928 270)
			(size 2.413 4.5212)
			(layers "F.Cu" "F.Mask" "F.Paste")
			(net "SW_PVDDIO_P1_SW3")
		)
		(pad "2" smd rect
			(at 0 -1.175004 270)
			(size 1.3716 4.5212)
			(layers "F.Cu" "F.Mask" "F.Paste")
			(net "IND_PVDDIO_P1_CPL4")
		)
		(pad "3" smd rect
			(at 0 1.175004 270)
			(size 1.3716 4.5212)
			(layers "F.Cu" "F.Mask" "F.Paste")
			(net "IND_PVDDIO_P1_CPL3")
		)
		(pad "4" smd rect
			(at 0 4.249928 270)
			(size 2.413 4.5212)
			(layers "F.Cu" "F.Mask" "F.Paste")
			(net "PVDDIO_P1")
		)
	)
	(footprint ""
		(layer "F.Cu")
		(at 157.692852 -351.247456 180)
		(property "Reference" "C8641"
			(at 0 0 180)
			(layer "F.SilkS")
			(hide yes)
			(effects
				(font
					(size 1.27 1.27)
				)
			)
		)
		(property "Value" ""
			(at 0 0 180)
			(layer "F.Fab")
			(effects
				(font
					(size 1.27 1.27)
				)
			)
		)
		(duplicate_pad_numbers_are_jumpers no)
		(fp_line
			(start 0.7874 0.4064)
			(end -0.7874 0.4064)
			(stroke
				(width 0.1524)
				(type default)
			)
			(layer "F.SilkS")
		)
		(fp_line
			(start 0.7874 -0.4064)
			(end 0.7874 0.4064)
			(stroke
				(width 0.1524)
				(type default)
			)
			(layer "F.SilkS")
		)
		(fp_line
			(start -0.7874 0.4064)
			(end -0.7874 -0.4064)
			(stroke
				(width 0.1524)
				(type default)
			)
			(layer "F.SilkS")
		)
		(fp_line
			(start -0.7874 -0.4064)
			(end 0.7874 -0.4064)
			(stroke
				(width 0.1524)
				(type default)
			)
			(layer "F.SilkS")
		)
		(fp_line
			(start 0.67945 0.3048)
			(end 0.120396 0.3048)
			(stroke
				(width 0.1)
				(type default)
			)
			(layer "F.Fab")
		)
		(fp_line
			(start 0.67945 -0.3048)
			(end 0.67945 0.3048)
			(stroke
				(width 0.1)
				(type default)
			)
			(layer "F.Fab")
		)
		(fp_line
			(start 0.12065 -0.2794)
			(end 0.12065 -0.3048)
			(stroke
				(width 0.1)
				(type default)
			)
			(layer "F.Fab")
		)
		(fp_line
			(start 0.12065 -0.3048)
			(end 0.67945 -0.3048)
			(stroke
				(width 0.1)
				(type default)
			)
			(layer "F.Fab")
		)
		(fp_line
			(start 0.120396 0.3048)
			(end 0.120396 0.2794)
			(stroke
				(width 0.1)
				(type default)
			)
			(layer "F.Fab")
		)
		(fp_line
			(start 0.120396 0.2794)
			(end -0.12065 0.2794)
			(stroke
				(width 0.1)
				(type default)
			)
			(layer "F.Fab")
		)
		(fp_line
			(start -0.12065 0.3048)
			(end -0.67945 0.3048)
			(stroke
				(width 0.1)
				(type default)
			)
			(layer "F.Fab")
		)
		(fp_line
			(start -0.12065 0.2794)
			(end -0.12065 0.3048)
			(stroke
				(width 0.1)
				(type default)
			)
			(layer "F.Fab")
		)
		(fp_line
			(start -0.12065 -0.2794)
			(end 0.12065 -0.2794)
			(stroke
				(width 0.1)
				(type default)
			)
			(layer "F.Fab")
		)
		(fp_line
			(start -0.12065 -0.305054)
			(end -0.12065 -0.2794)
			(stroke
				(width 0.1)
				(type default)
			)
			(layer "F.Fab")
		)
		(fp_line
			(start -0.67945 0.3048)
			(end -0.67945 -0.305054)
			(stroke
				(width 0.1)
				(type default)
			)
			(layer "F.Fab")
		)
		(fp_line
			(start -0.67945 -0.305054)
			(end -0.12065 -0.305054)
			(stroke
				(width 0.1)
				(type default)
			)
			(layer "F.Fab")
		)
		(pad "1" smd circle
			(at -0.40005 0 180)
			(size 0 0)
			(layers "F.Cu" "F.Mask" "F.Paste")
			(net "PWRGD_PVDD11_S3_P1_R")
		)
		(pad "2" smd circle
			(at 0.40005 0 180)
			(size 0 0)
			(layers "F.Cu" "F.Mask" "F.Paste")
			(net "GND")
		)
	)
	(footprint ""
		(layer "F.Cu")
		(at 429.171354 -397.135604)
		(property "Reference" "C669"
			(at 0 0 0)
			(layer "F.SilkS")
			(hide yes)
			(effects
				(font
					(size 1.27 1.27)
				)
			)
		)
		(property "Value" ""
			(at 0 0 0)
			(layer "F.Fab")
			(effects
				(font
					(size 1.27 1.27)
				)
			)
		)
		(duplicate_pad_numbers_are_jumpers no)
		(fp_line
			(start -0.7874 -0.4064)
			(end 0.7874 -0.4064)
			(stroke
				(width 0.1524)
				(type default)
			)
			(layer "F.SilkS")
		)
		(fp_line
			(start -0.7874 0.4064)
			(end -0.7874 -0.4064)
			(stroke
				(width 0.1524)
				(type default)
			)
			(layer "F.SilkS")
		)
		(fp_line
			(start 0.7874 -0.4064)
			(end 0.7874 0.4064)
			(stroke
				(width 0.1524)
				(type default)
			)
			(layer "F.SilkS")
		)
		(fp_line
			(start 0.7874 0.4064)
			(end -0.7874 0.4064)
			(stroke
				(width 0.1524)
				(type default)
			)
			(layer "F.SilkS")
		)
		(fp_line
			(start -0.67945 -0.305054)
			(end -0.12065 -0.305054)
			(stroke
				(width 0.1)
				(type default)
			)
			(layer "F.Fab")
		)
		(fp_line
			(start -0.67945 0.3048)
			(end -0.67945 -0.305054)
			(stroke
				(width 0.1)
				(type default)
			)
			(layer "F.Fab")
		)
		(fp_line
			(start -0.12065 -0.305054)
			(end -0.12065 -0.2794)
			(stroke
				(width 0.1)
				(type default)
			)
			(layer "F.Fab")
		)
		(fp_line
			(start -0.12065 -0.2794)
			(end 0.12065 -0.2794)
			(stroke
				(width 0.1)
				(type default)
			)
			(layer "F.Fab")
		)
		(fp_line
			(start -0.12065 0.2794)
			(end -0.12065 0.3048)
			(stroke
				(width 0.1)
				(type default)
			)
			(layer "F.Fab")
		)
		(fp_line
			(start -0.12065 0.3048)
			(end -0.67945 0.3048)
			(stroke
				(width 0.1)
				(type default)
			)
			(layer "F.Fab")
		)
		(fp_line
			(start 0.120396 0.2794)
			(end -0.12065 0.2794)
			(stroke
				(width 0.1)
				(type default)
			)
			(layer "F.Fab")
		)
		(fp_line
			(start 0.120396 0.3048)
			(end 0.120396 0.2794)
			(stroke
				(width 0.1)
				(type default)
			)
			(layer "F.Fab")
		)
		(fp_line
			(start 0.12065 -0.3048)
			(end 0.67945 -0.3048)
			(stroke
				(width 0.1)
				(type default)
			)
			(layer "F.Fab")
		)
		(fp_line
			(start 0.12065 -0.2794)
			(end 0.12065 -0.3048)
			(stroke
				(width 0.1)
				(type default)
			)
			(layer "F.Fab")
		)
		(fp_line
			(start 0.67945 -0.3048)
			(end 0.67945 0.3048)
			(stroke
				(width 0.1)
				(type default)
			)
			(layer "F.Fab")
		)
		(fp_line
			(start 0.67945 0.3048)
			(end 0.120396 0.3048)
			(stroke
				(width 0.1)
				(type default)
			)
			(layer "F.Fab")
		)
		(pad "1" smd circle
			(at -0.40005 0)
			(size 0 0)
			(layers "F.Cu" "F.Mask" "F.Paste")
			(net "P1V8_CPU0_RT_1D")
		)
		(pad "2" smd circle
			(at 0.40005 0)
			(size 0 0)
			(layers "F.Cu" "F.Mask" "F.Paste")
			(net "GND")
		)
	)
	(footprint ""
		(layer "F.Cu")
		(at 23.012654 -351.609406 90)
		(property "Reference" "PR341"
			(at 0 0 90)
			(layer "F.SilkS")
			(hide yes)
			(effects
				(font
					(size 1.27 1.27)
				)
			)
		)
		(property "Value" ""
			(at 0 0 90)
			(layer "F.Fab")
			(effects
				(font
					(size 1.27 1.27)
				)
			)
		)
		(duplicate_pad_numbers_are_jumpers no)
		(fp_line
			(start 0.7874 -0.4064)
			(end 0.7874 0.4064)
			(stroke
				(width 0.1524)
				(type default)
			)
			(layer "F.SilkS")
		)
		(fp_line
			(start -0.7874 -0.4064)
			(end 0.7874 -0.4064)
			(stroke
				(width 0.1524)
				(type default)
			)
			(layer "F.SilkS")
		)
		(fp_line
			(start 0.7874 0.4064)
			(end -0.7874 0.4064)
			(stroke
				(width 0.1524)
				(type default)
			)
			(layer "F.SilkS")
		)
		(fp_line
			(start -0.7874 0.4064)
			(end -0.7874 -0.4064)
			(stroke
				(width 0.1524)
				(type default)
			)
			(layer "F.SilkS")
		)
		(fp_line
			(start -0.12065 -0.305054)
			(end -0.12065 -0.2794)
			(stroke
				(width 0.1)
				(type default)
			)
			(layer "F.Fab")
		)
		(fp_line
			(start -0.67945 -0.305054)
			(end -0.12065 -0.305054)
			(stroke
				(width 0.1)
				(type default)
			)
			(layer "F.Fab")
		)
		(fp_line
			(start 0.67945 -0.3048)
			(end 0.67945 0.3048)
			(stroke
				(width 0.1)
				(type default)
			)
			(layer "F.Fab")
		)
		(fp_line
			(start 0.12065 -0.3048)
			(end 0.67945 -0.3048)
			(stroke
				(width 0.1)
				(type default)
			)
			(layer "F.Fab")
		)
		(fp_line
			(start 0.12065 -0.2794)
			(end 0.12065 -0.3048)
			(stroke
				(width 0.1)
				(type default)
			)
			(layer "F.Fab")
		)
		(fp_line
			(start -0.12065 -0.2794)
			(end 0.12065 -0.2794)
			(stroke
				(width 0.1)
				(type default)
			)
			(layer "F.Fab")
		)
		(fp_line
			(start 0.120396 0.2794)
			(end -0.12065 0.2794)
			(stroke
				(width 0.1)
				(type default)
			)
			(layer "F.Fab")
		)
		(fp_line
			(start -0.12065 0.2794)
			(end -0.12065 0.3048)
			(stroke
				(width 0.1)
				(type default)
			)
			(layer "F.Fab")
		)
		(fp_line
			(start 0.67945 0.3048)
			(end 0.120396 0.3048)
			(stroke
				(width 0.1)
				(type default)
			)
			(layer "F.Fab")
		)
		(fp_line
			(start 0.120396 0.3048)
			(end 0.120396 0.2794)
			(stroke
				(width 0.1)
				(type default)
			)
			(layer "F.Fab")
		)
		(fp_line
			(start -0.12065 0.3048)
			(end -0.67945 0.3048)
			(stroke
				(width 0.1)
				(type default)
			)
			(layer "F.Fab")
		)
		(fp_line
			(start -0.67945 0.3048)
			(end -0.67945 -0.305054)
			(stroke
				(width 0.1)
				(type default)
			)
			(layer "F.Fab")
		)
		(pad "1" smd circle
			(at -0.40005 0 90)
			(size 0 0)
			(layers "F.Cu" "F.Mask" "F.Paste")
			(net "PVDDCR_CPU1_P1_PVCC")
		)
		(pad "2" smd circle
			(at 0.40005 0 90)
			(size 0 0)
			(layers "F.Cu" "F.Mask" "F.Paste")
			(net "P3V3_AUX")
		)
	)
	(footprint ""
		(layer "F.Cu")
		(at 188.296804 -426.353478 -90)
		(property "Reference" "R3516"
			(at 0 0 270)
			(layer "F.SilkS")
			(hide yes)
			(effects
				(font
					(size 1.27 1.27)
				)
			)
		)
		(property "Value" ""
			(at 0 0 270)
			(layer "F.Fab")
			(effects
				(font
					(size 1.27 1.27)
				)
			)
		)
		(duplicate_pad_numbers_are_jumpers no)
		(fp_line
			(start -0.7874 0.4064)
			(end -0.7874 -0.4064)
			(stroke
				(width 0.1524)
				(type default)
			)
			(layer "F.SilkS")
		)
		(fp_line
			(start 0.7874 0.4064)
			(end -0.7874 0.4064)
			(stroke
				(width 0.1524)
				(type default)
			)
			(layer "F.SilkS")
		)
		(fp_line
			(start -0.7874 -0.4064)
			(end 0.7874 -0.4064)
			(stroke
				(width 0.1524)
				(type default)
			)
			(layer "F.SilkS")
		)
		(fp_line
			(start 0.7874 -0.4064)
			(end 0.7874 0.4064)
			(stroke
				(width 0.1524)
				(type default)
			)
			(layer "F.SilkS")
		)
		(fp_line
			(start -0.67945 0.3048)
			(end -0.67945 -0.305054)
			(stroke
				(width 0.1)
				(type default)
			)
			(layer "F.Fab")
		)
		(fp_line
			(start -0.12065 0.3048)
			(end -0.67945 0.3048)
			(stroke
				(width 0.1)
				(type default)
			)
			(layer "F.Fab")
		)
		(fp_line
			(start 0.120396 0.3048)
			(end 0.120396 0.2794)
			(stroke
				(width 0.1)
				(type default)
			)
			(layer "F.Fab")
		)
		(fp_line
			(start 0.67945 0.3048)
			(end 0.120396 0.3048)
			(stroke
				(width 0.1)
				(type default)
			)
			(layer "F.Fab")
		)
		(fp_line
			(start -0.12065 0.2794)
			(end -0.12065 0.3048)
			(stroke
				(width 0.1)
				(type default)
			)
			(layer "F.Fab")
		)
		(fp_line
			(start 0.120396 0.2794)
			(end -0.12065 0.2794)
			(stroke
				(width 0.1)
				(type default)
			)
			(layer "F.Fab")
		)
		(fp_line
			(start -0.12065 -0.2794)
			(end 0.12065 -0.2794)
			(stroke
				(width 0.1)
				(type default)
			)
			(layer "F.Fab")
		)
		(fp_line
			(start 0.12065 -0.2794)
			(end 0.12065 -0.3048)
			(stroke
				(width 0.1)
				(type default)
			)
			(layer "F.Fab")
		)
		(fp_line
			(start 0.12065 -0.3048)
			(end 0.67945 -0.3048)
			(stroke
				(width 0.1)
				(type default)
			)
			(layer "F.Fab")
		)
		(fp_line
			(start 0.67945 -0.3048)
			(end 0.67945 0.3048)
			(stroke
				(width 0.1)
				(type default)
			)
			(layer "F.Fab")
		)
		(fp_line
			(start -0.67945 -0.305054)
			(end -0.12065 -0.305054)
			(stroke
				(width 0.1)
				(type default)
			)
			(layer "F.Fab")
		)
		(fp_line
			(start -0.12065 -0.305054)
			(end -0.12065 -0.2794)
			(stroke
				(width 0.1)
				(type default)
			)
			(layer "F.Fab")
		)
		(pad "1" smd circle
			(at -0.40005 0 270)
			(size 0 0)
			(layers "F.Cu" "F.Mask" "F.Paste")
			(net "GPU_BASE_ID0")
		)
		(pad "2" smd circle
			(at 0.40005 0 270)
			(size 0 0)
			(layers "F.Cu" "F.Mask" "F.Paste")
			(net "GPU_BASE_ID0_R")
		)
	)
	(footprint ""
		(layer "F.Cu")
		(at 105.84561 -66.58991 180)
		(property "Reference" "R6219"
			(at 0 0 180)
			(layer "F.SilkS")
			(hide yes)
			(effects
				(font
					(size 1.27 1.27)
				)
			)
		)
		(property "Value" ""
			(at 0 0 180)
			(layer "F.Fab")
			(effects
				(font
					(size 1.27 1.27)
				)
			)
		)
		(duplicate_pad_numbers_are_jumpers no)
		(fp_line
			(start 0.7874 0.4064)
			(end -0.7874 0.4064)
			(stroke
				(width 0.1524)
				(type default)
			)
			(layer "F.SilkS")
		)
		(fp_line
			(start 0.7874 -0.4064)
			(end 0.7874 0.4064)
			(stroke
				(width 0.1524)
				(type default)
			)
			(layer "F.SilkS")
		)
		(fp_line
			(start -0.7874 0.4064)
			(end -0.7874 -0.4064)
			(stroke
				(width 0.1524)
				(type default)
			)
			(layer "F.SilkS")
		)
		(fp_line
			(start -0.7874 -0.4064)
			(end 0.7874 -0.4064)
			(stroke
				(width 0.1524)
				(type default)
			)
			(layer "F.SilkS")
		)
		(fp_line
			(start 0.67945 0.3048)
			(end 0.120396 0.3048)
			(stroke
				(width 0.1)
				(type default)
			)
			(layer "F.Fab")
		)
		(fp_line
			(start 0.67945 -0.3048)
			(end 0.67945 0.3048)
			(stroke
				(width 0.1)
				(type default)
			)
			(layer "F.Fab")
		)
		(fp_line
			(start 0.12065 -0.2794)
			(end 0.12065 -0.3048)
			(stroke
				(width 0.1)
				(type default)
			)
			(layer "F.Fab")
		)
		(fp_line
			(start 0.12065 -0.3048)
			(end 0.67945 -0.3048)
			(stroke
				(width 0.1)
				(type default)
			)
			(layer "F.Fab")
		)
		(fp_line
			(start 0.120396 0.3048)
			(end 0.120396 0.2794)
			(stroke
				(width 0.1)
				(type default)
			)
			(layer "F.Fab")
		)
		(fp_line
			(start 0.120396 0.2794)
			(end -0.12065 0.2794)
			(stroke
				(width 0.1)
				(type default)
			)
			(layer "F.Fab")
		)
		(fp_line
			(start -0.12065 0.3048)
			(end -0.67945 0.3048)
			(stroke
				(width 0.1)
				(type default)
			)
			(layer "F.Fab")
		)
		(fp_line
			(start -0.12065 0.2794)
			(end -0.12065 0.3048)
			(stroke
				(width 0.1)
				(type default)
			)
			(layer "F.Fab")
		)
		(fp_line
			(start -0.12065 -0.2794)
			(end 0.12065 -0.2794)
			(stroke
				(width 0.1)
				(type default)
			)
			(layer "F.Fab")
		)
		(fp_line
			(start -0.12065 -0.305054)
			(end -0.12065 -0.2794)
			(stroke
				(width 0.1)
				(type default)
			)
			(layer "F.Fab")
		)
		(fp_line
			(start -0.67945 0.3048)
			(end -0.67945 -0.305054)
			(stroke
				(width 0.1)
				(type default)
			)
			(layer "F.Fab")
		)
		(fp_line
			(start -0.67945 -0.305054)
			(end -0.12065 -0.305054)
			(stroke
				(width 0.1)
				(type default)
			)
			(layer "F.Fab")
		)
		(pad "1" smd circle
			(at -0.40005 0 180)
			(size 0 0)
			(layers "F.Cu" "F.Mask" "F.Paste")
			(net "USB_CPU0_ADD_A1")
		)
		(pad "2" smd circle
			(at 0.40005 0 180)
			(size 0 0)
			(layers "F.Cu" "F.Mask" "F.Paste")
			(net "GND")
		)
	)
	(footprint ""
		(layer "F.Cu")
		(at 240.854484 -55.612792)
		(property "Reference" "C1991"
			(at 0 0 0)
			(layer "F.SilkS")
			(hide yes)
			(effects
				(font
					(size 1.27 1.27)
				)
			)
		)
		(property "Value" ""
			(at 0 0 0)
			(layer "F.Fab")
			(effects
				(font
					(size 1.27 1.27)
				)
			)
		)
		(duplicate_pad_numbers_are_jumpers no)
		(fp_line
			(start -0.299974 -0.150114)
			(end 0.299974 -0.150114)
			(stroke
				(width 0.1)
				(type default)
			)
			(layer "F.Fab")
		)
		(fp_line
			(start -0.299974 0.150114)
			(end -0.299974 -0.150114)
			(stroke
				(width 0.1)
				(type default)
			)
			(layer "F.Fab")
		)
		(fp_line
			(start 0.299974 -0.150114)
			(end 0.299974 0.150114)
			(stroke
				(width 0.1)
				(type default)
			)
			(layer "F.Fab")
		)
		(fp_line
			(start 0.299974 0.150114)
			(end -0.299974 0.150114)
			(stroke
				(width 0.1)
				(type default)
			)
			(layer "F.Fab")
		)
		(pad "1" smd rect
			(at -0.2667 0)
			(size 0.3048 0.381)
			(layers "F.Cu" "F.Mask" "F.Paste")
			(net "P3E_CPU0_P4_TX_C_DP<2>")
		)
		(pad "2" smd rect
			(at 0.2667 0)
			(size 0.3048 0.381)
			(layers "F.Cu" "F.Mask" "F.Paste")
			(net "P3E_CPU0_P4_TX_DP<2>")
		)
	)
	(footprint ""
		(layer "F.Cu")
		(at 75.49515 -381.48006 180)
		(property "Reference" "C740"
			(at 0 0 180)
			(layer "F.SilkS")
			(hide yes)
			(effects
				(font
					(size 1.27 1.27)
				)
			)
		)
		(property "Value" ""
			(at 0 0 180)
			(layer "F.Fab")
			(effects
				(font
					(size 1.27 1.27)
				)
			)
		)
		(duplicate_pad_numbers_are_jumpers no)
		(fp_line
			(start 0.299974 0.150114)
			(end -0.299974 0.150114)
			(stroke
				(width 0.1)
				(type default)
			)
			(layer "F.Fab")
		)
		(fp_line
			(start 0.299974 -0.150114)
			(end 0.299974 0.150114)
			(stroke
				(width 0.1)
				(type default)
			)
			(layer "F.Fab")
		)
		(fp_line
			(start -0.299974 0.150114)
			(end -0.299974 -0.150114)
			(stroke
				(width 0.1)
				(type default)
			)
			(layer "F.Fab")
		)
		(fp_line
			(start -0.299974 -0.150114)
			(end 0.299974 -0.150114)
			(stroke
				(width 0.1)
				(type default)
			)
			(layer "F.Fab")
		)
		(pad "1" smd rect
			(at -0.2667 0 180)
			(size 0.3048 0.381)
			(layers "F.Cu" "F.Mask" "F.Paste")
			(net "P5E_CPU1_P1_TX_C_DN<0>")
		)
		(pad "2" smd rect
			(at 0.2667 0 180)
			(size 0.3048 0.381)
			(layers "F.Cu" "F.Mask" "F.Paste")
			(net "P5E_CPU1_P1_TX_DN<0>")
		)
	)
	(footprint ""
		(layer "F.Cu")
		(at 393.762484 -392.48588 180)
		(property "Reference" "R1093"
			(at 0 0 180)
			(layer "F.SilkS")
			(hide yes)
			(effects
				(font
					(size 1.27 1.27)
				)
			)
		)
		(property "Value" ""
			(at 0 0 180)
			(layer "F.Fab")
			(effects
				(font
					(size 1.27 1.27)
				)
			)
		)
		(duplicate_pad_numbers_are_jumpers no)
		(fp_line
			(start 0.7874 0.4064)
			(end -0.7874 0.4064)
			(stroke
				(width 0.1524)
				(type default)
			)
			(layer "F.SilkS")
		)
		(fp_line
			(start 0.7874 -0.4064)
			(end 0.7874 0.4064)
			(stroke
				(width 0.1524)
				(type default)
			)
			(layer "F.SilkS")
		)
		(fp_line
			(start -0.7874 0.4064)
			(end -0.7874 -0.4064)
			(stroke
				(width 0.1524)
				(type default)
			)
			(layer "F.SilkS")
		)
		(fp_line
			(start -0.7874 -0.4064)
			(end 0.7874 -0.4064)
			(stroke
				(width 0.1524)
				(type default)
			)
			(layer "F.SilkS")
		)
		(fp_line
			(start 0.67945 0.3048)
			(end 0.120396 0.3048)
			(stroke
				(width 0.1)
				(type default)
			)
			(layer "F.Fab")
		)
		(fp_line
			(start 0.67945 -0.3048)
			(end 0.67945 0.3048)
			(stroke
				(width 0.1)
				(type default)
			)
			(layer "F.Fab")
		)
		(fp_line
			(start 0.12065 -0.2794)
			(end 0.12065 -0.3048)
			(stroke
				(width 0.1)
				(type default)
			)
			(layer "F.Fab")
		)
		(fp_line
			(start 0.12065 -0.3048)
			(end 0.67945 -0.3048)
			(stroke
				(width 0.1)
				(type default)
			)
			(layer "F.Fab")
		)
		(fp_line
			(start 0.120396 0.3048)
			(end 0.120396 0.2794)
			(stroke
				(width 0.1)
				(type default)
			)
			(layer "F.Fab")
		)
		(fp_line
			(start 0.120396 0.2794)
			(end -0.12065 0.2794)
			(stroke
				(width 0.1)
				(type default)
			)
			(layer "F.Fab")
		)
		(fp_line
			(start -0.12065 0.3048)
			(end -0.67945 0.3048)
			(stroke
				(width 0.1)
				(type default)
			)
			(layer "F.Fab")
		)
		(fp_line
			(start -0.12065 0.2794)
			(end -0.12065 0.3048)
			(stroke
				(width 0.1)
				(type default)
			)
			(layer "F.Fab")
		)
		(fp_line
			(start -0.12065 -0.2794)
			(end 0.12065 -0.2794)
			(stroke
				(width 0.1)
				(type default)
			)
			(layer "F.Fab")
		)
		(fp_line
			(start -0.12065 -0.305054)
			(end -0.12065 -0.2794)
			(stroke
				(width 0.1)
				(type default)
			)
			(layer "F.Fab")
		)
		(fp_line
			(start -0.67945 0.3048)
			(end -0.67945 -0.305054)
			(stroke
				(width 0.1)
				(type default)
			)
			(layer "F.Fab")
		)
		(fp_line
			(start -0.67945 -0.305054)
			(end -0.12065 -0.305054)
			(stroke
				(width 0.1)
				(type default)
			)
			(layer "F.Fab")
		)
		(pad "1" smd rect
			(at -0.40005 0)
			(size 0.4572 0.508)
			(layers "F.Cu" "F.Mask" "F.Paste")
			(net "P1V8_CPU0_RT_1D")
		)
		(pad "2" smd rect
			(at 0.40005 0)
			(size 0.4572 0.508)
			(layers "F.Cu" "F.Mask" "F.Paste")
			(net "P1V8_CPU0_RT3_1A_1D")
		)
	)
	(footprint ""
		(layer "F.Cu")
		(at 140.385546 -75.19924 -90)
		(property "Reference" "PR6003"
			(at 0 0 270)
			(layer "F.SilkS")
			(hide yes)
			(effects
				(font
					(size 1.27 1.27)
				)
			)
		)
		(property "Value" ""
			(at 0 0 270)
			(layer "F.Fab")
			(effects
				(font
					(size 1.27 1.27)
				)
			)
		)
		(duplicate_pad_numbers_are_jumpers no)
		(fp_line
			(start -0.7874 0.4064)
			(end -0.7874 -0.4064)
			(stroke
				(width 0.1524)
				(type default)
			)
			(layer "F.SilkS")
		)
		(fp_line
			(start 0.7874 0.4064)
			(end -0.7874 0.4064)
			(stroke
				(width 0.1524)
				(type default)
			)
			(layer "F.SilkS")
		)
		(fp_line
			(start -0.7874 -0.4064)
			(end 0.7874 -0.4064)
			(stroke
				(width 0.1524)
				(type default)
			)
			(layer "F.SilkS")
		)
		(fp_line
			(start 0.7874 -0.4064)
			(end 0.7874 0.4064)
			(stroke
				(width 0.1524)
				(type default)
			)
			(layer "F.SilkS")
		)
		(fp_line
			(start -0.67945 0.3048)
			(end -0.67945 -0.305054)
			(stroke
				(width 0.1)
				(type default)
			)
			(layer "F.Fab")
		)
		(fp_line
			(start -0.12065 0.3048)
			(end -0.67945 0.3048)
			(stroke
				(width 0.1)
				(type default)
			)
			(layer "F.Fab")
		)
		(fp_line
			(start 0.120396 0.3048)
			(end 0.120396 0.2794)
			(stroke
				(width 0.1)
				(type default)
			)
			(layer "F.Fab")
		)
		(fp_line
			(start 0.67945 0.3048)
			(end 0.120396 0.3048)
			(stroke
				(width 0.1)
				(type default)
			)
			(layer "F.Fab")
		)
		(fp_line
			(start -0.12065 0.2794)
			(end -0.12065 0.3048)
			(stroke
				(width 0.1)
				(type default)
			)
			(layer "F.Fab")
		)
		(fp_line
			(start 0.120396 0.2794)
			(end -0.12065 0.2794)
			(stroke
				(width 0.1)
				(type default)
			)
			(layer "F.Fab")
		)
		(fp_line
			(start -0.12065 -0.2794)
			(end 0.12065 -0.2794)
			(stroke
				(width 0.1)
				(type default)
			)
			(layer "F.Fab")
		)
		(fp_line
			(start 0.12065 -0.2794)
			(end 0.12065 -0.3048)
			(stroke
				(width 0.1)
				(type default)
			)
			(layer "F.Fab")
		)
		(fp_line
			(start 0.12065 -0.3048)
			(end 0.67945 -0.3048)
			(stroke
				(width 0.1)
				(type default)
			)
			(layer "F.Fab")
		)
		(fp_line
			(start 0.67945 -0.3048)
			(end 0.67945 0.3048)
			(stroke
				(width 0.1)
				(type default)
			)
			(layer "F.Fab")
		)
		(fp_line
			(start -0.67945 -0.305054)
			(end -0.12065 -0.305054)
			(stroke
				(width 0.1)
				(type default)
			)
			(layer "F.Fab")
		)
		(fp_line
			(start -0.12065 -0.305054)
			(end -0.12065 -0.2794)
			(stroke
				(width 0.1)
				(type default)
			)
			(layer "F.Fab")
		)
		(pad "1" smd circle
			(at -0.40005 0 270)
			(size 0 0)
			(layers "F.Cu" "F.Mask" "F.Paste")
			(net "P1V8_AUX_CS")
		)
		(pad "2" smd circle
			(at 0.40005 0 270)
			(size 0 0)
			(layers "F.Cu" "F.Mask" "F.Paste")
			(net "GND")
		)
	)
	(footprint ""
		(layer "F.Cu")
		(at 257.242056 -115.86337 180)
		(property "Reference" "R3720"
			(at 0 0 180)
			(layer "F.SilkS")
			(hide yes)
			(effects
				(font
					(size 1.27 1.27)
				)
			)
		)
		(property "Value" ""
			(at 0 0 180)
			(layer "F.Fab")
			(effects
				(font
					(size 1.27 1.27)
				)
			)
		)
		(duplicate_pad_numbers_are_jumpers no)
		(fp_line
			(start 0.7874 0.4064)
			(end -0.7874 0.4064)
			(stroke
				(width 0.1524)
				(type default)
			)
			(layer "F.SilkS")
		)
		(fp_line
			(start 0.7874 -0.4064)
			(end 0.7874 0.4064)
			(stroke
				(width 0.1524)
				(type default)
			)
			(layer "F.SilkS")
		)
		(fp_line
			(start -0.7874 0.4064)
			(end -0.7874 -0.4064)
			(stroke
				(width 0.1524)
				(type default)
			)
			(layer "F.SilkS")
		)
		(fp_line
			(start -0.7874 -0.4064)
			(end 0.7874 -0.4064)
			(stroke
				(width 0.1524)
				(type default)
			)
			(layer "F.SilkS")
		)
		(fp_line
			(start 0.67945 0.3048)
			(end 0.120396 0.3048)
			(stroke
				(width 0.1)
				(type default)
			)
			(layer "F.Fab")
		)
		(fp_line
			(start 0.67945 -0.3048)
			(end 0.67945 0.3048)
			(stroke
				(width 0.1)
				(type default)
			)
			(layer "F.Fab")
		)
		(fp_line
			(start 0.12065 -0.2794)
			(end 0.12065 -0.3048)
			(stroke
				(width 0.1)
				(type default)
			)
			(layer "F.Fab")
		)
		(fp_line
			(start 0.12065 -0.3048)
			(end 0.67945 -0.3048)
			(stroke
				(width 0.1)
				(type default)
			)
			(layer "F.Fab")
		)
		(fp_line
			(start 0.120396 0.3048)
			(end 0.120396 0.2794)
			(stroke
				(width 0.1)
				(type default)
			)
			(layer "F.Fab")
		)
		(fp_line
			(start 0.120396 0.2794)
			(end -0.12065 0.2794)
			(stroke
				(width 0.1)
				(type default)
			)
			(layer "F.Fab")
		)
		(fp_line
			(start -0.12065 0.3048)
			(end -0.67945 0.3048)
			(stroke
				(width 0.1)
				(type default)
			)
			(layer "F.Fab")
		)
		(fp_line
			(start -0.12065 0.2794)
			(end -0.12065 0.3048)
			(stroke
				(width 0.1)
				(type default)
			)
			(layer "F.Fab")
		)
		(fp_line
			(start -0.12065 -0.2794)
			(end 0.12065 -0.2794)
			(stroke
				(width 0.1)
				(type default)
			)
			(layer "F.Fab")
		)
		(fp_line
			(start -0.12065 -0.305054)
			(end -0.12065 -0.2794)
			(stroke
				(width 0.1)
				(type default)
			)
			(layer "F.Fab")
		)
		(fp_line
			(start -0.67945 0.3048)
			(end -0.67945 -0.305054)
			(stroke
				(width 0.1)
				(type default)
			)
			(layer "F.Fab")
		)
		(fp_line
			(start -0.67945 -0.305054)
			(end -0.12065 -0.305054)
			(stroke
				(width 0.1)
				(type default)
			)
			(layer "F.Fab")
		)
		(pad "1" smd circle
			(at -0.40005 0 180)
			(size 0 0)
			(layers "F.Cu" "F.Mask" "F.Paste")
			(net "SMB_LM75_2_3V3AUX_SDA_R")
		)
		(pad "2" smd circle
			(at 0.40005 0 180)
			(size 0 0)
			(layers "F.Cu" "F.Mask" "F.Paste")
			(net "SMB_LM75_2_3V3AUX_SDA")
		)
	)
	(footprint ""
		(layer "F.Cu")
		(at 136.10717 -156.532834 90)
		(property "Reference" "PC347_SOP1_3"
			(at 0 0 90)
			(layer "F.SilkS")
			(hide yes)
			(effects
				(font
					(size 1.27 1.27)
				)
			)
		)
		(property "Value" ""
			(at 0 0 90)
			(layer "F.Fab")
			(effects
				(font
					(size 1.27 1.27)
				)
			)
		)
		(duplicate_pad_numbers_are_jumpers no)
		(fp_line
			(start 0.7874 -0.4064)
			(end 0.7874 0.4064)
			(stroke
				(width 0.1524)
				(type default)
			)
			(layer "F.SilkS")
		)
		(fp_line
			(start -0.7874 -0.4064)
			(end 0.7874 -0.4064)
			(stroke
				(width 0.1524)
				(type default)
			)
			(layer "F.SilkS")
		)
		(fp_line
			(start 0.7874 0.4064)
			(end -0.7874 0.4064)
			(stroke
				(width 0.1524)
				(type default)
			)
			(layer "F.SilkS")
		)
		(fp_line
			(start -0.7874 0.4064)
			(end -0.7874 -0.4064)
			(stroke
				(width 0.1524)
				(type default)
			)
			(layer "F.SilkS")
		)
		(fp_line
			(start -0.12065 -0.305054)
			(end -0.12065 -0.2794)
			(stroke
				(width 0.1)
				(type default)
			)
			(layer "F.Fab")
		)
		(fp_line
			(start -0.67945 -0.305054)
			(end -0.12065 -0.305054)
			(stroke
				(width 0.1)
				(type default)
			)
			(layer "F.Fab")
		)
		(fp_line
			(start 0.67945 -0.3048)
			(end 0.67945 0.3048)
			(stroke
				(width 0.1)
				(type default)
			)
			(layer "F.Fab")
		)
		(fp_line
			(start 0.12065 -0.3048)
			(end 0.67945 -0.3048)
			(stroke
				(width 0.1)
				(type default)
			)
			(layer "F.Fab")
		)
		(fp_line
			(start 0.12065 -0.2794)
			(end 0.12065 -0.3048)
			(stroke
				(width 0.1)
				(type default)
			)
			(layer "F.Fab")
		)
		(fp_line
			(start -0.12065 -0.2794)
			(end 0.12065 -0.2794)
			(stroke
				(width 0.1)
				(type default)
			)
			(layer "F.Fab")
		)
		(fp_line
			(start 0.120396 0.2794)
			(end -0.12065 0.2794)
			(stroke
				(width 0.1)
				(type default)
			)
			(layer "F.Fab")
		)
		(fp_line
			(start -0.12065 0.2794)
			(end -0.12065 0.3048)
			(stroke
				(width 0.1)
				(type default)
			)
			(layer "F.Fab")
		)
		(fp_line
			(start 0.67945 0.3048)
			(end 0.120396 0.3048)
			(stroke
				(width 0.1)
				(type default)
			)
			(layer "F.Fab")
		)
		(fp_line
			(start 0.120396 0.3048)
			(end 0.120396 0.2794)
			(stroke
				(width 0.1)
				(type default)
			)
			(layer "F.Fab")
		)
		(fp_line
			(start -0.12065 0.3048)
			(end -0.67945 0.3048)
			(stroke
				(width 0.1)
				(type default)
			)
			(layer "F.Fab")
		)
		(fp_line
			(start -0.67945 0.3048)
			(end -0.67945 -0.305054)
			(stroke
				(width 0.1)
				(type default)
			)
			(layer "F.Fab")
		)
		(pad "1" smd circle
			(at -0.40005 0 90)
			(size 0 0)
			(layers "F.Cu" "F.Mask" "F.Paste")
			(net "PVDDCR_CPU0_P1_PVCC")
		)
		(pad "2" smd circle
			(at 0.40005 0 90)
			(size 0 0)
			(layers "F.Cu" "F.Mask" "F.Paste")
			(net "GND")
		)
	)
	(footprint ""
		(layer "F.Cu")
		(at 150.502366 -55.188358)
		(property "Reference" "R3621"
			(at 0 0 0)
			(layer "F.SilkS")
			(hide yes)
			(effects
				(font
					(size 1.27 1.27)
				)
			)
		)
		(property "Value" ""
			(at 0 0 0)
			(layer "F.Fab")
			(effects
				(font
					(size 1.27 1.27)
				)
			)
		)
		(duplicate_pad_numbers_are_jumpers no)
		(fp_line
			(start -0.7874 -0.4064)
			(end 0.7874 -0.4064)
			(stroke
				(width 0.1524)
				(type default)
			)
			(layer "F.SilkS")
		)
		(fp_line
			(start -0.7874 0.4064)
			(end -0.7874 -0.4064)
			(stroke
				(width 0.1524)
				(type default)
			)
			(layer "F.SilkS")
		)
		(fp_line
			(start 0.7874 -0.4064)
			(end 0.7874 0.4064)
			(stroke
				(width 0.1524)
				(type default)
			)
			(layer "F.SilkS")
		)
		(fp_line
			(start 0.7874 0.4064)
			(end -0.7874 0.4064)
			(stroke
				(width 0.1524)
				(type default)
			)
			(layer "F.SilkS")
		)
		(fp_line
			(start -0.67945 -0.305054)
			(end -0.12065 -0.305054)
			(stroke
				(width 0.1)
				(type default)
			)
			(layer "F.Fab")
		)
		(fp_line
			(start -0.67945 0.3048)
			(end -0.67945 -0.305054)
			(stroke
				(width 0.1)
				(type default)
			)
			(layer "F.Fab")
		)
		(fp_line
			(start -0.12065 -0.305054)
			(end -0.12065 -0.2794)
			(stroke
				(width 0.1)
				(type default)
			)
			(layer "F.Fab")
		)
		(fp_line
			(start -0.12065 -0.2794)
			(end 0.12065 -0.2794)
			(stroke
				(width 0.1)
				(type default)
			)
			(layer "F.Fab")
		)
		(fp_line
			(start -0.12065 0.2794)
			(end -0.12065 0.3048)
			(stroke
				(width 0.1)
				(type default)
			)
			(layer "F.Fab")
		)
		(fp_line
			(start -0.12065 0.3048)
			(end -0.67945 0.3048)
			(stroke
				(width 0.1)
				(type default)
			)
			(layer "F.Fab")
		)
		(fp_line
			(start 0.120396 0.2794)
			(end -0.12065 0.2794)
			(stroke
				(width 0.1)
				(type default)
			)
			(layer "F.Fab")
		)
		(fp_line
			(start 0.120396 0.3048)
			(end 0.120396 0.2794)
			(stroke
				(width 0.1)
				(type default)
			)
			(layer "F.Fab")
		)
		(fp_line
			(start 0.12065 -0.3048)
			(end 0.67945 -0.3048)
			(stroke
				(width 0.1)
				(type default)
			)
			(layer "F.Fab")
		)
		(fp_line
			(start 0.12065 -0.2794)
			(end 0.12065 -0.3048)
			(stroke
				(width 0.1)
				(type default)
			)
			(layer "F.Fab")
		)
		(fp_line
			(start 0.67945 -0.3048)
			(end 0.67945 0.3048)
			(stroke
				(width 0.1)
				(type default)
			)
			(layer "F.Fab")
		)
		(fp_line
			(start 0.67945 0.3048)
			(end 0.120396 0.3048)
			(stroke
				(width 0.1)
				(type default)
			)
			(layer "F.Fab")
		)
		(pad "1" smd circle
			(at -0.40005 0)
			(size 0 0)
			(layers "F.Cu" "F.Mask" "F.Paste")
			(net "P3V3_AUX")
		)
		(pad "2" smd circle
			(at 0.40005 0)
			(size 0 0)
			(layers "F.Cu" "F.Mask" "F.Paste")
			(net "INA230_4_A0")
		)
	)
	(footprint ""
		(layer "F.Cu")
		(at 217.047826 -125.62459)
		(property "Reference" "R6826"
			(at 0 0 0)
			(layer "F.SilkS")
			(hide yes)
			(effects
				(font
					(size 1.27 1.27)
				)
			)
		)
		(property "Value" ""
			(at 0 0 0)
			(layer "F.Fab")
			(effects
				(font
					(size 1.27 1.27)
				)
			)
		)
		(duplicate_pad_numbers_are_jumpers no)
		(fp_line
			(start -0.7874 -0.4064)
			(end 0.7874 -0.4064)
			(stroke
				(width 0.1524)
				(type default)
			)
			(layer "F.SilkS")
		)
		(fp_line
			(start -0.7874 0.4064)
			(end -0.7874 -0.4064)
			(stroke
				(width 0.1524)
				(type default)
			)
			(layer "F.SilkS")
		)
		(fp_line
			(start 0.7874 -0.4064)
			(end 0.7874 0.4064)
			(stroke
				(width 0.1524)
				(type default)
			)
			(layer "F.SilkS")
		)
		(fp_line
			(start 0.7874 0.4064)
			(end -0.7874 0.4064)
			(stroke
				(width 0.1524)
				(type default)
			)
			(layer "F.SilkS")
		)
		(fp_line
			(start -0.67945 -0.305054)
			(end -0.12065 -0.305054)
			(stroke
				(width 0.1)
				(type default)
			)
			(layer "F.Fab")
		)
		(fp_line
			(start -0.67945 0.3048)
			(end -0.67945 -0.305054)
			(stroke
				(width 0.1)
				(type default)
			)
			(layer "F.Fab")
		)
		(fp_line
			(start -0.12065 -0.305054)
			(end -0.12065 -0.2794)
			(stroke
				(width 0.1)
				(type default)
			)
			(layer "F.Fab")
		)
		(fp_line
			(start -0.12065 -0.2794)
			(end 0.12065 -0.2794)
			(stroke
				(width 0.1)
				(type default)
			)
			(layer "F.Fab")
		)
		(fp_line
			(start -0.12065 0.2794)
			(end -0.12065 0.3048)
			(stroke
				(width 0.1)
				(type default)
			)
			(layer "F.Fab")
		)
		(fp_line
			(start -0.12065 0.3048)
			(end -0.67945 0.3048)
			(stroke
				(width 0.1)
				(type default)
			)
			(layer "F.Fab")
		)
		(fp_line
			(start 0.120396 0.2794)
			(end -0.12065 0.2794)
			(stroke
				(width 0.1)
				(type default)
			)
			(layer "F.Fab")
		)
		(fp_line
			(start 0.120396 0.3048)
			(end 0.120396 0.2794)
			(stroke
				(width 0.1)
				(type default)
			)
			(layer "F.Fab")
		)
		(fp_line
			(start 0.12065 -0.3048)
			(end 0.67945 -0.3048)
			(stroke
				(width 0.1)
				(type default)
			)
			(layer "F.Fab")
		)
		(fp_line
			(start 0.12065 -0.2794)
			(end 0.12065 -0.3048)
			(stroke
				(width 0.1)
				(type default)
			)
			(layer "F.Fab")
		)
		(fp_line
			(start 0.67945 -0.3048)
			(end 0.67945 0.3048)
			(stroke
				(width 0.1)
				(type default)
			)
			(layer "F.Fab")
		)
		(fp_line
			(start 0.67945 0.3048)
			(end 0.120396 0.3048)
			(stroke
				(width 0.1)
				(type default)
			)
			(layer "F.Fab")
		)
		(pad "1" smd circle
			(at -0.40005 0)
			(size 0 0)
			(layers "F.Cu" "F.Mask" "F.Paste")
			(net "RST_RT_CPU0_P3_RESET_R2_N")
		)
		(pad "2" smd circle
			(at 0.40005 0)
			(size 0 0)
			(layers "F.Cu" "F.Mask" "F.Paste")
			(net "RST_RT_CPU0_P3_RESET_R_N")
		)
	)
	(footprint ""
		(layer "F.Cu")
		(at 283.216858 -405.066754 -90)
		(property "Reference" "R354"
			(at 0 0 270)
			(layer "F.SilkS")
			(hide yes)
			(effects
				(font
					(size 1.27 1.27)
				)
			)
		)
		(property "Value" ""
			(at 0 0 270)
			(layer "F.Fab")
			(effects
				(font
					(size 1.27 1.27)
				)
			)
		)
		(duplicate_pad_numbers_are_jumpers no)
		(fp_line
			(start -0.7874 0.4064)
			(end -0.7874 -0.4064)
			(stroke
				(width 0.1524)
				(type default)
			)
			(layer "F.SilkS")
		)
		(fp_line
			(start 0.7874 0.4064)
			(end -0.7874 0.4064)
			(stroke
				(width 0.1524)
				(type default)
			)
			(layer "F.SilkS")
		)
		(fp_line
			(start -0.7874 -0.4064)
			(end 0.7874 -0.4064)
			(stroke
				(width 0.1524)
				(type default)
			)
			(layer "F.SilkS")
		)
		(fp_line
			(start 0.7874 -0.4064)
			(end 0.7874 0.4064)
			(stroke
				(width 0.1524)
				(type default)
			)
			(layer "F.SilkS")
		)
		(fp_line
			(start -0.67945 0.3048)
			(end -0.67945 -0.305054)
			(stroke
				(width 0.1)
				(type default)
			)
			(layer "F.Fab")
		)
		(fp_line
			(start -0.12065 0.3048)
			(end -0.67945 0.3048)
			(stroke
				(width 0.1)
				(type default)
			)
			(layer "F.Fab")
		)
		(fp_line
			(start 0.120396 0.3048)
			(end 0.120396 0.2794)
			(stroke
				(width 0.1)
				(type default)
			)
			(layer "F.Fab")
		)
		(fp_line
			(start 0.67945 0.3048)
			(end 0.120396 0.3048)
			(stroke
				(width 0.1)
				(type default)
			)
			(layer "F.Fab")
		)
		(fp_line
			(start -0.12065 0.2794)
			(end -0.12065 0.3048)
			(stroke
				(width 0.1)
				(type default)
			)
			(layer "F.Fab")
		)
		(fp_line
			(start 0.120396 0.2794)
			(end -0.12065 0.2794)
			(stroke
				(width 0.1)
				(type default)
			)
			(layer "F.Fab")
		)
		(fp_line
			(start -0.12065 -0.2794)
			(end 0.12065 -0.2794)
			(stroke
				(width 0.1)
				(type default)
			)
			(layer "F.Fab")
		)
		(fp_line
			(start 0.12065 -0.2794)
			(end 0.12065 -0.3048)
			(stroke
				(width 0.1)
				(type default)
			)
			(layer "F.Fab")
		)
		(fp_line
			(start 0.12065 -0.3048)
			(end 0.67945 -0.3048)
			(stroke
				(width 0.1)
				(type default)
			)
			(layer "F.Fab")
		)
		(fp_line
			(start 0.67945 -0.3048)
			(end 0.67945 0.3048)
			(stroke
				(width 0.1)
				(type default)
			)
			(layer "F.Fab")
		)
		(fp_line
			(start -0.67945 -0.305054)
			(end -0.12065 -0.305054)
			(stroke
				(width 0.1)
				(type default)
			)
			(layer "F.Fab")
		)
		(fp_line
			(start -0.12065 -0.305054)
			(end -0.12065 -0.2794)
			(stroke
				(width 0.1)
				(type default)
			)
			(layer "F.Fab")
		)
		(pad "1" smd circle
			(at -0.40005 0 270)
			(size 0 0)
			(layers "F.Cu" "F.Mask" "F.Paste")
			(net "P3V3_AUX")
		)
		(pad "2" smd circle
			(at 0.40005 0 270)
			(size 0 0)
			(layers "F.Cu" "F.Mask" "F.Paste")
			(net "P12V_HSC_T_CRIT_R_N")
		)
	)
	(footprint ""
		(layer "F.Cu")
		(at 41.5544 -390.652)
		(property "Reference" "R728"
			(at 0 0 0)
			(layer "F.SilkS")
			(hide yes)
			(effects
				(font
					(size 1.27 1.27)
				)
			)
		)
		(property "Value" ""
			(at 0 0 0)
			(layer "F.Fab")
			(effects
				(font
					(size 1.27 1.27)
				)
			)
		)
		(duplicate_pad_numbers_are_jumpers no)
		(fp_line
			(start -0.32512 -0.175006)
			(end 0.32512 -0.175006)
			(stroke
				(width 0.1)
				(type default)
			)
			(layer "F.Fab")
		)
		(fp_line
			(start -0.32512 0.175006)
			(end -0.32512 -0.175006)
			(stroke
				(width 0.1)
				(type default)
			)
			(layer "F.Fab")
		)
		(fp_line
			(start 0.32512 -0.175006)
			(end 0.32512 0.175006)
			(stroke
				(width 0.1)
				(type default)
			)
			(layer "F.Fab")
		)
		(fp_line
			(start 0.32512 0.175006)
			(end -0.32512 0.175006)
			(stroke
				(width 0.1)
				(type default)
			)
			(layer "F.Fab")
		)
		(pad "1" smd rect
			(at -0.2667 0)
			(size 0.3048 0.381)
			(layers "F.Cu" "F.Mask" "F.Paste")
			(net "MODE_RT_CPU1_P0")
		)
		(pad "2" smd rect
			(at 0.2667 0 180)
			(size 0.3048 0.381)
			(layers "F.Cu" "F.Mask" "F.Paste")
			(net "GND")
		)
	)
	(footprint ""
		(layer "F.Cu")
		(at 391.291318 -75.391264 180)
		(property "Reference" "R1355"
			(at 0 0 180)
			(layer "F.SilkS")
			(hide yes)
			(effects
				(font
					(size 1.27 1.27)
				)
			)
		)
		(property "Value" ""
			(at 0 0 180)
			(layer "F.Fab")
			(effects
				(font
					(size 1.27 1.27)
				)
			)
		)
		(duplicate_pad_numbers_are_jumpers no)
		(fp_line
			(start 0.7874 0.4064)
			(end -0.7874 0.4064)
			(stroke
				(width 0.1524)
				(type default)
			)
			(layer "F.SilkS")
		)
		(fp_line
			(start 0.7874 -0.4064)
			(end 0.7874 0.4064)
			(stroke
				(width 0.1524)
				(type default)
			)
			(layer "F.SilkS")
		)
		(fp_line
			(start -0.7874 0.4064)
			(end -0.7874 -0.4064)
			(stroke
				(width 0.1524)
				(type default)
			)
			(layer "F.SilkS")
		)
		(fp_line
			(start -0.7874 -0.4064)
			(end 0.7874 -0.4064)
			(stroke
				(width 0.1524)
				(type default)
			)
			(layer "F.SilkS")
		)
		(fp_line
			(start 0.67945 0.3048)
			(end 0.120396 0.3048)
			(stroke
				(width 0.1)
				(type default)
			)
			(layer "F.Fab")
		)
		(fp_line
			(start 0.67945 -0.3048)
			(end 0.67945 0.3048)
			(stroke
				(width 0.1)
				(type default)
			)
			(layer "F.Fab")
		)
		(fp_line
			(start 0.12065 -0.2794)
			(end 0.12065 -0.3048)
			(stroke
				(width 0.1)
				(type default)
			)
			(layer "F.Fab")
		)
		(fp_line
			(start 0.12065 -0.3048)
			(end 0.67945 -0.3048)
			(stroke
				(width 0.1)
				(type default)
			)
			(layer "F.Fab")
		)
		(fp_line
			(start 0.120396 0.3048)
			(end 0.120396 0.2794)
			(stroke
				(width 0.1)
				(type default)
			)
			(layer "F.Fab")
		)
		(fp_line
			(start 0.120396 0.2794)
			(end -0.12065 0.2794)
			(stroke
				(width 0.1)
				(type default)
			)
			(layer "F.Fab")
		)
		(fp_line
			(start -0.12065 0.3048)
			(end -0.67945 0.3048)
			(stroke
				(width 0.1)
				(type default)
			)
			(layer "F.Fab")
		)
		(fp_line
			(start -0.12065 0.2794)
			(end -0.12065 0.3048)
			(stroke
				(width 0.1)
				(type default)
			)
			(layer "F.Fab")
		)
		(fp_line
			(start -0.12065 -0.2794)
			(end 0.12065 -0.2794)
			(stroke
				(width 0.1)
				(type default)
			)
			(layer "F.Fab")
		)
		(fp_line
			(start -0.12065 -0.305054)
			(end -0.12065 -0.2794)
			(stroke
				(width 0.1)
				(type default)
			)
			(layer "F.Fab")
		)
		(fp_line
			(start -0.67945 0.3048)
			(end -0.67945 -0.305054)
			(stroke
				(width 0.1)
				(type default)
			)
			(layer "F.Fab")
		)
		(fp_line
			(start -0.67945 -0.305054)
			(end -0.12065 -0.305054)
			(stroke
				(width 0.1)
				(type default)
			)
			(layer "F.Fab")
		)
		(pad "1" smd circle
			(at -0.40005 0 180)
			(size 0 0)
			(layers "F.Cu" "F.Mask" "F.Paste")
			(net "INA230_6_A0")
		)
		(pad "2" smd circle
			(at 0.40005 0 180)
			(size 0 0)
			(layers "F.Cu" "F.Mask" "F.Paste")
			(net "SMB_INA230_6_3V3AUX_SDA_R1")
		)
	)
	(footprint ""
		(layer "F.Cu")
		(at 85.961728 -184.478168 -90)
		(property "Reference" "PR485"
			(at 0 0 270)
			(layer "F.SilkS")
			(hide yes)
			(effects
				(font
					(size 1.27 1.27)
				)
			)
		)
		(property "Value" ""
			(at 0 0 270)
			(layer "F.Fab")
			(effects
				(font
					(size 1.27 1.27)
				)
			)
		)
		(duplicate_pad_numbers_are_jumpers no)
		(fp_line
			(start -0.7874 0.4064)
			(end -0.7874 -0.4064)
			(stroke
				(width 0.1524)
				(type default)
			)
			(layer "F.SilkS")
		)
		(fp_line
			(start 0.7874 0.4064)
			(end -0.7874 0.4064)
			(stroke
				(width 0.1524)
				(type default)
			)
			(layer "F.SilkS")
		)
		(fp_line
			(start -0.7874 -0.4064)
			(end 0.7874 -0.4064)
			(stroke
				(width 0.1524)
				(type default)
			)
			(layer "F.SilkS")
		)
		(fp_line
			(start 0.7874 -0.4064)
			(end 0.7874 0.4064)
			(stroke
				(width 0.1524)
				(type default)
			)
			(layer "F.SilkS")
		)
		(fp_line
			(start -0.67945 0.3048)
			(end -0.67945 -0.305054)
			(stroke
				(width 0.1)
				(type default)
			)
			(layer "F.Fab")
		)
		(fp_line
			(start -0.12065 0.3048)
			(end -0.67945 0.3048)
			(stroke
				(width 0.1)
				(type default)
			)
			(layer "F.Fab")
		)
		(fp_line
			(start 0.120396 0.3048)
			(end 0.120396 0.2794)
			(stroke
				(width 0.1)
				(type default)
			)
			(layer "F.Fab")
		)
		(fp_line
			(start 0.67945 0.3048)
			(end 0.120396 0.3048)
			(stroke
				(width 0.1)
				(type default)
			)
			(layer "F.Fab")
		)
		(fp_line
			(start -0.12065 0.2794)
			(end -0.12065 0.3048)
			(stroke
				(width 0.1)
				(type default)
			)
			(layer "F.Fab")
		)
		(fp_line
			(start 0.120396 0.2794)
			(end -0.12065 0.2794)
			(stroke
				(width 0.1)
				(type default)
			)
			(layer "F.Fab")
		)
		(fp_line
			(start -0.12065 -0.2794)
			(end 0.12065 -0.2794)
			(stroke
				(width 0.1)
				(type default)
			)
			(layer "F.Fab")
		)
		(fp_line
			(start 0.12065 -0.2794)
			(end 0.12065 -0.3048)
			(stroke
				(width 0.1)
				(type default)
			)
			(layer "F.Fab")
		)
		(fp_line
			(start 0.12065 -0.3048)
			(end 0.67945 -0.3048)
			(stroke
				(width 0.1)
				(type default)
			)
			(layer "F.Fab")
		)
		(fp_line
			(start 0.67945 -0.3048)
			(end 0.67945 0.3048)
			(stroke
				(width 0.1)
				(type default)
			)
			(layer "F.Fab")
		)
		(fp_line
			(start -0.67945 -0.305054)
			(end -0.12065 -0.305054)
			(stroke
				(width 0.1)
				(type default)
			)
			(layer "F.Fab")
		)
		(fp_line
			(start -0.12065 -0.305054)
			(end -0.12065 -0.2794)
			(stroke
				(width 0.1)
				(type default)
			)
			(layer "F.Fab")
		)
		(pad "1" smd circle
			(at -0.40005 0 270)
			(size 0 0)
			(layers "F.Cu" "F.Mask" "F.Paste")
			(net "SW_PVDDCR_CPU0_P1_SW1_RC")
		)
		(pad "2" smd circle
			(at 0.40005 0 270)
			(size 0 0)
			(layers "F.Cu" "F.Mask" "F.Paste")
			(net "GND")
		)
	)
	(footprint ""
		(layer "F.Cu")
		(at 442.353192 -28.175458 -90)
		(property "Reference" "PU204"
			(at -6.397498 0.707136 0)
			(unlocked yes)
			(layer "F.SilkS")
			(effects
				(font
					(size 0.7874 0.5842)
					(thickness 0.1524)
				)
				(justify left)
			)
		)
		(property "Value" ""
			(at 0 0 270)
			(layer "F.Fab")
			(effects
				(font
					(size 1.27 1.27)
				)
			)
		)
		(duplicate_pad_numbers_are_jumpers no)
		(fp_line
			(start -1.549908 2.549906)
			(end -0.753872 2.549906)
			(stroke
				(width 0.1524)
				(type default)
			)
			(layer "F.SilkS")
		)
		(fp_line
			(start -0.245872 2.549906)
			(end 0.245872 2.549906)
			(stroke
				(width 0.1524)
				(type default)
			)
			(layer "F.SilkS")
		)
		(fp_line
			(start 0.753872 2.549906)
			(end 1.549908 2.549906)
			(stroke
				(width 0.1524)
				(type default)
			)
			(layer "F.SilkS")
		)
		(fp_line
			(start 1.549908 2.549906)
			(end 1.549908 2.253996)
			(stroke
				(width 0.1524)
				(type default)
			)
			(layer "F.SilkS")
		)
		(fp_line
			(start -1.549908 2.253996)
			(end -1.549908 2.549906)
			(stroke
				(width 0.1524)
				(type default)
			)
			(layer "F.SilkS")
		)
		(fp_line
			(start 1.549908 -2.253996)
			(end 1.549908 -2.549906)
			(stroke
				(width 0.1524)
				(type default)
			)
			(layer "F.SilkS")
		)
		(fp_line
			(start -1.549908 -2.549906)
			(end -1.549908 -2.251964)
			(stroke
				(width 0.1524)
				(type default)
			)
			(layer "F.SilkS")
		)
		(fp_line
			(start -0.752094 -2.549906)
			(end -1.549908 -2.549906)
			(stroke
				(width 0.1524)
				(type default)
			)
			(layer "F.SilkS")
		)
		(fp_line
			(start 0.2413 -2.549906)
			(end -0.2413 -2.549906)
			(stroke
				(width 0.1524)
				(type default)
			)
			(layer "F.SilkS")
		)
		(fp_line
			(start 1.549908 -2.549906)
			(end 0.752094 -2.549906)
			(stroke
				(width 0.1524)
				(type default)
			)
			(layer "F.SilkS")
		)
		(fp_poly
			(pts
				(xy -2.461768 -3.528568) (xy -1.981708 -2.70637) (xy -2.927604 -2.816098)
			)
			(stroke
				(width 0)
				(type default)
			)
			(fill yes)
			(layer "F.SilkS")
		)
		(fp_line
			(start -1.549908 2.549906)
			(end 1.549908 2.549906)
			(stroke
				(width 0.1)
				(type default)
			)
			(layer "F.Fab")
		)
		(fp_line
			(start 1.549908 2.549906)
			(end 1.549908 -2.549906)
			(stroke
				(width 0.1)
				(type default)
			)
			(layer "F.Fab")
		)
		(fp_line
			(start -1.549908 -2.549906)
			(end -1.549908 2.549906)
			(stroke
				(width 0.1)
				(type default)
			)
			(layer "F.Fab")
		)
		(fp_line
			(start 1.549908 -2.549906)
			(end -1.549908 -2.549906)
			(stroke
				(width 0.1)
				(type default)
			)
			(layer "F.Fab")
		)
		(fp_poly
			(pts
				(xy -1.891538 -1.999996) (xy -2.7432 -1.574292) (xy -2.7432 -2.4257)
			)
			(stroke
				(width 0)
				(type default)
			)
			(fill yes)
			(layer "F.Fab")
		)
		(fp_text user "11"
			(at 1.00076 7.279132 270)
			(unlocked yes)
			(layer "F.SilkS")
			(effects
				(font
					(size 0.635 0.4064)
					(thickness 0.1524)
				)
			)
		)
		(fp_text user "12"
			(at 3.553968 5.04698 180)
			(unlocked yes)
			(layer "F.SilkS")
			(effects
				(font
					(size 0.635 0.4064)
					(thickness 0.1524)
				)
			)
		)
		(fp_text user "10"
			(at -2.50952 4.215892 270)
			(unlocked yes)
			(layer "F.SilkS")
			(effects
				(font
					(size 0.635 0.4064)
					(thickness 0.1524)
				)
			)
		)
		(fp_text user "9"
			(at -2.338832 2.5908 180)
			(unlocked yes)
			(layer "F.SilkS")
			(effects
				(font
					(size 0.635 0.4064)
					(thickness 0.1524)
				)
			)
		)
		(fp_text user "21_22"
			(at -0.0762 -3.401568 270)
			(unlocked yes)
			(layer "F.SilkS")
			(effects
				(font
					(size 0.635 0.4064)
					(thickness 0.1524)
				)
			)
		)
		(fp_text user "20"
			(at 1.905508 -3.51536 180)
			(unlocked yes)
			(layer "F.SilkS")
			(effects
				(font
					(size 0.635 0.4064)
					(thickness 0.1524)
				)
			)
		)
		(fp_text user "11"
			(at 1.1938 3.329432 270)
			(unlocked yes)
			(layer "F.Fab")
			(effects
				(font
					(size 0.635 0.4064)
					(thickness 0.1524)
				)
			)
		)
		(fp_text user "10"
			(at -1.4224 3.253232 270)
			(unlocked yes)
			(layer "F.Fab")
			(effects
				(font
					(size 0.635 0.4064)
					(thickness 0.1524)
				)
			)
		)
		(fp_text user "12"
			(at 2.207768 2.7178 180)
			(unlocked yes)
			(layer "F.Fab")
			(effects
				(font
					(size 0.635 0.4064)
					(thickness 0.1524)
				)
			)
		)
		(fp_text user "9"
			(at -2.338832 2.5908 180)
			(unlocked yes)
			(layer "F.Fab")
			(effects
				(font
					(size 0.635 0.4064)
					(thickness 0.1524)
				)
			)
		)
		(fp_text user "20"
			(at 2.055368 -2.7686 180)
			(unlocked yes)
			(layer "F.Fab")
			(effects
				(font
					(size 0.635 0.4064)
					(thickness 0.1524)
				)
			)
		)
		(fp_text user "21_22"
			(at -0.0762 -3.401568 270)
			(unlocked yes)
			(layer "F.Fab")
			(effects
				(font
					(size 0.635 0.4064)
					(thickness 0.1524)
				)
			)
		)
		(pad "1" smd circle
			(at -1.374902 -1.999996 180)
			(size 0 0)
			(layers "F.Cu" "F.Mask" "F.Paste")
			(net "P12V_OCP_EN_1_R2")
		)
		(pad "2" smd rect
			(at -1.400048 -1.500124 180)
			(size 0.254 0.8128)
			(layers "F.Cu" "F.Mask" "F.Paste")
			(net "GND")
		)
		(pad "3" smd rect
			(at -1.400048 -0.999998 180)
			(size 0.254 0.8128)
			(layers "F.Cu" "F.Mask" "F.Paste")
			(net "GND")
		)
		(pad "4" smd rect
			(at -1.400048 -0.499872 180)
			(size 0.254 0.8128)
			(layers "F.Cu" "F.Mask" "F.Paste")
			(net "P12V_OCP_TIMER_1")
		)
		(pad "5" smd rect
			(at -1.400048 0 180)
			(size 0.254 0.8128)
			(layers "F.Cu" "F.Mask" "F.Paste")
			(net "P12V_OCP_ISET_1")
		)
		(pad "6" smd rect
			(at -1.400048 0.499872 180)
			(size 0.254 0.8128)
			(layers "F.Cu" "F.Mask" "F.Paste")
			(net "P12V_OCP_SS_1")
		)
		(pad "7" smd rect
			(at -1.400048 0.999998 180)
			(size 0.254 0.8128)
			(layers "F.Cu" "F.Mask" "F.Paste")
			(net "GND")
		)
		(pad "8" smd rect
			(at -1.400048 1.500124 180)
			(size 0.254 0.8128)
			(layers "F.Cu" "F.Mask" "F.Paste")
			(net "P12V_OCP_IMON_1")
		)
		(pad "9" smd rect
			(at -1.400048 1.999996 180)
			(size 0.254 0.8128)
			(layers "F.Cu" "F.Mask" "F.Paste")
			(net "P12V_OCP_FLTB_1")
		)
		(pad "10" smd rect
			(at -0.499872 2.400046 270)
			(size 0.254 0.8128)
			(layers "F.Cu" "F.Mask" "F.Paste")
			(net "HP_LVC3_OCP_V3_1_P12V_PWRGD")
		)
		(pad "11" smd rect
			(at 0.499872 2.400046 270)
			(size 0.254 0.8128)
			(layers "F.Cu" "F.Mask" "F.Paste")
			(net "P12V_OCP_OV_FB_1")
		)
		(pad "12" smd rect
			(at 1.400048 1.999996 180)
			(size 0.254 0.8128)
			(layers "F.Cu" "F.Mask" "F.Paste")
			(net "P12V_OCP_AVIN_PD_1")
		)
		(pad "13" smd rect
			(at 1.400048 1.500124 180)
			(size 0.254 0.8128)
			(layers "F.Cu" "F.Mask" "F.Paste")
			(net "P12V_OCP_SFF")
		)
		(pad "14" smd rect
			(at 1.400048 0.999998 180)
			(size 0.254 0.8128)
			(layers "F.Cu" "F.Mask" "F.Paste")
			(net "P12V_OCP_SFF")
		)
		(pad "15" smd rect
			(at 1.400048 0.499872 180)
			(size 0.254 0.8128)
			(layers "F.Cu" "F.Mask" "F.Paste")
			(net "P12V_OCP_SFF")
		)
		(pad "16" smd rect
			(at 1.400048 0 180)
			(size 0.254 0.8128)
			(layers "F.Cu" "F.Mask" "F.Paste")
			(net "P12V_OCP_SFF")
		)
		(pad "17" smd rect
			(at 1.400048 -0.499872 180)
			(size 0.254 0.8128)
			(layers "F.Cu" "F.Mask" "F.Paste")
			(net "P12V_OCP_SFF")
		)
		(pad "18" smd rect
			(at 1.400048 -0.999998 180)
			(size 0.254 0.8128)
			(layers "F.Cu" "F.Mask" "F.Paste")
			(net "P12V_OCP_SFF")
		)
		(pad "19" smd rect
			(at 1.400048 -1.500124 180)
			(size 0.254 0.8128)
			(layers "F.Cu" "F.Mask" "F.Paste")
			(net "P12V_OCP_SFF")
		)
		(pad "20" smd rect
			(at 1.400048 -1.999996 180)
			(size 0.254 0.8128)
			(layers "F.Cu" "F.Mask" "F.Paste")
			(net "P12V_OCP_SFF")
		)
		(pad "21_22" smd circle
			(at 0.499872 -2.337562 180)
			(size 0 0)
			(layers "F.Cu" "F.Mask" "F.Paste")
			(net "P12V_AUX")
		)
		(pad "23" smd rect
			(at 0 -1.100074 180)
			(size 0.254 1.27)
			(layers "F.Cu" "F.Mask" "F.Paste")
			(net "P12V_AUX")
		)
		(pad "24" smd rect
			(at 0 -0.199898 180)
			(size 0.254 1.27)
			(layers "F.Cu" "F.Mask" "F.Paste")
			(net "P12V_AUX")
		)
		(pad "25" smd rect
			(at 0 0.700024 180)
			(size 0.254 1.27)
			(layers "F.Cu" "F.Mask" "F.Paste")
			(net "P12V_AUX")
		)
		(pad "26" smd rect
			(at 0 1.599946 180)
			(size 0.254 1.27)
			(layers "F.Cu" "F.Mask" "F.Paste")
			(net "P12V_AUX")
		)
	)
	(footprint ""
		(layer "F.Cu")
		(at 81.537302 -375.49963 -90)
		(property "Reference" "C732"
			(at 0 0 270)
			(layer "F.SilkS")
			(hide yes)
			(effects
				(font
					(size 1.27 1.27)
				)
			)
		)
		(property "Value" ""
			(at 0 0 270)
			(layer "F.Fab")
			(effects
				(font
					(size 1.27 1.27)
				)
			)
		)
		(duplicate_pad_numbers_are_jumpers no)
		(fp_line
			(start -0.299974 0.150114)
			(end -0.299974 -0.150114)
			(stroke
				(width 0.1)
				(type default)
			)
			(layer "F.Fab")
		)
		(fp_line
			(start 0.299974 0.150114)
			(end -0.299974 0.150114)
			(stroke
				(width 0.1)
				(type default)
			)
			(layer "F.Fab")
		)
		(fp_line
			(start -0.299974 -0.150114)
			(end 0.299974 -0.150114)
			(stroke
				(width 0.1)
				(type default)
			)
			(layer "F.Fab")
		)
		(fp_line
			(start 0.299974 -0.150114)
			(end 0.299974 0.150114)
			(stroke
				(width 0.1)
				(type default)
			)
			(layer "F.Fab")
		)
		(pad "1" smd rect
			(at -0.2667 0 270)
			(size 0.3048 0.381)
			(layers "F.Cu" "F.Mask" "F.Paste")
			(net "P5E_CPU1_P1_TX_C_DN<4>")
		)
		(pad "2" smd rect
			(at 0.2667 0 270)
			(size 0.3048 0.381)
			(layers "F.Cu" "F.Mask" "F.Paste")
			(net "P5E_CPU1_P1_TX_DN<4>")
		)
	)
	(footprint ""
		(layer "F.Cu")
		(at 335.818226 -339.625432 90)
		(property "Reference" "PR82"
			(at 0 0 90)
			(layer "F.SilkS")
			(hide yes)
			(effects
				(font
					(size 1.27 1.27)
				)
			)
		)
		(property "Value" ""
			(at 0 0 90)
			(layer "F.Fab")
			(effects
				(font
					(size 1.27 1.27)
				)
			)
		)
		(duplicate_pad_numbers_are_jumpers no)
		(fp_line
			(start 0.7874 -0.4064)
			(end 0.7874 0.4064)
			(stroke
				(width 0.1524)
				(type default)
			)
			(layer "F.SilkS")
		)
		(fp_line
			(start -0.7874 -0.4064)
			(end 0.7874 -0.4064)
			(stroke
				(width 0.1524)
				(type default)
			)
			(layer "F.SilkS")
		)
		(fp_line
			(start 0.7874 0.4064)
			(end -0.7874 0.4064)
			(stroke
				(width 0.1524)
				(type default)
			)
			(layer "F.SilkS")
		)
		(fp_line
			(start -0.7874 0.4064)
			(end -0.7874 -0.4064)
			(stroke
				(width 0.1524)
				(type default)
			)
			(layer "F.SilkS")
		)
		(fp_line
			(start -0.12065 -0.305054)
			(end -0.12065 -0.2794)
			(stroke
				(width 0.1)
				(type default)
			)
			(layer "F.Fab")
		)
		(fp_line
			(start -0.67945 -0.305054)
			(end -0.12065 -0.305054)
			(stroke
				(width 0.1)
				(type default)
			)
			(layer "F.Fab")
		)
		(fp_line
			(start 0.67945 -0.3048)
			(end 0.67945 0.3048)
			(stroke
				(width 0.1)
				(type default)
			)
			(layer "F.Fab")
		)
		(fp_line
			(start 0.12065 -0.3048)
			(end 0.67945 -0.3048)
			(stroke
				(width 0.1)
				(type default)
			)
			(layer "F.Fab")
		)
		(fp_line
			(start 0.12065 -0.2794)
			(end 0.12065 -0.3048)
			(stroke
				(width 0.1)
				(type default)
			)
			(layer "F.Fab")
		)
		(fp_line
			(start -0.12065 -0.2794)
			(end 0.12065 -0.2794)
			(stroke
				(width 0.1)
				(type default)
			)
			(layer "F.Fab")
		)
		(fp_line
			(start 0.120396 0.2794)
			(end -0.12065 0.2794)
			(stroke
				(width 0.1)
				(type default)
			)
			(layer "F.Fab")
		)
		(fp_line
			(start -0.12065 0.2794)
			(end -0.12065 0.3048)
			(stroke
				(width 0.1)
				(type default)
			)
			(layer "F.Fab")
		)
		(fp_line
			(start 0.67945 0.3048)
			(end 0.120396 0.3048)
			(stroke
				(width 0.1)
				(type default)
			)
			(layer "F.Fab")
		)
		(fp_line
			(start 0.120396 0.3048)
			(end 0.120396 0.2794)
			(stroke
				(width 0.1)
				(type default)
			)
			(layer "F.Fab")
		)
		(fp_line
			(start -0.12065 0.3048)
			(end -0.67945 0.3048)
			(stroke
				(width 0.1)
				(type default)
			)
			(layer "F.Fab")
		)
		(fp_line
			(start -0.67945 0.3048)
			(end -0.67945 -0.305054)
			(stroke
				(width 0.1)
				(type default)
			)
			(layer "F.Fab")
		)
		(pad "1" smd circle
			(at -0.40005 0 90)
			(size 0 0)
			(layers "F.Cu" "F.Mask" "F.Paste")
			(net "SW_PVDDCR_CPU1_P0_BOOT1")
		)
		(pad "2" smd circle
			(at 0.40005 0 90)
			(size 0 0)
			(layers "F.Cu" "F.Mask" "F.Paste")
			(net "SW_PVDDCR_CPU1_P0_BOOT1_R")
		)
	)
	(footprint ""
		(layer "F.Cu")
		(at 293.038022 -52.02809)
		(property "Reference" "R422"
			(at 0 0 0)
			(layer "F.SilkS")
			(hide yes)
			(effects
				(font
					(size 1.27 1.27)
				)
			)
		)
		(property "Value" ""
			(at 0 0 0)
			(layer "F.Fab")
			(effects
				(font
					(size 1.27 1.27)
				)
			)
		)
		(duplicate_pad_numbers_are_jumpers no)
		(fp_line
			(start -0.7874 -0.4064)
			(end 0.7874 -0.4064)
			(stroke
				(width 0.1524)
				(type default)
			)
			(layer "F.SilkS")
		)
		(fp_line
			(start -0.7874 0.4064)
			(end -0.7874 -0.4064)
			(stroke
				(width 0.1524)
				(type default)
			)
			(layer "F.SilkS")
		)
		(fp_line
			(start 0.7874 -0.4064)
			(end 0.7874 0.4064)
			(stroke
				(width 0.1524)
				(type default)
			)
			(layer "F.SilkS")
		)
		(fp_line
			(start 0.7874 0.4064)
			(end -0.7874 0.4064)
			(stroke
				(width 0.1524)
				(type default)
			)
			(layer "F.SilkS")
		)
		(fp_line
			(start -0.67945 -0.305054)
			(end -0.12065 -0.305054)
			(stroke
				(width 0.1)
				(type default)
			)
			(layer "F.Fab")
		)
		(fp_line
			(start -0.67945 0.3048)
			(end -0.67945 -0.305054)
			(stroke
				(width 0.1)
				(type default)
			)
			(layer "F.Fab")
		)
		(fp_line
			(start -0.12065 -0.305054)
			(end -0.12065 -0.2794)
			(stroke
				(width 0.1)
				(type default)
			)
			(layer "F.Fab")
		)
		(fp_line
			(start -0.12065 -0.2794)
			(end 0.12065 -0.2794)
			(stroke
				(width 0.1)
				(type default)
			)
			(layer "F.Fab")
		)
		(fp_line
			(start -0.12065 0.2794)
			(end -0.12065 0.3048)
			(stroke
				(width 0.1)
				(type default)
			)
			(layer "F.Fab")
		)
		(fp_line
			(start -0.12065 0.3048)
			(end -0.67945 0.3048)
			(stroke
				(width 0.1)
				(type default)
			)
			(layer "F.Fab")
		)
		(fp_line
			(start 0.120396 0.2794)
			(end -0.12065 0.2794)
			(stroke
				(width 0.1)
				(type default)
			)
			(layer "F.Fab")
		)
		(fp_line
			(start 0.120396 0.3048)
			(end 0.120396 0.2794)
			(stroke
				(width 0.1)
				(type default)
			)
			(layer "F.Fab")
		)
		(fp_line
			(start 0.12065 -0.3048)
			(end 0.67945 -0.3048)
			(stroke
				(width 0.1)
				(type default)
			)
			(layer "F.Fab")
		)
		(fp_line
			(start 0.12065 -0.2794)
			(end 0.12065 -0.3048)
			(stroke
				(width 0.1)
				(type default)
			)
			(layer "F.Fab")
		)
		(fp_line
			(start 0.67945 -0.3048)
			(end 0.67945 0.3048)
			(stroke
				(width 0.1)
				(type default)
			)
			(layer "F.Fab")
		)
		(fp_line
			(start 0.67945 0.3048)
			(end 0.120396 0.3048)
			(stroke
				(width 0.1)
				(type default)
			)
			(layer "F.Fab")
		)
		(pad "1" smd circle
			(at -0.40005 0)
			(size 0 0)
			(layers "F.Cu" "F.Mask" "F.Paste")
			(net "PVDD18_S5_P0")
		)
		(pad "2" smd circle
			(at 0.40005 0)
			(size 0 0)
			(layers "F.Cu" "F.Mask" "F.Paste")
			(net "RST_CPU0_SYS_N")
		)
	)
	(footprint ""
		(layer "F.Cu")
		(at 162.22853 -348.553278 -90)
		(property "Reference" "PU54"
			(at 1.566926 -7.369048 90)
			(unlocked yes)
			(layer "F.SilkS")
			(effects
				(font
					(size 0.7874 0.5842)
					(thickness 0.1524)
				)
				(justify left)
			)
		)
		(property "Value" ""
			(at 0 0 270)
			(layer "F.Fab")
			(effects
				(font
					(size 1.27 1.27)
				)
			)
		)
		(duplicate_pad_numbers_are_jumpers no)
		(fp_line
			(start 1.778 3.6322)
			(end 1.778 2.8702)
			(stroke
				(width 0.1524)
				(type default)
			)
			(layer "F.SilkS")
		)
		(fp_line
			(start -0.2032 2.8829)
			(end -0.2032 3.2639)
			(stroke
				(width 0.1524)
				(type default)
			)
			(layer "F.SilkS")
		)
		(fp_line
			(start -2.500122 2.500122)
			(end -2.500122 2.018538)
			(stroke
				(width 0.1524)
				(type default)
			)
			(layer "F.SilkS")
		)
		(fp_line
			(start -2.015998 2.500122)
			(end -2.500122 2.500122)
			(stroke
				(width 0.1524)
				(type default)
			)
			(layer "F.SilkS")
		)
		(fp_line
			(start 2.500122 2.500122)
			(end 2.015998 2.500122)
			(stroke
				(width 0.1524)
				(type default)
			)
			(layer "F.SilkS")
		)
		(fp_line
			(start 2.500122 2.015998)
			(end 2.500122 2.500122)
			(stroke
				(width 0.1524)
				(type default)
			)
			(layer "F.SilkS")
		)
		(fp_line
			(start -3.084322 1.8034)
			(end -2.8956 1.8034)
			(stroke
				(width 0.1524)
				(type default)
			)
			(layer "F.SilkS")
		)
		(fp_line
			(start 2.8829 0.2032)
			(end 3.2639 0.2032)
			(stroke
				(width 0.1524)
				(type default)
			)
			(layer "F.SilkS")
		)
		(fp_line
			(start -3.2639 -0.1778)
			(end -2.8829 -0.1778)
			(stroke
				(width 0.1524)
				(type default)
			)
			(layer "F.SilkS")
		)
		(fp_line
			(start 2.8702 -1.778)
			(end 3.6322 -1.778)
			(stroke
				(width 0.1524)
				(type default)
			)
			(layer "F.SilkS")
		)
		(fp_line
			(start -2.500122 -2.015998)
			(end -2.500122 -2.500122)
			(stroke
				(width 0.1524)
				(type default)
			)
			(layer "F.SilkS")
		)
		(fp_line
			(start -2.500122 -2.500122)
			(end -2.015998 -2.500122)
			(stroke
				(width 0.1524)
				(type default)
			)
			(layer "F.SilkS")
		)
		(fp_line
			(start 2.015998 -2.500122)
			(end 2.500122 -2.500122)
			(stroke
				(width 0.1524)
				(type default)
			)
			(layer "F.SilkS")
		)
		(fp_line
			(start 2.500122 -2.500122)
			(end 2.500122 -2.015998)
			(stroke
				(width 0.1524)
				(type default)
			)
			(layer "F.SilkS")
		)
		(fp_line
			(start -1.8034 -2.8702)
			(end -1.8034 -3.6322)
			(stroke
				(width 0.1524)
				(type default)
			)
			(layer "F.SilkS")
		)
		(fp_line
			(start 0.1778 -3.2385)
			(end 0.1778 -2.8575)
			(stroke
				(width 0.1524)
				(type default)
			)
			(layer "F.SilkS")
		)
		(fp_poly
			(pts
				(xy -2.606294 -2.945638) (xy -2.623058 -2.293874) (xy -3.13436 -2.698496)
			)
			(stroke
				(width 0)
				(type default)
			)
			(fill yes)
			(layer "F.SilkS")
		)
		(fp_line
			(start 1.778 3.6322)
			(end 1.778 2.8702)
			(stroke
				(width 0.1)
				(type default)
			)
			(layer "F.Fab")
		)
		(fp_line
			(start -0.2032 2.8829)
			(end -0.2032 3.2639)
			(stroke
				(width 0.1)
				(type default)
			)
			(layer "F.Fab")
		)
		(fp_line
			(start -2.500122 2.500122)
			(end -2.500122 -2.500122)
			(stroke
				(width 0.1)
				(type default)
			)
			(layer "F.Fab")
		)
		(fp_line
			(start 2.500122 2.500122)
			(end -2.500122 2.500122)
			(stroke
				(width 0.1)
				(type default)
			)
			(layer "F.Fab")
		)
		(fp_line
			(start -3.6576 1.8034)
			(end -2.8956 1.8034)
			(stroke
				(width 0.1)
				(type default)
			)
			(layer "F.Fab")
		)
		(fp_line
			(start 2.8829 0.2032)
			(end 3.2639 0.2032)
			(stroke
				(width 0.1)
				(type default)
			)
			(layer "F.Fab")
		)
		(fp_line
			(start -3.2639 -0.1778)
			(end -2.8829 -0.1778)
			(stroke
				(width 0.1)
				(type default)
			)
			(layer "F.Fab")
		)
		(fp_line
			(start 2.8702 -1.778)
			(end 3.6322 -1.778)
			(stroke
				(width 0.1)
				(type default)
			)
			(layer "F.Fab")
		)
		(fp_line
			(start -2.500122 -2.500122)
			(end 2.500122 -2.500122)
			(stroke
				(width 0.1)
				(type default)
			)
			(layer "F.Fab")
		)
		(fp_line
			(start 2.500122 -2.500122)
			(end 2.500122 2.500122)
			(stroke
				(width 0.1)
				(type default)
			)
			(layer "F.Fab")
		)
		(fp_line
			(start -1.8034 -2.8702)
			(end -1.8034 -3.6322)
			(stroke
				(width 0.1)
				(type default)
			)
			(layer "F.Fab")
		)
		(fp_line
			(start 0.1778 -3.2385)
			(end 0.1778 -2.8575)
			(stroke
				(width 0.1)
				(type default)
			)
			(layer "F.Fab")
		)
		(fp_poly
			(pts
				(xy -2.921 -1.800098) (xy -3.504184 -1.508506) (xy -3.504184 -2.09169)
			)
			(stroke
				(width 0)
				(type default)
			)
			(fill yes)
			(layer "F.Fab")
		)
		(fp_text user "11"
			(at -2.76352 6.448552 270)
			(unlocked yes)
			(layer "F.SilkS")
			(effects
				(font
					(size 0.635 0.4064)
					(thickness 0.1524)
				)
				(justify left)
			)
		)
		(fp_text user "21"
			(at 3.744468 3.57886 180)
			(unlocked yes)
			(layer "F.SilkS")
			(effects
				(font
					(size 0.635 0.4064)
					(thickness 0.1524)
				)
				(justify left)
			)
		)
		(fp_text user "20"
			(at 2.0828 3.253232 270)
			(unlocked yes)
			(layer "F.SilkS")
			(effects
				(font
					(size 0.635 0.4064)
					(thickness 0.1524)
				)
				(justify left)
			)
		)
		(fp_text user "10"
			(at -6.070092 3.1369 180)
			(unlocked yes)
			(layer "F.SilkS")
			(effects
				(font
					(size 0.635 0.4064)
					(thickness 0.1524)
				)
				(justify left)
			)
		)
		(fp_text user "30"
			(at 3.040888 -2.96926 180)
			(unlocked yes)
			(layer "F.SilkS")
			(effects
				(font
					(size 0.635 0.4064)
					(thickness 0.1524)
				)
				(justify left)
			)
		)
		(fp_text user "31"
			(at 1.60782 -3.119628 270)
			(unlocked yes)
			(layer "F.SilkS")
			(effects
				(font
					(size 0.635 0.4064)
					(thickness 0.1524)
				)
				(justify left)
			)
		)
		(fp_text user "40"
			(at -2.464562 -3.243072 0)
			(unlocked yes)
			(layer "F.SilkS")
			(effects
				(font
					(size 0.635 0.4064)
					(thickness 0.1524)
				)
				(justify left)
			)
		)
		(fp_text user "11"
			(at -2.8702 3.278632 270)
			(unlocked yes)
			(layer "F.Fab")
			(effects
				(font
					(size 0.635 0.4064)
					(thickness 0.1524)
				)
				(justify left)
			)
		)
		(fp_text user "20"
			(at 2.0828 3.253232 270)
			(unlocked yes)
			(layer "F.Fab")
			(effects
				(font
					(size 0.635 0.4064)
					(thickness 0.1524)
				)
				(justify left)
			)
		)
		(fp_text user "10"
			(at -3.253232 2.1336 180)
			(unlocked yes)
			(layer "F.Fab")
			(effects
				(font
					(size 0.635 0.4064)
					(thickness 0.1524)
				)
				(justify left)
			)
		)
		(fp_text user "21"
			(at 3.274568 1.8796 180)
			(unlocked yes)
			(layer "F.Fab")
			(effects
				(font
					(size 0.635 0.4064)
					(thickness 0.1524)
				)
				(justify left)
			)
		)
		(fp_text user "40"
			(at -3.2004 -3.096768 270)
			(unlocked yes)
			(layer "F.Fab")
			(effects
				(font
					(size 0.635 0.4064)
					(thickness 0.1524)
				)
				(justify left)
			)
		)
		(fp_text user "30"
			(at 3.223768 -3.0988 180)
			(unlocked yes)
			(layer "F.Fab")
			(effects
				(font
					(size 0.635 0.4064)
					(thickness 0.1524)
				)
				(justify left)
			)
		)
		(fp_text user "31"
			(at 1.8542 -3.172968 270)
			(unlocked yes)
			(layer "F.Fab")
			(effects
				(font
					(size 0.635 0.4064)
					(thickness 0.1524)
				)
				(justify left)
			)
		)
		(pad "1" smd rect
			(at -2.400046 -1.800098 180)
			(size 0.1778 0.6096)
			(layers "F.Cu" "F.Mask" "F.Paste")
			(net "NC_PVDD11_S3_P1_PWM8")
		)
		(pad "2" smd rect
			(at -2.400046 -1.400048 180)
			(size 0.1778 0.6096)
			(layers "F.Cu" "F.Mask" "F.Paste")
			(net "NC_PVDD11_S3_P1_PWM7")
		)
		(pad "3" smd rect
			(at -2.400046 -0.999998 180)
			(size 0.1778 0.6096)
			(layers "F.Cu" "F.Mask" "F.Paste")
			(net "NC_PVDD11_S3_P1_PWM6")
		)
		(pad "4" smd rect
			(at -2.400046 -0.599948 180)
			(size 0.1778 0.6096)
			(layers "F.Cu" "F.Mask" "F.Paste")
			(net "NC_PVDD11_S3_P1_PWM5")
		)
		(pad "5" smd rect
			(at -2.400046 -0.199898 180)
			(size 0.1778 0.6096)
			(layers "F.Cu" "F.Mask" "F.Paste")
			(net "NC_PVDD11_S3_P1_PWM4")
		)
		(pad "6" smd rect
			(at -2.400046 0.199898 180)
			(size 0.1778 0.6096)
			(layers "F.Cu" "F.Mask" "F.Paste")
			(net "NC_PVDD11_S3_P1_PWM3")
		)
		(pad "7" smd rect
			(at -2.400046 0.599948 180)
			(size 0.1778 0.6096)
			(layers "F.Cu" "F.Mask" "F.Paste")
			(net "PVDD11_S3_P1_PWM2")
		)
		(pad "8" smd rect
			(at -2.400046 0.999998 180)
			(size 0.1778 0.6096)
			(layers "F.Cu" "F.Mask" "F.Paste")
			(net "PVDD11_S3_P1_PWM1")
		)
		(pad "9" smd rect
			(at -2.400046 1.400048 180)
			(size 0.1778 0.6096)
			(layers "F.Cu" "F.Mask" "F.Paste")
			(net "PVDD11_S3_P1_PMSDA_R")
		)
		(pad "10" smd rect
			(at -2.400046 1.800098 180)
			(size 0.1778 0.6096)
			(layers "F.Cu" "F.Mask" "F.Paste")
			(net "PVDD11_S3_P1_PMSCL_R")
		)
		(pad "11" smd rect
			(at -1.800098 2.400046 270)
			(size 0.1778 0.6096)
			(layers "F.Cu" "F.Mask" "F.Paste")
			(net "PVDD11_S3_P1_PMALERT_R")
		)
		(pad "12" smd rect
			(at -1.400048 2.400046 270)
			(size 0.1778 0.6096)
			(layers "F.Cu" "F.Mask" "F.Paste")
			(net "PWRGD_PVDD11_S3_P1_R")
		)
		(pad "13" smd rect
			(at -0.999998 2.400046 270)
			(size 0.1778 0.6096)
			(layers "F.Cu" "F.Mask" "F.Paste")
			(net "PVDD11_S3_P1_EN_R")
		)
		(pad "14" smd rect
			(at -0.599948 2.400046 270)
			(size 0.1778 0.6096)
			(layers "F.Cu" "F.Mask" "F.Paste")
			(net "PVDD11_S3_P1_RESET_N_R")
		)
		(pad "15" smd rect
			(at -0.199898 2.400046 270)
			(size 0.1778 0.6096)
			(layers "F.Cu" "F.Mask" "F.Paste")
			(net "PVDD11_S3_P1_VDDIO")
		)
		(pad "16" smd rect
			(at 0.199898 2.400046 270)
			(size 0.1778 0.6096)
			(layers "F.Cu" "F.Mask" "F.Paste")
			(net "NC_PVDD11_S3_P1_PG1")
		)
		(pad "17" smd rect
			(at 0.599948 2.400046 270)
			(size 0.1778 0.6096)
			(layers "F.Cu" "F.Mask" "F.Paste")
			(net "GND")
		)
		(pad "18" smd rect
			(at 0.999998 2.400046 270)
			(size 0.1778 0.6096)
			(layers "F.Cu" "F.Mask" "F.Paste")
			(net "GND")
		)
		(pad "19" smd rect
			(at 1.400048 2.400046 270)
			(size 0.1778 0.6096)
			(layers "F.Cu" "F.Mask" "F.Paste")
			(net "NC_PVDD11_S3_P1_SVTO")
		)
		(pad "20" smd rect
			(at 1.800098 2.400046 270)
			(size 0.1778 0.6096)
			(layers "F.Cu" "F.Mask" "F.Paste")
			(net "GND")
		)
		(pad "21" smd rect
			(at 2.400046 1.800098 180)
			(size 0.1778 0.6096)
			(layers "F.Cu" "F.Mask" "F.Paste")
			(net "VSENSE_PVDD11_S3_P1_R")
		)
		(pad "22" smd rect
			(at 2.400046 1.400048 180)
			(size 0.1778 0.6096)
			(layers "F.Cu" "F.Mask" "F.Paste")
			(net "VSENSE_VSS_SENSE_C_P1")
		)
		(pad "23" smd rect
			(at 2.400046 0.999998 180)
			(size 0.1778 0.6096)
			(layers "F.Cu" "F.Mask" "F.Paste")
			(net "PVDD11_S3_P1_IMON1")
		)
		(pad "24" smd rect
			(at 2.400046 0.599948 180)
			(size 0.1778 0.6096)
			(layers "F.Cu" "F.Mask" "F.Paste")
			(net "PVDD11_S3_P1_IMON2")
		)
		(pad "25" smd rect
			(at 2.400046 0.199898 180)
			(size 0.1778 0.6096)
			(layers "F.Cu" "F.Mask" "F.Paste")
			(net "NC_PVDD11_S3_P1_IMON3")
		)
		(pad "26" smd rect
			(at 2.400046 -0.199898 180)
			(size 0.1778 0.6096)
			(layers "F.Cu" "F.Mask" "F.Paste")
			(net "NC_PVDD11_S3_P1_IMON4")
		)
		(pad "27" smd rect
			(at 2.400046 -0.599948 180)
			(size 0.1778 0.6096)
			(layers "F.Cu" "F.Mask" "F.Paste")
			(net "NC_PVDD11_S3_P1_IMON5")
		)
		(pad "28" smd rect
			(at 2.400046 -0.999998 180)
			(size 0.1778 0.6096)
			(layers "F.Cu" "F.Mask" "F.Paste")
			(net "NC_PVDD11_S3_P1_IMON6")
		)
		(pad "29" smd rect
			(at 2.400046 -1.400048 180)
			(size 0.1778 0.6096)
			(layers "F.Cu" "F.Mask" "F.Paste")
			(net "NC_PVDD11_S3_P1_IMON7")
		)
		(pad "30" smd rect
			(at 2.400046 -1.800098 180)
			(size 0.1778 0.6096)
			(layers "F.Cu" "F.Mask" "F.Paste")
			(net "NC_PVDD11_S3_P1_IMON8")
		)
		(pad "31" smd rect
			(at 1.800098 -2.400046 270)
			(size 0.1778 0.6096)
			(layers "F.Cu" "F.Mask" "F.Paste")
			(net "GND")
		)
		(pad "32" smd rect
			(at 1.400048 -2.400046 270)
			(size 0.1778 0.6096)
			(layers "F.Cu" "F.Mask" "F.Paste")
			(net "GND")
		)
		(pad "33" smd rect
			(at 0.999998 -2.400046 270)
			(size 0.1778 0.6096)
			(layers "F.Cu" "F.Mask" "F.Paste")
			(net "PVDD11_S3_P1_OCP_N_R")
		)
		(pad "34" smd rect
			(at 0.599948 -2.400046 270)
			(size 0.1778 0.6096)
			(layers "F.Cu" "F.Mask" "F.Paste")
			(net "PVDD11_S3_P1_ADDR_CFG")
		)
		(pad "35" smd rect
			(at 0.199898 -2.400046 270)
			(size 0.1778 0.6096)
			(layers "F.Cu" "F.Mask" "F.Paste")
			(net "PVDD11_S3_P1_TEMP1")
		)
		(pad "36" smd rect
			(at -0.199898 -2.400046 270)
			(size 0.1778 0.6096)
			(layers "F.Cu" "F.Mask" "F.Paste")
			(net "PVDD11_S3_P1_TEMP0")
		)
		(pad "37" smd rect
			(at -0.599948 -2.400046 270)
			(size 0.1778 0.6096)
			(layers "F.Cu" "F.Mask" "F.Paste")
			(net "PVDD11_S3_P1_VMON")
		)
		(pad "38" smd rect
			(at -0.999998 -2.400046 270)
			(size 0.1778 0.6096)
			(layers "F.Cu" "F.Mask" "F.Paste")
			(net "PVDD11_S3_P1_VINSEN")
		)
		(pad "39" smd rect
			(at -1.400048 -2.400046 270)
			(size 0.1778 0.6096)
			(layers "F.Cu" "F.Mask" "F.Paste")
			(net "PVDD11_S3_P1_VCC")
		)
		(pad "40" smd rect
			(at -1.800098 -2.400046 270)
			(size 0.1778 0.6096)
			(layers "F.Cu" "F.Mask" "F.Paste")
			(net "PVDD11_S3_P1_VCCS")
		)
		(pad "TH" smd rect
			(at 0 0 270)
			(size 3.6576 3.6576)
			(layers "F.Cu" "F.Mask" "F.Paste")
			(net "GND")
		)
		(zone
			(layer "F.Cu")
			(hatch none 0.5)
			(connect_pads
				(clearance 0)
			)
			(min_thickness 0.25)
			(keepout
				(tracks not_allowed)
				(vias allowed)
				(pads allowed)
				(copperpour not_allowed)
				(footprints allowed)
			)
			(placement
				(enabled no)
				(sheetname "")
			)
			(fill
				(thermal_gap 0.5)
				(thermal_bridge_width 0.5)
				(island_removal_mode 0)
			)
			(polygon
				(pts
					(xy 160.19653 -348.181168) (xy 160.19653 -350.585278) (xy 164.08273 -350.585278) (xy 164.08273 -350.432878)
					(xy 160.34893 -350.432878) (xy 160.34893 -348.181168)
				)
			)
		)
	)
	(footprint ""
		(layer "F.Cu")
		(at 347.568266 -416.899344 -90)
		(property "Reference" "C6529"
			(at 0 0 270)
			(layer "F.SilkS")
			(hide yes)
			(effects
				(font
					(size 1.27 1.27)
				)
			)
		)
		(property "Value" ""
			(at 0 0 270)
			(layer "F.Fab")
			(effects
				(font
					(size 1.27 1.27)
				)
			)
		)
		(duplicate_pad_numbers_are_jumpers no)
		(fp_line
			(start -0.299974 0.150114)
			(end -0.299974 -0.150114)
			(stroke
				(width 0.1)
				(type default)
			)
			(layer "F.Fab")
		)
		(fp_line
			(start 0.299974 0.150114)
			(end -0.299974 0.150114)
			(stroke
				(width 0.1)
				(type default)
			)
			(layer "F.Fab")
		)
		(fp_line
			(start -0.299974 -0.150114)
			(end 0.299974 -0.150114)
			(stroke
				(width 0.1)
				(type default)
			)
			(layer "F.Fab")
		)
		(fp_line
			(start 0.299974 -0.150114)
			(end 0.299974 0.150114)
			(stroke
				(width 0.1)
				(type default)
			)
			(layer "F.Fab")
		)
		(pad "1" smd rect
			(at -0.2667 0 270)
			(size 0.3048 0.381)
			(layers "F.Cu" "F.Mask" "F.Paste")
			(net "P5E_CPU0_P0_TX_BUF_C_DP<14>")
		)
		(pad "2" smd rect
			(at 0.2667 0 270)
			(size 0.3048 0.381)
			(layers "F.Cu" "F.Mask" "F.Paste")
			(net "P5E_CPU0_P0_TX_BUF_DP<14>")
		)
	)
	(footprint ""
		(layer "F.Cu")
		(at 177.419 -404.495 90)
		(property "Reference" "PC2191"
			(at 0 0 90)
			(layer "F.SilkS")
			(hide yes)
			(effects
				(font
					(size 1.27 1.27)
				)
			)
		)
		(property "Value" ""
			(at 0 0 90)
			(layer "F.Fab")
			(effects
				(font
					(size 1.27 1.27)
				)
			)
		)
		(duplicate_pad_numbers_are_jumpers no)
		(fp_line
			(start 0.7874 -0.4064)
			(end 0.7874 0.4064)
			(stroke
				(width 0.1524)
				(type default)
			)
			(layer "F.SilkS")
		)
		(fp_line
			(start -0.7874 -0.4064)
			(end 0.7874 -0.4064)
			(stroke
				(width 0.1524)
				(type default)
			)
			(layer "F.SilkS")
		)
		(fp_line
			(start 0.7874 0.4064)
			(end -0.7874 0.4064)
			(stroke
				(width 0.1524)
				(type default)
			)
			(layer "F.SilkS")
		)
		(fp_line
			(start -0.7874 0.4064)
			(end -0.7874 -0.4064)
			(stroke
				(width 0.1524)
				(type default)
			)
			(layer "F.SilkS")
		)
		(fp_line
			(start -0.12065 -0.305054)
			(end -0.12065 -0.2794)
			(stroke
				(width 0.1)
				(type default)
			)
			(layer "F.Fab")
		)
		(fp_line
			(start -0.67945 -0.305054)
			(end -0.12065 -0.305054)
			(stroke
				(width 0.1)
				(type default)
			)
			(layer "F.Fab")
		)
		(fp_line
			(start 0.67945 -0.3048)
			(end 0.67945 0.3048)
			(stroke
				(width 0.1)
				(type default)
			)
			(layer "F.Fab")
		)
		(fp_line
			(start 0.12065 -0.3048)
			(end 0.67945 -0.3048)
			(stroke
				(width 0.1)
				(type default)
			)
			(layer "F.Fab")
		)
		(fp_line
			(start 0.12065 -0.2794)
			(end 0.12065 -0.3048)
			(stroke
				(width 0.1)
				(type default)
			)
			(layer "F.Fab")
		)
		(fp_line
			(start -0.12065 -0.2794)
			(end 0.12065 -0.2794)
			(stroke
				(width 0.1)
				(type default)
			)
			(layer "F.Fab")
		)
		(fp_line
			(start 0.120396 0.2794)
			(end -0.12065 0.2794)
			(stroke
				(width 0.1)
				(type default)
			)
			(layer "F.Fab")
		)
		(fp_line
			(start -0.12065 0.2794)
			(end -0.12065 0.3048)
			(stroke
				(width 0.1)
				(type default)
			)
			(layer "F.Fab")
		)
		(fp_line
			(start 0.67945 0.3048)
			(end 0.120396 0.3048)
			(stroke
				(width 0.1)
				(type default)
			)
			(layer "F.Fab")
		)
		(fp_line
			(start 0.120396 0.3048)
			(end 0.120396 0.2794)
			(stroke
				(width 0.1)
				(type default)
			)
			(layer "F.Fab")
		)
		(fp_line
			(start -0.12065 0.3048)
			(end -0.67945 0.3048)
			(stroke
				(width 0.1)
				(type default)
			)
			(layer "F.Fab")
		)
		(fp_line
			(start -0.67945 0.3048)
			(end -0.67945 -0.305054)
			(stroke
				(width 0.1)
				(type default)
			)
			(layer "F.Fab")
		)
		(pad "1" smd circle
			(at -0.40005 0 90)
			(size 0 0)
			(layers "F.Cu" "F.Mask" "F.Paste")
			(net "HSC_SS")
		)
		(pad "2" smd circle
			(at 0.40005 0 90)
			(size 0 0)
			(layers "F.Cu" "F.Mask" "F.Paste")
			(net "AGND_HSC")
		)
	)
	(footprint ""
		(layer "F.Cu")
		(at 111.13897 -178.173634 90)
		(property "Reference" "PC289_C0P1_4"
			(at 0 0 90)
			(layer "F.SilkS")
			(hide yes)
			(effects
				(font
					(size 1.27 1.27)
				)
			)
		)
		(property "Value" ""
			(at 0 0 90)
			(layer "F.Fab")
			(effects
				(font
					(size 1.27 1.27)
				)
			)
		)
		(duplicate_pad_numbers_are_jumpers no)
		(fp_line
			(start 0.7874 -0.4064)
			(end 0.7874 0.4064)
			(stroke
				(width 0.1524)
				(type default)
			)
			(layer "F.SilkS")
		)
		(fp_line
			(start -0.7874 -0.4064)
			(end 0.7874 -0.4064)
			(stroke
				(width 0.1524)
				(type default)
			)
			(layer "F.SilkS")
		)
		(fp_line
			(start 0.7874 0.4064)
			(end -0.7874 0.4064)
			(stroke
				(width 0.1524)
				(type default)
			)
			(layer "F.SilkS")
		)
		(fp_line
			(start -0.7874 0.4064)
			(end -0.7874 -0.4064)
			(stroke
				(width 0.1524)
				(type default)
			)
			(layer "F.SilkS")
		)
		(fp_line
			(start -0.12065 -0.305054)
			(end -0.12065 -0.2794)
			(stroke
				(width 0.1)
				(type default)
			)
			(layer "F.Fab")
		)
		(fp_line
			(start -0.67945 -0.305054)
			(end -0.12065 -0.305054)
			(stroke
				(width 0.1)
				(type default)
			)
			(layer "F.Fab")
		)
		(fp_line
			(start 0.67945 -0.3048)
			(end 0.67945 0.3048)
			(stroke
				(width 0.1)
				(type default)
			)
			(layer "F.Fab")
		)
		(fp_line
			(start 0.12065 -0.3048)
			(end 0.67945 -0.3048)
			(stroke
				(width 0.1)
				(type default)
			)
			(layer "F.Fab")
		)
		(fp_line
			(start 0.12065 -0.2794)
			(end 0.12065 -0.3048)
			(stroke
				(width 0.1)
				(type default)
			)
			(layer "F.Fab")
		)
		(fp_line
			(start -0.12065 -0.2794)
			(end 0.12065 -0.2794)
			(stroke
				(width 0.1)
				(type default)
			)
			(layer "F.Fab")
		)
		(fp_line
			(start 0.120396 0.2794)
			(end -0.12065 0.2794)
			(stroke
				(width 0.1)
				(type default)
			)
			(layer "F.Fab")
		)
		(fp_line
			(start -0.12065 0.2794)
			(end -0.12065 0.3048)
			(stroke
				(width 0.1)
				(type default)
			)
			(layer "F.Fab")
		)
		(fp_line
			(start 0.67945 0.3048)
			(end 0.120396 0.3048)
			(stroke
				(width 0.1)
				(type default)
			)
			(layer "F.Fab")
		)
		(fp_line
			(start 0.120396 0.3048)
			(end 0.120396 0.2794)
			(stroke
				(width 0.1)
				(type default)
			)
			(layer "F.Fab")
		)
		(fp_line
			(start -0.12065 0.3048)
			(end -0.67945 0.3048)
			(stroke
				(width 0.1)
				(type default)
			)
			(layer "F.Fab")
		)
		(fp_line
			(start -0.67945 0.3048)
			(end -0.67945 -0.305054)
			(stroke
				(width 0.1)
				(type default)
			)
			(layer "F.Fab")
		)
		(pad "1" smd circle
			(at -0.40005 0 90)
			(size 0 0)
			(layers "F.Cu" "F.Mask" "F.Paste")
			(net "PVDDCR_CPU0_P1_PVCC")
		)
		(pad "2" smd circle
			(at 0.40005 0 90)
			(size 0 0)
			(layers "F.Cu" "F.Mask" "F.Paste")
			(net "GND")
		)
	)
	(footprint ""
		(layer "F.Cu")
		(at 428.283116 -109.26699 90)
		(property "Reference" "PR3791"
			(at 0 0 90)
			(layer "F.SilkS")
			(hide yes)
			(effects
				(font
					(size 1.27 1.27)
				)
			)
		)
		(property "Value" ""
			(at 0 0 90)
			(layer "F.Fab")
			(effects
				(font
					(size 1.27 1.27)
				)
			)
		)
		(duplicate_pad_numbers_are_jumpers no)
		(fp_line
			(start 0.7874 -0.4064)
			(end 0.7874 0.4064)
			(stroke
				(width 0.1524)
				(type default)
			)
			(layer "F.SilkS")
		)
		(fp_line
			(start -0.7874 -0.4064)
			(end 0.7874 -0.4064)
			(stroke
				(width 0.1524)
				(type default)
			)
			(layer "F.SilkS")
		)
		(fp_line
			(start 0.7874 0.4064)
			(end -0.7874 0.4064)
			(stroke
				(width 0.1524)
				(type default)
			)
			(layer "F.SilkS")
		)
		(fp_line
			(start -0.7874 0.4064)
			(end -0.7874 -0.4064)
			(stroke
				(width 0.1524)
				(type default)
			)
			(layer "F.SilkS")
		)
		(fp_line
			(start -0.12065 -0.305054)
			(end -0.12065 -0.2794)
			(stroke
				(width 0.1)
				(type default)
			)
			(layer "F.Fab")
		)
		(fp_line
			(start -0.67945 -0.305054)
			(end -0.12065 -0.305054)
			(stroke
				(width 0.1)
				(type default)
			)
			(layer "F.Fab")
		)
		(fp_line
			(start 0.67945 -0.3048)
			(end 0.67945 0.3048)
			(stroke
				(width 0.1)
				(type default)
			)
			(layer "F.Fab")
		)
		(fp_line
			(start 0.12065 -0.3048)
			(end 0.67945 -0.3048)
			(stroke
				(width 0.1)
				(type default)
			)
			(layer "F.Fab")
		)
		(fp_line
			(start 0.12065 -0.2794)
			(end 0.12065 -0.3048)
			(stroke
				(width 0.1)
				(type default)
			)
			(layer "F.Fab")
		)
		(fp_line
			(start -0.12065 -0.2794)
			(end 0.12065 -0.2794)
			(stroke
				(width 0.1)
				(type default)
			)
			(layer "F.Fab")
		)
		(fp_line
			(start 0.120396 0.2794)
			(end -0.12065 0.2794)
			(stroke
				(width 0.1)
				(type default)
			)
			(layer "F.Fab")
		)
		(fp_line
			(start -0.12065 0.2794)
			(end -0.12065 0.3048)
			(stroke
				(width 0.1)
				(type default)
			)
			(layer "F.Fab")
		)
		(fp_line
			(start 0.67945 0.3048)
			(end 0.120396 0.3048)
			(stroke
				(width 0.1)
				(type default)
			)
			(layer "F.Fab")
		)
		(fp_line
			(start 0.120396 0.3048)
			(end 0.120396 0.2794)
			(stroke
				(width 0.1)
				(type default)
			)
			(layer "F.Fab")
		)
		(fp_line
			(start -0.12065 0.3048)
			(end -0.67945 0.3048)
			(stroke
				(width 0.1)
				(type default)
			)
			(layer "F.Fab")
		)
		(fp_line
			(start -0.67945 0.3048)
			(end -0.67945 -0.305054)
			(stroke
				(width 0.1)
				(type default)
			)
			(layer "F.Fab")
		)
		(pad "1" smd circle
			(at -0.40005 0 90)
			(size 0 0)
			(layers "F.Cu" "F.Mask" "F.Paste")
			(net "P3V3_OCP_OV_1")
		)
		(pad "2" smd circle
			(at 0.40005 0 90)
			(size 0 0)
			(layers "F.Cu" "F.Mask" "F.Paste")
			(net "GND")
		)
	)
	(footprint ""
		(layer "F.Cu")
		(at 360.40949 -393.9032 90)
		(property "Reference" "R1013"
			(at 0 0 90)
			(layer "F.SilkS")
			(hide yes)
			(effects
				(font
					(size 1.27 1.27)
				)
			)
		)
		(property "Value" ""
			(at 0 0 90)
			(layer "F.Fab")
			(effects
				(font
					(size 1.27 1.27)
				)
			)
		)
		(duplicate_pad_numbers_are_jumpers no)
		(fp_line
			(start 0.32512 -0.175006)
			(end 0.32512 0.175006)
			(stroke
				(width 0.1)
				(type default)
			)
			(layer "F.Fab")
		)
		(fp_line
			(start -0.32512 -0.175006)
			(end 0.32512 -0.175006)
			(stroke
				(width 0.1)
				(type default)
			)
			(layer "F.Fab")
		)
		(fp_line
			(start 0.32512 0.175006)
			(end -0.32512 0.175006)
			(stroke
				(width 0.1)
				(type default)
			)
			(layer "F.Fab")
		)
		(fp_line
			(start -0.32512 0.175006)
			(end -0.32512 -0.175006)
			(stroke
				(width 0.1)
				(type default)
			)
			(layer "F.Fab")
		)
		(pad "1" smd rect
			(at -0.2667 0 90)
			(size 0.3048 0.381)
			(layers "F.Cu" "F.Mask" "F.Paste")
			(net "P1V8_CPU0_RT_1D")
		)
		(pad "2" smd rect
			(at 0.2667 0 270)
			(size 0.3048 0.381)
			(layers "F.Cu" "F.Mask" "F.Paste")
			(net "RT_CPU0_P1_ADDR3")
		)
	)
	(footprint ""
		(layer "F.Cu")
		(at 192.599564 -68.407788 180)
		(property "Reference" "PC2197"
			(at 0 0 180)
			(layer "F.SilkS")
			(hide yes)
			(effects
				(font
					(size 1.27 1.27)
				)
			)
		)
		(property "Value" ""
			(at 0 0 180)
			(layer "F.Fab")
			(effects
				(font
					(size 1.27 1.27)
				)
			)
		)
		(duplicate_pad_numbers_are_jumpers no)
		(fp_line
			(start 0.7874 0.4064)
			(end -0.7874 0.4064)
			(stroke
				(width 0.1524)
				(type default)
			)
			(layer "F.SilkS")
		)
		(fp_line
			(start 0.7874 -0.4064)
			(end 0.7874 0.4064)
			(stroke
				(width 0.1524)
				(type default)
			)
			(layer "F.SilkS")
		)
		(fp_line
			(start -0.7874 0.4064)
			(end -0.7874 -0.4064)
			(stroke
				(width 0.1524)
				(type default)
			)
			(layer "F.SilkS")
		)
		(fp_line
			(start -0.7874 -0.4064)
			(end 0.7874 -0.4064)
			(stroke
				(width 0.1524)
				(type default)
			)
			(layer "F.SilkS")
		)
		(fp_line
			(start 0.67945 0.3048)
			(end 0.120396 0.3048)
			(stroke
				(width 0.1)
				(type default)
			)
			(layer "F.Fab")
		)
		(fp_line
			(start 0.67945 -0.3048)
			(end 0.67945 0.3048)
			(stroke
				(width 0.1)
				(type default)
			)
			(layer "F.Fab")
		)
		(fp_line
			(start 0.12065 -0.2794)
			(end 0.12065 -0.3048)
			(stroke
				(width 0.1)
				(type default)
			)
			(layer "F.Fab")
		)
		(fp_line
			(start 0.12065 -0.3048)
			(end 0.67945 -0.3048)
			(stroke
				(width 0.1)
				(type default)
			)
			(layer "F.Fab")
		)
		(fp_line
			(start 0.120396 0.3048)
			(end 0.120396 0.2794)
			(stroke
				(width 0.1)
				(type default)
			)
			(layer "F.Fab")
		)
		(fp_line
			(start 0.120396 0.2794)
			(end -0.12065 0.2794)
			(stroke
				(width 0.1)
				(type default)
			)
			(layer "F.Fab")
		)
		(fp_line
			(start -0.12065 0.3048)
			(end -0.67945 0.3048)
			(stroke
				(width 0.1)
				(type default)
			)
			(layer "F.Fab")
		)
		(fp_line
			(start -0.12065 0.2794)
			(end -0.12065 0.3048)
			(stroke
				(width 0.1)
				(type default)
			)
			(layer "F.Fab")
		)
		(fp_line
			(start -0.12065 -0.2794)
			(end 0.12065 -0.2794)
			(stroke
				(width 0.1)
				(type default)
			)
			(layer "F.Fab")
		)
		(fp_line
			(start -0.12065 -0.305054)
			(end -0.12065 -0.2794)
			(stroke
				(width 0.1)
				(type default)
			)
			(layer "F.Fab")
		)
		(fp_line
			(start -0.67945 0.3048)
			(end -0.67945 -0.305054)
			(stroke
				(width 0.1)
				(type default)
			)
			(layer "F.Fab")
		)
		(fp_line
			(start -0.67945 -0.305054)
			(end -0.12065 -0.305054)
			(stroke
				(width 0.1)
				(type default)
			)
			(layer "F.Fab")
		)
		(pad "1" smd circle
			(at -0.40005 0 180)
			(size 0 0)
			(layers "F.Cu" "F.Mask" "F.Paste")
			(net "P3V3_E1S_MODE_0")
		)
		(pad "2" smd circle
			(at 0.40005 0 180)
			(size 0 0)
			(layers "F.Cu" "F.Mask" "F.Paste")
			(net "GND")
		)
	)
	(footprint ""
		(layer "F.Cu")
		(at 482.294946 -457.301092 90)
		(property "Reference" "X9004"
			(at -2.091182 1.02362 0)
			(unlocked yes)
			(layer "F.SilkS")
			(effects
				(font
					(size 0.7874 0.5842)
					(thickness 0.1524)
				)
				(justify left)
			)
		)
		(property "Value" ""
			(at 0 0 90)
			(layer "F.Fab")
			(effects
				(font
					(size 1.27 1.27)
				)
			)
		)
		(property "User Part Number" "N_A"
			(at 1.30175 1.27 180)
			(unlocked yes)
			(layer "Cmts.User")
			(hide yes)
			(effects
				(font
					(size 0.635 0.4064)
					(thickness 0.1524)
				)
			)
		)
		(property "Device Type" "TP_TDR_4P_FTS_TH-TP_TDR_4P_DIP,EMPTY,TP15"
			(at 1.30175 1.27 180)
			(unlocked yes)
			(layer "F.Fab")
			(hide yes)
			(effects
				(font
					(size 0.635 0.4064)
					(thickness 0.1524)
				)
			)
		)
		(duplicate_pad_numbers_are_jumpers no)
		(fp_line
			(start 2.54 -1.27)
			(end 0 -1.27)
			(stroke
				(width 0.1524)
				(type default)
			)
			(layer "F.SilkS")
		)
		(fp_line
			(start 0 -1.27)
			(end 0 -0.635)
			(stroke
				(width 0.1524)
				(type default)
			)
			(layer "F.SilkS")
		)
		(fp_line
			(start 2.54 -1.1303)
			(end 2.54 -1.27)
			(stroke
				(width 0.1524)
				(type default)
			)
			(layer "F.SilkS")
		)
		(fp_line
			(start 0 0.635)
			(end 0 1.905)
			(stroke
				(width 0.1524)
				(type default)
			)
			(layer "F.SilkS")
		)
		(fp_line
			(start 2.54 1.4097)
			(end 2.54 1.1303)
			(stroke
				(width 0.1524)
				(type default)
			)
			(layer "F.SilkS")
		)
		(fp_line
			(start 0 3.175)
			(end 0 3.81)
			(stroke
				(width 0.1524)
				(type default)
			)
			(layer "F.SilkS")
		)
		(fp_line
			(start 2.54 3.81)
			(end 2.54 3.6703)
			(stroke
				(width 0.1524)
				(type default)
			)
			(layer "F.SilkS")
		)
		(fp_line
			(start 0 3.81)
			(end 2.54 3.81)
			(stroke
				(width 0.1524)
				(type default)
			)
			(layer "F.SilkS")
		)
		(fp_poly
			(pts
				(xy -2.285746 -0.762) (xy -0.761746 0) (xy -2.285746 0.762)
			)
			(stroke
				(width 0)
				(type default)
			)
			(fill yes)
			(layer "F.SilkS")
		)
		(fp_line
			(start 2.54 -1.27)
			(end 0 -1.27)
			(stroke
				(width 0.1)
				(type default)
			)
			(layer "F.Fab")
		)
		(fp_line
			(start 0 -1.27)
			(end 0 3.81)
			(stroke
				(width 0.1)
				(type default)
			)
			(layer "F.Fab")
		)
		(fp_line
			(start 2.54 3.81)
			(end 2.54 -1.27)
			(stroke
				(width 0.1)
				(type default)
			)
			(layer "F.Fab")
		)
		(fp_line
			(start 0 3.81)
			(end 2.54 3.81)
			(stroke
				(width 0.1)
				(type default)
			)
			(layer "F.Fab")
		)
		(fp_poly
			(pts
				(xy -0.761746 0) (xy -2.285746 -0.762) (xy -2.285746 0.762)
			)
			(stroke
				(width 0)
				(type default)
			)
			(fill yes)
			(layer "F.Fab")
		)
		(pad "1" thru_hole circle
			(at 0 0 90)
			(size 1.0033 1.0033)
			(drill 0.249936)
			(layers "*.Cu" "*.Mask")
			(remove_unused_layers no)
			(net "TDR_DIFF_85_NECK_IN3_DP")
			(clearance 0.10795)
			(thermal_gap 0.10795)
			(padstack
				(mode front_inner_back)
				(layer "Inner"
					(shape circle)
					(size 0.8001 0.8001)
					(clearance 0.1524)
				)
				(layer "B.Cu"
					(shape circle)
					(size 1.0033 1.0033)
					(clearance 0.10795)
				)
			)
		)
		(pad "2" thru_hole circle
			(at 2.54 0 90)
			(size 1.9939 1.9939)
			(drill 0.249936)
			(layers "*.Cu" "*.Mask")
			(remove_unused_layers no)
			(net "T1_GND")
			(clearance 0.10795)
			(thermal_gap 0.10795)
			(padstack
				(mode front_inner_back)
				(layer "Inner"
					(shape circle)
					(size 0.8001 0.8001)
					(clearance 0.1524)
				)
				(layer "B.Cu"
					(shape circle)
					(size 1.9939 1.9939)
					(clearance 0.10795)
				)
			)
		)
		(pad "3" thru_hole circle
			(at 2.54 2.54 90)
			(size 1.9939 1.9939)
			(drill 0.249936)
			(layers "*.Cu" "*.Mask")
			(remove_unused_layers no)
			(net "T1_GND")
			(clearance 0.10795)
			(thermal_gap 0.10795)
			(padstack
				(mode front_inner_back)
				(layer "Inner"
					(shape circle)
					(size 0.8001 0.8001)
					(clearance 0.1524)
				)
				(layer "B.Cu"
					(shape circle)
					(size 1.9939 1.9939)
					(clearance 0.10795)
				)
			)
		)
		(pad "4" thru_hole circle
			(at 0 2.54 90)
			(size 1.0033 1.0033)
			(drill 0.249936)
			(layers "*.Cu" "*.Mask")
			(remove_unused_layers no)
			(net "TDR_DIFF_85_NECK_IN3_DN")
			(clearance 0.10795)
			(thermal_gap 0.10795)
			(padstack
				(mode front_inner_back)
				(layer "Inner"
					(shape circle)
					(size 0.8001 0.8001)
					(clearance 0.1524)
				)
				(layer "B.Cu"
					(shape circle)
					(size 1.0033 1.0033)
					(clearance 0.10795)
				)
			)
		)
	)
	(footprint ""
		(layer "F.Cu")
		(at 189.738762 -25.643332)
		(property "Reference" "PU300"
			(at 3.987546 -1.268222 0)
			(unlocked yes)
			(layer "F.SilkS")
			(effects
				(font
					(size 0.7874 0.5842)
					(thickness 0.1524)
				)
				(justify left)
			)
		)
		(property "Value" ""
			(at 0 0 0)
			(layer "F.Fab")
			(effects
				(font
					(size 1.27 1.27)
				)
			)
		)
		(duplicate_pad_numbers_are_jumpers no)
		(fp_line
			(start -1.774952 -1.039876)
			(end -1.774952 1.039876)
			(stroke
				(width 0.1524)
				(type default)
			)
			(layer "F.SilkS")
		)
		(fp_line
			(start -1.774952 1.039876)
			(end 1.774952 1.039876)
			(stroke
				(width 0.1524)
				(type default)
			)
			(layer "F.SilkS")
		)
		(fp_line
			(start 1.774952 -1.039876)
			(end -1.774952 -1.039876)
			(stroke
				(width 0.1524)
				(type default)
			)
			(layer "F.SilkS")
		)
		(fp_line
			(start 1.774952 1.039876)
			(end 1.774952 -1.039876)
			(stroke
				(width 0.1524)
				(type default)
			)
			(layer "F.SilkS")
		)
		(fp_poly
			(pts
				(xy -0.999998 -1.801876) (xy -0.999998 -1.039876) (xy -1.769872 -1.039876) (xy -1.769872 -0.249936)
				(xy -2.531872 -0.249936) (xy -2.531872 -1.801876)
			)
			(stroke
				(width 0)
				(type default)
			)
			(fill yes)
			(layer "F.SilkS")
		)
		(fp_line
			(start -1.769872 -1.039876)
			(end -1.769872 1.039876)
			(stroke
				(width 0.1)
				(type default)
			)
			(layer "F.Fab")
		)
		(fp_line
			(start -1.769872 1.039876)
			(end 1.769872 1.039876)
			(stroke
				(width 0.1)
				(type default)
			)
			(layer "F.Fab")
		)
		(fp_line
			(start 1.769872 -1.039876)
			(end -1.769872 -1.039876)
			(stroke
				(width 0.1)
				(type default)
			)
			(layer "F.Fab")
		)
		(fp_line
			(start 1.769872 1.039876)
			(end 1.769872 -1.039876)
			(stroke
				(width 0.1)
				(type default)
			)
			(layer "F.Fab")
		)
		(fp_poly
			(pts
				(xy -1.769872 -1.039876) (xy -0.999998 -1.039876) (xy -0.999998 -1.801876) (xy -2.531872 -1.801876)
				(xy -2.531872 -0.249936) (xy -1.769872 -0.249936)
			)
			(stroke
				(width 0)
				(type default)
			)
			(fill yes)
			(layer "F.Fab")
		)
		(pad "A1" smd circle
			(at -1.500124 -0.750062)
			(size 0.2286 0.2286)
			(layers "F.Cu" "F.Mask" "F.Paste")
			(net "P12V_SCM_SENSE")
		)
		(pad "A2" smd circle
			(at -0.999998 -0.750062)
			(size 0.2286 0.2286)
			(layers "F.Cu" "F.Mask" "F.Paste")
			(net "P12V_SCM_VCC")
		)
		(pad "A3" smd circle
			(at -0.499872 -0.750062)
			(size 0.2286 0.2286)
			(layers "F.Cu" "F.Mask" "F.Paste")
			(net "P12V_AUX")
		)
		(pad "A4" smd circle
			(at 0 -0.750062)
			(size 0.2286 0.2286)
			(layers "F.Cu" "F.Mask" "F.Paste")
			(net "P12V_SCM_R")
		)
		(pad "A5" smd circle
			(at 0.499872 -0.750062)
			(size 0.2286 0.2286)
			(layers "F.Cu" "F.Mask" "F.Paste")
			(net "P12V_AUX")
		)
		(pad "A6" smd circle
			(at 0.999998 -0.750062)
			(size 0.2286 0.2286)
			(layers "F.Cu" "F.Mask" "F.Paste")
			(net "P12V_SCM_GATE")
		)
		(pad "A7" smd circle
			(at 1.500124 -0.750062)
			(size 0.2286 0.2286)
			(layers "F.Cu" "F.Mask" "F.Paste")
			(net "GND")
		)
		(pad "B1" smd circle
			(at -1.500124 -0.249936)
			(size 0.2286 0.2286)
			(layers "F.Cu" "F.Mask" "F.Paste")
			(net "P12V_SCM_CB")
		)
		(pad "B2" smd circle
			(at -0.999998 -0.249936)
			(size 0.2286 0.2286)
			(layers "F.Cu" "F.Mask" "F.Paste")
			(net "GND")
		)
		(pad "B3" smd circle
			(at -0.499872 -0.249936)
			(size 0.2286 0.2286)
			(layers "F.Cu" "F.Mask" "F.Paste")
			(net "P12V_AUX")
		)
		(pad "B4" smd circle
			(at 0 -0.249936)
			(size 0.2286 0.2286)
			(layers "F.Cu" "F.Mask" "F.Paste")
			(net "P12V_SCM_R")
		)
		(pad "B5" smd circle
			(at 0.499872 -0.249936)
			(size 0.2286 0.2286)
			(layers "F.Cu" "F.Mask" "F.Paste")
			(net "P12V_AUX")
		)
		(pad "B6" smd circle
			(at 0.999998 -0.249936)
			(size 0.2286 0.2286)
			(layers "F.Cu" "F.Mask" "F.Paste")
			(net "P12V_SCM_R")
		)
		(pad "B7" smd circle
			(at 1.500124 -0.249936)
			(size 0.2286 0.2286)
			(layers "F.Cu" "F.Mask" "F.Paste")
			(net "GND")
		)
		(pad "C1" smd circle
			(at -1.500124 0.249936)
			(size 0.2286 0.2286)
			(layers "F.Cu" "F.Mask" "F.Paste")
			(net "GND")
		)
		(pad "C2" smd circle
			(at -0.999998 0.249936)
			(size 0.2286 0.2286)
			(layers "F.Cu" "F.Mask" "F.Paste")
			(net "GND")
		)
		(pad "C3" smd circle
			(at -0.499872 0.249936)
			(size 0.2286 0.2286)
			(layers "F.Cu" "F.Mask" "F.Paste")
			(net "P12V_AUX")
		)
		(pad "C4" smd circle
			(at 0 0.249936)
			(size 0.2286 0.2286)
			(layers "F.Cu" "F.Mask" "F.Paste")
			(net "P12V_SCM_R")
		)
		(pad "C5" smd circle
			(at 0.499872 0.249936)
			(size 0.2286 0.2286)
			(layers "F.Cu" "F.Mask" "F.Paste")
			(net "P12V_AUX")
		)
		(pad "C6" smd circle
			(at 0.999998 0.249936)
			(size 0.2286 0.2286)
			(layers "F.Cu" "F.Mask" "F.Paste")
			(net "P12V_SCM_R")
		)
		(pad "C7" smd circle
			(at 1.500124 0.249936)
			(size 0.2286 0.2286)
			(layers "F.Cu" "F.Mask" "F.Paste")
			(net "P12V_SCM_FAULT_N")
		)
		(pad "D1" smd circle
			(at -1.500124 0.750062)
			(size 0.2286 0.2286)
			(layers "F.Cu" "F.Mask" "F.Paste")
			(net "P12V_SCM_REG")
		)
		(pad "D2" smd circle
			(at -0.999998 0.750062)
			(size 0.2286 0.2286)
			(layers "F.Cu" "F.Mask" "F.Paste")
			(net "P12V_SCM_UV")
		)
		(pad "D3" smd circle
			(at -0.499872 0.750062)
			(size 0.2286 0.2286)
			(layers "F.Cu" "F.Mask" "F.Paste")
			(net "P12V_SCM_OV")
		)
		(pad "D4" smd circle
			(at 0 0.750062)
			(size 0.2286 0.2286)
			(layers "F.Cu" "F.Mask" "F.Paste")
			(net "P12V_SCM_R")
		)
		(pad "D5" smd circle
			(at 0.499872 0.750062)
			(size 0.2286 0.2286)
			(layers "F.Cu" "F.Mask" "F.Paste")
			(net "P12V_AUX")
		)
		(pad "D6" smd circle
			(at 0.999998 0.750062)
			(size 0.2286 0.2286)
			(layers "F.Cu" "F.Mask" "F.Paste")
			(net "P12V_SCM_R")
		)
		(pad "D7" smd circle
			(at 1.500124 0.750062)
			(size 0.2286 0.2286)
			(layers "F.Cu" "F.Mask" "F.Paste")
			(net "P12V_SCM_PWRGD")
		)
	)
	(footprint ""
		(layer "F.Cu")
		(at 395.374622 -416.899344 -90)
		(property "Reference" "C6582"
			(at 0 0 270)
			(layer "F.SilkS")
			(hide yes)
			(effects
				(font
					(size 1.27 1.27)
				)
			)
		)
		(property "Value" ""
			(at 0 0 270)
			(layer "F.Fab")
			(effects
				(font
					(size 1.27 1.27)
				)
			)
		)
		(duplicate_pad_numbers_are_jumpers no)
		(fp_line
			(start -0.299974 0.150114)
			(end -0.299974 -0.150114)
			(stroke
				(width 0.1)
				(type default)
			)
			(layer "F.Fab")
		)
		(fp_line
			(start 0.299974 0.150114)
			(end -0.299974 0.150114)
			(stroke
				(width 0.1)
				(type default)
			)
			(layer "F.Fab")
		)
		(fp_line
			(start -0.299974 -0.150114)
			(end 0.299974 -0.150114)
			(stroke
				(width 0.1)
				(type default)
			)
			(layer "F.Fab")
		)
		(fp_line
			(start 0.299974 -0.150114)
			(end 0.299974 0.150114)
			(stroke
				(width 0.1)
				(type default)
			)
			(layer "F.Fab")
		)
		(pad "1" smd rect
			(at -0.2667 0 270)
			(size 0.3048 0.381)
			(layers "F.Cu" "F.Mask" "F.Paste")
			(net "P5E_CPU0_P2_TX_BUF_C_DN<8>")
		)
		(pad "2" smd rect
			(at 0.2667 0 270)
			(size 0.3048 0.381)
			(layers "F.Cu" "F.Mask" "F.Paste")
			(net "P5E_CPU0_P2_TX_BUF_DN<8>")
		)
	)
	(footprint ""
		(layer "F.Cu")
		(at 414.316418 -365.764064)
		(property "Reference" "R117"
			(at 0 0 0)
			(layer "F.SilkS")
			(hide yes)
			(effects
				(font
					(size 1.27 1.27)
				)
			)
		)
		(property "Value" ""
			(at 0 0 0)
			(layer "F.Fab")
			(effects
				(font
					(size 1.27 1.27)
				)
			)
		)
		(duplicate_pad_numbers_are_jumpers no)
		(fp_line
			(start -0.7874 -0.4064)
			(end 0.7874 -0.4064)
			(stroke
				(width 0.1524)
				(type default)
			)
			(layer "F.SilkS")
		)
		(fp_line
			(start -0.7874 0.4064)
			(end -0.7874 -0.4064)
			(stroke
				(width 0.1524)
				(type default)
			)
			(layer "F.SilkS")
		)
		(fp_line
			(start 0.7874 -0.4064)
			(end 0.7874 0.4064)
			(stroke
				(width 0.1524)
				(type default)
			)
			(layer "F.SilkS")
		)
		(fp_line
			(start 0.7874 0.4064)
			(end -0.7874 0.4064)
			(stroke
				(width 0.1524)
				(type default)
			)
			(layer "F.SilkS")
		)
		(fp_line
			(start -0.67945 -0.305054)
			(end -0.12065 -0.305054)
			(stroke
				(width 0.1)
				(type default)
			)
			(layer "F.Fab")
		)
		(fp_line
			(start -0.67945 0.3048)
			(end -0.67945 -0.305054)
			(stroke
				(width 0.1)
				(type default)
			)
			(layer "F.Fab")
		)
		(fp_line
			(start -0.12065 -0.305054)
			(end -0.12065 -0.2794)
			(stroke
				(width 0.1)
				(type default)
			)
			(layer "F.Fab")
		)
		(fp_line
			(start -0.12065 -0.2794)
			(end 0.12065 -0.2794)
			(stroke
				(width 0.1)
				(type default)
			)
			(layer "F.Fab")
		)
		(fp_line
			(start -0.12065 0.2794)
			(end -0.12065 0.3048)
			(stroke
				(width 0.1)
				(type default)
			)
			(layer "F.Fab")
		)
		(fp_line
			(start -0.12065 0.3048)
			(end -0.67945 0.3048)
			(stroke
				(width 0.1)
				(type default)
			)
			(layer "F.Fab")
		)
		(fp_line
			(start 0.120396 0.2794)
			(end -0.12065 0.2794)
			(stroke
				(width 0.1)
				(type default)
			)
			(layer "F.Fab")
		)
		(fp_line
			(start 0.120396 0.3048)
			(end 0.120396 0.2794)
			(stroke
				(width 0.1)
				(type default)
			)
			(layer "F.Fab")
		)
		(fp_line
			(start 0.12065 -0.3048)
			(end 0.67945 -0.3048)
			(stroke
				(width 0.1)
				(type default)
			)
			(layer "F.Fab")
		)
		(fp_line
			(start 0.12065 -0.2794)
			(end 0.12065 -0.3048)
			(stroke
				(width 0.1)
				(type default)
			)
			(layer "F.Fab")
		)
		(fp_line
			(start 0.67945 -0.3048)
			(end 0.67945 0.3048)
			(stroke
				(width 0.1)
				(type default)
			)
			(layer "F.Fab")
		)
		(fp_line
			(start 0.67945 0.3048)
			(end 0.120396 0.3048)
			(stroke
				(width 0.1)
				(type default)
			)
			(layer "F.Fab")
		)
		(pad "1" smd circle
			(at -0.40005 0)
			(size 0 0)
			(layers "F.Cu" "F.Mask" "F.Paste")
			(net "P3V3_AUX")
		)
		(pad "2" smd circle
			(at 0.40005 0)
			(size 0 0)
			(layers "F.Cu" "F.Mask" "F.Paste")
			(net "PWRGD_PVDD11_S3_P0_R")
		)
	)
	(footprint ""
		(layer "F.Cu")
		(at 419.966902 -349.380556 90)
		(property "Reference" "PR482"
			(at 0 0 90)
			(layer "F.SilkS")
			(hide yes)
			(effects
				(font
					(size 1.27 1.27)
				)
			)
		)
		(property "Value" ""
			(at 0 0 90)
			(layer "F.Fab")
			(effects
				(font
					(size 1.27 1.27)
				)
			)
		)
		(duplicate_pad_numbers_are_jumpers no)
		(fp_line
			(start 0.7874 -0.4064)
			(end 0.7874 0.4064)
			(stroke
				(width 0.1524)
				(type default)
			)
			(layer "F.SilkS")
		)
		(fp_line
			(start -0.7874 -0.4064)
			(end 0.7874 -0.4064)
			(stroke
				(width 0.1524)
				(type default)
			)
			(layer "F.SilkS")
		)
		(fp_line
			(start 0.7874 0.4064)
			(end -0.7874 0.4064)
			(stroke
				(width 0.1524)
				(type default)
			)
			(layer "F.SilkS")
		)
		(fp_line
			(start -0.7874 0.4064)
			(end -0.7874 -0.4064)
			(stroke
				(width 0.1524)
				(type default)
			)
			(layer "F.SilkS")
		)
		(fp_line
			(start -0.12065 -0.305054)
			(end -0.12065 -0.2794)
			(stroke
				(width 0.1)
				(type default)
			)
			(layer "F.Fab")
		)
		(fp_line
			(start -0.67945 -0.305054)
			(end -0.12065 -0.305054)
			(stroke
				(width 0.1)
				(type default)
			)
			(layer "F.Fab")
		)
		(fp_line
			(start 0.67945 -0.3048)
			(end 0.67945 0.3048)
			(stroke
				(width 0.1)
				(type default)
			)
			(layer "F.Fab")
		)
		(fp_line
			(start 0.12065 -0.3048)
			(end 0.67945 -0.3048)
			(stroke
				(width 0.1)
				(type default)
			)
			(layer "F.Fab")
		)
		(fp_line
			(start 0.12065 -0.2794)
			(end 0.12065 -0.3048)
			(stroke
				(width 0.1)
				(type default)
			)
			(layer "F.Fab")
		)
		(fp_line
			(start -0.12065 -0.2794)
			(end 0.12065 -0.2794)
			(stroke
				(width 0.1)
				(type default)
			)
			(layer "F.Fab")
		)
		(fp_line
			(start 0.120396 0.2794)
			(end -0.12065 0.2794)
			(stroke
				(width 0.1)
				(type default)
			)
			(layer "F.Fab")
		)
		(fp_line
			(start -0.12065 0.2794)
			(end -0.12065 0.3048)
			(stroke
				(width 0.1)
				(type default)
			)
			(layer "F.Fab")
		)
		(fp_line
			(start 0.67945 0.3048)
			(end 0.120396 0.3048)
			(stroke
				(width 0.1)
				(type default)
			)
			(layer "F.Fab")
		)
		(fp_line
			(start 0.120396 0.3048)
			(end 0.120396 0.2794)
			(stroke
				(width 0.1)
				(type default)
			)
			(layer "F.Fab")
		)
		(fp_line
			(start -0.12065 0.3048)
			(end -0.67945 0.3048)
			(stroke
				(width 0.1)
				(type default)
			)
			(layer "F.Fab")
		)
		(fp_line
			(start -0.67945 0.3048)
			(end -0.67945 -0.305054)
			(stroke
				(width 0.1)
				(type default)
			)
			(layer "F.Fab")
		)
		(pad "1" smd circle
			(at -0.40005 0 90)
			(size 0 0)
			(layers "F.Cu" "F.Mask" "F.Paste")
			(net "SW_PVDD11_S3_P0_SW1_RC")
		)
		(pad "2" smd circle
			(at 0.40005 0 90)
			(size 0 0)
			(layers "F.Cu" "F.Mask" "F.Paste")
			(net "GND")
		)
	)
	(footprint ""
		(layer "F.Cu")
		(at 254.362966 -68.946522)
		(property "Reference" "Q126"
			(at -1.4224 -1.768348 0)
			(unlocked yes)
			(layer "F.SilkS")
			(effects
				(font
					(size 0.7874 0.5842)
					(thickness 0.1524)
				)
				(justify left)
			)
		)
		(property "Value" ""
			(at 0 0 0)
			(layer "F.Fab")
			(effects
				(font
					(size 1.27 1.27)
				)
			)
		)
		(duplicate_pad_numbers_are_jumpers no)
		(fp_line
			(start -1.332738 -1.100074)
			(end -0.4826 -1.100074)
			(stroke
				(width 0.1524)
				(type default)
			)
			(layer "F.SilkS")
		)
		(fp_line
			(start -1.332738 1.100074)
			(end -1.332738 -1.100074)
			(stroke
				(width 0.1524)
				(type default)
			)
			(layer "F.SilkS")
		)
		(fp_line
			(start -0.4826 -1.100074)
			(end 0 -0.541274)
			(stroke
				(width 0.1524)
				(type default)
			)
			(layer "F.SilkS")
		)
		(fp_line
			(start 0 -0.541274)
			(end 0.4826 -1.100074)
			(stroke
				(width 0.1524)
				(type default)
			)
			(layer "F.SilkS")
		)
		(fp_line
			(start 0.4826 -1.100074)
			(end 1.332738 -1.100074)
			(stroke
				(width 0.1524)
				(type default)
			)
			(layer "F.SilkS")
		)
		(fp_line
			(start 1.332738 -1.100074)
			(end 1.332738 1.100074)
			(stroke
				(width 0.1524)
				(type default)
			)
			(layer "F.SilkS")
		)
		(fp_line
			(start 1.332738 1.100074)
			(end -1.332738 1.100074)
			(stroke
				(width 0.1524)
				(type default)
			)
			(layer "F.SilkS")
		)
		(fp_poly
			(pts
				(xy -1.909064 -0.710184) (xy -2.61112 -0.359156) (xy -2.61112 -1.061212)
			)
			(stroke
				(width 0)
				(type default)
			)
			(fill yes)
			(layer "F.SilkS")
		)
		(fp_line
			(start -0.674878 -1.100074)
			(end 0.674878 -1.100074)
			(stroke
				(width 0.1)
				(type default)
			)
			(layer "F.Fab")
		)
		(fp_line
			(start -0.674878 1.100074)
			(end -0.674878 -1.100074)
			(stroke
				(width 0.1)
				(type default)
			)
			(layer "F.Fab")
		)
		(fp_line
			(start 0.674878 -1.100074)
			(end 0.674878 1.100074)
			(stroke
				(width 0.1)
				(type default)
			)
			(layer "F.Fab")
		)
		(fp_line
			(start 0.674878 1.100074)
			(end -0.674878 1.100074)
			(stroke
				(width 0.1)
				(type default)
			)
			(layer "F.Fab")
		)
		(fp_poly
			(pts
				(xy -2.2352 -0.298958) (xy -2.2352 -1.001014) (xy -1.533144 -0.649986)
			)
			(stroke
				(width 0)
				(type default)
			)
			(fill yes)
			(layer "F.Fab")
		)
		(pad "1" smd rect
			(at -0.94996 -0.649986 90)
			(size 0.4318 0.508)
			(layers "F.Cu" "F.Mask" "F.Paste")
			(net "GND")
		)
		(pad "2" smd rect
			(at -0.94996 0 90)
			(size 0.4318 0.508)
			(layers "F.Cu" "F.Mask" "F.Paste")
			(net "P3V3_E1S_EN_0_R")
		)
		(pad "3" smd rect
			(at -0.94996 0.649986 90)
			(size 0.4318 0.508)
			(layers "F.Cu" "F.Mask" "F.Paste")
			(net "P3V3_E1S_UV_0_R")
		)
		(pad "4" smd rect
			(at 0.94996 0.649986 90)
			(size 0.4318 0.508)
			(layers "F.Cu" "F.Mask" "F.Paste")
			(net "GND")
		)
		(pad "5" smd rect
			(at 0.94996 0 90)
			(size 0.4318 0.508)
			(layers "F.Cu" "F.Mask" "F.Paste")
			(net "P3V3_E1S_0_EN_G")
		)
		(pad "6" smd rect
			(at 0.94996 -0.649986 90)
			(size 0.4318 0.508)
			(layers "F.Cu" "F.Mask" "F.Paste")
			(net "P3V3_E1S_0_EN_G")
		)
	)
	(footprint ""
		(layer "F.Cu")
		(at 253.08941 -45.865542 90)
		(property "Reference" "PR3968"
			(at 0 0 90)
			(layer "F.SilkS")
			(hide yes)
			(effects
				(font
					(size 1.27 1.27)
				)
			)
		)
		(property "Value" ""
			(at 0 0 90)
			(layer "F.Fab")
			(effects
				(font
					(size 1.27 1.27)
				)
			)
		)
		(duplicate_pad_numbers_are_jumpers no)
		(fp_line
			(start 0.7874 -0.4064)
			(end 0.7874 0.4064)
			(stroke
				(width 0.1524)
				(type default)
			)
			(layer "F.SilkS")
		)
		(fp_line
			(start -0.7874 -0.4064)
			(end 0.7874 -0.4064)
			(stroke
				(width 0.1524)
				(type default)
			)
			(layer "F.SilkS")
		)
		(fp_line
			(start 0.7874 0.4064)
			(end -0.7874 0.4064)
			(stroke
				(width 0.1524)
				(type default)
			)
			(layer "F.SilkS")
		)
		(fp_line
			(start -0.7874 0.4064)
			(end -0.7874 -0.4064)
			(stroke
				(width 0.1524)
				(type default)
			)
			(layer "F.SilkS")
		)
		(fp_line
			(start -0.12065 -0.305054)
			(end -0.12065 -0.2794)
			(stroke
				(width 0.1)
				(type default)
			)
			(layer "F.Fab")
		)
		(fp_line
			(start -0.67945 -0.305054)
			(end -0.12065 -0.305054)
			(stroke
				(width 0.1)
				(type default)
			)
			(layer "F.Fab")
		)
		(fp_line
			(start 0.67945 -0.3048)
			(end 0.67945 0.3048)
			(stroke
				(width 0.1)
				(type default)
			)
			(layer "F.Fab")
		)
		(fp_line
			(start 0.12065 -0.3048)
			(end 0.67945 -0.3048)
			(stroke
				(width 0.1)
				(type default)
			)
			(layer "F.Fab")
		)
		(fp_line
			(start 0.12065 -0.2794)
			(end 0.12065 -0.3048)
			(stroke
				(width 0.1)
				(type default)
			)
			(layer "F.Fab")
		)
		(fp_line
			(start -0.12065 -0.2794)
			(end 0.12065 -0.2794)
			(stroke
				(width 0.1)
				(type default)
			)
			(layer "F.Fab")
		)
		(fp_line
			(start 0.120396 0.2794)
			(end -0.12065 0.2794)
			(stroke
				(width 0.1)
				(type default)
			)
			(layer "F.Fab")
		)
		(fp_line
			(start -0.12065 0.2794)
			(end -0.12065 0.3048)
			(stroke
				(width 0.1)
				(type default)
			)
			(layer "F.Fab")
		)
		(fp_line
			(start 0.67945 0.3048)
			(end 0.120396 0.3048)
			(stroke
				(width 0.1)
				(type default)
			)
			(layer "F.Fab")
		)
		(fp_line
			(start 0.120396 0.3048)
			(end 0.120396 0.2794)
			(stroke
				(width 0.1)
				(type default)
			)
			(layer "F.Fab")
		)
		(fp_line
			(start -0.12065 0.3048)
			(end -0.67945 0.3048)
			(stroke
				(width 0.1)
				(type default)
			)
			(layer "F.Fab")
		)
		(fp_line
			(start -0.67945 0.3048)
			(end -0.67945 -0.305054)
			(stroke
				(width 0.1)
				(type default)
			)
			(layer "F.Fab")
		)
		(pad "1" smd circle
			(at -0.40005 0 90)
			(size 0 0)
			(layers "F.Cu" "F.Mask" "F.Paste")
			(net "P12V_E1S_CB_0")
		)
		(pad "2" smd circle
			(at 0.40005 0 90)
			(size 0 0)
			(layers "F.Cu" "F.Mask" "F.Paste")
			(net "GND")
		)
	)
	(footprint ""
		(layer "F.Cu")
		(at 204.689456 -340.553548)
		(property "Reference" "PC127"
			(at 0 0 0)
			(layer "F.SilkS")
			(hide yes)
			(effects
				(font
					(size 1.27 1.27)
				)
			)
		)
		(property "Value" ""
			(at 0 0 0)
			(layer "F.Fab")
			(effects
				(font
					(size 1.27 1.27)
				)
			)
		)
		(duplicate_pad_numbers_are_jumpers no)
		(fp_line
			(start -0.7874 -0.4064)
			(end 0.7874 -0.4064)
			(stroke
				(width 0.1524)
				(type default)
			)
			(layer "F.SilkS")
		)
		(fp_line
			(start -0.7874 0.4064)
			(end -0.7874 -0.4064)
			(stroke
				(width 0.1524)
				(type default)
			)
			(layer "F.SilkS")
		)
		(fp_line
			(start 0.7874 -0.4064)
			(end 0.7874 0.4064)
			(stroke
				(width 0.1524)
				(type default)
			)
			(layer "F.SilkS")
		)
		(fp_line
			(start 0.7874 0.4064)
			(end -0.7874 0.4064)
			(stroke
				(width 0.1524)
				(type default)
			)
			(layer "F.SilkS")
		)
		(fp_line
			(start -0.67945 -0.305054)
			(end -0.12065 -0.305054)
			(stroke
				(width 0.1)
				(type default)
			)
			(layer "F.Fab")
		)
		(fp_line
			(start -0.67945 0.3048)
			(end -0.67945 -0.305054)
			(stroke
				(width 0.1)
				(type default)
			)
			(layer "F.Fab")
		)
		(fp_line
			(start -0.12065 -0.305054)
			(end -0.12065 -0.2794)
			(stroke
				(width 0.1)
				(type default)
			)
			(layer "F.Fab")
		)
		(fp_line
			(start -0.12065 -0.2794)
			(end 0.12065 -0.2794)
			(stroke
				(width 0.1)
				(type default)
			)
			(layer "F.Fab")
		)
		(fp_line
			(start -0.12065 0.2794)
			(end -0.12065 0.3048)
			(stroke
				(width 0.1)
				(type default)
			)
			(layer "F.Fab")
		)
		(fp_line
			(start -0.12065 0.3048)
			(end -0.67945 0.3048)
			(stroke
				(width 0.1)
				(type default)
			)
			(layer "F.Fab")
		)
		(fp_line
			(start 0.120396 0.2794)
			(end -0.12065 0.2794)
			(stroke
				(width 0.1)
				(type default)
			)
			(layer "F.Fab")
		)
		(fp_line
			(start 0.120396 0.3048)
			(end 0.120396 0.2794)
			(stroke
				(width 0.1)
				(type default)
			)
			(layer "F.Fab")
		)
		(fp_line
			(start 0.12065 -0.3048)
			(end 0.67945 -0.3048)
			(stroke
				(width 0.1)
				(type default)
			)
			(layer "F.Fab")
		)
		(fp_line
			(start 0.12065 -0.2794)
			(end 0.12065 -0.3048)
			(stroke
				(width 0.1)
				(type default)
			)
			(layer "F.Fab")
		)
		(fp_line
			(start 0.67945 -0.3048)
			(end 0.67945 0.3048)
			(stroke
				(width 0.1)
				(type default)
			)
			(layer "F.Fab")
		)
		(fp_line
			(start 0.67945 0.3048)
			(end 0.120396 0.3048)
			(stroke
				(width 0.1)
				(type default)
			)
			(layer "F.Fab")
		)
		(pad "1" smd circle
			(at -0.40005 0)
			(size 0 0)
			(layers "F.Cu" "F.Mask" "F.Paste")
			(net "PVDD_33_S5_REF")
		)
		(pad "2" smd circle
			(at 0.40005 0)
			(size 0 0)
			(layers "F.Cu" "F.Mask" "F.Paste")
			(net "GND")
		)
	)
	(footprint ""
		(layer "F.Cu")
		(at 18.158968 -400.099276 180)
		(property "Reference" "PC6619"
			(at 8.887968 0.051054 0)
			(unlocked yes)
			(layer "F.SilkS")
			(effects
				(font
					(size 0.7874 0.5842)
					(thickness 0.1524)
				)
				(justify left)
			)
		)
		(property "Value" ""
			(at 0 0 180)
			(layer "F.Fab")
			(effects
				(font
					(size 1.27 1.27)
				)
			)
		)
		(duplicate_pad_numbers_are_jumpers no)
		(fp_line
			(start 2.750058 2.750058)
			(end 2.750058 0.9398)
			(stroke
				(width 0.1524)
				(type default)
			)
			(layer "F.SilkS")
		)
		(fp_line
			(start 2.750058 -0.9398)
			(end 2.750058 -2.750058)
			(stroke
				(width 0.1524)
				(type default)
			)
			(layer "F.SilkS")
		)
		(fp_line
			(start 2.750058 -2.750058)
			(end -1.988058 -2.750058)
			(stroke
				(width 0.1524)
				(type default)
			)
			(layer "F.SilkS")
		)
		(fp_line
			(start -1.988058 2.750058)
			(end 2.750058 2.750058)
			(stroke
				(width 0.1524)
				(type default)
			)
			(layer "F.SilkS")
		)
		(fp_line
			(start -1.988058 -2.750058)
			(end -2.750058 -1.988058)
			(stroke
				(width 0.1524)
				(type default)
			)
			(layer "F.SilkS")
		)
		(fp_line
			(start -2.750058 1.988058)
			(end -1.988058 2.750058)
			(stroke
				(width 0.1524)
				(type default)
			)
			(layer "F.SilkS")
		)
		(fp_line
			(start -2.750058 0.9398)
			(end -2.750058 1.988058)
			(stroke
				(width 0.1524)
				(type default)
			)
			(layer "F.SilkS")
		)
		(fp_line
			(start -2.750058 -1.988058)
			(end -2.750058 -0.9398)
			(stroke
				(width 0.1524)
				(type default)
			)
			(layer "F.SilkS")
		)
		(fp_line
			(start 2.750058 2.750058)
			(end 2.750058 -2.750058)
			(stroke
				(width 0.1)
				(type default)
			)
			(layer "F.Fab")
		)
		(fp_line
			(start 2.750058 -2.750058)
			(end -2.750058 -2.750058)
			(stroke
				(width 0.1)
				(type default)
			)
			(layer "F.Fab")
		)
		(fp_line
			(start -2.750058 2.750058)
			(end 2.750058 2.750058)
			(stroke
				(width 0.1)
				(type default)
			)
			(layer "F.Fab")
		)
		(fp_line
			(start -2.750058 -2.750058)
			(end -2.750058 2.750058)
			(stroke
				(width 0.1)
				(type default)
			)
			(layer "F.Fab")
		)
		(pad "1" smd rect
			(at -2.199894 0 270)
			(size 1.6002 3.0226)
			(layers "F.Cu" "F.Mask" "F.Paste")
			(net "SW_P12V_AUX_P0V9_RETIMER_CPU1_FLT")
		)
		(pad "2" smd rect
			(at 2.199894 0 270)
			(size 1.6002 3.0226)
			(layers "F.Cu" "F.Mask" "F.Paste")
			(net "GND")
		)
	)
	(footprint ""
		(layer "F.Cu")
		(at 208.894426 -116.673376 180)
		(property "Reference" "R2939"
			(at 0 0 180)
			(layer "F.SilkS")
			(hide yes)
			(effects
				(font
					(size 1.27 1.27)
				)
			)
		)
		(property "Value" ""
			(at 0 0 180)
			(layer "F.Fab")
			(effects
				(font
					(size 1.27 1.27)
				)
			)
		)
		(duplicate_pad_numbers_are_jumpers no)
		(fp_line
			(start 0.7874 0.4064)
			(end -0.7874 0.4064)
			(stroke
				(width 0.1524)
				(type default)
			)
			(layer "F.SilkS")
		)
		(fp_line
			(start 0.7874 -0.4064)
			(end 0.7874 0.4064)
			(stroke
				(width 0.1524)
				(type default)
			)
			(layer "F.SilkS")
		)
		(fp_line
			(start -0.7874 0.4064)
			(end -0.7874 -0.4064)
			(stroke
				(width 0.1524)
				(type default)
			)
			(layer "F.SilkS")
		)
		(fp_line
			(start -0.7874 -0.4064)
			(end 0.7874 -0.4064)
			(stroke
				(width 0.1524)
				(type default)
			)
			(layer "F.SilkS")
		)
		(fp_line
			(start 0.67945 0.3048)
			(end 0.120396 0.3048)
			(stroke
				(width 0.1)
				(type default)
			)
			(layer "F.Fab")
		)
		(fp_line
			(start 0.67945 -0.3048)
			(end 0.67945 0.3048)
			(stroke
				(width 0.1)
				(type default)
			)
			(layer "F.Fab")
		)
		(fp_line
			(start 0.12065 -0.2794)
			(end 0.12065 -0.3048)
			(stroke
				(width 0.1)
				(type default)
			)
			(layer "F.Fab")
		)
		(fp_line
			(start 0.12065 -0.3048)
			(end 0.67945 -0.3048)
			(stroke
				(width 0.1)
				(type default)
			)
			(layer "F.Fab")
		)
		(fp_line
			(start 0.120396 0.3048)
			(end 0.120396 0.2794)
			(stroke
				(width 0.1)
				(type default)
			)
			(layer "F.Fab")
		)
		(fp_line
			(start 0.120396 0.2794)
			(end -0.12065 0.2794)
			(stroke
				(width 0.1)
				(type default)
			)
			(layer "F.Fab")
		)
		(fp_line
			(start -0.12065 0.3048)
			(end -0.67945 0.3048)
			(stroke
				(width 0.1)
				(type default)
			)
			(layer "F.Fab")
		)
		(fp_line
			(start -0.12065 0.2794)
			(end -0.12065 0.3048)
			(stroke
				(width 0.1)
				(type default)
			)
			(layer "F.Fab")
		)
		(fp_line
			(start -0.12065 -0.2794)
			(end 0.12065 -0.2794)
			(stroke
				(width 0.1)
				(type default)
			)
			(layer "F.Fab")
		)
		(fp_line
			(start -0.12065 -0.305054)
			(end -0.12065 -0.2794)
			(stroke
				(width 0.1)
				(type default)
			)
			(layer "F.Fab")
		)
		(fp_line
			(start -0.67945 0.3048)
			(end -0.67945 -0.305054)
			(stroke
				(width 0.1)
				(type default)
			)
			(layer "F.Fab")
		)
		(fp_line
			(start -0.67945 -0.305054)
			(end -0.12065 -0.305054)
			(stroke
				(width 0.1)
				(type default)
			)
			(layer "F.Fab")
		)
		(pad "1" smd circle
			(at -0.40005 0 180)
			(size 0 0)
			(layers "F.Cu" "F.Mask" "F.Paste")
			(net "FM_GPU_HSC_EN")
		)
		(pad "2" smd circle
			(at 0.40005 0 180)
			(size 0 0)
			(layers "F.Cu" "F.Mask" "F.Paste")
			(net "FM_GPU_HSC_EN_R")
		)
	)
	(footprint ""
		(layer "F.Cu")
		(at 240.771426 -294.597074 180)
		(property "Reference" "PR6800"
			(at 0 0 180)
			(layer "F.SilkS")
			(hide yes)
			(effects
				(font
					(size 1.27 1.27)
				)
			)
		)
		(property "Value" ""
			(at 0 0 180)
			(layer "F.Fab")
			(effects
				(font
					(size 1.27 1.27)
				)
			)
		)
		(duplicate_pad_numbers_are_jumpers no)
		(fp_line
			(start 0.7874 0.4064)
			(end -0.7874 0.4064)
			(stroke
				(width 0.1524)
				(type default)
			)
			(layer "F.SilkS")
		)
		(fp_line
			(start 0.7874 -0.4064)
			(end 0.7874 0.4064)
			(stroke
				(width 0.1524)
				(type default)
			)
			(layer "F.SilkS")
		)
		(fp_line
			(start -0.7874 0.4064)
			(end -0.7874 -0.4064)
			(stroke
				(width 0.1524)
				(type default)
			)
			(layer "F.SilkS")
		)
		(fp_line
			(start -0.7874 -0.4064)
			(end 0.7874 -0.4064)
			(stroke
				(width 0.1524)
				(type default)
			)
			(layer "F.SilkS")
		)
		(fp_line
			(start 0.67945 0.3048)
			(end 0.120396 0.3048)
			(stroke
				(width 0.1)
				(type default)
			)
			(layer "F.Fab")
		)
		(fp_line
			(start 0.67945 -0.3048)
			(end 0.67945 0.3048)
			(stroke
				(width 0.1)
				(type default)
			)
			(layer "F.Fab")
		)
		(fp_line
			(start 0.12065 -0.2794)
			(end 0.12065 -0.3048)
			(stroke
				(width 0.1)
				(type default)
			)
			(layer "F.Fab")
		)
		(fp_line
			(start 0.12065 -0.3048)
			(end 0.67945 -0.3048)
			(stroke
				(width 0.1)
				(type default)
			)
			(layer "F.Fab")
		)
		(fp_line
			(start 0.120396 0.3048)
			(end 0.120396 0.2794)
			(stroke
				(width 0.1)
				(type default)
			)
			(layer "F.Fab")
		)
		(fp_line
			(start 0.120396 0.2794)
			(end -0.12065 0.2794)
			(stroke
				(width 0.1)
				(type default)
			)
			(layer "F.Fab")
		)
		(fp_line
			(start -0.12065 0.3048)
			(end -0.67945 0.3048)
			(stroke
				(width 0.1)
				(type default)
			)
			(layer "F.Fab")
		)
		(fp_line
			(start -0.12065 0.2794)
			(end -0.12065 0.3048)
			(stroke
				(width 0.1)
				(type default)
			)
			(layer "F.Fab")
		)
		(fp_line
			(start -0.12065 -0.2794)
			(end 0.12065 -0.2794)
			(stroke
				(width 0.1)
				(type default)
			)
			(layer "F.Fab")
		)
		(fp_line
			(start -0.12065 -0.305054)
			(end -0.12065 -0.2794)
			(stroke
				(width 0.1)
				(type default)
			)
			(layer "F.Fab")
		)
		(fp_line
			(start -0.67945 0.3048)
			(end -0.67945 -0.305054)
			(stroke
				(width 0.1)
				(type default)
			)
			(layer "F.Fab")
		)
		(fp_line
			(start -0.67945 -0.305054)
			(end -0.12065 -0.305054)
			(stroke
				(width 0.1)
				(type default)
			)
			(layer "F.Fab")
		)
		(pad "1" smd circle
			(at -0.40005 0 180)
			(size 0 0)
			(layers "F.Cu" "F.Mask" "F.Paste")
			(net "SW_P1V8_RETIMER_CPU0_BST")
		)
		(pad "2" smd circle
			(at 0.40005 0 180)
			(size 0 0)
			(layers "F.Cu" "F.Mask" "F.Paste")
			(net "SW_P1V8_RETIMER_CPU0_BST_R")
		)
	)
	(footprint ""
		(layer "F.Cu")
		(at 299.935646 -117.65026 90)
		(property "Reference" "R3587"
			(at 0 0 90)
			(layer "F.SilkS")
			(hide yes)
			(effects
				(font
					(size 1.27 1.27)
				)
			)
		)
		(property "Value" ""
			(at 0 0 90)
			(layer "F.Fab")
			(effects
				(font
					(size 1.27 1.27)
				)
			)
		)
		(duplicate_pad_numbers_are_jumpers no)
		(fp_line
			(start 0.7874 -0.4064)
			(end 0.7874 0.4064)
			(stroke
				(width 0.1524)
				(type default)
			)
			(layer "F.SilkS")
		)
		(fp_line
			(start -0.7874 -0.4064)
			(end 0.7874 -0.4064)
			(stroke
				(width 0.1524)
				(type default)
			)
			(layer "F.SilkS")
		)
		(fp_line
			(start 0.7874 0.4064)
			(end -0.7874 0.4064)
			(stroke
				(width 0.1524)
				(type default)
			)
			(layer "F.SilkS")
		)
		(fp_line
			(start -0.7874 0.4064)
			(end -0.7874 -0.4064)
			(stroke
				(width 0.1524)
				(type default)
			)
			(layer "F.SilkS")
		)
		(fp_line
			(start -0.12065 -0.305054)
			(end -0.12065 -0.2794)
			(stroke
				(width 0.1)
				(type default)
			)
			(layer "F.Fab")
		)
		(fp_line
			(start -0.67945 -0.305054)
			(end -0.12065 -0.305054)
			(stroke
				(width 0.1)
				(type default)
			)
			(layer "F.Fab")
		)
		(fp_line
			(start 0.67945 -0.3048)
			(end 0.67945 0.3048)
			(stroke
				(width 0.1)
				(type default)
			)
			(layer "F.Fab")
		)
		(fp_line
			(start 0.12065 -0.3048)
			(end 0.67945 -0.3048)
			(stroke
				(width 0.1)
				(type default)
			)
			(layer "F.Fab")
		)
		(fp_line
			(start 0.12065 -0.2794)
			(end 0.12065 -0.3048)
			(stroke
				(width 0.1)
				(type default)
			)
			(layer "F.Fab")
		)
		(fp_line
			(start -0.12065 -0.2794)
			(end 0.12065 -0.2794)
			(stroke
				(width 0.1)
				(type default)
			)
			(layer "F.Fab")
		)
		(fp_line
			(start 0.120396 0.2794)
			(end -0.12065 0.2794)
			(stroke
				(width 0.1)
				(type default)
			)
			(layer "F.Fab")
		)
		(fp_line
			(start -0.12065 0.2794)
			(end -0.12065 0.3048)
			(stroke
				(width 0.1)
				(type default)
			)
			(layer "F.Fab")
		)
		(fp_line
			(start 0.67945 0.3048)
			(end 0.120396 0.3048)
			(stroke
				(width 0.1)
				(type default)
			)
			(layer "F.Fab")
		)
		(fp_line
			(start 0.120396 0.3048)
			(end 0.120396 0.2794)
			(stroke
				(width 0.1)
				(type default)
			)
			(layer "F.Fab")
		)
		(fp_line
			(start -0.12065 0.3048)
			(end -0.67945 0.3048)
			(stroke
				(width 0.1)
				(type default)
			)
			(layer "F.Fab")
		)
		(fp_line
			(start -0.67945 0.3048)
			(end -0.67945 -0.305054)
			(stroke
				(width 0.1)
				(type default)
			)
			(layer "F.Fab")
		)
		(pad "1" smd circle
			(at -0.40005 0 90)
			(size 0 0)
			(layers "F.Cu" "F.Mask" "F.Paste")
			(net "SMB_INA230_3V3AUX_SDA")
		)
		(pad "2" smd circle
			(at 0.40005 0 90)
			(size 0 0)
			(layers "F.Cu" "F.Mask" "F.Paste")
			(net "SMB_INA230_1_3V3AUX_SDA_R")
		)
	)
	(footprint ""
		(layer "F.Cu")
		(at 101.948234 -142.59941 180)
		(property "Reference" "PR157"
			(at 0 0 180)
			(layer "F.SilkS")
			(hide yes)
			(effects
				(font
					(size 1.27 1.27)
				)
			)
		)
		(property "Value" ""
			(at 0 0 180)
			(layer "F.Fab")
			(effects
				(font
					(size 1.27 1.27)
				)
			)
		)
		(duplicate_pad_numbers_are_jumpers no)
		(fp_line
			(start 0.7874 0.4064)
			(end -0.7874 0.4064)
			(stroke
				(width 0.1524)
				(type default)
			)
			(layer "F.SilkS")
		)
		(fp_line
			(start 0.7874 -0.4064)
			(end 0.7874 0.4064)
			(stroke
				(width 0.1524)
				(type default)
			)
			(layer "F.SilkS")
		)
		(fp_line
			(start -0.7874 0.4064)
			(end -0.7874 -0.4064)
			(stroke
				(width 0.1524)
				(type default)
			)
			(layer "F.SilkS")
		)
		(fp_line
			(start -0.7874 -0.4064)
			(end 0.7874 -0.4064)
			(stroke
				(width 0.1524)
				(type default)
			)
			(layer "F.SilkS")
		)
		(fp_line
			(start 0.67945 0.3048)
			(end 0.120396 0.3048)
			(stroke
				(width 0.1)
				(type default)
			)
			(layer "F.Fab")
		)
		(fp_line
			(start 0.67945 -0.3048)
			(end 0.67945 0.3048)
			(stroke
				(width 0.1)
				(type default)
			)
			(layer "F.Fab")
		)
		(fp_line
			(start 0.12065 -0.2794)
			(end 0.12065 -0.3048)
			(stroke
				(width 0.1)
				(type default)
			)
			(layer "F.Fab")
		)
		(fp_line
			(start 0.12065 -0.3048)
			(end 0.67945 -0.3048)
			(stroke
				(width 0.1)
				(type default)
			)
			(layer "F.Fab")
		)
		(fp_line
			(start 0.120396 0.3048)
			(end 0.120396 0.2794)
			(stroke
				(width 0.1)
				(type default)
			)
			(layer "F.Fab")
		)
		(fp_line
			(start 0.120396 0.2794)
			(end -0.12065 0.2794)
			(stroke
				(width 0.1)
				(type default)
			)
			(layer "F.Fab")
		)
		(fp_line
			(start -0.12065 0.3048)
			(end -0.67945 0.3048)
			(stroke
				(width 0.1)
				(type default)
			)
			(layer "F.Fab")
		)
		(fp_line
			(start -0.12065 0.2794)
			(end -0.12065 0.3048)
			(stroke
				(width 0.1)
				(type default)
			)
			(layer "F.Fab")
		)
		(fp_line
			(start -0.12065 -0.2794)
			(end 0.12065 -0.2794)
			(stroke
				(width 0.1)
				(type default)
			)
			(layer "F.Fab")
		)
		(fp_line
			(start -0.12065 -0.305054)
			(end -0.12065 -0.2794)
			(stroke
				(width 0.1)
				(type default)
			)
			(layer "F.Fab")
		)
		(fp_line
			(start -0.67945 0.3048)
			(end -0.67945 -0.305054)
			(stroke
				(width 0.1)
				(type default)
			)
			(layer "F.Fab")
		)
		(fp_line
			(start -0.67945 -0.305054)
			(end -0.12065 -0.305054)
			(stroke
				(width 0.1)
				(type default)
			)
			(layer "F.Fab")
		)
		(pad "1" smd circle
			(at -0.40005 0 180)
			(size 0 0)
			(layers "F.Cu" "F.Mask" "F.Paste")
			(net "P5V_AUX")
		)
		(pad "2" smd circle
			(at 0.40005 0 180)
			(size 0 0)
			(layers "F.Cu" "F.Mask" "F.Paste")
			(net "PVDDCR_CPU0_P1_VMON")
		)
	)
	(footprint ""
		(layer "F.Cu")
		(at 439.072782 -439.12536 -90)
		(property "Reference" "R4160"
			(at 0 0 270)
			(layer "F.SilkS")
			(hide yes)
			(effects
				(font
					(size 1.27 1.27)
				)
			)
		)
		(property "Value" ""
			(at 0 0 270)
			(layer "F.Fab")
			(effects
				(font
					(size 1.27 1.27)
				)
			)
		)
		(duplicate_pad_numbers_are_jumpers no)
		(fp_line
			(start -0.7874 0.4064)
			(end -0.7874 -0.4064)
			(stroke
				(width 0.1524)
				(type default)
			)
			(layer "F.SilkS")
		)
		(fp_line
			(start 0.7874 0.4064)
			(end -0.7874 0.4064)
			(stroke
				(width 0.1524)
				(type default)
			)
			(layer "F.SilkS")
		)
		(fp_line
			(start -0.7874 -0.4064)
			(end 0.7874 -0.4064)
			(stroke
				(width 0.1524)
				(type default)
			)
			(layer "F.SilkS")
		)
		(fp_line
			(start 0.7874 -0.4064)
			(end 0.7874 0.4064)
			(stroke
				(width 0.1524)
				(type default)
			)
			(layer "F.SilkS")
		)
		(fp_line
			(start -0.67945 0.3048)
			(end -0.67945 -0.305054)
			(stroke
				(width 0.1)
				(type default)
			)
			(layer "F.Fab")
		)
		(fp_line
			(start -0.12065 0.3048)
			(end -0.67945 0.3048)
			(stroke
				(width 0.1)
				(type default)
			)
			(layer "F.Fab")
		)
		(fp_line
			(start 0.120396 0.3048)
			(end 0.120396 0.2794)
			(stroke
				(width 0.1)
				(type default)
			)
			(layer "F.Fab")
		)
		(fp_line
			(start 0.67945 0.3048)
			(end 0.120396 0.3048)
			(stroke
				(width 0.1)
				(type default)
			)
			(layer "F.Fab")
		)
		(fp_line
			(start -0.12065 0.2794)
			(end -0.12065 0.3048)
			(stroke
				(width 0.1)
				(type default)
			)
			(layer "F.Fab")
		)
		(fp_line
			(start 0.120396 0.2794)
			(end -0.12065 0.2794)
			(stroke
				(width 0.1)
				(type default)
			)
			(layer "F.Fab")
		)
		(fp_line
			(start -0.12065 -0.2794)
			(end 0.12065 -0.2794)
			(stroke
				(width 0.1)
				(type default)
			)
			(layer "F.Fab")
		)
		(fp_line
			(start 0.12065 -0.2794)
			(end 0.12065 -0.3048)
			(stroke
				(width 0.1)
				(type default)
			)
			(layer "F.Fab")
		)
		(fp_line
			(start 0.12065 -0.3048)
			(end 0.67945 -0.3048)
			(stroke
				(width 0.1)
				(type default)
			)
			(layer "F.Fab")
		)
		(fp_line
			(start 0.67945 -0.3048)
			(end 0.67945 0.3048)
			(stroke
				(width 0.1)
				(type default)
			)
			(layer "F.Fab")
		)
		(fp_line
			(start -0.67945 -0.305054)
			(end -0.12065 -0.305054)
			(stroke
				(width 0.1)
				(type default)
			)
			(layer "F.Fab")
		)
		(fp_line
			(start -0.12065 -0.305054)
			(end -0.12065 -0.2794)
			(stroke
				(width 0.1)
				(type default)
			)
			(layer "F.Fab")
		)
		(pad "1" smd circle
			(at -0.40005 0 270)
			(size 0 0)
			(layers "F.Cu" "F.Mask" "F.Paste")
			(net "P3V3_AUX")
		)
		(pad "2" smd circle
			(at 0.40005 0 270)
			(size 0 0)
			(layers "F.Cu" "F.Mask" "F.Paste")
			(net "GPU_3V3IO_RSVD4")
		)
	)
	(footprint ""
		(layer "F.Cu")
		(at 277.265892 -385.27736 90)
		(property "Reference" "PPQ9"
			(at -7.517384 -2.267712 0)
			(unlocked yes)
			(layer "F.SilkS")
			(effects
				(font
					(size 0.7874 0.5842)
					(thickness 0.1524)
				)
				(justify left)
			)
		)
		(property "Value" ""
			(at 0 0 90)
			(layer "F.Fab")
			(effects
				(font
					(size 1.27 1.27)
				)
			)
		)
		(duplicate_pad_numbers_are_jumpers no)
		(fp_line
			(start 2.350008 -2.649982)
			(end 2.350008 -2.4892)
			(stroke
				(width 0.1524)
				(type default)
			)
			(layer "F.SilkS")
		)
		(fp_line
			(start -2.350008 -2.649982)
			(end 2.350008 -2.649982)
			(stroke
				(width 0.1524)
				(type default)
			)
			(layer "F.SilkS")
		)
		(fp_line
			(start -2.350008 -2.4384)
			(end -2.350008 -2.649982)
			(stroke
				(width 0.1524)
				(type default)
			)
			(layer "F.SilkS")
		)
		(fp_line
			(start 2.350008 2.4892)
			(end 2.350008 2.649982)
			(stroke
				(width 0.1524)
				(type default)
			)
			(layer "F.SilkS")
		)
		(fp_line
			(start 2.350008 2.649982)
			(end -2.350008 2.649982)
			(stroke
				(width 0.1524)
				(type default)
			)
			(layer "F.SilkS")
		)
		(fp_line
			(start -2.350008 2.649982)
			(end -2.350008 2.413)
			(stroke
				(width 0.1524)
				(type default)
			)
			(layer "F.SilkS")
		)
		(fp_poly
			(pts
				(xy -3.440938 -3.44805) (xy -2.640838 -3.440176) (xy -3.070098 -2.40284)
			)
			(stroke
				(width 0)
				(type default)
			)
			(fill yes)
			(layer "F.SilkS")
		)
		(fp_line
			(start 2.350008 -2.649982)
			(end 2.350008 2.649982)
			(stroke
				(width 0.1)
				(type default)
			)
			(layer "F.Fab")
		)
		(fp_line
			(start -2.350008 -2.649982)
			(end 2.350008 -2.649982)
			(stroke
				(width 0.1)
				(type default)
			)
			(layer "F.Fab")
		)
		(fp_line
			(start 2.350008 2.649982)
			(end -2.350008 2.649982)
			(stroke
				(width 0.1)
				(type default)
			)
			(layer "F.Fab")
		)
		(fp_line
			(start -2.350008 2.649982)
			(end -2.350008 -2.649982)
			(stroke
				(width 0.1)
				(type default)
			)
			(layer "F.Fab")
		)
		(fp_poly
			(pts
				(xy -3.717544 -1.905) (xy -4.758944 -2.3241) (xy -4.758944 -1.524)
			)
			(stroke
				(width 0)
				(type default)
			)
			(fill yes)
			(layer "F.Fab")
		)
		(pad "1" smd rect
			(at -2.999994 -1.905)
			(size 0.7112 1.1684)
			(layers "F.Cu" "F.Mask" "F.Paste")
			(net "P12V_AUX")
		)
		(pad "2" smd rect
			(at -2.999994 -0.635)
			(size 0.7112 1.1684)
			(layers "F.Cu" "F.Mask" "F.Paste")
			(net "P12V_AUX")
		)
		(pad "3" smd rect
			(at -2.999994 0.635)
			(size 0.7112 1.1684)
			(layers "F.Cu" "F.Mask" "F.Paste")
			(net "P12V_AUX")
		)
		(pad "4" smd rect
			(at -2.999994 1.905)
			(size 0.7112 1.1684)
			(layers "F.Cu" "F.Mask" "F.Paste")
			(net "MB0_CM_GATE_G0")
		)
		(pad "5" smd circle
			(at 0.925068 0)
			(size 0 0)
			(layers "F.Cu" "F.Mask" "F.Paste")
			(net "P12V_MAIN_R_0")
		)
		(zone
			(layer "F.Cu")
			(hatch none 0.5)
			(connect_pads
				(clearance 0)
			)
			(min_thickness 0.25)
			(keepout
				(tracks not_allowed)
				(vias allowed)
				(pads allowed)
				(copperpour not_allowed)
				(footprints allowed)
			)
			(placement
				(enabled no)
				(sheetname "")
			)
			(fill
				(thermal_gap 0.5)
				(thermal_bridge_width 0.5)
				(island_removal_mode 0)
			)
			(polygon
				(pts
					(xy 274.624292 -383.7178) (xy 279.907492 -383.7178) (xy 279.907492 -382.92786) (xy 274.624292 -382.92786)
				)
			)
		)
	)
	(footprint ""
		(layer "F.Cu")
		(at 101.035358 -344.796872 90)
		(property "Reference" "PC136_6"
			(at 0 0 90)
			(layer "F.SilkS")
			(hide yes)
			(effects
				(font
					(size 1.27 1.27)
				)
			)
		)
		(property "Value" ""
			(at 0 0 90)
			(layer "F.Fab")
			(effects
				(font
					(size 1.27 1.27)
				)
			)
		)
		(duplicate_pad_numbers_are_jumpers no)
		(fp_line
			(start 0.7874 -0.4064)
			(end 0.7874 0.4064)
			(stroke
				(width 0.1524)
				(type default)
			)
			(layer "F.SilkS")
		)
		(fp_line
			(start -0.7874 -0.4064)
			(end 0.7874 -0.4064)
			(stroke
				(width 0.1524)
				(type default)
			)
			(layer "F.SilkS")
		)
		(fp_line
			(start 0.7874 0.4064)
			(end -0.7874 0.4064)
			(stroke
				(width 0.1524)
				(type default)
			)
			(layer "F.SilkS")
		)
		(fp_line
			(start -0.7874 0.4064)
			(end -0.7874 -0.4064)
			(stroke
				(width 0.1524)
				(type default)
			)
			(layer "F.SilkS")
		)
		(fp_line
			(start -0.12065 -0.305054)
			(end -0.12065 -0.2794)
			(stroke
				(width 0.1)
				(type default)
			)
			(layer "F.Fab")
		)
		(fp_line
			(start -0.67945 -0.305054)
			(end -0.12065 -0.305054)
			(stroke
				(width 0.1)
				(type default)
			)
			(layer "F.Fab")
		)
		(fp_line
			(start 0.67945 -0.3048)
			(end 0.67945 0.3048)
			(stroke
				(width 0.1)
				(type default)
			)
			(layer "F.Fab")
		)
		(fp_line
			(start 0.12065 -0.3048)
			(end 0.67945 -0.3048)
			(stroke
				(width 0.1)
				(type default)
			)
			(layer "F.Fab")
		)
		(fp_line
			(start 0.12065 -0.2794)
			(end 0.12065 -0.3048)
			(stroke
				(width 0.1)
				(type default)
			)
			(layer "F.Fab")
		)
		(fp_line
			(start -0.12065 -0.2794)
			(end 0.12065 -0.2794)
			(stroke
				(width 0.1)
				(type default)
			)
			(layer "F.Fab")
		)
		(fp_line
			(start 0.120396 0.2794)
			(end -0.12065 0.2794)
			(stroke
				(width 0.1)
				(type default)
			)
			(layer "F.Fab")
		)
		(fp_line
			(start -0.12065 0.2794)
			(end -0.12065 0.3048)
			(stroke
				(width 0.1)
				(type default)
			)
			(layer "F.Fab")
		)
		(fp_line
			(start 0.67945 0.3048)
			(end 0.120396 0.3048)
			(stroke
				(width 0.1)
				(type default)
			)
			(layer "F.Fab")
		)
		(fp_line
			(start 0.120396 0.3048)
			(end 0.120396 0.2794)
			(stroke
				(width 0.1)
				(type default)
			)
			(layer "F.Fab")
		)
		(fp_line
			(start -0.12065 0.3048)
			(end -0.67945 0.3048)
			(stroke
				(width 0.1)
				(type default)
			)
			(layer "F.Fab")
		)
		(fp_line
			(start -0.67945 0.3048)
			(end -0.67945 -0.305054)
			(stroke
				(width 0.1)
				(type default)
			)
			(layer "F.Fab")
		)
		(pad "1" smd circle
			(at -0.40005 0 90)
			(size 0 0)
			(layers "F.Cu" "F.Mask" "F.Paste")
			(net "PVDDCR_CPU1_P1_VCCS")
		)
		(pad "2" smd circle
			(at 0.40005 0 90)
			(size 0 0)
			(layers "F.Cu" "F.Mask" "F.Paste")
			(net "GND")
		)
	)
	(footprint ""
		(layer "F.Cu")
		(at 289.136074 -397.85163 -90)
		(property "Reference" "R1210"
			(at 0 0 270)
			(layer "F.SilkS")
			(hide yes)
			(effects
				(font
					(size 1.27 1.27)
				)
			)
		)
		(property "Value" ""
			(at 0 0 270)
			(layer "F.Fab")
			(effects
				(font
					(size 1.27 1.27)
				)
			)
		)
		(duplicate_pad_numbers_are_jumpers no)
		(fp_line
			(start -0.32512 0.175006)
			(end -0.32512 -0.175006)
			(stroke
				(width 0.1)
				(type default)
			)
			(layer "F.Fab")
		)
		(fp_line
			(start 0.32512 0.175006)
			(end -0.32512 0.175006)
			(stroke
				(width 0.1)
				(type default)
			)
			(layer "F.Fab")
		)
		(fp_line
			(start -0.32512 -0.175006)
			(end 0.32512 -0.175006)
			(stroke
				(width 0.1)
				(type default)
			)
			(layer "F.Fab")
		)
		(fp_line
			(start 0.32512 -0.175006)
			(end 0.32512 0.175006)
			(stroke
				(width 0.1)
				(type default)
			)
			(layer "F.Fab")
		)
		(pad "1" smd rect
			(at -0.2667 0 270)
			(size 0.3048 0.381)
			(layers "F.Cu" "F.Mask" "F.Paste")
			(net "RST_SMB_RT_ROM_R1_N")
		)
		(pad "2" smd rect
			(at 0.2667 0 90)
			(size 0.3048 0.381)
			(layers "F.Cu" "F.Mask" "F.Paste")
			(net "FM_SMB_RT_ROM_MUX6_SEL")
		)
	)
	(footprint ""
		(layer "F.Cu")
		(at 324.168262 -404.0124 -90)
		(property "Reference" "R953"
			(at 0 0 270)
			(layer "F.SilkS")
			(hide yes)
			(effects
				(font
					(size 1.27 1.27)
				)
			)
		)
		(property "Value" ""
			(at 0 0 270)
			(layer "F.Fab")
			(effects
				(font
					(size 1.27 1.27)
				)
			)
		)
		(duplicate_pad_numbers_are_jumpers no)
		(fp_line
			(start -0.32512 0.175006)
			(end -0.32512 -0.175006)
			(stroke
				(width 0.1)
				(type default)
			)
			(layer "F.Fab")
		)
		(fp_line
			(start 0.32512 0.175006)
			(end -0.32512 0.175006)
			(stroke
				(width 0.1)
				(type default)
			)
			(layer "F.Fab")
		)
		(fp_line
			(start -0.32512 -0.175006)
			(end 0.32512 -0.175006)
			(stroke
				(width 0.1)
				(type default)
			)
			(layer "F.Fab")
		)
		(fp_line
			(start 0.32512 -0.175006)
			(end 0.32512 0.175006)
			(stroke
				(width 0.1)
				(type default)
			)
			(layer "F.Fab")
		)
		(pad "1" smd rect
			(at -0.2667 0 270)
			(size 0.3048 0.381)
			(layers "F.Cu" "F.Mask" "F.Paste")
			(net "RST_RT_CPU0_P0_PERST_N")
		)
		(pad "2" smd rect
			(at 0.2667 0 90)
			(size 0.3048 0.381)
			(layers "F.Cu" "F.Mask" "F.Paste")
			(net "RST_RT_CPU0_P0_PERST_R_N")
		)
	)
	(footprint ""
		(layer "F.Cu")
		(at 390.513316 -22.789134 90)
		(property "Reference" "R46"
			(at 0 0 90)
			(layer "F.SilkS")
			(hide yes)
			(effects
				(font
					(size 1.27 1.27)
				)
			)
		)
		(property "Value" ""
			(at 0 0 90)
			(layer "F.Fab")
			(effects
				(font
					(size 1.27 1.27)
				)
			)
		)
		(duplicate_pad_numbers_are_jumpers no)
		(fp_line
			(start 0.7874 0.011684)
			(end 0.7874 0.4064)
			(stroke
				(width 0.1524)
				(type default)
			)
			(layer "F.SilkS")
		)
		(fp_line
			(start 0.7874 0.4064)
			(end -0.7874 0.4064)
			(stroke
				(width 0.1524)
				(type default)
			)
			(layer "F.SilkS")
		)
		(fp_line
			(start -0.7874 0.4064)
			(end -0.7874 0.011684)
			(stroke
				(width 0.1524)
				(type default)
			)
			(layer "F.SilkS")
		)
		(fp_line
			(start -0.12065 -0.305054)
			(end -0.12065 -0.2794)
			(stroke
				(width 0.1)
				(type default)
			)
			(layer "F.Fab")
		)
		(fp_line
			(start -0.67945 -0.305054)
			(end -0.12065 -0.305054)
			(stroke
				(width 0.1)
				(type default)
			)
			(layer "F.Fab")
		)
		(fp_line
			(start 0.67945 -0.3048)
			(end 0.67945 0.3048)
			(stroke
				(width 0.1)
				(type default)
			)
			(layer "F.Fab")
		)
		(fp_line
			(start 0.12065 -0.3048)
			(end 0.67945 -0.3048)
			(stroke
				(width 0.1)
				(type default)
			)
			(layer "F.Fab")
		)
		(fp_line
			(start 0.12065 -0.2794)
			(end 0.12065 -0.3048)
			(stroke
				(width 0.1)
				(type default)
			)
			(layer "F.Fab")
		)
		(fp_line
			(start -0.12065 -0.2794)
			(end 0.12065 -0.2794)
			(stroke
				(width 0.1)
				(type default)
			)
			(layer "F.Fab")
		)
		(fp_line
			(start 0.120396 0.2794)
			(end -0.12065 0.2794)
			(stroke
				(width 0.1)
				(type default)
			)
			(layer "F.Fab")
		)
		(fp_line
			(start -0.12065 0.2794)
			(end -0.12065 0.3048)
			(stroke
				(width 0.1)
				(type default)
			)
			(layer "F.Fab")
		)
		(fp_line
			(start 0.67945 0.3048)
			(end 0.120396 0.3048)
			(stroke
				(width 0.1)
				(type default)
			)
			(layer "F.Fab")
		)
		(fp_line
			(start 0.120396 0.3048)
			(end 0.120396 0.2794)
			(stroke
				(width 0.1)
				(type default)
			)
			(layer "F.Fab")
		)
		(fp_line
			(start -0.12065 0.3048)
			(end -0.67945 0.3048)
			(stroke
				(width 0.1)
				(type default)
			)
			(layer "F.Fab")
		)
		(fp_line
			(start -0.67945 0.3048)
			(end -0.67945 -0.305054)
			(stroke
				(width 0.1)
				(type default)
			)
			(layer "F.Fab")
		)
		(pad "1" smd circle
			(at -0.40005 0 90)
			(size 0 0)
			(layers "F.Cu" "F.Mask" "F.Paste")
			(net "USB2_P11_DP")
		)
		(pad "2" smd circle
			(at 0.40005 0 90)
			(size 0 0)
			(layers "F.Cu" "F.Mask" "F.Paste")
			(net "USB2_CPU0_P11_DP")
		)
	)
	(footprint ""
		(layer "F.Cu")
		(at 43.4721 -171.831)
		(property "Reference" "R989"
			(at 0 0 0)
			(layer "F.SilkS")
			(hide yes)
			(effects
				(font
					(size 1.27 1.27)
				)
			)
		)
		(property "Value" ""
			(at 0 0 0)
			(layer "F.Fab")
			(effects
				(font
					(size 1.27 1.27)
				)
			)
		)
		(duplicate_pad_numbers_are_jumpers no)
		(fp_line
			(start -0.7874 -0.4064)
			(end 0.7874 -0.4064)
			(stroke
				(width 0.1524)
				(type default)
			)
			(layer "F.SilkS")
		)
		(fp_line
			(start -0.7874 0.4064)
			(end -0.7874 -0.4064)
			(stroke
				(width 0.1524)
				(type default)
			)
			(layer "F.SilkS")
		)
		(fp_line
			(start 0.7874 -0.4064)
			(end 0.7874 0.4064)
			(stroke
				(width 0.1524)
				(type default)
			)
			(layer "F.SilkS")
		)
		(fp_line
			(start 0.7874 0.4064)
			(end -0.7874 0.4064)
			(stroke
				(width 0.1524)
				(type default)
			)
			(layer "F.SilkS")
		)
		(fp_line
			(start -0.67945 -0.305054)
			(end -0.12065 -0.305054)
			(stroke
				(width 0.1)
				(type default)
			)
			(layer "F.Fab")
		)
		(fp_line
			(start -0.67945 0.3048)
			(end -0.67945 -0.305054)
			(stroke
				(width 0.1)
				(type default)
			)
			(layer "F.Fab")
		)
		(fp_line
			(start -0.12065 -0.305054)
			(end -0.12065 -0.2794)
			(stroke
				(width 0.1)
				(type default)
			)
			(layer "F.Fab")
		)
		(fp_line
			(start -0.12065 -0.2794)
			(end 0.12065 -0.2794)
			(stroke
				(width 0.1)
				(type default)
			)
			(layer "F.Fab")
		)
		(fp_line
			(start -0.12065 0.2794)
			(end -0.12065 0.3048)
			(stroke
				(width 0.1)
				(type default)
			)
			(layer "F.Fab")
		)
		(fp_line
			(start -0.12065 0.3048)
			(end -0.67945 0.3048)
			(stroke
				(width 0.1)
				(type default)
			)
			(layer "F.Fab")
		)
		(fp_line
			(start 0.120396 0.2794)
			(end -0.12065 0.2794)
			(stroke
				(width 0.1)
				(type default)
			)
			(layer "F.Fab")
		)
		(fp_line
			(start 0.120396 0.3048)
			(end 0.120396 0.2794)
			(stroke
				(width 0.1)
				(type default)
			)
			(layer "F.Fab")
		)
		(fp_line
			(start 0.12065 -0.3048)
			(end 0.67945 -0.3048)
			(stroke
				(width 0.1)
				(type default)
			)
			(layer "F.Fab")
		)
		(fp_line
			(start 0.12065 -0.2794)
			(end 0.12065 -0.3048)
			(stroke
				(width 0.1)
				(type default)
			)
			(layer "F.Fab")
		)
		(fp_line
			(start 0.67945 -0.3048)
			(end 0.67945 0.3048)
			(stroke
				(width 0.1)
				(type default)
			)
			(layer "F.Fab")
		)
		(fp_line
			(start 0.67945 0.3048)
			(end 0.120396 0.3048)
			(stroke
				(width 0.1)
				(type default)
			)
			(layer "F.Fab")
		)
		(pad "1" smd rect
			(at -0.40005 0 180)
			(size 0.4572 0.508)
			(layers "F.Cu" "F.Mask" "F.Paste")
			(net "I3C_0_SPD_DDRAF_CPU1_R_SDA")
		)
		(pad "2" smd rect
			(at 0.40005 0 180)
			(size 0.4572 0.508)
			(layers "F.Cu" "F.Mask" "F.Paste")
			(net "I3C_SPD_DDRAF_CPU1_BYPASS_SDA")
		)
	)
	(footprint ""
		(layer "F.Cu")
		(at 49.866296 -344.986864 90)
		(property "Reference" "PR488"
			(at 0 0 90)
			(layer "F.SilkS")
			(hide yes)
			(effects
				(font
					(size 1.27 1.27)
				)
			)
		)
		(property "Value" ""
			(at 0 0 90)
			(layer "F.Fab")
			(effects
				(font
					(size 1.27 1.27)
				)
			)
		)
		(duplicate_pad_numbers_are_jumpers no)
		(fp_line
			(start 0.7874 -0.4064)
			(end 0.7874 0.4064)
			(stroke
				(width 0.1524)
				(type default)
			)
			(layer "F.SilkS")
		)
		(fp_line
			(start -0.7874 -0.4064)
			(end 0.7874 -0.4064)
			(stroke
				(width 0.1524)
				(type default)
			)
			(layer "F.SilkS")
		)
		(fp_line
			(start 0.7874 0.4064)
			(end -0.7874 0.4064)
			(stroke
				(width 0.1524)
				(type default)
			)
			(layer "F.SilkS")
		)
		(fp_line
			(start -0.7874 0.4064)
			(end -0.7874 -0.4064)
			(stroke
				(width 0.1524)
				(type default)
			)
			(layer "F.SilkS")
		)
		(fp_line
			(start -0.12065 -0.305054)
			(end -0.12065 -0.2794)
			(stroke
				(width 0.1)
				(type default)
			)
			(layer "F.Fab")
		)
		(fp_line
			(start -0.67945 -0.305054)
			(end -0.12065 -0.305054)
			(stroke
				(width 0.1)
				(type default)
			)
			(layer "F.Fab")
		)
		(fp_line
			(start 0.67945 -0.3048)
			(end 0.67945 0.3048)
			(stroke
				(width 0.1)
				(type default)
			)
			(layer "F.Fab")
		)
		(fp_line
			(start 0.12065 -0.3048)
			(end 0.67945 -0.3048)
			(stroke
				(width 0.1)
				(type default)
			)
			(layer "F.Fab")
		)
		(fp_line
			(start 0.12065 -0.2794)
			(end 0.12065 -0.3048)
			(stroke
				(width 0.1)
				(type default)
			)
			(layer "F.Fab")
		)
		(fp_line
			(start -0.12065 -0.2794)
			(end 0.12065 -0.2794)
			(stroke
				(width 0.1)
				(type default)
			)
			(layer "F.Fab")
		)
		(fp_line
			(start 0.120396 0.2794)
			(end -0.12065 0.2794)
			(stroke
				(width 0.1)
				(type default)
			)
			(layer "F.Fab")
		)
		(fp_line
			(start -0.12065 0.2794)
			(end -0.12065 0.3048)
			(stroke
				(width 0.1)
				(type default)
			)
			(layer "F.Fab")
		)
		(fp_line
			(start 0.67945 0.3048)
			(end 0.120396 0.3048)
			(stroke
				(width 0.1)
				(type default)
			)
			(layer "F.Fab")
		)
		(fp_line
			(start 0.120396 0.3048)
			(end 0.120396 0.2794)
			(stroke
				(width 0.1)
				(type default)
			)
			(layer "F.Fab")
		)
		(fp_line
			(start -0.12065 0.3048)
			(end -0.67945 0.3048)
			(stroke
				(width 0.1)
				(type default)
			)
			(layer "F.Fab")
		)
		(fp_line
			(start -0.67945 0.3048)
			(end -0.67945 -0.305054)
			(stroke
				(width 0.1)
				(type default)
			)
			(layer "F.Fab")
		)
		(pad "1" smd circle
			(at -0.40005 0 90)
			(size 0 0)
			(layers "F.Cu" "F.Mask" "F.Paste")
			(net "SW_PVDDIO_P1_SW1_RC")
		)
		(pad "2" smd circle
			(at 0.40005 0 90)
			(size 0 0)
			(layers "F.Cu" "F.Mask" "F.Paste")
			(net "GND")
		)
	)
	(footprint ""
		(layer "F.Cu")
		(at 47.861982 -397.751808)
		(property "Reference" "C240"
			(at 0 0 0)
			(layer "F.SilkS")
			(hide yes)
			(effects
				(font
					(size 1.27 1.27)
				)
			)
		)
		(property "Value" ""
			(at 0 0 0)
			(layer "F.Fab")
			(effects
				(font
					(size 1.27 1.27)
				)
			)
		)
		(duplicate_pad_numbers_are_jumpers no)
		(fp_line
			(start -1.524 -0.762)
			(end 1.524 -0.762)
			(stroke
				(width 0.1524)
				(type default)
			)
			(layer "F.SilkS")
		)
		(fp_line
			(start -1.524 0.762)
			(end -1.524 -0.762)
			(stroke
				(width 0.1524)
				(type default)
			)
			(layer "F.SilkS")
		)
		(fp_line
			(start 1.524 -0.762)
			(end 1.524 0.762)
			(stroke
				(width 0.1524)
				(type default)
			)
			(layer "F.SilkS")
		)
		(fp_line
			(start 1.524 0.762)
			(end -1.524 0.762)
			(stroke
				(width 0.1524)
				(type default)
			)
			(layer "F.SilkS")
		)
		(fp_line
			(start -1.1049 -0.724916)
			(end -1.1049 0.724916)
			(stroke
				(width 0.1)
				(type default)
			)
			(layer "F.Fab")
		)
		(fp_line
			(start -1.1049 0.724916)
			(end 1.1049 0.724916)
			(stroke
				(width 0.1)
				(type default)
			)
			(layer "F.Fab")
		)
		(fp_line
			(start 1.1049 -0.724916)
			(end -1.1049 -0.724916)
			(stroke
				(width 0.1)
				(type default)
			)
			(layer "F.Fab")
		)
		(fp_line
			(start 1.1049 0.724916)
			(end 1.1049 -0.724916)
			(stroke
				(width 0.1)
				(type default)
			)
			(layer "F.Fab")
		)
		(pad "1" smd rect
			(at -0.889 0 180)
			(size 1.016 1.27)
			(layers "F.Cu" "F.Mask" "F.Paste")
			(net "P0V9_CPU1_RT0_2A")
		)
		(pad "2" smd rect
			(at 0.889 0 180)
			(size 1.016 1.27)
			(layers "F.Cu" "F.Mask" "F.Paste")
			(net "GND")
		)
	)
	(footprint ""
		(layer "F.Cu")
		(at 41.73601 -438.531)
		(property "Reference" "R3468"
			(at 0 0 0)
			(layer "F.SilkS")
			(hide yes)
			(effects
				(font
					(size 1.27 1.27)
				)
			)
		)
		(property "Value" ""
			(at 0 0 0)
			(layer "F.Fab")
			(effects
				(font
					(size 1.27 1.27)
				)
			)
		)
		(duplicate_pad_numbers_are_jumpers no)
		(fp_line
			(start -0.7874 -0.4064)
			(end 0.7874 -0.4064)
			(stroke
				(width 0.1524)
				(type default)
			)
			(layer "F.SilkS")
		)
		(fp_line
			(start -0.7874 0.4064)
			(end -0.7874 -0.4064)
			(stroke
				(width 0.1524)
				(type default)
			)
			(layer "F.SilkS")
		)
		(fp_line
			(start 0.7874 -0.4064)
			(end 0.7874 0.4064)
			(stroke
				(width 0.1524)
				(type default)
			)
			(layer "F.SilkS")
		)
		(fp_line
			(start 0.7874 0.4064)
			(end -0.7874 0.4064)
			(stroke
				(width 0.1524)
				(type default)
			)
			(layer "F.SilkS")
		)
		(fp_line
			(start -0.67945 -0.305054)
			(end -0.12065 -0.305054)
			(stroke
				(width 0.1)
				(type default)
			)
			(layer "F.Fab")
		)
		(fp_line
			(start -0.67945 0.3048)
			(end -0.67945 -0.305054)
			(stroke
				(width 0.1)
				(type default)
			)
			(layer "F.Fab")
		)
		(fp_line
			(start -0.12065 -0.305054)
			(end -0.12065 -0.2794)
			(stroke
				(width 0.1)
				(type default)
			)
			(layer "F.Fab")
		)
		(fp_line
			(start -0.12065 -0.2794)
			(end 0.12065 -0.2794)
			(stroke
				(width 0.1)
				(type default)
			)
			(layer "F.Fab")
		)
		(fp_line
			(start -0.12065 0.2794)
			(end -0.12065 0.3048)
			(stroke
				(width 0.1)
				(type default)
			)
			(layer "F.Fab")
		)
		(fp_line
			(start -0.12065 0.3048)
			(end -0.67945 0.3048)
			(stroke
				(width 0.1)
				(type default)
			)
			(layer "F.Fab")
		)
		(fp_line
			(start 0.120396 0.2794)
			(end -0.12065 0.2794)
			(stroke
				(width 0.1)
				(type default)
			)
			(layer "F.Fab")
		)
		(fp_line
			(start 0.120396 0.3048)
			(end 0.120396 0.2794)
			(stroke
				(width 0.1)
				(type default)
			)
			(layer "F.Fab")
		)
		(fp_line
			(start 0.12065 -0.3048)
			(end 0.67945 -0.3048)
			(stroke
				(width 0.1)
				(type default)
			)
			(layer "F.Fab")
		)
		(fp_line
			(start 0.12065 -0.2794)
			(end 0.12065 -0.3048)
			(stroke
				(width 0.1)
				(type default)
			)
			(layer "F.Fab")
		)
		(fp_line
			(start 0.67945 -0.3048)
			(end 0.67945 0.3048)
			(stroke
				(width 0.1)
				(type default)
			)
			(layer "F.Fab")
		)
		(fp_line
			(start 0.67945 0.3048)
			(end 0.120396 0.3048)
			(stroke
				(width 0.1)
				(type default)
			)
			(layer "F.Fab")
		)
		(pad "1" smd circle
			(at -0.40005 0)
			(size 0 0)
			(layers "F.Cu" "F.Mask" "F.Paste")
			(net "RST_PERST_1_SWB_BUF_R_N")
		)
		(pad "2" smd circle
			(at 0.40005 0)
			(size 0 0)
			(layers "F.Cu" "F.Mask" "F.Paste")
			(net "RST_PERST_1_SWB_BUF_N")
		)
	)
	(footprint ""
		(layer "F.Cu")
		(at 261.76605 -380.66853)
		(property "Reference" "PR2529"
			(at 0 0 0)
			(layer "F.SilkS")
			(hide yes)
			(effects
				(font
					(size 1.27 1.27)
				)
			)
		)
		(property "Value" ""
			(at 0 0 0)
			(layer "F.Fab")
			(effects
				(font
					(size 1.27 1.27)
				)
			)
		)
		(duplicate_pad_numbers_are_jumpers no)
		(fp_line
			(start -0.7874 -0.4064)
			(end 0.7874 -0.4064)
			(stroke
				(width 0.1524)
				(type default)
			)
			(layer "F.SilkS")
		)
		(fp_line
			(start -0.7874 0.4064)
			(end -0.7874 -0.4064)
			(stroke
				(width 0.1524)
				(type default)
			)
			(layer "F.SilkS")
		)
		(fp_line
			(start 0.7874 -0.4064)
			(end 0.7874 0.4064)
			(stroke
				(width 0.1524)
				(type default)
			)
			(layer "F.SilkS")
		)
		(fp_line
			(start 0.7874 0.4064)
			(end -0.7874 0.4064)
			(stroke
				(width 0.1524)
				(type default)
			)
			(layer "F.SilkS")
		)
		(fp_line
			(start -0.67945 -0.305054)
			(end -0.12065 -0.305054)
			(stroke
				(width 0.1)
				(type default)
			)
			(layer "F.Fab")
		)
		(fp_line
			(start -0.67945 0.3048)
			(end -0.67945 -0.305054)
			(stroke
				(width 0.1)
				(type default)
			)
			(layer "F.Fab")
		)
		(fp_line
			(start -0.12065 -0.305054)
			(end -0.12065 -0.2794)
			(stroke
				(width 0.1)
				(type default)
			)
			(layer "F.Fab")
		)
		(fp_line
			(start -0.12065 -0.2794)
			(end 0.12065 -0.2794)
			(stroke
				(width 0.1)
				(type default)
			)
			(layer "F.Fab")
		)
		(fp_line
			(start -0.12065 0.2794)
			(end -0.12065 0.3048)
			(stroke
				(width 0.1)
				(type default)
			)
			(layer "F.Fab")
		)
		(fp_line
			(start -0.12065 0.3048)
			(end -0.67945 0.3048)
			(stroke
				(width 0.1)
				(type default)
			)
			(layer "F.Fab")
		)
		(fp_line
			(start 0.120396 0.2794)
			(end -0.12065 0.2794)
			(stroke
				(width 0.1)
				(type default)
			)
			(layer "F.Fab")
		)
		(fp_line
			(start 0.120396 0.3048)
			(end 0.120396 0.2794)
			(stroke
				(width 0.1)
				(type default)
			)
			(layer "F.Fab")
		)
		(fp_line
			(start 0.12065 -0.3048)
			(end 0.67945 -0.3048)
			(stroke
				(width 0.1)
				(type default)
			)
			(layer "F.Fab")
		)
		(fp_line
			(start 0.12065 -0.2794)
			(end 0.12065 -0.3048)
			(stroke
				(width 0.1)
				(type default)
			)
			(layer "F.Fab")
		)
		(fp_line
			(start 0.67945 -0.3048)
			(end 0.67945 0.3048)
			(stroke
				(width 0.1)
				(type default)
			)
			(layer "F.Fab")
		)
		(fp_line
			(start 0.67945 0.3048)
			(end 0.120396 0.3048)
			(stroke
				(width 0.1)
				(type default)
			)
			(layer "F.Fab")
		)
		(pad "1" smd circle
			(at -0.40005 0)
			(size 0 0)
			(layers "F.Cu" "F.Mask" "F.Paste")
			(net "P12V_HSC_GATE_G2")
		)
		(pad "2" smd circle
			(at 0.40005 0)
			(size 0 0)
			(layers "F.Cu" "F.Mask" "F.Paste")
			(net "P12V_HSC_GATE2")
		)
	)
	(footprint ""
		(layer "F.Cu")
		(at 122.002296 -375.49963 -90)
		(property "Reference" "C1533"
			(at 0 0 270)
			(layer "F.SilkS")
			(hide yes)
			(effects
				(font
					(size 1.27 1.27)
				)
			)
		)
		(property "Value" ""
			(at 0 0 270)
			(layer "F.Fab")
			(effects
				(font
					(size 1.27 1.27)
				)
			)
		)
		(duplicate_pad_numbers_are_jumpers no)
		(fp_line
			(start -0.299974 0.150114)
			(end -0.299974 -0.150114)
			(stroke
				(width 0.1)
				(type default)
			)
			(layer "F.Fab")
		)
		(fp_line
			(start 0.299974 0.150114)
			(end -0.299974 0.150114)
			(stroke
				(width 0.1)
				(type default)
			)
			(layer "F.Fab")
		)
		(fp_line
			(start -0.299974 -0.150114)
			(end 0.299974 -0.150114)
			(stroke
				(width 0.1)
				(type default)
			)
			(layer "F.Fab")
		)
		(fp_line
			(start 0.299974 -0.150114)
			(end 0.299974 0.150114)
			(stroke
				(width 0.1)
				(type default)
			)
			(layer "F.Fab")
		)
		(pad "1" smd rect
			(at -0.2667 0 270)
			(size 0.3048 0.381)
			(layers "F.Cu" "F.Mask" "F.Paste")
			(net "P5E_CPU1_P3_TX_C_DP<7>")
		)
		(pad "2" smd rect
			(at 0.2667 0 270)
			(size 0.3048 0.381)
			(layers "F.Cu" "F.Mask" "F.Paste")
			(net "P5E_CPU1_P3_TX_DP<7>")
		)
	)
	(footprint ""
		(layer "F.Cu")
		(at 306.420266 -431.256186)
		(property "Reference" "R4142"
			(at 0 0 0)
			(layer "F.SilkS")
			(hide yes)
			(effects
				(font
					(size 1.27 1.27)
				)
			)
		)
		(property "Value" ""
			(at 0 0 0)
			(layer "F.Fab")
			(effects
				(font
					(size 1.27 1.27)
				)
			)
		)
		(duplicate_pad_numbers_are_jumpers no)
		(fp_line
			(start -0.7874 -0.4064)
			(end 0.7874 -0.4064)
			(stroke
				(width 0.1524)
				(type default)
			)
			(layer "F.SilkS")
		)
		(fp_line
			(start -0.7874 0.4064)
			(end -0.7874 -0.4064)
			(stroke
				(width 0.1524)
				(type default)
			)
			(layer "F.SilkS")
		)
		(fp_line
			(start 0.7874 -0.4064)
			(end 0.7874 0.4064)
			(stroke
				(width 0.1524)
				(type default)
			)
			(layer "F.SilkS")
		)
		(fp_line
			(start 0.7874 0.4064)
			(end -0.7874 0.4064)
			(stroke
				(width 0.1524)
				(type default)
			)
			(layer "F.SilkS")
		)
		(fp_line
			(start -0.67945 -0.305054)
			(end -0.12065 -0.305054)
			(stroke
				(width 0.1)
				(type default)
			)
			(layer "F.Fab")
		)
		(fp_line
			(start -0.67945 0.3048)
			(end -0.67945 -0.305054)
			(stroke
				(width 0.1)
				(type default)
			)
			(layer "F.Fab")
		)
		(fp_line
			(start -0.12065 -0.305054)
			(end -0.12065 -0.2794)
			(stroke
				(width 0.1)
				(type default)
			)
			(layer "F.Fab")
		)
		(fp_line
			(start -0.12065 -0.2794)
			(end 0.12065 -0.2794)
			(stroke
				(width 0.1)
				(type default)
			)
			(layer "F.Fab")
		)
		(fp_line
			(start -0.12065 0.2794)
			(end -0.12065 0.3048)
			(stroke
				(width 0.1)
				(type default)
			)
			(layer "F.Fab")
		)
		(fp_line
			(start -0.12065 0.3048)
			(end -0.67945 0.3048)
			(stroke
				(width 0.1)
				(type default)
			)
			(layer "F.Fab")
		)
		(fp_line
			(start 0.120396 0.2794)
			(end -0.12065 0.2794)
			(stroke
				(width 0.1)
				(type default)
			)
			(layer "F.Fab")
		)
		(fp_line
			(start 0.120396 0.3048)
			(end 0.120396 0.2794)
			(stroke
				(width 0.1)
				(type default)
			)
			(layer "F.Fab")
		)
		(fp_line
			(start 0.12065 -0.3048)
			(end 0.67945 -0.3048)
			(stroke
				(width 0.1)
				(type default)
			)
			(layer "F.Fab")
		)
		(fp_line
			(start 0.12065 -0.2794)
			(end 0.12065 -0.3048)
			(stroke
				(width 0.1)
				(type default)
			)
			(layer "F.Fab")
		)
		(fp_line
			(start 0.67945 -0.3048)
			(end 0.67945 0.3048)
			(stroke
				(width 0.1)
				(type default)
			)
			(layer "F.Fab")
		)
		(fp_line
			(start 0.67945 0.3048)
			(end 0.120396 0.3048)
			(stroke
				(width 0.1)
				(type default)
			)
			(layer "F.Fab")
		)
		(pad "1" smd circle
			(at -0.40005 0)
			(size 0 0)
			(layers "F.Cu" "F.Mask" "F.Paste")
			(net "P3V3_AUX")
		)
		(pad "2" smd circle
			(at 0.40005 0)
			(size 0 0)
			(layers "F.Cu" "F.Mask" "F.Paste")
			(net "PRSNT_CABLE_GPU_A2_ISO_N")
		)
	)
	(footprint ""
		(layer "F.Cu")
		(at 363.645958 -259.845048)
		(property "Reference" "C3893"
			(at 0 0 0)
			(layer "F.SilkS")
			(hide yes)
			(effects
				(font
					(size 1.27 1.27)
				)
			)
		)
		(property "Value" ""
			(at 0 0 0)
			(layer "F.Fab")
			(effects
				(font
					(size 1.27 1.27)
				)
			)
		)
		(duplicate_pad_numbers_are_jumpers no)
		(fp_line
			(start -0.7874 -0.4064)
			(end 0.7874 -0.4064)
			(stroke
				(width 0.1524)
				(type default)
			)
			(layer "F.SilkS")
		)
		(fp_line
			(start -0.7874 0.4064)
			(end -0.7874 -0.4064)
			(stroke
				(width 0.1524)
				(type default)
			)
			(layer "F.SilkS")
		)
		(fp_line
			(start 0.7874 -0.4064)
			(end 0.7874 0.4064)
			(stroke
				(width 0.1524)
				(type default)
			)
			(layer "F.SilkS")
		)
		(fp_line
			(start 0.7874 0.4064)
			(end -0.7874 0.4064)
			(stroke
				(width 0.1524)
				(type default)
			)
			(layer "F.SilkS")
		)
		(fp_line
			(start -0.67945 -0.305054)
			(end -0.12065 -0.305054)
			(stroke
				(width 0.1)
				(type default)
			)
			(layer "F.Fab")
		)
		(fp_line
			(start -0.67945 0.3048)
			(end -0.67945 -0.305054)
			(stroke
				(width 0.1)
				(type default)
			)
			(layer "F.Fab")
		)
		(fp_line
			(start -0.12065 -0.305054)
			(end -0.12065 -0.2794)
			(stroke
				(width 0.1)
				(type default)
			)
			(layer "F.Fab")
		)
		(fp_line
			(start -0.12065 -0.2794)
			(end 0.12065 -0.2794)
			(stroke
				(width 0.1)
				(type default)
			)
			(layer "F.Fab")
		)
		(fp_line
			(start -0.12065 0.2794)
			(end -0.12065 0.3048)
			(stroke
				(width 0.1)
				(type default)
			)
			(layer "F.Fab")
		)
		(fp_line
			(start -0.12065 0.3048)
			(end -0.67945 0.3048)
			(stroke
				(width 0.1)
				(type default)
			)
			(layer "F.Fab")
		)
		(fp_line
			(start 0.120396 0.2794)
			(end -0.12065 0.2794)
			(stroke
				(width 0.1)
				(type default)
			)
			(layer "F.Fab")
		)
		(fp_line
			(start 0.120396 0.3048)
			(end 0.120396 0.2794)
			(stroke
				(width 0.1)
				(type default)
			)
			(layer "F.Fab")
		)
		(fp_line
			(start 0.12065 -0.3048)
			(end 0.67945 -0.3048)
			(stroke
				(width 0.1)
				(type default)
			)
			(layer "F.Fab")
		)
		(fp_line
			(start 0.12065 -0.2794)
			(end 0.12065 -0.3048)
			(stroke
				(width 0.1)
				(type default)
			)
			(layer "F.Fab")
		)
		(fp_line
			(start 0.67945 -0.3048)
			(end 0.67945 0.3048)
			(stroke
				(width 0.1)
				(type default)
			)
			(layer "F.Fab")
		)
		(fp_line
			(start 0.67945 0.3048)
			(end 0.120396 0.3048)
			(stroke
				(width 0.1)
				(type default)
			)
			(layer "F.Fab")
		)
		(pad "1" smd circle
			(at -0.40005 0)
			(size 0 0)
			(layers "F.Cu" "F.Mask" "F.Paste")
			(net "PVDD11_S3_P0")
		)
		(pad "2" smd circle
			(at 0.40005 0)
			(size 0 0)
			(layers "F.Cu" "F.Mask" "F.Paste")
			(net "GND")
		)
	)
	(footprint ""
		(layer "F.Cu")
		(at 435.208172 -32.173418 -90)
		(property "Reference" "R3869"
			(at 0 0 270)
			(layer "F.SilkS")
			(hide yes)
			(effects
				(font
					(size 1.27 1.27)
				)
			)
		)
		(property "Value" ""
			(at 0 0 270)
			(layer "F.Fab")
			(effects
				(font
					(size 1.27 1.27)
				)
			)
		)
		(duplicate_pad_numbers_are_jumpers no)
		(fp_line
			(start -0.7874 0.4064)
			(end -0.7874 -0.4064)
			(stroke
				(width 0.1524)
				(type default)
			)
			(layer "F.SilkS")
		)
		(fp_line
			(start 0.7874 0.4064)
			(end -0.7874 0.4064)
			(stroke
				(width 0.1524)
				(type default)
			)
			(layer "F.SilkS")
		)
		(fp_line
			(start -0.7874 -0.4064)
			(end 0.7874 -0.4064)
			(stroke
				(width 0.1524)
				(type default)
			)
			(layer "F.SilkS")
		)
		(fp_line
			(start 0.7874 -0.4064)
			(end 0.7874 0.4064)
			(stroke
				(width 0.1524)
				(type default)
			)
			(layer "F.SilkS")
		)
		(fp_line
			(start -0.67945 0.3048)
			(end -0.67945 -0.305054)
			(stroke
				(width 0.1)
				(type default)
			)
			(layer "F.Fab")
		)
		(fp_line
			(start -0.12065 0.3048)
			(end -0.67945 0.3048)
			(stroke
				(width 0.1)
				(type default)
			)
			(layer "F.Fab")
		)
		(fp_line
			(start 0.120396 0.3048)
			(end 0.120396 0.2794)
			(stroke
				(width 0.1)
				(type default)
			)
			(layer "F.Fab")
		)
		(fp_line
			(start 0.67945 0.3048)
			(end 0.120396 0.3048)
			(stroke
				(width 0.1)
				(type default)
			)
			(layer "F.Fab")
		)
		(fp_line
			(start -0.12065 0.2794)
			(end -0.12065 0.3048)
			(stroke
				(width 0.1)
				(type default)
			)
			(layer "F.Fab")
		)
		(fp_line
			(start 0.120396 0.2794)
			(end -0.12065 0.2794)
			(stroke
				(width 0.1)
				(type default)
			)
			(layer "F.Fab")
		)
		(fp_line
			(start -0.12065 -0.2794)
			(end 0.12065 -0.2794)
			(stroke
				(width 0.1)
				(type default)
			)
			(layer "F.Fab")
		)
		(fp_line
			(start 0.12065 -0.2794)
			(end 0.12065 -0.3048)
			(stroke
				(width 0.1)
				(type default)
			)
			(layer "F.Fab")
		)
		(fp_line
			(start 0.12065 -0.3048)
			(end 0.67945 -0.3048)
			(stroke
				(width 0.1)
				(type default)
			)
			(layer "F.Fab")
		)
		(fp_line
			(start 0.67945 -0.3048)
			(end 0.67945 0.3048)
			(stroke
				(width 0.1)
				(type default)
			)
			(layer "F.Fab")
		)
		(fp_line
			(start -0.67945 -0.305054)
			(end -0.12065 -0.305054)
			(stroke
				(width 0.1)
				(type default)
			)
			(layer "F.Fab")
		)
		(fp_line
			(start -0.12065 -0.305054)
			(end -0.12065 -0.2794)
			(stroke
				(width 0.1)
				(type default)
			)
			(layer "F.Fab")
		)
		(pad "1" smd circle
			(at -0.40005 0 270)
			(size 0 0)
			(layers "F.Cu" "F.Mask" "F.Paste")
			(net "P12V_OCP_SENSE_1")
		)
		(pad "2" smd circle
			(at 0.40005 0 270)
			(size 0 0)
			(layers "F.Cu" "F.Mask" "F.Paste")
			(net "P12V_OCP_SFF_ISENSE_MAM_MAM")
		)
	)
	(footprint ""
		(layer "F.Cu")
		(at 372.67515 -182.743856 180)
		(property "Reference" "PU43"
			(at -0.013208 -7.145274 0)
			(unlocked yes)
			(layer "F.SilkS")
			(effects
				(font
					(size 0.7874 0.5842)
					(thickness 0.1524)
				)
				(justify left)
			)
		)
		(property "Value" ""
			(at 0 0 180)
			(layer "F.Fab")
			(effects
				(font
					(size 1.27 1.27)
				)
			)
		)
		(duplicate_pad_numbers_are_jumpers no)
		(fp_line
			(start 2.500122 2.999994)
			(end 2.2987 2.999994)
			(stroke
				(width 0.1524)
				(type default)
			)
			(layer "F.SilkS")
		)
		(fp_line
			(start 2.500122 2.339594)
			(end 2.500122 2.999994)
			(stroke
				(width 0.1524)
				(type default)
			)
			(layer "F.SilkS")
		)
		(fp_line
			(start 2.500122 -2.999994)
			(end 2.500122 -2.44348)
			(stroke
				(width 0.1524)
				(type default)
			)
			(layer "F.SilkS")
		)
		(fp_line
			(start 2.31394 -2.999994)
			(end 2.500122 -2.999994)
			(stroke
				(width 0.1524)
				(type default)
			)
			(layer "F.SilkS")
		)
		(fp_line
			(start -2.2987 2.999994)
			(end -2.500122 2.999994)
			(stroke
				(width 0.1524)
				(type default)
			)
			(layer "F.SilkS")
		)
		(fp_line
			(start -2.500122 2.999994)
			(end -2.500122 2.339594)
			(stroke
				(width 0.1524)
				(type default)
			)
			(layer "F.SilkS")
		)
		(fp_line
			(start -2.500122 0.6604)
			(end -2.500122 0.229108)
			(stroke
				(width 0.1524)
				(type default)
			)
			(layer "F.SilkS")
		)
		(fp_line
			(start -2.500122 -2.529078)
			(end -2.500122 -2.999994)
			(stroke
				(width 0.1524)
				(type default)
			)
			(layer "F.SilkS")
		)
		(fp_line
			(start -2.500122 -2.999994)
			(end -2.24409 -2.999994)
			(stroke
				(width 0.1524)
				(type default)
			)
			(layer "F.SilkS")
		)
		(fp_poly
			(pts
				(xy -2.755138 -2.475484) (xy -3.387598 -2.686304) (xy -2.965958 -3.108198)
			)
			(stroke
				(width 0)
				(type default)
			)
			(fill yes)
			(layer "F.SilkS")
		)
		(fp_line
			(start 2.500122 2.999994)
			(end -2.500122 2.999994)
			(stroke
				(width 0.1)
				(type default)
			)
			(layer "F.Fab")
		)
		(fp_line
			(start 2.500122 -2.999994)
			(end 2.500122 2.999994)
			(stroke
				(width 0.1)
				(type default)
			)
			(layer "F.Fab")
		)
		(fp_line
			(start -2.500122 2.999994)
			(end -2.500122 -2.999994)
			(stroke
				(width 0.1)
				(type default)
			)
			(layer "F.Fab")
		)
		(fp_line
			(start -2.500122 -2.999994)
			(end 2.500122 -2.999994)
			(stroke
				(width 0.1)
				(type default)
			)
			(layer "F.Fab")
		)
		(fp_poly
			(pts
				(xy -4.218432 -2.783078) (xy -4.218432 -1.767078) (xy -3.202432 -2.275078)
			)
			(stroke
				(width 0)
				(type default)
			)
			(fill yes)
			(layer "F.Fab")
		)
		(pad "1" smd rect
			(at -2.400046 -2.275078 270)
			(size 0.2286 0.6096)
			(layers "F.Cu" "F.Mask" "F.Paste")
			(net "PVDDCR_CPU0_P0_VOS2")
		)
		(pad "2" smd rect
			(at -2.400046 -1.82499 270)
			(size 0.2286 0.6096)
			(layers "F.Cu" "F.Mask" "F.Paste")
			(net "GND")
		)
		(pad "3" smd rect
			(at -2.400046 -1.374902 270)
			(size 0.2286 0.6096)
			(layers "F.Cu" "F.Mask" "F.Paste")
			(net "PVDDCR_CPU0_P0_VCC2")
		)
		(pad "4" smd rect
			(at -2.400046 -0.925068 270)
			(size 0.2286 0.6096)
			(layers "F.Cu" "F.Mask" "F.Paste")
			(net "PVDDCR_CPU0_P0_PVCC")
		)
		(pad "5" smd rect
			(at -2.400046 -0.47498 270)
			(size 0.2286 0.6096)
			(layers "F.Cu" "F.Mask" "F.Paste")
			(net "GND")
		)
		(pad "6" smd rect
			(at -2.400046 -0.024892 270)
			(size 0.2286 0.6096)
			(layers "F.Cu" "F.Mask" "F.Paste")
			(net "NC_PVDDCR_CPU0_P0_GL1_2")
		)
		(pad "7_9-20_24" smd circle
			(at 0 1.150112 270)
			(size 0 0)
			(layers "F.Cu" "F.Mask" "F.Paste")
			(net "GND")
		)
		(pad "10_19" smd rect
			(at 0 2.899918 270)
			(size 0.6096 4.318)
			(layers "F.Cu" "F.Mask" "F.Paste")
			(net "SW_PVDDCR_CPU0_P0_SW2")
		)
		(pad "25_29" smd rect
			(at 1.549908 -1.279906 90)
			(size 2.0574 2.3114)
			(layers "F.Cu" "F.Mask" "F.Paste")
			(net "SW_P12V_AUX_PVDDCR_CPU0_P0_FLT")
		)
		(pad "30" smd rect
			(at 2.05994 -2.899918 180)
			(size 0.2286 0.6096)
			(layers "F.Cu" "F.Mask" "F.Paste")
			(net "SW_P12V_AUX_PVDDCR_CPU0_P0_FLT")
		)
		(pad "31" smd rect
			(at 1.610106 -2.899918 180)
			(size 0.2286 0.6096)
			(layers "F.Cu" "F.Mask" "F.Paste")
			(net "NC_PVDDCR_CPU0_P0_DNC2")
		)
		(pad "32" smd rect
			(at 1.160018 -2.899918 180)
			(size 0.2286 0.6096)
			(layers "F.Cu" "F.Mask" "F.Paste")
			(net "SW_PVDDCR_CPU0_P0_PH2")
		)
		(pad "33" smd rect
			(at 0.70993 -2.899918 180)
			(size 0.2286 0.6096)
			(layers "F.Cu" "F.Mask" "F.Paste")
			(net "SW_PVDDCR_CPU0_P0_BOOT2")
		)
		(pad "34" smd rect
			(at 0.260096 -2.899918 180)
			(size 0.2286 0.6096)
			(layers "F.Cu" "F.Mask" "F.Paste")
			(net "PVDDCR_CPU0_P0_PWM2")
		)
		(pad "35" smd rect
			(at -0.189992 -2.899918 180)
			(size 0.2286 0.6096)
			(layers "F.Cu" "F.Mask" "F.Paste")
			(net "PVDDCR_CPU0_P0_VCC2")
		)
		(pad "36" smd rect
			(at -0.64008 -2.899918 180)
			(size 0.2286 0.6096)
			(layers "F.Cu" "F.Mask" "F.Paste")
			(net "PVDDCR_CPU0_P0_TEMP0")
		)
		(pad "37" smd rect
			(at -1.089914 -2.899918 180)
			(size 0.2286 0.6096)
			(layers "F.Cu" "F.Mask" "F.Paste")
			(net "PVDDCR_CPU0_P0_LSET2")
		)
		(pad "38" smd rect
			(at -1.540002 -2.899918 180)
			(size 0.2286 0.6096)
			(layers "F.Cu" "F.Mask" "F.Paste")
			(net "PVDDCR_CPU0_P0_IMON2")
		)
		(pad "39" smd rect
			(at -1.99009 -2.899918 180)
			(size 0.2286 0.6096)
			(layers "F.Cu" "F.Mask" "F.Paste")
			(net "PVDDCR_CPU0_P0_VCCS")
		)
		(pad "40" smd rect
			(at -0.87503 -1.27508 180)
			(size 1.7526 1.9558)
			(layers "F.Cu" "F.Mask" "F.Paste")
			(net "GND")
		)
		(pad "41" smd rect
			(at -1.525016 0.249936 90)
			(size 0.3048 0.4572)
			(layers "F.Cu" "F.Mask" "F.Paste")
			(net "NC_PVDDCR_CPU0_P0_GL2_2")
		)
		(zone
			(layer "F.Cu")
			(hatch none 0.5)
			(connect_pads
				(clearance 0)
			)
			(min_thickness 0.25)
			(keepout
				(tracks not_allowed)
				(vias allowed)
				(pads allowed)
				(copperpour not_allowed)
				(footprints allowed)
			)
			(placement
				(enabled no)
				(sheetname "")
			)
			(fill
				(thermal_gap 0.5)
				(thermal_bridge_width 0.5)
				(island_removal_mode 0)
			)
			(polygon
				(pts
					(xy 375.175272 -185.32729) (xy 375.175272 -184.99455) (xy 370.175028 -184.99455) (xy 370.175028 -185.318654)
					(xy 370.46535 -185.318654) (xy 370.46535 -185.288174) (xy 374.88495 -185.288174) (xy 374.88495 -185.32729)
				)
			)
		)
		(zone
			(layer "F.Cu")
			(hatch none 0.5)
			(connect_pads
				(clearance 0)
			)
			(min_thickness 0.25)
			(keepout
				(tracks not_allowed)
				(vias allowed)
				(pads allowed)
				(copperpour not_allowed)
				(footprints allowed)
			)
			(placement
				(enabled no)
				(sheetname "")
			)
			(fill
				(thermal_gap 0.5)
				(thermal_bridge_width 0.5)
				(island_removal_mode 0)
			)
			(polygon
				(pts
					(xy 372.62308 -182.497476) (xy 372.62308 -180.440076) (xy 374.47728 -180.440076) (xy 374.47728 -180.681122)
					(xy 374.719596 -180.681122) (xy 374.719596 -180.199538) (xy 370.902484 -180.199538) (xy 370.902484 -180.38445)
					(xy 372.331742 -180.38445) (xy 372.331742 -182.54345) (xy 370.175028 -182.54345) (xy 370.175028 -182.793132)
					(xy 372.327424 -182.793132)
				)
			)
		)
	)
	(footprint ""
		(layer "F.Cu")
		(at 392.840972 -388.767828)
		(property "Reference" "C870"
			(at 0 0 0)
			(layer "F.SilkS")
			(hide yes)
			(effects
				(font
					(size 1.27 1.27)
				)
			)
		)
		(property "Value" ""
			(at 0 0 0)
			(layer "F.Fab")
			(effects
				(font
					(size 1.27 1.27)
				)
			)
		)
		(duplicate_pad_numbers_are_jumpers no)
		(fp_line
			(start -0.299974 -0.150114)
			(end 0.299974 -0.150114)
			(stroke
				(width 0.1)
				(type default)
			)
			(layer "F.Fab")
		)
		(fp_line
			(start -0.299974 0.150114)
			(end -0.299974 -0.150114)
			(stroke
				(width 0.1)
				(type default)
			)
			(layer "F.Fab")
		)
		(fp_line
			(start 0.299974 -0.150114)
			(end 0.299974 0.150114)
			(stroke
				(width 0.1)
				(type default)
			)
			(layer "F.Fab")
		)
		(fp_line
			(start 0.299974 0.150114)
			(end -0.299974 0.150114)
			(stroke
				(width 0.1)
				(type default)
			)
			(layer "F.Fab")
		)
		(pad "1" smd rect
			(at -0.2667 0)
			(size 0.3048 0.381)
			(layers "F.Cu" "F.Mask" "F.Paste")
			(net "P5E_CPU0_P3_TX_C_DN<15>")
		)
		(pad "2" smd rect
			(at 0.2667 0)
			(size 0.3048 0.381)
			(layers "F.Cu" "F.Mask" "F.Paste")
			(net "P5E_CPU0_P3_TX_DN<15>")
		)
	)
	(footprint ""
		(layer "F.Cu")
		(at 345.467686 -23.8887 -90)
		(property "Reference" "R947"
			(at 0 0 270)
			(layer "F.SilkS")
			(hide yes)
			(effects
				(font
					(size 1.27 1.27)
				)
			)
		)
		(property "Value" ""
			(at 0 0 270)
			(layer "F.Fab")
			(effects
				(font
					(size 1.27 1.27)
				)
			)
		)
		(duplicate_pad_numbers_are_jumpers no)
		(fp_line
			(start -0.7874 0.4064)
			(end -0.7874 -0.4064)
			(stroke
				(width 0.1524)
				(type default)
			)
			(layer "F.SilkS")
		)
		(fp_line
			(start 0.7874 0.4064)
			(end -0.7874 0.4064)
			(stroke
				(width 0.1524)
				(type default)
			)
			(layer "F.SilkS")
		)
		(fp_line
			(start -0.7874 -0.4064)
			(end 0.7874 -0.4064)
			(stroke
				(width 0.1524)
				(type default)
			)
			(layer "F.SilkS")
		)
		(fp_line
			(start 0.7874 -0.4064)
			(end 0.7874 0.4064)
			(stroke
				(width 0.1524)
				(type default)
			)
			(layer "F.SilkS")
		)
		(fp_line
			(start -0.67945 0.3048)
			(end -0.67945 -0.305054)
			(stroke
				(width 0.1)
				(type default)
			)
			(layer "F.Fab")
		)
		(fp_line
			(start -0.12065 0.3048)
			(end -0.67945 0.3048)
			(stroke
				(width 0.1)
				(type default)
			)
			(layer "F.Fab")
		)
		(fp_line
			(start 0.120396 0.3048)
			(end 0.120396 0.2794)
			(stroke
				(width 0.1)
				(type default)
			)
			(layer "F.Fab")
		)
		(fp_line
			(start 0.67945 0.3048)
			(end 0.120396 0.3048)
			(stroke
				(width 0.1)
				(type default)
			)
			(layer "F.Fab")
		)
		(fp_line
			(start -0.12065 0.2794)
			(end -0.12065 0.3048)
			(stroke
				(width 0.1)
				(type default)
			)
			(layer "F.Fab")
		)
		(fp_line
			(start 0.120396 0.2794)
			(end -0.12065 0.2794)
			(stroke
				(width 0.1)
				(type default)
			)
			(layer "F.Fab")
		)
		(fp_line
			(start -0.12065 -0.2794)
			(end 0.12065 -0.2794)
			(stroke
				(width 0.1)
				(type default)
			)
			(layer "F.Fab")
		)
		(fp_line
			(start 0.12065 -0.2794)
			(end 0.12065 -0.3048)
			(stroke
				(width 0.1)
				(type default)
			)
			(layer "F.Fab")
		)
		(fp_line
			(start 0.12065 -0.3048)
			(end 0.67945 -0.3048)
			(stroke
				(width 0.1)
				(type default)
			)
			(layer "F.Fab")
		)
		(fp_line
			(start 0.67945 -0.3048)
			(end 0.67945 0.3048)
			(stroke
				(width 0.1)
				(type default)
			)
			(layer "F.Fab")
		)
		(fp_line
			(start -0.67945 -0.305054)
			(end -0.12065 -0.305054)
			(stroke
				(width 0.1)
				(type default)
			)
			(layer "F.Fab")
		)
		(fp_line
			(start -0.12065 -0.305054)
			(end -0.12065 -0.2794)
			(stroke
				(width 0.1)
				(type default)
			)
			(layer "F.Fab")
		)
		(pad "1" smd circle
			(at -0.40005 0 270)
			(size 0 0)
			(layers "F.Cu" "F.Mask" "F.Paste")
			(net "P3V3_AUX")
		)
		(pad "2" smd circle
			(at 0.40005 0 270)
			(size 0 0)
			(layers "F.Cu" "F.Mask" "F.Paste")
			(net "SMERR_LED")
		)
	)
	(footprint ""
		(layer "F.Cu")
		(at 310.75757 -22.185884 90)
		(property "Reference" "C63"
			(at 0 0 90)
			(layer "F.SilkS")
			(hide yes)
			(effects
				(font
					(size 1.27 1.27)
				)
			)
		)
		(property "Value" ""
			(at 0 0 90)
			(layer "F.Fab")
			(effects
				(font
					(size 1.27 1.27)
				)
			)
		)
		(duplicate_pad_numbers_are_jumpers no)
		(fp_line
			(start 0.7874 -0.4064)
			(end 0.7874 0.4064)
			(stroke
				(width 0.1524)
				(type default)
			)
			(layer "F.SilkS")
		)
		(fp_line
			(start -0.7874 -0.4064)
			(end 0.7874 -0.4064)
			(stroke
				(width 0.1524)
				(type default)
			)
			(layer "F.SilkS")
		)
		(fp_line
			(start 0.7874 0.4064)
			(end -0.7874 0.4064)
			(stroke
				(width 0.1524)
				(type default)
			)
			(layer "F.SilkS")
		)
		(fp_line
			(start -0.7874 0.4064)
			(end -0.7874 -0.4064)
			(stroke
				(width 0.1524)
				(type default)
			)
			(layer "F.SilkS")
		)
		(fp_line
			(start -0.12065 -0.305054)
			(end -0.12065 -0.2794)
			(stroke
				(width 0.1)
				(type default)
			)
			(layer "F.Fab")
		)
		(fp_line
			(start -0.67945 -0.305054)
			(end -0.12065 -0.305054)
			(stroke
				(width 0.1)
				(type default)
			)
			(layer "F.Fab")
		)
		(fp_line
			(start 0.67945 -0.3048)
			(end 0.67945 0.3048)
			(stroke
				(width 0.1)
				(type default)
			)
			(layer "F.Fab")
		)
		(fp_line
			(start 0.12065 -0.3048)
			(end 0.67945 -0.3048)
			(stroke
				(width 0.1)
				(type default)
			)
			(layer "F.Fab")
		)
		(fp_line
			(start 0.12065 -0.2794)
			(end 0.12065 -0.3048)
			(stroke
				(width 0.1)
				(type default)
			)
			(layer "F.Fab")
		)
		(fp_line
			(start -0.12065 -0.2794)
			(end 0.12065 -0.2794)
			(stroke
				(width 0.1)
				(type default)
			)
			(layer "F.Fab")
		)
		(fp_line
			(start 0.120396 0.2794)
			(end -0.12065 0.2794)
			(stroke
				(width 0.1)
				(type default)
			)
			(layer "F.Fab")
		)
		(fp_line
			(start -0.12065 0.2794)
			(end -0.12065 0.3048)
			(stroke
				(width 0.1)
				(type default)
			)
			(layer "F.Fab")
		)
		(fp_line
			(start 0.67945 0.3048)
			(end 0.120396 0.3048)
			(stroke
				(width 0.1)
				(type default)
			)
			(layer "F.Fab")
		)
		(fp_line
			(start 0.120396 0.3048)
			(end 0.120396 0.2794)
			(stroke
				(width 0.1)
				(type default)
			)
			(layer "F.Fab")
		)
		(fp_line
			(start -0.12065 0.3048)
			(end -0.67945 0.3048)
			(stroke
				(width 0.1)
				(type default)
			)
			(layer "F.Fab")
		)
		(fp_line
			(start -0.67945 0.3048)
			(end -0.67945 -0.305054)
			(stroke
				(width 0.1)
				(type default)
			)
			(layer "F.Fab")
		)
		(pad "1" smd circle
			(at -0.40005 0 90)
			(size 0 0)
			(layers "F.Cu" "F.Mask" "F.Paste")
			(net "UART_CPU0_SCM_LVC3_UART1_R_RX")
		)
		(pad "2" smd circle
			(at 0.40005 0 90)
			(size 0 0)
			(layers "F.Cu" "F.Mask" "F.Paste")
			(net "GND")
		)
	)
	(footprint ""
		(layer "F.Cu")
		(at 76.431902 -373.03583 -90)
		(property "Reference" "C736"
			(at 0 0 270)
			(layer "F.SilkS")
			(hide yes)
			(effects
				(font
					(size 1.27 1.27)
				)
			)
		)
		(property "Value" ""
			(at 0 0 270)
			(layer "F.Fab")
			(effects
				(font
					(size 1.27 1.27)
				)
			)
		)
		(duplicate_pad_numbers_are_jumpers no)
		(fp_line
			(start -0.299974 0.150114)
			(end -0.299974 -0.150114)
			(stroke
				(width 0.1)
				(type default)
			)
			(layer "F.Fab")
		)
		(fp_line
			(start 0.299974 0.150114)
			(end -0.299974 0.150114)
			(stroke
				(width 0.1)
				(type default)
			)
			(layer "F.Fab")
		)
		(fp_line
			(start -0.299974 -0.150114)
			(end 0.299974 -0.150114)
			(stroke
				(width 0.1)
				(type default)
			)
			(layer "F.Fab")
		)
		(fp_line
			(start 0.299974 -0.150114)
			(end 0.299974 0.150114)
			(stroke
				(width 0.1)
				(type default)
			)
			(layer "F.Fab")
		)
		(pad "1" smd rect
			(at -0.2667 0 270)
			(size 0.3048 0.381)
			(layers "F.Cu" "F.Mask" "F.Paste")
			(net "P5E_CPU1_P1_TX_C_DN<2>")
		)
		(pad "2" smd rect
			(at 0.2667 0 270)
			(size 0.3048 0.381)
			(layers "F.Cu" "F.Mask" "F.Paste")
			(net "P5E_CPU1_P1_TX_DN<2>")
		)
	)
	(footprint ""
		(layer "F.Cu")
		(at 48.11014 -99.60864 -90)
		(property "Reference" "R954"
			(at 0 0 270)
			(layer "F.SilkS")
			(hide yes)
			(effects
				(font
					(size 1.27 1.27)
				)
			)
		)
		(property "Value" ""
			(at 0 0 270)
			(layer "F.Fab")
			(effects
				(font
					(size 1.27 1.27)
				)
			)
		)
		(duplicate_pad_numbers_are_jumpers no)
		(fp_line
			(start -0.7874 0.4064)
			(end -0.7874 -0.4064)
			(stroke
				(width 0.1524)
				(type default)
			)
			(layer "F.SilkS")
		)
		(fp_line
			(start 0.7874 0.4064)
			(end -0.7874 0.4064)
			(stroke
				(width 0.1524)
				(type default)
			)
			(layer "F.SilkS")
		)
		(fp_line
			(start -0.7874 -0.4064)
			(end 0.7874 -0.4064)
			(stroke
				(width 0.1524)
				(type default)
			)
			(layer "F.SilkS")
		)
		(fp_line
			(start 0.7874 -0.4064)
			(end 0.7874 0.4064)
			(stroke
				(width 0.1524)
				(type default)
			)
			(layer "F.SilkS")
		)
		(fp_line
			(start -0.67945 0.3048)
			(end -0.67945 -0.305054)
			(stroke
				(width 0.1)
				(type default)
			)
			(layer "F.Fab")
		)
		(fp_line
			(start -0.12065 0.3048)
			(end -0.67945 0.3048)
			(stroke
				(width 0.1)
				(type default)
			)
			(layer "F.Fab")
		)
		(fp_line
			(start 0.120396 0.3048)
			(end 0.120396 0.2794)
			(stroke
				(width 0.1)
				(type default)
			)
			(layer "F.Fab")
		)
		(fp_line
			(start 0.67945 0.3048)
			(end 0.120396 0.3048)
			(stroke
				(width 0.1)
				(type default)
			)
			(layer "F.Fab")
		)
		(fp_line
			(start -0.12065 0.2794)
			(end -0.12065 0.3048)
			(stroke
				(width 0.1)
				(type default)
			)
			(layer "F.Fab")
		)
		(fp_line
			(start 0.120396 0.2794)
			(end -0.12065 0.2794)
			(stroke
				(width 0.1)
				(type default)
			)
			(layer "F.Fab")
		)
		(fp_line
			(start -0.12065 -0.2794)
			(end 0.12065 -0.2794)
			(stroke
				(width 0.1)
				(type default)
			)
			(layer "F.Fab")
		)
		(fp_line
			(start 0.12065 -0.2794)
			(end 0.12065 -0.3048)
			(stroke
				(width 0.1)
				(type default)
			)
			(layer "F.Fab")
		)
		(fp_line
			(start 0.12065 -0.3048)
			(end 0.67945 -0.3048)
			(stroke
				(width 0.1)
				(type default)
			)
			(layer "F.Fab")
		)
		(fp_line
			(start 0.67945 -0.3048)
			(end 0.67945 0.3048)
			(stroke
				(width 0.1)
				(type default)
			)
			(layer "F.Fab")
		)
		(fp_line
			(start -0.67945 -0.305054)
			(end -0.12065 -0.305054)
			(stroke
				(width 0.1)
				(type default)
			)
			(layer "F.Fab")
		)
		(fp_line
			(start -0.12065 -0.305054)
			(end -0.12065 -0.2794)
			(stroke
				(width 0.1)
				(type default)
			)
			(layer "F.Fab")
		)
		(pad "1" smd circle
			(at -0.40005 0 270)
			(size 0 0)
			(layers "F.Cu" "F.Mask" "F.Paste")
			(net "P3V3_AUX_DSC_VOL")
		)
		(pad "2" smd circle
			(at 0.40005 0 270)
			(size 0 0)
			(layers "F.Cu" "F.Mask" "F.Paste")
			(net "GND")
		)
	)
	(footprint ""
		(layer "F.Cu")
		(at 128.768856 -156.443934 90)
		(property "Reference" "PC349_3"
			(at 0 0 90)
			(layer "F.SilkS")
			(hide yes)
			(effects
				(font
					(size 1.27 1.27)
				)
			)
		)
		(property "Value" ""
			(at 0 0 90)
			(layer "F.Fab")
			(effects
				(font
					(size 1.27 1.27)
				)
			)
		)
		(duplicate_pad_numbers_are_jumpers no)
		(fp_line
			(start 0.7874 -0.4064)
			(end 0.7874 0.4064)
			(stroke
				(width 0.1524)
				(type default)
			)
			(layer "F.SilkS")
		)
		(fp_line
			(start -0.7874 -0.4064)
			(end 0.7874 -0.4064)
			(stroke
				(width 0.1524)
				(type default)
			)
			(layer "F.SilkS")
		)
		(fp_line
			(start 0.7874 0.4064)
			(end -0.7874 0.4064)
			(stroke
				(width 0.1524)
				(type default)
			)
			(layer "F.SilkS")
		)
		(fp_line
			(start -0.7874 0.4064)
			(end -0.7874 -0.4064)
			(stroke
				(width 0.1524)
				(type default)
			)
			(layer "F.SilkS")
		)
		(fp_line
			(start -0.12065 -0.305054)
			(end -0.12065 -0.2794)
			(stroke
				(width 0.1)
				(type default)
			)
			(layer "F.Fab")
		)
		(fp_line
			(start -0.67945 -0.305054)
			(end -0.12065 -0.305054)
			(stroke
				(width 0.1)
				(type default)
			)
			(layer "F.Fab")
		)
		(fp_line
			(start 0.67945 -0.3048)
			(end 0.67945 0.3048)
			(stroke
				(width 0.1)
				(type default)
			)
			(layer "F.Fab")
		)
		(fp_line
			(start 0.12065 -0.3048)
			(end 0.67945 -0.3048)
			(stroke
				(width 0.1)
				(type default)
			)
			(layer "F.Fab")
		)
		(fp_line
			(start 0.12065 -0.2794)
			(end 0.12065 -0.3048)
			(stroke
				(width 0.1)
				(type default)
			)
			(layer "F.Fab")
		)
		(fp_line
			(start -0.12065 -0.2794)
			(end 0.12065 -0.2794)
			(stroke
				(width 0.1)
				(type default)
			)
			(layer "F.Fab")
		)
		(fp_line
			(start 0.120396 0.2794)
			(end -0.12065 0.2794)
			(stroke
				(width 0.1)
				(type default)
			)
			(layer "F.Fab")
		)
		(fp_line
			(start -0.12065 0.2794)
			(end -0.12065 0.3048)
			(stroke
				(width 0.1)
				(type default)
			)
			(layer "F.Fab")
		)
		(fp_line
			(start 0.67945 0.3048)
			(end 0.120396 0.3048)
			(stroke
				(width 0.1)
				(type default)
			)
			(layer "F.Fab")
		)
		(fp_line
			(start 0.120396 0.3048)
			(end 0.120396 0.2794)
			(stroke
				(width 0.1)
				(type default)
			)
			(layer "F.Fab")
		)
		(fp_line
			(start -0.12065 0.3048)
			(end -0.67945 0.3048)
			(stroke
				(width 0.1)
				(type default)
			)
			(layer "F.Fab")
		)
		(fp_line
			(start -0.67945 0.3048)
			(end -0.67945 -0.305054)
			(stroke
				(width 0.1)
				(type default)
			)
			(layer "F.Fab")
		)
		(pad "1" smd circle
			(at -0.40005 0 90)
			(size 0 0)
			(layers "F.Cu" "F.Mask" "F.Paste")
			(net "SW_P12V_AUX_PVDDCR_SOC_P1_FLT")
		)
		(pad "2" smd circle
			(at 0.40005 0 90)
			(size 0 0)
			(layers "F.Cu" "F.Mask" "F.Paste")
			(net "GND")
		)
	)
	(footprint ""
		(layer "F.Cu")
		(at 457.200508 -72.373236 180)
		(property "Reference" "PC1866"
			(at -2.201164 -2.058162 0)
			(unlocked yes)
			(layer "F.SilkS")
			(effects
				(font
					(size 0.7874 0.5842)
					(thickness 0.1524)
				)
				(justify left)
			)
		)
		(property "Value" ""
			(at 0 0 180)
			(layer "F.Fab")
			(effects
				(font
					(size 1.27 1.27)
				)
			)
		)
		(duplicate_pad_numbers_are_jumpers no)
		(fp_line
			(start -3.400044 1.249934)
			(end 3.400044 1.249934)
			(stroke
				(width 0.1524)
				(type default)
			)
			(layer "F.SilkS")
		)
		(fp_circle
			(center 0 1.249934)
			(end -3.400044 1.249934)
			(stroke
				(width 0.1524)
				(type default)
			)
			(fill no)
			(layer "F.SilkS")
		)
		(fp_poly
			(pts
				(arc
					(start 3.400044 1.249934)
					(mid 0 4.649978)
					(end -3.400044 1.249934)
				)
			)
			(stroke
				(width 0)
				(type default)
			)
			(fill yes)
			(layer "F.SilkS")
		)
		(fp_circle
			(center 0 1.249934)
			(end -3.400044 1.249934)
			(stroke
				(width 0.1)
				(type default)
			)
			(fill no)
			(layer "F.Fab")
		)
		(pad "1" thru_hole rect
			(at 0 0 180)
			(size 1.524 1.524)
			(drill 1.016)
			(layers "*.Cu" "*.Mask")
			(remove_unused_layers no)
			(net "P3V3_AUX")
			(clearance 0)
			(padstack
				(mode front_inner_back)
				(layer "Inner"
					(shape circle)
					(size 1.524 1.524)
					(clearance 0)
				)
				(layer "B.Cu"
					(shape rect)
					(size 1.524 1.524)
					(clearance 0)
				)
			)
		)
		(pad "2" thru_hole circle
			(at 0 2.500122 180)
			(size 1.524 1.524)
			(drill 1.016)
			(layers "*.Cu" "*.Mask")
			(remove_unused_layers no)
			(net "GND")
			(clearance 0)
		)
	)
	(footprint ""
		(layer "F.Cu")
		(at 319.137538 -117.950488)
		(property "Reference" "R710"
			(at 0 0 0)
			(layer "F.SilkS")
			(hide yes)
			(effects
				(font
					(size 1.27 1.27)
				)
			)
		)
		(property "Value" ""
			(at 0 0 0)
			(layer "F.Fab")
			(effects
				(font
					(size 1.27 1.27)
				)
			)
		)
		(duplicate_pad_numbers_are_jumpers no)
		(fp_line
			(start -0.7874 -0.4064)
			(end 0.7874 -0.4064)
			(stroke
				(width 0.1524)
				(type default)
			)
			(layer "F.SilkS")
		)
		(fp_line
			(start -0.7874 0.4064)
			(end -0.7874 -0.4064)
			(stroke
				(width 0.1524)
				(type default)
			)
			(layer "F.SilkS")
		)
		(fp_line
			(start 0.7874 -0.4064)
			(end 0.7874 0.4064)
			(stroke
				(width 0.1524)
				(type default)
			)
			(layer "F.SilkS")
		)
		(fp_line
			(start 0.7874 0.4064)
			(end -0.7874 0.4064)
			(stroke
				(width 0.1524)
				(type default)
			)
			(layer "F.SilkS")
		)
		(fp_line
			(start -0.67945 -0.305054)
			(end -0.12065 -0.305054)
			(stroke
				(width 0.1)
				(type default)
			)
			(layer "F.Fab")
		)
		(fp_line
			(start -0.67945 0.3048)
			(end -0.67945 -0.305054)
			(stroke
				(width 0.1)
				(type default)
			)
			(layer "F.Fab")
		)
		(fp_line
			(start -0.12065 -0.305054)
			(end -0.12065 -0.2794)
			(stroke
				(width 0.1)
				(type default)
			)
			(layer "F.Fab")
		)
		(fp_line
			(start -0.12065 -0.2794)
			(end 0.12065 -0.2794)
			(stroke
				(width 0.1)
				(type default)
			)
			(layer "F.Fab")
		)
		(fp_line
			(start -0.12065 0.2794)
			(end -0.12065 0.3048)
			(stroke
				(width 0.1)
				(type default)
			)
			(layer "F.Fab")
		)
		(fp_line
			(start -0.12065 0.3048)
			(end -0.67945 0.3048)
			(stroke
				(width 0.1)
				(type default)
			)
			(layer "F.Fab")
		)
		(fp_line
			(start 0.120396 0.2794)
			(end -0.12065 0.2794)
			(stroke
				(width 0.1)
				(type default)
			)
			(layer "F.Fab")
		)
		(fp_line
			(start 0.120396 0.3048)
			(end 0.120396 0.2794)
			(stroke
				(width 0.1)
				(type default)
			)
			(layer "F.Fab")
		)
		(fp_line
			(start 0.12065 -0.3048)
			(end 0.67945 -0.3048)
			(stroke
				(width 0.1)
				(type default)
			)
			(layer "F.Fab")
		)
		(fp_line
			(start 0.12065 -0.2794)
			(end 0.12065 -0.3048)
			(stroke
				(width 0.1)
				(type default)
			)
			(layer "F.Fab")
		)
		(fp_line
			(start 0.67945 -0.3048)
			(end 0.67945 0.3048)
			(stroke
				(width 0.1)
				(type default)
			)
			(layer "F.Fab")
		)
		(fp_line
			(start 0.67945 0.3048)
			(end 0.120396 0.3048)
			(stroke
				(width 0.1)
				(type default)
			)
			(layer "F.Fab")
		)
		(pad "1" smd circle
			(at -0.40005 0)
			(size 0 0)
			(layers "F.Cu" "F.Mask" "F.Paste")
			(net "PD_MB_FRU_WP")
		)
		(pad "2" smd circle
			(at 0.40005 0)
			(size 0 0)
			(layers "F.Cu" "F.Mask" "F.Paste")
			(net "GND")
		)
	)
	(footprint ""
		(layer "F.Cu")
		(at 157.353 -111.887 90)
		(property "Reference" "R1128"
			(at 0 0 90)
			(layer "F.SilkS")
			(hide yes)
			(effects
				(font
					(size 1.27 1.27)
				)
			)
		)
		(property "Value" ""
			(at 0 0 90)
			(layer "F.Fab")
			(effects
				(font
					(size 1.27 1.27)
				)
			)
		)
		(duplicate_pad_numbers_are_jumpers no)
		(fp_line
			(start 0.7874 -0.4064)
			(end 0.7874 0.4064)
			(stroke
				(width 0.1524)
				(type default)
			)
			(layer "F.SilkS")
		)
		(fp_line
			(start -0.7874 -0.4064)
			(end 0.7874 -0.4064)
			(stroke
				(width 0.1524)
				(type default)
			)
			(layer "F.SilkS")
		)
		(fp_line
			(start 0.7874 0.4064)
			(end -0.7874 0.4064)
			(stroke
				(width 0.1524)
				(type default)
			)
			(layer "F.SilkS")
		)
		(fp_line
			(start -0.7874 0.4064)
			(end -0.7874 -0.4064)
			(stroke
				(width 0.1524)
				(type default)
			)
			(layer "F.SilkS")
		)
		(fp_line
			(start -0.12065 -0.305054)
			(end -0.12065 -0.2794)
			(stroke
				(width 0.1)
				(type default)
			)
			(layer "F.Fab")
		)
		(fp_line
			(start -0.67945 -0.305054)
			(end -0.12065 -0.305054)
			(stroke
				(width 0.1)
				(type default)
			)
			(layer "F.Fab")
		)
		(fp_line
			(start 0.67945 -0.3048)
			(end 0.67945 0.3048)
			(stroke
				(width 0.1)
				(type default)
			)
			(layer "F.Fab")
		)
		(fp_line
			(start 0.12065 -0.3048)
			(end 0.67945 -0.3048)
			(stroke
				(width 0.1)
				(type default)
			)
			(layer "F.Fab")
		)
		(fp_line
			(start 0.12065 -0.2794)
			(end 0.12065 -0.3048)
			(stroke
				(width 0.1)
				(type default)
			)
			(layer "F.Fab")
		)
		(fp_line
			(start -0.12065 -0.2794)
			(end 0.12065 -0.2794)
			(stroke
				(width 0.1)
				(type default)
			)
			(layer "F.Fab")
		)
		(fp_line
			(start 0.120396 0.2794)
			(end -0.12065 0.2794)
			(stroke
				(width 0.1)
				(type default)
			)
			(layer "F.Fab")
		)
		(fp_line
			(start -0.12065 0.2794)
			(end -0.12065 0.3048)
			(stroke
				(width 0.1)
				(type default)
			)
			(layer "F.Fab")
		)
		(fp_line
			(start 0.67945 0.3048)
			(end 0.120396 0.3048)
			(stroke
				(width 0.1)
				(type default)
			)
			(layer "F.Fab")
		)
		(fp_line
			(start 0.120396 0.3048)
			(end 0.120396 0.2794)
			(stroke
				(width 0.1)
				(type default)
			)
			(layer "F.Fab")
		)
		(fp_line
			(start -0.12065 0.3048)
			(end -0.67945 0.3048)
			(stroke
				(width 0.1)
				(type default)
			)
			(layer "F.Fab")
		)
		(fp_line
			(start -0.67945 0.3048)
			(end -0.67945 -0.305054)
			(stroke
				(width 0.1)
				(type default)
			)
			(layer "F.Fab")
		)
		(pad "1" smd circle
			(at -0.40005 0 90)
			(size 0 0)
			(layers "F.Cu" "F.Mask" "F.Paste")
			(net "P3V3_AUX")
		)
		(pad "2" smd circle
			(at 0.40005 0 90)
			(size 0 0)
			(layers "F.Cu" "F.Mask" "F.Paste")
			(net "HP_LVC3_OCP_SFF_PRSNT2")
		)
	)
	(footprint ""
		(layer "F.Cu")
		(at 302.241458 -112.827308)
		(property "Reference" "R60"
			(at 0 0 0)
			(layer "F.SilkS")
			(hide yes)
			(effects
				(font
					(size 1.27 1.27)
				)
			)
		)
		(property "Value" ""
			(at 0 0 0)
			(layer "F.Fab")
			(effects
				(font
					(size 1.27 1.27)
				)
			)
		)
		(duplicate_pad_numbers_are_jumpers no)
		(fp_line
			(start -0.7874 -0.4064)
			(end 0.7874 -0.4064)
			(stroke
				(width 0.1524)
				(type default)
			)
			(layer "F.SilkS")
		)
		(fp_line
			(start -0.7874 0.4064)
			(end -0.7874 -0.4064)
			(stroke
				(width 0.1524)
				(type default)
			)
			(layer "F.SilkS")
		)
		(fp_line
			(start 0.7874 -0.4064)
			(end 0.7874 0.4064)
			(stroke
				(width 0.1524)
				(type default)
			)
			(layer "F.SilkS")
		)
		(fp_line
			(start 0.7874 0.4064)
			(end -0.7874 0.4064)
			(stroke
				(width 0.1524)
				(type default)
			)
			(layer "F.SilkS")
		)
		(fp_line
			(start -0.67945 -0.305054)
			(end -0.12065 -0.305054)
			(stroke
				(width 0.1)
				(type default)
			)
			(layer "F.Fab")
		)
		(fp_line
			(start -0.67945 0.3048)
			(end -0.67945 -0.305054)
			(stroke
				(width 0.1)
				(type default)
			)
			(layer "F.Fab")
		)
		(fp_line
			(start -0.12065 -0.305054)
			(end -0.12065 -0.2794)
			(stroke
				(width 0.1)
				(type default)
			)
			(layer "F.Fab")
		)
		(fp_line
			(start -0.12065 -0.2794)
			(end 0.12065 -0.2794)
			(stroke
				(width 0.1)
				(type default)
			)
			(layer "F.Fab")
		)
		(fp_line
			(start -0.12065 0.2794)
			(end -0.12065 0.3048)
			(stroke
				(width 0.1)
				(type default)
			)
			(layer "F.Fab")
		)
		(fp_line
			(start -0.12065 0.3048)
			(end -0.67945 0.3048)
			(stroke
				(width 0.1)
				(type default)
			)
			(layer "F.Fab")
		)
		(fp_line
			(start 0.120396 0.2794)
			(end -0.12065 0.2794)
			(stroke
				(width 0.1)
				(type default)
			)
			(layer "F.Fab")
		)
		(fp_line
			(start 0.120396 0.3048)
			(end 0.120396 0.2794)
			(stroke
				(width 0.1)
				(type default)
			)
			(layer "F.Fab")
		)
		(fp_line
			(start 0.12065 -0.3048)
			(end 0.67945 -0.3048)
			(stroke
				(width 0.1)
				(type default)
			)
			(layer "F.Fab")
		)
		(fp_line
			(start 0.12065 -0.2794)
			(end 0.12065 -0.3048)
			(stroke
				(width 0.1)
				(type default)
			)
			(layer "F.Fab")
		)
		(fp_line
			(start 0.67945 -0.3048)
			(end 0.67945 0.3048)
			(stroke
				(width 0.1)
				(type default)
			)
			(layer "F.Fab")
		)
		(fp_line
			(start 0.67945 0.3048)
			(end 0.120396 0.3048)
			(stroke
				(width 0.1)
				(type default)
			)
			(layer "F.Fab")
		)
		(pad "1" smd circle
			(at -0.40005 0)
			(size 0 0)
			(layers "F.Cu" "F.Mask" "F.Paste")
			(net "P3V3_AUX")
		)
		(pad "2" smd circle
			(at 0.40005 0)
			(size 0 0)
			(layers "F.Cu" "F.Mask" "F.Paste")
			(net "CPU_FRU_ADDR1")
		)
	)
	(footprint ""
		(layer "F.Cu")
		(at 410.869638 -163.684966 90)
		(property "Reference" "PC608_3"
			(at 0 0 90)
			(layer "F.SilkS")
			(hide yes)
			(effects
				(font
					(size 1.27 1.27)
				)
			)
		)
		(property "Value" ""
			(at 0 0 90)
			(layer "F.Fab")
			(effects
				(font
					(size 1.27 1.27)
				)
			)
		)
		(duplicate_pad_numbers_are_jumpers no)
		(fp_line
			(start 0.7874 -0.4064)
			(end 0.7874 0.4064)
			(stroke
				(width 0.1524)
				(type default)
			)
			(layer "F.SilkS")
		)
		(fp_line
			(start -0.7874 -0.4064)
			(end 0.7874 -0.4064)
			(stroke
				(width 0.1524)
				(type default)
			)
			(layer "F.SilkS")
		)
		(fp_line
			(start 0.7874 0.4064)
			(end -0.7874 0.4064)
			(stroke
				(width 0.1524)
				(type default)
			)
			(layer "F.SilkS")
		)
		(fp_line
			(start -0.7874 0.4064)
			(end -0.7874 -0.4064)
			(stroke
				(width 0.1524)
				(type default)
			)
			(layer "F.SilkS")
		)
		(fp_line
			(start -0.12065 -0.305054)
			(end -0.12065 -0.2794)
			(stroke
				(width 0.1)
				(type default)
			)
			(layer "F.Fab")
		)
		(fp_line
			(start -0.67945 -0.305054)
			(end -0.12065 -0.305054)
			(stroke
				(width 0.1)
				(type default)
			)
			(layer "F.Fab")
		)
		(fp_line
			(start 0.67945 -0.3048)
			(end 0.67945 0.3048)
			(stroke
				(width 0.1)
				(type default)
			)
			(layer "F.Fab")
		)
		(fp_line
			(start 0.12065 -0.3048)
			(end 0.67945 -0.3048)
			(stroke
				(width 0.1)
				(type default)
			)
			(layer "F.Fab")
		)
		(fp_line
			(start 0.12065 -0.2794)
			(end 0.12065 -0.3048)
			(stroke
				(width 0.1)
				(type default)
			)
			(layer "F.Fab")
		)
		(fp_line
			(start -0.12065 -0.2794)
			(end 0.12065 -0.2794)
			(stroke
				(width 0.1)
				(type default)
			)
			(layer "F.Fab")
		)
		(fp_line
			(start 0.120396 0.2794)
			(end -0.12065 0.2794)
			(stroke
				(width 0.1)
				(type default)
			)
			(layer "F.Fab")
		)
		(fp_line
			(start -0.12065 0.2794)
			(end -0.12065 0.3048)
			(stroke
				(width 0.1)
				(type default)
			)
			(layer "F.Fab")
		)
		(fp_line
			(start 0.67945 0.3048)
			(end 0.120396 0.3048)
			(stroke
				(width 0.1)
				(type default)
			)
			(layer "F.Fab")
		)
		(fp_line
			(start 0.120396 0.3048)
			(end 0.120396 0.2794)
			(stroke
				(width 0.1)
				(type default)
			)
			(layer "F.Fab")
		)
		(fp_line
			(start -0.12065 0.3048)
			(end -0.67945 0.3048)
			(stroke
				(width 0.1)
				(type default)
			)
			(layer "F.Fab")
		)
		(fp_line
			(start -0.67945 0.3048)
			(end -0.67945 -0.305054)
			(stroke
				(width 0.1)
				(type default)
			)
			(layer "F.Fab")
		)
		(pad "1" smd circle
			(at -0.40005 0 90)
			(size 0 0)
			(layers "F.Cu" "F.Mask" "F.Paste")
			(net "SW_P12V_AUX_PVDDCR_SOC_P0_FLT")
		)
		(pad "2" smd circle
			(at 0.40005 0 90)
			(size 0 0)
			(layers "F.Cu" "F.Mask" "F.Paste")
			(net "GND")
		)
	)
	(footprint ""
		(layer "F.Cu")
		(at 4.410202 -58.863992 -90)
		(property "Reference" "R929"
			(at 0 0 270)
			(layer "F.SilkS")
			(hide yes)
			(effects
				(font
					(size 1.27 1.27)
				)
			)
		)
		(property "Value" ""
			(at 0 0 270)
			(layer "F.Fab")
			(effects
				(font
					(size 1.27 1.27)
				)
			)
		)
		(duplicate_pad_numbers_are_jumpers no)
		(fp_line
			(start -0.7874 0.4064)
			(end -0.7874 -0.4064)
			(stroke
				(width 0.1524)
				(type default)
			)
			(layer "F.SilkS")
		)
		(fp_line
			(start 0.7874 0.4064)
			(end -0.7874 0.4064)
			(stroke
				(width 0.1524)
				(type default)
			)
			(layer "F.SilkS")
		)
		(fp_line
			(start -0.7874 -0.4064)
			(end 0.7874 -0.4064)
			(stroke
				(width 0.1524)
				(type default)
			)
			(layer "F.SilkS")
		)
		(fp_line
			(start 0.7874 -0.4064)
			(end 0.7874 0.4064)
			(stroke
				(width 0.1524)
				(type default)
			)
			(layer "F.SilkS")
		)
		(fp_line
			(start -0.67945 0.3048)
			(end -0.67945 -0.305054)
			(stroke
				(width 0.1)
				(type default)
			)
			(layer "F.Fab")
		)
		(fp_line
			(start -0.12065 0.3048)
			(end -0.67945 0.3048)
			(stroke
				(width 0.1)
				(type default)
			)
			(layer "F.Fab")
		)
		(fp_line
			(start 0.120396 0.3048)
			(end 0.120396 0.2794)
			(stroke
				(width 0.1)
				(type default)
			)
			(layer "F.Fab")
		)
		(fp_line
			(start 0.67945 0.3048)
			(end 0.120396 0.3048)
			(stroke
				(width 0.1)
				(type default)
			)
			(layer "F.Fab")
		)
		(fp_line
			(start -0.12065 0.2794)
			(end -0.12065 0.3048)
			(stroke
				(width 0.1)
				(type default)
			)
			(layer "F.Fab")
		)
		(fp_line
			(start 0.120396 0.2794)
			(end -0.12065 0.2794)
			(stroke
				(width 0.1)
				(type default)
			)
			(layer "F.Fab")
		)
		(fp_line
			(start -0.12065 -0.2794)
			(end 0.12065 -0.2794)
			(stroke
				(width 0.1)
				(type default)
			)
			(layer "F.Fab")
		)
		(fp_line
			(start 0.12065 -0.2794)
			(end 0.12065 -0.3048)
			(stroke
				(width 0.1)
				(type default)
			)
			(layer "F.Fab")
		)
		(fp_line
			(start 0.12065 -0.3048)
			(end 0.67945 -0.3048)
			(stroke
				(width 0.1)
				(type default)
			)
			(layer "F.Fab")
		)
		(fp_line
			(start 0.67945 -0.3048)
			(end 0.67945 0.3048)
			(stroke
				(width 0.1)
				(type default)
			)
			(layer "F.Fab")
		)
		(fp_line
			(start -0.67945 -0.305054)
			(end -0.12065 -0.305054)
			(stroke
				(width 0.1)
				(type default)
			)
			(layer "F.Fab")
		)
		(fp_line
			(start -0.12065 -0.305054)
			(end -0.12065 -0.2794)
			(stroke
				(width 0.1)
				(type default)
			)
			(layer "F.Fab")
		)
		(pad "1" smd circle
			(at -0.40005 0 270)
			(size 0 0)
			(layers "F.Cu" "F.Mask" "F.Paste")
			(net "CPU1_XTRIG_L4")
		)
		(pad "2" smd circle
			(at 0.40005 0 270)
			(size 0 0)
			(layers "F.Cu" "F.Mask" "F.Paste")
			(net "CPU1_XTRIG_R1_L4")
		)
	)
	(footprint ""
		(layer "F.Cu")
		(at 53.08473 -17.623536 90)
		(property "Reference" "C705"
			(at 0 0 90)
			(layer "F.SilkS")
			(hide yes)
			(effects
				(font
					(size 1.27 1.27)
				)
			)
		)
		(property "Value" ""
			(at 0 0 90)
			(layer "F.Fab")
			(effects
				(font
					(size 1.27 1.27)
				)
			)
		)
		(duplicate_pad_numbers_are_jumpers no)
		(fp_line
			(start 0.299974 -0.150114)
			(end 0.299974 0.150114)
			(stroke
				(width 0.1)
				(type default)
			)
			(layer "F.Fab")
		)
		(fp_line
			(start -0.299974 -0.150114)
			(end 0.299974 -0.150114)
			(stroke
				(width 0.1)
				(type default)
			)
			(layer "F.Fab")
		)
		(fp_line
			(start 0.299974 0.150114)
			(end -0.299974 0.150114)
			(stroke
				(width 0.1)
				(type default)
			)
			(layer "F.Fab")
		)
		(fp_line
			(start -0.299974 0.150114)
			(end -0.299974 -0.150114)
			(stroke
				(width 0.1)
				(type default)
			)
			(layer "F.Fab")
		)
		(pad "1" smd rect
			(at -0.2667 0 90)
			(size 0.3048 0.381)
			(layers "F.Cu" "F.Mask" "F.Paste")
			(net "P5E_CPU1_G1_TX_C_DP<2>")
		)
		(pad "2" smd rect
			(at 0.2667 0 90)
			(size 0.3048 0.381)
			(layers "F.Cu" "F.Mask" "F.Paste")
			(net "P5E_CPU1_G1_TX_DP<2>")
		)
	)
	(footprint ""
		(layer "F.Cu")
		(at 227.430076 -294.978074 90)
		(property "Reference" "PC6526"
			(at 0 0 90)
			(layer "F.SilkS")
			(hide yes)
			(effects
				(font
					(size 1.27 1.27)
				)
			)
		)
		(property "Value" ""
			(at 0 0 90)
			(layer "F.Fab")
			(effects
				(font
					(size 1.27 1.27)
				)
			)
		)
		(duplicate_pad_numbers_are_jumpers no)
		(fp_line
			(start 0.7874 -0.4064)
			(end 0.7874 0.4064)
			(stroke
				(width 0.1524)
				(type default)
			)
			(layer "F.SilkS")
		)
		(fp_line
			(start -0.7874 -0.4064)
			(end 0.7874 -0.4064)
			(stroke
				(width 0.1524)
				(type default)
			)
			(layer "F.SilkS")
		)
		(fp_line
			(start 0.7874 0.4064)
			(end -0.7874 0.4064)
			(stroke
				(width 0.1524)
				(type default)
			)
			(layer "F.SilkS")
		)
		(fp_line
			(start -0.7874 0.4064)
			(end -0.7874 -0.4064)
			(stroke
				(width 0.1524)
				(type default)
			)
			(layer "F.SilkS")
		)
		(fp_line
			(start -0.12065 -0.305054)
			(end -0.12065 -0.2794)
			(stroke
				(width 0.1)
				(type default)
			)
			(layer "F.Fab")
		)
		(fp_line
			(start -0.67945 -0.305054)
			(end -0.12065 -0.305054)
			(stroke
				(width 0.1)
				(type default)
			)
			(layer "F.Fab")
		)
		(fp_line
			(start 0.67945 -0.3048)
			(end 0.67945 0.3048)
			(stroke
				(width 0.1)
				(type default)
			)
			(layer "F.Fab")
		)
		(fp_line
			(start 0.12065 -0.3048)
			(end 0.67945 -0.3048)
			(stroke
				(width 0.1)
				(type default)
			)
			(layer "F.Fab")
		)
		(fp_line
			(start 0.12065 -0.2794)
			(end 0.12065 -0.3048)
			(stroke
				(width 0.1)
				(type default)
			)
			(layer "F.Fab")
		)
		(fp_line
			(start -0.12065 -0.2794)
			(end 0.12065 -0.2794)
			(stroke
				(width 0.1)
				(type default)
			)
			(layer "F.Fab")
		)
		(fp_line
			(start 0.120396 0.2794)
			(end -0.12065 0.2794)
			(stroke
				(width 0.1)
				(type default)
			)
			(layer "F.Fab")
		)
		(fp_line
			(start -0.12065 0.2794)
			(end -0.12065 0.3048)
			(stroke
				(width 0.1)
				(type default)
			)
			(layer "F.Fab")
		)
		(fp_line
			(start 0.67945 0.3048)
			(end 0.120396 0.3048)
			(stroke
				(width 0.1)
				(type default)
			)
			(layer "F.Fab")
		)
		(fp_line
			(start 0.120396 0.3048)
			(end 0.120396 0.2794)
			(stroke
				(width 0.1)
				(type default)
			)
			(layer "F.Fab")
		)
		(fp_line
			(start -0.12065 0.3048)
			(end -0.67945 0.3048)
			(stroke
				(width 0.1)
				(type default)
			)
			(layer "F.Fab")
		)
		(fp_line
			(start -0.67945 0.3048)
			(end -0.67945 -0.305054)
			(stroke
				(width 0.1)
				(type default)
			)
			(layer "F.Fab")
		)
		(pad "1" smd circle
			(at -0.40005 0 90)
			(size 0 0)
			(layers "F.Cu" "F.Mask" "F.Paste")
			(net "SW_P1V8_RETIMER_CPU1_BST_R")
		)
		(pad "2" smd circle
			(at 0.40005 0 90)
			(size 0 0)
			(layers "F.Cu" "F.Mask" "F.Paste")
			(net "SW_P1V8_RETIMER_CPU1_SW")
		)
	)
	(footprint ""
		(layer "F.Cu")
		(at 107.256834 -136.306052 90)
		(property "Reference" "PQ11"
			(at -1.27 2.31267 90)
			(unlocked yes)
			(layer "F.SilkS")
			(effects
				(font
					(size 0.7874 0.5842)
					(thickness 0.1524)
				)
				(justify left)
			)
		)
		(property "Value" ""
			(at 0 0 90)
			(layer "F.Fab")
			(effects
				(font
					(size 1.27 1.27)
				)
			)
		)
		(duplicate_pad_numbers_are_jumpers no)
		(fp_line
			(start 1.603248 -1.500124)
			(end 1.603248 1.500124)
			(stroke
				(width 0.1524)
				(type default)
			)
			(layer "F.SilkS")
		)
		(fp_line
			(start -1.603248 -1.500124)
			(end 1.603248 -1.500124)
			(stroke
				(width 0.1524)
				(type default)
			)
			(layer "F.SilkS")
		)
		(fp_line
			(start 1.603248 1.500124)
			(end -1.603248 1.500124)
			(stroke
				(width 0.1524)
				(type default)
			)
			(layer "F.SilkS")
		)
		(fp_line
			(start -1.603248 1.500124)
			(end -1.603248 -1.500124)
			(stroke
				(width 0.1524)
				(type default)
			)
			(layer "F.SilkS")
		)
		(fp_line
			(start 0.700024 -1.500124)
			(end -0.700024 -1.500124)
			(stroke
				(width 0.1)
				(type default)
			)
			(layer "F.Fab")
		)
		(fp_line
			(start -0.700024 -1.500124)
			(end -0.700024 -1.169924)
			(stroke
				(width 0.1)
				(type default)
			)
			(layer "F.Fab")
		)
		(fp_line
			(start -0.700024 -1.169924)
			(end -1.249934 -1.169924)
			(stroke
				(width 0.1)
				(type default)
			)
			(layer "F.Fab")
		)
		(fp_line
			(start -1.249934 -1.169924)
			(end -1.249934 -0.729996)
			(stroke
				(width 0.1)
				(type default)
			)
			(layer "F.Fab")
		)
		(fp_line
			(start -0.6985 -0.729996)
			(end -0.6985 0.729996)
			(stroke
				(width 0.1)
				(type default)
			)
			(layer "F.Fab")
		)
		(fp_line
			(start -1.249934 -0.729996)
			(end -0.6985 -0.729996)
			(stroke
				(width 0.1)
				(type default)
			)
			(layer "F.Fab")
		)
		(fp_line
			(start 1.249934 -0.219964)
			(end 0.700024 -0.219964)
			(stroke
				(width 0.1)
				(type default)
			)
			(layer "F.Fab")
		)
		(fp_line
			(start 0.700024 -0.219964)
			(end 0.700024 -1.500124)
			(stroke
				(width 0.1)
				(type default)
			)
			(layer "F.Fab")
		)
		(fp_line
			(start 1.249934 0.219964)
			(end 1.249934 -0.219964)
			(stroke
				(width 0.1)
				(type default)
			)
			(layer "F.Fab")
		)
		(fp_line
			(start 0.700024 0.219964)
			(end 1.249934 0.219964)
			(stroke
				(width 0.1)
				(type default)
			)
			(layer "F.Fab")
		)
		(fp_line
			(start -0.6985 0.729996)
			(end -1.249934 0.729996)
			(stroke
				(width 0.1)
				(type default)
			)
			(layer "F.Fab")
		)
		(fp_line
			(start -1.249934 0.729996)
			(end -1.249934 1.169924)
			(stroke
				(width 0.1)
				(type default)
			)
			(layer "F.Fab")
		)
		(fp_line
			(start -0.700024 1.169924)
			(end -0.700024 1.500124)
			(stroke
				(width 0.1)
				(type default)
			)
			(layer "F.Fab")
		)
		(fp_line
			(start -1.249934 1.169924)
			(end -0.700024 1.169924)
			(stroke
				(width 0.1)
				(type default)
			)
			(layer "F.Fab")
		)
		(fp_line
			(start 0.700024 1.500124)
			(end 0.700024 0.219964)
			(stroke
				(width 0.1)
				(type default)
			)
			(layer "F.Fab")
		)
		(fp_line
			(start -0.700024 1.500124)
			(end 0.700024 1.500124)
			(stroke
				(width 0.1)
				(type default)
			)
			(layer "F.Fab")
		)
		(fp_rect
			(start -0.700024 1.500124)
			(end 0.700024 -1.500124)
			(stroke
				(width 0)
				(type default)
			)
			(fill no)
			(layer "F.Fab")
		)
		(pad "D" smd rect
			(at 0.999998 0)
			(size 0.8128 0.9144)
			(layers "F.Cu" "F.Mask" "F.Paste")
			(net "PVDDCR_SOC_P1_EN//ADDR_CFG")
		)
		(pad "G" smd rect
			(at -0.999998 -0.94996)
			(size 0.8128 0.9144)
			(layers "F.Cu" "F.Mask" "F.Paste")
			(net "PVDDCR_SOC_P1_EN_GD")
		)
		(pad "S" smd rect
			(at -0.999998 0.94996)
			(size 0.8128 0.9144)
			(layers "F.Cu" "F.Mask" "F.Paste")
			(net "P3V3_AUX")
		)
	)
	(footprint ""
		(layer "F.Cu")
		(at 300.3804 -363.982)
		(property "Reference" "C5004"
			(at 0 0 0)
			(layer "F.SilkS")
			(hide yes)
			(effects
				(font
					(size 1.27 1.27)
				)
			)
		)
		(property "Value" ""
			(at 0 0 0)
			(layer "F.Fab")
			(effects
				(font
					(size 1.27 1.27)
				)
			)
		)
		(duplicate_pad_numbers_are_jumpers no)
		(fp_line
			(start -0.7874 -0.4064)
			(end 0.7874 -0.4064)
			(stroke
				(width 0.1524)
				(type default)
			)
			(layer "F.SilkS")
		)
		(fp_line
			(start -0.7874 0.4064)
			(end -0.7874 -0.4064)
			(stroke
				(width 0.1524)
				(type default)
			)
			(layer "F.SilkS")
		)
		(fp_line
			(start 0.7874 -0.4064)
			(end 0.7874 0.4064)
			(stroke
				(width 0.1524)
				(type default)
			)
			(layer "F.SilkS")
		)
		(fp_line
			(start 0.7874 0.4064)
			(end -0.7874 0.4064)
			(stroke
				(width 0.1524)
				(type default)
			)
			(layer "F.SilkS")
		)
		(fp_line
			(start -0.67945 -0.305054)
			(end -0.12065 -0.305054)
			(stroke
				(width 0.1)
				(type default)
			)
			(layer "F.Fab")
		)
		(fp_line
			(start -0.67945 0.3048)
			(end -0.67945 -0.305054)
			(stroke
				(width 0.1)
				(type default)
			)
			(layer "F.Fab")
		)
		(fp_line
			(start -0.12065 -0.305054)
			(end -0.12065 -0.2794)
			(stroke
				(width 0.1)
				(type default)
			)
			(layer "F.Fab")
		)
		(fp_line
			(start -0.12065 -0.2794)
			(end 0.12065 -0.2794)
			(stroke
				(width 0.1)
				(type default)
			)
			(layer "F.Fab")
		)
		(fp_line
			(start -0.12065 0.2794)
			(end -0.12065 0.3048)
			(stroke
				(width 0.1)
				(type default)
			)
			(layer "F.Fab")
		)
		(fp_line
			(start -0.12065 0.3048)
			(end -0.67945 0.3048)
			(stroke
				(width 0.1)
				(type default)
			)
			(layer "F.Fab")
		)
		(fp_line
			(start 0.120396 0.2794)
			(end -0.12065 0.2794)
			(stroke
				(width 0.1)
				(type default)
			)
			(layer "F.Fab")
		)
		(fp_line
			(start 0.120396 0.3048)
			(end 0.120396 0.2794)
			(stroke
				(width 0.1)
				(type default)
			)
			(layer "F.Fab")
		)
		(fp_line
			(start 0.12065 -0.3048)
			(end 0.67945 -0.3048)
			(stroke
				(width 0.1)
				(type default)
			)
			(layer "F.Fab")
		)
		(fp_line
			(start 0.12065 -0.2794)
			(end 0.12065 -0.3048)
			(stroke
				(width 0.1)
				(type default)
			)
			(layer "F.Fab")
		)
		(fp_line
			(start 0.67945 -0.3048)
			(end 0.67945 0.3048)
			(stroke
				(width 0.1)
				(type default)
			)
			(layer "F.Fab")
		)
		(fp_line
			(start 0.67945 0.3048)
			(end 0.120396 0.3048)
			(stroke
				(width 0.1)
				(type default)
			)
			(layer "F.Fab")
		)
		(pad "1" smd circle
			(at -0.40005 0)
			(size 0 0)
			(layers "F.Cu" "F.Mask" "F.Paste")
			(net "GND")
		)
		(pad "2" smd circle
			(at 0.40005 0)
			(size 0 0)
			(layers "F.Cu" "F.Mask" "F.Paste")
			(net "PWRGD_PVDDCR_CPU1_P0")
		)
	)
	(footprint ""
		(layer "F.Cu")
		(at 27.29611 -351.932748)
		(property "Reference" "PR368"
			(at 0 0 0)
			(layer "F.SilkS")
			(hide yes)
			(effects
				(font
					(size 1.27 1.27)
				)
			)
		)
		(property "Value" ""
			(at 0 0 0)
			(layer "F.Fab")
			(effects
				(font
					(size 1.27 1.27)
				)
			)
		)
		(duplicate_pad_numbers_are_jumpers no)
		(fp_line
			(start -0.7874 -0.4064)
			(end 0.7874 -0.4064)
			(stroke
				(width 0.1524)
				(type default)
			)
			(layer "F.SilkS")
		)
		(fp_line
			(start -0.7874 0.4064)
			(end -0.7874 -0.4064)
			(stroke
				(width 0.1524)
				(type default)
			)
			(layer "F.SilkS")
		)
		(fp_line
			(start 0.7874 -0.4064)
			(end 0.7874 0.4064)
			(stroke
				(width 0.1524)
				(type default)
			)
			(layer "F.SilkS")
		)
		(fp_line
			(start 0.7874 0.4064)
			(end -0.7874 0.4064)
			(stroke
				(width 0.1524)
				(type default)
			)
			(layer "F.SilkS")
		)
		(fp_line
			(start -0.67945 -0.305054)
			(end -0.12065 -0.305054)
			(stroke
				(width 0.1)
				(type default)
			)
			(layer "F.Fab")
		)
		(fp_line
			(start -0.67945 0.3048)
			(end -0.67945 -0.305054)
			(stroke
				(width 0.1)
				(type default)
			)
			(layer "F.Fab")
		)
		(fp_line
			(start -0.12065 -0.305054)
			(end -0.12065 -0.2794)
			(stroke
				(width 0.1)
				(type default)
			)
			(layer "F.Fab")
		)
		(fp_line
			(start -0.12065 -0.2794)
			(end 0.12065 -0.2794)
			(stroke
				(width 0.1)
				(type default)
			)
			(layer "F.Fab")
		)
		(fp_line
			(start -0.12065 0.2794)
			(end -0.12065 0.3048)
			(stroke
				(width 0.1)
				(type default)
			)
			(layer "F.Fab")
		)
		(fp_line
			(start -0.12065 0.3048)
			(end -0.67945 0.3048)
			(stroke
				(width 0.1)
				(type default)
			)
			(layer "F.Fab")
		)
		(fp_line
			(start 0.120396 0.2794)
			(end -0.12065 0.2794)
			(stroke
				(width 0.1)
				(type default)
			)
			(layer "F.Fab")
		)
		(fp_line
			(start 0.120396 0.3048)
			(end 0.120396 0.2794)
			(stroke
				(width 0.1)
				(type default)
			)
			(layer "F.Fab")
		)
		(fp_line
			(start 0.12065 -0.3048)
			(end 0.67945 -0.3048)
			(stroke
				(width 0.1)
				(type default)
			)
			(layer "F.Fab")
		)
		(fp_line
			(start 0.12065 -0.2794)
			(end 0.12065 -0.3048)
			(stroke
				(width 0.1)
				(type default)
			)
			(layer "F.Fab")
		)
		(fp_line
			(start 0.67945 -0.3048)
			(end 0.67945 0.3048)
			(stroke
				(width 0.1)
				(type default)
			)
			(layer "F.Fab")
		)
		(fp_line
			(start 0.67945 0.3048)
			(end 0.120396 0.3048)
			(stroke
				(width 0.1)
				(type default)
			)
			(layer "F.Fab")
		)
		(pad "1" smd circle
			(at -0.40005 0)
			(size 0 0)
			(layers "F.Cu" "F.Mask" "F.Paste")
			(net "PVDDIO_P1_LSET4")
		)
		(pad "2" smd circle
			(at 0.40005 0)
			(size 0 0)
			(layers "F.Cu" "F.Mask" "F.Paste")
			(net "GND")
		)
	)
	(footprint ""
		(layer "F.Cu")
		(at 97.902522 -67.038982 -90)
		(property "Reference" "PD109"
			(at 4.125722 -2.54254 90)
			(unlocked yes)
			(layer "F.SilkS")
			(effects
				(font
					(size 0.7874 0.5842)
					(thickness 0.1524)
				)
				(justify left)
			)
		)
		(property "Value" ""
			(at 0 0 270)
			(layer "F.Fab")
			(effects
				(font
					(size 1.27 1.27)
				)
			)
		)
		(duplicate_pad_numbers_are_jumpers no)
		(fp_line
			(start -3.400044 1.459992)
			(end -3.400044 -1.459992)
			(stroke
				(width 0.1524)
				(type default)
			)
			(layer "F.SilkS")
		)
		(fp_line
			(start 4.107942 1.459992)
			(end -3.400044 1.459992)
			(stroke
				(width 0.1524)
				(type default)
			)
			(layer "F.SilkS")
		)
		(fp_line
			(start -3.400044 -1.459992)
			(end 4.107942 -1.459992)
			(stroke
				(width 0.1524)
				(type default)
			)
			(layer "F.SilkS")
		)
		(fp_line
			(start 4.107942 -1.459992)
			(end 4.107942 1.459992)
			(stroke
				(width 0.1524)
				(type default)
			)
			(layer "F.SilkS")
		)
		(fp_rect
			(start 4.107942 1.459992)
			(end 3.308096 -1.459992)
			(stroke
				(width 0)
				(type default)
			)
			(fill yes)
			(layer "F.SilkS")
		)
		(fp_line
			(start -2.29997 1.459992)
			(end -2.29997 -1.459992)
			(stroke
				(width 0.1)
				(type default)
			)
			(layer "F.Fab")
		)
		(fp_line
			(start 2.29997 1.459992)
			(end -2.29997 1.459992)
			(stroke
				(width 0.1)
				(type default)
			)
			(layer "F.Fab")
		)
		(fp_line
			(start -2.29997 -1.459992)
			(end 2.29997 -1.459992)
			(stroke
				(width 0.1)
				(type default)
			)
			(layer "F.Fab")
		)
		(fp_line
			(start 2.29997 -1.459992)
			(end 2.29997 1.459992)
			(stroke
				(width 0.1)
				(type default)
			)
			(layer "F.Fab")
		)
		(fp_text user "-"
			(at 5.4102 0.29845 90)
			(unlocked yes)
			(layer "F.SilkS")
			(effects
				(font
					(size 1.905 1.4224)
					(thickness 0.1524)
				)
				(justify left)
			)
		)
		(fp_text user "+"
			(at -5.329174 -1.367536 270)
			(unlocked yes)
			(layer "F.SilkS")
			(effects
				(font
					(size 1.905 1.4224)
					(thickness 0.1524)
				)
				(justify left)
			)
		)
		(fp_text user "-"
			(at 5.4102 0.29845 90)
			(unlocked yes)
			(layer "F.Fab")
			(effects
				(font
					(size 1.905 1.4224)
					(thickness 0.1524)
				)
				(justify left)
			)
		)
		(fp_text user "+"
			(at -4.7752 -0.12065 270)
			(unlocked yes)
			(layer "F.Fab")
			(effects
				(font
					(size 1.905 1.4224)
					(thickness 0.1524)
				)
				(justify left)
			)
		)
		(pad "A" smd rect
			(at -1.999996 0)
			(size 1.7018 2.5146)
			(layers "F.Cu" "F.Mask" "F.Paste")
			(net "GND")
		)
		(pad "C" smd rect
			(at 1.999996 0)
			(size 1.7018 2.5146)
			(layers "F.Cu" "F.Mask" "F.Paste")
			(net "P3V3_OCP_V3_2_R")
		)
	)
	(footprint ""
		(layer "F.Cu")
		(at 98.52533 -39.465758 180)
		(property "Reference" "U217"
			(at 1.229868 1.844548 0)
			(unlocked yes)
			(layer "F.SilkS")
			(effects
				(font
					(size 0.7874 0.5842)
					(thickness 0.1524)
				)
				(justify left)
			)
		)
		(property "Value" ""
			(at 0 0 180)
			(layer "F.Fab")
			(effects
				(font
					(size 1.27 1.27)
				)
			)
		)
		(duplicate_pad_numbers_are_jumpers no)
		(fp_line
			(start 1.400048 1.100074)
			(end -1.400048 1.100074)
			(stroke
				(width 0.1524)
				(type default)
			)
			(layer "F.SilkS")
		)
		(fp_line
			(start 1.400048 -1.100074)
			(end 1.400048 1.100074)
			(stroke
				(width 0.1524)
				(type default)
			)
			(layer "F.SilkS")
		)
		(fp_line
			(start 1.400048 -1.100074)
			(end -1.400048 -1.100074)
			(stroke
				(width 0.1524)
				(type default)
			)
			(layer "F.SilkS")
		)
		(fp_line
			(start -1.400048 1.100074)
			(end -1.400048 -1.100074)
			(stroke
				(width 0.1524)
				(type default)
			)
			(layer "F.SilkS")
		)
		(fp_poly
			(pts
				(xy -0.51562 -2.307082) (xy -1.02362 -1.291082) (xy -1.53162 -2.307082)
			)
			(stroke
				(width 0)
				(type default)
			)
			(fill yes)
			(layer "F.SilkS")
		)
		(fp_line
			(start 0.674878 1.100074)
			(end -0.674878 1.100074)
			(stroke
				(width 0.1)
				(type default)
			)
			(layer "F.Fab")
		)
		(fp_line
			(start 0.674878 -1.100074)
			(end 0.674878 1.100074)
			(stroke
				(width 0.1)
				(type default)
			)
			(layer "F.Fab")
		)
		(fp_line
			(start -0.674878 1.100074)
			(end -0.674878 -1.100074)
			(stroke
				(width 0.1)
				(type default)
			)
			(layer "F.Fab")
		)
		(fp_line
			(start -0.674878 -1.100074)
			(end 0.674878 -1.100074)
			(stroke
				(width 0.1)
				(type default)
			)
			(layer "F.Fab")
		)
		(fp_poly
			(pts
				(xy -1.590548 -0.649986) (xy -2.606548 -1.157986) (xy -2.606548 -0.141986)
			)
			(stroke
				(width 0)
				(type default)
			)
			(fill yes)
			(layer "F.Fab")
		)
		(pad "1" smd rect
			(at -0.94996 -0.649986 90)
			(size 0.4318 0.6096)
			(layers "F.Cu" "F.Mask" "F.Paste")
			(net "PU_OCP_V3_2_WAKE_OE")
		)
		(pad "2" smd rect
			(at -0.94996 0 90)
			(size 0.4318 0.6096)
			(layers "F.Cu" "F.Mask" "F.Paste")
			(net "IRQ_LVC3_OCP_V3_2_WAKE_N")
		)
		(pad "3" smd rect
			(at -0.94996 0.649986 90)
			(size 0.4318 0.6096)
			(layers "F.Cu" "F.Mask" "F.Paste")
			(net "GND")
		)
		(pad "4" smd rect
			(at 0.94996 0.649986 90)
			(size 0.4318 0.6096)
			(layers "F.Cu" "F.Mask" "F.Paste")
			(net "OCP_V3_2_WAKE_BUFF_N")
		)
		(pad "5" smd rect
			(at 0.94996 -0.649986 90)
			(size 0.4318 0.6096)
			(layers "F.Cu" "F.Mask" "F.Paste")
			(net "P3V3_AUX")
		)
	)
	(footprint ""
		(layer "F.Cu")
		(at 212.993732 -116.732812 180)
		(property "Reference" "R136"
			(at 0 0 180)
			(layer "F.SilkS")
			(hide yes)
			(effects
				(font
					(size 1.27 1.27)
				)
			)
		)
		(property "Value" ""
			(at 0 0 180)
			(layer "F.Fab")
			(effects
				(font
					(size 1.27 1.27)
				)
			)
		)
		(duplicate_pad_numbers_are_jumpers no)
		(fp_line
			(start 0.7874 0.4064)
			(end -0.7874 0.4064)
			(stroke
				(width 0.1524)
				(type default)
			)
			(layer "F.SilkS")
		)
		(fp_line
			(start 0.7874 -0.4064)
			(end 0.7874 0.4064)
			(stroke
				(width 0.1524)
				(type default)
			)
			(layer "F.SilkS")
		)
		(fp_line
			(start -0.7874 0.4064)
			(end -0.7874 -0.4064)
			(stroke
				(width 0.1524)
				(type default)
			)
			(layer "F.SilkS")
		)
		(fp_line
			(start -0.7874 -0.4064)
			(end 0.7874 -0.4064)
			(stroke
				(width 0.1524)
				(type default)
			)
			(layer "F.SilkS")
		)
		(fp_line
			(start 0.67945 0.3048)
			(end 0.120396 0.3048)
			(stroke
				(width 0.1)
				(type default)
			)
			(layer "F.Fab")
		)
		(fp_line
			(start 0.67945 -0.3048)
			(end 0.67945 0.3048)
			(stroke
				(width 0.1)
				(type default)
			)
			(layer "F.Fab")
		)
		(fp_line
			(start 0.12065 -0.2794)
			(end 0.12065 -0.3048)
			(stroke
				(width 0.1)
				(type default)
			)
			(layer "F.Fab")
		)
		(fp_line
			(start 0.12065 -0.3048)
			(end 0.67945 -0.3048)
			(stroke
				(width 0.1)
				(type default)
			)
			(layer "F.Fab")
		)
		(fp_line
			(start 0.120396 0.3048)
			(end 0.120396 0.2794)
			(stroke
				(width 0.1)
				(type default)
			)
			(layer "F.Fab")
		)
		(fp_line
			(start 0.120396 0.2794)
			(end -0.12065 0.2794)
			(stroke
				(width 0.1)
				(type default)
			)
			(layer "F.Fab")
		)
		(fp_line
			(start -0.12065 0.3048)
			(end -0.67945 0.3048)
			(stroke
				(width 0.1)
				(type default)
			)
			(layer "F.Fab")
		)
		(fp_line
			(start -0.12065 0.2794)
			(end -0.12065 0.3048)
			(stroke
				(width 0.1)
				(type default)
			)
			(layer "F.Fab")
		)
		(fp_line
			(start -0.12065 -0.2794)
			(end 0.12065 -0.2794)
			(stroke
				(width 0.1)
				(type default)
			)
			(layer "F.Fab")
		)
		(fp_line
			(start -0.12065 -0.305054)
			(end -0.12065 -0.2794)
			(stroke
				(width 0.1)
				(type default)
			)
			(layer "F.Fab")
		)
		(fp_line
			(start -0.67945 0.3048)
			(end -0.67945 -0.305054)
			(stroke
				(width 0.1)
				(type default)
			)
			(layer "F.Fab")
		)
		(fp_line
			(start -0.67945 -0.305054)
			(end -0.12065 -0.305054)
			(stroke
				(width 0.1)
				(type default)
			)
			(layer "F.Fab")
		)
		(pad "1" smd circle
			(at -0.40005 0 180)
			(size 0 0)
			(layers "F.Cu" "F.Mask" "F.Paste")
			(net "FM_APML_MUX2_SEL")
		)
		(pad "2" smd circle
			(at 0.40005 0 180)
			(size 0 0)
			(layers "F.Cu" "F.Mask" "F.Paste")
			(net "GND")
		)
	)
	(footprint ""
		(layer "F.Cu")
		(at 176.911 -133.568948 90)
		(property "Reference" "R17"
			(at 0 0 90)
			(layer "F.SilkS")
			(hide yes)
			(effects
				(font
					(size 1.27 1.27)
				)
			)
		)
		(property "Value" ""
			(at 0 0 90)
			(layer "F.Fab")
			(effects
				(font
					(size 1.27 1.27)
				)
			)
		)
		(duplicate_pad_numbers_are_jumpers no)
		(fp_line
			(start 0.7874 -0.4064)
			(end 0.7874 0.4064)
			(stroke
				(width 0.1524)
				(type default)
			)
			(layer "F.SilkS")
		)
		(fp_line
			(start -0.7874 -0.4064)
			(end 0.7874 -0.4064)
			(stroke
				(width 0.1524)
				(type default)
			)
			(layer "F.SilkS")
		)
		(fp_line
			(start 0.7874 0.4064)
			(end -0.7874 0.4064)
			(stroke
				(width 0.1524)
				(type default)
			)
			(layer "F.SilkS")
		)
		(fp_line
			(start -0.7874 0.4064)
			(end -0.7874 -0.4064)
			(stroke
				(width 0.1524)
				(type default)
			)
			(layer "F.SilkS")
		)
		(fp_line
			(start -0.12065 -0.305054)
			(end -0.12065 -0.2794)
			(stroke
				(width 0.1)
				(type default)
			)
			(layer "F.Fab")
		)
		(fp_line
			(start -0.67945 -0.305054)
			(end -0.12065 -0.305054)
			(stroke
				(width 0.1)
				(type default)
			)
			(layer "F.Fab")
		)
		(fp_line
			(start 0.67945 -0.3048)
			(end 0.67945 0.3048)
			(stroke
				(width 0.1)
				(type default)
			)
			(layer "F.Fab")
		)
		(fp_line
			(start 0.12065 -0.3048)
			(end 0.67945 -0.3048)
			(stroke
				(width 0.1)
				(type default)
			)
			(layer "F.Fab")
		)
		(fp_line
			(start 0.12065 -0.2794)
			(end 0.12065 -0.3048)
			(stroke
				(width 0.1)
				(type default)
			)
			(layer "F.Fab")
		)
		(fp_line
			(start -0.12065 -0.2794)
			(end 0.12065 -0.2794)
			(stroke
				(width 0.1)
				(type default)
			)
			(layer "F.Fab")
		)
		(fp_line
			(start 0.120396 0.2794)
			(end -0.12065 0.2794)
			(stroke
				(width 0.1)
				(type default)
			)
			(layer "F.Fab")
		)
		(fp_line
			(start -0.12065 0.2794)
			(end -0.12065 0.3048)
			(stroke
				(width 0.1)
				(type default)
			)
			(layer "F.Fab")
		)
		(fp_line
			(start 0.67945 0.3048)
			(end 0.120396 0.3048)
			(stroke
				(width 0.1)
				(type default)
			)
			(layer "F.Fab")
		)
		(fp_line
			(start 0.120396 0.3048)
			(end 0.120396 0.2794)
			(stroke
				(width 0.1)
				(type default)
			)
			(layer "F.Fab")
		)
		(fp_line
			(start -0.12065 0.3048)
			(end -0.67945 0.3048)
			(stroke
				(width 0.1)
				(type default)
			)
			(layer "F.Fab")
		)
		(fp_line
			(start -0.67945 0.3048)
			(end -0.67945 -0.305054)
			(stroke
				(width 0.1)
				(type default)
			)
			(layer "F.Fab")
		)
		(pad "1" smd circle
			(at -0.40005 0 90)
			(size 0 0)
			(layers "F.Cu" "F.Mask" "F.Paste")
			(net "RST_CPU0_PERST1_N")
		)
		(pad "2" smd circle
			(at 0.40005 0 90)
			(size 0 0)
			(layers "F.Cu" "F.Mask" "F.Paste")
			(net "GND")
		)
	)
	(footprint ""
		(layer "F.Cu")
		(at 16.20012 -76.144628 90)
		(property "Reference" "C1876"
			(at 0 0 90)
			(layer "F.SilkS")
			(hide yes)
			(effects
				(font
					(size 1.27 1.27)
				)
			)
		)
		(property "Value" ""
			(at 0 0 90)
			(layer "F.Fab")
			(effects
				(font
					(size 1.27 1.27)
				)
			)
		)
		(duplicate_pad_numbers_are_jumpers no)
		(fp_line
			(start 0.7874 -0.4064)
			(end 0.7874 0.4064)
			(stroke
				(width 0.1524)
				(type default)
			)
			(layer "F.SilkS")
		)
		(fp_line
			(start -0.7874 -0.4064)
			(end 0.7874 -0.4064)
			(stroke
				(width 0.1524)
				(type default)
			)
			(layer "F.SilkS")
		)
		(fp_line
			(start 0.7874 0.4064)
			(end -0.7874 0.4064)
			(stroke
				(width 0.1524)
				(type default)
			)
			(layer "F.SilkS")
		)
		(fp_line
			(start -0.7874 0.4064)
			(end -0.7874 -0.4064)
			(stroke
				(width 0.1524)
				(type default)
			)
			(layer "F.SilkS")
		)
		(fp_line
			(start -0.12065 -0.305054)
			(end -0.12065 -0.2794)
			(stroke
				(width 0.1)
				(type default)
			)
			(layer "F.Fab")
		)
		(fp_line
			(start -0.67945 -0.305054)
			(end -0.12065 -0.305054)
			(stroke
				(width 0.1)
				(type default)
			)
			(layer "F.Fab")
		)
		(fp_line
			(start 0.67945 -0.3048)
			(end 0.67945 0.3048)
			(stroke
				(width 0.1)
				(type default)
			)
			(layer "F.Fab")
		)
		(fp_line
			(start 0.12065 -0.3048)
			(end 0.67945 -0.3048)
			(stroke
				(width 0.1)
				(type default)
			)
			(layer "F.Fab")
		)
		(fp_line
			(start 0.12065 -0.2794)
			(end 0.12065 -0.3048)
			(stroke
				(width 0.1)
				(type default)
			)
			(layer "F.Fab")
		)
		(fp_line
			(start -0.12065 -0.2794)
			(end 0.12065 -0.2794)
			(stroke
				(width 0.1)
				(type default)
			)
			(layer "F.Fab")
		)
		(fp_line
			(start 0.120396 0.2794)
			(end -0.12065 0.2794)
			(stroke
				(width 0.1)
				(type default)
			)
			(layer "F.Fab")
		)
		(fp_line
			(start -0.12065 0.2794)
			(end -0.12065 0.3048)
			(stroke
				(width 0.1)
				(type default)
			)
			(layer "F.Fab")
		)
		(fp_line
			(start 0.67945 0.3048)
			(end 0.120396 0.3048)
			(stroke
				(width 0.1)
				(type default)
			)
			(layer "F.Fab")
		)
		(fp_line
			(start 0.120396 0.3048)
			(end 0.120396 0.2794)
			(stroke
				(width 0.1)
				(type default)
			)
			(layer "F.Fab")
		)
		(fp_line
			(start -0.12065 0.3048)
			(end -0.67945 0.3048)
			(stroke
				(width 0.1)
				(type default)
			)
			(layer "F.Fab")
		)
		(fp_line
			(start -0.67945 0.3048)
			(end -0.67945 -0.305054)
			(stroke
				(width 0.1)
				(type default)
			)
			(layer "F.Fab")
		)
		(pad "1" smd circle
			(at -0.40005 0 90)
			(size 0 0)
			(layers "F.Cu" "F.Mask" "F.Paste")
			(net "P3V3_AUX")
		)
		(pad "2" smd circle
			(at 0.40005 0 90)
			(size 0 0)
			(layers "F.Cu" "F.Mask" "F.Paste")
			(net "GND")
		)
	)
	(footprint ""
		(layer "F.Cu")
		(at 180.3908 -392.4554)
		(property "Reference" "R1416"
			(at 0 0 0)
			(layer "F.SilkS")
			(hide yes)
			(effects
				(font
					(size 1.27 1.27)
				)
			)
		)
		(property "Value" ""
			(at 0 0 0)
			(layer "F.Fab")
			(effects
				(font
					(size 1.27 1.27)
				)
			)
		)
		(duplicate_pad_numbers_are_jumpers no)
		(fp_line
			(start -0.32512 -0.175006)
			(end 0.32512 -0.175006)
			(stroke
				(width 0.1)
				(type default)
			)
			(layer "F.Fab")
		)
		(fp_line
			(start -0.32512 0.175006)
			(end -0.32512 -0.175006)
			(stroke
				(width 0.1)
				(type default)
			)
			(layer "F.Fab")
		)
		(fp_line
			(start 0.32512 -0.175006)
			(end 0.32512 0.175006)
			(stroke
				(width 0.1)
				(type default)
			)
			(layer "F.Fab")
		)
		(fp_line
			(start 0.32512 0.175006)
			(end -0.32512 0.175006)
			(stroke
				(width 0.1)
				(type default)
			)
			(layer "F.Fab")
		)
		(pad "1" smd rect
			(at -0.2667 0)
			(size 0.3048 0.381)
			(layers "F.Cu" "F.Mask" "F.Paste")
			(net "JTAG_TRST_RT_CPU1_P2_N")
		)
		(pad "2" smd rect
			(at 0.2667 0 180)
			(size 0.3048 0.381)
			(layers "F.Cu" "F.Mask" "F.Paste")
			(net "GND")
		)
	)
	(footprint ""
		(layer "F.Cu")
		(at 100.48367 -409.199588 180)
		(property "Reference" "C28"
			(at 0 0 180)
			(layer "F.SilkS")
			(hide yes)
			(effects
				(font
					(size 1.27 1.27)
				)
			)
		)
		(property "Value" ""
			(at 0 0 180)
			(layer "F.Fab")
			(effects
				(font
					(size 1.27 1.27)
				)
			)
		)
		(duplicate_pad_numbers_are_jumpers no)
		(fp_line
			(start 0.7874 0.4064)
			(end -0.7874 0.4064)
			(stroke
				(width 0.1524)
				(type default)
			)
			(layer "F.SilkS")
		)
		(fp_line
			(start 0.7874 -0.4064)
			(end 0.7874 0.4064)
			(stroke
				(width 0.1524)
				(type default)
			)
			(layer "F.SilkS")
		)
		(fp_line
			(start -0.7874 0.4064)
			(end -0.7874 -0.4064)
			(stroke
				(width 0.1524)
				(type default)
			)
			(layer "F.SilkS")
		)
		(fp_line
			(start -0.7874 -0.4064)
			(end 0.7874 -0.4064)
			(stroke
				(width 0.1524)
				(type default)
			)
			(layer "F.SilkS")
		)
		(fp_line
			(start 0.67945 0.3048)
			(end 0.120396 0.3048)
			(stroke
				(width 0.1)
				(type default)
			)
			(layer "F.Fab")
		)
		(fp_line
			(start 0.67945 -0.3048)
			(end 0.67945 0.3048)
			(stroke
				(width 0.1)
				(type default)
			)
			(layer "F.Fab")
		)
		(fp_line
			(start 0.12065 -0.2794)
			(end 0.12065 -0.3048)
			(stroke
				(width 0.1)
				(type default)
			)
			(layer "F.Fab")
		)
		(fp_line
			(start 0.12065 -0.3048)
			(end 0.67945 -0.3048)
			(stroke
				(width 0.1)
				(type default)
			)
			(layer "F.Fab")
		)
		(fp_line
			(start 0.120396 0.3048)
			(end 0.120396 0.2794)
			(stroke
				(width 0.1)
				(type default)
			)
			(layer "F.Fab")
		)
		(fp_line
			(start 0.120396 0.2794)
			(end -0.12065 0.2794)
			(stroke
				(width 0.1)
				(type default)
			)
			(layer "F.Fab")
		)
		(fp_line
			(start -0.12065 0.3048)
			(end -0.67945 0.3048)
			(stroke
				(width 0.1)
				(type default)
			)
			(layer "F.Fab")
		)
		(fp_line
			(start -0.12065 0.2794)
			(end -0.12065 0.3048)
			(stroke
				(width 0.1)
				(type default)
			)
			(layer "F.Fab")
		)
		(fp_line
			(start -0.12065 -0.2794)
			(end 0.12065 -0.2794)
			(stroke
				(width 0.1)
				(type default)
			)
			(layer "F.Fab")
		)
		(fp_line
			(start -0.12065 -0.305054)
			(end -0.12065 -0.2794)
			(stroke
				(width 0.1)
				(type default)
			)
			(layer "F.Fab")
		)
		(fp_line
			(start -0.67945 0.3048)
			(end -0.67945 -0.305054)
			(stroke
				(width 0.1)
				(type default)
			)
			(layer "F.Fab")
		)
		(fp_line
			(start -0.67945 -0.305054)
			(end -0.12065 -0.305054)
			(stroke
				(width 0.1)
				(type default)
			)
			(layer "F.Fab")
		)
		(pad "1" smd circle
			(at -0.40005 0 180)
			(size 0 0)
			(layers "F.Cu" "F.Mask" "F.Paste")
			(net "P3V3_9ZXL045_P1_VDD")
		)
		(pad "2" smd circle
			(at 0.40005 0 180)
			(size 0 0)
			(layers "F.Cu" "F.Mask" "F.Paste")
			(net "GND")
		)
	)
	(footprint ""
		(layer "F.Cu")
		(at 316.23 -362.839 90)
		(property "Reference" "PC74"
			(at 0 0 90)
			(layer "F.SilkS")
			(hide yes)
			(effects
				(font
					(size 1.27 1.27)
				)
			)
		)
		(property "Value" ""
			(at 0 0 90)
			(layer "F.Fab")
			(effects
				(font
					(size 1.27 1.27)
				)
			)
		)
		(duplicate_pad_numbers_are_jumpers no)
		(fp_line
			(start 0.7874 -0.4064)
			(end 0.7874 0.4064)
			(stroke
				(width 0.1524)
				(type default)
			)
			(layer "F.SilkS")
		)
		(fp_line
			(start -0.7874 -0.4064)
			(end 0.7874 -0.4064)
			(stroke
				(width 0.1524)
				(type default)
			)
			(layer "F.SilkS")
		)
		(fp_line
			(start 0.7874 0.4064)
			(end -0.7874 0.4064)
			(stroke
				(width 0.1524)
				(type default)
			)
			(layer "F.SilkS")
		)
		(fp_line
			(start -0.7874 0.4064)
			(end -0.7874 -0.4064)
			(stroke
				(width 0.1524)
				(type default)
			)
			(layer "F.SilkS")
		)
		(fp_line
			(start -0.12065 -0.305054)
			(end -0.12065 -0.2794)
			(stroke
				(width 0.1)
				(type default)
			)
			(layer "F.Fab")
		)
		(fp_line
			(start -0.67945 -0.305054)
			(end -0.12065 -0.305054)
			(stroke
				(width 0.1)
				(type default)
			)
			(layer "F.Fab")
		)
		(fp_line
			(start 0.67945 -0.3048)
			(end 0.67945 0.3048)
			(stroke
				(width 0.1)
				(type default)
			)
			(layer "F.Fab")
		)
		(fp_line
			(start 0.12065 -0.3048)
			(end 0.67945 -0.3048)
			(stroke
				(width 0.1)
				(type default)
			)
			(layer "F.Fab")
		)
		(fp_line
			(start 0.12065 -0.2794)
			(end 0.12065 -0.3048)
			(stroke
				(width 0.1)
				(type default)
			)
			(layer "F.Fab")
		)
		(fp_line
			(start -0.12065 -0.2794)
			(end 0.12065 -0.2794)
			(stroke
				(width 0.1)
				(type default)
			)
			(layer "F.Fab")
		)
		(fp_line
			(start 0.120396 0.2794)
			(end -0.12065 0.2794)
			(stroke
				(width 0.1)
				(type default)
			)
			(layer "F.Fab")
		)
		(fp_line
			(start -0.12065 0.2794)
			(end -0.12065 0.3048)
			(stroke
				(width 0.1)
				(type default)
			)
			(layer "F.Fab")
		)
		(fp_line
			(start 0.67945 0.3048)
			(end 0.120396 0.3048)
			(stroke
				(width 0.1)
				(type default)
			)
			(layer "F.Fab")
		)
		(fp_line
			(start 0.120396 0.3048)
			(end 0.120396 0.2794)
			(stroke
				(width 0.1)
				(type default)
			)
			(layer "F.Fab")
		)
		(fp_line
			(start -0.12065 0.3048)
			(end -0.67945 0.3048)
			(stroke
				(width 0.1)
				(type default)
			)
			(layer "F.Fab")
		)
		(fp_line
			(start -0.67945 0.3048)
			(end -0.67945 -0.305054)
			(stroke
				(width 0.1)
				(type default)
			)
			(layer "F.Fab")
		)
		(pad "1" smd circle
			(at -0.40005 0 90)
			(size 0 0)
			(layers "F.Cu" "F.Mask" "F.Paste")
			(net "PVDDCR_CPU1_P0_VINSEN")
		)
		(pad "2" smd circle
			(at 0.40005 0 90)
			(size 0 0)
			(layers "F.Cu" "F.Mask" "F.Paste")
			(net "GND")
		)
	)
	(footprint ""
		(layer "F.Cu")
		(at 415.119058 -357.61676 90)
		(property "Reference" "PR121"
			(at 0 0 90)
			(layer "F.SilkS")
			(hide yes)
			(effects
				(font
					(size 1.27 1.27)
				)
			)
		)
		(property "Value" ""
			(at 0 0 90)
			(layer "F.Fab")
			(effects
				(font
					(size 1.27 1.27)
				)
			)
		)
		(duplicate_pad_numbers_are_jumpers no)
		(fp_line
			(start 0.7874 -0.4064)
			(end 0.7874 0.4064)
			(stroke
				(width 0.1524)
				(type default)
			)
			(layer "F.SilkS")
		)
		(fp_line
			(start -0.7874 -0.4064)
			(end 0.7874 -0.4064)
			(stroke
				(width 0.1524)
				(type default)
			)
			(layer "F.SilkS")
		)
		(fp_line
			(start 0.7874 0.4064)
			(end -0.7874 0.4064)
			(stroke
				(width 0.1524)
				(type default)
			)
			(layer "F.SilkS")
		)
		(fp_line
			(start -0.7874 0.4064)
			(end -0.7874 -0.4064)
			(stroke
				(width 0.1524)
				(type default)
			)
			(layer "F.SilkS")
		)
		(fp_line
			(start -0.12065 -0.305054)
			(end -0.12065 -0.2794)
			(stroke
				(width 0.1)
				(type default)
			)
			(layer "F.Fab")
		)
		(fp_line
			(start -0.67945 -0.305054)
			(end -0.12065 -0.305054)
			(stroke
				(width 0.1)
				(type default)
			)
			(layer "F.Fab")
		)
		(fp_line
			(start 0.67945 -0.3048)
			(end 0.67945 0.3048)
			(stroke
				(width 0.1)
				(type default)
			)
			(layer "F.Fab")
		)
		(fp_line
			(start 0.12065 -0.3048)
			(end 0.67945 -0.3048)
			(stroke
				(width 0.1)
				(type default)
			)
			(layer "F.Fab")
		)
		(fp_line
			(start 0.12065 -0.2794)
			(end 0.12065 -0.3048)
			(stroke
				(width 0.1)
				(type default)
			)
			(layer "F.Fab")
		)
		(fp_line
			(start -0.12065 -0.2794)
			(end 0.12065 -0.2794)
			(stroke
				(width 0.1)
				(type default)
			)
			(layer "F.Fab")
		)
		(fp_line
			(start 0.120396 0.2794)
			(end -0.12065 0.2794)
			(stroke
				(width 0.1)
				(type default)
			)
			(layer "F.Fab")
		)
		(fp_line
			(start -0.12065 0.2794)
			(end -0.12065 0.3048)
			(stroke
				(width 0.1)
				(type default)
			)
			(layer "F.Fab")
		)
		(fp_line
			(start 0.67945 0.3048)
			(end 0.120396 0.3048)
			(stroke
				(width 0.1)
				(type default)
			)
			(layer "F.Fab")
		)
		(fp_line
			(start 0.120396 0.3048)
			(end 0.120396 0.2794)
			(stroke
				(width 0.1)
				(type default)
			)
			(layer "F.Fab")
		)
		(fp_line
			(start -0.12065 0.3048)
			(end -0.67945 0.3048)
			(stroke
				(width 0.1)
				(type default)
			)
			(layer "F.Fab")
		)
		(fp_line
			(start -0.67945 0.3048)
			(end -0.67945 -0.305054)
			(stroke
				(width 0.1)
				(type default)
			)
			(layer "F.Fab")
		)
		(pad "1" smd circle
			(at -0.40005 0 90)
			(size 0 0)
			(layers "F.Cu" "F.Mask" "F.Paste")
			(net "VSENSE_PVDD11_S3_P0_DP")
		)
		(pad "2" smd circle
			(at 0.40005 0 90)
			(size 0 0)
			(layers "F.Cu" "F.Mask" "F.Paste")
			(net "VSENSE_PVDD11_S3_P0_R")
		)
	)
	(footprint ""
		(layer "F.Cu")
		(at 296.670984 -343.712038 180)
		(property "Reference" "PC158"
			(at 0 0 180)
			(layer "F.SilkS")
			(hide yes)
			(effects
				(font
					(size 1.27 1.27)
				)
			)
		)
		(property "Value" ""
			(at 0 0 180)
			(layer "F.Fab")
			(effects
				(font
					(size 1.27 1.27)
				)
			)
		)
		(duplicate_pad_numbers_are_jumpers no)
		(fp_line
			(start 0.7874 0.4064)
			(end -0.7874 0.4064)
			(stroke
				(width 0.1524)
				(type default)
			)
			(layer "F.SilkS")
		)
		(fp_line
			(start 0.7874 -0.4064)
			(end 0.7874 0.4064)
			(stroke
				(width 0.1524)
				(type default)
			)
			(layer "F.SilkS")
		)
		(fp_line
			(start -0.7874 0.4064)
			(end -0.7874 -0.4064)
			(stroke
				(width 0.1524)
				(type default)
			)
			(layer "F.SilkS")
		)
		(fp_line
			(start -0.7874 -0.4064)
			(end 0.7874 -0.4064)
			(stroke
				(width 0.1524)
				(type default)
			)
			(layer "F.SilkS")
		)
		(fp_line
			(start 0.67945 0.3048)
			(end 0.120396 0.3048)
			(stroke
				(width 0.1)
				(type default)
			)
			(layer "F.Fab")
		)
		(fp_line
			(start 0.67945 -0.3048)
			(end 0.67945 0.3048)
			(stroke
				(width 0.1)
				(type default)
			)
			(layer "F.Fab")
		)
		(fp_line
			(start 0.12065 -0.2794)
			(end 0.12065 -0.3048)
			(stroke
				(width 0.1)
				(type default)
			)
			(layer "F.Fab")
		)
		(fp_line
			(start 0.12065 -0.3048)
			(end 0.67945 -0.3048)
			(stroke
				(width 0.1)
				(type default)
			)
			(layer "F.Fab")
		)
		(fp_line
			(start 0.120396 0.3048)
			(end 0.120396 0.2794)
			(stroke
				(width 0.1)
				(type default)
			)
			(layer "F.Fab")
		)
		(fp_line
			(start 0.120396 0.2794)
			(end -0.12065 0.2794)
			(stroke
				(width 0.1)
				(type default)
			)
			(layer "F.Fab")
		)
		(fp_line
			(start -0.12065 0.3048)
			(end -0.67945 0.3048)
			(stroke
				(width 0.1)
				(type default)
			)
			(layer "F.Fab")
		)
		(fp_line
			(start -0.12065 0.2794)
			(end -0.12065 0.3048)
			(stroke
				(width 0.1)
				(type default)
			)
			(layer "F.Fab")
		)
		(fp_line
			(start -0.12065 -0.2794)
			(end 0.12065 -0.2794)
			(stroke
				(width 0.1)
				(type default)
			)
			(layer "F.Fab")
		)
		(fp_line
			(start -0.12065 -0.305054)
			(end -0.12065 -0.2794)
			(stroke
				(width 0.1)
				(type default)
			)
			(layer "F.Fab")
		)
		(fp_line
			(start -0.67945 0.3048)
			(end -0.67945 -0.305054)
			(stroke
				(width 0.1)
				(type default)
			)
			(layer "F.Fab")
		)
		(fp_line
			(start -0.67945 -0.305054)
			(end -0.12065 -0.305054)
			(stroke
				(width 0.1)
				(type default)
			)
			(layer "F.Fab")
		)
		(pad "1" smd circle
			(at -0.40005 0 180)
			(size 0 0)
			(layers "F.Cu" "F.Mask" "F.Paste")
			(net "SW_PVDDIO_P0_SW1")
		)
		(pad "2" smd circle
			(at 0.40005 0 180)
			(size 0 0)
			(layers "F.Cu" "F.Mask" "F.Paste")
			(net "SW_PVDDIO_P0_SW1_RC")
		)
	)
	(footprint ""
		(layer "F.Cu")
		(at 138.426952 -58.532014)
		(property "Reference" "R1742"
			(at 0 0 0)
			(layer "F.SilkS")
			(hide yes)
			(effects
				(font
					(size 1.27 1.27)
				)
			)
		)
		(property "Value" ""
			(at 0 0 0)
			(layer "F.Fab")
			(effects
				(font
					(size 1.27 1.27)
				)
			)
		)
		(duplicate_pad_numbers_are_jumpers no)
		(fp_line
			(start -0.7874 -0.4064)
			(end 0.7874 -0.4064)
			(stroke
				(width 0.1524)
				(type default)
			)
			(layer "F.SilkS")
		)
		(fp_line
			(start -0.7874 0.4064)
			(end -0.7874 -0.4064)
			(stroke
				(width 0.1524)
				(type default)
			)
			(layer "F.SilkS")
		)
		(fp_line
			(start 0.7874 -0.4064)
			(end 0.7874 0.4064)
			(stroke
				(width 0.1524)
				(type default)
			)
			(layer "F.SilkS")
		)
		(fp_line
			(start 0.7874 0.4064)
			(end -0.7874 0.4064)
			(stroke
				(width 0.1524)
				(type default)
			)
			(layer "F.SilkS")
		)
		(fp_line
			(start -0.67945 -0.305054)
			(end -0.12065 -0.305054)
			(stroke
				(width 0.1)
				(type default)
			)
			(layer "F.Fab")
		)
		(fp_line
			(start -0.67945 0.3048)
			(end -0.67945 -0.305054)
			(stroke
				(width 0.1)
				(type default)
			)
			(layer "F.Fab")
		)
		(fp_line
			(start -0.12065 -0.305054)
			(end -0.12065 -0.2794)
			(stroke
				(width 0.1)
				(type default)
			)
			(layer "F.Fab")
		)
		(fp_line
			(start -0.12065 -0.2794)
			(end 0.12065 -0.2794)
			(stroke
				(width 0.1)
				(type default)
			)
			(layer "F.Fab")
		)
		(fp_line
			(start -0.12065 0.2794)
			(end -0.12065 0.3048)
			(stroke
				(width 0.1)
				(type default)
			)
			(layer "F.Fab")
		)
		(fp_line
			(start -0.12065 0.3048)
			(end -0.67945 0.3048)
			(stroke
				(width 0.1)
				(type default)
			)
			(layer "F.Fab")
		)
		(fp_line
			(start 0.120396 0.2794)
			(end -0.12065 0.2794)
			(stroke
				(width 0.1)
				(type default)
			)
			(layer "F.Fab")
		)
		(fp_line
			(start 0.120396 0.3048)
			(end 0.120396 0.2794)
			(stroke
				(width 0.1)
				(type default)
			)
			(layer "F.Fab")
		)
		(fp_line
			(start 0.12065 -0.3048)
			(end 0.67945 -0.3048)
			(stroke
				(width 0.1)
				(type default)
			)
			(layer "F.Fab")
		)
		(fp_line
			(start 0.12065 -0.2794)
			(end 0.12065 -0.3048)
			(stroke
				(width 0.1)
				(type default)
			)
			(layer "F.Fab")
		)
		(fp_line
			(start 0.67945 -0.3048)
			(end 0.67945 0.3048)
			(stroke
				(width 0.1)
				(type default)
			)
			(layer "F.Fab")
		)
		(fp_line
			(start 0.67945 0.3048)
			(end 0.120396 0.3048)
			(stroke
				(width 0.1)
				(type default)
			)
			(layer "F.Fab")
		)
		(pad "1" smd circle
			(at -0.40005 0)
			(size 0 0)
			(layers "F.Cu" "F.Mask" "F.Paste")
			(net "JTAG_SCM_PLD_R_TDI")
		)
		(pad "2" smd circle
			(at 0.40005 0)
			(size 0 0)
			(layers "F.Cu" "F.Mask" "F.Paste")
			(net "JTAG_SCM_PLD_TDI")
		)
	)
	(footprint ""
		(layer "F.Cu")
		(at 171.664122 -26.84399 90)
		(property "Reference" "PR4009"
			(at 0 0 90)
			(layer "F.SilkS")
			(hide yes)
			(effects
				(font
					(size 1.27 1.27)
				)
			)
		)
		(property "Value" ""
			(at 0 0 90)
			(layer "F.Fab")
			(effects
				(font
					(size 1.27 1.27)
				)
			)
		)
		(duplicate_pad_numbers_are_jumpers no)
		(fp_line
			(start 0.7874 -0.4064)
			(end 0.7874 0.4064)
			(stroke
				(width 0.1524)
				(type default)
			)
			(layer "F.SilkS")
		)
		(fp_line
			(start -0.7874 -0.4064)
			(end 0.7874 -0.4064)
			(stroke
				(width 0.1524)
				(type default)
			)
			(layer "F.SilkS")
		)
		(fp_line
			(start 0.7874 0.4064)
			(end -0.7874 0.4064)
			(stroke
				(width 0.1524)
				(type default)
			)
			(layer "F.SilkS")
		)
		(fp_line
			(start -0.7874 0.4064)
			(end -0.7874 -0.4064)
			(stroke
				(width 0.1524)
				(type default)
			)
			(layer "F.SilkS")
		)
		(fp_line
			(start -0.12065 -0.305054)
			(end -0.12065 -0.2794)
			(stroke
				(width 0.1)
				(type default)
			)
			(layer "F.Fab")
		)
		(fp_line
			(start -0.67945 -0.305054)
			(end -0.12065 -0.305054)
			(stroke
				(width 0.1)
				(type default)
			)
			(layer "F.Fab")
		)
		(fp_line
			(start 0.67945 -0.3048)
			(end 0.67945 0.3048)
			(stroke
				(width 0.1)
				(type default)
			)
			(layer "F.Fab")
		)
		(fp_line
			(start 0.12065 -0.3048)
			(end 0.67945 -0.3048)
			(stroke
				(width 0.1)
				(type default)
			)
			(layer "F.Fab")
		)
		(fp_line
			(start 0.12065 -0.2794)
			(end 0.12065 -0.3048)
			(stroke
				(width 0.1)
				(type default)
			)
			(layer "F.Fab")
		)
		(fp_line
			(start -0.12065 -0.2794)
			(end 0.12065 -0.2794)
			(stroke
				(width 0.1)
				(type default)
			)
			(layer "F.Fab")
		)
		(fp_line
			(start 0.120396 0.2794)
			(end -0.12065 0.2794)
			(stroke
				(width 0.1)
				(type default)
			)
			(layer "F.Fab")
		)
		(fp_line
			(start -0.12065 0.2794)
			(end -0.12065 0.3048)
			(stroke
				(width 0.1)
				(type default)
			)
			(layer "F.Fab")
		)
		(fp_line
			(start 0.67945 0.3048)
			(end 0.120396 0.3048)
			(stroke
				(width 0.1)
				(type default)
			)
			(layer "F.Fab")
		)
		(fp_line
			(start 0.120396 0.3048)
			(end 0.120396 0.2794)
			(stroke
				(width 0.1)
				(type default)
			)
			(layer "F.Fab")
		)
		(fp_line
			(start -0.12065 0.3048)
			(end -0.67945 0.3048)
			(stroke
				(width 0.1)
				(type default)
			)
			(layer "F.Fab")
		)
		(fp_line
			(start -0.67945 0.3048)
			(end -0.67945 -0.305054)
			(stroke
				(width 0.1)
				(type default)
			)
			(layer "F.Fab")
		)
		(pad "1" smd circle
			(at -0.40005 0 90)
			(size 0 0)
			(layers "F.Cu" "F.Mask" "F.Paste")
			(net "P12V_SCM_R")
		)
		(pad "2" smd circle
			(at 0.40005 0 90)
			(size 0 0)
			(layers "F.Cu" "F.Mask" "F.Paste")
			(net "P12V_SCM_OV_FB")
		)
	)
	(footprint ""
		(layer "F.Cu")
		(at 117.243352 -357.19766)
		(property "Reference" "ME17"
			(at 0 0 0)
			(layer "F.SilkS")
			(hide yes)
			(effects
				(font
					(size 1.27 1.27)
				)
			)
		)
		(property "Value" ""
			(at 0 0 0)
			(layer "F.Fab")
			(effects
				(font
					(size 1.27 1.27)
				)
			)
		)
		(duplicate_pad_numbers_are_jumpers no)
		(fp_line
			(start 0 -10.500106)
			(end 1.524 -10.500106)
			(stroke
				(width 0.1524)
				(type default)
			)
			(layer "F.SilkS")
		)
		(fp_line
			(start 0 -8.976106)
			(end 0 -10.500106)
			(stroke
				(width 0.1524)
				(type default)
			)
			(layer "F.SilkS")
		)
		(fp_line
			(start 0 0)
			(end 0 -1.524)
			(stroke
				(width 0.1524)
				(type default)
			)
			(layer "F.SilkS")
		)
		(fp_line
			(start 1.524 0)
			(end 0 0)
			(stroke
				(width 0.1524)
				(type default)
			)
			(layer "F.SilkS")
		)
		(fp_line
			(start 8.976106 0)
			(end 10.500106 0)
			(stroke
				(width 0.1524)
				(type default)
			)
			(layer "F.SilkS")
		)
		(fp_line
			(start 10.500106 -10.500106)
			(end 8.976106 -10.500106)
			(stroke
				(width 0.1524)
				(type default)
			)
			(layer "F.SilkS")
		)
		(fp_line
			(start 10.500106 -8.976106)
			(end 10.500106 -10.500106)
			(stroke
				(width 0.1524)
				(type default)
			)
			(layer "F.SilkS")
		)
		(fp_line
			(start 10.500106 0)
			(end 10.500106 -1.524)
			(stroke
				(width 0.1524)
				(type default)
			)
			(layer "F.SilkS")
		)
		(fp_text user "BIOS"
			(at 1.681226 -8.494776 0)
			(unlocked yes)
			(layer "F.SilkS")
			(effects
				(font
					(size 1.905 1.4224)
					(thickness 0.1524)
				)
				(justify left)
			)
		)
		(fp_text user "BMC"
			(at 2.303526 -1.865376 0)
			(unlocked yes)
			(layer "F.SilkS")
			(effects
				(font
					(size 1.905 1.4224)
					(thickness 0.1524)
				)
				(justify left)
			)
		)
		(fp_text user "&"
			(at 4.183126 -5.624576 0)
			(unlocked yes)
			(layer "F.SilkS")
			(effects
				(font
					(size 1.905 1.4224)
					(thickness 0.1524)
				)
				(justify left)
			)
		)
		(zone
			(layer "F.Cu")
			(hatch none 0.5)
			(connect_pads
				(clearance 0)
			)
			(min_thickness 0.25)
			(keepout
				(tracks not_allowed)
				(vias allowed)
				(pads allowed)
				(copperpour not_allowed)
				(footprints allowed)
			)
			(placement
				(enabled no)
				(sheetname "")
			)
			(fill
				(thermal_gap 0.5)
				(thermal_bridge_width 0.5)
				(island_removal_mode 0)
			)
			(polygon
				(pts
					(xy 117.243352 -357.19766) (xy 127.743458 -357.19766) (xy 127.743458 -367.697766) (xy 117.243352 -367.697766)
				)
			)
		)
	)
	(footprint ""
		(layer "F.Cu")
		(at 39.95039 -425.256706 180)
		(property "Reference" "C6008"
			(at 0 0 180)
			(layer "F.SilkS")
			(hide yes)
			(effects
				(font
					(size 1.27 1.27)
				)
			)
		)
		(property "Value" ""
			(at 0 0 180)
			(layer "F.Fab")
			(effects
				(font
					(size 1.27 1.27)
				)
			)
		)
		(duplicate_pad_numbers_are_jumpers no)
		(fp_line
			(start 0.7874 -0.4064)
			(end 0.7874 0.294894)
			(stroke
				(width 0.1524)
				(type default)
			)
			(layer "F.SilkS")
		)
		(fp_line
			(start -0.35941 0.4064)
			(end -0.7874 0.4064)
			(stroke
				(width 0.1524)
				(type default)
			)
			(layer "F.SilkS")
		)
		(fp_line
			(start -0.7874 -0.4064)
			(end 0.7874 -0.4064)
			(stroke
				(width 0.1524)
				(type default)
			)
			(layer "F.SilkS")
		)
		(fp_line
			(start 0.6858 0.3048)
			(end 0.1016 0.3048)
			(stroke
				(width 0.1)
				(type default)
			)
			(layer "F.Fab")
		)
		(fp_line
			(start 0.6858 -0.3048)
			(end 0.6858 0.3048)
			(stroke
				(width 0.1)
				(type default)
			)
			(layer "F.Fab")
		)
		(fp_line
			(start 0.1016 0.3048)
			(end 0.1016 0.2794)
			(stroke
				(width 0.1)
				(type default)
			)
			(layer "F.Fab")
		)
		(fp_line
			(start 0.1016 0.2794)
			(end -0.1016 0.2794)
			(stroke
				(width 0.1)
				(type default)
			)
			(layer "F.Fab")
		)
		(fp_line
			(start 0.1016 -0.2794)
			(end 0.1016 -0.3048)
			(stroke
				(width 0.1)
				(type default)
			)
			(layer "F.Fab")
		)
		(fp_line
			(start 0.1016 -0.3048)
			(end 0.6858 -0.3048)
			(stroke
				(width 0.1)
				(type default)
			)
			(layer "F.Fab")
		)
		(fp_line
			(start -0.1016 0.3048)
			(end -0.6858 0.3048)
			(stroke
				(width 0.1)
				(type default)
			)
			(layer "F.Fab")
		)
		(fp_line
			(start -0.1016 0.2794)
			(end -0.1016 0.3048)
			(stroke
				(width 0.1)
				(type default)
			)
			(layer "F.Fab")
		)
		(fp_line
			(start -0.1016 -0.2794)
			(end 0.1016 -0.2794)
			(stroke
				(width 0.1)
				(type default)
			)
			(layer "F.Fab")
		)
		(fp_line
			(start -0.1016 -0.3048)
			(end -0.1016 -0.2794)
			(stroke
				(width 0.1)
				(type default)
			)
			(layer "F.Fab")
		)
		(fp_line
			(start -0.6858 0.3048)
			(end -0.6858 -0.3048)
			(stroke
				(width 0.1)
				(type default)
			)
			(layer "F.Fab")
		)
		(fp_line
			(start -0.6858 -0.3048)
			(end -0.1016 -0.3048)
			(stroke
				(width 0.1)
				(type default)
			)
			(layer "F.Fab")
		)
		(pad "1" smd rect
			(at -0.40005 0)
			(size 0.4572 0.508)
			(layers "F.Cu" "F.Mask" "F.Paste")
			(net "P2E_MB_BMC_RX_BUF2_C_DN<0>")
		)
		(pad "2" smd rect
			(at 0.40005 0)
			(size 0.4572 0.508)
			(layers "F.Cu" "F.Mask" "F.Paste")
			(net "P2E_MB_BMC_RX_BUF_DN<0>")
		)
	)
	(footprint ""
		(layer "F.Cu")
		(at 263.017 -141.986 -90)
		(property "Reference" "R8007"
			(at 0 0 270)
			(layer "F.SilkS")
			(hide yes)
			(effects
				(font
					(size 1.27 1.27)
				)
			)
		)
		(property "Value" ""
			(at 0 0 270)
			(layer "F.Fab")
			(effects
				(font
					(size 1.27 1.27)
				)
			)
		)
		(duplicate_pad_numbers_are_jumpers no)
		(fp_line
			(start -0.7874 0.4064)
			(end -0.7874 -0.4064)
			(stroke
				(width 0.1524)
				(type default)
			)
			(layer "F.SilkS")
		)
		(fp_line
			(start 0.7874 0.4064)
			(end -0.7874 0.4064)
			(stroke
				(width 0.1524)
				(type default)
			)
			(layer "F.SilkS")
		)
		(fp_line
			(start -0.7874 -0.4064)
			(end 0.7874 -0.4064)
			(stroke
				(width 0.1524)
				(type default)
			)
			(layer "F.SilkS")
		)
		(fp_line
			(start 0.7874 -0.4064)
			(end 0.7874 0.4064)
			(stroke
				(width 0.1524)
				(type default)
			)
			(layer "F.SilkS")
		)
		(fp_line
			(start -0.67945 0.3048)
			(end -0.67945 -0.305054)
			(stroke
				(width 0.1)
				(type default)
			)
			(layer "F.Fab")
		)
		(fp_line
			(start -0.12065 0.3048)
			(end -0.67945 0.3048)
			(stroke
				(width 0.1)
				(type default)
			)
			(layer "F.Fab")
		)
		(fp_line
			(start 0.120396 0.3048)
			(end 0.120396 0.2794)
			(stroke
				(width 0.1)
				(type default)
			)
			(layer "F.Fab")
		)
		(fp_line
			(start 0.67945 0.3048)
			(end 0.120396 0.3048)
			(stroke
				(width 0.1)
				(type default)
			)
			(layer "F.Fab")
		)
		(fp_line
			(start -0.12065 0.2794)
			(end -0.12065 0.3048)
			(stroke
				(width 0.1)
				(type default)
			)
			(layer "F.Fab")
		)
		(fp_line
			(start 0.120396 0.2794)
			(end -0.12065 0.2794)
			(stroke
				(width 0.1)
				(type default)
			)
			(layer "F.Fab")
		)
		(fp_line
			(start -0.12065 -0.2794)
			(end 0.12065 -0.2794)
			(stroke
				(width 0.1)
				(type default)
			)
			(layer "F.Fab")
		)
		(fp_line
			(start 0.12065 -0.2794)
			(end 0.12065 -0.3048)
			(stroke
				(width 0.1)
				(type default)
			)
			(layer "F.Fab")
		)
		(fp_line
			(start 0.12065 -0.3048)
			(end 0.67945 -0.3048)
			(stroke
				(width 0.1)
				(type default)
			)
			(layer "F.Fab")
		)
		(fp_line
			(start 0.67945 -0.3048)
			(end 0.67945 0.3048)
			(stroke
				(width 0.1)
				(type default)
			)
			(layer "F.Fab")
		)
		(fp_line
			(start -0.67945 -0.305054)
			(end -0.12065 -0.305054)
			(stroke
				(width 0.1)
				(type default)
			)
			(layer "F.Fab")
		)
		(fp_line
			(start -0.12065 -0.305054)
			(end -0.12065 -0.2794)
			(stroke
				(width 0.1)
				(type default)
			)
			(layer "F.Fab")
		)
		(pad "1" smd circle
			(at -0.40005 0 270)
			(size 0 0)
			(layers "F.Cu" "F.Mask" "F.Paste")
			(net "SPI_CPU0_D0")
		)
		(pad "2" smd circle
			(at 0.40005 0 270)
			(size 0 0)
			(layers "F.Cu" "F.Mask" "F.Paste")
			(net "SPI_CPU0_R1_D0")
		)
	)
	(footprint ""
		(layer "F.Cu")
		(at 114.868706 -408.517344 -90)
		(property "Reference" "C6694"
			(at 0 0 270)
			(layer "F.SilkS")
			(hide yes)
			(effects
				(font
					(size 1.27 1.27)
				)
			)
		)
		(property "Value" ""
			(at 0 0 270)
			(layer "F.Fab")
			(effects
				(font
					(size 1.27 1.27)
				)
			)
		)
		(duplicate_pad_numbers_are_jumpers no)
		(fp_line
			(start -0.299974 0.150114)
			(end -0.299974 -0.150114)
			(stroke
				(width 0.1)
				(type default)
			)
			(layer "F.Fab")
		)
		(fp_line
			(start 0.299974 0.150114)
			(end -0.299974 0.150114)
			(stroke
				(width 0.1)
				(type default)
			)
			(layer "F.Fab")
		)
		(fp_line
			(start -0.299974 -0.150114)
			(end 0.299974 -0.150114)
			(stroke
				(width 0.1)
				(type default)
			)
			(layer "F.Fab")
		)
		(fp_line
			(start 0.299974 -0.150114)
			(end 0.299974 0.150114)
			(stroke
				(width 0.1)
				(type default)
			)
			(layer "F.Fab")
		)
		(pad "1" smd rect
			(at -0.2667 0 270)
			(size 0.3048 0.381)
			(layers "F.Cu" "F.Mask" "F.Paste")
			(net "P5E_CPU1_P2_TX_BUF_C_DN<0>")
		)
		(pad "2" smd rect
			(at 0.2667 0 270)
			(size 0.3048 0.381)
			(layers "F.Cu" "F.Mask" "F.Paste")
			(net "P5E_CPU1_P2_TX_BUF_DN<0>")
		)
	)
	(footprint ""
		(layer "F.Cu")
		(at 254.592836 -118.91645)
		(property "Reference" "R3725"
			(at 0 0 0)
			(layer "F.SilkS")
			(hide yes)
			(effects
				(font
					(size 1.27 1.27)
				)
			)
		)
		(property "Value" ""
			(at 0 0 0)
			(layer "F.Fab")
			(effects
				(font
					(size 1.27 1.27)
				)
			)
		)
		(duplicate_pad_numbers_are_jumpers no)
		(fp_line
			(start -0.7874 -0.4064)
			(end 0.7874 -0.4064)
			(stroke
				(width 0.1524)
				(type default)
			)
			(layer "F.SilkS")
		)
		(fp_line
			(start -0.7874 0.4064)
			(end -0.7874 -0.4064)
			(stroke
				(width 0.1524)
				(type default)
			)
			(layer "F.SilkS")
		)
		(fp_line
			(start 0.7874 -0.4064)
			(end 0.7874 0.4064)
			(stroke
				(width 0.1524)
				(type default)
			)
			(layer "F.SilkS")
		)
		(fp_line
			(start 0.7874 0.4064)
			(end -0.7874 0.4064)
			(stroke
				(width 0.1524)
				(type default)
			)
			(layer "F.SilkS")
		)
		(fp_line
			(start -0.67945 -0.305054)
			(end -0.12065 -0.305054)
			(stroke
				(width 0.1)
				(type default)
			)
			(layer "F.Fab")
		)
		(fp_line
			(start -0.67945 0.3048)
			(end -0.67945 -0.305054)
			(stroke
				(width 0.1)
				(type default)
			)
			(layer "F.Fab")
		)
		(fp_line
			(start -0.12065 -0.305054)
			(end -0.12065 -0.2794)
			(stroke
				(width 0.1)
				(type default)
			)
			(layer "F.Fab")
		)
		(fp_line
			(start -0.12065 -0.2794)
			(end 0.12065 -0.2794)
			(stroke
				(width 0.1)
				(type default)
			)
			(layer "F.Fab")
		)
		(fp_line
			(start -0.12065 0.2794)
			(end -0.12065 0.3048)
			(stroke
				(width 0.1)
				(type default)
			)
			(layer "F.Fab")
		)
		(fp_line
			(start -0.12065 0.3048)
			(end -0.67945 0.3048)
			(stroke
				(width 0.1)
				(type default)
			)
			(layer "F.Fab")
		)
		(fp_line
			(start 0.120396 0.2794)
			(end -0.12065 0.2794)
			(stroke
				(width 0.1)
				(type default)
			)
			(layer "F.Fab")
		)
		(fp_line
			(start 0.120396 0.3048)
			(end 0.120396 0.2794)
			(stroke
				(width 0.1)
				(type default)
			)
			(layer "F.Fab")
		)
		(fp_line
			(start 0.12065 -0.3048)
			(end 0.67945 -0.3048)
			(stroke
				(width 0.1)
				(type default)
			)
			(layer "F.Fab")
		)
		(fp_line
			(start 0.12065 -0.2794)
			(end 0.12065 -0.3048)
			(stroke
				(width 0.1)
				(type default)
			)
			(layer "F.Fab")
		)
		(fp_line
			(start 0.67945 -0.3048)
			(end 0.67945 0.3048)
			(stroke
				(width 0.1)
				(type default)
			)
			(layer "F.Fab")
		)
		(fp_line
			(start 0.67945 0.3048)
			(end 0.120396 0.3048)
			(stroke
				(width 0.1)
				(type default)
			)
			(layer "F.Fab")
		)
		(pad "1" smd circle
			(at -0.40005 0)
			(size 0 0)
			(layers "F.Cu" "F.Mask" "F.Paste")
			(net "P3V3_AUX")
		)
		(pad "2" smd circle
			(at 0.40005 0)
			(size 0 0)
			(layers "F.Cu" "F.Mask" "F.Paste")
			(net "SMB_LM75_0_3V3AUX_SCL")
		)
	)
	(footprint ""
		(layer "F.Cu")
		(at 412.23184 -381.41783 -90)
		(property "Reference" "C853"
			(at 0 0 270)
			(layer "F.SilkS")
			(hide yes)
			(effects
				(font
					(size 1.27 1.27)
				)
			)
		)
		(property "Value" ""
			(at 0 0 270)
			(layer "F.Fab")
			(effects
				(font
					(size 1.27 1.27)
				)
			)
		)
		(duplicate_pad_numbers_are_jumpers no)
		(fp_line
			(start -0.299974 0.150114)
			(end -0.299974 -0.150114)
			(stroke
				(width 0.1)
				(type default)
			)
			(layer "F.Fab")
		)
		(fp_line
			(start 0.299974 0.150114)
			(end -0.299974 0.150114)
			(stroke
				(width 0.1)
				(type default)
			)
			(layer "F.Fab")
		)
		(fp_line
			(start -0.299974 -0.150114)
			(end 0.299974 -0.150114)
			(stroke
				(width 0.1)
				(type default)
			)
			(layer "F.Fab")
		)
		(fp_line
			(start 0.299974 -0.150114)
			(end 0.299974 0.150114)
			(stroke
				(width 0.1)
				(type default)
			)
			(layer "F.Fab")
		)
		(pad "1" smd rect
			(at -0.2667 0 270)
			(size 0.3048 0.381)
			(layers "F.Cu" "F.Mask" "F.Paste")
			(net "P5E_CPU0_P2_TX_C_DP<8>")
		)
		(pad "2" smd rect
			(at 0.2667 0 270)
			(size 0.3048 0.381)
			(layers "F.Cu" "F.Mask" "F.Paste")
			(net "P5E_CPU0_P2_TX_DP<8>")
		)
	)
	(footprint ""
		(layer "F.Cu")
		(at 51.577494 -32.277558 90)
		(property "Reference" "C1841"
			(at 0 0 90)
			(layer "F.SilkS")
			(hide yes)
			(effects
				(font
					(size 1.27 1.27)
				)
			)
		)
		(property "Value" ""
			(at 0 0 90)
			(layer "F.Fab")
			(effects
				(font
					(size 1.27 1.27)
				)
			)
		)
		(duplicate_pad_numbers_are_jumpers no)
		(fp_line
			(start 0.7874 -0.4064)
			(end 0.7874 0.4064)
			(stroke
				(width 0.1524)
				(type default)
			)
			(layer "F.SilkS")
		)
		(fp_line
			(start -0.7874 -0.4064)
			(end 0.7874 -0.4064)
			(stroke
				(width 0.1524)
				(type default)
			)
			(layer "F.SilkS")
		)
		(fp_line
			(start 0.7874 0.4064)
			(end -0.7874 0.4064)
			(stroke
				(width 0.1524)
				(type default)
			)
			(layer "F.SilkS")
		)
		(fp_line
			(start -0.7874 0.4064)
			(end -0.7874 -0.4064)
			(stroke
				(width 0.1524)
				(type default)
			)
			(layer "F.SilkS")
		)
		(fp_line
			(start -0.12065 -0.305054)
			(end -0.12065 -0.2794)
			(stroke
				(width 0.1)
				(type default)
			)
			(layer "F.Fab")
		)
		(fp_line
			(start -0.67945 -0.305054)
			(end -0.12065 -0.305054)
			(stroke
				(width 0.1)
				(type default)
			)
			(layer "F.Fab")
		)
		(fp_line
			(start 0.67945 -0.3048)
			(end 0.67945 0.3048)
			(stroke
				(width 0.1)
				(type default)
			)
			(layer "F.Fab")
		)
		(fp_line
			(start 0.12065 -0.3048)
			(end 0.67945 -0.3048)
			(stroke
				(width 0.1)
				(type default)
			)
			(layer "F.Fab")
		)
		(fp_line
			(start 0.12065 -0.2794)
			(end 0.12065 -0.3048)
			(stroke
				(width 0.1)
				(type default)
			)
			(layer "F.Fab")
		)
		(fp_line
			(start -0.12065 -0.2794)
			(end 0.12065 -0.2794)
			(stroke
				(width 0.1)
				(type default)
			)
			(layer "F.Fab")
		)
		(fp_line
			(start 0.120396 0.2794)
			(end -0.12065 0.2794)
			(stroke
				(width 0.1)
				(type default)
			)
			(layer "F.Fab")
		)
		(fp_line
			(start -0.12065 0.2794)
			(end -0.12065 0.3048)
			(stroke
				(width 0.1)
				(type default)
			)
			(layer "F.Fab")
		)
		(fp_line
			(start 0.67945 0.3048)
			(end 0.120396 0.3048)
			(stroke
				(width 0.1)
				(type default)
			)
			(layer "F.Fab")
		)
		(fp_line
			(start 0.120396 0.3048)
			(end 0.120396 0.2794)
			(stroke
				(width 0.1)
				(type default)
			)
			(layer "F.Fab")
		)
		(fp_line
			(start -0.12065 0.3048)
			(end -0.67945 0.3048)
			(stroke
				(width 0.1)
				(type default)
			)
			(layer "F.Fab")
		)
		(fp_line
			(start -0.67945 0.3048)
			(end -0.67945 -0.305054)
			(stroke
				(width 0.1)
				(type default)
			)
			(layer "F.Fab")
		)
		(pad "1" smd circle
			(at -0.40005 0 90)
			(size 0 0)
			(layers "F.Cu" "F.Mask" "F.Paste")
			(net "P3V3_AUX")
		)
		(pad "2" smd circle
			(at 0.40005 0 90)
			(size 0 0)
			(layers "F.Cu" "F.Mask" "F.Paste")
			(net "GND")
		)
	)
	(footprint ""
		(layer "F.Cu")
		(at 77.537564 -17.680178 -90)
		(property "Reference" "PR3806"
			(at 0 0 270)
			(layer "F.SilkS")
			(hide yes)
			(effects
				(font
					(size 1.27 1.27)
				)
			)
		)
		(property "Value" ""
			(at 0 0 270)
			(layer "F.Fab")
			(effects
				(font
					(size 1.27 1.27)
				)
			)
		)
		(duplicate_pad_numbers_are_jumpers no)
		(fp_line
			(start -0.7874 0.4064)
			(end -0.7874 -0.4064)
			(stroke
				(width 0.1524)
				(type default)
			)
			(layer "F.SilkS")
		)
		(fp_line
			(start 0.7874 0.4064)
			(end -0.7874 0.4064)
			(stroke
				(width 0.1524)
				(type default)
			)
			(layer "F.SilkS")
		)
		(fp_line
			(start -0.7874 -0.4064)
			(end 0.7874 -0.4064)
			(stroke
				(width 0.1524)
				(type default)
			)
			(layer "F.SilkS")
		)
		(fp_line
			(start 0.7874 -0.4064)
			(end 0.7874 0.4064)
			(stroke
				(width 0.1524)
				(type default)
			)
			(layer "F.SilkS")
		)
		(fp_line
			(start -0.67945 0.3048)
			(end -0.67945 -0.305054)
			(stroke
				(width 0.1)
				(type default)
			)
			(layer "F.Fab")
		)
		(fp_line
			(start -0.12065 0.3048)
			(end -0.67945 0.3048)
			(stroke
				(width 0.1)
				(type default)
			)
			(layer "F.Fab")
		)
		(fp_line
			(start 0.120396 0.3048)
			(end 0.120396 0.2794)
			(stroke
				(width 0.1)
				(type default)
			)
			(layer "F.Fab")
		)
		(fp_line
			(start 0.67945 0.3048)
			(end 0.120396 0.3048)
			(stroke
				(width 0.1)
				(type default)
			)
			(layer "F.Fab")
		)
		(fp_line
			(start -0.12065 0.2794)
			(end -0.12065 0.3048)
			(stroke
				(width 0.1)
				(type default)
			)
			(layer "F.Fab")
		)
		(fp_line
			(start 0.120396 0.2794)
			(end -0.12065 0.2794)
			(stroke
				(width 0.1)
				(type default)
			)
			(layer "F.Fab")
		)
		(fp_line
			(start -0.12065 -0.2794)
			(end 0.12065 -0.2794)
			(stroke
				(width 0.1)
				(type default)
			)
			(layer "F.Fab")
		)
		(fp_line
			(start 0.12065 -0.2794)
			(end 0.12065 -0.3048)
			(stroke
				(width 0.1)
				(type default)
			)
			(layer "F.Fab")
		)
		(fp_line
			(start 0.12065 -0.3048)
			(end 0.67945 -0.3048)
			(stroke
				(width 0.1)
				(type default)
			)
			(layer "F.Fab")
		)
		(fp_line
			(start 0.67945 -0.3048)
			(end 0.67945 0.3048)
			(stroke
				(width 0.1)
				(type default)
			)
			(layer "F.Fab")
		)
		(fp_line
			(start -0.67945 -0.305054)
			(end -0.12065 -0.305054)
			(stroke
				(width 0.1)
				(type default)
			)
			(layer "F.Fab")
		)
		(fp_line
			(start -0.12065 -0.305054)
			(end -0.12065 -0.2794)
			(stroke
				(width 0.1)
				(type default)
			)
			(layer "F.Fab")
		)
		(pad "1" smd circle
			(at -0.40005 0 270)
			(size 0 0)
			(layers "F.Cu" "F.Mask" "F.Paste")
			(net "P12V_OCP_UV_2")
		)
		(pad "2" smd circle
			(at 0.40005 0 270)
			(size 0 0)
			(layers "F.Cu" "F.Mask" "F.Paste")
			(net "P12V_OCP_OV_2")
		)
	)
	(footprint ""
		(layer "F.Cu")
		(at 209.628232 -124.21997)
		(property "Reference" "U75"
			(at -2.433574 -2.925318 0)
			(unlocked yes)
			(layer "F.SilkS")
			(effects
				(font
					(size 0.7874 0.5842)
					(thickness 0.1524)
				)
				(justify left)
			)
		)
		(property "Value" ""
			(at 0 0 0)
			(layer "F.Fab")
			(effects
				(font
					(size 1.27 1.27)
				)
			)
		)
		(duplicate_pad_numbers_are_jumpers no)
		(fp_line
			(start -1.695958 -1.124966)
			(end 1.695958 -1.124966)
			(stroke
				(width 0.1524)
				(type default)
			)
			(layer "F.SilkS")
		)
		(fp_line
			(start -1.695958 1.124966)
			(end -1.695958 -1.124966)
			(stroke
				(width 0.1524)
				(type default)
			)
			(layer "F.SilkS")
		)
		(fp_line
			(start 1.695958 -1.124966)
			(end 1.695958 1.124966)
			(stroke
				(width 0.1524)
				(type default)
			)
			(layer "F.SilkS")
		)
		(fp_line
			(start 1.695958 1.124966)
			(end -1.695958 1.124966)
			(stroke
				(width 0.1524)
				(type default)
			)
			(layer "F.SilkS")
		)
		(fp_poly
			(pts
				(xy -2.935478 -0.403352) (xy -2.935478 -1.023112) (xy -2.315718 -0.713232)
			)
			(stroke
				(width 0)
				(type default)
			)
			(fill yes)
			(layer "F.SilkS")
		)
		(fp_line
			(start -0.674878 -1.124966)
			(end 0.674878 -1.124966)
			(stroke
				(width 0.1)
				(type default)
			)
			(layer "F.Fab")
		)
		(fp_line
			(start -0.674878 1.124966)
			(end -0.674878 -1.124966)
			(stroke
				(width 0.1)
				(type default)
			)
			(layer "F.Fab")
		)
		(fp_line
			(start 0.674878 -1.124966)
			(end 0.674878 1.124966)
			(stroke
				(width 0.1)
				(type default)
			)
			(layer "F.Fab")
		)
		(fp_line
			(start 0.674878 1.124966)
			(end -0.674878 1.124966)
			(stroke
				(width 0.1)
				(type default)
			)
			(layer "F.Fab")
		)
		(fp_poly
			(pts
				(xy -2.4892 -0.959866) (xy -1.86944 -0.649986) (xy -2.4892 -0.340106)
			)
			(stroke
				(width 0)
				(type default)
			)
			(fill yes)
			(layer "F.Fab")
		)
		(pad "1" smd rect
			(at -0.94488 -0.649986 90)
			(size 0.3556 1.2446)
			(layers "F.Cu" "F.Mask" "F.Paste")
			(net "Net_10785")
		)
		(pad "2" smd rect
			(at -0.94488 0 90)
			(size 0.3556 1.2446)
			(layers "F.Cu" "F.Mask" "F.Paste")
			(net "RST_PERST_OCP_SFF_BUF_N")
		)
		(pad "3" smd rect
			(at -0.94488 0.649986 90)
			(size 0.3556 1.2446)
			(layers "F.Cu" "F.Mask" "F.Paste")
			(net "GND")
		)
		(pad "4" smd rect
			(at 0.94488 0.649986 90)
			(size 0.3556 1.2446)
			(layers "F.Cu" "F.Mask" "F.Paste")
			(net "RST_PERST_OCP_SFF_BUF2_N")
		)
		(pad "5" smd rect
			(at 0.94488 -0.649986 90)
			(size 0.3556 1.2446)
			(layers "F.Cu" "F.Mask" "F.Paste")
			(net "P3V3_AUX")
		)
	)
	(footprint ""
		(layer "F.Cu")
		(at 182.757572 -133.561074 -90)
		(property "Reference" "R1279"
			(at 0 0 270)
			(layer "F.SilkS")
			(hide yes)
			(effects
				(font
					(size 1.27 1.27)
				)
			)
		)
		(property "Value" ""
			(at 0 0 270)
			(layer "F.Fab")
			(effects
				(font
					(size 1.27 1.27)
				)
			)
		)
		(duplicate_pad_numbers_are_jumpers no)
		(fp_line
			(start -0.7874 0.4064)
			(end -0.7874 -0.4064)
			(stroke
				(width 0.1524)
				(type default)
			)
			(layer "F.SilkS")
		)
		(fp_line
			(start 0.7874 0.4064)
			(end -0.7874 0.4064)
			(stroke
				(width 0.1524)
				(type default)
			)
			(layer "F.SilkS")
		)
		(fp_line
			(start -0.7874 -0.4064)
			(end 0.7874 -0.4064)
			(stroke
				(width 0.1524)
				(type default)
			)
			(layer "F.SilkS")
		)
		(fp_line
			(start 0.7874 -0.4064)
			(end 0.7874 0.4064)
			(stroke
				(width 0.1524)
				(type default)
			)
			(layer "F.SilkS")
		)
		(fp_line
			(start -0.67945 0.3048)
			(end -0.67945 -0.305054)
			(stroke
				(width 0.1)
				(type default)
			)
			(layer "F.Fab")
		)
		(fp_line
			(start -0.12065 0.3048)
			(end -0.67945 0.3048)
			(stroke
				(width 0.1)
				(type default)
			)
			(layer "F.Fab")
		)
		(fp_line
			(start 0.120396 0.3048)
			(end 0.120396 0.2794)
			(stroke
				(width 0.1)
				(type default)
			)
			(layer "F.Fab")
		)
		(fp_line
			(start 0.67945 0.3048)
			(end 0.120396 0.3048)
			(stroke
				(width 0.1)
				(type default)
			)
			(layer "F.Fab")
		)
		(fp_line
			(start -0.12065 0.2794)
			(end -0.12065 0.3048)
			(stroke
				(width 0.1)
				(type default)
			)
			(layer "F.Fab")
		)
		(fp_line
			(start 0.120396 0.2794)
			(end -0.12065 0.2794)
			(stroke
				(width 0.1)
				(type default)
			)
			(layer "F.Fab")
		)
		(fp_line
			(start -0.12065 -0.2794)
			(end 0.12065 -0.2794)
			(stroke
				(width 0.1)
				(type default)
			)
			(layer "F.Fab")
		)
		(fp_line
			(start 0.12065 -0.2794)
			(end 0.12065 -0.3048)
			(stroke
				(width 0.1)
				(type default)
			)
			(layer "F.Fab")
		)
		(fp_line
			(start 0.12065 -0.3048)
			(end 0.67945 -0.3048)
			(stroke
				(width 0.1)
				(type default)
			)
			(layer "F.Fab")
		)
		(fp_line
			(start 0.67945 -0.3048)
			(end 0.67945 0.3048)
			(stroke
				(width 0.1)
				(type default)
			)
			(layer "F.Fab")
		)
		(fp_line
			(start -0.67945 -0.305054)
			(end -0.12065 -0.305054)
			(stroke
				(width 0.1)
				(type default)
			)
			(layer "F.Fab")
		)
		(fp_line
			(start -0.12065 -0.305054)
			(end -0.12065 -0.2794)
			(stroke
				(width 0.1)
				(type default)
			)
			(layer "F.Fab")
		)
		(pad "1" smd circle
			(at -0.40005 0 270)
			(size 0 0)
			(layers "F.Cu" "F.Mask" "F.Paste")
			(net "FM_P1_PCC1_N")
		)
		(pad "2" smd circle
			(at 0.40005 0 270)
			(size 0 0)
			(layers "F.Cu" "F.Mask" "F.Paste")
			(net "FM_P1_PCC1_R_N")
		)
	)
	(footprint ""
		(layer "F.Cu")
		(at 413.928306 -137.16762)
		(property "Reference" "PC1898"
			(at 0 0 0)
			(layer "F.SilkS")
			(hide yes)
			(effects
				(font
					(size 1.27 1.27)
				)
			)
		)
		(property "Value" ""
			(at 0 0 0)
			(layer "F.Fab")
			(effects
				(font
					(size 1.27 1.27)
				)
			)
		)
		(duplicate_pad_numbers_are_jumpers no)
		(fp_line
			(start -1.524 -0.762)
			(end 1.524 -0.762)
			(stroke
				(width 0.1524)
				(type default)
			)
			(layer "F.SilkS")
		)
		(fp_line
			(start -1.524 0.762)
			(end -1.524 -0.762)
			(stroke
				(width 0.1524)
				(type default)
			)
			(layer "F.SilkS")
		)
		(fp_line
			(start 1.524 -0.762)
			(end 1.524 0.762)
			(stroke
				(width 0.1524)
				(type default)
			)
			(layer "F.SilkS")
		)
		(fp_line
			(start 1.524 0.762)
			(end -1.524 0.762)
			(stroke
				(width 0.1524)
				(type default)
			)
			(layer "F.SilkS")
		)
		(fp_line
			(start -1.1049 -0.724916)
			(end -1.1049 0.724916)
			(stroke
				(width 0.1)
				(type default)
			)
			(layer "F.Fab")
		)
		(fp_line
			(start -1.1049 0.724916)
			(end 1.1049 0.724916)
			(stroke
				(width 0.1)
				(type default)
			)
			(layer "F.Fab")
		)
		(fp_line
			(start 1.1049 -0.724916)
			(end -1.1049 -0.724916)
			(stroke
				(width 0.1)
				(type default)
			)
			(layer "F.Fab")
		)
		(fp_line
			(start 1.1049 0.724916)
			(end 1.1049 -0.724916)
			(stroke
				(width 0.1)
				(type default)
			)
			(layer "F.Fab")
		)
		(pad "1" smd rect
			(at -0.889 0 180)
			(size 1.016 1.27)
			(layers "F.Cu" "F.Mask" "F.Paste")
			(net "SW_P5V_AUX_FLT")
		)
		(pad "2" smd rect
			(at 0.889 0 180)
			(size 1.016 1.27)
			(layers "F.Cu" "F.Mask" "F.Paste")
			(net "GND")
		)
	)
	(footprint ""
		(layer "F.Cu")
		(at 384.760978 -180.078634 -90)
		(property "Reference" "PC546"
			(at 0 0 270)
			(layer "F.SilkS")
			(hide yes)
			(effects
				(font
					(size 1.27 1.27)
				)
			)
		)
		(property "Value" ""
			(at 0 0 270)
			(layer "F.Fab")
			(effects
				(font
					(size 1.27 1.27)
				)
			)
		)
		(duplicate_pad_numbers_are_jumpers no)
		(fp_line
			(start -0.7874 0.4064)
			(end -0.7874 -0.4064)
			(stroke
				(width 0.1524)
				(type default)
			)
			(layer "F.SilkS")
		)
		(fp_line
			(start -0.362966 0.4064)
			(end -0.7874 0.4064)
			(stroke
				(width 0.1524)
				(type default)
			)
			(layer "F.SilkS")
		)
		(fp_line
			(start 0.7874 0.4064)
			(end 0.500634 0.4064)
			(stroke
				(width 0.1524)
				(type default)
			)
			(layer "F.SilkS")
		)
		(fp_line
			(start -0.7874 -0.4064)
			(end 0.7874 -0.4064)
			(stroke
				(width 0.1524)
				(type default)
			)
			(layer "F.SilkS")
		)
		(fp_line
			(start 0.7874 -0.4064)
			(end 0.7874 0.4064)
			(stroke
				(width 0.1524)
				(type default)
			)
			(layer "F.SilkS")
		)
		(fp_line
			(start -0.67945 0.3048)
			(end -0.67945 -0.305054)
			(stroke
				(width 0.1)
				(type default)
			)
			(layer "F.Fab")
		)
		(fp_line
			(start -0.12065 0.3048)
			(end -0.67945 0.3048)
			(stroke
				(width 0.1)
				(type default)
			)
			(layer "F.Fab")
		)
		(fp_line
			(start 0.120396 0.3048)
			(end 0.120396 0.2794)
			(stroke
				(width 0.1)
				(type default)
			)
			(layer "F.Fab")
		)
		(fp_line
			(start 0.67945 0.3048)
			(end 0.120396 0.3048)
			(stroke
				(width 0.1)
				(type default)
			)
			(layer "F.Fab")
		)
		(fp_line
			(start -0.12065 0.2794)
			(end -0.12065 0.3048)
			(stroke
				(width 0.1)
				(type default)
			)
			(layer "F.Fab")
		)
		(fp_line
			(start 0.120396 0.2794)
			(end -0.12065 0.2794)
			(stroke
				(width 0.1)
				(type default)
			)
			(layer "F.Fab")
		)
		(fp_line
			(start -0.12065 -0.2794)
			(end 0.12065 -0.2794)
			(stroke
				(width 0.1)
				(type default)
			)
			(layer "F.Fab")
		)
		(fp_line
			(start 0.12065 -0.2794)
			(end 0.12065 -0.3048)
			(stroke
				(width 0.1)
				(type default)
			)
			(layer "F.Fab")
		)
		(fp_line
			(start 0.12065 -0.3048)
			(end 0.67945 -0.3048)
			(stroke
				(width 0.1)
				(type default)
			)
			(layer "F.Fab")
		)
		(fp_line
			(start 0.67945 -0.3048)
			(end 0.67945 0.3048)
			(stroke
				(width 0.1)
				(type default)
			)
			(layer "F.Fab")
		)
		(fp_line
			(start -0.67945 -0.305054)
			(end -0.12065 -0.305054)
			(stroke
				(width 0.1)
				(type default)
			)
			(layer "F.Fab")
		)
		(fp_line
			(start -0.12065 -0.305054)
			(end -0.12065 -0.2794)
			(stroke
				(width 0.1)
				(type default)
			)
			(layer "F.Fab")
		)
		(pad "1" smd circle
			(at -0.40005 0 270)
			(size 0 0)
			(layers "F.Cu" "F.Mask" "F.Paste")
			(net "PVDDCR_CPU0_P0_VCC3")
		)
		(pad "2" smd circle
			(at 0.40005 0 270)
			(size 0 0)
			(layers "F.Cu" "F.Mask" "F.Paste")
			(net "GND")
		)
	)
	(footprint ""
		(layer "F.Cu")
		(at 84.940902 -370.57203 -90)
		(property "Reference" "C728"
			(at 0 0 270)
			(layer "F.SilkS")
			(hide yes)
			(effects
				(font
					(size 1.27 1.27)
				)
			)
		)
		(property "Value" ""
			(at 0 0 270)
			(layer "F.Fab")
			(effects
				(font
					(size 1.27 1.27)
				)
			)
		)
		(duplicate_pad_numbers_are_jumpers no)
		(fp_line
			(start -0.299974 0.150114)
			(end -0.299974 -0.150114)
			(stroke
				(width 0.1)
				(type default)
			)
			(layer "F.Fab")
		)
		(fp_line
			(start 0.299974 0.150114)
			(end -0.299974 0.150114)
			(stroke
				(width 0.1)
				(type default)
			)
			(layer "F.Fab")
		)
		(fp_line
			(start -0.299974 -0.150114)
			(end 0.299974 -0.150114)
			(stroke
				(width 0.1)
				(type default)
			)
			(layer "F.Fab")
		)
		(fp_line
			(start 0.299974 -0.150114)
			(end 0.299974 0.150114)
			(stroke
				(width 0.1)
				(type default)
			)
			(layer "F.Fab")
		)
		(pad "1" smd rect
			(at -0.2667 0 270)
			(size 0.3048 0.381)
			(layers "F.Cu" "F.Mask" "F.Paste")
			(net "P5E_CPU1_P1_TX_C_DN<6>")
		)
		(pad "2" smd rect
			(at 0.2667 0 270)
			(size 0.3048 0.381)
			(layers "F.Cu" "F.Mask" "F.Paste")
			(net "P5E_CPU1_P1_TX_DN<6>")
		)
	)
	(footprint ""
		(layer "F.Cu")
		(at 150.814532 -106.73207 -90)
		(property "Reference" "R1134"
			(at 0 0 270)
			(layer "F.SilkS")
			(hide yes)
			(effects
				(font
					(size 1.27 1.27)
				)
			)
		)
		(property "Value" ""
			(at 0 0 270)
			(layer "F.Fab")
			(effects
				(font
					(size 1.27 1.27)
				)
			)
		)
		(duplicate_pad_numbers_are_jumpers no)
		(fp_line
			(start -0.7874 0.4064)
			(end -0.7874 -0.4064)
			(stroke
				(width 0.1524)
				(type default)
			)
			(layer "F.SilkS")
		)
		(fp_line
			(start 0.7874 0.4064)
			(end -0.7874 0.4064)
			(stroke
				(width 0.1524)
				(type default)
			)
			(layer "F.SilkS")
		)
		(fp_line
			(start -0.7874 -0.4064)
			(end 0.7874 -0.4064)
			(stroke
				(width 0.1524)
				(type default)
			)
			(layer "F.SilkS")
		)
		(fp_line
			(start 0.7874 -0.4064)
			(end 0.7874 0.4064)
			(stroke
				(width 0.1524)
				(type default)
			)
			(layer "F.SilkS")
		)
		(fp_line
			(start -0.67945 0.3048)
			(end -0.67945 -0.305054)
			(stroke
				(width 0.1)
				(type default)
			)
			(layer "F.Fab")
		)
		(fp_line
			(start -0.12065 0.3048)
			(end -0.67945 0.3048)
			(stroke
				(width 0.1)
				(type default)
			)
			(layer "F.Fab")
		)
		(fp_line
			(start 0.120396 0.3048)
			(end 0.120396 0.2794)
			(stroke
				(width 0.1)
				(type default)
			)
			(layer "F.Fab")
		)
		(fp_line
			(start 0.67945 0.3048)
			(end 0.120396 0.3048)
			(stroke
				(width 0.1)
				(type default)
			)
			(layer "F.Fab")
		)
		(fp_line
			(start -0.12065 0.2794)
			(end -0.12065 0.3048)
			(stroke
				(width 0.1)
				(type default)
			)
			(layer "F.Fab")
		)
		(fp_line
			(start 0.120396 0.2794)
			(end -0.12065 0.2794)
			(stroke
				(width 0.1)
				(type default)
			)
			(layer "F.Fab")
		)
		(fp_line
			(start -0.12065 -0.2794)
			(end 0.12065 -0.2794)
			(stroke
				(width 0.1)
				(type default)
			)
			(layer "F.Fab")
		)
		(fp_line
			(start 0.12065 -0.2794)
			(end 0.12065 -0.3048)
			(stroke
				(width 0.1)
				(type default)
			)
			(layer "F.Fab")
		)
		(fp_line
			(start 0.12065 -0.3048)
			(end 0.67945 -0.3048)
			(stroke
				(width 0.1)
				(type default)
			)
			(layer "F.Fab")
		)
		(fp_line
			(start 0.67945 -0.3048)
			(end 0.67945 0.3048)
			(stroke
				(width 0.1)
				(type default)
			)
			(layer "F.Fab")
		)
		(fp_line
			(start -0.67945 -0.305054)
			(end -0.12065 -0.305054)
			(stroke
				(width 0.1)
				(type default)
			)
			(layer "F.Fab")
		)
		(fp_line
			(start -0.12065 -0.305054)
			(end -0.12065 -0.2794)
			(stroke
				(width 0.1)
				(type default)
			)
			(layer "F.Fab")
		)
		(pad "1" smd circle
			(at -0.40005 0 270)
			(size 0 0)
			(layers "F.Cu" "F.Mask" "F.Paste")
			(net "P12V_OCP_SFF_BUF_EN")
		)
		(pad "2" smd circle
			(at 0.40005 0 270)
			(size 0 0)
			(layers "F.Cu" "F.Mask" "F.Paste")
			(net "P12V_OCP_SFF_BUF_EN_R")
		)
	)
	(footprint ""
		(layer "F.Cu")
		(at 58.08345 -143.664686 -90)
		(property "Reference" "PR402"
			(at 0 0 270)
			(layer "F.SilkS")
			(hide yes)
			(effects
				(font
					(size 1.27 1.27)
				)
			)
		)
		(property "Value" ""
			(at 0 0 270)
			(layer "F.Fab")
			(effects
				(font
					(size 1.27 1.27)
				)
			)
		)
		(duplicate_pad_numbers_are_jumpers no)
		(fp_line
			(start -0.7874 0.4064)
			(end -0.7874 -0.4064)
			(stroke
				(width 0.1524)
				(type default)
			)
			(layer "F.SilkS")
		)
		(fp_line
			(start 0.7874 0.4064)
			(end -0.7874 0.4064)
			(stroke
				(width 0.1524)
				(type default)
			)
			(layer "F.SilkS")
		)
		(fp_line
			(start -0.7874 -0.4064)
			(end 0.7874 -0.4064)
			(stroke
				(width 0.1524)
				(type default)
			)
			(layer "F.SilkS")
		)
		(fp_line
			(start 0.7874 -0.4064)
			(end 0.7874 0.4064)
			(stroke
				(width 0.1524)
				(type default)
			)
			(layer "F.SilkS")
		)
		(fp_line
			(start -0.67945 0.3048)
			(end -0.67945 -0.305054)
			(stroke
				(width 0.1)
				(type default)
			)
			(layer "F.Fab")
		)
		(fp_line
			(start -0.12065 0.3048)
			(end -0.67945 0.3048)
			(stroke
				(width 0.1)
				(type default)
			)
			(layer "F.Fab")
		)
		(fp_line
			(start 0.120396 0.3048)
			(end 0.120396 0.2794)
			(stroke
				(width 0.1)
				(type default)
			)
			(layer "F.Fab")
		)
		(fp_line
			(start 0.67945 0.3048)
			(end 0.120396 0.3048)
			(stroke
				(width 0.1)
				(type default)
			)
			(layer "F.Fab")
		)
		(fp_line
			(start -0.12065 0.2794)
			(end -0.12065 0.3048)
			(stroke
				(width 0.1)
				(type default)
			)
			(layer "F.Fab")
		)
		(fp_line
			(start 0.120396 0.2794)
			(end -0.12065 0.2794)
			(stroke
				(width 0.1)
				(type default)
			)
			(layer "F.Fab")
		)
		(fp_line
			(start -0.12065 -0.2794)
			(end 0.12065 -0.2794)
			(stroke
				(width 0.1)
				(type default)
			)
			(layer "F.Fab")
		)
		(fp_line
			(start 0.12065 -0.2794)
			(end 0.12065 -0.3048)
			(stroke
				(width 0.1)
				(type default)
			)
			(layer "F.Fab")
		)
		(fp_line
			(start 0.12065 -0.3048)
			(end 0.67945 -0.3048)
			(stroke
				(width 0.1)
				(type default)
			)
			(layer "F.Fab")
		)
		(fp_line
			(start 0.67945 -0.3048)
			(end 0.67945 0.3048)
			(stroke
				(width 0.1)
				(type default)
			)
			(layer "F.Fab")
		)
		(fp_line
			(start -0.67945 -0.305054)
			(end -0.12065 -0.305054)
			(stroke
				(width 0.1)
				(type default)
			)
			(layer "F.Fab")
		)
		(fp_line
			(start -0.12065 -0.305054)
			(end -0.12065 -0.2794)
			(stroke
				(width 0.1)
				(type default)
			)
			(layer "F.Fab")
		)
		(pad "1" smd circle
			(at -0.40005 0 270)
			(size 0 0)
			(layers "F.Cu" "F.Mask" "F.Paste")
			(net "PVDD18_S5_P1")
		)
		(pad "2" smd circle
			(at 0.40005 0 270)
			(size 0 0)
			(layers "F.Cu" "F.Mask" "F.Paste")
			(net "PVDD18_S5_P1_FB_RC")
		)
	)
	(footprint ""
		(layer "F.Cu")
		(at 462.20507 -40.226488 -90)
		(property "Reference" "R4068"
			(at 0 0 270)
			(layer "F.SilkS")
			(hide yes)
			(effects
				(font
					(size 1.27 1.27)
				)
			)
		)
		(property "Value" ""
			(at 0 0 270)
			(layer "F.Fab")
			(effects
				(font
					(size 1.27 1.27)
				)
			)
		)
		(duplicate_pad_numbers_are_jumpers no)
		(fp_line
			(start -0.7874 0.4064)
			(end -0.7874 -0.4064)
			(stroke
				(width 0.1524)
				(type default)
			)
			(layer "F.SilkS")
		)
		(fp_line
			(start 0.7874 0.4064)
			(end -0.7874 0.4064)
			(stroke
				(width 0.1524)
				(type default)
			)
			(layer "F.SilkS")
		)
		(fp_line
			(start -0.7874 -0.4064)
			(end 0.7874 -0.4064)
			(stroke
				(width 0.1524)
				(type default)
			)
			(layer "F.SilkS")
		)
		(fp_line
			(start 0.7874 -0.4064)
			(end 0.7874 0.4064)
			(stroke
				(width 0.1524)
				(type default)
			)
			(layer "F.SilkS")
		)
		(fp_line
			(start -0.67945 0.3048)
			(end -0.67945 -0.305054)
			(stroke
				(width 0.1)
				(type default)
			)
			(layer "F.Fab")
		)
		(fp_line
			(start -0.12065 0.3048)
			(end -0.67945 0.3048)
			(stroke
				(width 0.1)
				(type default)
			)
			(layer "F.Fab")
		)
		(fp_line
			(start 0.120396 0.3048)
			(end 0.120396 0.2794)
			(stroke
				(width 0.1)
				(type default)
			)
			(layer "F.Fab")
		)
		(fp_line
			(start 0.67945 0.3048)
			(end 0.120396 0.3048)
			(stroke
				(width 0.1)
				(type default)
			)
			(layer "F.Fab")
		)
		(fp_line
			(start -0.12065 0.2794)
			(end -0.12065 0.3048)
			(stroke
				(width 0.1)
				(type default)
			)
			(layer "F.Fab")
		)
		(fp_line
			(start 0.120396 0.2794)
			(end -0.12065 0.2794)
			(stroke
				(width 0.1)
				(type default)
			)
			(layer "F.Fab")
		)
		(fp_line
			(start -0.12065 -0.2794)
			(end 0.12065 -0.2794)
			(stroke
				(width 0.1)
				(type default)
			)
			(layer "F.Fab")
		)
		(fp_line
			(start 0.12065 -0.2794)
			(end 0.12065 -0.3048)
			(stroke
				(width 0.1)
				(type default)
			)
			(layer "F.Fab")
		)
		(fp_line
			(start 0.12065 -0.3048)
			(end 0.67945 -0.3048)
			(stroke
				(width 0.1)
				(type default)
			)
			(layer "F.Fab")
		)
		(fp_line
			(start 0.67945 -0.3048)
			(end 0.67945 0.3048)
			(stroke
				(width 0.1)
				(type default)
			)
			(layer "F.Fab")
		)
		(fp_line
			(start -0.67945 -0.305054)
			(end -0.12065 -0.305054)
			(stroke
				(width 0.1)
				(type default)
			)
			(layer "F.Fab")
		)
		(fp_line
			(start -0.12065 -0.305054)
			(end -0.12065 -0.2794)
			(stroke
				(width 0.1)
				(type default)
			)
			(layer "F.Fab")
		)
		(pad "1" smd circle
			(at -0.40005 0 270)
			(size 0 0)
			(layers "F.Cu" "F.Mask" "F.Paste")
			(net "P12V_AUX")
		)
		(pad "2" smd circle
			(at 0.40005 0 270)
			(size 0 0)
			(layers "F.Cu" "F.Mask" "F.Paste")
			(net "P12V_OCP_1_EN_G")
		)
	)
	(footprint ""
		(layer "F.Cu")
		(at 64.325754 -373.03583 -90)
		(property "Reference" "C814"
			(at 0 0 270)
			(layer "F.SilkS")
			(hide yes)
			(effects
				(font
					(size 1.27 1.27)
				)
			)
		)
		(property "Value" ""
			(at 0 0 270)
			(layer "F.Fab")
			(effects
				(font
					(size 1.27 1.27)
				)
			)
		)
		(duplicate_pad_numbers_are_jumpers no)
		(fp_line
			(start -0.299974 0.150114)
			(end -0.299974 -0.150114)
			(stroke
				(width 0.1)
				(type default)
			)
			(layer "F.Fab")
		)
		(fp_line
			(start 0.299974 0.150114)
			(end -0.299974 0.150114)
			(stroke
				(width 0.1)
				(type default)
			)
			(layer "F.Fab")
		)
		(fp_line
			(start -0.299974 -0.150114)
			(end 0.299974 -0.150114)
			(stroke
				(width 0.1)
				(type default)
			)
			(layer "F.Fab")
		)
		(fp_line
			(start 0.299974 -0.150114)
			(end 0.299974 0.150114)
			(stroke
				(width 0.1)
				(type default)
			)
			(layer "F.Fab")
		)
		(pad "1" smd rect
			(at -0.2667 0 270)
			(size 0.3048 0.381)
			(layers "F.Cu" "F.Mask" "F.Paste")
			(net "P5E_CPU1_P0_TX_C_DN<11>")
		)
		(pad "2" smd rect
			(at 0.2667 0 270)
			(size 0.3048 0.381)
			(layers "F.Cu" "F.Mask" "F.Paste")
			(net "P5E_CPU1_P0_TX_DN<11>")
		)
	)
	(footprint ""
		(layer "F.Cu")
		(at 220.363034 -75.02779 -90)
		(property "Reference" "PR3967"
			(at 0 0 270)
			(layer "F.SilkS")
			(hide yes)
			(effects
				(font
					(size 1.27 1.27)
				)
			)
		)
		(property "Value" ""
			(at 0 0 270)
			(layer "F.Fab")
			(effects
				(font
					(size 1.27 1.27)
				)
			)
		)
		(duplicate_pad_numbers_are_jumpers no)
		(fp_line
			(start -0.7874 0.4064)
			(end -0.7874 -0.4064)
			(stroke
				(width 0.1524)
				(type default)
			)
			(layer "F.SilkS")
		)
		(fp_line
			(start 0.7874 0.4064)
			(end -0.7874 0.4064)
			(stroke
				(width 0.1524)
				(type default)
			)
			(layer "F.SilkS")
		)
		(fp_line
			(start -0.7874 -0.4064)
			(end 0.7874 -0.4064)
			(stroke
				(width 0.1524)
				(type default)
			)
			(layer "F.SilkS")
		)
		(fp_line
			(start 0.7874 -0.4064)
			(end 0.7874 0.4064)
			(stroke
				(width 0.1524)
				(type default)
			)
			(layer "F.SilkS")
		)
		(fp_line
			(start -0.67945 0.3048)
			(end -0.67945 -0.305054)
			(stroke
				(width 0.1)
				(type default)
			)
			(layer "F.Fab")
		)
		(fp_line
			(start -0.12065 0.3048)
			(end -0.67945 0.3048)
			(stroke
				(width 0.1)
				(type default)
			)
			(layer "F.Fab")
		)
		(fp_line
			(start 0.120396 0.3048)
			(end 0.120396 0.2794)
			(stroke
				(width 0.1)
				(type default)
			)
			(layer "F.Fab")
		)
		(fp_line
			(start 0.67945 0.3048)
			(end 0.120396 0.3048)
			(stroke
				(width 0.1)
				(type default)
			)
			(layer "F.Fab")
		)
		(fp_line
			(start -0.12065 0.2794)
			(end -0.12065 0.3048)
			(stroke
				(width 0.1)
				(type default)
			)
			(layer "F.Fab")
		)
		(fp_line
			(start 0.120396 0.2794)
			(end -0.12065 0.2794)
			(stroke
				(width 0.1)
				(type default)
			)
			(layer "F.Fab")
		)
		(fp_line
			(start -0.12065 -0.2794)
			(end 0.12065 -0.2794)
			(stroke
				(width 0.1)
				(type default)
			)
			(layer "F.Fab")
		)
		(fp_line
			(start 0.12065 -0.2794)
			(end 0.12065 -0.3048)
			(stroke
				(width 0.1)
				(type default)
			)
			(layer "F.Fab")
		)
		(fp_line
			(start 0.12065 -0.3048)
			(end 0.67945 -0.3048)
			(stroke
				(width 0.1)
				(type default)
			)
			(layer "F.Fab")
		)
		(fp_line
			(start 0.67945 -0.3048)
			(end 0.67945 0.3048)
			(stroke
				(width 0.1)
				(type default)
			)
			(layer "F.Fab")
		)
		(fp_line
			(start -0.67945 -0.305054)
			(end -0.12065 -0.305054)
			(stroke
				(width 0.1)
				(type default)
			)
			(layer "F.Fab")
		)
		(fp_line
			(start -0.12065 -0.305054)
			(end -0.12065 -0.2794)
			(stroke
				(width 0.1)
				(type default)
			)
			(layer "F.Fab")
		)
		(pad "1" smd circle
			(at -0.40005 0 270)
			(size 0 0)
			(layers "F.Cu" "F.Mask" "F.Paste")
			(net "P3V3_AUX")
		)
		(pad "2" smd circle
			(at 0.40005 0 270)
			(size 0 0)
			(layers "F.Cu" "F.Mask" "F.Paste")
			(net "P3V3_E1S_VCC_0")
		)
	)
	(footprint ""
		(layer "F.Cu")
		(at 240.792 -281.7368 180)
		(property "Reference" "PC6504"
			(at 0 0 180)
			(layer "F.SilkS")
			(hide yes)
			(effects
				(font
					(size 1.27 1.27)
				)
			)
		)
		(property "Value" ""
			(at 0 0 180)
			(layer "F.Fab")
			(effects
				(font
					(size 1.27 1.27)
				)
			)
		)
		(duplicate_pad_numbers_are_jumpers no)
		(fp_line
			(start 1.524 0.762)
			(end -1.524 0.762)
			(stroke
				(width 0.1524)
				(type default)
			)
			(layer "F.SilkS")
		)
		(fp_line
			(start 1.524 -0.762)
			(end 1.524 0.762)
			(stroke
				(width 0.1524)
				(type default)
			)
			(layer "F.SilkS")
		)
		(fp_line
			(start -1.524 0.762)
			(end -1.524 -0.762)
			(stroke
				(width 0.1524)
				(type default)
			)
			(layer "F.SilkS")
		)
		(fp_line
			(start -1.524 -0.762)
			(end 1.524 -0.762)
			(stroke
				(width 0.1524)
				(type default)
			)
			(layer "F.SilkS")
		)
		(fp_line
			(start 1.1049 0.724916)
			(end 1.1049 -0.724916)
			(stroke
				(width 0.1)
				(type default)
			)
			(layer "F.Fab")
		)
		(fp_line
			(start 1.1049 -0.724916)
			(end -1.1049 -0.724916)
			(stroke
				(width 0.1)
				(type default)
			)
			(layer "F.Fab")
		)
		(fp_line
			(start -1.1049 0.724916)
			(end 1.1049 0.724916)
			(stroke
				(width 0.1)
				(type default)
			)
			(layer "F.Fab")
		)
		(fp_line
			(start -1.1049 -0.724916)
			(end -1.1049 0.724916)
			(stroke
				(width 0.1)
				(type default)
			)
			(layer "F.Fab")
		)
		(pad "1" smd rect
			(at -0.889 0)
			(size 1.016 1.27)
			(layers "F.Cu" "F.Mask" "F.Paste")
			(net "SW_P12V_AUX_P1V8_RETIMER_CPU0_FLT")
		)
		(pad "2" smd rect
			(at 0.889 0)
			(size 1.016 1.27)
			(layers "F.Cu" "F.Mask" "F.Paste")
			(net "GND")
		)
	)
	(footprint ""
		(layer "F.Cu")
		(at 205.232508 -124.801376)
		(property "Reference" "R2663"
			(at 0 0 0)
			(layer "F.SilkS")
			(hide yes)
			(effects
				(font
					(size 1.27 1.27)
				)
			)
		)
		(property "Value" ""
			(at 0 0 0)
			(layer "F.Fab")
			(effects
				(font
					(size 1.27 1.27)
				)
			)
		)
		(duplicate_pad_numbers_are_jumpers no)
		(fp_line
			(start -0.7874 -0.4064)
			(end 0.7874 -0.4064)
			(stroke
				(width 0.1524)
				(type default)
			)
			(layer "F.SilkS")
		)
		(fp_line
			(start -0.7874 0.4064)
			(end -0.7874 -0.4064)
			(stroke
				(width 0.1524)
				(type default)
			)
			(layer "F.SilkS")
		)
		(fp_line
			(start 0.7874 -0.4064)
			(end 0.7874 0.4064)
			(stroke
				(width 0.1524)
				(type default)
			)
			(layer "F.SilkS")
		)
		(fp_line
			(start 0.7874 0.4064)
			(end -0.7874 0.4064)
			(stroke
				(width 0.1524)
				(type default)
			)
			(layer "F.SilkS")
		)
		(fp_line
			(start -0.67945 -0.305054)
			(end -0.12065 -0.305054)
			(stroke
				(width 0.1)
				(type default)
			)
			(layer "F.Fab")
		)
		(fp_line
			(start -0.67945 0.3048)
			(end -0.67945 -0.305054)
			(stroke
				(width 0.1)
				(type default)
			)
			(layer "F.Fab")
		)
		(fp_line
			(start -0.12065 -0.305054)
			(end -0.12065 -0.2794)
			(stroke
				(width 0.1)
				(type default)
			)
			(layer "F.Fab")
		)
		(fp_line
			(start -0.12065 -0.2794)
			(end 0.12065 -0.2794)
			(stroke
				(width 0.1)
				(type default)
			)
			(layer "F.Fab")
		)
		(fp_line
			(start -0.12065 0.2794)
			(end -0.12065 0.3048)
			(stroke
				(width 0.1)
				(type default)
			)
			(layer "F.Fab")
		)
		(fp_line
			(start -0.12065 0.3048)
			(end -0.67945 0.3048)
			(stroke
				(width 0.1)
				(type default)
			)
			(layer "F.Fab")
		)
		(fp_line
			(start 0.120396 0.2794)
			(end -0.12065 0.2794)
			(stroke
				(width 0.1)
				(type default)
			)
			(layer "F.Fab")
		)
		(fp_line
			(start 0.120396 0.3048)
			(end 0.120396 0.2794)
			(stroke
				(width 0.1)
				(type default)
			)
			(layer "F.Fab")
		)
		(fp_line
			(start 0.12065 -0.3048)
			(end 0.67945 -0.3048)
			(stroke
				(width 0.1)
				(type default)
			)
			(layer "F.Fab")
		)
		(fp_line
			(start 0.12065 -0.2794)
			(end 0.12065 -0.3048)
			(stroke
				(width 0.1)
				(type default)
			)
			(layer "F.Fab")
		)
		(fp_line
			(start 0.67945 -0.3048)
			(end 0.67945 0.3048)
			(stroke
				(width 0.1)
				(type default)
			)
			(layer "F.Fab")
		)
		(fp_line
			(start 0.67945 0.3048)
			(end 0.120396 0.3048)
			(stroke
				(width 0.1)
				(type default)
			)
			(layer "F.Fab")
		)
		(pad "1" smd circle
			(at -0.40005 0)
			(size 0 0)
			(layers "F.Cu" "F.Mask" "F.Paste")
			(net "FM_SWB_PWRGD_ISO_R")
		)
		(pad "2" smd circle
			(at 0.40005 0)
			(size 0 0)
			(layers "F.Cu" "F.Mask" "F.Paste")
			(net "FM_SWB_PWRGD_ISO")
		)
	)
	(footprint ""
		(layer "F.Cu")
		(at 221.821502 -70.870318)
		(property "Reference" "PU295"
			(at -1.640332 2.305558 0)
			(unlocked yes)
			(layer "F.SilkS")
			(effects
				(font
					(size 0.7874 0.5842)
					(thickness 0.1524)
				)
				(justify left)
			)
		)
		(property "Value" ""
			(at 0 0 0)
			(layer "F.Fab")
			(effects
				(font
					(size 1.27 1.27)
				)
			)
		)
		(duplicate_pad_numbers_are_jumpers no)
		(fp_line
			(start -1.774952 -1.039876)
			(end -1.774952 1.039876)
			(stroke
				(width 0.1524)
				(type default)
			)
			(layer "F.SilkS")
		)
		(fp_line
			(start -1.774952 1.039876)
			(end 1.774952 1.039876)
			(stroke
				(width 0.1524)
				(type default)
			)
			(layer "F.SilkS")
		)
		(fp_line
			(start 1.774952 -1.039876)
			(end -1.774952 -1.039876)
			(stroke
				(width 0.1524)
				(type default)
			)
			(layer "F.SilkS")
		)
		(fp_line
			(start 1.774952 1.039876)
			(end 1.774952 -1.039876)
			(stroke
				(width 0.1524)
				(type default)
			)
			(layer "F.SilkS")
		)
		(fp_poly
			(pts
				(xy -0.999998 -1.801876) (xy -0.999998 -1.039876) (xy -1.769872 -1.039876) (xy -1.769872 -0.249936)
				(xy -2.531872 -0.249936) (xy -2.531872 -1.801876)
			)
			(stroke
				(width 0)
				(type default)
			)
			(fill yes)
			(layer "F.SilkS")
		)
		(fp_line
			(start -1.769872 -1.039876)
			(end -1.769872 1.039876)
			(stroke
				(width 0.1)
				(type default)
			)
			(layer "F.Fab")
		)
		(fp_line
			(start -1.769872 1.039876)
			(end 1.769872 1.039876)
			(stroke
				(width 0.1)
				(type default)
			)
			(layer "F.Fab")
		)
		(fp_line
			(start 1.769872 -1.039876)
			(end -1.769872 -1.039876)
			(stroke
				(width 0.1)
				(type default)
			)
			(layer "F.Fab")
		)
		(fp_line
			(start 1.769872 1.039876)
			(end 1.769872 -1.039876)
			(stroke
				(width 0.1)
				(type default)
			)
			(layer "F.Fab")
		)
		(fp_poly
			(pts
				(xy -1.769872 -1.039876) (xy -0.999998 -1.039876) (xy -0.999998 -1.801876) (xy -2.531872 -1.801876)
				(xy -2.531872 -0.249936) (xy -1.769872 -0.249936)
			)
			(stroke
				(width 0)
				(type default)
			)
			(fill yes)
			(layer "F.Fab")
		)
		(pad "A1" smd circle
			(at -1.500124 -0.750062)
			(size 0.2286 0.2286)
			(layers "F.Cu" "F.Mask" "F.Paste")
			(net "P3V3_E1S_SENSE_0")
		)
		(pad "A2" smd circle
			(at -0.999998 -0.750062)
			(size 0.2286 0.2286)
			(layers "F.Cu" "F.Mask" "F.Paste")
			(net "P3V3_E1S_VCC_0")
		)
		(pad "A3" smd circle
			(at -0.499872 -0.750062)
			(size 0.2286 0.2286)
			(layers "F.Cu" "F.Mask" "F.Paste")
			(net "P3V3_AUX")
		)
		(pad "A4" smd circle
			(at 0 -0.750062)
			(size 0.2286 0.2286)
			(layers "F.Cu" "F.Mask" "F.Paste")
			(net "P3V3_E1S_0_R")
		)
		(pad "A5" smd circle
			(at 0.499872 -0.750062)
			(size 0.2286 0.2286)
			(layers "F.Cu" "F.Mask" "F.Paste")
			(net "P3V3_AUX")
		)
		(pad "A6" smd circle
			(at 0.999998 -0.750062)
			(size 0.2286 0.2286)
			(layers "F.Cu" "F.Mask" "F.Paste")
			(net "P3V3_E1S_GATE_0")
		)
		(pad "A7" smd circle
			(at 1.500124 -0.750062)
			(size 0.2286 0.2286)
			(layers "F.Cu" "F.Mask" "F.Paste")
			(net "GND")
		)
		(pad "B1" smd circle
			(at -1.500124 -0.249936)
			(size 0.2286 0.2286)
			(layers "F.Cu" "F.Mask" "F.Paste")
			(net "P3V3_E1S_CB_0")
		)
		(pad "B2" smd circle
			(at -0.999998 -0.249936)
			(size 0.2286 0.2286)
			(layers "F.Cu" "F.Mask" "F.Paste")
			(net "GND")
		)
		(pad "B3" smd circle
			(at -0.499872 -0.249936)
			(size 0.2286 0.2286)
			(layers "F.Cu" "F.Mask" "F.Paste")
			(net "P3V3_AUX")
		)
		(pad "B4" smd circle
			(at 0 -0.249936)
			(size 0.2286 0.2286)
			(layers "F.Cu" "F.Mask" "F.Paste")
			(net "P3V3_E1S_0_R")
		)
		(pad "B5" smd circle
			(at 0.499872 -0.249936)
			(size 0.2286 0.2286)
			(layers "F.Cu" "F.Mask" "F.Paste")
			(net "P3V3_AUX")
		)
		(pad "B6" smd circle
			(at 0.999998 -0.249936)
			(size 0.2286 0.2286)
			(layers "F.Cu" "F.Mask" "F.Paste")
			(net "P3V3_E1S_0_R")
		)
		(pad "B7" smd circle
			(at 1.500124 -0.249936)
			(size 0.2286 0.2286)
			(layers "F.Cu" "F.Mask" "F.Paste")
			(net "GND")
		)
		(pad "C1" smd circle
			(at -1.500124 0.249936)
			(size 0.2286 0.2286)
			(layers "F.Cu" "F.Mask" "F.Paste")
			(net "GND")
		)
		(pad "C2" smd circle
			(at -0.999998 0.249936)
			(size 0.2286 0.2286)
			(layers "F.Cu" "F.Mask" "F.Paste")
			(net "GND")
		)
		(pad "C3" smd circle
			(at -0.499872 0.249936)
			(size 0.2286 0.2286)
			(layers "F.Cu" "F.Mask" "F.Paste")
			(net "P3V3_AUX")
		)
		(pad "C4" smd circle
			(at 0 0.249936)
			(size 0.2286 0.2286)
			(layers "F.Cu" "F.Mask" "F.Paste")
			(net "P3V3_E1S_0_R")
		)
		(pad "C5" smd circle
			(at 0.499872 0.249936)
			(size 0.2286 0.2286)
			(layers "F.Cu" "F.Mask" "F.Paste")
			(net "P3V3_AUX")
		)
		(pad "C6" smd circle
			(at 0.999998 0.249936)
			(size 0.2286 0.2286)
			(layers "F.Cu" "F.Mask" "F.Paste")
			(net "P3V3_E1S_0_R")
		)
		(pad "C7" smd circle
			(at 1.500124 0.249936)
			(size 0.2286 0.2286)
			(layers "F.Cu" "F.Mask" "F.Paste")
			(net "P3V3_E1S_FAULT_0")
		)
		(pad "D1" smd circle
			(at -1.500124 0.750062)
			(size 0.2286 0.2286)
			(layers "F.Cu" "F.Mask" "F.Paste")
			(net "P3V3_E1S_REG_0")
		)
		(pad "D2" smd circle
			(at -0.999998 0.750062)
			(size 0.2286 0.2286)
			(layers "F.Cu" "F.Mask" "F.Paste")
			(net "P3V3_E1S_UV_0")
		)
		(pad "D3" smd circle
			(at -0.499872 0.750062)
			(size 0.2286 0.2286)
			(layers "F.Cu" "F.Mask" "F.Paste")
			(net "P3V3_E1S_OV_0")
		)
		(pad "D4" smd circle
			(at 0 0.750062)
			(size 0.2286 0.2286)
			(layers "F.Cu" "F.Mask" "F.Paste")
			(net "P3V3_E1S_0_R")
		)
		(pad "D5" smd circle
			(at 0.499872 0.750062)
			(size 0.2286 0.2286)
			(layers "F.Cu" "F.Mask" "F.Paste")
			(net "P3V3_AUX")
		)
		(pad "D6" smd circle
			(at 0.999998 0.750062)
			(size 0.2286 0.2286)
			(layers "F.Cu" "F.Mask" "F.Paste")
			(net "P3V3_E1S_0_R")
		)
		(pad "D7" smd circle
			(at 1.500124 0.750062)
			(size 0.2286 0.2286)
			(layers "F.Cu" "F.Mask" "F.Paste")
			(net "P3V3_E1S_PWRGD_0")
		)
	)
	(footprint ""
		(layer "F.Cu")
		(at 279.513792 -116.67617 180)
		(property "Reference" "R2968"
			(at 0 0 180)
			(layer "F.SilkS")
			(hide yes)
			(effects
				(font
					(size 1.27 1.27)
				)
			)
		)
		(property "Value" ""
			(at 0 0 180)
			(layer "F.Fab")
			(effects
				(font
					(size 1.27 1.27)
				)
			)
		)
		(duplicate_pad_numbers_are_jumpers no)
		(fp_line
			(start 0.7874 0.4064)
			(end -0.7874 0.4064)
			(stroke
				(width 0.1524)
				(type default)
			)
			(layer "F.SilkS")
		)
		(fp_line
			(start 0.7874 -0.4064)
			(end 0.7874 0.4064)
			(stroke
				(width 0.1524)
				(type default)
			)
			(layer "F.SilkS")
		)
		(fp_line
			(start -0.7874 0.4064)
			(end -0.7874 -0.4064)
			(stroke
				(width 0.1524)
				(type default)
			)
			(layer "F.SilkS")
		)
		(fp_line
			(start -0.7874 -0.4064)
			(end 0.7874 -0.4064)
			(stroke
				(width 0.1524)
				(type default)
			)
			(layer "F.SilkS")
		)
		(fp_line
			(start 0.67945 0.3048)
			(end 0.120396 0.3048)
			(stroke
				(width 0.1)
				(type default)
			)
			(layer "F.Fab")
		)
		(fp_line
			(start 0.67945 -0.3048)
			(end 0.67945 0.3048)
			(stroke
				(width 0.1)
				(type default)
			)
			(layer "F.Fab")
		)
		(fp_line
			(start 0.12065 -0.2794)
			(end 0.12065 -0.3048)
			(stroke
				(width 0.1)
				(type default)
			)
			(layer "F.Fab")
		)
		(fp_line
			(start 0.12065 -0.3048)
			(end 0.67945 -0.3048)
			(stroke
				(width 0.1)
				(type default)
			)
			(layer "F.Fab")
		)
		(fp_line
			(start 0.120396 0.3048)
			(end 0.120396 0.2794)
			(stroke
				(width 0.1)
				(type default)
			)
			(layer "F.Fab")
		)
		(fp_line
			(start 0.120396 0.2794)
			(end -0.12065 0.2794)
			(stroke
				(width 0.1)
				(type default)
			)
			(layer "F.Fab")
		)
		(fp_line
			(start -0.12065 0.3048)
			(end -0.67945 0.3048)
			(stroke
				(width 0.1)
				(type default)
			)
			(layer "F.Fab")
		)
		(fp_line
			(start -0.12065 0.2794)
			(end -0.12065 0.3048)
			(stroke
				(width 0.1)
				(type default)
			)
			(layer "F.Fab")
		)
		(fp_line
			(start -0.12065 -0.2794)
			(end 0.12065 -0.2794)
			(stroke
				(width 0.1)
				(type default)
			)
			(layer "F.Fab")
		)
		(fp_line
			(start -0.12065 -0.305054)
			(end -0.12065 -0.2794)
			(stroke
				(width 0.1)
				(type default)
			)
			(layer "F.Fab")
		)
		(fp_line
			(start -0.67945 0.3048)
			(end -0.67945 -0.305054)
			(stroke
				(width 0.1)
				(type default)
			)
			(layer "F.Fab")
		)
		(fp_line
			(start -0.67945 -0.305054)
			(end -0.12065 -0.305054)
			(stroke
				(width 0.1)
				(type default)
			)
			(layer "F.Fab")
		)
		(pad "1" smd circle
			(at -0.40005 0 180)
			(size 0 0)
			(layers "F.Cu" "F.Mask" "F.Paste")
			(net "SMB_PCIE0_3V3AUX_SDA_R3")
		)
		(pad "2" smd circle
			(at 0.40005 0 180)
			(size 0 0)
			(layers "F.Cu" "F.Mask" "F.Paste")
			(net "SMB_SENSOR_M2_P1_3V3AUX_SDA")
		)
	)
	(footprint ""
		(layer "F.Cu")
		(at 413.766 -100.203 90)
		(property "Reference" "R8093"
			(at 0 0 90)
			(layer "F.SilkS")
			(hide yes)
			(effects
				(font
					(size 1.27 1.27)
				)
			)
		)
		(property "Value" ""
			(at 0 0 90)
			(layer "F.Fab")
			(effects
				(font
					(size 1.27 1.27)
				)
			)
		)
		(duplicate_pad_numbers_are_jumpers no)
		(fp_line
			(start 0.7874 -0.4064)
			(end 0.7874 0.4064)
			(stroke
				(width 0.1524)
				(type default)
			)
			(layer "F.SilkS")
		)
		(fp_line
			(start -0.7874 -0.4064)
			(end 0.7874 -0.4064)
			(stroke
				(width 0.1524)
				(type default)
			)
			(layer "F.SilkS")
		)
		(fp_line
			(start 0.7874 0.4064)
			(end -0.7874 0.4064)
			(stroke
				(width 0.1524)
				(type default)
			)
			(layer "F.SilkS")
		)
		(fp_line
			(start -0.7874 0.4064)
			(end -0.7874 -0.4064)
			(stroke
				(width 0.1524)
				(type default)
			)
			(layer "F.SilkS")
		)
		(fp_line
			(start -0.12065 -0.305054)
			(end -0.12065 -0.2794)
			(stroke
				(width 0.1)
				(type default)
			)
			(layer "F.Fab")
		)
		(fp_line
			(start -0.67945 -0.305054)
			(end -0.12065 -0.305054)
			(stroke
				(width 0.1)
				(type default)
			)
			(layer "F.Fab")
		)
		(fp_line
			(start 0.67945 -0.3048)
			(end 0.67945 0.3048)
			(stroke
				(width 0.1)
				(type default)
			)
			(layer "F.Fab")
		)
		(fp_line
			(start 0.12065 -0.3048)
			(end 0.67945 -0.3048)
			(stroke
				(width 0.1)
				(type default)
			)
			(layer "F.Fab")
		)
		(fp_line
			(start 0.12065 -0.2794)
			(end 0.12065 -0.3048)
			(stroke
				(width 0.1)
				(type default)
			)
			(layer "F.Fab")
		)
		(fp_line
			(start -0.12065 -0.2794)
			(end 0.12065 -0.2794)
			(stroke
				(width 0.1)
				(type default)
			)
			(layer "F.Fab")
		)
		(fp_line
			(start 0.120396 0.2794)
			(end -0.12065 0.2794)
			(stroke
				(width 0.1)
				(type default)
			)
			(layer "F.Fab")
		)
		(fp_line
			(start -0.12065 0.2794)
			(end -0.12065 0.3048)
			(stroke
				(width 0.1)
				(type default)
			)
			(layer "F.Fab")
		)
		(fp_line
			(start 0.67945 0.3048)
			(end 0.120396 0.3048)
			(stroke
				(width 0.1)
				(type default)
			)
			(layer "F.Fab")
		)
		(fp_line
			(start 0.120396 0.3048)
			(end 0.120396 0.2794)
			(stroke
				(width 0.1)
				(type default)
			)
			(layer "F.Fab")
		)
		(fp_line
			(start -0.12065 0.3048)
			(end -0.67945 0.3048)
			(stroke
				(width 0.1)
				(type default)
			)
			(layer "F.Fab")
		)
		(fp_line
			(start -0.67945 0.3048)
			(end -0.67945 -0.305054)
			(stroke
				(width 0.1)
				(type default)
			)
			(layer "F.Fab")
		)
		(pad "1" smd circle
			(at -0.40005 0 90)
			(size 0 0)
			(layers "F.Cu" "F.Mask" "F.Paste")
			(net "OCP_V3_1_P3V3_R1_PWRGD")
		)
		(pad "2" smd circle
			(at 0.40005 0 90)
			(size 0 0)
			(layers "F.Cu" "F.Mask" "F.Paste")
			(net "GND")
		)
	)
	(footprint ""
		(layer "F.Cu")
		(at 75.265534 -172.414184)
		(property "Reference" "PR202"
			(at 0 0 0)
			(layer "F.SilkS")
			(hide yes)
			(effects
				(font
					(size 1.27 1.27)
				)
			)
		)
		(property "Value" ""
			(at 0 0 0)
			(layer "F.Fab")
			(effects
				(font
					(size 1.27 1.27)
				)
			)
		)
		(duplicate_pad_numbers_are_jumpers no)
		(fp_line
			(start -0.7874 -0.4064)
			(end 0.7874 -0.4064)
			(stroke
				(width 0.1524)
				(type default)
			)
			(layer "F.SilkS")
		)
		(fp_line
			(start -0.7874 0.4064)
			(end -0.7874 -0.4064)
			(stroke
				(width 0.1524)
				(type default)
			)
			(layer "F.SilkS")
		)
		(fp_line
			(start 0.7874 -0.4064)
			(end 0.7874 0.4064)
			(stroke
				(width 0.1524)
				(type default)
			)
			(layer "F.SilkS")
		)
		(fp_line
			(start 0.7874 0.4064)
			(end -0.7874 0.4064)
			(stroke
				(width 0.1524)
				(type default)
			)
			(layer "F.SilkS")
		)
		(fp_line
			(start -0.67945 -0.305054)
			(end -0.12065 -0.305054)
			(stroke
				(width 0.1)
				(type default)
			)
			(layer "F.Fab")
		)
		(fp_line
			(start -0.67945 0.3048)
			(end -0.67945 -0.305054)
			(stroke
				(width 0.1)
				(type default)
			)
			(layer "F.Fab")
		)
		(fp_line
			(start -0.12065 -0.305054)
			(end -0.12065 -0.2794)
			(stroke
				(width 0.1)
				(type default)
			)
			(layer "F.Fab")
		)
		(fp_line
			(start -0.12065 -0.2794)
			(end 0.12065 -0.2794)
			(stroke
				(width 0.1)
				(type default)
			)
			(layer "F.Fab")
		)
		(fp_line
			(start -0.12065 0.2794)
			(end -0.12065 0.3048)
			(stroke
				(width 0.1)
				(type default)
			)
			(layer "F.Fab")
		)
		(fp_line
			(start -0.12065 0.3048)
			(end -0.67945 0.3048)
			(stroke
				(width 0.1)
				(type default)
			)
			(layer "F.Fab")
		)
		(fp_line
			(start 0.120396 0.2794)
			(end -0.12065 0.2794)
			(stroke
				(width 0.1)
				(type default)
			)
			(layer "F.Fab")
		)
		(fp_line
			(start 0.120396 0.3048)
			(end 0.120396 0.2794)
			(stroke
				(width 0.1)
				(type default)
			)
			(layer "F.Fab")
		)
		(fp_line
			(start 0.12065 -0.3048)
			(end 0.67945 -0.3048)
			(stroke
				(width 0.1)
				(type default)
			)
			(layer "F.Fab")
		)
		(fp_line
			(start 0.12065 -0.2794)
			(end 0.12065 -0.3048)
			(stroke
				(width 0.1)
				(type default)
			)
			(layer "F.Fab")
		)
		(fp_line
			(start 0.67945 -0.3048)
			(end 0.67945 0.3048)
			(stroke
				(width 0.1)
				(type default)
			)
			(layer "F.Fab")
		)
		(fp_line
			(start 0.67945 0.3048)
			(end 0.120396 0.3048)
			(stroke
				(width 0.1)
				(type default)
			)
			(layer "F.Fab")
		)
		(pad "1" smd circle
			(at -0.40005 0)
			(size 0 0)
			(layers "F.Cu" "F.Mask" "F.Paste")
			(net "GND")
		)
		(pad "2" smd circle
			(at 0.40005 0)
			(size 0 0)
			(layers "F.Cu" "F.Mask" "F.Paste")
			(net "PVDDCR_CPU0_P1_LSET5")
		)
	)
	(footprint ""
		(layer "F.Cu")
		(at 278.006556 -436.223664 -90)
		(property "Reference" "C70"
			(at 0 0 270)
			(layer "F.SilkS")
			(hide yes)
			(effects
				(font
					(size 1.27 1.27)
				)
			)
		)
		(property "Value" ""
			(at 0 0 270)
			(layer "F.Fab")
			(effects
				(font
					(size 1.27 1.27)
				)
			)
		)
		(duplicate_pad_numbers_are_jumpers no)
		(fp_line
			(start -0.7874 0.4064)
			(end -0.7874 -0.4064)
			(stroke
				(width 0.1524)
				(type default)
			)
			(layer "F.SilkS")
		)
		(fp_line
			(start 0.7874 0.4064)
			(end -0.7874 0.4064)
			(stroke
				(width 0.1524)
				(type default)
			)
			(layer "F.SilkS")
		)
		(fp_line
			(start -0.7874 -0.4064)
			(end 0.7874 -0.4064)
			(stroke
				(width 0.1524)
				(type default)
			)
			(layer "F.SilkS")
		)
		(fp_line
			(start 0.7874 -0.4064)
			(end 0.7874 0.4064)
			(stroke
				(width 0.1524)
				(type default)
			)
			(layer "F.SilkS")
		)
		(fp_line
			(start -0.67945 0.3048)
			(end -0.67945 -0.305054)
			(stroke
				(width 0.1)
				(type default)
			)
			(layer "F.Fab")
		)
		(fp_line
			(start -0.12065 0.3048)
			(end -0.67945 0.3048)
			(stroke
				(width 0.1)
				(type default)
			)
			(layer "F.Fab")
		)
		(fp_line
			(start 0.120396 0.3048)
			(end 0.120396 0.2794)
			(stroke
				(width 0.1)
				(type default)
			)
			(layer "F.Fab")
		)
		(fp_line
			(start 0.67945 0.3048)
			(end 0.120396 0.3048)
			(stroke
				(width 0.1)
				(type default)
			)
			(layer "F.Fab")
		)
		(fp_line
			(start -0.12065 0.2794)
			(end -0.12065 0.3048)
			(stroke
				(width 0.1)
				(type default)
			)
			(layer "F.Fab")
		)
		(fp_line
			(start 0.120396 0.2794)
			(end -0.12065 0.2794)
			(stroke
				(width 0.1)
				(type default)
			)
			(layer "F.Fab")
		)
		(fp_line
			(start -0.12065 -0.2794)
			(end 0.12065 -0.2794)
			(stroke
				(width 0.1)
				(type default)
			)
			(layer "F.Fab")
		)
		(fp_line
			(start 0.12065 -0.2794)
			(end 0.12065 -0.3048)
			(stroke
				(width 0.1)
				(type default)
			)
			(layer "F.Fab")
		)
		(fp_line
			(start 0.12065 -0.3048)
			(end 0.67945 -0.3048)
			(stroke
				(width 0.1)
				(type default)
			)
			(layer "F.Fab")
		)
		(fp_line
			(start 0.67945 -0.3048)
			(end 0.67945 0.3048)
			(stroke
				(width 0.1)
				(type default)
			)
			(layer "F.Fab")
		)
		(fp_line
			(start -0.67945 -0.305054)
			(end -0.12065 -0.305054)
			(stroke
				(width 0.1)
				(type default)
			)
			(layer "F.Fab")
		)
		(fp_line
			(start -0.12065 -0.305054)
			(end -0.12065 -0.2794)
			(stroke
				(width 0.1)
				(type default)
			)
			(layer "F.Fab")
		)
		(pad "1" smd circle
			(at -0.40005 0 270)
			(size 0 0)
			(layers "F.Cu" "F.Mask" "F.Paste")
			(net "HPDB_HSC_PWRGD_ISO")
		)
		(pad "2" smd circle
			(at 0.40005 0 270)
			(size 0 0)
			(layers "F.Cu" "F.Mask" "F.Paste")
			(net "GND")
		)
	)
	(footprint ""
		(layer "F.Cu")
		(at 359.710736 -171.23029 -90)
		(property "Reference" "PR501"
			(at 0 0 270)
			(layer "F.SilkS")
			(hide yes)
			(effects
				(font
					(size 1.27 1.27)
				)
			)
		)
		(property "Value" ""
			(at 0 0 270)
			(layer "F.Fab")
			(effects
				(font
					(size 1.27 1.27)
				)
			)
		)
		(duplicate_pad_numbers_are_jumpers no)
		(fp_line
			(start -0.7874 0.4064)
			(end -0.7874 -0.4064)
			(stroke
				(width 0.1524)
				(type default)
			)
			(layer "F.SilkS")
		)
		(fp_line
			(start 0.7874 0.4064)
			(end -0.7874 0.4064)
			(stroke
				(width 0.1524)
				(type default)
			)
			(layer "F.SilkS")
		)
		(fp_line
			(start -0.7874 -0.4064)
			(end 0.7874 -0.4064)
			(stroke
				(width 0.1524)
				(type default)
			)
			(layer "F.SilkS")
		)
		(fp_line
			(start 0.7874 -0.4064)
			(end 0.7874 0.4064)
			(stroke
				(width 0.1524)
				(type default)
			)
			(layer "F.SilkS")
		)
		(fp_line
			(start -0.67945 0.3048)
			(end -0.67945 -0.305054)
			(stroke
				(width 0.1)
				(type default)
			)
			(layer "F.Fab")
		)
		(fp_line
			(start -0.12065 0.3048)
			(end -0.67945 0.3048)
			(stroke
				(width 0.1)
				(type default)
			)
			(layer "F.Fab")
		)
		(fp_line
			(start 0.120396 0.3048)
			(end 0.120396 0.2794)
			(stroke
				(width 0.1)
				(type default)
			)
			(layer "F.Fab")
		)
		(fp_line
			(start 0.67945 0.3048)
			(end 0.120396 0.3048)
			(stroke
				(width 0.1)
				(type default)
			)
			(layer "F.Fab")
		)
		(fp_line
			(start -0.12065 0.2794)
			(end -0.12065 0.3048)
			(stroke
				(width 0.1)
				(type default)
			)
			(layer "F.Fab")
		)
		(fp_line
			(start 0.120396 0.2794)
			(end -0.12065 0.2794)
			(stroke
				(width 0.1)
				(type default)
			)
			(layer "F.Fab")
		)
		(fp_line
			(start -0.12065 -0.2794)
			(end 0.12065 -0.2794)
			(stroke
				(width 0.1)
				(type default)
			)
			(layer "F.Fab")
		)
		(fp_line
			(start 0.12065 -0.2794)
			(end 0.12065 -0.3048)
			(stroke
				(width 0.1)
				(type default)
			)
			(layer "F.Fab")
		)
		(fp_line
			(start 0.12065 -0.3048)
			(end 0.67945 -0.3048)
			(stroke
				(width 0.1)
				(type default)
			)
			(layer "F.Fab")
		)
		(fp_line
			(start 0.67945 -0.3048)
			(end 0.67945 0.3048)
			(stroke
				(width 0.1)
				(type default)
			)
			(layer "F.Fab")
		)
		(fp_line
			(start -0.67945 -0.305054)
			(end -0.12065 -0.305054)
			(stroke
				(width 0.1)
				(type default)
			)
			(layer "F.Fab")
		)
		(fp_line
			(start -0.12065 -0.305054)
			(end -0.12065 -0.2794)
			(stroke
				(width 0.1)
				(type default)
			)
			(layer "F.Fab")
		)
		(pad "1" smd circle
			(at -0.40005 0 270)
			(size 0 0)
			(layers "F.Cu" "F.Mask" "F.Paste")
			(net "SW_PVDDCR_CPU0_P0_SW5_RC")
		)
		(pad "2" smd circle
			(at 0.40005 0 270)
			(size 0 0)
			(layers "F.Cu" "F.Mask" "F.Paste")
			(net "GND")
		)
	)
	(footprint ""
		(layer "F.Cu")
		(at 178.72456 -396.385542)
		(property "Reference" "PR3930"
			(at 0 0 0)
			(layer "F.SilkS")
			(hide yes)
			(effects
				(font
					(size 1.27 1.27)
				)
			)
		)
		(property "Value" ""
			(at 0 0 0)
			(layer "F.Fab")
			(effects
				(font
					(size 1.27 1.27)
				)
			)
		)
		(duplicate_pad_numbers_are_jumpers no)
		(fp_line
			(start -0.7874 -0.4064)
			(end 0.7874 -0.4064)
			(stroke
				(width 0.1524)
				(type default)
			)
			(layer "F.SilkS")
		)
		(fp_line
			(start -0.7874 0.4064)
			(end -0.7874 -0.4064)
			(stroke
				(width 0.1524)
				(type default)
			)
			(layer "F.SilkS")
		)
		(fp_line
			(start 0.7874 -0.4064)
			(end 0.7874 0.4064)
			(stroke
				(width 0.1524)
				(type default)
			)
			(layer "F.SilkS")
		)
		(fp_line
			(start 0.7874 0.4064)
			(end -0.7874 0.4064)
			(stroke
				(width 0.1524)
				(type default)
			)
			(layer "F.SilkS")
		)
		(fp_line
			(start -0.67945 -0.305054)
			(end -0.12065 -0.305054)
			(stroke
				(width 0.1)
				(type default)
			)
			(layer "F.Fab")
		)
		(fp_line
			(start -0.67945 0.3048)
			(end -0.67945 -0.305054)
			(stroke
				(width 0.1)
				(type default)
			)
			(layer "F.Fab")
		)
		(fp_line
			(start -0.12065 -0.305054)
			(end -0.12065 -0.2794)
			(stroke
				(width 0.1)
				(type default)
			)
			(layer "F.Fab")
		)
		(fp_line
			(start -0.12065 -0.2794)
			(end 0.12065 -0.2794)
			(stroke
				(width 0.1)
				(type default)
			)
			(layer "F.Fab")
		)
		(fp_line
			(start -0.12065 0.2794)
			(end -0.12065 0.3048)
			(stroke
				(width 0.1)
				(type default)
			)
			(layer "F.Fab")
		)
		(fp_line
			(start -0.12065 0.3048)
			(end -0.67945 0.3048)
			(stroke
				(width 0.1)
				(type default)
			)
			(layer "F.Fab")
		)
		(fp_line
			(start 0.120396 0.2794)
			(end -0.12065 0.2794)
			(stroke
				(width 0.1)
				(type default)
			)
			(layer "F.Fab")
		)
		(fp_line
			(start 0.120396 0.3048)
			(end 0.120396 0.2794)
			(stroke
				(width 0.1)
				(type default)
			)
			(layer "F.Fab")
		)
		(fp_line
			(start 0.12065 -0.3048)
			(end 0.67945 -0.3048)
			(stroke
				(width 0.1)
				(type default)
			)
			(layer "F.Fab")
		)
		(fp_line
			(start 0.12065 -0.2794)
			(end 0.12065 -0.3048)
			(stroke
				(width 0.1)
				(type default)
			)
			(layer "F.Fab")
		)
		(fp_line
			(start 0.67945 -0.3048)
			(end 0.67945 0.3048)
			(stroke
				(width 0.1)
				(type default)
			)
			(layer "F.Fab")
		)
		(fp_line
			(start 0.67945 0.3048)
			(end 0.120396 0.3048)
			(stroke
				(width 0.1)
				(type default)
			)
			(layer "F.Fab")
		)
		(pad "1" smd circle
			(at -0.40005 0)
			(size 0 0)
			(layers "F.Cu" "F.Mask" "F.Paste")
			(net "AGND_HSC")
		)
		(pad "2" smd circle
			(at 0.40005 0)
			(size 0 0)
			(layers "F.Cu" "F.Mask" "F.Paste")
			(net "HSC_ADDR")
		)
	)
	(footprint ""
		(layer "F.Cu")
		(at 449.443602 -426.255688)
		(property "Reference" "PC6602"
			(at 0 0 0)
			(layer "F.SilkS")
			(hide yes)
			(effects
				(font
					(size 1.27 1.27)
				)
			)
		)
		(property "Value" ""
			(at 0 0 0)
			(layer "F.Fab")
			(effects
				(font
					(size 1.27 1.27)
				)
			)
		)
		(duplicate_pad_numbers_are_jumpers no)
		(fp_line
			(start -0.7874 -0.4064)
			(end 0.7874 -0.4064)
			(stroke
				(width 0.1524)
				(type default)
			)
			(layer "F.SilkS")
		)
		(fp_line
			(start -0.7874 0.4064)
			(end -0.7874 -0.4064)
			(stroke
				(width 0.1524)
				(type default)
			)
			(layer "F.SilkS")
		)
		(fp_line
			(start 0.7874 -0.4064)
			(end 0.7874 0.4064)
			(stroke
				(width 0.1524)
				(type default)
			)
			(layer "F.SilkS")
		)
		(fp_line
			(start 0.7874 0.4064)
			(end -0.7874 0.4064)
			(stroke
				(width 0.1524)
				(type default)
			)
			(layer "F.SilkS")
		)
		(fp_line
			(start -0.67945 -0.305054)
			(end -0.12065 -0.305054)
			(stroke
				(width 0.1)
				(type default)
			)
			(layer "F.Fab")
		)
		(fp_line
			(start -0.67945 0.3048)
			(end -0.67945 -0.305054)
			(stroke
				(width 0.1)
				(type default)
			)
			(layer "F.Fab")
		)
		(fp_line
			(start -0.12065 -0.305054)
			(end -0.12065 -0.2794)
			(stroke
				(width 0.1)
				(type default)
			)
			(layer "F.Fab")
		)
		(fp_line
			(start -0.12065 -0.2794)
			(end 0.12065 -0.2794)
			(stroke
				(width 0.1)
				(type default)
			)
			(layer "F.Fab")
		)
		(fp_line
			(start -0.12065 0.2794)
			(end -0.12065 0.3048)
			(stroke
				(width 0.1)
				(type default)
			)
			(layer "F.Fab")
		)
		(fp_line
			(start -0.12065 0.3048)
			(end -0.67945 0.3048)
			(stroke
				(width 0.1)
				(type default)
			)
			(layer "F.Fab")
		)
		(fp_line
			(start 0.120396 0.2794)
			(end -0.12065 0.2794)
			(stroke
				(width 0.1)
				(type default)
			)
			(layer "F.Fab")
		)
		(fp_line
			(start 0.120396 0.3048)
			(end 0.120396 0.2794)
			(stroke
				(width 0.1)
				(type default)
			)
			(layer "F.Fab")
		)
		(fp_line
			(start 0.12065 -0.3048)
			(end 0.67945 -0.3048)
			(stroke
				(width 0.1)
				(type default)
			)
			(layer "F.Fab")
		)
		(fp_line
			(start 0.12065 -0.2794)
			(end 0.12065 -0.3048)
			(stroke
				(width 0.1)
				(type default)
			)
			(layer "F.Fab")
		)
		(fp_line
			(start 0.67945 -0.3048)
			(end 0.67945 0.3048)
			(stroke
				(width 0.1)
				(type default)
			)
			(layer "F.Fab")
		)
		(fp_line
			(start 0.67945 0.3048)
			(end 0.120396 0.3048)
			(stroke
				(width 0.1)
				(type default)
			)
			(layer "F.Fab")
		)
		(pad "1" smd circle
			(at -0.40005 0)
			(size 0 0)
			(layers "F.Cu" "F.Mask" "F.Paste")
			(net "P0V9_RETIMER_CPU0_VINSEN")
		)
		(pad "2" smd circle
			(at 0.40005 0)
			(size 0 0)
			(layers "F.Cu" "F.Mask" "F.Paste")
			(net "GND")
		)
	)
	(footprint ""
		(layer "F.Cu")
		(at 442.18352 -438.397396)
		(property "Reference" "Q136"
			(at -1.4224 -1.768348 0)
			(unlocked yes)
			(layer "F.SilkS")
			(effects
				(font
					(size 0.7874 0.5842)
					(thickness 0.1524)
				)
				(justify left)
			)
		)
		(property "Value" ""
			(at 0 0 0)
			(layer "F.Fab")
			(effects
				(font
					(size 1.27 1.27)
				)
			)
		)
		(duplicate_pad_numbers_are_jumpers no)
		(fp_line
			(start -1.332738 -1.100074)
			(end -0.4826 -1.100074)
			(stroke
				(width 0.1524)
				(type default)
			)
			(layer "F.SilkS")
		)
		(fp_line
			(start -1.332738 1.100074)
			(end -1.332738 -1.100074)
			(stroke
				(width 0.1524)
				(type default)
			)
			(layer "F.SilkS")
		)
		(fp_line
			(start -0.4826 -1.100074)
			(end 0 -0.541274)
			(stroke
				(width 0.1524)
				(type default)
			)
			(layer "F.SilkS")
		)
		(fp_line
			(start 0 -0.541274)
			(end 0.4826 -1.100074)
			(stroke
				(width 0.1524)
				(type default)
			)
			(layer "F.SilkS")
		)
		(fp_line
			(start 0.4826 -1.100074)
			(end 1.332738 -1.100074)
			(stroke
				(width 0.1524)
				(type default)
			)
			(layer "F.SilkS")
		)
		(fp_line
			(start 1.332738 -1.100074)
			(end 1.332738 1.100074)
			(stroke
				(width 0.1524)
				(type default)
			)
			(layer "F.SilkS")
		)
		(fp_line
			(start 1.332738 1.100074)
			(end -1.332738 1.100074)
			(stroke
				(width 0.1524)
				(type default)
			)
			(layer "F.SilkS")
		)
		(fp_poly
			(pts
				(xy -1.467104 -1.284986) (xy -2.16916 -0.933958) (xy -2.16916 -1.636014)
			)
			(stroke
				(width 0)
				(type default)
			)
			(fill yes)
			(layer "F.SilkS")
		)
		(fp_line
			(start -0.674878 -1.100074)
			(end 0.674878 -1.100074)
			(stroke
				(width 0.1)
				(type default)
			)
			(layer "F.Fab")
		)
		(fp_line
			(start -0.674878 1.100074)
			(end -0.674878 -1.100074)
			(stroke
				(width 0.1)
				(type default)
			)
			(layer "F.Fab")
		)
		(fp_line
			(start 0.674878 -1.100074)
			(end 0.674878 1.100074)
			(stroke
				(width 0.1)
				(type default)
			)
			(layer "F.Fab")
		)
		(fp_line
			(start 0.674878 1.100074)
			(end -0.674878 1.100074)
			(stroke
				(width 0.1)
				(type default)
			)
			(layer "F.Fab")
		)
		(fp_poly
			(pts
				(xy -2.2352 -0.298958) (xy -2.2352 -1.001014) (xy -1.533144 -0.649986)
			)
			(stroke
				(width 0)
				(type default)
			)
			(fill yes)
			(layer "F.Fab")
		)
		(pad "1" smd rect
			(at -0.94996 -0.649986 90)
			(size 0.4318 0.508)
			(layers "F.Cu" "F.Mask" "F.Paste")
			(net "GND")
		)
		(pad "2" smd rect
			(at -0.94996 0 90)
			(size 0.4318 0.508)
			(layers "F.Cu" "F.Mask" "F.Paste")
			(net "GPU_3V3IO_RSVD4")
		)
		(pad "3" smd rect
			(at -0.94996 0.649986 90)
			(size 0.4318 0.508)
			(layers "F.Cu" "F.Mask" "F.Paste")
			(net "GPU_3V3IO_RSVD4_ISO")
		)
		(pad "4" smd rect
			(at 0.94996 0.649986 90)
			(size 0.4318 0.508)
			(layers "F.Cu" "F.Mask" "F.Paste")
			(net "GND")
		)
		(pad "5" smd rect
			(at 0.94996 0 90)
			(size 0.4318 0.508)
			(layers "F.Cu" "F.Mask" "F.Paste")
			(net "GPU_3V3IO_RSVD4_N")
		)
		(pad "6" smd rect
			(at 0.94996 -0.649986 90)
			(size 0.4318 0.508)
			(layers "F.Cu" "F.Mask" "F.Paste")
			(net "GPU_3V3IO_RSVD4_N")
		)
	)
	(footprint ""
		(layer "F.Cu")
		(at 456.131676 -401.709128 -90)
		(property "Reference" "PC6584"
			(at 0 0 270)
			(layer "F.SilkS")
			(hide yes)
			(effects
				(font
					(size 1.27 1.27)
				)
			)
		)
		(property "Value" ""
			(at 0 0 270)
			(layer "F.Fab")
			(effects
				(font
					(size 1.27 1.27)
				)
			)
		)
		(duplicate_pad_numbers_are_jumpers no)
		(fp_line
			(start -0.7874 0.4064)
			(end -0.7874 -0.4064)
			(stroke
				(width 0.1524)
				(type default)
			)
			(layer "F.SilkS")
		)
		(fp_line
			(start 0.7874 0.4064)
			(end -0.7874 0.4064)
			(stroke
				(width 0.1524)
				(type default)
			)
			(layer "F.SilkS")
		)
		(fp_line
			(start -0.7874 -0.4064)
			(end 0.7874 -0.4064)
			(stroke
				(width 0.1524)
				(type default)
			)
			(layer "F.SilkS")
		)
		(fp_line
			(start 0.7874 -0.4064)
			(end 0.7874 0.4064)
			(stroke
				(width 0.1524)
				(type default)
			)
			(layer "F.SilkS")
		)
		(fp_line
			(start -0.67945 0.3048)
			(end -0.67945 -0.305054)
			(stroke
				(width 0.1)
				(type default)
			)
			(layer "F.Fab")
		)
		(fp_line
			(start -0.12065 0.3048)
			(end -0.67945 0.3048)
			(stroke
				(width 0.1)
				(type default)
			)
			(layer "F.Fab")
		)
		(fp_line
			(start 0.120396 0.3048)
			(end 0.120396 0.2794)
			(stroke
				(width 0.1)
				(type default)
			)
			(layer "F.Fab")
		)
		(fp_line
			(start 0.67945 0.3048)
			(end 0.120396 0.3048)
			(stroke
				(width 0.1)
				(type default)
			)
			(layer "F.Fab")
		)
		(fp_line
			(start -0.12065 0.2794)
			(end -0.12065 0.3048)
			(stroke
				(width 0.1)
				(type default)
			)
			(layer "F.Fab")
		)
		(fp_line
			(start 0.120396 0.2794)
			(end -0.12065 0.2794)
			(stroke
				(width 0.1)
				(type default)
			)
			(layer "F.Fab")
		)
		(fp_line
			(start -0.12065 -0.2794)
			(end 0.12065 -0.2794)
			(stroke
				(width 0.1)
				(type default)
			)
			(layer "F.Fab")
		)
		(fp_line
			(start 0.12065 -0.2794)
			(end 0.12065 -0.3048)
			(stroke
				(width 0.1)
				(type default)
			)
			(layer "F.Fab")
		)
		(fp_line
			(start 0.12065 -0.3048)
			(end 0.67945 -0.3048)
			(stroke
				(width 0.1)
				(type default)
			)
			(layer "F.Fab")
		)
		(fp_line
			(start 0.67945 -0.3048)
			(end 0.67945 0.3048)
			(stroke
				(width 0.1)
				(type default)
			)
			(layer "F.Fab")
		)
		(fp_line
			(start -0.67945 -0.305054)
			(end -0.12065 -0.305054)
			(stroke
				(width 0.1)
				(type default)
			)
			(layer "F.Fab")
		)
		(fp_line
			(start -0.12065 -0.305054)
			(end -0.12065 -0.2794)
			(stroke
				(width 0.1)
				(type default)
			)
			(layer "F.Fab")
		)
		(pad "1" smd circle
			(at -0.40005 0 270)
			(size 0 0)
			(layers "F.Cu" "F.Mask" "F.Paste")
			(net "SW_P0V9_RETIMER_CPU0_BOOT2_RC")
		)
		(pad "2" smd circle
			(at 0.40005 0 270)
			(size 0 0)
			(layers "F.Cu" "F.Mask" "F.Paste")
			(net "SW_P0V9_RETIMER_CPU0_PH2")
		)
	)
	(footprint ""
		(layer "F.Cu")
		(at 190.119 -137.632948 -90)
		(property "Reference" "R1447"
			(at 0 0 270)
			(layer "F.SilkS")
			(hide yes)
			(effects
				(font
					(size 1.27 1.27)
				)
			)
		)
		(property "Value" ""
			(at 0 0 270)
			(layer "F.Fab")
			(effects
				(font
					(size 1.27 1.27)
				)
			)
		)
		(duplicate_pad_numbers_are_jumpers no)
		(fp_line
			(start -0.7874 0.4064)
			(end -0.7874 -0.4064)
			(stroke
				(width 0.1524)
				(type default)
			)
			(layer "F.SilkS")
		)
		(fp_line
			(start 0.7874 0.4064)
			(end -0.7874 0.4064)
			(stroke
				(width 0.1524)
				(type default)
			)
			(layer "F.SilkS")
		)
		(fp_line
			(start -0.7874 -0.4064)
			(end 0.7874 -0.4064)
			(stroke
				(width 0.1524)
				(type default)
			)
			(layer "F.SilkS")
		)
		(fp_line
			(start 0.7874 -0.4064)
			(end 0.7874 0.4064)
			(stroke
				(width 0.1524)
				(type default)
			)
			(layer "F.SilkS")
		)
		(fp_line
			(start -0.67945 0.3048)
			(end -0.67945 -0.305054)
			(stroke
				(width 0.1)
				(type default)
			)
			(layer "F.Fab")
		)
		(fp_line
			(start -0.12065 0.3048)
			(end -0.67945 0.3048)
			(stroke
				(width 0.1)
				(type default)
			)
			(layer "F.Fab")
		)
		(fp_line
			(start 0.120396 0.3048)
			(end 0.120396 0.2794)
			(stroke
				(width 0.1)
				(type default)
			)
			(layer "F.Fab")
		)
		(fp_line
			(start 0.67945 0.3048)
			(end 0.120396 0.3048)
			(stroke
				(width 0.1)
				(type default)
			)
			(layer "F.Fab")
		)
		(fp_line
			(start -0.12065 0.2794)
			(end -0.12065 0.3048)
			(stroke
				(width 0.1)
				(type default)
			)
			(layer "F.Fab")
		)
		(fp_line
			(start 0.120396 0.2794)
			(end -0.12065 0.2794)
			(stroke
				(width 0.1)
				(type default)
			)
			(layer "F.Fab")
		)
		(fp_line
			(start -0.12065 -0.2794)
			(end 0.12065 -0.2794)
			(stroke
				(width 0.1)
				(type default)
			)
			(layer "F.Fab")
		)
		(fp_line
			(start 0.12065 -0.2794)
			(end 0.12065 -0.3048)
			(stroke
				(width 0.1)
				(type default)
			)
			(layer "F.Fab")
		)
		(fp_line
			(start 0.12065 -0.3048)
			(end 0.67945 -0.3048)
			(stroke
				(width 0.1)
				(type default)
			)
			(layer "F.Fab")
		)
		(fp_line
			(start 0.67945 -0.3048)
			(end 0.67945 0.3048)
			(stroke
				(width 0.1)
				(type default)
			)
			(layer "F.Fab")
		)
		(fp_line
			(start -0.67945 -0.305054)
			(end -0.12065 -0.305054)
			(stroke
				(width 0.1)
				(type default)
			)
			(layer "F.Fab")
		)
		(fp_line
			(start -0.12065 -0.305054)
			(end -0.12065 -0.2794)
			(stroke
				(width 0.1)
				(type default)
			)
			(layer "F.Fab")
		)
		(pad "1" smd circle
			(at -0.40005 0 270)
			(size 0 0)
			(layers "F.Cu" "F.Mask" "F.Paste")
			(net "SMB_CPU_5_SCL")
		)
		(pad "2" smd circle
			(at 0.40005 0 270)
			(size 0 0)
			(layers "F.Cu" "F.Mask" "F.Paste")
			(net "SMB_CPU_5_R1_SCL")
		)
	)
	(footprint ""
		(layer "F.Cu")
		(at 336.172556 -137.25525)
		(property "Reference" "PC227"
			(at 0 0 0)
			(layer "F.SilkS")
			(hide yes)
			(effects
				(font
					(size 1.27 1.27)
				)
			)
		)
		(property "Value" ""
			(at 0 0 0)
			(layer "F.Fab")
			(effects
				(font
					(size 1.27 1.27)
				)
			)
		)
		(duplicate_pad_numbers_are_jumpers no)
		(fp_line
			(start -1.524 -0.762)
			(end 1.524 -0.762)
			(stroke
				(width 0.1524)
				(type default)
			)
			(layer "F.SilkS")
		)
		(fp_line
			(start -1.524 0.762)
			(end -1.524 -0.762)
			(stroke
				(width 0.1524)
				(type default)
			)
			(layer "F.SilkS")
		)
		(fp_line
			(start 1.524 -0.762)
			(end 1.524 0.762)
			(stroke
				(width 0.1524)
				(type default)
			)
			(layer "F.SilkS")
		)
		(fp_line
			(start 1.524 0.762)
			(end -1.524 0.762)
			(stroke
				(width 0.1524)
				(type default)
			)
			(layer "F.SilkS")
		)
		(fp_line
			(start -1.1049 -0.724916)
			(end -1.1049 0.724916)
			(stroke
				(width 0.1)
				(type default)
			)
			(layer "F.Fab")
		)
		(fp_line
			(start -1.1049 0.724916)
			(end 1.1049 0.724916)
			(stroke
				(width 0.1)
				(type default)
			)
			(layer "F.Fab")
		)
		(fp_line
			(start 1.1049 -0.724916)
			(end -1.1049 -0.724916)
			(stroke
				(width 0.1)
				(type default)
			)
			(layer "F.Fab")
		)
		(fp_line
			(start 1.1049 0.724916)
			(end 1.1049 -0.724916)
			(stroke
				(width 0.1)
				(type default)
			)
			(layer "F.Fab")
		)
		(pad "1" smd rect
			(at -0.889 0 180)
			(size 1.016 1.27)
			(layers "F.Cu" "F.Mask" "F.Paste")
			(net "SW_P12V_AUX_PVDD18_S5_P0_FLT")
		)
		(pad "2" smd rect
			(at 0.889 0 180)
			(size 1.016 1.27)
			(layers "F.Cu" "F.Mask" "F.Paste")
			(net "GND")
		)
	)
	(footprint ""
		(layer "F.Cu")
		(at 175.11776 -92.685616 90)
		(property "Reference" "R6743"
			(at 0 0 90)
			(layer "F.SilkS")
			(hide yes)
			(effects
				(font
					(size 1.27 1.27)
				)
			)
		)
		(property "Value" ""
			(at 0 0 90)
			(layer "F.Fab")
			(effects
				(font
					(size 1.27 1.27)
				)
			)
		)
		(duplicate_pad_numbers_are_jumpers no)
		(fp_line
			(start 0.7874 -0.4064)
			(end 0.7874 0.4064)
			(stroke
				(width 0.1524)
				(type default)
			)
			(layer "F.SilkS")
		)
		(fp_line
			(start -0.7874 -0.4064)
			(end 0.7874 -0.4064)
			(stroke
				(width 0.1524)
				(type default)
			)
			(layer "F.SilkS")
		)
		(fp_line
			(start 0.7874 0.4064)
			(end -0.7874 0.4064)
			(stroke
				(width 0.1524)
				(type default)
			)
			(layer "F.SilkS")
		)
		(fp_line
			(start -0.7874 0.4064)
			(end -0.7874 -0.4064)
			(stroke
				(width 0.1524)
				(type default)
			)
			(layer "F.SilkS")
		)
		(fp_line
			(start -0.12065 -0.305054)
			(end -0.12065 -0.2794)
			(stroke
				(width 0.1)
				(type default)
			)
			(layer "F.Fab")
		)
		(fp_line
			(start -0.67945 -0.305054)
			(end -0.12065 -0.305054)
			(stroke
				(width 0.1)
				(type default)
			)
			(layer "F.Fab")
		)
		(fp_line
			(start 0.67945 -0.3048)
			(end 0.67945 0.3048)
			(stroke
				(width 0.1)
				(type default)
			)
			(layer "F.Fab")
		)
		(fp_line
			(start 0.12065 -0.3048)
			(end 0.67945 -0.3048)
			(stroke
				(width 0.1)
				(type default)
			)
			(layer "F.Fab")
		)
		(fp_line
			(start 0.12065 -0.2794)
			(end 0.12065 -0.3048)
			(stroke
				(width 0.1)
				(type default)
			)
			(layer "F.Fab")
		)
		(fp_line
			(start -0.12065 -0.2794)
			(end 0.12065 -0.2794)
			(stroke
				(width 0.1)
				(type default)
			)
			(layer "F.Fab")
		)
		(fp_line
			(start 0.120396 0.2794)
			(end -0.12065 0.2794)
			(stroke
				(width 0.1)
				(type default)
			)
			(layer "F.Fab")
		)
		(fp_line
			(start -0.12065 0.2794)
			(end -0.12065 0.3048)
			(stroke
				(width 0.1)
				(type default)
			)
			(layer "F.Fab")
		)
		(fp_line
			(start 0.67945 0.3048)
			(end 0.120396 0.3048)
			(stroke
				(width 0.1)
				(type default)
			)
			(layer "F.Fab")
		)
		(fp_line
			(start 0.120396 0.3048)
			(end 0.120396 0.2794)
			(stroke
				(width 0.1)
				(type default)
			)
			(layer "F.Fab")
		)
		(fp_line
			(start -0.12065 0.3048)
			(end -0.67945 0.3048)
			(stroke
				(width 0.1)
				(type default)
			)
			(layer "F.Fab")
		)
		(fp_line
			(start -0.67945 0.3048)
			(end -0.67945 -0.305054)
			(stroke
				(width 0.1)
				(type default)
			)
			(layer "F.Fab")
		)
		(pad "1" smd circle
			(at -0.40005 0 90)
			(size 0 0)
			(layers "F.Cu" "F.Mask" "F.Paste")
			(net "P1V8_AUX")
		)
		(pad "2" smd circle
			(at 0.40005 0 90)
			(size 0 0)
			(layers "F.Cu" "F.Mask" "F.Paste")
			(net "RT_BOARD_ID_ID0")
		)
	)
	(footprint ""
		(layer "F.Cu")
		(at 225.171 -82.804)
		(property "Reference" "R8100"
			(at 0 0 0)
			(layer "F.SilkS")
			(hide yes)
			(effects
				(font
					(size 1.27 1.27)
				)
			)
		)
		(property "Value" ""
			(at 0 0 0)
			(layer "F.Fab")
			(effects
				(font
					(size 1.27 1.27)
				)
			)
		)
		(duplicate_pad_numbers_are_jumpers no)
		(fp_line
			(start -0.7874 -0.4064)
			(end 0.7874 -0.4064)
			(stroke
				(width 0.1524)
				(type default)
			)
			(layer "F.SilkS")
		)
		(fp_line
			(start -0.7874 0.4064)
			(end -0.7874 -0.4064)
			(stroke
				(width 0.1524)
				(type default)
			)
			(layer "F.SilkS")
		)
		(fp_line
			(start 0.7874 -0.4064)
			(end 0.7874 0.4064)
			(stroke
				(width 0.1524)
				(type default)
			)
			(layer "F.SilkS")
		)
		(fp_line
			(start 0.7874 0.4064)
			(end -0.7874 0.4064)
			(stroke
				(width 0.1524)
				(type default)
			)
			(layer "F.SilkS")
		)
		(fp_line
			(start -0.67945 -0.305054)
			(end -0.12065 -0.305054)
			(stroke
				(width 0.1)
				(type default)
			)
			(layer "F.Fab")
		)
		(fp_line
			(start -0.67945 0.3048)
			(end -0.67945 -0.305054)
			(stroke
				(width 0.1)
				(type default)
			)
			(layer "F.Fab")
		)
		(fp_line
			(start -0.12065 -0.305054)
			(end -0.12065 -0.2794)
			(stroke
				(width 0.1)
				(type default)
			)
			(layer "F.Fab")
		)
		(fp_line
			(start -0.12065 -0.2794)
			(end 0.12065 -0.2794)
			(stroke
				(width 0.1)
				(type default)
			)
			(layer "F.Fab")
		)
		(fp_line
			(start -0.12065 0.2794)
			(end -0.12065 0.3048)
			(stroke
				(width 0.1)
				(type default)
			)
			(layer "F.Fab")
		)
		(fp_line
			(start -0.12065 0.3048)
			(end -0.67945 0.3048)
			(stroke
				(width 0.1)
				(type default)
			)
			(layer "F.Fab")
		)
		(fp_line
			(start 0.120396 0.2794)
			(end -0.12065 0.2794)
			(stroke
				(width 0.1)
				(type default)
			)
			(layer "F.Fab")
		)
		(fp_line
			(start 0.120396 0.3048)
			(end 0.120396 0.2794)
			(stroke
				(width 0.1)
				(type default)
			)
			(layer "F.Fab")
		)
		(fp_line
			(start 0.12065 -0.3048)
			(end 0.67945 -0.3048)
			(stroke
				(width 0.1)
				(type default)
			)
			(layer "F.Fab")
		)
		(fp_line
			(start 0.12065 -0.2794)
			(end 0.12065 -0.3048)
			(stroke
				(width 0.1)
				(type default)
			)
			(layer "F.Fab")
		)
		(fp_line
			(start 0.67945 -0.3048)
			(end 0.67945 0.3048)
			(stroke
				(width 0.1)
				(type default)
			)
			(layer "F.Fab")
		)
		(fp_line
			(start 0.67945 0.3048)
			(end 0.120396 0.3048)
			(stroke
				(width 0.1)
				(type default)
			)
			(layer "F.Fab")
		)
		(pad "1" smd circle
			(at -0.40005 0)
			(size 0 0)
			(layers "F.Cu" "F.Mask" "F.Paste")
			(net "P3V3_E1S_PWRGD_0_R1")
		)
		(pad "2" smd circle
			(at 0.40005 0)
			(size 0 0)
			(layers "F.Cu" "F.Mask" "F.Paste")
			(net "P3V3_E1S_PWRGD_0_R")
		)
	)
	(footprint ""
		(layer "F.Cu")
		(at 38.443662 -429.790098 90)
		(property "Reference" "R4537"
			(at 0 0 90)
			(layer "F.SilkS")
			(hide yes)
			(effects
				(font
					(size 1.27 1.27)
				)
			)
		)
		(property "Value" ""
			(at 0 0 90)
			(layer "F.Fab")
			(effects
				(font
					(size 1.27 1.27)
				)
			)
		)
		(duplicate_pad_numbers_are_jumpers no)
		(fp_line
			(start 0.7874 -0.4064)
			(end 0.7874 0.4064)
			(stroke
				(width 0.1524)
				(type default)
			)
			(layer "F.SilkS")
		)
		(fp_line
			(start -0.7874 -0.4064)
			(end 0.7874 -0.4064)
			(stroke
				(width 0.1524)
				(type default)
			)
			(layer "F.SilkS")
		)
		(fp_line
			(start 0.7874 0.4064)
			(end -0.7874 0.4064)
			(stroke
				(width 0.1524)
				(type default)
			)
			(layer "F.SilkS")
		)
		(fp_line
			(start -0.7874 0.4064)
			(end -0.7874 -0.4064)
			(stroke
				(width 0.1524)
				(type default)
			)
			(layer "F.SilkS")
		)
		(fp_line
			(start -0.12065 -0.305054)
			(end -0.12065 -0.2794)
			(stroke
				(width 0.1)
				(type default)
			)
			(layer "F.Fab")
		)
		(fp_line
			(start -0.67945 -0.305054)
			(end -0.12065 -0.305054)
			(stroke
				(width 0.1)
				(type default)
			)
			(layer "F.Fab")
		)
		(fp_line
			(start 0.67945 -0.3048)
			(end 0.67945 0.3048)
			(stroke
				(width 0.1)
				(type default)
			)
			(layer "F.Fab")
		)
		(fp_line
			(start 0.12065 -0.3048)
			(end 0.67945 -0.3048)
			(stroke
				(width 0.1)
				(type default)
			)
			(layer "F.Fab")
		)
		(fp_line
			(start 0.12065 -0.2794)
			(end 0.12065 -0.3048)
			(stroke
				(width 0.1)
				(type default)
			)
			(layer "F.Fab")
		)
		(fp_line
			(start -0.12065 -0.2794)
			(end 0.12065 -0.2794)
			(stroke
				(width 0.1)
				(type default)
			)
			(layer "F.Fab")
		)
		(fp_line
			(start 0.120396 0.2794)
			(end -0.12065 0.2794)
			(stroke
				(width 0.1)
				(type default)
			)
			(layer "F.Fab")
		)
		(fp_line
			(start -0.12065 0.2794)
			(end -0.12065 0.3048)
			(stroke
				(width 0.1)
				(type default)
			)
			(layer "F.Fab")
		)
		(fp_line
			(start 0.67945 0.3048)
			(end 0.120396 0.3048)
			(stroke
				(width 0.1)
				(type default)
			)
			(layer "F.Fab")
		)
		(fp_line
			(start 0.120396 0.3048)
			(end 0.120396 0.2794)
			(stroke
				(width 0.1)
				(type default)
			)
			(layer "F.Fab")
		)
		(fp_line
			(start -0.12065 0.3048)
			(end -0.67945 0.3048)
			(stroke
				(width 0.1)
				(type default)
			)
			(layer "F.Fab")
		)
		(fp_line
			(start -0.67945 0.3048)
			(end -0.67945 -0.305054)
			(stroke
				(width 0.1)
				(type default)
			)
			(layer "F.Fab")
		)
		(pad "1" smd circle
			(at -0.40005 0 90)
			(size 0 0)
			(layers "F.Cu" "F.Mask" "F.Paste")
			(net "FM_P2E_EN_N")
		)
		(pad "2" smd circle
			(at 0.40005 0 90)
			(size 0 0)
			(layers "F.Cu" "F.Mask" "F.Paste")
			(net "CLK_GEN2_GPU_FPGA_OE_OR_N")
		)
	)
	(footprint ""
		(layer "F.Cu")
		(at 105.960164 -261.255256)
		(property "Reference" "C3911"
			(at 0 0 0)
			(layer "F.SilkS")
			(hide yes)
			(effects
				(font
					(size 1.27 1.27)
				)
			)
		)
		(property "Value" ""
			(at 0 0 0)
			(layer "F.Fab")
			(effects
				(font
					(size 1.27 1.27)
				)
			)
		)
		(duplicate_pad_numbers_are_jumpers no)
		(fp_line
			(start -0.7874 -0.4064)
			(end 0.7874 -0.4064)
			(stroke
				(width 0.1524)
				(type default)
			)
			(layer "F.SilkS")
		)
		(fp_line
			(start -0.7874 0.4064)
			(end -0.7874 -0.4064)
			(stroke
				(width 0.1524)
				(type default)
			)
			(layer "F.SilkS")
		)
		(fp_line
			(start 0.7874 -0.4064)
			(end 0.7874 0.4064)
			(stroke
				(width 0.1524)
				(type default)
			)
			(layer "F.SilkS")
		)
		(fp_line
			(start 0.7874 0.4064)
			(end -0.7874 0.4064)
			(stroke
				(width 0.1524)
				(type default)
			)
			(layer "F.SilkS")
		)
		(fp_line
			(start -0.67945 -0.305054)
			(end -0.12065 -0.305054)
			(stroke
				(width 0.1)
				(type default)
			)
			(layer "F.Fab")
		)
		(fp_line
			(start -0.67945 0.3048)
			(end -0.67945 -0.305054)
			(stroke
				(width 0.1)
				(type default)
			)
			(layer "F.Fab")
		)
		(fp_line
			(start -0.12065 -0.305054)
			(end -0.12065 -0.2794)
			(stroke
				(width 0.1)
				(type default)
			)
			(layer "F.Fab")
		)
		(fp_line
			(start -0.12065 -0.2794)
			(end 0.12065 -0.2794)
			(stroke
				(width 0.1)
				(type default)
			)
			(layer "F.Fab")
		)
		(fp_line
			(start -0.12065 0.2794)
			(end -0.12065 0.3048)
			(stroke
				(width 0.1)
				(type default)
			)
			(layer "F.Fab")
		)
		(fp_line
			(start -0.12065 0.3048)
			(end -0.67945 0.3048)
			(stroke
				(width 0.1)
				(type default)
			)
			(layer "F.Fab")
		)
		(fp_line
			(start 0.120396 0.2794)
			(end -0.12065 0.2794)
			(stroke
				(width 0.1)
				(type default)
			)
			(layer "F.Fab")
		)
		(fp_line
			(start 0.120396 0.3048)
			(end 0.120396 0.2794)
			(stroke
				(width 0.1)
				(type default)
			)
			(layer "F.Fab")
		)
		(fp_line
			(start 0.12065 -0.3048)
			(end 0.67945 -0.3048)
			(stroke
				(width 0.1)
				(type default)
			)
			(layer "F.Fab")
		)
		(fp_line
			(start 0.12065 -0.2794)
			(end 0.12065 -0.3048)
			(stroke
				(width 0.1)
				(type default)
			)
			(layer "F.Fab")
		)
		(fp_line
			(start 0.67945 -0.3048)
			(end 0.67945 0.3048)
			(stroke
				(width 0.1)
				(type default)
			)
			(layer "F.Fab")
		)
		(fp_line
			(start 0.67945 0.3048)
			(end 0.120396 0.3048)
			(stroke
				(width 0.1)
				(type default)
			)
			(layer "F.Fab")
		)
		(pad "1" smd circle
			(at -0.40005 0)
			(size 0 0)
			(layers "F.Cu" "F.Mask" "F.Paste")
			(net "PVDDIO_P1")
		)
		(pad "2" smd circle
			(at 0.40005 0)
			(size 0 0)
			(layers "F.Cu" "F.Mask" "F.Paste")
			(net "GND")
		)
	)
	(footprint ""
		(layer "F.Cu")
		(at 82.986118 -339.362796)
		(property "Reference" "PC375_1"
			(at 0 0 0)
			(layer "F.SilkS")
			(hide yes)
			(effects
				(font
					(size 1.27 1.27)
				)
			)
		)
		(property "Value" ""
			(at 0 0 0)
			(layer "F.Fab")
			(effects
				(font
					(size 1.27 1.27)
				)
			)
		)
		(duplicate_pad_numbers_are_jumpers no)
		(fp_line
			(start -0.7874 -0.4064)
			(end 0.7874 -0.4064)
			(stroke
				(width 0.1524)
				(type default)
			)
			(layer "F.SilkS")
		)
		(fp_line
			(start -0.7874 0.4064)
			(end -0.7874 -0.4064)
			(stroke
				(width 0.1524)
				(type default)
			)
			(layer "F.SilkS")
		)
		(fp_line
			(start 0.7874 -0.4064)
			(end 0.7874 0.4064)
			(stroke
				(width 0.1524)
				(type default)
			)
			(layer "F.SilkS")
		)
		(fp_line
			(start 0.7874 0.4064)
			(end -0.7874 0.4064)
			(stroke
				(width 0.1524)
				(type default)
			)
			(layer "F.SilkS")
		)
		(fp_line
			(start -0.67945 -0.305054)
			(end -0.12065 -0.305054)
			(stroke
				(width 0.1)
				(type default)
			)
			(layer "F.Fab")
		)
		(fp_line
			(start -0.67945 0.3048)
			(end -0.67945 -0.305054)
			(stroke
				(width 0.1)
				(type default)
			)
			(layer "F.Fab")
		)
		(fp_line
			(start -0.12065 -0.305054)
			(end -0.12065 -0.2794)
			(stroke
				(width 0.1)
				(type default)
			)
			(layer "F.Fab")
		)
		(fp_line
			(start -0.12065 -0.2794)
			(end 0.12065 -0.2794)
			(stroke
				(width 0.1)
				(type default)
			)
			(layer "F.Fab")
		)
		(fp_line
			(start -0.12065 0.2794)
			(end -0.12065 0.3048)
			(stroke
				(width 0.1)
				(type default)
			)
			(layer "F.Fab")
		)
		(fp_line
			(start -0.12065 0.3048)
			(end -0.67945 0.3048)
			(stroke
				(width 0.1)
				(type default)
			)
			(layer "F.Fab")
		)
		(fp_line
			(start 0.120396 0.2794)
			(end -0.12065 0.2794)
			(stroke
				(width 0.1)
				(type default)
			)
			(layer "F.Fab")
		)
		(fp_line
			(start 0.120396 0.3048)
			(end 0.120396 0.2794)
			(stroke
				(width 0.1)
				(type default)
			)
			(layer "F.Fab")
		)
		(fp_line
			(start 0.12065 -0.3048)
			(end 0.67945 -0.3048)
			(stroke
				(width 0.1)
				(type default)
			)
			(layer "F.Fab")
		)
		(fp_line
			(start 0.12065 -0.2794)
			(end 0.12065 -0.3048)
			(stroke
				(width 0.1)
				(type default)
			)
			(layer "F.Fab")
		)
		(fp_line
			(start 0.67945 -0.3048)
			(end 0.67945 0.3048)
			(stroke
				(width 0.1)
				(type default)
			)
			(layer "F.Fab")
		)
		(fp_line
			(start 0.67945 0.3048)
			(end 0.120396 0.3048)
			(stroke
				(width 0.1)
				(type default)
			)
			(layer "F.Fab")
		)
		(pad "1" smd circle
			(at -0.40005 0)
			(size 0 0)
			(layers "F.Cu" "F.Mask" "F.Paste")
			(net "SW_P12V_AUX_PVDDCR_CPU1_P1_FLT")
		)
		(pad "2" smd circle
			(at 0.40005 0)
			(size 0 0)
			(layers "F.Cu" "F.Mask" "F.Paste")
			(net "GND")
		)
	)
	(footprint ""
		(layer "F.Cu")
		(at 45.71492 -111.32058 180)
		(property "Reference" "R1475"
			(at 0 0 180)
			(layer "F.SilkS")
			(hide yes)
			(effects
				(font
					(size 1.27 1.27)
				)
			)
		)
		(property "Value" ""
			(at 0 0 180)
			(layer "F.Fab")
			(effects
				(font
					(size 1.27 1.27)
				)
			)
		)
		(duplicate_pad_numbers_are_jumpers no)
		(fp_line
			(start 0.7874 0.4064)
			(end -0.7874 0.4064)
			(stroke
				(width 0.1524)
				(type default)
			)
			(layer "F.SilkS")
		)
		(fp_line
			(start 0.7874 -0.4064)
			(end 0.7874 0.4064)
			(stroke
				(width 0.1524)
				(type default)
			)
			(layer "F.SilkS")
		)
		(fp_line
			(start -0.7874 0.4064)
			(end -0.7874 -0.4064)
			(stroke
				(width 0.1524)
				(type default)
			)
			(layer "F.SilkS")
		)
		(fp_line
			(start -0.7874 -0.4064)
			(end 0.7874 -0.4064)
			(stroke
				(width 0.1524)
				(type default)
			)
			(layer "F.SilkS")
		)
		(fp_line
			(start 0.67945 0.3048)
			(end 0.120396 0.3048)
			(stroke
				(width 0.1)
				(type default)
			)
			(layer "F.Fab")
		)
		(fp_line
			(start 0.67945 -0.3048)
			(end 0.67945 0.3048)
			(stroke
				(width 0.1)
				(type default)
			)
			(layer "F.Fab")
		)
		(fp_line
			(start 0.12065 -0.2794)
			(end 0.12065 -0.3048)
			(stroke
				(width 0.1)
				(type default)
			)
			(layer "F.Fab")
		)
		(fp_line
			(start 0.12065 -0.3048)
			(end 0.67945 -0.3048)
			(stroke
				(width 0.1)
				(type default)
			)
			(layer "F.Fab")
		)
		(fp_line
			(start 0.120396 0.3048)
			(end 0.120396 0.2794)
			(stroke
				(width 0.1)
				(type default)
			)
			(layer "F.Fab")
		)
		(fp_line
			(start 0.120396 0.2794)
			(end -0.12065 0.2794)
			(stroke
				(width 0.1)
				(type default)
			)
			(layer "F.Fab")
		)
		(fp_line
			(start -0.12065 0.3048)
			(end -0.67945 0.3048)
			(stroke
				(width 0.1)
				(type default)
			)
			(layer "F.Fab")
		)
		(fp_line
			(start -0.12065 0.2794)
			(end -0.12065 0.3048)
			(stroke
				(width 0.1)
				(type default)
			)
			(layer "F.Fab")
		)
		(fp_line
			(start -0.12065 -0.2794)
			(end 0.12065 -0.2794)
			(stroke
				(width 0.1)
				(type default)
			)
			(layer "F.Fab")
		)
		(fp_line
			(start -0.12065 -0.305054)
			(end -0.12065 -0.2794)
			(stroke
				(width 0.1)
				(type default)
			)
			(layer "F.Fab")
		)
		(fp_line
			(start -0.67945 0.3048)
			(end -0.67945 -0.305054)
			(stroke
				(width 0.1)
				(type default)
			)
			(layer "F.Fab")
		)
		(fp_line
			(start -0.67945 -0.305054)
			(end -0.12065 -0.305054)
			(stroke
				(width 0.1)
				(type default)
			)
			(layer "F.Fab")
		)
		(pad "1" smd circle
			(at -0.40005 0 180)
			(size 0 0)
			(layers "F.Cu" "F.Mask" "F.Paste")
			(net "P3V3_AUX_DSC_G2")
		)
		(pad "2" smd circle
			(at 0.40005 0 180)
			(size 0 0)
			(layers "F.Cu" "F.Mask" "F.Paste")
			(net "GND")
		)
	)
	(footprint ""
		(layer "F.Cu")
		(at 425.36872 -388.767828)
		(property "Reference" "C838"
			(at 0 0 0)
			(layer "F.SilkS")
			(hide yes)
			(effects
				(font
					(size 1.27 1.27)
				)
			)
		)
		(property "Value" ""
			(at 0 0 0)
			(layer "F.Fab")
			(effects
				(font
					(size 1.27 1.27)
				)
			)
		)
		(duplicate_pad_numbers_are_jumpers no)
		(fp_line
			(start -0.299974 -0.150114)
			(end 0.299974 -0.150114)
			(stroke
				(width 0.1)
				(type default)
			)
			(layer "F.Fab")
		)
		(fp_line
			(start -0.299974 0.150114)
			(end -0.299974 -0.150114)
			(stroke
				(width 0.1)
				(type default)
			)
			(layer "F.Fab")
		)
		(fp_line
			(start 0.299974 -0.150114)
			(end 0.299974 0.150114)
			(stroke
				(width 0.1)
				(type default)
			)
			(layer "F.Fab")
		)
		(fp_line
			(start 0.299974 0.150114)
			(end -0.299974 0.150114)
			(stroke
				(width 0.1)
				(type default)
			)
			(layer "F.Fab")
		)
		(pad "1" smd rect
			(at -0.2667 0)
			(size 0.3048 0.381)
			(layers "F.Cu" "F.Mask" "F.Paste")
			(net "P5E_CPU0_P2_TX_C_DN<15>")
		)
		(pad "2" smd rect
			(at 0.2667 0)
			(size 0.3048 0.381)
			(layers "F.Cu" "F.Mask" "F.Paste")
			(net "P5E_CPU0_P2_TX_DN<15>")
		)
	)
	(footprint ""
		(layer "F.Cu")
		(at 264.174986 -119.207026)
		(property "Reference" "U39"
			(at -2.482342 -5.187696 0)
			(unlocked yes)
			(layer "F.SilkS")
			(effects
				(font
					(size 0.7874 0.5842)
					(thickness 0.1524)
				)
				(justify left)
			)
		)
		(property "Value" ""
			(at 0 0 0)
			(layer "F.Fab")
			(effects
				(font
					(size 1.27 1.27)
				)
			)
		)
		(duplicate_pad_numbers_are_jumpers no)
		(fp_line
			(start -1.8542 -3.949954)
			(end -1.8542 3.949954)
			(stroke
				(width 0.1524)
				(type default)
			)
			(layer "F.SilkS")
		)
		(fp_line
			(start -1.8542 3.949954)
			(end 1.8542 3.949954)
			(stroke
				(width 0.1524)
				(type default)
			)
			(layer "F.SilkS")
		)
		(fp_line
			(start -1.282954 -3.949954)
			(end -1.8542 -3.949954)
			(stroke
				(width 0.1524)
				(type default)
			)
			(layer "F.SilkS")
		)
		(fp_line
			(start 0 -2.667)
			(end -1.282954 -3.949954)
			(stroke
				(width 0.1524)
				(type default)
			)
			(layer "F.SilkS")
		)
		(fp_line
			(start 1.282954 -3.949954)
			(end 0 -2.667)
			(stroke
				(width 0.1524)
				(type default)
			)
			(layer "F.SilkS")
		)
		(fp_line
			(start 1.8542 -3.949954)
			(end 1.282954 -3.949954)
			(stroke
				(width 0.1524)
				(type default)
			)
			(layer "F.SilkS")
		)
		(fp_line
			(start 1.8542 3.949954)
			(end 1.8542 -3.949954)
			(stroke
				(width 0.1524)
				(type default)
			)
			(layer "F.SilkS")
		)
		(fp_poly
			(pts
				(xy -3.7846 -3.57505) (xy -4.8006 -3.06705) (xy -4.8006 -4.08305)
			)
			(stroke
				(width 0)
				(type default)
			)
			(fill yes)
			(layer "F.SilkS")
		)
		(fp_line
			(start -2.249932 -3.949954)
			(end -2.249932 3.949954)
			(stroke
				(width 0.1)
				(type default)
			)
			(layer "F.Fab")
		)
		(fp_line
			(start -2.249932 3.949954)
			(end 2.249932 3.949954)
			(stroke
				(width 0.1)
				(type default)
			)
			(layer "F.Fab")
		)
		(fp_line
			(start 2.249932 -3.949954)
			(end -2.249932 -3.949954)
			(stroke
				(width 0.1)
				(type default)
			)
			(layer "F.Fab")
		)
		(fp_line
			(start 2.249932 3.949954)
			(end 2.249932 -3.949954)
			(stroke
				(width 0.1)
				(type default)
			)
			(layer "F.Fab")
		)
		(fp_poly
			(pts
				(xy -4.8006 -4.08305) (xy -4.8006 -3.06705) (xy -3.7846 -3.57505)
			)
			(stroke
				(width 0)
				(type default)
			)
			(fill yes)
			(layer "F.Fab")
		)
		(pad "1" smd rect
			(at -2.800096 -3.57505 270)
			(size 0.3048 1.6002)
			(layers "F.Cu" "F.Mask" "F.Paste")
			(net "PCA9548_PCIE0_ADDR0")
		)
		(pad "2" smd rect
			(at -2.800096 -2.925064 270)
			(size 0.3048 1.6002)
			(layers "F.Cu" "F.Mask" "F.Paste")
			(net "PCA9548_PCIE0_ADDR1")
		)
		(pad "3" smd rect
			(at -2.800096 -2.275078 270)
			(size 0.3048 1.6002)
			(layers "F.Cu" "F.Mask" "F.Paste")
			(net "PU_RST_SMB_PCIE2_N")
		)
		(pad "4" smd rect
			(at -2.800096 -1.625092 270)
			(size 0.3048 1.6002)
			(layers "F.Cu" "F.Mask" "F.Paste")
			(net "SMB_VR_3V3AUX_SDA_R6")
		)
		(pad "5" smd rect
			(at -2.800096 -0.975106 270)
			(size 0.3048 1.6002)
			(layers "F.Cu" "F.Mask" "F.Paste")
			(net "SMB_VR_3V3AUX_SCL_R6")
		)
		(pad "6" smd rect
			(at -2.800096 -0.32512 270)
			(size 0.3048 1.6002)
			(layers "F.Cu" "F.Mask" "F.Paste")
			(net "SMB_LM75_0_3V3AUX_SDA_R")
		)
		(pad "7" smd rect
			(at -2.800096 0.32512 270)
			(size 0.3048 1.6002)
			(layers "F.Cu" "F.Mask" "F.Paste")
			(net "SMB_LM75_0_3V3AUX_SCL_R")
		)
		(pad "8" smd rect
			(at -2.800096 0.975106 270)
			(size 0.3048 1.6002)
			(layers "F.Cu" "F.Mask" "F.Paste")
			(net "SMB_LM75_1_3V3AUX_SDA_R")
		)
		(pad "9" smd rect
			(at -2.800096 1.625092 270)
			(size 0.3048 1.6002)
			(layers "F.Cu" "F.Mask" "F.Paste")
			(net "SMB_LM75_1_3V3AUX_SCL_R")
		)
		(pad "10" smd rect
			(at -2.800096 2.275078 270)
			(size 0.3048 1.6002)
			(layers "F.Cu" "F.Mask" "F.Paste")
			(net "SMB_LM75_2_3V3AUX_SDA_R")
		)
		(pad "11" smd rect
			(at -2.800096 2.925064 270)
			(size 0.3048 1.6002)
			(layers "F.Cu" "F.Mask" "F.Paste")
			(net "SMB_LM75_2_3V3AUX_SCL_R")
		)
		(pad "12" smd rect
			(at -2.800096 3.57505 270)
			(size 0.3048 1.6002)
			(layers "F.Cu" "F.Mask" "F.Paste")
			(net "GND")
		)
		(pad "13" smd rect
			(at 2.800096 3.57505 270)
			(size 0.3048 1.6002)
			(layers "F.Cu" "F.Mask" "F.Paste")
			(net "SMB_LM75_3_3V3AUX_SDA_R")
		)
		(pad "14" smd rect
			(at 2.800096 2.925064 270)
			(size 0.3048 1.6002)
			(layers "F.Cu" "F.Mask" "F.Paste")
			(net "SMB_LM75_3_3V3AUX_SCL_R")
		)
		(pad "15" smd rect
			(at 2.800096 2.275078 270)
			(size 0.3048 1.6002)
			(layers "F.Cu" "F.Mask" "F.Paste")
			(net "SMB_P12V_HSC_SDA_R")
		)
		(pad "16" smd rect
			(at 2.800096 1.625092 270)
			(size 0.3048 1.6002)
			(layers "F.Cu" "F.Mask" "F.Paste")
			(net "SMB_P12V_HSC_SCL_R")
		)
		(pad "17" smd rect
			(at 2.800096 0.975106 270)
			(size 0.3048 1.6002)
			(layers "F.Cu" "F.Mask" "F.Paste")
			(net "SMB_ADC_SDA")
		)
		(pad "18" smd rect
			(at 2.800096 0.32512 270)
			(size 0.3048 1.6002)
			(layers "F.Cu" "F.Mask" "F.Paste")
			(net "SMB_ADC_SCL")
		)
		(pad "19" smd rect
			(at 2.800096 -0.32512 270)
			(size 0.3048 1.6002)
			(layers "F.Cu" "F.Mask" "F.Paste")
			(net "Net_10755")
		)
		(pad "20" smd rect
			(at 2.800096 -0.975106 270)
			(size 0.3048 1.6002)
			(layers "F.Cu" "F.Mask" "F.Paste")
			(net "Net_10756")
		)
		(pad "21" smd rect
			(at 2.800096 -1.625092 270)
			(size 0.3048 1.6002)
			(layers "F.Cu" "F.Mask" "F.Paste")
			(net "PCA9548_PCIE0_ADDR2")
		)
		(pad "22" smd rect
			(at 2.800096 -2.275078 270)
			(size 0.3048 1.6002)
			(layers "F.Cu" "F.Mask" "F.Paste")
			(net "SMB_VR_SENSOR_3V3AUX_SCL_R")
		)
		(pad "23" smd rect
			(at 2.800096 -2.925064 270)
			(size 0.3048 1.6002)
			(layers "F.Cu" "F.Mask" "F.Paste")
			(net "SMB_VR_SENSOR_3V3AUX_SDA_R")
		)
		(pad "24" smd rect
			(at 2.800096 -3.57505 270)
			(size 0.3048 1.6002)
			(layers "F.Cu" "F.Mask" "F.Paste")
			(net "P3V3_AUX")
		)
	)
	(footprint ""
		(layer "F.Cu")
		(at 16.645382 -104.76611 90)
		(property "Reference" "R3652"
			(at 0 0 90)
			(layer "F.SilkS")
			(hide yes)
			(effects
				(font
					(size 1.27 1.27)
				)
			)
		)
		(property "Value" ""
			(at 0 0 90)
			(layer "F.Fab")
			(effects
				(font
					(size 1.27 1.27)
				)
			)
		)
		(duplicate_pad_numbers_are_jumpers no)
		(fp_line
			(start 0.7874 -0.4064)
			(end 0.7874 0.4064)
			(stroke
				(width 0.1524)
				(type default)
			)
			(layer "F.SilkS")
		)
		(fp_line
			(start -0.7874 -0.4064)
			(end 0.7874 -0.4064)
			(stroke
				(width 0.1524)
				(type default)
			)
			(layer "F.SilkS")
		)
		(fp_line
			(start 0.7874 0.4064)
			(end -0.7874 0.4064)
			(stroke
				(width 0.1524)
				(type default)
			)
			(layer "F.SilkS")
		)
		(fp_line
			(start -0.7874 0.4064)
			(end -0.7874 -0.4064)
			(stroke
				(width 0.1524)
				(type default)
			)
			(layer "F.SilkS")
		)
		(fp_line
			(start -0.12065 -0.305054)
			(end -0.12065 -0.2794)
			(stroke
				(width 0.1)
				(type default)
			)
			(layer "F.Fab")
		)
		(fp_line
			(start -0.67945 -0.305054)
			(end -0.12065 -0.305054)
			(stroke
				(width 0.1)
				(type default)
			)
			(layer "F.Fab")
		)
		(fp_line
			(start 0.67945 -0.3048)
			(end 0.67945 0.3048)
			(stroke
				(width 0.1)
				(type default)
			)
			(layer "F.Fab")
		)
		(fp_line
			(start 0.12065 -0.3048)
			(end 0.67945 -0.3048)
			(stroke
				(width 0.1)
				(type default)
			)
			(layer "F.Fab")
		)
		(fp_line
			(start 0.12065 -0.2794)
			(end 0.12065 -0.3048)
			(stroke
				(width 0.1)
				(type default)
			)
			(layer "F.Fab")
		)
		(fp_line
			(start -0.12065 -0.2794)
			(end 0.12065 -0.2794)
			(stroke
				(width 0.1)
				(type default)
			)
			(layer "F.Fab")
		)
		(fp_line
			(start 0.120396 0.2794)
			(end -0.12065 0.2794)
			(stroke
				(width 0.1)
				(type default)
			)
			(layer "F.Fab")
		)
		(fp_line
			(start -0.12065 0.2794)
			(end -0.12065 0.3048)
			(stroke
				(width 0.1)
				(type default)
			)
			(layer "F.Fab")
		)
		(fp_line
			(start 0.67945 0.3048)
			(end 0.120396 0.3048)
			(stroke
				(width 0.1)
				(type default)
			)
			(layer "F.Fab")
		)
		(fp_line
			(start 0.120396 0.3048)
			(end 0.120396 0.2794)
			(stroke
				(width 0.1)
				(type default)
			)
			(layer "F.Fab")
		)
		(fp_line
			(start -0.12065 0.3048)
			(end -0.67945 0.3048)
			(stroke
				(width 0.1)
				(type default)
			)
			(layer "F.Fab")
		)
		(fp_line
			(start -0.67945 0.3048)
			(end -0.67945 -0.305054)
			(stroke
				(width 0.1)
				(type default)
			)
			(layer "F.Fab")
		)
		(pad "1" smd rect
			(at -0.40005 0 270)
			(size 0.4572 0.508)
			(layers "F.Cu" "F.Mask" "F.Paste")
			(net "USB2_P0_R_DN")
		)
		(pad "2" smd rect
			(at 0.40005 0 270)
			(size 0.4572 0.508)
			(layers "F.Cu" "F.Mask" "F.Paste")
			(net "USB2_HOST_BMC_B_DN")
		)
	)
	(footprint ""
		(layer "F.Cu")
		(at 124.459238 -41.17975 90)
		(property "Reference" "R6275"
			(at 0 0 90)
			(layer "F.SilkS")
			(hide yes)
			(effects
				(font
					(size 1.27 1.27)
				)
			)
		)
		(property "Value" ""
			(at 0 0 90)
			(layer "F.Fab")
			(effects
				(font
					(size 1.27 1.27)
				)
			)
		)
		(duplicate_pad_numbers_are_jumpers no)
		(fp_line
			(start 0.7874 -0.4064)
			(end 0.7874 0.4064)
			(stroke
				(width 0.1524)
				(type default)
			)
			(layer "F.SilkS")
		)
		(fp_line
			(start -0.7874 -0.4064)
			(end 0.7874 -0.4064)
			(stroke
				(width 0.1524)
				(type default)
			)
			(layer "F.SilkS")
		)
		(fp_line
			(start 0.7874 0.4064)
			(end -0.7874 0.4064)
			(stroke
				(width 0.1524)
				(type default)
			)
			(layer "F.SilkS")
		)
		(fp_line
			(start -0.7874 0.4064)
			(end -0.7874 -0.4064)
			(stroke
				(width 0.1524)
				(type default)
			)
			(layer "F.SilkS")
		)
		(fp_line
			(start -0.12065 -0.305054)
			(end -0.12065 -0.2794)
			(stroke
				(width 0.1)
				(type default)
			)
			(layer "F.Fab")
		)
		(fp_line
			(start -0.67945 -0.305054)
			(end -0.12065 -0.305054)
			(stroke
				(width 0.1)
				(type default)
			)
			(layer "F.Fab")
		)
		(fp_line
			(start 0.67945 -0.3048)
			(end 0.67945 0.3048)
			(stroke
				(width 0.1)
				(type default)
			)
			(layer "F.Fab")
		)
		(fp_line
			(start 0.12065 -0.3048)
			(end 0.67945 -0.3048)
			(stroke
				(width 0.1)
				(type default)
			)
			(layer "F.Fab")
		)
		(fp_line
			(start 0.12065 -0.2794)
			(end 0.12065 -0.3048)
			(stroke
				(width 0.1)
				(type default)
			)
			(layer "F.Fab")
		)
		(fp_line
			(start -0.12065 -0.2794)
			(end 0.12065 -0.2794)
			(stroke
				(width 0.1)
				(type default)
			)
			(layer "F.Fab")
		)
		(fp_line
			(start 0.120396 0.2794)
			(end -0.12065 0.2794)
			(stroke
				(width 0.1)
				(type default)
			)
			(layer "F.Fab")
		)
		(fp_line
			(start -0.12065 0.2794)
			(end -0.12065 0.3048)
			(stroke
				(width 0.1)
				(type default)
			)
			(layer "F.Fab")
		)
		(fp_line
			(start 0.67945 0.3048)
			(end 0.120396 0.3048)
			(stroke
				(width 0.1)
				(type default)
			)
			(layer "F.Fab")
		)
		(fp_line
			(start 0.120396 0.3048)
			(end 0.120396 0.2794)
			(stroke
				(width 0.1)
				(type default)
			)
			(layer "F.Fab")
		)
		(fp_line
			(start -0.12065 0.3048)
			(end -0.67945 0.3048)
			(stroke
				(width 0.1)
				(type default)
			)
			(layer "F.Fab")
		)
		(fp_line
			(start -0.67945 0.3048)
			(end -0.67945 -0.305054)
			(stroke
				(width 0.1)
				(type default)
			)
			(layer "F.Fab")
		)
		(pad "1" smd circle
			(at -0.40005 0 90)
			(size 0 0)
			(layers "F.Cu" "F.Mask" "F.Paste")
			(net "USB_HUB2_TI_VDD33_MRP_PRT_CTL4_GANGPWR")
		)
		(pad "2" smd circle
			(at 0.40005 0 90)
			(size 0 0)
			(layers "F.Cu" "F.Mask" "F.Paste")
			(net "P3V3_AUX_CPU0_USB2_AVDD33")
		)
	)
	(footprint ""
		(layer "F.Cu")
		(at 184.455054 -168.317926 -90)
		(property "Reference" "R1296"
			(at 0 0 270)
			(layer "F.SilkS")
			(hide yes)
			(effects
				(font
					(size 1.27 1.27)
				)
			)
		)
		(property "Value" ""
			(at 0 0 270)
			(layer "F.Fab")
			(effects
				(font
					(size 1.27 1.27)
				)
			)
		)
		(duplicate_pad_numbers_are_jumpers no)
		(fp_line
			(start -0.7874 0.4064)
			(end -0.7874 -0.4064)
			(stroke
				(width 0.1524)
				(type default)
			)
			(layer "F.SilkS")
		)
		(fp_line
			(start 0.7874 0.4064)
			(end -0.7874 0.4064)
			(stroke
				(width 0.1524)
				(type default)
			)
			(layer "F.SilkS")
		)
		(fp_line
			(start -0.7874 -0.4064)
			(end 0.7874 -0.4064)
			(stroke
				(width 0.1524)
				(type default)
			)
			(layer "F.SilkS")
		)
		(fp_line
			(start 0.7874 -0.4064)
			(end 0.7874 0.4064)
			(stroke
				(width 0.1524)
				(type default)
			)
			(layer "F.SilkS")
		)
		(fp_line
			(start -0.67945 0.3048)
			(end -0.67945 -0.305054)
			(stroke
				(width 0.1)
				(type default)
			)
			(layer "F.Fab")
		)
		(fp_line
			(start -0.12065 0.3048)
			(end -0.67945 0.3048)
			(stroke
				(width 0.1)
				(type default)
			)
			(layer "F.Fab")
		)
		(fp_line
			(start 0.120396 0.3048)
			(end 0.120396 0.2794)
			(stroke
				(width 0.1)
				(type default)
			)
			(layer "F.Fab")
		)
		(fp_line
			(start 0.67945 0.3048)
			(end 0.120396 0.3048)
			(stroke
				(width 0.1)
				(type default)
			)
			(layer "F.Fab")
		)
		(fp_line
			(start -0.12065 0.2794)
			(end -0.12065 0.3048)
			(stroke
				(width 0.1)
				(type default)
			)
			(layer "F.Fab")
		)
		(fp_line
			(start 0.120396 0.2794)
			(end -0.12065 0.2794)
			(stroke
				(width 0.1)
				(type default)
			)
			(layer "F.Fab")
		)
		(fp_line
			(start -0.12065 -0.2794)
			(end 0.12065 -0.2794)
			(stroke
				(width 0.1)
				(type default)
			)
			(layer "F.Fab")
		)
		(fp_line
			(start 0.12065 -0.2794)
			(end 0.12065 -0.3048)
			(stroke
				(width 0.1)
				(type default)
			)
			(layer "F.Fab")
		)
		(fp_line
			(start 0.12065 -0.3048)
			(end 0.67945 -0.3048)
			(stroke
				(width 0.1)
				(type default)
			)
			(layer "F.Fab")
		)
		(fp_line
			(start 0.67945 -0.3048)
			(end 0.67945 0.3048)
			(stroke
				(width 0.1)
				(type default)
			)
			(layer "F.Fab")
		)
		(fp_line
			(start -0.67945 -0.305054)
			(end -0.12065 -0.305054)
			(stroke
				(width 0.1)
				(type default)
			)
			(layer "F.Fab")
		)
		(fp_line
			(start -0.12065 -0.305054)
			(end -0.12065 -0.2794)
			(stroke
				(width 0.1)
				(type default)
			)
			(layer "F.Fab")
		)
		(pad "1" smd rect
			(at -0.40005 0 90)
			(size 0.4572 0.508)
			(layers "F.Cu" "F.Mask" "F.Paste")
			(net "I3C_SPD_DDRGL_CPU1_SDA")
		)
		(pad "2" smd rect
			(at 0.40005 0 90)
			(size 0.4572 0.508)
			(layers "F.Cu" "F.Mask" "F.Paste")
			(net "I3C_SPD_DDRGL_CPU1_LVC1_SDA")
		)
	)
	(footprint ""
		(layer "F.Cu")
		(at 184.337198 -420.329868 90)
		(property "Reference" "U181"
			(at -0.339344 -7.867396 90)
			(unlocked yes)
			(layer "F.SilkS")
			(effects
				(font
					(size 0.7874 0.5842)
					(thickness 0.1524)
				)
				(justify left)
			)
		)
		(property "Value" ""
			(at 0 0 90)
			(layer "F.Fab")
			(effects
				(font
					(size 1.27 1.27)
				)
			)
		)
		(duplicate_pad_numbers_are_jumpers no)
		(fp_line
			(start 2.097532 -3.949954)
			(end 1.409954 -3.949954)
			(stroke
				(width 0.1524)
				(type default)
			)
			(layer "F.SilkS")
		)
		(fp_line
			(start 1.409954 -3.949954)
			(end 0 -2.54)
			(stroke
				(width 0.1524)
				(type default)
			)
			(layer "F.SilkS")
		)
		(fp_line
			(start -1.409954 -3.949954)
			(end -2.097532 -3.949954)
			(stroke
				(width 0.1524)
				(type default)
			)
			(layer "F.SilkS")
		)
		(fp_line
			(start -2.097532 -3.949954)
			(end -2.097532 3.949954)
			(stroke
				(width 0.1524)
				(type default)
			)
			(layer "F.SilkS")
		)
		(fp_line
			(start 0 -2.54)
			(end -1.409954 -3.949954)
			(stroke
				(width 0.1524)
				(type default)
			)
			(layer "F.SilkS")
		)
		(fp_line
			(start 2.097532 3.949954)
			(end 2.097532 -3.949954)
			(stroke
				(width 0.1524)
				(type default)
			)
			(layer "F.SilkS")
		)
		(fp_line
			(start -2.097532 3.949954)
			(end 2.097532 3.949954)
			(stroke
				(width 0.1524)
				(type default)
			)
			(layer "F.SilkS")
		)
		(fp_poly
			(pts
				(xy -4.509262 -5.070856) (xy -3.67538 -5.650992) (xy -3.512058 -4.527042)
			)
			(stroke
				(width 0)
				(type default)
			)
			(fill yes)
			(layer "F.SilkS")
		)
		(fp_line
			(start 2.249932 -3.949954)
			(end -2.249932 -3.949954)
			(stroke
				(width 0.1)
				(type default)
			)
			(layer "F.Fab")
		)
		(fp_line
			(start -2.249932 -3.949954)
			(end -2.249932 3.949954)
			(stroke
				(width 0.1)
				(type default)
			)
			(layer "F.Fab")
		)
		(fp_line
			(start 2.249932 3.949954)
			(end 2.249932 -3.949954)
			(stroke
				(width 0.1)
				(type default)
			)
			(layer "F.Fab")
		)
		(fp_line
			(start -2.249932 3.949954)
			(end 2.249932 3.949954)
			(stroke
				(width 0.1)
				(type default)
			)
			(layer "F.Fab")
		)
		(fp_poly
			(pts
				(xy -4.7498 -4.182872) (xy -4.7498 -3.166872) (xy -3.7338 -3.674872)
			)
			(stroke
				(width 0)
				(type default)
			)
			(fill yes)
			(layer "F.Fab")
		)
		(pad "1" smd rect
			(at -2.925064 -3.674872)
			(size 0.6096 1.3716)
			(layers "F.Cu" "F.Mask" "F.Paste")
			(net "PU_U181_INT")
		)
		(pad "2" smd rect
			(at -2.925064 -2.925064)
			(size 0.4064 1.3716)
			(layers "F.Cu" "F.Mask" "F.Paste")
			(net "TCA9539_0_ADD1")
		)
		(pad "3" smd rect
			(at -2.925064 -2.275078)
			(size 0.4064 1.3716)
			(layers "F.Cu" "F.Mask" "F.Paste")
			(net "PU_RST_SMB_U181_N")
		)
		(pad "4" smd rect
			(at -2.925064 -1.625092)
			(size 0.4064 1.3716)
			(layers "F.Cu" "F.Mask" "F.Paste")
			(net "RST_USB_HUB_N")
		)
		(pad "5" smd rect
			(at -2.925064 -0.975106)
			(size 0.4064 1.3716)
			(layers "F.Cu" "F.Mask" "F.Paste")
			(net "RST_SWB_BIC_N")
		)
		(pad "6" smd rect
			(at -2.925064 -0.32512)
			(size 0.4064 1.3716)
			(layers "F.Cu" "F.Mask" "F.Paste")
			(net "TP_TCA9539_0_P0_2")
		)
		(pad "7" smd rect
			(at -2.925064 0.32512)
			(size 0.4064 1.3716)
			(layers "F.Cu" "F.Mask" "F.Paste")
			(net "TP_TCA9539_0_P0_3")
		)
		(pad "8" smd rect
			(at -2.925064 0.975106)
			(size 0.4064 1.3716)
			(layers "F.Cu" "F.Mask" "F.Paste")
			(net "PRSNT_SWB_ISO_R1_N")
		)
		(pad "9" smd rect
			(at -2.925064 1.625092)
			(size 0.4064 1.3716)
			(layers "F.Cu" "F.Mask" "F.Paste")
			(net "GPU_PRSNT_N_ISO_R1")
		)
		(pad "10" smd rect
			(at -2.925064 2.275078)
			(size 0.4064 1.3716)
			(layers "F.Cu" "F.Mask" "F.Paste")
			(net "PRSNT_CABLE_GPU_B3_ISO_R1_N")
		)
		(pad "11" smd rect
			(at -2.925064 2.925064)
			(size 0.4064 1.3716)
			(layers "F.Cu" "F.Mask" "F.Paste")
			(net "PRSNT_CABLE_SWB_B2_ISO_R_N")
		)
		(pad "12" smd rect
			(at -2.925064 3.674872)
			(size 0.6096 1.3716)
			(layers "F.Cu" "F.Mask" "F.Paste")
			(net "GND")
		)
		(pad "13" smd rect
			(at 2.925064 3.674872)
			(size 0.6096 1.3716)
			(layers "F.Cu" "F.Mask" "F.Paste")
			(net "PRSNT_CABLE_GPU_A2_ISO_R1_N")
		)
		(pad "14" smd rect
			(at 2.925064 2.925064)
			(size 0.4064 1.3716)
			(layers "F.Cu" "F.Mask" "F.Paste")
			(net "PRSNT_CABLE_SWB_B1_ISO_R_N")
		)
		(pad "15" smd rect
			(at 2.925064 2.275078)
			(size 0.4064 1.3716)
			(layers "F.Cu" "F.Mask" "F.Paste")
			(net "GPU_BASE_ID0_R")
		)
		(pad "16" smd rect
			(at 2.925064 1.625092)
			(size 0.4064 1.3716)
			(layers "F.Cu" "F.Mask" "F.Paste")
			(net "GPU_BASE_ID1_R")
		)
		(pad "17" smd rect
			(at 2.925064 0.975106)
			(size 0.4064 1.3716)
			(layers "F.Cu" "F.Mask" "F.Paste")
			(net "GPU_PEX_STRAP0_R")
		)
		(pad "18" smd rect
			(at 2.925064 0.32512)
			(size 0.4064 1.3716)
			(layers "F.Cu" "F.Mask" "F.Paste")
			(net "GPU_PEX_STRAP1_R")
		)
		(pad "19" smd rect
			(at 2.925064 -0.32512)
			(size 0.4064 1.3716)
			(layers "F.Cu" "F.Mask" "F.Paste")
			(net "PRSNT_CABLE_GPU_A1_ISO_R1_N")
		)
		(pad "20" smd rect
			(at 2.925064 -0.975106)
			(size 0.4064 1.3716)
			(layers "F.Cu" "F.Mask" "F.Paste")
			(net "PRSNT_CABLE_GPU_A3_ISO_R_N")
		)
		(pad "21" smd rect
			(at 2.925064 -1.625092)
			(size 0.4064 1.3716)
			(layers "F.Cu" "F.Mask" "F.Paste")
			(net "TCA9539_0_ADD0")
		)
		(pad "22" smd rect
			(at 2.925064 -2.275078)
			(size 0.4064 1.3716)
			(layers "F.Cu" "F.Mask" "F.Paste")
			(net "SMB_IOEXP_3V3AUX_SCL_R1")
		)
		(pad "23" smd rect
			(at 2.925064 -2.925064)
			(size 0.4064 1.3716)
			(layers "F.Cu" "F.Mask" "F.Paste")
			(net "SMB_IOEXP_3V3AUX_SDA_R1")
		)
		(pad "24" smd rect
			(at 2.925064 -3.674872)
			(size 0.6096 1.3716)
			(layers "F.Cu" "F.Mask" "F.Paste")
			(net "P3V3_AUX")
		)
	)
	(footprint ""
		(layer "F.Cu")
		(at 213.67496 -360.764074)
		(property "Reference" "H111"
			(at -8.086852 -7.844028 0)
			(unlocked yes)
			(layer "F.SilkS")
			(effects
				(font
					(size 0.7874 0.5842)
					(thickness 0.1524)
				)
				(justify left)
			)
		)
		(property "Value" ""
			(at 0 0 0)
			(layer "F.Fab")
			(effects
				(font
					(size 1.27 1.27)
				)
			)
		)
		(duplicate_pad_numbers_are_jumpers no)
		(fp_circle
			(center 0 0)
			(end 7.999984 0)
			(stroke
				(width 0.1524)
				(type default)
			)
			(fill no)
			(layer "F.SilkS")
		)
		(fp_circle
			(center 0 0)
			(end 7.999984 0)
			(stroke
				(width 0.1524)
				(type default)
			)
			(fill no)
			(layer "B.SilkS")
		)
		(fp_circle
			(center 0 0)
			(end 7.999984 0)
			(stroke
				(width 0.1)
				(type default)
			)
			(fill no)
			(layer "B.Fab")
		)
		(fp_circle
			(center 0 0)
			(end 7.999984 0)
			(stroke
				(width 0.1)
				(type default)
			)
			(fill no)
			(layer "F.Fab")
		)
		(pad "" np_thru_hole circle
			(at 0 0)
			(size 4.0132 4.0132)
			(drill 4.0132)
			(layers "*.Cu" "*.Mask")
			(clearance 0.381)
			(thermal_gap 0.381)
		)
		(pad "2" thru_hole circle
			(at 3.2639 0)
			(size 0.9144 0.9144)
			(drill 0.5588)
			(layers "*.Cu" "*.Mask")
			(remove_unused_layers no)
			(net "GND")
			(clearance 0.0762)
			(thermal_gap 0.0762)
		)
		(pad "3" thru_hole circle
			(at 2.307844 -2.307844)
			(size 0.9144 0.9144)
			(drill 0.5588)
			(layers "*.Cu" "*.Mask")
			(remove_unused_layers no)
			(net "GND")
			(clearance 0.0762)
			(thermal_gap 0.0762)
		)
		(pad "4" thru_hole circle
			(at 0 -3.2639)
			(size 0.9144 0.9144)
			(drill 0.5588)
			(layers "*.Cu" "*.Mask")
			(remove_unused_layers no)
			(net "GND")
			(clearance 0.0762)
			(thermal_gap 0.0762)
		)
		(pad "5" thru_hole circle
			(at -2.307844 -2.307844)
			(size 0.9144 0.9144)
			(drill 0.5588)
			(layers "*.Cu" "*.Mask")
			(remove_unused_layers no)
			(net "GND")
			(clearance 0.0762)
			(thermal_gap 0.0762)
		)
		(pad "6" thru_hole circle
			(at -3.2639 0)
			(size 0.9144 0.9144)
			(drill 0.5588)
			(layers "*.Cu" "*.Mask")
			(remove_unused_layers no)
			(net "GND")
			(clearance 0.0762)
			(thermal_gap 0.0762)
		)
		(pad "7" thru_hole circle
			(at -2.307844 2.307844)
			(size 0.9144 0.9144)
			(drill 0.5588)
			(layers "*.Cu" "*.Mask")
			(remove_unused_layers no)
			(net "GND")
			(clearance 0.0762)
			(thermal_gap 0.0762)
		)
		(pad "8" thru_hole circle
			(at 0 3.2639)
			(size 0.9144 0.9144)
			(drill 0.5588)
			(layers "*.Cu" "*.Mask")
			(remove_unused_layers no)
			(net "GND")
			(clearance 0.0762)
			(thermal_gap 0.0762)
		)
		(pad "9" thru_hole circle
			(at 2.307844 2.307844)
			(size 0.9144 0.9144)
			(drill 0.5588)
			(layers "*.Cu" "*.Mask")
			(remove_unused_layers no)
			(net "GND")
			(clearance 0.0762)
			(thermal_gap 0.0762)
		)
		(zone
			(layer "F.Cu")
			(hatch none 0.5)
			(connect_pads
				(clearance 0)
			)
			(min_thickness 0.25)
			(keepout
				(tracks not_allowed)
				(vias allowed)
				(pads allowed)
				(copperpour not_allowed)
				(footprints allowed)
			)
			(placement
				(enabled no)
				(sheetname "")
			)
			(fill
				(thermal_gap 0.5)
				(thermal_bridge_width 0.5)
				(island_removal_mode 0)
			)
			(polygon
				(pts
					(arc
						(start 213.67496 -356.496874)
						(mid 209.40776 -360.764074)
						(end 213.67496 -365.031274)
					)
					(arc
						(start 213.67496 -368.764058)
						(mid 208.018117 -366.420917)
						(end 205.674976 -360.764074)
					)
					(arc
						(start 205.674976 -360.764074)
						(mid 208.018117 -355.107231)
						(end 213.67496 -352.76409)
					)
				)
			)
		)
		(zone
			(layer "F.Cu")
			(hatch none 0.5)
			(connect_pads
				(clearance 0)
			)
			(min_thickness 0.25)
			(keepout
				(tracks not_allowed)
				(vias allowed)
				(pads allowed)
				(copperpour not_allowed)
				(footprints allowed)
			)
			(placement
				(enabled no)
				(sheetname "")
			)
			(fill
				(thermal_gap 0.5)
				(thermal_bridge_width 0.5)
				(island_removal_mode 0)
			)
			(polygon
				(pts
					(arc
						(start 213.67496 -356.496874)
						(mid 217.94216 -360.764074)
						(end 213.67496 -365.031274)
					)
					(arc
						(start 213.67496 -368.764058)
						(mid 219.331803 -366.420917)
						(end 221.674944 -360.764074)
					)
					(arc
						(start 221.674944 -360.764074)
						(mid 219.331803 -355.107231)
						(end 213.67496 -352.76409)
					)
				)
			)
		)
		(zone
			(layers "F.Cu" "B.Cu" "In1.Cu" "In2.Cu" "In3.Cu" "In4.Cu" "In5.Cu" "In6.Cu"
				"In7.Cu" "In8.Cu" "In9.Cu" "In10.Cu" "In11.Cu" "In12.Cu" "In13.Cu" "In14.Cu"
				"In15.Cu" "In16.Cu"
			)
			(hatch none 0.5)
			(connect_pads
				(clearance 0)
			)
			(min_thickness 0.25)
			(keepout
				(tracks not_allowed)
				(vias allowed)
				(pads allowed)
				(copperpour not_allowed)
				(footprints allowed)
			)
			(placement
				(enabled no)
				(sheetname "")
			)
			(fill
				(thermal_gap 0.5)
				(thermal_bridge_width 0.5)
				(island_removal_mode 0)
			)
			(polygon
				(pts
					(arc
						(start 216.18702 -360.764074)
						(mid 211.1629 -360.764074)
						(end 216.18702 -360.764074)
					)
				)
			)
		)
		(zone
			(layer "B.Cu")
			(hatch none 0.5)
			(connect_pads
				(clearance 0)
			)
			(min_thickness 0.25)
			(keepout
				(tracks not_allowed)
				(vias allowed)
				(pads allowed)
				(copperpour not_allowed)
				(footprints allowed)
			)
			(placement
				(enabled no)
				(sheetname "")
			)
			(fill
				(thermal_gap 0.5)
				(thermal_bridge_width 0.5)
				(island_removal_mode 0)
			)
			(polygon
				(pts
					(arc
						(start 213.67496 -365.285274)
						(mid 209.15376 -360.764074)
						(end 213.67496 -356.242874)
					)
					(arc
						(start 213.67496 -356.725474)
						(mid 209.63636 -360.764074)
						(end 213.67496 -364.802674)
					)
				)
			)
		)
		(zone
			(layer "B.Cu")
			(hatch none 0.5)
			(connect_pads
				(clearance 0)
			)
			(min_thickness 0.25)
			(keepout
				(tracks not_allowed)
				(vias allowed)
				(pads allowed)
				(copperpour not_allowed)
				(footprints allowed)
			)
			(placement
				(enabled no)
				(sheetname "")
			)
			(fill
				(thermal_gap 0.5)
				(thermal_bridge_width 0.5)
				(island_removal_mode 0)
			)
			(polygon
				(pts
					(arc
						(start 213.67496 -365.285274)
						(mid 218.19616 -360.764074)
						(end 213.67496 -356.242874)
					)
					(arc
						(start 213.67496 -356.725474)
						(mid 217.71356 -360.764074)
						(end 213.67496 -364.802674)
					)
				)
			)
		)
	)
	(footprint ""
		(layer "F.Cu")
		(at 278.254206 -431.191416 -90)
		(property "Reference" "C69"
			(at 0 0 270)
			(layer "F.SilkS")
			(hide yes)
			(effects
				(font
					(size 1.27 1.27)
				)
			)
		)
		(property "Value" ""
			(at 0 0 270)
			(layer "F.Fab")
			(effects
				(font
					(size 1.27 1.27)
				)
			)
		)
		(duplicate_pad_numbers_are_jumpers no)
		(fp_line
			(start -0.7874 0.4064)
			(end -0.7874 -0.4064)
			(stroke
				(width 0.1524)
				(type default)
			)
			(layer "F.SilkS")
		)
		(fp_line
			(start 0.7874 0.4064)
			(end -0.7874 0.4064)
			(stroke
				(width 0.1524)
				(type default)
			)
			(layer "F.SilkS")
		)
		(fp_line
			(start -0.7874 -0.4064)
			(end 0.7874 -0.4064)
			(stroke
				(width 0.1524)
				(type default)
			)
			(layer "F.SilkS")
		)
		(fp_line
			(start 0.7874 -0.4064)
			(end 0.7874 0.4064)
			(stroke
				(width 0.1524)
				(type default)
			)
			(layer "F.SilkS")
		)
		(fp_line
			(start -0.67945 0.3048)
			(end -0.67945 -0.305054)
			(stroke
				(width 0.1)
				(type default)
			)
			(layer "F.Fab")
		)
		(fp_line
			(start -0.12065 0.3048)
			(end -0.67945 0.3048)
			(stroke
				(width 0.1)
				(type default)
			)
			(layer "F.Fab")
		)
		(fp_line
			(start 0.120396 0.3048)
			(end 0.120396 0.2794)
			(stroke
				(width 0.1)
				(type default)
			)
			(layer "F.Fab")
		)
		(fp_line
			(start 0.67945 0.3048)
			(end 0.120396 0.3048)
			(stroke
				(width 0.1)
				(type default)
			)
			(layer "F.Fab")
		)
		(fp_line
			(start -0.12065 0.2794)
			(end -0.12065 0.3048)
			(stroke
				(width 0.1)
				(type default)
			)
			(layer "F.Fab")
		)
		(fp_line
			(start 0.120396 0.2794)
			(end -0.12065 0.2794)
			(stroke
				(width 0.1)
				(type default)
			)
			(layer "F.Fab")
		)
		(fp_line
			(start -0.12065 -0.2794)
			(end 0.12065 -0.2794)
			(stroke
				(width 0.1)
				(type default)
			)
			(layer "F.Fab")
		)
		(fp_line
			(start 0.12065 -0.2794)
			(end 0.12065 -0.3048)
			(stroke
				(width 0.1)
				(type default)
			)
			(layer "F.Fab")
		)
		(fp_line
			(start 0.12065 -0.3048)
			(end 0.67945 -0.3048)
			(stroke
				(width 0.1)
				(type default)
			)
			(layer "F.Fab")
		)
		(fp_line
			(start 0.67945 -0.3048)
			(end 0.67945 0.3048)
			(stroke
				(width 0.1)
				(type default)
			)
			(layer "F.Fab")
		)
		(fp_line
			(start -0.67945 -0.305054)
			(end -0.12065 -0.305054)
			(stroke
				(width 0.1)
				(type default)
			)
			(layer "F.Fab")
		)
		(fp_line
			(start -0.12065 -0.305054)
			(end -0.12065 -0.2794)
			(stroke
				(width 0.1)
				(type default)
			)
			(layer "F.Fab")
		)
		(pad "1" smd circle
			(at -0.40005 0 270)
			(size 0 0)
			(layers "F.Cu" "F.Mask" "F.Paste")
			(net "P3V3_AUX")
		)
		(pad "2" smd circle
			(at 0.40005 0 270)
			(size 0 0)
			(layers "F.Cu" "F.Mask" "F.Paste")
			(net "GND")
		)
	)
	(footprint ""
		(layer "F.Cu")
		(at 404.891748 -17.624298 90)
		(property "Reference" "C1559"
			(at 0 0 90)
			(layer "F.SilkS")
			(hide yes)
			(effects
				(font
					(size 1.27 1.27)
				)
			)
		)
		(property "Value" ""
			(at 0 0 90)
			(layer "F.Fab")
			(effects
				(font
					(size 1.27 1.27)
				)
			)
		)
		(duplicate_pad_numbers_are_jumpers no)
		(fp_line
			(start 0.299974 -0.150114)
			(end 0.299974 0.150114)
			(stroke
				(width 0.1)
				(type default)
			)
			(layer "F.Fab")
		)
		(fp_line
			(start -0.299974 -0.150114)
			(end 0.299974 -0.150114)
			(stroke
				(width 0.1)
				(type default)
			)
			(layer "F.Fab")
		)
		(fp_line
			(start 0.299974 0.150114)
			(end -0.299974 0.150114)
			(stroke
				(width 0.1)
				(type default)
			)
			(layer "F.Fab")
		)
		(fp_line
			(start -0.299974 0.150114)
			(end -0.299974 -0.150114)
			(stroke
				(width 0.1)
				(type default)
			)
			(layer "F.Fab")
		)
		(pad "1" smd rect
			(at -0.2667 0 90)
			(size 0.3048 0.381)
			(layers "F.Cu" "F.Mask" "F.Paste")
			(net "P5E_CPU0_G3_TX_C_DP<10>")
		)
		(pad "2" smd rect
			(at 0.2667 0 90)
			(size 0.3048 0.381)
			(layers "F.Cu" "F.Mask" "F.Paste")
			(net "P5E_CPU0_G3_TX_DP<10>")
		)
	)
	(footprint ""
		(layer "F.Cu")
		(at 80.498696 -178.0921 90)
		(property "Reference" "PC270"
			(at 0 0 90)
			(layer "F.SilkS")
			(hide yes)
			(effects
				(font
					(size 1.27 1.27)
				)
			)
		)
		(property "Value" ""
			(at 0 0 90)
			(layer "F.Fab")
			(effects
				(font
					(size 1.27 1.27)
				)
			)
		)
		(duplicate_pad_numbers_are_jumpers no)
		(fp_line
			(start 0.7874 -0.4064)
			(end 0.7874 0.4064)
			(stroke
				(width 0.1524)
				(type default)
			)
			(layer "F.SilkS")
		)
		(fp_line
			(start -0.7874 -0.4064)
			(end 0.7874 -0.4064)
			(stroke
				(width 0.1524)
				(type default)
			)
			(layer "F.SilkS")
		)
		(fp_line
			(start 0.7874 0.4064)
			(end -0.7874 0.4064)
			(stroke
				(width 0.1524)
				(type default)
			)
			(layer "F.SilkS")
		)
		(fp_line
			(start -0.7874 0.4064)
			(end -0.7874 -0.4064)
			(stroke
				(width 0.1524)
				(type default)
			)
			(layer "F.SilkS")
		)
		(fp_line
			(start -0.12065 -0.305054)
			(end -0.12065 -0.2794)
			(stroke
				(width 0.1)
				(type default)
			)
			(layer "F.Fab")
		)
		(fp_line
			(start -0.67945 -0.305054)
			(end -0.12065 -0.305054)
			(stroke
				(width 0.1)
				(type default)
			)
			(layer "F.Fab")
		)
		(fp_line
			(start 0.67945 -0.3048)
			(end 0.67945 0.3048)
			(stroke
				(width 0.1)
				(type default)
			)
			(layer "F.Fab")
		)
		(fp_line
			(start 0.12065 -0.3048)
			(end 0.67945 -0.3048)
			(stroke
				(width 0.1)
				(type default)
			)
			(layer "F.Fab")
		)
		(fp_line
			(start 0.12065 -0.2794)
			(end 0.12065 -0.3048)
			(stroke
				(width 0.1)
				(type default)
			)
			(layer "F.Fab")
		)
		(fp_line
			(start -0.12065 -0.2794)
			(end 0.12065 -0.2794)
			(stroke
				(width 0.1)
				(type default)
			)
			(layer "F.Fab")
		)
		(fp_line
			(start 0.120396 0.2794)
			(end -0.12065 0.2794)
			(stroke
				(width 0.1)
				(type default)
			)
			(layer "F.Fab")
		)
		(fp_line
			(start -0.12065 0.2794)
			(end -0.12065 0.3048)
			(stroke
				(width 0.1)
				(type default)
			)
			(layer "F.Fab")
		)
		(fp_line
			(start 0.67945 0.3048)
			(end 0.120396 0.3048)
			(stroke
				(width 0.1)
				(type default)
			)
			(layer "F.Fab")
		)
		(fp_line
			(start 0.120396 0.3048)
			(end 0.120396 0.2794)
			(stroke
				(width 0.1)
				(type default)
			)
			(layer "F.Fab")
		)
		(fp_line
			(start -0.12065 0.3048)
			(end -0.67945 0.3048)
			(stroke
				(width 0.1)
				(type default)
			)
			(layer "F.Fab")
		)
		(fp_line
			(start -0.67945 0.3048)
			(end -0.67945 -0.305054)
			(stroke
				(width 0.1)
				(type default)
			)
			(layer "F.Fab")
		)
		(pad "1" smd circle
			(at -0.40005 0 90)
			(size 0 0)
			(layers "F.Cu" "F.Mask" "F.Paste")
			(net "SW_PVDDCR_CPU0_P1_BOOT1_RC")
		)
		(pad "2" smd circle
			(at 0.40005 0 90)
			(size 0 0)
			(layers "F.Cu" "F.Mask" "F.Paste")
			(net "SW_PVDDCR_CPU0_P1_PH1")
		)
	)
	(footprint ""
		(layer "F.Cu")
		(at 49.009554 -375.49963 -90)
		(property "Reference" "C828"
			(at 0 0 270)
			(layer "F.SilkS")
			(hide yes)
			(effects
				(font
					(size 1.27 1.27)
				)
			)
		)
		(property "Value" ""
			(at 0 0 270)
			(layer "F.Fab")
			(effects
				(font
					(size 1.27 1.27)
				)
			)
		)
		(duplicate_pad_numbers_are_jumpers no)
		(fp_line
			(start -0.299974 0.150114)
			(end -0.299974 -0.150114)
			(stroke
				(width 0.1)
				(type default)
			)
			(layer "F.Fab")
		)
		(fp_line
			(start 0.299974 0.150114)
			(end -0.299974 0.150114)
			(stroke
				(width 0.1)
				(type default)
			)
			(layer "F.Fab")
		)
		(fp_line
			(start -0.299974 -0.150114)
			(end 0.299974 -0.150114)
			(stroke
				(width 0.1)
				(type default)
			)
			(layer "F.Fab")
		)
		(fp_line
			(start 0.299974 -0.150114)
			(end 0.299974 0.150114)
			(stroke
				(width 0.1)
				(type default)
			)
			(layer "F.Fab")
		)
		(pad "1" smd rect
			(at -0.2667 0 270)
			(size 0.3048 0.381)
			(layers "F.Cu" "F.Mask" "F.Paste")
			(net "P5E_CPU1_P0_TX_C_DN<4>")
		)
		(pad "2" smd rect
			(at 0.2667 0 270)
			(size 0.3048 0.381)
			(layers "F.Cu" "F.Mask" "F.Paste")
			(net "P5E_CPU1_P0_TX_DN<4>")
		)
	)
	(footprint ""
		(layer "F.Cu")
		(at 353.640644 -378.95403 -90)
		(property "Reference" "C941"
			(at 0 0 270)
			(layer "F.SilkS")
			(hide yes)
			(effects
				(font
					(size 1.27 1.27)
				)
			)
		)
		(property "Value" ""
			(at 0 0 270)
			(layer "F.Fab")
			(effects
				(font
					(size 1.27 1.27)
				)
			)
		)
		(duplicate_pad_numbers_are_jumpers no)
		(fp_line
			(start -0.299974 0.150114)
			(end -0.299974 -0.150114)
			(stroke
				(width 0.1)
				(type default)
			)
			(layer "F.Fab")
		)
		(fp_line
			(start 0.299974 0.150114)
			(end -0.299974 0.150114)
			(stroke
				(width 0.1)
				(type default)
			)
			(layer "F.Fab")
		)
		(fp_line
			(start -0.299974 -0.150114)
			(end 0.299974 -0.150114)
			(stroke
				(width 0.1)
				(type default)
			)
			(layer "F.Fab")
		)
		(fp_line
			(start 0.299974 -0.150114)
			(end 0.299974 0.150114)
			(stroke
				(width 0.1)
				(type default)
			)
			(layer "F.Fab")
		)
		(pad "1" smd rect
			(at -0.2667 0 270)
			(size 0.3048 0.381)
			(layers "F.Cu" "F.Mask" "F.Paste")
			(net "P5E_CPU0_P1_TX_C_DP<12>")
		)
		(pad "2" smd rect
			(at 0.2667 0 270)
			(size 0.3048 0.381)
			(layers "F.Cu" "F.Mask" "F.Paste")
			(net "P5E_CPU0_P1_TX_DP<12>")
		)
	)
	(footprint ""
		(layer "F.Cu")
		(at 109.332014 -405.633682 180)
		(property "Reference" "R6789"
			(at 0 0 180)
			(layer "F.SilkS")
			(hide yes)
			(effects
				(font
					(size 1.27 1.27)
				)
			)
		)
		(property "Value" ""
			(at 0 0 180)
			(layer "F.Fab")
			(effects
				(font
					(size 1.27 1.27)
				)
			)
		)
		(duplicate_pad_numbers_are_jumpers no)
		(fp_line
			(start 0.32512 0.175006)
			(end -0.32512 0.175006)
			(stroke
				(width 0.1)
				(type default)
			)
			(layer "F.Fab")
		)
		(fp_line
			(start 0.32512 -0.175006)
			(end 0.32512 0.175006)
			(stroke
				(width 0.1)
				(type default)
			)
			(layer "F.Fab")
		)
		(fp_line
			(start -0.32512 0.175006)
			(end -0.32512 -0.175006)
			(stroke
				(width 0.1)
				(type default)
			)
			(layer "F.Fab")
		)
		(fp_line
			(start -0.32512 -0.175006)
			(end 0.32512 -0.175006)
			(stroke
				(width 0.1)
				(type default)
			)
			(layer "F.Fab")
		)
		(pad "1" smd rect
			(at -0.2667 0 180)
			(size 0.3048 0.381)
			(layers "F.Cu" "F.Mask" "F.Paste")
			(net "U19_E2")
		)
		(pad "2" smd rect
			(at 0.2667 0)
			(size 0.3048 0.381)
			(layers "F.Cu" "F.Mask" "F.Paste")
			(net "GND")
		)
	)
	(footprint ""
		(layer "F.Cu")
		(at 440.592972 -22.816058 180)
		(property "Reference" "PR3838"
			(at 0 0 180)
			(layer "F.SilkS")
			(hide yes)
			(effects
				(font
					(size 1.27 1.27)
				)
			)
		)
		(property "Value" ""
			(at 0 0 180)
			(layer "F.Fab")
			(effects
				(font
					(size 1.27 1.27)
				)
			)
		)
		(duplicate_pad_numbers_are_jumpers no)
		(fp_line
			(start 0.7874 0.4064)
			(end -0.7874 0.4064)
			(stroke
				(width 0.1524)
				(type default)
			)
			(layer "F.SilkS")
		)
		(fp_line
			(start 0.7874 -0.4064)
			(end 0.7874 0.4064)
			(stroke
				(width 0.1524)
				(type default)
			)
			(layer "F.SilkS")
		)
		(fp_line
			(start -0.7874 0.4064)
			(end -0.7874 -0.4064)
			(stroke
				(width 0.1524)
				(type default)
			)
			(layer "F.SilkS")
		)
		(fp_line
			(start -0.7874 -0.4064)
			(end 0.7874 -0.4064)
			(stroke
				(width 0.1524)
				(type default)
			)
			(layer "F.SilkS")
		)
		(fp_line
			(start 0.67945 0.3048)
			(end 0.120396 0.3048)
			(stroke
				(width 0.1)
				(type default)
			)
			(layer "F.Fab")
		)
		(fp_line
			(start 0.67945 -0.3048)
			(end 0.67945 0.3048)
			(stroke
				(width 0.1)
				(type default)
			)
			(layer "F.Fab")
		)
		(fp_line
			(start 0.12065 -0.2794)
			(end 0.12065 -0.3048)
			(stroke
				(width 0.1)
				(type default)
			)
			(layer "F.Fab")
		)
		(fp_line
			(start 0.12065 -0.3048)
			(end 0.67945 -0.3048)
			(stroke
				(width 0.1)
				(type default)
			)
			(layer "F.Fab")
		)
		(fp_line
			(start 0.120396 0.3048)
			(end 0.120396 0.2794)
			(stroke
				(width 0.1)
				(type default)
			)
			(layer "F.Fab")
		)
		(fp_line
			(start 0.120396 0.2794)
			(end -0.12065 0.2794)
			(stroke
				(width 0.1)
				(type default)
			)
			(layer "F.Fab")
		)
		(fp_line
			(start -0.12065 0.3048)
			(end -0.67945 0.3048)
			(stroke
				(width 0.1)
				(type default)
			)
			(layer "F.Fab")
		)
		(fp_line
			(start -0.12065 0.2794)
			(end -0.12065 0.3048)
			(stroke
				(width 0.1)
				(type default)
			)
			(layer "F.Fab")
		)
		(fp_line
			(start -0.12065 -0.2794)
			(end 0.12065 -0.2794)
			(stroke
				(width 0.1)
				(type default)
			)
			(layer "F.Fab")
		)
		(fp_line
			(start -0.12065 -0.305054)
			(end -0.12065 -0.2794)
			(stroke
				(width 0.1)
				(type default)
			)
			(layer "F.Fab")
		)
		(fp_line
			(start -0.67945 0.3048)
			(end -0.67945 -0.305054)
			(stroke
				(width 0.1)
				(type default)
			)
			(layer "F.Fab")
		)
		(fp_line
			(start -0.67945 -0.305054)
			(end -0.12065 -0.305054)
			(stroke
				(width 0.1)
				(type default)
			)
			(layer "F.Fab")
		)
		(pad "1" smd circle
			(at -0.40005 0 180)
			(size 0 0)
			(layers "F.Cu" "F.Mask" "F.Paste")
			(net "P12V_OCP_SFF")
		)
		(pad "2" smd circle
			(at 0.40005 0 180)
			(size 0 0)
			(layers "F.Cu" "F.Mask" "F.Paste")
			(net "P12V_OCP_AVIN_PD_1")
		)
	)
	(footprint ""
		(layer "F.Cu")
		(at 171.174664 -120.464072)
		(property "Reference" "R6804"
			(at 0 0 0)
			(layer "F.SilkS")
			(hide yes)
			(effects
				(font
					(size 1.27 1.27)
				)
			)
		)
		(property "Value" ""
			(at 0 0 0)
			(layer "F.Fab")
			(effects
				(font
					(size 1.27 1.27)
				)
			)
		)
		(duplicate_pad_numbers_are_jumpers no)
		(fp_line
			(start -0.7874 -0.4064)
			(end 0.7874 -0.4064)
			(stroke
				(width 0.1524)
				(type default)
			)
			(layer "F.SilkS")
		)
		(fp_line
			(start -0.7874 0.4064)
			(end -0.7874 -0.4064)
			(stroke
				(width 0.1524)
				(type default)
			)
			(layer "F.SilkS")
		)
		(fp_line
			(start 0.7874 -0.4064)
			(end 0.7874 0.4064)
			(stroke
				(width 0.1524)
				(type default)
			)
			(layer "F.SilkS")
		)
		(fp_line
			(start 0.7874 0.4064)
			(end -0.7874 0.4064)
			(stroke
				(width 0.1524)
				(type default)
			)
			(layer "F.SilkS")
		)
		(fp_line
			(start -0.67945 -0.305054)
			(end -0.12065 -0.305054)
			(stroke
				(width 0.1)
				(type default)
			)
			(layer "F.Fab")
		)
		(fp_line
			(start -0.67945 0.3048)
			(end -0.67945 -0.305054)
			(stroke
				(width 0.1)
				(type default)
			)
			(layer "F.Fab")
		)
		(fp_line
			(start -0.12065 -0.305054)
			(end -0.12065 -0.2794)
			(stroke
				(width 0.1)
				(type default)
			)
			(layer "F.Fab")
		)
		(fp_line
			(start -0.12065 -0.2794)
			(end 0.12065 -0.2794)
			(stroke
				(width 0.1)
				(type default)
			)
			(layer "F.Fab")
		)
		(fp_line
			(start -0.12065 0.2794)
			(end -0.12065 0.3048)
			(stroke
				(width 0.1)
				(type default)
			)
			(layer "F.Fab")
		)
		(fp_line
			(start -0.12065 0.3048)
			(end -0.67945 0.3048)
			(stroke
				(width 0.1)
				(type default)
			)
			(layer "F.Fab")
		)
		(fp_line
			(start 0.120396 0.2794)
			(end -0.12065 0.2794)
			(stroke
				(width 0.1)
				(type default)
			)
			(layer "F.Fab")
		)
		(fp_line
			(start 0.120396 0.3048)
			(end 0.120396 0.2794)
			(stroke
				(width 0.1)
				(type default)
			)
			(layer "F.Fab")
		)
		(fp_line
			(start 0.12065 -0.3048)
			(end 0.67945 -0.3048)
			(stroke
				(width 0.1)
				(type default)
			)
			(layer "F.Fab")
		)
		(fp_line
			(start 0.12065 -0.2794)
			(end 0.12065 -0.3048)
			(stroke
				(width 0.1)
				(type default)
			)
			(layer "F.Fab")
		)
		(fp_line
			(start 0.67945 -0.3048)
			(end 0.67945 0.3048)
			(stroke
				(width 0.1)
				(type default)
			)
			(layer "F.Fab")
		)
		(fp_line
			(start 0.67945 0.3048)
			(end 0.120396 0.3048)
			(stroke
				(width 0.1)
				(type default)
			)
			(layer "F.Fab")
		)
		(pad "1" smd circle
			(at -0.40005 0)
			(size 0 0)
			(layers "F.Cu" "F.Mask" "F.Paste")
			(net "RST_RT_CPU0_P0_PERST_R_N")
		)
		(pad "2" smd circle
			(at 0.40005 0)
			(size 0 0)
			(layers "F.Cu" "F.Mask" "F.Paste")
			(net "RST_RT_CPU0_P0_PERST_R2_N")
		)
	)
	(footprint ""
		(layer "F.Cu")
		(at 330.932536 -388.149338)
		(property "Reference" "R677"
			(at 0 0 0)
			(layer "F.SilkS")
			(hide yes)
			(effects
				(font
					(size 1.27 1.27)
				)
			)
		)
		(property "Value" ""
			(at 0 0 0)
			(layer "F.Fab")
			(effects
				(font
					(size 1.27 1.27)
				)
			)
		)
		(duplicate_pad_numbers_are_jumpers no)
		(fp_line
			(start -0.32512 -0.175006)
			(end 0.32512 -0.175006)
			(stroke
				(width 0.1)
				(type default)
			)
			(layer "F.Fab")
		)
		(fp_line
			(start -0.32512 0.175006)
			(end -0.32512 -0.175006)
			(stroke
				(width 0.1)
				(type default)
			)
			(layer "F.Fab")
		)
		(fp_line
			(start 0.32512 -0.175006)
			(end 0.32512 0.175006)
			(stroke
				(width 0.1)
				(type default)
			)
			(layer "F.Fab")
		)
		(fp_line
			(start 0.32512 0.175006)
			(end -0.32512 0.175006)
			(stroke
				(width 0.1)
				(type default)
			)
			(layer "F.Fab")
		)
		(pad "1" smd rect
			(at -0.2667 0)
			(size 0.3048 0.381)
			(layers "F.Cu" "F.Mask" "F.Paste")
			(net "SMB_RT_CPU0_P1_ROM_MUX_1D_SDA")
		)
		(pad "2" smd rect
			(at 0.2667 0 180)
			(size 0.3048 0.381)
			(layers "F.Cu" "F.Mask" "F.Paste")
			(net "SMB_RT_CPU0_P1_ROM_MUX_1D_R_SDA")
		)
	)
	(footprint ""
		(layer "F.Cu")
		(at 193.55562 -422.804082 90)
		(property "Reference" "R2948"
			(at 0 0 90)
			(layer "F.SilkS")
			(hide yes)
			(effects
				(font
					(size 1.27 1.27)
				)
			)
		)
		(property "Value" ""
			(at 0 0 90)
			(layer "F.Fab")
			(effects
				(font
					(size 1.27 1.27)
				)
			)
		)
		(duplicate_pad_numbers_are_jumpers no)
		(fp_line
			(start 0.7874 -0.4064)
			(end 0.7874 0.4064)
			(stroke
				(width 0.1524)
				(type default)
			)
			(layer "F.SilkS")
		)
		(fp_line
			(start -0.7874 -0.4064)
			(end 0.7874 -0.4064)
			(stroke
				(width 0.1524)
				(type default)
			)
			(layer "F.SilkS")
		)
		(fp_line
			(start 0.7874 0.4064)
			(end -0.7874 0.4064)
			(stroke
				(width 0.1524)
				(type default)
			)
			(layer "F.SilkS")
		)
		(fp_line
			(start -0.7874 0.4064)
			(end -0.7874 -0.4064)
			(stroke
				(width 0.1524)
				(type default)
			)
			(layer "F.SilkS")
		)
		(fp_line
			(start -0.12065 -0.305054)
			(end -0.12065 -0.2794)
			(stroke
				(width 0.1)
				(type default)
			)
			(layer "F.Fab")
		)
		(fp_line
			(start -0.67945 -0.305054)
			(end -0.12065 -0.305054)
			(stroke
				(width 0.1)
				(type default)
			)
			(layer "F.Fab")
		)
		(fp_line
			(start 0.67945 -0.3048)
			(end 0.67945 0.3048)
			(stroke
				(width 0.1)
				(type default)
			)
			(layer "F.Fab")
		)
		(fp_line
			(start 0.12065 -0.3048)
			(end 0.67945 -0.3048)
			(stroke
				(width 0.1)
				(type default)
			)
			(layer "F.Fab")
		)
		(fp_line
			(start 0.12065 -0.2794)
			(end 0.12065 -0.3048)
			(stroke
				(width 0.1)
				(type default)
			)
			(layer "F.Fab")
		)
		(fp_line
			(start -0.12065 -0.2794)
			(end 0.12065 -0.2794)
			(stroke
				(width 0.1)
				(type default)
			)
			(layer "F.Fab")
		)
		(fp_line
			(start 0.120396 0.2794)
			(end -0.12065 0.2794)
			(stroke
				(width 0.1)
				(type default)
			)
			(layer "F.Fab")
		)
		(fp_line
			(start -0.12065 0.2794)
			(end -0.12065 0.3048)
			(stroke
				(width 0.1)
				(type default)
			)
			(layer "F.Fab")
		)
		(fp_line
			(start 0.67945 0.3048)
			(end 0.120396 0.3048)
			(stroke
				(width 0.1)
				(type default)
			)
			(layer "F.Fab")
		)
		(fp_line
			(start 0.120396 0.3048)
			(end 0.120396 0.2794)
			(stroke
				(width 0.1)
				(type default)
			)
			(layer "F.Fab")
		)
		(fp_line
			(start -0.12065 0.3048)
			(end -0.67945 0.3048)
			(stroke
				(width 0.1)
				(type default)
			)
			(layer "F.Fab")
		)
		(fp_line
			(start -0.67945 0.3048)
			(end -0.67945 -0.305054)
			(stroke
				(width 0.1)
				(type default)
			)
			(layer "F.Fab")
		)
		(pad "1" smd circle
			(at -0.40005 0 90)
			(size 0 0)
			(layers "F.Cu" "F.Mask" "F.Paste")
			(net "FM_GPU_HSC_EN_BUF_R")
		)
		(pad "2" smd circle
			(at 0.40005 0 90)
			(size 0 0)
			(layers "F.Cu" "F.Mask" "F.Paste")
			(net "GND")
		)
	)
	(footprint ""
		(layer "F.Cu")
		(at 262.848852 -137.103104 -90)
		(property "Reference" "C1103"
			(at 0 0 270)
			(layer "F.SilkS")
			(hide yes)
			(effects
				(font
					(size 1.27 1.27)
				)
			)
		)
		(property "Value" ""
			(at 0 0 270)
			(layer "F.Fab")
			(effects
				(font
					(size 1.27 1.27)
				)
			)
		)
		(duplicate_pad_numbers_are_jumpers no)
		(fp_line
			(start -0.7874 0.4064)
			(end -0.7874 -0.4064)
			(stroke
				(width 0.1524)
				(type default)
			)
			(layer "F.SilkS")
		)
		(fp_line
			(start 0.7874 0.4064)
			(end -0.7874 0.4064)
			(stroke
				(width 0.1524)
				(type default)
			)
			(layer "F.SilkS")
		)
		(fp_line
			(start -0.7874 -0.4064)
			(end 0.7874 -0.4064)
			(stroke
				(width 0.1524)
				(type default)
			)
			(layer "F.SilkS")
		)
		(fp_line
			(start 0.7874 -0.4064)
			(end 0.7874 0.4064)
			(stroke
				(width 0.1524)
				(type default)
			)
			(layer "F.SilkS")
		)
		(fp_line
			(start -0.67945 0.3048)
			(end -0.67945 -0.305054)
			(stroke
				(width 0.1)
				(type default)
			)
			(layer "F.Fab")
		)
		(fp_line
			(start -0.12065 0.3048)
			(end -0.67945 0.3048)
			(stroke
				(width 0.1)
				(type default)
			)
			(layer "F.Fab")
		)
		(fp_line
			(start 0.120396 0.3048)
			(end 0.120396 0.2794)
			(stroke
				(width 0.1)
				(type default)
			)
			(layer "F.Fab")
		)
		(fp_line
			(start 0.67945 0.3048)
			(end 0.120396 0.3048)
			(stroke
				(width 0.1)
				(type default)
			)
			(layer "F.Fab")
		)
		(fp_line
			(start -0.12065 0.2794)
			(end -0.12065 0.3048)
			(stroke
				(width 0.1)
				(type default)
			)
			(layer "F.Fab")
		)
		(fp_line
			(start 0.120396 0.2794)
			(end -0.12065 0.2794)
			(stroke
				(width 0.1)
				(type default)
			)
			(layer "F.Fab")
		)
		(fp_line
			(start -0.12065 -0.2794)
			(end 0.12065 -0.2794)
			(stroke
				(width 0.1)
				(type default)
			)
			(layer "F.Fab")
		)
		(fp_line
			(start 0.12065 -0.2794)
			(end 0.12065 -0.3048)
			(stroke
				(width 0.1)
				(type default)
			)
			(layer "F.Fab")
		)
		(fp_line
			(start 0.12065 -0.3048)
			(end 0.67945 -0.3048)
			(stroke
				(width 0.1)
				(type default)
			)
			(layer "F.Fab")
		)
		(fp_line
			(start 0.67945 -0.3048)
			(end 0.67945 0.3048)
			(stroke
				(width 0.1)
				(type default)
			)
			(layer "F.Fab")
		)
		(fp_line
			(start -0.67945 -0.305054)
			(end -0.12065 -0.305054)
			(stroke
				(width 0.1)
				(type default)
			)
			(layer "F.Fab")
		)
		(fp_line
			(start -0.12065 -0.305054)
			(end -0.12065 -0.2794)
			(stroke
				(width 0.1)
				(type default)
			)
			(layer "F.Fab")
		)
		(pad "1" smd circle
			(at -0.40005 0 270)
			(size 0 0)
			(layers "F.Cu" "F.Mask" "F.Paste")
			(net "PVDD18_S5_P0")
		)
		(pad "2" smd circle
			(at 0.40005 0 270)
			(size 0 0)
			(layers "F.Cu" "F.Mask" "F.Paste")
			(net "GND")
		)
	)
	(footprint ""
		(layer "F.Cu")
		(at 170.979846 -383.11709 180)
		(property "Reference" "R887"
			(at 0 0 180)
			(layer "F.SilkS")
			(hide yes)
			(effects
				(font
					(size 1.27 1.27)
				)
			)
		)
		(property "Value" ""
			(at 0 0 180)
			(layer "F.Fab")
			(effects
				(font
					(size 1.27 1.27)
				)
			)
		)
		(duplicate_pad_numbers_are_jumpers no)
		(fp_line
			(start 0.32512 0.175006)
			(end -0.32512 0.175006)
			(stroke
				(width 0.1)
				(type default)
			)
			(layer "F.Fab")
		)
		(fp_line
			(start 0.32512 -0.175006)
			(end 0.32512 0.175006)
			(stroke
				(width 0.1)
				(type default)
			)
			(layer "F.Fab")
		)
		(fp_line
			(start -0.32512 0.175006)
			(end -0.32512 -0.175006)
			(stroke
				(width 0.1)
				(type default)
			)
			(layer "F.Fab")
		)
		(fp_line
			(start -0.32512 -0.175006)
			(end 0.32512 -0.175006)
			(stroke
				(width 0.1)
				(type default)
			)
			(layer "F.Fab")
		)
		(pad "1" smd rect
			(at -0.2667 0 180)
			(size 0.3048 0.381)
			(layers "F.Cu" "F.Mask" "F.Paste")
			(net "P1V8_CPU1_RT_1D")
		)
		(pad "2" smd rect
			(at 0.2667 0)
			(size 0.3048 0.381)
			(layers "F.Cu" "F.Mask" "F.Paste")
			(net "RT_CPU1_P2_ADDR1")
		)
	)
	(footprint ""
		(layer "F.Cu")
		(at 317.896748 -115.108228 180)
		(property "Reference" "R86"
			(at 0 0 180)
			(layer "F.SilkS")
			(hide yes)
			(effects
				(font
					(size 1.27 1.27)
				)
			)
		)
		(property "Value" ""
			(at 0 0 180)
			(layer "F.Fab")
			(effects
				(font
					(size 1.27 1.27)
				)
			)
		)
		(duplicate_pad_numbers_are_jumpers no)
		(fp_line
			(start 0.7874 0.4064)
			(end -0.7874 0.4064)
			(stroke
				(width 0.1524)
				(type default)
			)
			(layer "F.SilkS")
		)
		(fp_line
			(start 0.7874 -0.4064)
			(end 0.7874 0.4064)
			(stroke
				(width 0.1524)
				(type default)
			)
			(layer "F.SilkS")
		)
		(fp_line
			(start -0.7874 0.4064)
			(end -0.7874 -0.4064)
			(stroke
				(width 0.1524)
				(type default)
			)
			(layer "F.SilkS")
		)
		(fp_line
			(start -0.7874 -0.4064)
			(end 0.7874 -0.4064)
			(stroke
				(width 0.1524)
				(type default)
			)
			(layer "F.SilkS")
		)
		(fp_line
			(start 0.67945 0.3048)
			(end 0.120396 0.3048)
			(stroke
				(width 0.1)
				(type default)
			)
			(layer "F.Fab")
		)
		(fp_line
			(start 0.67945 -0.3048)
			(end 0.67945 0.3048)
			(stroke
				(width 0.1)
				(type default)
			)
			(layer "F.Fab")
		)
		(fp_line
			(start 0.12065 -0.2794)
			(end 0.12065 -0.3048)
			(stroke
				(width 0.1)
				(type default)
			)
			(layer "F.Fab")
		)
		(fp_line
			(start 0.12065 -0.3048)
			(end 0.67945 -0.3048)
			(stroke
				(width 0.1)
				(type default)
			)
			(layer "F.Fab")
		)
		(fp_line
			(start 0.120396 0.3048)
			(end 0.120396 0.2794)
			(stroke
				(width 0.1)
				(type default)
			)
			(layer "F.Fab")
		)
		(fp_line
			(start 0.120396 0.2794)
			(end -0.12065 0.2794)
			(stroke
				(width 0.1)
				(type default)
			)
			(layer "F.Fab")
		)
		(fp_line
			(start -0.12065 0.3048)
			(end -0.67945 0.3048)
			(stroke
				(width 0.1)
				(type default)
			)
			(layer "F.Fab")
		)
		(fp_line
			(start -0.12065 0.2794)
			(end -0.12065 0.3048)
			(stroke
				(width 0.1)
				(type default)
			)
			(layer "F.Fab")
		)
		(fp_line
			(start -0.12065 -0.2794)
			(end 0.12065 -0.2794)
			(stroke
				(width 0.1)
				(type default)
			)
			(layer "F.Fab")
		)
		(fp_line
			(start -0.12065 -0.305054)
			(end -0.12065 -0.2794)
			(stroke
				(width 0.1)
				(type default)
			)
			(layer "F.Fab")
		)
		(fp_line
			(start -0.67945 0.3048)
			(end -0.67945 -0.305054)
			(stroke
				(width 0.1)
				(type default)
			)
			(layer "F.Fab")
		)
		(fp_line
			(start -0.67945 -0.305054)
			(end -0.12065 -0.305054)
			(stroke
				(width 0.1)
				(type default)
			)
			(layer "F.Fab")
		)
		(pad "1" smd circle
			(at -0.40005 0 180)
			(size 0 0)
			(layers "F.Cu" "F.Mask" "F.Paste")
			(net "SMB_FRU_3V3AUX_SDA")
		)
		(pad "2" smd circle
			(at 0.40005 0 180)
			(size 0 0)
			(layers "F.Cu" "F.Mask" "F.Paste")
			(net "SMB_FRU_3V3AUX_R1_SDA")
		)
	)
	(footprint ""
		(layer "F.Cu")
		(at 447.237866 -405.7777 180)
		(property "Reference" "PC6558_1"
			(at 0 0 180)
			(layer "F.SilkS")
			(hide yes)
			(effects
				(font
					(size 1.27 1.27)
				)
			)
		)
		(property "Value" ""
			(at 0 0 180)
			(layer "F.Fab")
			(effects
				(font
					(size 1.27 1.27)
				)
			)
		)
		(duplicate_pad_numbers_are_jumpers no)
		(fp_line
			(start 1.524 0.762)
			(end -1.524 0.762)
			(stroke
				(width 0.1524)
				(type default)
			)
			(layer "F.SilkS")
		)
		(fp_line
			(start 1.524 -0.762)
			(end 1.524 0.762)
			(stroke
				(width 0.1524)
				(type default)
			)
			(layer "F.SilkS")
		)
		(fp_line
			(start -1.524 0.762)
			(end -1.524 -0.762)
			(stroke
				(width 0.1524)
				(type default)
			)
			(layer "F.SilkS")
		)
		(fp_line
			(start -1.524 -0.762)
			(end 1.524 -0.762)
			(stroke
				(width 0.1524)
				(type default)
			)
			(layer "F.SilkS")
		)
		(fp_line
			(start 1.1049 0.724916)
			(end 1.1049 -0.724916)
			(stroke
				(width 0.1)
				(type default)
			)
			(layer "F.Fab")
		)
		(fp_line
			(start 1.1049 -0.724916)
			(end -1.1049 -0.724916)
			(stroke
				(width 0.1)
				(type default)
			)
			(layer "F.Fab")
		)
		(fp_line
			(start -1.1049 0.724916)
			(end 1.1049 0.724916)
			(stroke
				(width 0.1)
				(type default)
			)
			(layer "F.Fab")
		)
		(fp_line
			(start -1.1049 -0.724916)
			(end -1.1049 0.724916)
			(stroke
				(width 0.1)
				(type default)
			)
			(layer "F.Fab")
		)
		(pad "1" smd rect
			(at -0.889 0)
			(size 1.016 1.27)
			(layers "F.Cu" "F.Mask" "F.Paste")
			(net "SW_P12V_AUX_P0V9_RETIMER_CPU0_FLT")
		)
		(pad "2" smd rect
			(at 0.889 0)
			(size 1.016 1.27)
			(layers "F.Cu" "F.Mask" "F.Paste")
			(net "GND")
		)
	)
	(footprint ""
		(layer "F.Cu")
		(at 446.52438 -65.767458 -90)
		(property "Reference" "C60"
			(at 0 0 270)
			(layer "F.SilkS")
			(hide yes)
			(effects
				(font
					(size 1.27 1.27)
				)
			)
		)
		(property "Value" ""
			(at 0 0 270)
			(layer "F.Fab")
			(effects
				(font
					(size 1.27 1.27)
				)
			)
		)
		(duplicate_pad_numbers_are_jumpers no)
		(fp_line
			(start -1.524 0.762)
			(end -1.524 -0.762)
			(stroke
				(width 0.1524)
				(type default)
			)
			(layer "F.SilkS")
		)
		(fp_line
			(start 1.524 0.762)
			(end -1.524 0.762)
			(stroke
				(width 0.1524)
				(type default)
			)
			(layer "F.SilkS")
		)
		(fp_line
			(start -1.524 -0.762)
			(end 1.524 -0.762)
			(stroke
				(width 0.1524)
				(type default)
			)
			(layer "F.SilkS")
		)
		(fp_line
			(start 1.524 -0.762)
			(end 1.524 0.762)
			(stroke
				(width 0.1524)
				(type default)
			)
			(layer "F.SilkS")
		)
		(fp_line
			(start -1.1049 0.724916)
			(end 1.1049 0.724916)
			(stroke
				(width 0.1)
				(type default)
			)
			(layer "F.Fab")
		)
		(fp_line
			(start 1.1049 0.724916)
			(end 1.1049 -0.724916)
			(stroke
				(width 0.1)
				(type default)
			)
			(layer "F.Fab")
		)
		(fp_line
			(start -1.1049 -0.724916)
			(end -1.1049 0.724916)
			(stroke
				(width 0.1)
				(type default)
			)
			(layer "F.Fab")
		)
		(fp_line
			(start 1.1049 -0.724916)
			(end -1.1049 -0.724916)
			(stroke
				(width 0.1)
				(type default)
			)
			(layer "F.Fab")
		)
		(pad "1" smd rect
			(at -0.889 0 90)
			(size 1.016 1.27)
			(layers "F.Cu" "F.Mask" "F.Paste")
			(net "P3V3_AUX")
		)
		(pad "2" smd rect
			(at 0.889 0 90)
			(size 1.016 1.27)
			(layers "F.Cu" "F.Mask" "F.Paste")
			(net "GND")
		)
	)
	(footprint ""
		(layer "F.Cu")
		(at 69.85127 -152.33269 90)
		(property "Reference" "PU3"
			(at 4.542536 -1.890014 0)
			(unlocked yes)
			(layer "F.SilkS")
			(effects
				(font
					(size 0.7874 0.5842)
					(thickness 0.1524)
				)
				(justify left)
			)
		)
		(property "Value" ""
			(at 0 0 90)
			(layer "F.Fab")
			(effects
				(font
					(size 1.27 1.27)
				)
			)
		)
		(duplicate_pad_numbers_are_jumpers no)
		(fp_line
			(start 1.549908 -2.050034)
			(end 0.5842 -2.050034)
			(stroke
				(width 0.1524)
				(type default)
			)
			(layer "F.SilkS")
		)
		(fp_line
			(start -0.5842 -2.050034)
			(end -1.549908 -2.050034)
			(stroke
				(width 0.1524)
				(type default)
			)
			(layer "F.SilkS")
		)
		(fp_line
			(start -1.549908 -2.050034)
			(end -1.549908 -1.9812)
			(stroke
				(width 0.1524)
				(type default)
			)
			(layer "F.SilkS")
		)
		(fp_line
			(start 1.549908 -1.9812)
			(end 1.549908 -2.050034)
			(stroke
				(width 0.1524)
				(type default)
			)
			(layer "F.SilkS")
		)
		(fp_line
			(start -1.549908 1.9812)
			(end -1.549908 2.050034)
			(stroke
				(width 0.1524)
				(type default)
			)
			(layer "F.SilkS")
		)
		(fp_line
			(start 0 2.050034)
			(end 1.549908 2.050034)
			(stroke
				(width 0.1524)
				(type default)
			)
			(layer "F.SilkS")
		)
		(fp_line
			(start -1.549908 2.050034)
			(end -0.5842 2.050034)
			(stroke
				(width 0.1524)
				(type default)
			)
			(layer "F.SilkS")
		)
		(fp_poly
			(pts
				(xy -1.991868 -1.787398) (xy -3.007868 -1.279398) (xy -3.007868 -2.295398)
			)
			(stroke
				(width 0)
				(type default)
			)
			(fill yes)
			(layer "F.SilkS")
		)
		(fp_line
			(start 1.549908 -2.050034)
			(end -1.549908 -2.050034)
			(stroke
				(width 0.1)
				(type default)
			)
			(layer "F.Fab")
		)
		(fp_line
			(start -1.549908 -2.050034)
			(end -1.549908 2.050034)
			(stroke
				(width 0.1)
				(type default)
			)
			(layer "F.Fab")
		)
		(fp_line
			(start 1.549908 2.050034)
			(end 1.549908 -2.050034)
			(stroke
				(width 0.1)
				(type default)
			)
			(layer "F.Fab")
		)
		(fp_line
			(start -1.549908 2.050034)
			(end 1.549908 2.050034)
			(stroke
				(width 0.1)
				(type default)
			)
			(layer "F.Fab")
		)
		(fp_poly
			(pts
				(xy -2.9464 -2.208022) (xy -2.9464 -1.192022) (xy -1.9304 -1.700022)
			)
			(stroke
				(width 0)
				(type default)
			)
			(fill yes)
			(layer "F.Fab")
		)
		(pad "1" smd circle
			(at -1.35001 -1.700022 90)
			(size 0 0)
			(layers "F.Cu" "F.Mask" "F.Paste")
			(net "SW_PVDD18_S5_P1_BST")
		)
		(pad "2" smd rect
			(at -1.400048 -1.199896 180)
			(size 0.1778 0.8128)
			(layers "F.Cu" "F.Mask" "F.Paste")
			(net "GND")
		)
		(pad "3" smd rect
			(at -1.400048 -0.8001 180)
			(size 0.1778 0.8128)
			(layers "F.Cu" "F.Mask" "F.Paste")
			(net "PVDD18_S5_P1_CS")
		)
		(pad "4" smd rect
			(at -1.400048 -0.40005 180)
			(size 0.1778 0.8128)
			(layers "F.Cu" "F.Mask" "F.Paste")
			(net "PVDD18_S5_P1_MODE")
		)
		(pad "5" smd rect
			(at -1.400048 0 180)
			(size 0.1778 0.8128)
			(layers "F.Cu" "F.Mask" "F.Paste")
			(net "PVDD18_S5_P1_REF")
		)
		(pad "6" smd rect
			(at -1.400048 0.40005 180)
			(size 0.1778 0.8128)
			(layers "F.Cu" "F.Mask" "F.Paste")
			(net "PVDD18_SS_P1_RGND")
		)
		(pad "7" smd rect
			(at -1.400048 0.8001 180)
			(size 0.1778 0.8128)
			(layers "F.Cu" "F.Mask" "F.Paste")
			(net "PVDD18_S5_P1_FB")
		)
		(pad "8" smd rect
			(at -1.400048 1.199896 180)
			(size 0.1778 0.8128)
			(layers "F.Cu" "F.Mask" "F.Paste")
			(net "PVDD18_S5_P1_EN")
		)
		(pad "9" smd rect
			(at -1.400048 1.700022 180)
			(size 0.3048 0.8128)
			(layers "F.Cu" "F.Mask" "F.Paste")
			(net "PWRGD_PVDD18_S5_P1")
		)
		(pad "10" smd rect
			(at -0.299974 1.299972 90)
			(size 0.3048 2.0066)
			(layers "F.Cu" "F.Mask" "F.Paste")
			(net "SW_P12V_AUX_PVDD18_S5_P1_FLT")
		)
		(pad "11_18" smd circle
			(at 1.175004 0.275082 90)
			(size 0 0)
			(layers "F.Cu" "F.Mask" "F.Paste")
			(net "GND")
		)
		(pad "19" smd rect
			(at 1.400048 -1.700022)
			(size 0.3048 0.8128)
			(layers "F.Cu" "F.Mask" "F.Paste")
			(net "PVDD18_S5_P1_VCC")
		)
		(pad "20" smd rect
			(at 0.299974 -1.299972 90)
			(size 0.3048 2.0066)
			(layers "F.Cu" "F.Mask" "F.Paste")
			(net "SW_PVDD18_S5_P1_SW")
		)
		(pad "21" smd rect
			(at -0.299974 -1.299972 90)
			(size 0.3048 2.0066)
			(layers "F.Cu" "F.Mask" "F.Paste")
			(net "SW_P12V_AUX_PVDD18_S5_P1_FLT")
		)
	)
	(footprint ""
		(layer "F.Cu")
		(at 147.16379 -98.755708 90)
		(property "Reference" "C1880"
			(at 0 0 90)
			(layer "F.SilkS")
			(hide yes)
			(effects
				(font
					(size 1.27 1.27)
				)
			)
		)
		(property "Value" ""
			(at 0 0 90)
			(layer "F.Fab")
			(effects
				(font
					(size 1.27 1.27)
				)
			)
		)
		(duplicate_pad_numbers_are_jumpers no)
		(fp_line
			(start 0.7874 -0.4064)
			(end 0.7874 0.4064)
			(stroke
				(width 0.1524)
				(type default)
			)
			(layer "F.SilkS")
		)
		(fp_line
			(start -0.7874 -0.4064)
			(end 0.7874 -0.4064)
			(stroke
				(width 0.1524)
				(type default)
			)
			(layer "F.SilkS")
		)
		(fp_line
			(start 0.7874 0.4064)
			(end -0.7874 0.4064)
			(stroke
				(width 0.1524)
				(type default)
			)
			(layer "F.SilkS")
		)
		(fp_line
			(start -0.7874 0.4064)
			(end -0.7874 -0.4064)
			(stroke
				(width 0.1524)
				(type default)
			)
			(layer "F.SilkS")
		)
		(fp_line
			(start -0.12065 -0.305054)
			(end -0.12065 -0.2794)
			(stroke
				(width 0.1)
				(type default)
			)
			(layer "F.Fab")
		)
		(fp_line
			(start -0.67945 -0.305054)
			(end -0.12065 -0.305054)
			(stroke
				(width 0.1)
				(type default)
			)
			(layer "F.Fab")
		)
		(fp_line
			(start 0.67945 -0.3048)
			(end 0.67945 0.3048)
			(stroke
				(width 0.1)
				(type default)
			)
			(layer "F.Fab")
		)
		(fp_line
			(start 0.12065 -0.3048)
			(end 0.67945 -0.3048)
			(stroke
				(width 0.1)
				(type default)
			)
			(layer "F.Fab")
		)
		(fp_line
			(start 0.12065 -0.2794)
			(end 0.12065 -0.3048)
			(stroke
				(width 0.1)
				(type default)
			)
			(layer "F.Fab")
		)
		(fp_line
			(start -0.12065 -0.2794)
			(end 0.12065 -0.2794)
			(stroke
				(width 0.1)
				(type default)
			)
			(layer "F.Fab")
		)
		(fp_line
			(start 0.120396 0.2794)
			(end -0.12065 0.2794)
			(stroke
				(width 0.1)
				(type default)
			)
			(layer "F.Fab")
		)
		(fp_line
			(start -0.12065 0.2794)
			(end -0.12065 0.3048)
			(stroke
				(width 0.1)
				(type default)
			)
			(layer "F.Fab")
		)
		(fp_line
			(start 0.67945 0.3048)
			(end 0.120396 0.3048)
			(stroke
				(width 0.1)
				(type default)
			)
			(layer "F.Fab")
		)
		(fp_line
			(start 0.120396 0.3048)
			(end 0.120396 0.2794)
			(stroke
				(width 0.1)
				(type default)
			)
			(layer "F.Fab")
		)
		(fp_line
			(start -0.12065 0.3048)
			(end -0.67945 0.3048)
			(stroke
				(width 0.1)
				(type default)
			)
			(layer "F.Fab")
		)
		(fp_line
			(start -0.67945 0.3048)
			(end -0.67945 -0.305054)
			(stroke
				(width 0.1)
				(type default)
			)
			(layer "F.Fab")
		)
		(pad "1" smd circle
			(at -0.40005 0 90)
			(size 0 0)
			(layers "F.Cu" "F.Mask" "F.Paste")
			(net "P3V3_AUX")
		)
		(pad "2" smd circle
			(at 0.40005 0 90)
			(size 0 0)
			(layers "F.Cu" "F.Mask" "F.Paste")
			(net "GND")
		)
	)
	(footprint ""
		(layer "F.Cu")
		(at 297.774106 -255.560068 180)
		(property "Reference" "J15"
			(at -2.2098 -81.984088 0)
			(unlocked yes)
			(layer "F.SilkS")
			(effects
				(font
					(size 0.7874 0.5842)
					(thickness 0.1524)
				)
			)
		)
		(property "Value" ""
			(at 0 0 180)
			(layer "F.Fab")
			(effects
				(font
					(size 1.27 1.27)
				)
			)
		)
		(duplicate_pad_numbers_are_jumpers no)
		(fp_line
			(start 3.24993 -81.000092)
			(end 3.24993 75.617832)
			(stroke
				(width 0.1524)
				(type default)
			)
			(layer "F.SilkS")
		)
		(fp_line
			(start -3.24993 75.617832)
			(end -3.24993 -81.000092)
			(stroke
				(width 0.1524)
				(type default)
			)
			(layer "F.SilkS")
		)
		(fp_line
			(start -3.24993 72.499982)
			(end 3.24993 72.499982)
			(stroke
				(width 0.1524)
				(type default)
			)
			(layer "F.SilkS")
		)
		(fp_line
			(start -3.24993 -72.499982)
			(end 3.24993 -72.499982)
			(stroke
				(width 0.1524)
				(type default)
			)
			(layer "F.SilkS")
		)
		(fp_line
			(start -3.24993 -81.000092)
			(end 3.24993 -81.000092)
			(stroke
				(width 0.1524)
				(type default)
			)
			(layer "F.SilkS")
		)
		(fp_poly
			(pts
				(xy -3.853434 -64.48552) (xy -3.399028 -63.940182) (xy -4.107942 -63.90386)
			)
			(stroke
				(width 0)
				(type default)
			)
			(fill yes)
			(layer "F.SilkS")
		)
		(fp_line
			(start 3.24993 81.000092)
			(end -3.24993 81.000092)
			(stroke
				(width 0.1)
				(type default)
			)
			(layer "F.Fab")
		)
		(fp_line
			(start 3.24993 -81.000092)
			(end 3.24993 81.000092)
			(stroke
				(width 0.1)
				(type default)
			)
			(layer "F.Fab")
		)
		(fp_line
			(start -3.24993 81.000092)
			(end -3.24993 -81.000092)
			(stroke
				(width 0.1)
				(type default)
			)
			(layer "F.Fab")
		)
		(fp_line
			(start -3.24993 72.499982)
			(end 3.24993 72.499982)
			(stroke
				(width 0.1)
				(type default)
			)
			(layer "F.Fab")
		)
		(fp_line
			(start -3.24993 71.000112)
			(end 3.24993 71.000112)
			(stroke
				(width 0.1)
				(type default)
			)
			(layer "F.Fab")
		)
		(fp_line
			(start -3.24993 -71.000112)
			(end 3.24993 -71.000112)
			(stroke
				(width 0.1)
				(type default)
			)
			(layer "F.Fab")
		)
		(fp_line
			(start -3.24993 -72.499982)
			(end 3.24993 -72.499982)
			(stroke
				(width 0.1)
				(type default)
			)
			(layer "F.Fab")
		)
		(fp_line
			(start -3.24993 -81.000092)
			(end 3.24993 -81.000092)
			(stroke
				(width 0.1)
				(type default)
			)
			(layer "F.Fab")
		)
		(fp_poly
			(pts
				(xy -3.41503 -63.324994) (xy -4.43103 -62.816994) (xy -4.43103 -63.832994)
			)
			(stroke
				(width 0)
				(type default)
			)
			(fill yes)
			(layer "F.Fab")
		)
		(pad "1" smd rect
			(at -2.050034 -63.324994 90)
			(size 0.519938 1.4986)
			(layers "F.Cu" "F.Mask" "F.Paste")
			(net "P12V_MEM_CPU0")
		)
		(pad "2" smd rect
			(at -2.050034 -62.47511 90)
			(size 0.519938 1.4986)
			(layers "F.Cu" "F.Mask" "F.Paste")
			(net "Net_2263")
		)
		(pad "3" smd rect
			(at -2.050034 -61.624972 90)
			(size 0.519938 1.4986)
			(layers "F.Cu" "F.Mask" "F.Paste")
			(net "P3V3_AUX")
		)
		(pad "4" smd rect
			(at -2.050034 -60.775088 90)
			(size 0.519938 1.4986)
			(layers "F.Cu" "F.Mask" "F.Paste")
			(net "I3C_SPD_DDRB_CPU0_SCL")
		)
		(pad "5" smd rect
			(at -2.050034 -59.92495 90)
			(size 0.519938 1.4986)
			(layers "F.Cu" "F.Mask" "F.Paste")
			(net "I3C_SPD_DDRB_CPU0_SDA")
		)
		(pad "6" smd rect
			(at -2.050034 -59.075066 90)
			(size 0.519938 1.4986)
			(layers "F.Cu" "F.Mask" "F.Paste")
			(net "GND")
		)
		(pad "7" smd rect
			(at -2.050034 -58.224928 90)
			(size 0.519938 1.4986)
			(layers "F.Cu" "F.Mask" "F.Paste")
			(net "M_B_CPU0_SA_DQ<0>")
		)
		(pad "8" smd rect
			(at -2.050034 -57.375044 90)
			(size 0.519938 1.4986)
			(layers "F.Cu" "F.Mask" "F.Paste")
			(net "GND")
		)
		(pad "9" smd rect
			(at -2.050034 -56.524906 90)
			(size 0.519938 1.4986)
			(layers "F.Cu" "F.Mask" "F.Paste")
			(net "M_B_CPU0_SA_DQ<1>")
		)
		(pad "10" smd rect
			(at -2.050034 -55.675022 90)
			(size 0.519938 1.4986)
			(layers "F.Cu" "F.Mask" "F.Paste")
			(net "GND")
		)
		(pad "11" smd rect
			(at -2.050034 -54.824884 90)
			(size 0.519938 1.4986)
			(layers "F.Cu" "F.Mask" "F.Paste")
			(net "M_B_CPU0_SA_DQS_DP<0>")
		)
		(pad "12" smd rect
			(at -2.050034 -53.975 90)
			(size 0.519938 1.4986)
			(layers "F.Cu" "F.Mask" "F.Paste")
			(net "M_B_CPU0_SA_DQS_DN<0>")
		)
		(pad "13" smd rect
			(at -2.050034 -53.125116 90)
			(size 0.519938 1.4986)
			(layers "F.Cu" "F.Mask" "F.Paste")
			(net "GND")
		)
		(pad "14" smd rect
			(at -2.050034 -52.274978 90)
			(size 0.519938 1.4986)
			(layers "F.Cu" "F.Mask" "F.Paste")
			(net "M_B_CPU0_SA_DQ<4>")
		)
		(pad "15" smd rect
			(at -2.050034 -51.425094 90)
			(size 0.519938 1.4986)
			(layers "F.Cu" "F.Mask" "F.Paste")
			(net "GND")
		)
		(pad "16" smd rect
			(at -2.050034 -50.574956 90)
			(size 0.519938 1.4986)
			(layers "F.Cu" "F.Mask" "F.Paste")
			(net "M_B_CPU0_SA_DQ<5>")
		)
		(pad "17" smd rect
			(at -2.050034 -49.725072 90)
			(size 0.519938 1.4986)
			(layers "F.Cu" "F.Mask" "F.Paste")
			(net "GND")
		)
		(pad "18" smd rect
			(at -2.050034 -48.874934 90)
			(size 0.519938 1.4986)
			(layers "F.Cu" "F.Mask" "F.Paste")
			(net "M_B_CPU0_SA_DQ<8>")
		)
		(pad "19" smd rect
			(at -2.050034 -48.02505 90)
			(size 0.519938 1.4986)
			(layers "F.Cu" "F.Mask" "F.Paste")
			(net "GND")
		)
		(pad "20" smd rect
			(at -2.050034 -47.174912 90)
			(size 0.519938 1.4986)
			(layers "F.Cu" "F.Mask" "F.Paste")
			(net "M_B_CPU0_SA_DQ<9>")
		)
		(pad "21" smd rect
			(at -2.050034 -46.325028 90)
			(size 0.519938 1.4986)
			(layers "F.Cu" "F.Mask" "F.Paste")
			(net "GND")
		)
		(pad "22" smd rect
			(at -2.050034 -45.47489 90)
			(size 0.519938 1.4986)
			(layers "F.Cu" "F.Mask" "F.Paste")
			(net "M_B_CPU0_SA_DQS_DP<1>")
		)
		(pad "23" smd rect
			(at -2.050034 -44.625006 90)
			(size 0.519938 1.4986)
			(layers "F.Cu" "F.Mask" "F.Paste")
			(net "M_B_CPU0_SA_DQS_DN<1>")
		)
		(pad "24" smd rect
			(at -2.050034 -43.775122 90)
			(size 0.519938 1.4986)
			(layers "F.Cu" "F.Mask" "F.Paste")
			(net "GND")
		)
		(pad "25" smd rect
			(at -2.050034 -42.924984 90)
			(size 0.519938 1.4986)
			(layers "F.Cu" "F.Mask" "F.Paste")
			(net "M_B_CPU0_SA_DQ<12>")
		)
		(pad "26" smd rect
			(at -2.050034 -42.0751 90)
			(size 0.519938 1.4986)
			(layers "F.Cu" "F.Mask" "F.Paste")
			(net "GND")
		)
		(pad "27" smd rect
			(at -2.050034 -41.224962 90)
			(size 0.519938 1.4986)
			(layers "F.Cu" "F.Mask" "F.Paste")
			(net "M_B_CPU0_SA_DQ<13>")
		)
		(pad "28" smd rect
			(at -2.050034 -40.375078 90)
			(size 0.519938 1.4986)
			(layers "F.Cu" "F.Mask" "F.Paste")
			(net "GND")
		)
		(pad "29" smd rect
			(at -2.050034 -39.52494 90)
			(size 0.519938 1.4986)
			(layers "F.Cu" "F.Mask" "F.Paste")
			(net "M_B_CPU0_SA_DQ<16>")
		)
		(pad "30" smd rect
			(at -2.050034 -38.675056 90)
			(size 0.519938 1.4986)
			(layers "F.Cu" "F.Mask" "F.Paste")
			(net "GND")
		)
		(pad "31" smd rect
			(at -2.050034 -37.824918 90)
			(size 0.519938 1.4986)
			(layers "F.Cu" "F.Mask" "F.Paste")
			(net "M_B_CPU0_SA_DQ<17>")
		)
		(pad "32" smd rect
			(at -2.050034 -36.975034 90)
			(size 0.519938 1.4986)
			(layers "F.Cu" "F.Mask" "F.Paste")
			(net "GND")
		)
		(pad "33" smd rect
			(at -2.050034 -36.124896 90)
			(size 0.519938 1.4986)
			(layers "F.Cu" "F.Mask" "F.Paste")
			(net "M_B_CPU0_SA_DQS_DP<2>")
		)
		(pad "34" smd rect
			(at -2.050034 -35.275012 90)
			(size 0.519938 1.4986)
			(layers "F.Cu" "F.Mask" "F.Paste")
			(net "M_B_CPU0_SA_DQS_DN<2>")
		)
		(pad "35" smd rect
			(at -2.050034 -34.425128 90)
			(size 0.519938 1.4986)
			(layers "F.Cu" "F.Mask" "F.Paste")
			(net "GND")
		)
		(pad "36" smd rect
			(at -2.050034 -33.57499 90)
			(size 0.519938 1.4986)
			(layers "F.Cu" "F.Mask" "F.Paste")
			(net "M_B_CPU0_SA_DQ<20>")
		)
		(pad "37" smd rect
			(at -2.050034 -32.725106 90)
			(size 0.519938 1.4986)
			(layers "F.Cu" "F.Mask" "F.Paste")
			(net "GND")
		)
		(pad "38" smd rect
			(at -2.050034 -31.874968 90)
			(size 0.519938 1.4986)
			(layers "F.Cu" "F.Mask" "F.Paste")
			(net "M_B_CPU0_SA_DQ<21>")
		)
		(pad "39" smd rect
			(at -2.050034 -31.025084 90)
			(size 0.519938 1.4986)
			(layers "F.Cu" "F.Mask" "F.Paste")
			(net "GND")
		)
		(pad "40" smd rect
			(at -2.050034 -30.174946 90)
			(size 0.519938 1.4986)
			(layers "F.Cu" "F.Mask" "F.Paste")
			(net "M_B_CPU0_SA_DQ<24>")
		)
		(pad "41" smd rect
			(at -2.050034 -29.325062 90)
			(size 0.519938 1.4986)
			(layers "F.Cu" "F.Mask" "F.Paste")
			(net "GND")
		)
		(pad "42" smd rect
			(at -2.050034 -28.474924 90)
			(size 0.519938 1.4986)
			(layers "F.Cu" "F.Mask" "F.Paste")
			(net "M_B_CPU0_SA_DQ<25>")
		)
		(pad "43" smd rect
			(at -2.050034 -27.62504 90)
			(size 0.519938 1.4986)
			(layers "F.Cu" "F.Mask" "F.Paste")
			(net "GND")
		)
		(pad "44" smd rect
			(at -2.050034 -26.774902 90)
			(size 0.519938 1.4986)
			(layers "F.Cu" "F.Mask" "F.Paste")
			(net "M_B_CPU0_SA_DQS_DP<3>")
		)
		(pad "45" smd rect
			(at -2.050034 -25.925018 90)
			(size 0.519938 1.4986)
			(layers "F.Cu" "F.Mask" "F.Paste")
			(net "M_B_CPU0_SA_DQS_DN<3>")
		)
		(pad "46" smd rect
			(at -2.050034 -25.07488 90)
			(size 0.519938 1.4986)
			(layers "F.Cu" "F.Mask" "F.Paste")
			(net "GND")
		)
		(pad "47" smd rect
			(at -2.050034 -24.224996 90)
			(size 0.519938 1.4986)
			(layers "F.Cu" "F.Mask" "F.Paste")
			(net "M_B_CPU0_SA_DQ<28>")
		)
		(pad "48" smd rect
			(at -2.050034 -23.375112 90)
			(size 0.519938 1.4986)
			(layers "F.Cu" "F.Mask" "F.Paste")
			(net "GND")
		)
		(pad "49" smd rect
			(at -2.050034 -22.524974 90)
			(size 0.519938 1.4986)
			(layers "F.Cu" "F.Mask" "F.Paste")
			(net "M_B_CPU0_SA_DQ<29>")
		)
		(pad "50" smd rect
			(at -2.050034 -21.67509 90)
			(size 0.519938 1.4986)
			(layers "F.Cu" "F.Mask" "F.Paste")
			(net "GND")
		)
		(pad "51" smd rect
			(at -2.050034 -20.824952 90)
			(size 0.519938 1.4986)
			(layers "F.Cu" "F.Mask" "F.Paste")
			(net "M_B_CPU0_SA_CB<0>")
		)
		(pad "52" smd rect
			(at -2.050034 -19.975068 90)
			(size 0.519938 1.4986)
			(layers "F.Cu" "F.Mask" "F.Paste")
			(net "GND")
		)
		(pad "53" smd rect
			(at -2.050034 -19.12493 90)
			(size 0.519938 1.4986)
			(layers "F.Cu" "F.Mask" "F.Paste")
			(net "M_B_CPU0_SA_CB<1>")
		)
		(pad "54" smd rect
			(at -2.050034 -18.275046 90)
			(size 0.519938 1.4986)
			(layers "F.Cu" "F.Mask" "F.Paste")
			(net "GND")
		)
		(pad "55" smd rect
			(at -2.050034 -17.424908 90)
			(size 0.519938 1.4986)
			(layers "F.Cu" "F.Mask" "F.Paste")
			(net "M_B_CPU0_SA_DQS_DP<4>")
		)
		(pad "56" smd rect
			(at -2.050034 -16.575024 90)
			(size 0.519938 1.4986)
			(layers "F.Cu" "F.Mask" "F.Paste")
			(net "M_B_CPU0_SA_DQS_DN<4>")
		)
		(pad "57" smd rect
			(at -2.050034 -15.724886 90)
			(size 0.519938 1.4986)
			(layers "F.Cu" "F.Mask" "F.Paste")
			(net "GND")
		)
		(pad "58" smd rect
			(at -2.050034 -14.875002 90)
			(size 0.519938 1.4986)
			(layers "F.Cu" "F.Mask" "F.Paste")
			(net "M_B_CPU0_SA_CB<4>")
		)
		(pad "59" smd rect
			(at -2.050034 -14.025118 90)
			(size 0.519938 1.4986)
			(layers "F.Cu" "F.Mask" "F.Paste")
			(net "GND")
		)
		(pad "60" smd rect
			(at -2.050034 -13.17498 90)
			(size 0.519938 1.4986)
			(layers "F.Cu" "F.Mask" "F.Paste")
			(net "M_B_CPU0_SA_CB<5>")
		)
		(pad "61" smd rect
			(at -2.050034 -12.325096 90)
			(size 0.519938 1.4986)
			(layers "F.Cu" "F.Mask" "F.Paste")
			(net "GND")
		)
		(pad "62" smd rect
			(at -2.050034 -11.474958 90)
			(size 0.519938 1.4986)
			(layers "F.Cu" "F.Mask" "F.Paste")
			(net "M_B_CPU0_ALERT_N")
		)
		(pad "63" smd rect
			(at -2.050034 -10.625074 90)
			(size 0.519938 1.4986)
			(layers "F.Cu" "F.Mask" "F.Paste")
			(net "GND")
		)
		(pad "64" smd rect
			(at -2.050034 -9.774936 90)
			(size 0.519938 1.4986)
			(layers "F.Cu" "F.Mask" "F.Paste")
			(net "M_B_CPU0_SA_CS_N<0>")
		)
		(pad "65" smd rect
			(at -2.050034 -8.925052 90)
			(size 0.519938 1.4986)
			(layers "F.Cu" "F.Mask" "F.Paste")
			(net "GND")
		)
		(pad "66" smd rect
			(at -2.050034 -8.074914 90)
			(size 0.519938 1.4986)
			(layers "F.Cu" "F.Mask" "F.Paste")
			(net "M_B_CPU0_SA_CA<0>")
		)
		(pad "67" smd rect
			(at -2.050034 -7.22503 90)
			(size 0.519938 1.4986)
			(layers "F.Cu" "F.Mask" "F.Paste")
			(net "GND")
		)
		(pad "68" smd rect
			(at -2.050034 -6.374892 90)
			(size 0.519938 1.4986)
			(layers "F.Cu" "F.Mask" "F.Paste")
			(net "M_B_CPU0_SA_CA<2>")
		)
		(pad "69" smd rect
			(at -2.050034 -5.525008 90)
			(size 0.519938 1.4986)
			(layers "F.Cu" "F.Mask" "F.Paste")
			(net "GND")
		)
		(pad "70" smd rect
			(at -2.050034 -4.675124 90)
			(size 0.519938 1.4986)
			(layers "F.Cu" "F.Mask" "F.Paste")
			(net "M_B_CPU0_SA_CA<4>")
		)
		(pad "71" smd rect
			(at -2.050034 -3.824986 90)
			(size 0.519938 1.4986)
			(layers "F.Cu" "F.Mask" "F.Paste")
			(net "GND")
		)
		(pad "72" smd rect
			(at -2.050034 -2.975102 90)
			(size 0.519938 1.4986)
			(layers "F.Cu" "F.Mask" "F.Paste")
			(net "M_B_CPU0_SA_CA<6>")
		)
		(pad "73" smd rect
			(at -2.050034 -2.124964 90)
			(size 0.519938 1.4986)
			(layers "F.Cu" "F.Mask" "F.Paste")
			(net "GND")
		)
		(pad "74" smd rect
			(at -2.050034 -1.27508 90)
			(size 0.519938 1.4986)
			(layers "F.Cu" "F.Mask" "F.Paste")
			(net "M_B_CPU0_SA_PAR")
		)
		(pad "75" smd rect
			(at -2.050034 -0.424942 90)
			(size 0.519938 1.4986)
			(layers "F.Cu" "F.Mask" "F.Paste")
			(net "GND")
		)
		(pad "76" smd rect
			(at -2.050034 5.525008 90)
			(size 0.519938 1.4986)
			(layers "F.Cu" "F.Mask" "F.Paste")
			(net "M_B_CPU0_SB_CA<0>")
		)
		(pad "77" smd rect
			(at -2.050034 6.374892 90)
			(size 0.519938 1.4986)
			(layers "F.Cu" "F.Mask" "F.Paste")
			(net "GND")
		)
		(pad "78" smd rect
			(at -2.050034 7.22503 90)
			(size 0.519938 1.4986)
			(layers "F.Cu" "F.Mask" "F.Paste")
			(net "M_B_CPU0_SB_CA<2>")
		)
		(pad "79" smd rect
			(at -2.050034 8.074914 90)
			(size 0.519938 1.4986)
			(layers "F.Cu" "F.Mask" "F.Paste")
			(net "GND")
		)
		(pad "80" smd rect
			(at -2.050034 8.925052 90)
			(size 0.519938 1.4986)
			(layers "F.Cu" "F.Mask" "F.Paste")
			(net "M_B_CPU0_SB_CA<4>")
		)
		(pad "81" smd rect
			(at -2.050034 9.774936 90)
			(size 0.519938 1.4986)
			(layers "F.Cu" "F.Mask" "F.Paste")
			(net "GND")
		)
		(pad "82" smd rect
			(at -2.050034 10.625074 90)
			(size 0.519938 1.4986)
			(layers "F.Cu" "F.Mask" "F.Paste")
			(net "M_B_CPU0_SB_CA<6>")
		)
		(pad "83" smd rect
			(at -2.050034 11.474958 90)
			(size 0.519938 1.4986)
			(layers "F.Cu" "F.Mask" "F.Paste")
			(net "GND")
		)
		(pad "84" smd rect
			(at -2.050034 12.325096 90)
			(size 0.519938 1.4986)
			(layers "F.Cu" "F.Mask" "F.Paste")
			(net "M_B_CPU0_SB_CS_N<0>")
		)
		(pad "85" smd rect
			(at -2.050034 13.17498 90)
			(size 0.519938 1.4986)
			(layers "F.Cu" "F.Mask" "F.Paste")
			(net "GND")
		)
		(pad "86" smd rect
			(at -2.050034 14.025118 90)
			(size 0.519938 1.4986)
			(layers "F.Cu" "F.Mask" "F.Paste")
			(net "M_B_CPU0_SA_RSP<0>")
		)
		(pad "87" smd rect
			(at -2.050034 14.875002 90)
			(size 0.519938 1.4986)
			(layers "F.Cu" "F.Mask" "F.Paste")
			(net "M_B_CPU0_SB_RSP<0>")
		)
		(pad "88" smd rect
			(at -2.050034 15.724886 90)
			(size 0.519938 1.4986)
			(layers "F.Cu" "F.Mask" "F.Paste")
			(net "GND")
		)
		(pad "89" smd rect
			(at -2.050034 16.575024 90)
			(size 0.519938 1.4986)
			(layers "F.Cu" "F.Mask" "F.Paste")
			(net "M_B_CPU0_SB_CB<4>")
		)
		(pad "90" smd rect
			(at -2.050034 17.424908 90)
			(size 0.519938 1.4986)
			(layers "F.Cu" "F.Mask" "F.Paste")
			(net "GND")
		)
		(pad "91" smd rect
			(at -2.050034 18.275046 90)
			(size 0.519938 1.4986)
			(layers "F.Cu" "F.Mask" "F.Paste")
			(net "M_B_CPU0_SB_CB<5>")
		)
		(pad "92" smd rect
			(at -2.050034 19.12493 90)
			(size 0.519938 1.4986)
			(layers "F.Cu" "F.Mask" "F.Paste")
			(net "GND")
		)
		(pad "93" smd rect
			(at -2.050034 19.975068 90)
			(size 0.519938 1.4986)
			(layers "F.Cu" "F.Mask" "F.Paste")
			(net "M_B_CPU0_SB_DQS_DP<9>")
		)
		(pad "94" smd rect
			(at -2.050034 20.824952 90)
			(size 0.519938 1.4986)
			(layers "F.Cu" "F.Mask" "F.Paste")
			(net "M_B_CPU0_SB_DQS_DN<9>")
		)
		(pad "95" smd rect
			(at -2.050034 21.67509 90)
			(size 0.519938 1.4986)
			(layers "F.Cu" "F.Mask" "F.Paste")
			(net "GND")
		)
		(pad "96" smd rect
			(at -2.050034 22.524974 90)
			(size 0.519938 1.4986)
			(layers "F.Cu" "F.Mask" "F.Paste")
			(net "M_B_CPU0_SB_CB<0>")
		)
		(pad "97" smd rect
			(at -2.050034 23.375112 90)
			(size 0.519938 1.4986)
			(layers "F.Cu" "F.Mask" "F.Paste")
			(net "GND")
		)
		(pad "98" smd rect
			(at -2.050034 24.224996 90)
			(size 0.519938 1.4986)
			(layers "F.Cu" "F.Mask" "F.Paste")
			(net "M_B_CPU0_SB_CB<1>")
		)
		(pad "99" smd rect
			(at -2.050034 25.07488 90)
			(size 0.519938 1.4986)
			(layers "F.Cu" "F.Mask" "F.Paste")
			(net "GND")
		)
		(pad "100" smd rect
			(at -2.050034 25.925018 90)
			(size 0.519938 1.4986)
			(layers "F.Cu" "F.Mask" "F.Paste")
			(net "M_B_CPU0_SB_DQ<0>")
		)
		(pad "101" smd rect
			(at -2.050034 26.774902 90)
			(size 0.519938 1.4986)
			(layers "F.Cu" "F.Mask" "F.Paste")
			(net "GND")
		)
		(pad "102" smd rect
			(at -2.050034 27.62504 90)
			(size 0.519938 1.4986)
			(layers "F.Cu" "F.Mask" "F.Paste")
			(net "M_B_CPU0_SB_DQ<1>")
		)
		(pad "103" smd rect
			(at -2.050034 28.474924 90)
			(size 0.519938 1.4986)
			(layers "F.Cu" "F.Mask" "F.Paste")
			(net "GND")
		)
		(pad "104" smd rect
			(at -2.050034 29.325062 90)
			(size 0.519938 1.4986)
			(layers "F.Cu" "F.Mask" "F.Paste")
			(net "M_B_CPU0_SB_DQS_DP<0>")
		)
		(pad "105" smd rect
			(at -2.050034 30.174946 90)
			(size 0.519938 1.4986)
			(layers "F.Cu" "F.Mask" "F.Paste")
			(net "M_B_CPU0_SB_DQS_DN<0>")
		)
		(pad "106" smd rect
			(at -2.050034 31.025084 90)
			(size 0.519938 1.4986)
			(layers "F.Cu" "F.Mask" "F.Paste")
			(net "GND")
		)
		(pad "107" smd rect
			(at -2.050034 31.874968 90)
			(size 0.519938 1.4986)
			(layers "F.Cu" "F.Mask" "F.Paste")
			(net "M_B_CPU0_SB_DQ<4>")
		)
		(pad "108" smd rect
			(at -2.050034 32.725106 90)
			(size 0.519938 1.4986)
			(layers "F.Cu" "F.Mask" "F.Paste")
			(net "GND")
		)
		(pad "109" smd rect
			(at -2.050034 33.57499 90)
			(size 0.519938 1.4986)
			(layers "F.Cu" "F.Mask" "F.Paste")
			(net "M_B_CPU0_SB_DQ<5>")
		)
		(pad "110" smd rect
			(at -2.050034 34.425128 90)
			(size 0.519938 1.4986)
			(layers "F.Cu" "F.Mask" "F.Paste")
			(net "GND")
		)
		(pad "111" smd rect
			(at -2.050034 35.275012 90)
			(size 0.519938 1.4986)
			(layers "F.Cu" "F.Mask" "F.Paste")
			(net "M_B_CPU0_SB_DQ<8>")
		)
		(pad "112" smd rect
			(at -2.050034 36.124896 90)
			(size 0.519938 1.4986)
			(layers "F.Cu" "F.Mask" "F.Paste")
			(net "GND")
		)
		(pad "113" smd rect
			(at -2.050034 36.975034 90)
			(size 0.519938 1.4986)
			(layers "F.Cu" "F.Mask" "F.Paste")
			(net "M_B_CPU0_SB_DQ<9>")
		)
		(pad "114" smd rect
			(at -2.050034 37.824918 90)
			(size 0.519938 1.4986)
			(layers "F.Cu" "F.Mask" "F.Paste")
			(net "GND")
		)
		(pad "115" smd rect
			(at -2.050034 38.675056 90)
			(size 0.519938 1.4986)
			(layers "F.Cu" "F.Mask" "F.Paste")
			(net "M_B_CPU0_SB_DQS_DP<1>")
		)
		(pad "116" smd rect
			(at -2.050034 39.52494 90)
			(size 0.519938 1.4986)
			(layers "F.Cu" "F.Mask" "F.Paste")
			(net "M_B_CPU0_SB_DQS_DN<1>")
		)
		(pad "117" smd rect
			(at -2.050034 40.375078 90)
			(size 0.519938 1.4986)
			(layers "F.Cu" "F.Mask" "F.Paste")
			(net "GND")
		)
		(pad "118" smd rect
			(at -2.050034 41.224962 90)
			(size 0.519938 1.4986)
			(layers "F.Cu" "F.Mask" "F.Paste")
			(net "M_B_CPU0_SB_DQ<12>")
		)
		(pad "119" smd rect
			(at -2.050034 42.0751 90)
			(size 0.519938 1.4986)
			(layers "F.Cu" "F.Mask" "F.Paste")
			(net "GND")
		)
		(pad "120" smd rect
			(at -2.050034 42.924984 90)
			(size 0.519938 1.4986)
			(layers "F.Cu" "F.Mask" "F.Paste")
			(net "M_B_CPU0_SB_DQ<13>")
		)
		(pad "121" smd rect
			(at -2.050034 43.775122 90)
			(size 0.519938 1.4986)
			(layers "F.Cu" "F.Mask" "F.Paste")
			(net "GND")
		)
		(pad "122" smd rect
			(at -2.050034 44.625006 90)
			(size 0.519938 1.4986)
			(layers "F.Cu" "F.Mask" "F.Paste")
			(net "M_B_CPU0_SB_DQ<16>")
		)
		(pad "123" smd rect
			(at -2.050034 45.47489 90)
			(size 0.519938 1.4986)
			(layers "F.Cu" "F.Mask" "F.Paste")
			(net "GND")
		)
		(pad "124" smd rect
			(at -2.050034 46.325028 90)
			(size 0.519938 1.4986)
			(layers "F.Cu" "F.Mask" "F.Paste")
			(net "M_B_CPU0_SB_DQ<17>")
		)
		(pad "125" smd rect
			(at -2.050034 47.174912 90)
			(size 0.519938 1.4986)
			(layers "F.Cu" "F.Mask" "F.Paste")
			(net "GND")
		)
		(pad "126" smd rect
			(at -2.050034 48.02505 90)
			(size 0.519938 1.4986)
			(layers "F.Cu" "F.Mask" "F.Paste")
			(net "M_B_CPU0_SB_DQS_DP<2>")
		)
		(pad "127" smd rect
			(at -2.050034 48.874934 90)
			(size 0.519938 1.4986)
			(layers "F.Cu" "F.Mask" "F.Paste")
			(net "M_B_CPU0_SB_DQS_DN<2>")
		)
		(pad "128" smd rect
			(at -2.050034 49.725072 90)
			(size 0.519938 1.4986)
			(layers "F.Cu" "F.Mask" "F.Paste")
			(net "GND")
		)
		(pad "129" smd rect
			(at -2.050034 50.574956 90)
			(size 0.519938 1.4986)
			(layers "F.Cu" "F.Mask" "F.Paste")
			(net "M_B_CPU0_SB_DQ<20>")
		)
		(pad "130" smd rect
			(at -2.050034 51.425094 90)
			(size 0.519938 1.4986)
			(layers "F.Cu" "F.Mask" "F.Paste")
			(net "GND")
		)
		(pad "131" smd rect
			(at -2.050034 52.274978 90)
			(size 0.519938 1.4986)
			(layers "F.Cu" "F.Mask" "F.Paste")
			(net "M_B_CPU0_SB_DQ<21>")
		)
		(pad "132" smd rect
			(at -2.050034 53.125116 90)
			(size 0.519938 1.4986)
			(layers "F.Cu" "F.Mask" "F.Paste")
			(net "GND")
		)
		(pad "133" smd rect
			(at -2.050034 53.975 90)
			(size 0.519938 1.4986)
			(layers "F.Cu" "F.Mask" "F.Paste")
			(net "M_B_CPU0_SB_DQ<24>")
		)
		(pad "134" smd rect
			(at -2.050034 54.824884 90)
			(size 0.519938 1.4986)
			(layers "F.Cu" "F.Mask" "F.Paste")
			(net "GND")
		)
		(pad "135" smd rect
			(at -2.050034 55.675022 90)
			(size 0.519938 1.4986)
			(layers "F.Cu" "F.Mask" "F.Paste")
			(net "M_B_CPU0_SB_DQ<25>")
		)
		(pad "136" smd rect
			(at -2.050034 56.524906 90)
			(size 0.519938 1.4986)
			(layers "F.Cu" "F.Mask" "F.Paste")
			(net "GND")
		)
		(pad "137" smd rect
			(at -2.050034 57.375044 90)
			(size 0.519938 1.4986)
			(layers "F.Cu" "F.Mask" "F.Paste")
			(net "M_B_CPU0_SB_DQS_DP<3>")
		)
		(pad "138" smd rect
			(at -2.050034 58.224928 90)
			(size 0.519938 1.4986)
			(layers "F.Cu" "F.Mask" "F.Paste")
			(net "M_B_CPU0_SB_DQS_DN<3>")
		)
		(pad "139" smd rect
			(at -2.050034 59.075066 90)
			(size 0.519938 1.4986)
			(layers "F.Cu" "F.Mask" "F.Paste")
			(net "GND")
		)
		(pad "140" smd rect
			(at -2.050034 59.92495 90)
			(size 0.519938 1.4986)
			(layers "F.Cu" "F.Mask" "F.Paste")
			(net "M_B_CPU0_SB_DQ<28>")
		)
		(pad "141" smd rect
			(at -2.050034 60.775088 90)
			(size 0.519938 1.4986)
			(layers "F.Cu" "F.Mask" "F.Paste")
			(net "GND")
		)
		(pad "142" smd rect
			(at -2.050034 61.624972 90)
			(size 0.519938 1.4986)
			(layers "F.Cu" "F.Mask" "F.Paste")
			(net "M_B_CPU0_SB_DQ<29>")
		)
		(pad "143" smd rect
			(at -2.050034 62.47511 90)
			(size 0.519938 1.4986)
			(layers "F.Cu" "F.Mask" "F.Paste")
			(net "GND")
		)
		(pad "144" smd rect
			(at -2.050034 63.324994 90)
			(size 0.519938 1.4986)
			(layers "F.Cu" "F.Mask" "F.Paste")
			(net "Net_2264")
		)
		(pad "145" smd rect
			(at 2.050034 -63.324994 90)
			(size 0.519938 1.4986)
			(layers "F.Cu" "F.Mask" "F.Paste")
			(net "P12V_MEM_CPU0")
		)
		(pad "146" smd rect
			(at 2.050034 -62.47511 90)
			(size 0.519938 1.4986)
			(layers "F.Cu" "F.Mask" "F.Paste")
			(net "P12V_MEM_CPU0")
		)
		(pad "147" smd rect
			(at 2.050034 -61.624972 90)
			(size 0.519938 1.4986)
			(layers "F.Cu" "F.Mask" "F.Paste")
			(net "PWRGD_CHB_CPU0_DIMM")
		)
		(pad "148" smd rect
			(at 2.050034 -60.775088 90)
			(size 0.519938 1.4986)
			(layers "F.Cu" "F.Mask" "F.Paste")
			(net "PD_CHB_CPU0_DIMM_SAA")
		)
		(pad "149" smd rect
			(at 2.050034 -59.92495 90)
			(size 0.519938 1.4986)
			(layers "F.Cu" "F.Mask" "F.Paste")
			(net "Net_2265")
		)
		(pad "150" smd rect
			(at 2.050034 -59.075066 90)
			(size 0.519938 1.4986)
			(layers "F.Cu" "F.Mask" "F.Paste")
			(net "Net_2266")
		)
		(pad "151" smd rect
			(at 2.050034 -58.224928 90)
			(size 0.519938 1.4986)
			(layers "F.Cu" "F.Mask" "F.Paste")
			(net "GND")
		)
		(pad "152" smd rect
			(at 2.050034 -57.375044 90)
			(size 0.519938 1.4986)
			(layers "F.Cu" "F.Mask" "F.Paste")
			(net "M_B_CPU0_SA_DQ<2>")
		)
		(pad "153" smd rect
			(at 2.050034 -56.524906 90)
			(size 0.519938 1.4986)
			(layers "F.Cu" "F.Mask" "F.Paste")
			(net "GND")
		)
		(pad "154" smd rect
			(at 2.050034 -55.675022 90)
			(size 0.519938 1.4986)
			(layers "F.Cu" "F.Mask" "F.Paste")
			(net "M_B_CPU0_SA_DQ<3>")
		)
		(pad "155" smd rect
			(at 2.050034 -54.824884 90)
			(size 0.519938 1.4986)
			(layers "F.Cu" "F.Mask" "F.Paste")
			(net "GND")
		)
		(pad "156" smd rect
			(at 2.050034 -53.975 90)
			(size 0.519938 1.4986)
			(layers "F.Cu" "F.Mask" "F.Paste")
			(net "M_B_CPU0_SA_DQS_DN<5>")
		)
		(pad "157" smd rect
			(at 2.050034 -53.125116 90)
			(size 0.519938 1.4986)
			(layers "F.Cu" "F.Mask" "F.Paste")
			(net "M_B_CPU0_SA_DQS_DP<5>")
		)
		(pad "158" smd rect
			(at 2.050034 -52.274978 90)
			(size 0.519938 1.4986)
			(layers "F.Cu" "F.Mask" "F.Paste")
			(net "GND")
		)
		(pad "159" smd rect
			(at 2.050034 -51.425094 90)
			(size 0.519938 1.4986)
			(layers "F.Cu" "F.Mask" "F.Paste")
			(net "M_B_CPU0_SA_DQ<6>")
		)
		(pad "160" smd rect
			(at 2.050034 -50.574956 90)
			(size 0.519938 1.4986)
			(layers "F.Cu" "F.Mask" "F.Paste")
			(net "GND")
		)
		(pad "161" smd rect
			(at 2.050034 -49.725072 90)
			(size 0.519938 1.4986)
			(layers "F.Cu" "F.Mask" "F.Paste")
			(net "M_B_CPU0_SA_DQ<7>")
		)
		(pad "162" smd rect
			(at 2.050034 -48.874934 90)
			(size 0.519938 1.4986)
			(layers "F.Cu" "F.Mask" "F.Paste")
			(net "GND")
		)
		(pad "163" smd rect
			(at 2.050034 -48.02505 90)
			(size 0.519938 1.4986)
			(layers "F.Cu" "F.Mask" "F.Paste")
			(net "M_B_CPU0_SA_DQ<10>")
		)
		(pad "164" smd rect
			(at 2.050034 -47.174912 90)
			(size 0.519938 1.4986)
			(layers "F.Cu" "F.Mask" "F.Paste")
			(net "GND")
		)
		(pad "165" smd rect
			(at 2.050034 -46.325028 90)
			(size 0.519938 1.4986)
			(layers "F.Cu" "F.Mask" "F.Paste")
			(net "M_B_CPU0_SA_DQ<11>")
		)
		(pad "166" smd rect
			(at 2.050034 -45.47489 90)
			(size 0.519938 1.4986)
			(layers "F.Cu" "F.Mask" "F.Paste")
			(net "GND")
		)
		(pad "167" smd rect
			(at 2.050034 -44.625006 90)
			(size 0.519938 1.4986)
			(layers "F.Cu" "F.Mask" "F.Paste")
			(net "M_B_CPU0_SA_DQS_DN<6>")
		)
		(pad "168" smd rect
			(at 2.050034 -43.775122 90)
			(size 0.519938 1.4986)
			(layers "F.Cu" "F.Mask" "F.Paste")
			(net "M_B_CPU0_SA_DQS_DP<6>")
		)
		(pad "169" smd rect
			(at 2.050034 -42.924984 90)
			(size 0.519938 1.4986)
			(layers "F.Cu" "F.Mask" "F.Paste")
			(net "GND")
		)
		(pad "170" smd rect
			(at 2.050034 -42.0751 90)
			(size 0.519938 1.4986)
			(layers "F.Cu" "F.Mask" "F.Paste")
			(net "M_B_CPU0_SA_DQ<14>")
		)
		(pad "171" smd rect
			(at 2.050034 -41.224962 90)
			(size 0.519938 1.4986)
			(layers "F.Cu" "F.Mask" "F.Paste")
			(net "GND")
		)
		(pad "172" smd rect
			(at 2.050034 -40.375078 90)
			(size 0.519938 1.4986)
			(layers "F.Cu" "F.Mask" "F.Paste")
			(net "M_B_CPU0_SA_DQ<15>")
		)
		(pad "173" smd rect
			(at 2.050034 -39.52494 90)
			(size 0.519938 1.4986)
			(layers "F.Cu" "F.Mask" "F.Paste")
			(net "GND")
		)
		(pad "174" smd rect
			(at 2.050034 -38.675056 90)
			(size 0.519938 1.4986)
			(layers "F.Cu" "F.Mask" "F.Paste")
			(net "M_B_CPU0_SA_DQ<18>")
		)
		(pad "175" smd rect
			(at 2.050034 -37.824918 90)
			(size 0.519938 1.4986)
			(layers "F.Cu" "F.Mask" "F.Paste")
			(net "GND")
		)
		(pad "176" smd rect
			(at 2.050034 -36.975034 90)
			(size 0.519938 1.4986)
			(layers "F.Cu" "F.Mask" "F.Paste")
			(net "M_B_CPU0_SA_DQ<19>")
		)
		(pad "177" smd rect
			(at 2.050034 -36.124896 90)
			(size 0.519938 1.4986)
			(layers "F.Cu" "F.Mask" "F.Paste")
			(net "GND")
		)
		(pad "178" smd rect
			(at 2.050034 -35.275012 90)
			(size 0.519938 1.4986)
			(layers "F.Cu" "F.Mask" "F.Paste")
			(net "M_B_CPU0_SA_DQS_DN<7>")
		)
		(pad "179" smd rect
			(at 2.050034 -34.425128 90)
			(size 0.519938 1.4986)
			(layers "F.Cu" "F.Mask" "F.Paste")
			(net "M_B_CPU0_SA_DQS_DP<7>")
		)
		(pad "180" smd rect
			(at 2.050034 -33.57499 90)
			(size 0.519938 1.4986)
			(layers "F.Cu" "F.Mask" "F.Paste")
			(net "GND")
		)
		(pad "181" smd rect
			(at 2.050034 -32.725106 90)
			(size 0.519938 1.4986)
			(layers "F.Cu" "F.Mask" "F.Paste")
			(net "M_B_CPU0_SA_DQ<22>")
		)
		(pad "182" smd rect
			(at 2.050034 -31.874968 90)
			(size 0.519938 1.4986)
			(layers "F.Cu" "F.Mask" "F.Paste")
			(net "GND")
		)
		(pad "183" smd rect
			(at 2.050034 -31.025084 90)
			(size 0.519938 1.4986)
			(layers "F.Cu" "F.Mask" "F.Paste")
			(net "M_B_CPU0_SA_DQ<23>")
		)
		(pad "184" smd rect
			(at 2.050034 -30.174946 90)
			(size 0.519938 1.4986)
			(layers "F.Cu" "F.Mask" "F.Paste")
			(net "GND")
		)
		(pad "185" smd rect
			(at 2.050034 -29.325062 90)
			(size 0.519938 1.4986)
			(layers "F.Cu" "F.Mask" "F.Paste")
			(net "M_B_CPU0_SA_DQ<26>")
		)
		(pad "186" smd rect
			(at 2.050034 -28.474924 90)
			(size 0.519938 1.4986)
			(layers "F.Cu" "F.Mask" "F.Paste")
			(net "GND")
		)
		(pad "187" smd rect
			(at 2.050034 -27.62504 90)
			(size 0.519938 1.4986)
			(layers "F.Cu" "F.Mask" "F.Paste")
			(net "M_B_CPU0_SA_DQ<27>")
		)
		(pad "188" smd rect
			(at 2.050034 -26.774902 90)
			(size 0.519938 1.4986)
			(layers "F.Cu" "F.Mask" "F.Paste")
			(net "GND")
		)
		(pad "189" smd rect
			(at 2.050034 -25.925018 90)
			(size 0.519938 1.4986)
			(layers "F.Cu" "F.Mask" "F.Paste")
			(net "M_B_CPU0_SA_DQS_DN<8>")
		)
		(pad "190" smd rect
			(at 2.050034 -25.07488 90)
			(size 0.519938 1.4986)
			(layers "F.Cu" "F.Mask" "F.Paste")
			(net "M_B_CPU0_SA_DQS_DP<8>")
		)
		(pad "191" smd rect
			(at 2.050034 -24.224996 90)
			(size 0.519938 1.4986)
			(layers "F.Cu" "F.Mask" "F.Paste")
			(net "GND")
		)
		(pad "192" smd rect
			(at 2.050034 -23.375112 90)
			(size 0.519938 1.4986)
			(layers "F.Cu" "F.Mask" "F.Paste")
			(net "M_B_CPU0_SA_DQ<30>")
		)
		(pad "193" smd rect
			(at 2.050034 -22.524974 90)
			(size 0.519938 1.4986)
			(layers "F.Cu" "F.Mask" "F.Paste")
			(net "GND")
		)
		(pad "194" smd rect
			(at 2.050034 -21.67509 90)
			(size 0.519938 1.4986)
			(layers "F.Cu" "F.Mask" "F.Paste")
			(net "M_B_CPU0_SA_DQ<31>")
		)
		(pad "195" smd rect
			(at 2.050034 -20.824952 90)
			(size 0.519938 1.4986)
			(layers "F.Cu" "F.Mask" "F.Paste")
			(net "GND")
		)
		(pad "196" smd rect
			(at 2.050034 -19.975068 90)
			(size 0.519938 1.4986)
			(layers "F.Cu" "F.Mask" "F.Paste")
			(net "M_B_CPU0_SA_CB<2>")
		)
		(pad "197" smd rect
			(at 2.050034 -19.12493 90)
			(size 0.519938 1.4986)
			(layers "F.Cu" "F.Mask" "F.Paste")
			(net "GND")
		)
		(pad "198" smd rect
			(at 2.050034 -18.275046 90)
			(size 0.519938 1.4986)
			(layers "F.Cu" "F.Mask" "F.Paste")
			(net "M_B_CPU0_SA_CB<3>")
		)
		(pad "199" smd rect
			(at 2.050034 -17.424908 90)
			(size 0.519938 1.4986)
			(layers "F.Cu" "F.Mask" "F.Paste")
			(net "GND")
		)
		(pad "200" smd rect
			(at 2.050034 -16.575024 90)
			(size 0.519938 1.4986)
			(layers "F.Cu" "F.Mask" "F.Paste")
			(net "M_B_CPU0_SA_DQS_DN<9>")
		)
		(pad "201" smd rect
			(at 2.050034 -15.724886 90)
			(size 0.519938 1.4986)
			(layers "F.Cu" "F.Mask" "F.Paste")
			(net "M_B_CPU0_SA_DQS_DP<9>")
		)
		(pad "202" smd rect
			(at 2.050034 -14.875002 90)
			(size 0.519938 1.4986)
			(layers "F.Cu" "F.Mask" "F.Paste")
			(net "GND")
		)
		(pad "203" smd rect
			(at 2.050034 -14.025118 90)
			(size 0.519938 1.4986)
			(layers "F.Cu" "F.Mask" "F.Paste")
			(net "M_B_CPU0_SA_CB<6>")
		)
		(pad "204" smd rect
			(at 2.050034 -13.17498 90)
			(size 0.519938 1.4986)
			(layers "F.Cu" "F.Mask" "F.Paste")
			(net "GND")
		)
		(pad "205" smd rect
			(at 2.050034 -12.325096 90)
			(size 0.519938 1.4986)
			(layers "F.Cu" "F.Mask" "F.Paste")
			(net "M_B_CPU0_SA_CB<7>")
		)
		(pad "206" smd rect
			(at 2.050034 -11.474958 90)
			(size 0.519938 1.4986)
			(layers "F.Cu" "F.Mask" "F.Paste")
			(net "GND")
		)
		(pad "207" smd rect
			(at 2.050034 -10.625074 90)
			(size 0.519938 1.4986)
			(layers "F.Cu" "F.Mask" "F.Paste")
			(net "M_B_CPU0_RESET_N")
		)
		(pad "208" smd rect
			(at 2.050034 -9.774936 90)
			(size 0.519938 1.4986)
			(layers "F.Cu" "F.Mask" "F.Paste")
			(net "GND")
		)
		(pad "209" smd rect
			(at 2.050034 -8.925052 90)
			(size 0.519938 1.4986)
			(layers "F.Cu" "F.Mask" "F.Paste")
			(net "M_B_CPU0_SA_CS_N<1>")
		)
		(pad "210" smd rect
			(at 2.050034 -8.074914 90)
			(size 0.519938 1.4986)
			(layers "F.Cu" "F.Mask" "F.Paste")
			(net "GND")
		)
		(pad "211" smd rect
			(at 2.050034 -7.22503 90)
			(size 0.519938 1.4986)
			(layers "F.Cu" "F.Mask" "F.Paste")
			(net "M_B_CPU0_SA_CA<1>")
		)
		(pad "212" smd rect
			(at 2.050034 -6.374892 90)
			(size 0.519938 1.4986)
			(layers "F.Cu" "F.Mask" "F.Paste")
			(net "GND")
		)
		(pad "213" smd rect
			(at 2.050034 -5.525008 90)
			(size 0.519938 1.4986)
			(layers "F.Cu" "F.Mask" "F.Paste")
			(net "M_B_CPU0_SA_CA<3>")
		)
		(pad "214" smd rect
			(at 2.050034 -4.675124 90)
			(size 0.519938 1.4986)
			(layers "F.Cu" "F.Mask" "F.Paste")
			(net "GND")
		)
		(pad "215" smd rect
			(at 2.050034 -3.824986 90)
			(size 0.519938 1.4986)
			(layers "F.Cu" "F.Mask" "F.Paste")
			(net "M_B_CPU0_SA_CA<5>")
		)
		(pad "216" smd rect
			(at 2.050034 -2.975102 90)
			(size 0.519938 1.4986)
			(layers "F.Cu" "F.Mask" "F.Paste")
			(net "GND")
		)
		(pad "217" smd rect
			(at 2.050034 -2.124964 90)
			(size 0.519938 1.4986)
			(layers "F.Cu" "F.Mask" "F.Paste")
			(net "M_B_CPU0_CLK_DP<0>")
		)
		(pad "218" smd rect
			(at 2.050034 -1.27508 90)
			(size 0.519938 1.4986)
			(layers "F.Cu" "F.Mask" "F.Paste")
			(net "M_B_CPU0_CLK_DN<0>")
		)
		(pad "219" smd rect
			(at 2.050034 -0.424942 90)
			(size 0.519938 1.4986)
			(layers "F.Cu" "F.Mask" "F.Paste")
			(net "GND")
		)
		(pad "220" smd rect
			(at 2.050034 5.525008 90)
			(size 0.519938 1.4986)
			(layers "F.Cu" "F.Mask" "F.Paste")
			(net "Net_2267")
		)
		(pad "221" smd rect
			(at 2.050034 6.374892 90)
			(size 0.519938 1.4986)
			(layers "F.Cu" "F.Mask" "F.Paste")
			(net "M_B_CPU0_SB_CA<1>")
		)
		(pad "222" smd rect
			(at 2.050034 7.22503 90)
			(size 0.519938 1.4986)
			(layers "F.Cu" "F.Mask" "F.Paste")
			(net "GND")
		)
		(pad "223" smd rect
			(at 2.050034 8.074914 90)
			(size 0.519938 1.4986)
			(layers "F.Cu" "F.Mask" "F.Paste")
			(net "M_B_CPU0_SB_CA<3>")
		)
		(pad "224" smd rect
			(at 2.050034 8.925052 90)
			(size 0.519938 1.4986)
			(layers "F.Cu" "F.Mask" "F.Paste")
			(net "GND")
		)
		(pad "225" smd rect
			(at 2.050034 9.774936 90)
			(size 0.519938 1.4986)
			(layers "F.Cu" "F.Mask" "F.Paste")
			(net "M_B_CPU0_SB_CA<5>")
		)
		(pad "226" smd rect
			(at 2.050034 10.625074 90)
			(size 0.519938 1.4986)
			(layers "F.Cu" "F.Mask" "F.Paste")
			(net "GND")
		)
		(pad "227" smd rect
			(at 2.050034 11.474958 90)
			(size 0.519938 1.4986)
			(layers "F.Cu" "F.Mask" "F.Paste")
			(net "M_B_CPU0_SB_PAR")
		)
		(pad "228" smd rect
			(at 2.050034 12.325096 90)
			(size 0.519938 1.4986)
			(layers "F.Cu" "F.Mask" "F.Paste")
			(net "GND")
		)
		(pad "229" smd rect
			(at 2.050034 13.17498 90)
			(size 0.519938 1.4986)
			(layers "F.Cu" "F.Mask" "F.Paste")
			(net "M_B_CPU0_SB_CS_N<1>")
		)
		(pad "230" smd rect
			(at 2.050034 14.025118 90)
			(size 0.519938 1.4986)
			(layers "F.Cu" "F.Mask" "F.Paste")
			(net "GND")
		)
		(pad "231" smd rect
			(at 2.050034 14.875002 90)
			(size 0.519938 1.4986)
			(layers "F.Cu" "F.Mask" "F.Paste")
			(net "Net_2268")
		)
		(pad "232" smd rect
			(at 2.050034 15.724886 90)
			(size 0.519938 1.4986)
			(layers "F.Cu" "F.Mask" "F.Paste")
			(net "Net_2269")
		)
		(pad "233" smd rect
			(at 2.050034 16.575024 90)
			(size 0.519938 1.4986)
			(layers "F.Cu" "F.Mask" "F.Paste")
			(net "GND")
		)
		(pad "234" smd rect
			(at 2.050034 17.424908 90)
			(size 0.519938 1.4986)
			(layers "F.Cu" "F.Mask" "F.Paste")
			(net "M_B_CPU0_SB_CB<6>")
		)
		(pad "235" smd rect
			(at 2.050034 18.275046 90)
			(size 0.519938 1.4986)
			(layers "F.Cu" "F.Mask" "F.Paste")
			(net "GND")
		)
		(pad "236" smd rect
			(at 2.050034 19.12493 90)
			(size 0.519938 1.4986)
			(layers "F.Cu" "F.Mask" "F.Paste")
			(net "M_B_CPU0_SB_CB<7>")
		)
		(pad "237" smd rect
			(at 2.050034 19.975068 90)
			(size 0.519938 1.4986)
			(layers "F.Cu" "F.Mask" "F.Paste")
			(net "GND")
		)
		(pad "238" smd rect
			(at 2.050034 20.824952 90)
			(size 0.519938 1.4986)
			(layers "F.Cu" "F.Mask" "F.Paste")
			(net "M_B_CPU0_SB_DQS_DN<4>")
		)
		(pad "239" smd rect
			(at 2.050034 21.67509 90)
			(size 0.519938 1.4986)
			(layers "F.Cu" "F.Mask" "F.Paste")
			(net "M_B_CPU0_SB_DQS_DP<4>")
		)
		(pad "240" smd rect
			(at 2.050034 22.524974 90)
			(size 0.519938 1.4986)
			(layers "F.Cu" "F.Mask" "F.Paste")
			(net "GND")
		)
		(pad "241" smd rect
			(at 2.050034 23.375112 90)
			(size 0.519938 1.4986)
			(layers "F.Cu" "F.Mask" "F.Paste")
			(net "M_B_CPU0_SB_CB<2>")
		)
		(pad "242" smd rect
			(at 2.050034 24.224996 90)
			(size 0.519938 1.4986)
			(layers "F.Cu" "F.Mask" "F.Paste")
			(net "GND")
		)
		(pad "243" smd rect
			(at 2.050034 25.07488 90)
			(size 0.519938 1.4986)
			(layers "F.Cu" "F.Mask" "F.Paste")
			(net "M_B_CPU0_SB_CB<3>")
		)
		(pad "244" smd rect
			(at 2.050034 25.925018 90)
			(size 0.519938 1.4986)
			(layers "F.Cu" "F.Mask" "F.Paste")
			(net "GND")
		)
		(pad "245" smd rect
			(at 2.050034 26.774902 90)
			(size 0.519938 1.4986)
			(layers "F.Cu" "F.Mask" "F.Paste")
			(net "M_B_CPU0_SB_DQ<2>")
		)
		(pad "246" smd rect
			(at 2.050034 27.62504 90)
			(size 0.519938 1.4986)
			(layers "F.Cu" "F.Mask" "F.Paste")
			(net "GND")
		)
		(pad "247" smd rect
			(at 2.050034 28.474924 90)
			(size 0.519938 1.4986)
			(layers "F.Cu" "F.Mask" "F.Paste")
			(net "M_B_CPU0_SB_DQ<3>")
		)
		(pad "248" smd rect
			(at 2.050034 29.325062 90)
			(size 0.519938 1.4986)
			(layers "F.Cu" "F.Mask" "F.Paste")
			(net "GND")
		)
		(pad "249" smd rect
			(at 2.050034 30.174946 90)
			(size 0.519938 1.4986)
			(layers "F.Cu" "F.Mask" "F.Paste")
			(net "M_B_CPU0_SB_DQS_DN<5>")
		)
		(pad "250" smd rect
			(at 2.050034 31.025084 90)
			(size 0.519938 1.4986)
			(layers "F.Cu" "F.Mask" "F.Paste")
			(net "M_B_CPU0_SB_DQS_DP<5>")
		)
		(pad "251" smd rect
			(at 2.050034 31.874968 90)
			(size 0.519938 1.4986)
			(layers "F.Cu" "F.Mask" "F.Paste")
			(net "GND")
		)
		(pad "252" smd rect
			(at 2.050034 32.725106 90)
			(size 0.519938 1.4986)
			(layers "F.Cu" "F.Mask" "F.Paste")
			(net "M_B_CPU0_SB_DQ<6>")
		)
		(pad "253" smd rect
			(at 2.050034 33.57499 90)
			(size 0.519938 1.4986)
			(layers "F.Cu" "F.Mask" "F.Paste")
			(net "GND")
		)
		(pad "254" smd rect
			(at 2.050034 34.425128 90)
			(size 0.519938 1.4986)
			(layers "F.Cu" "F.Mask" "F.Paste")
			(net "M_B_CPU0_SB_DQ<7>")
		)
		(pad "255" smd rect
			(at 2.050034 35.275012 90)
			(size 0.519938 1.4986)
			(layers "F.Cu" "F.Mask" "F.Paste")
			(net "GND")
		)
		(pad "256" smd rect
			(at 2.050034 36.124896 90)
			(size 0.519938 1.4986)
			(layers "F.Cu" "F.Mask" "F.Paste")
			(net "M_B_CPU0_SB_DQ<10>")
		)
		(pad "257" smd rect
			(at 2.050034 36.975034 90)
			(size 0.519938 1.4986)
			(layers "F.Cu" "F.Mask" "F.Paste")
			(net "GND")
		)
		(pad "258" smd rect
			(at 2.050034 37.824918 90)
			(size 0.519938 1.4986)
			(layers "F.Cu" "F.Mask" "F.Paste")
			(net "M_B_CPU0_SB_DQ<11>")
		)
		(pad "259" smd rect
			(at 2.050034 38.675056 90)
			(size 0.519938 1.4986)
			(layers "F.Cu" "F.Mask" "F.Paste")
			(net "GND")
		)
		(pad "260" smd rect
			(at 2.050034 39.52494 90)
			(size 0.519938 1.4986)
			(layers "F.Cu" "F.Mask" "F.Paste")
			(net "M_B_CPU0_SB_DQS_DN<6>")
		)
		(pad "261" smd rect
			(at 2.050034 40.375078 90)
			(size 0.519938 1.4986)
			(layers "F.Cu" "F.Mask" "F.Paste")
			(net "M_B_CPU0_SB_DQS_DP<6>")
		)
		(pad "262" smd rect
			(at 2.050034 41.224962 90)
			(size 0.519938 1.4986)
			(layers "F.Cu" "F.Mask" "F.Paste")
			(net "GND")
		)
		(pad "263" smd rect
			(at 2.050034 42.0751 90)
			(size 0.519938 1.4986)
			(layers "F.Cu" "F.Mask" "F.Paste")
			(net "M_B_CPU0_SB_DQ<14>")
		)
		(pad "264" smd rect
			(at 2.050034 42.924984 90)
			(size 0.519938 1.4986)
			(layers "F.Cu" "F.Mask" "F.Paste")
			(net "GND")
		)
		(pad "265" smd rect
			(at 2.050034 43.775122 90)
			(size 0.519938 1.4986)
			(layers "F.Cu" "F.Mask" "F.Paste")
			(net "M_B_CPU0_SB_DQ<15>")
		)
		(pad "266" smd rect
			(at 2.050034 44.625006 90)
			(size 0.519938 1.4986)
			(layers "F.Cu" "F.Mask" "F.Paste")
			(net "GND")
		)
		(pad "267" smd rect
			(at 2.050034 45.47489 90)
			(size 0.519938 1.4986)
			(layers "F.Cu" "F.Mask" "F.Paste")
			(net "M_B_CPU0_SB_DQ<18>")
		)
		(pad "268" smd rect
			(at 2.050034 46.325028 90)
			(size 0.519938 1.4986)
			(layers "F.Cu" "F.Mask" "F.Paste")
			(net "GND")
		)
		(pad "269" smd rect
			(at 2.050034 47.174912 90)
			(size 0.519938 1.4986)
			(layers "F.Cu" "F.Mask" "F.Paste")
			(net "M_B_CPU0_SB_DQ<19>")
		)
		(pad "270" smd rect
			(at 2.050034 48.02505 90)
			(size 0.519938 1.4986)
			(layers "F.Cu" "F.Mask" "F.Paste")
			(net "GND")
		)
		(pad "271" smd rect
			(at 2.050034 48.874934 90)
			(size 0.519938 1.4986)
			(layers "F.Cu" "F.Mask" "F.Paste")
			(net "M_B_CPU0_SB_DQS_DN<7>")
		)
		(pad "272" smd rect
			(at 2.050034 49.725072 90)
			(size 0.519938 1.4986)
			(layers "F.Cu" "F.Mask" "F.Paste")
			(net "M_B_CPU0_SB_DQS_DP<7>")
		)
		(pad "273" smd rect
			(at 2.050034 50.574956 90)
			(size 0.519938 1.4986)
			(layers "F.Cu" "F.Mask" "F.Paste")
			(net "GND")
		)
		(pad "274" smd rect
			(at 2.050034 51.425094 90)
			(size 0.519938 1.4986)
			(layers "F.Cu" "F.Mask" "F.Paste")
			(net "M_B_CPU0_SB_DQ<22>")
		)
		(pad "275" smd rect
			(at 2.050034 52.274978 90)
			(size 0.519938 1.4986)
			(layers "F.Cu" "F.Mask" "F.Paste")
			(net "GND")
		)
		(pad "276" smd rect
			(at 2.050034 53.125116 90)
			(size 0.519938 1.4986)
			(layers "F.Cu" "F.Mask" "F.Paste")
			(net "M_B_CPU0_SB_DQ<23>")
		)
		(pad "277" smd rect
			(at 2.050034 53.975 90)
			(size 0.519938 1.4986)
			(layers "F.Cu" "F.Mask" "F.Paste")
			(net "GND")
		)
		(pad "278" smd rect
			(at 2.050034 54.824884 90)
			(size 0.519938 1.4986)
			(layers "F.Cu" "F.Mask" "F.Paste")
			(net "M_B_CPU0_SB_DQ<26>")
		)
		(pad "279" smd rect
			(at 2.050034 55.675022 90)
			(size 0.519938 1.4986)
			(layers "F.Cu" "F.Mask" "F.Paste")
			(net "GND")
		)
		(pad "280" smd rect
			(at 2.050034 56.524906 90)
			(size 0.519938 1.4986)
			(layers "F.Cu" "F.Mask" "F.Paste")
			(net "M_B_CPU0_SB_DQ<27>")
		)
		(pad "281" smd rect
			(at 2.050034 57.375044 90)
			(size 0.519938 1.4986)
			(layers "F.Cu" "F.Mask" "F.Paste")
			(net "GND")
		)
		(pad "282" smd rect
			(at 2.050034 58.224928 90)
			(size 0.519938 1.4986)
			(layers "F.Cu" "F.Mask" "F.Paste")
			(net "M_B_CPU0_SB_DQS_DN<8>")
		)
		(pad "283" smd rect
			(at 2.050034 59.075066 90)
			(size 0.519938 1.4986)
			(layers "F.Cu" "F.Mask" "F.Paste")
			(net "M_B_CPU0_SB_DQS_DP<8>")
		)
		(pad "284" smd rect
			(at 2.050034 59.92495 90)
			(size 0.519938 1.4986)
			(layers "F.Cu" "F.Mask" "F.Paste")
			(net "GND")
		)
		(pad "285" smd rect
			(at 2.050034 60.775088 90)
			(size 0.519938 1.4986)
			(layers "F.Cu" "F.Mask" "F.Paste")
			(net "M_B_CPU0_SB_DQ<30>")
		)
		(pad "286" smd rect
			(at 2.050034 61.624972 90)
			(size 0.519938 1.4986)
			(layers "F.Cu" "F.Mask" "F.Paste")
			(net "GND")
		)
		(pad "287" smd rect
			(at 2.050034 62.47511 90)
			(size 0.519938 1.4986)
			(layers "F.Cu" "F.Mask" "F.Paste")
			(net "M_B_CPU0_SB_DQ<31>")
		)
		(pad "288" smd rect
			(at 2.050034 63.324994 90)
			(size 0.519938 1.4986)
			(layers "F.Cu" "F.Mask" "F.Paste")
			(net "GND")
		)
		(pad "G1" thru_hole oval
			(at 0 -68.97497 90)
			(size 1.7272 3.4798)
			(drill oval 1.2192 2.4638)
			(layers "*.Cu" "*.Mask")
			(remove_unused_layers no)
			(net "GND")
			(clearance 0.127)
			(thermal_gap 0.127)
		)
		(pad "G2" thru_hole oval
			(at 0 3.875024 90)
			(size 1.7272 3.4798)
			(drill oval 1.2192 2.4638)
			(layers "*.Cu" "*.Mask")
			(remove_unused_layers no)
			(net "GND")
			(clearance 0.127)
			(thermal_gap 0.127)
		)
		(pad "G3" thru_hole oval
			(at 0 68.97497 90)
			(size 1.7272 3.4798)
			(drill oval 1.2192 2.4638)
			(layers "*.Cu" "*.Mask")
			(remove_unused_layers no)
			(net "GND")
			(clearance 0.127)
			(thermal_gap 0.127)
		)
	)
	(footprint ""
		(layer "F.Cu")
		(at 435.102 -170.688 -90)
		(property "Reference" "R1300"
			(at 0 0 270)
			(layer "F.SilkS")
			(hide yes)
			(effects
				(font
					(size 1.27 1.27)
				)
			)
		)
		(property "Value" ""
			(at 0 0 270)
			(layer "F.Fab")
			(effects
				(font
					(size 1.27 1.27)
				)
			)
		)
		(duplicate_pad_numbers_are_jumpers no)
		(fp_line
			(start -0.7874 0.4064)
			(end -0.7874 -0.4064)
			(stroke
				(width 0.1524)
				(type default)
			)
			(layer "F.SilkS")
		)
		(fp_line
			(start 0.7874 0.4064)
			(end -0.7874 0.4064)
			(stroke
				(width 0.1524)
				(type default)
			)
			(layer "F.SilkS")
		)
		(fp_line
			(start -0.7874 -0.4064)
			(end 0.7874 -0.4064)
			(stroke
				(width 0.1524)
				(type default)
			)
			(layer "F.SilkS")
		)
		(fp_line
			(start 0.7874 -0.4064)
			(end 0.7874 0.4064)
			(stroke
				(width 0.1524)
				(type default)
			)
			(layer "F.SilkS")
		)
		(fp_line
			(start -0.67945 0.3048)
			(end -0.67945 -0.305054)
			(stroke
				(width 0.1)
				(type default)
			)
			(layer "F.Fab")
		)
		(fp_line
			(start -0.12065 0.3048)
			(end -0.67945 0.3048)
			(stroke
				(width 0.1)
				(type default)
			)
			(layer "F.Fab")
		)
		(fp_line
			(start 0.120396 0.3048)
			(end 0.120396 0.2794)
			(stroke
				(width 0.1)
				(type default)
			)
			(layer "F.Fab")
		)
		(fp_line
			(start 0.67945 0.3048)
			(end 0.120396 0.3048)
			(stroke
				(width 0.1)
				(type default)
			)
			(layer "F.Fab")
		)
		(fp_line
			(start -0.12065 0.2794)
			(end -0.12065 0.3048)
			(stroke
				(width 0.1)
				(type default)
			)
			(layer "F.Fab")
		)
		(fp_line
			(start 0.120396 0.2794)
			(end -0.12065 0.2794)
			(stroke
				(width 0.1)
				(type default)
			)
			(layer "F.Fab")
		)
		(fp_line
			(start -0.12065 -0.2794)
			(end 0.12065 -0.2794)
			(stroke
				(width 0.1)
				(type default)
			)
			(layer "F.Fab")
		)
		(fp_line
			(start 0.12065 -0.2794)
			(end 0.12065 -0.3048)
			(stroke
				(width 0.1)
				(type default)
			)
			(layer "F.Fab")
		)
		(fp_line
			(start 0.12065 -0.3048)
			(end 0.67945 -0.3048)
			(stroke
				(width 0.1)
				(type default)
			)
			(layer "F.Fab")
		)
		(fp_line
			(start 0.67945 -0.3048)
			(end 0.67945 0.3048)
			(stroke
				(width 0.1)
				(type default)
			)
			(layer "F.Fab")
		)
		(fp_line
			(start -0.67945 -0.305054)
			(end -0.12065 -0.305054)
			(stroke
				(width 0.1)
				(type default)
			)
			(layer "F.Fab")
		)
		(fp_line
			(start -0.12065 -0.305054)
			(end -0.12065 -0.2794)
			(stroke
				(width 0.1)
				(type default)
			)
			(layer "F.Fab")
		)
		(pad "1" smd rect
			(at -0.40005 0 90)
			(size 0.4572 0.508)
			(layers "F.Cu" "F.Mask" "F.Paste")
			(net "I3C_SPD_DDRGL_CPU0_SDA")
		)
		(pad "2" smd rect
			(at 0.40005 0 90)
			(size 0.4572 0.508)
			(layers "F.Cu" "F.Mask" "F.Paste")
			(net "I3C_SPD_DDRGL_CPU0_LVC1_SDA")
		)
	)
	(footprint ""
		(layer "F.Cu")
		(at 192.151 -137.632948 -90)
		(property "Reference" "R1567"
			(at 0 0 270)
			(layer "F.SilkS")
			(hide yes)
			(effects
				(font
					(size 1.27 1.27)
				)
			)
		)
		(property "Value" ""
			(at 0 0 270)
			(layer "F.Fab")
			(effects
				(font
					(size 1.27 1.27)
				)
			)
		)
		(duplicate_pad_numbers_are_jumpers no)
		(fp_line
			(start -0.7874 0.4064)
			(end -0.7874 -0.4064)
			(stroke
				(width 0.1524)
				(type default)
			)
			(layer "F.SilkS")
		)
		(fp_line
			(start 0.7874 0.4064)
			(end -0.7874 0.4064)
			(stroke
				(width 0.1524)
				(type default)
			)
			(layer "F.SilkS")
		)
		(fp_line
			(start -0.7874 -0.4064)
			(end 0.7874 -0.4064)
			(stroke
				(width 0.1524)
				(type default)
			)
			(layer "F.SilkS")
		)
		(fp_line
			(start 0.7874 -0.4064)
			(end 0.7874 0.4064)
			(stroke
				(width 0.1524)
				(type default)
			)
			(layer "F.SilkS")
		)
		(fp_line
			(start -0.67945 0.3048)
			(end -0.67945 -0.305054)
			(stroke
				(width 0.1)
				(type default)
			)
			(layer "F.Fab")
		)
		(fp_line
			(start -0.12065 0.3048)
			(end -0.67945 0.3048)
			(stroke
				(width 0.1)
				(type default)
			)
			(layer "F.Fab")
		)
		(fp_line
			(start 0.120396 0.3048)
			(end 0.120396 0.2794)
			(stroke
				(width 0.1)
				(type default)
			)
			(layer "F.Fab")
		)
		(fp_line
			(start 0.67945 0.3048)
			(end 0.120396 0.3048)
			(stroke
				(width 0.1)
				(type default)
			)
			(layer "F.Fab")
		)
		(fp_line
			(start -0.12065 0.2794)
			(end -0.12065 0.3048)
			(stroke
				(width 0.1)
				(type default)
			)
			(layer "F.Fab")
		)
		(fp_line
			(start 0.120396 0.2794)
			(end -0.12065 0.2794)
			(stroke
				(width 0.1)
				(type default)
			)
			(layer "F.Fab")
		)
		(fp_line
			(start -0.12065 -0.2794)
			(end 0.12065 -0.2794)
			(stroke
				(width 0.1)
				(type default)
			)
			(layer "F.Fab")
		)
		(fp_line
			(start 0.12065 -0.2794)
			(end 0.12065 -0.3048)
			(stroke
				(width 0.1)
				(type default)
			)
			(layer "F.Fab")
		)
		(fp_line
			(start 0.12065 -0.3048)
			(end 0.67945 -0.3048)
			(stroke
				(width 0.1)
				(type default)
			)
			(layer "F.Fab")
		)
		(fp_line
			(start 0.67945 -0.3048)
			(end 0.67945 0.3048)
			(stroke
				(width 0.1)
				(type default)
			)
			(layer "F.Fab")
		)
		(fp_line
			(start -0.67945 -0.305054)
			(end -0.12065 -0.305054)
			(stroke
				(width 0.1)
				(type default)
			)
			(layer "F.Fab")
		)
		(fp_line
			(start -0.12065 -0.305054)
			(end -0.12065 -0.2794)
			(stroke
				(width 0.1)
				(type default)
			)
			(layer "F.Fab")
		)
		(pad "1" smd circle
			(at -0.40005 0 270)
			(size 0 0)
			(layers "F.Cu" "F.Mask" "F.Paste")
			(net "PVDD18_S5_P0")
		)
		(pad "2" smd circle
			(at 0.40005 0 270)
			(size 0 0)
			(layers "F.Cu" "F.Mask" "F.Paste")
			(net "ROM_LS_EN")
		)
	)
	(footprint ""
		(layer "F.Cu")
		(at 332.071472 -395.066774 -90)
		(property "Reference" "R629"
			(at 0 0 270)
			(layer "F.SilkS")
			(hide yes)
			(effects
				(font
					(size 1.27 1.27)
				)
			)
		)
		(property "Value" ""
			(at 0 0 270)
			(layer "F.Fab")
			(effects
				(font
					(size 1.27 1.27)
				)
			)
		)
		(duplicate_pad_numbers_are_jumpers no)
		(fp_line
			(start -0.32512 0.175006)
			(end -0.32512 -0.175006)
			(stroke
				(width 0.1)
				(type default)
			)
			(layer "F.Fab")
		)
		(fp_line
			(start 0.32512 0.175006)
			(end -0.32512 0.175006)
			(stroke
				(width 0.1)
				(type default)
			)
			(layer "F.Fab")
		)
		(fp_line
			(start -0.32512 -0.175006)
			(end 0.32512 -0.175006)
			(stroke
				(width 0.1)
				(type default)
			)
			(layer "F.Fab")
		)
		(fp_line
			(start 0.32512 -0.175006)
			(end 0.32512 0.175006)
			(stroke
				(width 0.1)
				(type default)
			)
			(layer "F.Fab")
		)
		(pad "1" smd rect
			(at -0.2667 0 270)
			(size 0.3048 0.381)
			(layers "F.Cu" "F.Mask" "F.Paste")
			(net "CLK_100M_RETIMER_CPU0_P1_DN")
		)
		(pad "2" smd rect
			(at 0.2667 0 90)
			(size 0.3048 0.381)
			(layers "F.Cu" "F.Mask" "F.Paste")
			(net "GND")
		)
	)
	(footprint ""
		(layer "F.Cu")
		(at 152.849326 -39.02456 180)
		(property "Reference" "R3519"
			(at 0 0 180)
			(layer "F.SilkS")
			(hide yes)
			(effects
				(font
					(size 1.27 1.27)
				)
			)
		)
		(property "Value" ""
			(at 0 0 180)
			(layer "F.Fab")
			(effects
				(font
					(size 1.27 1.27)
				)
			)
		)
		(duplicate_pad_numbers_are_jumpers no)
		(fp_line
			(start 0.7874 0.4064)
			(end -0.7874 0.4064)
			(stroke
				(width 0.1524)
				(type default)
			)
			(layer "F.SilkS")
		)
		(fp_line
			(start 0.7874 -0.4064)
			(end 0.7874 0.4064)
			(stroke
				(width 0.1524)
				(type default)
			)
			(layer "F.SilkS")
		)
		(fp_line
			(start -0.7874 0.4064)
			(end -0.7874 -0.4064)
			(stroke
				(width 0.1524)
				(type default)
			)
			(layer "F.SilkS")
		)
		(fp_line
			(start -0.7874 -0.4064)
			(end 0.7874 -0.4064)
			(stroke
				(width 0.1524)
				(type default)
			)
			(layer "F.SilkS")
		)
		(fp_line
			(start 0.67945 0.3048)
			(end 0.120396 0.3048)
			(stroke
				(width 0.1)
				(type default)
			)
			(layer "F.Fab")
		)
		(fp_line
			(start 0.67945 -0.3048)
			(end 0.67945 0.3048)
			(stroke
				(width 0.1)
				(type default)
			)
			(layer "F.Fab")
		)
		(fp_line
			(start 0.12065 -0.2794)
			(end 0.12065 -0.3048)
			(stroke
				(width 0.1)
				(type default)
			)
			(layer "F.Fab")
		)
		(fp_line
			(start 0.12065 -0.3048)
			(end 0.67945 -0.3048)
			(stroke
				(width 0.1)
				(type default)
			)
			(layer "F.Fab")
		)
		(fp_line
			(start 0.120396 0.3048)
			(end 0.120396 0.2794)
			(stroke
				(width 0.1)
				(type default)
			)
			(layer "F.Fab")
		)
		(fp_line
			(start 0.120396 0.2794)
			(end -0.12065 0.2794)
			(stroke
				(width 0.1)
				(type default)
			)
			(layer "F.Fab")
		)
		(fp_line
			(start -0.12065 0.3048)
			(end -0.67945 0.3048)
			(stroke
				(width 0.1)
				(type default)
			)
			(layer "F.Fab")
		)
		(fp_line
			(start -0.12065 0.2794)
			(end -0.12065 0.3048)
			(stroke
				(width 0.1)
				(type default)
			)
			(layer "F.Fab")
		)
		(fp_line
			(start -0.12065 -0.2794)
			(end 0.12065 -0.2794)
			(stroke
				(width 0.1)
				(type default)
			)
			(layer "F.Fab")
		)
		(fp_line
			(start -0.12065 -0.305054)
			(end -0.12065 -0.2794)
			(stroke
				(width 0.1)
				(type default)
			)
			(layer "F.Fab")
		)
		(fp_line
			(start -0.67945 0.3048)
			(end -0.67945 -0.305054)
			(stroke
				(width 0.1)
				(type default)
			)
			(layer "F.Fab")
		)
		(fp_line
			(start -0.67945 -0.305054)
			(end -0.12065 -0.305054)
			(stroke
				(width 0.1)
				(type default)
			)
			(layer "F.Fab")
		)
		(pad "1" smd circle
			(at -0.40005 0 180)
			(size 0 0)
			(layers "F.Cu" "F.Mask" "F.Paste")
			(net "P3V3_OCP_V3_2")
		)
		(pad "2" smd circle
			(at 0.40005 0 180)
			(size 0 0)
			(layers "F.Cu" "F.Mask" "F.Paste")
			(net "SMB_OCP_V3_2_3V3AUX_BUF_SCL")
		)
	)
	(footprint ""
		(layer "F.Cu")
		(at 434.443632 -107.17403 90)
		(property "Reference" "PC2086"
			(at 0 0 90)
			(layer "F.SilkS")
			(hide yes)
			(effects
				(font
					(size 1.27 1.27)
				)
			)
		)
		(property "Value" ""
			(at 0 0 90)
			(layer "F.Fab")
			(effects
				(font
					(size 1.27 1.27)
				)
			)
		)
		(duplicate_pad_numbers_are_jumpers no)
		(fp_line
			(start 0.7874 -0.4064)
			(end 0.7874 0.4064)
			(stroke
				(width 0.1524)
				(type default)
			)
			(layer "F.SilkS")
		)
		(fp_line
			(start -0.7874 -0.4064)
			(end 0.7874 -0.4064)
			(stroke
				(width 0.1524)
				(type default)
			)
			(layer "F.SilkS")
		)
		(fp_line
			(start 0.7874 0.4064)
			(end -0.7874 0.4064)
			(stroke
				(width 0.1524)
				(type default)
			)
			(layer "F.SilkS")
		)
		(fp_line
			(start -0.7874 0.4064)
			(end -0.7874 -0.4064)
			(stroke
				(width 0.1524)
				(type default)
			)
			(layer "F.SilkS")
		)
		(fp_line
			(start -0.12065 -0.305054)
			(end -0.12065 -0.2794)
			(stroke
				(width 0.1)
				(type default)
			)
			(layer "F.Fab")
		)
		(fp_line
			(start -0.67945 -0.305054)
			(end -0.12065 -0.305054)
			(stroke
				(width 0.1)
				(type default)
			)
			(layer "F.Fab")
		)
		(fp_line
			(start 0.67945 -0.3048)
			(end 0.67945 0.3048)
			(stroke
				(width 0.1)
				(type default)
			)
			(layer "F.Fab")
		)
		(fp_line
			(start 0.12065 -0.3048)
			(end 0.67945 -0.3048)
			(stroke
				(width 0.1)
				(type default)
			)
			(layer "F.Fab")
		)
		(fp_line
			(start 0.12065 -0.2794)
			(end 0.12065 -0.3048)
			(stroke
				(width 0.1)
				(type default)
			)
			(layer "F.Fab")
		)
		(fp_line
			(start -0.12065 -0.2794)
			(end 0.12065 -0.2794)
			(stroke
				(width 0.1)
				(type default)
			)
			(layer "F.Fab")
		)
		(fp_line
			(start 0.120396 0.2794)
			(end -0.12065 0.2794)
			(stroke
				(width 0.1)
				(type default)
			)
			(layer "F.Fab")
		)
		(fp_line
			(start -0.12065 0.2794)
			(end -0.12065 0.3048)
			(stroke
				(width 0.1)
				(type default)
			)
			(layer "F.Fab")
		)
		(fp_line
			(start 0.67945 0.3048)
			(end 0.120396 0.3048)
			(stroke
				(width 0.1)
				(type default)
			)
			(layer "F.Fab")
		)
		(fp_line
			(start 0.120396 0.3048)
			(end 0.120396 0.2794)
			(stroke
				(width 0.1)
				(type default)
			)
			(layer "F.Fab")
		)
		(fp_line
			(start -0.12065 0.3048)
			(end -0.67945 0.3048)
			(stroke
				(width 0.1)
				(type default)
			)
			(layer "F.Fab")
		)
		(fp_line
			(start -0.67945 0.3048)
			(end -0.67945 -0.305054)
			(stroke
				(width 0.1)
				(type default)
			)
			(layer "F.Fab")
		)
		(pad "1" smd circle
			(at -0.40005 0 90)
			(size 0 0)
			(layers "F.Cu" "F.Mask" "F.Paste")
			(net "P3V3_OCP_VCC_1")
		)
		(pad "2" smd circle
			(at 0.40005 0 90)
			(size 0 0)
			(layers "F.Cu" "F.Mask" "F.Paste")
			(net "GND")
		)
	)
	(footprint ""
		(layer "F.Cu")
		(at 316.23 -366.395 90)
		(property "Reference" "PC76"
			(at 0 0 90)
			(layer "F.SilkS")
			(hide yes)
			(effects
				(font
					(size 1.27 1.27)
				)
			)
		)
		(property "Value" ""
			(at 0 0 90)
			(layer "F.Fab")
			(effects
				(font
					(size 1.27 1.27)
				)
			)
		)
		(duplicate_pad_numbers_are_jumpers no)
		(fp_line
			(start 0.7874 -0.4064)
			(end 0.7874 0.4064)
			(stroke
				(width 0.1524)
				(type default)
			)
			(layer "F.SilkS")
		)
		(fp_line
			(start -0.7874 -0.4064)
			(end 0.7874 -0.4064)
			(stroke
				(width 0.1524)
				(type default)
			)
			(layer "F.SilkS")
		)
		(fp_line
			(start 0.7874 0.4064)
			(end -0.7874 0.4064)
			(stroke
				(width 0.1524)
				(type default)
			)
			(layer "F.SilkS")
		)
		(fp_line
			(start -0.7874 0.4064)
			(end -0.7874 -0.4064)
			(stroke
				(width 0.1524)
				(type default)
			)
			(layer "F.SilkS")
		)
		(fp_line
			(start -0.12065 -0.305054)
			(end -0.12065 -0.2794)
			(stroke
				(width 0.1)
				(type default)
			)
			(layer "F.Fab")
		)
		(fp_line
			(start -0.67945 -0.305054)
			(end -0.12065 -0.305054)
			(stroke
				(width 0.1)
				(type default)
			)
			(layer "F.Fab")
		)
		(fp_line
			(start 0.67945 -0.3048)
			(end 0.67945 0.3048)
			(stroke
				(width 0.1)
				(type default)
			)
			(layer "F.Fab")
		)
		(fp_line
			(start 0.12065 -0.3048)
			(end 0.67945 -0.3048)
			(stroke
				(width 0.1)
				(type default)
			)
			(layer "F.Fab")
		)
		(fp_line
			(start 0.12065 -0.2794)
			(end 0.12065 -0.3048)
			(stroke
				(width 0.1)
				(type default)
			)
			(layer "F.Fab")
		)
		(fp_line
			(start -0.12065 -0.2794)
			(end 0.12065 -0.2794)
			(stroke
				(width 0.1)
				(type default)
			)
			(layer "F.Fab")
		)
		(fp_line
			(start 0.120396 0.2794)
			(end -0.12065 0.2794)
			(stroke
				(width 0.1)
				(type default)
			)
			(layer "F.Fab")
		)
		(fp_line
			(start -0.12065 0.2794)
			(end -0.12065 0.3048)
			(stroke
				(width 0.1)
				(type default)
			)
			(layer "F.Fab")
		)
		(fp_line
			(start 0.67945 0.3048)
			(end 0.120396 0.3048)
			(stroke
				(width 0.1)
				(type default)
			)
			(layer "F.Fab")
		)
		(fp_line
			(start 0.120396 0.3048)
			(end 0.120396 0.2794)
			(stroke
				(width 0.1)
				(type default)
			)
			(layer "F.Fab")
		)
		(fp_line
			(start -0.12065 0.3048)
			(end -0.67945 0.3048)
			(stroke
				(width 0.1)
				(type default)
			)
			(layer "F.Fab")
		)
		(fp_line
			(start -0.67945 0.3048)
			(end -0.67945 -0.305054)
			(stroke
				(width 0.1)
				(type default)
			)
			(layer "F.Fab")
		)
		(pad "1" smd circle
			(at -0.40005 0 90)
			(size 0 0)
			(layers "F.Cu" "F.Mask" "F.Paste")
			(net "PVDDCR_CPU1_P0_VCCS")
		)
		(pad "2" smd circle
			(at 0.40005 0 90)
			(size 0 0)
			(layers "F.Cu" "F.Mask" "F.Paste")
			(net "GND")
		)
	)
	(footprint ""
		(layer "F.Cu")
		(at 76.070714 -339.850476 90)
		(property "Reference" "PC373_2"
			(at 0 0 90)
			(layer "F.SilkS")
			(hide yes)
			(effects
				(font
					(size 1.27 1.27)
				)
			)
		)
		(property "Value" ""
			(at 0 0 90)
			(layer "F.Fab")
			(effects
				(font
					(size 1.27 1.27)
				)
			)
		)
		(duplicate_pad_numbers_are_jumpers no)
		(fp_line
			(start 0.7874 -0.4064)
			(end 0.7874 0.4064)
			(stroke
				(width 0.1524)
				(type default)
			)
			(layer "F.SilkS")
		)
		(fp_line
			(start -0.7874 -0.4064)
			(end 0.7874 -0.4064)
			(stroke
				(width 0.1524)
				(type default)
			)
			(layer "F.SilkS")
		)
		(fp_line
			(start 0.7874 0.4064)
			(end -0.7874 0.4064)
			(stroke
				(width 0.1524)
				(type default)
			)
			(layer "F.SilkS")
		)
		(fp_line
			(start -0.7874 0.4064)
			(end -0.7874 -0.4064)
			(stroke
				(width 0.1524)
				(type default)
			)
			(layer "F.SilkS")
		)
		(fp_line
			(start -0.12065 -0.305054)
			(end -0.12065 -0.2794)
			(stroke
				(width 0.1)
				(type default)
			)
			(layer "F.Fab")
		)
		(fp_line
			(start -0.67945 -0.305054)
			(end -0.12065 -0.305054)
			(stroke
				(width 0.1)
				(type default)
			)
			(layer "F.Fab")
		)
		(fp_line
			(start 0.67945 -0.3048)
			(end 0.67945 0.3048)
			(stroke
				(width 0.1)
				(type default)
			)
			(layer "F.Fab")
		)
		(fp_line
			(start 0.12065 -0.3048)
			(end 0.67945 -0.3048)
			(stroke
				(width 0.1)
				(type default)
			)
			(layer "F.Fab")
		)
		(fp_line
			(start 0.12065 -0.2794)
			(end 0.12065 -0.3048)
			(stroke
				(width 0.1)
				(type default)
			)
			(layer "F.Fab")
		)
		(fp_line
			(start -0.12065 -0.2794)
			(end 0.12065 -0.2794)
			(stroke
				(width 0.1)
				(type default)
			)
			(layer "F.Fab")
		)
		(fp_line
			(start 0.120396 0.2794)
			(end -0.12065 0.2794)
			(stroke
				(width 0.1)
				(type default)
			)
			(layer "F.Fab")
		)
		(fp_line
			(start -0.12065 0.2794)
			(end -0.12065 0.3048)
			(stroke
				(width 0.1)
				(type default)
			)
			(layer "F.Fab")
		)
		(fp_line
			(start 0.67945 0.3048)
			(end 0.120396 0.3048)
			(stroke
				(width 0.1)
				(type default)
			)
			(layer "F.Fab")
		)
		(fp_line
			(start 0.120396 0.3048)
			(end 0.120396 0.2794)
			(stroke
				(width 0.1)
				(type default)
			)
			(layer "F.Fab")
		)
		(fp_line
			(start -0.12065 0.3048)
			(end -0.67945 0.3048)
			(stroke
				(width 0.1)
				(type default)
			)
			(layer "F.Fab")
		)
		(fp_line
			(start -0.67945 0.3048)
			(end -0.67945 -0.305054)
			(stroke
				(width 0.1)
				(type default)
			)
			(layer "F.Fab")
		)
		(pad "1" smd circle
			(at -0.40005 0 90)
			(size 0 0)
			(layers "F.Cu" "F.Mask" "F.Paste")
			(net "PVDDCR_CPU1_P1_VCCS")
		)
		(pad "2" smd circle
			(at 0.40005 0 90)
			(size 0 0)
			(layers "F.Cu" "F.Mask" "F.Paste")
			(net "GND")
		)
	)
	(footprint ""
		(layer "F.Cu")
		(at 63.084964 -408.517344 -90)
		(property "Reference" "C6640"
			(at 0 0 270)
			(layer "F.SilkS")
			(hide yes)
			(effects
				(font
					(size 1.27 1.27)
				)
			)
		)
		(property "Value" ""
			(at 0 0 270)
			(layer "F.Fab")
			(effects
				(font
					(size 1.27 1.27)
				)
			)
		)
		(duplicate_pad_numbers_are_jumpers no)
		(fp_line
			(start -0.299974 0.150114)
			(end -0.299974 -0.150114)
			(stroke
				(width 0.1)
				(type default)
			)
			(layer "F.Fab")
		)
		(fp_line
			(start 0.299974 0.150114)
			(end -0.299974 0.150114)
			(stroke
				(width 0.1)
				(type default)
			)
			(layer "F.Fab")
		)
		(fp_line
			(start -0.299974 -0.150114)
			(end 0.299974 -0.150114)
			(stroke
				(width 0.1)
				(type default)
			)
			(layer "F.Fab")
		)
		(fp_line
			(start 0.299974 -0.150114)
			(end 0.299974 0.150114)
			(stroke
				(width 0.1)
				(type default)
			)
			(layer "F.Fab")
		)
		(pad "1" smd rect
			(at -0.2667 0 270)
			(size 0.3048 0.381)
			(layers "F.Cu" "F.Mask" "F.Paste")
			(net "P5E_CPU1_P0_TX_BUF_C_DN<5>")
		)
		(pad "2" smd rect
			(at 0.2667 0 270)
			(size 0.3048 0.381)
			(layers "F.Cu" "F.Mask" "F.Paste")
			(net "P5E_CPU1_P0_TX_BUF_DN<5>")
		)
	)
	(footprint ""
		(layer "F.Cu")
		(at 212.993732 -117.748812 180)
		(property "Reference" "R133"
			(at 0 0 180)
			(layer "F.SilkS")
			(hide yes)
			(effects
				(font
					(size 1.27 1.27)
				)
			)
		)
		(property "Value" ""
			(at 0 0 180)
			(layer "F.Fab")
			(effects
				(font
					(size 1.27 1.27)
				)
			)
		)
		(duplicate_pad_numbers_are_jumpers no)
		(fp_line
			(start 0.7874 0.4064)
			(end -0.7874 0.4064)
			(stroke
				(width 0.1524)
				(type default)
			)
			(layer "F.SilkS")
		)
		(fp_line
			(start 0.7874 -0.4064)
			(end 0.7874 0.4064)
			(stroke
				(width 0.1524)
				(type default)
			)
			(layer "F.SilkS")
		)
		(fp_line
			(start -0.7874 0.4064)
			(end -0.7874 -0.4064)
			(stroke
				(width 0.1524)
				(type default)
			)
			(layer "F.SilkS")
		)
		(fp_line
			(start -0.7874 -0.4064)
			(end 0.7874 -0.4064)
			(stroke
				(width 0.1524)
				(type default)
			)
			(layer "F.SilkS")
		)
		(fp_line
			(start 0.67945 0.3048)
			(end 0.120396 0.3048)
			(stroke
				(width 0.1)
				(type default)
			)
			(layer "F.Fab")
		)
		(fp_line
			(start 0.67945 -0.3048)
			(end 0.67945 0.3048)
			(stroke
				(width 0.1)
				(type default)
			)
			(layer "F.Fab")
		)
		(fp_line
			(start 0.12065 -0.2794)
			(end 0.12065 -0.3048)
			(stroke
				(width 0.1)
				(type default)
			)
			(layer "F.Fab")
		)
		(fp_line
			(start 0.12065 -0.3048)
			(end 0.67945 -0.3048)
			(stroke
				(width 0.1)
				(type default)
			)
			(layer "F.Fab")
		)
		(fp_line
			(start 0.120396 0.3048)
			(end 0.120396 0.2794)
			(stroke
				(width 0.1)
				(type default)
			)
			(layer "F.Fab")
		)
		(fp_line
			(start 0.120396 0.2794)
			(end -0.12065 0.2794)
			(stroke
				(width 0.1)
				(type default)
			)
			(layer "F.Fab")
		)
		(fp_line
			(start -0.12065 0.3048)
			(end -0.67945 0.3048)
			(stroke
				(width 0.1)
				(type default)
			)
			(layer "F.Fab")
		)
		(fp_line
			(start -0.12065 0.2794)
			(end -0.12065 0.3048)
			(stroke
				(width 0.1)
				(type default)
			)
			(layer "F.Fab")
		)
		(fp_line
			(start -0.12065 -0.2794)
			(end 0.12065 -0.2794)
			(stroke
				(width 0.1)
				(type default)
			)
			(layer "F.Fab")
		)
		(fp_line
			(start -0.12065 -0.305054)
			(end -0.12065 -0.2794)
			(stroke
				(width 0.1)
				(type default)
			)
			(layer "F.Fab")
		)
		(fp_line
			(start -0.67945 0.3048)
			(end -0.67945 -0.305054)
			(stroke
				(width 0.1)
				(type default)
			)
			(layer "F.Fab")
		)
		(fp_line
			(start -0.67945 -0.305054)
			(end -0.12065 -0.305054)
			(stroke
				(width 0.1)
				(type default)
			)
			(layer "F.Fab")
		)
		(pad "1" smd circle
			(at -0.40005 0 180)
			(size 0 0)
			(layers "F.Cu" "F.Mask" "F.Paste")
			(net "FM_APML_MUX2_SEL")
		)
		(pad "2" smd circle
			(at 0.40005 0 180)
			(size 0 0)
			(layers "F.Cu" "F.Mask" "F.Paste")
			(net "FM_APML_MUX2_SEL_R")
		)
	)
	(footprint ""
		(layer "F.Cu")
		(at 438.827418 -332.63586 -90)
		(property "Reference" "PC801"
			(at -4.98094 -2.990596 90)
			(unlocked yes)
			(layer "F.SilkS")
			(effects
				(font
					(size 0.7874 0.5842)
					(thickness 0.1524)
				)
				(justify left)
			)
		)
		(property "Value" ""
			(at 0 0 270)
			(layer "F.Fab")
			(effects
				(font
					(size 1.27 1.27)
				)
			)
		)
		(duplicate_pad_numbers_are_jumpers no)
		(fp_line
			(start -1.988058 2.750058)
			(end 2.750058 2.750058)
			(stroke
				(width 0.1524)
				(type default)
			)
			(layer "F.SilkS")
		)
		(fp_line
			(start 2.750058 2.750058)
			(end 2.750058 0.9398)
			(stroke
				(width 0.1524)
				(type default)
			)
			(layer "F.SilkS")
		)
		(fp_line
			(start -2.750058 1.988058)
			(end -1.988058 2.750058)
			(stroke
				(width 0.1524)
				(type default)
			)
			(layer "F.SilkS")
		)
		(fp_line
			(start -2.750058 0.9398)
			(end -2.750058 1.988058)
			(stroke
				(width 0.1524)
				(type default)
			)
			(layer "F.SilkS")
		)
		(fp_line
			(start 2.750058 -0.9398)
			(end 2.750058 -2.750058)
			(stroke
				(width 0.1524)
				(type default)
			)
			(layer "F.SilkS")
		)
		(fp_line
			(start -2.750058 -1.988058)
			(end -2.750058 -0.9398)
			(stroke
				(width 0.1524)
				(type default)
			)
			(layer "F.SilkS")
		)
		(fp_line
			(start -1.988058 -2.750058)
			(end -2.750058 -1.988058)
			(stroke
				(width 0.1524)
				(type default)
			)
			(layer "F.SilkS")
		)
		(fp_line
			(start 2.750058 -2.750058)
			(end -1.988058 -2.750058)
			(stroke
				(width 0.1524)
				(type default)
			)
			(layer "F.SilkS")
		)
		(fp_line
			(start -2.750058 2.750058)
			(end 2.750058 2.750058)
			(stroke
				(width 0.1)
				(type default)
			)
			(layer "F.Fab")
		)
		(fp_line
			(start 2.750058 2.750058)
			(end 2.750058 -2.750058)
			(stroke
				(width 0.1)
				(type default)
			)
			(layer "F.Fab")
		)
		(fp_line
			(start -2.750058 -2.750058)
			(end -2.750058 2.750058)
			(stroke
				(width 0.1)
				(type default)
			)
			(layer "F.Fab")
		)
		(fp_line
			(start 2.750058 -2.750058)
			(end -2.750058 -2.750058)
			(stroke
				(width 0.1)
				(type default)
			)
			(layer "F.Fab")
		)
		(pad "1" smd rect
			(at -2.199894 0)
			(size 1.6002 3.0226)
			(layers "F.Cu" "F.Mask" "F.Paste")
			(net "PVDD11_S3_P0")
		)
		(pad "2" smd rect
			(at 2.199894 0)
			(size 1.6002 3.0226)
			(layers "F.Cu" "F.Mask" "F.Paste")
			(net "GND")
		)
	)
	(footprint ""
		(layer "F.Cu")
		(at 152.849834 -320.699892)
		(property "Reference" "R583"
			(at 0 0 0)
			(layer "F.SilkS")
			(hide yes)
			(effects
				(font
					(size 1.27 1.27)
				)
			)
		)
		(property "Value" ""
			(at 0 0 0)
			(layer "F.Fab")
			(effects
				(font
					(size 1.27 1.27)
				)
			)
		)
		(duplicate_pad_numbers_are_jumpers no)
		(fp_line
			(start -0.7874 -0.4064)
			(end 0.7874 -0.4064)
			(stroke
				(width 0.1524)
				(type default)
			)
			(layer "F.SilkS")
		)
		(fp_line
			(start -0.7874 0.4064)
			(end -0.7874 -0.4064)
			(stroke
				(width 0.1524)
				(type default)
			)
			(layer "F.SilkS")
		)
		(fp_line
			(start 0.7874 -0.4064)
			(end 0.7874 0.4064)
			(stroke
				(width 0.1524)
				(type default)
			)
			(layer "F.SilkS")
		)
		(fp_line
			(start 0.7874 0.4064)
			(end -0.7874 0.4064)
			(stroke
				(width 0.1524)
				(type default)
			)
			(layer "F.SilkS")
		)
		(fp_line
			(start -0.67945 -0.305054)
			(end -0.12065 -0.305054)
			(stroke
				(width 0.1)
				(type default)
			)
			(layer "F.Fab")
		)
		(fp_line
			(start -0.67945 0.3048)
			(end -0.67945 -0.305054)
			(stroke
				(width 0.1)
				(type default)
			)
			(layer "F.Fab")
		)
		(fp_line
			(start -0.12065 -0.305054)
			(end -0.12065 -0.2794)
			(stroke
				(width 0.1)
				(type default)
			)
			(layer "F.Fab")
		)
		(fp_line
			(start -0.12065 -0.2794)
			(end 0.12065 -0.2794)
			(stroke
				(width 0.1)
				(type default)
			)
			(layer "F.Fab")
		)
		(fp_line
			(start -0.12065 0.2794)
			(end -0.12065 0.3048)
			(stroke
				(width 0.1)
				(type default)
			)
			(layer "F.Fab")
		)
		(fp_line
			(start -0.12065 0.3048)
			(end -0.67945 0.3048)
			(stroke
				(width 0.1)
				(type default)
			)
			(layer "F.Fab")
		)
		(fp_line
			(start 0.120396 0.2794)
			(end -0.12065 0.2794)
			(stroke
				(width 0.1)
				(type default)
			)
			(layer "F.Fab")
		)
		(fp_line
			(start 0.120396 0.3048)
			(end 0.120396 0.2794)
			(stroke
				(width 0.1)
				(type default)
			)
			(layer "F.Fab")
		)
		(fp_line
			(start 0.12065 -0.3048)
			(end 0.67945 -0.3048)
			(stroke
				(width 0.1)
				(type default)
			)
			(layer "F.Fab")
		)
		(fp_line
			(start 0.12065 -0.2794)
			(end 0.12065 -0.3048)
			(stroke
				(width 0.1)
				(type default)
			)
			(layer "F.Fab")
		)
		(fp_line
			(start 0.67945 -0.3048)
			(end 0.67945 0.3048)
			(stroke
				(width 0.1)
				(type default)
			)
			(layer "F.Fab")
		)
		(fp_line
			(start 0.67945 0.3048)
			(end 0.120396 0.3048)
			(stroke
				(width 0.1)
				(type default)
			)
			(layer "F.Fab")
		)
		(pad "1" smd circle
			(at -0.40005 0)
			(size 0 0)
			(layers "F.Cu" "F.Mask" "F.Paste")
			(net "RST_CPU1_RSMRST_N")
		)
		(pad "2" smd circle
			(at 0.40005 0)
			(size 0 0)
			(layers "F.Cu" "F.Mask" "F.Paste")
			(net "PVDD18_S5_P1")
		)
	)
	(footprint ""
		(layer "F.Cu")
		(at 169.66819 -419.116256 90)
		(property "Reference" "R697"
			(at 0 0 90)
			(layer "F.SilkS")
			(hide yes)
			(effects
				(font
					(size 1.27 1.27)
				)
			)
		)
		(property "Value" ""
			(at 0 0 90)
			(layer "F.Fab")
			(effects
				(font
					(size 1.27 1.27)
				)
			)
		)
		(duplicate_pad_numbers_are_jumpers no)
		(fp_line
			(start 0.32512 -0.175006)
			(end 0.32512 0.175006)
			(stroke
				(width 0.1)
				(type default)
			)
			(layer "F.Fab")
		)
		(fp_line
			(start -0.32512 -0.175006)
			(end 0.32512 -0.175006)
			(stroke
				(width 0.1)
				(type default)
			)
			(layer "F.Fab")
		)
		(fp_line
			(start 0.32512 0.175006)
			(end -0.32512 0.175006)
			(stroke
				(width 0.1)
				(type default)
			)
			(layer "F.Fab")
		)
		(fp_line
			(start -0.32512 0.175006)
			(end -0.32512 -0.175006)
			(stroke
				(width 0.1)
				(type default)
			)
			(layer "F.Fab")
		)
		(pad "1" smd rect
			(at -0.2667 0 90)
			(size 0.3048 0.381)
			(layers "F.Cu" "F.Mask" "F.Paste")
			(net "SMB_RT_CPU1_P3_ROM_R_SCL")
		)
		(pad "2" smd rect
			(at 0.2667 0 270)
			(size 0.3048 0.381)
			(layers "F.Cu" "F.Mask" "F.Paste")
			(net "SMB_RT_CPU1_P3_ROM_SCL")
		)
	)
	(footprint ""
		(layer "F.Cu")
		(at 92.997528 -156.829252)
		(property "Reference" "PC6004"
			(at 0 0 0)
			(layer "F.SilkS")
			(hide yes)
			(effects
				(font
					(size 1.27 1.27)
				)
			)
		)
		(property "Value" ""
			(at 0 0 0)
			(layer "F.Fab")
			(effects
				(font
					(size 1.27 1.27)
				)
			)
		)
		(duplicate_pad_numbers_are_jumpers no)
		(fp_line
			(start -0.7874 -0.4064)
			(end 0.7874 -0.4064)
			(stroke
				(width 0.1524)
				(type default)
			)
			(layer "F.SilkS")
		)
		(fp_line
			(start -0.7874 0.4064)
			(end -0.7874 -0.4064)
			(stroke
				(width 0.1524)
				(type default)
			)
			(layer "F.SilkS")
		)
		(fp_line
			(start 0.7874 -0.4064)
			(end 0.7874 0.4064)
			(stroke
				(width 0.1524)
				(type default)
			)
			(layer "F.SilkS")
		)
		(fp_line
			(start 0.7874 0.4064)
			(end -0.7874 0.4064)
			(stroke
				(width 0.1524)
				(type default)
			)
			(layer "F.SilkS")
		)
		(fp_line
			(start -0.67945 -0.305054)
			(end -0.12065 -0.305054)
			(stroke
				(width 0.1)
				(type default)
			)
			(layer "F.Fab")
		)
		(fp_line
			(start -0.67945 0.3048)
			(end -0.67945 -0.305054)
			(stroke
				(width 0.1)
				(type default)
			)
			(layer "F.Fab")
		)
		(fp_line
			(start -0.12065 -0.305054)
			(end -0.12065 -0.2794)
			(stroke
				(width 0.1)
				(type default)
			)
			(layer "F.Fab")
		)
		(fp_line
			(start -0.12065 -0.2794)
			(end 0.12065 -0.2794)
			(stroke
				(width 0.1)
				(type default)
			)
			(layer "F.Fab")
		)
		(fp_line
			(start -0.12065 0.2794)
			(end -0.12065 0.3048)
			(stroke
				(width 0.1)
				(type default)
			)
			(layer "F.Fab")
		)
		(fp_line
			(start -0.12065 0.3048)
			(end -0.67945 0.3048)
			(stroke
				(width 0.1)
				(type default)
			)
			(layer "F.Fab")
		)
		(fp_line
			(start 0.120396 0.2794)
			(end -0.12065 0.2794)
			(stroke
				(width 0.1)
				(type default)
			)
			(layer "F.Fab")
		)
		(fp_line
			(start 0.120396 0.3048)
			(end 0.120396 0.2794)
			(stroke
				(width 0.1)
				(type default)
			)
			(layer "F.Fab")
		)
		(fp_line
			(start 0.12065 -0.3048)
			(end 0.67945 -0.3048)
			(stroke
				(width 0.1)
				(type default)
			)
			(layer "F.Fab")
		)
		(fp_line
			(start 0.12065 -0.2794)
			(end 0.12065 -0.3048)
			(stroke
				(width 0.1)
				(type default)
			)
			(layer "F.Fab")
		)
		(fp_line
			(start 0.67945 -0.3048)
			(end 0.67945 0.3048)
			(stroke
				(width 0.1)
				(type default)
			)
			(layer "F.Fab")
		)
		(fp_line
			(start 0.67945 0.3048)
			(end 0.120396 0.3048)
			(stroke
				(width 0.1)
				(type default)
			)
			(layer "F.Fab")
		)
		(pad "1" smd circle
			(at -0.40005 0)
			(size 0 0)
			(layers "F.Cu" "F.Mask" "F.Paste")
			(net "P12V_AUX")
		)
		(pad "2" smd circle
			(at 0.40005 0)
			(size 0 0)
			(layers "F.Cu" "F.Mask" "F.Paste")
			(net "GND")
		)
	)
	(footprint ""
		(layer "F.Cu")
		(at 10.066782 -407.262584 180)
		(property "Reference" "PC6543"
			(at 0 0 180)
			(layer "F.SilkS")
			(hide yes)
			(effects
				(font
					(size 1.27 1.27)
				)
			)
		)
		(property "Value" ""
			(at 0 0 180)
			(layer "F.Fab")
			(effects
				(font
					(size 1.27 1.27)
				)
			)
		)
		(duplicate_pad_numbers_are_jumpers no)
		(fp_line
			(start 0.7874 0.4064)
			(end -0.7874 0.4064)
			(stroke
				(width 0.1524)
				(type default)
			)
			(layer "F.SilkS")
		)
		(fp_line
			(start 0.7874 -0.4064)
			(end 0.7874 0.4064)
			(stroke
				(width 0.1524)
				(type default)
			)
			(layer "F.SilkS")
		)
		(fp_line
			(start -0.7874 0.4064)
			(end -0.7874 -0.4064)
			(stroke
				(width 0.1524)
				(type default)
			)
			(layer "F.SilkS")
		)
		(fp_line
			(start -0.7874 -0.4064)
			(end 0.7874 -0.4064)
			(stroke
				(width 0.1524)
				(type default)
			)
			(layer "F.SilkS")
		)
		(fp_line
			(start 0.67945 0.3048)
			(end 0.120396 0.3048)
			(stroke
				(width 0.1)
				(type default)
			)
			(layer "F.Fab")
		)
		(fp_line
			(start 0.67945 -0.3048)
			(end 0.67945 0.3048)
			(stroke
				(width 0.1)
				(type default)
			)
			(layer "F.Fab")
		)
		(fp_line
			(start 0.12065 -0.2794)
			(end 0.12065 -0.3048)
			(stroke
				(width 0.1)
				(type default)
			)
			(layer "F.Fab")
		)
		(fp_line
			(start 0.12065 -0.3048)
			(end 0.67945 -0.3048)
			(stroke
				(width 0.1)
				(type default)
			)
			(layer "F.Fab")
		)
		(fp_line
			(start 0.120396 0.3048)
			(end 0.120396 0.2794)
			(stroke
				(width 0.1)
				(type default)
			)
			(layer "F.Fab")
		)
		(fp_line
			(start 0.120396 0.2794)
			(end -0.12065 0.2794)
			(stroke
				(width 0.1)
				(type default)
			)
			(layer "F.Fab")
		)
		(fp_line
			(start -0.12065 0.3048)
			(end -0.67945 0.3048)
			(stroke
				(width 0.1)
				(type default)
			)
			(layer "F.Fab")
		)
		(fp_line
			(start -0.12065 0.2794)
			(end -0.12065 0.3048)
			(stroke
				(width 0.1)
				(type default)
			)
			(layer "F.Fab")
		)
		(fp_line
			(start -0.12065 -0.2794)
			(end 0.12065 -0.2794)
			(stroke
				(width 0.1)
				(type default)
			)
			(layer "F.Fab")
		)
		(fp_line
			(start -0.12065 -0.305054)
			(end -0.12065 -0.2794)
			(stroke
				(width 0.1)
				(type default)
			)
			(layer "F.Fab")
		)
		(fp_line
			(start -0.67945 0.3048)
			(end -0.67945 -0.305054)
			(stroke
				(width 0.1)
				(type default)
			)
			(layer "F.Fab")
		)
		(fp_line
			(start -0.67945 -0.305054)
			(end -0.12065 -0.305054)
			(stroke
				(width 0.1)
				(type default)
			)
			(layer "F.Fab")
		)
		(pad "1" smd circle
			(at -0.40005 0 180)
			(size 0 0)
			(layers "F.Cu" "F.Mask" "F.Paste")
			(net "P0V9_RETIMER_CPU1_VCC")
		)
		(pad "2" smd circle
			(at 0.40005 0 180)
			(size 0 0)
			(layers "F.Cu" "F.Mask" "F.Paste")
			(net "GND")
		)
	)
	(footprint ""
		(layer "F.Cu")
		(at 164.719 -107.315 180)
		(property "Reference" "R9027"
			(at 0 0 180)
			(layer "F.SilkS")
			(hide yes)
			(effects
				(font
					(size 1.27 1.27)
				)
			)
		)
		(property "Value" ""
			(at 0 0 180)
			(layer "F.Fab")
			(effects
				(font
					(size 1.27 1.27)
				)
			)
		)
		(duplicate_pad_numbers_are_jumpers no)
		(fp_line
			(start 0.7874 0.4064)
			(end -0.7874 0.4064)
			(stroke
				(width 0.1524)
				(type default)
			)
			(layer "F.SilkS")
		)
		(fp_line
			(start 0.7874 -0.4064)
			(end 0.7874 0.4064)
			(stroke
				(width 0.1524)
				(type default)
			)
			(layer "F.SilkS")
		)
		(fp_line
			(start -0.7874 0.4064)
			(end -0.7874 -0.4064)
			(stroke
				(width 0.1524)
				(type default)
			)
			(layer "F.SilkS")
		)
		(fp_line
			(start -0.7874 -0.4064)
			(end 0.7874 -0.4064)
			(stroke
				(width 0.1524)
				(type default)
			)
			(layer "F.SilkS")
		)
		(fp_line
			(start 0.67945 0.3048)
			(end 0.120396 0.3048)
			(stroke
				(width 0.1)
				(type default)
			)
			(layer "F.Fab")
		)
		(fp_line
			(start 0.67945 -0.3048)
			(end 0.67945 0.3048)
			(stroke
				(width 0.1)
				(type default)
			)
			(layer "F.Fab")
		)
		(fp_line
			(start 0.12065 -0.2794)
			(end 0.12065 -0.3048)
			(stroke
				(width 0.1)
				(type default)
			)
			(layer "F.Fab")
		)
		(fp_line
			(start 0.12065 -0.3048)
			(end 0.67945 -0.3048)
			(stroke
				(width 0.1)
				(type default)
			)
			(layer "F.Fab")
		)
		(fp_line
			(start 0.120396 0.3048)
			(end 0.120396 0.2794)
			(stroke
				(width 0.1)
				(type default)
			)
			(layer "F.Fab")
		)
		(fp_line
			(start 0.120396 0.2794)
			(end -0.12065 0.2794)
			(stroke
				(width 0.1)
				(type default)
			)
			(layer "F.Fab")
		)
		(fp_line
			(start -0.12065 0.3048)
			(end -0.67945 0.3048)
			(stroke
				(width 0.1)
				(type default)
			)
			(layer "F.Fab")
		)
		(fp_line
			(start -0.12065 0.2794)
			(end -0.12065 0.3048)
			(stroke
				(width 0.1)
				(type default)
			)
			(layer "F.Fab")
		)
		(fp_line
			(start -0.12065 -0.2794)
			(end 0.12065 -0.2794)
			(stroke
				(width 0.1)
				(type default)
			)
			(layer "F.Fab")
		)
		(fp_line
			(start -0.12065 -0.305054)
			(end -0.12065 -0.2794)
			(stroke
				(width 0.1)
				(type default)
			)
			(layer "F.Fab")
		)
		(fp_line
			(start -0.67945 0.3048)
			(end -0.67945 -0.305054)
			(stroke
				(width 0.1)
				(type default)
			)
			(layer "F.Fab")
		)
		(fp_line
			(start -0.67945 -0.305054)
			(end -0.12065 -0.305054)
			(stroke
				(width 0.1)
				(type default)
			)
			(layer "F.Fab")
		)
		(pad "1" smd circle
			(at -0.40005 0 180)
			(size 0 0)
			(layers "F.Cu" "F.Mask" "F.Paste")
			(net "P3V3_AUX")
		)
		(pad "2" smd circle
			(at 0.40005 0 180)
			(size 0 0)
			(layers "F.Cu" "F.Mask" "F.Paste")
			(net "IRQ_HSC_FAULT_BUF_N")
		)
	)
	(footprint ""
		(layer "F.Cu")
		(at 254.362966 -66.238374)
		(property "Reference" "Q127"
			(at -1.35382 1.881632 0)
			(unlocked yes)
			(layer "F.SilkS")
			(effects
				(font
					(size 0.7874 0.5842)
					(thickness 0.1524)
				)
				(justify left)
			)
		)
		(property "Value" ""
			(at 0 0 0)
			(layer "F.Fab")
			(effects
				(font
					(size 1.27 1.27)
				)
			)
		)
		(duplicate_pad_numbers_are_jumpers no)
		(fp_line
			(start -1.332738 -1.100074)
			(end -0.4826 -1.100074)
			(stroke
				(width 0.1524)
				(type default)
			)
			(layer "F.SilkS")
		)
		(fp_line
			(start -1.332738 1.100074)
			(end -1.332738 -1.100074)
			(stroke
				(width 0.1524)
				(type default)
			)
			(layer "F.SilkS")
		)
		(fp_line
			(start -0.4826 -1.100074)
			(end 0 -0.541274)
			(stroke
				(width 0.1524)
				(type default)
			)
			(layer "F.SilkS")
		)
		(fp_line
			(start 0 -0.541274)
			(end 0.4826 -1.100074)
			(stroke
				(width 0.1524)
				(type default)
			)
			(layer "F.SilkS")
		)
		(fp_line
			(start 0.4826 -1.100074)
			(end 1.332738 -1.100074)
			(stroke
				(width 0.1524)
				(type default)
			)
			(layer "F.SilkS")
		)
		(fp_line
			(start 1.332738 -1.100074)
			(end 1.332738 1.100074)
			(stroke
				(width 0.1524)
				(type default)
			)
			(layer "F.SilkS")
		)
		(fp_line
			(start 1.332738 1.100074)
			(end -1.332738 1.100074)
			(stroke
				(width 0.1524)
				(type default)
			)
			(layer "F.SilkS")
		)
		(fp_poly
			(pts
				(xy -1.909064 -0.755396) (xy -2.61112 -0.404368) (xy -2.61112 -1.106424)
			)
			(stroke
				(width 0)
				(type default)
			)
			(fill yes)
			(layer "F.SilkS")
		)
		(fp_line
			(start -0.674878 -1.100074)
			(end 0.674878 -1.100074)
			(stroke
				(width 0.1)
				(type default)
			)
			(layer "F.Fab")
		)
		(fp_line
			(start -0.674878 1.100074)
			(end -0.674878 -1.100074)
			(stroke
				(width 0.1)
				(type default)
			)
			(layer "F.Fab")
		)
		(fp_line
			(start 0.674878 -1.100074)
			(end 0.674878 1.100074)
			(stroke
				(width 0.1)
				(type default)
			)
			(layer "F.Fab")
		)
		(fp_line
			(start 0.674878 1.100074)
			(end -0.674878 1.100074)
			(stroke
				(width 0.1)
				(type default)
			)
			(layer "F.Fab")
		)
		(fp_poly
			(pts
				(xy -2.2352 -0.298958) (xy -2.2352 -1.001014) (xy -1.533144 -0.649986)
			)
			(stroke
				(width 0)
				(type default)
			)
			(fill yes)
			(layer "F.Fab")
		)
		(pad "1" smd rect
			(at -0.94996 -0.649986 90)
			(size 0.4318 0.508)
			(layers "F.Cu" "F.Mask" "F.Paste")
			(net "GND")
		)
		(pad "2" smd rect
			(at -0.94996 0 90)
			(size 0.4318 0.508)
			(layers "F.Cu" "F.Mask" "F.Paste")
			(net "P12V_E1S_EN_0_R")
		)
		(pad "3" smd rect
			(at -0.94996 0.649986 90)
			(size 0.4318 0.508)
			(layers "F.Cu" "F.Mask" "F.Paste")
			(net "P12V_E1S_UV_0_R")
		)
		(pad "4" smd rect
			(at 0.94996 0.649986 90)
			(size 0.4318 0.508)
			(layers "F.Cu" "F.Mask" "F.Paste")
			(net "GND")
		)
		(pad "5" smd rect
			(at 0.94996 0 90)
			(size 0.4318 0.508)
			(layers "F.Cu" "F.Mask" "F.Paste")
			(net "P12V_E1S_0_EN_G")
		)
		(pad "6" smd rect
			(at 0.94996 -0.649986 90)
			(size 0.4318 0.508)
			(layers "F.Cu" "F.Mask" "F.Paste")
			(net "P12V_E1S_0_EN_G")
		)
	)
	(footprint ""
		(layer "F.Cu")
		(at 369.00231 -182.602378 90)
		(property "Reference" "PC480_2"
			(at 0 0 90)
			(layer "F.SilkS")
			(hide yes)
			(effects
				(font
					(size 1.27 1.27)
				)
			)
		)
		(property "Value" ""
			(at 0 0 90)
			(layer "F.Fab")
			(effects
				(font
					(size 1.27 1.27)
				)
			)
		)
		(duplicate_pad_numbers_are_jumpers no)
		(fp_line
			(start 0.7874 -0.4064)
			(end 0.7874 0.4064)
			(stroke
				(width 0.1524)
				(type default)
			)
			(layer "F.SilkS")
		)
		(fp_line
			(start -0.7874 -0.4064)
			(end 0.7874 -0.4064)
			(stroke
				(width 0.1524)
				(type default)
			)
			(layer "F.SilkS")
		)
		(fp_line
			(start 0.7874 0.4064)
			(end -0.7874 0.4064)
			(stroke
				(width 0.1524)
				(type default)
			)
			(layer "F.SilkS")
		)
		(fp_line
			(start -0.7874 0.4064)
			(end -0.7874 -0.4064)
			(stroke
				(width 0.1524)
				(type default)
			)
			(layer "F.SilkS")
		)
		(fp_line
			(start -0.12065 -0.305054)
			(end -0.12065 -0.2794)
			(stroke
				(width 0.1)
				(type default)
			)
			(layer "F.Fab")
		)
		(fp_line
			(start -0.67945 -0.305054)
			(end -0.12065 -0.305054)
			(stroke
				(width 0.1)
				(type default)
			)
			(layer "F.Fab")
		)
		(fp_line
			(start 0.67945 -0.3048)
			(end 0.67945 0.3048)
			(stroke
				(width 0.1)
				(type default)
			)
			(layer "F.Fab")
		)
		(fp_line
			(start 0.12065 -0.3048)
			(end 0.67945 -0.3048)
			(stroke
				(width 0.1)
				(type default)
			)
			(layer "F.Fab")
		)
		(fp_line
			(start 0.12065 -0.2794)
			(end 0.12065 -0.3048)
			(stroke
				(width 0.1)
				(type default)
			)
			(layer "F.Fab")
		)
		(fp_line
			(start -0.12065 -0.2794)
			(end 0.12065 -0.2794)
			(stroke
				(width 0.1)
				(type default)
			)
			(layer "F.Fab")
		)
		(fp_line
			(start 0.120396 0.2794)
			(end -0.12065 0.2794)
			(stroke
				(width 0.1)
				(type default)
			)
			(layer "F.Fab")
		)
		(fp_line
			(start -0.12065 0.2794)
			(end -0.12065 0.3048)
			(stroke
				(width 0.1)
				(type default)
			)
			(layer "F.Fab")
		)
		(fp_line
			(start 0.67945 0.3048)
			(end 0.120396 0.3048)
			(stroke
				(width 0.1)
				(type default)
			)
			(layer "F.Fab")
		)
		(fp_line
			(start 0.120396 0.3048)
			(end 0.120396 0.2794)
			(stroke
				(width 0.1)
				(type default)
			)
			(layer "F.Fab")
		)
		(fp_line
			(start -0.12065 0.3048)
			(end -0.67945 0.3048)
			(stroke
				(width 0.1)
				(type default)
			)
			(layer "F.Fab")
		)
		(fp_line
			(start -0.67945 0.3048)
			(end -0.67945 -0.305054)
			(stroke
				(width 0.1)
				(type default)
			)
			(layer "F.Fab")
		)
		(pad "1" smd circle
			(at -0.40005 0 90)
			(size 0 0)
			(layers "F.Cu" "F.Mask" "F.Paste")
			(net "SW_P12V_AUX_PVDDCR_CPU0_P0_FLT")
		)
		(pad "2" smd circle
			(at 0.40005 0 90)
			(size 0 0)
			(layers "F.Cu" "F.Mask" "F.Paste")
			(net "GND")
		)
	)
	(footprint ""
		(layer "F.Cu")
		(at 326.992488 -394.82268 90)
		(property "Reference" "C504"
			(at 0 0 90)
			(layer "F.SilkS")
			(hide yes)
			(effects
				(font
					(size 1.27 1.27)
				)
			)
		)
		(property "Value" ""
			(at 0 0 90)
			(layer "F.Fab")
			(effects
				(font
					(size 1.27 1.27)
				)
			)
		)
		(duplicate_pad_numbers_are_jumpers no)
		(fp_line
			(start 0.7874 -0.4064)
			(end 0.7874 0.4064)
			(stroke
				(width 0.1524)
				(type default)
			)
			(layer "F.SilkS")
		)
		(fp_line
			(start -0.7874 -0.4064)
			(end 0.7874 -0.4064)
			(stroke
				(width 0.1524)
				(type default)
			)
			(layer "F.SilkS")
		)
		(fp_line
			(start 0.7874 0.4064)
			(end -0.7874 0.4064)
			(stroke
				(width 0.1524)
				(type default)
			)
			(layer "F.SilkS")
		)
		(fp_line
			(start -0.7874 0.4064)
			(end -0.7874 -0.4064)
			(stroke
				(width 0.1524)
				(type default)
			)
			(layer "F.SilkS")
		)
		(fp_line
			(start -0.12065 -0.305054)
			(end -0.12065 -0.2794)
			(stroke
				(width 0.1)
				(type default)
			)
			(layer "F.Fab")
		)
		(fp_line
			(start -0.67945 -0.305054)
			(end -0.12065 -0.305054)
			(stroke
				(width 0.1)
				(type default)
			)
			(layer "F.Fab")
		)
		(fp_line
			(start 0.67945 -0.3048)
			(end 0.67945 0.3048)
			(stroke
				(width 0.1)
				(type default)
			)
			(layer "F.Fab")
		)
		(fp_line
			(start 0.12065 -0.3048)
			(end 0.67945 -0.3048)
			(stroke
				(width 0.1)
				(type default)
			)
			(layer "F.Fab")
		)
		(fp_line
			(start 0.12065 -0.2794)
			(end 0.12065 -0.3048)
			(stroke
				(width 0.1)
				(type default)
			)
			(layer "F.Fab")
		)
		(fp_line
			(start -0.12065 -0.2794)
			(end 0.12065 -0.2794)
			(stroke
				(width 0.1)
				(type default)
			)
			(layer "F.Fab")
		)
		(fp_line
			(start 0.120396 0.2794)
			(end -0.12065 0.2794)
			(stroke
				(width 0.1)
				(type default)
			)
			(layer "F.Fab")
		)
		(fp_line
			(start -0.12065 0.2794)
			(end -0.12065 0.3048)
			(stroke
				(width 0.1)
				(type default)
			)
			(layer "F.Fab")
		)
		(fp_line
			(start 0.67945 0.3048)
			(end 0.120396 0.3048)
			(stroke
				(width 0.1)
				(type default)
			)
			(layer "F.Fab")
		)
		(fp_line
			(start 0.120396 0.3048)
			(end 0.120396 0.2794)
			(stroke
				(width 0.1)
				(type default)
			)
			(layer "F.Fab")
		)
		(fp_line
			(start -0.12065 0.3048)
			(end -0.67945 0.3048)
			(stroke
				(width 0.1)
				(type default)
			)
			(layer "F.Fab")
		)
		(fp_line
			(start -0.67945 0.3048)
			(end -0.67945 -0.305054)
			(stroke
				(width 0.1)
				(type default)
			)
			(layer "F.Fab")
		)
		(pad "1" smd circle
			(at -0.40005 0 90)
			(size 0 0)
			(layers "F.Cu" "F.Mask" "F.Paste")
			(net "P1V8_CPU0_RT_1D")
		)
		(pad "2" smd circle
			(at 0.40005 0 90)
			(size 0 0)
			(layers "F.Cu" "F.Mask" "F.Paste")
			(net "GND")
		)
	)
	(footprint ""
		(layer "F.Cu")
		(at 89.89441 -54.69255)
		(property "Reference" "PC2149"
			(at 0 0 0)
			(layer "F.SilkS")
			(hide yes)
			(effects
				(font
					(size 1.27 1.27)
				)
			)
		)
		(property "Value" ""
			(at 0 0 0)
			(layer "F.Fab")
			(effects
				(font
					(size 1.27 1.27)
				)
			)
		)
		(duplicate_pad_numbers_are_jumpers no)
		(fp_line
			(start -0.7874 -0.4064)
			(end 0.7874 -0.4064)
			(stroke
				(width 0.1524)
				(type default)
			)
			(layer "F.SilkS")
		)
		(fp_line
			(start -0.7874 0.4064)
			(end -0.7874 -0.4064)
			(stroke
				(width 0.1524)
				(type default)
			)
			(layer "F.SilkS")
		)
		(fp_line
			(start 0.7874 -0.4064)
			(end 0.7874 0.4064)
			(stroke
				(width 0.1524)
				(type default)
			)
			(layer "F.SilkS")
		)
		(fp_line
			(start 0.7874 0.4064)
			(end -0.7874 0.4064)
			(stroke
				(width 0.1524)
				(type default)
			)
			(layer "F.SilkS")
		)
		(fp_line
			(start -0.67945 -0.305054)
			(end -0.12065 -0.305054)
			(stroke
				(width 0.1)
				(type default)
			)
			(layer "F.Fab")
		)
		(fp_line
			(start -0.67945 0.3048)
			(end -0.67945 -0.305054)
			(stroke
				(width 0.1)
				(type default)
			)
			(layer "F.Fab")
		)
		(fp_line
			(start -0.12065 -0.305054)
			(end -0.12065 -0.2794)
			(stroke
				(width 0.1)
				(type default)
			)
			(layer "F.Fab")
		)
		(fp_line
			(start -0.12065 -0.2794)
			(end 0.12065 -0.2794)
			(stroke
				(width 0.1)
				(type default)
			)
			(layer "F.Fab")
		)
		(fp_line
			(start -0.12065 0.2794)
			(end -0.12065 0.3048)
			(stroke
				(width 0.1)
				(type default)
			)
			(layer "F.Fab")
		)
		(fp_line
			(start -0.12065 0.3048)
			(end -0.67945 0.3048)
			(stroke
				(width 0.1)
				(type default)
			)
			(layer "F.Fab")
		)
		(fp_line
			(start 0.120396 0.2794)
			(end -0.12065 0.2794)
			(stroke
				(width 0.1)
				(type default)
			)
			(layer "F.Fab")
		)
		(fp_line
			(start 0.120396 0.3048)
			(end 0.120396 0.2794)
			(stroke
				(width 0.1)
				(type default)
			)
			(layer "F.Fab")
		)
		(fp_line
			(start 0.12065 -0.3048)
			(end 0.67945 -0.3048)
			(stroke
				(width 0.1)
				(type default)
			)
			(layer "F.Fab")
		)
		(fp_line
			(start 0.12065 -0.2794)
			(end 0.12065 -0.3048)
			(stroke
				(width 0.1)
				(type default)
			)
			(layer "F.Fab")
		)
		(fp_line
			(start 0.67945 -0.3048)
			(end 0.67945 0.3048)
			(stroke
				(width 0.1)
				(type default)
			)
			(layer "F.Fab")
		)
		(fp_line
			(start 0.67945 0.3048)
			(end 0.120396 0.3048)
			(stroke
				(width 0.1)
				(type default)
			)
			(layer "F.Fab")
		)
		(pad "1" smd circle
			(at -0.40005 0)
			(size 0 0)
			(layers "F.Cu" "F.Mask" "F.Paste")
			(net "P3V3_OCP_V3_2_R")
		)
		(pad "2" smd circle
			(at 0.40005 0)
			(size 0 0)
			(layers "F.Cu" "F.Mask" "F.Paste")
			(net "P3V3_OCP_GATE_2")
		)
	)
	(footprint ""
		(layer "F.Cu")
		(at 177.378106 -427.226984 180)
		(property "Reference" "R2696"
			(at 0 0 180)
			(layer "F.SilkS")
			(hide yes)
			(effects
				(font
					(size 1.27 1.27)
				)
			)
		)
		(property "Value" ""
			(at 0 0 180)
			(layer "F.Fab")
			(effects
				(font
					(size 1.27 1.27)
				)
			)
		)
		(duplicate_pad_numbers_are_jumpers no)
		(fp_line
			(start 0.7874 0.4064)
			(end -0.7874 0.4064)
			(stroke
				(width 0.1524)
				(type default)
			)
			(layer "F.SilkS")
		)
		(fp_line
			(start 0.7874 -0.4064)
			(end 0.7874 0.4064)
			(stroke
				(width 0.1524)
				(type default)
			)
			(layer "F.SilkS")
		)
		(fp_line
			(start -0.7874 0.4064)
			(end -0.7874 -0.4064)
			(stroke
				(width 0.1524)
				(type default)
			)
			(layer "F.SilkS")
		)
		(fp_line
			(start -0.7874 -0.4064)
			(end 0.7874 -0.4064)
			(stroke
				(width 0.1524)
				(type default)
			)
			(layer "F.SilkS")
		)
		(fp_line
			(start 0.67945 0.3048)
			(end 0.120396 0.3048)
			(stroke
				(width 0.1)
				(type default)
			)
			(layer "F.Fab")
		)
		(fp_line
			(start 0.67945 -0.3048)
			(end 0.67945 0.3048)
			(stroke
				(width 0.1)
				(type default)
			)
			(layer "F.Fab")
		)
		(fp_line
			(start 0.12065 -0.2794)
			(end 0.12065 -0.3048)
			(stroke
				(width 0.1)
				(type default)
			)
			(layer "F.Fab")
		)
		(fp_line
			(start 0.12065 -0.3048)
			(end 0.67945 -0.3048)
			(stroke
				(width 0.1)
				(type default)
			)
			(layer "F.Fab")
		)
		(fp_line
			(start 0.120396 0.3048)
			(end 0.120396 0.2794)
			(stroke
				(width 0.1)
				(type default)
			)
			(layer "F.Fab")
		)
		(fp_line
			(start 0.120396 0.2794)
			(end -0.12065 0.2794)
			(stroke
				(width 0.1)
				(type default)
			)
			(layer "F.Fab")
		)
		(fp_line
			(start -0.12065 0.3048)
			(end -0.67945 0.3048)
			(stroke
				(width 0.1)
				(type default)
			)
			(layer "F.Fab")
		)
		(fp_line
			(start -0.12065 0.2794)
			(end -0.12065 0.3048)
			(stroke
				(width 0.1)
				(type default)
			)
			(layer "F.Fab")
		)
		(fp_line
			(start -0.12065 -0.2794)
			(end 0.12065 -0.2794)
			(stroke
				(width 0.1)
				(type default)
			)
			(layer "F.Fab")
		)
		(fp_line
			(start -0.12065 -0.305054)
			(end -0.12065 -0.2794)
			(stroke
				(width 0.1)
				(type default)
			)
			(layer "F.Fab")
		)
		(fp_line
			(start -0.67945 0.3048)
			(end -0.67945 -0.305054)
			(stroke
				(width 0.1)
				(type default)
			)
			(layer "F.Fab")
		)
		(fp_line
			(start -0.67945 -0.305054)
			(end -0.12065 -0.305054)
			(stroke
				(width 0.1)
				(type default)
			)
			(layer "F.Fab")
		)
		(pad "1" smd circle
			(at -0.40005 0 180)
			(size 0 0)
			(layers "F.Cu" "F.Mask" "F.Paste")
			(net "TCA9539_0_ADD0")
		)
		(pad "2" smd circle
			(at 0.40005 0 180)
			(size 0 0)
			(layers "F.Cu" "F.Mask" "F.Paste")
			(net "GND")
		)
	)
	(footprint ""
		(layer "F.Cu")
		(at 95.433642 -35.279838)
		(property "Reference" "U219"
			(at -1.20904 2.445512 0)
			(unlocked yes)
			(layer "F.SilkS")
			(effects
				(font
					(size 0.7874 0.5842)
					(thickness 0.1524)
				)
				(justify left)
			)
		)
		(property "Value" ""
			(at 0 0 0)
			(layer "F.Fab")
			(effects
				(font
					(size 1.27 1.27)
				)
			)
		)
		(duplicate_pad_numbers_are_jumpers no)
		(fp_line
			(start -1.733296 -1.549908)
			(end -1.733296 1.549908)
			(stroke
				(width 0.1524)
				(type default)
			)
			(layer "F.SilkS")
		)
		(fp_line
			(start -1.733296 1.549908)
			(end 1.733296 1.549908)
			(stroke
				(width 0.1524)
				(type default)
			)
			(layer "F.SilkS")
		)
		(fp_line
			(start -0.660908 -1.549908)
			(end -1.733296 -1.549908)
			(stroke
				(width 0.1524)
				(type default)
			)
			(layer "F.SilkS")
		)
		(fp_line
			(start 0 -0.889)
			(end -0.660908 -1.549908)
			(stroke
				(width 0.1524)
				(type default)
			)
			(layer "F.SilkS")
		)
		(fp_line
			(start 0.660908 -1.549908)
			(end 0 -0.889)
			(stroke
				(width 0.1524)
				(type default)
			)
			(layer "F.SilkS")
		)
		(fp_line
			(start 1.733296 -1.549908)
			(end 0.660908 -1.549908)
			(stroke
				(width 0.1524)
				(type default)
			)
			(layer "F.SilkS")
		)
		(fp_line
			(start 1.733296 1.549908)
			(end 1.733296 -1.549908)
			(stroke
				(width 0.1524)
				(type default)
			)
			(layer "F.SilkS")
		)
		(fp_poly
			(pts
				(xy -2.4384 -0.69596) (xy -2.4384 -1.20396) (xy -1.9304 -0.94996)
			)
			(stroke
				(width 0)
				(type default)
			)
			(fill yes)
			(layer "F.SilkS")
		)
		(fp_line
			(start -0.849884 -1.549908)
			(end -0.849884 1.549908)
			(stroke
				(width 0.1)
				(type default)
			)
			(layer "F.Fab")
		)
		(fp_line
			(start -0.849884 1.549908)
			(end 0.849884 1.549908)
			(stroke
				(width 0.1)
				(type default)
			)
			(layer "F.Fab")
		)
		(fp_line
			(start 0.849884 -1.549908)
			(end -0.849884 -1.549908)
			(stroke
				(width 0.1)
				(type default)
			)
			(layer "F.Fab")
		)
		(fp_line
			(start 0.849884 1.549908)
			(end 0.849884 -1.549908)
			(stroke
				(width 0.1)
				(type default)
			)
			(layer "F.Fab")
		)
		(fp_poly
			(pts
				(xy -2.4384 -1.20396) (xy -2.4384 -0.69596) (xy -1.9304 -0.94996)
			)
			(stroke
				(width 0)
				(type default)
			)
			(fill yes)
			(layer "F.Fab")
		)
		(pad "1" smd rect
			(at -1.199896 -0.94996 270)
			(size 0.5588 0.8128)
			(layers "F.Cu" "F.Mask" "F.Paste")
			(net "NC_U219_NC1")
		)
		(pad "2" smd rect
			(at -1.199896 0 270)
			(size 0.5588 0.8128)
			(layers "F.Cu" "F.Mask" "F.Paste")
			(net "OCP_V3_2_WAKE_BUFF_R_N")
		)
		(pad "3" smd rect
			(at -1.199896 0.94996 270)
			(size 0.5588 0.8128)
			(layers "F.Cu" "F.Mask" "F.Paste")
			(net "GND")
		)
		(pad "4" smd rect
			(at 1.199896 0.94996 270)
			(size 0.5588 0.8128)
			(layers "F.Cu" "F.Mask" "F.Paste")
			(net "IRQ_LVC3_V3_2_WAKE_BUF_N")
		)
		(pad "5" smd rect
			(at 1.199896 -0.94996 270)
			(size 0.5588 0.8128)
			(layers "F.Cu" "F.Mask" "F.Paste")
			(net "P3V3_AUX")
		)
	)
	(footprint ""
		(layer "F.Cu")
		(at 288.325306 -349.381572 90)
		(property "Reference" "PC142"
			(at 0 0 90)
			(layer "F.SilkS")
			(hide yes)
			(effects
				(font
					(size 1.27 1.27)
				)
			)
		)
		(property "Value" ""
			(at 0 0 90)
			(layer "F.Fab")
			(effects
				(font
					(size 1.27 1.27)
				)
			)
		)
		(duplicate_pad_numbers_are_jumpers no)
		(fp_line
			(start 0.7874 -0.4064)
			(end 0.7874 0.4064)
			(stroke
				(width 0.1524)
				(type default)
			)
			(layer "F.SilkS")
		)
		(fp_line
			(start -0.7874 -0.4064)
			(end 0.7874 -0.4064)
			(stroke
				(width 0.1524)
				(type default)
			)
			(layer "F.SilkS")
		)
		(fp_line
			(start 0.7874 0.4064)
			(end 0.376428 0.4064)
			(stroke
				(width 0.1524)
				(type default)
			)
			(layer "F.SilkS")
		)
		(fp_line
			(start -0.258572 0.4064)
			(end -0.7874 0.4064)
			(stroke
				(width 0.1524)
				(type default)
			)
			(layer "F.SilkS")
		)
		(fp_line
			(start -0.7874 0.4064)
			(end -0.7874 -0.4064)
			(stroke
				(width 0.1524)
				(type default)
			)
			(layer "F.SilkS")
		)
		(fp_line
			(start -0.12065 -0.305054)
			(end -0.12065 -0.2794)
			(stroke
				(width 0.1)
				(type default)
			)
			(layer "F.Fab")
		)
		(fp_line
			(start -0.67945 -0.305054)
			(end -0.12065 -0.305054)
			(stroke
				(width 0.1)
				(type default)
			)
			(layer "F.Fab")
		)
		(fp_line
			(start 0.67945 -0.3048)
			(end 0.67945 0.3048)
			(stroke
				(width 0.1)
				(type default)
			)
			(layer "F.Fab")
		)
		(fp_line
			(start 0.12065 -0.3048)
			(end 0.67945 -0.3048)
			(stroke
				(width 0.1)
				(type default)
			)
			(layer "F.Fab")
		)
		(fp_line
			(start 0.12065 -0.2794)
			(end 0.12065 -0.3048)
			(stroke
				(width 0.1)
				(type default)
			)
			(layer "F.Fab")
		)
		(fp_line
			(start -0.12065 -0.2794)
			(end 0.12065 -0.2794)
			(stroke
				(width 0.1)
				(type default)
			)
			(layer "F.Fab")
		)
		(fp_line
			(start 0.120396 0.2794)
			(end -0.12065 0.2794)
			(stroke
				(width 0.1)
				(type default)
			)
			(layer "F.Fab")
		)
		(fp_line
			(start -0.12065 0.2794)
			(end -0.12065 0.3048)
			(stroke
				(width 0.1)
				(type default)
			)
			(layer "F.Fab")
		)
		(fp_line
			(start 0.67945 0.3048)
			(end 0.120396 0.3048)
			(stroke
				(width 0.1)
				(type default)
			)
			(layer "F.Fab")
		)
		(fp_line
			(start 0.120396 0.3048)
			(end 0.120396 0.2794)
			(stroke
				(width 0.1)
				(type default)
			)
			(layer "F.Fab")
		)
		(fp_line
			(start -0.12065 0.3048)
			(end -0.67945 0.3048)
			(stroke
				(width 0.1)
				(type default)
			)
			(layer "F.Fab")
		)
		(fp_line
			(start -0.67945 0.3048)
			(end -0.67945 -0.305054)
			(stroke
				(width 0.1)
				(type default)
			)
			(layer "F.Fab")
		)
		(pad "1" smd circle
			(at -0.40005 0 90)
			(size 0 0)
			(layers "F.Cu" "F.Mask" "F.Paste")
			(net "PVDDIO_P0_VCC2")
		)
		(pad "2" smd circle
			(at 0.40005 0 90)
			(size 0 0)
			(layers "F.Cu" "F.Mask" "F.Paste")
			(net "GND")
		)
	)
	(footprint ""
		(layer "F.Cu")
		(at 254.362966 -74.44105)
		(property "Reference" "U134"
			(at -1.4732 -1.768348 0)
			(unlocked yes)
			(layer "F.SilkS")
			(effects
				(font
					(size 0.7874 0.5842)
					(thickness 0.1524)
				)
				(justify left)
			)
		)
		(property "Value" ""
			(at 0 0 0)
			(layer "F.Fab")
			(effects
				(font
					(size 1.27 1.27)
				)
			)
		)
		(duplicate_pad_numbers_are_jumpers no)
		(fp_line
			(start -1.38176 -1.100074)
			(end -1.38176 1.100074)
			(stroke
				(width 0.1524)
				(type default)
			)
			(layer "F.SilkS")
		)
		(fp_line
			(start -1.38176 1.100074)
			(end 1.38176 1.100074)
			(stroke
				(width 0.1524)
				(type default)
			)
			(layer "F.SilkS")
		)
		(fp_line
			(start -0.592074 -1.100074)
			(end -1.38176 -1.100074)
			(stroke
				(width 0.1524)
				(type default)
			)
			(layer "F.SilkS")
		)
		(fp_line
			(start 0 -0.508)
			(end -0.592074 -1.100074)
			(stroke
				(width 0.1524)
				(type default)
			)
			(layer "F.SilkS")
		)
		(fp_line
			(start 0.592074 -1.100074)
			(end 0 -0.508)
			(stroke
				(width 0.1524)
				(type default)
			)
			(layer "F.SilkS")
		)
		(fp_line
			(start 1.38176 -1.100074)
			(end 0.592074 -1.100074)
			(stroke
				(width 0.1524)
				(type default)
			)
			(layer "F.SilkS")
		)
		(fp_line
			(start 1.38176 1.100074)
			(end 1.38176 -1.100074)
			(stroke
				(width 0.1524)
				(type default)
			)
			(layer "F.SilkS")
		)
		(fp_poly
			(pts
				(xy -2.041652 -1.321308) (xy -1.735328 -1.637792) (xy -1.572006 -1.172972)
			)
			(stroke
				(width 0)
				(type default)
			)
			(fill yes)
			(layer "F.SilkS")
		)
		(fp_line
			(start -0.674878 -1.100074)
			(end -0.674878 1.100074)
			(stroke
				(width 0.1)
				(type default)
			)
			(layer "F.Fab")
		)
		(fp_line
			(start -0.674878 1.100074)
			(end 0.674878 1.100074)
			(stroke
				(width 0.1)
				(type default)
			)
			(layer "F.Fab")
		)
		(fp_line
			(start 0.674878 -1.100074)
			(end -0.674878 -1.100074)
			(stroke
				(width 0.1)
				(type default)
			)
			(layer "F.Fab")
		)
		(fp_line
			(start 0.674878 1.100074)
			(end 0.674878 -1.100074)
			(stroke
				(width 0.1)
				(type default)
			)
			(layer "F.Fab")
		)
		(fp_poly
			(pts
				(xy -1.9431 -0.870204) (xy -1.50241 -0.649986) (xy -1.9431 -0.429768)
			)
			(stroke
				(width 0)
				(type default)
			)
			(fill yes)
			(layer "F.Fab")
		)
		(pad "1" smd rect
			(at -0.94996 -0.649986 270)
			(size 0.4318 0.6096)
			(layers "F.Cu" "F.Mask" "F.Paste")
			(net "RST_SMB_E1S_N")
		)
		(pad "2" smd rect
			(at -0.94996 0 270)
			(size 0.4318 0.6096)
			(layers "F.Cu" "F.Mask" "F.Paste")
			(net "GND")
		)
		(pad "3" smd rect
			(at -0.94996 0.649986 270)
			(size 0.4318 0.6096)
			(layers "F.Cu" "F.Mask" "F.Paste")
			(net "RST_SMB_E1S_N")
		)
		(pad "4" smd rect
			(at 0.94996 0.649986 270)
			(size 0.4318 0.6096)
			(layers "F.Cu" "F.Mask" "F.Paste")
			(net "SMB_PCIE_E1S_ISO_EN_R2")
		)
		(pad "5" smd rect
			(at 0.94996 0 270)
			(size 0.4318 0.6096)
			(layers "F.Cu" "F.Mask" "F.Paste")
			(net "P3V3_AUX")
		)
		(pad "6" smd rect
			(at 0.94996 -0.649986 270)
			(size 0.4318 0.6096)
			(layers "F.Cu" "F.Mask" "F.Paste")
			(net "RST_SMB_BUF_E1S_0_N")
		)
	)
	(footprint ""
		(layer "F.Cu")
		(at 376.89028 -32.323532 -90)
		(property "Reference" "C2344"
			(at 0 0 270)
			(layer "F.SilkS")
			(hide yes)
			(effects
				(font
					(size 1.27 1.27)
				)
			)
		)
		(property "Value" ""
			(at 0 0 270)
			(layer "F.Fab")
			(effects
				(font
					(size 1.27 1.27)
				)
			)
		)
		(duplicate_pad_numbers_are_jumpers no)
		(fp_line
			(start -0.7874 0.4064)
			(end -0.7874 -0.4064)
			(stroke
				(width 0.1524)
				(type default)
			)
			(layer "F.SilkS")
		)
		(fp_line
			(start 0.7874 0.4064)
			(end -0.7874 0.4064)
			(stroke
				(width 0.1524)
				(type default)
			)
			(layer "F.SilkS")
		)
		(fp_line
			(start -0.7874 -0.4064)
			(end 0.7874 -0.4064)
			(stroke
				(width 0.1524)
				(type default)
			)
			(layer "F.SilkS")
		)
		(fp_line
			(start 0.7874 -0.4064)
			(end 0.7874 0.4064)
			(stroke
				(width 0.1524)
				(type default)
			)
			(layer "F.SilkS")
		)
		(fp_line
			(start -0.67945 0.3048)
			(end -0.67945 -0.305054)
			(stroke
				(width 0.1)
				(type default)
			)
			(layer "F.Fab")
		)
		(fp_line
			(start -0.12065 0.3048)
			(end -0.67945 0.3048)
			(stroke
				(width 0.1)
				(type default)
			)
			(layer "F.Fab")
		)
		(fp_line
			(start 0.120396 0.3048)
			(end 0.120396 0.2794)
			(stroke
				(width 0.1)
				(type default)
			)
			(layer "F.Fab")
		)
		(fp_line
			(start 0.67945 0.3048)
			(end 0.120396 0.3048)
			(stroke
				(width 0.1)
				(type default)
			)
			(layer "F.Fab")
		)
		(fp_line
			(start -0.12065 0.2794)
			(end -0.12065 0.3048)
			(stroke
				(width 0.1)
				(type default)
			)
			(layer "F.Fab")
		)
		(fp_line
			(start 0.120396 0.2794)
			(end -0.12065 0.2794)
			(stroke
				(width 0.1)
				(type default)
			)
			(layer "F.Fab")
		)
		(fp_line
			(start -0.12065 -0.2794)
			(end 0.12065 -0.2794)
			(stroke
				(width 0.1)
				(type default)
			)
			(layer "F.Fab")
		)
		(fp_line
			(start 0.12065 -0.2794)
			(end 0.12065 -0.3048)
			(stroke
				(width 0.1)
				(type default)
			)
			(layer "F.Fab")
		)
		(fp_line
			(start 0.12065 -0.3048)
			(end 0.67945 -0.3048)
			(stroke
				(width 0.1)
				(type default)
			)
			(layer "F.Fab")
		)
		(fp_line
			(start 0.67945 -0.3048)
			(end 0.67945 0.3048)
			(stroke
				(width 0.1)
				(type default)
			)
			(layer "F.Fab")
		)
		(fp_line
			(start -0.67945 -0.305054)
			(end -0.12065 -0.305054)
			(stroke
				(width 0.1)
				(type default)
			)
			(layer "F.Fab")
		)
		(fp_line
			(start -0.12065 -0.305054)
			(end -0.12065 -0.2794)
			(stroke
				(width 0.1)
				(type default)
			)
			(layer "F.Fab")
		)
		(pad "1" smd circle
			(at -0.40005 0 270)
			(size 0 0)
			(layers "F.Cu" "F.Mask" "F.Paste")
			(net "P3V3_AUX")
		)
		(pad "2" smd circle
			(at 0.40005 0 270)
			(size 0 0)
			(layers "F.Cu" "F.Mask" "F.Paste")
			(net "GND")
		)
	)
	(footprint ""
		(layer "F.Cu")
		(at 294.421052 -116.253514)
		(property "Reference" "R2566"
			(at 0 0 0)
			(layer "F.SilkS")
			(hide yes)
			(effects
				(font
					(size 1.27 1.27)
				)
			)
		)
		(property "Value" ""
			(at 0 0 0)
			(layer "F.Fab")
			(effects
				(font
					(size 1.27 1.27)
				)
			)
		)
		(duplicate_pad_numbers_are_jumpers no)
		(fp_line
			(start -0.7874 -0.4064)
			(end 0.7874 -0.4064)
			(stroke
				(width 0.1524)
				(type default)
			)
			(layer "F.SilkS")
		)
		(fp_line
			(start -0.7874 0.4064)
			(end -0.7874 -0.4064)
			(stroke
				(width 0.1524)
				(type default)
			)
			(layer "F.SilkS")
		)
		(fp_line
			(start 0.7874 -0.4064)
			(end 0.7874 0.4064)
			(stroke
				(width 0.1524)
				(type default)
			)
			(layer "F.SilkS")
		)
		(fp_line
			(start 0.7874 0.4064)
			(end -0.7874 0.4064)
			(stroke
				(width 0.1524)
				(type default)
			)
			(layer "F.SilkS")
		)
		(fp_line
			(start -0.67945 -0.305054)
			(end -0.12065 -0.305054)
			(stroke
				(width 0.1)
				(type default)
			)
			(layer "F.Fab")
		)
		(fp_line
			(start -0.67945 0.3048)
			(end -0.67945 -0.305054)
			(stroke
				(width 0.1)
				(type default)
			)
			(layer "F.Fab")
		)
		(fp_line
			(start -0.12065 -0.305054)
			(end -0.12065 -0.2794)
			(stroke
				(width 0.1)
				(type default)
			)
			(layer "F.Fab")
		)
		(fp_line
			(start -0.12065 -0.2794)
			(end 0.12065 -0.2794)
			(stroke
				(width 0.1)
				(type default)
			)
			(layer "F.Fab")
		)
		(fp_line
			(start -0.12065 0.2794)
			(end -0.12065 0.3048)
			(stroke
				(width 0.1)
				(type default)
			)
			(layer "F.Fab")
		)
		(fp_line
			(start -0.12065 0.3048)
			(end -0.67945 0.3048)
			(stroke
				(width 0.1)
				(type default)
			)
			(layer "F.Fab")
		)
		(fp_line
			(start 0.120396 0.2794)
			(end -0.12065 0.2794)
			(stroke
				(width 0.1)
				(type default)
			)
			(layer "F.Fab")
		)
		(fp_line
			(start 0.120396 0.3048)
			(end 0.120396 0.2794)
			(stroke
				(width 0.1)
				(type default)
			)
			(layer "F.Fab")
		)
		(fp_line
			(start 0.12065 -0.3048)
			(end 0.67945 -0.3048)
			(stroke
				(width 0.1)
				(type default)
			)
			(layer "F.Fab")
		)
		(fp_line
			(start 0.12065 -0.2794)
			(end 0.12065 -0.3048)
			(stroke
				(width 0.1)
				(type default)
			)
			(layer "F.Fab")
		)
		(fp_line
			(start 0.67945 -0.3048)
			(end 0.67945 0.3048)
			(stroke
				(width 0.1)
				(type default)
			)
			(layer "F.Fab")
		)
		(fp_line
			(start 0.67945 0.3048)
			(end 0.120396 0.3048)
			(stroke
				(width 0.1)
				(type default)
			)
			(layer "F.Fab")
		)
		(pad "1" smd circle
			(at -0.40005 0)
			(size 0 0)
			(layers "F.Cu" "F.Mask" "F.Paste")
			(net "SMB_FRU_3V3AUX_SDA_R")
		)
		(pad "2" smd circle
			(at 0.40005 0)
			(size 0 0)
			(layers "F.Cu" "F.Mask" "F.Paste")
			(net "SMB_FRU_3V3AUX_SDA")
		)
	)
	(footprint ""
		(layer "F.Cu")
		(at 181.991 -129.377948 -90)
		(property "Reference" "R57"
			(at 0 0 270)
			(layer "F.SilkS")
			(hide yes)
			(effects
				(font
					(size 1.27 1.27)
				)
			)
		)
		(property "Value" ""
			(at 0 0 270)
			(layer "F.Fab")
			(effects
				(font
					(size 1.27 1.27)
				)
			)
		)
		(duplicate_pad_numbers_are_jumpers no)
		(fp_line
			(start -0.7874 0.4064)
			(end -0.7874 -0.4064)
			(stroke
				(width 0.1524)
				(type default)
			)
			(layer "F.SilkS")
		)
		(fp_line
			(start 0.7874 0.4064)
			(end -0.7874 0.4064)
			(stroke
				(width 0.1524)
				(type default)
			)
			(layer "F.SilkS")
		)
		(fp_line
			(start -0.7874 -0.4064)
			(end 0.7874 -0.4064)
			(stroke
				(width 0.1524)
				(type default)
			)
			(layer "F.SilkS")
		)
		(fp_line
			(start 0.7874 -0.4064)
			(end 0.7874 0.4064)
			(stroke
				(width 0.1524)
				(type default)
			)
			(layer "F.SilkS")
		)
		(fp_line
			(start -0.67945 0.3048)
			(end -0.67945 -0.305054)
			(stroke
				(width 0.1)
				(type default)
			)
			(layer "F.Fab")
		)
		(fp_line
			(start -0.12065 0.3048)
			(end -0.67945 0.3048)
			(stroke
				(width 0.1)
				(type default)
			)
			(layer "F.Fab")
		)
		(fp_line
			(start 0.120396 0.3048)
			(end 0.120396 0.2794)
			(stroke
				(width 0.1)
				(type default)
			)
			(layer "F.Fab")
		)
		(fp_line
			(start 0.67945 0.3048)
			(end 0.120396 0.3048)
			(stroke
				(width 0.1)
				(type default)
			)
			(layer "F.Fab")
		)
		(fp_line
			(start -0.12065 0.2794)
			(end -0.12065 0.3048)
			(stroke
				(width 0.1)
				(type default)
			)
			(layer "F.Fab")
		)
		(fp_line
			(start 0.120396 0.2794)
			(end -0.12065 0.2794)
			(stroke
				(width 0.1)
				(type default)
			)
			(layer "F.Fab")
		)
		(fp_line
			(start -0.12065 -0.2794)
			(end 0.12065 -0.2794)
			(stroke
				(width 0.1)
				(type default)
			)
			(layer "F.Fab")
		)
		(fp_line
			(start 0.12065 -0.2794)
			(end 0.12065 -0.3048)
			(stroke
				(width 0.1)
				(type default)
			)
			(layer "F.Fab")
		)
		(fp_line
			(start 0.12065 -0.3048)
			(end 0.67945 -0.3048)
			(stroke
				(width 0.1)
				(type default)
			)
			(layer "F.Fab")
		)
		(fp_line
			(start 0.67945 -0.3048)
			(end 0.67945 0.3048)
			(stroke
				(width 0.1)
				(type default)
			)
			(layer "F.Fab")
		)
		(fp_line
			(start -0.67945 -0.305054)
			(end -0.12065 -0.305054)
			(stroke
				(width 0.1)
				(type default)
			)
			(layer "F.Fab")
		)
		(fp_line
			(start -0.12065 -0.305054)
			(end -0.12065 -0.2794)
			(stroke
				(width 0.1)
				(type default)
			)
			(layer "F.Fab")
		)
		(pad "1" smd circle
			(at -0.40005 0 270)
			(size 0 0)
			(layers "F.Cu" "F.Mask" "F.Paste")
			(net "RST_CPU1_RESETL_N")
		)
		(pad "2" smd circle
			(at 0.40005 0 270)
			(size 0 0)
			(layers "F.Cu" "F.Mask" "F.Paste")
			(net "FM_RST_CPU1_RESETL_N")
		)
	)
	(footprint ""
		(layer "F.Cu")
		(at 459.579726 -98.514408)
		(property "Reference" "U66"
			(at -4.11226 -1.882648 0)
			(unlocked yes)
			(layer "F.SilkS")
			(effects
				(font
					(size 0.7874 0.5842)
					(thickness 0.1524)
				)
				(justify left)
			)
		)
		(property "Value" ""
			(at 0 0 0)
			(layer "F.Fab")
			(effects
				(font
					(size 1.27 1.27)
				)
			)
		)
		(duplicate_pad_numbers_are_jumpers no)
		(fp_line
			(start -1.400048 1.100074)
			(end -1.400048 -1.100074)
			(stroke
				(width 0.1524)
				(type default)
			)
			(layer "F.SilkS")
		)
		(fp_line
			(start 1.400048 -1.100074)
			(end -1.400048 -1.100074)
			(stroke
				(width 0.1524)
				(type default)
			)
			(layer "F.SilkS")
		)
		(fp_line
			(start 1.400048 -1.100074)
			(end 1.400048 1.100074)
			(stroke
				(width 0.1524)
				(type default)
			)
			(layer "F.SilkS")
		)
		(fp_line
			(start 1.400048 1.100074)
			(end -1.400048 1.100074)
			(stroke
				(width 0.1524)
				(type default)
			)
			(layer "F.SilkS")
		)
		(fp_poly
			(pts
				(xy -1.559052 -2.258314) (xy -0.543052 -2.258314) (xy -1.051052 -1.242314)
			)
			(stroke
				(width 0)
				(type default)
			)
			(fill yes)
			(layer "F.SilkS")
		)
		(fp_line
			(start -0.674878 -1.100074)
			(end 0.674878 -1.100074)
			(stroke
				(width 0.1)
				(type default)
			)
			(layer "F.Fab")
		)
		(fp_line
			(start -0.674878 1.100074)
			(end -0.674878 -1.100074)
			(stroke
				(width 0.1)
				(type default)
			)
			(layer "F.Fab")
		)
		(fp_line
			(start 0.674878 -1.100074)
			(end 0.674878 1.100074)
			(stroke
				(width 0.1)
				(type default)
			)
			(layer "F.Fab")
		)
		(fp_line
			(start 0.674878 1.100074)
			(end -0.674878 1.100074)
			(stroke
				(width 0.1)
				(type default)
			)
			(layer "F.Fab")
		)
		(fp_poly
			(pts
				(xy -1.590548 -0.649986) (xy -2.606548 -1.157986) (xy -2.606548 -0.141986)
			)
			(stroke
				(width 0)
				(type default)
			)
			(fill yes)
			(layer "F.Fab")
		)
		(pad "1" smd rect
			(at -0.94996 -0.649986 270)
			(size 0.4318 0.6096)
			(layers "F.Cu" "F.Mask" "F.Paste")
			(net "OCP_SFF_AUX_PWR_EN_R1")
		)
		(pad "2" smd rect
			(at -0.94996 0 270)
			(size 0.4318 0.6096)
			(layers "F.Cu" "F.Mask" "F.Paste")
			(net "FM_OCP_SFF_PWR_GOOD")
		)
		(pad "3" smd rect
			(at -0.94996 0.649986 270)
			(size 0.4318 0.6096)
			(layers "F.Cu" "F.Mask" "F.Paste")
			(net "GND")
		)
		(pad "4" smd rect
			(at 0.94996 0.649986 270)
			(size 0.4318 0.6096)
			(layers "F.Cu" "F.Mask" "F.Paste")
			(net "FB_BMC_ISOLATE_R1")
		)
		(pad "5" smd rect
			(at 0.94996 -0.649986 270)
			(size 0.4318 0.6096)
			(layers "F.Cu" "F.Mask" "F.Paste")
			(net "P3V3_AUX")
		)
	)
	(footprint ""
		(layer "F.Cu")
		(at 249.713496 -48.094138)
		(property "Reference" "PC2217"
			(at 0 0 0)
			(layer "F.SilkS")
			(hide yes)
			(effects
				(font
					(size 1.27 1.27)
				)
			)
		)
		(property "Value" ""
			(at 0 0 0)
			(layer "F.Fab")
			(effects
				(font
					(size 1.27 1.27)
				)
			)
		)
		(duplicate_pad_numbers_are_jumpers no)
		(fp_line
			(start -0.7874 -0.4064)
			(end 0.7874 -0.4064)
			(stroke
				(width 0.1524)
				(type default)
			)
			(layer "F.SilkS")
		)
		(fp_line
			(start -0.7874 0.4064)
			(end -0.7874 -0.4064)
			(stroke
				(width 0.1524)
				(type default)
			)
			(layer "F.SilkS")
		)
		(fp_line
			(start 0.7874 -0.4064)
			(end 0.7874 0.4064)
			(stroke
				(width 0.1524)
				(type default)
			)
			(layer "F.SilkS")
		)
		(fp_line
			(start 0.7874 0.4064)
			(end -0.7874 0.4064)
			(stroke
				(width 0.1524)
				(type default)
			)
			(layer "F.SilkS")
		)
		(fp_line
			(start -0.67945 -0.305054)
			(end -0.12065 -0.305054)
			(stroke
				(width 0.1)
				(type default)
			)
			(layer "F.Fab")
		)
		(fp_line
			(start -0.67945 0.3048)
			(end -0.67945 -0.305054)
			(stroke
				(width 0.1)
				(type default)
			)
			(layer "F.Fab")
		)
		(fp_line
			(start -0.12065 -0.305054)
			(end -0.12065 -0.2794)
			(stroke
				(width 0.1)
				(type default)
			)
			(layer "F.Fab")
		)
		(fp_line
			(start -0.12065 -0.2794)
			(end 0.12065 -0.2794)
			(stroke
				(width 0.1)
				(type default)
			)
			(layer "F.Fab")
		)
		(fp_line
			(start -0.12065 0.2794)
			(end -0.12065 0.3048)
			(stroke
				(width 0.1)
				(type default)
			)
			(layer "F.Fab")
		)
		(fp_line
			(start -0.12065 0.3048)
			(end -0.67945 0.3048)
			(stroke
				(width 0.1)
				(type default)
			)
			(layer "F.Fab")
		)
		(fp_line
			(start 0.120396 0.2794)
			(end -0.12065 0.2794)
			(stroke
				(width 0.1)
				(type default)
			)
			(layer "F.Fab")
		)
		(fp_line
			(start 0.120396 0.3048)
			(end 0.120396 0.2794)
			(stroke
				(width 0.1)
				(type default)
			)
			(layer "F.Fab")
		)
		(fp_line
			(start 0.12065 -0.3048)
			(end 0.67945 -0.3048)
			(stroke
				(width 0.1)
				(type default)
			)
			(layer "F.Fab")
		)
		(fp_line
			(start 0.12065 -0.2794)
			(end 0.12065 -0.3048)
			(stroke
				(width 0.1)
				(type default)
			)
			(layer "F.Fab")
		)
		(fp_line
			(start 0.67945 -0.3048)
			(end 0.67945 0.3048)
			(stroke
				(width 0.1)
				(type default)
			)
			(layer "F.Fab")
		)
		(fp_line
			(start 0.67945 0.3048)
			(end 0.120396 0.3048)
			(stroke
				(width 0.1)
				(type default)
			)
			(layer "F.Fab")
		)
		(pad "1" smd circle
			(at -0.40005 0)
			(size 0 0)
			(layers "F.Cu" "F.Mask" "F.Paste")
			(net "P12V_E1S_0")
		)
		(pad "2" smd circle
			(at 0.40005 0)
			(size 0 0)
			(layers "F.Cu" "F.Mask" "F.Paste")
			(net "GND")
		)
	)
	(footprint ""
		(layer "F.Cu")
		(at 312.342022 -33.715706 180)
		(property "Reference" "R3864"
			(at 0 0 180)
			(layer "F.SilkS")
			(hide yes)
			(effects
				(font
					(size 1.27 1.27)
				)
			)
		)
		(property "Value" ""
			(at 0 0 180)
			(layer "F.Fab")
			(effects
				(font
					(size 1.27 1.27)
				)
			)
		)
		(duplicate_pad_numbers_are_jumpers no)
		(fp_line
			(start 0.7874 0.4064)
			(end -0.7874 0.4064)
			(stroke
				(width 0.1524)
				(type default)
			)
			(layer "F.SilkS")
		)
		(fp_line
			(start 0.7874 -0.4064)
			(end 0.7874 0.4064)
			(stroke
				(width 0.1524)
				(type default)
			)
			(layer "F.SilkS")
		)
		(fp_line
			(start -0.7874 0.4064)
			(end -0.7874 -0.4064)
			(stroke
				(width 0.1524)
				(type default)
			)
			(layer "F.SilkS")
		)
		(fp_line
			(start -0.7874 -0.4064)
			(end 0.7874 -0.4064)
			(stroke
				(width 0.1524)
				(type default)
			)
			(layer "F.SilkS")
		)
		(fp_line
			(start 0.67945 0.3048)
			(end 0.120396 0.3048)
			(stroke
				(width 0.1)
				(type default)
			)
			(layer "F.Fab")
		)
		(fp_line
			(start 0.67945 -0.3048)
			(end 0.67945 0.3048)
			(stroke
				(width 0.1)
				(type default)
			)
			(layer "F.Fab")
		)
		(fp_line
			(start 0.12065 -0.2794)
			(end 0.12065 -0.3048)
			(stroke
				(width 0.1)
				(type default)
			)
			(layer "F.Fab")
		)
		(fp_line
			(start 0.12065 -0.3048)
			(end 0.67945 -0.3048)
			(stroke
				(width 0.1)
				(type default)
			)
			(layer "F.Fab")
		)
		(fp_line
			(start 0.120396 0.3048)
			(end 0.120396 0.2794)
			(stroke
				(width 0.1)
				(type default)
			)
			(layer "F.Fab")
		)
		(fp_line
			(start 0.120396 0.2794)
			(end -0.12065 0.2794)
			(stroke
				(width 0.1)
				(type default)
			)
			(layer "F.Fab")
		)
		(fp_line
			(start -0.12065 0.3048)
			(end -0.67945 0.3048)
			(stroke
				(width 0.1)
				(type default)
			)
			(layer "F.Fab")
		)
		(fp_line
			(start -0.12065 0.2794)
			(end -0.12065 0.3048)
			(stroke
				(width 0.1)
				(type default)
			)
			(layer "F.Fab")
		)
		(fp_line
			(start -0.12065 -0.2794)
			(end 0.12065 -0.2794)
			(stroke
				(width 0.1)
				(type default)
			)
			(layer "F.Fab")
		)
		(fp_line
			(start -0.12065 -0.305054)
			(end -0.12065 -0.2794)
			(stroke
				(width 0.1)
				(type default)
			)
			(layer "F.Fab")
		)
		(fp_line
			(start -0.67945 0.3048)
			(end -0.67945 -0.305054)
			(stroke
				(width 0.1)
				(type default)
			)
			(layer "F.Fab")
		)
		(fp_line
			(start -0.67945 -0.305054)
			(end -0.12065 -0.305054)
			(stroke
				(width 0.1)
				(type default)
			)
			(layer "F.Fab")
		)
		(pad "1" smd rect
			(at -0.40005 0)
			(size 0.4572 0.508)
			(layers "F.Cu" "F.Mask" "F.Paste")
			(net "P12V_OCP_SFF_ISENSE_MPS_MAM")
		)
		(pad "2" smd rect
			(at 0.40005 0)
			(size 0.4572 0.508)
			(layers "F.Cu" "F.Mask" "F.Paste")
			(net "P12V_OCP_SFF_ISENSE_MAM")
		)
	)
	(footprint ""
		(layer "F.Cu")
		(at 35.132772 -433.112164 180)
		(property "Reference" "R3524"
			(at 0 0 180)
			(layer "F.SilkS")
			(hide yes)
			(effects
				(font
					(size 1.27 1.27)
				)
			)
		)
		(property "Value" ""
			(at 0 0 180)
			(layer "F.Fab")
			(effects
				(font
					(size 1.27 1.27)
				)
			)
		)
		(duplicate_pad_numbers_are_jumpers no)
		(fp_line
			(start 0.7874 0.4064)
			(end -0.7874 0.4064)
			(stroke
				(width 0.1524)
				(type default)
			)
			(layer "F.SilkS")
		)
		(fp_line
			(start 0.7874 -0.4064)
			(end 0.7874 0.4064)
			(stroke
				(width 0.1524)
				(type default)
			)
			(layer "F.SilkS")
		)
		(fp_line
			(start -0.7874 0.4064)
			(end -0.7874 -0.4064)
			(stroke
				(width 0.1524)
				(type default)
			)
			(layer "F.SilkS")
		)
		(fp_line
			(start -0.7874 -0.4064)
			(end 0.7874 -0.4064)
			(stroke
				(width 0.1524)
				(type default)
			)
			(layer "F.SilkS")
		)
		(fp_line
			(start 0.67945 0.3048)
			(end 0.120396 0.3048)
			(stroke
				(width 0.1)
				(type default)
			)
			(layer "F.Fab")
		)
		(fp_line
			(start 0.67945 -0.3048)
			(end 0.67945 0.3048)
			(stroke
				(width 0.1)
				(type default)
			)
			(layer "F.Fab")
		)
		(fp_line
			(start 0.12065 -0.2794)
			(end 0.12065 -0.3048)
			(stroke
				(width 0.1)
				(type default)
			)
			(layer "F.Fab")
		)
		(fp_line
			(start 0.12065 -0.3048)
			(end 0.67945 -0.3048)
			(stroke
				(width 0.1)
				(type default)
			)
			(layer "F.Fab")
		)
		(fp_line
			(start 0.120396 0.3048)
			(end 0.120396 0.2794)
			(stroke
				(width 0.1)
				(type default)
			)
			(layer "F.Fab")
		)
		(fp_line
			(start 0.120396 0.2794)
			(end -0.12065 0.2794)
			(stroke
				(width 0.1)
				(type default)
			)
			(layer "F.Fab")
		)
		(fp_line
			(start -0.12065 0.3048)
			(end -0.67945 0.3048)
			(stroke
				(width 0.1)
				(type default)
			)
			(layer "F.Fab")
		)
		(fp_line
			(start -0.12065 0.2794)
			(end -0.12065 0.3048)
			(stroke
				(width 0.1)
				(type default)
			)
			(layer "F.Fab")
		)
		(fp_line
			(start -0.12065 -0.2794)
			(end 0.12065 -0.2794)
			(stroke
				(width 0.1)
				(type default)
			)
			(layer "F.Fab")
		)
		(fp_line
			(start -0.12065 -0.305054)
			(end -0.12065 -0.2794)
			(stroke
				(width 0.1)
				(type default)
			)
			(layer "F.Fab")
		)
		(fp_line
			(start -0.67945 0.3048)
			(end -0.67945 -0.305054)
			(stroke
				(width 0.1)
				(type default)
			)
			(layer "F.Fab")
		)
		(fp_line
			(start -0.67945 -0.305054)
			(end -0.12065 -0.305054)
			(stroke
				(width 0.1)
				(type default)
			)
			(layer "F.Fab")
		)
		(pad "1" smd circle
			(at -0.40005 0 180)
			(size 0 0)
			(layers "F.Cu" "F.Mask" "F.Paste")
			(net "P3V3_AUX")
		)
		(pad "2" smd circle
			(at 0.40005 0 180)
			(size 0 0)
			(layers "F.Cu" "F.Mask" "F.Paste")
			(net "SMB_1_BMC_GPU_BUF_R_SDA")
		)
	)
	(footprint ""
		(layer "F.Cu")
		(at 19.400012 -358.30637 -90)
		(property "Reference" "C8356"
			(at 0 0 270)
			(layer "F.SilkS")
			(hide yes)
			(effects
				(font
					(size 1.27 1.27)
				)
			)
		)
		(property "Value" ""
			(at 0 0 270)
			(layer "F.Fab")
			(effects
				(font
					(size 1.27 1.27)
				)
			)
		)
		(duplicate_pad_numbers_are_jumpers no)
		(fp_line
			(start -0.7874 0.4064)
			(end -0.7874 -0.4064)
			(stroke
				(width 0.1524)
				(type default)
			)
			(layer "F.SilkS")
		)
		(fp_line
			(start 0.7874 0.4064)
			(end -0.7874 0.4064)
			(stroke
				(width 0.1524)
				(type default)
			)
			(layer "F.SilkS")
		)
		(fp_line
			(start -0.7874 -0.4064)
			(end 0.7874 -0.4064)
			(stroke
				(width 0.1524)
				(type default)
			)
			(layer "F.SilkS")
		)
		(fp_line
			(start 0.7874 -0.4064)
			(end 0.7874 0.4064)
			(stroke
				(width 0.1524)
				(type default)
			)
			(layer "F.SilkS")
		)
		(fp_line
			(start -0.67945 0.3048)
			(end -0.67945 -0.305054)
			(stroke
				(width 0.1)
				(type default)
			)
			(layer "F.Fab")
		)
		(fp_line
			(start -0.12065 0.3048)
			(end -0.67945 0.3048)
			(stroke
				(width 0.1)
				(type default)
			)
			(layer "F.Fab")
		)
		(fp_line
			(start 0.120396 0.3048)
			(end 0.120396 0.2794)
			(stroke
				(width 0.1)
				(type default)
			)
			(layer "F.Fab")
		)
		(fp_line
			(start 0.67945 0.3048)
			(end 0.120396 0.3048)
			(stroke
				(width 0.1)
				(type default)
			)
			(layer "F.Fab")
		)
		(fp_line
			(start -0.12065 0.2794)
			(end -0.12065 0.3048)
			(stroke
				(width 0.1)
				(type default)
			)
			(layer "F.Fab")
		)
		(fp_line
			(start 0.120396 0.2794)
			(end -0.12065 0.2794)
			(stroke
				(width 0.1)
				(type default)
			)
			(layer "F.Fab")
		)
		(fp_line
			(start -0.12065 -0.2794)
			(end 0.12065 -0.2794)
			(stroke
				(width 0.1)
				(type default)
			)
			(layer "F.Fab")
		)
		(fp_line
			(start 0.12065 -0.2794)
			(end 0.12065 -0.3048)
			(stroke
				(width 0.1)
				(type default)
			)
			(layer "F.Fab")
		)
		(fp_line
			(start 0.12065 -0.3048)
			(end 0.67945 -0.3048)
			(stroke
				(width 0.1)
				(type default)
			)
			(layer "F.Fab")
		)
		(fp_line
			(start 0.67945 -0.3048)
			(end 0.67945 0.3048)
			(stroke
				(width 0.1)
				(type default)
			)
			(layer "F.Fab")
		)
		(fp_line
			(start -0.67945 -0.305054)
			(end -0.12065 -0.305054)
			(stroke
				(width 0.1)
				(type default)
			)
			(layer "F.Fab")
		)
		(fp_line
			(start -0.12065 -0.305054)
			(end -0.12065 -0.2794)
			(stroke
				(width 0.1)
				(type default)
			)
			(layer "F.Fab")
		)
		(pad "1" smd circle
			(at -0.40005 0 270)
			(size 0 0)
			(layers "F.Cu" "F.Mask" "F.Paste")
			(net "PVDDIO_P1_EN_R")
		)
		(pad "2" smd circle
			(at 0.40005 0 270)
			(size 0 0)
			(layers "F.Cu" "F.Mask" "F.Paste")
			(net "GND")
		)
	)
	(footprint ""
		(layer "F.Cu")
		(at 132.213096 -370.57203 -90)
		(property "Reference" "C55"
			(at 0 0 270)
			(layer "F.SilkS")
			(hide yes)
			(effects
				(font
					(size 1.27 1.27)
				)
			)
		)
		(property "Value" ""
			(at 0 0 270)
			(layer "F.Fab")
			(effects
				(font
					(size 1.27 1.27)
				)
			)
		)
		(duplicate_pad_numbers_are_jumpers no)
		(fp_line
			(start -0.299974 0.150114)
			(end -0.299974 -0.150114)
			(stroke
				(width 0.1)
				(type default)
			)
			(layer "F.Fab")
		)
		(fp_line
			(start 0.299974 0.150114)
			(end -0.299974 0.150114)
			(stroke
				(width 0.1)
				(type default)
			)
			(layer "F.Fab")
		)
		(fp_line
			(start -0.299974 -0.150114)
			(end 0.299974 -0.150114)
			(stroke
				(width 0.1)
				(type default)
			)
			(layer "F.Fab")
		)
		(fp_line
			(start 0.299974 -0.150114)
			(end 0.299974 0.150114)
			(stroke
				(width 0.1)
				(type default)
			)
			(layer "F.Fab")
		)
		(pad "1" smd rect
			(at -0.2667 0 270)
			(size 0.3048 0.381)
			(layers "F.Cu" "F.Mask" "F.Paste")
			(net "P5E_CPU1_P3_TX_C_DP<12>")
		)
		(pad "2" smd rect
			(at 0.2667 0 270)
			(size 0.3048 0.381)
			(layers "F.Cu" "F.Mask" "F.Paste")
			(net "P5E_CPU1_P3_TX_DP<12>")
		)
	)
	(footprint ""
		(layer "F.Cu")
		(at 142.750032 -440.489848)
		(property "Reference" "J109"
			(at 17.580102 23.22576 0)
			(unlocked yes)
			(layer "F.SilkS")
			(effects
				(font
					(size 0.7874 0.5842)
					(thickness 0.1524)
				)
				(justify left)
			)
		)
		(property "Value" ""
			(at 0 0 0)
			(layer "F.Fab")
			(effects
				(font
					(size 1.27 1.27)
				)
			)
		)
		(duplicate_pad_numbers_are_jumpers no)
		(fp_line
			(start -4.249928 22.400006)
			(end -4.249928 -0.484124)
			(stroke
				(width 0.1524)
				(type default)
			)
			(layer "F.SilkS")
		)
		(fp_line
			(start -1.249934 -1.500124)
			(end 15.649956 -1.500124)
			(stroke
				(width 0.1524)
				(type default)
			)
			(layer "F.SilkS")
		)
		(fp_line
			(start -1.249934 16.563848)
			(end -1.249934 19.400012)
			(stroke
				(width 0.1524)
				(type default)
			)
			(layer "F.SilkS")
		)
		(fp_line
			(start -1.249934 19.400012)
			(end 15.649956 19.400012)
			(stroke
				(width 0.1524)
				(type default)
			)
			(layer "F.SilkS")
		)
		(fp_line
			(start 0.0254 -0.9144)
			(end 1.0414 -0.9144)
			(stroke
				(width 0.1524)
				(type default)
			)
			(layer "F.SilkS")
		)
		(fp_line
			(start 0.5334 -1.4224)
			(end 0.0254 -0.9144)
			(stroke
				(width 0.1524)
				(type default)
			)
			(layer "F.SilkS")
		)
		(fp_line
			(start 0.5334 -1.4224)
			(end 0.5334 -0.5588)
			(stroke
				(width 0.1524)
				(type default)
			)
			(layer "F.SilkS")
		)
		(fp_line
			(start 0.5334 -0.5588)
			(end 1.8034 -0.5588)
			(stroke
				(width 0.1524)
				(type default)
			)
			(layer "F.SilkS")
		)
		(fp_line
			(start 1.0414 -0.9144)
			(end 0.5334 -1.4224)
			(stroke
				(width 0.1524)
				(type default)
			)
			(layer "F.SilkS")
		)
		(fp_line
			(start 1.8034 -0.5588)
			(end 2.032 -0.7874)
			(stroke
				(width 0.1524)
				(type default)
			)
			(layer "F.SilkS")
		)
		(fp_line
			(start 15.649956 19.400012)
			(end 15.649956 -0.484124)
			(stroke
				(width 0.1524)
				(type default)
			)
			(layer "F.SilkS")
		)
		(fp_line
			(start 18.64995 -0.484124)
			(end 18.64995 22.400006)
			(stroke
				(width 0.1524)
				(type default)
			)
			(layer "F.SilkS")
		)
		(fp_line
			(start 18.64995 22.400006)
			(end -4.249928 22.400006)
			(stroke
				(width 0.1524)
				(type default)
			)
			(layer "F.SilkS")
		)
		(fp_poly
			(pts
				(xy -1.019048 0) (xy -2.035048 0.508) (xy -2.035048 -0.508)
			)
			(stroke
				(width 0)
				(type default)
			)
			(fill yes)
			(layer "F.SilkS")
		)
		(fp_line
			(start -4.249928 -11.999976)
			(end 18.64995 -11.999976)
			(stroke
				(width 0.1524)
				(type default)
			)
			(layer "B.SilkS")
		)
		(fp_line
			(start -4.249928 22.400006)
			(end -4.249928 -11.999976)
			(stroke
				(width 0.1524)
				(type default)
			)
			(layer "B.SilkS")
		)
		(fp_line
			(start 13.307568 22.400006)
			(end -4.249928 22.400006)
			(stroke
				(width 0.1524)
				(type default)
			)
			(layer "B.SilkS")
		)
		(fp_line
			(start 18.64995 -11.999976)
			(end 18.64995 4.956048)
			(stroke
				(width 0.1524)
				(type default)
			)
			(layer "B.SilkS")
		)
		(fp_line
			(start 18.64995 6.530848)
			(end 18.64995 8.791448)
			(stroke
				(width 0.1524)
				(type default)
			)
			(layer "B.SilkS")
		)
		(fp_line
			(start 18.64995 10.163048)
			(end 18.64995 20.754848)
			(stroke
				(width 0.1524)
				(type default)
			)
			(layer "B.SilkS")
		)
		(fp_line
			(start -4.249928 -11.999976)
			(end 18.64995 -11.999976)
			(stroke
				(width 0.1)
				(type default)
			)
			(layer "B.Fab")
		)
		(fp_line
			(start -4.249928 22.400006)
			(end -4.249928 -11.999976)
			(stroke
				(width 0.1)
				(type default)
			)
			(layer "B.Fab")
		)
		(fp_line
			(start 18.64995 -11.999976)
			(end 18.64995 22.400006)
			(stroke
				(width 0.1)
				(type default)
			)
			(layer "B.Fab")
		)
		(fp_line
			(start 18.64995 22.400006)
			(end -4.249928 22.400006)
			(stroke
				(width 0.1)
				(type default)
			)
			(layer "B.Fab")
		)
		(fp_line
			(start -1.249934 -8.999982)
			(end -1.249934 19.400012)
			(stroke
				(width 0.1)
				(type default)
			)
			(layer "F.Fab")
		)
		(fp_line
			(start -1.249934 19.400012)
			(end 15.649956 19.400012)
			(stroke
				(width 0.1)
				(type default)
			)
			(layer "F.Fab")
		)
		(fp_line
			(start 15.649956 -8.999982)
			(end -1.249934 -8.999982)
			(stroke
				(width 0.1)
				(type default)
			)
			(layer "F.Fab")
		)
		(fp_line
			(start 15.649956 19.400012)
			(end 15.649956 -8.999982)
			(stroke
				(width 0.1)
				(type default)
			)
			(layer "F.Fab")
		)
		(fp_poly
			(pts
				(xy -2.670048 -0.508) (xy -2.670048 0.508) (xy -1.654048 0)
			)
			(stroke
				(width 0)
				(type default)
			)
			(fill yes)
			(layer "F.Fab")
		)
		(fp_text user "1"
			(at 0.111252 19.8628 90)
			(unlocked yes)
			(layer "F.SilkS")
			(effects
				(font
					(size 0.7874 0.5842)
					(thickness 0.1524)
				)
			)
		)
		(fp_text user "2"
			(at 2.111248 19.8628 90)
			(unlocked yes)
			(layer "F.SilkS")
			(effects
				(font
					(size 0.7874 0.5842)
					(thickness 0.1524)
				)
			)
		)
		(fp_text user "EDGE OF DAUGHTER CARD"
			(at 2.2479 -0.899668 0)
			(unlocked yes)
			(layer "F.SilkS")
			(effects
				(font
					(size 0.635 0.4064)
					(thickness 0.1524)
				)
				(justify left)
			)
		)
		(fp_text user "PRESS-FIT"
			(at 3.57886 26.504646 0)
			(unlocked yes)
			(layer "F.SilkS")
			(effects
				(font
					(size 1.905 1.4224)
					(thickness 0.1524)
				)
				(justify left)
			)
		)
		(fp_text user "3"
			(at 4.111244 19.8628 90)
			(unlocked yes)
			(layer "F.SilkS")
			(effects
				(font
					(size 0.7874 0.5842)
					(thickness 0.1524)
				)
			)
		)
		(fp_text user "4"
			(at 6.11124 19.8628 90)
			(unlocked yes)
			(layer "F.SilkS")
			(effects
				(font
					(size 0.7874 0.5842)
					(thickness 0.1524)
				)
			)
		)
		(fp_text user "5"
			(at 8.111236 19.8628 90)
			(unlocked yes)
			(layer "F.SilkS")
			(effects
				(font
					(size 0.7874 0.5842)
					(thickness 0.1524)
				)
			)
		)
		(fp_text user "6"
			(at 10.111232 19.8628 90)
			(unlocked yes)
			(layer "F.SilkS")
			(effects
				(font
					(size 0.7874 0.5842)
					(thickness 0.1524)
				)
			)
		)
		(fp_text user "7"
			(at 12.111228 19.8628 90)
			(unlocked yes)
			(layer "F.SilkS")
			(effects
				(font
					(size 0.7874 0.5842)
					(thickness 0.1524)
				)
			)
		)
		(fp_text user "8"
			(at 14.111224 19.8628 90)
			(unlocked yes)
			(layer "F.SilkS")
			(effects
				(font
					(size 0.7874 0.5842)
					(thickness 0.1524)
				)
			)
		)
		(fp_text user "B"
			(at 16.524478 1.199896 90)
			(unlocked yes)
			(layer "F.SilkS")
			(effects
				(font
					(size 0.7874 0.5842)
					(thickness 0.1524)
				)
			)
		)
		(fp_text user "C"
			(at 16.524478 2.400046 90)
			(unlocked yes)
			(layer "F.SilkS")
			(effects
				(font
					(size 0.7874 0.5842)
					(thickness 0.1524)
				)
			)
		)
		(fp_text user "D"
			(at 16.524478 3.599942 90)
			(unlocked yes)
			(layer "F.SilkS")
			(effects
				(font
					(size 0.7874 0.5842)
					(thickness 0.1524)
				)
			)
		)
		(fp_text user "E"
			(at 16.524478 4.800092 90)
			(unlocked yes)
			(layer "F.SilkS")
			(effects
				(font
					(size 0.7874 0.5842)
					(thickness 0.1524)
				)
			)
		)
		(fp_text user "F"
			(at 16.524478 5.999988 90)
			(unlocked yes)
			(layer "F.SilkS")
			(effects
				(font
					(size 0.7874 0.5842)
					(thickness 0.1524)
				)
			)
		)
		(fp_text user "G"
			(at 16.524478 7.199884 90)
			(unlocked yes)
			(layer "F.SilkS")
			(effects
				(font
					(size 0.7874 0.5842)
					(thickness 0.1524)
				)
			)
		)
		(fp_text user "H"
			(at 16.524478 8.400034 90)
			(unlocked yes)
			(layer "F.SilkS")
			(effects
				(font
					(size 0.7874 0.5842)
					(thickness 0.1524)
				)
			)
		)
		(fp_text user "I"
			(at 16.524478 9.59993 90)
			(unlocked yes)
			(layer "F.SilkS")
			(effects
				(font
					(size 0.7874 0.5842)
					(thickness 0.1524)
				)
			)
		)
		(fp_text user "J"
			(at 16.524478 10.80008 90)
			(unlocked yes)
			(layer "F.SilkS")
			(effects
				(font
					(size 0.7874 0.5842)
					(thickness 0.1524)
				)
			)
		)
		(fp_text user "K"
			(at 16.524478 11.999976 90)
			(unlocked yes)
			(layer "F.SilkS")
			(effects
				(font
					(size 0.7874 0.5842)
					(thickness 0.1524)
				)
			)
		)
		(fp_text user "L"
			(at 16.524478 13.200126 90)
			(unlocked yes)
			(layer "F.SilkS")
			(effects
				(font
					(size 0.7874 0.5842)
					(thickness 0.1524)
				)
			)
		)
		(fp_text user "M"
			(at 16.524478 14.400022 90)
			(unlocked yes)
			(layer "F.SilkS")
			(effects
				(font
					(size 0.7874 0.5842)
					(thickness 0.1524)
				)
			)
		)
		(fp_text user "N"
			(at 16.524478 15.599918 90)
			(unlocked yes)
			(layer "F.SilkS")
			(effects
				(font
					(size 0.7874 0.5842)
					(thickness 0.1524)
				)
			)
		)
		(fp_text user "A"
			(at -1.199134 0 90)
			(unlocked yes)
			(layer "B.SilkS")
			(effects
				(font
					(size 0.7874 0.5842)
					(thickness 0.1524)
				)
				(justify mirror)
			)
		)
		(fp_text user "G"
			(at -1.173734 7.4168 90)
			(unlocked yes)
			(layer "B.SilkS")
			(effects
				(font
					(size 0.7874 0.5842)
					(thickness 0.1524)
				)
				(justify mirror)
			)
		)
		(fp_text user "H"
			(at -1.148334 8.636 90)
			(unlocked yes)
			(layer "B.SilkS")
			(effects
				(font
					(size 0.7874 0.5842)
					(thickness 0.1524)
				)
				(justify mirror)
			)
		)
		(fp_text user "B"
			(at -1.14681 1.326896 90)
			(unlocked yes)
			(layer "B.SilkS")
			(effects
				(font
					(size 0.7874 0.5842)
					(thickness 0.1524)
				)
				(justify mirror)
			)
		)
		(fp_text user "C"
			(at -1.14681 2.527046 90)
			(unlocked yes)
			(layer "B.SilkS")
			(effects
				(font
					(size 0.7874 0.5842)
					(thickness 0.1524)
				)
				(justify mirror)
			)
		)
		(fp_text user "D"
			(at -1.14681 3.726942 90)
			(unlocked yes)
			(layer "B.SilkS")
			(effects
				(font
					(size 0.7874 0.5842)
					(thickness 0.1524)
				)
				(justify mirror)
			)
		)
		(fp_text user "E"
			(at -1.14681 4.927092 90)
			(unlocked yes)
			(layer "B.SilkS")
			(effects
				(font
					(size 0.7874 0.5842)
					(thickness 0.1524)
				)
				(justify mirror)
			)
		)
		(fp_text user "F"
			(at -1.14681 6.126988 90)
			(unlocked yes)
			(layer "B.SilkS")
			(effects
				(font
					(size 0.7874 0.5842)
					(thickness 0.1524)
				)
				(justify mirror)
			)
		)
		(fp_text user "I"
			(at -1.14681 9.72693 90)
			(unlocked yes)
			(layer "B.SilkS")
			(effects
				(font
					(size 0.7874 0.5842)
					(thickness 0.1524)
				)
				(justify mirror)
			)
		)
		(fp_text user "J"
			(at -1.14681 10.92708 90)
			(unlocked yes)
			(layer "B.SilkS")
			(effects
				(font
					(size 0.7874 0.5842)
					(thickness 0.1524)
				)
				(justify mirror)
			)
		)
		(fp_text user "K"
			(at -1.14681 12.126976 90)
			(unlocked yes)
			(layer "B.SilkS")
			(effects
				(font
					(size 0.7874 0.5842)
					(thickness 0.1524)
				)
				(justify mirror)
			)
		)
		(fp_text user "L"
			(at -1.14681 13.327126 90)
			(unlocked yes)
			(layer "B.SilkS")
			(effects
				(font
					(size 0.7874 0.5842)
					(thickness 0.1524)
				)
				(justify mirror)
			)
		)
		(fp_text user "M"
			(at -1.14681 14.527022 90)
			(unlocked yes)
			(layer "B.SilkS")
			(effects
				(font
					(size 0.7874 0.5842)
					(thickness 0.1524)
				)
				(justify mirror)
			)
		)
		(fp_text user "N"
			(at -1.14681 15.726918 90)
			(unlocked yes)
			(layer "B.SilkS")
			(effects
				(font
					(size 0.7874 0.5842)
					(thickness 0.1524)
				)
				(justify mirror)
			)
		)
		(fp_text user "1"
			(at 0.060452 16.764 90)
			(unlocked yes)
			(layer "B.SilkS")
			(effects
				(font
					(size 0.7874 0.5842)
					(thickness 0.1524)
				)
				(justify mirror)
			)
		)
		(fp_text user "2"
			(at 2.060448 16.764 90)
			(unlocked yes)
			(layer "B.SilkS")
			(effects
				(font
					(size 0.7874 0.5842)
					(thickness 0.1524)
				)
				(justify mirror)
			)
		)
		(fp_text user "3"
			(at 4.060444 16.764 90)
			(unlocked yes)
			(layer "B.SilkS")
			(effects
				(font
					(size 0.7874 0.5842)
					(thickness 0.1524)
				)
				(justify mirror)
			)
		)
		(fp_text user "4"
			(at 6.06044 16.764 90)
			(unlocked yes)
			(layer "B.SilkS")
			(effects
				(font
					(size 0.7874 0.5842)
					(thickness 0.1524)
				)
				(justify mirror)
			)
		)
		(fp_text user "5"
			(at 8.060436 16.764 90)
			(unlocked yes)
			(layer "B.SilkS")
			(effects
				(font
					(size 0.7874 0.5842)
					(thickness 0.1524)
				)
				(justify mirror)
			)
		)
		(fp_text user "6"
			(at 10.060432 16.764 90)
			(unlocked yes)
			(layer "B.SilkS")
			(effects
				(font
					(size 0.7874 0.5842)
					(thickness 0.1524)
				)
				(justify mirror)
			)
		)
		(fp_text user "7"
			(at 12.060428 16.764 90)
			(unlocked yes)
			(layer "B.SilkS")
			(effects
				(font
					(size 0.7874 0.5842)
					(thickness 0.1524)
				)
				(justify mirror)
			)
		)
		(fp_text user "8"
			(at 14.060424 16.764 90)
			(unlocked yes)
			(layer "B.SilkS")
			(effects
				(font
					(size 0.7874 0.5842)
					(thickness 0.1524)
				)
				(justify mirror)
			)
		)
		(fp_text user "PRESS-FIT"
			(at 17.23771 -0.0762 90)
			(unlocked yes)
			(layer "B.SilkS")
			(effects
				(font
					(size 1.905 1.4224)
					(thickness 0.1524)
				)
				(justify left mirror)
			)
		)
		(fp_text user "A"
			(at -1.199134 0 90)
			(unlocked yes)
			(layer "B.Fab")
			(effects
				(font
					(size 0.7874 0.5842)
					(thickness 0.1524)
				)
				(justify mirror)
			)
		)
		(fp_text user "G"
			(at -1.173734 7.4168 90)
			(unlocked yes)
			(layer "B.Fab")
			(effects
				(font
					(size 0.7874 0.5842)
					(thickness 0.1524)
				)
				(justify mirror)
			)
		)
		(fp_text user "H"
			(at -1.148334 8.636 90)
			(unlocked yes)
			(layer "B.Fab")
			(effects
				(font
					(size 0.7874 0.5842)
					(thickness 0.1524)
				)
				(justify mirror)
			)
		)
		(fp_text user "B"
			(at -1.14681 1.326896 90)
			(unlocked yes)
			(layer "B.Fab")
			(effects
				(font
					(size 0.7874 0.5842)
					(thickness 0.1524)
				)
				(justify mirror)
			)
		)
		(fp_text user "C"
			(at -1.14681 2.527046 90)
			(unlocked yes)
			(layer "B.Fab")
			(effects
				(font
					(size 0.7874 0.5842)
					(thickness 0.1524)
				)
				(justify mirror)
			)
		)
		(fp_text user "D"
			(at -1.14681 3.726942 90)
			(unlocked yes)
			(layer "B.Fab")
			(effects
				(font
					(size 0.7874 0.5842)
					(thickness 0.1524)
				)
				(justify mirror)
			)
		)
		(fp_text user "E"
			(at -1.14681 4.927092 90)
			(unlocked yes)
			(layer "B.Fab")
			(effects
				(font
					(size 0.7874 0.5842)
					(thickness 0.1524)
				)
				(justify mirror)
			)
		)
		(fp_text user "F"
			(at -1.14681 6.126988 90)
			(unlocked yes)
			(layer "B.Fab")
			(effects
				(font
					(size 0.7874 0.5842)
					(thickness 0.1524)
				)
				(justify mirror)
			)
		)
		(fp_text user "I"
			(at -1.14681 9.72693 90)
			(unlocked yes)
			(layer "B.Fab")
			(effects
				(font
					(size 0.7874 0.5842)
					(thickness 0.1524)
				)
				(justify mirror)
			)
		)
		(fp_text user "J"
			(at -1.14681 10.92708 90)
			(unlocked yes)
			(layer "B.Fab")
			(effects
				(font
					(size 0.7874 0.5842)
					(thickness 0.1524)
				)
				(justify mirror)
			)
		)
		(fp_text user "K"
			(at -1.14681 12.126976 90)
			(unlocked yes)
			(layer "B.Fab")
			(effects
				(font
					(size 0.7874 0.5842)
					(thickness 0.1524)
				)
				(justify mirror)
			)
		)
		(fp_text user "L"
			(at -1.14681 13.327126 90)
			(unlocked yes)
			(layer "B.Fab")
			(effects
				(font
					(size 0.7874 0.5842)
					(thickness 0.1524)
				)
				(justify mirror)
			)
		)
		(fp_text user "M"
			(at -1.14681 14.527022 90)
			(unlocked yes)
			(layer "B.Fab")
			(effects
				(font
					(size 0.7874 0.5842)
					(thickness 0.1524)
				)
				(justify mirror)
			)
		)
		(fp_text user "N"
			(at -1.14681 15.726918 90)
			(unlocked yes)
			(layer "B.Fab")
			(effects
				(font
					(size 0.7874 0.5842)
					(thickness 0.1524)
				)
				(justify mirror)
			)
		)
		(fp_text user "1"
			(at 0.060452 16.764 90)
			(unlocked yes)
			(layer "B.Fab")
			(effects
				(font
					(size 0.7874 0.5842)
					(thickness 0.1524)
				)
				(justify mirror)
			)
		)
		(fp_text user "2"
			(at 2.060448 16.764 90)
			(unlocked yes)
			(layer "B.Fab")
			(effects
				(font
					(size 0.7874 0.5842)
					(thickness 0.1524)
				)
				(justify mirror)
			)
		)
		(fp_text user "3"
			(at 4.060444 16.764 90)
			(unlocked yes)
			(layer "B.Fab")
			(effects
				(font
					(size 0.7874 0.5842)
					(thickness 0.1524)
				)
				(justify mirror)
			)
		)
		(fp_text user "4"
			(at 6.06044 16.764 90)
			(unlocked yes)
			(layer "B.Fab")
			(effects
				(font
					(size 0.7874 0.5842)
					(thickness 0.1524)
				)
				(justify mirror)
			)
		)
		(fp_text user "5"
			(at 8.060436 16.764 90)
			(unlocked yes)
			(layer "B.Fab")
			(effects
				(font
					(size 0.7874 0.5842)
					(thickness 0.1524)
				)
				(justify mirror)
			)
		)
		(fp_text user "6"
			(at 10.060432 16.764 90)
			(unlocked yes)
			(layer "B.Fab")
			(effects
				(font
					(size 0.7874 0.5842)
					(thickness 0.1524)
				)
				(justify mirror)
			)
		)
		(fp_text user "7"
			(at 12.060428 16.764 90)
			(unlocked yes)
			(layer "B.Fab")
			(effects
				(font
					(size 0.7874 0.5842)
					(thickness 0.1524)
				)
				(justify mirror)
			)
		)
		(fp_text user "8"
			(at 14.060424 16.764 90)
			(unlocked yes)
			(layer "B.Fab")
			(effects
				(font
					(size 0.7874 0.5842)
					(thickness 0.1524)
				)
				(justify mirror)
			)
		)
		(fp_text user "PRESS-FIT"
			(at 17.23771 -0.0762 90)
			(unlocked yes)
			(layer "B.Fab")
			(effects
				(font
					(size 1.905 1.4224)
					(thickness 0.1524)
				)
				(justify left mirror)
			)
		)
		(fp_text user "B"
			(at -2.253742 1.199896 90)
			(unlocked yes)
			(layer "F.Fab")
			(effects
				(font
					(size 0.7874 0.5842)
					(thickness 0.1524)
				)
			)
		)
		(fp_text user "C"
			(at -2.253742 2.400046 90)
			(unlocked yes)
			(layer "F.Fab")
			(effects
				(font
					(size 0.7874 0.5842)
					(thickness 0.1524)
				)
			)
		)
		(fp_text user "D"
			(at -2.253742 3.599942 90)
			(unlocked yes)
			(layer "F.Fab")
			(effects
				(font
					(size 0.7874 0.5842)
					(thickness 0.1524)
				)
			)
		)
		(fp_text user "E"
			(at -2.253742 4.800092 90)
			(unlocked yes)
			(layer "F.Fab")
			(effects
				(font
					(size 0.7874 0.5842)
					(thickness 0.1524)
				)
			)
		)
		(fp_text user "F"
			(at -2.253742 5.999988 90)
			(unlocked yes)
			(layer "F.Fab")
			(effects
				(font
					(size 0.7874 0.5842)
					(thickness 0.1524)
				)
			)
		)
		(fp_text user "G"
			(at -2.253742 7.199884 90)
			(unlocked yes)
			(layer "F.Fab")
			(effects
				(font
					(size 0.7874 0.5842)
					(thickness 0.1524)
				)
			)
		)
		(fp_text user "H"
			(at -2.253742 8.400034 90)
			(unlocked yes)
			(layer "F.Fab")
			(effects
				(font
					(size 0.7874 0.5842)
					(thickness 0.1524)
				)
			)
		)
		(fp_text user "I"
			(at -2.253742 9.59993 90)
			(unlocked yes)
			(layer "F.Fab")
			(effects
				(font
					(size 0.7874 0.5842)
					(thickness 0.1524)
				)
			)
		)
		(fp_text user "J"
			(at -2.253742 10.80008 90)
			(unlocked yes)
			(layer "F.Fab")
			(effects
				(font
					(size 0.7874 0.5842)
					(thickness 0.1524)
				)
			)
		)
		(fp_text user "K"
			(at -2.253742 11.999976 90)
			(unlocked yes)
			(layer "F.Fab")
			(effects
				(font
					(size 0.7874 0.5842)
					(thickness 0.1524)
				)
			)
		)
		(fp_text user "L"
			(at -2.253742 13.200126 90)
			(unlocked yes)
			(layer "F.Fab")
			(effects
				(font
					(size 0.7874 0.5842)
					(thickness 0.1524)
				)
			)
		)
		(fp_text user "M"
			(at -2.253742 14.400022 90)
			(unlocked yes)
			(layer "F.Fab")
			(effects
				(font
					(size 0.7874 0.5842)
					(thickness 0.1524)
				)
			)
		)
		(fp_text user "N"
			(at -2.253742 15.599918 90)
			(unlocked yes)
			(layer "F.Fab")
			(effects
				(font
					(size 0.7874 0.5842)
					(thickness 0.1524)
				)
			)
		)
		(fp_text user "1"
			(at 0.111252 19.8628 90)
			(unlocked yes)
			(layer "F.Fab")
			(effects
				(font
					(size 0.7874 0.5842)
					(thickness 0.1524)
				)
			)
		)
		(fp_text user "2"
			(at 2.111248 19.8628 90)
			(unlocked yes)
			(layer "F.Fab")
			(effects
				(font
					(size 0.7874 0.5842)
					(thickness 0.1524)
				)
			)
		)
		(fp_text user "3"
			(at 4.111244 19.8628 90)
			(unlocked yes)
			(layer "F.Fab")
			(effects
				(font
					(size 0.7874 0.5842)
					(thickness 0.1524)
				)
			)
		)
		(fp_text user "4"
			(at 6.11124 19.8628 90)
			(unlocked yes)
			(layer "F.Fab")
			(effects
				(font
					(size 0.7874 0.5842)
					(thickness 0.1524)
				)
			)
		)
		(fp_text user "5"
			(at 8.111236 19.8628 90)
			(unlocked yes)
			(layer "F.Fab")
			(effects
				(font
					(size 0.7874 0.5842)
					(thickness 0.1524)
				)
			)
		)
		(fp_text user "6"
			(at 10.111232 19.8628 90)
			(unlocked yes)
			(layer "F.Fab")
			(effects
				(font
					(size 0.7874 0.5842)
					(thickness 0.1524)
				)
			)
		)
		(fp_text user "7"
			(at 12.111228 19.8628 90)
			(unlocked yes)
			(layer "F.Fab")
			(effects
				(font
					(size 0.7874 0.5842)
					(thickness 0.1524)
				)
			)
		)
		(fp_text user "8"
			(at 14.111224 19.8628 90)
			(unlocked yes)
			(layer "F.Fab")
			(effects
				(font
					(size 0.7874 0.5842)
					(thickness 0.1524)
				)
			)
		)
		(fp_text user "PRESS-FIT"
			(at 17.240758 16.521684 90)
			(unlocked yes)
			(layer "F.Fab")
			(effects
				(font
					(size 1.905 1.4224)
					(thickness 0.1524)
				)
				(justify left)
			)
		)
		(pad "A1" thru_hole rect
			(at 0 0 180)
			(size 0.766318 0.766318)
			(drill 0.359918)
			(layers "*.Cu" "*.Mask")
			(remove_unused_layers no)
			(net "BMC_MONITER_BUF")
			(clearance 0.0508)
			(thermal_gap 0.0508)
			(padstack
				(mode front_inner_back)
				(layer "Inner"
					(shape circle)
					(size 0.766318 0.766318)
					(clearance 0.0508)
				)
				(layer "B.Cu"
					(shape rect)
					(size 0.766318 0.766318)
					(clearance 0.0508)
				)
			)
		)
		(pad "A2" thru_hole circle
			(at 1.999996 0.199898 180)
			(size 0.906272 0.906272)
			(drill 0.499872)
			(layers "*.Cu" "*.Mask")
			(remove_unused_layers no)
			(net "GND")
			(clearance 0.0508)
			(thermal_gap 0.0508)
		)
		(pad "A3" thru_hole circle
			(at 3.999992 0 180)
			(size 0.766318 0.766318)
			(drill 0.359918)
			(layers "*.Cu" "*.Mask")
			(remove_unused_layers no)
			(net "BIC_MONITER")
			(clearance 0.0508)
			(thermal_gap 0.0508)
		)
		(pad "A4" thru_hole circle
			(at 5.999988 0.199898 180)
			(size 0.906272 0.906272)
			(drill 0.499872)
			(layers "*.Cu" "*.Mask")
			(remove_unused_layers no)
			(net "GND")
			(clearance 0.0508)
			(thermal_gap 0.0508)
		)
		(pad "A5" thru_hole circle
			(at 7.999984 0 180)
			(size 0.766318 0.766318)
			(drill 0.359918)
			(layers "*.Cu" "*.Mask")
			(remove_unused_layers no)
			(net "SMB_BMC_SWB_BUF_SCL")
			(clearance 0.0508)
			(thermal_gap 0.0508)
		)
		(pad "A6" thru_hole circle
			(at 9.99998 0.199898 180)
			(size 0.906272 0.906272)
			(drill 0.499872)
			(layers "*.Cu" "*.Mask")
			(remove_unused_layers no)
			(net "GND")
			(clearance 0.0508)
			(thermal_gap 0.0508)
		)
		(pad "A7" thru_hole circle
			(at 11.999976 0 180)
			(size 0.766318 0.766318)
			(drill 0.359918)
			(layers "*.Cu" "*.Mask")
			(remove_unused_layers no)
			(net "SMB_BMC_SWB_BUF_SDA")
			(clearance 0.0508)
			(thermal_gap 0.0508)
		)
		(pad "A8" thru_hole circle
			(at 13.999972 0.199898 180)
			(size 0.906272 0.906272)
			(drill 0.499872)
			(layers "*.Cu" "*.Mask")
			(remove_unused_layers no)
			(net "GND")
			(clearance 0.0508)
			(thermal_gap 0.0508)
		)
		(pad "B1" thru_hole circle
			(at 0 1.199896 180)
			(size 0.906272 0.906272)
			(drill 0.499872)
			(layers "*.Cu" "*.Mask")
			(remove_unused_layers no)
			(net "GND")
			(clearance 0.0508)
			(thermal_gap 0.0508)
		)
		(pad "B3" thru_hole circle
			(at 3.999992 1.199896 180)
			(size 0.906272 0.906272)
			(drill 0.499872)
			(layers "*.Cu" "*.Mask")
			(remove_unused_layers no)
			(net "GND")
			(clearance 0.0508)
			(thermal_gap 0.0508)
		)
		(pad "B5" thru_hole circle
			(at 7.999984 1.199896 180)
			(size 0.906272 0.906272)
			(drill 0.499872)
			(layers "*.Cu" "*.Mask")
			(remove_unused_layers no)
			(net "GND")
			(clearance 0.0508)
			(thermal_gap 0.0508)
		)
		(pad "B7" thru_hole circle
			(at 11.999976 1.199896 180)
			(size 0.906272 0.906272)
			(drill 0.499872)
			(layers "*.Cu" "*.Mask")
			(remove_unused_layers no)
			(net "GND")
			(clearance 0.0508)
			(thermal_gap 0.0508)
		)
		(pad "D2" thru_hole circle
			(at 1.999996 3.800094 180)
			(size 0.906272 0.906272)
			(drill 0.499872)
			(layers "*.Cu" "*.Mask")
			(remove_unused_layers no)
			(net "GND")
			(clearance 0.0508)
			(thermal_gap 0.0508)
		)
		(pad "D4" thru_hole circle
			(at 5.999988 3.800094 180)
			(size 0.906272 0.906272)
			(drill 0.499872)
			(layers "*.Cu" "*.Mask")
			(remove_unused_layers no)
			(net "GND")
			(clearance 0.0508)
			(thermal_gap 0.0508)
		)
		(pad "D6" thru_hole circle
			(at 9.99998 3.800094 180)
			(size 0.906272 0.906272)
			(drill 0.499872)
			(layers "*.Cu" "*.Mask")
			(remove_unused_layers no)
			(net "GND")
			(clearance 0.0508)
			(thermal_gap 0.0508)
		)
		(pad "D8" thru_hole circle
			(at 13.999972 3.800094 180)
			(size 0.906272 0.906272)
			(drill 0.499872)
			(layers "*.Cu" "*.Mask")
			(remove_unused_layers no)
			(net "GND")
			(clearance 0.0508)
			(thermal_gap 0.0508)
		)
		(pad "E1" thru_hole circle
			(at 0 4.800092 180)
			(size 0.906272 0.906272)
			(drill 0.499872)
			(layers "*.Cu" "*.Mask")
			(remove_unused_layers no)
			(net "GND")
			(clearance 0.0508)
			(thermal_gap 0.0508)
		)
		(pad "E3" thru_hole circle
			(at 3.999992 4.800092 180)
			(size 0.906272 0.906272)
			(drill 0.499872)
			(layers "*.Cu" "*.Mask")
			(remove_unused_layers no)
			(net "GND")
			(clearance 0.0508)
			(thermal_gap 0.0508)
		)
		(pad "E5" thru_hole circle
			(at 7.999984 4.800092 180)
			(size 0.906272 0.906272)
			(drill 0.499872)
			(layers "*.Cu" "*.Mask")
			(remove_unused_layers no)
			(net "GND")
			(clearance 0.0508)
			(thermal_gap 0.0508)
		)
		(pad "E7" thru_hole circle
			(at 11.999976 4.800092 180)
			(size 0.906272 0.906272)
			(drill 0.499872)
			(layers "*.Cu" "*.Mask")
			(remove_unused_layers no)
			(net "GND")
			(clearance 0.0508)
			(thermal_gap 0.0508)
		)
		(pad "G2" thru_hole circle
			(at 1.999996 7.400036 180)
			(size 0.906272 0.906272)
			(drill 0.499872)
			(layers "*.Cu" "*.Mask")
			(remove_unused_layers no)
			(net "GND")
			(clearance 0.0508)
			(thermal_gap 0.0508)
		)
		(pad "G4" thru_hole circle
			(at 5.999988 7.400036 180)
			(size 0.906272 0.906272)
			(drill 0.499872)
			(layers "*.Cu" "*.Mask")
			(remove_unused_layers no)
			(net "GND")
			(clearance 0.0508)
			(thermal_gap 0.0508)
		)
		(pad "G6" thru_hole circle
			(at 9.99998 7.400036 180)
			(size 0.906272 0.906272)
			(drill 0.499872)
			(layers "*.Cu" "*.Mask")
			(remove_unused_layers no)
			(net "GND")
			(clearance 0.0508)
			(thermal_gap 0.0508)
		)
		(pad "G8" thru_hole circle
			(at 13.999972 7.400036 180)
			(size 0.906272 0.906272)
			(drill 0.499872)
			(layers "*.Cu" "*.Mask")
			(remove_unused_layers no)
			(net "GND")
			(clearance 0.0508)
			(thermal_gap 0.0508)
		)
		(pad "H1" thru_hole circle
			(at 0 8.400034 180)
			(size 0.906272 0.906272)
			(drill 0.499872)
			(layers "*.Cu" "*.Mask")
			(remove_unused_layers no)
			(net "GND")
			(clearance 0.0508)
			(thermal_gap 0.0508)
		)
		(pad "H3" thru_hole circle
			(at 3.999992 8.400034 180)
			(size 0.906272 0.906272)
			(drill 0.499872)
			(layers "*.Cu" "*.Mask")
			(remove_unused_layers no)
			(net "GND")
			(clearance 0.0508)
			(thermal_gap 0.0508)
		)
		(pad "H5" thru_hole circle
			(at 7.999984 8.400034 180)
			(size 0.906272 0.906272)
			(drill 0.499872)
			(layers "*.Cu" "*.Mask")
			(remove_unused_layers no)
			(net "GND")
			(clearance 0.0508)
			(thermal_gap 0.0508)
		)
		(pad "H7" thru_hole circle
			(at 11.999976 8.400034 180)
			(size 0.906272 0.906272)
			(drill 0.499872)
			(layers "*.Cu" "*.Mask")
			(remove_unused_layers no)
			(net "GND")
			(clearance 0.0508)
			(thermal_gap 0.0508)
		)
		(pad "J2" thru_hole circle
			(at 1.999996 10.999978 180)
			(size 0.906272 0.906272)
			(drill 0.499872)
			(layers "*.Cu" "*.Mask")
			(remove_unused_layers no)
			(net "GND")
			(clearance 0.0508)
			(thermal_gap 0.0508)
		)
		(pad "J4" thru_hole circle
			(at 5.999988 10.999978 180)
			(size 0.906272 0.906272)
			(drill 0.499872)
			(layers "*.Cu" "*.Mask")
			(remove_unused_layers no)
			(net "GND")
			(clearance 0.0508)
			(thermal_gap 0.0508)
		)
		(pad "J6" thru_hole circle
			(at 9.99998 10.999978 180)
			(size 0.906272 0.906272)
			(drill 0.499872)
			(layers "*.Cu" "*.Mask")
			(remove_unused_layers no)
			(net "GND")
			(clearance 0.0508)
			(thermal_gap 0.0508)
		)
		(pad "J8" thru_hole circle
			(at 13.999972 10.999978 180)
			(size 0.906272 0.906272)
			(drill 0.499872)
			(layers "*.Cu" "*.Mask")
			(remove_unused_layers no)
			(net "GND")
			(clearance 0.0508)
			(thermal_gap 0.0508)
		)
		(pad "K1" thru_hole circle
			(at 0 11.999976 180)
			(size 0.906272 0.906272)
			(drill 0.499872)
			(layers "*.Cu" "*.Mask")
			(remove_unused_layers no)
			(net "GND")
			(clearance 0.0508)
			(thermal_gap 0.0508)
		)
		(pad "K3" thru_hole circle
			(at 3.999992 11.999976 180)
			(size 0.906272 0.906272)
			(drill 0.499872)
			(layers "*.Cu" "*.Mask")
			(remove_unused_layers no)
			(net "GND")
			(clearance 0.0508)
			(thermal_gap 0.0508)
		)
		(pad "K5" thru_hole circle
			(at 7.999984 11.999976 180)
			(size 0.906272 0.906272)
			(drill 0.499872)
			(layers "*.Cu" "*.Mask")
			(remove_unused_layers no)
			(net "GND")
			(clearance 0.0508)
			(thermal_gap 0.0508)
		)
		(pad "K7" thru_hole circle
			(at 11.999976 11.999976 180)
			(size 0.906272 0.906272)
			(drill 0.499872)
			(layers "*.Cu" "*.Mask")
			(remove_unused_layers no)
			(net "GND")
			(clearance 0.0508)
			(thermal_gap 0.0508)
		)
		(pad "M2" thru_hole circle
			(at 1.999996 14.59992 180)
			(size 0.906272 0.906272)
			(drill 0.499872)
			(layers "*.Cu" "*.Mask")
			(remove_unused_layers no)
			(net "GND")
			(clearance 0.0508)
			(thermal_gap 0.0508)
		)
		(pad "M4" thru_hole circle
			(at 5.999988 14.59992 180)
			(size 0.906272 0.906272)
			(drill 0.499872)
			(layers "*.Cu" "*.Mask")
			(remove_unused_layers no)
			(net "GND")
			(clearance 0.0508)
			(thermal_gap 0.0508)
		)
		(pad "M6" thru_hole circle
			(at 9.99998 14.59992 180)
			(size 0.906272 0.906272)
			(drill 0.499872)
			(layers "*.Cu" "*.Mask")
			(remove_unused_layers no)
			(net "GND")
			(clearance 0.0508)
			(thermal_gap 0.0508)
		)
		(pad "M8" thru_hole circle
			(at 13.999972 14.59992 180)
			(size 0.906272 0.906272)
			(drill 0.499872)
			(layers "*.Cu" "*.Mask")
			(remove_unused_layers no)
			(net "GND")
			(clearance 0.0508)
			(thermal_gap 0.0508)
		)
		(pad "N1" thru_hole circle
			(at 0 15.599918 180)
			(size 0.906272 0.906272)
			(drill 0.499872)
			(layers "*.Cu" "*.Mask")
			(remove_unused_layers no)
			(net "GND")
			(clearance 0.0508)
			(thermal_gap 0.0508)
		)
		(pad "N2" thru_hole circle
			(at 1.999996 15.80007 180)
			(size 0.766318 0.766318)
			(drill 0.359918)
			(layers "*.Cu" "*.Mask")
			(remove_unused_layers no)
			(net "GPU_FPGA_EROT_FATALERR_N")
			(clearance 0.0508)
			(thermal_gap 0.0508)
		)
		(pad "N3" thru_hole circle
			(at 3.999992 15.599918 180)
			(size 0.906272 0.906272)
			(drill 0.499872)
			(layers "*.Cu" "*.Mask")
			(remove_unused_layers no)
			(net "GND")
			(clearance 0.0508)
			(thermal_gap 0.0508)
		)
		(pad "N4" thru_hole circle
			(at 5.999988 15.80007 180)
			(size 0.766318 0.766318)
			(drill 0.359918)
			(layers "*.Cu" "*.Mask")
			(remove_unused_layers no)
			(net "GPU_3V3IO_RSVD0_FFU")
			(clearance 0.0508)
			(thermal_gap 0.0508)
		)
		(pad "N5" thru_hole circle
			(at 7.999984 15.599918 180)
			(size 0.906272 0.906272)
			(drill 0.499872)
			(layers "*.Cu" "*.Mask")
			(remove_unused_layers no)
			(net "GND")
			(clearance 0.0508)
			(thermal_gap 0.0508)
		)
		(pad "N6" thru_hole circle
			(at 9.99998 15.80007 180)
			(size 0.766318 0.766318)
			(drill 0.359918)
			(layers "*.Cu" "*.Mask")
			(remove_unused_layers no)
			(net "GPU_3V3IO_RSVD1_FFU")
			(clearance 0.0508)
			(thermal_gap 0.0508)
		)
		(pad "N7" thru_hole circle
			(at 11.999976 15.599918 180)
			(size 0.906272 0.906272)
			(drill 0.499872)
			(layers "*.Cu" "*.Mask")
			(remove_unused_layers no)
			(net "GND")
			(clearance 0.0508)
			(thermal_gap 0.0508)
		)
		(pad "N8" thru_hole circle
			(at 13.999972 15.80007 180)
			(size 0.766318 0.766318)
			(drill 0.359918)
			(layers "*.Cu" "*.Mask")
			(remove_unused_layers no)
			(net "PRSNT_CABLE_GPU_B3_N")
			(clearance 0.0508)
			(thermal_gap 0.0508)
		)
		(zone
			(layer "B.Cu")
			(hatch none 0.5)
			(connect_pads
				(clearance 0)
			)
			(min_thickness 0.25)
			(keepout
				(tracks allowed)
				(vias not_allowed)
				(pads allowed)
				(copperpour not_allowed)
				(footprints allowed)
			)
			(placement
				(enabled no)
				(sheetname "")
			)
			(fill
				(thermal_gap 0.5)
				(thermal_bridge_width 0.5)
				(island_removal_mode 0)
			)
			(polygon
				(pts
					(xy 142.242032 -424.246548) (xy 157.266132 -424.246548) (xy 157.266132 -440.934348) (xy 142.242032 -440.934348)
				)
			)
		)
	)
	(footprint ""
		(layer "F.Cu")
		(at 271.085056 -121.83237)
		(property "Reference" "R3704"
			(at 0 0 0)
			(layer "F.SilkS")
			(hide yes)
			(effects
				(font
					(size 1.27 1.27)
				)
			)
		)
		(property "Value" ""
			(at 0 0 0)
			(layer "F.Fab")
			(effects
				(font
					(size 1.27 1.27)
				)
			)
		)
		(duplicate_pad_numbers_are_jumpers no)
		(fp_line
			(start -0.7874 -0.4064)
			(end 0.7874 -0.4064)
			(stroke
				(width 0.1524)
				(type default)
			)
			(layer "F.SilkS")
		)
		(fp_line
			(start -0.7874 0.4064)
			(end -0.7874 -0.4064)
			(stroke
				(width 0.1524)
				(type default)
			)
			(layer "F.SilkS")
		)
		(fp_line
			(start 0.7874 -0.4064)
			(end 0.7874 0.4064)
			(stroke
				(width 0.1524)
				(type default)
			)
			(layer "F.SilkS")
		)
		(fp_line
			(start 0.7874 0.4064)
			(end -0.7874 0.4064)
			(stroke
				(width 0.1524)
				(type default)
			)
			(layer "F.SilkS")
		)
		(fp_line
			(start -0.67945 -0.305054)
			(end -0.12065 -0.305054)
			(stroke
				(width 0.1)
				(type default)
			)
			(layer "F.Fab")
		)
		(fp_line
			(start -0.67945 0.3048)
			(end -0.67945 -0.305054)
			(stroke
				(width 0.1)
				(type default)
			)
			(layer "F.Fab")
		)
		(fp_line
			(start -0.12065 -0.305054)
			(end -0.12065 -0.2794)
			(stroke
				(width 0.1)
				(type default)
			)
			(layer "F.Fab")
		)
		(fp_line
			(start -0.12065 -0.2794)
			(end 0.12065 -0.2794)
			(stroke
				(width 0.1)
				(type default)
			)
			(layer "F.Fab")
		)
		(fp_line
			(start -0.12065 0.2794)
			(end -0.12065 0.3048)
			(stroke
				(width 0.1)
				(type default)
			)
			(layer "F.Fab")
		)
		(fp_line
			(start -0.12065 0.3048)
			(end -0.67945 0.3048)
			(stroke
				(width 0.1)
				(type default)
			)
			(layer "F.Fab")
		)
		(fp_line
			(start 0.120396 0.2794)
			(end -0.12065 0.2794)
			(stroke
				(width 0.1)
				(type default)
			)
			(layer "F.Fab")
		)
		(fp_line
			(start 0.120396 0.3048)
			(end 0.120396 0.2794)
			(stroke
				(width 0.1)
				(type default)
			)
			(layer "F.Fab")
		)
		(fp_line
			(start 0.12065 -0.3048)
			(end 0.67945 -0.3048)
			(stroke
				(width 0.1)
				(type default)
			)
			(layer "F.Fab")
		)
		(fp_line
			(start 0.12065 -0.2794)
			(end 0.12065 -0.3048)
			(stroke
				(width 0.1)
				(type default)
			)
			(layer "F.Fab")
		)
		(fp_line
			(start 0.67945 -0.3048)
			(end 0.67945 0.3048)
			(stroke
				(width 0.1)
				(type default)
			)
			(layer "F.Fab")
		)
		(fp_line
			(start 0.67945 0.3048)
			(end 0.120396 0.3048)
			(stroke
				(width 0.1)
				(type default)
			)
			(layer "F.Fab")
		)
		(pad "1" smd circle
			(at -0.40005 0)
			(size 0 0)
			(layers "F.Cu" "F.Mask" "F.Paste")
			(net "PCA9548_PCIE0_ADDR2")
		)
		(pad "2" smd circle
			(at 0.40005 0)
			(size 0 0)
			(layers "F.Cu" "F.Mask" "F.Paste")
			(net "GND")
		)
	)
	(footprint ""
		(layer "F.Cu")
		(at 442.419486 -22.673056 180)
		(property "Reference" "C1111"
			(at 0 0 180)
			(layer "F.SilkS")
			(hide yes)
			(effects
				(font
					(size 1.27 1.27)
				)
			)
		)
		(property "Value" ""
			(at 0 0 180)
			(layer "F.Fab")
			(effects
				(font
					(size 1.27 1.27)
				)
			)
		)
		(duplicate_pad_numbers_are_jumpers no)
		(fp_line
			(start 0.7874 0.4064)
			(end -0.7874 0.4064)
			(stroke
				(width 0.1524)
				(type default)
			)
			(layer "F.SilkS")
		)
		(fp_line
			(start 0.7874 -0.4064)
			(end 0.7874 0.4064)
			(stroke
				(width 0.1524)
				(type default)
			)
			(layer "F.SilkS")
		)
		(fp_line
			(start -0.7874 0.4064)
			(end -0.7874 -0.4064)
			(stroke
				(width 0.1524)
				(type default)
			)
			(layer "F.SilkS")
		)
		(fp_line
			(start -0.7874 -0.4064)
			(end 0.7874 -0.4064)
			(stroke
				(width 0.1524)
				(type default)
			)
			(layer "F.SilkS")
		)
		(fp_line
			(start 0.67945 0.3048)
			(end 0.120396 0.3048)
			(stroke
				(width 0.1)
				(type default)
			)
			(layer "F.Fab")
		)
		(fp_line
			(start 0.67945 -0.3048)
			(end 0.67945 0.3048)
			(stroke
				(width 0.1)
				(type default)
			)
			(layer "F.Fab")
		)
		(fp_line
			(start 0.12065 -0.2794)
			(end 0.12065 -0.3048)
			(stroke
				(width 0.1)
				(type default)
			)
			(layer "F.Fab")
		)
		(fp_line
			(start 0.12065 -0.3048)
			(end 0.67945 -0.3048)
			(stroke
				(width 0.1)
				(type default)
			)
			(layer "F.Fab")
		)
		(fp_line
			(start 0.120396 0.3048)
			(end 0.120396 0.2794)
			(stroke
				(width 0.1)
				(type default)
			)
			(layer "F.Fab")
		)
		(fp_line
			(start 0.120396 0.2794)
			(end -0.12065 0.2794)
			(stroke
				(width 0.1)
				(type default)
			)
			(layer "F.Fab")
		)
		(fp_line
			(start -0.12065 0.3048)
			(end -0.67945 0.3048)
			(stroke
				(width 0.1)
				(type default)
			)
			(layer "F.Fab")
		)
		(fp_line
			(start -0.12065 0.2794)
			(end -0.12065 0.3048)
			(stroke
				(width 0.1)
				(type default)
			)
			(layer "F.Fab")
		)
		(fp_line
			(start -0.12065 -0.2794)
			(end 0.12065 -0.2794)
			(stroke
				(width 0.1)
				(type default)
			)
			(layer "F.Fab")
		)
		(fp_line
			(start -0.12065 -0.305054)
			(end -0.12065 -0.2794)
			(stroke
				(width 0.1)
				(type default)
			)
			(layer "F.Fab")
		)
		(fp_line
			(start -0.67945 0.3048)
			(end -0.67945 -0.305054)
			(stroke
				(width 0.1)
				(type default)
			)
			(layer "F.Fab")
		)
		(fp_line
			(start -0.67945 -0.305054)
			(end -0.12065 -0.305054)
			(stroke
				(width 0.1)
				(type default)
			)
			(layer "F.Fab")
		)
		(pad "1" smd circle
			(at -0.40005 0 180)
			(size 0 0)
			(layers "F.Cu" "F.Mask" "F.Paste")
			(net "VSENSE_P12V_INA230_6_INP")
		)
		(pad "2" smd circle
			(at 0.40005 0 180)
			(size 0 0)
			(layers "F.Cu" "F.Mask" "F.Paste")
			(net "VSENSE_P12V_INA230_6_INN")
		)
	)
	(footprint ""
		(layer "F.Cu")
		(at 445.753744 -21.693378)
		(property "Reference" "PC2092"
			(at 0 0 0)
			(layer "F.SilkS")
			(hide yes)
			(effects
				(font
					(size 1.27 1.27)
				)
			)
		)
		(property "Value" ""
			(at 0 0 0)
			(layer "F.Fab")
			(effects
				(font
					(size 1.27 1.27)
				)
			)
		)
		(duplicate_pad_numbers_are_jumpers no)
		(fp_line
			(start -0.7874 -0.4064)
			(end 0.7874 -0.4064)
			(stroke
				(width 0.1524)
				(type default)
			)
			(layer "F.SilkS")
		)
		(fp_line
			(start -0.7874 0.4064)
			(end -0.7874 -0.4064)
			(stroke
				(width 0.1524)
				(type default)
			)
			(layer "F.SilkS")
		)
		(fp_line
			(start 0.7874 -0.4064)
			(end 0.7874 0.4064)
			(stroke
				(width 0.1524)
				(type default)
			)
			(layer "F.SilkS")
		)
		(fp_line
			(start 0.7874 0.4064)
			(end -0.7874 0.4064)
			(stroke
				(width 0.1524)
				(type default)
			)
			(layer "F.SilkS")
		)
		(fp_line
			(start -0.67945 -0.305054)
			(end -0.12065 -0.305054)
			(stroke
				(width 0.1)
				(type default)
			)
			(layer "F.Fab")
		)
		(fp_line
			(start -0.67945 0.3048)
			(end -0.67945 -0.305054)
			(stroke
				(width 0.1)
				(type default)
			)
			(layer "F.Fab")
		)
		(fp_line
			(start -0.12065 -0.305054)
			(end -0.12065 -0.2794)
			(stroke
				(width 0.1)
				(type default)
			)
			(layer "F.Fab")
		)
		(fp_line
			(start -0.12065 -0.2794)
			(end 0.12065 -0.2794)
			(stroke
				(width 0.1)
				(type default)
			)
			(layer "F.Fab")
		)
		(fp_line
			(start -0.12065 0.2794)
			(end -0.12065 0.3048)
			(stroke
				(width 0.1)
				(type default)
			)
			(layer "F.Fab")
		)
		(fp_line
			(start -0.12065 0.3048)
			(end -0.67945 0.3048)
			(stroke
				(width 0.1)
				(type default)
			)
			(layer "F.Fab")
		)
		(fp_line
			(start 0.120396 0.2794)
			(end -0.12065 0.2794)
			(stroke
				(width 0.1)
				(type default)
			)
			(layer "F.Fab")
		)
		(fp_line
			(start 0.120396 0.3048)
			(end 0.120396 0.2794)
			(stroke
				(width 0.1)
				(type default)
			)
			(layer "F.Fab")
		)
		(fp_line
			(start 0.12065 -0.3048)
			(end 0.67945 -0.3048)
			(stroke
				(width 0.1)
				(type default)
			)
			(layer "F.Fab")
		)
		(fp_line
			(start 0.12065 -0.2794)
			(end 0.12065 -0.3048)
			(stroke
				(width 0.1)
				(type default)
			)
			(layer "F.Fab")
		)
		(fp_line
			(start 0.67945 -0.3048)
			(end 0.67945 0.3048)
			(stroke
				(width 0.1)
				(type default)
			)
			(layer "F.Fab")
		)
		(fp_line
			(start 0.67945 0.3048)
			(end 0.120396 0.3048)
			(stroke
				(width 0.1)
				(type default)
			)
			(layer "F.Fab")
		)
		(pad "1" smd circle
			(at -0.40005 0)
			(size 0 0)
			(layers "F.Cu" "F.Mask" "F.Paste")
			(net "P12V_OCP_SFF")
		)
		(pad "2" smd circle
			(at 0.40005 0)
			(size 0 0)
			(layers "F.Cu" "F.Mask" "F.Paste")
			(net "GND")
		)
	)
	(footprint ""
		(layer "F.Cu")
		(at 112.705896 -370.57203 -90)
		(property "Reference" "C1540"
			(at 0 0 270)
			(layer "F.SilkS")
			(hide yes)
			(effects
				(font
					(size 1.27 1.27)
				)
			)
		)
		(property "Value" ""
			(at 0 0 270)
			(layer "F.Fab")
			(effects
				(font
					(size 1.27 1.27)
				)
			)
		)
		(duplicate_pad_numbers_are_jumpers no)
		(fp_line
			(start -0.299974 0.150114)
			(end -0.299974 -0.150114)
			(stroke
				(width 0.1)
				(type default)
			)
			(layer "F.Fab")
		)
		(fp_line
			(start 0.299974 0.150114)
			(end -0.299974 0.150114)
			(stroke
				(width 0.1)
				(type default)
			)
			(layer "F.Fab")
		)
		(fp_line
			(start -0.299974 -0.150114)
			(end 0.299974 -0.150114)
			(stroke
				(width 0.1)
				(type default)
			)
			(layer "F.Fab")
		)
		(fp_line
			(start 0.299974 -0.150114)
			(end 0.299974 0.150114)
			(stroke
				(width 0.1)
				(type default)
			)
			(layer "F.Fab")
		)
		(pad "1" smd rect
			(at -0.2667 0 270)
			(size 0.3048 0.381)
			(layers "F.Cu" "F.Mask" "F.Paste")
			(net "P5E_CPU1_P3_TX_C_DN<3>")
		)
		(pad "2" smd rect
			(at 0.2667 0 270)
			(size 0.3048 0.381)
			(layers "F.Cu" "F.Mask" "F.Paste")
			(net "P5E_CPU1_P3_TX_DN<3>")
		)
	)
	(footprint ""
		(layer "F.Cu")
		(at 212.598 -120.65 180)
		(property "Reference" "C1060"
			(at 0 0 180)
			(layer "F.SilkS")
			(hide yes)
			(effects
				(font
					(size 1.27 1.27)
				)
			)
		)
		(property "Value" ""
			(at 0 0 180)
			(layer "F.Fab")
			(effects
				(font
					(size 1.27 1.27)
				)
			)
		)
		(duplicate_pad_numbers_are_jumpers no)
		(fp_line
			(start 0.7874 0.4064)
			(end -0.7874 0.4064)
			(stroke
				(width 0.1524)
				(type default)
			)
			(layer "F.SilkS")
		)
		(fp_line
			(start 0.7874 -0.4064)
			(end 0.7874 0.4064)
			(stroke
				(width 0.1524)
				(type default)
			)
			(layer "F.SilkS")
		)
		(fp_line
			(start -0.7874 0.4064)
			(end -0.7874 -0.4064)
			(stroke
				(width 0.1524)
				(type default)
			)
			(layer "F.SilkS")
		)
		(fp_line
			(start -0.7874 -0.4064)
			(end 0.7874 -0.4064)
			(stroke
				(width 0.1524)
				(type default)
			)
			(layer "F.SilkS")
		)
		(fp_line
			(start 0.67945 0.3048)
			(end 0.120396 0.3048)
			(stroke
				(width 0.1)
				(type default)
			)
			(layer "F.Fab")
		)
		(fp_line
			(start 0.67945 -0.3048)
			(end 0.67945 0.3048)
			(stroke
				(width 0.1)
				(type default)
			)
			(layer "F.Fab")
		)
		(fp_line
			(start 0.12065 -0.2794)
			(end 0.12065 -0.3048)
			(stroke
				(width 0.1)
				(type default)
			)
			(layer "F.Fab")
		)
		(fp_line
			(start 0.12065 -0.3048)
			(end 0.67945 -0.3048)
			(stroke
				(width 0.1)
				(type default)
			)
			(layer "F.Fab")
		)
		(fp_line
			(start 0.120396 0.3048)
			(end 0.120396 0.2794)
			(stroke
				(width 0.1)
				(type default)
			)
			(layer "F.Fab")
		)
		(fp_line
			(start 0.120396 0.2794)
			(end -0.12065 0.2794)
			(stroke
				(width 0.1)
				(type default)
			)
			(layer "F.Fab")
		)
		(fp_line
			(start -0.12065 0.3048)
			(end -0.67945 0.3048)
			(stroke
				(width 0.1)
				(type default)
			)
			(layer "F.Fab")
		)
		(fp_line
			(start -0.12065 0.2794)
			(end -0.12065 0.3048)
			(stroke
				(width 0.1)
				(type default)
			)
			(layer "F.Fab")
		)
		(fp_line
			(start -0.12065 -0.2794)
			(end 0.12065 -0.2794)
			(stroke
				(width 0.1)
				(type default)
			)
			(layer "F.Fab")
		)
		(fp_line
			(start -0.12065 -0.305054)
			(end -0.12065 -0.2794)
			(stroke
				(width 0.1)
				(type default)
			)
			(layer "F.Fab")
		)
		(fp_line
			(start -0.67945 0.3048)
			(end -0.67945 -0.305054)
			(stroke
				(width 0.1)
				(type default)
			)
			(layer "F.Fab")
		)
		(fp_line
			(start -0.67945 -0.305054)
			(end -0.12065 -0.305054)
			(stroke
				(width 0.1)
				(type default)
			)
			(layer "F.Fab")
		)
		(pad "1" smd circle
			(at -0.40005 0 180)
			(size 0 0)
			(layers "F.Cu" "F.Mask" "F.Paste")
			(net "P3V3_AUX")
		)
		(pad "2" smd circle
			(at 0.40005 0 180)
			(size 0 0)
			(layers "F.Cu" "F.Mask" "F.Paste")
			(net "GND")
		)
	)
	(footprint ""
		(layer "F.Cu")
		(at 256.592324 -129.617216)
		(property "Reference" "C1102"
			(at 0 0 0)
			(layer "F.SilkS")
			(hide yes)
			(effects
				(font
					(size 1.27 1.27)
				)
			)
		)
		(property "Value" ""
			(at 0 0 0)
			(layer "F.Fab")
			(effects
				(font
					(size 1.27 1.27)
				)
			)
		)
		(duplicate_pad_numbers_are_jumpers no)
		(fp_line
			(start -0.7874 -0.4064)
			(end 0.7874 -0.4064)
			(stroke
				(width 0.1524)
				(type default)
			)
			(layer "F.SilkS")
		)
		(fp_line
			(start -0.7874 0.4064)
			(end -0.7874 -0.4064)
			(stroke
				(width 0.1524)
				(type default)
			)
			(layer "F.SilkS")
		)
		(fp_line
			(start 0.7874 -0.4064)
			(end 0.7874 0.4064)
			(stroke
				(width 0.1524)
				(type default)
			)
			(layer "F.SilkS")
		)
		(fp_line
			(start 0.7874 0.4064)
			(end -0.7874 0.4064)
			(stroke
				(width 0.1524)
				(type default)
			)
			(layer "F.SilkS")
		)
		(fp_line
			(start -0.67945 -0.305054)
			(end -0.12065 -0.305054)
			(stroke
				(width 0.1)
				(type default)
			)
			(layer "F.Fab")
		)
		(fp_line
			(start -0.67945 0.3048)
			(end -0.67945 -0.305054)
			(stroke
				(width 0.1)
				(type default)
			)
			(layer "F.Fab")
		)
		(fp_line
			(start -0.12065 -0.305054)
			(end -0.12065 -0.2794)
			(stroke
				(width 0.1)
				(type default)
			)
			(layer "F.Fab")
		)
		(fp_line
			(start -0.12065 -0.2794)
			(end 0.12065 -0.2794)
			(stroke
				(width 0.1)
				(type default)
			)
			(layer "F.Fab")
		)
		(fp_line
			(start -0.12065 0.2794)
			(end -0.12065 0.3048)
			(stroke
				(width 0.1)
				(type default)
			)
			(layer "F.Fab")
		)
		(fp_line
			(start -0.12065 0.3048)
			(end -0.67945 0.3048)
			(stroke
				(width 0.1)
				(type default)
			)
			(layer "F.Fab")
		)
		(fp_line
			(start 0.120396 0.2794)
			(end -0.12065 0.2794)
			(stroke
				(width 0.1)
				(type default)
			)
			(layer "F.Fab")
		)
		(fp_line
			(start 0.120396 0.3048)
			(end 0.120396 0.2794)
			(stroke
				(width 0.1)
				(type default)
			)
			(layer "F.Fab")
		)
		(fp_line
			(start 0.12065 -0.3048)
			(end 0.67945 -0.3048)
			(stroke
				(width 0.1)
				(type default)
			)
			(layer "F.Fab")
		)
		(fp_line
			(start 0.12065 -0.2794)
			(end 0.12065 -0.3048)
			(stroke
				(width 0.1)
				(type default)
			)
			(layer "F.Fab")
		)
		(fp_line
			(start 0.67945 -0.3048)
			(end 0.67945 0.3048)
			(stroke
				(width 0.1)
				(type default)
			)
			(layer "F.Fab")
		)
		(fp_line
			(start 0.67945 0.3048)
			(end 0.120396 0.3048)
			(stroke
				(width 0.1)
				(type default)
			)
			(layer "F.Fab")
		)
		(pad "1" smd circle
			(at -0.40005 0)
			(size 0 0)
			(layers "F.Cu" "F.Mask" "F.Paste")
			(net "PVDD18_S5_P0")
		)
		(pad "2" smd circle
			(at 0.40005 0)
			(size 0 0)
			(layers "F.Cu" "F.Mask" "F.Paste")
			(net "GND")
		)
	)
	(footprint ""
		(layer "F.Cu")
		(at 37.211 -364.109)
		(property "Reference" "PC368"
			(at 0 0 0)
			(layer "F.SilkS")
			(hide yes)
			(effects
				(font
					(size 1.27 1.27)
				)
			)
		)
		(property "Value" ""
			(at 0 0 0)
			(layer "F.Fab")
			(effects
				(font
					(size 1.27 1.27)
				)
			)
		)
		(duplicate_pad_numbers_are_jumpers no)
		(fp_line
			(start -0.7874 -0.4064)
			(end 0.7874 -0.4064)
			(stroke
				(width 0.1524)
				(type default)
			)
			(layer "F.SilkS")
		)
		(fp_line
			(start -0.7874 0.4064)
			(end -0.7874 -0.4064)
			(stroke
				(width 0.1524)
				(type default)
			)
			(layer "F.SilkS")
		)
		(fp_line
			(start 0.7874 -0.4064)
			(end 0.7874 0.4064)
			(stroke
				(width 0.1524)
				(type default)
			)
			(layer "F.SilkS")
		)
		(fp_line
			(start 0.7874 0.4064)
			(end -0.7874 0.4064)
			(stroke
				(width 0.1524)
				(type default)
			)
			(layer "F.SilkS")
		)
		(fp_line
			(start -0.67945 -0.305054)
			(end -0.12065 -0.305054)
			(stroke
				(width 0.1)
				(type default)
			)
			(layer "F.Fab")
		)
		(fp_line
			(start -0.67945 0.3048)
			(end -0.67945 -0.305054)
			(stroke
				(width 0.1)
				(type default)
			)
			(layer "F.Fab")
		)
		(fp_line
			(start -0.12065 -0.305054)
			(end -0.12065 -0.2794)
			(stroke
				(width 0.1)
				(type default)
			)
			(layer "F.Fab")
		)
		(fp_line
			(start -0.12065 -0.2794)
			(end 0.12065 -0.2794)
			(stroke
				(width 0.1)
				(type default)
			)
			(layer "F.Fab")
		)
		(fp_line
			(start -0.12065 0.2794)
			(end -0.12065 0.3048)
			(stroke
				(width 0.1)
				(type default)
			)
			(layer "F.Fab")
		)
		(fp_line
			(start -0.12065 0.3048)
			(end -0.67945 0.3048)
			(stroke
				(width 0.1)
				(type default)
			)
			(layer "F.Fab")
		)
		(fp_line
			(start 0.120396 0.2794)
			(end -0.12065 0.2794)
			(stroke
				(width 0.1)
				(type default)
			)
			(layer "F.Fab")
		)
		(fp_line
			(start 0.120396 0.3048)
			(end 0.120396 0.2794)
			(stroke
				(width 0.1)
				(type default)
			)
			(layer "F.Fab")
		)
		(fp_line
			(start 0.12065 -0.3048)
			(end 0.67945 -0.3048)
			(stroke
				(width 0.1)
				(type default)
			)
			(layer "F.Fab")
		)
		(fp_line
			(start 0.12065 -0.2794)
			(end 0.12065 -0.3048)
			(stroke
				(width 0.1)
				(type default)
			)
			(layer "F.Fab")
		)
		(fp_line
			(start 0.67945 -0.3048)
			(end 0.67945 0.3048)
			(stroke
				(width 0.1)
				(type default)
			)
			(layer "F.Fab")
		)
		(fp_line
			(start 0.67945 0.3048)
			(end 0.120396 0.3048)
			(stroke
				(width 0.1)
				(type default)
			)
			(layer "F.Fab")
		)
		(pad "1" smd circle
			(at -0.40005 0)
			(size 0 0)
			(layers "F.Cu" "F.Mask" "F.Paste")
			(net "PVDDCR_CPU1_P1_TEMP0")
		)
		(pad "2" smd circle
			(at 0.40005 0)
			(size 0 0)
			(layers "F.Cu" "F.Mask" "F.Paste")
			(net "GND")
		)
	)
	(footprint ""
		(layer "F.Cu")
		(at 302.344836 -422.967404 90)
		(property "Reference" "C7510"
			(at 0 0 90)
			(layer "F.SilkS")
			(hide yes)
			(effects
				(font
					(size 1.27 1.27)
				)
			)
		)
		(property "Value" ""
			(at 0 0 90)
			(layer "F.Fab")
			(effects
				(font
					(size 1.27 1.27)
				)
			)
		)
		(duplicate_pad_numbers_are_jumpers no)
		(fp_line
			(start 0.299974 -0.150114)
			(end 0.299974 0.150114)
			(stroke
				(width 0.1)
				(type default)
			)
			(layer "F.Fab")
		)
		(fp_line
			(start -0.299974 -0.150114)
			(end 0.299974 -0.150114)
			(stroke
				(width 0.1)
				(type default)
			)
			(layer "F.Fab")
		)
		(fp_line
			(start 0.299974 0.150114)
			(end -0.299974 0.150114)
			(stroke
				(width 0.1)
				(type default)
			)
			(layer "F.Fab")
		)
		(fp_line
			(start -0.299974 0.150114)
			(end -0.299974 -0.150114)
			(stroke
				(width 0.1)
				(type default)
			)
			(layer "F.Fab")
		)
		(pad "1" smd rect
			(at -0.2667 0 90)
			(size 0.3048 0.381)
			(layers "F.Cu" "F.Mask" "F.Paste")
			(net "P1V8_CPU0_RT_1D")
		)
		(pad "2" smd rect
			(at 0.2667 0 90)
			(size 0.3048 0.381)
			(layers "F.Cu" "F.Mask" "F.Paste")
			(net "GND")
		)
	)
	(footprint ""
		(layer "F.Cu")
		(at 100.151184 -35.30092)
		(property "Reference" "R3192"
			(at 0 0 0)
			(layer "F.SilkS")
			(hide yes)
			(effects
				(font
					(size 1.27 1.27)
				)
			)
		)
		(property "Value" ""
			(at 0 0 0)
			(layer "F.Fab")
			(effects
				(font
					(size 1.27 1.27)
				)
			)
		)
		(duplicate_pad_numbers_are_jumpers no)
		(fp_line
			(start -0.7874 -0.4064)
			(end 0.7874 -0.4064)
			(stroke
				(width 0.1524)
				(type default)
			)
			(layer "F.SilkS")
		)
		(fp_line
			(start -0.7874 0.4064)
			(end -0.7874 -0.4064)
			(stroke
				(width 0.1524)
				(type default)
			)
			(layer "F.SilkS")
		)
		(fp_line
			(start 0.7874 -0.4064)
			(end 0.7874 0.4064)
			(stroke
				(width 0.1524)
				(type default)
			)
			(layer "F.SilkS")
		)
		(fp_line
			(start 0.7874 0.4064)
			(end -0.7874 0.4064)
			(stroke
				(width 0.1524)
				(type default)
			)
			(layer "F.SilkS")
		)
		(fp_line
			(start -0.67945 -0.305054)
			(end -0.12065 -0.305054)
			(stroke
				(width 0.1)
				(type default)
			)
			(layer "F.Fab")
		)
		(fp_line
			(start -0.67945 0.3048)
			(end -0.67945 -0.305054)
			(stroke
				(width 0.1)
				(type default)
			)
			(layer "F.Fab")
		)
		(fp_line
			(start -0.12065 -0.305054)
			(end -0.12065 -0.2794)
			(stroke
				(width 0.1)
				(type default)
			)
			(layer "F.Fab")
		)
		(fp_line
			(start -0.12065 -0.2794)
			(end 0.12065 -0.2794)
			(stroke
				(width 0.1)
				(type default)
			)
			(layer "F.Fab")
		)
		(fp_line
			(start -0.12065 0.2794)
			(end -0.12065 0.3048)
			(stroke
				(width 0.1)
				(type default)
			)
			(layer "F.Fab")
		)
		(fp_line
			(start -0.12065 0.3048)
			(end -0.67945 0.3048)
			(stroke
				(width 0.1)
				(type default)
			)
			(layer "F.Fab")
		)
		(fp_line
			(start 0.120396 0.2794)
			(end -0.12065 0.2794)
			(stroke
				(width 0.1)
				(type default)
			)
			(layer "F.Fab")
		)
		(fp_line
			(start 0.120396 0.3048)
			(end 0.120396 0.2794)
			(stroke
				(width 0.1)
				(type default)
			)
			(layer "F.Fab")
		)
		(fp_line
			(start 0.12065 -0.3048)
			(end 0.67945 -0.3048)
			(stroke
				(width 0.1)
				(type default)
			)
			(layer "F.Fab")
		)
		(fp_line
			(start 0.12065 -0.2794)
			(end 0.12065 -0.3048)
			(stroke
				(width 0.1)
				(type default)
			)
			(layer "F.Fab")
		)
		(fp_line
			(start 0.67945 -0.3048)
			(end 0.67945 0.3048)
			(stroke
				(width 0.1)
				(type default)
			)
			(layer "F.Fab")
		)
		(fp_line
			(start 0.67945 0.3048)
			(end 0.120396 0.3048)
			(stroke
				(width 0.1)
				(type default)
			)
			(layer "F.Fab")
		)
		(pad "1" smd circle
			(at -0.40005 0)
			(size 0 0)
			(layers "F.Cu" "F.Mask" "F.Paste")
			(net "P3V3_AUX")
		)
		(pad "2" smd circle
			(at 0.40005 0)
			(size 0 0)
			(layers "F.Cu" "F.Mask" "F.Paste")
			(net "IRQ_LVC3_V3_2_WAKE_BUF_N")
		)
	)
	(footprint ""
		(layer "F.Cu")
		(at 394.067284 -390.1694)
		(property "Reference" "R1412"
			(at 0 0 0)
			(layer "F.SilkS")
			(hide yes)
			(effects
				(font
					(size 1.27 1.27)
				)
			)
		)
		(property "Value" ""
			(at 0 0 0)
			(layer "F.Fab")
			(effects
				(font
					(size 1.27 1.27)
				)
			)
		)
		(duplicate_pad_numbers_are_jumpers no)
		(fp_line
			(start -0.32512 -0.175006)
			(end 0.32512 -0.175006)
			(stroke
				(width 0.1)
				(type default)
			)
			(layer "F.Fab")
		)
		(fp_line
			(start -0.32512 0.175006)
			(end -0.32512 -0.175006)
			(stroke
				(width 0.1)
				(type default)
			)
			(layer "F.Fab")
		)
		(fp_line
			(start 0.32512 -0.175006)
			(end 0.32512 0.175006)
			(stroke
				(width 0.1)
				(type default)
			)
			(layer "F.Fab")
		)
		(fp_line
			(start 0.32512 0.175006)
			(end -0.32512 0.175006)
			(stroke
				(width 0.1)
				(type default)
			)
			(layer "F.Fab")
		)
		(pad "1" smd rect
			(at -0.2667 0)
			(size 0.3048 0.381)
			(layers "F.Cu" "F.Mask" "F.Paste")
			(net "CLKREQ_RT_CPU0_P3_N")
		)
		(pad "2" smd rect
			(at 0.2667 0 180)
			(size 0.3048 0.381)
			(layers "F.Cu" "F.Mask" "F.Paste")
			(net "GND")
		)
	)
	(footprint ""
		(layer "F.Cu")
		(at 206.4385 -402.191982 90)
		(property "Reference" "PC2181"
			(at 0 0 90)
			(layer "F.SilkS")
			(hide yes)
			(effects
				(font
					(size 1.27 1.27)
				)
			)
		)
		(property "Value" ""
			(at 0 0 90)
			(layer "F.Fab")
			(effects
				(font
					(size 1.27 1.27)
				)
			)
		)
		(duplicate_pad_numbers_are_jumpers no)
		(fp_line
			(start 0.7874 -0.4064)
			(end 0.7874 0.4064)
			(stroke
				(width 0.1524)
				(type default)
			)
			(layer "F.SilkS")
		)
		(fp_line
			(start -0.7874 -0.4064)
			(end 0.7874 -0.4064)
			(stroke
				(width 0.1524)
				(type default)
			)
			(layer "F.SilkS")
		)
		(fp_line
			(start 0.7874 0.4064)
			(end -0.7874 0.4064)
			(stroke
				(width 0.1524)
				(type default)
			)
			(layer "F.SilkS")
		)
		(fp_line
			(start -0.7874 0.4064)
			(end -0.7874 -0.4064)
			(stroke
				(width 0.1524)
				(type default)
			)
			(layer "F.SilkS")
		)
		(fp_line
			(start -0.12065 -0.305054)
			(end -0.12065 -0.2794)
			(stroke
				(width 0.1)
				(type default)
			)
			(layer "F.Fab")
		)
		(fp_line
			(start -0.67945 -0.305054)
			(end -0.12065 -0.305054)
			(stroke
				(width 0.1)
				(type default)
			)
			(layer "F.Fab")
		)
		(fp_line
			(start 0.67945 -0.3048)
			(end 0.67945 0.3048)
			(stroke
				(width 0.1)
				(type default)
			)
			(layer "F.Fab")
		)
		(fp_line
			(start 0.12065 -0.3048)
			(end 0.67945 -0.3048)
			(stroke
				(width 0.1)
				(type default)
			)
			(layer "F.Fab")
		)
		(fp_line
			(start 0.12065 -0.2794)
			(end 0.12065 -0.3048)
			(stroke
				(width 0.1)
				(type default)
			)
			(layer "F.Fab")
		)
		(fp_line
			(start -0.12065 -0.2794)
			(end 0.12065 -0.2794)
			(stroke
				(width 0.1)
				(type default)
			)
			(layer "F.Fab")
		)
		(fp_line
			(start 0.120396 0.2794)
			(end -0.12065 0.2794)
			(stroke
				(width 0.1)
				(type default)
			)
			(layer "F.Fab")
		)
		(fp_line
			(start -0.12065 0.2794)
			(end -0.12065 0.3048)
			(stroke
				(width 0.1)
				(type default)
			)
			(layer "F.Fab")
		)
		(fp_line
			(start 0.67945 0.3048)
			(end 0.120396 0.3048)
			(stroke
				(width 0.1)
				(type default)
			)
			(layer "F.Fab")
		)
		(fp_line
			(start 0.120396 0.3048)
			(end 0.120396 0.2794)
			(stroke
				(width 0.1)
				(type default)
			)
			(layer "F.Fab")
		)
		(fp_line
			(start -0.12065 0.3048)
			(end -0.67945 0.3048)
			(stroke
				(width 0.1)
				(type default)
			)
			(layer "F.Fab")
		)
		(fp_line
			(start -0.67945 0.3048)
			(end -0.67945 -0.305054)
			(stroke
				(width 0.1)
				(type default)
			)
			(layer "F.Fab")
		)
		(pad "1" smd circle
			(at -0.40005 0 90)
			(size 0 0)
			(layers "F.Cu" "F.Mask" "F.Paste")
			(net "HSC_VDD_R_2")
		)
		(pad "2" smd circle
			(at 0.40005 0 90)
			(size 0 0)
			(layers "F.Cu" "F.Mask" "F.Paste")
			(net "AGND_HSC")
		)
	)
	(footprint ""
		(layer "F.Cu")
		(at 90.75674 -335.128616 -90)
		(property "Reference" "PC377_1"
			(at 0 0 270)
			(layer "F.SilkS")
			(hide yes)
			(effects
				(font
					(size 1.27 1.27)
				)
			)
		)
		(property "Value" ""
			(at 0 0 270)
			(layer "F.Fab")
			(effects
				(font
					(size 1.27 1.27)
				)
			)
		)
		(duplicate_pad_numbers_are_jumpers no)
		(fp_line
			(start -0.7874 0.4064)
			(end -0.7874 -0.4064)
			(stroke
				(width 0.1524)
				(type default)
			)
			(layer "F.SilkS")
		)
		(fp_line
			(start 0.7874 0.4064)
			(end -0.7874 0.4064)
			(stroke
				(width 0.1524)
				(type default)
			)
			(layer "F.SilkS")
		)
		(fp_line
			(start -0.7874 -0.4064)
			(end 0.7874 -0.4064)
			(stroke
				(width 0.1524)
				(type default)
			)
			(layer "F.SilkS")
		)
		(fp_line
			(start 0.7874 -0.4064)
			(end 0.7874 0.4064)
			(stroke
				(width 0.1524)
				(type default)
			)
			(layer "F.SilkS")
		)
		(fp_line
			(start -0.67945 0.3048)
			(end -0.67945 -0.305054)
			(stroke
				(width 0.1)
				(type default)
			)
			(layer "F.Fab")
		)
		(fp_line
			(start -0.12065 0.3048)
			(end -0.67945 0.3048)
			(stroke
				(width 0.1)
				(type default)
			)
			(layer "F.Fab")
		)
		(fp_line
			(start 0.120396 0.3048)
			(end 0.120396 0.2794)
			(stroke
				(width 0.1)
				(type default)
			)
			(layer "F.Fab")
		)
		(fp_line
			(start 0.67945 0.3048)
			(end 0.120396 0.3048)
			(stroke
				(width 0.1)
				(type default)
			)
			(layer "F.Fab")
		)
		(fp_line
			(start -0.12065 0.2794)
			(end -0.12065 0.3048)
			(stroke
				(width 0.1)
				(type default)
			)
			(layer "F.Fab")
		)
		(fp_line
			(start 0.120396 0.2794)
			(end -0.12065 0.2794)
			(stroke
				(width 0.1)
				(type default)
			)
			(layer "F.Fab")
		)
		(fp_line
			(start -0.12065 -0.2794)
			(end 0.12065 -0.2794)
			(stroke
				(width 0.1)
				(type default)
			)
			(layer "F.Fab")
		)
		(fp_line
			(start 0.12065 -0.2794)
			(end 0.12065 -0.3048)
			(stroke
				(width 0.1)
				(type default)
			)
			(layer "F.Fab")
		)
		(fp_line
			(start 0.12065 -0.3048)
			(end 0.67945 -0.3048)
			(stroke
				(width 0.1)
				(type default)
			)
			(layer "F.Fab")
		)
		(fp_line
			(start 0.67945 -0.3048)
			(end 0.67945 0.3048)
			(stroke
				(width 0.1)
				(type default)
			)
			(layer "F.Fab")
		)
		(fp_line
			(start -0.67945 -0.305054)
			(end -0.12065 -0.305054)
			(stroke
				(width 0.1)
				(type default)
			)
			(layer "F.Fab")
		)
		(fp_line
			(start -0.12065 -0.305054)
			(end -0.12065 -0.2794)
			(stroke
				(width 0.1)
				(type default)
			)
			(layer "F.Fab")
		)
		(pad "1" smd circle
			(at -0.40005 0 270)
			(size 0 0)
			(layers "F.Cu" "F.Mask" "F.Paste")
			(net "SW_P12V_AUX_PVDDCR_CPU1_P1_FLT")
		)
		(pad "2" smd circle
			(at 0.40005 0 270)
			(size 0 0)
			(layers "F.Cu" "F.Mask" "F.Paste")
			(net "GND")
		)
	)
	(footprint ""
		(layer "F.Cu")
		(at 15.094458 -418.690298 -90)
		(property "Reference" "R6178"
			(at 0 0 270)
			(layer "F.SilkS")
			(hide yes)
			(effects
				(font
					(size 1.27 1.27)
				)
			)
		)
		(property "Value" ""
			(at 0 0 270)
			(layer "F.Fab")
			(effects
				(font
					(size 1.27 1.27)
				)
			)
		)
		(duplicate_pad_numbers_are_jumpers no)
		(fp_line
			(start -0.7874 0.4064)
			(end -0.7874 -0.4064)
			(stroke
				(width 0.1524)
				(type default)
			)
			(layer "F.SilkS")
		)
		(fp_line
			(start 0.7874 0.4064)
			(end -0.7874 0.4064)
			(stroke
				(width 0.1524)
				(type default)
			)
			(layer "F.SilkS")
		)
		(fp_line
			(start -0.7874 -0.4064)
			(end 0.7874 -0.4064)
			(stroke
				(width 0.1524)
				(type default)
			)
			(layer "F.SilkS")
		)
		(fp_line
			(start 0.7874 -0.4064)
			(end 0.7874 0.4064)
			(stroke
				(width 0.1524)
				(type default)
			)
			(layer "F.SilkS")
		)
		(fp_line
			(start -0.67945 0.3048)
			(end -0.67945 -0.305054)
			(stroke
				(width 0.1)
				(type default)
			)
			(layer "F.Fab")
		)
		(fp_line
			(start -0.12065 0.3048)
			(end -0.67945 0.3048)
			(stroke
				(width 0.1)
				(type default)
			)
			(layer "F.Fab")
		)
		(fp_line
			(start 0.120396 0.3048)
			(end 0.120396 0.2794)
			(stroke
				(width 0.1)
				(type default)
			)
			(layer "F.Fab")
		)
		(fp_line
			(start 0.67945 0.3048)
			(end 0.120396 0.3048)
			(stroke
				(width 0.1)
				(type default)
			)
			(layer "F.Fab")
		)
		(fp_line
			(start -0.12065 0.2794)
			(end -0.12065 0.3048)
			(stroke
				(width 0.1)
				(type default)
			)
			(layer "F.Fab")
		)
		(fp_line
			(start 0.120396 0.2794)
			(end -0.12065 0.2794)
			(stroke
				(width 0.1)
				(type default)
			)
			(layer "F.Fab")
		)
		(fp_line
			(start -0.12065 -0.2794)
			(end 0.12065 -0.2794)
			(stroke
				(width 0.1)
				(type default)
			)
			(layer "F.Fab")
		)
		(fp_line
			(start 0.12065 -0.2794)
			(end 0.12065 -0.3048)
			(stroke
				(width 0.1)
				(type default)
			)
			(layer "F.Fab")
		)
		(fp_line
			(start 0.12065 -0.3048)
			(end 0.67945 -0.3048)
			(stroke
				(width 0.1)
				(type default)
			)
			(layer "F.Fab")
		)
		(fp_line
			(start 0.67945 -0.3048)
			(end 0.67945 0.3048)
			(stroke
				(width 0.1)
				(type default)
			)
			(layer "F.Fab")
		)
		(fp_line
			(start -0.67945 -0.305054)
			(end -0.12065 -0.305054)
			(stroke
				(width 0.1)
				(type default)
			)
			(layer "F.Fab")
		)
		(fp_line
			(start -0.12065 -0.305054)
			(end -0.12065 -0.2794)
			(stroke
				(width 0.1)
				(type default)
			)
			(layer "F.Fab")
		)
		(pad "1" smd circle
			(at -0.40005 0 270)
			(size 0 0)
			(layers "F.Cu" "F.Mask" "F.Paste")
			(net "FM_P2E_BUF2_SD_TH")
		)
		(pad "2" smd circle
			(at 0.40005 0 270)
			(size 0 0)
			(layers "F.Cu" "F.Mask" "F.Paste")
			(net "GND")
		)
	)
	(footprint ""
		(layer "F.Cu")
		(at 203.310744 -346.505022 180)
		(property "Reference" "PL71"
			(at 0 0 180)
			(layer "F.SilkS")
			(hide yes)
			(effects
				(font
					(size 1.27 1.27)
				)
			)
		)
		(property "Value" ""
			(at 0 0 180)
			(layer "F.Fab")
			(effects
				(font
					(size 1.27 1.27)
				)
			)
		)
		(duplicate_pad_numbers_are_jumpers no)
		(fp_line
			(start 1.27 0.5842)
			(end 1.27 -0.5842)
			(stroke
				(width 0.1524)
				(type default)
			)
			(layer "F.SilkS")
		)
		(fp_line
			(start 1.27 0.5842)
			(end -1.27 0.5842)
			(stroke
				(width 0.1524)
				(type default)
			)
			(layer "F.SilkS")
		)
		(fp_line
			(start -1.27 0.5842)
			(end -1.27 -0.5842)
			(stroke
				(width 0.1524)
				(type default)
			)
			(layer "F.SilkS")
		)
		(fp_line
			(start -1.27 -0.5588)
			(end -1.27 -0.5842)
			(stroke
				(width 0.1524)
				(type default)
			)
			(layer "F.SilkS")
		)
		(fp_line
			(start -1.27 -0.5842)
			(end 1.27 -0.5842)
			(stroke
				(width 0.1524)
				(type default)
			)
			(layer "F.SilkS")
		)
		(fp_line
			(start 1.1938 0.4064)
			(end 0.9144 0.4064)
			(stroke
				(width 0.1)
				(type default)
			)
			(layer "F.Fab")
		)
		(fp_line
			(start 1.1938 -0.406654)
			(end 1.1938 0.4064)
			(stroke
				(width 0.1)
				(type default)
			)
			(layer "F.Fab")
		)
		(fp_line
			(start 0.9144 0.508)
			(end -0.9144 0.508)
			(stroke
				(width 0.1)
				(type default)
			)
			(layer "F.Fab")
		)
		(fp_line
			(start 0.9144 0.4064)
			(end 0.9144 0.508)
			(stroke
				(width 0.1)
				(type default)
			)
			(layer "F.Fab")
		)
		(fp_line
			(start 0.9144 -0.406654)
			(end 1.1938 -0.406654)
			(stroke
				(width 0.1)
				(type default)
			)
			(layer "F.Fab")
		)
		(fp_line
			(start 0.9144 -0.508)
			(end 0.9144 -0.406654)
			(stroke
				(width 0.1)
				(type default)
			)
			(layer "F.Fab")
		)
		(fp_line
			(start -0.9144 0.508)
			(end -0.9144 0.406654)
			(stroke
				(width 0.1)
				(type default)
			)
			(layer "F.Fab")
		)
		(fp_line
			(start -0.9144 0.406654)
			(end -1.194308 0.406654)
			(stroke
				(width 0.1)
				(type default)
			)
			(layer "F.Fab")
		)
		(fp_line
			(start -0.9144 -0.406654)
			(end -0.9144 -0.508)
			(stroke
				(width 0.1)
				(type default)
			)
			(layer "F.Fab")
		)
		(fp_line
			(start -0.9144 -0.508)
			(end 0.9144 -0.508)
			(stroke
				(width 0.1)
				(type default)
			)
			(layer "F.Fab")
		)
		(fp_line
			(start -1.194308 0.406654)
			(end -1.194308 -0.406654)
			(stroke
				(width 0.1)
				(type default)
			)
			(layer "F.Fab")
		)
		(fp_line
			(start -1.194308 -0.406654)
			(end -0.9144 -0.406654)
			(stroke
				(width 0.1)
				(type default)
			)
			(layer "F.Fab")
		)
		(pad "1" smd rect
			(at -0.7366 0 90)
			(size 0.7112 0.8128)
			(layers "F.Cu" "F.Mask" "F.Paste")
			(net "P12V_AUX")
		)
		(pad "2" smd rect
			(at 0.7366 0 90)
			(size 0.7112 0.8128)
			(layers "F.Cu" "F.Mask" "F.Paste")
			(net "SW_P12V_AUX_PVDD_33_S5_FLT")
		)
	)
	(footprint ""
		(layer "F.Cu")
		(at 13.546582 -134.039102)
		(property "Reference" "U247"
			(at -2.7432 -3.012948 0)
			(unlocked yes)
			(layer "F.SilkS")
			(effects
				(font
					(size 0.7874 0.5842)
					(thickness 0.1524)
				)
				(justify left)
			)
		)
		(property "Value" ""
			(at 0 0 0)
			(layer "F.Fab")
			(effects
				(font
					(size 1.27 1.27)
				)
			)
		)
		(duplicate_pad_numbers_are_jumpers no)
		(fp_line
			(start -2.050034 -2.050034)
			(end -2.050034 -1.516634)
			(stroke
				(width 0.1524)
				(type default)
			)
			(layer "F.SilkS")
		)
		(fp_line
			(start -2.050034 1.516634)
			(end -2.050034 2.050034)
			(stroke
				(width 0.1524)
				(type default)
			)
			(layer "F.SilkS")
		)
		(fp_line
			(start -2.050034 2.050034)
			(end -1.516634 2.050034)
			(stroke
				(width 0.1524)
				(type default)
			)
			(layer "F.SilkS")
		)
		(fp_line
			(start -1.516634 -2.050034)
			(end -2.050034 -2.050034)
			(stroke
				(width 0.1524)
				(type default)
			)
			(layer "F.SilkS")
		)
		(fp_line
			(start 1.516634 2.050034)
			(end 2.050034 2.050034)
			(stroke
				(width 0.1524)
				(type default)
			)
			(layer "F.SilkS")
		)
		(fp_line
			(start 2.050034 -2.050034)
			(end 1.516634 -2.050034)
			(stroke
				(width 0.1524)
				(type default)
			)
			(layer "F.SilkS")
		)
		(fp_line
			(start 2.050034 -1.516634)
			(end 2.050034 -2.050034)
			(stroke
				(width 0.1524)
				(type default)
			)
			(layer "F.SilkS")
		)
		(fp_line
			(start 2.050034 2.050034)
			(end 2.050034 1.516634)
			(stroke
				(width 0.1524)
				(type default)
			)
			(layer "F.SilkS")
		)
		(fp_poly
			(pts
				(xy -2.634234 -1.542034) (xy -2.050034 -1.542034) (xy -2.050034 -2.126234) (xy -2.634234 -2.126234)
			)
			(stroke
				(width 0)
				(type default)
			)
			(fill yes)
			(layer "F.SilkS")
		)
		(fp_line
			(start -2.050034 -2.050034)
			(end -2.050034 2.050034)
			(stroke
				(width 0.1)
				(type default)
			)
			(layer "F.Fab")
		)
		(fp_line
			(start -2.050034 2.050034)
			(end 2.050034 2.050034)
			(stroke
				(width 0.1)
				(type default)
			)
			(layer "F.Fab")
		)
		(fp_line
			(start 2.050034 -2.050034)
			(end -2.050034 -2.050034)
			(stroke
				(width 0.1)
				(type default)
			)
			(layer "F.Fab")
		)
		(fp_line
			(start 2.050034 2.050034)
			(end 2.050034 -2.050034)
			(stroke
				(width 0.1)
				(type default)
			)
			(layer "F.Fab")
		)
		(fp_poly
			(pts
				(xy -2.634234 -1.542034) (xy -2.050034 -1.542034) (xy -2.050034 -2.126234) (xy -2.634234 -2.126234)
			)
			(stroke
				(width 0)
				(type default)
			)
			(fill yes)
			(layer "F.Fab")
		)
		(pad "1" smd rect
			(at -1.875028 -1.249934 270)
			(size 0.254 0.5588)
			(layers "F.Cu" "F.Mask" "F.Paste")
			(net "CLK_GEN2_XTAL_IN")
		)
		(pad "2" smd rect
			(at -1.875028 -0.750062 270)
			(size 0.254 0.5588)
			(layers "F.Cu" "F.Mask" "F.Paste")
			(net "CLK_GEN2_XTAL_OUT")
		)
		(pad "3" smd rect
			(at -1.875028 -0.249936 270)
			(size 0.254 0.5588)
			(layers "F.Cu" "F.Mask" "F.Paste")
			(net "VFG3P3_CLK_GEN")
		)
		(pad "4" smd rect
			(at -1.875028 0.249936 270)
			(size 0.254 0.5588)
			(layers "F.Cu" "F.Mask" "F.Paste")
			(net "CLK_GEN2_SMB_SADR")
		)
		(pad "5" smd rect
			(at -1.875028 0.750062 270)
			(size 0.254 0.5588)
			(layers "F.Cu" "F.Mask" "F.Paste")
			(net "GND")
		)
		(pad "6" smd rect
			(at -1.875028 1.249934 270)
			(size 0.254 0.5588)
			(layers "F.Cu" "F.Mask" "F.Paste")
			(net "GND")
		)
		(pad "7" smd rect
			(at -1.249934 1.875028)
			(size 0.254 0.5588)
			(layers "F.Cu" "F.Mask" "F.Paste")
			(net "VFG3P3_CLK_GEN")
		)
		(pad "8" smd rect
			(at -0.750062 1.875028)
			(size 0.254 0.5588)
			(layers "F.Cu" "F.Mask" "F.Paste")
			(net "SMB_HOST_CLK_GEN2_3V3AUX_SCL")
		)
		(pad "9" smd rect
			(at -0.249936 1.875028)
			(size 0.254 0.5588)
			(layers "F.Cu" "F.Mask" "F.Paste")
			(net "SMB_HOST_CLK_GEN2_3V3AUX_SDA")
		)
		(pad "10" smd rect
			(at 0.249936 1.875028)
			(size 0.254 0.5588)
			(layers "F.Cu" "F.Mask" "F.Paste")
			(net "GND")
		)
		(pad "11" smd rect
			(at 0.750062 1.875028)
			(size 0.254 0.5588)
			(layers "F.Cu" "F.Mask" "F.Paste")
			(net "VFG3P3_CLK_GEN")
		)
		(pad "12" smd rect
			(at 1.249934 1.875028)
			(size 0.254 0.5588)
			(layers "F.Cu" "F.Mask" "F.Paste")
			(net "CLK_GEN2_BMC_RC_OE_R3_N")
		)
		(pad "13" smd rect
			(at 1.875028 1.249934 270)
			(size 0.254 0.5588)
			(layers "F.Cu" "F.Mask" "F.Paste")
			(net "CLK_100M_BMC_RC_DP_R")
		)
		(pad "14" smd rect
			(at 1.875028 0.750062 270)
			(size 0.254 0.5588)
			(layers "F.Cu" "F.Mask" "F.Paste")
			(net "CLK_100M_BMC_RC_DN_R")
		)
		(pad "15" smd rect
			(at 1.875028 0.249936 270)
			(size 0.254 0.5588)
			(layers "F.Cu" "F.Mask" "F.Paste")
			(net "GND")
		)
		(pad "16" smd rect
			(at 1.875028 -0.249936 270)
			(size 0.254 0.5588)
			(layers "F.Cu" "F.Mask" "F.Paste")
			(net "VFG_3P3A_CLK_GEN")
		)
		(pad "17" smd rect
			(at 1.875028 -0.750062 270)
			(size 0.254 0.5588)
			(layers "F.Cu" "F.Mask" "F.Paste")
			(net "CLK_100M_GPU_FPGA_DP_R")
		)
		(pad "18" smd rect
			(at 1.875028 -1.249934 270)
			(size 0.254 0.5588)
			(layers "F.Cu" "F.Mask" "F.Paste")
			(net "CLK_100M_GPU_FPGA_DN_R")
		)
		(pad "19" smd rect
			(at 1.249934 -1.875028)
			(size 0.254 0.5588)
			(layers "F.Cu" "F.Mask" "F.Paste")
			(net "CLK_GEN2_GPU_OE_N")
		)
		(pad "20" smd rect
			(at 0.750062 -1.875028)
			(size 0.254 0.5588)
			(layers "F.Cu" "F.Mask" "F.Paste")
			(net "VFG3P3_CLK_GEN")
		)
		(pad "21" smd rect
			(at 0.249936 -1.875028)
			(size 0.254 0.5588)
			(layers "F.Cu" "F.Mask" "F.Paste")
			(net "GND")
		)
		(pad "22" smd rect
			(at -0.249936 -1.875028)
			(size 0.254 0.5588)
			(layers "F.Cu" "F.Mask" "F.Paste")
			(net "P3V3_PWRGD_CLKGEN")
		)
		(pad "23" smd rect
			(at -0.750062 -1.875028)
			(size 0.254 0.5588)
			(layers "F.Cu" "F.Mask" "F.Paste")
			(net "FG_SS_EN")
		)
		(pad "24" smd rect
			(at -1.249934 -1.875028)
			(size 0.254 0.5588)
			(layers "F.Cu" "F.Mask" "F.Paste")
			(net "GND")
		)
		(pad "25" smd circle
			(at 0 0)
			(size 0 0)
			(layers "F.Cu" "F.Mask" "F.Paste")
			(net "GND")
		)
	)
	(footprint ""
		(layer "F.Cu")
		(at 419.230302 -434.386736 90)
		(property "Reference" "R4167"
			(at 0 0 90)
			(layer "F.SilkS")
			(hide yes)
			(effects
				(font
					(size 1.27 1.27)
				)
			)
		)
		(property "Value" ""
			(at 0 0 90)
			(layer "F.Fab")
			(effects
				(font
					(size 1.27 1.27)
				)
			)
		)
		(duplicate_pad_numbers_are_jumpers no)
		(fp_line
			(start 0.7874 -0.4064)
			(end 0.7874 0.4064)
			(stroke
				(width 0.1524)
				(type default)
			)
			(layer "F.SilkS")
		)
		(fp_line
			(start -0.7874 -0.4064)
			(end 0.7874 -0.4064)
			(stroke
				(width 0.1524)
				(type default)
			)
			(layer "F.SilkS")
		)
		(fp_line
			(start 0.7874 0.4064)
			(end -0.7874 0.4064)
			(stroke
				(width 0.1524)
				(type default)
			)
			(layer "F.SilkS")
		)
		(fp_line
			(start -0.7874 0.4064)
			(end -0.7874 -0.4064)
			(stroke
				(width 0.1524)
				(type default)
			)
			(layer "F.SilkS")
		)
		(fp_line
			(start -0.12065 -0.305054)
			(end -0.12065 -0.2794)
			(stroke
				(width 0.1)
				(type default)
			)
			(layer "F.Fab")
		)
		(fp_line
			(start -0.67945 -0.305054)
			(end -0.12065 -0.305054)
			(stroke
				(width 0.1)
				(type default)
			)
			(layer "F.Fab")
		)
		(fp_line
			(start 0.67945 -0.3048)
			(end 0.67945 0.3048)
			(stroke
				(width 0.1)
				(type default)
			)
			(layer "F.Fab")
		)
		(fp_line
			(start 0.12065 -0.3048)
			(end 0.67945 -0.3048)
			(stroke
				(width 0.1)
				(type default)
			)
			(layer "F.Fab")
		)
		(fp_line
			(start 0.12065 -0.2794)
			(end 0.12065 -0.3048)
			(stroke
				(width 0.1)
				(type default)
			)
			(layer "F.Fab")
		)
		(fp_line
			(start -0.12065 -0.2794)
			(end 0.12065 -0.2794)
			(stroke
				(width 0.1)
				(type default)
			)
			(layer "F.Fab")
		)
		(fp_line
			(start 0.120396 0.2794)
			(end -0.12065 0.2794)
			(stroke
				(width 0.1)
				(type default)
			)
			(layer "F.Fab")
		)
		(fp_line
			(start -0.12065 0.2794)
			(end -0.12065 0.3048)
			(stroke
				(width 0.1)
				(type default)
			)
			(layer "F.Fab")
		)
		(fp_line
			(start 0.67945 0.3048)
			(end 0.120396 0.3048)
			(stroke
				(width 0.1)
				(type default)
			)
			(layer "F.Fab")
		)
		(fp_line
			(start 0.120396 0.3048)
			(end 0.120396 0.2794)
			(stroke
				(width 0.1)
				(type default)
			)
			(layer "F.Fab")
		)
		(fp_line
			(start -0.12065 0.3048)
			(end -0.67945 0.3048)
			(stroke
				(width 0.1)
				(type default)
			)
			(layer "F.Fab")
		)
		(fp_line
			(start -0.67945 0.3048)
			(end -0.67945 -0.305054)
			(stroke
				(width 0.1)
				(type default)
			)
			(layer "F.Fab")
		)
		(pad "1" smd circle
			(at -0.40005 0 90)
			(size 0 0)
			(layers "F.Cu" "F.Mask" "F.Paste")
			(net "P3V3_AUX")
		)
		(pad "2" smd circle
			(at 0.40005 0 90)
			(size 0 0)
			(layers "F.Cu" "F.Mask" "F.Paste")
			(net "GPU_3V3IO_RSVD1_ISO")
		)
	)
	(footprint ""
		(layer "F.Cu")
		(at 66.372994 -36.800028)
		(property "Reference" "R6060"
			(at 0 0 0)
			(layer "F.SilkS")
			(hide yes)
			(effects
				(font
					(size 1.27 1.27)
				)
			)
		)
		(property "Value" ""
			(at 0 0 0)
			(layer "F.Fab")
			(effects
				(font
					(size 1.27 1.27)
				)
			)
		)
		(duplicate_pad_numbers_are_jumpers no)
		(fp_line
			(start -0.7874 -0.4064)
			(end 0.7874 -0.4064)
			(stroke
				(width 0.1524)
				(type default)
			)
			(layer "F.SilkS")
		)
		(fp_line
			(start -0.7874 0.4064)
			(end -0.7874 -0.4064)
			(stroke
				(width 0.1524)
				(type default)
			)
			(layer "F.SilkS")
		)
		(fp_line
			(start 0.7874 -0.4064)
			(end 0.7874 0.4064)
			(stroke
				(width 0.1524)
				(type default)
			)
			(layer "F.SilkS")
		)
		(fp_line
			(start 0.7874 0.4064)
			(end -0.7874 0.4064)
			(stroke
				(width 0.1524)
				(type default)
			)
			(layer "F.SilkS")
		)
		(fp_line
			(start -0.67945 -0.305054)
			(end -0.12065 -0.305054)
			(stroke
				(width 0.1)
				(type default)
			)
			(layer "F.Fab")
		)
		(fp_line
			(start -0.67945 0.3048)
			(end -0.67945 -0.305054)
			(stroke
				(width 0.1)
				(type default)
			)
			(layer "F.Fab")
		)
		(fp_line
			(start -0.12065 -0.305054)
			(end -0.12065 -0.2794)
			(stroke
				(width 0.1)
				(type default)
			)
			(layer "F.Fab")
		)
		(fp_line
			(start -0.12065 -0.2794)
			(end 0.12065 -0.2794)
			(stroke
				(width 0.1)
				(type default)
			)
			(layer "F.Fab")
		)
		(fp_line
			(start -0.12065 0.2794)
			(end -0.12065 0.3048)
			(stroke
				(width 0.1)
				(type default)
			)
			(layer "F.Fab")
		)
		(fp_line
			(start -0.12065 0.3048)
			(end -0.67945 0.3048)
			(stroke
				(width 0.1)
				(type default)
			)
			(layer "F.Fab")
		)
		(fp_line
			(start 0.120396 0.2794)
			(end -0.12065 0.2794)
			(stroke
				(width 0.1)
				(type default)
			)
			(layer "F.Fab")
		)
		(fp_line
			(start 0.120396 0.3048)
			(end 0.120396 0.2794)
			(stroke
				(width 0.1)
				(type default)
			)
			(layer "F.Fab")
		)
		(fp_line
			(start 0.12065 -0.3048)
			(end 0.67945 -0.3048)
			(stroke
				(width 0.1)
				(type default)
			)
			(layer "F.Fab")
		)
		(fp_line
			(start 0.12065 -0.2794)
			(end 0.12065 -0.3048)
			(stroke
				(width 0.1)
				(type default)
			)
			(layer "F.Fab")
		)
		(fp_line
			(start 0.67945 -0.3048)
			(end 0.67945 0.3048)
			(stroke
				(width 0.1)
				(type default)
			)
			(layer "F.Fab")
		)
		(fp_line
			(start 0.67945 0.3048)
			(end 0.120396 0.3048)
			(stroke
				(width 0.1)
				(type default)
			)
			(layer "F.Fab")
		)
		(pad "1" smd circle
			(at -0.40005 0)
			(size 0 0)
			(layers "F.Cu" "F.Mask" "F.Paste")
			(net "P12V_OCP_EN_2_R")
		)
		(pad "2" smd circle
			(at 0.40005 0)
			(size 0 0)
			(layers "F.Cu" "F.Mask" "F.Paste")
			(net "GND")
		)
	)
	(footprint ""
		(layer "F.Cu")
		(at 343.43086 -325.670926)
		(property "Reference" "PL15"
			(at -3.115056 -16.014446 0)
			(unlocked yes)
			(layer "F.SilkS")
			(effects
				(font
					(size 0.7874 0.5842)
					(thickness 0.1524)
				)
				(justify left)
			)
		)
		(property "Value" ""
			(at 0 0 0)
			(layer "F.Fab")
			(effects
				(font
					(size 1.27 1.27)
				)
			)
		)
		(duplicate_pad_numbers_are_jumpers no)
		(fp_line
			(start -3.750056 -5.500116)
			(end -2.393442 -5.500116)
			(stroke
				(width 0.1524)
				(type default)
			)
			(layer "F.SilkS")
		)
		(fp_line
			(start -3.750056 5.500116)
			(end -3.750056 -5.500116)
			(stroke
				(width 0.1524)
				(type default)
			)
			(layer "F.SilkS")
		)
		(fp_line
			(start -2.393442 5.500116)
			(end -3.750056 5.500116)
			(stroke
				(width 0.1524)
				(type default)
			)
			(layer "F.SilkS")
		)
		(fp_line
			(start 2.393442 5.500116)
			(end 3.750056 5.500116)
			(stroke
				(width 0.1524)
				(type default)
			)
			(layer "F.SilkS")
		)
		(fp_line
			(start 3.750056 -5.500116)
			(end 2.393442 -5.500116)
			(stroke
				(width 0.1524)
				(type default)
			)
			(layer "F.SilkS")
		)
		(fp_line
			(start 3.750056 5.500116)
			(end 3.750056 -5.500116)
			(stroke
				(width 0.1524)
				(type default)
			)
			(layer "F.SilkS")
		)
		(fp_poly
			(pts
				(xy -3.9116 -4.249928) (xy -4.3434 -4.034028) (xy -4.3434 -4.465828)
			)
			(stroke
				(width 0)
				(type default)
			)
			(fill yes)
			(layer "F.SilkS")
		)
		(fp_line
			(start -3.750056 -5.500116)
			(end -3.750056 5.500116)
			(stroke
				(width 0.1)
				(type default)
			)
			(layer "F.Fab")
		)
		(fp_line
			(start -3.750056 5.500116)
			(end 3.750056 5.500116)
			(stroke
				(width 0.1)
				(type default)
			)
			(layer "F.Fab")
		)
		(fp_line
			(start 3.750056 -5.500116)
			(end -3.750056 -5.500116)
			(stroke
				(width 0.1)
				(type default)
			)
			(layer "F.Fab")
		)
		(fp_line
			(start 3.750056 5.500116)
			(end 3.750056 -5.500116)
			(stroke
				(width 0.1)
				(type default)
			)
			(layer "F.Fab")
		)
		(fp_poly
			(pts
				(xy -4.9276 -4.757928) (xy -4.9276 -3.741928) (xy -3.9116 -4.249928)
			)
			(stroke
				(width 0)
				(type default)
			)
			(fill yes)
			(layer "F.Fab")
		)
		(pad "1" smd rect
			(at 0 -4.249928 270)
			(size 2.413 4.5212)
			(layers "F.Cu" "F.Mask" "F.Paste")
			(net "SW_PVDDCR_CPU1_P0_SW5")
		)
		(pad "2" smd rect
			(at 0 -1.175004 270)
			(size 1.3716 4.5212)
			(layers "F.Cu" "F.Mask" "F.Paste")
			(net "IND_CPU1_P0_CPL6")
		)
		(pad "3" smd rect
			(at 0 1.175004 270)
			(size 1.3716 4.5212)
			(layers "F.Cu" "F.Mask" "F.Paste")
			(net "IND_CPU1_P0_CPL5")
		)
		(pad "4" smd rect
			(at 0 4.249928 270)
			(size 2.413 4.5212)
			(layers "F.Cu" "F.Mask" "F.Paste")
			(net "PVDDCR_CPU1_P0")
		)
	)
	(footprint ""
		(layer "F.Cu")
		(at 267.869924 -419.648386 -90)
		(property "Reference" "U290"
			(at 3.294888 1.383538 0)
			(unlocked yes)
			(layer "F.SilkS")
			(effects
				(font
					(size 0.7874 0.5842)
					(thickness 0.1524)
				)
				(justify left)
			)
		)
		(property "Value" ""
			(at 0 0 270)
			(layer "F.Fab")
			(effects
				(font
					(size 1.27 1.27)
				)
			)
		)
		(duplicate_pad_numbers_are_jumpers no)
		(fp_line
			(start -1.603248 1.500124)
			(end -1.603248 -1.500124)
			(stroke
				(width 0.1524)
				(type default)
			)
			(layer "F.SilkS")
		)
		(fp_line
			(start 1.603248 1.500124)
			(end -1.603248 1.500124)
			(stroke
				(width 0.1524)
				(type default)
			)
			(layer "F.SilkS")
		)
		(fp_line
			(start -1.603248 -1.500124)
			(end 1.603248 -1.500124)
			(stroke
				(width 0.1524)
				(type default)
			)
			(layer "F.SilkS")
		)
		(fp_line
			(start 1.603248 -1.500124)
			(end 1.603248 1.500124)
			(stroke
				(width 0.1524)
				(type default)
			)
			(layer "F.SilkS")
		)
		(fp_line
			(start -0.700024 1.500124)
			(end 0.700024 1.500124)
			(stroke
				(width 0.1)
				(type default)
			)
			(layer "F.Fab")
		)
		(fp_line
			(start 0.700024 1.500124)
			(end 0.700024 0.219964)
			(stroke
				(width 0.1)
				(type default)
			)
			(layer "F.Fab")
		)
		(fp_line
			(start -1.249934 1.169924)
			(end -0.700024 1.169924)
			(stroke
				(width 0.1)
				(type default)
			)
			(layer "F.Fab")
		)
		(fp_line
			(start -0.700024 1.169924)
			(end -0.700024 1.500124)
			(stroke
				(width 0.1)
				(type default)
			)
			(layer "F.Fab")
		)
		(fp_line
			(start -1.249934 0.729996)
			(end -1.249934 1.169924)
			(stroke
				(width 0.1)
				(type default)
			)
			(layer "F.Fab")
		)
		(fp_line
			(start -0.6985 0.729996)
			(end -1.249934 0.729996)
			(stroke
				(width 0.1)
				(type default)
			)
			(layer "F.Fab")
		)
		(fp_line
			(start 0.700024 0.219964)
			(end 1.249934 0.219964)
			(stroke
				(width 0.1)
				(type default)
			)
			(layer "F.Fab")
		)
		(fp_line
			(start 1.249934 0.219964)
			(end 1.249934 -0.219964)
			(stroke
				(width 0.1)
				(type default)
			)
			(layer "F.Fab")
		)
		(fp_line
			(start 0.700024 -0.219964)
			(end 0.700024 -1.500124)
			(stroke
				(width 0.1)
				(type default)
			)
			(layer "F.Fab")
		)
		(fp_line
			(start 1.249934 -0.219964)
			(end 0.700024 -0.219964)
			(stroke
				(width 0.1)
				(type default)
			)
			(layer "F.Fab")
		)
		(fp_line
			(start -1.249934 -0.729996)
			(end -0.6985 -0.729996)
			(stroke
				(width 0.1)
				(type default)
			)
			(layer "F.Fab")
		)
		(fp_line
			(start -0.6985 -0.729996)
			(end -0.6985 0.729996)
			(stroke
				(width 0.1)
				(type default)
			)
			(layer "F.Fab")
		)
		(fp_line
			(start -1.249934 -1.169924)
			(end -1.249934 -0.729996)
			(stroke
				(width 0.1)
				(type default)
			)
			(layer "F.Fab")
		)
		(fp_line
			(start -0.700024 -1.169924)
			(end -1.249934 -1.169924)
			(stroke
				(width 0.1)
				(type default)
			)
			(layer "F.Fab")
		)
		(fp_line
			(start -0.700024 -1.500124)
			(end -0.700024 -1.169924)
			(stroke
				(width 0.1)
				(type default)
			)
			(layer "F.Fab")
		)
		(fp_line
			(start 0.700024 -1.500124)
			(end -0.700024 -1.500124)
			(stroke
				(width 0.1)
				(type default)
			)
			(layer "F.Fab")
		)
		(fp_rect
			(start -0.700024 1.500124)
			(end 0.700024 -1.500124)
			(stroke
				(width 0)
				(type default)
			)
			(fill no)
			(layer "F.Fab")
		)
		(pad "D" smd rect
			(at 0.999998 0 180)
			(size 0.8128 0.9144)
			(layers "F.Cu" "F.Mask" "F.Paste")
			(net "HSC_EN")
		)
		(pad "G" smd rect
			(at -0.999998 -0.94996 180)
			(size 0.8128 0.9144)
			(layers "F.Cu" "F.Mask" "F.Paste")
			(net "PDB_PRSNT_R_N")
		)
		(pad "S" smd rect
			(at -0.999998 0.94996 180)
			(size 0.8128 0.9144)
			(layers "F.Cu" "F.Mask" "F.Paste")
			(net "GND")
		)
	)
	(footprint ""
		(layer "F.Cu")
		(at 134.112 -109.855)
		(property "Reference" "R8117"
			(at 0 0 0)
			(layer "F.SilkS")
			(hide yes)
			(effects
				(font
					(size 1.27 1.27)
				)
			)
		)
		(property "Value" ""
			(at 0 0 0)
			(layer "F.Fab")
			(effects
				(font
					(size 1.27 1.27)
				)
			)
		)
		(duplicate_pad_numbers_are_jumpers no)
		(fp_line
			(start -0.7874 -0.4064)
			(end 0.7874 -0.4064)
			(stroke
				(width 0.1524)
				(type default)
			)
			(layer "F.SilkS")
		)
		(fp_line
			(start -0.7874 0.4064)
			(end -0.7874 -0.4064)
			(stroke
				(width 0.1524)
				(type default)
			)
			(layer "F.SilkS")
		)
		(fp_line
			(start 0.7874 -0.4064)
			(end 0.7874 0.4064)
			(stroke
				(width 0.1524)
				(type default)
			)
			(layer "F.SilkS")
		)
		(fp_line
			(start 0.7874 0.4064)
			(end -0.7874 0.4064)
			(stroke
				(width 0.1524)
				(type default)
			)
			(layer "F.SilkS")
		)
		(fp_line
			(start -0.67945 -0.305054)
			(end -0.12065 -0.305054)
			(stroke
				(width 0.1)
				(type default)
			)
			(layer "F.Fab")
		)
		(fp_line
			(start -0.67945 0.3048)
			(end -0.67945 -0.305054)
			(stroke
				(width 0.1)
				(type default)
			)
			(layer "F.Fab")
		)
		(fp_line
			(start -0.12065 -0.305054)
			(end -0.12065 -0.2794)
			(stroke
				(width 0.1)
				(type default)
			)
			(layer "F.Fab")
		)
		(fp_line
			(start -0.12065 -0.2794)
			(end 0.12065 -0.2794)
			(stroke
				(width 0.1)
				(type default)
			)
			(layer "F.Fab")
		)
		(fp_line
			(start -0.12065 0.2794)
			(end -0.12065 0.3048)
			(stroke
				(width 0.1)
				(type default)
			)
			(layer "F.Fab")
		)
		(fp_line
			(start -0.12065 0.3048)
			(end -0.67945 0.3048)
			(stroke
				(width 0.1)
				(type default)
			)
			(layer "F.Fab")
		)
		(fp_line
			(start 0.120396 0.2794)
			(end -0.12065 0.2794)
			(stroke
				(width 0.1)
				(type default)
			)
			(layer "F.Fab")
		)
		(fp_line
			(start 0.120396 0.3048)
			(end 0.120396 0.2794)
			(stroke
				(width 0.1)
				(type default)
			)
			(layer "F.Fab")
		)
		(fp_line
			(start 0.12065 -0.3048)
			(end 0.67945 -0.3048)
			(stroke
				(width 0.1)
				(type default)
			)
			(layer "F.Fab")
		)
		(fp_line
			(start 0.12065 -0.2794)
			(end 0.12065 -0.3048)
			(stroke
				(width 0.1)
				(type default)
			)
			(layer "F.Fab")
		)
		(fp_line
			(start 0.67945 -0.3048)
			(end 0.67945 0.3048)
			(stroke
				(width 0.1)
				(type default)
			)
			(layer "F.Fab")
		)
		(fp_line
			(start 0.67945 0.3048)
			(end 0.120396 0.3048)
			(stroke
				(width 0.1)
				(type default)
			)
			(layer "F.Fab")
		)
		(pad "1" smd circle
			(at -0.40005 0)
			(size 0 0)
			(layers "F.Cu" "F.Mask" "F.Paste")
			(net "P12V_AUX_UV_ADR_TRIGGER")
		)
		(pad "2" smd circle
			(at 0.40005 0)
			(size 0 0)
			(layers "F.Cu" "F.Mask" "F.Paste")
			(net "FM_UV_ADR_TRIGGER_N_R2")
		)
	)
	(footprint ""
		(layer "F.Cu")
		(at 393.762484 -393.47648 180)
		(property "Reference" "L30"
			(at 0 0 180)
			(layer "F.SilkS")
			(hide yes)
			(effects
				(font
					(size 1.27 1.27)
				)
			)
		)
		(property "Value" ""
			(at 0 0 180)
			(layer "F.Fab")
			(effects
				(font
					(size 1.27 1.27)
				)
			)
		)
		(duplicate_pad_numbers_are_jumpers no)
		(fp_line
			(start 0.762 0.381)
			(end -0.762 0.381)
			(stroke
				(width 0.1524)
				(type default)
			)
			(layer "F.SilkS")
		)
		(fp_line
			(start 0.762 -0.381)
			(end 0.762 0.381)
			(stroke
				(width 0.1524)
				(type default)
			)
			(layer "F.SilkS")
		)
		(fp_line
			(start -0.762 0.381)
			(end -0.762 -0.381)
			(stroke
				(width 0.1524)
				(type default)
			)
			(layer "F.SilkS")
		)
		(fp_line
			(start -0.762 -0.381)
			(end 0.762 -0.381)
			(stroke
				(width 0.1524)
				(type default)
			)
			(layer "F.SilkS")
		)
		(fp_line
			(start 0.680466 0.306324)
			(end 0.118364 0.306324)
			(stroke
				(width 0.1)
				(type default)
			)
			(layer "F.Fab")
		)
		(fp_line
			(start 0.680466 -0.306324)
			(end 0.680466 0.306324)
			(stroke
				(width 0.1)
				(type default)
			)
			(layer "F.Fab")
		)
		(fp_line
			(start 0.118872 -0.2794)
			(end 0.118872 -0.306324)
			(stroke
				(width 0.1)
				(type default)
			)
			(layer "F.Fab")
		)
		(fp_line
			(start 0.118872 -0.306324)
			(end 0.680466 -0.306324)
			(stroke
				(width 0.1)
				(type default)
			)
			(layer "F.Fab")
		)
		(fp_line
			(start 0.118364 0.306324)
			(end 0.118364 0.2794)
			(stroke
				(width 0.1)
				(type default)
			)
			(layer "F.Fab")
		)
		(fp_line
			(start 0.118364 0.2794)
			(end -0.119634 0.2794)
			(stroke
				(width 0.1)
				(type default)
			)
			(layer "F.Fab")
		)
		(fp_line
			(start -0.118364 -0.2794)
			(end 0.118872 -0.2794)
			(stroke
				(width 0.1)
				(type default)
			)
			(layer "F.Fab")
		)
		(fp_line
			(start -0.118364 -0.307086)
			(end -0.118364 -0.2794)
			(stroke
				(width 0.1)
				(type default)
			)
			(layer "F.Fab")
		)
		(fp_line
			(start -0.119634 0.30607)
			(end -0.681736 0.30607)
			(stroke
				(width 0.1)
				(type default)
			)
			(layer "F.Fab")
		)
		(fp_line
			(start -0.119634 0.2794)
			(end -0.119634 0.30607)
			(stroke
				(width 0.1)
				(type default)
			)
			(layer "F.Fab")
		)
		(fp_line
			(start -0.681736 0.30607)
			(end -0.681736 -0.307086)
			(stroke
				(width 0.1)
				(type default)
			)
			(layer "F.Fab")
		)
		(fp_line
			(start -0.681736 -0.307086)
			(end -0.118364 -0.307086)
			(stroke
				(width 0.1)
				(type default)
			)
			(layer "F.Fab")
		)
		(pad "1" smd rect
			(at -0.40005 0)
			(size 0.4572 0.508)
			(layers "F.Cu" "F.Mask" "F.Paste")
			(net "P1V8_CPU0_RT_1D")
		)
		(pad "2" smd rect
			(at 0.40005 0)
			(size 0.4572 0.508)
			(layers "F.Cu" "F.Mask" "F.Paste")
			(net "P1V8_CPU0_RT3_1A_1D")
		)
	)
	(footprint ""
		(layer "F.Cu")
		(at 68.961 -54.61)
		(property "Reference" "R1178"
			(at 0 0 0)
			(layer "F.SilkS")
			(hide yes)
			(effects
				(font
					(size 1.27 1.27)
				)
			)
		)
		(property "Value" ""
			(at 0 0 0)
			(layer "F.Fab")
			(effects
				(font
					(size 1.27 1.27)
				)
			)
		)
		(duplicate_pad_numbers_are_jumpers no)
		(fp_line
			(start -0.7874 -0.4064)
			(end 0.7874 -0.4064)
			(stroke
				(width 0.1524)
				(type default)
			)
			(layer "F.SilkS")
		)
		(fp_line
			(start -0.7874 0.4064)
			(end -0.7874 -0.4064)
			(stroke
				(width 0.1524)
				(type default)
			)
			(layer "F.SilkS")
		)
		(fp_line
			(start 0.7874 -0.4064)
			(end 0.7874 0.4064)
			(stroke
				(width 0.1524)
				(type default)
			)
			(layer "F.SilkS")
		)
		(fp_line
			(start 0.7874 0.4064)
			(end -0.7874 0.4064)
			(stroke
				(width 0.1524)
				(type default)
			)
			(layer "F.SilkS")
		)
		(fp_line
			(start -0.67945 -0.305054)
			(end -0.12065 -0.305054)
			(stroke
				(width 0.1)
				(type default)
			)
			(layer "F.Fab")
		)
		(fp_line
			(start -0.67945 0.3048)
			(end -0.67945 -0.305054)
			(stroke
				(width 0.1)
				(type default)
			)
			(layer "F.Fab")
		)
		(fp_line
			(start -0.12065 -0.305054)
			(end -0.12065 -0.2794)
			(stroke
				(width 0.1)
				(type default)
			)
			(layer "F.Fab")
		)
		(fp_line
			(start -0.12065 -0.2794)
			(end 0.12065 -0.2794)
			(stroke
				(width 0.1)
				(type default)
			)
			(layer "F.Fab")
		)
		(fp_line
			(start -0.12065 0.2794)
			(end -0.12065 0.3048)
			(stroke
				(width 0.1)
				(type default)
			)
			(layer "F.Fab")
		)
		(fp_line
			(start -0.12065 0.3048)
			(end -0.67945 0.3048)
			(stroke
				(width 0.1)
				(type default)
			)
			(layer "F.Fab")
		)
		(fp_line
			(start 0.120396 0.2794)
			(end -0.12065 0.2794)
			(stroke
				(width 0.1)
				(type default)
			)
			(layer "F.Fab")
		)
		(fp_line
			(start 0.120396 0.3048)
			(end 0.120396 0.2794)
			(stroke
				(width 0.1)
				(type default)
			)
			(layer "F.Fab")
		)
		(fp_line
			(start 0.12065 -0.3048)
			(end 0.67945 -0.3048)
			(stroke
				(width 0.1)
				(type default)
			)
			(layer "F.Fab")
		)
		(fp_line
			(start 0.12065 -0.2794)
			(end 0.12065 -0.3048)
			(stroke
				(width 0.1)
				(type default)
			)
			(layer "F.Fab")
		)
		(fp_line
			(start 0.67945 -0.3048)
			(end 0.67945 0.3048)
			(stroke
				(width 0.1)
				(type default)
			)
			(layer "F.Fab")
		)
		(fp_line
			(start 0.67945 0.3048)
			(end 0.120396 0.3048)
			(stroke
				(width 0.1)
				(type default)
			)
			(layer "F.Fab")
		)
		(pad "1" smd circle
			(at -0.40005 0)
			(size 0 0)
			(layers "F.Cu" "F.Mask" "F.Paste")
			(net "OCP_V3_2_P3V3_R3_PWRGD")
		)
		(pad "2" smd circle
			(at 0.40005 0)
			(size 0 0)
			(layers "F.Cu" "F.Mask" "F.Paste")
			(net "HP_LVC3_OCP_V3_2_PWRGD_R1")
		)
	)
	(footprint ""
		(layer "F.Cu")
		(at 120.395238 -41.17975 -90)
		(property "Reference" "R6279"
			(at 0 0 270)
			(layer "F.SilkS")
			(hide yes)
			(effects
				(font
					(size 1.27 1.27)
				)
			)
		)
		(property "Value" ""
			(at 0 0 270)
			(layer "F.Fab")
			(effects
				(font
					(size 1.27 1.27)
				)
			)
		)
		(duplicate_pad_numbers_are_jumpers no)
		(fp_line
			(start -0.7874 0.4064)
			(end -0.7874 -0.4064)
			(stroke
				(width 0.1524)
				(type default)
			)
			(layer "F.SilkS")
		)
		(fp_line
			(start 0.7874 0.4064)
			(end -0.7874 0.4064)
			(stroke
				(width 0.1524)
				(type default)
			)
			(layer "F.SilkS")
		)
		(fp_line
			(start -0.7874 -0.4064)
			(end 0.7874 -0.4064)
			(stroke
				(width 0.1524)
				(type default)
			)
			(layer "F.SilkS")
		)
		(fp_line
			(start 0.7874 -0.4064)
			(end 0.7874 0.4064)
			(stroke
				(width 0.1524)
				(type default)
			)
			(layer "F.SilkS")
		)
		(fp_line
			(start -0.67945 0.3048)
			(end -0.67945 -0.305054)
			(stroke
				(width 0.1)
				(type default)
			)
			(layer "F.Fab")
		)
		(fp_line
			(start -0.12065 0.3048)
			(end -0.67945 0.3048)
			(stroke
				(width 0.1)
				(type default)
			)
			(layer "F.Fab")
		)
		(fp_line
			(start 0.120396 0.3048)
			(end 0.120396 0.2794)
			(stroke
				(width 0.1)
				(type default)
			)
			(layer "F.Fab")
		)
		(fp_line
			(start 0.67945 0.3048)
			(end 0.120396 0.3048)
			(stroke
				(width 0.1)
				(type default)
			)
			(layer "F.Fab")
		)
		(fp_line
			(start -0.12065 0.2794)
			(end -0.12065 0.3048)
			(stroke
				(width 0.1)
				(type default)
			)
			(layer "F.Fab")
		)
		(fp_line
			(start 0.120396 0.2794)
			(end -0.12065 0.2794)
			(stroke
				(width 0.1)
				(type default)
			)
			(layer "F.Fab")
		)
		(fp_line
			(start -0.12065 -0.2794)
			(end 0.12065 -0.2794)
			(stroke
				(width 0.1)
				(type default)
			)
			(layer "F.Fab")
		)
		(fp_line
			(start 0.12065 -0.2794)
			(end 0.12065 -0.3048)
			(stroke
				(width 0.1)
				(type default)
			)
			(layer "F.Fab")
		)
		(fp_line
			(start 0.12065 -0.3048)
			(end 0.67945 -0.3048)
			(stroke
				(width 0.1)
				(type default)
			)
			(layer "F.Fab")
		)
		(fp_line
			(start 0.67945 -0.3048)
			(end 0.67945 0.3048)
			(stroke
				(width 0.1)
				(type default)
			)
			(layer "F.Fab")
		)
		(fp_line
			(start -0.67945 -0.305054)
			(end -0.12065 -0.305054)
			(stroke
				(width 0.1)
				(type default)
			)
			(layer "F.Fab")
		)
		(fp_line
			(start -0.12065 -0.305054)
			(end -0.12065 -0.2794)
			(stroke
				(width 0.1)
				(type default)
			)
			(layer "F.Fab")
		)
		(pad "1" smd circle
			(at -0.40005 0 270)
			(size 0 0)
			(layers "F.Cu" "F.Mask" "F.Paste")
			(net "SMB_USB_CPU0_HUB1_SDA")
		)
		(pad "2" smd circle
			(at 0.40005 0 270)
			(size 0 0)
			(layers "F.Cu" "F.Mask" "F.Paste")
			(net "SMB_USB_HUB2_TI_SDA_MRP_PRT_CTL2")
		)
	)
	(footprint ""
		(layer "F.Cu")
		(at 110.85703 -257.74523)
		(property "Reference" "C2427"
			(at 0 0 0)
			(layer "F.SilkS")
			(hide yes)
			(effects
				(font
					(size 1.27 1.27)
				)
			)
		)
		(property "Value" ""
			(at 0 0 0)
			(layer "F.Fab")
			(effects
				(font
					(size 1.27 1.27)
				)
			)
		)
		(duplicate_pad_numbers_are_jumpers no)
		(fp_line
			(start -0.7874 -0.4064)
			(end 0.7874 -0.4064)
			(stroke
				(width 0.1524)
				(type default)
			)
			(layer "F.SilkS")
		)
		(fp_line
			(start -0.7874 0.4064)
			(end -0.7874 -0.4064)
			(stroke
				(width 0.1524)
				(type default)
			)
			(layer "F.SilkS")
		)
		(fp_line
			(start 0.7874 -0.4064)
			(end 0.7874 0.4064)
			(stroke
				(width 0.1524)
				(type default)
			)
			(layer "F.SilkS")
		)
		(fp_line
			(start 0.7874 0.4064)
			(end -0.7874 0.4064)
			(stroke
				(width 0.1524)
				(type default)
			)
			(layer "F.SilkS")
		)
		(fp_line
			(start -0.67945 -0.305054)
			(end -0.12065 -0.305054)
			(stroke
				(width 0.1)
				(type default)
			)
			(layer "F.Fab")
		)
		(fp_line
			(start -0.67945 0.3048)
			(end -0.67945 -0.305054)
			(stroke
				(width 0.1)
				(type default)
			)
			(layer "F.Fab")
		)
		(fp_line
			(start -0.12065 -0.305054)
			(end -0.12065 -0.2794)
			(stroke
				(width 0.1)
				(type default)
			)
			(layer "F.Fab")
		)
		(fp_line
			(start -0.12065 -0.2794)
			(end 0.12065 -0.2794)
			(stroke
				(width 0.1)
				(type default)
			)
			(layer "F.Fab")
		)
		(fp_line
			(start -0.12065 0.2794)
			(end -0.12065 0.3048)
			(stroke
				(width 0.1)
				(type default)
			)
			(layer "F.Fab")
		)
		(fp_line
			(start -0.12065 0.3048)
			(end -0.67945 0.3048)
			(stroke
				(width 0.1)
				(type default)
			)
			(layer "F.Fab")
		)
		(fp_line
			(start 0.120396 0.2794)
			(end -0.12065 0.2794)
			(stroke
				(width 0.1)
				(type default)
			)
			(layer "F.Fab")
		)
		(fp_line
			(start 0.120396 0.3048)
			(end 0.120396 0.2794)
			(stroke
				(width 0.1)
				(type default)
			)
			(layer "F.Fab")
		)
		(fp_line
			(start 0.12065 -0.3048)
			(end 0.67945 -0.3048)
			(stroke
				(width 0.1)
				(type default)
			)
			(layer "F.Fab")
		)
		(fp_line
			(start 0.12065 -0.2794)
			(end 0.12065 -0.3048)
			(stroke
				(width 0.1)
				(type default)
			)
			(layer "F.Fab")
		)
		(fp_line
			(start 0.67945 -0.3048)
			(end 0.67945 0.3048)
			(stroke
				(width 0.1)
				(type default)
			)
			(layer "F.Fab")
		)
		(fp_line
			(start 0.67945 0.3048)
			(end 0.120396 0.3048)
			(stroke
				(width 0.1)
				(type default)
			)
			(layer "F.Fab")
		)
		(pad "1" smd circle
			(at -0.40005 0)
			(size 0 0)
			(layers "F.Cu" "F.Mask" "F.Paste")
			(net "PVDDCR_SOC_P1")
		)
		(pad "2" smd circle
			(at 0.40005 0)
			(size 0 0)
			(layers "F.Cu" "F.Mask" "F.Paste")
			(net "GND")
		)
	)
	(footprint ""
		(layer "F.Cu")
		(at 257.242056 -125.38837 180)
		(property "Reference" "R3709"
			(at 0 0 180)
			(layer "F.SilkS")
			(hide yes)
			(effects
				(font
					(size 1.27 1.27)
				)
			)
		)
		(property "Value" ""
			(at 0 0 180)
			(layer "F.Fab")
			(effects
				(font
					(size 1.27 1.27)
				)
			)
		)
		(duplicate_pad_numbers_are_jumpers no)
		(fp_line
			(start 0.7874 0.4064)
			(end -0.7874 0.4064)
			(stroke
				(width 0.1524)
				(type default)
			)
			(layer "F.SilkS")
		)
		(fp_line
			(start 0.7874 -0.4064)
			(end 0.7874 0.4064)
			(stroke
				(width 0.1524)
				(type default)
			)
			(layer "F.SilkS")
		)
		(fp_line
			(start -0.7874 0.4064)
			(end -0.7874 -0.4064)
			(stroke
				(width 0.1524)
				(type default)
			)
			(layer "F.SilkS")
		)
		(fp_line
			(start -0.7874 -0.4064)
			(end 0.7874 -0.4064)
			(stroke
				(width 0.1524)
				(type default)
			)
			(layer "F.SilkS")
		)
		(fp_line
			(start 0.67945 0.3048)
			(end 0.120396 0.3048)
			(stroke
				(width 0.1)
				(type default)
			)
			(layer "F.Fab")
		)
		(fp_line
			(start 0.67945 -0.3048)
			(end 0.67945 0.3048)
			(stroke
				(width 0.1)
				(type default)
			)
			(layer "F.Fab")
		)
		(fp_line
			(start 0.12065 -0.2794)
			(end 0.12065 -0.3048)
			(stroke
				(width 0.1)
				(type default)
			)
			(layer "F.Fab")
		)
		(fp_line
			(start 0.12065 -0.3048)
			(end 0.67945 -0.3048)
			(stroke
				(width 0.1)
				(type default)
			)
			(layer "F.Fab")
		)
		(fp_line
			(start 0.120396 0.3048)
			(end 0.120396 0.2794)
			(stroke
				(width 0.1)
				(type default)
			)
			(layer "F.Fab")
		)
		(fp_line
			(start 0.120396 0.2794)
			(end -0.12065 0.2794)
			(stroke
				(width 0.1)
				(type default)
			)
			(layer "F.Fab")
		)
		(fp_line
			(start -0.12065 0.3048)
			(end -0.67945 0.3048)
			(stroke
				(width 0.1)
				(type default)
			)
			(layer "F.Fab")
		)
		(fp_line
			(start -0.12065 0.2794)
			(end -0.12065 0.3048)
			(stroke
				(width 0.1)
				(type default)
			)
			(layer "F.Fab")
		)
		(fp_line
			(start -0.12065 -0.2794)
			(end 0.12065 -0.2794)
			(stroke
				(width 0.1)
				(type default)
			)
			(layer "F.Fab")
		)
		(fp_line
			(start -0.12065 -0.305054)
			(end -0.12065 -0.2794)
			(stroke
				(width 0.1)
				(type default)
			)
			(layer "F.Fab")
		)
		(fp_line
			(start -0.67945 0.3048)
			(end -0.67945 -0.305054)
			(stroke
				(width 0.1)
				(type default)
			)
			(layer "F.Fab")
		)
		(fp_line
			(start -0.67945 -0.305054)
			(end -0.12065 -0.305054)
			(stroke
				(width 0.1)
				(type default)
			)
			(layer "F.Fab")
		)
		(pad "1" smd circle
			(at -0.40005 0 180)
			(size 0 0)
			(layers "F.Cu" "F.Mask" "F.Paste")
			(net "PCA9548_PCIE0_ADDR0")
		)
		(pad "2" smd circle
			(at 0.40005 0 180)
			(size 0 0)
			(layers "F.Cu" "F.Mask" "F.Paste")
			(net "GND")
		)
	)
	(footprint ""
		(layer "F.Cu")
		(at 72.175116 -172.974 90)
		(property "Reference" "PC314"
			(at 0 0 90)
			(layer "F.SilkS")
			(hide yes)
			(effects
				(font
					(size 1.27 1.27)
				)
			)
		)
		(property "Value" ""
			(at 0 0 90)
			(layer "F.Fab")
			(effects
				(font
					(size 1.27 1.27)
				)
			)
		)
		(duplicate_pad_numbers_are_jumpers no)
		(fp_line
			(start 0.7874 -0.4064)
			(end 0.7874 0.4064)
			(stroke
				(width 0.1524)
				(type default)
			)
			(layer "F.SilkS")
		)
		(fp_line
			(start -0.7874 -0.4064)
			(end 0.7874 -0.4064)
			(stroke
				(width 0.1524)
				(type default)
			)
			(layer "F.SilkS")
		)
		(fp_line
			(start 0.7874 0.4064)
			(end -0.7874 0.4064)
			(stroke
				(width 0.1524)
				(type default)
			)
			(layer "F.SilkS")
		)
		(fp_line
			(start -0.7874 0.4064)
			(end -0.7874 -0.4064)
			(stroke
				(width 0.1524)
				(type default)
			)
			(layer "F.SilkS")
		)
		(fp_line
			(start -0.12065 -0.305054)
			(end -0.12065 -0.2794)
			(stroke
				(width 0.1)
				(type default)
			)
			(layer "F.Fab")
		)
		(fp_line
			(start -0.67945 -0.305054)
			(end -0.12065 -0.305054)
			(stroke
				(width 0.1)
				(type default)
			)
			(layer "F.Fab")
		)
		(fp_line
			(start 0.67945 -0.3048)
			(end 0.67945 0.3048)
			(stroke
				(width 0.1)
				(type default)
			)
			(layer "F.Fab")
		)
		(fp_line
			(start 0.12065 -0.3048)
			(end 0.67945 -0.3048)
			(stroke
				(width 0.1)
				(type default)
			)
			(layer "F.Fab")
		)
		(fp_line
			(start 0.12065 -0.2794)
			(end 0.12065 -0.3048)
			(stroke
				(width 0.1)
				(type default)
			)
			(layer "F.Fab")
		)
		(fp_line
			(start -0.12065 -0.2794)
			(end 0.12065 -0.2794)
			(stroke
				(width 0.1)
				(type default)
			)
			(layer "F.Fab")
		)
		(fp_line
			(start 0.120396 0.2794)
			(end -0.12065 0.2794)
			(stroke
				(width 0.1)
				(type default)
			)
			(layer "F.Fab")
		)
		(fp_line
			(start -0.12065 0.2794)
			(end -0.12065 0.3048)
			(stroke
				(width 0.1)
				(type default)
			)
			(layer "F.Fab")
		)
		(fp_line
			(start 0.67945 0.3048)
			(end 0.120396 0.3048)
			(stroke
				(width 0.1)
				(type default)
			)
			(layer "F.Fab")
		)
		(fp_line
			(start 0.120396 0.3048)
			(end 0.120396 0.2794)
			(stroke
				(width 0.1)
				(type default)
			)
			(layer "F.Fab")
		)
		(fp_line
			(start -0.12065 0.3048)
			(end -0.67945 0.3048)
			(stroke
				(width 0.1)
				(type default)
			)
			(layer "F.Fab")
		)
		(fp_line
			(start -0.67945 0.3048)
			(end -0.67945 -0.305054)
			(stroke
				(width 0.1)
				(type default)
			)
			(layer "F.Fab")
		)
		(pad "1" smd circle
			(at -0.40005 0 90)
			(size 0 0)
			(layers "F.Cu" "F.Mask" "F.Paste")
			(net "SW_PVDDCR_CPU0_P1_BOOT5_RC")
		)
		(pad "2" smd circle
			(at 0.40005 0 90)
			(size 0 0)
			(layers "F.Cu" "F.Mask" "F.Paste")
			(net "SW_PVDDCR_CPU0_P1_PH5")
		)
	)
	(footprint ""
		(layer "F.Cu")
		(at 173.358302 -47.049944)
		(property "Reference" "J59"
			(at -4.4958 -11.852148 0)
			(unlocked yes)
			(layer "F.SilkS")
			(effects
				(font
					(size 0.7874 0.5842)
					(thickness 0.1524)
				)
				(justify left)
			)
		)
		(property "Value" ""
			(at 0 0 0)
			(layer "F.Fab")
			(effects
				(font
					(size 1.27 1.27)
				)
			)
		)
		(duplicate_pad_numbers_are_jumpers no)
		(fp_line
			(start -4.325112 -10.999978)
			(end 1.451102 -10.999978)
			(stroke
				(width 0.1524)
				(type default)
			)
			(layer "F.SilkS")
		)
		(fp_line
			(start -4.325112 -9.266682)
			(end -4.325112 -10.999978)
			(stroke
				(width 0.1524)
				(type default)
			)
			(layer "F.SilkS")
		)
		(fp_line
			(start -4.325112 7.233412)
			(end -4.325112 5.26669)
			(stroke
				(width 0.1524)
				(type default)
			)
			(layer "F.SilkS")
		)
		(fp_line
			(start -4.325112 10.999978)
			(end -4.325112 9.266682)
			(stroke
				(width 0.1524)
				(type default)
			)
			(layer "F.SilkS")
		)
		(fp_line
			(start -4.2037 6.34238)
			(end -3.1623 6.34238)
			(stroke
				(width 0.1524)
				(type default)
			)
			(layer "F.SilkS")
		)
		(fp_line
			(start -4.2037 6.34238)
			(end -3.1623 7.00278)
			(stroke
				(width 0.1524)
				(type default)
			)
			(layer "F.SilkS")
		)
		(fp_line
			(start -3.57505 -10.925048)
			(end -3.57505 -9.266682)
			(stroke
				(width 0.1524)
				(type default)
			)
			(layer "F.SilkS")
		)
		(fp_line
			(start -3.57505 5.26669)
			(end -3.57505 7.233412)
			(stroke
				(width 0.1524)
				(type default)
			)
			(layer "F.SilkS")
		)
		(fp_line
			(start -3.57505 9.266682)
			(end -3.57505 10.925048)
			(stroke
				(width 0.1524)
				(type default)
			)
			(layer "F.SilkS")
		)
		(fp_line
			(start -3.57505 10.925048)
			(end -2.2352 10.925048)
			(stroke
				(width 0.1524)
				(type default)
			)
			(layer "F.SilkS")
		)
		(fp_line
			(start -3.1623 6.34238)
			(end -3.1369 6.36778)
			(stroke
				(width 0.1524)
				(type default)
			)
			(layer "F.SilkS")
		)
		(fp_line
			(start -3.1623 6.34238)
			(end -1.0287 6.34238)
			(stroke
				(width 0.1524)
				(type default)
			)
			(layer "F.SilkS")
		)
		(fp_line
			(start -3.1623 7.00278)
			(end -3.1623 6.34238)
			(stroke
				(width 0.1524)
				(type default)
			)
			(layer "F.SilkS")
		)
		(fp_line
			(start -3.1369 5.73278)
			(end -4.2037 6.34238)
			(stroke
				(width 0.1524)
				(type default)
			)
			(layer "F.SilkS")
		)
		(fp_line
			(start -3.1369 6.36778)
			(end -3.1369 5.73278)
			(stroke
				(width 0.1524)
				(type default)
			)
			(layer "F.SilkS")
		)
		(fp_line
			(start -2.1082 10.999978)
			(end -4.325112 10.999978)
			(stroke
				(width 0.1524)
				(type default)
			)
			(layer "F.SilkS")
		)
		(fp_line
			(start -1.0287 4.181856)
			(end -1.6002 3.6576)
			(stroke
				(width 0.1524)
				(type default)
			)
			(layer "F.SilkS")
		)
		(fp_line
			(start -1.0287 6.34238)
			(end -1.0287 4.181856)
			(stroke
				(width 0.1524)
				(type default)
			)
			(layer "F.SilkS")
		)
		(fp_line
			(start -0.8128 10.925048)
			(end 1.451102 10.925048)
			(stroke
				(width 0.1524)
				(type default)
			)
			(layer "F.SilkS")
		)
		(fp_line
			(start 1.4478 10.999978)
			(end -0.9398 10.999978)
			(stroke
				(width 0.1524)
				(type default)
			)
			(layer "F.SilkS")
		)
		(fp_line
			(start 1.451102 -10.925048)
			(end -3.57505 -10.925048)
			(stroke
				(width 0.1524)
				(type default)
			)
			(layer "F.SilkS")
		)
		(fp_line
			(start 3.57505 6.983222)
			(end 3.57505 5.016754)
			(stroke
				(width 0.1524)
				(type default)
			)
			(layer "F.SilkS")
		)
		(fp_line
			(start 3.875024 5.016754)
			(end 3.875024 6.983222)
			(stroke
				(width 0.1524)
				(type default)
			)
			(layer "F.SilkS")
		)
		(fp_poly
			(pts
				(xy 4.699 -9.249918) (xy 5.715 -9.757918) (xy 5.715 -8.741918)
			)
			(stroke
				(width 0)
				(type default)
			)
			(fill yes)
			(layer "F.SilkS")
		)
		(fp_line
			(start -3.57505 -10.925048)
			(end -3.57505 10.925048)
			(stroke
				(width 0.1)
				(type default)
			)
			(layer "F.Fab")
		)
		(fp_line
			(start -3.57505 10.925048)
			(end 3.57505 10.925048)
			(stroke
				(width 0.1)
				(type default)
			)
			(layer "F.Fab")
		)
		(fp_line
			(start 3.57505 -10.925048)
			(end -3.57505 -10.925048)
			(stroke
				(width 0.1)
				(type default)
			)
			(layer "F.Fab")
		)
		(fp_line
			(start 3.57505 10.925048)
			(end 3.57505 -10.925048)
			(stroke
				(width 0.1)
				(type default)
			)
			(layer "F.Fab")
		)
		(fp_poly
			(pts
				(xy 5.715 -8.741918) (xy 5.715 -9.757918) (xy 4.699 -9.249918)
			)
			(stroke
				(width 0)
				(type default)
			)
			(fill yes)
			(layer "F.Fab")
		)
		(fp_text user "74"
			(at -5.853176 9.476486 270)
			(unlocked yes)
			(layer "F.SilkS")
			(effects
				(font
					(size 0.7874 0.5842)
					(thickness 0.1524)
				)
			)
		)
		(fp_text user "2"
			(at -5.350764 -8.999982 270)
			(unlocked yes)
			(layer "F.SilkS")
			(effects
				(font
					(size 0.7874 0.5842)
					(thickness 0.1524)
				)
			)
		)
		(fp_text user "58"
			(at -5.350764 4.74599 270)
			(unlocked yes)
			(layer "F.SilkS")
			(effects
				(font
					(size 0.7874 0.5842)
					(thickness 0.1524)
				)
			)
		)
		(fp_text user "68"
			(at -5.343652 7.0104 270)
			(unlocked yes)
			(layer "F.SilkS")
			(effects
				(font
					(size 0.7874 0.5842)
					(thickness 0.1524)
				)
			)
		)
		(fp_text user "CONNECTOR KEEPOUT ZONE"
			(at -2.186432 -7.366 270)
			(unlocked yes)
			(layer "F.SilkS")
			(effects
				(font
					(size 0.635 0.4064)
					(thickness 0.1524)
				)
				(justify left)
			)
		)
		(fp_text user "57"
			(at 5.247386 4.470654 270)
			(unlocked yes)
			(layer "F.SilkS")
			(effects
				(font
					(size 0.7874 0.5842)
					(thickness 0.1524)
				)
			)
		)
		(fp_text user "75"
			(at 5.248148 9.3472 270)
			(unlocked yes)
			(layer "F.SilkS")
			(effects
				(font
					(size 0.7874 0.5842)
					(thickness 0.1524)
				)
			)
		)
		(fp_text user "67"
			(at 5.273548 7.0358 270)
			(unlocked yes)
			(layer "F.SilkS")
			(effects
				(font
					(size 0.7874 0.5842)
					(thickness 0.1524)
				)
			)
		)
		(fp_text user "74"
			(at -5.369052 9.398 270)
			(unlocked yes)
			(layer "F.Fab")
			(effects
				(font
					(size 0.7874 0.5842)
					(thickness 0.1524)
				)
			)
		)
		(fp_text user "2"
			(at -5.350764 -8.999982 270)
			(unlocked yes)
			(layer "F.Fab")
			(effects
				(font
					(size 0.7874 0.5842)
					(thickness 0.1524)
				)
			)
		)
		(fp_text user "58"
			(at -5.350764 4.74599 270)
			(unlocked yes)
			(layer "F.Fab")
			(effects
				(font
					(size 0.7874 0.5842)
					(thickness 0.1524)
				)
			)
		)
		(fp_text user "68"
			(at -5.343652 7.0104 270)
			(unlocked yes)
			(layer "F.Fab")
			(effects
				(font
					(size 0.7874 0.5842)
					(thickness 0.1524)
				)
			)
		)
		(fp_text user "57"
			(at 5.247386 4.470654 270)
			(unlocked yes)
			(layer "F.Fab")
			(effects
				(font
					(size 0.7874 0.5842)
					(thickness 0.1524)
				)
			)
		)
		(fp_text user "75"
			(at 5.248148 9.3472 270)
			(unlocked yes)
			(layer "F.Fab")
			(effects
				(font
					(size 0.7874 0.5842)
					(thickness 0.1524)
				)
			)
		)
		(fp_text user "67"
			(at 5.273548 7.0358 270)
			(unlocked yes)
			(layer "F.Fab")
			(effects
				(font
					(size 0.7874 0.5842)
					(thickness 0.1524)
				)
			)
		)
		(pad "" np_thru_hole circle
			(at -1.525016 -9.99998 270)
			(size 1.1684 1.1684)
			(drill 1.1684)
			(layers "*.Cu" "*.Mask")
			(clearance 0.381)
			(thermal_gap 0.381)
		)
		(pad "" np_thru_hole circle
			(at -1.525016 9.99998 270)
			(size 1.651 1.651)
			(drill 1.651)
			(layers "*.Cu" "*.Mask")
			(clearance 0.381)
			(thermal_gap 0.381)
		)
		(pad "1" smd rect
			(at 3.750056 -9.249918 270)
			(size 0.2794 1.6002)
			(layers "F.Cu" "F.Mask" "F.Paste")
			(net "PCIE_M2_SSD0_PRSNT_N")
		)
		(pad "2" smd rect
			(at -3.800094 -8.999982 270)
			(size 0.2794 1.6002)
			(layers "F.Cu" "F.Mask" "F.Paste")
			(net "P3V3_M2_0")
		)
		(pad "3" smd rect
			(at 3.750056 -8.750046 270)
			(size 0.2794 1.6002)
			(layers "F.Cu" "F.Mask" "F.Paste")
			(net "GND")
		)
		(pad "4" smd rect
			(at -3.800094 -8.50011 270)
			(size 0.2794 1.6002)
			(layers "F.Cu" "F.Mask" "F.Paste")
			(net "P3V3_M2_0")
		)
		(pad "5" smd rect
			(at 3.750056 -8.24992 270)
			(size 0.2794 1.6002)
			(layers "F.Cu" "F.Mask" "F.Paste")
			(net "P3E_CPU1_P4_RX_DN<3>")
		)
		(pad "6" smd rect
			(at -3.800094 -7.999984 270)
			(size 0.2794 1.6002)
			(layers "F.Cu" "F.Mask" "F.Paste")
			(net "NC_M2_0_NC1")
		)
		(pad "7" smd rect
			(at 3.750056 -7.750048 270)
			(size 0.2794 1.6002)
			(layers "F.Cu" "F.Mask" "F.Paste")
			(net "P3E_CPU1_P4_RX_DP<3>")
		)
		(pad "8" smd rect
			(at -3.800094 -7.500112 270)
			(size 0.2794 1.6002)
			(layers "F.Cu" "F.Mask" "F.Paste")
			(net "NC_M2_0_NC2")
		)
		(pad "9" smd rect
			(at 3.750056 -7.249922 270)
			(size 0.2794 1.6002)
			(layers "F.Cu" "F.Mask" "F.Paste")
			(net "GND")
		)
		(pad "10" smd rect
			(at -3.800094 -6.999986 270)
			(size 0.2794 1.6002)
			(layers "F.Cu" "F.Mask" "F.Paste")
			(net "LED_M2_SSD_0_ACT_N")
		)
		(pad "11" smd rect
			(at 3.750056 -6.75005 270)
			(size 0.2794 1.6002)
			(layers "F.Cu" "F.Mask" "F.Paste")
			(net "P3E_CPU1_P4_TX_C_DN<3>")
		)
		(pad "12" smd rect
			(at -3.800094 -6.500114 270)
			(size 0.2794 1.6002)
			(layers "F.Cu" "F.Mask" "F.Paste")
			(net "P3V3_M2_0")
		)
		(pad "13" smd rect
			(at 3.750056 -6.249924 270)
			(size 0.2794 1.6002)
			(layers "F.Cu" "F.Mask" "F.Paste")
			(net "P3E_CPU1_P4_TX_C_DP<3>")
		)
		(pad "14" smd rect
			(at -3.800094 -5.999988 270)
			(size 0.2794 1.6002)
			(layers "F.Cu" "F.Mask" "F.Paste")
			(net "P3V3_M2_0")
		)
		(pad "15" smd rect
			(at 3.750056 -5.750052 270)
			(size 0.2794 1.6002)
			(layers "F.Cu" "F.Mask" "F.Paste")
			(net "GND")
		)
		(pad "16" smd rect
			(at -3.800094 -5.500116 270)
			(size 0.2794 1.6002)
			(layers "F.Cu" "F.Mask" "F.Paste")
			(net "P3V3_M2_0")
		)
		(pad "17" smd rect
			(at 3.750056 -5.249926 270)
			(size 0.2794 1.6002)
			(layers "F.Cu" "F.Mask" "F.Paste")
			(net "P3E_CPU1_P4_RX_DN<2>")
		)
		(pad "18" smd rect
			(at -3.800094 -4.99999 270)
			(size 0.2794 1.6002)
			(layers "F.Cu" "F.Mask" "F.Paste")
			(net "P3V3_M2_0")
		)
		(pad "19" smd rect
			(at 3.750056 -4.750054 270)
			(size 0.2794 1.6002)
			(layers "F.Cu" "F.Mask" "F.Paste")
			(net "P3E_CPU1_P4_RX_DP<2>")
		)
		(pad "20" smd rect
			(at -3.800094 -4.500118 270)
			(size 0.2794 1.6002)
			(layers "F.Cu" "F.Mask" "F.Paste")
			(net "NC_M2_0_NC3")
		)
		(pad "21" smd rect
			(at 3.750056 -4.249928 270)
			(size 0.2794 1.6002)
			(layers "F.Cu" "F.Mask" "F.Paste")
			(net "GND")
		)
		(pad "22" smd rect
			(at -3.800094 -3.999992 270)
			(size 0.2794 1.6002)
			(layers "F.Cu" "F.Mask" "F.Paste")
			(net "NC_M2_0_NC4")
		)
		(pad "23" smd rect
			(at 3.750056 -3.750056 270)
			(size 0.2794 1.6002)
			(layers "F.Cu" "F.Mask" "F.Paste")
			(net "P3E_CPU1_P4_TX_C_DN<2>")
		)
		(pad "24" smd rect
			(at -3.800094 -3.50012 270)
			(size 0.2794 1.6002)
			(layers "F.Cu" "F.Mask" "F.Paste")
			(net "NC_M2_0_NC5")
		)
		(pad "25" smd rect
			(at 3.750056 -3.24993 270)
			(size 0.2794 1.6002)
			(layers "F.Cu" "F.Mask" "F.Paste")
			(net "P3E_CPU1_P4_TX_C_DP<2>")
		)
		(pad "26" smd rect
			(at -3.800094 -2.999994 270)
			(size 0.2794 1.6002)
			(layers "F.Cu" "F.Mask" "F.Paste")
			(net "NC_M2_0_NC6")
		)
		(pad "27" smd rect
			(at 3.750056 -2.750058 270)
			(size 0.2794 1.6002)
			(layers "F.Cu" "F.Mask" "F.Paste")
			(net "GND")
		)
		(pad "28" smd rect
			(at -3.800094 -2.500122 270)
			(size 0.2794 1.6002)
			(layers "F.Cu" "F.Mask" "F.Paste")
			(net "NC_M2_0_NC7")
		)
		(pad "29" smd rect
			(at 3.750056 -2.249932 270)
			(size 0.2794 1.6002)
			(layers "F.Cu" "F.Mask" "F.Paste")
			(net "P3E_CPU1_P4_RX_DN<1>")
		)
		(pad "30" smd rect
			(at -3.800094 -1.999996 270)
			(size 0.2794 1.6002)
			(layers "F.Cu" "F.Mask" "F.Paste")
			(net "NC_M2_0_NC8")
		)
		(pad "31" smd rect
			(at 3.750056 -1.75006 270)
			(size 0.2794 1.6002)
			(layers "F.Cu" "F.Mask" "F.Paste")
			(net "P3E_CPU1_P4_RX_DP<1>")
		)
		(pad "32" smd rect
			(at -3.800094 -1.500124 270)
			(size 0.2794 1.6002)
			(layers "F.Cu" "F.Mask" "F.Paste")
			(net "NC_M2_0_NC9")
		)
		(pad "33" smd rect
			(at 3.750056 -1.249934 270)
			(size 0.2794 1.6002)
			(layers "F.Cu" "F.Mask" "F.Paste")
			(net "GND")
		)
		(pad "34" smd rect
			(at -3.800094 -0.999998 270)
			(size 0.2794 1.6002)
			(layers "F.Cu" "F.Mask" "F.Paste")
			(net "NC_M2_0_NC10")
		)
		(pad "35" smd rect
			(at 3.750056 -0.750062 270)
			(size 0.2794 1.6002)
			(layers "F.Cu" "F.Mask" "F.Paste")
			(net "P3E_CPU1_P4_TX_C_DN<1>")
		)
		(pad "36" smd rect
			(at -3.800094 -0.499872 270)
			(size 0.2794 1.6002)
			(layers "F.Cu" "F.Mask" "F.Paste")
			(net "NC_M2_0_NC11")
		)
		(pad "37" smd rect
			(at 3.750056 -0.249936 270)
			(size 0.2794 1.6002)
			(layers "F.Cu" "F.Mask" "F.Paste")
			(net "P3E_CPU1_P4_TX_C_DP<1>")
		)
		(pad "38" smd rect
			(at -3.800094 0 270)
			(size 0.2794 1.6002)
			(layers "F.Cu" "F.Mask" "F.Paste")
			(net "PD_M2_0_DEVSLP")
		)
		(pad "39" smd rect
			(at 3.750056 0.249936 270)
			(size 0.2794 1.6002)
			(layers "F.Cu" "F.Mask" "F.Paste")
			(net "GND")
		)
		(pad "40" smd rect
			(at -3.800094 0.499872 270)
			(size 0.2794 1.6002)
			(layers "F.Cu" "F.Mask" "F.Paste")
			(net "SMB_M2_P1_1V8AUX_SCL")
		)
		(pad "41" smd rect
			(at 3.750056 0.750062 270)
			(size 0.2794 1.6002)
			(layers "F.Cu" "F.Mask" "F.Paste")
			(net "P3E_CPU1_P4_RX_DN<0>")
		)
		(pad "42" smd rect
			(at -3.800094 0.999998 270)
			(size 0.2794 1.6002)
			(layers "F.Cu" "F.Mask" "F.Paste")
			(net "SMB_M2_P1_1V8AUX_SDA")
		)
		(pad "43" smd rect
			(at 3.750056 1.249934 270)
			(size 0.2794 1.6002)
			(layers "F.Cu" "F.Mask" "F.Paste")
			(net "P3E_CPU1_P4_RX_DP<0>")
		)
		(pad "44" smd rect
			(at -3.800094 1.500124 270)
			(size 0.2794 1.6002)
			(layers "F.Cu" "F.Mask" "F.Paste")
			(net "NC_M2_0_NC14")
		)
		(pad "45" smd rect
			(at 3.750056 1.75006 270)
			(size 0.2794 1.6002)
			(layers "F.Cu" "F.Mask" "F.Paste")
			(net "GND")
		)
		(pad "46" smd rect
			(at -3.800094 1.999996 270)
			(size 0.2794 1.6002)
			(layers "F.Cu" "F.Mask" "F.Paste")
			(net "NC_M2_0_NC15")
		)
		(pad "47" smd rect
			(at 3.750056 2.249932 270)
			(size 0.2794 1.6002)
			(layers "F.Cu" "F.Mask" "F.Paste")
			(net "P3E_CPU1_P4_TX_C_DN<0>")
		)
		(pad "48" smd rect
			(at -3.800094 2.500122 270)
			(size 0.2794 1.6002)
			(layers "F.Cu" "F.Mask" "F.Paste")
			(net "NC_M2_0_NC16")
		)
		(pad "49" smd rect
			(at 3.750056 2.750058 270)
			(size 0.2794 1.6002)
			(layers "F.Cu" "F.Mask" "F.Paste")
			(net "P3E_CPU1_P4_TX_C_DP<0>")
		)
		(pad "50" smd rect
			(at -3.800094 2.999994 270)
			(size 0.2794 1.6002)
			(layers "F.Cu" "F.Mask" "F.Paste")
			(net "RST_PERST_BUF_M2_0_R_N")
		)
		(pad "51" smd rect
			(at 3.750056 3.24993 270)
			(size 0.2794 1.6002)
			(layers "F.Cu" "F.Mask" "F.Paste")
			(net "GND")
		)
		(pad "52" smd rect
			(at -3.800094 3.50012 270)
			(size 0.2794 1.6002)
			(layers "F.Cu" "F.Mask" "F.Paste")
			(net "M2_SSD0_CLKREQ_EN_N_BUF")
		)
		(pad "53" smd rect
			(at 3.750056 3.750056 270)
			(size 0.2794 1.6002)
			(layers "F.Cu" "F.Mask" "F.Paste")
			(net "CLK_100M_CPU1_CLK12_DN")
		)
		(pad "54" smd rect
			(at -3.800094 3.999992 270)
			(size 0.2794 1.6002)
			(layers "F.Cu" "F.Mask" "F.Paste")
			(net "M2_0_PEWAKE_N")
		)
		(pad "55" smd rect
			(at 3.750056 4.249928 270)
			(size 0.2794 1.6002)
			(layers "F.Cu" "F.Mask" "F.Paste")
			(net "CLK_100M_CPU1_CLK12_DP")
		)
		(pad "56" smd rect
			(at -3.800094 4.500118 270)
			(size 0.2794 1.6002)
			(layers "F.Cu" "F.Mask" "F.Paste")
			(net "NC_M2_0_NC17")
		)
		(pad "57" smd rect
			(at 3.750056 4.750054 270)
			(size 0.2794 1.6002)
			(layers "F.Cu" "F.Mask" "F.Paste")
			(net "GND")
		)
		(pad "58" smd rect
			(at -3.800094 4.99999 270)
			(size 0.2794 1.6002)
			(layers "F.Cu" "F.Mask" "F.Paste")
			(net "NC_M2_0_NC18")
		)
		(pad "67" smd rect
			(at 3.750056 7.249922 270)
			(size 0.2794 1.6002)
			(layers "F.Cu" "F.Mask" "F.Paste")
			(net "NC_M2_0_NC19")
		)
		(pad "68" smd rect
			(at -3.800094 7.500112 270)
			(size 0.2794 1.6002)
			(layers "F.Cu" "F.Mask" "F.Paste")
			(net "NC_M2_0_SUSCLK")
		)
		(pad "69" smd rect
			(at 3.750056 7.750048 270)
			(size 0.2794 1.6002)
			(layers "F.Cu" "F.Mask" "F.Paste")
			(net "FM_M2_SSD_0_PEDET")
		)
		(pad "70" smd rect
			(at -3.800094 7.999984 270)
			(size 0.2794 1.6002)
			(layers "F.Cu" "F.Mask" "F.Paste")
			(net "P3V3_M2_0")
		)
		(pad "71" smd rect
			(at 3.750056 8.24992 270)
			(size 0.2794 1.6002)
			(layers "F.Cu" "F.Mask" "F.Paste")
			(net "GND")
		)
		(pad "72" smd rect
			(at -3.800094 8.50011 270)
			(size 0.2794 1.6002)
			(layers "F.Cu" "F.Mask" "F.Paste")
			(net "P3V3_M2_0")
		)
		(pad "73" smd rect
			(at 3.750056 8.750046 270)
			(size 0.2794 1.6002)
			(layers "F.Cu" "F.Mask" "F.Paste")
			(net "GND")
		)
		(pad "74" smd rect
			(at -3.800094 8.999982 270)
			(size 0.2794 1.6002)
			(layers "F.Cu" "F.Mask" "F.Paste")
			(net "P3V3_M2_0")
		)
		(pad "75" smd rect
			(at 3.750056 9.249918 270)
			(size 0.2794 1.6002)
			(layers "F.Cu" "F.Mask" "F.Paste")
			(net "GND")
		)
		(pad "G1" smd rect
			(at 2.975102 -10.349992 270)
			(size 1.2446 2.794)
			(layers "F.Cu" "F.Mask" "F.Paste")
			(net "GND")
		)
		(pad "G2" smd rect
			(at 2.975102 10.349992 270)
			(size 1.2446 2.794)
			(layers "F.Cu" "F.Mask" "F.Paste")
			(net "GND")
		)
		(zone
			(layers "F.Cu" "B.Cu" "In1.Cu" "In2.Cu" "In3.Cu" "In4.Cu" "In5.Cu" "In6.Cu"
				"In7.Cu" "In8.Cu" "In9.Cu" "In10.Cu" "In11.Cu" "In12.Cu" "In13.Cu" "In14.Cu"
				"In15.Cu" "In16.Cu"
			)
			(hatch none 0.5)
			(connect_pads
				(clearance 0)
			)
			(min_thickness 0.25)
			(keepout
				(tracks not_allowed)
				(vias allowed)
				(pads allowed)
				(copperpour not_allowed)
				(footprints allowed)
			)
			(placement
				(enabled no)
				(sheetname "")
			)
			(fill
				(thermal_gap 0.5)
				(thermal_bridge_width 0.5)
				(island_removal_mode 0)
			)
			(polygon
				(pts
					(arc
						(start 172.823886 -57.049924)
						(mid 170.842686 -57.049924)
						(end 172.823886 -57.049924)
					)
				)
			)
		)
		(zone
			(layers "F.Cu" "B.Cu" "In1.Cu" "In2.Cu" "In3.Cu" "In4.Cu" "In5.Cu" "In6.Cu"
				"In7.Cu" "In8.Cu" "In9.Cu" "In10.Cu" "In11.Cu" "In12.Cu" "In13.Cu" "In14.Cu"
				"In15.Cu" "In16.Cu"
			)
			(hatch none 0.5)
			(connect_pads
				(clearance 0)
			)
			(min_thickness 0.25)
			(keepout
				(tracks not_allowed)
				(vias allowed)
				(pads allowed)
				(copperpour not_allowed)
				(footprints allowed)
			)
			(placement
				(enabled no)
				(sheetname "")
			)
			(fill
				(thermal_gap 0.5)
				(thermal_bridge_width 0.5)
				(island_removal_mode 0)
			)
			(polygon
				(pts
					(arc
						(start 173.065186 -37.049964)
						(mid 170.601386 -37.049964)
						(end 173.065186 -37.049964)
					)
				)
			)
		)
	)
	(footprint ""
		(layer "F.Cu")
		(at 111.076486 -171.812458 90)
		(property "Reference" "PC325_1"
			(at 0 0 90)
			(layer "F.SilkS")
			(hide yes)
			(effects
				(font
					(size 1.27 1.27)
				)
			)
		)
		(property "Value" ""
			(at 0 0 90)
			(layer "F.Fab")
			(effects
				(font
					(size 1.27 1.27)
				)
			)
		)
		(duplicate_pad_numbers_are_jumpers no)
		(fp_line
			(start 0.7874 -0.4064)
			(end 0.7874 0.4064)
			(stroke
				(width 0.1524)
				(type default)
			)
			(layer "F.SilkS")
		)
		(fp_line
			(start -0.7874 -0.4064)
			(end 0.7874 -0.4064)
			(stroke
				(width 0.1524)
				(type default)
			)
			(layer "F.SilkS")
		)
		(fp_line
			(start 0.7874 0.4064)
			(end -0.7874 0.4064)
			(stroke
				(width 0.1524)
				(type default)
			)
			(layer "F.SilkS")
		)
		(fp_line
			(start -0.7874 0.4064)
			(end -0.7874 -0.4064)
			(stroke
				(width 0.1524)
				(type default)
			)
			(layer "F.SilkS")
		)
		(fp_line
			(start -0.12065 -0.305054)
			(end -0.12065 -0.2794)
			(stroke
				(width 0.1)
				(type default)
			)
			(layer "F.Fab")
		)
		(fp_line
			(start -0.67945 -0.305054)
			(end -0.12065 -0.305054)
			(stroke
				(width 0.1)
				(type default)
			)
			(layer "F.Fab")
		)
		(fp_line
			(start 0.67945 -0.3048)
			(end 0.67945 0.3048)
			(stroke
				(width 0.1)
				(type default)
			)
			(layer "F.Fab")
		)
		(fp_line
			(start 0.12065 -0.3048)
			(end 0.67945 -0.3048)
			(stroke
				(width 0.1)
				(type default)
			)
			(layer "F.Fab")
		)
		(fp_line
			(start 0.12065 -0.2794)
			(end 0.12065 -0.3048)
			(stroke
				(width 0.1)
				(type default)
			)
			(layer "F.Fab")
		)
		(fp_line
			(start -0.12065 -0.2794)
			(end 0.12065 -0.2794)
			(stroke
				(width 0.1)
				(type default)
			)
			(layer "F.Fab")
		)
		(fp_line
			(start 0.120396 0.2794)
			(end -0.12065 0.2794)
			(stroke
				(width 0.1)
				(type default)
			)
			(layer "F.Fab")
		)
		(fp_line
			(start -0.12065 0.2794)
			(end -0.12065 0.3048)
			(stroke
				(width 0.1)
				(type default)
			)
			(layer "F.Fab")
		)
		(fp_line
			(start 0.67945 0.3048)
			(end 0.120396 0.3048)
			(stroke
				(width 0.1)
				(type default)
			)
			(layer "F.Fab")
		)
		(fp_line
			(start 0.120396 0.3048)
			(end 0.120396 0.2794)
			(stroke
				(width 0.1)
				(type default)
			)
			(layer "F.Fab")
		)
		(fp_line
			(start -0.12065 0.3048)
			(end -0.67945 0.3048)
			(stroke
				(width 0.1)
				(type default)
			)
			(layer "F.Fab")
		)
		(fp_line
			(start -0.67945 0.3048)
			(end -0.67945 -0.305054)
			(stroke
				(width 0.1)
				(type default)
			)
			(layer "F.Fab")
		)
		(pad "1" smd circle
			(at -0.40005 0 90)
			(size 0 0)
			(layers "F.Cu" "F.Mask" "F.Paste")
			(net "SW_P12V_AUX_PVDDCR_SOC_P1_FLT")
		)
		(pad "2" smd circle
			(at 0.40005 0 90)
			(size 0 0)
			(layers "F.Cu" "F.Mask" "F.Paste")
			(net "GND")
		)
	)
	(footprint ""
		(layer "F.Cu")
		(at 329.360022 -33.969706)
		(property "Reference" "C2045"
			(at 0 0 0)
			(layer "F.SilkS")
			(hide yes)
			(effects
				(font
					(size 1.27 1.27)
				)
			)
		)
		(property "Value" ""
			(at 0 0 0)
			(layer "F.Fab")
			(effects
				(font
					(size 1.27 1.27)
				)
			)
		)
		(duplicate_pad_numbers_are_jumpers no)
		(fp_line
			(start -0.7874 -0.4064)
			(end 0.7874 -0.4064)
			(stroke
				(width 0.1524)
				(type default)
			)
			(layer "F.SilkS")
		)
		(fp_line
			(start -0.7874 0.4064)
			(end -0.7874 -0.4064)
			(stroke
				(width 0.1524)
				(type default)
			)
			(layer "F.SilkS")
		)
		(fp_line
			(start 0.7874 -0.4064)
			(end 0.7874 0.4064)
			(stroke
				(width 0.1524)
				(type default)
			)
			(layer "F.SilkS")
		)
		(fp_line
			(start 0.7874 0.4064)
			(end -0.7874 0.4064)
			(stroke
				(width 0.1524)
				(type default)
			)
			(layer "F.SilkS")
		)
		(fp_line
			(start -0.67945 -0.305054)
			(end -0.12065 -0.305054)
			(stroke
				(width 0.1)
				(type default)
			)
			(layer "F.Fab")
		)
		(fp_line
			(start -0.67945 0.3048)
			(end -0.67945 -0.305054)
			(stroke
				(width 0.1)
				(type default)
			)
			(layer "F.Fab")
		)
		(fp_line
			(start -0.12065 -0.305054)
			(end -0.12065 -0.2794)
			(stroke
				(width 0.1)
				(type default)
			)
			(layer "F.Fab")
		)
		(fp_line
			(start -0.12065 -0.2794)
			(end 0.12065 -0.2794)
			(stroke
				(width 0.1)
				(type default)
			)
			(layer "F.Fab")
		)
		(fp_line
			(start -0.12065 0.2794)
			(end -0.12065 0.3048)
			(stroke
				(width 0.1)
				(type default)
			)
			(layer "F.Fab")
		)
		(fp_line
			(start -0.12065 0.3048)
			(end -0.67945 0.3048)
			(stroke
				(width 0.1)
				(type default)
			)
			(layer "F.Fab")
		)
		(fp_line
			(start 0.120396 0.2794)
			(end -0.12065 0.2794)
			(stroke
				(width 0.1)
				(type default)
			)
			(layer "F.Fab")
		)
		(fp_line
			(start 0.120396 0.3048)
			(end 0.120396 0.2794)
			(stroke
				(width 0.1)
				(type default)
			)
			(layer "F.Fab")
		)
		(fp_line
			(start 0.12065 -0.3048)
			(end 0.67945 -0.3048)
			(stroke
				(width 0.1)
				(type default)
			)
			(layer "F.Fab")
		)
		(fp_line
			(start 0.12065 -0.2794)
			(end 0.12065 -0.3048)
			(stroke
				(width 0.1)
				(type default)
			)
			(layer "F.Fab")
		)
		(fp_line
			(start 0.67945 -0.3048)
			(end 0.67945 0.3048)
			(stroke
				(width 0.1)
				(type default)
			)
			(layer "F.Fab")
		)
		(fp_line
			(start 0.67945 0.3048)
			(end 0.120396 0.3048)
			(stroke
				(width 0.1)
				(type default)
			)
			(layer "F.Fab")
		)
		(pad "1" smd circle
			(at -0.40005 0)
			(size 0 0)
			(layers "F.Cu" "F.Mask" "F.Paste")
			(net "P3V3_PDB_AUX_ADC_MAM")
		)
		(pad "2" smd circle
			(at 0.40005 0)
			(size 0 0)
			(layers "F.Cu" "F.Mask" "F.Paste")
			(net "GND")
		)
	)
	(footprint ""
		(layer "F.Cu")
		(at 344.149426 -339.676232 90)
		(property "Reference" "PR95"
			(at 0 0 90)
			(layer "F.SilkS")
			(hide yes)
			(effects
				(font
					(size 1.27 1.27)
				)
			)
		)
		(property "Value" ""
			(at 0 0 90)
			(layer "F.Fab")
			(effects
				(font
					(size 1.27 1.27)
				)
			)
		)
		(duplicate_pad_numbers_are_jumpers no)
		(fp_line
			(start 0.7874 -0.4064)
			(end 0.7874 0.4064)
			(stroke
				(width 0.1524)
				(type default)
			)
			(layer "F.SilkS")
		)
		(fp_line
			(start -0.7874 -0.4064)
			(end 0.7874 -0.4064)
			(stroke
				(width 0.1524)
				(type default)
			)
			(layer "F.SilkS")
		)
		(fp_line
			(start 0.7874 0.4064)
			(end -0.7874 0.4064)
			(stroke
				(width 0.1524)
				(type default)
			)
			(layer "F.SilkS")
		)
		(fp_line
			(start -0.7874 0.4064)
			(end -0.7874 -0.4064)
			(stroke
				(width 0.1524)
				(type default)
			)
			(layer "F.SilkS")
		)
		(fp_line
			(start -0.12065 -0.305054)
			(end -0.12065 -0.2794)
			(stroke
				(width 0.1)
				(type default)
			)
			(layer "F.Fab")
		)
		(fp_line
			(start -0.67945 -0.305054)
			(end -0.12065 -0.305054)
			(stroke
				(width 0.1)
				(type default)
			)
			(layer "F.Fab")
		)
		(fp_line
			(start 0.67945 -0.3048)
			(end 0.67945 0.3048)
			(stroke
				(width 0.1)
				(type default)
			)
			(layer "F.Fab")
		)
		(fp_line
			(start 0.12065 -0.3048)
			(end 0.67945 -0.3048)
			(stroke
				(width 0.1)
				(type default)
			)
			(layer "F.Fab")
		)
		(fp_line
			(start 0.12065 -0.2794)
			(end 0.12065 -0.3048)
			(stroke
				(width 0.1)
				(type default)
			)
			(layer "F.Fab")
		)
		(fp_line
			(start -0.12065 -0.2794)
			(end 0.12065 -0.2794)
			(stroke
				(width 0.1)
				(type default)
			)
			(layer "F.Fab")
		)
		(fp_line
			(start 0.120396 0.2794)
			(end -0.12065 0.2794)
			(stroke
				(width 0.1)
				(type default)
			)
			(layer "F.Fab")
		)
		(fp_line
			(start -0.12065 0.2794)
			(end -0.12065 0.3048)
			(stroke
				(width 0.1)
				(type default)
			)
			(layer "F.Fab")
		)
		(fp_line
			(start 0.67945 0.3048)
			(end 0.120396 0.3048)
			(stroke
				(width 0.1)
				(type default)
			)
			(layer "F.Fab")
		)
		(fp_line
			(start 0.120396 0.3048)
			(end 0.120396 0.2794)
			(stroke
				(width 0.1)
				(type default)
			)
			(layer "F.Fab")
		)
		(fp_line
			(start -0.12065 0.3048)
			(end -0.67945 0.3048)
			(stroke
				(width 0.1)
				(type default)
			)
			(layer "F.Fab")
		)
		(fp_line
			(start -0.67945 0.3048)
			(end -0.67945 -0.305054)
			(stroke
				(width 0.1)
				(type default)
			)
			(layer "F.Fab")
		)
		(pad "1" smd circle
			(at -0.40005 0 90)
			(size 0 0)
			(layers "F.Cu" "F.Mask" "F.Paste")
			(net "SW_PVDDCR_CPU1_P0_BOOT5")
		)
		(pad "2" smd circle
			(at 0.40005 0 90)
			(size 0 0)
			(layers "F.Cu" "F.Mask" "F.Paste")
			(net "SW_PVDDCR_CPU1_P0_BOOT5_R")
		)
	)
	(footprint ""
		(layer "F.Cu")
		(at 210.086956 -30.276292 90)
		(property "Reference" "R3622"
			(at 0 0 90)
			(layer "F.SilkS")
			(hide yes)
			(effects
				(font
					(size 1.27 1.27)
				)
			)
		)
		(property "Value" ""
			(at 0 0 90)
			(layer "F.Fab")
			(effects
				(font
					(size 1.27 1.27)
				)
			)
		)
		(duplicate_pad_numbers_are_jumpers no)
		(fp_line
			(start 0.7874 -0.4064)
			(end 0.7874 0.4064)
			(stroke
				(width 0.1524)
				(type default)
			)
			(layer "F.SilkS")
		)
		(fp_line
			(start -0.7874 -0.4064)
			(end 0.7874 -0.4064)
			(stroke
				(width 0.1524)
				(type default)
			)
			(layer "F.SilkS")
		)
		(fp_line
			(start 0.7874 0.4064)
			(end -0.7874 0.4064)
			(stroke
				(width 0.1524)
				(type default)
			)
			(layer "F.SilkS")
		)
		(fp_line
			(start -0.7874 0.4064)
			(end -0.7874 -0.4064)
			(stroke
				(width 0.1524)
				(type default)
			)
			(layer "F.SilkS")
		)
		(fp_line
			(start -0.12065 -0.305054)
			(end -0.12065 -0.2794)
			(stroke
				(width 0.1)
				(type default)
			)
			(layer "F.Fab")
		)
		(fp_line
			(start -0.67945 -0.305054)
			(end -0.12065 -0.305054)
			(stroke
				(width 0.1)
				(type default)
			)
			(layer "F.Fab")
		)
		(fp_line
			(start 0.67945 -0.3048)
			(end 0.67945 0.3048)
			(stroke
				(width 0.1)
				(type default)
			)
			(layer "F.Fab")
		)
		(fp_line
			(start 0.12065 -0.3048)
			(end 0.67945 -0.3048)
			(stroke
				(width 0.1)
				(type default)
			)
			(layer "F.Fab")
		)
		(fp_line
			(start 0.12065 -0.2794)
			(end 0.12065 -0.3048)
			(stroke
				(width 0.1)
				(type default)
			)
			(layer "F.Fab")
		)
		(fp_line
			(start -0.12065 -0.2794)
			(end 0.12065 -0.2794)
			(stroke
				(width 0.1)
				(type default)
			)
			(layer "F.Fab")
		)
		(fp_line
			(start 0.120396 0.2794)
			(end -0.12065 0.2794)
			(stroke
				(width 0.1)
				(type default)
			)
			(layer "F.Fab")
		)
		(fp_line
			(start -0.12065 0.2794)
			(end -0.12065 0.3048)
			(stroke
				(width 0.1)
				(type default)
			)
			(layer "F.Fab")
		)
		(fp_line
			(start 0.67945 0.3048)
			(end 0.120396 0.3048)
			(stroke
				(width 0.1)
				(type default)
			)
			(layer "F.Fab")
		)
		(fp_line
			(start 0.120396 0.3048)
			(end 0.120396 0.2794)
			(stroke
				(width 0.1)
				(type default)
			)
			(layer "F.Fab")
		)
		(fp_line
			(start -0.12065 0.3048)
			(end -0.67945 0.3048)
			(stroke
				(width 0.1)
				(type default)
			)
			(layer "F.Fab")
		)
		(fp_line
			(start -0.67945 0.3048)
			(end -0.67945 -0.305054)
			(stroke
				(width 0.1)
				(type default)
			)
			(layer "F.Fab")
		)
		(pad "1" smd circle
			(at -0.40005 0 90)
			(size 0 0)
			(layers "F.Cu" "F.Mask" "F.Paste")
			(net "P3V3_AUX")
		)
		(pad "2" smd circle
			(at 0.40005 0 90)
			(size 0 0)
			(layers "F.Cu" "F.Mask" "F.Paste")
			(net "INA230_5_A0")
		)
	)
	(footprint ""
		(layer "F.Cu")
		(at 294.421052 -115.237514)
		(property "Reference" "R2703"
			(at 0 0 0)
			(layer "F.SilkS")
			(hide yes)
			(effects
				(font
					(size 1.27 1.27)
				)
			)
		)
		(property "Value" ""
			(at 0 0 0)
			(layer "F.Fab")
			(effects
				(font
					(size 1.27 1.27)
				)
			)
		)
		(duplicate_pad_numbers_are_jumpers no)
		(fp_line
			(start -0.7874 -0.4064)
			(end 0.7874 -0.4064)
			(stroke
				(width 0.1524)
				(type default)
			)
			(layer "F.SilkS")
		)
		(fp_line
			(start -0.7874 0.4064)
			(end -0.7874 -0.4064)
			(stroke
				(width 0.1524)
				(type default)
			)
			(layer "F.SilkS")
		)
		(fp_line
			(start 0.7874 -0.4064)
			(end 0.7874 0.4064)
			(stroke
				(width 0.1524)
				(type default)
			)
			(layer "F.SilkS")
		)
		(fp_line
			(start 0.7874 0.4064)
			(end -0.7874 0.4064)
			(stroke
				(width 0.1524)
				(type default)
			)
			(layer "F.SilkS")
		)
		(fp_line
			(start -0.67945 -0.305054)
			(end -0.12065 -0.305054)
			(stroke
				(width 0.1)
				(type default)
			)
			(layer "F.Fab")
		)
		(fp_line
			(start -0.67945 0.3048)
			(end -0.67945 -0.305054)
			(stroke
				(width 0.1)
				(type default)
			)
			(layer "F.Fab")
		)
		(fp_line
			(start -0.12065 -0.305054)
			(end -0.12065 -0.2794)
			(stroke
				(width 0.1)
				(type default)
			)
			(layer "F.Fab")
		)
		(fp_line
			(start -0.12065 -0.2794)
			(end 0.12065 -0.2794)
			(stroke
				(width 0.1)
				(type default)
			)
			(layer "F.Fab")
		)
		(fp_line
			(start -0.12065 0.2794)
			(end -0.12065 0.3048)
			(stroke
				(width 0.1)
				(type default)
			)
			(layer "F.Fab")
		)
		(fp_line
			(start -0.12065 0.3048)
			(end -0.67945 0.3048)
			(stroke
				(width 0.1)
				(type default)
			)
			(layer "F.Fab")
		)
		(fp_line
			(start 0.120396 0.2794)
			(end -0.12065 0.2794)
			(stroke
				(width 0.1)
				(type default)
			)
			(layer "F.Fab")
		)
		(fp_line
			(start 0.120396 0.3048)
			(end 0.120396 0.2794)
			(stroke
				(width 0.1)
				(type default)
			)
			(layer "F.Fab")
		)
		(fp_line
			(start 0.12065 -0.3048)
			(end 0.67945 -0.3048)
			(stroke
				(width 0.1)
				(type default)
			)
			(layer "F.Fab")
		)
		(fp_line
			(start 0.12065 -0.2794)
			(end 0.12065 -0.3048)
			(stroke
				(width 0.1)
				(type default)
			)
			(layer "F.Fab")
		)
		(fp_line
			(start 0.67945 -0.3048)
			(end 0.67945 0.3048)
			(stroke
				(width 0.1)
				(type default)
			)
			(layer "F.Fab")
		)
		(fp_line
			(start 0.67945 0.3048)
			(end 0.120396 0.3048)
			(stroke
				(width 0.1)
				(type default)
			)
			(layer "F.Fab")
		)
		(pad "1" smd circle
			(at -0.40005 0)
			(size 0 0)
			(layers "F.Cu" "F.Mask" "F.Paste")
			(net "SMB_BMC_SWB_SCL_R4")
		)
		(pad "2" smd circle
			(at 0.40005 0)
			(size 0 0)
			(layers "F.Cu" "F.Mask" "F.Paste")
			(net "SMB_BMC_SWB_SCL")
		)
	)
	(footprint ""
		(layer "F.Cu")
		(at 370.767102 -414.636458 -90)
		(property "Reference" "C6566"
			(at 0 0 270)
			(layer "F.SilkS")
			(hide yes)
			(effects
				(font
					(size 1.27 1.27)
				)
			)
		)
		(property "Value" ""
			(at 0 0 270)
			(layer "F.Fab")
			(effects
				(font
					(size 1.27 1.27)
				)
			)
		)
		(duplicate_pad_numbers_are_jumpers no)
		(fp_line
			(start -0.299974 0.150114)
			(end -0.299974 -0.150114)
			(stroke
				(width 0.1)
				(type default)
			)
			(layer "F.Fab")
		)
		(fp_line
			(start 0.299974 0.150114)
			(end -0.299974 0.150114)
			(stroke
				(width 0.1)
				(type default)
			)
			(layer "F.Fab")
		)
		(fp_line
			(start -0.299974 -0.150114)
			(end 0.299974 -0.150114)
			(stroke
				(width 0.1)
				(type default)
			)
			(layer "F.Fab")
		)
		(fp_line
			(start 0.299974 -0.150114)
			(end 0.299974 0.150114)
			(stroke
				(width 0.1)
				(type default)
			)
			(layer "F.Fab")
		)
		(pad "1" smd rect
			(at -0.2667 0 270)
			(size 0.3048 0.381)
			(layers "F.Cu" "F.Mask" "F.Paste")
			(net "P5E_CPU0_P2_TX_BUF_C_DN<0>")
		)
		(pad "2" smd rect
			(at 0.2667 0 270)
			(size 0.3048 0.381)
			(layers "F.Cu" "F.Mask" "F.Paste")
			(net "P5E_CPU0_P2_TX_BUF_DN<0>")
		)
	)
	(footprint ""
		(layer "F.Cu")
		(at 23.890478 -17.623536 90)
		(property "Reference" "C684"
			(at 0 0 90)
			(layer "F.SilkS")
			(hide yes)
			(effects
				(font
					(size 1.27 1.27)
				)
			)
		)
		(property "Value" ""
			(at 0 0 90)
			(layer "F.Fab")
			(effects
				(font
					(size 1.27 1.27)
				)
			)
		)
		(duplicate_pad_numbers_are_jumpers no)
		(fp_line
			(start 0.299974 -0.150114)
			(end 0.299974 0.150114)
			(stroke
				(width 0.1)
				(type default)
			)
			(layer "F.Fab")
		)
		(fp_line
			(start -0.299974 -0.150114)
			(end 0.299974 -0.150114)
			(stroke
				(width 0.1)
				(type default)
			)
			(layer "F.Fab")
		)
		(fp_line
			(start 0.299974 0.150114)
			(end -0.299974 0.150114)
			(stroke
				(width 0.1)
				(type default)
			)
			(layer "F.Fab")
		)
		(fp_line
			(start -0.299974 0.150114)
			(end -0.299974 -0.150114)
			(stroke
				(width 0.1)
				(type default)
			)
			(layer "F.Fab")
		)
		(pad "1" smd rect
			(at -0.2667 0 90)
			(size 0.3048 0.381)
			(layers "F.Cu" "F.Mask" "F.Paste")
			(net "P5E_CPU1_G1_TX_C_DN<12>")
		)
		(pad "2" smd rect
			(at 0.2667 0 90)
			(size 0.3048 0.381)
			(layers "F.Cu" "F.Mask" "F.Paste")
			(net "P5E_CPU1_G1_TX_DN<12>")
		)
	)
	(footprint ""
		(layer "F.Cu")
		(at 223.393 -76.581 180)
		(property "Reference" "C8010"
			(at 0 0 180)
			(layer "F.SilkS")
			(hide yes)
			(effects
				(font
					(size 1.27 1.27)
				)
			)
		)
		(property "Value" ""
			(at 0 0 180)
			(layer "F.Fab")
			(effects
				(font
					(size 1.27 1.27)
				)
			)
		)
		(duplicate_pad_numbers_are_jumpers no)
		(fp_line
			(start 0.7874 0.4064)
			(end -0.7874 0.4064)
			(stroke
				(width 0.1524)
				(type default)
			)
			(layer "F.SilkS")
		)
		(fp_line
			(start 0.7874 -0.4064)
			(end 0.7874 0.4064)
			(stroke
				(width 0.1524)
				(type default)
			)
			(layer "F.SilkS")
		)
		(fp_line
			(start -0.7874 0.4064)
			(end -0.7874 -0.4064)
			(stroke
				(width 0.1524)
				(type default)
			)
			(layer "F.SilkS")
		)
		(fp_line
			(start -0.7874 -0.4064)
			(end 0.7874 -0.4064)
			(stroke
				(width 0.1524)
				(type default)
			)
			(layer "F.SilkS")
		)
		(fp_line
			(start 0.67945 0.3048)
			(end 0.120396 0.3048)
			(stroke
				(width 0.1)
				(type default)
			)
			(layer "F.Fab")
		)
		(fp_line
			(start 0.67945 -0.3048)
			(end 0.67945 0.3048)
			(stroke
				(width 0.1)
				(type default)
			)
			(layer "F.Fab")
		)
		(fp_line
			(start 0.12065 -0.2794)
			(end 0.12065 -0.3048)
			(stroke
				(width 0.1)
				(type default)
			)
			(layer "F.Fab")
		)
		(fp_line
			(start 0.12065 -0.3048)
			(end 0.67945 -0.3048)
			(stroke
				(width 0.1)
				(type default)
			)
			(layer "F.Fab")
		)
		(fp_line
			(start 0.120396 0.3048)
			(end 0.120396 0.2794)
			(stroke
				(width 0.1)
				(type default)
			)
			(layer "F.Fab")
		)
		(fp_line
			(start 0.120396 0.2794)
			(end -0.12065 0.2794)
			(stroke
				(width 0.1)
				(type default)
			)
			(layer "F.Fab")
		)
		(fp_line
			(start -0.12065 0.3048)
			(end -0.67945 0.3048)
			(stroke
				(width 0.1)
				(type default)
			)
			(layer "F.Fab")
		)
		(fp_line
			(start -0.12065 0.2794)
			(end -0.12065 0.3048)
			(stroke
				(width 0.1)
				(type default)
			)
			(layer "F.Fab")
		)
		(fp_line
			(start -0.12065 -0.2794)
			(end 0.12065 -0.2794)
			(stroke
				(width 0.1)
				(type default)
			)
			(layer "F.Fab")
		)
		(fp_line
			(start -0.12065 -0.305054)
			(end -0.12065 -0.2794)
			(stroke
				(width 0.1)
				(type default)
			)
			(layer "F.Fab")
		)
		(fp_line
			(start -0.67945 0.3048)
			(end -0.67945 -0.305054)
			(stroke
				(width 0.1)
				(type default)
			)
			(layer "F.Fab")
		)
		(fp_line
			(start -0.67945 -0.305054)
			(end -0.12065 -0.305054)
			(stroke
				(width 0.1)
				(type default)
			)
			(layer "F.Fab")
		)
		(pad "1" smd circle
			(at -0.40005 0 180)
			(size 0 0)
			(layers "F.Cu" "F.Mask" "F.Paste")
			(net "P3V3_E1S_0_R")
		)
		(pad "2" smd circle
			(at 0.40005 0 180)
			(size 0 0)
			(layers "F.Cu" "F.Mask" "F.Paste")
			(net "GND")
		)
	)
	(footprint ""
		(layer "F.Cu")
		(at 338.378546 -416.899344 -90)
		(property "Reference" "C6523"
			(at 0 0 270)
			(layer "F.SilkS")
			(hide yes)
			(effects
				(font
					(size 1.27 1.27)
				)
			)
		)
		(property "Value" ""
			(at 0 0 270)
			(layer "F.Fab")
			(effects
				(font
					(size 1.27 1.27)
				)
			)
		)
		(duplicate_pad_numbers_are_jumpers no)
		(fp_line
			(start -0.299974 0.150114)
			(end -0.299974 -0.150114)
			(stroke
				(width 0.1)
				(type default)
			)
			(layer "F.Fab")
		)
		(fp_line
			(start 0.299974 0.150114)
			(end -0.299974 0.150114)
			(stroke
				(width 0.1)
				(type default)
			)
			(layer "F.Fab")
		)
		(fp_line
			(start -0.299974 -0.150114)
			(end 0.299974 -0.150114)
			(stroke
				(width 0.1)
				(type default)
			)
			(layer "F.Fab")
		)
		(fp_line
			(start 0.299974 -0.150114)
			(end 0.299974 0.150114)
			(stroke
				(width 0.1)
				(type default)
			)
			(layer "F.Fab")
		)
		(pad "1" smd rect
			(at -0.2667 0 270)
			(size 0.3048 0.381)
			(layers "F.Cu" "F.Mask" "F.Paste")
			(net "P5E_CPU0_P0_TX_BUF_C_DP<11>")
		)
		(pad "2" smd rect
			(at 0.2667 0 270)
			(size 0.3048 0.381)
			(layers "F.Cu" "F.Mask" "F.Paste")
			(net "P5E_CPU0_P0_TX_BUF_DP<11>")
		)
	)
	(footprint ""
		(layer "F.Cu")
		(at 135.268462 -395.6304 -90)
		(property "Reference" "R895"
			(at 0 0 270)
			(layer "F.SilkS")
			(hide yes)
			(effects
				(font
					(size 1.27 1.27)
				)
			)
		)
		(property "Value" ""
			(at 0 0 270)
			(layer "F.Fab")
			(effects
				(font
					(size 1.27 1.27)
				)
			)
		)
		(duplicate_pad_numbers_are_jumpers no)
		(fp_line
			(start -0.32512 0.175006)
			(end -0.32512 -0.175006)
			(stroke
				(width 0.1)
				(type default)
			)
			(layer "F.Fab")
		)
		(fp_line
			(start 0.32512 0.175006)
			(end -0.32512 0.175006)
			(stroke
				(width 0.1)
				(type default)
			)
			(layer "F.Fab")
		)
		(fp_line
			(start -0.32512 -0.175006)
			(end 0.32512 -0.175006)
			(stroke
				(width 0.1)
				(type default)
			)
			(layer "F.Fab")
		)
		(fp_line
			(start 0.32512 -0.175006)
			(end 0.32512 0.175006)
			(stroke
				(width 0.1)
				(type default)
			)
			(layer "F.Fab")
		)
		(pad "1" smd rect
			(at -0.2667 0 270)
			(size 0.3048 0.381)
			(layers "F.Cu" "F.Mask" "F.Paste")
			(net "RST_RT_CPU1_P3_PERST_N")
		)
		(pad "2" smd rect
			(at 0.2667 0 90)
			(size 0.3048 0.381)
			(layers "F.Cu" "F.Mask" "F.Paste")
			(net "RST_RT_CPU1_P3_PERST_R_N")
		)
	)
	(footprint ""
		(layer "F.Cu")
		(at 50.927 -433.578 180)
		(property "Reference" "R3455"
			(at 0 0 180)
			(layer "F.SilkS")
			(hide yes)
			(effects
				(font
					(size 1.27 1.27)
				)
			)
		)
		(property "Value" ""
			(at 0 0 180)
			(layer "F.Fab")
			(effects
				(font
					(size 1.27 1.27)
				)
			)
		)
		(duplicate_pad_numbers_are_jumpers no)
		(fp_line
			(start 0.7874 0.4064)
			(end -0.7874 0.4064)
			(stroke
				(width 0.1524)
				(type default)
			)
			(layer "F.SilkS")
		)
		(fp_line
			(start 0.7874 -0.4064)
			(end 0.7874 0.4064)
			(stroke
				(width 0.1524)
				(type default)
			)
			(layer "F.SilkS")
		)
		(fp_line
			(start -0.7874 0.4064)
			(end -0.7874 -0.4064)
			(stroke
				(width 0.1524)
				(type default)
			)
			(layer "F.SilkS")
		)
		(fp_line
			(start -0.7874 -0.4064)
			(end 0.7874 -0.4064)
			(stroke
				(width 0.1524)
				(type default)
			)
			(layer "F.SilkS")
		)
		(fp_line
			(start 0.67945 0.3048)
			(end 0.120396 0.3048)
			(stroke
				(width 0.1)
				(type default)
			)
			(layer "F.Fab")
		)
		(fp_line
			(start 0.67945 -0.3048)
			(end 0.67945 0.3048)
			(stroke
				(width 0.1)
				(type default)
			)
			(layer "F.Fab")
		)
		(fp_line
			(start 0.12065 -0.2794)
			(end 0.12065 -0.3048)
			(stroke
				(width 0.1)
				(type default)
			)
			(layer "F.Fab")
		)
		(fp_line
			(start 0.12065 -0.3048)
			(end 0.67945 -0.3048)
			(stroke
				(width 0.1)
				(type default)
			)
			(layer "F.Fab")
		)
		(fp_line
			(start 0.120396 0.3048)
			(end 0.120396 0.2794)
			(stroke
				(width 0.1)
				(type default)
			)
			(layer "F.Fab")
		)
		(fp_line
			(start 0.120396 0.2794)
			(end -0.12065 0.2794)
			(stroke
				(width 0.1)
				(type default)
			)
			(layer "F.Fab")
		)
		(fp_line
			(start -0.12065 0.3048)
			(end -0.67945 0.3048)
			(stroke
				(width 0.1)
				(type default)
			)
			(layer "F.Fab")
		)
		(fp_line
			(start -0.12065 0.2794)
			(end -0.12065 0.3048)
			(stroke
				(width 0.1)
				(type default)
			)
			(layer "F.Fab")
		)
		(fp_line
			(start -0.12065 -0.2794)
			(end 0.12065 -0.2794)
			(stroke
				(width 0.1)
				(type default)
			)
			(layer "F.Fab")
		)
		(fp_line
			(start -0.12065 -0.305054)
			(end -0.12065 -0.2794)
			(stroke
				(width 0.1)
				(type default)
			)
			(layer "F.Fab")
		)
		(fp_line
			(start -0.67945 0.3048)
			(end -0.67945 -0.305054)
			(stroke
				(width 0.1)
				(type default)
			)
			(layer "F.Fab")
		)
		(fp_line
			(start -0.67945 -0.305054)
			(end -0.12065 -0.305054)
			(stroke
				(width 0.1)
				(type default)
			)
			(layer "F.Fab")
		)
		(pad "1" smd circle
			(at -0.40005 0 180)
			(size 0 0)
			(layers "F.Cu" "F.Mask" "F.Paste")
			(net "RST_PERST_2_SWB_BUF_R_N")
		)
		(pad "2" smd circle
			(at 0.40005 0 180)
			(size 0 0)
			(layers "F.Cu" "F.Mask" "F.Paste")
			(net "GND")
		)
	)
	(footprint ""
		(layer "F.Cu")
		(at 42.967402 -382.39446 180)
		(property "Reference" "C837"
			(at 0 0 180)
			(layer "F.SilkS")
			(hide yes)
			(effects
				(font
					(size 1.27 1.27)
				)
			)
		)
		(property "Value" ""
			(at 0 0 180)
			(layer "F.Fab")
			(effects
				(font
					(size 1.27 1.27)
				)
			)
		)
		(duplicate_pad_numbers_are_jumpers no)
		(fp_line
			(start 0.299974 0.150114)
			(end -0.299974 0.150114)
			(stroke
				(width 0.1)
				(type default)
			)
			(layer "F.Fab")
		)
		(fp_line
			(start 0.299974 -0.150114)
			(end 0.299974 0.150114)
			(stroke
				(width 0.1)
				(type default)
			)
			(layer "F.Fab")
		)
		(fp_line
			(start -0.299974 0.150114)
			(end -0.299974 -0.150114)
			(stroke
				(width 0.1)
				(type default)
			)
			(layer "F.Fab")
		)
		(fp_line
			(start -0.299974 -0.150114)
			(end 0.299974 -0.150114)
			(stroke
				(width 0.1)
				(type default)
			)
			(layer "F.Fab")
		)
		(pad "1" smd rect
			(at -0.2667 0 180)
			(size 0.3048 0.381)
			(layers "F.Cu" "F.Mask" "F.Paste")
			(net "P5E_CPU1_P0_TX_C_DP<0>")
		)
		(pad "2" smd rect
			(at 0.2667 0 180)
			(size 0.3048 0.381)
			(layers "F.Cu" "F.Mask" "F.Paste")
			(net "P5E_CPU1_P0_TX_DP<0>")
		)
	)
	(footprint ""
		(layer "F.Cu")
		(at 121.36374 -76.001626)
		(property "Reference" "PU6001"
			(at -4.776978 -4.383278 0)
			(unlocked yes)
			(layer "F.SilkS")
			(effects
				(font
					(size 0.7874 0.5842)
					(thickness 0.1524)
				)
				(justify left)
			)
		)
		(property "Value" ""
			(at 0 0 0)
			(layer "F.Fab")
			(effects
				(font
					(size 1.27 1.27)
				)
			)
		)
		(duplicate_pad_numbers_are_jumpers no)
		(fp_line
			(start -1.050036 -1.549908)
			(end -0.503936 -1.549908)
			(stroke
				(width 0.1524)
				(type default)
			)
			(layer "F.SilkS")
		)
		(fp_line
			(start -1.050036 -1.253998)
			(end -1.050036 -1.549908)
			(stroke
				(width 0.1524)
				(type default)
			)
			(layer "F.SilkS")
		)
		(fp_line
			(start -1.050036 1.549908)
			(end -1.050036 1.253998)
			(stroke
				(width 0.1524)
				(type default)
			)
			(layer "F.SilkS")
		)
		(fp_line
			(start -0.503936 1.549908)
			(end -1.050036 1.549908)
			(stroke
				(width 0.1524)
				(type default)
			)
			(layer "F.SilkS")
		)
		(fp_line
			(start 0.503936 -1.549908)
			(end 1.050036 -1.549908)
			(stroke
				(width 0.1524)
				(type default)
			)
			(layer "F.SilkS")
		)
		(fp_line
			(start 1.050036 -1.549908)
			(end 1.050036 -1.253998)
			(stroke
				(width 0.1524)
				(type default)
			)
			(layer "F.SilkS")
		)
		(fp_line
			(start 1.050036 1.253998)
			(end 1.050036 1.549908)
			(stroke
				(width 0.1524)
				(type default)
			)
			(layer "F.SilkS")
		)
		(fp_line
			(start 1.050036 1.549908)
			(end 0.503936 1.549908)
			(stroke
				(width 0.1524)
				(type default)
			)
			(layer "F.SilkS")
		)
		(fp_poly
			(pts
				(xy -1.394968 -1.542034) (xy -2.203196 -1.811528) (xy -1.664208 -2.350262)
			)
			(stroke
				(width 0)
				(type default)
			)
			(fill yes)
			(layer "F.SilkS")
		)
		(fp_line
			(start -1.050036 -1.549908)
			(end 1.050036 -1.549908)
			(stroke
				(width 0.1)
				(type default)
			)
			(layer "F.Fab")
		)
		(fp_line
			(start -1.050036 1.549908)
			(end -1.050036 -1.549908)
			(stroke
				(width 0.1)
				(type default)
			)
			(layer "F.Fab")
		)
		(fp_line
			(start 1.050036 -1.549908)
			(end 1.050036 1.549908)
			(stroke
				(width 0.1)
				(type default)
			)
			(layer "F.Fab")
		)
		(fp_line
			(start 1.050036 1.549908)
			(end -1.050036 1.549908)
			(stroke
				(width 0.1)
				(type default)
			)
			(layer "F.Fab")
		)
		(fp_poly
			(pts
				(xy -2.2352 -0.618998) (xy -2.2352 -1.380998) (xy -1.4732 -0.999998)
			)
			(stroke
				(width 0)
				(type default)
			)
			(fill yes)
			(layer "F.Fab")
		)
		(pad "1" smd circle
			(at -0.94996 -0.999998 270)
			(size 0 0)
			(layers "F.Cu" "F.Mask" "F.Paste")
			(net "GND")
		)
		(pad "2" smd rect
			(at -0.849884 -0.499872 90)
			(size 0.254 0.9144)
			(layers "F.Cu" "F.Mask" "F.Paste")
			(net "SW_P1V2_AUX_PH")
		)
		(pad "3" smd rect
			(at -0.649986 0 90)
			(size 0.254 1.3208)
			(layers "F.Cu" "F.Mask" "F.Paste")
			(net "SW_P12V_AUX_P1V2_AUX_FLT")
		)
		(pad "4" smd rect
			(at -0.849884 0.499872 90)
			(size 0.254 0.9144)
			(layers "F.Cu" "F.Mask" "F.Paste")
			(net "P1V2_AUX_CS")
		)
		(pad "5" smd circle
			(at -0.94996 0.999998 270)
			(size 0 0)
			(layers "F.Cu" "F.Mask" "F.Paste")
			(net "P1V2_AUX_ENABLE")
		)
		(pad "6" smd circle
			(at -0.249936 1.450086)
			(size 0 0)
			(layers "F.Cu" "F.Mask" "F.Paste")
			(net "P1V2_AUX_FB")
		)
		(pad "7" smd circle
			(at 0.249936 1.450086)
			(size 0 0)
			(layers "F.Cu" "F.Mask" "F.Paste")
			(net "GND")
		)
		(pad "8" smd circle
			(at 0.94996 0.999998 90)
			(size 0 0)
			(layers "F.Cu" "F.Mask" "F.Paste")
			(net "P1V2_AUX_REF")
		)
		(pad "9" smd rect
			(at 0.849884 0.499872 90)
			(size 0.254 0.9144)
			(layers "F.Cu" "F.Mask" "F.Paste")
			(net "PWRGD_P1V2_AUX")
		)
		(pad "10" smd rect
			(at 0.849884 0 90)
			(size 0.254 0.9144)
			(layers "F.Cu" "F.Mask" "F.Paste")
			(net "SW_P1V2_AUX_BT")
		)
		(pad "11" smd rect
			(at 0.849884 -0.499872 90)
			(size 0.254 0.9144)
			(layers "F.Cu" "F.Mask" "F.Paste")
			(net "SW_P1V2_AUX_PH")
		)
		(pad "12" smd circle
			(at 0.94996 -0.999998 90)
			(size 0 0)
			(layers "F.Cu" "F.Mask" "F.Paste")
			(net "P1V2_AUX_MODE")
		)
		(pad "13" smd circle
			(at 0.249936 -1.450086 180)
			(size 0 0)
			(layers "F.Cu" "F.Mask" "F.Paste")
			(net "P1V2_AUX_VCC")
		)
		(pad "14" smd circle
			(at -0.249936 -1.450086 180)
			(size 0 0)
			(layers "F.Cu" "F.Mask" "F.Paste")
			(net "GND")
		)
	)
	(footprint ""
		(layer "F.Cu")
		(at 355.506782 -413.046418)
		(property "Reference" "R4153"
			(at 0 0 0)
			(layer "F.SilkS")
			(hide yes)
			(effects
				(font
					(size 1.27 1.27)
				)
			)
		)
		(property "Value" ""
			(at 0 0 0)
			(layer "F.Fab")
			(effects
				(font
					(size 1.27 1.27)
				)
			)
		)
		(duplicate_pad_numbers_are_jumpers no)
		(fp_line
			(start -0.7874 -0.4064)
			(end 0.7874 -0.4064)
			(stroke
				(width 0.1524)
				(type default)
			)
			(layer "F.SilkS")
		)
		(fp_line
			(start -0.7874 0.4064)
			(end -0.7874 -0.4064)
			(stroke
				(width 0.1524)
				(type default)
			)
			(layer "F.SilkS")
		)
		(fp_line
			(start 0.7874 -0.4064)
			(end 0.7874 0.4064)
			(stroke
				(width 0.1524)
				(type default)
			)
			(layer "F.SilkS")
		)
		(fp_line
			(start 0.7874 0.4064)
			(end -0.7874 0.4064)
			(stroke
				(width 0.1524)
				(type default)
			)
			(layer "F.SilkS")
		)
		(fp_line
			(start -0.67945 -0.305054)
			(end -0.12065 -0.305054)
			(stroke
				(width 0.1)
				(type default)
			)
			(layer "F.Fab")
		)
		(fp_line
			(start -0.67945 0.3048)
			(end -0.67945 -0.305054)
			(stroke
				(width 0.1)
				(type default)
			)
			(layer "F.Fab")
		)
		(fp_line
			(start -0.12065 -0.305054)
			(end -0.12065 -0.2794)
			(stroke
				(width 0.1)
				(type default)
			)
			(layer "F.Fab")
		)
		(fp_line
			(start -0.12065 -0.2794)
			(end 0.12065 -0.2794)
			(stroke
				(width 0.1)
				(type default)
			)
			(layer "F.Fab")
		)
		(fp_line
			(start -0.12065 0.2794)
			(end -0.12065 0.3048)
			(stroke
				(width 0.1)
				(type default)
			)
			(layer "F.Fab")
		)
		(fp_line
			(start -0.12065 0.3048)
			(end -0.67945 0.3048)
			(stroke
				(width 0.1)
				(type default)
			)
			(layer "F.Fab")
		)
		(fp_line
			(start 0.120396 0.2794)
			(end -0.12065 0.2794)
			(stroke
				(width 0.1)
				(type default)
			)
			(layer "F.Fab")
		)
		(fp_line
			(start 0.120396 0.3048)
			(end 0.120396 0.2794)
			(stroke
				(width 0.1)
				(type default)
			)
			(layer "F.Fab")
		)
		(fp_line
			(start 0.12065 -0.3048)
			(end 0.67945 -0.3048)
			(stroke
				(width 0.1)
				(type default)
			)
			(layer "F.Fab")
		)
		(fp_line
			(start 0.12065 -0.2794)
			(end 0.12065 -0.3048)
			(stroke
				(width 0.1)
				(type default)
			)
			(layer "F.Fab")
		)
		(fp_line
			(start 0.67945 -0.3048)
			(end 0.67945 0.3048)
			(stroke
				(width 0.1)
				(type default)
			)
			(layer "F.Fab")
		)
		(fp_line
			(start 0.67945 0.3048)
			(end 0.120396 0.3048)
			(stroke
				(width 0.1)
				(type default)
			)
			(layer "F.Fab")
		)
		(pad "1" smd circle
			(at -0.40005 0)
			(size 0 0)
			(layers "F.Cu" "F.Mask" "F.Paste")
			(net "P3V3_AUX")
		)
		(pad "2" smd circle
			(at 0.40005 0)
			(size 0 0)
			(layers "F.Cu" "F.Mask" "F.Paste")
			(net "PRSNT_CABLE_GPU_A1_N")
		)
	)
	(footprint ""
		(layer "F.Cu")
		(at 44.623228 -399.41246)
		(property "Reference" "R6704"
			(at 0 0 0)
			(layer "F.SilkS")
			(hide yes)
			(effects
				(font
					(size 1.27 1.27)
				)
			)
		)
		(property "Value" ""
			(at 0 0 0)
			(layer "F.Fab")
			(effects
				(font
					(size 1.27 1.27)
				)
			)
		)
		(duplicate_pad_numbers_are_jumpers no)
		(fp_line
			(start -1.2954 -0.5842)
			(end 1.2954 -0.5842)
			(stroke
				(width 0.1524)
				(type default)
			)
			(layer "F.SilkS")
		)
		(fp_line
			(start -1.2954 0.5842)
			(end -1.2954 -0.5842)
			(stroke
				(width 0.1524)
				(type default)
			)
			(layer "F.SilkS")
		)
		(fp_line
			(start 1.2954 -0.5842)
			(end 1.2954 0.5842)
			(stroke
				(width 0.1524)
				(type default)
			)
			(layer "F.SilkS")
		)
		(fp_line
			(start 1.2954 0.5842)
			(end -1.2954 0.5842)
			(stroke
				(width 0.1524)
				(type default)
			)
			(layer "F.SilkS")
		)
		(fp_line
			(start -1.1938 -0.406654)
			(end -0.8636 -0.406654)
			(stroke
				(width 0.1)
				(type default)
			)
			(layer "F.Fab")
		)
		(fp_line
			(start -1.1938 0.4064)
			(end -1.1938 -0.406654)
			(stroke
				(width 0.1)
				(type default)
			)
			(layer "F.Fab")
		)
		(fp_line
			(start -0.8636 -0.4572)
			(end 0.8636 -0.4572)
			(stroke
				(width 0.1)
				(type default)
			)
			(layer "F.Fab")
		)
		(fp_line
			(start -0.8636 -0.406654)
			(end -0.8636 -0.4572)
			(stroke
				(width 0.1)
				(type default)
			)
			(layer "F.Fab")
		)
		(fp_line
			(start -0.8636 0.4064)
			(end -1.1938 0.4064)
			(stroke
				(width 0.1)
				(type default)
			)
			(layer "F.Fab")
		)
		(fp_line
			(start -0.8636 0.4318)
			(end -0.8636 0.4064)
			(stroke
				(width 0.1)
				(type default)
			)
			(layer "F.Fab")
		)
		(fp_line
			(start -0.8636 0.4572)
			(end -0.8636 0.4318)
			(stroke
				(width 0.1)
				(type default)
			)
			(layer "F.Fab")
		)
		(fp_line
			(start 0.8636 -0.4572)
			(end 0.8636 -0.406654)
			(stroke
				(width 0.1)
				(type default)
			)
			(layer "F.Fab")
		)
		(fp_line
			(start 0.8636 -0.406654)
			(end 1.1938 -0.406654)
			(stroke
				(width 0.1)
				(type default)
			)
			(layer "F.Fab")
		)
		(fp_line
			(start 0.8636 0.4064)
			(end 0.8636 0.4572)
			(stroke
				(width 0.1)
				(type default)
			)
			(layer "F.Fab")
		)
		(fp_line
			(start 0.8636 0.4572)
			(end -0.8636 0.4572)
			(stroke
				(width 0.1)
				(type default)
			)
			(layer "F.Fab")
		)
		(fp_line
			(start 1.1938 -0.406654)
			(end 1.1938 0.4064)
			(stroke
				(width 0.1)
				(type default)
			)
			(layer "F.Fab")
		)
		(fp_line
			(start 1.1938 0.4064)
			(end 0.8636 0.4064)
			(stroke
				(width 0.1)
				(type default)
			)
			(layer "F.Fab")
		)
		(pad "1" smd rect
			(at -0.7366 0 270)
			(size 0.7112 0.8128)
			(layers "F.Cu" "F.Mask" "F.Paste")
			(net "P0V9_CPU1_RT_2D")
		)
		(pad "2" smd rect
			(at 0.7366 0 270)
			(size 0.7112 0.8128)
			(layers "F.Cu" "F.Mask" "F.Paste")
			(net "P0V9_CPU1_RT0_2A_2D")
		)
	)
	(footprint ""
		(layer "F.Cu")
		(at 337.464146 -416.899344 -90)
		(property "Reference" "C6524"
			(at 0 0 270)
			(layer "F.SilkS")
			(hide yes)
			(effects
				(font
					(size 1.27 1.27)
				)
			)
		)
		(property "Value" ""
			(at 0 0 270)
			(layer "F.Fab")
			(effects
				(font
					(size 1.27 1.27)
				)
			)
		)
		(duplicate_pad_numbers_are_jumpers no)
		(fp_line
			(start -0.299974 0.150114)
			(end -0.299974 -0.150114)
			(stroke
				(width 0.1)
				(type default)
			)
			(layer "F.Fab")
		)
		(fp_line
			(start 0.299974 0.150114)
			(end -0.299974 0.150114)
			(stroke
				(width 0.1)
				(type default)
			)
			(layer "F.Fab")
		)
		(fp_line
			(start -0.299974 -0.150114)
			(end 0.299974 -0.150114)
			(stroke
				(width 0.1)
				(type default)
			)
			(layer "F.Fab")
		)
		(fp_line
			(start 0.299974 -0.150114)
			(end 0.299974 0.150114)
			(stroke
				(width 0.1)
				(type default)
			)
			(layer "F.Fab")
		)
		(pad "1" smd rect
			(at -0.2667 0 270)
			(size 0.3048 0.381)
			(layers "F.Cu" "F.Mask" "F.Paste")
			(net "P5E_CPU0_P0_TX_BUF_C_DN<11>")
		)
		(pad "2" smd rect
			(at 0.2667 0 270)
			(size 0.3048 0.381)
			(layers "F.Cu" "F.Mask" "F.Paste")
			(net "P5E_CPU0_P0_TX_BUF_DN<11>")
		)
	)
	(footprint ""
		(layer "F.Cu")
		(at 201.047604 -34.923984 90)
		(property "Reference" "R3635"
			(at 5.299456 -1.945132 0)
			(unlocked yes)
			(layer "F.SilkS")
			(effects
				(font
					(size 0.7874 0.5842)
					(thickness 0.1524)
				)
				(justify left)
			)
		)
		(property "Value" ""
			(at 0 0 90)
			(layer "F.Fab")
			(effects
				(font
					(size 1.27 1.27)
				)
			)
		)
		(duplicate_pad_numbers_are_jumpers no)
		(fp_line
			(start 3.937508 -1.8796)
			(end -3.937508 -1.8796)
			(stroke
				(width 0.1524)
				(type default)
			)
			(layer "F.SilkS")
		)
		(fp_line
			(start -3.937508 -1.8796)
			(end -3.937508 1.8796)
			(stroke
				(width 0.1524)
				(type default)
			)
			(layer "F.SilkS")
		)
		(fp_line
			(start 3.937508 1.8796)
			(end 3.937508 -1.8796)
			(stroke
				(width 0.1524)
				(type default)
			)
			(layer "F.SilkS")
		)
		(fp_line
			(start -3.937508 1.8796)
			(end 3.937508 1.8796)
			(stroke
				(width 0.1524)
				(type default)
			)
			(layer "F.SilkS")
		)
		(fp_line
			(start 3.275076 -1.674876)
			(end -3.275076 -1.674876)
			(stroke
				(width 0.1)
				(type default)
			)
			(layer "F.Fab")
		)
		(fp_line
			(start -3.275076 -1.674876)
			(end -3.275076 1.674876)
			(stroke
				(width 0.1)
				(type default)
			)
			(layer "F.Fab")
		)
		(fp_line
			(start 3.275076 1.674876)
			(end 3.275076 -1.674876)
			(stroke
				(width 0.1)
				(type default)
			)
			(layer "F.Fab")
		)
		(fp_line
			(start -3.275076 1.674876)
			(end 3.275076 1.674876)
			(stroke
				(width 0.1)
				(type default)
			)
			(layer "F.Fab")
		)
		(pad "1" smd rect
			(at -2.350008 0 90)
			(size 2.921 3.5052)
			(layers "F.Cu" "F.Mask" "F.Paste")
			(net "P12V_SCM")
		)
		(pad "2" smd rect
			(at 2.350008 0 90)
			(size 2.921 3.5052)
			(layers "F.Cu" "F.Mask" "F.Paste")
			(net "P12V_SCM_R")
		)
	)
	(footprint ""
		(layer "F.Cu")
		(at 379.704092 -381.41783 -90)
		(property "Reference" "C885"
			(at 0 0 270)
			(layer "F.SilkS")
			(hide yes)
			(effects
				(font
					(size 1.27 1.27)
				)
			)
		)
		(property "Value" ""
			(at 0 0 270)
			(layer "F.Fab")
			(effects
				(font
					(size 1.27 1.27)
				)
			)
		)
		(duplicate_pad_numbers_are_jumpers no)
		(fp_line
			(start -0.299974 0.150114)
			(end -0.299974 -0.150114)
			(stroke
				(width 0.1)
				(type default)
			)
			(layer "F.Fab")
		)
		(fp_line
			(start 0.299974 0.150114)
			(end -0.299974 0.150114)
			(stroke
				(width 0.1)
				(type default)
			)
			(layer "F.Fab")
		)
		(fp_line
			(start -0.299974 -0.150114)
			(end 0.299974 -0.150114)
			(stroke
				(width 0.1)
				(type default)
			)
			(layer "F.Fab")
		)
		(fp_line
			(start 0.299974 -0.150114)
			(end 0.299974 0.150114)
			(stroke
				(width 0.1)
				(type default)
			)
			(layer "F.Fab")
		)
		(pad "1" smd rect
			(at -0.2667 0 270)
			(size 0.3048 0.381)
			(layers "F.Cu" "F.Mask" "F.Paste")
			(net "P5E_CPU0_P3_TX_C_DP<8>")
		)
		(pad "2" smd rect
			(at 0.2667 0 270)
			(size 0.3048 0.381)
			(layers "F.Cu" "F.Mask" "F.Paste")
			(net "P5E_CPU0_P3_TX_DP<8>")
		)
	)
	(footprint ""
		(layer "F.Cu")
		(at 160.06953 -352.668078 -90)
		(property "Reference" "R8381"
			(at 0 0 270)
			(layer "F.SilkS")
			(hide yes)
			(effects
				(font
					(size 1.27 1.27)
				)
			)
		)
		(property "Value" ""
			(at 0 0 270)
			(layer "F.Fab")
			(effects
				(font
					(size 1.27 1.27)
				)
			)
		)
		(duplicate_pad_numbers_are_jumpers no)
		(fp_line
			(start -0.7874 0.4064)
			(end -0.7874 -0.4064)
			(stroke
				(width 0.1524)
				(type default)
			)
			(layer "F.SilkS")
		)
		(fp_line
			(start 0.7874 0.4064)
			(end -0.7874 0.4064)
			(stroke
				(width 0.1524)
				(type default)
			)
			(layer "F.SilkS")
		)
		(fp_line
			(start -0.7874 -0.4064)
			(end 0.7874 -0.4064)
			(stroke
				(width 0.1524)
				(type default)
			)
			(layer "F.SilkS")
		)
		(fp_line
			(start 0.7874 -0.4064)
			(end 0.7874 0.4064)
			(stroke
				(width 0.1524)
				(type default)
			)
			(layer "F.SilkS")
		)
		(fp_line
			(start -0.67945 0.3048)
			(end -0.67945 -0.305054)
			(stroke
				(width 0.1)
				(type default)
			)
			(layer "F.Fab")
		)
		(fp_line
			(start -0.12065 0.3048)
			(end -0.67945 0.3048)
			(stroke
				(width 0.1)
				(type default)
			)
			(layer "F.Fab")
		)
		(fp_line
			(start 0.120396 0.3048)
			(end 0.120396 0.2794)
			(stroke
				(width 0.1)
				(type default)
			)
			(layer "F.Fab")
		)
		(fp_line
			(start 0.67945 0.3048)
			(end 0.120396 0.3048)
			(stroke
				(width 0.1)
				(type default)
			)
			(layer "F.Fab")
		)
		(fp_line
			(start -0.12065 0.2794)
			(end -0.12065 0.3048)
			(stroke
				(width 0.1)
				(type default)
			)
			(layer "F.Fab")
		)
		(fp_line
			(start 0.120396 0.2794)
			(end -0.12065 0.2794)
			(stroke
				(width 0.1)
				(type default)
			)
			(layer "F.Fab")
		)
		(fp_line
			(start -0.12065 -0.2794)
			(end 0.12065 -0.2794)
			(stroke
				(width 0.1)
				(type default)
			)
			(layer "F.Fab")
		)
		(fp_line
			(start 0.12065 -0.2794)
			(end 0.12065 -0.3048)
			(stroke
				(width 0.1)
				(type default)
			)
			(layer "F.Fab")
		)
		(fp_line
			(start 0.12065 -0.3048)
			(end 0.67945 -0.3048)
			(stroke
				(width 0.1)
				(type default)
			)
			(layer "F.Fab")
		)
		(fp_line
			(start 0.67945 -0.3048)
			(end 0.67945 0.3048)
			(stroke
				(width 0.1)
				(type default)
			)
			(layer "F.Fab")
		)
		(fp_line
			(start -0.67945 -0.305054)
			(end -0.12065 -0.305054)
			(stroke
				(width 0.1)
				(type default)
			)
			(layer "F.Fab")
		)
		(fp_line
			(start -0.12065 -0.305054)
			(end -0.12065 -0.2794)
			(stroke
				(width 0.1)
				(type default)
			)
			(layer "F.Fab")
		)
		(pad "1" smd circle
			(at -0.40005 0 270)
			(size 0 0)
			(layers "F.Cu" "F.Mask" "F.Paste")
			(net "SMB_SCM_2_R2_SCL")
		)
		(pad "2" smd circle
			(at 0.40005 0 270)
			(size 0 0)
			(layers "F.Cu" "F.Mask" "F.Paste")
			(net "PVDD11_S3_P1_PMSCL_R")
		)
	)
	(footprint ""
		(layer "F.Cu")
		(at 77.638148 -179.360068 -90)
		(property "Reference" "PR46"
			(at 0 0 270)
			(layer "F.SilkS")
			(hide yes)
			(effects
				(font
					(size 1.27 1.27)
				)
			)
		)
		(property "Value" ""
			(at 0 0 270)
			(layer "F.Fab")
			(effects
				(font
					(size 1.27 1.27)
				)
			)
		)
		(duplicate_pad_numbers_are_jumpers no)
		(fp_line
			(start -0.7874 0.4064)
			(end -0.7874 -0.4064)
			(stroke
				(width 0.1524)
				(type default)
			)
			(layer "F.SilkS")
		)
		(fp_line
			(start 0.7874 0.4064)
			(end -0.7874 0.4064)
			(stroke
				(width 0.1524)
				(type default)
			)
			(layer "F.SilkS")
		)
		(fp_line
			(start -0.7874 -0.4064)
			(end 0.7874 -0.4064)
			(stroke
				(width 0.1524)
				(type default)
			)
			(layer "F.SilkS")
		)
		(fp_line
			(start 0.7874 -0.4064)
			(end 0.7874 0.4064)
			(stroke
				(width 0.1524)
				(type default)
			)
			(layer "F.SilkS")
		)
		(fp_line
			(start -0.67945 0.3048)
			(end -0.67945 -0.305054)
			(stroke
				(width 0.1)
				(type default)
			)
			(layer "F.Fab")
		)
		(fp_line
			(start -0.12065 0.3048)
			(end -0.67945 0.3048)
			(stroke
				(width 0.1)
				(type default)
			)
			(layer "F.Fab")
		)
		(fp_line
			(start 0.120396 0.3048)
			(end 0.120396 0.2794)
			(stroke
				(width 0.1)
				(type default)
			)
			(layer "F.Fab")
		)
		(fp_line
			(start 0.67945 0.3048)
			(end 0.120396 0.3048)
			(stroke
				(width 0.1)
				(type default)
			)
			(layer "F.Fab")
		)
		(fp_line
			(start -0.12065 0.2794)
			(end -0.12065 0.3048)
			(stroke
				(width 0.1)
				(type default)
			)
			(layer "F.Fab")
		)
		(fp_line
			(start 0.120396 0.2794)
			(end -0.12065 0.2794)
			(stroke
				(width 0.1)
				(type default)
			)
			(layer "F.Fab")
		)
		(fp_line
			(start -0.12065 -0.2794)
			(end 0.12065 -0.2794)
			(stroke
				(width 0.1)
				(type default)
			)
			(layer "F.Fab")
		)
		(fp_line
			(start 0.12065 -0.2794)
			(end 0.12065 -0.3048)
			(stroke
				(width 0.1)
				(type default)
			)
			(layer "F.Fab")
		)
		(fp_line
			(start 0.12065 -0.3048)
			(end 0.67945 -0.3048)
			(stroke
				(width 0.1)
				(type default)
			)
			(layer "F.Fab")
		)
		(fp_line
			(start 0.67945 -0.3048)
			(end 0.67945 0.3048)
			(stroke
				(width 0.1)
				(type default)
			)
			(layer "F.Fab")
		)
		(fp_line
			(start -0.67945 -0.305054)
			(end -0.12065 -0.305054)
			(stroke
				(width 0.1)
				(type default)
			)
			(layer "F.Fab")
		)
		(fp_line
			(start -0.12065 -0.305054)
			(end -0.12065 -0.2794)
			(stroke
				(width 0.1)
				(type default)
			)
			(layer "F.Fab")
		)
		(pad "1" smd circle
			(at -0.40005 0 270)
			(size 0 0)
			(layers "F.Cu" "F.Mask" "F.Paste")
			(net "SW_PVDDCR_CPU0_P1_SW5_RC")
		)
		(pad "2" smd circle
			(at 0.40005 0 270)
			(size 0 0)
			(layers "F.Cu" "F.Mask" "F.Paste")
			(net "GND")
		)
	)
	(footprint ""
		(layer "F.Cu")
		(at 372.557294 -192.061084 180)
		(property "Reference" "PL52"
			(at 4.468876 2.638806 90)
			(unlocked yes)
			(layer "F.SilkS")
			(effects
				(font
					(size 0.7874 0.5842)
					(thickness 0.1524)
				)
				(justify left)
			)
		)
		(property "Value" ""
			(at 0 0 180)
			(layer "F.Fab")
			(effects
				(font
					(size 1.27 1.27)
				)
			)
		)
		(duplicate_pad_numbers_are_jumpers no)
		(fp_line
			(start 3.750056 5.500116)
			(end 3.750056 -5.500116)
			(stroke
				(width 0.1524)
				(type default)
			)
			(layer "F.SilkS")
		)
		(fp_line
			(start 3.750056 -5.500116)
			(end 2.393442 -5.500116)
			(stroke
				(width 0.1524)
				(type default)
			)
			(layer "F.SilkS")
		)
		(fp_line
			(start 2.393442 5.500116)
			(end 3.750056 5.500116)
			(stroke
				(width 0.1524)
				(type default)
			)
			(layer "F.SilkS")
		)
		(fp_line
			(start -2.393442 5.500116)
			(end -3.750056 5.500116)
			(stroke
				(width 0.1524)
				(type default)
			)
			(layer "F.SilkS")
		)
		(fp_line
			(start -3.750056 5.500116)
			(end -3.750056 -5.500116)
			(stroke
				(width 0.1524)
				(type default)
			)
			(layer "F.SilkS")
		)
		(fp_line
			(start -3.750056 -5.500116)
			(end -2.393442 -5.500116)
			(stroke
				(width 0.1524)
				(type default)
			)
			(layer "F.SilkS")
		)
		(fp_poly
			(pts
				(xy -3.9116 -4.249928) (xy -4.505706 -3.952748) (xy -4.505706 -4.547108)
			)
			(stroke
				(width 0)
				(type default)
			)
			(fill yes)
			(layer "F.SilkS")
		)
		(fp_line
			(start 3.750056 5.500116)
			(end 3.750056 -5.500116)
			(stroke
				(width 0.1)
				(type default)
			)
			(layer "F.Fab")
		)
		(fp_line
			(start 3.750056 -5.500116)
			(end -3.750056 -5.500116)
			(stroke
				(width 0.1)
				(type default)
			)
			(layer "F.Fab")
		)
		(fp_line
			(start -3.750056 5.500116)
			(end 3.750056 5.500116)
			(stroke
				(width 0.1)
				(type default)
			)
			(layer "F.Fab")
		)
		(fp_line
			(start -3.750056 -5.500116)
			(end -3.750056 5.500116)
			(stroke
				(width 0.1)
				(type default)
			)
			(layer "F.Fab")
		)
		(fp_poly
			(pts
				(xy -4.9276 -4.757928) (xy -4.9276 -3.741928) (xy -3.9116 -4.249928)
			)
			(stroke
				(width 0)
				(type default)
			)
			(fill yes)
			(layer "F.Fab")
		)
		(pad "1" smd rect
			(at 0 -4.249928 90)
			(size 2.413 4.5212)
			(layers "F.Cu" "F.Mask" "F.Paste")
			(net "SW_PVDDCR_CPU0_P0_SW2")
		)
		(pad "2" smd rect
			(at 0 -1.175004 90)
			(size 1.3716 4.5212)
			(layers "F.Cu" "F.Mask" "F.Paste")
			(net "IND_CPU0_P0_CPL1")
		)
		(pad "3" smd rect
			(at 0 1.175004 90)
			(size 1.3716 4.5212)
			(layers "F.Cu" "F.Mask" "F.Paste")
			(net "IND_CPU0_P0_CPL2")
		)
		(pad "4" smd rect
			(at 0 4.249928 90)
			(size 2.413 4.5212)
			(layers "F.Cu" "F.Mask" "F.Paste")
			(net "PVDDCR_CPU0_P0")
		)
	)
	(footprint ""
		(layer "F.Cu")
		(at 142.595092 -382.39446 180)
		(property "Reference" "C773"
			(at 0 0 180)
			(layer "F.SilkS")
			(hide yes)
			(effects
				(font
					(size 1.27 1.27)
				)
			)
		)
		(property "Value" ""
			(at 0 0 180)
			(layer "F.Fab")
			(effects
				(font
					(size 1.27 1.27)
				)
			)
		)
		(duplicate_pad_numbers_are_jumpers no)
		(fp_line
			(start 0.299974 0.150114)
			(end -0.299974 0.150114)
			(stroke
				(width 0.1)
				(type default)
			)
			(layer "F.Fab")
		)
		(fp_line
			(start 0.299974 -0.150114)
			(end 0.299974 0.150114)
			(stroke
				(width 0.1)
				(type default)
			)
			(layer "F.Fab")
		)
		(fp_line
			(start -0.299974 0.150114)
			(end -0.299974 -0.150114)
			(stroke
				(width 0.1)
				(type default)
			)
			(layer "F.Fab")
		)
		(fp_line
			(start -0.299974 -0.150114)
			(end 0.299974 -0.150114)
			(stroke
				(width 0.1)
				(type default)
			)
			(layer "F.Fab")
		)
		(pad "1" smd rect
			(at -0.2667 0 180)
			(size 0.3048 0.381)
			(layers "F.Cu" "F.Mask" "F.Paste")
			(net "P5E_CPU1_P2_TX_C_DP<0>")
		)
		(pad "2" smd rect
			(at 0.2667 0 180)
			(size 0.3048 0.381)
			(layers "F.Cu" "F.Mask" "F.Paste")
			(net "P5E_CPU1_P2_TX_DP<0>")
		)
	)
	(footprint ""
		(layer "F.Cu")
		(at 426.974 -366.141 -90)
		(property "Reference" "PR125"
			(at 0 0 270)
			(layer "F.SilkS")
			(hide yes)
			(effects
				(font
					(size 1.27 1.27)
				)
			)
		)
		(property "Value" ""
			(at 0 0 270)
			(layer "F.Fab")
			(effects
				(font
					(size 1.27 1.27)
				)
			)
		)
		(duplicate_pad_numbers_are_jumpers no)
		(fp_line
			(start -0.7874 0.4064)
			(end -0.7874 -0.4064)
			(stroke
				(width 0.1524)
				(type default)
			)
			(layer "F.SilkS")
		)
		(fp_line
			(start 0.7874 0.4064)
			(end -0.7874 0.4064)
			(stroke
				(width 0.1524)
				(type default)
			)
			(layer "F.SilkS")
		)
		(fp_line
			(start -0.7874 -0.4064)
			(end 0.7874 -0.4064)
			(stroke
				(width 0.1524)
				(type default)
			)
			(layer "F.SilkS")
		)
		(fp_line
			(start 0.7874 -0.4064)
			(end 0.7874 0.4064)
			(stroke
				(width 0.1524)
				(type default)
			)
			(layer "F.SilkS")
		)
		(fp_line
			(start -0.67945 0.3048)
			(end -0.67945 -0.305054)
			(stroke
				(width 0.1)
				(type default)
			)
			(layer "F.Fab")
		)
		(fp_line
			(start -0.12065 0.3048)
			(end -0.67945 0.3048)
			(stroke
				(width 0.1)
				(type default)
			)
			(layer "F.Fab")
		)
		(fp_line
			(start 0.120396 0.3048)
			(end 0.120396 0.2794)
			(stroke
				(width 0.1)
				(type default)
			)
			(layer "F.Fab")
		)
		(fp_line
			(start 0.67945 0.3048)
			(end 0.120396 0.3048)
			(stroke
				(width 0.1)
				(type default)
			)
			(layer "F.Fab")
		)
		(fp_line
			(start -0.12065 0.2794)
			(end -0.12065 0.3048)
			(stroke
				(width 0.1)
				(type default)
			)
			(layer "F.Fab")
		)
		(fp_line
			(start 0.120396 0.2794)
			(end -0.12065 0.2794)
			(stroke
				(width 0.1)
				(type default)
			)
			(layer "F.Fab")
		)
		(fp_line
			(start -0.12065 -0.2794)
			(end 0.12065 -0.2794)
			(stroke
				(width 0.1)
				(type default)
			)
			(layer "F.Fab")
		)
		(fp_line
			(start 0.12065 -0.2794)
			(end 0.12065 -0.3048)
			(stroke
				(width 0.1)
				(type default)
			)
			(layer "F.Fab")
		)
		(fp_line
			(start 0.12065 -0.3048)
			(end 0.67945 -0.3048)
			(stroke
				(width 0.1)
				(type default)
			)
			(layer "F.Fab")
		)
		(fp_line
			(start 0.67945 -0.3048)
			(end 0.67945 0.3048)
			(stroke
				(width 0.1)
				(type default)
			)
			(layer "F.Fab")
		)
		(fp_line
			(start -0.67945 -0.305054)
			(end -0.12065 -0.305054)
			(stroke
				(width 0.1)
				(type default)
			)
			(layer "F.Fab")
		)
		(fp_line
			(start -0.12065 -0.305054)
			(end -0.12065 -0.2794)
			(stroke
				(width 0.1)
				(type default)
			)
			(layer "F.Fab")
		)
		(pad "1" smd circle
			(at -0.40005 0 270)
			(size 0 0)
			(layers "F.Cu" "F.Mask" "F.Paste")
			(net "P12V_AUX")
		)
		(pad "2" smd circle
			(at 0.40005 0 270)
			(size 0 0)
			(layers "F.Cu" "F.Mask" "F.Paste")
			(net "PVDD11_S3_P0_VINSEN")
		)
	)
	(footprint ""
		(layer "F.Cu")
		(at 337.537044 -383.88163 -90)
		(property "Reference" "C956"
			(at 0 0 270)
			(layer "F.SilkS")
			(hide yes)
			(effects
				(font
					(size 1.27 1.27)
				)
			)
		)
		(property "Value" ""
			(at 0 0 270)
			(layer "F.Fab")
			(effects
				(font
					(size 1.27 1.27)
				)
			)
		)
		(duplicate_pad_numbers_are_jumpers no)
		(fp_line
			(start -0.299974 0.150114)
			(end -0.299974 -0.150114)
			(stroke
				(width 0.1)
				(type default)
			)
			(layer "F.Fab")
		)
		(fp_line
			(start 0.299974 0.150114)
			(end -0.299974 0.150114)
			(stroke
				(width 0.1)
				(type default)
			)
			(layer "F.Fab")
		)
		(fp_line
			(start -0.299974 -0.150114)
			(end 0.299974 -0.150114)
			(stroke
				(width 0.1)
				(type default)
			)
			(layer "F.Fab")
		)
		(fp_line
			(start 0.299974 -0.150114)
			(end 0.299974 0.150114)
			(stroke
				(width 0.1)
				(type default)
			)
			(layer "F.Fab")
		)
		(pad "1" smd rect
			(at -0.2667 0 270)
			(size 0.3048 0.381)
			(layers "F.Cu" "F.Mask" "F.Paste")
			(net "P5E_CPU0_P1_TX_C_DN<4>")
		)
		(pad "2" smd rect
			(at 0.2667 0 270)
			(size 0.3048 0.381)
			(layers "F.Cu" "F.Mask" "F.Paste")
			(net "P5E_CPU0_P1_TX_DN<4>")
		)
	)
	(footprint ""
		(layer "F.Cu")
		(at 192.700148 -430.115726)
		(property "Reference" "R2793"
			(at 0 0 0)
			(layer "F.SilkS")
			(hide yes)
			(effects
				(font
					(size 1.27 1.27)
				)
			)
		)
		(property "Value" ""
			(at 0 0 0)
			(layer "F.Fab")
			(effects
				(font
					(size 1.27 1.27)
				)
			)
		)
		(duplicate_pad_numbers_are_jumpers no)
		(fp_line
			(start -0.7874 -0.4064)
			(end 0.7874 -0.4064)
			(stroke
				(width 0.1524)
				(type default)
			)
			(layer "F.SilkS")
		)
		(fp_line
			(start -0.7874 0.4064)
			(end -0.7874 -0.4064)
			(stroke
				(width 0.1524)
				(type default)
			)
			(layer "F.SilkS")
		)
		(fp_line
			(start 0.7874 -0.4064)
			(end 0.7874 0.4064)
			(stroke
				(width 0.1524)
				(type default)
			)
			(layer "F.SilkS")
		)
		(fp_line
			(start 0.7874 0.4064)
			(end -0.7874 0.4064)
			(stroke
				(width 0.1524)
				(type default)
			)
			(layer "F.SilkS")
		)
		(fp_line
			(start -0.67945 -0.305054)
			(end -0.12065 -0.305054)
			(stroke
				(width 0.1)
				(type default)
			)
			(layer "F.Fab")
		)
		(fp_line
			(start -0.67945 0.3048)
			(end -0.67945 -0.305054)
			(stroke
				(width 0.1)
				(type default)
			)
			(layer "F.Fab")
		)
		(fp_line
			(start -0.12065 -0.305054)
			(end -0.12065 -0.2794)
			(stroke
				(width 0.1)
				(type default)
			)
			(layer "F.Fab")
		)
		(fp_line
			(start -0.12065 -0.2794)
			(end 0.12065 -0.2794)
			(stroke
				(width 0.1)
				(type default)
			)
			(layer "F.Fab")
		)
		(fp_line
			(start -0.12065 0.2794)
			(end -0.12065 0.3048)
			(stroke
				(width 0.1)
				(type default)
			)
			(layer "F.Fab")
		)
		(fp_line
			(start -0.12065 0.3048)
			(end -0.67945 0.3048)
			(stroke
				(width 0.1)
				(type default)
			)
			(layer "F.Fab")
		)
		(fp_line
			(start 0.120396 0.2794)
			(end -0.12065 0.2794)
			(stroke
				(width 0.1)
				(type default)
			)
			(layer "F.Fab")
		)
		(fp_line
			(start 0.120396 0.3048)
			(end 0.120396 0.2794)
			(stroke
				(width 0.1)
				(type default)
			)
			(layer "F.Fab")
		)
		(fp_line
			(start 0.12065 -0.3048)
			(end 0.67945 -0.3048)
			(stroke
				(width 0.1)
				(type default)
			)
			(layer "F.Fab")
		)
		(fp_line
			(start 0.12065 -0.2794)
			(end 0.12065 -0.3048)
			(stroke
				(width 0.1)
				(type default)
			)
			(layer "F.Fab")
		)
		(fp_line
			(start 0.67945 -0.3048)
			(end 0.67945 0.3048)
			(stroke
				(width 0.1)
				(type default)
			)
			(layer "F.Fab")
		)
		(fp_line
			(start 0.67945 0.3048)
			(end 0.120396 0.3048)
			(stroke
				(width 0.1)
				(type default)
			)
			(layer "F.Fab")
		)
		(pad "1" smd circle
			(at -0.40005 0)
			(size 0 0)
			(layers "F.Cu" "F.Mask" "F.Paste")
			(net "FM_PDB_BUF_EN_R_N")
		)
		(pad "2" smd circle
			(at 0.40005 0)
			(size 0 0)
			(layers "F.Cu" "F.Mask" "F.Paste")
			(net "FM_PDB_BUF_EN_R1_N")
		)
	)
	(footprint ""
		(layer "F.Cu")
		(at 124.58827 -34.021268 180)
		(property "Reference" "C6022"
			(at 0 0 180)
			(layer "F.SilkS")
			(hide yes)
			(effects
				(font
					(size 1.27 1.27)
				)
			)
		)
		(property "Value" ""
			(at 0 0 180)
			(layer "F.Fab")
			(effects
				(font
					(size 1.27 1.27)
				)
			)
		)
		(duplicate_pad_numbers_are_jumpers no)
		(fp_line
			(start 0.40005 0.4064)
			(end -0.40005 0.4064)
			(stroke
				(width 0.1524)
				(type default)
			)
			(layer "F.SilkS")
		)
		(fp_line
			(start -0.40005 -0.4064)
			(end 0.40005 -0.4064)
			(stroke
				(width 0.1524)
				(type default)
			)
			(layer "F.SilkS")
		)
		(fp_line
			(start 0.6858 0.3048)
			(end 0.1016 0.3048)
			(stroke
				(width 0.1)
				(type default)
			)
			(layer "F.Fab")
		)
		(fp_line
			(start 0.6858 -0.3048)
			(end 0.6858 0.3048)
			(stroke
				(width 0.1)
				(type default)
			)
			(layer "F.Fab")
		)
		(fp_line
			(start 0.1016 0.3048)
			(end 0.1016 0.2794)
			(stroke
				(width 0.1)
				(type default)
			)
			(layer "F.Fab")
		)
		(fp_line
			(start 0.1016 0.2794)
			(end -0.1016 0.2794)
			(stroke
				(width 0.1)
				(type default)
			)
			(layer "F.Fab")
		)
		(fp_line
			(start 0.1016 -0.2794)
			(end 0.1016 -0.3048)
			(stroke
				(width 0.1)
				(type default)
			)
			(layer "F.Fab")
		)
		(fp_line
			(start 0.1016 -0.3048)
			(end 0.6858 -0.3048)
			(stroke
				(width 0.1)
				(type default)
			)
			(layer "F.Fab")
		)
		(fp_line
			(start -0.1016 0.3048)
			(end -0.6858 0.3048)
			(stroke
				(width 0.1)
				(type default)
			)
			(layer "F.Fab")
		)
		(fp_line
			(start -0.1016 0.2794)
			(end -0.1016 0.3048)
			(stroke
				(width 0.1)
				(type default)
			)
			(layer "F.Fab")
		)
		(fp_line
			(start -0.1016 -0.2794)
			(end 0.1016 -0.2794)
			(stroke
				(width 0.1)
				(type default)
			)
			(layer "F.Fab")
		)
		(fp_line
			(start -0.1016 -0.3048)
			(end -0.1016 -0.2794)
			(stroke
				(width 0.1)
				(type default)
			)
			(layer "F.Fab")
		)
		(fp_line
			(start -0.6858 0.3048)
			(end -0.6858 -0.3048)
			(stroke
				(width 0.1)
				(type default)
			)
			(layer "F.Fab")
		)
		(fp_line
			(start -0.6858 -0.3048)
			(end -0.1016 -0.3048)
			(stroke
				(width 0.1)
				(type default)
			)
			(layer "F.Fab")
		)
		(pad "1" smd rect
			(at -0.40005 0)
			(size 0.4572 0.508)
			(layers "F.Cu" "F.Mask" "F.Paste")
			(net "USB3_CPU0_BMC_RX_DN")
		)
		(pad "2" smd rect
			(at 0.40005 0)
			(size 0.4572 0.508)
			(layers "F.Cu" "F.Mask" "F.Paste")
			(net "USB3_CPU0_BMC_RX_C2_DN")
		)
	)
	(footprint ""
		(layer "F.Cu")
		(at 136.59358 -386.44068 90)
		(property "Reference" "C435"
			(at 0 0 90)
			(layer "F.SilkS")
			(hide yes)
			(effects
				(font
					(size 1.27 1.27)
				)
			)
		)
		(property "Value" ""
			(at 0 0 90)
			(layer "F.Fab")
			(effects
				(font
					(size 1.27 1.27)
				)
			)
		)
		(duplicate_pad_numbers_are_jumpers no)
		(fp_line
			(start 0.7874 -0.4064)
			(end 0.7874 0.4064)
			(stroke
				(width 0.1524)
				(type default)
			)
			(layer "F.SilkS")
		)
		(fp_line
			(start -0.7874 -0.4064)
			(end 0.7874 -0.4064)
			(stroke
				(width 0.1524)
				(type default)
			)
			(layer "F.SilkS")
		)
		(fp_line
			(start 0.7874 0.4064)
			(end -0.7874 0.4064)
			(stroke
				(width 0.1524)
				(type default)
			)
			(layer "F.SilkS")
		)
		(fp_line
			(start -0.7874 0.4064)
			(end -0.7874 -0.4064)
			(stroke
				(width 0.1524)
				(type default)
			)
			(layer "F.SilkS")
		)
		(fp_line
			(start -0.12065 -0.305054)
			(end -0.12065 -0.2794)
			(stroke
				(width 0.1)
				(type default)
			)
			(layer "F.Fab")
		)
		(fp_line
			(start -0.67945 -0.305054)
			(end -0.12065 -0.305054)
			(stroke
				(width 0.1)
				(type default)
			)
			(layer "F.Fab")
		)
		(fp_line
			(start 0.67945 -0.3048)
			(end 0.67945 0.3048)
			(stroke
				(width 0.1)
				(type default)
			)
			(layer "F.Fab")
		)
		(fp_line
			(start 0.12065 -0.3048)
			(end 0.67945 -0.3048)
			(stroke
				(width 0.1)
				(type default)
			)
			(layer "F.Fab")
		)
		(fp_line
			(start 0.12065 -0.2794)
			(end 0.12065 -0.3048)
			(stroke
				(width 0.1)
				(type default)
			)
			(layer "F.Fab")
		)
		(fp_line
			(start -0.12065 -0.2794)
			(end 0.12065 -0.2794)
			(stroke
				(width 0.1)
				(type default)
			)
			(layer "F.Fab")
		)
		(fp_line
			(start 0.120396 0.2794)
			(end -0.12065 0.2794)
			(stroke
				(width 0.1)
				(type default)
			)
			(layer "F.Fab")
		)
		(fp_line
			(start -0.12065 0.2794)
			(end -0.12065 0.3048)
			(stroke
				(width 0.1)
				(type default)
			)
			(layer "F.Fab")
		)
		(fp_line
			(start 0.67945 0.3048)
			(end 0.120396 0.3048)
			(stroke
				(width 0.1)
				(type default)
			)
			(layer "F.Fab")
		)
		(fp_line
			(start 0.120396 0.3048)
			(end 0.120396 0.2794)
			(stroke
				(width 0.1)
				(type default)
			)
			(layer "F.Fab")
		)
		(fp_line
			(start -0.12065 0.3048)
			(end -0.67945 0.3048)
			(stroke
				(width 0.1)
				(type default)
			)
			(layer "F.Fab")
		)
		(fp_line
			(start -0.67945 0.3048)
			(end -0.67945 -0.305054)
			(stroke
				(width 0.1)
				(type default)
			)
			(layer "F.Fab")
		)
		(pad "1" smd circle
			(at -0.40005 0 90)
			(size 0 0)
			(layers "F.Cu" "F.Mask" "F.Paste")
			(net "P1V8_CPU1_RT3_1A")
		)
		(pad "2" smd circle
			(at 0.40005 0 90)
			(size 0 0)
			(layers "F.Cu" "F.Mask" "F.Paste")
			(net "GND")
		)
	)
	(footprint ""
		(layer "F.Cu")
		(at 157.88259 -98.755708 90)
		(property "Reference" "R3303"
			(at 0 0 90)
			(layer "F.SilkS")
			(hide yes)
			(effects
				(font
					(size 1.27 1.27)
				)
			)
		)
		(property "Value" ""
			(at 0 0 90)
			(layer "F.Fab")
			(effects
				(font
					(size 1.27 1.27)
				)
			)
		)
		(duplicate_pad_numbers_are_jumpers no)
		(fp_line
			(start 0.7874 -0.4064)
			(end 0.7874 0.4064)
			(stroke
				(width 0.1524)
				(type default)
			)
			(layer "F.SilkS")
		)
		(fp_line
			(start -0.7874 -0.4064)
			(end 0.7874 -0.4064)
			(stroke
				(width 0.1524)
				(type default)
			)
			(layer "F.SilkS")
		)
		(fp_line
			(start 0.7874 0.4064)
			(end -0.7874 0.4064)
			(stroke
				(width 0.1524)
				(type default)
			)
			(layer "F.SilkS")
		)
		(fp_line
			(start -0.7874 0.4064)
			(end -0.7874 -0.4064)
			(stroke
				(width 0.1524)
				(type default)
			)
			(layer "F.SilkS")
		)
		(fp_line
			(start -0.12065 -0.305054)
			(end -0.12065 -0.2794)
			(stroke
				(width 0.1)
				(type default)
			)
			(layer "F.Fab")
		)
		(fp_line
			(start -0.67945 -0.305054)
			(end -0.12065 -0.305054)
			(stroke
				(width 0.1)
				(type default)
			)
			(layer "F.Fab")
		)
		(fp_line
			(start 0.67945 -0.3048)
			(end 0.67945 0.3048)
			(stroke
				(width 0.1)
				(type default)
			)
			(layer "F.Fab")
		)
		(fp_line
			(start 0.12065 -0.3048)
			(end 0.67945 -0.3048)
			(stroke
				(width 0.1)
				(type default)
			)
			(layer "F.Fab")
		)
		(fp_line
			(start 0.12065 -0.2794)
			(end 0.12065 -0.3048)
			(stroke
				(width 0.1)
				(type default)
			)
			(layer "F.Fab")
		)
		(fp_line
			(start -0.12065 -0.2794)
			(end 0.12065 -0.2794)
			(stroke
				(width 0.1)
				(type default)
			)
			(layer "F.Fab")
		)
		(fp_line
			(start 0.120396 0.2794)
			(end -0.12065 0.2794)
			(stroke
				(width 0.1)
				(type default)
			)
			(layer "F.Fab")
		)
		(fp_line
			(start -0.12065 0.2794)
			(end -0.12065 0.3048)
			(stroke
				(width 0.1)
				(type default)
			)
			(layer "F.Fab")
		)
		(fp_line
			(start 0.67945 0.3048)
			(end 0.120396 0.3048)
			(stroke
				(width 0.1)
				(type default)
			)
			(layer "F.Fab")
		)
		(fp_line
			(start 0.120396 0.3048)
			(end 0.120396 0.2794)
			(stroke
				(width 0.1)
				(type default)
			)
			(layer "F.Fab")
		)
		(fp_line
			(start -0.12065 0.3048)
			(end -0.67945 0.3048)
			(stroke
				(width 0.1)
				(type default)
			)
			(layer "F.Fab")
		)
		(fp_line
			(start -0.67945 0.3048)
			(end -0.67945 -0.305054)
			(stroke
				(width 0.1)
				(type default)
			)
			(layer "F.Fab")
		)
		(pad "1" smd circle
			(at -0.40005 0 90)
			(size 0 0)
			(layers "F.Cu" "F.Mask" "F.Paste")
			(net "OCP_SFF_PRSNT_ALL_R_N")
		)
		(pad "2" smd circle
			(at 0.40005 0 90)
			(size 0 0)
			(layers "F.Cu" "F.Mask" "F.Paste")
			(net "OCP_SFF_PRSNT_ALL_R1_N")
		)
	)
	(footprint ""
		(layer "F.Cu")
		(at 456.440794 -46.264576 -90)
		(property "Reference" "PR831"
			(at 0 0 270)
			(layer "F.SilkS")
			(hide yes)
			(effects
				(font
					(size 1.27 1.27)
				)
			)
		)
		(property "Value" ""
			(at 0 0 270)
			(layer "F.Fab")
			(effects
				(font
					(size 1.27 1.27)
				)
			)
		)
		(duplicate_pad_numbers_are_jumpers no)
		(fp_line
			(start -0.7874 0.4064)
			(end -0.7874 -0.4064)
			(stroke
				(width 0.1524)
				(type default)
			)
			(layer "F.SilkS")
		)
		(fp_line
			(start 0.7874 0.4064)
			(end -0.7874 0.4064)
			(stroke
				(width 0.1524)
				(type default)
			)
			(layer "F.SilkS")
		)
		(fp_line
			(start -0.7874 -0.4064)
			(end 0.7874 -0.4064)
			(stroke
				(width 0.1524)
				(type default)
			)
			(layer "F.SilkS")
		)
		(fp_line
			(start 0.7874 -0.4064)
			(end 0.7874 0.4064)
			(stroke
				(width 0.1524)
				(type default)
			)
			(layer "F.SilkS")
		)
		(fp_line
			(start -0.67945 0.3048)
			(end -0.67945 -0.305054)
			(stroke
				(width 0.1)
				(type default)
			)
			(layer "F.Fab")
		)
		(fp_line
			(start -0.12065 0.3048)
			(end -0.67945 0.3048)
			(stroke
				(width 0.1)
				(type default)
			)
			(layer "F.Fab")
		)
		(fp_line
			(start 0.120396 0.3048)
			(end 0.120396 0.2794)
			(stroke
				(width 0.1)
				(type default)
			)
			(layer "F.Fab")
		)
		(fp_line
			(start 0.67945 0.3048)
			(end 0.120396 0.3048)
			(stroke
				(width 0.1)
				(type default)
			)
			(layer "F.Fab")
		)
		(fp_line
			(start -0.12065 0.2794)
			(end -0.12065 0.3048)
			(stroke
				(width 0.1)
				(type default)
			)
			(layer "F.Fab")
		)
		(fp_line
			(start 0.120396 0.2794)
			(end -0.12065 0.2794)
			(stroke
				(width 0.1)
				(type default)
			)
			(layer "F.Fab")
		)
		(fp_line
			(start -0.12065 -0.2794)
			(end 0.12065 -0.2794)
			(stroke
				(width 0.1)
				(type default)
			)
			(layer "F.Fab")
		)
		(fp_line
			(start 0.12065 -0.2794)
			(end 0.12065 -0.3048)
			(stroke
				(width 0.1)
				(type default)
			)
			(layer "F.Fab")
		)
		(fp_line
			(start 0.12065 -0.3048)
			(end 0.67945 -0.3048)
			(stroke
				(width 0.1)
				(type default)
			)
			(layer "F.Fab")
		)
		(fp_line
			(start 0.67945 -0.3048)
			(end 0.67945 0.3048)
			(stroke
				(width 0.1)
				(type default)
			)
			(layer "F.Fab")
		)
		(fp_line
			(start -0.67945 -0.305054)
			(end -0.12065 -0.305054)
			(stroke
				(width 0.1)
				(type default)
			)
			(layer "F.Fab")
		)
		(fp_line
			(start -0.12065 -0.305054)
			(end -0.12065 -0.2794)
			(stroke
				(width 0.1)
				(type default)
			)
			(layer "F.Fab")
		)
		(pad "1" smd circle
			(at -0.40005 0 270)
			(size 0 0)
			(layers "F.Cu" "F.Mask" "F.Paste")
			(net "P3V3_AUX_FB")
		)
		(pad "2" smd circle
			(at 0.40005 0 270)
			(size 0 0)
			(layers "F.Cu" "F.Mask" "F.Paste")
			(net "P3V3_AUX")
		)
	)
	(footprint ""
		(layer "F.Cu")
		(at 68.16852 -394.3604 -90)
		(property "Reference" "R6720"
			(at 0 0 270)
			(layer "F.SilkS")
			(hide yes)
			(effects
				(font
					(size 1.27 1.27)
				)
			)
		)
		(property "Value" ""
			(at 0 0 270)
			(layer "F.Fab")
			(effects
				(font
					(size 1.27 1.27)
				)
			)
		)
		(duplicate_pad_numbers_are_jumpers no)
		(fp_line
			(start -0.32512 0.175006)
			(end -0.32512 -0.175006)
			(stroke
				(width 0.1)
				(type default)
			)
			(layer "F.Fab")
		)
		(fp_line
			(start 0.32512 0.175006)
			(end -0.32512 0.175006)
			(stroke
				(width 0.1)
				(type default)
			)
			(layer "F.Fab")
		)
		(fp_line
			(start -0.32512 -0.175006)
			(end 0.32512 -0.175006)
			(stroke
				(width 0.1)
				(type default)
			)
			(layer "F.Fab")
		)
		(fp_line
			(start 0.32512 -0.175006)
			(end 0.32512 0.175006)
			(stroke
				(width 0.1)
				(type default)
			)
			(layer "F.Fab")
		)
		(pad "1" smd rect
			(at -0.2667 0 270)
			(size 0.3048 0.381)
			(layers "F.Cu" "F.Mask" "F.Paste")
			(net "RST_RT_CPU1_P0_PERST_R_N")
		)
		(pad "2" smd rect
			(at 0.2667 0 90)
			(size 0.3048 0.381)
			(layers "F.Cu" "F.Mask" "F.Paste")
			(net "GND")
		)
	)
	(footprint ""
		(layer "F.Cu")
		(at 112.438942 -21.7678 -90)
		(property "Reference" "R6262"
			(at 0 0 270)
			(layer "F.SilkS")
			(hide yes)
			(effects
				(font
					(size 1.27 1.27)
				)
			)
		)
		(property "Value" ""
			(at 0 0 270)
			(layer "F.Fab")
			(effects
				(font
					(size 1.27 1.27)
				)
			)
		)
		(duplicate_pad_numbers_are_jumpers no)
		(fp_line
			(start -0.7874 0.4064)
			(end -0.7874 -0.4064)
			(stroke
				(width 0.1524)
				(type default)
			)
			(layer "F.SilkS")
		)
		(fp_line
			(start 0.7874 0.4064)
			(end -0.7874 0.4064)
			(stroke
				(width 0.1524)
				(type default)
			)
			(layer "F.SilkS")
		)
		(fp_line
			(start -0.7874 -0.4064)
			(end 0.7874 -0.4064)
			(stroke
				(width 0.1524)
				(type default)
			)
			(layer "F.SilkS")
		)
		(fp_line
			(start 0.7874 -0.4064)
			(end 0.7874 0.4064)
			(stroke
				(width 0.1524)
				(type default)
			)
			(layer "F.SilkS")
		)
		(fp_line
			(start -0.67945 0.3048)
			(end -0.67945 -0.305054)
			(stroke
				(width 0.1)
				(type default)
			)
			(layer "F.Fab")
		)
		(fp_line
			(start -0.12065 0.3048)
			(end -0.67945 0.3048)
			(stroke
				(width 0.1)
				(type default)
			)
			(layer "F.Fab")
		)
		(fp_line
			(start 0.120396 0.3048)
			(end 0.120396 0.2794)
			(stroke
				(width 0.1)
				(type default)
			)
			(layer "F.Fab")
		)
		(fp_line
			(start 0.67945 0.3048)
			(end 0.120396 0.3048)
			(stroke
				(width 0.1)
				(type default)
			)
			(layer "F.Fab")
		)
		(fp_line
			(start -0.12065 0.2794)
			(end -0.12065 0.3048)
			(stroke
				(width 0.1)
				(type default)
			)
			(layer "F.Fab")
		)
		(fp_line
			(start 0.120396 0.2794)
			(end -0.12065 0.2794)
			(stroke
				(width 0.1)
				(type default)
			)
			(layer "F.Fab")
		)
		(fp_line
			(start -0.12065 -0.2794)
			(end 0.12065 -0.2794)
			(stroke
				(width 0.1)
				(type default)
			)
			(layer "F.Fab")
		)
		(fp_line
			(start 0.12065 -0.2794)
			(end 0.12065 -0.3048)
			(stroke
				(width 0.1)
				(type default)
			)
			(layer "F.Fab")
		)
		(fp_line
			(start 0.12065 -0.3048)
			(end 0.67945 -0.3048)
			(stroke
				(width 0.1)
				(type default)
			)
			(layer "F.Fab")
		)
		(fp_line
			(start 0.67945 -0.3048)
			(end 0.67945 0.3048)
			(stroke
				(width 0.1)
				(type default)
			)
			(layer "F.Fab")
		)
		(fp_line
			(start -0.67945 -0.305054)
			(end -0.12065 -0.305054)
			(stroke
				(width 0.1)
				(type default)
			)
			(layer "F.Fab")
		)
		(fp_line
			(start -0.12065 -0.305054)
			(end -0.12065 -0.2794)
			(stroke
				(width 0.1)
				(type default)
			)
			(layer "F.Fab")
		)
		(pad "1" smd circle
			(at -0.40005 0 270)
			(size 0 0)
			(layers "F.Cu" "F.Mask" "F.Paste")
			(net "USB_HUB2_TI_VDD_MRP_USB3DN_RXDM1")
		)
		(pad "2" smd circle
			(at 0.40005 0 270)
			(size 0 0)
			(layers "F.Cu" "F.Mask" "F.Paste")
			(net "P1V2_CPU0_USB2_DVDD12")
		)
	)
	(footprint ""
		(layer "F.Cu")
		(at 509.384808 -142.846806 90)
		(property "Reference" "X8008"
			(at -2.000758 1.744472 0)
			(unlocked yes)
			(layer "F.SilkS")
			(effects
				(font
					(size 0.7874 0.5842)
					(thickness 0.1524)
				)
				(justify left)
			)
		)
		(property "Value" ""
			(at 0 0 90)
			(layer "F.Fab")
			(effects
				(font
					(size 1.27 1.27)
				)
			)
		)
		(property "Device Type" "TP_TDR_4P_FTS_TH-TP_TDR_4P_DIP,EMPTY,TP15"
			(at 1.30175 1.27 180)
			(unlocked yes)
			(layer "F.Fab")
			(hide yes)
			(effects
				(font
					(size 0.635 0.4064)
					(thickness 0.1524)
				)
			)
		)
		(property "User Part Number" "N_A"
			(at 1.30175 1.27 180)
			(unlocked yes)
			(layer "Cmts.User")
			(hide yes)
			(effects
				(font
					(size 0.635 0.4064)
					(thickness 0.1524)
				)
			)
		)
		(duplicate_pad_numbers_are_jumpers no)
		(fp_line
			(start 2.54 -1.27)
			(end 0 -1.27)
			(stroke
				(width 0.1524)
				(type default)
			)
			(layer "F.SilkS")
		)
		(fp_line
			(start 0 -1.27)
			(end 0 -0.635)
			(stroke
				(width 0.1524)
				(type default)
			)
			(layer "F.SilkS")
		)
		(fp_line
			(start 2.54 -1.1303)
			(end 2.54 -1.27)
			(stroke
				(width 0.1524)
				(type default)
			)
			(layer "F.SilkS")
		)
		(fp_line
			(start 0 0.635)
			(end 0 1.905)
			(stroke
				(width 0.1524)
				(type default)
			)
			(layer "F.SilkS")
		)
		(fp_line
			(start 2.54 1.4097)
			(end 2.54 1.1303)
			(stroke
				(width 0.1524)
				(type default)
			)
			(layer "F.SilkS")
		)
		(fp_line
			(start 0 3.175)
			(end 0 3.81)
			(stroke
				(width 0.1524)
				(type default)
			)
			(layer "F.SilkS")
		)
		(fp_line
			(start 2.54 3.81)
			(end 2.54 3.6703)
			(stroke
				(width 0.1524)
				(type default)
			)
			(layer "F.SilkS")
		)
		(fp_line
			(start 0 3.81)
			(end 2.54 3.81)
			(stroke
				(width 0.1524)
				(type default)
			)
			(layer "F.SilkS")
		)
		(fp_poly
			(pts
				(xy -2.285746 -0.762) (xy -0.761746 0) (xy -2.285746 0.762)
			)
			(stroke
				(width 0)
				(type default)
			)
			(fill yes)
			(layer "F.SilkS")
		)
		(fp_line
			(start 2.54 -1.27)
			(end 0 -1.27)
			(stroke
				(width 0.1)
				(type default)
			)
			(layer "F.Fab")
		)
		(fp_line
			(start 0 -1.27)
			(end 0 3.81)
			(stroke
				(width 0.1)
				(type default)
			)
			(layer "F.Fab")
		)
		(fp_line
			(start 2.54 3.81)
			(end 2.54 -1.27)
			(stroke
				(width 0.1)
				(type default)
			)
			(layer "F.Fab")
		)
		(fp_line
			(start 0 3.81)
			(end 2.54 3.81)
			(stroke
				(width 0.1)
				(type default)
			)
			(layer "F.Fab")
		)
		(fp_poly
			(pts
				(xy -0.761746 0) (xy -2.285746 -0.762) (xy -2.285746 0.762)
			)
			(stroke
				(width 0)
				(type default)
			)
			(fill yes)
			(layer "F.Fab")
		)
		(pad "1" thru_hole circle
			(at 0 0 90)
			(size 1.0033 1.0033)
			(drill 0.249936)
			(layers "*.Cu" "*.Mask")
			(remove_unused_layers no)
			(net "TDR_DIFF_85_IN1_DN")
			(clearance 0.10795)
			(thermal_gap 0.10795)
			(padstack
				(mode front_inner_back)
				(layer "Inner"
					(shape circle)
					(size 0.8001 0.8001)
					(clearance 0.1524)
				)
				(layer "B.Cu"
					(shape circle)
					(size 1.0033 1.0033)
					(clearance 0.10795)
				)
			)
		)
		(pad "2" thru_hole circle
			(at 2.54 0 90)
			(size 1.9939 1.9939)
			(drill 0.249936)
			(layers "*.Cu" "*.Mask")
			(remove_unused_layers no)
			(net "T1_GND")
			(clearance 0.10795)
			(thermal_gap 0.10795)
			(padstack
				(mode front_inner_back)
				(layer "Inner"
					(shape circle)
					(size 0.8001 0.8001)
					(clearance 0.1524)
				)
				(layer "B.Cu"
					(shape circle)
					(size 1.9939 1.9939)
					(clearance 0.10795)
				)
			)
		)
		(pad "3" thru_hole circle
			(at 2.54 2.54 90)
			(size 1.9939 1.9939)
			(drill 0.249936)
			(layers "*.Cu" "*.Mask")
			(remove_unused_layers no)
			(net "T1_GND")
			(clearance 0.10795)
			(thermal_gap 0.10795)
			(padstack
				(mode front_inner_back)
				(layer "Inner"
					(shape circle)
					(size 0.8001 0.8001)
					(clearance 0.1524)
				)
				(layer "B.Cu"
					(shape circle)
					(size 1.9939 1.9939)
					(clearance 0.10795)
				)
			)
		)
		(pad "4" thru_hole circle
			(at 0 2.54 90)
			(size 1.0033 1.0033)
			(drill 0.249936)
			(layers "*.Cu" "*.Mask")
			(remove_unused_layers no)
			(net "TDR_DIFF_85_IN1_DP")
			(clearance 0.10795)
			(thermal_gap 0.10795)
			(padstack
				(mode front_inner_back)
				(layer "Inner"
					(shape circle)
					(size 0.8001 0.8001)
					(clearance 0.1524)
				)
				(layer "B.Cu"
					(shape circle)
					(size 1.0033 1.0033)
					(clearance 0.10795)
				)
			)
		)
	)
	(footprint ""
		(layer "F.Cu")
		(at 365.62792 -395.333474)
		(property "Reference" "R616"
			(at 0 0 0)
			(layer "F.SilkS")
			(hide yes)
			(effects
				(font
					(size 1.27 1.27)
				)
			)
		)
		(property "Value" ""
			(at 0 0 0)
			(layer "F.Fab")
			(effects
				(font
					(size 1.27 1.27)
				)
			)
		)
		(duplicate_pad_numbers_are_jumpers no)
		(fp_line
			(start -0.32512 -0.175006)
			(end 0.32512 -0.175006)
			(stroke
				(width 0.1)
				(type default)
			)
			(layer "F.Fab")
		)
		(fp_line
			(start -0.32512 0.175006)
			(end -0.32512 -0.175006)
			(stroke
				(width 0.1)
				(type default)
			)
			(layer "F.Fab")
		)
		(fp_line
			(start 0.32512 -0.175006)
			(end 0.32512 0.175006)
			(stroke
				(width 0.1)
				(type default)
			)
			(layer "F.Fab")
		)
		(fp_line
			(start 0.32512 0.175006)
			(end -0.32512 0.175006)
			(stroke
				(width 0.1)
				(type default)
			)
			(layer "F.Fab")
		)
		(pad "1" smd rect
			(at -0.2667 0)
			(size 0.3048 0.381)
			(layers "F.Cu" "F.Mask" "F.Paste")
			(net "CLK_100M_RETIMER_CPU0_P3_R_DN")
		)
		(pad "2" smd rect
			(at 0.2667 0 180)
			(size 0.3048 0.381)
			(layers "F.Cu" "F.Mask" "F.Paste")
			(net "CLK_100M_RETIMER_CPU0_P3_DN")
		)
	)
	(footprint ""
		(layer "F.Cu")
		(at 289.17392 -399.553684 -90)
		(property "Reference" "R1044"
			(at 0 0 270)
			(layer "F.SilkS")
			(hide yes)
			(effects
				(font
					(size 1.27 1.27)
				)
			)
		)
		(property "Value" ""
			(at 0 0 270)
			(layer "F.Fab")
			(effects
				(font
					(size 1.27 1.27)
				)
			)
		)
		(duplicate_pad_numbers_are_jumpers no)
		(fp_line
			(start -0.32512 0.175006)
			(end -0.32512 -0.175006)
			(stroke
				(width 0.1)
				(type default)
			)
			(layer "F.Fab")
		)
		(fp_line
			(start 0.32512 0.175006)
			(end -0.32512 0.175006)
			(stroke
				(width 0.1)
				(type default)
			)
			(layer "F.Fab")
		)
		(fp_line
			(start -0.32512 -0.175006)
			(end 0.32512 -0.175006)
			(stroke
				(width 0.1)
				(type default)
			)
			(layer "F.Fab")
		)
		(fp_line
			(start 0.32512 -0.175006)
			(end 0.32512 0.175006)
			(stroke
				(width 0.1)
				(type default)
			)
			(layer "F.Fab")
		)
		(pad "1" smd rect
			(at -0.2667 0 270)
			(size 0.3048 0.381)
			(layers "F.Cu" "F.Mask" "F.Paste")
			(net "U15_E2")
		)
		(pad "2" smd rect
			(at 0.2667 0 90)
			(size 0.3048 0.381)
			(layers "F.Cu" "F.Mask" "F.Paste")
			(net "GND")
		)
	)
	(footprint ""
		(layer "F.Cu")
		(at 14.078458 -418.690298 90)
		(property "Reference" "R6177"
			(at 0 0 90)
			(layer "F.SilkS")
			(hide yes)
			(effects
				(font
					(size 1.27 1.27)
				)
			)
		)
		(property "Value" ""
			(at 0 0 90)
			(layer "F.Fab")
			(effects
				(font
					(size 1.27 1.27)
				)
			)
		)
		(duplicate_pad_numbers_are_jumpers no)
		(fp_line
			(start 0.7874 -0.4064)
			(end 0.7874 0.4064)
			(stroke
				(width 0.1524)
				(type default)
			)
			(layer "F.SilkS")
		)
		(fp_line
			(start -0.7874 -0.4064)
			(end 0.7874 -0.4064)
			(stroke
				(width 0.1524)
				(type default)
			)
			(layer "F.SilkS")
		)
		(fp_line
			(start 0.7874 0.4064)
			(end -0.7874 0.4064)
			(stroke
				(width 0.1524)
				(type default)
			)
			(layer "F.SilkS")
		)
		(fp_line
			(start -0.7874 0.4064)
			(end -0.7874 -0.4064)
			(stroke
				(width 0.1524)
				(type default)
			)
			(layer "F.SilkS")
		)
		(fp_line
			(start -0.12065 -0.305054)
			(end -0.12065 -0.2794)
			(stroke
				(width 0.1)
				(type default)
			)
			(layer "F.Fab")
		)
		(fp_line
			(start -0.67945 -0.305054)
			(end -0.12065 -0.305054)
			(stroke
				(width 0.1)
				(type default)
			)
			(layer "F.Fab")
		)
		(fp_line
			(start 0.67945 -0.3048)
			(end 0.67945 0.3048)
			(stroke
				(width 0.1)
				(type default)
			)
			(layer "F.Fab")
		)
		(fp_line
			(start 0.12065 -0.3048)
			(end 0.67945 -0.3048)
			(stroke
				(width 0.1)
				(type default)
			)
			(layer "F.Fab")
		)
		(fp_line
			(start 0.12065 -0.2794)
			(end 0.12065 -0.3048)
			(stroke
				(width 0.1)
				(type default)
			)
			(layer "F.Fab")
		)
		(fp_line
			(start -0.12065 -0.2794)
			(end 0.12065 -0.2794)
			(stroke
				(width 0.1)
				(type default)
			)
			(layer "F.Fab")
		)
		(fp_line
			(start 0.120396 0.2794)
			(end -0.12065 0.2794)
			(stroke
				(width 0.1)
				(type default)
			)
			(layer "F.Fab")
		)
		(fp_line
			(start -0.12065 0.2794)
			(end -0.12065 0.3048)
			(stroke
				(width 0.1)
				(type default)
			)
			(layer "F.Fab")
		)
		(fp_line
			(start 0.67945 0.3048)
			(end 0.120396 0.3048)
			(stroke
				(width 0.1)
				(type default)
			)
			(layer "F.Fab")
		)
		(fp_line
			(start 0.120396 0.3048)
			(end 0.120396 0.2794)
			(stroke
				(width 0.1)
				(type default)
			)
			(layer "F.Fab")
		)
		(fp_line
			(start -0.12065 0.3048)
			(end -0.67945 0.3048)
			(stroke
				(width 0.1)
				(type default)
			)
			(layer "F.Fab")
		)
		(fp_line
			(start -0.67945 0.3048)
			(end -0.67945 -0.305054)
			(stroke
				(width 0.1)
				(type default)
			)
			(layer "F.Fab")
		)
		(pad "1" smd circle
			(at -0.40005 0 90)
			(size 0 0)
			(layers "F.Cu" "F.Mask" "F.Paste")
			(net "P3V3_AUX")
		)
		(pad "2" smd circle
			(at 0.40005 0 90)
			(size 0 0)
			(layers "F.Cu" "F.Mask" "F.Paste")
			(net "FM_P2E_BUF2_SD_TH")
		)
	)
	(footprint ""
		(layer "F.Cu")
		(at 83.222084 -39.65448 180)
		(property "Reference" "R6057"
			(at 0 0 180)
			(layer "F.SilkS")
			(hide yes)
			(effects
				(font
					(size 1.27 1.27)
				)
			)
		)
		(property "Value" ""
			(at 0 0 180)
			(layer "F.Fab")
			(effects
				(font
					(size 1.27 1.27)
				)
			)
		)
		(duplicate_pad_numbers_are_jumpers no)
		(fp_line
			(start 0.7874 0.4064)
			(end -0.7874 0.4064)
			(stroke
				(width 0.1524)
				(type default)
			)
			(layer "F.SilkS")
		)
		(fp_line
			(start 0.7874 -0.4064)
			(end 0.7874 0.4064)
			(stroke
				(width 0.1524)
				(type default)
			)
			(layer "F.SilkS")
		)
		(fp_line
			(start -0.7874 0.4064)
			(end -0.7874 -0.4064)
			(stroke
				(width 0.1524)
				(type default)
			)
			(layer "F.SilkS")
		)
		(fp_line
			(start -0.7874 -0.4064)
			(end 0.7874 -0.4064)
			(stroke
				(width 0.1524)
				(type default)
			)
			(layer "F.SilkS")
		)
		(fp_line
			(start 0.67945 0.3048)
			(end 0.120396 0.3048)
			(stroke
				(width 0.1)
				(type default)
			)
			(layer "F.Fab")
		)
		(fp_line
			(start 0.67945 -0.3048)
			(end 0.67945 0.3048)
			(stroke
				(width 0.1)
				(type default)
			)
			(layer "F.Fab")
		)
		(fp_line
			(start 0.12065 -0.2794)
			(end 0.12065 -0.3048)
			(stroke
				(width 0.1)
				(type default)
			)
			(layer "F.Fab")
		)
		(fp_line
			(start 0.12065 -0.3048)
			(end 0.67945 -0.3048)
			(stroke
				(width 0.1)
				(type default)
			)
			(layer "F.Fab")
		)
		(fp_line
			(start 0.120396 0.3048)
			(end 0.120396 0.2794)
			(stroke
				(width 0.1)
				(type default)
			)
			(layer "F.Fab")
		)
		(fp_line
			(start 0.120396 0.2794)
			(end -0.12065 0.2794)
			(stroke
				(width 0.1)
				(type default)
			)
			(layer "F.Fab")
		)
		(fp_line
			(start -0.12065 0.3048)
			(end -0.67945 0.3048)
			(stroke
				(width 0.1)
				(type default)
			)
			(layer "F.Fab")
		)
		(fp_line
			(start -0.12065 0.2794)
			(end -0.12065 0.3048)
			(stroke
				(width 0.1)
				(type default)
			)
			(layer "F.Fab")
		)
		(fp_line
			(start -0.12065 -0.2794)
			(end 0.12065 -0.2794)
			(stroke
				(width 0.1)
				(type default)
			)
			(layer "F.Fab")
		)
		(fp_line
			(start -0.12065 -0.305054)
			(end -0.12065 -0.2794)
			(stroke
				(width 0.1)
				(type default)
			)
			(layer "F.Fab")
		)
		(fp_line
			(start -0.67945 0.3048)
			(end -0.67945 -0.305054)
			(stroke
				(width 0.1)
				(type default)
			)
			(layer "F.Fab")
		)
		(fp_line
			(start -0.67945 -0.305054)
			(end -0.12065 -0.305054)
			(stroke
				(width 0.1)
				(type default)
			)
			(layer "F.Fab")
		)
		(pad "1" smd circle
			(at -0.40005 0 180)
			(size 0 0)
			(layers "F.Cu" "F.Mask" "F.Paste")
			(net "RST_PERST_OCP_V3_2_BUF2_N")
		)
		(pad "2" smd circle
			(at 0.40005 0 180)
			(size 0 0)
			(layers "F.Cu" "F.Mask" "F.Paste")
			(net "RST_PERST1_OCP_V3_2_N")
		)
	)
	(footprint ""
		(layer "F.Cu")
		(at 330.196444 -138.893042 90)
		(property "Reference" "PR471"
			(at 0 0 90)
			(layer "F.SilkS")
			(hide yes)
			(effects
				(font
					(size 1.27 1.27)
				)
			)
		)
		(property "Value" ""
			(at 0 0 90)
			(layer "F.Fab")
			(effects
				(font
					(size 1.27 1.27)
				)
			)
		)
		(duplicate_pad_numbers_are_jumpers no)
		(fp_line
			(start 0.7874 -0.4064)
			(end 0.7874 0.4064)
			(stroke
				(width 0.1524)
				(type default)
			)
			(layer "F.SilkS")
		)
		(fp_line
			(start -0.7874 -0.4064)
			(end 0.7874 -0.4064)
			(stroke
				(width 0.1524)
				(type default)
			)
			(layer "F.SilkS")
		)
		(fp_line
			(start 0.7874 0.4064)
			(end -0.7874 0.4064)
			(stroke
				(width 0.1524)
				(type default)
			)
			(layer "F.SilkS")
		)
		(fp_line
			(start -0.7874 0.4064)
			(end -0.7874 -0.4064)
			(stroke
				(width 0.1524)
				(type default)
			)
			(layer "F.SilkS")
		)
		(fp_line
			(start -0.12065 -0.305054)
			(end -0.12065 -0.2794)
			(stroke
				(width 0.1)
				(type default)
			)
			(layer "F.Fab")
		)
		(fp_line
			(start -0.67945 -0.305054)
			(end -0.12065 -0.305054)
			(stroke
				(width 0.1)
				(type default)
			)
			(layer "F.Fab")
		)
		(fp_line
			(start 0.67945 -0.3048)
			(end 0.67945 0.3048)
			(stroke
				(width 0.1)
				(type default)
			)
			(layer "F.Fab")
		)
		(fp_line
			(start 0.12065 -0.3048)
			(end 0.67945 -0.3048)
			(stroke
				(width 0.1)
				(type default)
			)
			(layer "F.Fab")
		)
		(fp_line
			(start 0.12065 -0.2794)
			(end 0.12065 -0.3048)
			(stroke
				(width 0.1)
				(type default)
			)
			(layer "F.Fab")
		)
		(fp_line
			(start -0.12065 -0.2794)
			(end 0.12065 -0.2794)
			(stroke
				(width 0.1)
				(type default)
			)
			(layer "F.Fab")
		)
		(fp_line
			(start 0.120396 0.2794)
			(end -0.12065 0.2794)
			(stroke
				(width 0.1)
				(type default)
			)
			(layer "F.Fab")
		)
		(fp_line
			(start -0.12065 0.2794)
			(end -0.12065 0.3048)
			(stroke
				(width 0.1)
				(type default)
			)
			(layer "F.Fab")
		)
		(fp_line
			(start 0.67945 0.3048)
			(end 0.120396 0.3048)
			(stroke
				(width 0.1)
				(type default)
			)
			(layer "F.Fab")
		)
		(fp_line
			(start 0.120396 0.3048)
			(end 0.120396 0.2794)
			(stroke
				(width 0.1)
				(type default)
			)
			(layer "F.Fab")
		)
		(fp_line
			(start -0.12065 0.3048)
			(end -0.67945 0.3048)
			(stroke
				(width 0.1)
				(type default)
			)
			(layer "F.Fab")
		)
		(fp_line
			(start -0.67945 0.3048)
			(end -0.67945 -0.305054)
			(stroke
				(width 0.1)
				(type default)
			)
			(layer "F.Fab")
		)
		(pad "1" smd circle
			(at -0.40005 0 90)
			(size 0 0)
			(layers "F.Cu" "F.Mask" "F.Paste")
			(net "PVDD18_S5_P0_FB")
		)
		(pad "2" smd circle
			(at 0.40005 0 90)
			(size 0 0)
			(layers "F.Cu" "F.Mask" "F.Paste")
			(net "PVDD18_S5_P0_FB_RC")
		)
	)
	(footprint ""
		(layer "F.Cu")
		(at 257.951478 -108.179108 180)
		(property "Reference" "R3190"
			(at 0 0 180)
			(layer "F.SilkS")
			(hide yes)
			(effects
				(font
					(size 1.27 1.27)
				)
			)
		)
		(property "Value" ""
			(at 0 0 180)
			(layer "F.Fab")
			(effects
				(font
					(size 1.27 1.27)
				)
			)
		)
		(duplicate_pad_numbers_are_jumpers no)
		(fp_line
			(start 0.7874 0.4064)
			(end -0.7874 0.4064)
			(stroke
				(width 0.1524)
				(type default)
			)
			(layer "F.SilkS")
		)
		(fp_line
			(start 0.7874 -0.4064)
			(end 0.7874 0.4064)
			(stroke
				(width 0.1524)
				(type default)
			)
			(layer "F.SilkS")
		)
		(fp_line
			(start -0.7874 0.4064)
			(end -0.7874 -0.4064)
			(stroke
				(width 0.1524)
				(type default)
			)
			(layer "F.SilkS")
		)
		(fp_line
			(start -0.7874 -0.4064)
			(end 0.7874 -0.4064)
			(stroke
				(width 0.1524)
				(type default)
			)
			(layer "F.SilkS")
		)
		(fp_line
			(start 0.67945 0.3048)
			(end 0.120396 0.3048)
			(stroke
				(width 0.1)
				(type default)
			)
			(layer "F.Fab")
		)
		(fp_line
			(start 0.67945 -0.3048)
			(end 0.67945 0.3048)
			(stroke
				(width 0.1)
				(type default)
			)
			(layer "F.Fab")
		)
		(fp_line
			(start 0.12065 -0.2794)
			(end 0.12065 -0.3048)
			(stroke
				(width 0.1)
				(type default)
			)
			(layer "F.Fab")
		)
		(fp_line
			(start 0.12065 -0.3048)
			(end 0.67945 -0.3048)
			(stroke
				(width 0.1)
				(type default)
			)
			(layer "F.Fab")
		)
		(fp_line
			(start 0.120396 0.3048)
			(end 0.120396 0.2794)
			(stroke
				(width 0.1)
				(type default)
			)
			(layer "F.Fab")
		)
		(fp_line
			(start 0.120396 0.2794)
			(end -0.12065 0.2794)
			(stroke
				(width 0.1)
				(type default)
			)
			(layer "F.Fab")
		)
		(fp_line
			(start -0.12065 0.3048)
			(end -0.67945 0.3048)
			(stroke
				(width 0.1)
				(type default)
			)
			(layer "F.Fab")
		)
		(fp_line
			(start -0.12065 0.2794)
			(end -0.12065 0.3048)
			(stroke
				(width 0.1)
				(type default)
			)
			(layer "F.Fab")
		)
		(fp_line
			(start -0.12065 -0.2794)
			(end 0.12065 -0.2794)
			(stroke
				(width 0.1)
				(type default)
			)
			(layer "F.Fab")
		)
		(fp_line
			(start -0.12065 -0.305054)
			(end -0.12065 -0.2794)
			(stroke
				(width 0.1)
				(type default)
			)
			(layer "F.Fab")
		)
		(fp_line
			(start -0.67945 0.3048)
			(end -0.67945 -0.305054)
			(stroke
				(width 0.1)
				(type default)
			)
			(layer "F.Fab")
		)
		(fp_line
			(start -0.67945 -0.305054)
			(end -0.12065 -0.305054)
			(stroke
				(width 0.1)
				(type default)
			)
			(layer "F.Fab")
		)
		(pad "1" smd circle
			(at -0.40005 0 180)
			(size 0 0)
			(layers "F.Cu" "F.Mask" "F.Paste")
			(net "P3V3_AUX")
		)
		(pad "2" smd circle
			(at 0.40005 0 180)
			(size 0 0)
			(layers "F.Cu" "F.Mask" "F.Paste")
			(net "OCP_V3_2_PWRBRK_BUFF_N")
		)
	)
	(footprint ""
		(layer "F.Cu")
		(at 161.30524 -36.739322 90)
		(property "Reference" "C1663"
			(at 0 0 90)
			(layer "F.SilkS")
			(hide yes)
			(effects
				(font
					(size 1.27 1.27)
				)
			)
		)
		(property "Value" ""
			(at 0 0 90)
			(layer "F.Fab")
			(effects
				(font
					(size 1.27 1.27)
				)
			)
		)
		(duplicate_pad_numbers_are_jumpers no)
		(fp_line
			(start 0.7874 -0.4064)
			(end 0.7874 0.4064)
			(stroke
				(width 0.1524)
				(type default)
			)
			(layer "F.SilkS")
		)
		(fp_line
			(start -0.7874 -0.4064)
			(end 0.7874 -0.4064)
			(stroke
				(width 0.1524)
				(type default)
			)
			(layer "F.SilkS")
		)
		(fp_line
			(start 0.7874 0.4064)
			(end -0.7874 0.4064)
			(stroke
				(width 0.1524)
				(type default)
			)
			(layer "F.SilkS")
		)
		(fp_line
			(start -0.7874 0.4064)
			(end -0.7874 -0.4064)
			(stroke
				(width 0.1524)
				(type default)
			)
			(layer "F.SilkS")
		)
		(fp_line
			(start -0.12065 -0.305054)
			(end -0.12065 -0.2794)
			(stroke
				(width 0.1)
				(type default)
			)
			(layer "F.Fab")
		)
		(fp_line
			(start -0.67945 -0.305054)
			(end -0.12065 -0.305054)
			(stroke
				(width 0.1)
				(type default)
			)
			(layer "F.Fab")
		)
		(fp_line
			(start 0.67945 -0.3048)
			(end 0.67945 0.3048)
			(stroke
				(width 0.1)
				(type default)
			)
			(layer "F.Fab")
		)
		(fp_line
			(start 0.12065 -0.3048)
			(end 0.67945 -0.3048)
			(stroke
				(width 0.1)
				(type default)
			)
			(layer "F.Fab")
		)
		(fp_line
			(start 0.12065 -0.2794)
			(end 0.12065 -0.3048)
			(stroke
				(width 0.1)
				(type default)
			)
			(layer "F.Fab")
		)
		(fp_line
			(start -0.12065 -0.2794)
			(end 0.12065 -0.2794)
			(stroke
				(width 0.1)
				(type default)
			)
			(layer "F.Fab")
		)
		(fp_line
			(start 0.120396 0.2794)
			(end -0.12065 0.2794)
			(stroke
				(width 0.1)
				(type default)
			)
			(layer "F.Fab")
		)
		(fp_line
			(start -0.12065 0.2794)
			(end -0.12065 0.3048)
			(stroke
				(width 0.1)
				(type default)
			)
			(layer "F.Fab")
		)
		(fp_line
			(start 0.67945 0.3048)
			(end 0.120396 0.3048)
			(stroke
				(width 0.1)
				(type default)
			)
			(layer "F.Fab")
		)
		(fp_line
			(start 0.120396 0.3048)
			(end 0.120396 0.2794)
			(stroke
				(width 0.1)
				(type default)
			)
			(layer "F.Fab")
		)
		(fp_line
			(start -0.12065 0.3048)
			(end -0.67945 0.3048)
			(stroke
				(width 0.1)
				(type default)
			)
			(layer "F.Fab")
		)
		(fp_line
			(start -0.67945 0.3048)
			(end -0.67945 -0.305054)
			(stroke
				(width 0.1)
				(type default)
			)
			(layer "F.Fab")
		)
		(pad "1" smd circle
			(at -0.40005 0 90)
			(size 0 0)
			(layers "F.Cu" "F.Mask" "F.Paste")
			(net "P3V3_AUX")
		)
		(pad "2" smd circle
			(at 0.40005 0 90)
			(size 0 0)
			(layers "F.Cu" "F.Mask" "F.Paste")
			(net "GND")
		)
	)
	(footprint ""
		(layer "F.Cu")
		(at 51.698906 19.444716 -90)
		(property "Reference" "JP4003_12"
			(at 0 0 270)
			(layer "F.SilkS")
			(hide yes)
			(effects
				(font
					(size 1.27 1.27)
				)
			)
		)
		(property "Value" ""
			(at 0 0 270)
			(layer "F.Fab")
			(effects
				(font
					(size 1.27 1.27)
				)
			)
		)
		(duplicate_pad_numbers_are_jumpers no)
		(pad "1" smd circle
			(at 0 0 270)
			(size 0.762 0.762)
			(layers "F.Cu" "F.Mask" "F.Paste")
			(net "Net_10793")
		)
	)
	(footprint ""
		(layer "F.Cu")
		(at 311.937908 -117.570504)
		(property "Reference" "U64"
			(at -1.32842 -3.188208 0)
			(unlocked yes)
			(layer "F.SilkS")
			(effects
				(font
					(size 0.7874 0.5842)
					(thickness 0.1524)
				)
				(justify left)
			)
		)
		(property "Value" ""
			(at 0 0 0)
			(layer "F.Fab")
			(effects
				(font
					(size 1.27 1.27)
				)
			)
		)
		(duplicate_pad_numbers_are_jumpers no)
		(fp_line
			(start -1.8288 -2.500122)
			(end -1.8288 2.500122)
			(stroke
				(width 0.1524)
				(type default)
			)
			(layer "F.SilkS")
		)
		(fp_line
			(start -1.8288 2.500122)
			(end 1.8288 2.500122)
			(stroke
				(width 0.1524)
				(type default)
			)
			(layer "F.SilkS")
		)
		(fp_line
			(start -1.077722 -2.500122)
			(end -1.8288 -2.500122)
			(stroke
				(width 0.1524)
				(type default)
			)
			(layer "F.SilkS")
		)
		(fp_line
			(start 0 -1.4224)
			(end -1.077722 -2.500122)
			(stroke
				(width 0.1524)
				(type default)
			)
			(layer "F.SilkS")
		)
		(fp_line
			(start 1.077722 -2.500122)
			(end 0 -1.4224)
			(stroke
				(width 0.1524)
				(type default)
			)
			(layer "F.SilkS")
		)
		(fp_line
			(start 1.8288 -2.500122)
			(end 1.077722 -2.500122)
			(stroke
				(width 0.1524)
				(type default)
			)
			(layer "F.SilkS")
		)
		(fp_line
			(start 1.8288 2.500122)
			(end 1.8288 -2.500122)
			(stroke
				(width 0.1524)
				(type default)
			)
			(layer "F.SilkS")
		)
		(fp_poly
			(pts
				(xy -2.792984 -3.610102) (xy -3.300984 -4.626102) (xy -2.284984 -4.626102)
			)
			(stroke
				(width 0)
				(type default)
			)
			(fill yes)
			(layer "F.SilkS")
		)
		(fp_line
			(start -1.999996 -2.500122)
			(end -1.999996 2.500122)
			(stroke
				(width 0.1)
				(type default)
			)
			(layer "F.Fab")
		)
		(fp_line
			(start -1.999996 2.500122)
			(end 1.999996 2.500122)
			(stroke
				(width 0.1)
				(type default)
			)
			(layer "F.Fab")
		)
		(fp_line
			(start 1.999996 -2.500122)
			(end -1.999996 -2.500122)
			(stroke
				(width 0.1)
				(type default)
			)
			(layer "F.Fab")
		)
		(fp_line
			(start 1.999996 2.500122)
			(end 1.999996 -2.500122)
			(stroke
				(width 0.1)
				(type default)
			)
			(layer "F.Fab")
		)
		(fp_poly
			(pts
				(xy -4.5085 -2.413) (xy -4.5085 -1.397) (xy -3.4925 -1.905)
			)
			(stroke
				(width 0)
				(type default)
			)
			(fill yes)
			(layer "F.Fab")
		)
		(pad "1" smd rect
			(at -2.599944 -1.905 270)
			(size 0.889 1.27)
			(layers "F.Cu" "F.Mask" "F.Paste")
			(net "MB_FRU_ADDR0")
		)
		(pad "2" smd rect
			(at -2.599944 -0.635 270)
			(size 0.889 1.27)
			(layers "F.Cu" "F.Mask" "F.Paste")
			(net "MB_FRU_ADDR1")
		)
		(pad "3" smd rect
			(at -2.599944 0.635 270)
			(size 0.889 1.27)
			(layers "F.Cu" "F.Mask" "F.Paste")
			(net "MB_FRU_ADDR2")
		)
		(pad "4" smd rect
			(at -2.599944 1.905 270)
			(size 0.889 1.27)
			(layers "F.Cu" "F.Mask" "F.Paste")
			(net "GND")
		)
		(pad "5" smd rect
			(at 2.599944 1.905 270)
			(size 0.889 1.27)
			(layers "F.Cu" "F.Mask" "F.Paste")
			(net "SMB_FRU_3V3AUX_R1_SDA")
		)
		(pad "6" smd rect
			(at 2.599944 0.635 270)
			(size 0.889 1.27)
			(layers "F.Cu" "F.Mask" "F.Paste")
			(net "SMB_FRU_3V3AUX_R1_SCL")
		)
		(pad "7" smd rect
			(at 2.599944 -0.635 270)
			(size 0.889 1.27)
			(layers "F.Cu" "F.Mask" "F.Paste")
			(net "PD_MB_FRU_WP")
		)
		(pad "8" smd rect
			(at 2.599944 -1.905 270)
			(size 0.889 1.27)
			(layers "F.Cu" "F.Mask" "F.Paste")
			(net "P3V3_AUX")
		)
	)
	(footprint ""
		(layer "F.Cu")
		(at 331.055472 -395.333474)
		(property "Reference" "R612"
			(at 0 0 0)
			(layer "F.SilkS")
			(hide yes)
			(effects
				(font
					(size 1.27 1.27)
				)
			)
		)
		(property "Value" ""
			(at 0 0 0)
			(layer "F.Fab")
			(effects
				(font
					(size 1.27 1.27)
				)
			)
		)
		(duplicate_pad_numbers_are_jumpers no)
		(fp_line
			(start -0.32512 -0.175006)
			(end 0.32512 -0.175006)
			(stroke
				(width 0.1)
				(type default)
			)
			(layer "F.Fab")
		)
		(fp_line
			(start -0.32512 0.175006)
			(end -0.32512 -0.175006)
			(stroke
				(width 0.1)
				(type default)
			)
			(layer "F.Fab")
		)
		(fp_line
			(start 0.32512 -0.175006)
			(end 0.32512 0.175006)
			(stroke
				(width 0.1)
				(type default)
			)
			(layer "F.Fab")
		)
		(fp_line
			(start 0.32512 0.175006)
			(end -0.32512 0.175006)
			(stroke
				(width 0.1)
				(type default)
			)
			(layer "F.Fab")
		)
		(pad "1" smd rect
			(at -0.2667 0)
			(size 0.3048 0.381)
			(layers "F.Cu" "F.Mask" "F.Paste")
			(net "CLK_100M_RETIMER_CPU0_P1_R_DN")
		)
		(pad "2" smd rect
			(at 0.2667 0 180)
			(size 0.3048 0.381)
			(layers "F.Cu" "F.Mask" "F.Paste")
			(net "CLK_100M_RETIMER_CPU0_P1_DN")
		)
	)
	(footprint ""
		(layer "F.Cu")
		(at 282.397962 -351.927922)
		(property "Reference" "PR106"
			(at 0 0 0)
			(layer "F.SilkS")
			(hide yes)
			(effects
				(font
					(size 1.27 1.27)
				)
			)
		)
		(property "Value" ""
			(at 0 0 0)
			(layer "F.Fab")
			(effects
				(font
					(size 1.27 1.27)
				)
			)
		)
		(duplicate_pad_numbers_are_jumpers no)
		(fp_line
			(start -0.7874 -0.4064)
			(end 0.7874 -0.4064)
			(stroke
				(width 0.1524)
				(type default)
			)
			(layer "F.SilkS")
		)
		(fp_line
			(start -0.7874 0.4064)
			(end -0.7874 -0.4064)
			(stroke
				(width 0.1524)
				(type default)
			)
			(layer "F.SilkS")
		)
		(fp_line
			(start 0.7874 -0.4064)
			(end 0.7874 0.4064)
			(stroke
				(width 0.1524)
				(type default)
			)
			(layer "F.SilkS")
		)
		(fp_line
			(start 0.7874 0.4064)
			(end -0.7874 0.4064)
			(stroke
				(width 0.1524)
				(type default)
			)
			(layer "F.SilkS")
		)
		(fp_line
			(start -0.67945 -0.305054)
			(end -0.12065 -0.305054)
			(stroke
				(width 0.1)
				(type default)
			)
			(layer "F.Fab")
		)
		(fp_line
			(start -0.67945 0.3048)
			(end -0.67945 -0.305054)
			(stroke
				(width 0.1)
				(type default)
			)
			(layer "F.Fab")
		)
		(fp_line
			(start -0.12065 -0.305054)
			(end -0.12065 -0.2794)
			(stroke
				(width 0.1)
				(type default)
			)
			(layer "F.Fab")
		)
		(fp_line
			(start -0.12065 -0.2794)
			(end 0.12065 -0.2794)
			(stroke
				(width 0.1)
				(type default)
			)
			(layer "F.Fab")
		)
		(fp_line
			(start -0.12065 0.2794)
			(end -0.12065 0.3048)
			(stroke
				(width 0.1)
				(type default)
			)
			(layer "F.Fab")
		)
		(fp_line
			(start -0.12065 0.3048)
			(end -0.67945 0.3048)
			(stroke
				(width 0.1)
				(type default)
			)
			(layer "F.Fab")
		)
		(fp_line
			(start 0.120396 0.2794)
			(end -0.12065 0.2794)
			(stroke
				(width 0.1)
				(type default)
			)
			(layer "F.Fab")
		)
		(fp_line
			(start 0.120396 0.3048)
			(end 0.120396 0.2794)
			(stroke
				(width 0.1)
				(type default)
			)
			(layer "F.Fab")
		)
		(fp_line
			(start 0.12065 -0.3048)
			(end 0.67945 -0.3048)
			(stroke
				(width 0.1)
				(type default)
			)
			(layer "F.Fab")
		)
		(fp_line
			(start 0.12065 -0.2794)
			(end 0.12065 -0.3048)
			(stroke
				(width 0.1)
				(type default)
			)
			(layer "F.Fab")
		)
		(fp_line
			(start 0.67945 -0.3048)
			(end 0.67945 0.3048)
			(stroke
				(width 0.1)
				(type default)
			)
			(layer "F.Fab")
		)
		(fp_line
			(start 0.67945 0.3048)
			(end 0.120396 0.3048)
			(stroke
				(width 0.1)
				(type default)
			)
			(layer "F.Fab")
		)
		(pad "1" smd circle
			(at -0.40005 0)
			(size 0 0)
			(layers "F.Cu" "F.Mask" "F.Paste")
			(net "PVDDIO_P0_LSET3")
		)
		(pad "2" smd circle
			(at 0.40005 0)
			(size 0 0)
			(layers "F.Cu" "F.Mask" "F.Paste")
			(net "GND")
		)
	)
	(footprint ""
		(layer "F.Cu")
		(at 45.932344 -420.513764)
		(property "Reference" "R1464"
			(at 0 0 0)
			(layer "F.SilkS")
			(hide yes)
			(effects
				(font
					(size 1.27 1.27)
				)
			)
		)
		(property "Value" ""
			(at 0 0 0)
			(layer "F.Fab")
			(effects
				(font
					(size 1.27 1.27)
				)
			)
		)
		(duplicate_pad_numbers_are_jumpers no)
		(fp_line
			(start -0.32512 -0.175006)
			(end 0.32512 -0.175006)
			(stroke
				(width 0.1)
				(type default)
			)
			(layer "F.Fab")
		)
		(fp_line
			(start -0.32512 0.175006)
			(end -0.32512 -0.175006)
			(stroke
				(width 0.1)
				(type default)
			)
			(layer "F.Fab")
		)
		(fp_line
			(start 0.32512 -0.175006)
			(end 0.32512 0.175006)
			(stroke
				(width 0.1)
				(type default)
			)
			(layer "F.Fab")
		)
		(fp_line
			(start 0.32512 0.175006)
			(end -0.32512 0.175006)
			(stroke
				(width 0.1)
				(type default)
			)
			(layer "F.Fab")
		)
		(pad "1" smd rect
			(at -0.2667 0)
			(size 0.3048 0.381)
			(layers "F.Cu" "F.Mask" "F.Paste")
			(net "P1V8_CPU1_RT_1D")
		)
		(pad "2" smd rect
			(at 0.2667 0 180)
			(size 0.3048 0.381)
			(layers "F.Cu" "F.Mask" "F.Paste")
			(net "JTAG_TDI_RT_CPU1_P0")
		)
	)
	(footprint ""
		(layer "F.Cu")
		(at 77.64399 -174.960534 -90)
		(property "Reference" "PC307"
			(at 0 0 270)
			(layer "F.SilkS")
			(hide yes)
			(effects
				(font
					(size 1.27 1.27)
				)
			)
		)
		(property "Value" ""
			(at 0 0 270)
			(layer "F.Fab")
			(effects
				(font
					(size 1.27 1.27)
				)
			)
		)
		(duplicate_pad_numbers_are_jumpers no)
		(fp_line
			(start -0.7874 0.4064)
			(end -0.7874 -0.4064)
			(stroke
				(width 0.1524)
				(type default)
			)
			(layer "F.SilkS")
		)
		(fp_line
			(start -0.324866 0.4064)
			(end -0.7874 0.4064)
			(stroke
				(width 0.1524)
				(type default)
			)
			(layer "F.SilkS")
		)
		(fp_line
			(start 0.7874 0.4064)
			(end 0.411734 0.4064)
			(stroke
				(width 0.1524)
				(type default)
			)
			(layer "F.SilkS")
		)
		(fp_line
			(start -0.7874 -0.4064)
			(end 0.7874 -0.4064)
			(stroke
				(width 0.1524)
				(type default)
			)
			(layer "F.SilkS")
		)
		(fp_line
			(start 0.7874 -0.4064)
			(end 0.7874 0.4064)
			(stroke
				(width 0.1524)
				(type default)
			)
			(layer "F.SilkS")
		)
		(fp_line
			(start -0.67945 0.3048)
			(end -0.67945 -0.305054)
			(stroke
				(width 0.1)
				(type default)
			)
			(layer "F.Fab")
		)
		(fp_line
			(start -0.12065 0.3048)
			(end -0.67945 0.3048)
			(stroke
				(width 0.1)
				(type default)
			)
			(layer "F.Fab")
		)
		(fp_line
			(start 0.120396 0.3048)
			(end 0.120396 0.2794)
			(stroke
				(width 0.1)
				(type default)
			)
			(layer "F.Fab")
		)
		(fp_line
			(start 0.67945 0.3048)
			(end 0.120396 0.3048)
			(stroke
				(width 0.1)
				(type default)
			)
			(layer "F.Fab")
		)
		(fp_line
			(start -0.12065 0.2794)
			(end -0.12065 0.3048)
			(stroke
				(width 0.1)
				(type default)
			)
			(layer "F.Fab")
		)
		(fp_line
			(start 0.120396 0.2794)
			(end -0.12065 0.2794)
			(stroke
				(width 0.1)
				(type default)
			)
			(layer "F.Fab")
		)
		(fp_line
			(start -0.12065 -0.2794)
			(end 0.12065 -0.2794)
			(stroke
				(width 0.1)
				(type default)
			)
			(layer "F.Fab")
		)
		(fp_line
			(start 0.12065 -0.2794)
			(end 0.12065 -0.3048)
			(stroke
				(width 0.1)
				(type default)
			)
			(layer "F.Fab")
		)
		(fp_line
			(start 0.12065 -0.3048)
			(end 0.67945 -0.3048)
			(stroke
				(width 0.1)
				(type default)
			)
			(layer "F.Fab")
		)
		(fp_line
			(start 0.67945 -0.3048)
			(end 0.67945 0.3048)
			(stroke
				(width 0.1)
				(type default)
			)
			(layer "F.Fab")
		)
		(fp_line
			(start -0.67945 -0.305054)
			(end -0.12065 -0.305054)
			(stroke
				(width 0.1)
				(type default)
			)
			(layer "F.Fab")
		)
		(fp_line
			(start -0.12065 -0.305054)
			(end -0.12065 -0.2794)
			(stroke
				(width 0.1)
				(type default)
			)
			(layer "F.Fab")
		)
		(pad "1" smd circle
			(at -0.40005 0 270)
			(size 0 0)
			(layers "F.Cu" "F.Mask" "F.Paste")
			(net "PVDDCR_CPU0_P1_VCC5")
		)
		(pad "2" smd circle
			(at 0.40005 0 270)
			(size 0 0)
			(layers "F.Cu" "F.Mask" "F.Paste")
			(net "GND")
		)
	)
	(footprint ""
		(layer "F.Cu")
		(at 370.969032 -35.037522 -90)
		(property "Reference" "C1352"
			(at 0 0 270)
			(layer "F.SilkS")
			(hide yes)
			(effects
				(font
					(size 1.27 1.27)
				)
			)
		)
		(property "Value" ""
			(at 0 0 270)
			(layer "F.Fab")
			(effects
				(font
					(size 1.27 1.27)
				)
			)
		)
		(duplicate_pad_numbers_are_jumpers no)
		(fp_line
			(start -0.7874 0.4064)
			(end -0.7874 -0.4064)
			(stroke
				(width 0.1524)
				(type default)
			)
			(layer "F.SilkS")
		)
		(fp_line
			(start 0.7874 0.4064)
			(end -0.7874 0.4064)
			(stroke
				(width 0.1524)
				(type default)
			)
			(layer "F.SilkS")
		)
		(fp_line
			(start -0.7874 -0.4064)
			(end 0.7874 -0.4064)
			(stroke
				(width 0.1524)
				(type default)
			)
			(layer "F.SilkS")
		)
		(fp_line
			(start 0.7874 -0.4064)
			(end 0.7874 0.4064)
			(stroke
				(width 0.1524)
				(type default)
			)
			(layer "F.SilkS")
		)
		(fp_line
			(start -0.67945 0.3048)
			(end -0.67945 -0.305054)
			(stroke
				(width 0.1)
				(type default)
			)
			(layer "F.Fab")
		)
		(fp_line
			(start -0.12065 0.3048)
			(end -0.67945 0.3048)
			(stroke
				(width 0.1)
				(type default)
			)
			(layer "F.Fab")
		)
		(fp_line
			(start 0.120396 0.3048)
			(end 0.120396 0.2794)
			(stroke
				(width 0.1)
				(type default)
			)
			(layer "F.Fab")
		)
		(fp_line
			(start 0.67945 0.3048)
			(end 0.120396 0.3048)
			(stroke
				(width 0.1)
				(type default)
			)
			(layer "F.Fab")
		)
		(fp_line
			(start -0.12065 0.2794)
			(end -0.12065 0.3048)
			(stroke
				(width 0.1)
				(type default)
			)
			(layer "F.Fab")
		)
		(fp_line
			(start 0.120396 0.2794)
			(end -0.12065 0.2794)
			(stroke
				(width 0.1)
				(type default)
			)
			(layer "F.Fab")
		)
		(fp_line
			(start -0.12065 -0.2794)
			(end 0.12065 -0.2794)
			(stroke
				(width 0.1)
				(type default)
			)
			(layer "F.Fab")
		)
		(fp_line
			(start 0.12065 -0.2794)
			(end 0.12065 -0.3048)
			(stroke
				(width 0.1)
				(type default)
			)
			(layer "F.Fab")
		)
		(fp_line
			(start 0.12065 -0.3048)
			(end 0.67945 -0.3048)
			(stroke
				(width 0.1)
				(type default)
			)
			(layer "F.Fab")
		)
		(fp_line
			(start 0.67945 -0.3048)
			(end 0.67945 0.3048)
			(stroke
				(width 0.1)
				(type default)
			)
			(layer "F.Fab")
		)
		(fp_line
			(start -0.67945 -0.305054)
			(end -0.12065 -0.305054)
			(stroke
				(width 0.1)
				(type default)
			)
			(layer "F.Fab")
		)
		(fp_line
			(start -0.12065 -0.305054)
			(end -0.12065 -0.2794)
			(stroke
				(width 0.1)
				(type default)
			)
			(layer "F.Fab")
		)
		(pad "1" smd circle
			(at -0.40005 0 270)
			(size 0 0)
			(layers "F.Cu" "F.Mask" "F.Paste")
			(net "PVDD18_S5_P0")
		)
		(pad "2" smd circle
			(at 0.40005 0 270)
			(size 0 0)
			(layers "F.Cu" "F.Mask" "F.Paste")
			(net "GND")
		)
	)
	(footprint ""
		(layer "F.Cu")
		(at 422.763696 -357.688134 -90)
		(property "Reference" "PR419"
			(at 0 0 270)
			(layer "F.SilkS")
			(hide yes)
			(effects
				(font
					(size 1.27 1.27)
				)
			)
		)
		(property "Value" ""
			(at 0 0 270)
			(layer "F.Fab")
			(effects
				(font
					(size 1.27 1.27)
				)
			)
		)
		(duplicate_pad_numbers_are_jumpers no)
		(fp_line
			(start -0.7874 0.4064)
			(end -0.7874 -0.4064)
			(stroke
				(width 0.1524)
				(type default)
			)
			(layer "F.SilkS")
		)
		(fp_line
			(start 0.7874 0.4064)
			(end -0.7874 0.4064)
			(stroke
				(width 0.1524)
				(type default)
			)
			(layer "F.SilkS")
		)
		(fp_line
			(start -0.7874 -0.4064)
			(end 0.7874 -0.4064)
			(stroke
				(width 0.1524)
				(type default)
			)
			(layer "F.SilkS")
		)
		(fp_line
			(start 0.7874 -0.4064)
			(end 0.7874 0.4064)
			(stroke
				(width 0.1524)
				(type default)
			)
			(layer "F.SilkS")
		)
		(fp_line
			(start -0.67945 0.3048)
			(end -0.67945 -0.305054)
			(stroke
				(width 0.1)
				(type default)
			)
			(layer "F.Fab")
		)
		(fp_line
			(start -0.12065 0.3048)
			(end -0.67945 0.3048)
			(stroke
				(width 0.1)
				(type default)
			)
			(layer "F.Fab")
		)
		(fp_line
			(start 0.120396 0.3048)
			(end 0.120396 0.2794)
			(stroke
				(width 0.1)
				(type default)
			)
			(layer "F.Fab")
		)
		(fp_line
			(start 0.67945 0.3048)
			(end 0.120396 0.3048)
			(stroke
				(width 0.1)
				(type default)
			)
			(layer "F.Fab")
		)
		(fp_line
			(start -0.12065 0.2794)
			(end -0.12065 0.3048)
			(stroke
				(width 0.1)
				(type default)
			)
			(layer "F.Fab")
		)
		(fp_line
			(start 0.120396 0.2794)
			(end -0.12065 0.2794)
			(stroke
				(width 0.1)
				(type default)
			)
			(layer "F.Fab")
		)
		(fp_line
			(start -0.12065 -0.2794)
			(end 0.12065 -0.2794)
			(stroke
				(width 0.1)
				(type default)
			)
			(layer "F.Fab")
		)
		(fp_line
			(start 0.12065 -0.2794)
			(end 0.12065 -0.3048)
			(stroke
				(width 0.1)
				(type default)
			)
			(layer "F.Fab")
		)
		(fp_line
			(start 0.12065 -0.3048)
			(end 0.67945 -0.3048)
			(stroke
				(width 0.1)
				(type default)
			)
			(layer "F.Fab")
		)
		(fp_line
			(start 0.67945 -0.3048)
			(end 0.67945 0.3048)
			(stroke
				(width 0.1)
				(type default)
			)
			(layer "F.Fab")
		)
		(fp_line
			(start -0.67945 -0.305054)
			(end -0.12065 -0.305054)
			(stroke
				(width 0.1)
				(type default)
			)
			(layer "F.Fab")
		)
		(fp_line
			(start -0.12065 -0.305054)
			(end -0.12065 -0.2794)
			(stroke
				(width 0.1)
				(type default)
			)
			(layer "F.Fab")
		)
		(pad "1" smd circle
			(at -0.40005 0 270)
			(size 0 0)
			(layers "F.Cu" "F.Mask" "F.Paste")
			(net "NC_PVDD11_S3_P0_IMON7")
		)
		(pad "2" smd circle
			(at 0.40005 0 270)
			(size 0 0)
			(layers "F.Cu" "F.Mask" "F.Paste")
			(net "GND")
		)
	)
	(footprint ""
		(layer "F.Cu")
		(at 105.485946 -54.882034 -90)
		(property "Reference" "R6315"
			(at 0 0 270)
			(layer "F.SilkS")
			(hide yes)
			(effects
				(font
					(size 1.27 1.27)
				)
			)
		)
		(property "Value" ""
			(at 0 0 270)
			(layer "F.Fab")
			(effects
				(font
					(size 1.27 1.27)
				)
			)
		)
		(duplicate_pad_numbers_are_jumpers no)
		(fp_line
			(start -0.7874 0.4064)
			(end -0.7874 -0.4064)
			(stroke
				(width 0.1524)
				(type default)
			)
			(layer "F.SilkS")
		)
		(fp_line
			(start 0.7874 0.4064)
			(end -0.7874 0.4064)
			(stroke
				(width 0.1524)
				(type default)
			)
			(layer "F.SilkS")
		)
		(fp_line
			(start -0.7874 -0.4064)
			(end 0.7874 -0.4064)
			(stroke
				(width 0.1524)
				(type default)
			)
			(layer "F.SilkS")
		)
		(fp_line
			(start 0.7874 -0.4064)
			(end 0.7874 0.4064)
			(stroke
				(width 0.1524)
				(type default)
			)
			(layer "F.SilkS")
		)
		(fp_line
			(start -0.67945 0.3048)
			(end -0.67945 -0.305054)
			(stroke
				(width 0.1)
				(type default)
			)
			(layer "F.Fab")
		)
		(fp_line
			(start -0.12065 0.3048)
			(end -0.67945 0.3048)
			(stroke
				(width 0.1)
				(type default)
			)
			(layer "F.Fab")
		)
		(fp_line
			(start 0.120396 0.3048)
			(end 0.120396 0.2794)
			(stroke
				(width 0.1)
				(type default)
			)
			(layer "F.Fab")
		)
		(fp_line
			(start 0.67945 0.3048)
			(end 0.120396 0.3048)
			(stroke
				(width 0.1)
				(type default)
			)
			(layer "F.Fab")
		)
		(fp_line
			(start -0.12065 0.2794)
			(end -0.12065 0.3048)
			(stroke
				(width 0.1)
				(type default)
			)
			(layer "F.Fab")
		)
		(fp_line
			(start 0.120396 0.2794)
			(end -0.12065 0.2794)
			(stroke
				(width 0.1)
				(type default)
			)
			(layer "F.Fab")
		)
		(fp_line
			(start -0.12065 -0.2794)
			(end 0.12065 -0.2794)
			(stroke
				(width 0.1)
				(type default)
			)
			(layer "F.Fab")
		)
		(fp_line
			(start 0.12065 -0.2794)
			(end 0.12065 -0.3048)
			(stroke
				(width 0.1)
				(type default)
			)
			(layer "F.Fab")
		)
		(fp_line
			(start 0.12065 -0.3048)
			(end 0.67945 -0.3048)
			(stroke
				(width 0.1)
				(type default)
			)
			(layer "F.Fab")
		)
		(fp_line
			(start 0.67945 -0.3048)
			(end 0.67945 0.3048)
			(stroke
				(width 0.1)
				(type default)
			)
			(layer "F.Fab")
		)
		(fp_line
			(start -0.67945 -0.305054)
			(end -0.12065 -0.305054)
			(stroke
				(width 0.1)
				(type default)
			)
			(layer "F.Fab")
		)
		(fp_line
			(start -0.12065 -0.305054)
			(end -0.12065 -0.2794)
			(stroke
				(width 0.1)
				(type default)
			)
			(layer "F.Fab")
		)
		(pad "1" smd circle
			(at -0.40005 0 270)
			(size 0 0)
			(layers "F.Cu" "F.Mask" "F.Paste")
			(net "P3V3_AUX")
		)
		(pad "2" smd circle
			(at 0.40005 0 270)
			(size 0 0)
			(layers "F.Cu" "F.Mask" "F.Paste")
			(net "USB_HUB2_TI_OVERCUR2")
		)
	)
	(footprint ""
		(layer "F.Cu")
		(at 264.986516 -138.321796 180)
		(property "Reference" "R1529"
			(at 0 0 180)
			(layer "F.SilkS")
			(hide yes)
			(effects
				(font
					(size 1.27 1.27)
				)
			)
		)
		(property "Value" ""
			(at 0 0 180)
			(layer "F.Fab")
			(effects
				(font
					(size 1.27 1.27)
				)
			)
		)
		(duplicate_pad_numbers_are_jumpers no)
		(fp_line
			(start 0.7874 0.4064)
			(end -0.7874 0.4064)
			(stroke
				(width 0.1524)
				(type default)
			)
			(layer "F.SilkS")
		)
		(fp_line
			(start 0.7874 -0.4064)
			(end 0.7874 0.4064)
			(stroke
				(width 0.1524)
				(type default)
			)
			(layer "F.SilkS")
		)
		(fp_line
			(start -0.7874 0.4064)
			(end -0.7874 -0.4064)
			(stroke
				(width 0.1524)
				(type default)
			)
			(layer "F.SilkS")
		)
		(fp_line
			(start -0.7874 -0.4064)
			(end 0.7874 -0.4064)
			(stroke
				(width 0.1524)
				(type default)
			)
			(layer "F.SilkS")
		)
		(fp_line
			(start 0.67945 0.3048)
			(end 0.120396 0.3048)
			(stroke
				(width 0.1)
				(type default)
			)
			(layer "F.Fab")
		)
		(fp_line
			(start 0.67945 -0.3048)
			(end 0.67945 0.3048)
			(stroke
				(width 0.1)
				(type default)
			)
			(layer "F.Fab")
		)
		(fp_line
			(start 0.12065 -0.2794)
			(end 0.12065 -0.3048)
			(stroke
				(width 0.1)
				(type default)
			)
			(layer "F.Fab")
		)
		(fp_line
			(start 0.12065 -0.3048)
			(end 0.67945 -0.3048)
			(stroke
				(width 0.1)
				(type default)
			)
			(layer "F.Fab")
		)
		(fp_line
			(start 0.120396 0.3048)
			(end 0.120396 0.2794)
			(stroke
				(width 0.1)
				(type default)
			)
			(layer "F.Fab")
		)
		(fp_line
			(start 0.120396 0.2794)
			(end -0.12065 0.2794)
			(stroke
				(width 0.1)
				(type default)
			)
			(layer "F.Fab")
		)
		(fp_line
			(start -0.12065 0.3048)
			(end -0.67945 0.3048)
			(stroke
				(width 0.1)
				(type default)
			)
			(layer "F.Fab")
		)
		(fp_line
			(start -0.12065 0.2794)
			(end -0.12065 0.3048)
			(stroke
				(width 0.1)
				(type default)
			)
			(layer "F.Fab")
		)
		(fp_line
			(start -0.12065 -0.2794)
			(end 0.12065 -0.2794)
			(stroke
				(width 0.1)
				(type default)
			)
			(layer "F.Fab")
		)
		(fp_line
			(start -0.12065 -0.305054)
			(end -0.12065 -0.2794)
			(stroke
				(width 0.1)
				(type default)
			)
			(layer "F.Fab")
		)
		(fp_line
			(start -0.67945 0.3048)
			(end -0.67945 -0.305054)
			(stroke
				(width 0.1)
				(type default)
			)
			(layer "F.Fab")
		)
		(fp_line
			(start -0.67945 -0.305054)
			(end -0.12065 -0.305054)
			(stroke
				(width 0.1)
				(type default)
			)
			(layer "F.Fab")
		)
		(pad "1" smd circle
			(at -0.40005 0 180)
			(size 0 0)
			(layers "F.Cu" "F.Mask" "F.Paste")
			(net "PVDD18_S5_P0")
		)
		(pad "2" smd circle
			(at 0.40005 0 180)
			(size 0 0)
			(layers "F.Cu" "F.Mask" "F.Paste")
			(net "SPI_CPU0_D3")
		)
	)
	(footprint ""
		(layer "F.Cu")
		(at 297.670982 -351.573846 90)
		(property "Reference" "PC145_7"
			(at 0 0 90)
			(layer "F.SilkS")
			(hide yes)
			(effects
				(font
					(size 1.27 1.27)
				)
			)
		)
		(property "Value" ""
			(at 0 0 90)
			(layer "F.Fab")
			(effects
				(font
					(size 1.27 1.27)
				)
			)
		)
		(duplicate_pad_numbers_are_jumpers no)
		(fp_line
			(start 0.7874 -0.4064)
			(end 0.7874 0.4064)
			(stroke
				(width 0.1524)
				(type default)
			)
			(layer "F.SilkS")
		)
		(fp_line
			(start -0.7874 -0.4064)
			(end 0.7874 -0.4064)
			(stroke
				(width 0.1524)
				(type default)
			)
			(layer "F.SilkS")
		)
		(fp_line
			(start 0.7874 0.4064)
			(end -0.7874 0.4064)
			(stroke
				(width 0.1524)
				(type default)
			)
			(layer "F.SilkS")
		)
		(fp_line
			(start -0.7874 0.4064)
			(end -0.7874 -0.4064)
			(stroke
				(width 0.1524)
				(type default)
			)
			(layer "F.SilkS")
		)
		(fp_line
			(start -0.12065 -0.305054)
			(end -0.12065 -0.2794)
			(stroke
				(width 0.1)
				(type default)
			)
			(layer "F.Fab")
		)
		(fp_line
			(start -0.67945 -0.305054)
			(end -0.12065 -0.305054)
			(stroke
				(width 0.1)
				(type default)
			)
			(layer "F.Fab")
		)
		(fp_line
			(start 0.67945 -0.3048)
			(end 0.67945 0.3048)
			(stroke
				(width 0.1)
				(type default)
			)
			(layer "F.Fab")
		)
		(fp_line
			(start 0.12065 -0.3048)
			(end 0.67945 -0.3048)
			(stroke
				(width 0.1)
				(type default)
			)
			(layer "F.Fab")
		)
		(fp_line
			(start 0.12065 -0.2794)
			(end 0.12065 -0.3048)
			(stroke
				(width 0.1)
				(type default)
			)
			(layer "F.Fab")
		)
		(fp_line
			(start -0.12065 -0.2794)
			(end 0.12065 -0.2794)
			(stroke
				(width 0.1)
				(type default)
			)
			(layer "F.Fab")
		)
		(fp_line
			(start 0.120396 0.2794)
			(end -0.12065 0.2794)
			(stroke
				(width 0.1)
				(type default)
			)
			(layer "F.Fab")
		)
		(fp_line
			(start -0.12065 0.2794)
			(end -0.12065 0.3048)
			(stroke
				(width 0.1)
				(type default)
			)
			(layer "F.Fab")
		)
		(fp_line
			(start 0.67945 0.3048)
			(end 0.120396 0.3048)
			(stroke
				(width 0.1)
				(type default)
			)
			(layer "F.Fab")
		)
		(fp_line
			(start 0.120396 0.3048)
			(end 0.120396 0.2794)
			(stroke
				(width 0.1)
				(type default)
			)
			(layer "F.Fab")
		)
		(fp_line
			(start -0.12065 0.3048)
			(end -0.67945 0.3048)
			(stroke
				(width 0.1)
				(type default)
			)
			(layer "F.Fab")
		)
		(fp_line
			(start -0.67945 0.3048)
			(end -0.67945 -0.305054)
			(stroke
				(width 0.1)
				(type default)
			)
			(layer "F.Fab")
		)
		(pad "1" smd circle
			(at -0.40005 0 90)
			(size 0 0)
			(layers "F.Cu" "F.Mask" "F.Paste")
			(net "PVDDCR_CPU1_P0_VCCS")
		)
		(pad "2" smd circle
			(at 0.40005 0 90)
			(size 0 0)
			(layers "F.Cu" "F.Mask" "F.Paste")
			(net "GND")
		)
	)
	(footprint ""
		(layer "F.Cu")
		(at 420.246302 -434.386736 -90)
		(property "Reference" "C4"
			(at 0 0 270)
			(layer "F.SilkS")
			(hide yes)
			(effects
				(font
					(size 1.27 1.27)
				)
			)
		)
		(property "Value" ""
			(at 0 0 270)
			(layer "F.Fab")
			(effects
				(font
					(size 1.27 1.27)
				)
			)
		)
		(duplicate_pad_numbers_are_jumpers no)
		(fp_line
			(start -0.7874 0.4064)
			(end -0.7874 -0.4064)
			(stroke
				(width 0.1524)
				(type default)
			)
			(layer "F.SilkS")
		)
		(fp_line
			(start 0.7874 0.4064)
			(end -0.7874 0.4064)
			(stroke
				(width 0.1524)
				(type default)
			)
			(layer "F.SilkS")
		)
		(fp_line
			(start -0.7874 -0.4064)
			(end 0.7874 -0.4064)
			(stroke
				(width 0.1524)
				(type default)
			)
			(layer "F.SilkS")
		)
		(fp_line
			(start 0.7874 -0.4064)
			(end 0.7874 0.4064)
			(stroke
				(width 0.1524)
				(type default)
			)
			(layer "F.SilkS")
		)
		(fp_line
			(start -0.67945 0.3048)
			(end -0.67945 -0.305054)
			(stroke
				(width 0.1)
				(type default)
			)
			(layer "F.Fab")
		)
		(fp_line
			(start -0.12065 0.3048)
			(end -0.67945 0.3048)
			(stroke
				(width 0.1)
				(type default)
			)
			(layer "F.Fab")
		)
		(fp_line
			(start 0.120396 0.3048)
			(end 0.120396 0.2794)
			(stroke
				(width 0.1)
				(type default)
			)
			(layer "F.Fab")
		)
		(fp_line
			(start 0.67945 0.3048)
			(end 0.120396 0.3048)
			(stroke
				(width 0.1)
				(type default)
			)
			(layer "F.Fab")
		)
		(fp_line
			(start -0.12065 0.2794)
			(end -0.12065 0.3048)
			(stroke
				(width 0.1)
				(type default)
			)
			(layer "F.Fab")
		)
		(fp_line
			(start 0.120396 0.2794)
			(end -0.12065 0.2794)
			(stroke
				(width 0.1)
				(type default)
			)
			(layer "F.Fab")
		)
		(fp_line
			(start -0.12065 -0.2794)
			(end 0.12065 -0.2794)
			(stroke
				(width 0.1)
				(type default)
			)
			(layer "F.Fab")
		)
		(fp_line
			(start 0.12065 -0.2794)
			(end 0.12065 -0.3048)
			(stroke
				(width 0.1)
				(type default)
			)
			(layer "F.Fab")
		)
		(fp_line
			(start 0.12065 -0.3048)
			(end 0.67945 -0.3048)
			(stroke
				(width 0.1)
				(type default)
			)
			(layer "F.Fab")
		)
		(fp_line
			(start 0.67945 -0.3048)
			(end 0.67945 0.3048)
			(stroke
				(width 0.1)
				(type default)
			)
			(layer "F.Fab")
		)
		(fp_line
			(start -0.67945 -0.305054)
			(end -0.12065 -0.305054)
			(stroke
				(width 0.1)
				(type default)
			)
			(layer "F.Fab")
		)
		(fp_line
			(start -0.12065 -0.305054)
			(end -0.12065 -0.2794)
			(stroke
				(width 0.1)
				(type default)
			)
			(layer "F.Fab")
		)
		(pad "1" smd circle
			(at -0.40005 0 270)
			(size 0 0)
			(layers "F.Cu" "F.Mask" "F.Paste")
			(net "GPU_3V3IO_RSVD1_ISO")
		)
		(pad "2" smd circle
			(at 0.40005 0 270)
			(size 0 0)
			(layers "F.Cu" "F.Mask" "F.Paste")
			(net "GND")
		)
	)
	(footprint ""
		(layer "F.Cu")
		(at 120.340882 -14.00429)
		(property "Reference" "R4185"
			(at 0 0 0)
			(layer "F.SilkS")
			(hide yes)
			(effects
				(font
					(size 1.27 1.27)
				)
			)
		)
		(property "Value" ""
			(at 0 0 0)
			(layer "F.Fab")
			(effects
				(font
					(size 1.27 1.27)
				)
			)
		)
		(duplicate_pad_numbers_are_jumpers no)
		(fp_line
			(start -0.7874 -0.4064)
			(end 0.7874 -0.4064)
			(stroke
				(width 0.1524)
				(type default)
			)
			(layer "F.SilkS")
		)
		(fp_line
			(start -0.7874 0.4064)
			(end -0.7874 -0.4064)
			(stroke
				(width 0.1524)
				(type default)
			)
			(layer "F.SilkS")
		)
		(fp_line
			(start 0.7874 -0.4064)
			(end 0.7874 0.4064)
			(stroke
				(width 0.1524)
				(type default)
			)
			(layer "F.SilkS")
		)
		(fp_line
			(start 0.7874 0.4064)
			(end -0.7874 0.4064)
			(stroke
				(width 0.1524)
				(type default)
			)
			(layer "F.SilkS")
		)
		(fp_line
			(start -0.67945 -0.305054)
			(end -0.12065 -0.305054)
			(stroke
				(width 0.1)
				(type default)
			)
			(layer "F.Fab")
		)
		(fp_line
			(start -0.67945 0.3048)
			(end -0.67945 -0.305054)
			(stroke
				(width 0.1)
				(type default)
			)
			(layer "F.Fab")
		)
		(fp_line
			(start -0.12065 -0.305054)
			(end -0.12065 -0.2794)
			(stroke
				(width 0.1)
				(type default)
			)
			(layer "F.Fab")
		)
		(fp_line
			(start -0.12065 -0.2794)
			(end 0.12065 -0.2794)
			(stroke
				(width 0.1)
				(type default)
			)
			(layer "F.Fab")
		)
		(fp_line
			(start -0.12065 0.2794)
			(end -0.12065 0.3048)
			(stroke
				(width 0.1)
				(type default)
			)
			(layer "F.Fab")
		)
		(fp_line
			(start -0.12065 0.3048)
			(end -0.67945 0.3048)
			(stroke
				(width 0.1)
				(type default)
			)
			(layer "F.Fab")
		)
		(fp_line
			(start 0.120396 0.2794)
			(end -0.12065 0.2794)
			(stroke
				(width 0.1)
				(type default)
			)
			(layer "F.Fab")
		)
		(fp_line
			(start 0.120396 0.3048)
			(end 0.120396 0.2794)
			(stroke
				(width 0.1)
				(type default)
			)
			(layer "F.Fab")
		)
		(fp_line
			(start 0.12065 -0.3048)
			(end 0.67945 -0.3048)
			(stroke
				(width 0.1)
				(type default)
			)
			(layer "F.Fab")
		)
		(fp_line
			(start 0.12065 -0.2794)
			(end 0.12065 -0.3048)
			(stroke
				(width 0.1)
				(type default)
			)
			(layer "F.Fab")
		)
		(fp_line
			(start 0.67945 -0.3048)
			(end 0.67945 0.3048)
			(stroke
				(width 0.1)
				(type default)
			)
			(layer "F.Fab")
		)
		(fp_line
			(start 0.67945 0.3048)
			(end 0.120396 0.3048)
			(stroke
				(width 0.1)
				(type default)
			)
			(layer "F.Fab")
		)
		(pad "1" smd circle
			(at -0.40005 0)
			(size 0 0)
			(layers "F.Cu" "F.Mask" "F.Paste")
			(net "U273_3_ADD2")
		)
		(pad "2" smd circle
			(at 0.40005 0)
			(size 0 0)
			(layers "F.Cu" "F.Mask" "F.Paste")
			(net "GND")
		)
	)
	(footprint ""
		(layer "F.Cu")
		(at 31.726378 -401.398232)
		(property "Reference" "PC473"
			(at -1.627378 -3.578098 0)
			(unlocked yes)
			(layer "F.SilkS")
			(effects
				(font
					(size 0.7874 0.5842)
					(thickness 0.1524)
				)
				(justify left)
			)
		)
		(property "Value" ""
			(at 0 0 0)
			(layer "F.Fab")
			(effects
				(font
					(size 1.27 1.27)
				)
			)
		)
		(duplicate_pad_numbers_are_jumpers no)
		(fp_line
			(start -2.750058 -1.988058)
			(end -2.750058 -0.9398)
			(stroke
				(width 0.1524)
				(type default)
			)
			(layer "F.SilkS")
		)
		(fp_line
			(start -2.750058 0.9398)
			(end -2.750058 1.988058)
			(stroke
				(width 0.1524)
				(type default)
			)
			(layer "F.SilkS")
		)
		(fp_line
			(start -2.750058 1.988058)
			(end -1.988058 2.750058)
			(stroke
				(width 0.1524)
				(type default)
			)
			(layer "F.SilkS")
		)
		(fp_line
			(start -1.988058 -2.750058)
			(end -2.750058 -1.988058)
			(stroke
				(width 0.1524)
				(type default)
			)
			(layer "F.SilkS")
		)
		(fp_line
			(start -1.988058 2.750058)
			(end 2.750058 2.750058)
			(stroke
				(width 0.1524)
				(type default)
			)
			(layer "F.SilkS")
		)
		(fp_line
			(start 2.750058 -2.750058)
			(end -1.988058 -2.750058)
			(stroke
				(width 0.1524)
				(type default)
			)
			(layer "F.SilkS")
		)
		(fp_line
			(start 2.750058 -0.9398)
			(end 2.750058 -2.750058)
			(stroke
				(width 0.1524)
				(type default)
			)
			(layer "F.SilkS")
		)
		(fp_line
			(start 2.750058 2.750058)
			(end 2.750058 0.9398)
			(stroke
				(width 0.1524)
				(type default)
			)
			(layer "F.SilkS")
		)
		(fp_line
			(start -2.750058 -2.750058)
			(end -2.750058 2.750058)
			(stroke
				(width 0.1)
				(type default)
			)
			(layer "F.Fab")
		)
		(fp_line
			(start -2.750058 2.750058)
			(end 2.750058 2.750058)
			(stroke
				(width 0.1)
				(type default)
			)
			(layer "F.Fab")
		)
		(fp_line
			(start 2.750058 -2.750058)
			(end -2.750058 -2.750058)
			(stroke
				(width 0.1)
				(type default)
			)
			(layer "F.Fab")
		)
		(fp_line
			(start 2.750058 2.750058)
			(end 2.750058 -2.750058)
			(stroke
				(width 0.1)
				(type default)
			)
			(layer "F.Fab")
		)
		(pad "1" smd rect
			(at -2.199894 0 90)
			(size 1.6002 3.0226)
			(layers "F.Cu" "F.Mask" "F.Paste")
			(net "SW_P12V_AUX_P0V9_RETIMER_CPU1_FLT")
		)
		(pad "2" smd rect
			(at 2.199894 0 90)
			(size 1.6002 3.0226)
			(layers "F.Cu" "F.Mask" "F.Paste")
			(net "GND")
		)
	)
	(footprint ""
		(layer "F.Cu")
		(at 420.246302 -440.012836 -90)
		(property "Reference" "R2828"
			(at 0 0 270)
			(layer "F.SilkS")
			(hide yes)
			(effects
				(font
					(size 1.27 1.27)
				)
			)
		)
		(property "Value" ""
			(at 0 0 270)
			(layer "F.Fab")
			(effects
				(font
					(size 1.27 1.27)
				)
			)
		)
		(duplicate_pad_numbers_are_jumpers no)
		(fp_line
			(start -0.7874 0.4064)
			(end -0.7874 -0.4064)
			(stroke
				(width 0.1524)
				(type default)
			)
			(layer "F.SilkS")
		)
		(fp_line
			(start 0.7874 0.4064)
			(end -0.7874 0.4064)
			(stroke
				(width 0.1524)
				(type default)
			)
			(layer "F.SilkS")
		)
		(fp_line
			(start -0.7874 -0.4064)
			(end 0.7874 -0.4064)
			(stroke
				(width 0.1524)
				(type default)
			)
			(layer "F.SilkS")
		)
		(fp_line
			(start 0.7874 -0.4064)
			(end 0.7874 0.4064)
			(stroke
				(width 0.1524)
				(type default)
			)
			(layer "F.SilkS")
		)
		(fp_line
			(start -0.67945 0.3048)
			(end -0.67945 -0.305054)
			(stroke
				(width 0.1)
				(type default)
			)
			(layer "F.Fab")
		)
		(fp_line
			(start -0.12065 0.3048)
			(end -0.67945 0.3048)
			(stroke
				(width 0.1)
				(type default)
			)
			(layer "F.Fab")
		)
		(fp_line
			(start 0.120396 0.3048)
			(end 0.120396 0.2794)
			(stroke
				(width 0.1)
				(type default)
			)
			(layer "F.Fab")
		)
		(fp_line
			(start 0.67945 0.3048)
			(end 0.120396 0.3048)
			(stroke
				(width 0.1)
				(type default)
			)
			(layer "F.Fab")
		)
		(fp_line
			(start -0.12065 0.2794)
			(end -0.12065 0.3048)
			(stroke
				(width 0.1)
				(type default)
			)
			(layer "F.Fab")
		)
		(fp_line
			(start 0.120396 0.2794)
			(end -0.12065 0.2794)
			(stroke
				(width 0.1)
				(type default)
			)
			(layer "F.Fab")
		)
		(fp_line
			(start -0.12065 -0.2794)
			(end 0.12065 -0.2794)
			(stroke
				(width 0.1)
				(type default)
			)
			(layer "F.Fab")
		)
		(fp_line
			(start 0.12065 -0.2794)
			(end 0.12065 -0.3048)
			(stroke
				(width 0.1)
				(type default)
			)
			(layer "F.Fab")
		)
		(fp_line
			(start 0.12065 -0.3048)
			(end 0.67945 -0.3048)
			(stroke
				(width 0.1)
				(type default)
			)
			(layer "F.Fab")
		)
		(fp_line
			(start 0.67945 -0.3048)
			(end 0.67945 0.3048)
			(stroke
				(width 0.1)
				(type default)
			)
			(layer "F.Fab")
		)
		(fp_line
			(start -0.67945 -0.305054)
			(end -0.12065 -0.305054)
			(stroke
				(width 0.1)
				(type default)
			)
			(layer "F.Fab")
		)
		(fp_line
			(start -0.12065 -0.305054)
			(end -0.12065 -0.2794)
			(stroke
				(width 0.1)
				(type default)
			)
			(layer "F.Fab")
		)
		(pad "1" smd circle
			(at -0.40005 0 270)
			(size 0 0)
			(layers "F.Cu" "F.Mask" "F.Paste")
			(net "P3V3_AUX")
		)
		(pad "2" smd circle
			(at 0.40005 0 270)
			(size 0 0)
			(layers "F.Cu" "F.Mask" "F.Paste")
			(net "RST_BMC_FROM_SWB_N")
		)
	)
	(footprint ""
		(layer "F.Cu")
		(at 392.081258 -402.9202 -90)
		(property "Reference" "R1126"
			(at 0 0 270)
			(layer "F.SilkS")
			(hide yes)
			(effects
				(font
					(size 1.27 1.27)
				)
			)
		)
		(property "Value" ""
			(at 0 0 270)
			(layer "F.Fab")
			(effects
				(font
					(size 1.27 1.27)
				)
			)
		)
		(duplicate_pad_numbers_are_jumpers no)
		(fp_line
			(start -0.32512 0.175006)
			(end -0.32512 -0.175006)
			(stroke
				(width 0.1)
				(type default)
			)
			(layer "F.Fab")
		)
		(fp_line
			(start 0.32512 0.175006)
			(end -0.32512 0.175006)
			(stroke
				(width 0.1)
				(type default)
			)
			(layer "F.Fab")
		)
		(fp_line
			(start -0.32512 -0.175006)
			(end 0.32512 -0.175006)
			(stroke
				(width 0.1)
				(type default)
			)
			(layer "F.Fab")
		)
		(fp_line
			(start 0.32512 -0.175006)
			(end 0.32512 0.175006)
			(stroke
				(width 0.1)
				(type default)
			)
			(layer "F.Fab")
		)
		(pad "1" smd rect
			(at -0.2667 0 270)
			(size 0.3048 0.381)
			(layers "F.Cu" "F.Mask" "F.Paste")
			(net "NCF_A1_CPU0_P3_GND")
		)
		(pad "2" smd rect
			(at 0.2667 0 90)
			(size 0.3048 0.381)
			(layers "F.Cu" "F.Mask" "F.Paste")
			(net "GND")
		)
	)
	(footprint ""
		(layer "F.Cu")
		(at 290.311586 -398.613376 90)
		(property "Reference" "R678"
			(at 0 0 90)
			(layer "F.SilkS")
			(hide yes)
			(effects
				(font
					(size 1.27 1.27)
				)
			)
		)
		(property "Value" ""
			(at 0 0 90)
			(layer "F.Fab")
			(effects
				(font
					(size 1.27 1.27)
				)
			)
		)
		(duplicate_pad_numbers_are_jumpers no)
		(fp_line
			(start 0.32512 -0.175006)
			(end 0.32512 0.175006)
			(stroke
				(width 0.1)
				(type default)
			)
			(layer "F.Fab")
		)
		(fp_line
			(start -0.32512 -0.175006)
			(end 0.32512 -0.175006)
			(stroke
				(width 0.1)
				(type default)
			)
			(layer "F.Fab")
		)
		(fp_line
			(start 0.32512 0.175006)
			(end -0.32512 0.175006)
			(stroke
				(width 0.1)
				(type default)
			)
			(layer "F.Fab")
		)
		(fp_line
			(start -0.32512 0.175006)
			(end -0.32512 -0.175006)
			(stroke
				(width 0.1)
				(type default)
			)
			(layer "F.Fab")
		)
		(pad "1" smd rect
			(at -0.2667 0 90)
			(size 0.3048 0.381)
			(layers "F.Cu" "F.Mask" "F.Paste")
			(net "SMB_RT_CPU0_P1_ROM_R_SCL")
		)
		(pad "2" smd rect
			(at 0.2667 0 270)
			(size 0.3048 0.381)
			(layers "F.Cu" "F.Mask" "F.Paste")
			(net "SMB_RT_CPU0_P1_ROM_SCL")
		)
	)
	(footprint ""
		(layer "F.Cu")
		(at 110.644432 -397.232378 180)
		(property "Reference" "C7502"
			(at 0 0 180)
			(layer "F.SilkS")
			(hide yes)
			(effects
				(font
					(size 1.27 1.27)
				)
			)
		)
		(property "Value" ""
			(at 0 0 180)
			(layer "F.Fab")
			(effects
				(font
					(size 1.27 1.27)
				)
			)
		)
		(duplicate_pad_numbers_are_jumpers no)
		(fp_line
			(start 0.299974 0.150114)
			(end -0.299974 0.150114)
			(stroke
				(width 0.1)
				(type default)
			)
			(layer "F.Fab")
		)
		(fp_line
			(start 0.299974 -0.150114)
			(end 0.299974 0.150114)
			(stroke
				(width 0.1)
				(type default)
			)
			(layer "F.Fab")
		)
		(fp_line
			(start -0.299974 0.150114)
			(end -0.299974 -0.150114)
			(stroke
				(width 0.1)
				(type default)
			)
			(layer "F.Fab")
		)
		(fp_line
			(start -0.299974 -0.150114)
			(end 0.299974 -0.150114)
			(stroke
				(width 0.1)
				(type default)
			)
			(layer "F.Fab")
		)
		(pad "1" smd rect
			(at -0.2667 0 180)
			(size 0.3048 0.381)
			(layers "F.Cu" "F.Mask" "F.Paste")
			(net "P1V8_CPU1_RT_1D")
		)
		(pad "2" smd rect
			(at 0.2667 0 180)
			(size 0.3048 0.381)
			(layers "F.Cu" "F.Mask" "F.Paste")
			(net "GND")
		)
	)
	(footprint ""
		(layer "F.Cu")
		(at 140.886942 -102.510844 180)
		(property "Reference" "R2113"
			(at 0 0 180)
			(layer "F.SilkS")
			(hide yes)
			(effects
				(font
					(size 1.27 1.27)
				)
			)
		)
		(property "Value" ""
			(at 0 0 180)
			(layer "F.Fab")
			(effects
				(font
					(size 1.27 1.27)
				)
			)
		)
		(duplicate_pad_numbers_are_jumpers no)
		(fp_line
			(start 0.7874 0.4064)
			(end -0.7874 0.4064)
			(stroke
				(width 0.1524)
				(type default)
			)
			(layer "F.SilkS")
		)
		(fp_line
			(start 0.7874 -0.4064)
			(end 0.7874 0.4064)
			(stroke
				(width 0.1524)
				(type default)
			)
			(layer "F.SilkS")
		)
		(fp_line
			(start -0.7874 0.4064)
			(end -0.7874 -0.4064)
			(stroke
				(width 0.1524)
				(type default)
			)
			(layer "F.SilkS")
		)
		(fp_line
			(start -0.7874 -0.4064)
			(end 0.7874 -0.4064)
			(stroke
				(width 0.1524)
				(type default)
			)
			(layer "F.SilkS")
		)
		(fp_line
			(start 0.67945 0.3048)
			(end 0.120396 0.3048)
			(stroke
				(width 0.1)
				(type default)
			)
			(layer "F.Fab")
		)
		(fp_line
			(start 0.67945 -0.3048)
			(end 0.67945 0.3048)
			(stroke
				(width 0.1)
				(type default)
			)
			(layer "F.Fab")
		)
		(fp_line
			(start 0.12065 -0.2794)
			(end 0.12065 -0.3048)
			(stroke
				(width 0.1)
				(type default)
			)
			(layer "F.Fab")
		)
		(fp_line
			(start 0.12065 -0.3048)
			(end 0.67945 -0.3048)
			(stroke
				(width 0.1)
				(type default)
			)
			(layer "F.Fab")
		)
		(fp_line
			(start 0.120396 0.3048)
			(end 0.120396 0.2794)
			(stroke
				(width 0.1)
				(type default)
			)
			(layer "F.Fab")
		)
		(fp_line
			(start 0.120396 0.2794)
			(end -0.12065 0.2794)
			(stroke
				(width 0.1)
				(type default)
			)
			(layer "F.Fab")
		)
		(fp_line
			(start -0.12065 0.3048)
			(end -0.67945 0.3048)
			(stroke
				(width 0.1)
				(type default)
			)
			(layer "F.Fab")
		)
		(fp_line
			(start -0.12065 0.2794)
			(end -0.12065 0.3048)
			(stroke
				(width 0.1)
				(type default)
			)
			(layer "F.Fab")
		)
		(fp_line
			(start -0.12065 -0.2794)
			(end 0.12065 -0.2794)
			(stroke
				(width 0.1)
				(type default)
			)
			(layer "F.Fab")
		)
		(fp_line
			(start -0.12065 -0.305054)
			(end -0.12065 -0.2794)
			(stroke
				(width 0.1)
				(type default)
			)
			(layer "F.Fab")
		)
		(fp_line
			(start -0.67945 0.3048)
			(end -0.67945 -0.305054)
			(stroke
				(width 0.1)
				(type default)
			)
			(layer "F.Fab")
		)
		(fp_line
			(start -0.67945 -0.305054)
			(end -0.12065 -0.305054)
			(stroke
				(width 0.1)
				(type default)
			)
			(layer "F.Fab")
		)
		(pad "1" smd circle
			(at -0.40005 0 180)
			(size 0 0)
			(layers "F.Cu" "F.Mask" "F.Paste")
			(net "RST_PERST_BUF_M2_0_N")
		)
		(pad "2" smd circle
			(at 0.40005 0 180)
			(size 0 0)
			(layers "F.Cu" "F.Mask" "F.Paste")
			(net "RST_PERST_BUF_M2_0_R_N")
		)
	)
	(footprint ""
		(layer "F.Cu")
		(at 216.99855 -127.801116)
		(property "Reference" "R6825"
			(at 0 0 0)
			(layer "F.SilkS")
			(hide yes)
			(effects
				(font
					(size 1.27 1.27)
				)
			)
		)
		(property "Value" ""
			(at 0 0 0)
			(layer "F.Fab")
			(effects
				(font
					(size 1.27 1.27)
				)
			)
		)
		(duplicate_pad_numbers_are_jumpers no)
		(fp_line
			(start -0.7874 -0.4064)
			(end 0.7874 -0.4064)
			(stroke
				(width 0.1524)
				(type default)
			)
			(layer "F.SilkS")
		)
		(fp_line
			(start -0.7874 0.4064)
			(end -0.7874 -0.4064)
			(stroke
				(width 0.1524)
				(type default)
			)
			(layer "F.SilkS")
		)
		(fp_line
			(start 0.7874 -0.4064)
			(end 0.7874 0.4064)
			(stroke
				(width 0.1524)
				(type default)
			)
			(layer "F.SilkS")
		)
		(fp_line
			(start 0.7874 0.4064)
			(end -0.7874 0.4064)
			(stroke
				(width 0.1524)
				(type default)
			)
			(layer "F.SilkS")
		)
		(fp_line
			(start -0.67945 -0.305054)
			(end -0.12065 -0.305054)
			(stroke
				(width 0.1)
				(type default)
			)
			(layer "F.Fab")
		)
		(fp_line
			(start -0.67945 0.3048)
			(end -0.67945 -0.305054)
			(stroke
				(width 0.1)
				(type default)
			)
			(layer "F.Fab")
		)
		(fp_line
			(start -0.12065 -0.305054)
			(end -0.12065 -0.2794)
			(stroke
				(width 0.1)
				(type default)
			)
			(layer "F.Fab")
		)
		(fp_line
			(start -0.12065 -0.2794)
			(end 0.12065 -0.2794)
			(stroke
				(width 0.1)
				(type default)
			)
			(layer "F.Fab")
		)
		(fp_line
			(start -0.12065 0.2794)
			(end -0.12065 0.3048)
			(stroke
				(width 0.1)
				(type default)
			)
			(layer "F.Fab")
		)
		(fp_line
			(start -0.12065 0.3048)
			(end -0.67945 0.3048)
			(stroke
				(width 0.1)
				(type default)
			)
			(layer "F.Fab")
		)
		(fp_line
			(start 0.120396 0.2794)
			(end -0.12065 0.2794)
			(stroke
				(width 0.1)
				(type default)
			)
			(layer "F.Fab")
		)
		(fp_line
			(start 0.120396 0.3048)
			(end 0.120396 0.2794)
			(stroke
				(width 0.1)
				(type default)
			)
			(layer "F.Fab")
		)
		(fp_line
			(start 0.12065 -0.3048)
			(end 0.67945 -0.3048)
			(stroke
				(width 0.1)
				(type default)
			)
			(layer "F.Fab")
		)
		(fp_line
			(start 0.12065 -0.2794)
			(end 0.12065 -0.3048)
			(stroke
				(width 0.1)
				(type default)
			)
			(layer "F.Fab")
		)
		(fp_line
			(start 0.67945 -0.3048)
			(end 0.67945 0.3048)
			(stroke
				(width 0.1)
				(type default)
			)
			(layer "F.Fab")
		)
		(fp_line
			(start 0.67945 0.3048)
			(end 0.120396 0.3048)
			(stroke
				(width 0.1)
				(type default)
			)
			(layer "F.Fab")
		)
		(pad "1" smd circle
			(at -0.40005 0)
			(size 0 0)
			(layers "F.Cu" "F.Mask" "F.Paste")
			(net "RST_RT_CPU0_P3_PERST_R2_N")
		)
		(pad "2" smd circle
			(at 0.40005 0)
			(size 0 0)
			(layers "F.Cu" "F.Mask" "F.Paste")
			(net "RST_RT_CPU0_P3_PERST_R_N")
		)
	)
	(footprint ""
		(layer "F.Cu")
		(at 446.522602 -418.96411 -90)
		(property "Reference" "PR6613"
			(at 0 0 270)
			(layer "F.SilkS")
			(hide yes)
			(effects
				(font
					(size 1.27 1.27)
				)
			)
		)
		(property "Value" ""
			(at 0 0 270)
			(layer "F.Fab")
			(effects
				(font
					(size 1.27 1.27)
				)
			)
		)
		(duplicate_pad_numbers_are_jumpers no)
		(fp_line
			(start -0.7874 0.4064)
			(end -0.7874 -0.4064)
			(stroke
				(width 0.1524)
				(type default)
			)
			(layer "F.SilkS")
		)
		(fp_line
			(start 0.7874 0.4064)
			(end -0.7874 0.4064)
			(stroke
				(width 0.1524)
				(type default)
			)
			(layer "F.SilkS")
		)
		(fp_line
			(start -0.7874 -0.4064)
			(end 0.7874 -0.4064)
			(stroke
				(width 0.1524)
				(type default)
			)
			(layer "F.SilkS")
		)
		(fp_line
			(start 0.7874 -0.4064)
			(end 0.7874 0.4064)
			(stroke
				(width 0.1524)
				(type default)
			)
			(layer "F.SilkS")
		)
		(fp_line
			(start -0.67945 0.3048)
			(end -0.67945 -0.305054)
			(stroke
				(width 0.1)
				(type default)
			)
			(layer "F.Fab")
		)
		(fp_line
			(start -0.12065 0.3048)
			(end -0.67945 0.3048)
			(stroke
				(width 0.1)
				(type default)
			)
			(layer "F.Fab")
		)
		(fp_line
			(start 0.120396 0.3048)
			(end 0.120396 0.2794)
			(stroke
				(width 0.1)
				(type default)
			)
			(layer "F.Fab")
		)
		(fp_line
			(start 0.67945 0.3048)
			(end 0.120396 0.3048)
			(stroke
				(width 0.1)
				(type default)
			)
			(layer "F.Fab")
		)
		(fp_line
			(start -0.12065 0.2794)
			(end -0.12065 0.3048)
			(stroke
				(width 0.1)
				(type default)
			)
			(layer "F.Fab")
		)
		(fp_line
			(start 0.120396 0.2794)
			(end -0.12065 0.2794)
			(stroke
				(width 0.1)
				(type default)
			)
			(layer "F.Fab")
		)
		(fp_line
			(start -0.12065 -0.2794)
			(end 0.12065 -0.2794)
			(stroke
				(width 0.1)
				(type default)
			)
			(layer "F.Fab")
		)
		(fp_line
			(start 0.12065 -0.2794)
			(end 0.12065 -0.3048)
			(stroke
				(width 0.1)
				(type default)
			)
			(layer "F.Fab")
		)
		(fp_line
			(start 0.12065 -0.3048)
			(end 0.67945 -0.3048)
			(stroke
				(width 0.1)
				(type default)
			)
			(layer "F.Fab")
		)
		(fp_line
			(start 0.67945 -0.3048)
			(end 0.67945 0.3048)
			(stroke
				(width 0.1)
				(type default)
			)
			(layer "F.Fab")
		)
		(fp_line
			(start -0.67945 -0.305054)
			(end -0.12065 -0.305054)
			(stroke
				(width 0.1)
				(type default)
			)
			(layer "F.Fab")
		)
		(fp_line
			(start -0.12065 -0.305054)
			(end -0.12065 -0.2794)
			(stroke
				(width 0.1)
				(type default)
			)
			(layer "F.Fab")
		)
		(pad "1" smd circle
			(at -0.40005 0 270)
			(size 0 0)
			(layers "F.Cu" "F.Mask" "F.Paste")
			(net "NC_P0V9_RETIMER_CPU0_IMON7")
		)
		(pad "2" smd circle
			(at 0.40005 0 270)
			(size 0 0)
			(layers "F.Cu" "F.Mask" "F.Paste")
			(net "GND")
		)
	)
	(footprint ""
		(layer "F.Cu")
		(at 191.389 -50.673 90)
		(property "Reference" "D8002"
			(at -2.191004 -3.142488 90)
			(unlocked yes)
			(layer "F.SilkS")
			(effects
				(font
					(size 0.7874 0.5842)
					(thickness 0.1524)
				)
				(justify left)
			)
		)
		(property "Value" ""
			(at 0 0 90)
			(layer "F.Fab")
			(effects
				(font
					(size 1.27 1.27)
				)
			)
		)
		(duplicate_pad_numbers_are_jumpers no)
		(fp_line
			(start 1.778 -0.5588)
			(end 1.3208 -0.5588)
			(stroke
				(width 0.1524)
				(type default)
			)
			(layer "F.SilkS")
		)
		(fp_line
			(start 1.778 -0.5588)
			(end 1.778 0.5588)
			(stroke
				(width 0.1524)
				(type default)
			)
			(layer "F.SilkS")
		)
		(fp_line
			(start 1.4732 -0.5588)
			(end 1.4732 0.5588)
			(stroke
				(width 0.1524)
				(type default)
			)
			(layer "F.SilkS")
		)
		(fp_line
			(start 1.3208 -0.5588)
			(end 1.3208 0.5588)
			(stroke
				(width 0.1524)
				(type default)
			)
			(layer "F.SilkS")
		)
		(fp_line
			(start -1.3208 -0.5588)
			(end 1.3208 -0.5588)
			(stroke
				(width 0.1524)
				(type default)
			)
			(layer "F.SilkS")
		)
		(fp_line
			(start 1.778 0.5588)
			(end 1.3208 0.5588)
			(stroke
				(width 0.1524)
				(type default)
			)
			(layer "F.SilkS")
		)
		(fp_line
			(start 1.6256 0.5588)
			(end 1.6256 -0.5588)
			(stroke
				(width 0.1524)
				(type default)
			)
			(layer "F.SilkS")
		)
		(fp_line
			(start 1.3208 0.5588)
			(end -1.3208 0.5588)
			(stroke
				(width 0.1524)
				(type default)
			)
			(layer "F.SilkS")
		)
		(fp_line
			(start -1.3208 0.5588)
			(end -1.3208 -0.5588)
			(stroke
				(width 0.1524)
				(type default)
			)
			(layer "F.SilkS")
		)
		(fp_line
			(start 0.899922 -0.40005)
			(end 0.899922 0.40005)
			(stroke
				(width 0.1)
				(type default)
			)
			(layer "F.Fab")
		)
		(fp_line
			(start -0.899922 -0.40005)
			(end 0.899922 -0.40005)
			(stroke
				(width 0.1)
				(type default)
			)
			(layer "F.Fab")
		)
		(fp_line
			(start 0.899922 0.40005)
			(end -0.899922 0.40005)
			(stroke
				(width 0.1)
				(type default)
			)
			(layer "F.Fab")
		)
		(fp_line
			(start -0.899922 0.40005)
			(end -0.899922 -0.40005)
			(stroke
				(width 0.1)
				(type default)
			)
			(layer "F.Fab")
		)
		(fp_text user "+"
			(at -2.6162 -0.22225 90)
			(unlocked yes)
			(layer "F.SilkS")
			(effects
				(font
					(size 1.905 1.4224)
					(thickness 0.1524)
				)
				(justify left)
			)
		)
		(fp_text user "-"
			(at 1.73101 0.59436 90)
			(unlocked yes)
			(layer "F.SilkS")
			(effects
				(font
					(size 1.905 1.4224)
					(thickness 0.1524)
				)
				(justify left)
			)
		)
		(fp_text user "-"
			(at 1.651 -0.22225 90)
			(unlocked yes)
			(layer "F.Fab")
			(effects
				(font
					(size 1.905 1.4224)
					(thickness 0.1524)
				)
				(justify left)
			)
		)
		(fp_text user "+"
			(at -2.6162 -0.22225 90)
			(unlocked yes)
			(layer "F.Fab")
			(effects
				(font
					(size 1.905 1.4224)
					(thickness 0.1524)
				)
				(justify left)
			)
		)
		(pad "A" smd rect
			(at -0.750062 0 90)
			(size 0.8128 0.8128)
			(layers "F.Cu" "F.Mask" "F.Paste")
			(net "LED_P12V_SCM_FAULT")
		)
		(pad "C" smd rect
			(at 0.750062 0 90)
			(size 0.8128 0.8128)
			(layers "F.Cu" "F.Mask" "F.Paste")
			(net "LED_P12V_SCM_FAULT_D2")
		)
	)
	(footprint ""
		(layer "F.Cu")
		(at 178.71694 -402.468842 180)
		(property "Reference" "PC2187"
			(at 0 0 180)
			(layer "F.SilkS")
			(hide yes)
			(effects
				(font
					(size 1.27 1.27)
				)
			)
		)
		(property "Value" ""
			(at 0 0 180)
			(layer "F.Fab")
			(effects
				(font
					(size 1.27 1.27)
				)
			)
		)
		(duplicate_pad_numbers_are_jumpers no)
		(fp_line
			(start 0.7874 0.4064)
			(end -0.7874 0.4064)
			(stroke
				(width 0.1524)
				(type default)
			)
			(layer "F.SilkS")
		)
		(fp_line
			(start 0.7874 -0.4064)
			(end 0.7874 0.4064)
			(stroke
				(width 0.1524)
				(type default)
			)
			(layer "F.SilkS")
		)
		(fp_line
			(start -0.7874 0.4064)
			(end -0.7874 -0.4064)
			(stroke
				(width 0.1524)
				(type default)
			)
			(layer "F.SilkS")
		)
		(fp_line
			(start -0.7874 -0.4064)
			(end 0.7874 -0.4064)
			(stroke
				(width 0.1524)
				(type default)
			)
			(layer "F.SilkS")
		)
		(fp_line
			(start 0.67945 0.3048)
			(end 0.120396 0.3048)
			(stroke
				(width 0.1)
				(type default)
			)
			(layer "F.Fab")
		)
		(fp_line
			(start 0.67945 -0.3048)
			(end 0.67945 0.3048)
			(stroke
				(width 0.1)
				(type default)
			)
			(layer "F.Fab")
		)
		(fp_line
			(start 0.12065 -0.2794)
			(end 0.12065 -0.3048)
			(stroke
				(width 0.1)
				(type default)
			)
			(layer "F.Fab")
		)
		(fp_line
			(start 0.12065 -0.3048)
			(end 0.67945 -0.3048)
			(stroke
				(width 0.1)
				(type default)
			)
			(layer "F.Fab")
		)
		(fp_line
			(start 0.120396 0.3048)
			(end 0.120396 0.2794)
			(stroke
				(width 0.1)
				(type default)
			)
			(layer "F.Fab")
		)
		(fp_line
			(start 0.120396 0.2794)
			(end -0.12065 0.2794)
			(stroke
				(width 0.1)
				(type default)
			)
			(layer "F.Fab")
		)
		(fp_line
			(start -0.12065 0.3048)
			(end -0.67945 0.3048)
			(stroke
				(width 0.1)
				(type default)
			)
			(layer "F.Fab")
		)
		(fp_line
			(start -0.12065 0.2794)
			(end -0.12065 0.3048)
			(stroke
				(width 0.1)
				(type default)
			)
			(layer "F.Fab")
		)
		(fp_line
			(start -0.12065 -0.2794)
			(end 0.12065 -0.2794)
			(stroke
				(width 0.1)
				(type default)
			)
			(layer "F.Fab")
		)
		(fp_line
			(start -0.12065 -0.305054)
			(end -0.12065 -0.2794)
			(stroke
				(width 0.1)
				(type default)
			)
			(layer "F.Fab")
		)
		(fp_line
			(start -0.67945 0.3048)
			(end -0.67945 -0.305054)
			(stroke
				(width 0.1)
				(type default)
			)
			(layer "F.Fab")
		)
		(fp_line
			(start -0.67945 -0.305054)
			(end -0.12065 -0.305054)
			(stroke
				(width 0.1)
				(type default)
			)
			(layer "F.Fab")
		)
		(pad "1" smd circle
			(at -0.40005 0 180)
			(size 0 0)
			(layers "F.Cu" "F.Mask" "F.Paste")
			(net "HSC_VDD_R")
		)
		(pad "2" smd circle
			(at 0.40005 0 180)
			(size 0 0)
			(layers "F.Cu" "F.Mask" "F.Paste")
			(net "AGND_HSC")
		)
	)
	(footprint ""
		(layer "F.Cu")
		(at 42.637964 -173.938946 180)
		(property "Reference" "R5019"
			(at 0 0 180)
			(layer "F.SilkS")
			(hide yes)
			(effects
				(font
					(size 1.27 1.27)
				)
			)
		)
		(property "Value" ""
			(at 0 0 180)
			(layer "F.Fab")
			(effects
				(font
					(size 1.27 1.27)
				)
			)
		)
		(duplicate_pad_numbers_are_jumpers no)
		(fp_line
			(start 0.7874 0.4064)
			(end -0.7874 0.4064)
			(stroke
				(width 0.1524)
				(type default)
			)
			(layer "F.SilkS")
		)
		(fp_line
			(start 0.7874 -0.4064)
			(end 0.7874 0.4064)
			(stroke
				(width 0.1524)
				(type default)
			)
			(layer "F.SilkS")
		)
		(fp_line
			(start -0.7874 0.4064)
			(end -0.7874 -0.4064)
			(stroke
				(width 0.1524)
				(type default)
			)
			(layer "F.SilkS")
		)
		(fp_line
			(start -0.7874 -0.4064)
			(end 0.7874 -0.4064)
			(stroke
				(width 0.1524)
				(type default)
			)
			(layer "F.SilkS")
		)
		(fp_line
			(start 0.67945 0.3048)
			(end 0.120396 0.3048)
			(stroke
				(width 0.1)
				(type default)
			)
			(layer "F.Fab")
		)
		(fp_line
			(start 0.67945 -0.3048)
			(end 0.67945 0.3048)
			(stroke
				(width 0.1)
				(type default)
			)
			(layer "F.Fab")
		)
		(fp_line
			(start 0.12065 -0.2794)
			(end 0.12065 -0.3048)
			(stroke
				(width 0.1)
				(type default)
			)
			(layer "F.Fab")
		)
		(fp_line
			(start 0.12065 -0.3048)
			(end 0.67945 -0.3048)
			(stroke
				(width 0.1)
				(type default)
			)
			(layer "F.Fab")
		)
		(fp_line
			(start 0.120396 0.3048)
			(end 0.120396 0.2794)
			(stroke
				(width 0.1)
				(type default)
			)
			(layer "F.Fab")
		)
		(fp_line
			(start 0.120396 0.2794)
			(end -0.12065 0.2794)
			(stroke
				(width 0.1)
				(type default)
			)
			(layer "F.Fab")
		)
		(fp_line
			(start -0.12065 0.3048)
			(end -0.67945 0.3048)
			(stroke
				(width 0.1)
				(type default)
			)
			(layer "F.Fab")
		)
		(fp_line
			(start -0.12065 0.2794)
			(end -0.12065 0.3048)
			(stroke
				(width 0.1)
				(type default)
			)
			(layer "F.Fab")
		)
		(fp_line
			(start -0.12065 -0.2794)
			(end 0.12065 -0.2794)
			(stroke
				(width 0.1)
				(type default)
			)
			(layer "F.Fab")
		)
		(fp_line
			(start -0.12065 -0.305054)
			(end -0.12065 -0.2794)
			(stroke
				(width 0.1)
				(type default)
			)
			(layer "F.Fab")
		)
		(fp_line
			(start -0.67945 0.3048)
			(end -0.67945 -0.305054)
			(stroke
				(width 0.1)
				(type default)
			)
			(layer "F.Fab")
		)
		(fp_line
			(start -0.67945 -0.305054)
			(end -0.12065 -0.305054)
			(stroke
				(width 0.1)
				(type default)
			)
			(layer "F.Fab")
		)
		(pad "1" smd circle
			(at -0.40005 0 180)
			(size 0 0)
			(layers "F.Cu" "F.Mask" "F.Paste")
			(net "PVDD11_S3_P1")
		)
		(pad "2" smd circle
			(at 0.40005 0 180)
			(size 0 0)
			(layers "F.Cu" "F.Mask" "F.Paste")
			(net "I3C_SCM_2_R_SDA")
		)
	)
	(footprint ""
		(layer "F.Cu")
		(at 215.519 -119.888 90)
		(property "Reference" "U9001"
			(at -1.901444 4.060952 90)
			(unlocked yes)
			(layer "F.SilkS")
			(effects
				(font
					(size 0.7874 0.5842)
					(thickness 0.1524)
				)
				(justify left)
			)
		)
		(property "Value" ""
			(at 0 0 90)
			(layer "F.Fab")
			(effects
				(font
					(size 1.27 1.27)
				)
			)
		)
		(duplicate_pad_numbers_are_jumpers no)
		(fp_line
			(start 1.733296 -1.549908)
			(end 0.660908 -1.549908)
			(stroke
				(width 0.1524)
				(type default)
			)
			(layer "F.SilkS")
		)
		(fp_line
			(start 0.660908 -1.549908)
			(end 0 -0.889)
			(stroke
				(width 0.1524)
				(type default)
			)
			(layer "F.SilkS")
		)
		(fp_line
			(start -0.660908 -1.549908)
			(end -1.733296 -1.549908)
			(stroke
				(width 0.1524)
				(type default)
			)
			(layer "F.SilkS")
		)
		(fp_line
			(start -1.733296 -1.549908)
			(end -1.733296 1.549908)
			(stroke
				(width 0.1524)
				(type default)
			)
			(layer "F.SilkS")
		)
		(fp_line
			(start 0 -0.889)
			(end -0.660908 -1.549908)
			(stroke
				(width 0.1524)
				(type default)
			)
			(layer "F.SilkS")
		)
		(fp_line
			(start 1.733296 1.549908)
			(end 1.733296 -1.549908)
			(stroke
				(width 0.1524)
				(type default)
			)
			(layer "F.SilkS")
		)
		(fp_line
			(start -1.733296 1.549908)
			(end 1.733296 1.549908)
			(stroke
				(width 0.1524)
				(type default)
			)
			(layer "F.SilkS")
		)
		(fp_poly
			(pts
				(xy -2.4384 -1.20396) (xy -2.4384 -0.69596) (xy -1.9304 -0.94996)
			)
			(stroke
				(width 0)
				(type default)
			)
			(fill yes)
			(layer "F.SilkS")
		)
		(fp_line
			(start 0.849884 -1.549908)
			(end -0.849884 -1.549908)
			(stroke
				(width 0.1)
				(type default)
			)
			(layer "F.Fab")
		)
		(fp_line
			(start -0.849884 -1.549908)
			(end -0.849884 1.549908)
			(stroke
				(width 0.1)
				(type default)
			)
			(layer "F.Fab")
		)
		(fp_line
			(start 0.849884 1.549908)
			(end 0.849884 -1.549908)
			(stroke
				(width 0.1)
				(type default)
			)
			(layer "F.Fab")
		)
		(fp_line
			(start -0.849884 1.549908)
			(end 0.849884 1.549908)
			(stroke
				(width 0.1)
				(type default)
			)
			(layer "F.Fab")
		)
		(fp_poly
			(pts
				(xy -2.4384 -1.20396) (xy -2.4384 -0.69596) (xy -1.9304 -0.94996)
			)
			(stroke
				(width 0)
				(type default)
			)
			(fill yes)
			(layer "F.Fab")
		)
		(pad "1" smd rect
			(at -1.199896 -0.94996)
			(size 0.5588 0.8128)
			(layers "F.Cu" "F.Mask" "F.Paste")
			(net "RST_PERST_OCP_SFF_R_N")
		)
		(pad "2" smd rect
			(at -1.199896 0)
			(size 0.5588 0.8128)
			(layers "F.Cu" "F.Mask" "F.Paste")
			(net "HP_LVC3_OCP_V3_1_PWRGD")
		)
		(pad "3" smd rect
			(at -1.199896 0.94996)
			(size 0.5588 0.8128)
			(layers "F.Cu" "F.Mask" "F.Paste")
			(net "GND")
		)
		(pad "4" smd rect
			(at 1.199896 0.94996)
			(size 0.5588 0.8128)
			(layers "F.Cu" "F.Mask" "F.Paste")
			(net "RST_PERST_OCP_SFF_BUF_R_N")
		)
		(pad "5" smd rect
			(at 1.199896 -0.94996)
			(size 0.5588 0.8128)
			(layers "F.Cu" "F.Mask" "F.Paste")
			(net "P3V3_AUX")
		)
	)
	(footprint ""
		(layer "F.Cu")
		(at 211.76361 -57.548272 -90)
		(property "Reference" "R3763"
			(at 0 0 270)
			(layer "F.SilkS")
			(hide yes)
			(effects
				(font
					(size 1.27 1.27)
				)
			)
		)
		(property "Value" ""
			(at 0 0 270)
			(layer "F.Fab")
			(effects
				(font
					(size 1.27 1.27)
				)
			)
		)
		(duplicate_pad_numbers_are_jumpers no)
		(fp_line
			(start -0.7874 0.4064)
			(end -0.7874 -0.4064)
			(stroke
				(width 0.1524)
				(type default)
			)
			(layer "F.SilkS")
		)
		(fp_line
			(start 0.7874 0.4064)
			(end -0.7874 0.4064)
			(stroke
				(width 0.1524)
				(type default)
			)
			(layer "F.SilkS")
		)
		(fp_line
			(start -0.7874 -0.4064)
			(end 0.7874 -0.4064)
			(stroke
				(width 0.1524)
				(type default)
			)
			(layer "F.SilkS")
		)
		(fp_line
			(start 0.7874 -0.4064)
			(end 0.7874 0.4064)
			(stroke
				(width 0.1524)
				(type default)
			)
			(layer "F.SilkS")
		)
		(fp_line
			(start -0.67945 0.3048)
			(end -0.67945 -0.305054)
			(stroke
				(width 0.1)
				(type default)
			)
			(layer "F.Fab")
		)
		(fp_line
			(start -0.12065 0.3048)
			(end -0.67945 0.3048)
			(stroke
				(width 0.1)
				(type default)
			)
			(layer "F.Fab")
		)
		(fp_line
			(start 0.120396 0.3048)
			(end 0.120396 0.2794)
			(stroke
				(width 0.1)
				(type default)
			)
			(layer "F.Fab")
		)
		(fp_line
			(start 0.67945 0.3048)
			(end 0.120396 0.3048)
			(stroke
				(width 0.1)
				(type default)
			)
			(layer "F.Fab")
		)
		(fp_line
			(start -0.12065 0.2794)
			(end -0.12065 0.3048)
			(stroke
				(width 0.1)
				(type default)
			)
			(layer "F.Fab")
		)
		(fp_line
			(start 0.120396 0.2794)
			(end -0.12065 0.2794)
			(stroke
				(width 0.1)
				(type default)
			)
			(layer "F.Fab")
		)
		(fp_line
			(start -0.12065 -0.2794)
			(end 0.12065 -0.2794)
			(stroke
				(width 0.1)
				(type default)
			)
			(layer "F.Fab")
		)
		(fp_line
			(start 0.12065 -0.2794)
			(end 0.12065 -0.3048)
			(stroke
				(width 0.1)
				(type default)
			)
			(layer "F.Fab")
		)
		(fp_line
			(start 0.12065 -0.3048)
			(end 0.67945 -0.3048)
			(stroke
				(width 0.1)
				(type default)
			)
			(layer "F.Fab")
		)
		(fp_line
			(start 0.67945 -0.3048)
			(end 0.67945 0.3048)
			(stroke
				(width 0.1)
				(type default)
			)
			(layer "F.Fab")
		)
		(fp_line
			(start -0.67945 -0.305054)
			(end -0.12065 -0.305054)
			(stroke
				(width 0.1)
				(type default)
			)
			(layer "F.Fab")
		)
		(fp_line
			(start -0.12065 -0.305054)
			(end -0.12065 -0.2794)
			(stroke
				(width 0.1)
				(type default)
			)
			(layer "F.Fab")
		)
		(pad "1" smd circle
			(at -0.40005 0 270)
			(size 0 0)
			(layers "F.Cu" "F.Mask" "F.Paste")
			(net "GND")
		)
		(pad "2" smd circle
			(at 0.40005 0 270)
			(size 0 0)
			(layers "F.Cu" "F.Mask" "F.Paste")
			(net "INA230_2_A1")
		)
	)
	(footprint ""
		(layer "F.Cu")
		(at 123.127516 -57.137808 90)
		(property "Reference" "C1504"
			(at 0 0 90)
			(layer "F.SilkS")
			(hide yes)
			(effects
				(font
					(size 1.27 1.27)
				)
			)
		)
		(property "Value" ""
			(at 0 0 90)
			(layer "F.Fab")
			(effects
				(font
					(size 1.27 1.27)
				)
			)
		)
		(duplicate_pad_numbers_are_jumpers no)
		(fp_line
			(start 0.7874 -0.4064)
			(end 0.7874 0.4064)
			(stroke
				(width 0.1524)
				(type default)
			)
			(layer "F.SilkS")
		)
		(fp_line
			(start -0.7874 -0.4064)
			(end 0.7874 -0.4064)
			(stroke
				(width 0.1524)
				(type default)
			)
			(layer "F.SilkS")
		)
		(fp_line
			(start 0.7874 0.4064)
			(end -0.7874 0.4064)
			(stroke
				(width 0.1524)
				(type default)
			)
			(layer "F.SilkS")
		)
		(fp_line
			(start -0.7874 0.4064)
			(end -0.7874 -0.4064)
			(stroke
				(width 0.1524)
				(type default)
			)
			(layer "F.SilkS")
		)
		(fp_line
			(start -0.12065 -0.305054)
			(end -0.12065 -0.2794)
			(stroke
				(width 0.1)
				(type default)
			)
			(layer "F.Fab")
		)
		(fp_line
			(start -0.67945 -0.305054)
			(end -0.12065 -0.305054)
			(stroke
				(width 0.1)
				(type default)
			)
			(layer "F.Fab")
		)
		(fp_line
			(start 0.67945 -0.3048)
			(end 0.67945 0.3048)
			(stroke
				(width 0.1)
				(type default)
			)
			(layer "F.Fab")
		)
		(fp_line
			(start 0.12065 -0.3048)
			(end 0.67945 -0.3048)
			(stroke
				(width 0.1)
				(type default)
			)
			(layer "F.Fab")
		)
		(fp_line
			(start 0.12065 -0.2794)
			(end 0.12065 -0.3048)
			(stroke
				(width 0.1)
				(type default)
			)
			(layer "F.Fab")
		)
		(fp_line
			(start -0.12065 -0.2794)
			(end 0.12065 -0.2794)
			(stroke
				(width 0.1)
				(type default)
			)
			(layer "F.Fab")
		)
		(fp_line
			(start 0.120396 0.2794)
			(end -0.12065 0.2794)
			(stroke
				(width 0.1)
				(type default)
			)
			(layer "F.Fab")
		)
		(fp_line
			(start -0.12065 0.2794)
			(end -0.12065 0.3048)
			(stroke
				(width 0.1)
				(type default)
			)
			(layer "F.Fab")
		)
		(fp_line
			(start 0.67945 0.3048)
			(end 0.120396 0.3048)
			(stroke
				(width 0.1)
				(type default)
			)
			(layer "F.Fab")
		)
		(fp_line
			(start 0.120396 0.3048)
			(end 0.120396 0.2794)
			(stroke
				(width 0.1)
				(type default)
			)
			(layer "F.Fab")
		)
		(fp_line
			(start -0.12065 0.3048)
			(end -0.67945 0.3048)
			(stroke
				(width 0.1)
				(type default)
			)
			(layer "F.Fab")
		)
		(fp_line
			(start -0.67945 0.3048)
			(end -0.67945 -0.305054)
			(stroke
				(width 0.1)
				(type default)
			)
			(layer "F.Fab")
		)
		(pad "1" smd circle
			(at -0.40005 0 90)
			(size 0 0)
			(layers "F.Cu" "F.Mask" "F.Paste")
			(net "PVDD18_S5_P0")
		)
		(pad "2" smd circle
			(at 0.40005 0 90)
			(size 0 0)
			(layers "F.Cu" "F.Mask" "F.Paste")
			(net "GND")
		)
	)
	(footprint ""
		(layer "F.Cu")
		(at 75.705462 -38.532562)
		(property "Reference" "C2012"
			(at 0 0 0)
			(layer "F.SilkS")
			(hide yes)
			(effects
				(font
					(size 1.27 1.27)
				)
			)
		)
		(property "Value" ""
			(at 0 0 0)
			(layer "F.Fab")
			(effects
				(font
					(size 1.27 1.27)
				)
			)
		)
		(duplicate_pad_numbers_are_jumpers no)
		(fp_line
			(start -0.7874 -0.4064)
			(end 0.7874 -0.4064)
			(stroke
				(width 0.1524)
				(type default)
			)
			(layer "F.SilkS")
		)
		(fp_line
			(start -0.7874 0.4064)
			(end -0.7874 -0.4064)
			(stroke
				(width 0.1524)
				(type default)
			)
			(layer "F.SilkS")
		)
		(fp_line
			(start 0.7874 -0.4064)
			(end 0.7874 0.4064)
			(stroke
				(width 0.1524)
				(type default)
			)
			(layer "F.SilkS")
		)
		(fp_line
			(start 0.7874 0.4064)
			(end -0.7874 0.4064)
			(stroke
				(width 0.1524)
				(type default)
			)
			(layer "F.SilkS")
		)
		(fp_line
			(start -0.67945 -0.305054)
			(end -0.12065 -0.305054)
			(stroke
				(width 0.1)
				(type default)
			)
			(layer "F.Fab")
		)
		(fp_line
			(start -0.67945 0.3048)
			(end -0.67945 -0.305054)
			(stroke
				(width 0.1)
				(type default)
			)
			(layer "F.Fab")
		)
		(fp_line
			(start -0.12065 -0.305054)
			(end -0.12065 -0.2794)
			(stroke
				(width 0.1)
				(type default)
			)
			(layer "F.Fab")
		)
		(fp_line
			(start -0.12065 -0.2794)
			(end 0.12065 -0.2794)
			(stroke
				(width 0.1)
				(type default)
			)
			(layer "F.Fab")
		)
		(fp_line
			(start -0.12065 0.2794)
			(end -0.12065 0.3048)
			(stroke
				(width 0.1)
				(type default)
			)
			(layer "F.Fab")
		)
		(fp_line
			(start -0.12065 0.3048)
			(end -0.67945 0.3048)
			(stroke
				(width 0.1)
				(type default)
			)
			(layer "F.Fab")
		)
		(fp_line
			(start 0.120396 0.2794)
			(end -0.12065 0.2794)
			(stroke
				(width 0.1)
				(type default)
			)
			(layer "F.Fab")
		)
		(fp_line
			(start 0.120396 0.3048)
			(end 0.120396 0.2794)
			(stroke
				(width 0.1)
				(type default)
			)
			(layer "F.Fab")
		)
		(fp_line
			(start 0.12065 -0.3048)
			(end 0.67945 -0.3048)
			(stroke
				(width 0.1)
				(type default)
			)
			(layer "F.Fab")
		)
		(fp_line
			(start 0.12065 -0.2794)
			(end 0.12065 -0.3048)
			(stroke
				(width 0.1)
				(type default)
			)
			(layer "F.Fab")
		)
		(fp_line
			(start 0.67945 -0.3048)
			(end 0.67945 0.3048)
			(stroke
				(width 0.1)
				(type default)
			)
			(layer "F.Fab")
		)
		(fp_line
			(start 0.67945 0.3048)
			(end 0.120396 0.3048)
			(stroke
				(width 0.1)
				(type default)
			)
			(layer "F.Fab")
		)
		(pad "1" smd circle
			(at -0.40005 0)
			(size 0 0)
			(layers "F.Cu" "F.Mask" "F.Paste")
			(net "P3V3_AUX")
		)
		(pad "2" smd circle
			(at 0.40005 0)
			(size 0 0)
			(layers "F.Cu" "F.Mask" "F.Paste")
			(net "GND")
		)
	)
	(footprint ""
		(layer "F.Cu")
		(at 205.74 -135.763)
		(property "Reference" "R554"
			(at 0 0 0)
			(layer "F.SilkS")
			(hide yes)
			(effects
				(font
					(size 1.27 1.27)
				)
			)
		)
		(property "Value" ""
			(at 0 0 0)
			(layer "F.Fab")
			(effects
				(font
					(size 1.27 1.27)
				)
			)
		)
		(duplicate_pad_numbers_are_jumpers no)
		(fp_line
			(start -0.7874 -0.4064)
			(end 0.7874 -0.4064)
			(stroke
				(width 0.1524)
				(type default)
			)
			(layer "F.SilkS")
		)
		(fp_line
			(start -0.7874 0.4064)
			(end -0.7874 -0.4064)
			(stroke
				(width 0.1524)
				(type default)
			)
			(layer "F.SilkS")
		)
		(fp_line
			(start 0.7874 -0.4064)
			(end 0.7874 0.4064)
			(stroke
				(width 0.1524)
				(type default)
			)
			(layer "F.SilkS")
		)
		(fp_line
			(start 0.7874 0.4064)
			(end -0.7874 0.4064)
			(stroke
				(width 0.1524)
				(type default)
			)
			(layer "F.SilkS")
		)
		(fp_line
			(start -0.67945 -0.305054)
			(end -0.12065 -0.305054)
			(stroke
				(width 0.1)
				(type default)
			)
			(layer "F.Fab")
		)
		(fp_line
			(start -0.67945 0.3048)
			(end -0.67945 -0.305054)
			(stroke
				(width 0.1)
				(type default)
			)
			(layer "F.Fab")
		)
		(fp_line
			(start -0.12065 -0.305054)
			(end -0.12065 -0.2794)
			(stroke
				(width 0.1)
				(type default)
			)
			(layer "F.Fab")
		)
		(fp_line
			(start -0.12065 -0.2794)
			(end 0.12065 -0.2794)
			(stroke
				(width 0.1)
				(type default)
			)
			(layer "F.Fab")
		)
		(fp_line
			(start -0.12065 0.2794)
			(end -0.12065 0.3048)
			(stroke
				(width 0.1)
				(type default)
			)
			(layer "F.Fab")
		)
		(fp_line
			(start -0.12065 0.3048)
			(end -0.67945 0.3048)
			(stroke
				(width 0.1)
				(type default)
			)
			(layer "F.Fab")
		)
		(fp_line
			(start 0.120396 0.2794)
			(end -0.12065 0.2794)
			(stroke
				(width 0.1)
				(type default)
			)
			(layer "F.Fab")
		)
		(fp_line
			(start 0.120396 0.3048)
			(end 0.120396 0.2794)
			(stroke
				(width 0.1)
				(type default)
			)
			(layer "F.Fab")
		)
		(fp_line
			(start 0.12065 -0.3048)
			(end 0.67945 -0.3048)
			(stroke
				(width 0.1)
				(type default)
			)
			(layer "F.Fab")
		)
		(fp_line
			(start 0.12065 -0.2794)
			(end 0.12065 -0.3048)
			(stroke
				(width 0.1)
				(type default)
			)
			(layer "F.Fab")
		)
		(fp_line
			(start 0.67945 -0.3048)
			(end 0.67945 0.3048)
			(stroke
				(width 0.1)
				(type default)
			)
			(layer "F.Fab")
		)
		(fp_line
			(start 0.67945 0.3048)
			(end 0.120396 0.3048)
			(stroke
				(width 0.1)
				(type default)
			)
			(layer "F.Fab")
		)
		(pad "1" smd circle
			(at -0.40005 0)
			(size 0 0)
			(layers "F.Cu" "F.Mask" "F.Paste")
			(net "P12V_AUX")
		)
		(pad "2" smd circle
			(at 0.40005 0)
			(size 0 0)
			(layers "F.Cu" "F.Mask" "F.Paste")
			(net "SW_P3V3_EN_N")
		)
	)
	(footprint ""
		(layer "F.Cu")
		(at 24.765 -361.061)
		(property "Reference" "PR8012"
			(at 0 0 0)
			(layer "F.SilkS")
			(hide yes)
			(effects
				(font
					(size 1.27 1.27)
				)
			)
		)
		(property "Value" ""
			(at 0 0 0)
			(layer "F.Fab")
			(effects
				(font
					(size 1.27 1.27)
				)
			)
		)
		(duplicate_pad_numbers_are_jumpers no)
		(fp_line
			(start -0.7874 -0.4064)
			(end 0.7874 -0.4064)
			(stroke
				(width 0.1524)
				(type default)
			)
			(layer "F.SilkS")
		)
		(fp_line
			(start -0.7874 0.4064)
			(end -0.7874 -0.4064)
			(stroke
				(width 0.1524)
				(type default)
			)
			(layer "F.SilkS")
		)
		(fp_line
			(start 0.7874 -0.4064)
			(end 0.7874 0.4064)
			(stroke
				(width 0.1524)
				(type default)
			)
			(layer "F.SilkS")
		)
		(fp_line
			(start 0.7874 0.4064)
			(end -0.7874 0.4064)
			(stroke
				(width 0.1524)
				(type default)
			)
			(layer "F.SilkS")
		)
		(fp_line
			(start -0.67945 -0.305054)
			(end -0.12065 -0.305054)
			(stroke
				(width 0.1)
				(type default)
			)
			(layer "F.Fab")
		)
		(fp_line
			(start -0.67945 0.3048)
			(end -0.67945 -0.305054)
			(stroke
				(width 0.1)
				(type default)
			)
			(layer "F.Fab")
		)
		(fp_line
			(start -0.12065 -0.305054)
			(end -0.12065 -0.2794)
			(stroke
				(width 0.1)
				(type default)
			)
			(layer "F.Fab")
		)
		(fp_line
			(start -0.12065 -0.2794)
			(end 0.12065 -0.2794)
			(stroke
				(width 0.1)
				(type default)
			)
			(layer "F.Fab")
		)
		(fp_line
			(start -0.12065 0.2794)
			(end -0.12065 0.3048)
			(stroke
				(width 0.1)
				(type default)
			)
			(layer "F.Fab")
		)
		(fp_line
			(start -0.12065 0.3048)
			(end -0.67945 0.3048)
			(stroke
				(width 0.1)
				(type default)
			)
			(layer "F.Fab")
		)
		(fp_line
			(start 0.120396 0.2794)
			(end -0.12065 0.2794)
			(stroke
				(width 0.1)
				(type default)
			)
			(layer "F.Fab")
		)
		(fp_line
			(start 0.120396 0.3048)
			(end 0.120396 0.2794)
			(stroke
				(width 0.1)
				(type default)
			)
			(layer "F.Fab")
		)
		(fp_line
			(start 0.12065 -0.3048)
			(end 0.67945 -0.3048)
			(stroke
				(width 0.1)
				(type default)
			)
			(layer "F.Fab")
		)
		(fp_line
			(start 0.12065 -0.2794)
			(end 0.12065 -0.3048)
			(stroke
				(width 0.1)
				(type default)
			)
			(layer "F.Fab")
		)
		(fp_line
			(start 0.67945 -0.3048)
			(end 0.67945 0.3048)
			(stroke
				(width 0.1)
				(type default)
			)
			(layer "F.Fab")
		)
		(fp_line
			(start 0.67945 0.3048)
			(end 0.120396 0.3048)
			(stroke
				(width 0.1)
				(type default)
			)
			(layer "F.Fab")
		)
		(pad "1" smd circle
			(at -0.40005 0)
			(size 0 0)
			(layers "F.Cu" "F.Mask" "F.Paste")
			(net "SVID_PVDDCR_CPU1_P1_SVD_R")
		)
		(pad "2" smd circle
			(at 0.40005 0)
			(size 0 0)
			(layers "F.Cu" "F.Mask" "F.Paste")
			(net "SVID_PVDDCR_CPU1_P1_SVD_R1")
		)
	)
	(footprint ""
		(layer "F.Cu")
		(at 365.318548 -14.450568 -90)
		(property "Reference" "R820"
			(at 0 0 270)
			(layer "F.SilkS")
			(hide yes)
			(effects
				(font
					(size 1.27 1.27)
				)
			)
		)
		(property "Value" ""
			(at 0 0 270)
			(layer "F.Fab")
			(effects
				(font
					(size 1.27 1.27)
				)
			)
		)
		(duplicate_pad_numbers_are_jumpers no)
		(fp_line
			(start -0.7874 0.4064)
			(end -0.7874 -0.4064)
			(stroke
				(width 0.1524)
				(type default)
			)
			(layer "F.SilkS")
		)
		(fp_line
			(start 0.7874 0.4064)
			(end -0.7874 0.4064)
			(stroke
				(width 0.1524)
				(type default)
			)
			(layer "F.SilkS")
		)
		(fp_line
			(start -0.7874 -0.4064)
			(end 0.7874 -0.4064)
			(stroke
				(width 0.1524)
				(type default)
			)
			(layer "F.SilkS")
		)
		(fp_line
			(start 0.7874 -0.4064)
			(end 0.7874 0.4064)
			(stroke
				(width 0.1524)
				(type default)
			)
			(layer "F.SilkS")
		)
		(fp_line
			(start -0.67945 0.3048)
			(end -0.67945 -0.305054)
			(stroke
				(width 0.1)
				(type default)
			)
			(layer "F.Fab")
		)
		(fp_line
			(start -0.12065 0.3048)
			(end -0.67945 0.3048)
			(stroke
				(width 0.1)
				(type default)
			)
			(layer "F.Fab")
		)
		(fp_line
			(start 0.120396 0.3048)
			(end 0.120396 0.2794)
			(stroke
				(width 0.1)
				(type default)
			)
			(layer "F.Fab")
		)
		(fp_line
			(start 0.67945 0.3048)
			(end 0.120396 0.3048)
			(stroke
				(width 0.1)
				(type default)
			)
			(layer "F.Fab")
		)
		(fp_line
			(start -0.12065 0.2794)
			(end -0.12065 0.3048)
			(stroke
				(width 0.1)
				(type default)
			)
			(layer "F.Fab")
		)
		(fp_line
			(start 0.120396 0.2794)
			(end -0.12065 0.2794)
			(stroke
				(width 0.1)
				(type default)
			)
			(layer "F.Fab")
		)
		(fp_line
			(start -0.12065 -0.2794)
			(end 0.12065 -0.2794)
			(stroke
				(width 0.1)
				(type default)
			)
			(layer "F.Fab")
		)
		(fp_line
			(start 0.12065 -0.2794)
			(end 0.12065 -0.3048)
			(stroke
				(width 0.1)
				(type default)
			)
			(layer "F.Fab")
		)
		(fp_line
			(start 0.12065 -0.3048)
			(end 0.67945 -0.3048)
			(stroke
				(width 0.1)
				(type default)
			)
			(layer "F.Fab")
		)
		(fp_line
			(start 0.67945 -0.3048)
			(end 0.67945 0.3048)
			(stroke
				(width 0.1)
				(type default)
			)
			(layer "F.Fab")
		)
		(fp_line
			(start -0.67945 -0.305054)
			(end -0.12065 -0.305054)
			(stroke
				(width 0.1)
				(type default)
			)
			(layer "F.Fab")
		)
		(fp_line
			(start -0.12065 -0.305054)
			(end -0.12065 -0.2794)
			(stroke
				(width 0.1)
				(type default)
			)
			(layer "F.Fab")
		)
		(pad "1" smd circle
			(at -0.40005 0 270)
			(size 0 0)
			(layers "F.Cu" "F.Mask" "F.Paste")
			(net "UART_VCC_J13")
		)
		(pad "2" smd circle
			(at 0.40005 0 270)
			(size 0 0)
			(layers "F.Cu" "F.Mask" "F.Paste")
			(net "P5V_AUX")
		)
	)
	(footprint ""
		(layer "F.Cu")
		(at 50.254662 -401.98294 90)
		(property "Reference" "C7041"
			(at 0 0 90)
			(layer "F.SilkS")
			(hide yes)
			(effects
				(font
					(size 1.27 1.27)
				)
			)
		)
		(property "Value" ""
			(at 0 0 90)
			(layer "F.Fab")
			(effects
				(font
					(size 1.27 1.27)
				)
			)
		)
		(duplicate_pad_numbers_are_jumpers no)
		(fp_line
			(start 1.524 -0.762)
			(end 1.524 0.762)
			(stroke
				(width 0.1524)
				(type default)
			)
			(layer "F.SilkS")
		)
		(fp_line
			(start -1.524 -0.762)
			(end 1.524 -0.762)
			(stroke
				(width 0.1524)
				(type default)
			)
			(layer "F.SilkS")
		)
		(fp_line
			(start 1.524 0.762)
			(end -1.524 0.762)
			(stroke
				(width 0.1524)
				(type default)
			)
			(layer "F.SilkS")
		)
		(fp_line
			(start -1.524 0.762)
			(end -1.524 -0.762)
			(stroke
				(width 0.1524)
				(type default)
			)
			(layer "F.SilkS")
		)
		(fp_line
			(start 1.1049 -0.724916)
			(end -1.1049 -0.724916)
			(stroke
				(width 0.1)
				(type default)
			)
			(layer "F.Fab")
		)
		(fp_line
			(start -1.1049 -0.724916)
			(end -1.1049 0.724916)
			(stroke
				(width 0.1)
				(type default)
			)
			(layer "F.Fab")
		)
		(fp_line
			(start 1.1049 0.724916)
			(end 1.1049 -0.724916)
			(stroke
				(width 0.1)
				(type default)
			)
			(layer "F.Fab")
		)
		(fp_line
			(start -1.1049 0.724916)
			(end 1.1049 0.724916)
			(stroke
				(width 0.1)
				(type default)
			)
			(layer "F.Fab")
		)
		(pad "1" smd rect
			(at -0.889 0 270)
			(size 1.016 1.27)
			(layers "F.Cu" "F.Mask" "F.Paste")
			(net "P0V9_CPU1_RT_2D")
		)
		(pad "2" smd rect
			(at 0.889 0 270)
			(size 1.016 1.27)
			(layers "F.Cu" "F.Mask" "F.Paste")
			(net "GND")
		)
	)
	(footprint ""
		(layer "F.Cu")
		(at 321.183 -194.31 180)
		(property "Reference" "R425"
			(at 0 0 180)
			(layer "F.SilkS")
			(hide yes)
			(effects
				(font
					(size 1.27 1.27)
				)
			)
		)
		(property "Value" ""
			(at 0 0 180)
			(layer "F.Fab")
			(effects
				(font
					(size 1.27 1.27)
				)
			)
		)
		(duplicate_pad_numbers_are_jumpers no)
		(fp_line
			(start 0.7874 0.4064)
			(end -0.7874 0.4064)
			(stroke
				(width 0.1524)
				(type default)
			)
			(layer "F.SilkS")
		)
		(fp_line
			(start 0.7874 -0.4064)
			(end 0.7874 0.4064)
			(stroke
				(width 0.1524)
				(type default)
			)
			(layer "F.SilkS")
		)
		(fp_line
			(start -0.7874 0.4064)
			(end -0.7874 -0.4064)
			(stroke
				(width 0.1524)
				(type default)
			)
			(layer "F.SilkS")
		)
		(fp_line
			(start -0.7874 -0.4064)
			(end 0.7874 -0.4064)
			(stroke
				(width 0.1524)
				(type default)
			)
			(layer "F.SilkS")
		)
		(fp_line
			(start 0.67945 0.3048)
			(end 0.120396 0.3048)
			(stroke
				(width 0.1)
				(type default)
			)
			(layer "F.Fab")
		)
		(fp_line
			(start 0.67945 -0.3048)
			(end 0.67945 0.3048)
			(stroke
				(width 0.1)
				(type default)
			)
			(layer "F.Fab")
		)
		(fp_line
			(start 0.12065 -0.2794)
			(end 0.12065 -0.3048)
			(stroke
				(width 0.1)
				(type default)
			)
			(layer "F.Fab")
		)
		(fp_line
			(start 0.12065 -0.3048)
			(end 0.67945 -0.3048)
			(stroke
				(width 0.1)
				(type default)
			)
			(layer "F.Fab")
		)
		(fp_line
			(start 0.120396 0.3048)
			(end 0.120396 0.2794)
			(stroke
				(width 0.1)
				(type default)
			)
			(layer "F.Fab")
		)
		(fp_line
			(start 0.120396 0.2794)
			(end -0.12065 0.2794)
			(stroke
				(width 0.1)
				(type default)
			)
			(layer "F.Fab")
		)
		(fp_line
			(start -0.12065 0.3048)
			(end -0.67945 0.3048)
			(stroke
				(width 0.1)
				(type default)
			)
			(layer "F.Fab")
		)
		(fp_line
			(start -0.12065 0.2794)
			(end -0.12065 0.3048)
			(stroke
				(width 0.1)
				(type default)
			)
			(layer "F.Fab")
		)
		(fp_line
			(start -0.12065 -0.2794)
			(end 0.12065 -0.2794)
			(stroke
				(width 0.1)
				(type default)
			)
			(layer "F.Fab")
		)
		(fp_line
			(start -0.12065 -0.305054)
			(end -0.12065 -0.2794)
			(stroke
				(width 0.1)
				(type default)
			)
			(layer "F.Fab")
		)
		(fp_line
			(start -0.67945 0.3048)
			(end -0.67945 -0.305054)
			(stroke
				(width 0.1)
				(type default)
			)
			(layer "F.Fab")
		)
		(fp_line
			(start -0.67945 -0.305054)
			(end -0.12065 -0.305054)
			(stroke
				(width 0.1)
				(type default)
			)
			(layer "F.Fab")
		)
		(pad "1" smd circle
			(at -0.40005 0 180)
			(size 0 0)
			(layers "F.Cu" "F.Mask" "F.Paste")
			(net "PVDD11_S3_P0")
		)
		(pad "2" smd circle
			(at 0.40005 0 180)
			(size 0 0)
			(layers "F.Cu" "F.Mask" "F.Paste")
			(net "I3C_0_SPD_DDRAF_CPU0_R_SCL")
		)
	)
	(footprint ""
		(layer "F.Cu")
		(at 297.32605 -150.538942 180)
		(property "Reference" "R1331"
			(at 0 0 180)
			(layer "F.SilkS")
			(hide yes)
			(effects
				(font
					(size 1.27 1.27)
				)
			)
		)
		(property "Value" ""
			(at 0 0 180)
			(layer "F.Fab")
			(effects
				(font
					(size 1.27 1.27)
				)
			)
		)
		(duplicate_pad_numbers_are_jumpers no)
		(fp_line
			(start 0.7874 0.4064)
			(end -0.7874 0.4064)
			(stroke
				(width 0.1524)
				(type default)
			)
			(layer "F.SilkS")
		)
		(fp_line
			(start 0.7874 -0.4064)
			(end 0.7874 0.4064)
			(stroke
				(width 0.1524)
				(type default)
			)
			(layer "F.SilkS")
		)
		(fp_line
			(start -0.7874 0.4064)
			(end -0.7874 -0.4064)
			(stroke
				(width 0.1524)
				(type default)
			)
			(layer "F.SilkS")
		)
		(fp_line
			(start -0.7874 -0.4064)
			(end 0.7874 -0.4064)
			(stroke
				(width 0.1524)
				(type default)
			)
			(layer "F.SilkS")
		)
		(fp_line
			(start 0.67945 0.3048)
			(end 0.120396 0.3048)
			(stroke
				(width 0.1)
				(type default)
			)
			(layer "F.Fab")
		)
		(fp_line
			(start 0.67945 -0.3048)
			(end 0.67945 0.3048)
			(stroke
				(width 0.1)
				(type default)
			)
			(layer "F.Fab")
		)
		(fp_line
			(start 0.12065 -0.2794)
			(end 0.12065 -0.3048)
			(stroke
				(width 0.1)
				(type default)
			)
			(layer "F.Fab")
		)
		(fp_line
			(start 0.12065 -0.3048)
			(end 0.67945 -0.3048)
			(stroke
				(width 0.1)
				(type default)
			)
			(layer "F.Fab")
		)
		(fp_line
			(start 0.120396 0.3048)
			(end 0.120396 0.2794)
			(stroke
				(width 0.1)
				(type default)
			)
			(layer "F.Fab")
		)
		(fp_line
			(start 0.120396 0.2794)
			(end -0.12065 0.2794)
			(stroke
				(width 0.1)
				(type default)
			)
			(layer "F.Fab")
		)
		(fp_line
			(start -0.12065 0.3048)
			(end -0.67945 0.3048)
			(stroke
				(width 0.1)
				(type default)
			)
			(layer "F.Fab")
		)
		(fp_line
			(start -0.12065 0.2794)
			(end -0.12065 0.3048)
			(stroke
				(width 0.1)
				(type default)
			)
			(layer "F.Fab")
		)
		(fp_line
			(start -0.12065 -0.2794)
			(end 0.12065 -0.2794)
			(stroke
				(width 0.1)
				(type default)
			)
			(layer "F.Fab")
		)
		(fp_line
			(start -0.12065 -0.305054)
			(end -0.12065 -0.2794)
			(stroke
				(width 0.1)
				(type default)
			)
			(layer "F.Fab")
		)
		(fp_line
			(start -0.67945 0.3048)
			(end -0.67945 -0.305054)
			(stroke
				(width 0.1)
				(type default)
			)
			(layer "F.Fab")
		)
		(fp_line
			(start -0.67945 -0.305054)
			(end -0.12065 -0.305054)
			(stroke
				(width 0.1)
				(type default)
			)
			(layer "F.Fab")
		)
		(pad "1" smd rect
			(at -0.40005 0)
			(size 0.4572 0.508)
			(layers "F.Cu" "F.Mask" "F.Paste")
			(net "I3C_SPD_DDRAF_CPU0_BYPASS_SDA")
		)
		(pad "2" smd rect
			(at 0.40005 0)
			(size 0.4572 0.508)
			(layers "F.Cu" "F.Mask" "F.Paste")
			(net "I3C_SPD_DDRAF_CPU0_SDA")
		)
	)
	(footprint ""
		(layer "F.Cu")
		(at 12.786106 -105.50398 90)
		(property "Reference" "R2787"
			(at 0 0 90)
			(layer "F.SilkS")
			(hide yes)
			(effects
				(font
					(size 1.27 1.27)
				)
			)
		)
		(property "Value" ""
			(at 0 0 90)
			(layer "F.Fab")
			(effects
				(font
					(size 1.27 1.27)
				)
			)
		)
		(duplicate_pad_numbers_are_jumpers no)
		(fp_line
			(start 0.7874 -0.4064)
			(end 0.7874 0.4064)
			(stroke
				(width 0.1524)
				(type default)
			)
			(layer "F.SilkS")
		)
		(fp_line
			(start -0.7874 -0.4064)
			(end 0.7874 -0.4064)
			(stroke
				(width 0.1524)
				(type default)
			)
			(layer "F.SilkS")
		)
		(fp_line
			(start 0.7874 0.4064)
			(end -0.7874 0.4064)
			(stroke
				(width 0.1524)
				(type default)
			)
			(layer "F.SilkS")
		)
		(fp_line
			(start -0.7874 0.4064)
			(end -0.7874 -0.4064)
			(stroke
				(width 0.1524)
				(type default)
			)
			(layer "F.SilkS")
		)
		(fp_line
			(start -0.12065 -0.305054)
			(end -0.12065 -0.2794)
			(stroke
				(width 0.1)
				(type default)
			)
			(layer "F.Fab")
		)
		(fp_line
			(start -0.67945 -0.305054)
			(end -0.12065 -0.305054)
			(stroke
				(width 0.1)
				(type default)
			)
			(layer "F.Fab")
		)
		(fp_line
			(start 0.67945 -0.3048)
			(end 0.67945 0.3048)
			(stroke
				(width 0.1)
				(type default)
			)
			(layer "F.Fab")
		)
		(fp_line
			(start 0.12065 -0.3048)
			(end 0.67945 -0.3048)
			(stroke
				(width 0.1)
				(type default)
			)
			(layer "F.Fab")
		)
		(fp_line
			(start 0.12065 -0.2794)
			(end 0.12065 -0.3048)
			(stroke
				(width 0.1)
				(type default)
			)
			(layer "F.Fab")
		)
		(fp_line
			(start -0.12065 -0.2794)
			(end 0.12065 -0.2794)
			(stroke
				(width 0.1)
				(type default)
			)
			(layer "F.Fab")
		)
		(fp_line
			(start 0.120396 0.2794)
			(end -0.12065 0.2794)
			(stroke
				(width 0.1)
				(type default)
			)
			(layer "F.Fab")
		)
		(fp_line
			(start -0.12065 0.2794)
			(end -0.12065 0.3048)
			(stroke
				(width 0.1)
				(type default)
			)
			(layer "F.Fab")
		)
		(fp_line
			(start 0.67945 0.3048)
			(end 0.120396 0.3048)
			(stroke
				(width 0.1)
				(type default)
			)
			(layer "F.Fab")
		)
		(fp_line
			(start 0.120396 0.3048)
			(end 0.120396 0.2794)
			(stroke
				(width 0.1)
				(type default)
			)
			(layer "F.Fab")
		)
		(fp_line
			(start -0.12065 0.3048)
			(end -0.67945 0.3048)
			(stroke
				(width 0.1)
				(type default)
			)
			(layer "F.Fab")
		)
		(fp_line
			(start -0.67945 0.3048)
			(end -0.67945 -0.305054)
			(stroke
				(width 0.1)
				(type default)
			)
			(layer "F.Fab")
		)
		(pad "1" smd rect
			(at -0.40005 0 270)
			(size 0.4572 0.508)
			(layers "F.Cu" "F.Mask" "F.Paste")
			(net "USB2_HUB_SWB_DN")
		)
		(pad "2" smd rect
			(at 0.40005 0 270)
			(size 0.4572 0.508)
			(layers "F.Cu" "F.Mask" "F.Paste")
			(net "USB2_HUB_BUF_SWB_R_DN")
		)
	)
	(footprint ""
		(layer "F.Cu")
		(at 343.096088 -171.746672 -90)
		(property "Reference" "PC497"
			(at 0 0 270)
			(layer "F.SilkS")
			(hide yes)
			(effects
				(font
					(size 1.27 1.27)
				)
			)
		)
		(property "Value" ""
			(at 0 0 270)
			(layer "F.Fab")
			(effects
				(font
					(size 1.27 1.27)
				)
			)
		)
		(duplicate_pad_numbers_are_jumpers no)
		(fp_line
			(start -0.7874 0.4064)
			(end -0.7874 -0.4064)
			(stroke
				(width 0.1524)
				(type default)
			)
			(layer "F.SilkS")
		)
		(fp_line
			(start 0.7874 0.4064)
			(end -0.7874 0.4064)
			(stroke
				(width 0.1524)
				(type default)
			)
			(layer "F.SilkS")
		)
		(fp_line
			(start -0.7874 -0.4064)
			(end 0.7874 -0.4064)
			(stroke
				(width 0.1524)
				(type default)
			)
			(layer "F.SilkS")
		)
		(fp_line
			(start 0.7874 -0.4064)
			(end 0.7874 0.4064)
			(stroke
				(width 0.1524)
				(type default)
			)
			(layer "F.SilkS")
		)
		(fp_line
			(start -0.67945 0.3048)
			(end -0.67945 -0.305054)
			(stroke
				(width 0.1)
				(type default)
			)
			(layer "F.Fab")
		)
		(fp_line
			(start -0.12065 0.3048)
			(end -0.67945 0.3048)
			(stroke
				(width 0.1)
				(type default)
			)
			(layer "F.Fab")
		)
		(fp_line
			(start 0.120396 0.3048)
			(end 0.120396 0.2794)
			(stroke
				(width 0.1)
				(type default)
			)
			(layer "F.Fab")
		)
		(fp_line
			(start 0.67945 0.3048)
			(end 0.120396 0.3048)
			(stroke
				(width 0.1)
				(type default)
			)
			(layer "F.Fab")
		)
		(fp_line
			(start -0.12065 0.2794)
			(end -0.12065 0.3048)
			(stroke
				(width 0.1)
				(type default)
			)
			(layer "F.Fab")
		)
		(fp_line
			(start 0.120396 0.2794)
			(end -0.12065 0.2794)
			(stroke
				(width 0.1)
				(type default)
			)
			(layer "F.Fab")
		)
		(fp_line
			(start -0.12065 -0.2794)
			(end 0.12065 -0.2794)
			(stroke
				(width 0.1)
				(type default)
			)
			(layer "F.Fab")
		)
		(fp_line
			(start 0.12065 -0.2794)
			(end 0.12065 -0.3048)
			(stroke
				(width 0.1)
				(type default)
			)
			(layer "F.Fab")
		)
		(fp_line
			(start 0.12065 -0.3048)
			(end 0.67945 -0.3048)
			(stroke
				(width 0.1)
				(type default)
			)
			(layer "F.Fab")
		)
		(fp_line
			(start 0.67945 -0.3048)
			(end 0.67945 0.3048)
			(stroke
				(width 0.1)
				(type default)
			)
			(layer "F.Fab")
		)
		(fp_line
			(start -0.67945 -0.305054)
			(end -0.12065 -0.305054)
			(stroke
				(width 0.1)
				(type default)
			)
			(layer "F.Fab")
		)
		(fp_line
			(start -0.12065 -0.305054)
			(end -0.12065 -0.2794)
			(stroke
				(width 0.1)
				(type default)
			)
			(layer "F.Fab")
		)
		(pad "1" smd circle
			(at -0.40005 0 270)
			(size 0 0)
			(layers "F.Cu" "F.Mask" "F.Paste")
			(net "PVDDCR_CPU0_P0")
		)
		(pad "2" smd circle
			(at 0.40005 0 270)
			(size 0 0)
			(layers "F.Cu" "F.Mask" "F.Paste")
			(net "GND")
		)
	)
	(footprint ""
		(layer "F.Cu")
		(at 201.137266 -121.795794)
		(property "Reference" "R6777"
			(at 0 0 0)
			(layer "F.SilkS")
			(hide yes)
			(effects
				(font
					(size 1.27 1.27)
				)
			)
		)
		(property "Value" ""
			(at 0 0 0)
			(layer "F.Fab")
			(effects
				(font
					(size 1.27 1.27)
				)
			)
		)
		(duplicate_pad_numbers_are_jumpers no)
		(fp_line
			(start -0.7874 -0.4064)
			(end 0.7874 -0.4064)
			(stroke
				(width 0.1524)
				(type default)
			)
			(layer "F.SilkS")
		)
		(fp_line
			(start -0.7874 0.4064)
			(end -0.7874 -0.4064)
			(stroke
				(width 0.1524)
				(type default)
			)
			(layer "F.SilkS")
		)
		(fp_line
			(start 0.7874 -0.4064)
			(end 0.7874 0.4064)
			(stroke
				(width 0.1524)
				(type default)
			)
			(layer "F.SilkS")
		)
		(fp_line
			(start 0.7874 0.4064)
			(end -0.7874 0.4064)
			(stroke
				(width 0.1524)
				(type default)
			)
			(layer "F.SilkS")
		)
		(fp_line
			(start -0.67945 -0.305054)
			(end -0.12065 -0.305054)
			(stroke
				(width 0.1)
				(type default)
			)
			(layer "F.Fab")
		)
		(fp_line
			(start -0.67945 0.3048)
			(end -0.67945 -0.305054)
			(stroke
				(width 0.1)
				(type default)
			)
			(layer "F.Fab")
		)
		(fp_line
			(start -0.12065 -0.305054)
			(end -0.12065 -0.2794)
			(stroke
				(width 0.1)
				(type default)
			)
			(layer "F.Fab")
		)
		(fp_line
			(start -0.12065 -0.2794)
			(end 0.12065 -0.2794)
			(stroke
				(width 0.1)
				(type default)
			)
			(layer "F.Fab")
		)
		(fp_line
			(start -0.12065 0.2794)
			(end -0.12065 0.3048)
			(stroke
				(width 0.1)
				(type default)
			)
			(layer "F.Fab")
		)
		(fp_line
			(start -0.12065 0.3048)
			(end -0.67945 0.3048)
			(stroke
				(width 0.1)
				(type default)
			)
			(layer "F.Fab")
		)
		(fp_line
			(start 0.120396 0.2794)
			(end -0.12065 0.2794)
			(stroke
				(width 0.1)
				(type default)
			)
			(layer "F.Fab")
		)
		(fp_line
			(start 0.120396 0.3048)
			(end 0.120396 0.2794)
			(stroke
				(width 0.1)
				(type default)
			)
			(layer "F.Fab")
		)
		(fp_line
			(start 0.12065 -0.3048)
			(end 0.67945 -0.3048)
			(stroke
				(width 0.1)
				(type default)
			)
			(layer "F.Fab")
		)
		(fp_line
			(start 0.12065 -0.2794)
			(end 0.12065 -0.3048)
			(stroke
				(width 0.1)
				(type default)
			)
			(layer "F.Fab")
		)
		(fp_line
			(start 0.67945 -0.3048)
			(end 0.67945 0.3048)
			(stroke
				(width 0.1)
				(type default)
			)
			(layer "F.Fab")
		)
		(fp_line
			(start 0.67945 0.3048)
			(end 0.120396 0.3048)
			(stroke
				(width 0.1)
				(type default)
			)
			(layer "F.Fab")
		)
		(pad "1" smd circle
			(at -0.40005 0)
			(size 0 0)
			(layers "F.Cu" "F.Mask" "F.Paste")
			(net "RST_SMB_RT_R2_N")
		)
		(pad "2" smd circle
			(at 0.40005 0)
			(size 0 0)
			(layers "F.Cu" "F.Mask" "F.Paste")
			(net "RST_SMB_RT_R1_N")
		)
	)
	(footprint ""
		(layer "F.Cu")
		(at 70.713854 -148.635212)
		(property "Reference" "PC62"
			(at 0 0 0)
			(layer "F.SilkS")
			(hide yes)
			(effects
				(font
					(size 1.27 1.27)
				)
			)
		)
		(property "Value" ""
			(at 0 0 0)
			(layer "F.Fab")
			(effects
				(font
					(size 1.27 1.27)
				)
			)
		)
		(duplicate_pad_numbers_are_jumpers no)
		(fp_line
			(start -0.7874 -0.4064)
			(end 0.7874 -0.4064)
			(stroke
				(width 0.1524)
				(type default)
			)
			(layer "F.SilkS")
		)
		(fp_line
			(start -0.7874 0.4064)
			(end -0.7874 -0.4064)
			(stroke
				(width 0.1524)
				(type default)
			)
			(layer "F.SilkS")
		)
		(fp_line
			(start 0.7874 -0.4064)
			(end 0.7874 0.4064)
			(stroke
				(width 0.1524)
				(type default)
			)
			(layer "F.SilkS")
		)
		(fp_line
			(start 0.7874 0.4064)
			(end -0.7874 0.4064)
			(stroke
				(width 0.1524)
				(type default)
			)
			(layer "F.SilkS")
		)
		(fp_line
			(start -0.67945 -0.305054)
			(end -0.12065 -0.305054)
			(stroke
				(width 0.1)
				(type default)
			)
			(layer "F.Fab")
		)
		(fp_line
			(start -0.67945 0.3048)
			(end -0.67945 -0.305054)
			(stroke
				(width 0.1)
				(type default)
			)
			(layer "F.Fab")
		)
		(fp_line
			(start -0.12065 -0.305054)
			(end -0.12065 -0.2794)
			(stroke
				(width 0.1)
				(type default)
			)
			(layer "F.Fab")
		)
		(fp_line
			(start -0.12065 -0.2794)
			(end 0.12065 -0.2794)
			(stroke
				(width 0.1)
				(type default)
			)
			(layer "F.Fab")
		)
		(fp_line
			(start -0.12065 0.2794)
			(end -0.12065 0.3048)
			(stroke
				(width 0.1)
				(type default)
			)
			(layer "F.Fab")
		)
		(fp_line
			(start -0.12065 0.3048)
			(end -0.67945 0.3048)
			(stroke
				(width 0.1)
				(type default)
			)
			(layer "F.Fab")
		)
		(fp_line
			(start 0.120396 0.2794)
			(end -0.12065 0.2794)
			(stroke
				(width 0.1)
				(type default)
			)
			(layer "F.Fab")
		)
		(fp_line
			(start 0.120396 0.3048)
			(end 0.120396 0.2794)
			(stroke
				(width 0.1)
				(type default)
			)
			(layer "F.Fab")
		)
		(fp_line
			(start 0.12065 -0.3048)
			(end 0.67945 -0.3048)
			(stroke
				(width 0.1)
				(type default)
			)
			(layer "F.Fab")
		)
		(fp_line
			(start 0.12065 -0.2794)
			(end 0.12065 -0.3048)
			(stroke
				(width 0.1)
				(type default)
			)
			(layer "F.Fab")
		)
		(fp_line
			(start 0.67945 -0.3048)
			(end 0.67945 0.3048)
			(stroke
				(width 0.1)
				(type default)
			)
			(layer "F.Fab")
		)
		(fp_line
			(start 0.67945 0.3048)
			(end 0.120396 0.3048)
			(stroke
				(width 0.1)
				(type default)
			)
			(layer "F.Fab")
		)
		(pad "1" smd circle
			(at -0.40005 0)
			(size 0 0)
			(layers "F.Cu" "F.Mask" "F.Paste")
			(net "PVDD18_S5_P1_REF")
		)
		(pad "2" smd circle
			(at 0.40005 0)
			(size 0 0)
			(layers "F.Cu" "F.Mask" "F.Paste")
			(net "PVDD18_SS_P1_RGND")
		)
	)
	(footprint ""
		(layer "F.Cu")
		(at 17.045432 -107.631484)
		(property "Reference" "R4483"
			(at 0 0 0)
			(layer "F.SilkS")
			(hide yes)
			(effects
				(font
					(size 1.27 1.27)
				)
			)
		)
		(property "Value" ""
			(at 0 0 0)
			(layer "F.Fab")
			(effects
				(font
					(size 1.27 1.27)
				)
			)
		)
		(duplicate_pad_numbers_are_jumpers no)
		(fp_line
			(start -0.7874 -0.4064)
			(end 0.7874 -0.4064)
			(stroke
				(width 0.1524)
				(type default)
			)
			(layer "F.SilkS")
		)
		(fp_line
			(start -0.7874 0.4064)
			(end -0.7874 -0.4064)
			(stroke
				(width 0.1524)
				(type default)
			)
			(layer "F.SilkS")
		)
		(fp_line
			(start 0.7874 -0.4064)
			(end 0.7874 0.4064)
			(stroke
				(width 0.1524)
				(type default)
			)
			(layer "F.SilkS")
		)
		(fp_line
			(start 0.7874 0.4064)
			(end -0.7874 0.4064)
			(stroke
				(width 0.1524)
				(type default)
			)
			(layer "F.SilkS")
		)
		(fp_line
			(start -0.67945 -0.305054)
			(end -0.12065 -0.305054)
			(stroke
				(width 0.1)
				(type default)
			)
			(layer "F.Fab")
		)
		(fp_line
			(start -0.67945 0.3048)
			(end -0.67945 -0.305054)
			(stroke
				(width 0.1)
				(type default)
			)
			(layer "F.Fab")
		)
		(fp_line
			(start -0.12065 -0.305054)
			(end -0.12065 -0.2794)
			(stroke
				(width 0.1)
				(type default)
			)
			(layer "F.Fab")
		)
		(fp_line
			(start -0.12065 -0.2794)
			(end 0.12065 -0.2794)
			(stroke
				(width 0.1)
				(type default)
			)
			(layer "F.Fab")
		)
		(fp_line
			(start -0.12065 0.2794)
			(end -0.12065 0.3048)
			(stroke
				(width 0.1)
				(type default)
			)
			(layer "F.Fab")
		)
		(fp_line
			(start -0.12065 0.3048)
			(end -0.67945 0.3048)
			(stroke
				(width 0.1)
				(type default)
			)
			(layer "F.Fab")
		)
		(fp_line
			(start 0.120396 0.2794)
			(end -0.12065 0.2794)
			(stroke
				(width 0.1)
				(type default)
			)
			(layer "F.Fab")
		)
		(fp_line
			(start 0.120396 0.3048)
			(end 0.120396 0.2794)
			(stroke
				(width 0.1)
				(type default)
			)
			(layer "F.Fab")
		)
		(fp_line
			(start 0.12065 -0.3048)
			(end 0.67945 -0.3048)
			(stroke
				(width 0.1)
				(type default)
			)
			(layer "F.Fab")
		)
		(fp_line
			(start 0.12065 -0.2794)
			(end 0.12065 -0.3048)
			(stroke
				(width 0.1)
				(type default)
			)
			(layer "F.Fab")
		)
		(fp_line
			(start 0.67945 -0.3048)
			(end 0.67945 0.3048)
			(stroke
				(width 0.1)
				(type default)
			)
			(layer "F.Fab")
		)
		(fp_line
			(start 0.67945 0.3048)
			(end 0.120396 0.3048)
			(stroke
				(width 0.1)
				(type default)
			)
			(layer "F.Fab")
		)
		(pad "1" smd circle
			(at -0.40005 0)
			(size 0 0)
			(layers "F.Cu" "F.Mask" "F.Paste")
			(net "USB2_HOST_BMC_B_BUF_DN")
		)
		(pad "2" smd circle
			(at 0.40005 0)
			(size 0 0)
			(layers "F.Cu" "F.Mask" "F.Paste")
			(net "GND")
		)
	)
	(footprint ""
		(layer "F.Cu")
		(at 15.58417 -71.210678)
		(property "Reference" "C1810"
			(at 0 0 0)
			(layer "F.SilkS")
			(hide yes)
			(effects
				(font
					(size 1.27 1.27)
				)
			)
		)
		(property "Value" ""
			(at 0 0 0)
			(layer "F.Fab")
			(effects
				(font
					(size 1.27 1.27)
				)
			)
		)
		(duplicate_pad_numbers_are_jumpers no)
		(fp_line
			(start -0.7874 -0.4064)
			(end 0.7874 -0.4064)
			(stroke
				(width 0.1524)
				(type default)
			)
			(layer "F.SilkS")
		)
		(fp_line
			(start -0.7874 0.4064)
			(end -0.7874 -0.4064)
			(stroke
				(width 0.1524)
				(type default)
			)
			(layer "F.SilkS")
		)
		(fp_line
			(start 0.7874 -0.4064)
			(end 0.7874 0.4064)
			(stroke
				(width 0.1524)
				(type default)
			)
			(layer "F.SilkS")
		)
		(fp_line
			(start 0.7874 0.4064)
			(end -0.7874 0.4064)
			(stroke
				(width 0.1524)
				(type default)
			)
			(layer "F.SilkS")
		)
		(fp_line
			(start -0.67945 -0.305054)
			(end -0.12065 -0.305054)
			(stroke
				(width 0.1)
				(type default)
			)
			(layer "F.Fab")
		)
		(fp_line
			(start -0.67945 0.3048)
			(end -0.67945 -0.305054)
			(stroke
				(width 0.1)
				(type default)
			)
			(layer "F.Fab")
		)
		(fp_line
			(start -0.12065 -0.305054)
			(end -0.12065 -0.2794)
			(stroke
				(width 0.1)
				(type default)
			)
			(layer "F.Fab")
		)
		(fp_line
			(start -0.12065 -0.2794)
			(end 0.12065 -0.2794)
			(stroke
				(width 0.1)
				(type default)
			)
			(layer "F.Fab")
		)
		(fp_line
			(start -0.12065 0.2794)
			(end -0.12065 0.3048)
			(stroke
				(width 0.1)
				(type default)
			)
			(layer "F.Fab")
		)
		(fp_line
			(start -0.12065 0.3048)
			(end -0.67945 0.3048)
			(stroke
				(width 0.1)
				(type default)
			)
			(layer "F.Fab")
		)
		(fp_line
			(start 0.120396 0.2794)
			(end -0.12065 0.2794)
			(stroke
				(width 0.1)
				(type default)
			)
			(layer "F.Fab")
		)
		(fp_line
			(start 0.120396 0.3048)
			(end 0.120396 0.2794)
			(stroke
				(width 0.1)
				(type default)
			)
			(layer "F.Fab")
		)
		(fp_line
			(start 0.12065 -0.3048)
			(end 0.67945 -0.3048)
			(stroke
				(width 0.1)
				(type default)
			)
			(layer "F.Fab")
		)
		(fp_line
			(start 0.12065 -0.2794)
			(end 0.12065 -0.3048)
			(stroke
				(width 0.1)
				(type default)
			)
			(layer "F.Fab")
		)
		(fp_line
			(start 0.67945 -0.3048)
			(end 0.67945 0.3048)
			(stroke
				(width 0.1)
				(type default)
			)
			(layer "F.Fab")
		)
		(fp_line
			(start 0.67945 0.3048)
			(end 0.120396 0.3048)
			(stroke
				(width 0.1)
				(type default)
			)
			(layer "F.Fab")
		)
		(pad "1" smd circle
			(at -0.40005 0)
			(size 0 0)
			(layers "F.Cu" "F.Mask" "F.Paste")
			(net "P3V3_AUX")
		)
		(pad "2" smd circle
			(at 0.40005 0)
			(size 0 0)
			(layers "F.Cu" "F.Mask" "F.Paste")
			(net "GND")
		)
	)
	(footprint ""
		(layer "F.Cu")
		(at 428.287688 -351.13849 -90)
		(property "Reference" "PC206_11P0_2"
			(at 0 0 270)
			(layer "F.SilkS")
			(hide yes)
			(effects
				(font
					(size 1.27 1.27)
				)
			)
		)
		(property "Value" ""
			(at 0 0 270)
			(layer "F.Fab")
			(effects
				(font
					(size 1.27 1.27)
				)
			)
		)
		(duplicate_pad_numbers_are_jumpers no)
		(fp_line
			(start -0.7874 0.4064)
			(end -0.7874 -0.4064)
			(stroke
				(width 0.1524)
				(type default)
			)
			(layer "F.SilkS")
		)
		(fp_line
			(start 0.7874 0.4064)
			(end -0.7874 0.4064)
			(stroke
				(width 0.1524)
				(type default)
			)
			(layer "F.SilkS")
		)
		(fp_line
			(start -0.7874 -0.4064)
			(end 0.7874 -0.4064)
			(stroke
				(width 0.1524)
				(type default)
			)
			(layer "F.SilkS")
		)
		(fp_line
			(start 0.7874 -0.4064)
			(end 0.7874 0.4064)
			(stroke
				(width 0.1524)
				(type default)
			)
			(layer "F.SilkS")
		)
		(fp_line
			(start -0.67945 0.3048)
			(end -0.67945 -0.305054)
			(stroke
				(width 0.1)
				(type default)
			)
			(layer "F.Fab")
		)
		(fp_line
			(start -0.12065 0.3048)
			(end -0.67945 0.3048)
			(stroke
				(width 0.1)
				(type default)
			)
			(layer "F.Fab")
		)
		(fp_line
			(start 0.120396 0.3048)
			(end 0.120396 0.2794)
			(stroke
				(width 0.1)
				(type default)
			)
			(layer "F.Fab")
		)
		(fp_line
			(start 0.67945 0.3048)
			(end 0.120396 0.3048)
			(stroke
				(width 0.1)
				(type default)
			)
			(layer "F.Fab")
		)
		(fp_line
			(start -0.12065 0.2794)
			(end -0.12065 0.3048)
			(stroke
				(width 0.1)
				(type default)
			)
			(layer "F.Fab")
		)
		(fp_line
			(start 0.120396 0.2794)
			(end -0.12065 0.2794)
			(stroke
				(width 0.1)
				(type default)
			)
			(layer "F.Fab")
		)
		(fp_line
			(start -0.12065 -0.2794)
			(end 0.12065 -0.2794)
			(stroke
				(width 0.1)
				(type default)
			)
			(layer "F.Fab")
		)
		(fp_line
			(start 0.12065 -0.2794)
			(end 0.12065 -0.3048)
			(stroke
				(width 0.1)
				(type default)
			)
			(layer "F.Fab")
		)
		(fp_line
			(start 0.12065 -0.3048)
			(end 0.67945 -0.3048)
			(stroke
				(width 0.1)
				(type default)
			)
			(layer "F.Fab")
		)
		(fp_line
			(start 0.67945 -0.3048)
			(end 0.67945 0.3048)
			(stroke
				(width 0.1)
				(type default)
			)
			(layer "F.Fab")
		)
		(fp_line
			(start -0.67945 -0.305054)
			(end -0.12065 -0.305054)
			(stroke
				(width 0.1)
				(type default)
			)
			(layer "F.Fab")
		)
		(fp_line
			(start -0.12065 -0.305054)
			(end -0.12065 -0.2794)
			(stroke
				(width 0.1)
				(type default)
			)
			(layer "F.Fab")
		)
		(pad "1" smd circle
			(at -0.40005 0 270)
			(size 0 0)
			(layers "F.Cu" "F.Mask" "F.Paste")
			(net "PVDD11_S3_P0_PVCC")
		)
		(pad "2" smd circle
			(at 0.40005 0 270)
			(size 0 0)
			(layers "F.Cu" "F.Mask" "F.Paste")
			(net "GND")
		)
	)
	(footprint ""
		(layer "F.Cu")
		(at 20.860258 -427.580298 -90)
		(property "Reference" "R6163"
			(at 0 0 270)
			(layer "F.SilkS")
			(hide yes)
			(effects
				(font
					(size 1.27 1.27)
				)
			)
		)
		(property "Value" ""
			(at 0 0 270)
			(layer "F.Fab")
			(effects
				(font
					(size 1.27 1.27)
				)
			)
		)
		(duplicate_pad_numbers_are_jumpers no)
		(fp_line
			(start -0.7874 0.4064)
			(end -0.7874 -0.4064)
			(stroke
				(width 0.1524)
				(type default)
			)
			(layer "F.SilkS")
		)
		(fp_line
			(start 0.7874 0.4064)
			(end -0.7874 0.4064)
			(stroke
				(width 0.1524)
				(type default)
			)
			(layer "F.SilkS")
		)
		(fp_line
			(start -0.7874 -0.4064)
			(end 0.7874 -0.4064)
			(stroke
				(width 0.1524)
				(type default)
			)
			(layer "F.SilkS")
		)
		(fp_line
			(start 0.7874 -0.4064)
			(end 0.7874 0.4064)
			(stroke
				(width 0.1524)
				(type default)
			)
			(layer "F.SilkS")
		)
		(fp_line
			(start -0.67945 0.3048)
			(end -0.67945 -0.305054)
			(stroke
				(width 0.1)
				(type default)
			)
			(layer "F.Fab")
		)
		(fp_line
			(start -0.12065 0.3048)
			(end -0.67945 0.3048)
			(stroke
				(width 0.1)
				(type default)
			)
			(layer "F.Fab")
		)
		(fp_line
			(start 0.120396 0.3048)
			(end 0.120396 0.2794)
			(stroke
				(width 0.1)
				(type default)
			)
			(layer "F.Fab")
		)
		(fp_line
			(start 0.67945 0.3048)
			(end 0.120396 0.3048)
			(stroke
				(width 0.1)
				(type default)
			)
			(layer "F.Fab")
		)
		(fp_line
			(start -0.12065 0.2794)
			(end -0.12065 0.3048)
			(stroke
				(width 0.1)
				(type default)
			)
			(layer "F.Fab")
		)
		(fp_line
			(start 0.120396 0.2794)
			(end -0.12065 0.2794)
			(stroke
				(width 0.1)
				(type default)
			)
			(layer "F.Fab")
		)
		(fp_line
			(start -0.12065 -0.2794)
			(end 0.12065 -0.2794)
			(stroke
				(width 0.1)
				(type default)
			)
			(layer "F.Fab")
		)
		(fp_line
			(start 0.12065 -0.2794)
			(end 0.12065 -0.3048)
			(stroke
				(width 0.1)
				(type default)
			)
			(layer "F.Fab")
		)
		(fp_line
			(start 0.12065 -0.3048)
			(end 0.67945 -0.3048)
			(stroke
				(width 0.1)
				(type default)
			)
			(layer "F.Fab")
		)
		(fp_line
			(start 0.67945 -0.3048)
			(end 0.67945 0.3048)
			(stroke
				(width 0.1)
				(type default)
			)
			(layer "F.Fab")
		)
		(fp_line
			(start -0.67945 -0.305054)
			(end -0.12065 -0.305054)
			(stroke
				(width 0.1)
				(type default)
			)
			(layer "F.Fab")
		)
		(fp_line
			(start -0.12065 -0.305054)
			(end -0.12065 -0.2794)
			(stroke
				(width 0.1)
				(type default)
			)
			(layer "F.Fab")
		)
		(pad "1" smd circle
			(at -0.40005 0 270)
			(size 0 0)
			(layers "F.Cu" "F.Mask" "F.Paste")
			(net "P3V3_AUX")
		)
		(pad "2" smd circle
			(at 0.40005 0 270)
			(size 0 0)
			(layers "F.Cu" "F.Mask" "F.Paste")
			(net "FM_P2E_BUF2_EQB1")
		)
	)
	(footprint ""
		(layer "F.Cu")
		(at 358.268524 -384.449828)
		(property "Reference" "C936"
			(at 0 0 0)
			(layer "F.SilkS")
			(hide yes)
			(effects
				(font
					(size 1.27 1.27)
				)
			)
		)
		(property "Value" ""
			(at 0 0 0)
			(layer "F.Fab")
			(effects
				(font
					(size 1.27 1.27)
				)
			)
		)
		(duplicate_pad_numbers_are_jumpers no)
		(fp_line
			(start -0.299974 -0.150114)
			(end 0.299974 -0.150114)
			(stroke
				(width 0.1)
				(type default)
			)
			(layer "F.Fab")
		)
		(fp_line
			(start -0.299974 0.150114)
			(end -0.299974 -0.150114)
			(stroke
				(width 0.1)
				(type default)
			)
			(layer "F.Fab")
		)
		(fp_line
			(start 0.299974 -0.150114)
			(end 0.299974 0.150114)
			(stroke
				(width 0.1)
				(type default)
			)
			(layer "F.Fab")
		)
		(fp_line
			(start 0.299974 0.150114)
			(end -0.299974 0.150114)
			(stroke
				(width 0.1)
				(type default)
			)
			(layer "F.Fab")
		)
		(pad "1" smd rect
			(at -0.2667 0)
			(size 0.3048 0.381)
			(layers "F.Cu" "F.Mask" "F.Paste")
			(net "P5E_CPU0_P1_TX_C_DN<14>")
		)
		(pad "2" smd rect
			(at 0.2667 0)
			(size 0.3048 0.381)
			(layers "F.Cu" "F.Mask" "F.Paste")
			(net "P5E_CPU0_P1_TX_DN<14>")
		)
	)
	(footprint ""
		(layer "F.Cu")
		(at 338.683346 -23.897336 -90)
		(property "Reference" "R1507"
			(at 0 0 270)
			(layer "F.SilkS")
			(hide yes)
			(effects
				(font
					(size 1.27 1.27)
				)
			)
		)
		(property "Value" ""
			(at 0 0 270)
			(layer "F.Fab")
			(effects
				(font
					(size 1.27 1.27)
				)
			)
		)
		(duplicate_pad_numbers_are_jumpers no)
		(fp_line
			(start -0.7874 0.4064)
			(end -0.7874 -0.4064)
			(stroke
				(width 0.1524)
				(type default)
			)
			(layer "F.SilkS")
		)
		(fp_line
			(start 0.7874 0.4064)
			(end -0.7874 0.4064)
			(stroke
				(width 0.1524)
				(type default)
			)
			(layer "F.SilkS")
		)
		(fp_line
			(start -0.7874 -0.4064)
			(end 0.7874 -0.4064)
			(stroke
				(width 0.1524)
				(type default)
			)
			(layer "F.SilkS")
		)
		(fp_line
			(start 0.7874 -0.4064)
			(end 0.7874 0.4064)
			(stroke
				(width 0.1524)
				(type default)
			)
			(layer "F.SilkS")
		)
		(fp_line
			(start -0.67945 0.3048)
			(end -0.67945 -0.305054)
			(stroke
				(width 0.1)
				(type default)
			)
			(layer "F.Fab")
		)
		(fp_line
			(start -0.12065 0.3048)
			(end -0.67945 0.3048)
			(stroke
				(width 0.1)
				(type default)
			)
			(layer "F.Fab")
		)
		(fp_line
			(start 0.120396 0.3048)
			(end 0.120396 0.2794)
			(stroke
				(width 0.1)
				(type default)
			)
			(layer "F.Fab")
		)
		(fp_line
			(start 0.67945 0.3048)
			(end 0.120396 0.3048)
			(stroke
				(width 0.1)
				(type default)
			)
			(layer "F.Fab")
		)
		(fp_line
			(start -0.12065 0.2794)
			(end -0.12065 0.3048)
			(stroke
				(width 0.1)
				(type default)
			)
			(layer "F.Fab")
		)
		(fp_line
			(start 0.120396 0.2794)
			(end -0.12065 0.2794)
			(stroke
				(width 0.1)
				(type default)
			)
			(layer "F.Fab")
		)
		(fp_line
			(start -0.12065 -0.2794)
			(end 0.12065 -0.2794)
			(stroke
				(width 0.1)
				(type default)
			)
			(layer "F.Fab")
		)
		(fp_line
			(start 0.12065 -0.2794)
			(end 0.12065 -0.3048)
			(stroke
				(width 0.1)
				(type default)
			)
			(layer "F.Fab")
		)
		(fp_line
			(start 0.12065 -0.3048)
			(end 0.67945 -0.3048)
			(stroke
				(width 0.1)
				(type default)
			)
			(layer "F.Fab")
		)
		(fp_line
			(start 0.67945 -0.3048)
			(end 0.67945 0.3048)
			(stroke
				(width 0.1)
				(type default)
			)
			(layer "F.Fab")
		)
		(fp_line
			(start -0.67945 -0.305054)
			(end -0.12065 -0.305054)
			(stroke
				(width 0.1)
				(type default)
			)
			(layer "F.Fab")
		)
		(fp_line
			(start -0.12065 -0.305054)
			(end -0.12065 -0.2794)
			(stroke
				(width 0.1)
				(type default)
			)
			(layer "F.Fab")
		)
		(pad "1" smd circle
			(at -0.40005 0 270)
			(size 0 0)
			(layers "F.Cu" "F.Mask" "F.Paste")
			(net "P3V3_AUX")
		)
		(pad "2" smd circle
			(at 0.40005 0 270)
			(size 0 0)
			(layers "F.Cu" "F.Mask" "F.Paste")
			(net "LED_BIOS_DBG_MODE_N")
		)
	)
	(footprint ""
		(layer "F.Cu")
		(at 140.765784 -47.309024 90)
		(property "Reference" "R4450"
			(at 0 0 90)
			(layer "F.SilkS")
			(hide yes)
			(effects
				(font
					(size 1.27 1.27)
				)
			)
		)
		(property "Value" ""
			(at 0 0 90)
			(layer "F.Fab")
			(effects
				(font
					(size 1.27 1.27)
				)
			)
		)
		(duplicate_pad_numbers_are_jumpers no)
		(fp_line
			(start 0.7874 -0.4064)
			(end 0.7874 0.4064)
			(stroke
				(width 0.1524)
				(type default)
			)
			(layer "F.SilkS")
		)
		(fp_line
			(start -0.7874 -0.4064)
			(end 0.7874 -0.4064)
			(stroke
				(width 0.1524)
				(type default)
			)
			(layer "F.SilkS")
		)
		(fp_line
			(start 0.7874 0.4064)
			(end -0.7874 0.4064)
			(stroke
				(width 0.1524)
				(type default)
			)
			(layer "F.SilkS")
		)
		(fp_line
			(start -0.7874 0.4064)
			(end -0.7874 -0.4064)
			(stroke
				(width 0.1524)
				(type default)
			)
			(layer "F.SilkS")
		)
		(fp_line
			(start -0.12065 -0.305054)
			(end -0.12065 -0.2794)
			(stroke
				(width 0.1)
				(type default)
			)
			(layer "F.Fab")
		)
		(fp_line
			(start -0.67945 -0.305054)
			(end -0.12065 -0.305054)
			(stroke
				(width 0.1)
				(type default)
			)
			(layer "F.Fab")
		)
		(fp_line
			(start 0.67945 -0.3048)
			(end 0.67945 0.3048)
			(stroke
				(width 0.1)
				(type default)
			)
			(layer "F.Fab")
		)
		(fp_line
			(start 0.12065 -0.3048)
			(end 0.67945 -0.3048)
			(stroke
				(width 0.1)
				(type default)
			)
			(layer "F.Fab")
		)
		(fp_line
			(start 0.12065 -0.2794)
			(end 0.12065 -0.3048)
			(stroke
				(width 0.1)
				(type default)
			)
			(layer "F.Fab")
		)
		(fp_line
			(start -0.12065 -0.2794)
			(end 0.12065 -0.2794)
			(stroke
				(width 0.1)
				(type default)
			)
			(layer "F.Fab")
		)
		(fp_line
			(start 0.120396 0.2794)
			(end -0.12065 0.2794)
			(stroke
				(width 0.1)
				(type default)
			)
			(layer "F.Fab")
		)
		(fp_line
			(start -0.12065 0.2794)
			(end -0.12065 0.3048)
			(stroke
				(width 0.1)
				(type default)
			)
			(layer "F.Fab")
		)
		(fp_line
			(start 0.67945 0.3048)
			(end 0.120396 0.3048)
			(stroke
				(width 0.1)
				(type default)
			)
			(layer "F.Fab")
		)
		(fp_line
			(start 0.120396 0.3048)
			(end 0.120396 0.2794)
			(stroke
				(width 0.1)
				(type default)
			)
			(layer "F.Fab")
		)
		(fp_line
			(start -0.12065 0.3048)
			(end -0.67945 0.3048)
			(stroke
				(width 0.1)
				(type default)
			)
			(layer "F.Fab")
		)
		(fp_line
			(start -0.67945 0.3048)
			(end -0.67945 -0.305054)
			(stroke
				(width 0.1)
				(type default)
			)
			(layer "F.Fab")
		)
		(pad "1" smd circle
			(at -0.40005 0 90)
			(size 0 0)
			(layers "F.Cu" "F.Mask" "F.Paste")
			(net "USB_CPU0_HUB1_VBUS_DS")
		)
		(pad "2" smd circle
			(at 0.40005 0 90)
			(size 0 0)
			(layers "F.Cu" "F.Mask" "F.Paste")
			(net "P5V_AUX")
		)
	)
	(footprint ""
		(layer "F.Cu")
		(at 283.702506 -346.71635)
		(property "Reference" "PU19"
			(at -2.524506 -7.84098 0)
			(unlocked yes)
			(layer "F.SilkS")
			(effects
				(font
					(size 0.7874 0.5842)
					(thickness 0.1524)
				)
				(justify left)
			)
		)
		(property "Value" ""
			(at 0 0 0)
			(layer "F.Fab")
			(effects
				(font
					(size 1.27 1.27)
				)
			)
		)
		(duplicate_pad_numbers_are_jumpers no)
		(fp_line
			(start -2.500122 -2.999994)
			(end -2.24409 -2.999994)
			(stroke
				(width 0.1524)
				(type default)
			)
			(layer "F.SilkS")
		)
		(fp_line
			(start -2.500122 -2.529078)
			(end -2.500122 -2.999994)
			(stroke
				(width 0.1524)
				(type default)
			)
			(layer "F.SilkS")
		)
		(fp_line
			(start -2.500122 0.6604)
			(end -2.500122 0.229108)
			(stroke
				(width 0.1524)
				(type default)
			)
			(layer "F.SilkS")
		)
		(fp_line
			(start -2.500122 2.999994)
			(end -2.500122 2.339594)
			(stroke
				(width 0.1524)
				(type default)
			)
			(layer "F.SilkS")
		)
		(fp_line
			(start -2.2987 2.999994)
			(end -2.500122 2.999994)
			(stroke
				(width 0.1524)
				(type default)
			)
			(layer "F.SilkS")
		)
		(fp_line
			(start 2.31394 -2.999994)
			(end 2.500122 -2.999994)
			(stroke
				(width 0.1524)
				(type default)
			)
			(layer "F.SilkS")
		)
		(fp_line
			(start 2.500122 -2.999994)
			(end 2.500122 -2.44348)
			(stroke
				(width 0.1524)
				(type default)
			)
			(layer "F.SilkS")
		)
		(fp_line
			(start 2.500122 2.339594)
			(end 2.500122 2.999994)
			(stroke
				(width 0.1524)
				(type default)
			)
			(layer "F.SilkS")
		)
		(fp_line
			(start 2.500122 2.999994)
			(end 2.2987 2.999994)
			(stroke
				(width 0.1524)
				(type default)
			)
			(layer "F.SilkS")
		)
		(fp_poly
			(pts
				(xy -3.467354 -2.685288) (xy -2.981706 -3.170936) (xy -2.738882 -2.442464)
			)
			(stroke
				(width 0)
				(type default)
			)
			(fill yes)
			(layer "F.SilkS")
		)
		(fp_line
			(start -2.500122 -2.999994)
			(end 2.500122 -2.999994)
			(stroke
				(width 0.1)
				(type default)
			)
			(layer "F.Fab")
		)
		(fp_line
			(start -2.500122 2.999994)
			(end -2.500122 -2.999994)
			(stroke
				(width 0.1)
				(type default)
			)
			(layer "F.Fab")
		)
		(fp_line
			(start 2.500122 -2.999994)
			(end 2.500122 2.999994)
			(stroke
				(width 0.1)
				(type default)
			)
			(layer "F.Fab")
		)
		(fp_line
			(start 2.500122 2.999994)
			(end -2.500122 2.999994)
			(stroke
				(width 0.1)
				(type default)
			)
			(layer "F.Fab")
		)
		(fp_poly
			(pts
				(xy -4.218432 -2.783078) (xy -4.218432 -1.767078) (xy -3.202432 -2.275078)
			)
			(stroke
				(width 0)
				(type default)
			)
			(fill yes)
			(layer "F.Fab")
		)
		(pad "1" smd rect
			(at -2.400046 -2.275078 90)
			(size 0.2286 0.6096)
			(layers "F.Cu" "F.Mask" "F.Paste")
			(net "PVDDIO_P0_VOS3")
		)
		(pad "2" smd rect
			(at -2.400046 -1.82499 90)
			(size 0.2286 0.6096)
			(layers "F.Cu" "F.Mask" "F.Paste")
			(net "GND")
		)
		(pad "3" smd rect
			(at -2.400046 -1.374902 90)
			(size 0.2286 0.6096)
			(layers "F.Cu" "F.Mask" "F.Paste")
			(net "PVDDIO_P0_VCC3")
		)
		(pad "4" smd rect
			(at -2.400046 -0.925068 90)
			(size 0.2286 0.6096)
			(layers "F.Cu" "F.Mask" "F.Paste")
			(net "PVDDCR_CPU1_P0_PVCC")
		)
		(pad "5" smd rect
			(at -2.400046 -0.47498 90)
			(size 0.2286 0.6096)
			(layers "F.Cu" "F.Mask" "F.Paste")
			(net "GND")
		)
		(pad "6" smd rect
			(at -2.400046 -0.024892 90)
			(size 0.2286 0.6096)
			(layers "F.Cu" "F.Mask" "F.Paste")
			(net "NC_PVDDIO_P0_GL1_3")
		)
		(pad "7_9-20_24" smd circle
			(at 0 1.150112 90)
			(size 0 0)
			(layers "F.Cu" "F.Mask" "F.Paste")
			(net "GND")
		)
		(pad "10_19" smd rect
			(at 0 2.899918 90)
			(size 0.6096 4.318)
			(layers "F.Cu" "F.Mask" "F.Paste")
			(net "SW_PVDDIO_P0_SW3")
		)
		(pad "25_29" smd rect
			(at 1.549908 -1.279906 270)
			(size 2.0574 2.3114)
			(layers "F.Cu" "F.Mask" "F.Paste")
			(net "SW_P12V_AUX_PVDDIO_P0_FLT")
		)
		(pad "30" smd rect
			(at 2.05994 -2.899918)
			(size 0.2286 0.6096)
			(layers "F.Cu" "F.Mask" "F.Paste")
			(net "SW_P12V_AUX_PVDDIO_P0_FLT")
		)
		(pad "31" smd rect
			(at 1.610106 -2.899918)
			(size 0.2286 0.6096)
			(layers "F.Cu" "F.Mask" "F.Paste")
			(net "NC_PVDDIO_P0_DNC3")
		)
		(pad "32" smd rect
			(at 1.160018 -2.899918)
			(size 0.2286 0.6096)
			(layers "F.Cu" "F.Mask" "F.Paste")
			(net "SW_PVDDIO_P0_BOOTR3")
		)
		(pad "33" smd rect
			(at 0.70993 -2.899918)
			(size 0.2286 0.6096)
			(layers "F.Cu" "F.Mask" "F.Paste")
			(net "SW_PVDDIO_P0_BOOT3")
		)
		(pad "34" smd rect
			(at 0.260096 -2.899918)
			(size 0.2286 0.6096)
			(layers "F.Cu" "F.Mask" "F.Paste")
			(net "PVDDIO_P0_PWM3")
		)
		(pad "35" smd rect
			(at -0.189992 -2.899918)
			(size 0.2286 0.6096)
			(layers "F.Cu" "F.Mask" "F.Paste")
			(net "PVDDIO_P0_VCC3")
		)
		(pad "36" smd rect
			(at -0.64008 -2.899918)
			(size 0.2286 0.6096)
			(layers "F.Cu" "F.Mask" "F.Paste")
			(net "PVDDIO_P0_TEMP1")
		)
		(pad "37" smd rect
			(at -1.089914 -2.899918)
			(size 0.2286 0.6096)
			(layers "F.Cu" "F.Mask" "F.Paste")
			(net "PVDDIO_P0_LSET3")
		)
		(pad "38" smd rect
			(at -1.540002 -2.899918)
			(size 0.2286 0.6096)
			(layers "F.Cu" "F.Mask" "F.Paste")
			(net "PVDDIO_P0_IMON3")
		)
		(pad "39" smd rect
			(at -1.99009 -2.899918)
			(size 0.2286 0.6096)
			(layers "F.Cu" "F.Mask" "F.Paste")
			(net "PVDDCR_CPU1_P0_VCCS")
		)
		(pad "40" smd rect
			(at -0.87503 -1.27508)
			(size 1.7526 1.9558)
			(layers "F.Cu" "F.Mask" "F.Paste")
			(net "GND")
		)
		(pad "41" smd rect
			(at -1.525016 0.249936 270)
			(size 0.3048 0.4572)
			(layers "F.Cu" "F.Mask" "F.Paste")
			(net "NC_PVDDIO_P0_GL2_3")
		)
		(zone
			(layer "F.Cu")
			(hatch none 0.5)
			(connect_pads
				(clearance 0)
			)
			(min_thickness 0.25)
			(keepout
				(tracks not_allowed)
				(vias allowed)
				(pads allowed)
				(copperpour not_allowed)
				(footprints allowed)
			)
			(placement
				(enabled no)
				(sheetname "")
			)
			(fill
				(thermal_gap 0.5)
				(thermal_bridge_width 0.5)
				(island_removal_mode 0)
			)
			(polygon
				(pts
					(xy 281.202384 -344.124788) (xy 281.202384 -344.465656) (xy 286.202628 -344.465656) (xy 286.202628 -344.13063)
					(xy 285.912306 -344.13063) (xy 285.912306 -344.172032) (xy 281.492706 -344.172032) (xy 281.492706 -344.124788)
				)
			)
		)
		(zone
			(layer "F.Cu")
			(hatch none 0.5)
			(connect_pads
				(clearance 0)
			)
			(min_thickness 0.25)
			(keepout
				(tracks not_allowed)
				(vias allowed)
				(pads allowed)
				(copperpour not_allowed)
				(footprints allowed)
			)
			(placement
				(enabled no)
				(sheetname "")
			)
			(fill
				(thermal_gap 0.5)
				(thermal_bridge_width 0.5)
				(island_removal_mode 0)
			)
			(polygon
				(pts
					(xy 283.754576 -346.96273) (xy 283.754576 -349.02013) (xy 281.900376 -349.02013) (xy 281.900376 -348.779084)
					(xy 281.65806 -348.779084) (xy 281.65806 -349.260668) (xy 285.474918 -349.260668) (xy 285.474918 -349.075756)
					(xy 284.045914 -349.075756) (xy 284.045914 -346.916756) (xy 286.202628 -346.916756) (xy 286.202628 -346.667074)
					(xy 284.050232 -346.667074)
				)
			)
		)
	)
	(footprint ""
		(layer "F.Cu")
		(at 285.980886 -101.09708)
		(property "Reference" "C1515"
			(at 0 0 0)
			(layer "F.SilkS")
			(hide yes)
			(effects
				(font
					(size 1.27 1.27)
				)
			)
		)
		(property "Value" ""
			(at 0 0 0)
			(layer "F.Fab")
			(effects
				(font
					(size 1.27 1.27)
				)
			)
		)
		(duplicate_pad_numbers_are_jumpers no)
		(fp_line
			(start -0.7874 -0.4064)
			(end 0.7874 -0.4064)
			(stroke
				(width 0.1524)
				(type default)
			)
			(layer "F.SilkS")
		)
		(fp_line
			(start -0.7874 0.4064)
			(end -0.7874 -0.4064)
			(stroke
				(width 0.1524)
				(type default)
			)
			(layer "F.SilkS")
		)
		(fp_line
			(start 0.7874 -0.4064)
			(end 0.7874 0.4064)
			(stroke
				(width 0.1524)
				(type default)
			)
			(layer "F.SilkS")
		)
		(fp_line
			(start 0.7874 0.4064)
			(end -0.7874 0.4064)
			(stroke
				(width 0.1524)
				(type default)
			)
			(layer "F.SilkS")
		)
		(fp_line
			(start -0.67945 -0.305054)
			(end -0.12065 -0.305054)
			(stroke
				(width 0.1)
				(type default)
			)
			(layer "F.Fab")
		)
		(fp_line
			(start -0.67945 0.3048)
			(end -0.67945 -0.305054)
			(stroke
				(width 0.1)
				(type default)
			)
			(layer "F.Fab")
		)
		(fp_line
			(start -0.12065 -0.305054)
			(end -0.12065 -0.2794)
			(stroke
				(width 0.1)
				(type default)
			)
			(layer "F.Fab")
		)
		(fp_line
			(start -0.12065 -0.2794)
			(end 0.12065 -0.2794)
			(stroke
				(width 0.1)
				(type default)
			)
			(layer "F.Fab")
		)
		(fp_line
			(start -0.12065 0.2794)
			(end -0.12065 0.3048)
			(stroke
				(width 0.1)
				(type default)
			)
			(layer "F.Fab")
		)
		(fp_line
			(start -0.12065 0.3048)
			(end -0.67945 0.3048)
			(stroke
				(width 0.1)
				(type default)
			)
			(layer "F.Fab")
		)
		(fp_line
			(start 0.120396 0.2794)
			(end -0.12065 0.2794)
			(stroke
				(width 0.1)
				(type default)
			)
			(layer "F.Fab")
		)
		(fp_line
			(start 0.120396 0.3048)
			(end 0.120396 0.2794)
			(stroke
				(width 0.1)
				(type default)
			)
			(layer "F.Fab")
		)
		(fp_line
			(start 0.12065 -0.3048)
			(end 0.67945 -0.3048)
			(stroke
				(width 0.1)
				(type default)
			)
			(layer "F.Fab")
		)
		(fp_line
			(start 0.12065 -0.2794)
			(end 0.12065 -0.3048)
			(stroke
				(width 0.1)
				(type default)
			)
			(layer "F.Fab")
		)
		(fp_line
			(start 0.67945 -0.3048)
			(end 0.67945 0.3048)
			(stroke
				(width 0.1)
				(type default)
			)
			(layer "F.Fab")
		)
		(fp_line
			(start 0.67945 0.3048)
			(end 0.120396 0.3048)
			(stroke
				(width 0.1)
				(type default)
			)
			(layer "F.Fab")
		)
		(pad "1" smd circle
			(at -0.40005 0)
			(size 0 0)
			(layers "F.Cu" "F.Mask" "F.Paste")
			(net "PVDD18_S5_P0")
		)
		(pad "2" smd circle
			(at 0.40005 0)
			(size 0 0)
			(layers "F.Cu" "F.Mask" "F.Paste")
			(net "GND")
		)
	)
	(footprint ""
		(layer "F.Cu")
		(at 356.567232 -261.747762 -90)
		(property "Reference" "C2642"
			(at 0 0 270)
			(layer "F.SilkS")
			(hide yes)
			(effects
				(font
					(size 1.27 1.27)
				)
			)
		)
		(property "Value" ""
			(at 0 0 270)
			(layer "F.Fab")
			(effects
				(font
					(size 1.27 1.27)
				)
			)
		)
		(duplicate_pad_numbers_are_jumpers no)
		(fp_line
			(start -0.7874 0.4064)
			(end -0.7874 -0.4064)
			(stroke
				(width 0.1524)
				(type default)
			)
			(layer "F.SilkS")
		)
		(fp_line
			(start 0.7874 0.4064)
			(end -0.7874 0.4064)
			(stroke
				(width 0.1524)
				(type default)
			)
			(layer "F.SilkS")
		)
		(fp_line
			(start -0.7874 -0.4064)
			(end 0.7874 -0.4064)
			(stroke
				(width 0.1524)
				(type default)
			)
			(layer "F.SilkS")
		)
		(fp_line
			(start 0.7874 -0.4064)
			(end 0.7874 0.4064)
			(stroke
				(width 0.1524)
				(type default)
			)
			(layer "F.SilkS")
		)
		(fp_line
			(start -0.67945 0.3048)
			(end -0.67945 -0.305054)
			(stroke
				(width 0.1)
				(type default)
			)
			(layer "F.Fab")
		)
		(fp_line
			(start -0.12065 0.3048)
			(end -0.67945 0.3048)
			(stroke
				(width 0.1)
				(type default)
			)
			(layer "F.Fab")
		)
		(fp_line
			(start 0.120396 0.3048)
			(end 0.120396 0.2794)
			(stroke
				(width 0.1)
				(type default)
			)
			(layer "F.Fab")
		)
		(fp_line
			(start 0.67945 0.3048)
			(end 0.120396 0.3048)
			(stroke
				(width 0.1)
				(type default)
			)
			(layer "F.Fab")
		)
		(fp_line
			(start -0.12065 0.2794)
			(end -0.12065 0.3048)
			(stroke
				(width 0.1)
				(type default)
			)
			(layer "F.Fab")
		)
		(fp_line
			(start 0.120396 0.2794)
			(end -0.12065 0.2794)
			(stroke
				(width 0.1)
				(type default)
			)
			(layer "F.Fab")
		)
		(fp_line
			(start -0.12065 -0.2794)
			(end 0.12065 -0.2794)
			(stroke
				(width 0.1)
				(type default)
			)
			(layer "F.Fab")
		)
		(fp_line
			(start 0.12065 -0.2794)
			(end 0.12065 -0.3048)
			(stroke
				(width 0.1)
				(type default)
			)
			(layer "F.Fab")
		)
		(fp_line
			(start 0.12065 -0.3048)
			(end 0.67945 -0.3048)
			(stroke
				(width 0.1)
				(type default)
			)
			(layer "F.Fab")
		)
		(fp_line
			(start 0.67945 -0.3048)
			(end 0.67945 0.3048)
			(stroke
				(width 0.1)
				(type default)
			)
			(layer "F.Fab")
		)
		(fp_line
			(start -0.67945 -0.305054)
			(end -0.12065 -0.305054)
			(stroke
				(width 0.1)
				(type default)
			)
			(layer "F.Fab")
		)
		(fp_line
			(start -0.12065 -0.305054)
			(end -0.12065 -0.2794)
			(stroke
				(width 0.1)
				(type default)
			)
			(layer "F.Fab")
		)
		(pad "1" smd circle
			(at -0.40005 0 270)
			(size 0 0)
			(layers "F.Cu" "F.Mask" "F.Paste")
			(net "PVDD11_S3_P0")
		)
		(pad "2" smd circle
			(at 0.40005 0 270)
			(size 0 0)
			(layers "F.Cu" "F.Mask" "F.Paste")
			(net "GND")
		)
	)
	(footprint ""
		(layer "F.Cu")
		(at 185.278522 -401.919694 -90)
		(property "Reference" "PU289"
			(at 3.212592 -5.588762 0)
			(unlocked yes)
			(layer "F.SilkS")
			(effects
				(font
					(size 0.7874 0.5842)
					(thickness 0.1524)
				)
			)
		)
		(property "Value" ""
			(at 0 0 270)
			(layer "F.Fab")
			(effects
				(font
					(size 1.27 1.27)
				)
			)
		)
		(duplicate_pad_numbers_are_jumpers no)
		(fp_line
			(start -2.567686 3.567684)
			(end 2.567686 3.567684)
			(stroke
				(width 0.1524)
				(type default)
			)
			(layer "F.SilkS")
		)
		(fp_line
			(start 2.567686 3.567684)
			(end 2.567686 -3.567684)
			(stroke
				(width 0.1524)
				(type default)
			)
			(layer "F.SilkS")
		)
		(fp_line
			(start -2.567686 -3.567684)
			(end -2.567686 3.567684)
			(stroke
				(width 0.1524)
				(type default)
			)
			(layer "F.SilkS")
		)
		(fp_line
			(start 2.567686 -3.567684)
			(end -2.567686 -3.567684)
			(stroke
				(width 0.1524)
				(type default)
			)
			(layer "F.SilkS")
		)
		(fp_poly
			(pts
				(xy -2.736088 -2.894076) (xy -3.852926 -3.100324) (xy -3.241548 -3.9116)
			)
			(stroke
				(width 0)
				(type default)
			)
			(fill yes)
			(layer "F.SilkS")
		)
		(fp_line
			(start -2.549906 3.549904)
			(end 2.549906 3.549904)
			(stroke
				(width 0.1)
				(type default)
			)
			(layer "F.Fab")
		)
		(fp_line
			(start 2.549906 3.549904)
			(end 2.549906 -3.549904)
			(stroke
				(width 0.1)
				(type default)
			)
			(layer "F.Fab")
		)
		(fp_line
			(start -2.549906 -3.549904)
			(end -2.549906 3.549904)
			(stroke
				(width 0.1)
				(type default)
			)
			(layer "F.Fab")
		)
		(fp_line
			(start 2.549906 -3.549904)
			(end -2.549906 -3.549904)
			(stroke
				(width 0.1)
				(type default)
			)
			(layer "F.Fab")
		)
		(fp_poly
			(pts
				(xy -3.7592 -3.20802) (xy -3.7592 -2.19202) (xy -2.7432 -2.70002)
			)
			(stroke
				(width 0)
				(type default)
			)
			(fill yes)
			(layer "F.Fab")
		)
		(pad "1" smd rect
			(at -2.237486 -2.70002)
			(size 0.2286 0.381)
			(layers "F.Cu" "F.Mask" "F.Paste")
			(net "P12V_PSU")
		)
		(pad "2" smd rect
			(at -2.237486 -2.249932)
			(size 0.2286 0.381)
			(layers "F.Cu" "F.Mask" "F.Paste")
			(net "P12V_PSU")
		)
		(pad "3" smd rect
			(at -2.237486 -1.800098)
			(size 0.2286 0.381)
			(layers "F.Cu" "F.Mask" "F.Paste")
			(net "P12V_PSU")
		)
		(pad "4" smd rect
			(at -2.237486 -1.35001)
			(size 0.2286 0.381)
			(layers "F.Cu" "F.Mask" "F.Paste")
			(net "P12V_PSU")
		)
		(pad "5" smd rect
			(at -2.237486 -0.899922)
			(size 0.2286 0.381)
			(layers "F.Cu" "F.Mask" "F.Paste")
			(net "P12V_PSU")
		)
		(pad "6" smd rect
			(at -2.237486 -0.450088)
			(size 0.2286 0.381)
			(layers "F.Cu" "F.Mask" "F.Paste")
			(net "P12V_PSU")
		)
		(pad "7" smd rect
			(at -2.237486 0)
			(size 0.2286 0.381)
			(layers "F.Cu" "F.Mask" "F.Paste")
			(net "P12V_PSU")
		)
		(pad "8" smd rect
			(at -2.237486 0.450088)
			(size 0.2286 0.381)
			(layers "F.Cu" "F.Mask" "F.Paste")
			(net "P12V_PSU")
		)
		(pad "9" smd rect
			(at -2.237486 0.899922)
			(size 0.2286 0.381)
			(layers "F.Cu" "F.Mask" "F.Paste")
			(net "HSC_VSENSE")
		)
		(pad "10" smd rect
			(at -2.237486 1.35001)
			(size 0.2286 0.381)
			(layers "F.Cu" "F.Mask" "F.Paste")
			(net "IRQ_SML1_PMBUS_ALERT")
		)
		(pad "11" smd rect
			(at -2.237486 1.800098)
			(size 0.2286 0.381)
			(layers "F.Cu" "F.Mask" "F.Paste")
			(net "SMB_SML1_PMBUS_HSC_L_SCL")
		)
		(pad "12" smd rect
			(at -2.237486 2.249932)
			(size 0.2286 0.381)
			(layers "F.Cu" "F.Mask" "F.Paste")
			(net "SMB_SML1_PMBUS_HSC_R_SDA")
		)
		(pad "13" smd rect
			(at -2.237486 2.70002)
			(size 0.2286 0.381)
			(layers "F.Cu" "F.Mask" "F.Paste")
			(net "MB0_P12V_STBY_PWRGD")
		)
		(pad "14" smd rect
			(at -1.575054 3.237484 270)
			(size 0.2286 0.381)
			(layers "F.Cu" "F.Mask" "F.Paste")
			(net "HSC_VIN_UVW_N")
		)
		(pad "15" smd rect
			(at -1.124966 3.237484 270)
			(size 0.2286 0.381)
			(layers "F.Cu" "F.Mask" "F.Paste")
			(net "HSC_VTEMP")
		)
		(pad "16" smd rect
			(at -0.674878 3.237484 270)
			(size 0.2286 0.381)
			(layers "F.Cu" "F.Mask" "F.Paste")
			(net "HSC_SS")
		)
		(pad "17" smd rect
			(at -0.225044 3.237484 270)
			(size 0.2286 0.381)
			(layers "F.Cu" "F.Mask" "F.Paste")
			(net "HSC_VDD_R")
		)
		(pad "18" smd rect
			(at 0.225044 3.237484 270)
			(size 0.2286 0.381)
			(layers "F.Cu" "F.Mask" "F.Paste")
			(net "AGND_HSC")
		)
		(pad "19" smd rect
			(at 0.674878 3.237484 270)
			(size 0.2286 0.381)
			(layers "F.Cu" "F.Mask" "F.Paste")
			(net "HSC_VDD18")
		)
		(pad "20" smd rect
			(at 1.124966 3.237484 270)
			(size 0.2286 0.381)
			(layers "F.Cu" "F.Mask" "F.Paste")
			(net "HSC_CS")
		)
		(pad "21" smd rect
			(at 1.575054 3.237484 270)
			(size 0.2286 0.381)
			(layers "F.Cu" "F.Mask" "F.Paste")
			(net "HSC_IMON")
		)
		(pad "22" smd rect
			(at 2.237486 2.70002)
			(size 0.2286 0.381)
			(layers "F.Cu" "F.Mask" "F.Paste")
			(net "HSC_OCREF")
		)
		(pad "23" smd rect
			(at 2.237486 2.249932)
			(size 0.2286 0.381)
			(layers "F.Cu" "F.Mask" "F.Paste")
			(net "HSC_ADDR")
		)
		(pad "24" smd rect
			(at 2.237486 1.800098)
			(size 0.2286 0.381)
			(layers "F.Cu" "F.Mask" "F.Paste")
			(net "HSC_VOSEN")
		)
		(pad "25" smd rect
			(at 2.237486 1.35001)
			(size 0.2286 0.381)
			(layers "F.Cu" "F.Mask" "F.Paste")
			(net "HSC_SCREF")
		)
		(pad "26" smd rect
			(at 2.237486 0.899922)
			(size 0.2286 0.381)
			(layers "F.Cu" "F.Mask" "F.Paste")
			(net "HSC_EN_R")
		)
		(pad "27" smd rect
			(at 2.237486 0.450088)
			(size 0.2286 0.381)
			(layers "F.Cu" "F.Mask" "F.Paste")
			(net "P12V_AUX")
		)
		(pad "28" smd rect
			(at 2.237486 0)
			(size 0.2286 0.381)
			(layers "F.Cu" "F.Mask" "F.Paste")
			(net "P12V_AUX")
		)
		(pad "29" smd rect
			(at 2.237486 -0.450088)
			(size 0.2286 0.381)
			(layers "F.Cu" "F.Mask" "F.Paste")
			(net "P12V_AUX")
		)
		(pad "30" smd rect
			(at 2.237486 -0.899922)
			(size 0.2286 0.381)
			(layers "F.Cu" "F.Mask" "F.Paste")
			(net "P12V_AUX")
		)
		(pad "31" smd rect
			(at 2.237486 -1.35001)
			(size 0.2286 0.381)
			(layers "F.Cu" "F.Mask" "F.Paste")
			(net "P12V_AUX")
		)
		(pad "32" smd rect
			(at 2.237486 -1.800098)
			(size 0.2286 0.381)
			(layers "F.Cu" "F.Mask" "F.Paste")
			(net "P12V_AUX")
		)
		(pad "33" smd rect
			(at 2.237486 -2.249932)
			(size 0.2286 0.381)
			(layers "F.Cu" "F.Mask" "F.Paste")
			(net "P12V_AUX")
		)
		(pad "34" smd rect
			(at 2.237486 -2.70002)
			(size 0.2286 0.381)
			(layers "F.Cu" "F.Mask" "F.Paste")
			(net "P12V_AUX")
		)
		(pad "35" smd rect
			(at 1.575054 -3.237484 270)
			(size 0.2286 0.381)
			(layers "F.Cu" "F.Mask" "F.Paste")
			(net "P12V_AUX")
		)
		(pad "36" smd rect
			(at 1.124966 -3.237484 270)
			(size 0.2286 0.381)
			(layers "F.Cu" "F.Mask" "F.Paste")
			(net "P12V_AUX")
		)
		(pad "37" smd rect
			(at 0.674878 -3.237484 270)
			(size 0.2286 0.381)
			(layers "F.Cu" "F.Mask" "F.Paste")
			(net "HSC_D_OC_R")
		)
		(pad "38" smd rect
			(at 0.225044 -3.237484 270)
			(size 0.2286 0.381)
			(layers "F.Cu" "F.Mask" "F.Paste")
			(net "HSC_ON_R")
		)
		(pad "39" smd rect
			(at -0.225044 -3.237484 270)
			(size 0.2286 0.381)
			(layers "F.Cu" "F.Mask" "F.Paste")
			(net "HSC_FAULT")
		)
		(pad "40" smd rect
			(at -0.674878 -3.237484 270)
			(size 0.2286 0.381)
			(layers "F.Cu" "F.Mask" "F.Paste")
			(net "HSC_FLT_TYPE")
		)
		(pad "41" smd rect
			(at -1.124966 -3.237484 270)
			(size 0.2286 0.381)
			(layers "F.Cu" "F.Mask" "F.Paste")
			(net "HSC_MODE")
		)
		(pad "42" smd rect
			(at -1.575054 -3.237484 270)
			(size 0.2286 0.381)
			(layers "F.Cu" "F.Mask" "F.Paste")
			(net "P12V_PSU")
		)
		(pad "43" smd rect
			(at 0 -0.999998 270)
			(size 3.4036 3.4036)
			(layers "F.Cu" "F.Mask" "F.Paste")
			(net "P12V_PSU")
		)
		(pad "44" smd rect
			(at -1.124966 1.89992 270)
			(size 1.1684 1.6002)
			(layers "F.Cu" "F.Mask" "F.Paste")
			(net "AGND_HSC")
		)
		(pad "45" smd rect
			(at 1.124966 1.89992 270)
			(size 1.1684 1.6002)
			(layers "F.Cu" "F.Mask" "F.Paste")
			(net "HSC_VDD_R")
		)
		(zone
			(layer "F.Cu")
			(hatch none 0.5)
			(connect_pads
				(clearance 0)
			)
			(min_thickness 0.25)
			(keepout
				(tracks not_allowed)
				(vias allowed)
				(pads allowed)
				(copperpour not_allowed)
				(footprints allowed)
			)
			(placement
				(enabled no)
				(sheetname "")
			)
			(fill
				(thermal_gap 0.5)
				(thermal_bridge_width 0.5)
				(island_removal_mode 0)
			)
			(polygon
				(pts
					(xy 182.282338 -403.91588) (xy 184.52592 -403.91588) (xy 184.52592 -402.961094) (xy 184.229502 -402.961094)
					(xy 184.229502 -403.67966) (xy 182.527702 -403.67966) (xy 182.527702 -402.40966) (xy 184.229502 -402.40966)
					(xy 184.229502 -402.935694) (xy 184.52592 -402.935694) (xy 184.52592 -400.776694) (xy 184.229502 -400.776694)
					(xy 184.229502 -401.429728) (xy 182.527702 -401.429728) (xy 182.527702 -400.159728) (xy 184.229502 -400.159728)
					(xy 184.229502 -400.751294) (xy 184.52592 -400.751294) (xy 184.52592 -400.167094) (xy 188.03112 -400.167094)
					(xy 188.03112 -403.23008) (xy 188.274706 -403.23008) (xy 188.274706 -399.923508) (xy 182.282338 -399.923508)
				)
			)
		)
	)
	(footprint ""
		(layer "F.Cu")
		(at 365.62792 -396.146274)
		(property "Reference" "R615"
			(at 0 0 0)
			(layer "F.SilkS")
			(hide yes)
			(effects
				(font
					(size 1.27 1.27)
				)
			)
		)
		(property "Value" ""
			(at 0 0 0)
			(layer "F.Fab")
			(effects
				(font
					(size 1.27 1.27)
				)
			)
		)
		(duplicate_pad_numbers_are_jumpers no)
		(fp_line
			(start -0.32512 -0.175006)
			(end 0.32512 -0.175006)
			(stroke
				(width 0.1)
				(type default)
			)
			(layer "F.Fab")
		)
		(fp_line
			(start -0.32512 0.175006)
			(end -0.32512 -0.175006)
			(stroke
				(width 0.1)
				(type default)
			)
			(layer "F.Fab")
		)
		(fp_line
			(start 0.32512 -0.175006)
			(end 0.32512 0.175006)
			(stroke
				(width 0.1)
				(type default)
			)
			(layer "F.Fab")
		)
		(fp_line
			(start 0.32512 0.175006)
			(end -0.32512 0.175006)
			(stroke
				(width 0.1)
				(type default)
			)
			(layer "F.Fab")
		)
		(pad "1" smd rect
			(at -0.2667 0)
			(size 0.3048 0.381)
			(layers "F.Cu" "F.Mask" "F.Paste")
			(net "CLK_100M_RETIMER_CPU0_P3_R_DP")
		)
		(pad "2" smd rect
			(at 0.2667 0 180)
			(size 0.3048 0.381)
			(layers "F.Cu" "F.Mask" "F.Paste")
			(net "CLK_100M_RETIMER_CPU0_P3_DP")
		)
	)
	(footprint ""
		(layer "F.Cu")
		(at 60.011564 -16.220948 -90)
		(property "Reference" "R3172"
			(at 0 0 270)
			(layer "F.SilkS")
			(hide yes)
			(effects
				(font
					(size 1.27 1.27)
				)
			)
		)
		(property "Value" ""
			(at 0 0 270)
			(layer "F.Fab")
			(effects
				(font
					(size 1.27 1.27)
				)
			)
		)
		(duplicate_pad_numbers_are_jumpers no)
		(fp_line
			(start -0.7874 0.4064)
			(end -0.7874 -0.4064)
			(stroke
				(width 0.1524)
				(type default)
			)
			(layer "F.SilkS")
		)
		(fp_line
			(start 0.7874 0.4064)
			(end -0.7874 0.4064)
			(stroke
				(width 0.1524)
				(type default)
			)
			(layer "F.SilkS")
		)
		(fp_line
			(start -0.7874 -0.4064)
			(end 0.7874 -0.4064)
			(stroke
				(width 0.1524)
				(type default)
			)
			(layer "F.SilkS")
		)
		(fp_line
			(start 0.7874 -0.4064)
			(end 0.7874 0.4064)
			(stroke
				(width 0.1524)
				(type default)
			)
			(layer "F.SilkS")
		)
		(fp_line
			(start -0.67945 0.3048)
			(end -0.67945 -0.305054)
			(stroke
				(width 0.1)
				(type default)
			)
			(layer "F.Fab")
		)
		(fp_line
			(start -0.12065 0.3048)
			(end -0.67945 0.3048)
			(stroke
				(width 0.1)
				(type default)
			)
			(layer "F.Fab")
		)
		(fp_line
			(start 0.120396 0.3048)
			(end 0.120396 0.2794)
			(stroke
				(width 0.1)
				(type default)
			)
			(layer "F.Fab")
		)
		(fp_line
			(start 0.67945 0.3048)
			(end 0.120396 0.3048)
			(stroke
				(width 0.1)
				(type default)
			)
			(layer "F.Fab")
		)
		(fp_line
			(start -0.12065 0.2794)
			(end -0.12065 0.3048)
			(stroke
				(width 0.1)
				(type default)
			)
			(layer "F.Fab")
		)
		(fp_line
			(start 0.120396 0.2794)
			(end -0.12065 0.2794)
			(stroke
				(width 0.1)
				(type default)
			)
			(layer "F.Fab")
		)
		(fp_line
			(start -0.12065 -0.2794)
			(end 0.12065 -0.2794)
			(stroke
				(width 0.1)
				(type default)
			)
			(layer "F.Fab")
		)
		(fp_line
			(start 0.12065 -0.2794)
			(end 0.12065 -0.3048)
			(stroke
				(width 0.1)
				(type default)
			)
			(layer "F.Fab")
		)
		(fp_line
			(start 0.12065 -0.3048)
			(end 0.67945 -0.3048)
			(stroke
				(width 0.1)
				(type default)
			)
			(layer "F.Fab")
		)
		(fp_line
			(start 0.67945 -0.3048)
			(end 0.67945 0.3048)
			(stroke
				(width 0.1)
				(type default)
			)
			(layer "F.Fab")
		)
		(fp_line
			(start -0.67945 -0.305054)
			(end -0.12065 -0.305054)
			(stroke
				(width 0.1)
				(type default)
			)
			(layer "F.Fab")
		)
		(fp_line
			(start -0.12065 -0.305054)
			(end -0.12065 -0.2794)
			(stroke
				(width 0.1)
				(type default)
			)
			(layer "F.Fab")
		)
		(pad "1" smd circle
			(at -0.40005 0 270)
			(size 0 0)
			(layers "F.Cu" "F.Mask" "F.Paste")
			(net "OCP_V3_2_AUX_PWR_EN")
		)
		(pad "2" smd circle
			(at 0.40005 0 270)
			(size 0 0)
			(layers "F.Cu" "F.Mask" "F.Paste")
			(net "OCP_V3_2_AUX_PWR_EN_R")
		)
	)
	(footprint ""
		(layer "F.Cu")
		(at 197.876922 -76.016866)
		(property "Reference" "R77"
			(at 0 0 0)
			(layer "F.SilkS")
			(hide yes)
			(effects
				(font
					(size 1.27 1.27)
				)
			)
		)
		(property "Value" ""
			(at 0 0 0)
			(layer "F.Fab")
			(effects
				(font
					(size 1.27 1.27)
				)
			)
		)
		(duplicate_pad_numbers_are_jumpers no)
		(fp_line
			(start -0.7874 -0.4064)
			(end 0.7874 -0.4064)
			(stroke
				(width 0.1524)
				(type default)
			)
			(layer "F.SilkS")
		)
		(fp_line
			(start -0.7874 0.4064)
			(end -0.7874 -0.4064)
			(stroke
				(width 0.1524)
				(type default)
			)
			(layer "F.SilkS")
		)
		(fp_line
			(start 0.7874 -0.4064)
			(end 0.7874 0.4064)
			(stroke
				(width 0.1524)
				(type default)
			)
			(layer "F.SilkS")
		)
		(fp_line
			(start 0.7874 0.4064)
			(end -0.7874 0.4064)
			(stroke
				(width 0.1524)
				(type default)
			)
			(layer "F.SilkS")
		)
		(fp_line
			(start -0.67945 -0.305054)
			(end -0.12065 -0.305054)
			(stroke
				(width 0.1)
				(type default)
			)
			(layer "F.Fab")
		)
		(fp_line
			(start -0.67945 0.3048)
			(end -0.67945 -0.305054)
			(stroke
				(width 0.1)
				(type default)
			)
			(layer "F.Fab")
		)
		(fp_line
			(start -0.12065 -0.305054)
			(end -0.12065 -0.2794)
			(stroke
				(width 0.1)
				(type default)
			)
			(layer "F.Fab")
		)
		(fp_line
			(start -0.12065 -0.2794)
			(end 0.12065 -0.2794)
			(stroke
				(width 0.1)
				(type default)
			)
			(layer "F.Fab")
		)
		(fp_line
			(start -0.12065 0.2794)
			(end -0.12065 0.3048)
			(stroke
				(width 0.1)
				(type default)
			)
			(layer "F.Fab")
		)
		(fp_line
			(start -0.12065 0.3048)
			(end -0.67945 0.3048)
			(stroke
				(width 0.1)
				(type default)
			)
			(layer "F.Fab")
		)
		(fp_line
			(start 0.120396 0.2794)
			(end -0.12065 0.2794)
			(stroke
				(width 0.1)
				(type default)
			)
			(layer "F.Fab")
		)
		(fp_line
			(start 0.120396 0.3048)
			(end 0.120396 0.2794)
			(stroke
				(width 0.1)
				(type default)
			)
			(layer "F.Fab")
		)
		(fp_line
			(start 0.12065 -0.3048)
			(end 0.67945 -0.3048)
			(stroke
				(width 0.1)
				(type default)
			)
			(layer "F.Fab")
		)
		(fp_line
			(start 0.12065 -0.2794)
			(end 0.12065 -0.3048)
			(stroke
				(width 0.1)
				(type default)
			)
			(layer "F.Fab")
		)
		(fp_line
			(start 0.67945 -0.3048)
			(end 0.67945 0.3048)
			(stroke
				(width 0.1)
				(type default)
			)
			(layer "F.Fab")
		)
		(fp_line
			(start 0.67945 0.3048)
			(end 0.120396 0.3048)
			(stroke
				(width 0.1)
				(type default)
			)
			(layer "F.Fab")
		)
		(pad "1" smd circle
			(at -0.40005 0)
			(size 0 0)
			(layers "F.Cu" "F.Mask" "F.Paste")
			(net "RMII_OCP_BMC_CRSDV")
		)
		(pad "2" smd circle
			(at 0.40005 0)
			(size 0 0)
			(layers "F.Cu" "F.Mask" "F.Paste")
			(net "GND")
		)
	)
	(footprint ""
		(layer "F.Cu")
		(at 170.46956 -387.763004 180)
		(property "Reference" "R852"
			(at 0 0 180)
			(layer "F.SilkS")
			(hide yes)
			(effects
				(font
					(size 1.27 1.27)
				)
			)
		)
		(property "Value" ""
			(at 0 0 180)
			(layer "F.Fab")
			(effects
				(font
					(size 1.27 1.27)
				)
			)
		)
		(duplicate_pad_numbers_are_jumpers no)
		(fp_line
			(start 0.7874 0.4064)
			(end -0.7874 0.4064)
			(stroke
				(width 0.1524)
				(type default)
			)
			(layer "F.SilkS")
		)
		(fp_line
			(start 0.7874 -0.4064)
			(end 0.7874 0.4064)
			(stroke
				(width 0.1524)
				(type default)
			)
			(layer "F.SilkS")
		)
		(fp_line
			(start -0.7874 0.4064)
			(end -0.7874 -0.4064)
			(stroke
				(width 0.1524)
				(type default)
			)
			(layer "F.SilkS")
		)
		(fp_line
			(start -0.7874 -0.4064)
			(end 0.7874 -0.4064)
			(stroke
				(width 0.1524)
				(type default)
			)
			(layer "F.SilkS")
		)
		(fp_line
			(start 0.67945 0.3048)
			(end 0.120396 0.3048)
			(stroke
				(width 0.1)
				(type default)
			)
			(layer "F.Fab")
		)
		(fp_line
			(start 0.67945 -0.3048)
			(end 0.67945 0.3048)
			(stroke
				(width 0.1)
				(type default)
			)
			(layer "F.Fab")
		)
		(fp_line
			(start 0.12065 -0.2794)
			(end 0.12065 -0.3048)
			(stroke
				(width 0.1)
				(type default)
			)
			(layer "F.Fab")
		)
		(fp_line
			(start 0.12065 -0.3048)
			(end 0.67945 -0.3048)
			(stroke
				(width 0.1)
				(type default)
			)
			(layer "F.Fab")
		)
		(fp_line
			(start 0.120396 0.3048)
			(end 0.120396 0.2794)
			(stroke
				(width 0.1)
				(type default)
			)
			(layer "F.Fab")
		)
		(fp_line
			(start 0.120396 0.2794)
			(end -0.12065 0.2794)
			(stroke
				(width 0.1)
				(type default)
			)
			(layer "F.Fab")
		)
		(fp_line
			(start -0.12065 0.3048)
			(end -0.67945 0.3048)
			(stroke
				(width 0.1)
				(type default)
			)
			(layer "F.Fab")
		)
		(fp_line
			(start -0.12065 0.2794)
			(end -0.12065 0.3048)
			(stroke
				(width 0.1)
				(type default)
			)
			(layer "F.Fab")
		)
		(fp_line
			(start -0.12065 -0.2794)
			(end 0.12065 -0.2794)
			(stroke
				(width 0.1)
				(type default)
			)
			(layer "F.Fab")
		)
		(fp_line
			(start -0.12065 -0.305054)
			(end -0.12065 -0.2794)
			(stroke
				(width 0.1)
				(type default)
			)
			(layer "F.Fab")
		)
		(fp_line
			(start -0.67945 0.3048)
			(end -0.67945 -0.305054)
			(stroke
				(width 0.1)
				(type default)
			)
			(layer "F.Fab")
		)
		(fp_line
			(start -0.67945 -0.305054)
			(end -0.12065 -0.305054)
			(stroke
				(width 0.1)
				(type default)
			)
			(layer "F.Fab")
		)
		(pad "1" smd rect
			(at -0.40005 0)
			(size 0.4572 0.508)
			(layers "F.Cu" "F.Mask" "F.Paste")
			(net "P1V8_CPU1_RT2_1A_1D")
		)
		(pad "2" smd rect
			(at 0.40005 0)
			(size 0.4572 0.508)
			(layers "F.Cu" "F.Mask" "F.Paste")
			(net "P1V8_CPU1_RT2_1A")
		)
	)
	(footprint ""
		(layer "F.Cu")
		(at 137.955274 -31.70682 90)
		(property "Reference" "R6203"
			(at 0 0 90)
			(layer "F.SilkS")
			(hide yes)
			(effects
				(font
					(size 1.27 1.27)
				)
			)
		)
		(property "Value" ""
			(at 0 0 90)
			(layer "F.Fab")
			(effects
				(font
					(size 1.27 1.27)
				)
			)
		)
		(duplicate_pad_numbers_are_jumpers no)
		(fp_line
			(start 0.7874 -0.4064)
			(end 0.7874 0.4064)
			(stroke
				(width 0.1524)
				(type default)
			)
			(layer "F.SilkS")
		)
		(fp_line
			(start -0.7874 -0.4064)
			(end 0.7874 -0.4064)
			(stroke
				(width 0.1524)
				(type default)
			)
			(layer "F.SilkS")
		)
		(fp_line
			(start 0.7874 0.4064)
			(end -0.7874 0.4064)
			(stroke
				(width 0.1524)
				(type default)
			)
			(layer "F.SilkS")
		)
		(fp_line
			(start -0.7874 0.4064)
			(end -0.7874 -0.4064)
			(stroke
				(width 0.1524)
				(type default)
			)
			(layer "F.SilkS")
		)
		(fp_line
			(start -0.12065 -0.305054)
			(end -0.12065 -0.2794)
			(stroke
				(width 0.1)
				(type default)
			)
			(layer "F.Fab")
		)
		(fp_line
			(start -0.67945 -0.305054)
			(end -0.12065 -0.305054)
			(stroke
				(width 0.1)
				(type default)
			)
			(layer "F.Fab")
		)
		(fp_line
			(start 0.67945 -0.3048)
			(end 0.67945 0.3048)
			(stroke
				(width 0.1)
				(type default)
			)
			(layer "F.Fab")
		)
		(fp_line
			(start 0.12065 -0.3048)
			(end 0.67945 -0.3048)
			(stroke
				(width 0.1)
				(type default)
			)
			(layer "F.Fab")
		)
		(fp_line
			(start 0.12065 -0.2794)
			(end 0.12065 -0.3048)
			(stroke
				(width 0.1)
				(type default)
			)
			(layer "F.Fab")
		)
		(fp_line
			(start -0.12065 -0.2794)
			(end 0.12065 -0.2794)
			(stroke
				(width 0.1)
				(type default)
			)
			(layer "F.Fab")
		)
		(fp_line
			(start 0.120396 0.2794)
			(end -0.12065 0.2794)
			(stroke
				(width 0.1)
				(type default)
			)
			(layer "F.Fab")
		)
		(fp_line
			(start -0.12065 0.2794)
			(end -0.12065 0.3048)
			(stroke
				(width 0.1)
				(type default)
			)
			(layer "F.Fab")
		)
		(fp_line
			(start 0.67945 0.3048)
			(end 0.120396 0.3048)
			(stroke
				(width 0.1)
				(type default)
			)
			(layer "F.Fab")
		)
		(fp_line
			(start 0.120396 0.3048)
			(end 0.120396 0.2794)
			(stroke
				(width 0.1)
				(type default)
			)
			(layer "F.Fab")
		)
		(fp_line
			(start -0.12065 0.3048)
			(end -0.67945 0.3048)
			(stroke
				(width 0.1)
				(type default)
			)
			(layer "F.Fab")
		)
		(fp_line
			(start -0.67945 0.3048)
			(end -0.67945 -0.305054)
			(stroke
				(width 0.1)
				(type default)
			)
			(layer "F.Fab")
		)
		(pad "1" smd circle
			(at -0.40005 0 90)
			(size 0 0)
			(layers "F.Cu" "F.Mask" "F.Paste")
			(net "GND")
		)
		(pad "2" smd circle
			(at 0.40005 0 90)
			(size 0 0)
			(layers "F.Cu" "F.Mask" "F.Paste")
			(net "USB_CPU0_HUB1_RREF_USB2")
		)
	)
	(footprint ""
		(layer "F.Cu")
		(at 191.295782 -29.283152 180)
		(property "Reference" "PC2236"
			(at 0 0 180)
			(layer "F.SilkS")
			(hide yes)
			(effects
				(font
					(size 1.27 1.27)
				)
			)
		)
		(property "Value" ""
			(at 0 0 180)
			(layer "F.Fab")
			(effects
				(font
					(size 1.27 1.27)
				)
			)
		)
		(duplicate_pad_numbers_are_jumpers no)
		(fp_line
			(start 0.7874 0.4064)
			(end -0.7874 0.4064)
			(stroke
				(width 0.1524)
				(type default)
			)
			(layer "F.SilkS")
		)
		(fp_line
			(start 0.7874 -0.4064)
			(end 0.7874 0.4064)
			(stroke
				(width 0.1524)
				(type default)
			)
			(layer "F.SilkS")
		)
		(fp_line
			(start -0.7874 0.4064)
			(end -0.7874 -0.4064)
			(stroke
				(width 0.1524)
				(type default)
			)
			(layer "F.SilkS")
		)
		(fp_line
			(start -0.7874 -0.4064)
			(end 0.7874 -0.4064)
			(stroke
				(width 0.1524)
				(type default)
			)
			(layer "F.SilkS")
		)
		(fp_line
			(start 0.67945 0.3048)
			(end 0.120396 0.3048)
			(stroke
				(width 0.1)
				(type default)
			)
			(layer "F.Fab")
		)
		(fp_line
			(start 0.67945 -0.3048)
			(end 0.67945 0.3048)
			(stroke
				(width 0.1)
				(type default)
			)
			(layer "F.Fab")
		)
		(fp_line
			(start 0.12065 -0.2794)
			(end 0.12065 -0.3048)
			(stroke
				(width 0.1)
				(type default)
			)
			(layer "F.Fab")
		)
		(fp_line
			(start 0.12065 -0.3048)
			(end 0.67945 -0.3048)
			(stroke
				(width 0.1)
				(type default)
			)
			(layer "F.Fab")
		)
		(fp_line
			(start 0.120396 0.3048)
			(end 0.120396 0.2794)
			(stroke
				(width 0.1)
				(type default)
			)
			(layer "F.Fab")
		)
		(fp_line
			(start 0.120396 0.2794)
			(end -0.12065 0.2794)
			(stroke
				(width 0.1)
				(type default)
			)
			(layer "F.Fab")
		)
		(fp_line
			(start -0.12065 0.3048)
			(end -0.67945 0.3048)
			(stroke
				(width 0.1)
				(type default)
			)
			(layer "F.Fab")
		)
		(fp_line
			(start -0.12065 0.2794)
			(end -0.12065 0.3048)
			(stroke
				(width 0.1)
				(type default)
			)
			(layer "F.Fab")
		)
		(fp_line
			(start -0.12065 -0.2794)
			(end 0.12065 -0.2794)
			(stroke
				(width 0.1)
				(type default)
			)
			(layer "F.Fab")
		)
		(fp_line
			(start -0.12065 -0.305054)
			(end -0.12065 -0.2794)
			(stroke
				(width 0.1)
				(type default)
			)
			(layer "F.Fab")
		)
		(fp_line
			(start -0.67945 0.3048)
			(end -0.67945 -0.305054)
			(stroke
				(width 0.1)
				(type default)
			)
			(layer "F.Fab")
		)
		(fp_line
			(start -0.67945 -0.305054)
			(end -0.12065 -0.305054)
			(stroke
				(width 0.1)
				(type default)
			)
			(layer "F.Fab")
		)
		(pad "1" smd circle
			(at -0.40005 0 180)
			(size 0 0)
			(layers "F.Cu" "F.Mask" "F.Paste")
			(net "P12V_SCM_R")
		)
		(pad "2" smd circle
			(at 0.40005 0 180)
			(size 0 0)
			(layers "F.Cu" "F.Mask" "F.Paste")
			(net "P12V_SCM_GATE")
		)
	)
	(footprint ""
		(layer "F.Cu")
		(at 131.64058 -27.52598 90)
		(property "Reference" "R6191"
			(at 0 0 90)
			(layer "F.SilkS")
			(hide yes)
			(effects
				(font
					(size 1.27 1.27)
				)
			)
		)
		(property "Value" ""
			(at 0 0 90)
			(layer "F.Fab")
			(effects
				(font
					(size 1.27 1.27)
				)
			)
		)
		(duplicate_pad_numbers_are_jumpers no)
		(fp_line
			(start 0.32512 -0.175006)
			(end 0.32512 0.175006)
			(stroke
				(width 0.1)
				(type default)
			)
			(layer "F.Fab")
		)
		(fp_line
			(start -0.32512 -0.175006)
			(end 0.32512 -0.175006)
			(stroke
				(width 0.1)
				(type default)
			)
			(layer "F.Fab")
		)
		(fp_line
			(start 0.32512 0.175006)
			(end -0.32512 0.175006)
			(stroke
				(width 0.1)
				(type default)
			)
			(layer "F.Fab")
		)
		(fp_line
			(start -0.32512 0.175006)
			(end -0.32512 -0.175006)
			(stroke
				(width 0.1)
				(type default)
			)
			(layer "F.Fab")
		)
		(pad "1" smd rect
			(at -0.2667 0 90)
			(size 0.3048 0.381)
			(layers "F.Cu" "F.Mask" "F.Paste")
			(net "USB2_CPU0_P0_DN")
		)
		(pad "2" smd rect
			(at 0.2667 0 270)
			(size 0.3048 0.381)
			(layers "F.Cu" "F.Mask" "F.Paste")
			(net "USB2_CPU0_P0_R1_DN")
		)
	)
	(footprint ""
		(layer "F.Cu")
		(at 265.006074 -140.624814 180)
		(property "Reference" "R8006"
			(at 0 0 180)
			(layer "F.SilkS")
			(hide yes)
			(effects
				(font
					(size 1.27 1.27)
				)
			)
		)
		(property "Value" ""
			(at 0 0 180)
			(layer "F.Fab")
			(effects
				(font
					(size 1.27 1.27)
				)
			)
		)
		(duplicate_pad_numbers_are_jumpers no)
		(fp_line
			(start 0.7874 0.4064)
			(end -0.7874 0.4064)
			(stroke
				(width 0.1524)
				(type default)
			)
			(layer "F.SilkS")
		)
		(fp_line
			(start 0.7874 -0.4064)
			(end 0.7874 0.4064)
			(stroke
				(width 0.1524)
				(type default)
			)
			(layer "F.SilkS")
		)
		(fp_line
			(start -0.7874 0.4064)
			(end -0.7874 -0.4064)
			(stroke
				(width 0.1524)
				(type default)
			)
			(layer "F.SilkS")
		)
		(fp_line
			(start -0.7874 -0.4064)
			(end 0.7874 -0.4064)
			(stroke
				(width 0.1524)
				(type default)
			)
			(layer "F.SilkS")
		)
		(fp_line
			(start 0.67945 0.3048)
			(end 0.120396 0.3048)
			(stroke
				(width 0.1)
				(type default)
			)
			(layer "F.Fab")
		)
		(fp_line
			(start 0.67945 -0.3048)
			(end 0.67945 0.3048)
			(stroke
				(width 0.1)
				(type default)
			)
			(layer "F.Fab")
		)
		(fp_line
			(start 0.12065 -0.2794)
			(end 0.12065 -0.3048)
			(stroke
				(width 0.1)
				(type default)
			)
			(layer "F.Fab")
		)
		(fp_line
			(start 0.12065 -0.3048)
			(end 0.67945 -0.3048)
			(stroke
				(width 0.1)
				(type default)
			)
			(layer "F.Fab")
		)
		(fp_line
			(start 0.120396 0.3048)
			(end 0.120396 0.2794)
			(stroke
				(width 0.1)
				(type default)
			)
			(layer "F.Fab")
		)
		(fp_line
			(start 0.120396 0.2794)
			(end -0.12065 0.2794)
			(stroke
				(width 0.1)
				(type default)
			)
			(layer "F.Fab")
		)
		(fp_line
			(start -0.12065 0.3048)
			(end -0.67945 0.3048)
			(stroke
				(width 0.1)
				(type default)
			)
			(layer "F.Fab")
		)
		(fp_line
			(start -0.12065 0.2794)
			(end -0.12065 0.3048)
			(stroke
				(width 0.1)
				(type default)
			)
			(layer "F.Fab")
		)
		(fp_line
			(start -0.12065 -0.2794)
			(end 0.12065 -0.2794)
			(stroke
				(width 0.1)
				(type default)
			)
			(layer "F.Fab")
		)
		(fp_line
			(start -0.12065 -0.305054)
			(end -0.12065 -0.2794)
			(stroke
				(width 0.1)
				(type default)
			)
			(layer "F.Fab")
		)
		(fp_line
			(start -0.67945 0.3048)
			(end -0.67945 -0.305054)
			(stroke
				(width 0.1)
				(type default)
			)
			(layer "F.Fab")
		)
		(fp_line
			(start -0.67945 -0.305054)
			(end -0.12065 -0.305054)
			(stroke
				(width 0.1)
				(type default)
			)
			(layer "F.Fab")
		)
		(pad "1" smd circle
			(at -0.40005 0 180)
			(size 0 0)
			(layers "F.Cu" "F.Mask" "F.Paste")
			(net "SPI_CPU0_D2")
		)
		(pad "2" smd circle
			(at 0.40005 0 180)
			(size 0 0)
			(layers "F.Cu" "F.Mask" "F.Paste")
			(net "SPI_CPU0_R1_D2")
		)
	)
	(footprint ""
		(layer "F.Cu")
		(at 153.416508 -43.61053)
		(property "Reference" "U98"
			(at -1.397 -2.13233 0)
			(unlocked yes)
			(layer "F.SilkS")
			(effects
				(font
					(size 0.7874 0.5842)
					(thickness 0.1524)
				)
				(justify left)
			)
		)
		(property "Value" ""
			(at 0 0 0)
			(layer "F.Fab")
			(effects
				(font
					(size 1.27 1.27)
				)
			)
		)
		(duplicate_pad_numbers_are_jumpers no)
		(fp_line
			(start -1.3208 -1.525016)
			(end -0.508 -1.525016)
			(stroke
				(width 0.1524)
				(type default)
			)
			(layer "F.SilkS")
		)
		(fp_line
			(start -1.3208 1.525016)
			(end -1.3208 -1.525016)
			(stroke
				(width 0.1524)
				(type default)
			)
			(layer "F.SilkS")
		)
		(fp_line
			(start -0.508 -1.525016)
			(end 0 -0.999998)
			(stroke
				(width 0.1524)
				(type default)
			)
			(layer "F.SilkS")
		)
		(fp_line
			(start 0 -0.999998)
			(end 0.508 -1.525016)
			(stroke
				(width 0.1524)
				(type default)
			)
			(layer "F.SilkS")
		)
		(fp_line
			(start 0.508 -1.525016)
			(end 1.3208 -1.525016)
			(stroke
				(width 0.1524)
				(type default)
			)
			(layer "F.SilkS")
		)
		(fp_line
			(start 1.3208 -1.525016)
			(end 1.3208 1.525016)
			(stroke
				(width 0.1524)
				(type default)
			)
			(layer "F.SilkS")
		)
		(fp_line
			(start 1.3208 1.525016)
			(end -1.3208 1.525016)
			(stroke
				(width 0.1524)
				(type default)
			)
			(layer "F.SilkS")
		)
		(fp_poly
			(pts
				(xy -2.176018 -2.256282) (xy -2.557018 -1.494282) (xy -2.938018 -2.256282)
			)
			(stroke
				(width 0)
				(type default)
			)
			(fill yes)
			(layer "F.SilkS")
		)
		(fp_line
			(start -3.037078 -1.20777)
			(end -1.524 -1.20777)
			(stroke
				(width 0.1)
				(type default)
			)
			(layer "F.Fab")
		)
		(fp_line
			(start -3.037078 1.203706)
			(end -3.037078 -1.20777)
			(stroke
				(width 0.1)
				(type default)
			)
			(layer "F.Fab")
		)
		(fp_line
			(start -1.5494 1.203706)
			(end -3.037078 1.203706)
			(stroke
				(width 0.1)
				(type default)
			)
			(layer "F.Fab")
		)
		(fp_line
			(start -1.5494 1.5494)
			(end -1.5494 1.203706)
			(stroke
				(width 0.1)
				(type default)
			)
			(layer "F.Fab")
		)
		(fp_line
			(start -1.524 -1.524)
			(end 1.524 -1.524)
			(stroke
				(width 0.1)
				(type default)
			)
			(layer "F.Fab")
		)
		(fp_line
			(start -1.524 -1.20777)
			(end -1.524 -1.524)
			(stroke
				(width 0.1)
				(type default)
			)
			(layer "F.Fab")
		)
		(fp_line
			(start 1.524 -1.524)
			(end 1.524 -1.20777)
			(stroke
				(width 0.1)
				(type default)
			)
			(layer "F.Fab")
		)
		(fp_line
			(start 1.524 -1.20777)
			(end 3.0353 -1.20777)
			(stroke
				(width 0.1)
				(type default)
			)
			(layer "F.Fab")
		)
		(fp_line
			(start 1.524 1.208786)
			(end 1.524 1.5494)
			(stroke
				(width 0.1)
				(type default)
			)
			(layer "F.Fab")
		)
		(fp_line
			(start 1.524 1.5494)
			(end -1.5494 1.5494)
			(stroke
				(width 0.1)
				(type default)
			)
			(layer "F.Fab")
		)
		(fp_line
			(start 3.0353 -1.20777)
			(end 3.0353 1.208786)
			(stroke
				(width 0.1)
				(type default)
			)
			(layer "F.Fab")
		)
		(fp_line
			(start 3.0353 1.208786)
			(end 1.524 1.208786)
			(stroke
				(width 0.1)
				(type default)
			)
			(layer "F.Fab")
		)
		(fp_poly
			(pts
				(xy -3.175 -1.016) (xy -3.937 -0.635) (xy -3.937 -1.397)
			)
			(stroke
				(width 0)
				(type default)
			)
			(fill yes)
			(layer "F.Fab")
		)
		(pad "1" smd rect
			(at -2.234946 -0.975106 270)
			(size 0.3556 1.4986)
			(layers "F.Cu" "F.Mask" "F.Paste")
			(net "GND")
		)
		(pad "2" smd rect
			(at -2.234946 -0.32512 270)
			(size 0.3556 1.4986)
			(layers "F.Cu" "F.Mask" "F.Paste")
			(net "P1V8_AUX")
		)
		(pad "3" smd rect
			(at -2.234946 0.32512 270)
			(size 0.3556 1.4986)
			(layers "F.Cu" "F.Mask" "F.Paste")
			(net "SMB_M2_P1_1V8AUX_SCL_R")
		)
		(pad "4" smd rect
			(at -2.234946 0.975106 270)
			(size 0.3556 1.4986)
			(layers "F.Cu" "F.Mask" "F.Paste")
			(net "SMB_M2_P1_1V8AUX_SDA_R")
		)
		(pad "5" smd rect
			(at 2.234946 0.975106 270)
			(size 0.3556 1.4986)
			(layers "F.Cu" "F.Mask" "F.Paste")
			(net "SMB_SENSOR_M2_P1_3V3AUX_SDA")
		)
		(pad "6" smd rect
			(at 2.234946 0.32512 270)
			(size 0.3556 1.4986)
			(layers "F.Cu" "F.Mask" "F.Paste")
			(net "SMB_SENSOR_M2_P1_3V3AUX_SCL")
		)
		(pad "7" smd rect
			(at 2.234946 -0.32512 270)
			(size 0.3556 1.4986)
			(layers "F.Cu" "F.Mask" "F.Paste")
			(net "SMB_PCIE_M2_0_EN")
		)
		(pad "8" smd rect
			(at 2.234946 -0.975106 270)
			(size 0.3556 1.4986)
			(layers "F.Cu" "F.Mask" "F.Paste")
			(net "SMB_PCIE_M2_0_EN")
		)
	)
	(footprint ""
		(layer "F.Cu")
		(at 102.767892 -185.697368)
		(property "Reference" "PC316"
			(at 0 0 0)
			(layer "F.SilkS")
			(hide yes)
			(effects
				(font
					(size 1.27 1.27)
				)
			)
		)
		(property "Value" ""
			(at 0 0 0)
			(layer "F.Fab")
			(effects
				(font
					(size 1.27 1.27)
				)
			)
		)
		(duplicate_pad_numbers_are_jumpers no)
		(fp_line
			(start -0.7874 -0.4064)
			(end 0.7874 -0.4064)
			(stroke
				(width 0.1524)
				(type default)
			)
			(layer "F.SilkS")
		)
		(fp_line
			(start -0.7874 0.4064)
			(end -0.7874 -0.4064)
			(stroke
				(width 0.1524)
				(type default)
			)
			(layer "F.SilkS")
		)
		(fp_line
			(start 0.7874 -0.4064)
			(end 0.7874 0.4064)
			(stroke
				(width 0.1524)
				(type default)
			)
			(layer "F.SilkS")
		)
		(fp_line
			(start 0.7874 0.4064)
			(end -0.7874 0.4064)
			(stroke
				(width 0.1524)
				(type default)
			)
			(layer "F.SilkS")
		)
		(fp_line
			(start -0.67945 -0.305054)
			(end -0.12065 -0.305054)
			(stroke
				(width 0.1)
				(type default)
			)
			(layer "F.Fab")
		)
		(fp_line
			(start -0.67945 0.3048)
			(end -0.67945 -0.305054)
			(stroke
				(width 0.1)
				(type default)
			)
			(layer "F.Fab")
		)
		(fp_line
			(start -0.12065 -0.305054)
			(end -0.12065 -0.2794)
			(stroke
				(width 0.1)
				(type default)
			)
			(layer "F.Fab")
		)
		(fp_line
			(start -0.12065 -0.2794)
			(end 0.12065 -0.2794)
			(stroke
				(width 0.1)
				(type default)
			)
			(layer "F.Fab")
		)
		(fp_line
			(start -0.12065 0.2794)
			(end -0.12065 0.3048)
			(stroke
				(width 0.1)
				(type default)
			)
			(layer "F.Fab")
		)
		(fp_line
			(start -0.12065 0.3048)
			(end -0.67945 0.3048)
			(stroke
				(width 0.1)
				(type default)
			)
			(layer "F.Fab")
		)
		(fp_line
			(start 0.120396 0.2794)
			(end -0.12065 0.2794)
			(stroke
				(width 0.1)
				(type default)
			)
			(layer "F.Fab")
		)
		(fp_line
			(start 0.120396 0.3048)
			(end 0.120396 0.2794)
			(stroke
				(width 0.1)
				(type default)
			)
			(layer "F.Fab")
		)
		(fp_line
			(start 0.12065 -0.3048)
			(end 0.67945 -0.3048)
			(stroke
				(width 0.1)
				(type default)
			)
			(layer "F.Fab")
		)
		(fp_line
			(start 0.12065 -0.2794)
			(end 0.12065 -0.3048)
			(stroke
				(width 0.1)
				(type default)
			)
			(layer "F.Fab")
		)
		(fp_line
			(start 0.67945 -0.3048)
			(end 0.67945 0.3048)
			(stroke
				(width 0.1)
				(type default)
			)
			(layer "F.Fab")
		)
		(fp_line
			(start 0.67945 0.3048)
			(end 0.120396 0.3048)
			(stroke
				(width 0.1)
				(type default)
			)
			(layer "F.Fab")
		)
		(pad "1" smd circle
			(at -0.40005 0)
			(size 0 0)
			(layers "F.Cu" "F.Mask" "F.Paste")
			(net "SW_PVDDCR_CPU0_P1_SW3")
		)
		(pad "2" smd circle
			(at 0.40005 0)
			(size 0 0)
			(layers "F.Cu" "F.Mask" "F.Paste")
			(net "SW_PVDDCR_CPU0_P1_SW3_RC")
		)
	)
	(footprint ""
		(layer "F.Cu")
		(at 463.735928 -93.309186)
		(property "Reference" "R3232"
			(at 0 0 0)
			(layer "F.SilkS")
			(hide yes)
			(effects
				(font
					(size 1.27 1.27)
				)
			)
		)
		(property "Value" ""
			(at 0 0 0)
			(layer "F.Fab")
			(effects
				(font
					(size 1.27 1.27)
				)
			)
		)
		(duplicate_pad_numbers_are_jumpers no)
		(fp_line
			(start -0.7874 -0.4064)
			(end 0.7874 -0.4064)
			(stroke
				(width 0.1524)
				(type default)
			)
			(layer "F.SilkS")
		)
		(fp_line
			(start -0.7874 0.4064)
			(end -0.7874 -0.4064)
			(stroke
				(width 0.1524)
				(type default)
			)
			(layer "F.SilkS")
		)
		(fp_line
			(start 0.7874 -0.4064)
			(end 0.7874 0.4064)
			(stroke
				(width 0.1524)
				(type default)
			)
			(layer "F.SilkS")
		)
		(fp_line
			(start 0.7874 0.4064)
			(end -0.7874 0.4064)
			(stroke
				(width 0.1524)
				(type default)
			)
			(layer "F.SilkS")
		)
		(fp_line
			(start -0.67945 -0.305054)
			(end -0.12065 -0.305054)
			(stroke
				(width 0.1)
				(type default)
			)
			(layer "F.Fab")
		)
		(fp_line
			(start -0.67945 0.3048)
			(end -0.67945 -0.305054)
			(stroke
				(width 0.1)
				(type default)
			)
			(layer "F.Fab")
		)
		(fp_line
			(start -0.12065 -0.305054)
			(end -0.12065 -0.2794)
			(stroke
				(width 0.1)
				(type default)
			)
			(layer "F.Fab")
		)
		(fp_line
			(start -0.12065 -0.2794)
			(end 0.12065 -0.2794)
			(stroke
				(width 0.1)
				(type default)
			)
			(layer "F.Fab")
		)
		(fp_line
			(start -0.12065 0.2794)
			(end -0.12065 0.3048)
			(stroke
				(width 0.1)
				(type default)
			)
			(layer "F.Fab")
		)
		(fp_line
			(start -0.12065 0.3048)
			(end -0.67945 0.3048)
			(stroke
				(width 0.1)
				(type default)
			)
			(layer "F.Fab")
		)
		(fp_line
			(start 0.120396 0.2794)
			(end -0.12065 0.2794)
			(stroke
				(width 0.1)
				(type default)
			)
			(layer "F.Fab")
		)
		(fp_line
			(start 0.120396 0.3048)
			(end 0.120396 0.2794)
			(stroke
				(width 0.1)
				(type default)
			)
			(layer "F.Fab")
		)
		(fp_line
			(start 0.12065 -0.3048)
			(end 0.67945 -0.3048)
			(stroke
				(width 0.1)
				(type default)
			)
			(layer "F.Fab")
		)
		(fp_line
			(start 0.12065 -0.2794)
			(end 0.12065 -0.3048)
			(stroke
				(width 0.1)
				(type default)
			)
			(layer "F.Fab")
		)
		(fp_line
			(start 0.67945 -0.3048)
			(end 0.67945 0.3048)
			(stroke
				(width 0.1)
				(type default)
			)
			(layer "F.Fab")
		)
		(fp_line
			(start 0.67945 0.3048)
			(end 0.120396 0.3048)
			(stroke
				(width 0.1)
				(type default)
			)
			(layer "F.Fab")
		)
		(pad "1" smd circle
			(at -0.40005 0)
			(size 0 0)
			(layers "F.Cu" "F.Mask" "F.Paste")
			(net "RST_HP_OCP_SFF_R_N")
		)
		(pad "2" smd circle
			(at 0.40005 0)
			(size 0 0)
			(layers "F.Cu" "F.Mask" "F.Paste")
			(net "GND")
		)
	)
	(footprint ""
		(layer "F.Cu")
		(at 129.084832 -75.466956)
		(property "Reference" "PL6001"
			(at -5.210048 -5.253482 0)
			(unlocked yes)
			(layer "F.SilkS")
			(effects
				(font
					(size 0.7874 0.5842)
					(thickness 0.1524)
				)
				(justify left)
			)
		)
		(property "Value" ""
			(at 0 0 0)
			(layer "F.Fab")
			(effects
				(font
					(size 1.27 1.27)
				)
			)
		)
		(duplicate_pad_numbers_are_jumpers no)
		(fp_line
			(start -3.6576 -3.350006)
			(end 3.64998 -3.350006)
			(stroke
				(width 0.1524)
				(type default)
			)
			(layer "F.SilkS")
		)
		(fp_line
			(start -3.64998 -1.8034)
			(end -3.64998 -3.350006)
			(stroke
				(width 0.1524)
				(type default)
			)
			(layer "F.SilkS")
		)
		(fp_line
			(start -3.64998 3.350006)
			(end -3.64998 1.8288)
			(stroke
				(width 0.1524)
				(type default)
			)
			(layer "F.SilkS")
		)
		(fp_line
			(start 3.64998 -3.350006)
			(end 3.64998 -1.8034)
			(stroke
				(width 0.1524)
				(type default)
			)
			(layer "F.SilkS")
		)
		(fp_line
			(start 3.64998 1.8034)
			(end 3.64998 3.350006)
			(stroke
				(width 0.1524)
				(type default)
			)
			(layer "F.SilkS")
		)
		(fp_line
			(start 3.64998 3.350006)
			(end -3.64998 3.350006)
			(stroke
				(width 0.1524)
				(type default)
			)
			(layer "F.SilkS")
		)
		(fp_line
			(start -3.64998 -3.350006)
			(end 3.64998 -3.350006)
			(stroke
				(width 0.1)
				(type default)
			)
			(layer "F.Fab")
		)
		(fp_line
			(start -3.64998 3.350006)
			(end -3.64998 -3.350006)
			(stroke
				(width 0.1)
				(type default)
			)
			(layer "F.Fab")
		)
		(fp_line
			(start 3.64998 -3.350006)
			(end 3.64998 3.350006)
			(stroke
				(width 0.1)
				(type default)
			)
			(layer "F.Fab")
		)
		(fp_line
			(start 3.64998 3.350006)
			(end -3.64998 3.350006)
			(stroke
				(width 0.1)
				(type default)
			)
			(layer "F.Fab")
		)
		(pad "1" smd rect
			(at -2.92481 0)
			(size 2.15392 3.302)
			(layers "F.Cu" "F.Mask" "F.Paste")
			(net "SW_P1V2_AUX_PH")
		)
		(pad "2" smd rect
			(at 2.92481 0)
			(size 2.15392 3.302)
			(layers "F.Cu" "F.Mask" "F.Paste")
			(net "P1V2_AUX")
		)
	)
	(footprint ""
		(layer "F.Cu")
		(at 378.449078 -356.362508 180)
		(property "Reference" ""
			(at 0 0 180)
			(layer "F.SilkS")
			(hide yes)
			(effects
				(font
					(size 1.27 1.27)
				)
			)
		)
		(property "Value" ""
			(at 0 0 180)
			(layer "F.Fab")
			(effects
				(font
					(size 1.27 1.27)
				)
			)
		)
		(duplicate_pad_numbers_are_jumpers no)
		(pad "1" smd circle
			(at 0 0 180)
			(size 0.9906 0.9906)
			(layers "F.Cu" "F.Mask" "F.Paste")
			(net "Net_47")
		)
		(zone
			(layer "F.Cu")
			(hatch none 0.5)
			(connect_pads
				(clearance 0)
			)
			(min_thickness 0.25)
			(keepout
				(tracks not_allowed)
				(vias allowed)
				(pads allowed)
				(copperpour not_allowed)
				(footprints allowed)
			)
			(placement
				(enabled no)
				(sheetname "")
			)
			(fill
				(thermal_gap 0.5)
				(thermal_bridge_width 0.5)
				(island_removal_mode 0)
			)
			(polygon
				(pts
					(arc
						(start 380.074678 -356.362508)
						(mid 376.823478 -356.362508)
						(end 380.074678 -356.362508)
					)
				)
			)
		)
	)
	(footprint ""
		(layer "F.Cu")
		(at 363.044486 -406.172416 180)
		(property "Reference" "Q9002"
			(at -3.329432 -1.883156 90)
			(unlocked yes)
			(layer "F.SilkS")
			(effects
				(font
					(size 0.7874 0.5842)
					(thickness 0.1524)
				)
				(justify left)
			)
		)
		(property "Value" ""
			(at 0 0 180)
			(layer "F.Fab")
			(effects
				(font
					(size 1.27 1.27)
				)
			)
		)
		(duplicate_pad_numbers_are_jumpers no)
		(fp_line
			(start 1.332738 1.100074)
			(end -1.332738 1.100074)
			(stroke
				(width 0.1524)
				(type default)
			)
			(layer "F.SilkS")
		)
		(fp_line
			(start 1.332738 -1.100074)
			(end 1.332738 1.100074)
			(stroke
				(width 0.1524)
				(type default)
			)
			(layer "F.SilkS")
		)
		(fp_line
			(start 0.4826 -1.100074)
			(end 1.332738 -1.100074)
			(stroke
				(width 0.1524)
				(type default)
			)
			(layer "F.SilkS")
		)
		(fp_line
			(start 0 -0.541274)
			(end 0.4826 -1.100074)
			(stroke
				(width 0.1524)
				(type default)
			)
			(layer "F.SilkS")
		)
		(fp_line
			(start -0.4826 -1.100074)
			(end 0 -0.541274)
			(stroke
				(width 0.1524)
				(type default)
			)
			(layer "F.SilkS")
		)
		(fp_line
			(start -1.332738 1.100074)
			(end -1.332738 -1.100074)
			(stroke
				(width 0.1524)
				(type default)
			)
			(layer "F.SilkS")
		)
		(fp_line
			(start -1.332738 -1.100074)
			(end -0.4826 -1.100074)
			(stroke
				(width 0.1524)
				(type default)
			)
			(layer "F.SilkS")
		)
		(fp_poly
			(pts
				(xy -2.659634 -0.318262) (xy -2.659634 -1.020318) (xy -1.957578 -0.66929)
			)
			(stroke
				(width 0)
				(type default)
			)
			(fill yes)
			(layer "F.SilkS")
		)
		(fp_line
			(start 0.674878 1.100074)
			(end -0.674878 1.100074)
			(stroke
				(width 0.1)
				(type default)
			)
			(layer "F.Fab")
		)
		(fp_line
			(start 0.674878 -1.100074)
			(end 0.674878 1.100074)
			(stroke
				(width 0.1)
				(type default)
			)
			(layer "F.Fab")
		)
		(fp_line
			(start -0.674878 1.100074)
			(end -0.674878 -1.100074)
			(stroke
				(width 0.1)
				(type default)
			)
			(layer "F.Fab")
		)
		(fp_line
			(start -0.674878 -1.100074)
			(end 0.674878 -1.100074)
			(stroke
				(width 0.1)
				(type default)
			)
			(layer "F.Fab")
		)
		(fp_poly
			(pts
				(xy -2.2352 -0.298958) (xy -2.2352 -1.001014) (xy -1.533144 -0.649986)
			)
			(stroke
				(width 0)
				(type default)
			)
			(fill yes)
			(layer "F.Fab")
		)
		(pad "1" smd rect
			(at -0.94996 -0.649986 270)
			(size 0.4318 0.508)
			(layers "F.Cu" "F.Mask" "F.Paste")
			(net "GND")
		)
		(pad "2" smd rect
			(at -0.94996 0 270)
			(size 0.4318 0.508)
			(layers "F.Cu" "F.Mask" "F.Paste")
			(net "PRSNT_CABLE_GPU_A3_N")
		)
		(pad "3" smd rect
			(at -0.94996 0.649986 270)
			(size 0.4318 0.508)
			(layers "F.Cu" "F.Mask" "F.Paste")
			(net "PRSNT_CABLE_GPU_A3_ISO_N")
		)
		(pad "4" smd rect
			(at 0.94996 0.649986 270)
			(size 0.4318 0.508)
			(layers "F.Cu" "F.Mask" "F.Paste")
			(net "GND")
		)
		(pad "5" smd rect
			(at 0.94996 0 270)
			(size 0.4318 0.508)
			(layers "F.Cu" "F.Mask" "F.Paste")
			(net "PRSNT_CABLE_GPU_A3")
		)
		(pad "6" smd rect
			(at 0.94996 -0.649986 270)
			(size 0.4318 0.508)
			(layers "F.Cu" "F.Mask" "F.Paste")
			(net "PRSNT_CABLE_GPU_A3")
		)
	)
	(footprint ""
		(layer "F.Cu")
		(at 139.794742 -385.5212 90)
		(property "Reference" "R904"
			(at 0 0 90)
			(layer "F.SilkS")
			(hide yes)
			(effects
				(font
					(size 1.27 1.27)
				)
			)
		)
		(property "Value" ""
			(at 0 0 90)
			(layer "F.Fab")
			(effects
				(font
					(size 1.27 1.27)
				)
			)
		)
		(duplicate_pad_numbers_are_jumpers no)
		(fp_line
			(start 0.32512 -0.175006)
			(end 0.32512 0.175006)
			(stroke
				(width 0.1)
				(type default)
			)
			(layer "F.Fab")
		)
		(fp_line
			(start -0.32512 -0.175006)
			(end 0.32512 -0.175006)
			(stroke
				(width 0.1)
				(type default)
			)
			(layer "F.Fab")
		)
		(fp_line
			(start 0.32512 0.175006)
			(end -0.32512 0.175006)
			(stroke
				(width 0.1)
				(type default)
			)
			(layer "F.Fab")
		)
		(fp_line
			(start -0.32512 0.175006)
			(end -0.32512 -0.175006)
			(stroke
				(width 0.1)
				(type default)
			)
			(layer "F.Fab")
		)
		(pad "1" smd rect
			(at -0.2667 0 90)
			(size 0.3048 0.381)
			(layers "F.Cu" "F.Mask" "F.Paste")
			(net "P1V8_CPU1_RT_1D")
		)
		(pad "2" smd rect
			(at 0.2667 0 270)
			(size 0.3048 0.381)
			(layers "F.Cu" "F.Mask" "F.Paste")
			(net "RT_CPU1_P3_ADDR2")
		)
	)
	(footprint ""
		(layer "F.Cu")
		(at 432.636676 -93.922342)
		(property "Reference" "R3602"
			(at 0 0 0)
			(layer "F.SilkS")
			(hide yes)
			(effects
				(font
					(size 1.27 1.27)
				)
			)
		)
		(property "Value" ""
			(at 0 0 0)
			(layer "F.Fab")
			(effects
				(font
					(size 1.27 1.27)
				)
			)
		)
		(duplicate_pad_numbers_are_jumpers no)
		(fp_line
			(start -0.7874 -0.4064)
			(end 0.7874 -0.4064)
			(stroke
				(width 0.1524)
				(type default)
			)
			(layer "F.SilkS")
		)
		(fp_line
			(start -0.7874 0.4064)
			(end -0.7874 -0.4064)
			(stroke
				(width 0.1524)
				(type default)
			)
			(layer "F.SilkS")
		)
		(fp_line
			(start 0.7874 -0.4064)
			(end 0.7874 0.4064)
			(stroke
				(width 0.1524)
				(type default)
			)
			(layer "F.SilkS")
		)
		(fp_line
			(start 0.7874 0.4064)
			(end -0.7874 0.4064)
			(stroke
				(width 0.1524)
				(type default)
			)
			(layer "F.SilkS")
		)
		(fp_line
			(start -0.67945 -0.305054)
			(end -0.12065 -0.305054)
			(stroke
				(width 0.1)
				(type default)
			)
			(layer "F.Fab")
		)
		(fp_line
			(start -0.67945 0.3048)
			(end -0.67945 -0.305054)
			(stroke
				(width 0.1)
				(type default)
			)
			(layer "F.Fab")
		)
		(fp_line
			(start -0.12065 -0.305054)
			(end -0.12065 -0.2794)
			(stroke
				(width 0.1)
				(type default)
			)
			(layer "F.Fab")
		)
		(fp_line
			(start -0.12065 -0.2794)
			(end 0.12065 -0.2794)
			(stroke
				(width 0.1)
				(type default)
			)
			(layer "F.Fab")
		)
		(fp_line
			(start -0.12065 0.2794)
			(end -0.12065 0.3048)
			(stroke
				(width 0.1)
				(type default)
			)
			(layer "F.Fab")
		)
		(fp_line
			(start -0.12065 0.3048)
			(end -0.67945 0.3048)
			(stroke
				(width 0.1)
				(type default)
			)
			(layer "F.Fab")
		)
		(fp_line
			(start 0.120396 0.2794)
			(end -0.12065 0.2794)
			(stroke
				(width 0.1)
				(type default)
			)
			(layer "F.Fab")
		)
		(fp_line
			(start 0.120396 0.3048)
			(end 0.120396 0.2794)
			(stroke
				(width 0.1)
				(type default)
			)
			(layer "F.Fab")
		)
		(fp_line
			(start 0.12065 -0.3048)
			(end 0.67945 -0.3048)
			(stroke
				(width 0.1)
				(type default)
			)
			(layer "F.Fab")
		)
		(fp_line
			(start 0.12065 -0.2794)
			(end 0.12065 -0.3048)
			(stroke
				(width 0.1)
				(type default)
			)
			(layer "F.Fab")
		)
		(fp_line
			(start 0.67945 -0.3048)
			(end 0.67945 0.3048)
			(stroke
				(width 0.1)
				(type default)
			)
			(layer "F.Fab")
		)
		(fp_line
			(start 0.67945 0.3048)
			(end 0.120396 0.3048)
			(stroke
				(width 0.1)
				(type default)
			)
			(layer "F.Fab")
		)
		(pad "1" smd circle
			(at -0.40005 0)
			(size 0 0)
			(layers "F.Cu" "F.Mask" "F.Paste")
			(net "P3V3_OCP_SFF_R")
		)
		(pad "2" smd circle
			(at 0.40005 0)
			(size 0 0)
			(layers "F.Cu" "F.Mask" "F.Paste")
			(net "VSENSE_P3V3_INA230_1_INP")
		)
	)
	(footprint ""
		(layer "F.Cu")
		(at 461.460088 -160.499806)
		(property "Reference" "H98"
			(at -3.056382 -5.99186 0)
			(unlocked yes)
			(layer "F.SilkS")
			(effects
				(font
					(size 0.7874 0.5842)
					(thickness 0.1524)
				)
				(justify left)
			)
		)
		(property "Value" ""
			(at 0 0 0)
			(layer "F.Fab")
			(effects
				(font
					(size 1.27 1.27)
				)
			)
		)
		(duplicate_pad_numbers_are_jumpers no)
		(pad "1" thru_hole circle
			(at 0 0)
			(size 10.0076 10.0076)
			(drill 5.6134)
			(layers "*.Cu" "*.Mask")
			(remove_unused_layers no)
			(net "GND")
			(clearance -1.9431)
		)
	)
	(footprint ""
		(layer "F.Cu")
		(at 233.2228 -283.5148)
		(property "Reference" "PC6521"
			(at 0 0 0)
			(layer "F.SilkS")
			(hide yes)
			(effects
				(font
					(size 1.27 1.27)
				)
			)
		)
		(property "Value" ""
			(at 0 0 0)
			(layer "F.Fab")
			(effects
				(font
					(size 1.27 1.27)
				)
			)
		)
		(duplicate_pad_numbers_are_jumpers no)
		(fp_line
			(start -1.524 -0.762)
			(end 1.524 -0.762)
			(stroke
				(width 0.1524)
				(type default)
			)
			(layer "F.SilkS")
		)
		(fp_line
			(start -1.524 0.762)
			(end -1.524 -0.762)
			(stroke
				(width 0.1524)
				(type default)
			)
			(layer "F.SilkS")
		)
		(fp_line
			(start 1.524 -0.762)
			(end 1.524 0.762)
			(stroke
				(width 0.1524)
				(type default)
			)
			(layer "F.SilkS")
		)
		(fp_line
			(start 1.524 0.762)
			(end -1.524 0.762)
			(stroke
				(width 0.1524)
				(type default)
			)
			(layer "F.SilkS")
		)
		(fp_line
			(start -1.1049 -0.724916)
			(end -1.1049 0.724916)
			(stroke
				(width 0.1)
				(type default)
			)
			(layer "F.Fab")
		)
		(fp_line
			(start -1.1049 0.724916)
			(end 1.1049 0.724916)
			(stroke
				(width 0.1)
				(type default)
			)
			(layer "F.Fab")
		)
		(fp_line
			(start 1.1049 -0.724916)
			(end -1.1049 -0.724916)
			(stroke
				(width 0.1)
				(type default)
			)
			(layer "F.Fab")
		)
		(fp_line
			(start 1.1049 0.724916)
			(end 1.1049 -0.724916)
			(stroke
				(width 0.1)
				(type default)
			)
			(layer "F.Fab")
		)
		(pad "1" smd rect
			(at -0.889 0 180)
			(size 1.016 1.27)
			(layers "F.Cu" "F.Mask" "F.Paste")
			(net "SW_P12V_AUX_P1V8_RETIMER_CPU1_FLT")
		)
		(pad "2" smd rect
			(at 0.889 0 180)
			(size 1.016 1.27)
			(layers "F.Cu" "F.Mask" "F.Paste")
			(net "GND")
		)
	)
	(footprint ""
		(layer "F.Cu")
		(at 312.443876 -70.098412 90)
		(property "Reference" "D88"
			(at -3.934714 -0.691642 90)
			(unlocked yes)
			(layer "F.SilkS")
			(effects
				(font
					(size 0.7874 0.5842)
					(thickness 0.1524)
				)
				(justify left)
			)
		)
		(property "Value" ""
			(at 0 0 90)
			(layer "F.Fab")
			(effects
				(font
					(size 1.27 1.27)
				)
			)
		)
		(duplicate_pad_numbers_are_jumpers no)
		(fp_line
			(start 1.16078 -0.4826)
			(end 1.16078 0.4826)
			(stroke
				(width 0.1524)
				(type default)
			)
			(layer "F.SilkS")
		)
		(fp_line
			(start 1.03378 -0.4826)
			(end 1.03378 0.4826)
			(stroke
				(width 0.1524)
				(type default)
			)
			(layer "F.SilkS")
		)
		(fp_line
			(start 0.90678 -0.4826)
			(end 0.90678 0.4826)
			(stroke
				(width 0.1524)
				(type default)
			)
			(layer "F.SilkS")
		)
		(fp_line
			(start -0.64008 -0.4826)
			(end 1.16078 -0.4826)
			(stroke
				(width 0.1524)
				(type default)
			)
			(layer "F.SilkS")
		)
		(fp_line
			(start -0.79248 -0.4826)
			(end 1.03378 -0.4826)
			(stroke
				(width 0.1524)
				(type default)
			)
			(layer "F.SilkS")
		)
		(fp_line
			(start -0.89408 -0.4826)
			(end 0.90678 -0.4826)
			(stroke
				(width 0.1524)
				(type default)
			)
			(layer "F.SilkS")
		)
		(fp_line
			(start 1.16078 0.4826)
			(end -0.64008 0.4826)
			(stroke
				(width 0.1524)
				(type default)
			)
			(layer "F.SilkS")
		)
		(fp_line
			(start 1.03378 0.4826)
			(end -0.79248 0.4826)
			(stroke
				(width 0.1524)
				(type default)
			)
			(layer "F.SilkS")
		)
		(fp_line
			(start 0.90678 0.4826)
			(end -0.90678 0.4826)
			(stroke
				(width 0.1524)
				(type default)
			)
			(layer "F.SilkS")
		)
		(fp_line
			(start -0.90678 0.4826)
			(end -0.90678 -0.4699)
			(stroke
				(width 0.1524)
				(type default)
			)
			(layer "F.SilkS")
		)
		(fp_line
			(start 0.499872 -0.249936)
			(end 0.499872 0.249936)
			(stroke
				(width 0.1)
				(type default)
			)
			(layer "F.Fab")
		)
		(fp_line
			(start -0.499872 -0.249936)
			(end 0.499872 -0.249936)
			(stroke
				(width 0.1)
				(type default)
			)
			(layer "F.Fab")
		)
		(fp_line
			(start 0.499872 0.249936)
			(end -0.499872 0.249936)
			(stroke
				(width 0.1)
				(type default)
			)
			(layer "F.Fab")
		)
		(fp_line
			(start -0.499872 0.249936)
			(end -0.499872 -0.249936)
			(stroke
				(width 0.1)
				(type default)
			)
			(layer "F.Fab")
		)
		(pad "A" smd rect
			(at -0.47498 0 90)
			(size 0.6096 0.7112)
			(layers "F.Cu" "F.Mask" "F.Paste")
			(net "LED_PWRGD_SYS_PWROK_R")
		)
		(pad "C" smd rect
			(at 0.47498 0 90)
			(size 0.6096 0.7112)
			(layers "F.Cu" "F.Mask" "F.Paste")
			(net "LED_PWRGD_SYS_PWROK_R_D")
		)
	)
	(footprint ""
		(layer "F.Cu")
		(at 156.322522 -191.361314 -90)
		(property "Reference" "R3195"
			(at 0 0 270)
			(layer "F.SilkS")
			(hide yes)
			(effects
				(font
					(size 1.27 1.27)
				)
			)
		)
		(property "Value" ""
			(at 0 0 270)
			(layer "F.Fab")
			(effects
				(font
					(size 1.27 1.27)
				)
			)
		)
		(duplicate_pad_numbers_are_jumpers no)
		(fp_line
			(start 0.353314 0.4064)
			(end -0.383286 0.4064)
			(stroke
				(width 0.1524)
				(type default)
			)
			(layer "F.SilkS")
		)
		(fp_line
			(start -0.7874 -0.014478)
			(end -0.7874 -0.4064)
			(stroke
				(width 0.1524)
				(type default)
			)
			(layer "F.SilkS")
		)
		(fp_line
			(start -0.7874 -0.4064)
			(end 0.7874 -0.4064)
			(stroke
				(width 0.1524)
				(type default)
			)
			(layer "F.SilkS")
		)
		(fp_line
			(start 0.7874 -0.4064)
			(end 0.7874 -0.014478)
			(stroke
				(width 0.1524)
				(type default)
			)
			(layer "F.SilkS")
		)
		(fp_line
			(start -0.67945 0.3048)
			(end -0.67945 -0.305054)
			(stroke
				(width 0.1)
				(type default)
			)
			(layer "F.Fab")
		)
		(fp_line
			(start -0.12065 0.3048)
			(end -0.67945 0.3048)
			(stroke
				(width 0.1)
				(type default)
			)
			(layer "F.Fab")
		)
		(fp_line
			(start 0.120396 0.3048)
			(end 0.120396 0.2794)
			(stroke
				(width 0.1)
				(type default)
			)
			(layer "F.Fab")
		)
		(fp_line
			(start 0.67945 0.3048)
			(end 0.120396 0.3048)
			(stroke
				(width 0.1)
				(type default)
			)
			(layer "F.Fab")
		)
		(fp_line
			(start -0.12065 0.2794)
			(end -0.12065 0.3048)
			(stroke
				(width 0.1)
				(type default)
			)
			(layer "F.Fab")
		)
		(fp_line
			(start 0.120396 0.2794)
			(end -0.12065 0.2794)
			(stroke
				(width 0.1)
				(type default)
			)
			(layer "F.Fab")
		)
		(fp_line
			(start -0.12065 -0.2794)
			(end 0.12065 -0.2794)
			(stroke
				(width 0.1)
				(type default)
			)
			(layer "F.Fab")
		)
		(fp_line
			(start 0.12065 -0.2794)
			(end 0.12065 -0.3048)
			(stroke
				(width 0.1)
				(type default)
			)
			(layer "F.Fab")
		)
		(fp_line
			(start 0.12065 -0.3048)
			(end 0.67945 -0.3048)
			(stroke
				(width 0.1)
				(type default)
			)
			(layer "F.Fab")
		)
		(fp_line
			(start 0.67945 -0.3048)
			(end 0.67945 0.3048)
			(stroke
				(width 0.1)
				(type default)
			)
			(layer "F.Fab")
		)
		(fp_line
			(start -0.67945 -0.305054)
			(end -0.12065 -0.305054)
			(stroke
				(width 0.1)
				(type default)
			)
			(layer "F.Fab")
		)
		(fp_line
			(start -0.12065 -0.305054)
			(end -0.12065 -0.2794)
			(stroke
				(width 0.1)
				(type default)
			)
			(layer "F.Fab")
		)
		(pad "1" smd circle
			(at -0.40005 0 270)
			(size 0 0)
			(layers "F.Cu" "F.Mask" "F.Paste")
			(net "CLK_100M_CPU1_CLK02_R_DN")
		)
		(pad "2" smd circle
			(at 0.40005 0 270)
			(size 0 0)
			(layers "F.Cu" "F.Mask" "F.Paste")
			(net "CLK_100M_CPU1_CLK02_DN")
		)
	)
	(footprint ""
		(layer "F.Cu")
		(at 100.382832 -47.049944)
		(property "Reference" "H32"
			(at -1.7272 -4.511548 0)
			(unlocked yes)
			(layer "B.SilkS")
			(effects
				(font
					(size 0.7874 0.5842)
					(thickness 0.1524)
				)
				(justify left mirror)
			)
		)
		(property "Value" ""
			(at 0 0 0)
			(layer "F.Fab")
			(effects
				(font
					(size 1.27 1.27)
				)
			)
		)
		(duplicate_pad_numbers_are_jumpers no)
		(pad "1" thru_hole circle
			(at 0 0)
			(size 4.5212 4.5212)
			(drill 3.81)
			(layers "*.Cu" "*.Mask")
			(remove_unused_layers no)
			(net "GND")
			(clearance -0.1016)
			(padstack
				(mode front_inner_back)
				(layer "Inner"
					(shape circle)
					(size 5.6134 5.6134)
					(clearance -0.6477)
				)
				(layer "B.Cu"
					(shape circle)
					(size 8.001 8.001)
					(clearance -1.8415)
				)
			)
		)
	)
	(footprint ""
		(layer "F.Cu")
		(at 180.395118 -365.058452 90)
		(property "Reference" "PC511"
			(at 0 0 90)
			(layer "F.SilkS")
			(hide yes)
			(effects
				(font
					(size 1.27 1.27)
				)
			)
		)
		(property "Value" ""
			(at 0 0 90)
			(layer "F.Fab")
			(effects
				(font
					(size 1.27 1.27)
				)
			)
		)
		(duplicate_pad_numbers_are_jumpers no)
		(fp_line
			(start 0.7874 -0.4064)
			(end 0.7874 0.4064)
			(stroke
				(width 0.1524)
				(type default)
			)
			(layer "F.SilkS")
		)
		(fp_line
			(start -0.7874 -0.4064)
			(end 0.7874 -0.4064)
			(stroke
				(width 0.1524)
				(type default)
			)
			(layer "F.SilkS")
		)
		(fp_line
			(start 0.7874 0.4064)
			(end -0.7874 0.4064)
			(stroke
				(width 0.1524)
				(type default)
			)
			(layer "F.SilkS")
		)
		(fp_line
			(start -0.7874 0.4064)
			(end -0.7874 -0.4064)
			(stroke
				(width 0.1524)
				(type default)
			)
			(layer "F.SilkS")
		)
		(fp_line
			(start -0.12065 -0.305054)
			(end -0.12065 -0.2794)
			(stroke
				(width 0.1)
				(type default)
			)
			(layer "F.Fab")
		)
		(fp_line
			(start -0.67945 -0.305054)
			(end -0.12065 -0.305054)
			(stroke
				(width 0.1)
				(type default)
			)
			(layer "F.Fab")
		)
		(fp_line
			(start 0.67945 -0.3048)
			(end 0.67945 0.3048)
			(stroke
				(width 0.1)
				(type default)
			)
			(layer "F.Fab")
		)
		(fp_line
			(start 0.12065 -0.3048)
			(end 0.67945 -0.3048)
			(stroke
				(width 0.1)
				(type default)
			)
			(layer "F.Fab")
		)
		(fp_line
			(start 0.12065 -0.2794)
			(end 0.12065 -0.3048)
			(stroke
				(width 0.1)
				(type default)
			)
			(layer "F.Fab")
		)
		(fp_line
			(start -0.12065 -0.2794)
			(end 0.12065 -0.2794)
			(stroke
				(width 0.1)
				(type default)
			)
			(layer "F.Fab")
		)
		(fp_line
			(start 0.120396 0.2794)
			(end -0.12065 0.2794)
			(stroke
				(width 0.1)
				(type default)
			)
			(layer "F.Fab")
		)
		(fp_line
			(start -0.12065 0.2794)
			(end -0.12065 0.3048)
			(stroke
				(width 0.1)
				(type default)
			)
			(layer "F.Fab")
		)
		(fp_line
			(start 0.67945 0.3048)
			(end 0.120396 0.3048)
			(stroke
				(width 0.1)
				(type default)
			)
			(layer "F.Fab")
		)
		(fp_line
			(start 0.120396 0.3048)
			(end 0.120396 0.2794)
			(stroke
				(width 0.1)
				(type default)
			)
			(layer "F.Fab")
		)
		(fp_line
			(start -0.12065 0.3048)
			(end -0.67945 0.3048)
			(stroke
				(width 0.1)
				(type default)
			)
			(layer "F.Fab")
		)
		(fp_line
			(start -0.67945 0.3048)
			(end -0.67945 -0.305054)
			(stroke
				(width 0.1)
				(type default)
			)
			(layer "F.Fab")
		)
		(pad "1" smd circle
			(at -0.40005 0 90)
			(size 0 0)
			(layers "F.Cu" "F.Mask" "F.Paste")
			(net "P12V_AUX")
		)
		(pad "2" smd circle
			(at 0.40005 0 90)
			(size 0 0)
			(layers "F.Cu" "F.Mask" "F.Paste")
			(net "GND")
		)
	)
	(footprint ""
		(layer "F.Cu")
		(at 290.603178 -423.434764 90)
		(property "Reference" "R4518"
			(at 0 0 90)
			(layer "F.SilkS")
			(hide yes)
			(effects
				(font
					(size 1.27 1.27)
				)
			)
		)
		(property "Value" ""
			(at 0 0 90)
			(layer "F.Fab")
			(effects
				(font
					(size 1.27 1.27)
				)
			)
		)
		(duplicate_pad_numbers_are_jumpers no)
		(fp_line
			(start 0.7874 -0.4064)
			(end 0.7874 0.4064)
			(stroke
				(width 0.1524)
				(type default)
			)
			(layer "F.SilkS")
		)
		(fp_line
			(start -0.7874 -0.4064)
			(end 0.7874 -0.4064)
			(stroke
				(width 0.1524)
				(type default)
			)
			(layer "F.SilkS")
		)
		(fp_line
			(start 0.7874 0.4064)
			(end -0.7874 0.4064)
			(stroke
				(width 0.1524)
				(type default)
			)
			(layer "F.SilkS")
		)
		(fp_line
			(start -0.7874 0.4064)
			(end -0.7874 -0.4064)
			(stroke
				(width 0.1524)
				(type default)
			)
			(layer "F.SilkS")
		)
		(fp_line
			(start -0.12065 -0.305054)
			(end -0.12065 -0.2794)
			(stroke
				(width 0.1)
				(type default)
			)
			(layer "F.Fab")
		)
		(fp_line
			(start -0.67945 -0.305054)
			(end -0.12065 -0.305054)
			(stroke
				(width 0.1)
				(type default)
			)
			(layer "F.Fab")
		)
		(fp_line
			(start 0.67945 -0.3048)
			(end 0.67945 0.3048)
			(stroke
				(width 0.1)
				(type default)
			)
			(layer "F.Fab")
		)
		(fp_line
			(start 0.12065 -0.3048)
			(end 0.67945 -0.3048)
			(stroke
				(width 0.1)
				(type default)
			)
			(layer "F.Fab")
		)
		(fp_line
			(start 0.12065 -0.2794)
			(end 0.12065 -0.3048)
			(stroke
				(width 0.1)
				(type default)
			)
			(layer "F.Fab")
		)
		(fp_line
			(start -0.12065 -0.2794)
			(end 0.12065 -0.2794)
			(stroke
				(width 0.1)
				(type default)
			)
			(layer "F.Fab")
		)
		(fp_line
			(start 0.120396 0.2794)
			(end -0.12065 0.2794)
			(stroke
				(width 0.1)
				(type default)
			)
			(layer "F.Fab")
		)
		(fp_line
			(start -0.12065 0.2794)
			(end -0.12065 0.3048)
			(stroke
				(width 0.1)
				(type default)
			)
			(layer "F.Fab")
		)
		(fp_line
			(start 0.67945 0.3048)
			(end 0.120396 0.3048)
			(stroke
				(width 0.1)
				(type default)
			)
			(layer "F.Fab")
		)
		(fp_line
			(start 0.120396 0.3048)
			(end 0.120396 0.2794)
			(stroke
				(width 0.1)
				(type default)
			)
			(layer "F.Fab")
		)
		(fp_line
			(start -0.12065 0.3048)
			(end -0.67945 0.3048)
			(stroke
				(width 0.1)
				(type default)
			)
			(layer "F.Fab")
		)
		(fp_line
			(start -0.67945 0.3048)
			(end -0.67945 -0.305054)
			(stroke
				(width 0.1)
				(type default)
			)
			(layer "F.Fab")
		)
		(pad "1" smd circle
			(at -0.40005 0 90)
			(size 0 0)
			(layers "F.Cu" "F.Mask" "F.Paste")
			(net "FM_9ZXL045_P0_2_OE_N")
		)
		(pad "2" smd circle
			(at 0.40005 0 90)
			(size 0 0)
			(layers "F.Cu" "F.Mask" "F.Paste")
			(net "GND")
		)
	)
	(footprint ""
		(layer "F.Cu")
		(at 313.872626 -416.899344 -90)
		(property "Reference" "C6507"
			(at 0 0 270)
			(layer "F.SilkS")
			(hide yes)
			(effects
				(font
					(size 1.27 1.27)
				)
			)
		)
		(property "Value" ""
			(at 0 0 270)
			(layer "F.Fab")
			(effects
				(font
					(size 1.27 1.27)
				)
			)
		)
		(duplicate_pad_numbers_are_jumpers no)
		(fp_line
			(start -0.299974 0.150114)
			(end -0.299974 -0.150114)
			(stroke
				(width 0.1)
				(type default)
			)
			(layer "F.Fab")
		)
		(fp_line
			(start 0.299974 0.150114)
			(end -0.299974 0.150114)
			(stroke
				(width 0.1)
				(type default)
			)
			(layer "F.Fab")
		)
		(fp_line
			(start -0.299974 -0.150114)
			(end 0.299974 -0.150114)
			(stroke
				(width 0.1)
				(type default)
			)
			(layer "F.Fab")
		)
		(fp_line
			(start 0.299974 -0.150114)
			(end 0.299974 0.150114)
			(stroke
				(width 0.1)
				(type default)
			)
			(layer "F.Fab")
		)
		(pad "1" smd rect
			(at -0.2667 0 270)
			(size 0.3048 0.381)
			(layers "F.Cu" "F.Mask" "F.Paste")
			(net "P5E_CPU0_P0_TX_BUF_C_DP<3>")
		)
		(pad "2" smd rect
			(at 0.2667 0 270)
			(size 0.3048 0.381)
			(layers "F.Cu" "F.Mask" "F.Paste")
			(net "P5E_CPU0_P0_TX_BUF_DP<3>")
		)
	)
	(footprint ""
		(layer "F.Cu")
		(at 372.937278 -146.552158 180)
		(property "Reference" "R8287"
			(at 0 0 180)
			(layer "F.SilkS")
			(hide yes)
			(effects
				(font
					(size 1.27 1.27)
				)
			)
		)
		(property "Value" ""
			(at 0 0 180)
			(layer "F.Fab")
			(effects
				(font
					(size 1.27 1.27)
				)
			)
		)
		(duplicate_pad_numbers_are_jumpers no)
		(fp_line
			(start 0.7874 0.4064)
			(end -0.7874 0.4064)
			(stroke
				(width 0.1524)
				(type default)
			)
			(layer "F.SilkS")
		)
		(fp_line
			(start 0.7874 -0.4064)
			(end 0.7874 0.4064)
			(stroke
				(width 0.1524)
				(type default)
			)
			(layer "F.SilkS")
		)
		(fp_line
			(start -0.7874 0.4064)
			(end -0.7874 -0.4064)
			(stroke
				(width 0.1524)
				(type default)
			)
			(layer "F.SilkS")
		)
		(fp_line
			(start -0.7874 -0.4064)
			(end 0.7874 -0.4064)
			(stroke
				(width 0.1524)
				(type default)
			)
			(layer "F.SilkS")
		)
		(fp_line
			(start 0.67945 0.3048)
			(end 0.120396 0.3048)
			(stroke
				(width 0.1)
				(type default)
			)
			(layer "F.Fab")
		)
		(fp_line
			(start 0.67945 -0.3048)
			(end 0.67945 0.3048)
			(stroke
				(width 0.1)
				(type default)
			)
			(layer "F.Fab")
		)
		(fp_line
			(start 0.12065 -0.2794)
			(end 0.12065 -0.3048)
			(stroke
				(width 0.1)
				(type default)
			)
			(layer "F.Fab")
		)
		(fp_line
			(start 0.12065 -0.3048)
			(end 0.67945 -0.3048)
			(stroke
				(width 0.1)
				(type default)
			)
			(layer "F.Fab")
		)
		(fp_line
			(start 0.120396 0.3048)
			(end 0.120396 0.2794)
			(stroke
				(width 0.1)
				(type default)
			)
			(layer "F.Fab")
		)
		(fp_line
			(start 0.120396 0.2794)
			(end -0.12065 0.2794)
			(stroke
				(width 0.1)
				(type default)
			)
			(layer "F.Fab")
		)
		(fp_line
			(start -0.12065 0.3048)
			(end -0.67945 0.3048)
			(stroke
				(width 0.1)
				(type default)
			)
			(layer "F.Fab")
		)
		(fp_line
			(start -0.12065 0.2794)
			(end -0.12065 0.3048)
			(stroke
				(width 0.1)
				(type default)
			)
			(layer "F.Fab")
		)
		(fp_line
			(start -0.12065 -0.2794)
			(end 0.12065 -0.2794)
			(stroke
				(width 0.1)
				(type default)
			)
			(layer "F.Fab")
		)
		(fp_line
			(start -0.12065 -0.305054)
			(end -0.12065 -0.2794)
			(stroke
				(width 0.1)
				(type default)
			)
			(layer "F.Fab")
		)
		(fp_line
			(start -0.67945 0.3048)
			(end -0.67945 -0.305054)
			(stroke
				(width 0.1)
				(type default)
			)
			(layer "F.Fab")
		)
		(fp_line
			(start -0.67945 -0.305054)
			(end -0.12065 -0.305054)
			(stroke
				(width 0.1)
				(type default)
			)
			(layer "F.Fab")
		)
		(pad "1" smd circle
			(at -0.40005 0 180)
			(size 0 0)
			(layers "F.Cu" "F.Mask" "F.Paste")
			(net "PVDD18_S5_P0")
		)
		(pad "2" smd circle
			(at 0.40005 0 180)
			(size 0 0)
			(layers "F.Cu" "F.Mask" "F.Paste")
			(net "SVID_PVDDCR_CPU0_P0_SVTO")
		)
	)
	(footprint ""
		(layer "F.Cu")
		(at 108.533946 -54.882034 -90)
		(property "Reference" "R6312"
			(at 0 0 270)
			(layer "F.SilkS")
			(hide yes)
			(effects
				(font
					(size 1.27 1.27)
				)
			)
		)
		(property "Value" ""
			(at 0 0 270)
			(layer "F.Fab")
			(effects
				(font
					(size 1.27 1.27)
				)
			)
		)
		(duplicate_pad_numbers_are_jumpers no)
		(fp_line
			(start -0.7874 0.4064)
			(end -0.7874 -0.4064)
			(stroke
				(width 0.1524)
				(type default)
			)
			(layer "F.SilkS")
		)
		(fp_line
			(start 0.7874 0.4064)
			(end -0.7874 0.4064)
			(stroke
				(width 0.1524)
				(type default)
			)
			(layer "F.SilkS")
		)
		(fp_line
			(start -0.7874 -0.4064)
			(end 0.7874 -0.4064)
			(stroke
				(width 0.1524)
				(type default)
			)
			(layer "F.SilkS")
		)
		(fp_line
			(start 0.7874 -0.4064)
			(end 0.7874 0.4064)
			(stroke
				(width 0.1524)
				(type default)
			)
			(layer "F.SilkS")
		)
		(fp_line
			(start -0.67945 0.3048)
			(end -0.67945 -0.305054)
			(stroke
				(width 0.1)
				(type default)
			)
			(layer "F.Fab")
		)
		(fp_line
			(start -0.12065 0.3048)
			(end -0.67945 0.3048)
			(stroke
				(width 0.1)
				(type default)
			)
			(layer "F.Fab")
		)
		(fp_line
			(start 0.120396 0.3048)
			(end 0.120396 0.2794)
			(stroke
				(width 0.1)
				(type default)
			)
			(layer "F.Fab")
		)
		(fp_line
			(start 0.67945 0.3048)
			(end 0.120396 0.3048)
			(stroke
				(width 0.1)
				(type default)
			)
			(layer "F.Fab")
		)
		(fp_line
			(start -0.12065 0.2794)
			(end -0.12065 0.3048)
			(stroke
				(width 0.1)
				(type default)
			)
			(layer "F.Fab")
		)
		(fp_line
			(start 0.120396 0.2794)
			(end -0.12065 0.2794)
			(stroke
				(width 0.1)
				(type default)
			)
			(layer "F.Fab")
		)
		(fp_line
			(start -0.12065 -0.2794)
			(end 0.12065 -0.2794)
			(stroke
				(width 0.1)
				(type default)
			)
			(layer "F.Fab")
		)
		(fp_line
			(start 0.12065 -0.2794)
			(end 0.12065 -0.3048)
			(stroke
				(width 0.1)
				(type default)
			)
			(layer "F.Fab")
		)
		(fp_line
			(start 0.12065 -0.3048)
			(end 0.67945 -0.3048)
			(stroke
				(width 0.1)
				(type default)
			)
			(layer "F.Fab")
		)
		(fp_line
			(start 0.67945 -0.3048)
			(end 0.67945 0.3048)
			(stroke
				(width 0.1)
				(type default)
			)
			(layer "F.Fab")
		)
		(fp_line
			(start -0.67945 -0.305054)
			(end -0.12065 -0.305054)
			(stroke
				(width 0.1)
				(type default)
			)
			(layer "F.Fab")
		)
		(fp_line
			(start -0.12065 -0.305054)
			(end -0.12065 -0.2794)
			(stroke
				(width 0.1)
				(type default)
			)
			(layer "F.Fab")
		)
		(pad "1" smd circle
			(at -0.40005 0 270)
			(size 0 0)
			(layers "F.Cu" "F.Mask" "F.Paste")
			(net "P3V3_AUX")
		)
		(pad "2" smd circle
			(at 0.40005 0 270)
			(size 0 0)
			(layers "F.Cu" "F.Mask" "F.Paste")
			(net "USB_HUB2_TI_OVERCUR1")
		)
	)
	(footprint ""
		(layer "F.Cu")
		(at 217.881962 -68.340478)
		(property "Reference" "PR3963"
			(at 0 0 0)
			(layer "F.SilkS")
			(hide yes)
			(effects
				(font
					(size 1.27 1.27)
				)
			)
		)
		(property "Value" ""
			(at 0 0 0)
			(layer "F.Fab")
			(effects
				(font
					(size 1.27 1.27)
				)
			)
		)
		(duplicate_pad_numbers_are_jumpers no)
		(fp_line
			(start -0.7874 -0.4064)
			(end 0.7874 -0.4064)
			(stroke
				(width 0.1524)
				(type default)
			)
			(layer "F.SilkS")
		)
		(fp_line
			(start -0.7874 0.4064)
			(end -0.7874 -0.4064)
			(stroke
				(width 0.1524)
				(type default)
			)
			(layer "F.SilkS")
		)
		(fp_line
			(start 0.7874 -0.4064)
			(end 0.7874 0.4064)
			(stroke
				(width 0.1524)
				(type default)
			)
			(layer "F.SilkS")
		)
		(fp_line
			(start 0.7874 0.4064)
			(end -0.7874 0.4064)
			(stroke
				(width 0.1524)
				(type default)
			)
			(layer "F.SilkS")
		)
		(fp_line
			(start -0.67945 -0.305054)
			(end -0.12065 -0.305054)
			(stroke
				(width 0.1)
				(type default)
			)
			(layer "F.Fab")
		)
		(fp_line
			(start -0.67945 0.3048)
			(end -0.67945 -0.305054)
			(stroke
				(width 0.1)
				(type default)
			)
			(layer "F.Fab")
		)
		(fp_line
			(start -0.12065 -0.305054)
			(end -0.12065 -0.2794)
			(stroke
				(width 0.1)
				(type default)
			)
			(layer "F.Fab")
		)
		(fp_line
			(start -0.12065 -0.2794)
			(end 0.12065 -0.2794)
			(stroke
				(width 0.1)
				(type default)
			)
			(layer "F.Fab")
		)
		(fp_line
			(start -0.12065 0.2794)
			(end -0.12065 0.3048)
			(stroke
				(width 0.1)
				(type default)
			)
			(layer "F.Fab")
		)
		(fp_line
			(start -0.12065 0.3048)
			(end -0.67945 0.3048)
			(stroke
				(width 0.1)
				(type default)
			)
			(layer "F.Fab")
		)
		(fp_line
			(start 0.120396 0.2794)
			(end -0.12065 0.2794)
			(stroke
				(width 0.1)
				(type default)
			)
			(layer "F.Fab")
		)
		(fp_line
			(start 0.120396 0.3048)
			(end 0.120396 0.2794)
			(stroke
				(width 0.1)
				(type default)
			)
			(layer "F.Fab")
		)
		(fp_line
			(start 0.12065 -0.3048)
			(end 0.67945 -0.3048)
			(stroke
				(width 0.1)
				(type default)
			)
			(layer "F.Fab")
		)
		(fp_line
			(start 0.12065 -0.2794)
			(end 0.12065 -0.3048)
			(stroke
				(width 0.1)
				(type default)
			)
			(layer "F.Fab")
		)
		(fp_line
			(start 0.67945 -0.3048)
			(end 0.67945 0.3048)
			(stroke
				(width 0.1)
				(type default)
			)
			(layer "F.Fab")
		)
		(fp_line
			(start 0.67945 0.3048)
			(end 0.120396 0.3048)
			(stroke
				(width 0.1)
				(type default)
			)
			(layer "F.Fab")
		)
		(pad "1" smd circle
			(at -0.40005 0)
			(size 0 0)
			(layers "F.Cu" "F.Mask" "F.Paste")
			(net "P3V3_AUX")
		)
		(pad "2" smd circle
			(at 0.40005 0)
			(size 0 0)
			(layers "F.Cu" "F.Mask" "F.Paste")
			(net "P3V3_E1S_UV_0")
		)
	)
	(footprint ""
		(layer "F.Cu")
		(at 90.833702 -370.57203 -90)
		(property "Reference" "C723"
			(at 0 0 270)
			(layer "F.SilkS")
			(hide yes)
			(effects
				(font
					(size 1.27 1.27)
				)
			)
		)
		(property "Value" ""
			(at 0 0 270)
			(layer "F.Fab")
			(effects
				(font
					(size 1.27 1.27)
				)
			)
		)
		(duplicate_pad_numbers_are_jumpers no)
		(fp_line
			(start -0.299974 0.150114)
			(end -0.299974 -0.150114)
			(stroke
				(width 0.1)
				(type default)
			)
			(layer "F.Fab")
		)
		(fp_line
			(start 0.299974 0.150114)
			(end -0.299974 0.150114)
			(stroke
				(width 0.1)
				(type default)
			)
			(layer "F.Fab")
		)
		(fp_line
			(start -0.299974 -0.150114)
			(end 0.299974 -0.150114)
			(stroke
				(width 0.1)
				(type default)
			)
			(layer "F.Fab")
		)
		(fp_line
			(start 0.299974 -0.150114)
			(end 0.299974 0.150114)
			(stroke
				(width 0.1)
				(type default)
			)
			(layer "F.Fab")
		)
		(pad "1" smd rect
			(at -0.2667 0 270)
			(size 0.3048 0.381)
			(layers "F.Cu" "F.Mask" "F.Paste")
			(net "P5E_CPU1_P1_TX_C_DP<9>")
		)
		(pad "2" smd rect
			(at 0.2667 0 270)
			(size 0.3048 0.381)
			(layers "F.Cu" "F.Mask" "F.Paste")
			(net "P5E_CPU1_P1_TX_DP<9>")
		)
	)
	(footprint ""
		(layer "F.Cu")
		(at 365.387128 -324.29704 90)
		(property "Reference" "R2660"
			(at 0 0 90)
			(layer "F.SilkS")
			(hide yes)
			(effects
				(font
					(size 1.27 1.27)
				)
			)
		)
		(property "Value" ""
			(at 0 0 90)
			(layer "F.Fab")
			(effects
				(font
					(size 1.27 1.27)
				)
			)
		)
		(duplicate_pad_numbers_are_jumpers no)
		(fp_line
			(start 0.7874 -0.4064)
			(end 0.7874 -0.008128)
			(stroke
				(width 0.1524)
				(type default)
			)
			(layer "F.SilkS")
		)
		(fp_line
			(start -0.7874 -0.4064)
			(end 0.7874 -0.4064)
			(stroke
				(width 0.1524)
				(type default)
			)
			(layer "F.SilkS")
		)
		(fp_line
			(start -0.7874 -0.008128)
			(end -0.7874 -0.4064)
			(stroke
				(width 0.1524)
				(type default)
			)
			(layer "F.SilkS")
		)
		(fp_line
			(start 0.39116 0.4064)
			(end -0.34544 0.4064)
			(stroke
				(width 0.1524)
				(type default)
			)
			(layer "F.SilkS")
		)
		(fp_line
			(start -0.12065 -0.305054)
			(end -0.12065 -0.2794)
			(stroke
				(width 0.1)
				(type default)
			)
			(layer "F.Fab")
		)
		(fp_line
			(start -0.67945 -0.305054)
			(end -0.12065 -0.305054)
			(stroke
				(width 0.1)
				(type default)
			)
			(layer "F.Fab")
		)
		(fp_line
			(start 0.67945 -0.3048)
			(end 0.67945 0.3048)
			(stroke
				(width 0.1)
				(type default)
			)
			(layer "F.Fab")
		)
		(fp_line
			(start 0.12065 -0.3048)
			(end 0.67945 -0.3048)
			(stroke
				(width 0.1)
				(type default)
			)
			(layer "F.Fab")
		)
		(fp_line
			(start 0.12065 -0.2794)
			(end 0.12065 -0.3048)
			(stroke
				(width 0.1)
				(type default)
			)
			(layer "F.Fab")
		)
		(fp_line
			(start -0.12065 -0.2794)
			(end 0.12065 -0.2794)
			(stroke
				(width 0.1)
				(type default)
			)
			(layer "F.Fab")
		)
		(fp_line
			(start 0.120396 0.2794)
			(end -0.12065 0.2794)
			(stroke
				(width 0.1)
				(type default)
			)
			(layer "F.Fab")
		)
		(fp_line
			(start -0.12065 0.2794)
			(end -0.12065 0.3048)
			(stroke
				(width 0.1)
				(type default)
			)
			(layer "F.Fab")
		)
		(fp_line
			(start 0.67945 0.3048)
			(end 0.120396 0.3048)
			(stroke
				(width 0.1)
				(type default)
			)
			(layer "F.Fab")
		)
		(fp_line
			(start 0.120396 0.3048)
			(end 0.120396 0.2794)
			(stroke
				(width 0.1)
				(type default)
			)
			(layer "F.Fab")
		)
		(fp_line
			(start -0.12065 0.3048)
			(end -0.67945 0.3048)
			(stroke
				(width 0.1)
				(type default)
			)
			(layer "F.Fab")
		)
		(fp_line
			(start -0.67945 0.3048)
			(end -0.67945 -0.305054)
			(stroke
				(width 0.1)
				(type default)
			)
			(layer "F.Fab")
		)
		(pad "1" smd circle
			(at -0.40005 0 90)
			(size 0 0)
			(layers "F.Cu" "F.Mask" "F.Paste")
			(net "CLK_100M_CPU0_CLK11_R_DN")
		)
		(pad "2" smd circle
			(at 0.40005 0 90)
			(size 0 0)
			(layers "F.Cu" "F.Mask" "F.Paste")
			(net "CLK_100M_CPU0_CLK11_DN")
		)
	)
	(footprint ""
		(layer "F.Cu")
		(at 342.7349 -16.178276 90)
		(property "Reference" "D6"
			(at -3.95732 -1.496568 90)
			(unlocked yes)
			(layer "F.SilkS")
			(effects
				(font
					(size 0.7874 0.5842)
					(thickness 0.1524)
				)
				(justify left)
			)
		)
		(property "Value" ""
			(at 0 0 90)
			(layer "F.Fab")
			(effects
				(font
					(size 1.27 1.27)
				)
			)
		)
		(duplicate_pad_numbers_are_jumpers no)
		(fp_line
			(start 1.778 -0.5588)
			(end 1.3208 -0.5588)
			(stroke
				(width 0.1524)
				(type default)
			)
			(layer "F.SilkS")
		)
		(fp_line
			(start 1.778 -0.5588)
			(end 1.778 0.5588)
			(stroke
				(width 0.1524)
				(type default)
			)
			(layer "F.SilkS")
		)
		(fp_line
			(start 1.4732 -0.5588)
			(end 1.4732 0.5588)
			(stroke
				(width 0.1524)
				(type default)
			)
			(layer "F.SilkS")
		)
		(fp_line
			(start 1.3208 -0.5588)
			(end 1.3208 0.5588)
			(stroke
				(width 0.1524)
				(type default)
			)
			(layer "F.SilkS")
		)
		(fp_line
			(start -1.3208 -0.5588)
			(end 1.3208 -0.5588)
			(stroke
				(width 0.1524)
				(type default)
			)
			(layer "F.SilkS")
		)
		(fp_line
			(start 1.778 0.5588)
			(end 1.3208 0.5588)
			(stroke
				(width 0.1524)
				(type default)
			)
			(layer "F.SilkS")
		)
		(fp_line
			(start 1.6256 0.5588)
			(end 1.6256 -0.5588)
			(stroke
				(width 0.1524)
				(type default)
			)
			(layer "F.SilkS")
		)
		(fp_line
			(start 1.3208 0.5588)
			(end -1.3208 0.5588)
			(stroke
				(width 0.1524)
				(type default)
			)
			(layer "F.SilkS")
		)
		(fp_line
			(start -1.3208 0.5588)
			(end -1.3208 -0.5588)
			(stroke
				(width 0.1524)
				(type default)
			)
			(layer "F.SilkS")
		)
		(fp_line
			(start 0.899922 -0.40005)
			(end 0.899922 0.40005)
			(stroke
				(width 0.1)
				(type default)
			)
			(layer "F.Fab")
		)
		(fp_line
			(start -0.899922 -0.40005)
			(end 0.899922 -0.40005)
			(stroke
				(width 0.1)
				(type default)
			)
			(layer "F.Fab")
		)
		(fp_line
			(start 0.899922 0.40005)
			(end -0.899922 0.40005)
			(stroke
				(width 0.1)
				(type default)
			)
			(layer "F.Fab")
		)
		(fp_line
			(start -0.899922 0.40005)
			(end -0.899922 -0.40005)
			(stroke
				(width 0.1)
				(type default)
			)
			(layer "F.Fab")
		)
		(fp_text user "+"
			(at -2.620518 -0.653796 90)
			(unlocked yes)
			(layer "F.SilkS")
			(effects
				(font
					(size 1.905 1.4224)
					(thickness 0.1524)
				)
				(justify left)
			)
		)
		(fp_text user "-"
			(at 1.651 -0.22225 90)
			(unlocked yes)
			(layer "F.SilkS")
			(effects
				(font
					(size 1.905 1.4224)
					(thickness 0.1524)
				)
				(justify left)
			)
		)
		(fp_text user "-"
			(at 1.651 -0.22225 90)
			(unlocked yes)
			(layer "F.Fab")
			(effects
				(font
					(size 1.905 1.4224)
					(thickness 0.1524)
				)
				(justify left)
			)
		)
		(fp_text user "+"
			(at -2.6162 -0.22225 90)
			(unlocked yes)
			(layer "F.Fab")
			(effects
				(font
					(size 1.905 1.4224)
					(thickness 0.1524)
				)
				(justify left)
			)
		)
		(pad "A" smd rect
			(at -0.750062 0 90)
			(size 0.8128 0.8128)
			(layers "F.Cu" "F.Mask" "F.Paste")
			(net "PU_SMERR_LED")
		)
		(pad "C" smd rect
			(at 0.750062 0 90)
			(size 0.8128 0.8128)
			(layers "F.Cu" "F.Mask" "F.Paste")
			(net "SMERR_LED_N")
		)
	)
	(footprint ""
		(layer "F.Cu")
		(at 311.816496 -383.88163 -90)
		(property "Reference" "C918"
			(at 0 0 270)
			(layer "F.SilkS")
			(hide yes)
			(effects
				(font
					(size 1.27 1.27)
				)
			)
		)
		(property "Value" ""
			(at 0 0 270)
			(layer "F.Fab")
			(effects
				(font
					(size 1.27 1.27)
				)
			)
		)
		(duplicate_pad_numbers_are_jumpers no)
		(fp_line
			(start -0.299974 0.150114)
			(end -0.299974 -0.150114)
			(stroke
				(width 0.1)
				(type default)
			)
			(layer "F.Fab")
		)
		(fp_line
			(start 0.299974 0.150114)
			(end -0.299974 0.150114)
			(stroke
				(width 0.1)
				(type default)
			)
			(layer "F.Fab")
		)
		(fp_line
			(start -0.299974 -0.150114)
			(end 0.299974 -0.150114)
			(stroke
				(width 0.1)
				(type default)
			)
			(layer "F.Fab")
		)
		(fp_line
			(start 0.299974 -0.150114)
			(end 0.299974 0.150114)
			(stroke
				(width 0.1)
				(type default)
			)
			(layer "F.Fab")
		)
		(pad "1" smd rect
			(at -0.2667 0 270)
			(size 0.3048 0.381)
			(layers "F.Cu" "F.Mask" "F.Paste")
			(net "P5E_CPU0_P0_TX_C_DN<7>")
		)
		(pad "2" smd rect
			(at 0.2667 0 270)
			(size 0.3048 0.381)
			(layers "F.Cu" "F.Mask" "F.Paste")
			(net "P5E_CPU0_P0_TX_DN<7>")
		)
	)
	(footprint ""
		(layer "F.Cu")
		(at 183.269636 -361.600242 180)
		(property "Reference" "PL56"
			(at 0.643636 2.863088 0)
			(unlocked yes)
			(layer "F.SilkS")
			(effects
				(font
					(size 0.7874 0.5842)
					(thickness 0.1524)
				)
				(justify left)
			)
		)
		(property "Value" ""
			(at 0 0 180)
			(layer "F.Fab")
			(effects
				(font
					(size 1.27 1.27)
				)
			)
		)
		(duplicate_pad_numbers_are_jumpers no)
		(fp_line
			(start 2.249932 2.249932)
			(end -2.249932 2.249932)
			(stroke
				(width 0.1524)
				(type default)
			)
			(layer "F.SilkS")
		)
		(fp_line
			(start 2.249932 1.3843)
			(end 2.249932 2.249932)
			(stroke
				(width 0.1524)
				(type default)
			)
			(layer "F.SilkS")
		)
		(fp_line
			(start 2.249932 -2.249932)
			(end 2.249932 -1.3843)
			(stroke
				(width 0.1524)
				(type default)
			)
			(layer "F.SilkS")
		)
		(fp_line
			(start -2.249932 2.249932)
			(end -2.249932 1.3843)
			(stroke
				(width 0.1524)
				(type default)
			)
			(layer "F.SilkS")
		)
		(fp_line
			(start -2.249932 -1.3843)
			(end -2.249932 -2.249932)
			(stroke
				(width 0.1524)
				(type default)
			)
			(layer "F.SilkS")
		)
		(fp_line
			(start -2.249932 -2.249932)
			(end 2.249932 -2.249932)
			(stroke
				(width 0.1524)
				(type default)
			)
			(layer "F.SilkS")
		)
		(fp_line
			(start 2.249932 2.249932)
			(end -2.249932 2.249932)
			(stroke
				(width 0.1)
				(type default)
			)
			(layer "F.Fab")
		)
		(fp_line
			(start 2.249932 -2.249932)
			(end 2.249932 2.249932)
			(stroke
				(width 0.1)
				(type default)
			)
			(layer "F.Fab")
		)
		(fp_line
			(start -2.249932 2.249932)
			(end -2.249932 -2.249932)
			(stroke
				(width 0.1)
				(type default)
			)
			(layer "F.Fab")
		)
		(fp_line
			(start -2.249932 -2.249932)
			(end 2.249932 -2.249932)
			(stroke
				(width 0.1)
				(type default)
			)
			(layer "F.Fab")
		)
		(pad "1" smd rect
			(at -1.82499 0 180)
			(size 1.0668 2.5146)
			(layers "F.Cu" "F.Mask" "F.Paste")
			(net "SW_P12V_AUX_PVDD11_S3_P1_FLT")
		)
		(pad "2" smd rect
			(at 1.82499 0 180)
			(size 1.0668 2.5146)
			(layers "F.Cu" "F.Mask" "F.Paste")
			(net "P12V_AUX")
		)
	)
	(footprint ""
		(layer "F.Cu")
		(at 164.45103 -352.658934 90)
		(property "Reference" "PC644"
			(at 0 0 90)
			(layer "F.SilkS")
			(hide yes)
			(effects
				(font
					(size 1.27 1.27)
				)
			)
		)
		(property "Value" ""
			(at 0 0 90)
			(layer "F.Fab")
			(effects
				(font
					(size 1.27 1.27)
				)
			)
		)
		(duplicate_pad_numbers_are_jumpers no)
		(fp_line
			(start 0.7874 -0.4064)
			(end 0.7874 0.4064)
			(stroke
				(width 0.1524)
				(type default)
			)
			(layer "F.SilkS")
		)
		(fp_line
			(start -0.7874 -0.4064)
			(end 0.7874 -0.4064)
			(stroke
				(width 0.1524)
				(type default)
			)
			(layer "F.SilkS")
		)
		(fp_line
			(start 0.7874 0.4064)
			(end -0.7874 0.4064)
			(stroke
				(width 0.1524)
				(type default)
			)
			(layer "F.SilkS")
		)
		(fp_line
			(start -0.7874 0.4064)
			(end -0.7874 -0.4064)
			(stroke
				(width 0.1524)
				(type default)
			)
			(layer "F.SilkS")
		)
		(fp_line
			(start -0.12065 -0.305054)
			(end -0.12065 -0.2794)
			(stroke
				(width 0.1)
				(type default)
			)
			(layer "F.Fab")
		)
		(fp_line
			(start -0.67945 -0.305054)
			(end -0.12065 -0.305054)
			(stroke
				(width 0.1)
				(type default)
			)
			(layer "F.Fab")
		)
		(fp_line
			(start 0.67945 -0.3048)
			(end 0.67945 0.3048)
			(stroke
				(width 0.1)
				(type default)
			)
			(layer "F.Fab")
		)
		(fp_line
			(start 0.12065 -0.3048)
			(end 0.67945 -0.3048)
			(stroke
				(width 0.1)
				(type default)
			)
			(layer "F.Fab")
		)
		(fp_line
			(start 0.12065 -0.2794)
			(end 0.12065 -0.3048)
			(stroke
				(width 0.1)
				(type default)
			)
			(layer "F.Fab")
		)
		(fp_line
			(start -0.12065 -0.2794)
			(end 0.12065 -0.2794)
			(stroke
				(width 0.1)
				(type default)
			)
			(layer "F.Fab")
		)
		(fp_line
			(start 0.120396 0.2794)
			(end -0.12065 0.2794)
			(stroke
				(width 0.1)
				(type default)
			)
			(layer "F.Fab")
		)
		(fp_line
			(start -0.12065 0.2794)
			(end -0.12065 0.3048)
			(stroke
				(width 0.1)
				(type default)
			)
			(layer "F.Fab")
		)
		(fp_line
			(start 0.67945 0.3048)
			(end 0.120396 0.3048)
			(stroke
				(width 0.1)
				(type default)
			)
			(layer "F.Fab")
		)
		(fp_line
			(start 0.120396 0.3048)
			(end 0.120396 0.2794)
			(stroke
				(width 0.1)
				(type default)
			)
			(layer "F.Fab")
		)
		(fp_line
			(start -0.12065 0.3048)
			(end -0.67945 0.3048)
			(stroke
				(width 0.1)
				(type default)
			)
			(layer "F.Fab")
		)
		(fp_line
			(start -0.67945 0.3048)
			(end -0.67945 -0.305054)
			(stroke
				(width 0.1)
				(type default)
			)
			(layer "F.Fab")
		)
		(pad "1" smd circle
			(at -0.40005 0 90)
			(size 0 0)
			(layers "F.Cu" "F.Mask" "F.Paste")
			(net "PVDD11_S3_P1_VCCS")
		)
		(pad "2" smd circle
			(at 0.40005 0 90)
			(size 0 0)
			(layers "F.Cu" "F.Mask" "F.Paste")
			(net "GND")
		)
	)
	(footprint ""
		(layer "F.Cu")
		(at 296.681906 -349.381572 90)
		(property "Reference" "PC143"
			(at 0 0 90)
			(layer "F.SilkS")
			(hide yes)
			(effects
				(font
					(size 1.27 1.27)
				)
			)
		)
		(property "Value" ""
			(at 0 0 90)
			(layer "F.Fab")
			(effects
				(font
					(size 1.27 1.27)
				)
			)
		)
		(duplicate_pad_numbers_are_jumpers no)
		(fp_line
			(start 0.7874 -0.4064)
			(end 0.7874 0.4064)
			(stroke
				(width 0.1524)
				(type default)
			)
			(layer "F.SilkS")
		)
		(fp_line
			(start -0.7874 -0.4064)
			(end 0.7874 -0.4064)
			(stroke
				(width 0.1524)
				(type default)
			)
			(layer "F.SilkS")
		)
		(fp_line
			(start 0.7874 0.4064)
			(end 0.401828 0.4064)
			(stroke
				(width 0.1524)
				(type default)
			)
			(layer "F.SilkS")
		)
		(fp_line
			(start -0.207772 0.4064)
			(end -0.7874 0.4064)
			(stroke
				(width 0.1524)
				(type default)
			)
			(layer "F.SilkS")
		)
		(fp_line
			(start -0.7874 0.4064)
			(end -0.7874 -0.4064)
			(stroke
				(width 0.1524)
				(type default)
			)
			(layer "F.SilkS")
		)
		(fp_line
			(start -0.12065 -0.305054)
			(end -0.12065 -0.2794)
			(stroke
				(width 0.1)
				(type default)
			)
			(layer "F.Fab")
		)
		(fp_line
			(start -0.67945 -0.305054)
			(end -0.12065 -0.305054)
			(stroke
				(width 0.1)
				(type default)
			)
			(layer "F.Fab")
		)
		(fp_line
			(start 0.67945 -0.3048)
			(end 0.67945 0.3048)
			(stroke
				(width 0.1)
				(type default)
			)
			(layer "F.Fab")
		)
		(fp_line
			(start 0.12065 -0.3048)
			(end 0.67945 -0.3048)
			(stroke
				(width 0.1)
				(type default)
			)
			(layer "F.Fab")
		)
		(fp_line
			(start 0.12065 -0.2794)
			(end 0.12065 -0.3048)
			(stroke
				(width 0.1)
				(type default)
			)
			(layer "F.Fab")
		)
		(fp_line
			(start -0.12065 -0.2794)
			(end 0.12065 -0.2794)
			(stroke
				(width 0.1)
				(type default)
			)
			(layer "F.Fab")
		)
		(fp_line
			(start 0.120396 0.2794)
			(end -0.12065 0.2794)
			(stroke
				(width 0.1)
				(type default)
			)
			(layer "F.Fab")
		)
		(fp_line
			(start -0.12065 0.2794)
			(end -0.12065 0.3048)
			(stroke
				(width 0.1)
				(type default)
			)
			(layer "F.Fab")
		)
		(fp_line
			(start 0.67945 0.3048)
			(end 0.120396 0.3048)
			(stroke
				(width 0.1)
				(type default)
			)
			(layer "F.Fab")
		)
		(fp_line
			(start 0.120396 0.3048)
			(end 0.120396 0.2794)
			(stroke
				(width 0.1)
				(type default)
			)
			(layer "F.Fab")
		)
		(fp_line
			(start -0.12065 0.3048)
			(end -0.67945 0.3048)
			(stroke
				(width 0.1)
				(type default)
			)
			(layer "F.Fab")
		)
		(fp_line
			(start -0.67945 0.3048)
			(end -0.67945 -0.305054)
			(stroke
				(width 0.1)
				(type default)
			)
			(layer "F.Fab")
		)
		(pad "1" smd circle
			(at -0.40005 0 90)
			(size 0 0)
			(layers "F.Cu" "F.Mask" "F.Paste")
			(net "PVDDIO_P0_VCC1")
		)
		(pad "2" smd circle
			(at 0.40005 0 90)
			(size 0 0)
			(layers "F.Cu" "F.Mask" "F.Paste")
			(net "GND")
		)
	)
	(footprint ""
		(layer "F.Cu")
		(at 116.109496 -375.49963 -90)
		(property "Reference" "C1538"
			(at 0 0 270)
			(layer "F.SilkS")
			(hide yes)
			(effects
				(font
					(size 1.27 1.27)
				)
			)
		)
		(property "Value" ""
			(at 0 0 270)
			(layer "F.Fab")
			(effects
				(font
					(size 1.27 1.27)
				)
			)
		)
		(duplicate_pad_numbers_are_jumpers no)
		(fp_line
			(start -0.299974 0.150114)
			(end -0.299974 -0.150114)
			(stroke
				(width 0.1)
				(type default)
			)
			(layer "F.Fab")
		)
		(fp_line
			(start 0.299974 0.150114)
			(end -0.299974 0.150114)
			(stroke
				(width 0.1)
				(type default)
			)
			(layer "F.Fab")
		)
		(fp_line
			(start -0.299974 -0.150114)
			(end 0.299974 -0.150114)
			(stroke
				(width 0.1)
				(type default)
			)
			(layer "F.Fab")
		)
		(fp_line
			(start 0.299974 -0.150114)
			(end 0.299974 0.150114)
			(stroke
				(width 0.1)
				(type default)
			)
			(layer "F.Fab")
		)
		(pad "1" smd rect
			(at -0.2667 0 270)
			(size 0.3048 0.381)
			(layers "F.Cu" "F.Mask" "F.Paste")
			(net "P5E_CPU1_P3_TX_C_DN<4>")
		)
		(pad "2" smd rect
			(at 0.2667 0 270)
			(size 0.3048 0.381)
			(layers "F.Cu" "F.Mask" "F.Paste")
			(net "P5E_CPU1_P3_TX_DN<4>")
		)
	)
	(footprint ""
		(layer "F.Cu")
		(at 17.812258 -427.580298 90)
		(property "Reference" "R6170"
			(at 0 0 90)
			(layer "F.SilkS")
			(hide yes)
			(effects
				(font
					(size 1.27 1.27)
				)
			)
		)
		(property "Value" ""
			(at 0 0 90)
			(layer "F.Fab")
			(effects
				(font
					(size 1.27 1.27)
				)
			)
		)
		(duplicate_pad_numbers_are_jumpers no)
		(fp_line
			(start 0.7874 -0.4064)
			(end 0.7874 0.4064)
			(stroke
				(width 0.1524)
				(type default)
			)
			(layer "F.SilkS")
		)
		(fp_line
			(start -0.7874 -0.4064)
			(end 0.7874 -0.4064)
			(stroke
				(width 0.1524)
				(type default)
			)
			(layer "F.SilkS")
		)
		(fp_line
			(start 0.7874 0.4064)
			(end -0.7874 0.4064)
			(stroke
				(width 0.1524)
				(type default)
			)
			(layer "F.SilkS")
		)
		(fp_line
			(start -0.7874 0.4064)
			(end -0.7874 -0.4064)
			(stroke
				(width 0.1524)
				(type default)
			)
			(layer "F.SilkS")
		)
		(fp_line
			(start -0.12065 -0.305054)
			(end -0.12065 -0.2794)
			(stroke
				(width 0.1)
				(type default)
			)
			(layer "F.Fab")
		)
		(fp_line
			(start -0.67945 -0.305054)
			(end -0.12065 -0.305054)
			(stroke
				(width 0.1)
				(type default)
			)
			(layer "F.Fab")
		)
		(fp_line
			(start 0.67945 -0.3048)
			(end 0.67945 0.3048)
			(stroke
				(width 0.1)
				(type default)
			)
			(layer "F.Fab")
		)
		(fp_line
			(start 0.12065 -0.3048)
			(end 0.67945 -0.3048)
			(stroke
				(width 0.1)
				(type default)
			)
			(layer "F.Fab")
		)
		(fp_line
			(start 0.12065 -0.2794)
			(end 0.12065 -0.3048)
			(stroke
				(width 0.1)
				(type default)
			)
			(layer "F.Fab")
		)
		(fp_line
			(start -0.12065 -0.2794)
			(end 0.12065 -0.2794)
			(stroke
				(width 0.1)
				(type default)
			)
			(layer "F.Fab")
		)
		(fp_line
			(start 0.120396 0.2794)
			(end -0.12065 0.2794)
			(stroke
				(width 0.1)
				(type default)
			)
			(layer "F.Fab")
		)
		(fp_line
			(start -0.12065 0.2794)
			(end -0.12065 0.3048)
			(stroke
				(width 0.1)
				(type default)
			)
			(layer "F.Fab")
		)
		(fp_line
			(start 0.67945 0.3048)
			(end 0.120396 0.3048)
			(stroke
				(width 0.1)
				(type default)
			)
			(layer "F.Fab")
		)
		(fp_line
			(start 0.120396 0.3048)
			(end 0.120396 0.2794)
			(stroke
				(width 0.1)
				(type default)
			)
			(layer "F.Fab")
		)
		(fp_line
			(start -0.12065 0.3048)
			(end -0.67945 0.3048)
			(stroke
				(width 0.1)
				(type default)
			)
			(layer "F.Fab")
		)
		(fp_line
			(start -0.67945 0.3048)
			(end -0.67945 -0.305054)
			(stroke
				(width 0.1)
				(type default)
			)
			(layer "F.Fab")
		)
		(pad "1" smd circle
			(at -0.40005 0 90)
			(size 0 0)
			(layers "F.Cu" "F.Mask" "F.Paste")
			(net "FM_P2E_BUF2_VODA_DB")
		)
		(pad "2" smd circle
			(at 0.40005 0 90)
			(size 0 0)
			(layers "F.Cu" "F.Mask" "F.Paste")
			(net "GND")
		)
	)
	(footprint ""
		(layer "F.Cu")
		(at 329.917044 -151.14397 -90)
		(property "Reference" "PC215"
			(at 0 0 270)
			(layer "F.SilkS")
			(hide yes)
			(effects
				(font
					(size 1.27 1.27)
				)
			)
		)
		(property "Value" ""
			(at 0 0 270)
			(layer "F.Fab")
			(effects
				(font
					(size 1.27 1.27)
				)
			)
		)
		(duplicate_pad_numbers_are_jumpers no)
		(fp_line
			(start -0.7874 0.4064)
			(end -0.7874 -0.4064)
			(stroke
				(width 0.1524)
				(type default)
			)
			(layer "F.SilkS")
		)
		(fp_line
			(start 0.7874 0.4064)
			(end -0.7874 0.4064)
			(stroke
				(width 0.1524)
				(type default)
			)
			(layer "F.SilkS")
		)
		(fp_line
			(start -0.7874 -0.4064)
			(end 0.7874 -0.4064)
			(stroke
				(width 0.1524)
				(type default)
			)
			(layer "F.SilkS")
		)
		(fp_line
			(start 0.7874 -0.4064)
			(end 0.7874 0.4064)
			(stroke
				(width 0.1524)
				(type default)
			)
			(layer "F.SilkS")
		)
		(fp_line
			(start -0.67945 0.3048)
			(end -0.67945 -0.305054)
			(stroke
				(width 0.1)
				(type default)
			)
			(layer "F.Fab")
		)
		(fp_line
			(start -0.12065 0.3048)
			(end -0.67945 0.3048)
			(stroke
				(width 0.1)
				(type default)
			)
			(layer "F.Fab")
		)
		(fp_line
			(start 0.120396 0.3048)
			(end 0.120396 0.2794)
			(stroke
				(width 0.1)
				(type default)
			)
			(layer "F.Fab")
		)
		(fp_line
			(start 0.67945 0.3048)
			(end 0.120396 0.3048)
			(stroke
				(width 0.1)
				(type default)
			)
			(layer "F.Fab")
		)
		(fp_line
			(start -0.12065 0.2794)
			(end -0.12065 0.3048)
			(stroke
				(width 0.1)
				(type default)
			)
			(layer "F.Fab")
		)
		(fp_line
			(start 0.120396 0.2794)
			(end -0.12065 0.2794)
			(stroke
				(width 0.1)
				(type default)
			)
			(layer "F.Fab")
		)
		(fp_line
			(start -0.12065 -0.2794)
			(end 0.12065 -0.2794)
			(stroke
				(width 0.1)
				(type default)
			)
			(layer "F.Fab")
		)
		(fp_line
			(start 0.12065 -0.2794)
			(end 0.12065 -0.3048)
			(stroke
				(width 0.1)
				(type default)
			)
			(layer "F.Fab")
		)
		(fp_line
			(start 0.12065 -0.3048)
			(end 0.67945 -0.3048)
			(stroke
				(width 0.1)
				(type default)
			)
			(layer "F.Fab")
		)
		(fp_line
			(start 0.67945 -0.3048)
			(end 0.67945 0.3048)
			(stroke
				(width 0.1)
				(type default)
			)
			(layer "F.Fab")
		)
		(fp_line
			(start -0.67945 -0.305054)
			(end -0.12065 -0.305054)
			(stroke
				(width 0.1)
				(type default)
			)
			(layer "F.Fab")
		)
		(fp_line
			(start -0.12065 -0.305054)
			(end -0.12065 -0.2794)
			(stroke
				(width 0.1)
				(type default)
			)
			(layer "F.Fab")
		)
		(pad "1" smd circle
			(at -0.40005 0 270)
			(size 0 0)
			(layers "F.Cu" "F.Mask" "F.Paste")
			(net "PVDD18_S5_P0")
		)
		(pad "2" smd circle
			(at 0.40005 0 270)
			(size 0 0)
			(layers "F.Cu" "F.Mask" "F.Paste")
			(net "GND")
		)
	)
	(footprint ""
		(layer "F.Cu")
		(at 118.618 -440.309 180)
		(property "Reference" "R3491"
			(at 0 0 180)
			(layer "F.SilkS")
			(hide yes)
			(effects
				(font
					(size 1.27 1.27)
				)
			)
		)
		(property "Value" ""
			(at 0 0 180)
			(layer "F.Fab")
			(effects
				(font
					(size 1.27 1.27)
				)
			)
		)
		(duplicate_pad_numbers_are_jumpers no)
		(fp_line
			(start 0.7874 0.4064)
			(end -0.7874 0.4064)
			(stroke
				(width 0.1524)
				(type default)
			)
			(layer "F.SilkS")
		)
		(fp_line
			(start 0.7874 -0.4064)
			(end 0.7874 0.4064)
			(stroke
				(width 0.1524)
				(type default)
			)
			(layer "F.SilkS")
		)
		(fp_line
			(start -0.7874 0.4064)
			(end -0.7874 -0.4064)
			(stroke
				(width 0.1524)
				(type default)
			)
			(layer "F.SilkS")
		)
		(fp_line
			(start -0.7874 -0.4064)
			(end 0.7874 -0.4064)
			(stroke
				(width 0.1524)
				(type default)
			)
			(layer "F.SilkS")
		)
		(fp_line
			(start 0.67945 0.3048)
			(end 0.120396 0.3048)
			(stroke
				(width 0.1)
				(type default)
			)
			(layer "F.Fab")
		)
		(fp_line
			(start 0.67945 -0.3048)
			(end 0.67945 0.3048)
			(stroke
				(width 0.1)
				(type default)
			)
			(layer "F.Fab")
		)
		(fp_line
			(start 0.12065 -0.2794)
			(end 0.12065 -0.3048)
			(stroke
				(width 0.1)
				(type default)
			)
			(layer "F.Fab")
		)
		(fp_line
			(start 0.12065 -0.3048)
			(end 0.67945 -0.3048)
			(stroke
				(width 0.1)
				(type default)
			)
			(layer "F.Fab")
		)
		(fp_line
			(start 0.120396 0.3048)
			(end 0.120396 0.2794)
			(stroke
				(width 0.1)
				(type default)
			)
			(layer "F.Fab")
		)
		(fp_line
			(start 0.120396 0.2794)
			(end -0.12065 0.2794)
			(stroke
				(width 0.1)
				(type default)
			)
			(layer "F.Fab")
		)
		(fp_line
			(start -0.12065 0.3048)
			(end -0.67945 0.3048)
			(stroke
				(width 0.1)
				(type default)
			)
			(layer "F.Fab")
		)
		(fp_line
			(start -0.12065 0.2794)
			(end -0.12065 0.3048)
			(stroke
				(width 0.1)
				(type default)
			)
			(layer "F.Fab")
		)
		(fp_line
			(start -0.12065 -0.2794)
			(end 0.12065 -0.2794)
			(stroke
				(width 0.1)
				(type default)
			)
			(layer "F.Fab")
		)
		(fp_line
			(start -0.12065 -0.305054)
			(end -0.12065 -0.2794)
			(stroke
				(width 0.1)
				(type default)
			)
			(layer "F.Fab")
		)
		(fp_line
			(start -0.67945 0.3048)
			(end -0.67945 -0.305054)
			(stroke
				(width 0.1)
				(type default)
			)
			(layer "F.Fab")
		)
		(fp_line
			(start -0.67945 -0.305054)
			(end -0.12065 -0.305054)
			(stroke
				(width 0.1)
				(type default)
			)
			(layer "F.Fab")
		)
		(pad "1" smd circle
			(at -0.40005 0 180)
			(size 0 0)
			(layers "F.Cu" "F.Mask" "F.Paste")
			(net "GPU_FPGA_EROT_RECOV_N")
		)
		(pad "2" smd circle
			(at 0.40005 0 180)
			(size 0 0)
			(layers "F.Cu" "F.Mask" "F.Paste")
			(net "GND")
		)
	)
	(footprint ""
		(layer "F.Cu")
		(at 423.64406 -351.114868)
		(property "Reference" "PU22"
			(at -5.372862 3.17627 90)
			(unlocked yes)
			(layer "F.SilkS")
			(effects
				(font
					(size 0.7874 0.5842)
					(thickness 0.1524)
				)
				(justify left)
			)
		)
		(property "Value" ""
			(at 0 0 0)
			(layer "F.Fab")
			(effects
				(font
					(size 1.27 1.27)
				)
			)
		)
		(duplicate_pad_numbers_are_jumpers no)
		(fp_line
			(start -2.500122 -2.999994)
			(end -2.24409 -2.999994)
			(stroke
				(width 0.1524)
				(type default)
			)
			(layer "F.SilkS")
		)
		(fp_line
			(start -2.500122 -2.529078)
			(end -2.500122 -2.999994)
			(stroke
				(width 0.1524)
				(type default)
			)
			(layer "F.SilkS")
		)
		(fp_line
			(start -2.500122 0.6604)
			(end -2.500122 0.229108)
			(stroke
				(width 0.1524)
				(type default)
			)
			(layer "F.SilkS")
		)
		(fp_line
			(start -2.500122 2.999994)
			(end -2.500122 2.339594)
			(stroke
				(width 0.1524)
				(type default)
			)
			(layer "F.SilkS")
		)
		(fp_line
			(start -2.2987 2.999994)
			(end -2.500122 2.999994)
			(stroke
				(width 0.1524)
				(type default)
			)
			(layer "F.SilkS")
		)
		(fp_line
			(start 2.31394 -2.999994)
			(end 2.500122 -2.999994)
			(stroke
				(width 0.1524)
				(type default)
			)
			(layer "F.SilkS")
		)
		(fp_line
			(start 2.500122 -2.999994)
			(end 2.500122 -2.44348)
			(stroke
				(width 0.1524)
				(type default)
			)
			(layer "F.SilkS")
		)
		(fp_line
			(start 2.500122 2.339594)
			(end 2.500122 2.999994)
			(stroke
				(width 0.1524)
				(type default)
			)
			(layer "F.SilkS")
		)
		(fp_line
			(start 2.500122 2.999994)
			(end 2.2987 2.999994)
			(stroke
				(width 0.1524)
				(type default)
			)
			(layer "F.SilkS")
		)
		(fp_poly
			(pts
				(xy -2.712974 -2.443988) (xy -3.386328 -2.668524) (xy -2.93751 -3.117596)
			)
			(stroke
				(width 0)
				(type default)
			)
			(fill yes)
			(layer "F.SilkS")
		)
		(fp_line
			(start -2.500122 -2.999994)
			(end 2.500122 -2.999994)
			(stroke
				(width 0.1)
				(type default)
			)
			(layer "F.Fab")
		)
		(fp_line
			(start -2.500122 2.999994)
			(end -2.500122 -2.999994)
			(stroke
				(width 0.1)
				(type default)
			)
			(layer "F.Fab")
		)
		(fp_line
			(start 2.500122 -2.999994)
			(end 2.500122 2.999994)
			(stroke
				(width 0.1)
				(type default)
			)
			(layer "F.Fab")
		)
		(fp_line
			(start 2.500122 2.999994)
			(end -2.500122 2.999994)
			(stroke
				(width 0.1)
				(type default)
			)
			(layer "F.Fab")
		)
		(fp_poly
			(pts
				(xy -4.218432 -2.783078) (xy -4.218432 -1.767078) (xy -3.202432 -2.275078)
			)
			(stroke
				(width 0)
				(type default)
			)
			(fill yes)
			(layer "F.Fab")
		)
		(pad "1" smd rect
			(at -2.400046 -2.275078 90)
			(size 0.2286 0.6096)
			(layers "F.Cu" "F.Mask" "F.Paste")
			(net "PVDD11_S3_P0_VOS1")
		)
		(pad "2" smd rect
			(at -2.400046 -1.82499 90)
			(size 0.2286 0.6096)
			(layers "F.Cu" "F.Mask" "F.Paste")
			(net "GND")
		)
		(pad "3" smd rect
			(at -2.400046 -1.374902 90)
			(size 0.2286 0.6096)
			(layers "F.Cu" "F.Mask" "F.Paste")
			(net "PVDD11_S3_P0_VCC1")
		)
		(pad "4" smd rect
			(at -2.400046 -0.925068 90)
			(size 0.2286 0.6096)
			(layers "F.Cu" "F.Mask" "F.Paste")
			(net "PVDD11_S3_P0_PVCC")
		)
		(pad "5" smd rect
			(at -2.400046 -0.47498 90)
			(size 0.2286 0.6096)
			(layers "F.Cu" "F.Mask" "F.Paste")
			(net "GND")
		)
		(pad "6" smd rect
			(at -2.400046 -0.024892 90)
			(size 0.2286 0.6096)
			(layers "F.Cu" "F.Mask" "F.Paste")
			(net "NC_PVDD11_S3_P0_GL1_1")
		)
		(pad "7_9-20_24" smd circle
			(at 0 1.150112 90)
			(size 0 0)
			(layers "F.Cu" "F.Mask" "F.Paste")
			(net "GND")
		)
		(pad "10_19" smd rect
			(at 0 2.899918 90)
			(size 0.6096 4.318)
			(layers "F.Cu" "F.Mask" "F.Paste")
			(net "SW_PVDD11_S3_P0_SW1")
		)
		(pad "25_29" smd rect
			(at 1.549908 -1.279906 270)
			(size 2.0574 2.3114)
			(layers "F.Cu" "F.Mask" "F.Paste")
			(net "SW_P12V_AUX_PVDD11_S3_P0_FLT")
		)
		(pad "30" smd rect
			(at 2.05994 -2.899918)
			(size 0.2286 0.6096)
			(layers "F.Cu" "F.Mask" "F.Paste")
			(net "SW_P12V_AUX_PVDD11_S3_P0_FLT")
		)
		(pad "31" smd rect
			(at 1.610106 -2.899918)
			(size 0.2286 0.6096)
			(layers "F.Cu" "F.Mask" "F.Paste")
			(net "NC_PVDD11_S3_P0_DNC1")
		)
		(pad "32" smd rect
			(at 1.160018 -2.899918)
			(size 0.2286 0.6096)
			(layers "F.Cu" "F.Mask" "F.Paste")
			(net "SW_PVDD11_S3_P0_PH1")
		)
		(pad "33" smd rect
			(at 0.70993 -2.899918)
			(size 0.2286 0.6096)
			(layers "F.Cu" "F.Mask" "F.Paste")
			(net "SW_PVDD11_S3_P0_BOOT1")
		)
		(pad "34" smd rect
			(at 0.260096 -2.899918)
			(size 0.2286 0.6096)
			(layers "F.Cu" "F.Mask" "F.Paste")
			(net "PVDD11_S3_P0_PWM1")
		)
		(pad "35" smd rect
			(at -0.189992 -2.899918)
			(size 0.2286 0.6096)
			(layers "F.Cu" "F.Mask" "F.Paste")
			(net "PVDD11_S3_P0_VCC1")
		)
		(pad "36" smd rect
			(at -0.64008 -2.899918)
			(size 0.2286 0.6096)
			(layers "F.Cu" "F.Mask" "F.Paste")
			(net "PVDD11_S3_P0_TEMP0")
		)
		(pad "37" smd rect
			(at -1.089914 -2.899918)
			(size 0.2286 0.6096)
			(layers "F.Cu" "F.Mask" "F.Paste")
			(net "PVDD11_S3_P0_LSET1")
		)
		(pad "38" smd rect
			(at -1.540002 -2.899918)
			(size 0.2286 0.6096)
			(layers "F.Cu" "F.Mask" "F.Paste")
			(net "PVDD11_S3_P0_IMON1")
		)
		(pad "39" smd rect
			(at -1.99009 -2.899918)
			(size 0.2286 0.6096)
			(layers "F.Cu" "F.Mask" "F.Paste")
			(net "PVDD11_S3_P0_VCCS")
		)
		(pad "40" smd rect
			(at -0.87503 -1.27508)
			(size 1.7526 1.9558)
			(layers "F.Cu" "F.Mask" "F.Paste")
			(net "GND")
		)
		(pad "41" smd rect
			(at -1.525016 0.249936 270)
			(size 0.3048 0.4572)
			(layers "F.Cu" "F.Mask" "F.Paste")
			(net "NC_PVDD11_S3_P0_GL2_1")
		)
		(zone
			(layer "F.Cu")
			(hatch none 0.5)
			(connect_pads
				(clearance 0)
			)
			(min_thickness 0.25)
			(keepout
				(tracks not_allowed)
				(vias allowed)
				(pads allowed)
				(copperpour not_allowed)
				(footprints allowed)
			)
			(placement
				(enabled no)
				(sheetname "")
			)
			(fill
				(thermal_gap 0.5)
				(thermal_bridge_width 0.5)
				(island_removal_mode 0)
			)
			(polygon
				(pts
					(xy 421.143938 -348.54007) (xy 421.143938 -348.864174) (xy 426.144182 -348.864174) (xy 426.144182 -348.114874)
					(xy 425.85386 -348.114874) (xy 425.85386 -348.57055) (xy 421.43426 -348.57055) (xy 421.43426 -348.54007)
				)
			)
		)
		(zone
			(layer "F.Cu")
			(hatch none 0.5)
			(connect_pads
				(clearance 0)
			)
			(min_thickness 0.25)
			(keepout
				(tracks not_allowed)
				(vias allowed)
				(pads allowed)
				(copperpour not_allowed)
				(footprints allowed)
			)
			(placement
				(enabled no)
				(sheetname "")
			)
			(fill
				(thermal_gap 0.5)
				(thermal_bridge_width 0.5)
				(island_removal_mode 0)
			)
			(polygon
				(pts
					(xy 423.69613 -351.361248) (xy 423.69613 -353.418648) (xy 421.84193 -353.418648) (xy 421.84193 -353.177602)
					(xy 421.599614 -353.177602) (xy 421.599614 -353.659186) (xy 425.4246 -353.659186) (xy 425.4246 -353.474274)
					(xy 423.987468 -353.474274) (xy 423.987468 -351.315274) (xy 426.144182 -351.315274) (xy 426.144182 -351.065592)
					(xy 423.991786 -351.065592)
				)
			)
		)
	)
	(footprint ""
		(layer "F.Cu")
		(at 264.387076 -421.169084 180)
		(property "Reference" "C1115"
			(at 0 0 180)
			(layer "F.SilkS")
			(hide yes)
			(effects
				(font
					(size 1.27 1.27)
				)
			)
		)
		(property "Value" ""
			(at 0 0 180)
			(layer "F.Fab")
			(effects
				(font
					(size 1.27 1.27)
				)
			)
		)
		(duplicate_pad_numbers_are_jumpers no)
		(fp_line
			(start 1.524 0.762)
			(end -1.524 0.762)
			(stroke
				(width 0.1524)
				(type default)
			)
			(layer "F.SilkS")
		)
		(fp_line
			(start 1.524 -0.762)
			(end 1.524 0.762)
			(stroke
				(width 0.1524)
				(type default)
			)
			(layer "F.SilkS")
		)
		(fp_line
			(start -1.524 0.762)
			(end -1.524 -0.762)
			(stroke
				(width 0.1524)
				(type default)
			)
			(layer "F.SilkS")
		)
		(fp_line
			(start -1.524 -0.762)
			(end 1.524 -0.762)
			(stroke
				(width 0.1524)
				(type default)
			)
			(layer "F.SilkS")
		)
		(fp_line
			(start 1.1049 0.724916)
			(end 1.1049 -0.724916)
			(stroke
				(width 0.1)
				(type default)
			)
			(layer "F.Fab")
		)
		(fp_line
			(start 1.1049 -0.724916)
			(end -1.1049 -0.724916)
			(stroke
				(width 0.1)
				(type default)
			)
			(layer "F.Fab")
		)
		(fp_line
			(start -1.1049 0.724916)
			(end 1.1049 0.724916)
			(stroke
				(width 0.1)
				(type default)
			)
			(layer "F.Fab")
		)
		(fp_line
			(start -1.1049 -0.724916)
			(end -1.1049 0.724916)
			(stroke
				(width 0.1)
				(type default)
			)
			(layer "F.Fab")
		)
		(pad "1" smd rect
			(at -0.889 0)
			(size 1.016 1.27)
			(layers "F.Cu" "F.Mask" "F.Paste")
			(net "PDB_PRSNT_R_N")
		)
		(pad "2" smd rect
			(at 0.889 0)
			(size 1.016 1.27)
			(layers "F.Cu" "F.Mask" "F.Paste")
			(net "GND")
		)
	)
	(footprint ""
		(layer "F.Cu")
		(at 178.187604 -151.764238 -90)
		(property "Reference" "U27"
			(at 0.229108 -2.722118 0)
			(unlocked yes)
			(layer "F.SilkS")
			(effects
				(font
					(size 0.7874 0.5842)
					(thickness 0.1524)
				)
				(justify left)
			)
		)
		(property "Value" ""
			(at 0 0 270)
			(layer "F.Fab")
			(effects
				(font
					(size 1.27 1.27)
				)
			)
		)
		(duplicate_pad_numbers_are_jumpers no)
		(fp_line
			(start -1.463548 1.549908)
			(end -1.463548 -1.549908)
			(stroke
				(width 0.1524)
				(type default)
			)
			(layer "F.SilkS")
		)
		(fp_line
			(start 1.463548 1.549908)
			(end -1.463548 1.549908)
			(stroke
				(width 0.1524)
				(type default)
			)
			(layer "F.SilkS")
		)
		(fp_line
			(start 0 -0.762)
			(end 0.762 -1.549908)
			(stroke
				(width 0.1524)
				(type default)
			)
			(layer "F.SilkS")
		)
		(fp_line
			(start -1.463548 -1.549908)
			(end -0.787908 -1.549908)
			(stroke
				(width 0.1524)
				(type default)
			)
			(layer "F.SilkS")
		)
		(fp_line
			(start -0.787908 -1.549908)
			(end 0 -0.762)
			(stroke
				(width 0.1524)
				(type default)
			)
			(layer "F.SilkS")
		)
		(fp_line
			(start 0.762 -1.549908)
			(end 1.463548 -1.549908)
			(stroke
				(width 0.1524)
				(type default)
			)
			(layer "F.SilkS")
		)
		(fp_line
			(start 1.463548 -1.549908)
			(end 1.463548 1.549908)
			(stroke
				(width 0.1524)
				(type default)
			)
			(layer "F.SilkS")
		)
		(fp_poly
			(pts
				(xy -3.4798 -0.740156) (xy -3.4798 -1.359916) (xy -2.86004 -1.050036)
			)
			(stroke
				(width 0)
				(type default)
			)
			(fill yes)
			(layer "F.SilkS")
		)
		(fp_line
			(start -1.549908 1.549908)
			(end -1.549908 -1.549908)
			(stroke
				(width 0.1)
				(type default)
			)
			(layer "F.Fab")
		)
		(fp_line
			(start 1.549908 1.549908)
			(end -1.549908 1.549908)
			(stroke
				(width 0.1)
				(type default)
			)
			(layer "F.Fab")
		)
		(fp_line
			(start -1.549908 -1.549908)
			(end 1.549908 -1.549908)
			(stroke
				(width 0.1)
				(type default)
			)
			(layer "F.Fab")
		)
		(fp_line
			(start 1.549908 -1.549908)
			(end 1.549908 1.549908)
			(stroke
				(width 0.1)
				(type default)
			)
			(layer "F.Fab")
		)
		(fp_poly
			(pts
				(xy -3.4798 -1.359916) (xy -2.86004 -1.050036) (xy -3.4798 -0.740156)
			)
			(stroke
				(width 0)
				(type default)
			)
			(fill yes)
			(layer "F.Fab")
		)
		(pad "1" smd rect
			(at -2.175002 -1.050036)
			(size 0.6096 1.1684)
			(layers "F.Cu" "F.Mask" "F.Paste")
			(net "PVDD18_S5_P0")
		)
		(pad "2" smd rect
			(at -2.175002 -0.32512)
			(size 0.4318 1.1684)
			(layers "F.Cu" "F.Mask" "F.Paste")
			(net "SMB_CPU0_4_SCL")
		)
		(pad "3" smd rect
			(at -2.175002 0.32512)
			(size 0.4318 1.1684)
			(layers "F.Cu" "F.Mask" "F.Paste")
			(net "SMB_CPU0_4_SDA")
		)
		(pad "4" smd rect
			(at -2.175002 1.050036)
			(size 0.6096 1.1684)
			(layers "F.Cu" "F.Mask" "F.Paste")
			(net "GND")
		)
		(pad "5" smd rect
			(at 2.175002 1.050036)
			(size 0.6096 1.1684)
			(layers "F.Cu" "F.Mask" "F.Paste")
			(net "TP_U27_EN")
		)
		(pad "6" smd rect
			(at 2.175002 0.32512)
			(size 0.4318 1.1684)
			(layers "F.Cu" "F.Mask" "F.Paste")
			(net "SMB_CPU0_4_XLTR_SDA")
		)
		(pad "7" smd rect
			(at 2.175002 -0.32512)
			(size 0.4318 1.1684)
			(layers "F.Cu" "F.Mask" "F.Paste")
			(net "SMB_CPU0_4_XLTR_SCL")
		)
		(pad "8" smd rect
			(at 2.175002 -1.050036)
			(size 0.6096 1.1684)
			(layers "F.Cu" "F.Mask" "F.Paste")
			(net "P3V3_AUX")
		)
	)
	(footprint ""
		(layer "F.Cu")
		(at 281.818588 -394.444982 -90)
		(property "Reference" "R2628"
			(at 0 0 270)
			(layer "F.SilkS")
			(hide yes)
			(effects
				(font
					(size 1.27 1.27)
				)
			)
		)
		(property "Value" ""
			(at 0 0 270)
			(layer "F.Fab")
			(effects
				(font
					(size 1.27 1.27)
				)
			)
		)
		(duplicate_pad_numbers_are_jumpers no)
		(fp_line
			(start -0.7874 0.4064)
			(end -0.7874 -0.4064)
			(stroke
				(width 0.1524)
				(type default)
			)
			(layer "F.SilkS")
		)
		(fp_line
			(start 0.7874 0.4064)
			(end -0.7874 0.4064)
			(stroke
				(width 0.1524)
				(type default)
			)
			(layer "F.SilkS")
		)
		(fp_line
			(start -0.7874 -0.4064)
			(end 0.7874 -0.4064)
			(stroke
				(width 0.1524)
				(type default)
			)
			(layer "F.SilkS")
		)
		(fp_line
			(start 0.7874 -0.4064)
			(end 0.7874 0.4064)
			(stroke
				(width 0.1524)
				(type default)
			)
			(layer "F.SilkS")
		)
		(fp_line
			(start -0.67945 0.3048)
			(end -0.67945 -0.305054)
			(stroke
				(width 0.1)
				(type default)
			)
			(layer "F.Fab")
		)
		(fp_line
			(start -0.12065 0.3048)
			(end -0.67945 0.3048)
			(stroke
				(width 0.1)
				(type default)
			)
			(layer "F.Fab")
		)
		(fp_line
			(start 0.120396 0.3048)
			(end 0.120396 0.2794)
			(stroke
				(width 0.1)
				(type default)
			)
			(layer "F.Fab")
		)
		(fp_line
			(start 0.67945 0.3048)
			(end 0.120396 0.3048)
			(stroke
				(width 0.1)
				(type default)
			)
			(layer "F.Fab")
		)
		(fp_line
			(start -0.12065 0.2794)
			(end -0.12065 0.3048)
			(stroke
				(width 0.1)
				(type default)
			)
			(layer "F.Fab")
		)
		(fp_line
			(start 0.120396 0.2794)
			(end -0.12065 0.2794)
			(stroke
				(width 0.1)
				(type default)
			)
			(layer "F.Fab")
		)
		(fp_line
			(start -0.12065 -0.2794)
			(end 0.12065 -0.2794)
			(stroke
				(width 0.1)
				(type default)
			)
			(layer "F.Fab")
		)
		(fp_line
			(start 0.12065 -0.2794)
			(end 0.12065 -0.3048)
			(stroke
				(width 0.1)
				(type default)
			)
			(layer "F.Fab")
		)
		(fp_line
			(start 0.12065 -0.3048)
			(end 0.67945 -0.3048)
			(stroke
				(width 0.1)
				(type default)
			)
			(layer "F.Fab")
		)
		(fp_line
			(start 0.67945 -0.3048)
			(end 0.67945 0.3048)
			(stroke
				(width 0.1)
				(type default)
			)
			(layer "F.Fab")
		)
		(fp_line
			(start -0.67945 -0.305054)
			(end -0.12065 -0.305054)
			(stroke
				(width 0.1)
				(type default)
			)
			(layer "F.Fab")
		)
		(fp_line
			(start -0.12065 -0.305054)
			(end -0.12065 -0.2794)
			(stroke
				(width 0.1)
				(type default)
			)
			(layer "F.Fab")
		)
		(pad "1" smd circle
			(at -0.40005 0 270)
			(size 0 0)
			(layers "F.Cu" "F.Mask" "F.Paste")
			(net "P12V_HSC_TEMP_ALERT_N")
		)
		(pad "2" smd circle
			(at 0.40005 0 270)
			(size 0 0)
			(layers "F.Cu" "F.Mask" "F.Paste")
			(net "P12V_HSC_TEMP_ALERT_R_N")
		)
	)
	(footprint ""
		(layer "F.Cu")
		(at 364.313978 -177.771298 180)
		(property "Reference" "PU6"
			(at -0.973074 -6.571742 0)
			(unlocked yes)
			(layer "F.SilkS")
			(effects
				(font
					(size 0.7874 0.5842)
					(thickness 0.1524)
				)
				(justify left)
			)
		)
		(property "Value" ""
			(at 0 0 180)
			(layer "F.Fab")
			(effects
				(font
					(size 1.27 1.27)
				)
			)
		)
		(duplicate_pad_numbers_are_jumpers no)
		(fp_line
			(start 2.500122 2.999994)
			(end 2.2987 2.999994)
			(stroke
				(width 0.1524)
				(type default)
			)
			(layer "F.SilkS")
		)
		(fp_line
			(start 2.500122 2.339594)
			(end 2.500122 2.999994)
			(stroke
				(width 0.1524)
				(type default)
			)
			(layer "F.SilkS")
		)
		(fp_line
			(start 2.500122 -2.999994)
			(end 2.500122 -2.44348)
			(stroke
				(width 0.1524)
				(type default)
			)
			(layer "F.SilkS")
		)
		(fp_line
			(start 2.31394 -2.999994)
			(end 2.500122 -2.999994)
			(stroke
				(width 0.1524)
				(type default)
			)
			(layer "F.SilkS")
		)
		(fp_line
			(start -2.2987 2.999994)
			(end -2.500122 2.999994)
			(stroke
				(width 0.1524)
				(type default)
			)
			(layer "F.SilkS")
		)
		(fp_line
			(start -2.500122 2.999994)
			(end -2.500122 2.339594)
			(stroke
				(width 0.1524)
				(type default)
			)
			(layer "F.SilkS")
		)
		(fp_line
			(start -2.500122 0.6604)
			(end -2.500122 0.229108)
			(stroke
				(width 0.1524)
				(type default)
			)
			(layer "F.SilkS")
		)
		(fp_line
			(start -2.500122 -2.529078)
			(end -2.500122 -2.999994)
			(stroke
				(width 0.1524)
				(type default)
			)
			(layer "F.SilkS")
		)
		(fp_line
			(start -2.500122 -2.999994)
			(end -2.24409 -2.999994)
			(stroke
				(width 0.1524)
				(type default)
			)
			(layer "F.SilkS")
		)
		(fp_poly
			(pts
				(xy -2.686558 -2.45618) (xy -3.376422 -2.68605) (xy -2.916428 -3.146044)
			)
			(stroke
				(width 0)
				(type default)
			)
			(fill yes)
			(layer "F.SilkS")
		)
		(fp_line
			(start 2.500122 2.999994)
			(end -2.500122 2.999994)
			(stroke
				(width 0.1)
				(type default)
			)
			(layer "F.Fab")
		)
		(fp_line
			(start 2.500122 -2.999994)
			(end 2.500122 2.999994)
			(stroke
				(width 0.1)
				(type default)
			)
			(layer "F.Fab")
		)
		(fp_line
			(start -2.500122 2.999994)
			(end -2.500122 -2.999994)
			(stroke
				(width 0.1)
				(type default)
			)
			(layer "F.Fab")
		)
		(fp_line
			(start -2.500122 -2.999994)
			(end 2.500122 -2.999994)
			(stroke
				(width 0.1)
				(type default)
			)
			(layer "F.Fab")
		)
		(fp_poly
			(pts
				(xy -4.218432 -2.783078) (xy -4.218432 -1.767078) (xy -3.202432 -2.275078)
			)
			(stroke
				(width 0)
				(type default)
			)
			(fill yes)
			(layer "F.Fab")
		)
		(pad "1" smd rect
			(at -2.400046 -2.275078 270)
			(size 0.2286 0.6096)
			(layers "F.Cu" "F.Mask" "F.Paste")
			(net "PVDDCR_CPU0_P0_VOS1")
		)
		(pad "2" smd rect
			(at -2.400046 -1.82499 270)
			(size 0.2286 0.6096)
			(layers "F.Cu" "F.Mask" "F.Paste")
			(net "GND")
		)
		(pad "3" smd rect
			(at -2.400046 -1.374902 270)
			(size 0.2286 0.6096)
			(layers "F.Cu" "F.Mask" "F.Paste")
			(net "PVDDCR_CPU0_P0_VCC1")
		)
		(pad "4" smd rect
			(at -2.400046 -0.925068 270)
			(size 0.2286 0.6096)
			(layers "F.Cu" "F.Mask" "F.Paste")
			(net "PVDDCR_CPU0_P0_PVCC")
		)
		(pad "5" smd rect
			(at -2.400046 -0.47498 270)
			(size 0.2286 0.6096)
			(layers "F.Cu" "F.Mask" "F.Paste")
			(net "GND")
		)
		(pad "6" smd rect
			(at -2.400046 -0.024892 270)
			(size 0.2286 0.6096)
			(layers "F.Cu" "F.Mask" "F.Paste")
			(net "NC_PVDDCR_CPU0_P0_GL1_1")
		)
		(pad "7_9-20_24" smd circle
			(at 0 1.150112 270)
			(size 0 0)
			(layers "F.Cu" "F.Mask" "F.Paste")
			(net "GND")
		)
		(pad "10_19" smd rect
			(at 0 2.899918 270)
			(size 0.6096 4.318)
			(layers "F.Cu" "F.Mask" "F.Paste")
			(net "SW_PVDDCR_CPU0_P0_SW1")
		)
		(pad "25_29" smd rect
			(at 1.549908 -1.279906 90)
			(size 2.0574 2.3114)
			(layers "F.Cu" "F.Mask" "F.Paste")
			(net "SW_P12V_AUX_PVDDCR_CPU0_P0_FLT")
		)
		(pad "30" smd rect
			(at 2.05994 -2.899918 180)
			(size 0.2286 0.6096)
			(layers "F.Cu" "F.Mask" "F.Paste")
			(net "SW_P12V_AUX_PVDDCR_CPU0_P0_FLT")
		)
		(pad "31" smd rect
			(at 1.610106 -2.899918 180)
			(size 0.2286 0.6096)
			(layers "F.Cu" "F.Mask" "F.Paste")
			(net "NC_PVDDCR_CPU0_P0_DNC1")
		)
		(pad "32" smd rect
			(at 1.160018 -2.899918 180)
			(size 0.2286 0.6096)
			(layers "F.Cu" "F.Mask" "F.Paste")
			(net "SW_PVDDCR_CPU0_P0_PH1")
		)
		(pad "33" smd rect
			(at 0.70993 -2.899918 180)
			(size 0.2286 0.6096)
			(layers "F.Cu" "F.Mask" "F.Paste")
			(net "SW_PVDDCR_CPU0_P0_BOOT1")
		)
		(pad "34" smd rect
			(at 0.260096 -2.899918 180)
			(size 0.2286 0.6096)
			(layers "F.Cu" "F.Mask" "F.Paste")
			(net "PVDDCR_CPU0_P0_PWM1")
		)
		(pad "35" smd rect
			(at -0.189992 -2.899918 180)
			(size 0.2286 0.6096)
			(layers "F.Cu" "F.Mask" "F.Paste")
			(net "PVDDCR_CPU0_P0_VCC1")
		)
		(pad "36" smd rect
			(at -0.64008 -2.899918 180)
			(size 0.2286 0.6096)
			(layers "F.Cu" "F.Mask" "F.Paste")
			(net "PVDDCR_CPU0_P0_TEMP0")
		)
		(pad "37" smd rect
			(at -1.089914 -2.899918 180)
			(size 0.2286 0.6096)
			(layers "F.Cu" "F.Mask" "F.Paste")
			(net "PVDDCR_CPU0_P0_LSET1")
		)
		(pad "38" smd rect
			(at -1.540002 -2.899918 180)
			(size 0.2286 0.6096)
			(layers "F.Cu" "F.Mask" "F.Paste")
			(net "PVDDCR_CPU0_P0_IMON1")
		)
		(pad "39" smd rect
			(at -1.99009 -2.899918 180)
			(size 0.2286 0.6096)
			(layers "F.Cu" "F.Mask" "F.Paste")
			(net "PVDDCR_CPU0_P0_VCCS")
		)
		(pad "40" smd rect
			(at -0.87503 -1.27508 180)
			(size 1.7526 1.9558)
			(layers "F.Cu" "F.Mask" "F.Paste")
			(net "GND")
		)
		(pad "41" smd rect
			(at -1.525016 0.249936 90)
			(size 0.3048 0.4572)
			(layers "F.Cu" "F.Mask" "F.Paste")
			(net "NC_PVDDCR_CPU0_P0_GL2_1")
		)
		(zone
			(layer "F.Cu")
			(hatch none 0.5)
			(connect_pads
				(clearance 0)
			)
			(min_thickness 0.25)
			(keepout
				(tracks not_allowed)
				(vias allowed)
				(pads allowed)
				(copperpour not_allowed)
				(footprints allowed)
			)
			(placement
				(enabled no)
				(sheetname "")
			)
			(fill
				(thermal_gap 0.5)
				(thermal_bridge_width 0.5)
				(island_removal_mode 0)
			)
			(polygon
				(pts
					(xy 366.8141 -180.353462) (xy 366.8141 -180.021992) (xy 361.813856 -180.021992) (xy 361.813856 -180.350668)
					(xy 362.104178 -180.350668) (xy 362.104178 -180.315616) (xy 366.523778 -180.315616) (xy 366.523778 -180.353462)
				)
			)
		)
		(zone
			(layer "F.Cu")
			(hatch none 0.5)
			(connect_pads
				(clearance 0)
			)
			(min_thickness 0.25)
			(keepout
				(tracks not_allowed)
				(vias allowed)
				(pads allowed)
				(copperpour not_allowed)
				(footprints allowed)
			)
			(placement
				(enabled no)
				(sheetname "")
			)
			(fill
				(thermal_gap 0.5)
				(thermal_bridge_width 0.5)
				(island_removal_mode 0)
			)
			(polygon
				(pts
					(xy 364.261908 -177.52314) (xy 364.261908 -175.467518) (xy 366.116108 -175.467518) (xy 366.116108 -175.708564)
					(xy 366.358424 -175.708564) (xy 366.358424 -175.22698) (xy 362.445808 -175.22698) (xy 362.445808 -175.411892)
					(xy 363.97057 -175.411892) (xy 363.97057 -177.570892) (xy 361.813856 -177.570892) (xy 361.813856 -177.820574)
					(xy 363.964474 -177.820574)
				)
			)
		)
	)
	(footprint ""
		(layer "F.Cu")
		(at 65.1002 -18.6436 180)
		(property "Reference" "PC2152"
			(at 0 0 180)
			(layer "F.SilkS")
			(hide yes)
			(effects
				(font
					(size 1.27 1.27)
				)
			)
		)
		(property "Value" ""
			(at 0 0 180)
			(layer "F.Fab")
			(effects
				(font
					(size 1.27 1.27)
				)
			)
		)
		(duplicate_pad_numbers_are_jumpers no)
		(fp_line
			(start 0.7874 0.4064)
			(end -0.7874 0.4064)
			(stroke
				(width 0.1524)
				(type default)
			)
			(layer "F.SilkS")
		)
		(fp_line
			(start 0.7874 -0.4064)
			(end 0.7874 0.4064)
			(stroke
				(width 0.1524)
				(type default)
			)
			(layer "F.SilkS")
		)
		(fp_line
			(start -0.7874 0.4064)
			(end -0.7874 -0.4064)
			(stroke
				(width 0.1524)
				(type default)
			)
			(layer "F.SilkS")
		)
		(fp_line
			(start -0.7874 -0.4064)
			(end 0.7874 -0.4064)
			(stroke
				(width 0.1524)
				(type default)
			)
			(layer "F.SilkS")
		)
		(fp_line
			(start 0.67945 0.3048)
			(end 0.120396 0.3048)
			(stroke
				(width 0.1)
				(type default)
			)
			(layer "F.Fab")
		)
		(fp_line
			(start 0.67945 -0.3048)
			(end 0.67945 0.3048)
			(stroke
				(width 0.1)
				(type default)
			)
			(layer "F.Fab")
		)
		(fp_line
			(start 0.12065 -0.2794)
			(end 0.12065 -0.3048)
			(stroke
				(width 0.1)
				(type default)
			)
			(layer "F.Fab")
		)
		(fp_line
			(start 0.12065 -0.3048)
			(end 0.67945 -0.3048)
			(stroke
				(width 0.1)
				(type default)
			)
			(layer "F.Fab")
		)
		(fp_line
			(start 0.120396 0.3048)
			(end 0.120396 0.2794)
			(stroke
				(width 0.1)
				(type default)
			)
			(layer "F.Fab")
		)
		(fp_line
			(start 0.120396 0.2794)
			(end -0.12065 0.2794)
			(stroke
				(width 0.1)
				(type default)
			)
			(layer "F.Fab")
		)
		(fp_line
			(start -0.12065 0.3048)
			(end -0.67945 0.3048)
			(stroke
				(width 0.1)
				(type default)
			)
			(layer "F.Fab")
		)
		(fp_line
			(start -0.12065 0.2794)
			(end -0.12065 0.3048)
			(stroke
				(width 0.1)
				(type default)
			)
			(layer "F.Fab")
		)
		(fp_line
			(start -0.12065 -0.2794)
			(end 0.12065 -0.2794)
			(stroke
				(width 0.1)
				(type default)
			)
			(layer "F.Fab")
		)
		(fp_line
			(start -0.12065 -0.305054)
			(end -0.12065 -0.2794)
			(stroke
				(width 0.1)
				(type default)
			)
			(layer "F.Fab")
		)
		(fp_line
			(start -0.67945 0.3048)
			(end -0.67945 -0.305054)
			(stroke
				(width 0.1)
				(type default)
			)
			(layer "F.Fab")
		)
		(fp_line
			(start -0.67945 -0.305054)
			(end -0.12065 -0.305054)
			(stroke
				(width 0.1)
				(type default)
			)
			(layer "F.Fab")
		)
		(pad "1" smd circle
			(at -0.40005 0 180)
			(size 0 0)
			(layers "F.Cu" "F.Mask" "F.Paste")
			(net "P12V_OCP_V3_2")
		)
		(pad "2" smd circle
			(at 0.40005 0 180)
			(size 0 0)
			(layers "F.Cu" "F.Mask" "F.Paste")
			(net "GND")
		)
	)
	(footprint ""
		(layer "F.Cu")
		(at 439.295032 -25.330658 180)
		(property "Reference" "PC2158"
			(at 0 0 180)
			(layer "F.SilkS")
			(hide yes)
			(effects
				(font
					(size 1.27 1.27)
				)
			)
		)
		(property "Value" ""
			(at 0 0 180)
			(layer "F.Fab")
			(effects
				(font
					(size 1.27 1.27)
				)
			)
		)
		(duplicate_pad_numbers_are_jumpers no)
		(fp_line
			(start 1.2954 0.5842)
			(end -1.2954 0.5842)
			(stroke
				(width 0.1524)
				(type default)
			)
			(layer "F.SilkS")
		)
		(fp_line
			(start 1.2954 -0.5842)
			(end 1.2954 0.5842)
			(stroke
				(width 0.1524)
				(type default)
			)
			(layer "F.SilkS")
		)
		(fp_line
			(start -1.2954 0.5842)
			(end -1.2954 -0.5842)
			(stroke
				(width 0.1524)
				(type default)
			)
			(layer "F.SilkS")
		)
		(fp_line
			(start -1.2954 -0.5842)
			(end 1.2954 -0.5842)
			(stroke
				(width 0.1524)
				(type default)
			)
			(layer "F.SilkS")
		)
		(fp_line
			(start 1.1938 0.4064)
			(end 0.8636 0.4064)
			(stroke
				(width 0.1)
				(type default)
			)
			(layer "F.Fab")
		)
		(fp_line
			(start 1.1938 -0.4064)
			(end 1.1938 0.4064)
			(stroke
				(width 0.1)
				(type default)
			)
			(layer "F.Fab")
		)
		(fp_line
			(start 0.8636 0.4572)
			(end -0.8636 0.4572)
			(stroke
				(width 0.1)
				(type default)
			)
			(layer "F.Fab")
		)
		(fp_line
			(start 0.8636 0.4064)
			(end 0.8636 0.4572)
			(stroke
				(width 0.1)
				(type default)
			)
			(layer "F.Fab")
		)
		(fp_line
			(start 0.8636 -0.4064)
			(end 1.1938 -0.4064)
			(stroke
				(width 0.1)
				(type default)
			)
			(layer "F.Fab")
		)
		(fp_line
			(start 0.8636 -0.4572)
			(end 0.8636 -0.4064)
			(stroke
				(width 0.1)
				(type default)
			)
			(layer "F.Fab")
		)
		(fp_line
			(start -0.8636 0.4572)
			(end -0.8636 0.4064)
			(stroke
				(width 0.1)
				(type default)
			)
			(layer "F.Fab")
		)
		(fp_line
			(start -0.8636 0.4064)
			(end -1.1938 0.4064)
			(stroke
				(width 0.1)
				(type default)
			)
			(layer "F.Fab")
		)
		(fp_line
			(start -0.8636 -0.4064)
			(end -0.8636 -0.4572)
			(stroke
				(width 0.1)
				(type default)
			)
			(layer "F.Fab")
		)
		(fp_line
			(start -0.8636 -0.4572)
			(end 0.8636 -0.4572)
			(stroke
				(width 0.1)
				(type default)
			)
			(layer "F.Fab")
		)
		(fp_line
			(start -1.1938 0.4064)
			(end -1.1938 -0.4064)
			(stroke
				(width 0.1)
				(type default)
			)
			(layer "F.Fab")
		)
		(fp_line
			(start -1.1938 -0.4064)
			(end -0.8636 -0.4064)
			(stroke
				(width 0.1)
				(type default)
			)
			(layer "F.Fab")
		)
		(pad "1" smd rect
			(at -0.7366 0 90)
			(size 0.7112 0.8128)
			(layers "F.Cu" "F.Mask" "F.Paste")
			(net "P12V_OCP_AVIN_PD_1")
		)
		(pad "2" smd rect
			(at 0.7366 0 90)
			(size 0.7112 0.8128)
			(layers "F.Cu" "F.Mask" "F.Paste")
			(net "GND")
		)
	)
	(footprint ""
		(layer "F.Cu")
		(at 333.215488 -403.818852 -90)
		(property "Reference" "R1023"
			(at 0 0 270)
			(layer "F.SilkS")
			(hide yes)
			(effects
				(font
					(size 1.27 1.27)
				)
			)
		)
		(property "Value" ""
			(at 0 0 270)
			(layer "F.Fab")
			(effects
				(font
					(size 1.27 1.27)
				)
			)
		)
		(duplicate_pad_numbers_are_jumpers no)
		(fp_line
			(start -0.32512 0.175006)
			(end -0.32512 -0.175006)
			(stroke
				(width 0.1)
				(type default)
			)
			(layer "F.Fab")
		)
		(fp_line
			(start 0.32512 0.175006)
			(end -0.32512 0.175006)
			(stroke
				(width 0.1)
				(type default)
			)
			(layer "F.Fab")
		)
		(fp_line
			(start -0.32512 -0.175006)
			(end 0.32512 -0.175006)
			(stroke
				(width 0.1)
				(type default)
			)
			(layer "F.Fab")
		)
		(fp_line
			(start 0.32512 -0.175006)
			(end 0.32512 0.175006)
			(stroke
				(width 0.1)
				(type default)
			)
			(layer "F.Fab")
		)
		(pad "1" smd rect
			(at -0.2667 0 270)
			(size 0.3048 0.381)
			(layers "F.Cu" "F.Mask" "F.Paste")
			(net "P1V8_CPU0_RT_1D")
		)
		(pad "2" smd rect
			(at 0.2667 0 90)
			(size 0.3048 0.381)
			(layers "F.Cu" "F.Mask" "F.Paste")
			(net "RST_RT_CPU0_P1_RESET_R_N")
		)
	)
	(footprint ""
		(layer "F.Cu")
		(at 113.34496 -395.441932 -90)
		(property "Reference" "R925"
			(at 0 0 270)
			(layer "F.SilkS")
			(hide yes)
			(effects
				(font
					(size 1.27 1.27)
				)
			)
		)
		(property "Value" ""
			(at 0 0 270)
			(layer "F.Fab")
			(effects
				(font
					(size 1.27 1.27)
				)
			)
		)
		(duplicate_pad_numbers_are_jumpers no)
		(fp_line
			(start -0.32512 0.175006)
			(end -0.32512 -0.175006)
			(stroke
				(width 0.1)
				(type default)
			)
			(layer "F.Fab")
		)
		(fp_line
			(start 0.32512 0.175006)
			(end -0.32512 0.175006)
			(stroke
				(width 0.1)
				(type default)
			)
			(layer "F.Fab")
		)
		(fp_line
			(start -0.32512 -0.175006)
			(end 0.32512 -0.175006)
			(stroke
				(width 0.1)
				(type default)
			)
			(layer "F.Fab")
		)
		(fp_line
			(start 0.32512 -0.175006)
			(end 0.32512 0.175006)
			(stroke
				(width 0.1)
				(type default)
			)
			(layer "F.Fab")
		)
		(pad "1" smd rect
			(at -0.2667 0 270)
			(size 0.3048 0.381)
			(layers "F.Cu" "F.Mask" "F.Paste")
			(net "P1V8_CPU1_RT_1D")
		)
		(pad "2" smd rect
			(at 0.2667 0 90)
			(size 0.3048 0.381)
			(layers "F.Cu" "F.Mask" "F.Paste")
			(net "MODE_RT_CPU1_P3")
		)
	)
	(footprint ""
		(layer "F.Cu")
		(at 6.999986 -22.29993)
		(property "Reference" "H91"
			(at -5.190744 -5.784596 0)
			(unlocked yes)
			(layer "F.SilkS")
			(effects
				(font
					(size 0.7874 0.5842)
					(thickness 0.1524)
				)
				(justify left)
			)
		)
		(property "Value" ""
			(at 0 0 0)
			(layer "F.Fab")
			(effects
				(font
					(size 1.27 1.27)
				)
			)
		)
		(duplicate_pad_numbers_are_jumpers no)
		(pad "1" thru_hole circle
			(at 0 0)
			(size 10.0076 10.0076)
			(drill 5.6134)
			(layers "*.Cu" "*.Mask")
			(remove_unused_layers no)
			(net "GND")
			(clearance -1.9431)
		)
	)
	(footprint ""
		(layer "F.Cu")
		(at 31.585662 -419.249098 -90)
		(property "Reference" "R3276"
			(at 0 0 270)
			(layer "F.SilkS")
			(hide yes)
			(effects
				(font
					(size 1.27 1.27)
				)
			)
		)
		(property "Value" ""
			(at 0 0 270)
			(layer "F.Fab")
			(effects
				(font
					(size 1.27 1.27)
				)
			)
		)
		(duplicate_pad_numbers_are_jumpers no)
		(fp_line
			(start -0.7874 0.4064)
			(end -0.7874 -0.4064)
			(stroke
				(width 0.1524)
				(type default)
			)
			(layer "F.SilkS")
		)
		(fp_line
			(start 0.7874 0.4064)
			(end -0.7874 0.4064)
			(stroke
				(width 0.1524)
				(type default)
			)
			(layer "F.SilkS")
		)
		(fp_line
			(start -0.7874 -0.4064)
			(end 0.7874 -0.4064)
			(stroke
				(width 0.1524)
				(type default)
			)
			(layer "F.SilkS")
		)
		(fp_line
			(start 0.7874 -0.4064)
			(end 0.7874 0.4064)
			(stroke
				(width 0.1524)
				(type default)
			)
			(layer "F.SilkS")
		)
		(fp_line
			(start -0.67945 0.3048)
			(end -0.67945 -0.305054)
			(stroke
				(width 0.1)
				(type default)
			)
			(layer "F.Fab")
		)
		(fp_line
			(start -0.12065 0.3048)
			(end -0.67945 0.3048)
			(stroke
				(width 0.1)
				(type default)
			)
			(layer "F.Fab")
		)
		(fp_line
			(start 0.120396 0.3048)
			(end 0.120396 0.2794)
			(stroke
				(width 0.1)
				(type default)
			)
			(layer "F.Fab")
		)
		(fp_line
			(start 0.67945 0.3048)
			(end 0.120396 0.3048)
			(stroke
				(width 0.1)
				(type default)
			)
			(layer "F.Fab")
		)
		(fp_line
			(start -0.12065 0.2794)
			(end -0.12065 0.3048)
			(stroke
				(width 0.1)
				(type default)
			)
			(layer "F.Fab")
		)
		(fp_line
			(start 0.120396 0.2794)
			(end -0.12065 0.2794)
			(stroke
				(width 0.1)
				(type default)
			)
			(layer "F.Fab")
		)
		(fp_line
			(start -0.12065 -0.2794)
			(end 0.12065 -0.2794)
			(stroke
				(width 0.1)
				(type default)
			)
			(layer "F.Fab")
		)
		(fp_line
			(start 0.12065 -0.2794)
			(end 0.12065 -0.3048)
			(stroke
				(width 0.1)
				(type default)
			)
			(layer "F.Fab")
		)
		(fp_line
			(start 0.12065 -0.3048)
			(end 0.67945 -0.3048)
			(stroke
				(width 0.1)
				(type default)
			)
			(layer "F.Fab")
		)
		(fp_line
			(start 0.67945 -0.3048)
			(end 0.67945 0.3048)
			(stroke
				(width 0.1)
				(type default)
			)
			(layer "F.Fab")
		)
		(fp_line
			(start -0.67945 -0.305054)
			(end -0.12065 -0.305054)
			(stroke
				(width 0.1)
				(type default)
			)
			(layer "F.Fab")
		)
		(fp_line
			(start -0.12065 -0.305054)
			(end -0.12065 -0.2794)
			(stroke
				(width 0.1)
				(type default)
			)
			(layer "F.Fab")
		)
		(pad "1" smd circle
			(at -0.40005 0 270)
			(size 0 0)
			(layers "F.Cu" "F.Mask" "F.Paste")
			(net "FM_P2E_FGA")
		)
		(pad "2" smd circle
			(at 0.40005 0 270)
			(size 0 0)
			(layers "F.Cu" "F.Mask" "F.Paste")
			(net "GND")
		)
	)
	(footprint ""
		(layer "F.Cu")
		(at 330.775564 -140.414502 180)
		(property "Reference" "PC258"
			(at 0 0 180)
			(layer "F.SilkS")
			(hide yes)
			(effects
				(font
					(size 1.27 1.27)
				)
			)
		)
		(property "Value" ""
			(at 0 0 180)
			(layer "F.Fab")
			(effects
				(font
					(size 1.27 1.27)
				)
			)
		)
		(duplicate_pad_numbers_are_jumpers no)
		(fp_line
			(start 0.7874 0.4064)
			(end -0.7874 0.4064)
			(stroke
				(width 0.1524)
				(type default)
			)
			(layer "F.SilkS")
		)
		(fp_line
			(start 0.7874 -0.4064)
			(end 0.7874 0.4064)
			(stroke
				(width 0.1524)
				(type default)
			)
			(layer "F.SilkS")
		)
		(fp_line
			(start -0.7874 0.4064)
			(end -0.7874 -0.4064)
			(stroke
				(width 0.1524)
				(type default)
			)
			(layer "F.SilkS")
		)
		(fp_line
			(start -0.7874 -0.4064)
			(end 0.7874 -0.4064)
			(stroke
				(width 0.1524)
				(type default)
			)
			(layer "F.SilkS")
		)
		(fp_line
			(start 0.67945 0.3048)
			(end 0.120396 0.3048)
			(stroke
				(width 0.1)
				(type default)
			)
			(layer "F.Fab")
		)
		(fp_line
			(start 0.67945 -0.3048)
			(end 0.67945 0.3048)
			(stroke
				(width 0.1)
				(type default)
			)
			(layer "F.Fab")
		)
		(fp_line
			(start 0.12065 -0.2794)
			(end 0.12065 -0.3048)
			(stroke
				(width 0.1)
				(type default)
			)
			(layer "F.Fab")
		)
		(fp_line
			(start 0.12065 -0.3048)
			(end 0.67945 -0.3048)
			(stroke
				(width 0.1)
				(type default)
			)
			(layer "F.Fab")
		)
		(fp_line
			(start 0.120396 0.3048)
			(end 0.120396 0.2794)
			(stroke
				(width 0.1)
				(type default)
			)
			(layer "F.Fab")
		)
		(fp_line
			(start 0.120396 0.2794)
			(end -0.12065 0.2794)
			(stroke
				(width 0.1)
				(type default)
			)
			(layer "F.Fab")
		)
		(fp_line
			(start -0.12065 0.3048)
			(end -0.67945 0.3048)
			(stroke
				(width 0.1)
				(type default)
			)
			(layer "F.Fab")
		)
		(fp_line
			(start -0.12065 0.2794)
			(end -0.12065 0.3048)
			(stroke
				(width 0.1)
				(type default)
			)
			(layer "F.Fab")
		)
		(fp_line
			(start -0.12065 -0.2794)
			(end 0.12065 -0.2794)
			(stroke
				(width 0.1)
				(type default)
			)
			(layer "F.Fab")
		)
		(fp_line
			(start -0.12065 -0.305054)
			(end -0.12065 -0.2794)
			(stroke
				(width 0.1)
				(type default)
			)
			(layer "F.Fab")
		)
		(fp_line
			(start -0.67945 0.3048)
			(end -0.67945 -0.305054)
			(stroke
				(width 0.1)
				(type default)
			)
			(layer "F.Fab")
		)
		(fp_line
			(start -0.67945 -0.305054)
			(end -0.12065 -0.305054)
			(stroke
				(width 0.1)
				(type default)
			)
			(layer "F.Fab")
		)
		(pad "1" smd circle
			(at -0.40005 0 180)
			(size 0 0)
			(layers "F.Cu" "F.Mask" "F.Paste")
			(net "PVDD18_S5_P0_REF")
		)
		(pad "2" smd circle
			(at 0.40005 0 180)
			(size 0 0)
			(layers "F.Cu" "F.Mask" "F.Paste")
			(net "GND")
		)
	)
	(footprint ""
		(layer "F.Cu")
		(at 102.424738 -345.150948)
		(property "Reference" "PR426"
			(at 0 0 0)
			(layer "F.SilkS")
			(hide yes)
			(effects
				(font
					(size 1.27 1.27)
				)
			)
		)
		(property "Value" ""
			(at 0 0 0)
			(layer "F.Fab")
			(effects
				(font
					(size 1.27 1.27)
				)
			)
		)
		(duplicate_pad_numbers_are_jumpers no)
		(fp_line
			(start -0.7874 -0.4064)
			(end 0.7874 -0.4064)
			(stroke
				(width 0.1524)
				(type default)
			)
			(layer "F.SilkS")
		)
		(fp_line
			(start -0.7874 0.4064)
			(end -0.7874 -0.4064)
			(stroke
				(width 0.1524)
				(type default)
			)
			(layer "F.SilkS")
		)
		(fp_line
			(start 0.7874 -0.4064)
			(end 0.7874 0.4064)
			(stroke
				(width 0.1524)
				(type default)
			)
			(layer "F.SilkS")
		)
		(fp_line
			(start 0.7874 0.4064)
			(end -0.7874 0.4064)
			(stroke
				(width 0.1524)
				(type default)
			)
			(layer "F.SilkS")
		)
		(fp_line
			(start -0.67945 -0.305054)
			(end -0.12065 -0.305054)
			(stroke
				(width 0.1)
				(type default)
			)
			(layer "F.Fab")
		)
		(fp_line
			(start -0.67945 0.3048)
			(end -0.67945 -0.305054)
			(stroke
				(width 0.1)
				(type default)
			)
			(layer "F.Fab")
		)
		(fp_line
			(start -0.12065 -0.305054)
			(end -0.12065 -0.2794)
			(stroke
				(width 0.1)
				(type default)
			)
			(layer "F.Fab")
		)
		(fp_line
			(start -0.12065 -0.2794)
			(end 0.12065 -0.2794)
			(stroke
				(width 0.1)
				(type default)
			)
			(layer "F.Fab")
		)
		(fp_line
			(start -0.12065 0.2794)
			(end -0.12065 0.3048)
			(stroke
				(width 0.1)
				(type default)
			)
			(layer "F.Fab")
		)
		(fp_line
			(start -0.12065 0.3048)
			(end -0.67945 0.3048)
			(stroke
				(width 0.1)
				(type default)
			)
			(layer "F.Fab")
		)
		(fp_line
			(start 0.120396 0.2794)
			(end -0.12065 0.2794)
			(stroke
				(width 0.1)
				(type default)
			)
			(layer "F.Fab")
		)
		(fp_line
			(start 0.120396 0.3048)
			(end 0.120396 0.2794)
			(stroke
				(width 0.1)
				(type default)
			)
			(layer "F.Fab")
		)
		(fp_line
			(start 0.12065 -0.3048)
			(end 0.67945 -0.3048)
			(stroke
				(width 0.1)
				(type default)
			)
			(layer "F.Fab")
		)
		(fp_line
			(start 0.12065 -0.2794)
			(end 0.12065 -0.3048)
			(stroke
				(width 0.1)
				(type default)
			)
			(layer "F.Fab")
		)
		(fp_line
			(start 0.67945 -0.3048)
			(end 0.67945 0.3048)
			(stroke
				(width 0.1)
				(type default)
			)
			(layer "F.Fab")
		)
		(fp_line
			(start 0.67945 0.3048)
			(end 0.120396 0.3048)
			(stroke
				(width 0.1)
				(type default)
			)
			(layer "F.Fab")
		)
		(pad "1" smd circle
			(at -0.40005 0)
			(size 0 0)
			(layers "F.Cu" "F.Mask" "F.Paste")
			(net "PVDDCR_CPU1_P1_LSET6")
		)
		(pad "2" smd circle
			(at 0.40005 0)
			(size 0 0)
			(layers "F.Cu" "F.Mask" "F.Paste")
			(net "GND")
		)
	)
	(footprint ""
		(layer "F.Cu")
		(at 64.614298 -23.554182)
		(property "Reference" "PR3857"
			(at 0 0 0)
			(layer "F.SilkS")
			(hide yes)
			(effects
				(font
					(size 1.27 1.27)
				)
			)
		)
		(property "Value" ""
			(at 0 0 0)
			(layer "F.Fab")
			(effects
				(font
					(size 1.27 1.27)
				)
			)
		)
		(duplicate_pad_numbers_are_jumpers no)
		(fp_line
			(start -1.2954 -0.5842)
			(end 1.2954 -0.5842)
			(stroke
				(width 0.1524)
				(type default)
			)
			(layer "F.SilkS")
		)
		(fp_line
			(start -1.2954 0.5842)
			(end -1.2954 -0.5842)
			(stroke
				(width 0.1524)
				(type default)
			)
			(layer "F.SilkS")
		)
		(fp_line
			(start 1.2954 -0.5842)
			(end 1.2954 0.5842)
			(stroke
				(width 0.1524)
				(type default)
			)
			(layer "F.SilkS")
		)
		(fp_line
			(start 1.2954 0.5842)
			(end -1.2954 0.5842)
			(stroke
				(width 0.1524)
				(type default)
			)
			(layer "F.SilkS")
		)
		(fp_line
			(start -1.1938 -0.406654)
			(end -0.8636 -0.406654)
			(stroke
				(width 0.1)
				(type default)
			)
			(layer "F.Fab")
		)
		(fp_line
			(start -1.1938 0.4064)
			(end -1.1938 -0.406654)
			(stroke
				(width 0.1)
				(type default)
			)
			(layer "F.Fab")
		)
		(fp_line
			(start -0.8636 -0.4572)
			(end 0.8636 -0.4572)
			(stroke
				(width 0.1)
				(type default)
			)
			(layer "F.Fab")
		)
		(fp_line
			(start -0.8636 -0.406654)
			(end -0.8636 -0.4572)
			(stroke
				(width 0.1)
				(type default)
			)
			(layer "F.Fab")
		)
		(fp_line
			(start -0.8636 0.4064)
			(end -1.1938 0.4064)
			(stroke
				(width 0.1)
				(type default)
			)
			(layer "F.Fab")
		)
		(fp_line
			(start -0.8636 0.4318)
			(end -0.8636 0.4064)
			(stroke
				(width 0.1)
				(type default)
			)
			(layer "F.Fab")
		)
		(fp_line
			(start -0.8636 0.4572)
			(end -0.8636 0.4318)
			(stroke
				(width 0.1)
				(type default)
			)
			(layer "F.Fab")
		)
		(fp_line
			(start 0.8636 -0.4572)
			(end 0.8636 -0.406654)
			(stroke
				(width 0.1)
				(type default)
			)
			(layer "F.Fab")
		)
		(fp_line
			(start 0.8636 -0.406654)
			(end 1.1938 -0.406654)
			(stroke
				(width 0.1)
				(type default)
			)
			(layer "F.Fab")
		)
		(fp_line
			(start 0.8636 0.4064)
			(end 0.8636 0.4572)
			(stroke
				(width 0.1)
				(type default)
			)
			(layer "F.Fab")
		)
		(fp_line
			(start 0.8636 0.4572)
			(end -0.8636 0.4572)
			(stroke
				(width 0.1)
				(type default)
			)
			(layer "F.Fab")
		)
		(fp_line
			(start 1.1938 -0.406654)
			(end 1.1938 0.4064)
			(stroke
				(width 0.1)
				(type default)
			)
			(layer "F.Fab")
		)
		(fp_line
			(start 1.1938 0.4064)
			(end 0.8636 0.4064)
			(stroke
				(width 0.1)
				(type default)
			)
			(layer "F.Fab")
		)
		(pad "1" smd rect
			(at -0.7366 0 270)
			(size 0.7112 0.8128)
			(layers "F.Cu" "F.Mask" "F.Paste")
			(net "P12V_AUX")
		)
		(pad "2" smd rect
			(at 0.7366 0 270)
			(size 0.7112 0.8128)
			(layers "F.Cu" "F.Mask" "F.Paste")
			(net "P12V_OCP_AVIN_PD_2")
		)
	)
	(footprint ""
		(layer "F.Cu")
		(at 425.429934 -355.718364 -90)
		(property "Reference" "PC217"
			(at 0 0 270)
			(layer "F.SilkS")
			(hide yes)
			(effects
				(font
					(size 1.27 1.27)
				)
			)
		)
		(property "Value" ""
			(at 0 0 270)
			(layer "F.Fab")
			(effects
				(font
					(size 1.27 1.27)
				)
			)
		)
		(duplicate_pad_numbers_are_jumpers no)
		(fp_line
			(start -0.7874 0.4064)
			(end -0.7874 -0.4064)
			(stroke
				(width 0.1524)
				(type default)
			)
			(layer "F.SilkS")
		)
		(fp_line
			(start 0.7874 0.4064)
			(end -0.7874 0.4064)
			(stroke
				(width 0.1524)
				(type default)
			)
			(layer "F.SilkS")
		)
		(fp_line
			(start -0.7874 -0.4064)
			(end 0.7874 -0.4064)
			(stroke
				(width 0.1524)
				(type default)
			)
			(layer "F.SilkS")
		)
		(fp_line
			(start 0.7874 -0.4064)
			(end 0.7874 0.4064)
			(stroke
				(width 0.1524)
				(type default)
			)
			(layer "F.SilkS")
		)
		(fp_line
			(start -0.67945 0.3048)
			(end -0.67945 -0.305054)
			(stroke
				(width 0.1)
				(type default)
			)
			(layer "F.Fab")
		)
		(fp_line
			(start -0.12065 0.3048)
			(end -0.67945 0.3048)
			(stroke
				(width 0.1)
				(type default)
			)
			(layer "F.Fab")
		)
		(fp_line
			(start 0.120396 0.3048)
			(end 0.120396 0.2794)
			(stroke
				(width 0.1)
				(type default)
			)
			(layer "F.Fab")
		)
		(fp_line
			(start 0.67945 0.3048)
			(end 0.120396 0.3048)
			(stroke
				(width 0.1)
				(type default)
			)
			(layer "F.Fab")
		)
		(fp_line
			(start -0.12065 0.2794)
			(end -0.12065 0.3048)
			(stroke
				(width 0.1)
				(type default)
			)
			(layer "F.Fab")
		)
		(fp_line
			(start 0.120396 0.2794)
			(end -0.12065 0.2794)
			(stroke
				(width 0.1)
				(type default)
			)
			(layer "F.Fab")
		)
		(fp_line
			(start -0.12065 -0.2794)
			(end 0.12065 -0.2794)
			(stroke
				(width 0.1)
				(type default)
			)
			(layer "F.Fab")
		)
		(fp_line
			(start 0.12065 -0.2794)
			(end 0.12065 -0.3048)
			(stroke
				(width 0.1)
				(type default)
			)
			(layer "F.Fab")
		)
		(fp_line
			(start 0.12065 -0.3048)
			(end 0.67945 -0.3048)
			(stroke
				(width 0.1)
				(type default)
			)
			(layer "F.Fab")
		)
		(fp_line
			(start 0.67945 -0.3048)
			(end 0.67945 0.3048)
			(stroke
				(width 0.1)
				(type default)
			)
			(layer "F.Fab")
		)
		(fp_line
			(start -0.67945 -0.305054)
			(end -0.12065 -0.305054)
			(stroke
				(width 0.1)
				(type default)
			)
			(layer "F.Fab")
		)
		(fp_line
			(start -0.12065 -0.305054)
			(end -0.12065 -0.2794)
			(stroke
				(width 0.1)
				(type default)
			)
			(layer "F.Fab")
		)
		(pad "1" smd circle
			(at -0.40005 0 270)
			(size 0 0)
			(layers "F.Cu" "F.Mask" "F.Paste")
			(net "SW_PVDD11_S3_P0_BOOT1_RC")
		)
		(pad "2" smd circle
			(at 0.40005 0 270)
			(size 0 0)
			(layers "F.Cu" "F.Mask" "F.Paste")
			(net "SW_PVDD11_S3_P0_PH1")
		)
	)
	(footprint ""
		(layer "F.Cu")
		(at 40.386 -390.398 90)
		(property "Reference" "R727"
			(at 0 0 90)
			(layer "F.SilkS")
			(hide yes)
			(effects
				(font
					(size 1.27 1.27)
				)
			)
		)
		(property "Value" ""
			(at 0 0 90)
			(layer "F.Fab")
			(effects
				(font
					(size 1.27 1.27)
				)
			)
		)
		(duplicate_pad_numbers_are_jumpers no)
		(fp_line
			(start 0.32512 -0.175006)
			(end 0.32512 0.175006)
			(stroke
				(width 0.1)
				(type default)
			)
			(layer "F.Fab")
		)
		(fp_line
			(start -0.32512 -0.175006)
			(end 0.32512 -0.175006)
			(stroke
				(width 0.1)
				(type default)
			)
			(layer "F.Fab")
		)
		(fp_line
			(start 0.32512 0.175006)
			(end -0.32512 0.175006)
			(stroke
				(width 0.1)
				(type default)
			)
			(layer "F.Fab")
		)
		(fp_line
			(start -0.32512 0.175006)
			(end -0.32512 -0.175006)
			(stroke
				(width 0.1)
				(type default)
			)
			(layer "F.Fab")
		)
		(pad "1" smd rect
			(at -0.2667 0 90)
			(size 0.3048 0.381)
			(layers "F.Cu" "F.Mask" "F.Paste")
			(net "P1V8_CPU1_RT_1D")
		)
		(pad "2" smd rect
			(at 0.2667 0 270)
			(size 0.3048 0.381)
			(layers "F.Cu" "F.Mask" "F.Paste")
			(net "MODE_RT_CPU1_P0")
		)
	)
	(footprint ""
		(layer "F.Cu")
		(at 63.194438 -29.398722 180)
		(property "Reference" "PR3851"
			(at 0 0 180)
			(layer "F.SilkS")
			(hide yes)
			(effects
				(font
					(size 1.27 1.27)
				)
			)
		)
		(property "Value" ""
			(at 0 0 180)
			(layer "F.Fab")
			(effects
				(font
					(size 1.27 1.27)
				)
			)
		)
		(duplicate_pad_numbers_are_jumpers no)
		(fp_line
			(start 0.7874 0.4064)
			(end -0.7874 0.4064)
			(stroke
				(width 0.1524)
				(type default)
			)
			(layer "F.SilkS")
		)
		(fp_line
			(start 0.7874 -0.4064)
			(end 0.7874 0.4064)
			(stroke
				(width 0.1524)
				(type default)
			)
			(layer "F.SilkS")
		)
		(fp_line
			(start -0.7874 0.4064)
			(end -0.7874 -0.4064)
			(stroke
				(width 0.1524)
				(type default)
			)
			(layer "F.SilkS")
		)
		(fp_line
			(start -0.7874 -0.4064)
			(end 0.7874 -0.4064)
			(stroke
				(width 0.1524)
				(type default)
			)
			(layer "F.SilkS")
		)
		(fp_line
			(start 0.67945 0.3048)
			(end 0.120396 0.3048)
			(stroke
				(width 0.1)
				(type default)
			)
			(layer "F.Fab")
		)
		(fp_line
			(start 0.67945 -0.3048)
			(end 0.67945 0.3048)
			(stroke
				(width 0.1)
				(type default)
			)
			(layer "F.Fab")
		)
		(fp_line
			(start 0.12065 -0.2794)
			(end 0.12065 -0.3048)
			(stroke
				(width 0.1)
				(type default)
			)
			(layer "F.Fab")
		)
		(fp_line
			(start 0.12065 -0.3048)
			(end 0.67945 -0.3048)
			(stroke
				(width 0.1)
				(type default)
			)
			(layer "F.Fab")
		)
		(fp_line
			(start 0.120396 0.3048)
			(end 0.120396 0.2794)
			(stroke
				(width 0.1)
				(type default)
			)
			(layer "F.Fab")
		)
		(fp_line
			(start 0.120396 0.2794)
			(end -0.12065 0.2794)
			(stroke
				(width 0.1)
				(type default)
			)
			(layer "F.Fab")
		)
		(fp_line
			(start -0.12065 0.3048)
			(end -0.67945 0.3048)
			(stroke
				(width 0.1)
				(type default)
			)
			(layer "F.Fab")
		)
		(fp_line
			(start -0.12065 0.2794)
			(end -0.12065 0.3048)
			(stroke
				(width 0.1)
				(type default)
			)
			(layer "F.Fab")
		)
		(fp_line
			(start -0.12065 -0.2794)
			(end 0.12065 -0.2794)
			(stroke
				(width 0.1)
				(type default)
			)
			(layer "F.Fab")
		)
		(fp_line
			(start -0.12065 -0.305054)
			(end -0.12065 -0.2794)
			(stroke
				(width 0.1)
				(type default)
			)
			(layer "F.Fab")
		)
		(fp_line
			(start -0.67945 0.3048)
			(end -0.67945 -0.305054)
			(stroke
				(width 0.1)
				(type default)
			)
			(layer "F.Fab")
		)
		(fp_line
			(start -0.67945 -0.305054)
			(end -0.12065 -0.305054)
			(stroke
				(width 0.1)
				(type default)
			)
			(layer "F.Fab")
		)
		(pad "1" smd circle
			(at -0.40005 0 180)
			(size 0 0)
			(layers "F.Cu" "F.Mask" "F.Paste")
			(net "P12V_OCP_FLTB_2")
		)
		(pad "2" smd circle
			(at 0.40005 0 180)
			(size 0 0)
			(layers "F.Cu" "F.Mask" "F.Paste")
			(net "P3V3_AUX")
		)
	)
	(footprint ""
		(layer "F.Cu")
		(at 178.689 -408.559)
		(property "Reference" "R3933"
			(at 0 0 0)
			(layer "F.SilkS")
			(hide yes)
			(effects
				(font
					(size 1.27 1.27)
				)
			)
		)
		(property "Value" ""
			(at 0 0 0)
			(layer "F.Fab")
			(effects
				(font
					(size 1.27 1.27)
				)
			)
		)
		(duplicate_pad_numbers_are_jumpers no)
		(fp_line
			(start -0.7874 -0.4064)
			(end 0.7874 -0.4064)
			(stroke
				(width 0.1524)
				(type default)
			)
			(layer "F.SilkS")
		)
		(fp_line
			(start -0.7874 0.4064)
			(end -0.7874 -0.4064)
			(stroke
				(width 0.1524)
				(type default)
			)
			(layer "F.SilkS")
		)
		(fp_line
			(start 0.7874 -0.4064)
			(end 0.7874 0.4064)
			(stroke
				(width 0.1524)
				(type default)
			)
			(layer "F.SilkS")
		)
		(fp_line
			(start 0.7874 0.4064)
			(end -0.7874 0.4064)
			(stroke
				(width 0.1524)
				(type default)
			)
			(layer "F.SilkS")
		)
		(fp_line
			(start -0.67945 -0.305054)
			(end -0.12065 -0.305054)
			(stroke
				(width 0.1)
				(type default)
			)
			(layer "F.Fab")
		)
		(fp_line
			(start -0.67945 0.3048)
			(end -0.67945 -0.305054)
			(stroke
				(width 0.1)
				(type default)
			)
			(layer "F.Fab")
		)
		(fp_line
			(start -0.12065 -0.305054)
			(end -0.12065 -0.2794)
			(stroke
				(width 0.1)
				(type default)
			)
			(layer "F.Fab")
		)
		(fp_line
			(start -0.12065 -0.2794)
			(end 0.12065 -0.2794)
			(stroke
				(width 0.1)
				(type default)
			)
			(layer "F.Fab")
		)
		(fp_line
			(start -0.12065 0.2794)
			(end -0.12065 0.3048)
			(stroke
				(width 0.1)
				(type default)
			)
			(layer "F.Fab")
		)
		(fp_line
			(start -0.12065 0.3048)
			(end -0.67945 0.3048)
			(stroke
				(width 0.1)
				(type default)
			)
			(layer "F.Fab")
		)
		(fp_line
			(start 0.120396 0.2794)
			(end -0.12065 0.2794)
			(stroke
				(width 0.1)
				(type default)
			)
			(layer "F.Fab")
		)
		(fp_line
			(start 0.120396 0.3048)
			(end 0.120396 0.2794)
			(stroke
				(width 0.1)
				(type default)
			)
			(layer "F.Fab")
		)
		(fp_line
			(start 0.12065 -0.3048)
			(end 0.67945 -0.3048)
			(stroke
				(width 0.1)
				(type default)
			)
			(layer "F.Fab")
		)
		(fp_line
			(start 0.12065 -0.2794)
			(end 0.12065 -0.3048)
			(stroke
				(width 0.1)
				(type default)
			)
			(layer "F.Fab")
		)
		(fp_line
			(start 0.67945 -0.3048)
			(end 0.67945 0.3048)
			(stroke
				(width 0.1)
				(type default)
			)
			(layer "F.Fab")
		)
		(fp_line
			(start 0.67945 0.3048)
			(end 0.120396 0.3048)
			(stroke
				(width 0.1)
				(type default)
			)
			(layer "F.Fab")
		)
		(pad "1" smd circle
			(at -0.40005 0)
			(size 0 0)
			(layers "F.Cu" "F.Mask" "F.Paste")
			(net "P12V_AUX")
		)
		(pad "2" smd circle
			(at 0.40005 0)
			(size 0 0)
			(layers "F.Cu" "F.Mask" "F.Paste")
			(net "MB0_P12V_STBY_PWRGD")
		)
	)
	(footprint ""
		(layer "F.Cu")
		(at 451.573392 -52.84851 90)
		(property "Reference" "PC570"
			(at 0 0 90)
			(layer "F.SilkS")
			(hide yes)
			(effects
				(font
					(size 1.27 1.27)
				)
			)
		)
		(property "Value" ""
			(at 0 0 90)
			(layer "F.Fab")
			(effects
				(font
					(size 1.27 1.27)
				)
			)
		)
		(duplicate_pad_numbers_are_jumpers no)
		(fp_line
			(start 1.524 -0.762)
			(end 1.524 0.762)
			(stroke
				(width 0.1524)
				(type default)
			)
			(layer "F.SilkS")
		)
		(fp_line
			(start -1.524 -0.762)
			(end 1.524 -0.762)
			(stroke
				(width 0.1524)
				(type default)
			)
			(layer "F.SilkS")
		)
		(fp_line
			(start 1.524 0.762)
			(end -1.524 0.762)
			(stroke
				(width 0.1524)
				(type default)
			)
			(layer "F.SilkS")
		)
		(fp_line
			(start -1.524 0.762)
			(end -1.524 -0.762)
			(stroke
				(width 0.1524)
				(type default)
			)
			(layer "F.SilkS")
		)
		(fp_line
			(start 1.1049 -0.724916)
			(end -1.1049 -0.724916)
			(stroke
				(width 0.1)
				(type default)
			)
			(layer "F.Fab")
		)
		(fp_line
			(start -1.1049 -0.724916)
			(end -1.1049 0.724916)
			(stroke
				(width 0.1)
				(type default)
			)
			(layer "F.Fab")
		)
		(fp_line
			(start 1.1049 0.724916)
			(end 1.1049 -0.724916)
			(stroke
				(width 0.1)
				(type default)
			)
			(layer "F.Fab")
		)
		(fp_line
			(start -1.1049 0.724916)
			(end 1.1049 0.724916)
			(stroke
				(width 0.1)
				(type default)
			)
			(layer "F.Fab")
		)
		(pad "1" smd rect
			(at -0.889 0 270)
			(size 1.016 1.27)
			(layers "F.Cu" "F.Mask" "F.Paste")
			(net "SW_P3V3_AUX_FLT")
		)
		(pad "2" smd rect
			(at 0.889 0 270)
			(size 1.016 1.27)
			(layers "F.Cu" "F.Mask" "F.Paste")
			(net "GND")
		)
	)
	(footprint ""
		(layer "F.Cu")
		(at 267.701014 -380.66853)
		(property "Reference" "PR2530"
			(at 0 0 0)
			(layer "F.SilkS")
			(hide yes)
			(effects
				(font
					(size 1.27 1.27)
				)
			)
		)
		(property "Value" ""
			(at 0 0 0)
			(layer "F.Fab")
			(effects
				(font
					(size 1.27 1.27)
				)
			)
		)
		(duplicate_pad_numbers_are_jumpers no)
		(fp_line
			(start -0.7874 -0.4064)
			(end 0.7874 -0.4064)
			(stroke
				(width 0.1524)
				(type default)
			)
			(layer "F.SilkS")
		)
		(fp_line
			(start -0.7874 0.4064)
			(end -0.7874 -0.4064)
			(stroke
				(width 0.1524)
				(type default)
			)
			(layer "F.SilkS")
		)
		(fp_line
			(start 0.7874 -0.4064)
			(end 0.7874 0.4064)
			(stroke
				(width 0.1524)
				(type default)
			)
			(layer "F.SilkS")
		)
		(fp_line
			(start 0.7874 0.4064)
			(end -0.7874 0.4064)
			(stroke
				(width 0.1524)
				(type default)
			)
			(layer "F.SilkS")
		)
		(fp_line
			(start -0.67945 -0.305054)
			(end -0.12065 -0.305054)
			(stroke
				(width 0.1)
				(type default)
			)
			(layer "F.Fab")
		)
		(fp_line
			(start -0.67945 0.3048)
			(end -0.67945 -0.305054)
			(stroke
				(width 0.1)
				(type default)
			)
			(layer "F.Fab")
		)
		(fp_line
			(start -0.12065 -0.305054)
			(end -0.12065 -0.2794)
			(stroke
				(width 0.1)
				(type default)
			)
			(layer "F.Fab")
		)
		(fp_line
			(start -0.12065 -0.2794)
			(end 0.12065 -0.2794)
			(stroke
				(width 0.1)
				(type default)
			)
			(layer "F.Fab")
		)
		(fp_line
			(start -0.12065 0.2794)
			(end -0.12065 0.3048)
			(stroke
				(width 0.1)
				(type default)
			)
			(layer "F.Fab")
		)
		(fp_line
			(start -0.12065 0.3048)
			(end -0.67945 0.3048)
			(stroke
				(width 0.1)
				(type default)
			)
			(layer "F.Fab")
		)
		(fp_line
			(start 0.120396 0.2794)
			(end -0.12065 0.2794)
			(stroke
				(width 0.1)
				(type default)
			)
			(layer "F.Fab")
		)
		(fp_line
			(start 0.120396 0.3048)
			(end 0.120396 0.2794)
			(stroke
				(width 0.1)
				(type default)
			)
			(layer "F.Fab")
		)
		(fp_line
			(start 0.12065 -0.3048)
			(end 0.67945 -0.3048)
			(stroke
				(width 0.1)
				(type default)
			)
			(layer "F.Fab")
		)
		(fp_line
			(start 0.12065 -0.2794)
			(end 0.12065 -0.3048)
			(stroke
				(width 0.1)
				(type default)
			)
			(layer "F.Fab")
		)
		(fp_line
			(start 0.67945 -0.3048)
			(end 0.67945 0.3048)
			(stroke
				(width 0.1)
				(type default)
			)
			(layer "F.Fab")
		)
		(fp_line
			(start 0.67945 0.3048)
			(end 0.120396 0.3048)
			(stroke
				(width 0.1)
				(type default)
			)
			(layer "F.Fab")
		)
		(pad "1" smd circle
			(at -0.40005 0)
			(size 0 0)
			(layers "F.Cu" "F.Mask" "F.Paste")
			(net "P12V_HSC_GATE_G3")
		)
		(pad "2" smd circle
			(at 0.40005 0)
			(size 0 0)
			(layers "F.Cu" "F.Mask" "F.Paste")
			(net "P12V_HSC_GATE2")
		)
	)
	(footprint ""
		(layer "F.Cu")
		(at 82.378804 -408.517344 -90)
		(property "Reference" "C6651"
			(at 0 0 270)
			(layer "F.SilkS")
			(hide yes)
			(effects
				(font
					(size 1.27 1.27)
				)
			)
		)
		(property "Value" ""
			(at 0 0 270)
			(layer "F.Fab")
			(effects
				(font
					(size 1.27 1.27)
				)
			)
		)
		(duplicate_pad_numbers_are_jumpers no)
		(fp_line
			(start -0.299974 0.150114)
			(end -0.299974 -0.150114)
			(stroke
				(width 0.1)
				(type default)
			)
			(layer "F.Fab")
		)
		(fp_line
			(start 0.299974 0.150114)
			(end -0.299974 0.150114)
			(stroke
				(width 0.1)
				(type default)
			)
			(layer "F.Fab")
		)
		(fp_line
			(start -0.299974 -0.150114)
			(end 0.299974 -0.150114)
			(stroke
				(width 0.1)
				(type default)
			)
			(layer "F.Fab")
		)
		(fp_line
			(start 0.299974 -0.150114)
			(end 0.299974 0.150114)
			(stroke
				(width 0.1)
				(type default)
			)
			(layer "F.Fab")
		)
		(pad "1" smd rect
			(at -0.2667 0 270)
			(size 0.3048 0.381)
			(layers "F.Cu" "F.Mask" "F.Paste")
			(net "P5E_CPU1_P0_TX_BUF_C_DP<11>")
		)
		(pad "2" smd rect
			(at 0.2667 0 270)
			(size 0.3048 0.381)
			(layers "F.Cu" "F.Mask" "F.Paste")
			(net "P5E_CPU1_P0_TX_BUF_DP<11>")
		)
	)
	(footprint ""
		(layer "F.Cu")
		(at 15.288006 -104.73563 90)
		(property "Reference" "R3651"
			(at 0 0 90)
			(layer "F.SilkS")
			(hide yes)
			(effects
				(font
					(size 1.27 1.27)
				)
			)
		)
		(property "Value" ""
			(at 0 0 90)
			(layer "F.Fab")
			(effects
				(font
					(size 1.27 1.27)
				)
			)
		)
		(duplicate_pad_numbers_are_jumpers no)
		(fp_line
			(start 0.7874 -0.4064)
			(end 0.7874 0.4064)
			(stroke
				(width 0.1524)
				(type default)
			)
			(layer "F.SilkS")
		)
		(fp_line
			(start -0.7874 -0.4064)
			(end 0.7874 -0.4064)
			(stroke
				(width 0.1524)
				(type default)
			)
			(layer "F.SilkS")
		)
		(fp_line
			(start 0.7874 0.4064)
			(end -0.7874 0.4064)
			(stroke
				(width 0.1524)
				(type default)
			)
			(layer "F.SilkS")
		)
		(fp_line
			(start -0.7874 0.4064)
			(end -0.7874 -0.4064)
			(stroke
				(width 0.1524)
				(type default)
			)
			(layer "F.SilkS")
		)
		(fp_line
			(start -0.12065 -0.305054)
			(end -0.12065 -0.2794)
			(stroke
				(width 0.1)
				(type default)
			)
			(layer "F.Fab")
		)
		(fp_line
			(start -0.67945 -0.305054)
			(end -0.12065 -0.305054)
			(stroke
				(width 0.1)
				(type default)
			)
			(layer "F.Fab")
		)
		(fp_line
			(start 0.67945 -0.3048)
			(end 0.67945 0.3048)
			(stroke
				(width 0.1)
				(type default)
			)
			(layer "F.Fab")
		)
		(fp_line
			(start 0.12065 -0.3048)
			(end 0.67945 -0.3048)
			(stroke
				(width 0.1)
				(type default)
			)
			(layer "F.Fab")
		)
		(fp_line
			(start 0.12065 -0.2794)
			(end 0.12065 -0.3048)
			(stroke
				(width 0.1)
				(type default)
			)
			(layer "F.Fab")
		)
		(fp_line
			(start -0.12065 -0.2794)
			(end 0.12065 -0.2794)
			(stroke
				(width 0.1)
				(type default)
			)
			(layer "F.Fab")
		)
		(fp_line
			(start 0.120396 0.2794)
			(end -0.12065 0.2794)
			(stroke
				(width 0.1)
				(type default)
			)
			(layer "F.Fab")
		)
		(fp_line
			(start -0.12065 0.2794)
			(end -0.12065 0.3048)
			(stroke
				(width 0.1)
				(type default)
			)
			(layer "F.Fab")
		)
		(fp_line
			(start 0.67945 0.3048)
			(end 0.120396 0.3048)
			(stroke
				(width 0.1)
				(type default)
			)
			(layer "F.Fab")
		)
		(fp_line
			(start 0.120396 0.3048)
			(end 0.120396 0.2794)
			(stroke
				(width 0.1)
				(type default)
			)
			(layer "F.Fab")
		)
		(fp_line
			(start -0.12065 0.3048)
			(end -0.67945 0.3048)
			(stroke
				(width 0.1)
				(type default)
			)
			(layer "F.Fab")
		)
		(fp_line
			(start -0.67945 0.3048)
			(end -0.67945 -0.305054)
			(stroke
				(width 0.1)
				(type default)
			)
			(layer "F.Fab")
		)
		(pad "1" smd rect
			(at -0.40005 0 270)
			(size 0.4572 0.508)
			(layers "F.Cu" "F.Mask" "F.Paste")
			(net "USB2_P0_R_DP")
		)
		(pad "2" smd rect
			(at 0.40005 0 270)
			(size 0.4572 0.508)
			(layers "F.Cu" "F.Mask" "F.Paste")
			(net "USB2_HOST_BMC_B_DP")
		)
	)
	(footprint ""
		(layer "F.Cu")
		(at 104.1908 -390.652)
		(property "Reference" "R1377"
			(at 0 0 0)
			(layer "F.SilkS")
			(hide yes)
			(effects
				(font
					(size 1.27 1.27)
				)
			)
		)
		(property "Value" ""
			(at 0 0 0)
			(layer "F.Fab")
			(effects
				(font
					(size 1.27 1.27)
				)
			)
		)
		(duplicate_pad_numbers_are_jumpers no)
		(fp_line
			(start -0.32512 -0.175006)
			(end 0.32512 -0.175006)
			(stroke
				(width 0.1)
				(type default)
			)
			(layer "F.Fab")
		)
		(fp_line
			(start -0.32512 0.175006)
			(end -0.32512 -0.175006)
			(stroke
				(width 0.1)
				(type default)
			)
			(layer "F.Fab")
		)
		(fp_line
			(start 0.32512 -0.175006)
			(end 0.32512 0.175006)
			(stroke
				(width 0.1)
				(type default)
			)
			(layer "F.Fab")
		)
		(fp_line
			(start 0.32512 0.175006)
			(end -0.32512 0.175006)
			(stroke
				(width 0.1)
				(type default)
			)
			(layer "F.Fab")
		)
		(pad "1" smd rect
			(at -0.2667 0)
			(size 0.3048 0.381)
			(layers "F.Cu" "F.Mask" "F.Paste")
			(net "P1V8_CPU1_RT_1D")
		)
		(pad "2" smd rect
			(at 0.2667 0 180)
			(size 0.3048 0.381)
			(layers "F.Cu" "F.Mask" "F.Paste")
			(net "RXDET_BYP_RT_CPU1_P1")
		)
	)
	(footprint ""
		(layer "F.Cu")
		(at 99.917504 -119.557038 90)
		(property "Reference" "R6504"
			(at 0 0 90)
			(layer "F.SilkS")
			(hide yes)
			(effects
				(font
					(size 1.27 1.27)
				)
			)
		)
		(property "Value" ""
			(at 0 0 90)
			(layer "F.Fab")
			(effects
				(font
					(size 1.27 1.27)
				)
			)
		)
		(duplicate_pad_numbers_are_jumpers no)
		(fp_line
			(start 0.7874 -0.4064)
			(end 0.7874 0.4064)
			(stroke
				(width 0.1524)
				(type default)
			)
			(layer "F.SilkS")
		)
		(fp_line
			(start -0.7874 -0.4064)
			(end 0.7874 -0.4064)
			(stroke
				(width 0.1524)
				(type default)
			)
			(layer "F.SilkS")
		)
		(fp_line
			(start 0.7874 0.4064)
			(end -0.7874 0.4064)
			(stroke
				(width 0.1524)
				(type default)
			)
			(layer "F.SilkS")
		)
		(fp_line
			(start -0.7874 0.4064)
			(end -0.7874 -0.4064)
			(stroke
				(width 0.1524)
				(type default)
			)
			(layer "F.SilkS")
		)
		(fp_line
			(start -0.12065 -0.305054)
			(end -0.12065 -0.2794)
			(stroke
				(width 0.1)
				(type default)
			)
			(layer "F.Fab")
		)
		(fp_line
			(start -0.67945 -0.305054)
			(end -0.12065 -0.305054)
			(stroke
				(width 0.1)
				(type default)
			)
			(layer "F.Fab")
		)
		(fp_line
			(start 0.67945 -0.3048)
			(end 0.67945 0.3048)
			(stroke
				(width 0.1)
				(type default)
			)
			(layer "F.Fab")
		)
		(fp_line
			(start 0.12065 -0.3048)
			(end 0.67945 -0.3048)
			(stroke
				(width 0.1)
				(type default)
			)
			(layer "F.Fab")
		)
		(fp_line
			(start 0.12065 -0.2794)
			(end 0.12065 -0.3048)
			(stroke
				(width 0.1)
				(type default)
			)
			(layer "F.Fab")
		)
		(fp_line
			(start -0.12065 -0.2794)
			(end 0.12065 -0.2794)
			(stroke
				(width 0.1)
				(type default)
			)
			(layer "F.Fab")
		)
		(fp_line
			(start 0.120396 0.2794)
			(end -0.12065 0.2794)
			(stroke
				(width 0.1)
				(type default)
			)
			(layer "F.Fab")
		)
		(fp_line
			(start -0.12065 0.2794)
			(end -0.12065 0.3048)
			(stroke
				(width 0.1)
				(type default)
			)
			(layer "F.Fab")
		)
		(fp_line
			(start 0.67945 0.3048)
			(end 0.120396 0.3048)
			(stroke
				(width 0.1)
				(type default)
			)
			(layer "F.Fab")
		)
		(fp_line
			(start 0.120396 0.3048)
			(end 0.120396 0.2794)
			(stroke
				(width 0.1)
				(type default)
			)
			(layer "F.Fab")
		)
		(fp_line
			(start -0.12065 0.3048)
			(end -0.67945 0.3048)
			(stroke
				(width 0.1)
				(type default)
			)
			(layer "F.Fab")
		)
		(fp_line
			(start -0.67945 0.3048)
			(end -0.67945 -0.305054)
			(stroke
				(width 0.1)
				(type default)
			)
			(layer "F.Fab")
		)
		(pad "1" smd circle
			(at -0.40005 0 90)
			(size 0 0)
			(layers "F.Cu" "F.Mask" "F.Paste")
			(net "P1V8_AUX")
		)
		(pad "2" smd circle
			(at 0.40005 0 90)
			(size 0 0)
			(layers "F.Cu" "F.Mask" "F.Paste")
			(net "PU_U38_6")
		)
	)
	(footprint ""
		(layer "F.Cu")
		(at 329.360022 -32.953706)
		(property "Reference" "C2042"
			(at 0 0 0)
			(layer "F.SilkS")
			(hide yes)
			(effects
				(font
					(size 1.27 1.27)
				)
			)
		)
		(property "Value" ""
			(at 0 0 0)
			(layer "F.Fab")
			(effects
				(font
					(size 1.27 1.27)
				)
			)
		)
		(duplicate_pad_numbers_are_jumpers no)
		(fp_line
			(start -0.7874 -0.4064)
			(end 0.7874 -0.4064)
			(stroke
				(width 0.1524)
				(type default)
			)
			(layer "F.SilkS")
		)
		(fp_line
			(start -0.7874 0.4064)
			(end -0.7874 -0.4064)
			(stroke
				(width 0.1524)
				(type default)
			)
			(layer "F.SilkS")
		)
		(fp_line
			(start 0.7874 -0.4064)
			(end 0.7874 0.4064)
			(stroke
				(width 0.1524)
				(type default)
			)
			(layer "F.SilkS")
		)
		(fp_line
			(start 0.7874 0.4064)
			(end -0.7874 0.4064)
			(stroke
				(width 0.1524)
				(type default)
			)
			(layer "F.SilkS")
		)
		(fp_line
			(start -0.67945 -0.305054)
			(end -0.12065 -0.305054)
			(stroke
				(width 0.1)
				(type default)
			)
			(layer "F.Fab")
		)
		(fp_line
			(start -0.67945 0.3048)
			(end -0.67945 -0.305054)
			(stroke
				(width 0.1)
				(type default)
			)
			(layer "F.Fab")
		)
		(fp_line
			(start -0.12065 -0.305054)
			(end -0.12065 -0.2794)
			(stroke
				(width 0.1)
				(type default)
			)
			(layer "F.Fab")
		)
		(fp_line
			(start -0.12065 -0.2794)
			(end 0.12065 -0.2794)
			(stroke
				(width 0.1)
				(type default)
			)
			(layer "F.Fab")
		)
		(fp_line
			(start -0.12065 0.2794)
			(end -0.12065 0.3048)
			(stroke
				(width 0.1)
				(type default)
			)
			(layer "F.Fab")
		)
		(fp_line
			(start -0.12065 0.3048)
			(end -0.67945 0.3048)
			(stroke
				(width 0.1)
				(type default)
			)
			(layer "F.Fab")
		)
		(fp_line
			(start 0.120396 0.2794)
			(end -0.12065 0.2794)
			(stroke
				(width 0.1)
				(type default)
			)
			(layer "F.Fab")
		)
		(fp_line
			(start 0.120396 0.3048)
			(end 0.120396 0.2794)
			(stroke
				(width 0.1)
				(type default)
			)
			(layer "F.Fab")
		)
		(fp_line
			(start 0.12065 -0.3048)
			(end 0.67945 -0.3048)
			(stroke
				(width 0.1)
				(type default)
			)
			(layer "F.Fab")
		)
		(fp_line
			(start 0.12065 -0.2794)
			(end 0.12065 -0.3048)
			(stroke
				(width 0.1)
				(type default)
			)
			(layer "F.Fab")
		)
		(fp_line
			(start 0.67945 -0.3048)
			(end 0.67945 0.3048)
			(stroke
				(width 0.1)
				(type default)
			)
			(layer "F.Fab")
		)
		(fp_line
			(start 0.67945 0.3048)
			(end 0.120396 0.3048)
			(stroke
				(width 0.1)
				(type default)
			)
			(layer "F.Fab")
		)
		(pad "1" smd circle
			(at -0.40005 0)
			(size 0 0)
			(layers "F.Cu" "F.Mask" "F.Paste")
			(net "P3V3_AUX_ADC_MAM")
		)
		(pad "2" smd circle
			(at 0.40005 0)
			(size 0 0)
			(layers "F.Cu" "F.Mask" "F.Paste")
			(net "GND")
		)
	)
	(footprint ""
		(layer "F.Cu")
		(at 44.7294 -105.8164 180)
		(property "Reference" "R1092"
			(at 0 0 180)
			(layer "F.SilkS")
			(hide yes)
			(effects
				(font
					(size 1.27 1.27)
				)
			)
		)
		(property "Value" ""
			(at 0 0 180)
			(layer "F.Fab")
			(effects
				(font
					(size 1.27 1.27)
				)
			)
		)
		(duplicate_pad_numbers_are_jumpers no)
		(fp_line
			(start 0.7874 0.4064)
			(end -0.7874 0.4064)
			(stroke
				(width 0.1524)
				(type default)
			)
			(layer "F.SilkS")
		)
		(fp_line
			(start 0.7874 -0.4064)
			(end 0.7874 0.4064)
			(stroke
				(width 0.1524)
				(type default)
			)
			(layer "F.SilkS")
		)
		(fp_line
			(start -0.7874 0.4064)
			(end -0.7874 -0.4064)
			(stroke
				(width 0.1524)
				(type default)
			)
			(layer "F.SilkS")
		)
		(fp_line
			(start -0.7874 -0.4064)
			(end 0.7874 -0.4064)
			(stroke
				(width 0.1524)
				(type default)
			)
			(layer "F.SilkS")
		)
		(fp_line
			(start 0.67945 0.3048)
			(end 0.120396 0.3048)
			(stroke
				(width 0.1)
				(type default)
			)
			(layer "F.Fab")
		)
		(fp_line
			(start 0.67945 -0.3048)
			(end 0.67945 0.3048)
			(stroke
				(width 0.1)
				(type default)
			)
			(layer "F.Fab")
		)
		(fp_line
			(start 0.12065 -0.2794)
			(end 0.12065 -0.3048)
			(stroke
				(width 0.1)
				(type default)
			)
			(layer "F.Fab")
		)
		(fp_line
			(start 0.12065 -0.3048)
			(end 0.67945 -0.3048)
			(stroke
				(width 0.1)
				(type default)
			)
			(layer "F.Fab")
		)
		(fp_line
			(start 0.120396 0.3048)
			(end 0.120396 0.2794)
			(stroke
				(width 0.1)
				(type default)
			)
			(layer "F.Fab")
		)
		(fp_line
			(start 0.120396 0.2794)
			(end -0.12065 0.2794)
			(stroke
				(width 0.1)
				(type default)
			)
			(layer "F.Fab")
		)
		(fp_line
			(start -0.12065 0.3048)
			(end -0.67945 0.3048)
			(stroke
				(width 0.1)
				(type default)
			)
			(layer "F.Fab")
		)
		(fp_line
			(start -0.12065 0.2794)
			(end -0.12065 0.3048)
			(stroke
				(width 0.1)
				(type default)
			)
			(layer "F.Fab")
		)
		(fp_line
			(start -0.12065 -0.2794)
			(end 0.12065 -0.2794)
			(stroke
				(width 0.1)
				(type default)
			)
			(layer "F.Fab")
		)
		(fp_line
			(start -0.12065 -0.305054)
			(end -0.12065 -0.2794)
			(stroke
				(width 0.1)
				(type default)
			)
			(layer "F.Fab")
		)
		(fp_line
			(start -0.67945 0.3048)
			(end -0.67945 -0.305054)
			(stroke
				(width 0.1)
				(type default)
			)
			(layer "F.Fab")
		)
		(fp_line
			(start -0.67945 -0.305054)
			(end -0.12065 -0.305054)
			(stroke
				(width 0.1)
				(type default)
			)
			(layer "F.Fab")
		)
		(pad "1" smd circle
			(at -0.40005 0 180)
			(size 0 0)
			(layers "F.Cu" "F.Mask" "F.Paste")
			(net "P3V3_AUX_DSC_G1")
		)
		(pad "2" smd circle
			(at 0.40005 0 180)
			(size 0 0)
			(layers "F.Cu" "F.Mask" "F.Paste")
			(net "GND")
		)
	)
	(footprint ""
		(layer "F.Cu")
		(at 301.621952 -23.14575)
		(property "Reference" "R1776"
			(at 0 0 0)
			(layer "F.SilkS")
			(hide yes)
			(effects
				(font
					(size 1.27 1.27)
				)
			)
		)
		(property "Value" ""
			(at 0 0 0)
			(layer "F.Fab")
			(effects
				(font
					(size 1.27 1.27)
				)
			)
		)
		(duplicate_pad_numbers_are_jumpers no)
		(fp_line
			(start -0.7874 -0.4064)
			(end 0.7874 -0.4064)
			(stroke
				(width 0.1524)
				(type default)
			)
			(layer "F.SilkS")
		)
		(fp_line
			(start -0.7874 0.4064)
			(end -0.7874 -0.4064)
			(stroke
				(width 0.1524)
				(type default)
			)
			(layer "F.SilkS")
		)
		(fp_line
			(start 0.7874 -0.4064)
			(end 0.7874 0.4064)
			(stroke
				(width 0.1524)
				(type default)
			)
			(layer "F.SilkS")
		)
		(fp_line
			(start 0.7874 0.4064)
			(end -0.7874 0.4064)
			(stroke
				(width 0.1524)
				(type default)
			)
			(layer "F.SilkS")
		)
		(fp_line
			(start -0.67945 -0.305054)
			(end -0.12065 -0.305054)
			(stroke
				(width 0.1)
				(type default)
			)
			(layer "F.Fab")
		)
		(fp_line
			(start -0.67945 0.3048)
			(end -0.67945 -0.305054)
			(stroke
				(width 0.1)
				(type default)
			)
			(layer "F.Fab")
		)
		(fp_line
			(start -0.12065 -0.305054)
			(end -0.12065 -0.2794)
			(stroke
				(width 0.1)
				(type default)
			)
			(layer "F.Fab")
		)
		(fp_line
			(start -0.12065 -0.2794)
			(end 0.12065 -0.2794)
			(stroke
				(width 0.1)
				(type default)
			)
			(layer "F.Fab")
		)
		(fp_line
			(start -0.12065 0.2794)
			(end -0.12065 0.3048)
			(stroke
				(width 0.1)
				(type default)
			)
			(layer "F.Fab")
		)
		(fp_line
			(start -0.12065 0.3048)
			(end -0.67945 0.3048)
			(stroke
				(width 0.1)
				(type default)
			)
			(layer "F.Fab")
		)
		(fp_line
			(start 0.120396 0.2794)
			(end -0.12065 0.2794)
			(stroke
				(width 0.1)
				(type default)
			)
			(layer "F.Fab")
		)
		(fp_line
			(start 0.120396 0.3048)
			(end 0.120396 0.2794)
			(stroke
				(width 0.1)
				(type default)
			)
			(layer "F.Fab")
		)
		(fp_line
			(start 0.12065 -0.3048)
			(end 0.67945 -0.3048)
			(stroke
				(width 0.1)
				(type default)
			)
			(layer "F.Fab")
		)
		(fp_line
			(start 0.12065 -0.2794)
			(end 0.12065 -0.3048)
			(stroke
				(width 0.1)
				(type default)
			)
			(layer "F.Fab")
		)
		(fp_line
			(start 0.67945 -0.3048)
			(end 0.67945 0.3048)
			(stroke
				(width 0.1)
				(type default)
			)
			(layer "F.Fab")
		)
		(fp_line
			(start 0.67945 0.3048)
			(end 0.120396 0.3048)
			(stroke
				(width 0.1)
				(type default)
			)
			(layer "F.Fab")
		)
		(pad "1" smd circle
			(at -0.40005 0)
			(size 0 0)
			(layers "F.Cu" "F.Mask" "F.Paste")
			(net "CLR_CMOS")
		)
		(pad "2" smd circle
			(at 0.40005 0)
			(size 0 0)
			(layers "F.Cu" "F.Mask" "F.Paste")
			(net "GND")
		)
	)
	(footprint ""
		(layer "F.Cu")
		(at 156.30779 -96.012508 90)
		(property "Reference" "C1878"
			(at 0 0 90)
			(layer "F.SilkS")
			(hide yes)
			(effects
				(font
					(size 1.27 1.27)
				)
			)
		)
		(property "Value" ""
			(at 0 0 90)
			(layer "F.Fab")
			(effects
				(font
					(size 1.27 1.27)
				)
			)
		)
		(duplicate_pad_numbers_are_jumpers no)
		(fp_line
			(start 0.7874 -0.4064)
			(end 0.7874 0.4064)
			(stroke
				(width 0.1524)
				(type default)
			)
			(layer "F.SilkS")
		)
		(fp_line
			(start -0.7874 -0.4064)
			(end 0.7874 -0.4064)
			(stroke
				(width 0.1524)
				(type default)
			)
			(layer "F.SilkS")
		)
		(fp_line
			(start 0.7874 0.4064)
			(end -0.7874 0.4064)
			(stroke
				(width 0.1524)
				(type default)
			)
			(layer "F.SilkS")
		)
		(fp_line
			(start -0.7874 0.4064)
			(end -0.7874 -0.4064)
			(stroke
				(width 0.1524)
				(type default)
			)
			(layer "F.SilkS")
		)
		(fp_line
			(start -0.12065 -0.305054)
			(end -0.12065 -0.2794)
			(stroke
				(width 0.1)
				(type default)
			)
			(layer "F.Fab")
		)
		(fp_line
			(start -0.67945 -0.305054)
			(end -0.12065 -0.305054)
			(stroke
				(width 0.1)
				(type default)
			)
			(layer "F.Fab")
		)
		(fp_line
			(start 0.67945 -0.3048)
			(end 0.67945 0.3048)
			(stroke
				(width 0.1)
				(type default)
			)
			(layer "F.Fab")
		)
		(fp_line
			(start 0.12065 -0.3048)
			(end 0.67945 -0.3048)
			(stroke
				(width 0.1)
				(type default)
			)
			(layer "F.Fab")
		)
		(fp_line
			(start 0.12065 -0.2794)
			(end 0.12065 -0.3048)
			(stroke
				(width 0.1)
				(type default)
			)
			(layer "F.Fab")
		)
		(fp_line
			(start -0.12065 -0.2794)
			(end 0.12065 -0.2794)
			(stroke
				(width 0.1)
				(type default)
			)
			(layer "F.Fab")
		)
		(fp_line
			(start 0.120396 0.2794)
			(end -0.12065 0.2794)
			(stroke
				(width 0.1)
				(type default)
			)
			(layer "F.Fab")
		)
		(fp_line
			(start -0.12065 0.2794)
			(end -0.12065 0.3048)
			(stroke
				(width 0.1)
				(type default)
			)
			(layer "F.Fab")
		)
		(fp_line
			(start 0.67945 0.3048)
			(end 0.120396 0.3048)
			(stroke
				(width 0.1)
				(type default)
			)
			(layer "F.Fab")
		)
		(fp_line
			(start 0.120396 0.3048)
			(end 0.120396 0.2794)
			(stroke
				(width 0.1)
				(type default)
			)
			(layer "F.Fab")
		)
		(fp_line
			(start -0.12065 0.3048)
			(end -0.67945 0.3048)
			(stroke
				(width 0.1)
				(type default)
			)
			(layer "F.Fab")
		)
		(fp_line
			(start -0.67945 0.3048)
			(end -0.67945 -0.305054)
			(stroke
				(width 0.1)
				(type default)
			)
			(layer "F.Fab")
		)
		(pad "1" smd circle
			(at -0.40005 0 90)
			(size 0 0)
			(layers "F.Cu" "F.Mask" "F.Paste")
			(net "P3V3_AUX")
		)
		(pad "2" smd circle
			(at 0.40005 0 90)
			(size 0 0)
			(layers "F.Cu" "F.Mask" "F.Paste")
			(net "GND")
		)
	)
	(footprint ""
		(layer "F.Cu")
		(at 11.590782 -405.611584 -90)
		(property "Reference" "PC6545"
			(at 0 0 270)
			(layer "F.SilkS")
			(hide yes)
			(effects
				(font
					(size 1.27 1.27)
				)
			)
		)
		(property "Value" ""
			(at 0 0 270)
			(layer "F.Fab")
			(effects
				(font
					(size 1.27 1.27)
				)
			)
		)
		(duplicate_pad_numbers_are_jumpers no)
		(fp_line
			(start -0.7874 0.4064)
			(end -0.7874 -0.4064)
			(stroke
				(width 0.1524)
				(type default)
			)
			(layer "F.SilkS")
		)
		(fp_line
			(start 0.7874 0.4064)
			(end -0.7874 0.4064)
			(stroke
				(width 0.1524)
				(type default)
			)
			(layer "F.SilkS")
		)
		(fp_line
			(start -0.7874 -0.4064)
			(end 0.7874 -0.4064)
			(stroke
				(width 0.1524)
				(type default)
			)
			(layer "F.SilkS")
		)
		(fp_line
			(start 0.7874 -0.4064)
			(end 0.7874 0.4064)
			(stroke
				(width 0.1524)
				(type default)
			)
			(layer "F.SilkS")
		)
		(fp_line
			(start -0.67945 0.3048)
			(end -0.67945 -0.305054)
			(stroke
				(width 0.1)
				(type default)
			)
			(layer "F.Fab")
		)
		(fp_line
			(start -0.12065 0.3048)
			(end -0.67945 0.3048)
			(stroke
				(width 0.1)
				(type default)
			)
			(layer "F.Fab")
		)
		(fp_line
			(start 0.120396 0.3048)
			(end 0.120396 0.2794)
			(stroke
				(width 0.1)
				(type default)
			)
			(layer "F.Fab")
		)
		(fp_line
			(start 0.67945 0.3048)
			(end 0.120396 0.3048)
			(stroke
				(width 0.1)
				(type default)
			)
			(layer "F.Fab")
		)
		(fp_line
			(start -0.12065 0.2794)
			(end -0.12065 0.3048)
			(stroke
				(width 0.1)
				(type default)
			)
			(layer "F.Fab")
		)
		(fp_line
			(start 0.120396 0.2794)
			(end -0.12065 0.2794)
			(stroke
				(width 0.1)
				(type default)
			)
			(layer "F.Fab")
		)
		(fp_line
			(start -0.12065 -0.2794)
			(end 0.12065 -0.2794)
			(stroke
				(width 0.1)
				(type default)
			)
			(layer "F.Fab")
		)
		(fp_line
			(start 0.12065 -0.2794)
			(end 0.12065 -0.3048)
			(stroke
				(width 0.1)
				(type default)
			)
			(layer "F.Fab")
		)
		(fp_line
			(start 0.12065 -0.3048)
			(end 0.67945 -0.3048)
			(stroke
				(width 0.1)
				(type default)
			)
			(layer "F.Fab")
		)
		(fp_line
			(start 0.67945 -0.3048)
			(end 0.67945 0.3048)
			(stroke
				(width 0.1)
				(type default)
			)
			(layer "F.Fab")
		)
		(fp_line
			(start -0.67945 -0.305054)
			(end -0.12065 -0.305054)
			(stroke
				(width 0.1)
				(type default)
			)
			(layer "F.Fab")
		)
		(fp_line
			(start -0.12065 -0.305054)
			(end -0.12065 -0.2794)
			(stroke
				(width 0.1)
				(type default)
			)
			(layer "F.Fab")
		)
		(pad "1" smd circle
			(at -0.40005 0 270)
			(size 0 0)
			(layers "F.Cu" "F.Mask" "F.Paste")
			(net "PV09_RETIMER_CPU1_VCCS")
		)
		(pad "2" smd circle
			(at 0.40005 0 270)
			(size 0 0)
			(layers "F.Cu" "F.Mask" "F.Paste")
			(net "GND")
		)
	)
	(footprint ""
		(layer "F.Cu")
		(at 183.878982 -34.794952 90)
		(property "Reference" "PC2231"
			(at 0 0 90)
			(layer "F.SilkS")
			(hide yes)
			(effects
				(font
					(size 1.27 1.27)
				)
			)
		)
		(property "Value" ""
			(at 0 0 90)
			(layer "F.Fab")
			(effects
				(font
					(size 1.27 1.27)
				)
			)
		)
		(duplicate_pad_numbers_are_jumpers no)
		(fp_line
			(start 0.7874 -0.4064)
			(end 0.7874 0.4064)
			(stroke
				(width 0.1524)
				(type default)
			)
			(layer "F.SilkS")
		)
		(fp_line
			(start -0.7874 -0.4064)
			(end 0.7874 -0.4064)
			(stroke
				(width 0.1524)
				(type default)
			)
			(layer "F.SilkS")
		)
		(fp_line
			(start 0.7874 0.4064)
			(end -0.7874 0.4064)
			(stroke
				(width 0.1524)
				(type default)
			)
			(layer "F.SilkS")
		)
		(fp_line
			(start -0.7874 0.4064)
			(end -0.7874 -0.4064)
			(stroke
				(width 0.1524)
				(type default)
			)
			(layer "F.SilkS")
		)
		(fp_line
			(start -0.12065 -0.305054)
			(end -0.12065 -0.2794)
			(stroke
				(width 0.1)
				(type default)
			)
			(layer "F.Fab")
		)
		(fp_line
			(start -0.67945 -0.305054)
			(end -0.12065 -0.305054)
			(stroke
				(width 0.1)
				(type default)
			)
			(layer "F.Fab")
		)
		(fp_line
			(start 0.67945 -0.3048)
			(end 0.67945 0.3048)
			(stroke
				(width 0.1)
				(type default)
			)
			(layer "F.Fab")
		)
		(fp_line
			(start 0.12065 -0.3048)
			(end 0.67945 -0.3048)
			(stroke
				(width 0.1)
				(type default)
			)
			(layer "F.Fab")
		)
		(fp_line
			(start 0.12065 -0.2794)
			(end 0.12065 -0.3048)
			(stroke
				(width 0.1)
				(type default)
			)
			(layer "F.Fab")
		)
		(fp_line
			(start -0.12065 -0.2794)
			(end 0.12065 -0.2794)
			(stroke
				(width 0.1)
				(type default)
			)
			(layer "F.Fab")
		)
		(fp_line
			(start 0.120396 0.2794)
			(end -0.12065 0.2794)
			(stroke
				(width 0.1)
				(type default)
			)
			(layer "F.Fab")
		)
		(fp_line
			(start -0.12065 0.2794)
			(end -0.12065 0.3048)
			(stroke
				(width 0.1)
				(type default)
			)
			(layer "F.Fab")
		)
		(fp_line
			(start 0.67945 0.3048)
			(end 0.120396 0.3048)
			(stroke
				(width 0.1)
				(type default)
			)
			(layer "F.Fab")
		)
		(fp_line
			(start 0.120396 0.3048)
			(end 0.120396 0.2794)
			(stroke
				(width 0.1)
				(type default)
			)
			(layer "F.Fab")
		)
		(fp_line
			(start -0.12065 0.3048)
			(end -0.67945 0.3048)
			(stroke
				(width 0.1)
				(type default)
			)
			(layer "F.Fab")
		)
		(fp_line
			(start -0.67945 0.3048)
			(end -0.67945 -0.305054)
			(stroke
				(width 0.1)
				(type default)
			)
			(layer "F.Fab")
		)
		(pad "1" smd circle
			(at -0.40005 0 90)
			(size 0 0)
			(layers "F.Cu" "F.Mask" "F.Paste")
			(net "P12V_AUX")
		)
		(pad "2" smd circle
			(at 0.40005 0 90)
			(size 0 0)
			(layers "F.Cu" "F.Mask" "F.Paste")
			(net "GND")
		)
	)
	(footprint ""
		(layer "F.Cu")
		(at 166.934388 -346.302076 180)
		(property "Reference" "R8010"
			(at 0 0 180)
			(layer "F.SilkS")
			(hide yes)
			(effects
				(font
					(size 1.27 1.27)
				)
			)
		)
		(property "Value" ""
			(at 0 0 180)
			(layer "F.Fab")
			(effects
				(font
					(size 1.27 1.27)
				)
			)
		)
		(duplicate_pad_numbers_are_jumpers no)
		(fp_line
			(start 0.7874 0.4064)
			(end -0.7874 0.4064)
			(stroke
				(width 0.1524)
				(type default)
			)
			(layer "F.SilkS")
		)
		(fp_line
			(start 0.7874 -0.4064)
			(end 0.7874 0.4064)
			(stroke
				(width 0.1524)
				(type default)
			)
			(layer "F.SilkS")
		)
		(fp_line
			(start -0.7874 0.4064)
			(end -0.7874 -0.4064)
			(stroke
				(width 0.1524)
				(type default)
			)
			(layer "F.SilkS")
		)
		(fp_line
			(start -0.7874 -0.4064)
			(end 0.7874 -0.4064)
			(stroke
				(width 0.1524)
				(type default)
			)
			(layer "F.SilkS")
		)
		(fp_line
			(start 0.67945 0.3048)
			(end 0.120396 0.3048)
			(stroke
				(width 0.1)
				(type default)
			)
			(layer "F.Fab")
		)
		(fp_line
			(start 0.67945 -0.3048)
			(end 0.67945 0.3048)
			(stroke
				(width 0.1)
				(type default)
			)
			(layer "F.Fab")
		)
		(fp_line
			(start 0.12065 -0.2794)
			(end 0.12065 -0.3048)
			(stroke
				(width 0.1)
				(type default)
			)
			(layer "F.Fab")
		)
		(fp_line
			(start 0.12065 -0.3048)
			(end 0.67945 -0.3048)
			(stroke
				(width 0.1)
				(type default)
			)
			(layer "F.Fab")
		)
		(fp_line
			(start 0.120396 0.3048)
			(end 0.120396 0.2794)
			(stroke
				(width 0.1)
				(type default)
			)
			(layer "F.Fab")
		)
		(fp_line
			(start 0.120396 0.2794)
			(end -0.12065 0.2794)
			(stroke
				(width 0.1)
				(type default)
			)
			(layer "F.Fab")
		)
		(fp_line
			(start -0.12065 0.3048)
			(end -0.67945 0.3048)
			(stroke
				(width 0.1)
				(type default)
			)
			(layer "F.Fab")
		)
		(fp_line
			(start -0.12065 0.2794)
			(end -0.12065 0.3048)
			(stroke
				(width 0.1)
				(type default)
			)
			(layer "F.Fab")
		)
		(fp_line
			(start -0.12065 -0.2794)
			(end 0.12065 -0.2794)
			(stroke
				(width 0.1)
				(type default)
			)
			(layer "F.Fab")
		)
		(fp_line
			(start -0.12065 -0.305054)
			(end -0.12065 -0.2794)
			(stroke
				(width 0.1)
				(type default)
			)
			(layer "F.Fab")
		)
		(fp_line
			(start -0.67945 0.3048)
			(end -0.67945 -0.305054)
			(stroke
				(width 0.1)
				(type default)
			)
			(layer "F.Fab")
		)
		(fp_line
			(start -0.67945 -0.305054)
			(end -0.12065 -0.305054)
			(stroke
				(width 0.1)
				(type default)
			)
			(layer "F.Fab")
		)
		(pad "1" smd circle
			(at -0.40005 0 180)
			(size 0 0)
			(layers "F.Cu" "F.Mask" "F.Paste")
			(net "PVDD11_S3_P1_OCP_N")
		)
		(pad "2" smd circle
			(at 0.40005 0 180)
			(size 0 0)
			(layers "F.Cu" "F.Mask" "F.Paste")
			(net "PVDD11_S3_P1_OCP_N_R")
		)
	)
	(footprint ""
		(layer "F.Cu")
		(at 326.967342 -390.1694)
		(property "Reference" "R1368"
			(at 0 0 0)
			(layer "F.SilkS")
			(hide yes)
			(effects
				(font
					(size 1.27 1.27)
				)
			)
		)
		(property "Value" ""
			(at 0 0 0)
			(layer "F.Fab")
			(effects
				(font
					(size 1.27 1.27)
				)
			)
		)
		(duplicate_pad_numbers_are_jumpers no)
		(fp_line
			(start -0.32512 -0.175006)
			(end 0.32512 -0.175006)
			(stroke
				(width 0.1)
				(type default)
			)
			(layer "F.Fab")
		)
		(fp_line
			(start -0.32512 0.175006)
			(end -0.32512 -0.175006)
			(stroke
				(width 0.1)
				(type default)
			)
			(layer "F.Fab")
		)
		(fp_line
			(start 0.32512 -0.175006)
			(end 0.32512 0.175006)
			(stroke
				(width 0.1)
				(type default)
			)
			(layer "F.Fab")
		)
		(fp_line
			(start 0.32512 0.175006)
			(end -0.32512 0.175006)
			(stroke
				(width 0.1)
				(type default)
			)
			(layer "F.Fab")
		)
		(pad "1" smd rect
			(at -0.2667 0)
			(size 0.3048 0.381)
			(layers "F.Cu" "F.Mask" "F.Paste")
			(net "CLKREQ_RT_CPU0_P0_N")
		)
		(pad "2" smd rect
			(at 0.2667 0 180)
			(size 0.3048 0.381)
			(layers "F.Cu" "F.Mask" "F.Paste")
			(net "GND")
		)
	)
	(footprint ""
		(layer "F.Cu")
		(at 17.305782 -404.341584 90)
		(property "Reference" "R660"
			(at 0 0 90)
			(layer "F.SilkS")
			(hide yes)
			(effects
				(font
					(size 1.27 1.27)
				)
			)
		)
		(property "Value" ""
			(at 0 0 90)
			(layer "F.Fab")
			(effects
				(font
					(size 1.27 1.27)
				)
			)
		)
		(duplicate_pad_numbers_are_jumpers no)
		(fp_line
			(start 0.7874 -0.4064)
			(end 0.7874 0.4064)
			(stroke
				(width 0.1524)
				(type default)
			)
			(layer "F.SilkS")
		)
		(fp_line
			(start -0.7874 -0.4064)
			(end 0.7874 -0.4064)
			(stroke
				(width 0.1524)
				(type default)
			)
			(layer "F.SilkS")
		)
		(fp_line
			(start 0.7874 0.4064)
			(end -0.7874 0.4064)
			(stroke
				(width 0.1524)
				(type default)
			)
			(layer "F.SilkS")
		)
		(fp_line
			(start -0.7874 0.4064)
			(end -0.7874 -0.4064)
			(stroke
				(width 0.1524)
				(type default)
			)
			(layer "F.SilkS")
		)
		(fp_line
			(start -0.12065 -0.305054)
			(end -0.12065 -0.2794)
			(stroke
				(width 0.1)
				(type default)
			)
			(layer "F.Fab")
		)
		(fp_line
			(start -0.67945 -0.305054)
			(end -0.12065 -0.305054)
			(stroke
				(width 0.1)
				(type default)
			)
			(layer "F.Fab")
		)
		(fp_line
			(start 0.67945 -0.3048)
			(end 0.67945 0.3048)
			(stroke
				(width 0.1)
				(type default)
			)
			(layer "F.Fab")
		)
		(fp_line
			(start 0.12065 -0.3048)
			(end 0.67945 -0.3048)
			(stroke
				(width 0.1)
				(type default)
			)
			(layer "F.Fab")
		)
		(fp_line
			(start 0.12065 -0.2794)
			(end 0.12065 -0.3048)
			(stroke
				(width 0.1)
				(type default)
			)
			(layer "F.Fab")
		)
		(fp_line
			(start -0.12065 -0.2794)
			(end 0.12065 -0.2794)
			(stroke
				(width 0.1)
				(type default)
			)
			(layer "F.Fab")
		)
		(fp_line
			(start 0.120396 0.2794)
			(end -0.12065 0.2794)
			(stroke
				(width 0.1)
				(type default)
			)
			(layer "F.Fab")
		)
		(fp_line
			(start -0.12065 0.2794)
			(end -0.12065 0.3048)
			(stroke
				(width 0.1)
				(type default)
			)
			(layer "F.Fab")
		)
		(fp_line
			(start 0.67945 0.3048)
			(end 0.120396 0.3048)
			(stroke
				(width 0.1)
				(type default)
			)
			(layer "F.Fab")
		)
		(fp_line
			(start 0.120396 0.3048)
			(end 0.120396 0.2794)
			(stroke
				(width 0.1)
				(type default)
			)
			(layer "F.Fab")
		)
		(fp_line
			(start -0.12065 0.3048)
			(end -0.67945 0.3048)
			(stroke
				(width 0.1)
				(type default)
			)
			(layer "F.Fab")
		)
		(fp_line
			(start -0.67945 0.3048)
			(end -0.67945 -0.305054)
			(stroke
				(width 0.1)
				(type default)
			)
			(layer "F.Fab")
		)
		(pad "1" smd circle
			(at -0.40005 0 90)
			(size 0 0)
			(layers "F.Cu" "F.Mask" "F.Paste")
			(net "P3V3_AUX")
		)
		(pad "2" smd circle
			(at 0.40005 0 90)
			(size 0 0)
			(layers "F.Cu" "F.Mask" "F.Paste")
			(net "TP_P0V9_RETIMER_CPU1_PMALERT")
		)
	)
	(footprint ""
		(layer "F.Cu")
		(at 265.176 -136.652 180)
		(property "Reference" "R8005"
			(at 0 0 180)
			(layer "F.SilkS")
			(hide yes)
			(effects
				(font
					(size 1.27 1.27)
				)
			)
		)
		(property "Value" ""
			(at 0 0 180)
			(layer "F.Fab")
			(effects
				(font
					(size 1.27 1.27)
				)
			)
		)
		(duplicate_pad_numbers_are_jumpers no)
		(fp_line
			(start 0.7874 0.4064)
			(end -0.7874 0.4064)
			(stroke
				(width 0.1524)
				(type default)
			)
			(layer "F.SilkS")
		)
		(fp_line
			(start 0.7874 -0.4064)
			(end 0.7874 0.4064)
			(stroke
				(width 0.1524)
				(type default)
			)
			(layer "F.SilkS")
		)
		(fp_line
			(start -0.7874 0.4064)
			(end -0.7874 -0.4064)
			(stroke
				(width 0.1524)
				(type default)
			)
			(layer "F.SilkS")
		)
		(fp_line
			(start -0.7874 -0.4064)
			(end 0.7874 -0.4064)
			(stroke
				(width 0.1524)
				(type default)
			)
			(layer "F.SilkS")
		)
		(fp_line
			(start 0.67945 0.3048)
			(end 0.120396 0.3048)
			(stroke
				(width 0.1)
				(type default)
			)
			(layer "F.Fab")
		)
		(fp_line
			(start 0.67945 -0.3048)
			(end 0.67945 0.3048)
			(stroke
				(width 0.1)
				(type default)
			)
			(layer "F.Fab")
		)
		(fp_line
			(start 0.12065 -0.2794)
			(end 0.12065 -0.3048)
			(stroke
				(width 0.1)
				(type default)
			)
			(layer "F.Fab")
		)
		(fp_line
			(start 0.12065 -0.3048)
			(end 0.67945 -0.3048)
			(stroke
				(width 0.1)
				(type default)
			)
			(layer "F.Fab")
		)
		(fp_line
			(start 0.120396 0.3048)
			(end 0.120396 0.2794)
			(stroke
				(width 0.1)
				(type default)
			)
			(layer "F.Fab")
		)
		(fp_line
			(start 0.120396 0.2794)
			(end -0.12065 0.2794)
			(stroke
				(width 0.1)
				(type default)
			)
			(layer "F.Fab")
		)
		(fp_line
			(start -0.12065 0.3048)
			(end -0.67945 0.3048)
			(stroke
				(width 0.1)
				(type default)
			)
			(layer "F.Fab")
		)
		(fp_line
			(start -0.12065 0.2794)
			(end -0.12065 0.3048)
			(stroke
				(width 0.1)
				(type default)
			)
			(layer "F.Fab")
		)
		(fp_line
			(start -0.12065 -0.2794)
			(end 0.12065 -0.2794)
			(stroke
				(width 0.1)
				(type default)
			)
			(layer "F.Fab")
		)
		(fp_line
			(start -0.12065 -0.305054)
			(end -0.12065 -0.2794)
			(stroke
				(width 0.1)
				(type default)
			)
			(layer "F.Fab")
		)
		(fp_line
			(start -0.67945 0.3048)
			(end -0.67945 -0.305054)
			(stroke
				(width 0.1)
				(type default)
			)
			(layer "F.Fab")
		)
		(fp_line
			(start -0.67945 -0.305054)
			(end -0.12065 -0.305054)
			(stroke
				(width 0.1)
				(type default)
			)
			(layer "F.Fab")
		)
		(pad "1" smd circle
			(at -0.40005 0 180)
			(size 0 0)
			(layers "F.Cu" "F.Mask" "F.Paste")
			(net "SPI_CPU0_D3")
		)
		(pad "2" smd circle
			(at 0.40005 0 180)
			(size 0 0)
			(layers "F.Cu" "F.Mask" "F.Paste")
			(net "SPI_CPU0_R1_D3")
		)
	)
	(footprint ""
		(layer "F.Cu")
		(at 324.981062 -402.9202 -90)
		(property "Reference" "R6820"
			(at 0 0 270)
			(layer "F.SilkS")
			(hide yes)
			(effects
				(font
					(size 1.27 1.27)
				)
			)
		)
		(property "Value" ""
			(at 0 0 270)
			(layer "F.Fab")
			(effects
				(font
					(size 1.27 1.27)
				)
			)
		)
		(duplicate_pad_numbers_are_jumpers no)
		(fp_line
			(start -0.32512 0.175006)
			(end -0.32512 -0.175006)
			(stroke
				(width 0.1)
				(type default)
			)
			(layer "F.Fab")
		)
		(fp_line
			(start 0.32512 0.175006)
			(end -0.32512 0.175006)
			(stroke
				(width 0.1)
				(type default)
			)
			(layer "F.Fab")
		)
		(fp_line
			(start -0.32512 -0.175006)
			(end 0.32512 -0.175006)
			(stroke
				(width 0.1)
				(type default)
			)
			(layer "F.Fab")
		)
		(fp_line
			(start 0.32512 -0.175006)
			(end 0.32512 0.175006)
			(stroke
				(width 0.1)
				(type default)
			)
			(layer "F.Fab")
		)
		(pad "1" smd rect
			(at -0.2667 0 270)
			(size 0.3048 0.381)
			(layers "F.Cu" "F.Mask" "F.Paste")
			(net "NCF_A1_CPU0_P0_GND")
		)
		(pad "2" smd rect
			(at 0.2667 0 90)
			(size 0.3048 0.381)
			(layers "F.Cu" "F.Mask" "F.Paste")
			(net "GND")
		)
	)
	(footprint ""
		(layer "F.Cu")
		(at 30.48 -364.109 -90)
		(property "Reference" "PU34"
			(at 3.80873 0.935736 0)
			(unlocked yes)
			(layer "F.SilkS")
			(effects
				(font
					(size 0.7874 0.5842)
					(thickness 0.1524)
				)
			)
		)
		(property "Value" ""
			(at 0 0 270)
			(layer "F.Fab")
			(effects
				(font
					(size 1.27 1.27)
				)
			)
		)
		(duplicate_pad_numbers_are_jumpers no)
		(fp_line
			(start -3.024886 3.024886)
			(end -3.024886 2.428494)
			(stroke
				(width 0.1524)
				(type default)
			)
			(layer "F.SilkS")
		)
		(fp_line
			(start -2.428494 3.024886)
			(end -3.024886 3.024886)
			(stroke
				(width 0.1524)
				(type default)
			)
			(layer "F.SilkS")
		)
		(fp_line
			(start 3.024886 3.024886)
			(end 2.428494 3.024886)
			(stroke
				(width 0.1524)
				(type default)
			)
			(layer "F.SilkS")
		)
		(fp_line
			(start 3.024886 2.428494)
			(end 3.024886 3.024886)
			(stroke
				(width 0.1524)
				(type default)
			)
			(layer "F.SilkS")
		)
		(fp_line
			(start -3.024886 -2.428494)
			(end -3.024886 -3.024886)
			(stroke
				(width 0.1524)
				(type default)
			)
			(layer "F.SilkS")
		)
		(fp_line
			(start -3.024886 -3.024886)
			(end -2.428494 -3.024886)
			(stroke
				(width 0.1524)
				(type default)
			)
			(layer "F.SilkS")
		)
		(fp_line
			(start 2.428494 -3.024886)
			(end 3.024886 -3.024886)
			(stroke
				(width 0.1524)
				(type default)
			)
			(layer "F.SilkS")
		)
		(fp_line
			(start 3.024886 -3.024886)
			(end 3.024886 -2.428494)
			(stroke
				(width 0.1524)
				(type default)
			)
			(layer "F.SilkS")
		)
		(fp_poly
			(pts
				(xy -4.348226 -2.707894) (xy -4.348226 -1.691894) (xy -3.332226 -2.199894)
			)
			(stroke
				(width 0)
				(type default)
			)
			(fill yes)
			(layer "F.SilkS")
		)
		(fp_line
			(start -3.024886 3.024886)
			(end -3.024886 -3.024886)
			(stroke
				(width 0.1)
				(type default)
			)
			(layer "F.Fab")
		)
		(fp_line
			(start 3.024886 3.024886)
			(end -3.024886 3.024886)
			(stroke
				(width 0.1)
				(type default)
			)
			(layer "F.Fab")
		)
		(fp_line
			(start -3.024886 -3.024886)
			(end 3.024886 -3.024886)
			(stroke
				(width 0.1)
				(type default)
			)
			(layer "F.Fab")
		)
		(fp_line
			(start 3.024886 -3.024886)
			(end 3.024886 3.024886)
			(stroke
				(width 0.1)
				(type default)
			)
			(layer "F.Fab")
		)
		(fp_poly
			(pts
				(xy -3.332226 -2.199894) (xy -4.348226 -1.691894) (xy -4.348226 -2.707894)
			)
			(stroke
				(width 0)
				(type default)
			)
			(fill yes)
			(layer "F.Fab")
		)
		(pad "1" smd rect
			(at -2.875026 -2.199894 180)
			(size 0.1778 0.6604)
			(layers "F.Cu" "F.Mask" "F.Paste")
			(net "PVDDIO_P1_PWM1")
		)
		(pad "2" smd rect
			(at -2.875026 -1.800098 180)
			(size 0.1778 0.6604)
			(layers "F.Cu" "F.Mask" "F.Paste")
			(net "PVDDIO_P1_PWM2")
		)
		(pad "3" smd rect
			(at -2.875026 -1.400048 180)
			(size 0.1778 0.6604)
			(layers "F.Cu" "F.Mask" "F.Paste")
			(net "PVDDIO_P1_PWM3")
		)
		(pad "4" smd rect
			(at -2.875026 -0.999998 180)
			(size 0.1778 0.6604)
			(layers "F.Cu" "F.Mask" "F.Paste")
			(net "PVDDIO_P1_PWM4")
		)
		(pad "5" smd rect
			(at -2.875026 -0.599948 180)
			(size 0.1778 0.6604)
			(layers "F.Cu" "F.Mask" "F.Paste")
			(net "NC_PVDDCR_CPU1_P1_PWM8")
		)
		(pad "6" smd rect
			(at -2.875026 -0.199898 180)
			(size 0.1778 0.6604)
			(layers "F.Cu" "F.Mask" "F.Paste")
			(net "NC_PVDDCR_CPU1_P1_PWM7")
		)
		(pad "7" smd rect
			(at -2.875026 0.199898 180)
			(size 0.1778 0.6604)
			(layers "F.Cu" "F.Mask" "F.Paste")
			(net "PVDDCR_CPU1_P1_PWM6")
		)
		(pad "8" smd rect
			(at -2.875026 0.599948 180)
			(size 0.1778 0.6604)
			(layers "F.Cu" "F.Mask" "F.Paste")
			(net "PVDDCR_CPU1_P1_PWM5")
		)
		(pad "9" smd rect
			(at -2.875026 0.999998 180)
			(size 0.1778 0.6604)
			(layers "F.Cu" "F.Mask" "F.Paste")
			(net "PVDDCR_CPU1_P1_PWM4")
		)
		(pad "10" smd rect
			(at -2.875026 1.400048 180)
			(size 0.1778 0.6604)
			(layers "F.Cu" "F.Mask" "F.Paste")
			(net "PVDDCR_CPU1_P1_PWM3")
		)
		(pad "11" smd rect
			(at -2.875026 1.800098 180)
			(size 0.1778 0.6604)
			(layers "F.Cu" "F.Mask" "F.Paste")
			(net "PVDDCR_CPU1_P1_PWM2")
		)
		(pad "12" smd rect
			(at -2.875026 2.199894 180)
			(size 0.1778 0.6604)
			(layers "F.Cu" "F.Mask" "F.Paste")
			(net "PVDDCR_CPU1_P1_PWM1")
		)
		(pad "13" smd rect
			(at -2.199894 2.875026 270)
			(size 0.1778 0.6604)
			(layers "F.Cu" "F.Mask" "F.Paste")
			(net "SMB_DIO_PVDDCR_CPU1_P1_R")
		)
		(pad "14" smd rect
			(at -1.800098 2.875026 270)
			(size 0.1778 0.6604)
			(layers "F.Cu" "F.Mask" "F.Paste")
			(net "SMB_CLK_PVDDCR_CPU1_P1_R")
		)
		(pad "15" smd rect
			(at -1.400048 2.875026 270)
			(size 0.1778 0.6604)
			(layers "F.Cu" "F.Mask" "F.Paste")
			(net "PVDDCR_CPU1_P1_SMB_ALERT_R")
		)
		(pad "16" smd rect
			(at -0.999998 2.875026 270)
			(size 0.1778 0.6604)
			(layers "F.Cu" "F.Mask" "F.Paste")
			(net "PWRGD_PVDDCR_CPU1_P1_R")
		)
		(pad "17" smd rect
			(at -0.599948 2.875026 270)
			(size 0.1778 0.6604)
			(layers "F.Cu" "F.Mask" "F.Paste")
			(net "PVDDCR_CPU1_P1_EN_R")
		)
		(pad "18" smd rect
			(at -0.199898 2.875026 270)
			(size 0.1778 0.6604)
			(layers "F.Cu" "F.Mask" "F.Paste")
			(net "PVDDCR_CPU1_P1_RESET_N_R")
		)
		(pad "19" smd rect
			(at 0.199898 2.875026 270)
			(size 0.1778 0.6604)
			(layers "F.Cu" "F.Mask" "F.Paste")
			(net "PVDD18_S5_P1")
		)
		(pad "20" smd rect
			(at 0.599948 2.875026 270)
			(size 0.1778 0.6604)
			(layers "F.Cu" "F.Mask" "F.Paste")
			(net "PWRGD_PVDDIO_P1_R")
		)
		(pad "21" smd rect
			(at 0.999998 2.875026 270)
			(size 0.1778 0.6604)
			(layers "F.Cu" "F.Mask" "F.Paste")
			(net "SVID_PVDDCR_CPU1_P1_SVD_R1")
		)
		(pad "22" smd rect
			(at 1.400048 2.875026 270)
			(size 0.1778 0.6604)
			(layers "F.Cu" "F.Mask" "F.Paste")
			(net "SVID_PVDDCR_CPU1_P1_SVC_R1")
		)
		(pad "23" smd rect
			(at 1.800098 2.875026 270)
			(size 0.1778 0.6604)
			(layers "F.Cu" "F.Mask" "F.Paste")
			(net "SVID_PVDDCR_CPU1_P1_SVTO_R")
		)
		(pad "24" smd rect
			(at 2.199894 2.875026 270)
			(size 0.1778 0.6604)
			(layers "F.Cu" "F.Mask" "F.Paste")
			(net "SVID_PVDDCR_CPU1_P1_SVTI_R")
		)
		(pad "25" smd rect
			(at 2.875026 2.199894 180)
			(size 0.1778 0.6604)
			(layers "F.Cu" "F.Mask" "F.Paste")
			(net "VSENSE_PVDDCR_CPU1_P1_VSEN0")
		)
		(pad "26" smd rect
			(at 2.875026 1.800098 180)
			(size 0.1778 0.6604)
			(layers "F.Cu" "F.Mask" "F.Paste")
			(net "VSENSE_VSS_SENSE_C_P1")
		)
		(pad "27" smd rect
			(at 2.875026 1.400048 180)
			(size 0.1778 0.6604)
			(layers "F.Cu" "F.Mask" "F.Paste")
			(net "PVDDCR_CPU1_P1_IMON1")
		)
		(pad "28" smd rect
			(at 2.875026 0.999998 180)
			(size 0.1778 0.6604)
			(layers "F.Cu" "F.Mask" "F.Paste")
			(net "PVDDCR_CPU1_P1_IMON2")
		)
		(pad "29" smd rect
			(at 2.875026 0.599948 180)
			(size 0.1778 0.6604)
			(layers "F.Cu" "F.Mask" "F.Paste")
			(net "PVDDCR_CPU1_P1_IMON3")
		)
		(pad "30" smd rect
			(at 2.875026 0.199898 180)
			(size 0.1778 0.6604)
			(layers "F.Cu" "F.Mask" "F.Paste")
			(net "PVDDCR_CPU1_P1_IMON4")
		)
		(pad "31" smd rect
			(at 2.875026 -0.199898 180)
			(size 0.1778 0.6604)
			(layers "F.Cu" "F.Mask" "F.Paste")
			(net "PVDDCR_CPU1_P1_IMON5")
		)
		(pad "32" smd rect
			(at 2.875026 -0.599948 180)
			(size 0.1778 0.6604)
			(layers "F.Cu" "F.Mask" "F.Paste")
			(net "PVDDCR_CPU1_P1_IMON6")
		)
		(pad "33" smd rect
			(at 2.875026 -0.999998 180)
			(size 0.1778 0.6604)
			(layers "F.Cu" "F.Mask" "F.Paste")
			(net "NC_PVDDCR_CPU1_P1_IMON7")
		)
		(pad "34" smd rect
			(at 2.875026 -1.400048 180)
			(size 0.1778 0.6604)
			(layers "F.Cu" "F.Mask" "F.Paste")
			(net "NC_PVDDCR_CPU1_P1_IMON8")
		)
		(pad "35" smd rect
			(at 2.875026 -1.800098 180)
			(size 0.1778 0.6604)
			(layers "F.Cu" "F.Mask" "F.Paste")
			(net "PVDDIO_P1_IMON4")
		)
		(pad "36" smd rect
			(at 2.875026 -2.199894 180)
			(size 0.1778 0.6604)
			(layers "F.Cu" "F.Mask" "F.Paste")
			(net "PVDDIO_P1_IMON3")
		)
		(pad "37" smd rect
			(at 2.199894 -2.875026 270)
			(size 0.1778 0.6604)
			(layers "F.Cu" "F.Mask" "F.Paste")
			(net "PVDDIO_P1_IMON2")
		)
		(pad "38" smd rect
			(at 1.800098 -2.875026 270)
			(size 0.1778 0.6604)
			(layers "F.Cu" "F.Mask" "F.Paste")
			(net "PVDDIO_P1_IMON1")
		)
		(pad "39" smd rect
			(at 1.400048 -2.875026 270)
			(size 0.1778 0.6604)
			(layers "F.Cu" "F.Mask" "F.Paste")
			(net "VSENSE_VSS_SENSE_B_P1")
		)
		(pad "40" smd rect
			(at 0.999998 -2.875026 270)
			(size 0.1778 0.6604)
			(layers "F.Cu" "F.Mask" "F.Paste")
			(net "VSENSE_PVDDIO_P1_VSEN1")
		)
		(pad "41" smd rect
			(at 0.599948 -2.875026 270)
			(size 0.1778 0.6604)
			(layers "F.Cu" "F.Mask" "F.Paste")
			(net "PVDDCR_CPU1_P1_OCP_N_R")
		)
		(pad "42" smd rect
			(at 0.199898 -2.875026 270)
			(size 0.1778 0.6604)
			(layers "F.Cu" "F.Mask" "F.Paste")
			(net "PVDDCR_CPU1_P1_EN1_ADDR_CFG")
		)
		(pad "43" smd rect
			(at -0.199898 -2.875026 270)
			(size 0.1778 0.6604)
			(layers "F.Cu" "F.Mask" "F.Paste")
			(net "PVDDIO_P1_TEMP1")
		)
		(pad "44" smd rect
			(at -0.599948 -2.875026 270)
			(size 0.1778 0.6604)
			(layers "F.Cu" "F.Mask" "F.Paste")
			(net "PVDDCR_CPU1_P1_TEMP0")
		)
		(pad "45" smd rect
			(at -0.999998 -2.875026 270)
			(size 0.1778 0.6604)
			(layers "F.Cu" "F.Mask" "F.Paste")
			(net "PVDDCR_CPU1_P1_VMON")
		)
		(pad "46" smd rect
			(at -1.400048 -2.875026 270)
			(size 0.1778 0.6604)
			(layers "F.Cu" "F.Mask" "F.Paste")
			(net "PVDDCR_CPU1_P1_VINSEN")
		)
		(pad "47" smd rect
			(at -1.800098 -2.875026 270)
			(size 0.1778 0.6604)
			(layers "F.Cu" "F.Mask" "F.Paste")
			(net "PVDDCR_CPU1_P1_VCC")
		)
		(pad "48" smd rect
			(at -2.199894 -2.875026 270)
			(size 0.1778 0.6604)
			(layers "F.Cu" "F.Mask" "F.Paste")
			(net "PVDDCR_CPU1_P1_VCCS")
		)
		(pad "TH" smd rect
			(at 0 0 270)
			(size 4.4196 4.4196)
			(layers "F.Cu" "F.Mask" "F.Paste")
			(net "GND")
		)
		(zone
			(layer "F.Cu")
			(hatch none 0.5)
			(connect_pads
				(clearance 0)
			)
			(min_thickness 0.25)
			(keepout
				(tracks not_allowed)
				(vias allowed)
				(pads allowed)
				(copperpour not_allowed)
				(footprints allowed)
			)
			(placement
				(enabled no)
				(sheetname "")
			)
			(fill
				(thermal_gap 0.5)
				(thermal_bridge_width 0.5)
				(island_removal_mode 0)
			)
			(polygon
				(pts
					(xy 30.5054 -366.603026) (xy 32.974026 -366.603026) (xy 32.974026 -361.614974) (xy 27.985974 -361.614974)
					(xy 27.985974 -366.603026) (xy 30.48 -366.603026) (xy 30.48 -366.3696) (xy 28.2194 -366.3696) (xy 28.2194 -361.8484)
					(xy 32.7406 -361.8484) (xy 32.7406 -366.3696) (xy 30.5054 -366.3696)
				)
			)
		)
	)
	(footprint ""
		(layer "F.Cu")
		(at 115.389152 -401.353782 180)
		(property "Reference" "U42"
			(at -0.873252 -3.739642 0)
			(unlocked yes)
			(layer "F.SilkS")
			(effects
				(font
					(size 0.7874 0.5842)
					(thickness 0.1524)
				)
			)
		)
		(property "Value" ""
			(at 0 0 180)
			(layer "F.Fab")
			(effects
				(font
					(size 1.27 1.27)
				)
			)
		)
		(duplicate_pad_numbers_are_jumpers no)
		(fp_line
			(start 1.03378 1.284478)
			(end -1.03378 1.284478)
			(stroke
				(width 0.1524)
				(type default)
			)
			(layer "F.SilkS")
		)
		(fp_line
			(start 1.03378 -1.284478)
			(end 1.03378 1.284478)
			(stroke
				(width 0.1524)
				(type default)
			)
			(layer "F.SilkS")
		)
		(fp_line
			(start -1.03378 1.284478)
			(end -1.03378 -1.284478)
			(stroke
				(width 0.1524)
				(type default)
			)
			(layer "F.SilkS")
		)
		(fp_line
			(start -1.03378 -1.284478)
			(end 1.03378 -1.284478)
			(stroke
				(width 0.1524)
				(type default)
			)
			(layer "F.SilkS")
		)
		(fp_poly
			(pts
				(xy -1.176274 -0.652272) (xy -1.478788 -0.047244) (xy -1.841754 -0.531114)
			)
			(stroke
				(width 0)
				(type default)
			)
			(fill yes)
			(layer "F.SilkS")
		)
		(fp_line
			(start 0.774954 1.02489)
			(end -0.774954 1.02489)
			(stroke
				(width 0.1)
				(type default)
			)
			(layer "F.Fab")
		)
		(fp_line
			(start 0.774954 -1.02489)
			(end 0.774954 1.02489)
			(stroke
				(width 0.1)
				(type default)
			)
			(layer "F.Fab")
		)
		(fp_line
			(start -0.774954 1.02489)
			(end -0.774954 -1.02489)
			(stroke
				(width 0.1)
				(type default)
			)
			(layer "F.Fab")
		)
		(fp_line
			(start -0.774954 -1.02489)
			(end 0.774954 -1.02489)
			(stroke
				(width 0.1)
				(type default)
			)
			(layer "F.Fab")
		)
		(fp_poly
			(pts
				(xy -1.201674 -0.750062) (xy -1.806702 -0.447548) (xy -1.806702 -1.052576)
			)
			(stroke
				(width 0)
				(type default)
			)
			(fill yes)
			(layer "F.Fab")
		)
		(pad "1" smd rect
			(at -0.64008 -0.750062 270)
			(size 0.3048 0.5334)
			(layers "F.Cu" "F.Mask" "F.Paste")
			(net "SMB_RT_CPU1_P1_ROM_MUX_1D_SCL")
		)
		(pad "2" smd rect
			(at -0.64008 -0.249936 270)
			(size 0.254 0.5334)
			(layers "F.Cu" "F.Mask" "F.Paste")
			(net "SMB_RT_CPU1_P1_ROM_MUX_1D_SDA")
		)
		(pad "3" smd rect
			(at -0.64008 0.249936 270)
			(size 0.254 0.5334)
			(layers "F.Cu" "F.Mask" "F.Paste")
			(net "SMB_RT_CPU1_P1_ROM_MUX_2D_SCL")
		)
		(pad "4" smd rect
			(at -0.64008 0.750062 270)
			(size 0.3048 0.5334)
			(layers "F.Cu" "F.Mask" "F.Paste")
			(net "SMB_RT_CPU1_P1_ROM_MUX_2D_SDA")
		)
		(pad "5" smd rect
			(at 0 0.839978 180)
			(size 0.3302 0.635)
			(layers "F.Cu" "F.Mask" "F.Paste")
			(net "GND")
		)
		(pad "6" smd rect
			(at 0.64008 0.750062 270)
			(size 0.3048 0.5334)
			(layers "F.Cu" "F.Mask" "F.Paste")
			(net "RT_ROM_MUX2_OE_N")
		)
		(pad "7" smd rect
			(at 0.64008 0.249936 270)
			(size 0.254 0.5334)
			(layers "F.Cu" "F.Mask" "F.Paste")
			(net "SMB_RT_CPU1_P1_ROM_R_SDA")
		)
		(pad "8" smd rect
			(at 0.64008 -0.249936 270)
			(size 0.254 0.5334)
			(layers "F.Cu" "F.Mask" "F.Paste")
			(net "SMB_RT_CPU1_P1_ROM_R_SCL")
		)
		(pad "9" smd rect
			(at 0.64008 -0.750062 270)
			(size 0.3048 0.5334)
			(layers "F.Cu" "F.Mask" "F.Paste")
			(net "FM_SMB_RT_ROM_MUX2_SEL")
		)
		(pad "10" smd rect
			(at 0 -0.839978 180)
			(size 0.3302 0.635)
			(layers "F.Cu" "F.Mask" "F.Paste")
			(net "P3V3_AUX")
		)
	)
	(footprint ""
		(layer "F.Cu")
		(at 40.386 -389.0264 -90)
		(property "Reference" "R6724"
			(at 0 0 270)
			(layer "F.SilkS")
			(hide yes)
			(effects
				(font
					(size 1.27 1.27)
				)
			)
		)
		(property "Value" ""
			(at 0 0 270)
			(layer "F.Fab")
			(effects
				(font
					(size 1.27 1.27)
				)
			)
		)
		(duplicate_pad_numbers_are_jumpers no)
		(fp_line
			(start -0.32512 0.175006)
			(end -0.32512 -0.175006)
			(stroke
				(width 0.1)
				(type default)
			)
			(layer "F.Fab")
		)
		(fp_line
			(start 0.32512 0.175006)
			(end -0.32512 0.175006)
			(stroke
				(width 0.1)
				(type default)
			)
			(layer "F.Fab")
		)
		(fp_line
			(start -0.32512 -0.175006)
			(end 0.32512 -0.175006)
			(stroke
				(width 0.1)
				(type default)
			)
			(layer "F.Fab")
		)
		(fp_line
			(start 0.32512 -0.175006)
			(end 0.32512 0.175006)
			(stroke
				(width 0.1)
				(type default)
			)
			(layer "F.Fab")
		)
		(pad "1" smd rect
			(at -0.2667 0 270)
			(size 0.3048 0.381)
			(layers "F.Cu" "F.Mask" "F.Paste")
			(net "P1V8_CPU1_RT_1D")
		)
		(pad "2" smd rect
			(at 0.2667 0 90)
			(size 0.3048 0.381)
			(layers "F.Cu" "F.Mask" "F.Paste")
			(net "RST_RT_CPU1_P0_RESET_R_N")
		)
	)
	(footprint ""
		(layer "F.Cu")
		(at 246.04726 -418.118544 -90)
		(property "Reference" "PD15"
			(at -1.40208 3.638804 90)
			(unlocked yes)
			(layer "F.SilkS")
			(effects
				(font
					(size 0.7874 0.5842)
					(thickness 0.1524)
				)
				(justify left)
			)
		)
		(property "Value" ""
			(at 0 0 270)
			(layer "F.Fab")
			(effects
				(font
					(size 1.27 1.27)
				)
			)
		)
		(duplicate_pad_numbers_are_jumpers no)
		(fp_line
			(start -4.664456 3.109976)
			(end -4.664456 -3.109976)
			(stroke
				(width 0.1524)
				(type default)
			)
			(layer "F.SilkS")
		)
		(fp_line
			(start 4.156202 3.109976)
			(end 4.183126 3.109976)
			(stroke
				(width 0.1524)
				(type default)
			)
			(layer "F.SilkS")
		)
		(fp_line
			(start 4.743704 3.109976)
			(end 4.6101 3.109976)
			(stroke
				(width 0.1524)
				(type default)
			)
			(layer "F.SilkS")
		)
		(fp_line
			(start 4.743704 3.109976)
			(end 5.4102 3.109976)
			(stroke
				(width 0.1524)
				(type default)
			)
			(layer "F.SilkS")
		)
		(fp_line
			(start 4.769104 3.109976)
			(end -4.664456 3.109976)
			(stroke
				(width 0.1524)
				(type default)
			)
			(layer "F.SilkS")
		)
		(fp_line
			(start 4.794504 3.109976)
			(end 3.554984 3.109976)
			(stroke
				(width 0.1524)
				(type default)
			)
			(layer "F.SilkS")
		)
		(fp_line
			(start 5.4102 3.109976)
			(end 5.4102 -3.109976)
			(stroke
				(width 0.1524)
				(type default)
			)
			(layer "F.SilkS")
		)
		(fp_line
			(start 4.715002 3.035554)
			(end 4.7117 2.984754)
			(stroke
				(width 0.1524)
				(type default)
			)
			(layer "F.SilkS")
		)
		(fp_line
			(start 0.762 1.27)
			(end 0.762 -1.27)
			(stroke
				(width 0.1524)
				(type default)
			)
			(layer "F.SilkS")
		)
		(fp_line
			(start -0.508 1.016)
			(end -0.508 -1.016)
			(stroke
				(width 0.1524)
				(type default)
			)
			(layer "F.SilkS")
		)
		(fp_line
			(start -1.0668 0)
			(end -0.6096 0)
			(stroke
				(width 0.1524)
				(type default)
			)
			(layer "F.SilkS")
		)
		(fp_line
			(start 0.762 0)
			(end -0.508 1.016)
			(stroke
				(width 0.1524)
				(type default)
			)
			(layer "F.SilkS")
		)
		(fp_line
			(start 0.762 0)
			(end 1.2192 0)
			(stroke
				(width 0.1524)
				(type default)
			)
			(layer "F.SilkS")
		)
		(fp_line
			(start -0.508 -1.016)
			(end 0.762 0)
			(stroke
				(width 0.1524)
				(type default)
			)
			(layer "F.SilkS")
		)
		(fp_line
			(start -4.664456 -3.109976)
			(end 4.743704 -3.109976)
			(stroke
				(width 0.1524)
				(type default)
			)
			(layer "F.SilkS")
		)
		(fp_line
			(start 4.183126 -3.109976)
			(end 4.794504 -3.109976)
			(stroke
				(width 0.1524)
				(type default)
			)
			(layer "F.SilkS")
		)
		(fp_line
			(start 4.511802 -3.109976)
			(end 4.207002 -3.109976)
			(stroke
				(width 0.1524)
				(type default)
			)
			(layer "F.SilkS")
		)
		(fp_line
			(start 4.6101 -3.109976)
			(end 4.283202 -3.109976)
			(stroke
				(width 0.1524)
				(type default)
			)
			(layer "F.SilkS")
		)
		(fp_line
			(start 4.695444 -3.109976)
			(end 4.695444 3.109976)
			(stroke
				(width 0.1524)
				(type default)
			)
			(layer "F.SilkS")
		)
		(fp_line
			(start 4.70535 -3.109976)
			(end 4.70535 3.109976)
			(stroke
				(width 0.1524)
				(type default)
			)
			(layer "F.SilkS")
		)
		(fp_line
			(start 4.70535 -3.109976)
			(end 4.70535 3.109976)
			(stroke
				(width 0.1524)
				(type default)
			)
			(layer "F.SilkS")
		)
		(fp_line
			(start 4.70535 -3.109976)
			(end 4.70535 3.109976)
			(stroke
				(width 0.1524)
				(type default)
			)
			(layer "F.SilkS")
		)
		(fp_line
			(start 4.805426 -3.109976)
			(end 4.805426 3.109976)
			(stroke
				(width 0.1524)
				(type default)
			)
			(layer "F.SilkS")
		)
		(fp_line
			(start 4.932426 -3.109976)
			(end 4.932426 3.109976)
			(stroke
				(width 0.1524)
				(type default)
			)
			(layer "F.SilkS")
		)
		(fp_line
			(start 5.008626 -3.109976)
			(end 5.008626 3.109976)
			(stroke
				(width 0.1524)
				(type default)
			)
			(layer "F.SilkS")
		)
		(fp_line
			(start 5.110226 -3.109976)
			(end 5.110226 3.109976)
			(stroke
				(width 0.1524)
				(type default)
			)
			(layer "F.SilkS")
		)
		(fp_line
			(start 5.211826 -3.109976)
			(end 5.211826 3.109976)
			(stroke
				(width 0.1524)
				(type default)
			)
			(layer "F.SilkS")
		)
		(fp_line
			(start 5.262626 -3.109976)
			(end 5.262626 3.109976)
			(stroke
				(width 0.1524)
				(type default)
			)
			(layer "F.SilkS")
		)
		(fp_line
			(start 5.313426 -3.109976)
			(end 5.313426 3.109976)
			(stroke
				(width 0.1524)
				(type default)
			)
			(layer "F.SilkS")
		)
		(fp_line
			(start 5.4102 -3.109976)
			(end 4.783074 -3.109976)
			(stroke
				(width 0.1524)
				(type default)
			)
			(layer "F.SilkS")
		)
		(fp_line
			(start -4.065016 3.109976)
			(end -4.065016 -3.109976)
			(stroke
				(width 0.1)
				(type default)
			)
			(layer "F.Fab")
		)
		(fp_line
			(start 4.065016 3.109976)
			(end -4.065016 3.109976)
			(stroke
				(width 0.1)
				(type default)
			)
			(layer "F.Fab")
		)
		(fp_line
			(start -4.065016 -3.109976)
			(end 4.065016 -3.109976)
			(stroke
				(width 0.1)
				(type default)
			)
			(layer "F.Fab")
		)
		(fp_line
			(start 4.065016 -3.109976)
			(end 4.065016 3.109976)
			(stroke
				(width 0.1)
				(type default)
			)
			(layer "F.Fab")
		)
		(fp_text user "-"
			(at 6.643624 0.40005 90)
			(unlocked yes)
			(layer "F.SilkS")
			(effects
				(font
					(size 1.905 1.4224)
					(thickness 0.1524)
				)
				(justify left)
			)
		)
		(fp_text user "+"
			(at -4.5974 0.24765 90)
			(unlocked yes)
			(layer "F.SilkS")
			(effects
				(font
					(size 1.905 1.4224)
					(thickness 0.1524)
				)
				(justify left)
			)
		)
		(fp_text user "-"
			(at 6.643624 0.40005 90)
			(unlocked yes)
			(layer "F.Fab")
			(effects
				(font
					(size 1.905 1.4224)
					(thickness 0.1524)
				)
				(justify left)
			)
		)
		(fp_text user "+"
			(at -4.5974 0.24765 90)
			(unlocked yes)
			(layer "F.Fab")
			(effects
				(font
					(size 1.905 1.4224)
					(thickness 0.1524)
				)
				(justify left)
			)
		)
		(pad "A" smd rect
			(at -3.299968 0 90)
			(size 2.413 3.302)
			(layers "F.Cu" "F.Mask" "F.Paste")
			(net "GND")
		)
		(pad "C" smd rect
			(at 3.299968 0 90)
			(size 2.413 3.302)
			(layers "F.Cu" "F.Mask" "F.Paste")
			(net "P12V_PSU_FUSE")
		)
	)
	(footprint ""
		(layer "F.Cu")
		(at 49.778666 -25.309068 90)
		(property "Reference" "R3203"
			(at 0 0 90)
			(layer "F.SilkS")
			(hide yes)
			(effects
				(font
					(size 1.27 1.27)
				)
			)
		)
		(property "Value" ""
			(at 0 0 90)
			(layer "F.Fab")
			(effects
				(font
					(size 1.27 1.27)
				)
			)
		)
		(duplicate_pad_numbers_are_jumpers no)
		(fp_line
			(start 0.7874 -0.4064)
			(end 0.7874 0.4064)
			(stroke
				(width 0.1524)
				(type default)
			)
			(layer "F.SilkS")
		)
		(fp_line
			(start -0.7874 -0.4064)
			(end 0.7874 -0.4064)
			(stroke
				(width 0.1524)
				(type default)
			)
			(layer "F.SilkS")
		)
		(fp_line
			(start 0.7874 0.4064)
			(end -0.7874 0.4064)
			(stroke
				(width 0.1524)
				(type default)
			)
			(layer "F.SilkS")
		)
		(fp_line
			(start -0.7874 0.4064)
			(end -0.7874 -0.4064)
			(stroke
				(width 0.1524)
				(type default)
			)
			(layer "F.SilkS")
		)
		(fp_line
			(start -0.12065 -0.305054)
			(end -0.12065 -0.2794)
			(stroke
				(width 0.1)
				(type default)
			)
			(layer "F.Fab")
		)
		(fp_line
			(start -0.67945 -0.305054)
			(end -0.12065 -0.305054)
			(stroke
				(width 0.1)
				(type default)
			)
			(layer "F.Fab")
		)
		(fp_line
			(start 0.67945 -0.3048)
			(end 0.67945 0.3048)
			(stroke
				(width 0.1)
				(type default)
			)
			(layer "F.Fab")
		)
		(fp_line
			(start 0.12065 -0.3048)
			(end 0.67945 -0.3048)
			(stroke
				(width 0.1)
				(type default)
			)
			(layer "F.Fab")
		)
		(fp_line
			(start 0.12065 -0.2794)
			(end 0.12065 -0.3048)
			(stroke
				(width 0.1)
				(type default)
			)
			(layer "F.Fab")
		)
		(fp_line
			(start -0.12065 -0.2794)
			(end 0.12065 -0.2794)
			(stroke
				(width 0.1)
				(type default)
			)
			(layer "F.Fab")
		)
		(fp_line
			(start 0.120396 0.2794)
			(end -0.12065 0.2794)
			(stroke
				(width 0.1)
				(type default)
			)
			(layer "F.Fab")
		)
		(fp_line
			(start -0.12065 0.2794)
			(end -0.12065 0.3048)
			(stroke
				(width 0.1)
				(type default)
			)
			(layer "F.Fab")
		)
		(fp_line
			(start 0.67945 0.3048)
			(end 0.120396 0.3048)
			(stroke
				(width 0.1)
				(type default)
			)
			(layer "F.Fab")
		)
		(fp_line
			(start 0.120396 0.3048)
			(end 0.120396 0.2794)
			(stroke
				(width 0.1)
				(type default)
			)
			(layer "F.Fab")
		)
		(fp_line
			(start -0.12065 0.3048)
			(end -0.67945 0.3048)
			(stroke
				(width 0.1)
				(type default)
			)
			(layer "F.Fab")
		)
		(fp_line
			(start -0.67945 0.3048)
			(end -0.67945 -0.305054)
			(stroke
				(width 0.1)
				(type default)
			)
			(layer "F.Fab")
		)
		(pad "1" smd circle
			(at -0.40005 0 90)
			(size 0 0)
			(layers "F.Cu" "F.Mask" "F.Paste")
			(net "OCP_V3_2_AUX_PWR_EN")
		)
		(pad "2" smd circle
			(at 0.40005 0 90)
			(size 0 0)
			(layers "F.Cu" "F.Mask" "F.Paste")
			(net "OCP_V3_2_AUX_PWR_EN_R1")
		)
	)
	(footprint ""
		(layer "F.Cu")
		(at 148.971 -118.364 -90)
		(property "Reference" "R9021"
			(at 0 0 270)
			(layer "F.SilkS")
			(hide yes)
			(effects
				(font
					(size 1.27 1.27)
				)
			)
		)
		(property "Value" ""
			(at 0 0 270)
			(layer "F.Fab")
			(effects
				(font
					(size 1.27 1.27)
				)
			)
		)
		(duplicate_pad_numbers_are_jumpers no)
		(fp_line
			(start -0.7874 0.4064)
			(end -0.7874 -0.4064)
			(stroke
				(width 0.1524)
				(type default)
			)
			(layer "F.SilkS")
		)
		(fp_line
			(start 0.7874 0.4064)
			(end -0.7874 0.4064)
			(stroke
				(width 0.1524)
				(type default)
			)
			(layer "F.SilkS")
		)
		(fp_line
			(start -0.7874 -0.4064)
			(end 0.7874 -0.4064)
			(stroke
				(width 0.1524)
				(type default)
			)
			(layer "F.SilkS")
		)
		(fp_line
			(start 0.7874 -0.4064)
			(end 0.7874 0.4064)
			(stroke
				(width 0.1524)
				(type default)
			)
			(layer "F.SilkS")
		)
		(fp_line
			(start -0.67945 0.3048)
			(end -0.67945 -0.305054)
			(stroke
				(width 0.1)
				(type default)
			)
			(layer "F.Fab")
		)
		(fp_line
			(start -0.12065 0.3048)
			(end -0.67945 0.3048)
			(stroke
				(width 0.1)
				(type default)
			)
			(layer "F.Fab")
		)
		(fp_line
			(start 0.120396 0.3048)
			(end 0.120396 0.2794)
			(stroke
				(width 0.1)
				(type default)
			)
			(layer "F.Fab")
		)
		(fp_line
			(start 0.67945 0.3048)
			(end 0.120396 0.3048)
			(stroke
				(width 0.1)
				(type default)
			)
			(layer "F.Fab")
		)
		(fp_line
			(start -0.12065 0.2794)
			(end -0.12065 0.3048)
			(stroke
				(width 0.1)
				(type default)
			)
			(layer "F.Fab")
		)
		(fp_line
			(start 0.120396 0.2794)
			(end -0.12065 0.2794)
			(stroke
				(width 0.1)
				(type default)
			)
			(layer "F.Fab")
		)
		(fp_line
			(start -0.12065 -0.2794)
			(end 0.12065 -0.2794)
			(stroke
				(width 0.1)
				(type default)
			)
			(layer "F.Fab")
		)
		(fp_line
			(start 0.12065 -0.2794)
			(end 0.12065 -0.3048)
			(stroke
				(width 0.1)
				(type default)
			)
			(layer "F.Fab")
		)
		(fp_line
			(start 0.12065 -0.3048)
			(end 0.67945 -0.3048)
			(stroke
				(width 0.1)
				(type default)
			)
			(layer "F.Fab")
		)
		(fp_line
			(start 0.67945 -0.3048)
			(end 0.67945 0.3048)
			(stroke
				(width 0.1)
				(type default)
			)
			(layer "F.Fab")
		)
		(fp_line
			(start -0.67945 -0.305054)
			(end -0.12065 -0.305054)
			(stroke
				(width 0.1)
				(type default)
			)
			(layer "F.Fab")
		)
		(fp_line
			(start -0.12065 -0.305054)
			(end -0.12065 -0.2794)
			(stroke
				(width 0.1)
				(type default)
			)
			(layer "F.Fab")
		)
		(pad "1" smd circle
			(at -0.40005 0 270)
			(size 0 0)
			(layers "F.Cu" "F.Mask" "F.Paste")
			(net "P12V_AUX")
		)
		(pad "2" smd circle
			(at 0.40005 0 270)
			(size 0 0)
			(layers "F.Cu" "F.Mask" "F.Paste")
			(net "U206_VS")
		)
	)
	(footprint ""
		(layer "F.Cu")
		(at 74.357738 -401.884388 90)
		(property "Reference" "C7007"
			(at 0 0 90)
			(layer "F.SilkS")
			(hide yes)
			(effects
				(font
					(size 1.27 1.27)
				)
			)
		)
		(property "Value" ""
			(at 0 0 90)
			(layer "F.Fab")
			(effects
				(font
					(size 1.27 1.27)
				)
			)
		)
		(duplicate_pad_numbers_are_jumpers no)
		(fp_line
			(start 1.524 -0.762)
			(end 1.524 0.762)
			(stroke
				(width 0.1524)
				(type default)
			)
			(layer "F.SilkS")
		)
		(fp_line
			(start -1.524 -0.762)
			(end 1.524 -0.762)
			(stroke
				(width 0.1524)
				(type default)
			)
			(layer "F.SilkS")
		)
		(fp_line
			(start 1.524 0.762)
			(end -1.524 0.762)
			(stroke
				(width 0.1524)
				(type default)
			)
			(layer "F.SilkS")
		)
		(fp_line
			(start -1.524 0.762)
			(end -1.524 -0.762)
			(stroke
				(width 0.1524)
				(type default)
			)
			(layer "F.SilkS")
		)
		(fp_line
			(start 1.1049 -0.724916)
			(end -1.1049 -0.724916)
			(stroke
				(width 0.1)
				(type default)
			)
			(layer "F.Fab")
		)
		(fp_line
			(start -1.1049 -0.724916)
			(end -1.1049 0.724916)
			(stroke
				(width 0.1)
				(type default)
			)
			(layer "F.Fab")
		)
		(fp_line
			(start 1.1049 0.724916)
			(end 1.1049 -0.724916)
			(stroke
				(width 0.1)
				(type default)
			)
			(layer "F.Fab")
		)
		(fp_line
			(start -1.1049 0.724916)
			(end 1.1049 0.724916)
			(stroke
				(width 0.1)
				(type default)
			)
			(layer "F.Fab")
		)
		(pad "1" smd rect
			(at -0.889 0 270)
			(size 1.016 1.27)
			(layers "F.Cu" "F.Mask" "F.Paste")
			(net "P0V9_CPU1_RT_2D")
		)
		(pad "2" smd rect
			(at 0.889 0 270)
			(size 1.016 1.27)
			(layers "F.Cu" "F.Mask" "F.Paste")
			(net "GND")
		)
	)
	(footprint ""
		(layer "F.Cu")
		(at 177.748946 -413.815022 90)
		(property "Reference" "R2693"
			(at 0 0 90)
			(layer "F.SilkS")
			(hide yes)
			(effects
				(font
					(size 1.27 1.27)
				)
			)
		)
		(property "Value" ""
			(at 0 0 90)
			(layer "F.Fab")
			(effects
				(font
					(size 1.27 1.27)
				)
			)
		)
		(duplicate_pad_numbers_are_jumpers no)
		(fp_line
			(start 0.7874 -0.4064)
			(end 0.7874 0.4064)
			(stroke
				(width 0.1524)
				(type default)
			)
			(layer "F.SilkS")
		)
		(fp_line
			(start -0.7874 -0.4064)
			(end 0.7874 -0.4064)
			(stroke
				(width 0.1524)
				(type default)
			)
			(layer "F.SilkS")
		)
		(fp_line
			(start 0.7874 0.4064)
			(end -0.7874 0.4064)
			(stroke
				(width 0.1524)
				(type default)
			)
			(layer "F.SilkS")
		)
		(fp_line
			(start -0.7874 0.4064)
			(end -0.7874 -0.4064)
			(stroke
				(width 0.1524)
				(type default)
			)
			(layer "F.SilkS")
		)
		(fp_line
			(start -0.12065 -0.305054)
			(end -0.12065 -0.2794)
			(stroke
				(width 0.1)
				(type default)
			)
			(layer "F.Fab")
		)
		(fp_line
			(start -0.67945 -0.305054)
			(end -0.12065 -0.305054)
			(stroke
				(width 0.1)
				(type default)
			)
			(layer "F.Fab")
		)
		(fp_line
			(start 0.67945 -0.3048)
			(end 0.67945 0.3048)
			(stroke
				(width 0.1)
				(type default)
			)
			(layer "F.Fab")
		)
		(fp_line
			(start 0.12065 -0.3048)
			(end 0.67945 -0.3048)
			(stroke
				(width 0.1)
				(type default)
			)
			(layer "F.Fab")
		)
		(fp_line
			(start 0.12065 -0.2794)
			(end 0.12065 -0.3048)
			(stroke
				(width 0.1)
				(type default)
			)
			(layer "F.Fab")
		)
		(fp_line
			(start -0.12065 -0.2794)
			(end 0.12065 -0.2794)
			(stroke
				(width 0.1)
				(type default)
			)
			(layer "F.Fab")
		)
		(fp_line
			(start 0.120396 0.2794)
			(end -0.12065 0.2794)
			(stroke
				(width 0.1)
				(type default)
			)
			(layer "F.Fab")
		)
		(fp_line
			(start -0.12065 0.2794)
			(end -0.12065 0.3048)
			(stroke
				(width 0.1)
				(type default)
			)
			(layer "F.Fab")
		)
		(fp_line
			(start 0.67945 0.3048)
			(end 0.120396 0.3048)
			(stroke
				(width 0.1)
				(type default)
			)
			(layer "F.Fab")
		)
		(fp_line
			(start 0.120396 0.3048)
			(end 0.120396 0.2794)
			(stroke
				(width 0.1)
				(type default)
			)
			(layer "F.Fab")
		)
		(fp_line
			(start -0.12065 0.3048)
			(end -0.67945 0.3048)
			(stroke
				(width 0.1)
				(type default)
			)
			(layer "F.Fab")
		)
		(fp_line
			(start -0.67945 0.3048)
			(end -0.67945 -0.305054)
			(stroke
				(width 0.1)
				(type default)
			)
			(layer "F.Fab")
		)
		(pad "1" smd circle
			(at -0.40005 0 90)
			(size 0 0)
			(layers "F.Cu" "F.Mask" "F.Paste")
			(net "P3V3_AUX")
		)
		(pad "2" smd circle
			(at 0.40005 0 90)
			(size 0 0)
			(layers "F.Cu" "F.Mask" "F.Paste")
			(net "TCA9539_0_ADD1")
		)
	)
	(footprint ""
		(layer "F.Cu")
		(at 38.774878 -16.099536 90)
		(property "Reference" "C695"
			(at 0 0 90)
			(layer "F.SilkS")
			(hide yes)
			(effects
				(font
					(size 1.27 1.27)
				)
			)
		)
		(property "Value" ""
			(at 0 0 90)
			(layer "F.Fab")
			(effects
				(font
					(size 1.27 1.27)
				)
			)
		)
		(duplicate_pad_numbers_are_jumpers no)
		(fp_line
			(start 0.299974 -0.150114)
			(end 0.299974 0.150114)
			(stroke
				(width 0.1)
				(type default)
			)
			(layer "F.Fab")
		)
		(fp_line
			(start -0.299974 -0.150114)
			(end 0.299974 -0.150114)
			(stroke
				(width 0.1)
				(type default)
			)
			(layer "F.Fab")
		)
		(fp_line
			(start 0.299974 0.150114)
			(end -0.299974 0.150114)
			(stroke
				(width 0.1)
				(type default)
			)
			(layer "F.Fab")
		)
		(fp_line
			(start -0.299974 0.150114)
			(end -0.299974 -0.150114)
			(stroke
				(width 0.1)
				(type default)
			)
			(layer "F.Fab")
		)
		(pad "1" smd rect
			(at -0.2667 0 90)
			(size 0.3048 0.381)
			(layers "F.Cu" "F.Mask" "F.Paste")
			(net "P5E_CPU1_G1_TX_C_DP<7>")
		)
		(pad "2" smd rect
			(at 0.2667 0 90)
			(size 0.3048 0.381)
			(layers "F.Cu" "F.Mask" "F.Paste")
			(net "P5E_CPU1_G1_TX_DP<7>")
		)
	)
	(footprint ""
		(layer "F.Cu")
		(at 187.871608 -100.290376 90)
		(property "Reference" "R1339"
			(at 0 0 90)
			(layer "F.SilkS")
			(hide yes)
			(effects
				(font
					(size 1.27 1.27)
				)
			)
		)
		(property "Value" ""
			(at 0 0 90)
			(layer "F.Fab")
			(effects
				(font
					(size 1.27 1.27)
				)
			)
		)
		(duplicate_pad_numbers_are_jumpers no)
		(fp_line
			(start 0.7874 -0.4064)
			(end 0.7874 0.4064)
			(stroke
				(width 0.1524)
				(type default)
			)
			(layer "F.SilkS")
		)
		(fp_line
			(start -0.7874 -0.4064)
			(end 0.7874 -0.4064)
			(stroke
				(width 0.1524)
				(type default)
			)
			(layer "F.SilkS")
		)
		(fp_line
			(start 0.7874 0.4064)
			(end -0.7874 0.4064)
			(stroke
				(width 0.1524)
				(type default)
			)
			(layer "F.SilkS")
		)
		(fp_line
			(start -0.7874 0.4064)
			(end -0.7874 -0.4064)
			(stroke
				(width 0.1524)
				(type default)
			)
			(layer "F.SilkS")
		)
		(fp_line
			(start -0.12065 -0.305054)
			(end -0.12065 -0.2794)
			(stroke
				(width 0.1)
				(type default)
			)
			(layer "F.Fab")
		)
		(fp_line
			(start -0.67945 -0.305054)
			(end -0.12065 -0.305054)
			(stroke
				(width 0.1)
				(type default)
			)
			(layer "F.Fab")
		)
		(fp_line
			(start 0.67945 -0.3048)
			(end 0.67945 0.3048)
			(stroke
				(width 0.1)
				(type default)
			)
			(layer "F.Fab")
		)
		(fp_line
			(start 0.12065 -0.3048)
			(end 0.67945 -0.3048)
			(stroke
				(width 0.1)
				(type default)
			)
			(layer "F.Fab")
		)
		(fp_line
			(start 0.12065 -0.2794)
			(end 0.12065 -0.3048)
			(stroke
				(width 0.1)
				(type default)
			)
			(layer "F.Fab")
		)
		(fp_line
			(start -0.12065 -0.2794)
			(end 0.12065 -0.2794)
			(stroke
				(width 0.1)
				(type default)
			)
			(layer "F.Fab")
		)
		(fp_line
			(start 0.120396 0.2794)
			(end -0.12065 0.2794)
			(stroke
				(width 0.1)
				(type default)
			)
			(layer "F.Fab")
		)
		(fp_line
			(start -0.12065 0.2794)
			(end -0.12065 0.3048)
			(stroke
				(width 0.1)
				(type default)
			)
			(layer "F.Fab")
		)
		(fp_line
			(start 0.67945 0.3048)
			(end 0.120396 0.3048)
			(stroke
				(width 0.1)
				(type default)
			)
			(layer "F.Fab")
		)
		(fp_line
			(start 0.120396 0.3048)
			(end 0.120396 0.2794)
			(stroke
				(width 0.1)
				(type default)
			)
			(layer "F.Fab")
		)
		(fp_line
			(start -0.12065 0.3048)
			(end -0.67945 0.3048)
			(stroke
				(width 0.1)
				(type default)
			)
			(layer "F.Fab")
		)
		(fp_line
			(start -0.67945 0.3048)
			(end -0.67945 -0.305054)
			(stroke
				(width 0.1)
				(type default)
			)
			(layer "F.Fab")
		)
		(pad "1" smd circle
			(at -0.40005 0 90)
			(size 0 0)
			(layers "F.Cu" "F.Mask" "F.Paste")
			(net "OCP_V3_2_P3V3_P12V_ADC_R_ALERT")
		)
		(pad "2" smd circle
			(at 0.40005 0 90)
			(size 0 0)
			(layers "F.Cu" "F.Mask" "F.Paste")
			(net "OCP_V3_2_P3V3_P12V_ADC_ALERT")
		)
	)
	(footprint ""
		(layer "F.Cu")
		(at 78.65237 -182.585106 90)
		(property "Reference" "PC262_1"
			(at 0 0 90)
			(layer "F.SilkS")
			(hide yes)
			(effects
				(font
					(size 1.27 1.27)
				)
			)
		)
		(property "Value" ""
			(at 0 0 90)
			(layer "F.Fab")
			(effects
				(font
					(size 1.27 1.27)
				)
			)
		)
		(duplicate_pad_numbers_are_jumpers no)
		(fp_line
			(start 0.7874 -0.4064)
			(end 0.7874 0.4064)
			(stroke
				(width 0.1524)
				(type default)
			)
			(layer "F.SilkS")
		)
		(fp_line
			(start -0.7874 -0.4064)
			(end 0.7874 -0.4064)
			(stroke
				(width 0.1524)
				(type default)
			)
			(layer "F.SilkS")
		)
		(fp_line
			(start 0.7874 0.4064)
			(end -0.7874 0.4064)
			(stroke
				(width 0.1524)
				(type default)
			)
			(layer "F.SilkS")
		)
		(fp_line
			(start -0.7874 0.4064)
			(end -0.7874 -0.4064)
			(stroke
				(width 0.1524)
				(type default)
			)
			(layer "F.SilkS")
		)
		(fp_line
			(start -0.12065 -0.305054)
			(end -0.12065 -0.2794)
			(stroke
				(width 0.1)
				(type default)
			)
			(layer "F.Fab")
		)
		(fp_line
			(start -0.67945 -0.305054)
			(end -0.12065 -0.305054)
			(stroke
				(width 0.1)
				(type default)
			)
			(layer "F.Fab")
		)
		(fp_line
			(start 0.67945 -0.3048)
			(end 0.67945 0.3048)
			(stroke
				(width 0.1)
				(type default)
			)
			(layer "F.Fab")
		)
		(fp_line
			(start 0.12065 -0.3048)
			(end 0.67945 -0.3048)
			(stroke
				(width 0.1)
				(type default)
			)
			(layer "F.Fab")
		)
		(fp_line
			(start 0.12065 -0.2794)
			(end 0.12065 -0.3048)
			(stroke
				(width 0.1)
				(type default)
			)
			(layer "F.Fab")
		)
		(fp_line
			(start -0.12065 -0.2794)
			(end 0.12065 -0.2794)
			(stroke
				(width 0.1)
				(type default)
			)
			(layer "F.Fab")
		)
		(fp_line
			(start 0.120396 0.2794)
			(end -0.12065 0.2794)
			(stroke
				(width 0.1)
				(type default)
			)
			(layer "F.Fab")
		)
		(fp_line
			(start -0.12065 0.2794)
			(end -0.12065 0.3048)
			(stroke
				(width 0.1)
				(type default)
			)
			(layer "F.Fab")
		)
		(fp_line
			(start 0.67945 0.3048)
			(end 0.120396 0.3048)
			(stroke
				(width 0.1)
				(type default)
			)
			(layer "F.Fab")
		)
		(fp_line
			(start 0.120396 0.3048)
			(end 0.120396 0.2794)
			(stroke
				(width 0.1)
				(type default)
			)
			(layer "F.Fab")
		)
		(fp_line
			(start -0.12065 0.3048)
			(end -0.67945 0.3048)
			(stroke
				(width 0.1)
				(type default)
			)
			(layer "F.Fab")
		)
		(fp_line
			(start -0.67945 0.3048)
			(end -0.67945 -0.305054)
			(stroke
				(width 0.1)
				(type default)
			)
			(layer "F.Fab")
		)
		(pad "1" smd circle
			(at -0.40005 0 90)
			(size 0 0)
			(layers "F.Cu" "F.Mask" "F.Paste")
			(net "SW_P12V_AUX_PVDDCR_CPU0_P1_FLT")
		)
		(pad "2" smd circle
			(at 0.40005 0 90)
			(size 0 0)
			(layers "F.Cu" "F.Mask" "F.Paste")
			(net "GND")
		)
	)
	(footprint ""
		(layer "F.Cu")
		(at 22.036278 -436.964074)
		(property "Reference" "R3522"
			(at 0 0 0)
			(layer "F.SilkS")
			(hide yes)
			(effects
				(font
					(size 1.27 1.27)
				)
			)
		)
		(property "Value" ""
			(at 0 0 0)
			(layer "F.Fab")
			(effects
				(font
					(size 1.27 1.27)
				)
			)
		)
		(duplicate_pad_numbers_are_jumpers no)
		(fp_line
			(start -0.7874 -0.4064)
			(end 0.7874 -0.4064)
			(stroke
				(width 0.1524)
				(type default)
			)
			(layer "F.SilkS")
		)
		(fp_line
			(start -0.7874 0.4064)
			(end -0.7874 -0.4064)
			(stroke
				(width 0.1524)
				(type default)
			)
			(layer "F.SilkS")
		)
		(fp_line
			(start 0.7874 -0.4064)
			(end 0.7874 0.4064)
			(stroke
				(width 0.1524)
				(type default)
			)
			(layer "F.SilkS")
		)
		(fp_line
			(start 0.7874 0.4064)
			(end -0.7874 0.4064)
			(stroke
				(width 0.1524)
				(type default)
			)
			(layer "F.SilkS")
		)
		(fp_line
			(start -0.67945 -0.305054)
			(end -0.12065 -0.305054)
			(stroke
				(width 0.1)
				(type default)
			)
			(layer "F.Fab")
		)
		(fp_line
			(start -0.67945 0.3048)
			(end -0.67945 -0.305054)
			(stroke
				(width 0.1)
				(type default)
			)
			(layer "F.Fab")
		)
		(fp_line
			(start -0.12065 -0.305054)
			(end -0.12065 -0.2794)
			(stroke
				(width 0.1)
				(type default)
			)
			(layer "F.Fab")
		)
		(fp_line
			(start -0.12065 -0.2794)
			(end 0.12065 -0.2794)
			(stroke
				(width 0.1)
				(type default)
			)
			(layer "F.Fab")
		)
		(fp_line
			(start -0.12065 0.2794)
			(end -0.12065 0.3048)
			(stroke
				(width 0.1)
				(type default)
			)
			(layer "F.Fab")
		)
		(fp_line
			(start -0.12065 0.3048)
			(end -0.67945 0.3048)
			(stroke
				(width 0.1)
				(type default)
			)
			(layer "F.Fab")
		)
		(fp_line
			(start 0.120396 0.2794)
			(end -0.12065 0.2794)
			(stroke
				(width 0.1)
				(type default)
			)
			(layer "F.Fab")
		)
		(fp_line
			(start 0.120396 0.3048)
			(end 0.120396 0.2794)
			(stroke
				(width 0.1)
				(type default)
			)
			(layer "F.Fab")
		)
		(fp_line
			(start 0.12065 -0.3048)
			(end 0.67945 -0.3048)
			(stroke
				(width 0.1)
				(type default)
			)
			(layer "F.Fab")
		)
		(fp_line
			(start 0.12065 -0.2794)
			(end 0.12065 -0.3048)
			(stroke
				(width 0.1)
				(type default)
			)
			(layer "F.Fab")
		)
		(fp_line
			(start 0.67945 -0.3048)
			(end 0.67945 0.3048)
			(stroke
				(width 0.1)
				(type default)
			)
			(layer "F.Fab")
		)
		(fp_line
			(start 0.67945 0.3048)
			(end 0.120396 0.3048)
			(stroke
				(width 0.1)
				(type default)
			)
			(layer "F.Fab")
		)
		(pad "1" smd circle
			(at -0.40005 0)
			(size 0 0)
			(layers "F.Cu" "F.Mask" "F.Paste")
			(net "P3V3_AUX")
		)
		(pad "2" smd circle
			(at 0.40005 0)
			(size 0 0)
			(layers "F.Cu" "F.Mask" "F.Paste")
			(net "SMB_2_BMC_GPU_BUF_R_SDA")
		)
	)
	(footprint ""
		(layer "F.Cu")
		(at 163.383976 -129.549652)
		(property "Reference" "Q1"
			(at -2.297176 -2.115566 0)
			(unlocked yes)
			(layer "F.SilkS")
			(effects
				(font
					(size 0.7874 0.5842)
					(thickness 0.1524)
				)
				(justify left)
			)
		)
		(property "Value" ""
			(at 0 0 0)
			(layer "F.Fab")
			(effects
				(font
					(size 1.27 1.27)
				)
			)
		)
		(duplicate_pad_numbers_are_jumpers no)
		(fp_line
			(start -1.332738 -1.100074)
			(end -0.4826 -1.100074)
			(stroke
				(width 0.1524)
				(type default)
			)
			(layer "F.SilkS")
		)
		(fp_line
			(start -1.332738 1.100074)
			(end -1.332738 -1.100074)
			(stroke
				(width 0.1524)
				(type default)
			)
			(layer "F.SilkS")
		)
		(fp_line
			(start -0.4826 -1.100074)
			(end 0 -0.541274)
			(stroke
				(width 0.1524)
				(type default)
			)
			(layer "F.SilkS")
		)
		(fp_line
			(start 0 -0.541274)
			(end 0.4826 -1.100074)
			(stroke
				(width 0.1524)
				(type default)
			)
			(layer "F.SilkS")
		)
		(fp_line
			(start 0.4826 -1.100074)
			(end 1.332738 -1.100074)
			(stroke
				(width 0.1524)
				(type default)
			)
			(layer "F.SilkS")
		)
		(fp_line
			(start 1.332738 -1.100074)
			(end 1.332738 1.100074)
			(stroke
				(width 0.1524)
				(type default)
			)
			(layer "F.SilkS")
		)
		(fp_line
			(start 1.332738 1.100074)
			(end -1.332738 1.100074)
			(stroke
				(width 0.1524)
				(type default)
			)
			(layer "F.SilkS")
		)
		(fp_poly
			(pts
				(xy -2.72542 -0.998982) (xy -2.446782 -1.64338) (xy -1.94183 -1.042416)
			)
			(stroke
				(width 0)
				(type default)
			)
			(fill yes)
			(layer "F.SilkS")
		)
		(fp_line
			(start -0.674878 -1.100074)
			(end 0.674878 -1.100074)
			(stroke
				(width 0.1)
				(type default)
			)
			(layer "F.Fab")
		)
		(fp_line
			(start -0.674878 1.100074)
			(end -0.674878 -1.100074)
			(stroke
				(width 0.1)
				(type default)
			)
			(layer "F.Fab")
		)
		(fp_line
			(start 0.674878 -1.100074)
			(end 0.674878 1.100074)
			(stroke
				(width 0.1)
				(type default)
			)
			(layer "F.Fab")
		)
		(fp_line
			(start 0.674878 1.100074)
			(end -0.674878 1.100074)
			(stroke
				(width 0.1)
				(type default)
			)
			(layer "F.Fab")
		)
		(fp_poly
			(pts
				(xy -2.2352 -0.298958) (xy -2.2352 -1.001014) (xy -1.533144 -0.649986)
			)
			(stroke
				(width 0)
				(type default)
			)
			(fill yes)
			(layer "F.Fab")
		)
		(pad "1" smd rect
			(at -0.94996 -0.649986 90)
			(size 0.4318 0.508)
			(layers "F.Cu" "F.Mask" "F.Paste")
			(net "GND")
		)
		(pad "2" smd rect
			(at -0.94996 0 90)
			(size 0.4318 0.508)
			(layers "F.Cu" "F.Mask" "F.Paste")
			(net "PWRGD_P5V_R1")
		)
		(pad "3" smd rect
			(at -0.94996 0.649986 90)
			(size 0.4318 0.508)
			(layers "F.Cu" "F.Mask" "F.Paste")
			(net "PWRGD_P5V_R2")
		)
		(pad "4" smd rect
			(at 0.94996 0.649986 90)
			(size 0.4318 0.508)
			(layers "F.Cu" "F.Mask" "F.Paste")
			(net "GND")
		)
		(pad "5" smd rect
			(at 0.94996 0 90)
			(size 0.4318 0.508)
			(layers "F.Cu" "F.Mask" "F.Paste")
			(net "PWRGD_P5V_N")
		)
		(pad "6" smd rect
			(at 0.94996 -0.649986 90)
			(size 0.4318 0.508)
			(layers "F.Cu" "F.Mask" "F.Paste")
			(net "PWRGD_P5V_R_N")
		)
	)
	(footprint ""
		(layer "F.Cu")
		(at 298.967144 -385.23926 180)
		(property "Reference" "C930"
			(at 0 0 180)
			(layer "F.SilkS")
			(hide yes)
			(effects
				(font
					(size 1.27 1.27)
				)
			)
		)
		(property "Value" ""
			(at 0 0 180)
			(layer "F.Fab")
			(effects
				(font
					(size 1.27 1.27)
				)
			)
		)
		(duplicate_pad_numbers_are_jumpers no)
		(fp_line
			(start 0.299974 0.150114)
			(end -0.299974 0.150114)
			(stroke
				(width 0.1)
				(type default)
			)
			(layer "F.Fab")
		)
		(fp_line
			(start 0.299974 -0.150114)
			(end 0.299974 0.150114)
			(stroke
				(width 0.1)
				(type default)
			)
			(layer "F.Fab")
		)
		(fp_line
			(start -0.299974 0.150114)
			(end -0.299974 -0.150114)
			(stroke
				(width 0.1)
				(type default)
			)
			(layer "F.Fab")
		)
		(fp_line
			(start -0.299974 -0.150114)
			(end 0.299974 -0.150114)
			(stroke
				(width 0.1)
				(type default)
			)
			(layer "F.Fab")
		)
		(pad "1" smd rect
			(at -0.2667 0 180)
			(size 0.3048 0.381)
			(layers "F.Cu" "F.Mask" "F.Paste")
			(net "P5E_CPU0_P0_TX_C_DN<1>")
		)
		(pad "2" smd rect
			(at 0.2667 0 180)
			(size 0.3048 0.381)
			(layers "F.Cu" "F.Mask" "F.Paste")
			(net "P5E_CPU0_P0_TX_DN<1>")
		)
	)
	(footprint ""
		(layer "F.Cu")
		(at 30.386528 -351.372932 -90)
		(property "Reference" "PC630"
			(at 0 0 270)
			(layer "F.SilkS")
			(hide yes)
			(effects
				(font
					(size 1.27 1.27)
				)
			)
		)
		(property "Value" ""
			(at 0 0 270)
			(layer "F.Fab")
			(effects
				(font
					(size 1.27 1.27)
				)
			)
		)
		(duplicate_pad_numbers_are_jumpers no)
		(fp_line
			(start -0.7874 0.4064)
			(end -0.7874 -0.4064)
			(stroke
				(width 0.1524)
				(type default)
			)
			(layer "F.SilkS")
		)
		(fp_line
			(start 0.7874 0.4064)
			(end -0.7874 0.4064)
			(stroke
				(width 0.1524)
				(type default)
			)
			(layer "F.SilkS")
		)
		(fp_line
			(start -0.7874 -0.4064)
			(end 0.7874 -0.4064)
			(stroke
				(width 0.1524)
				(type default)
			)
			(layer "F.SilkS")
		)
		(fp_line
			(start 0.7874 -0.4064)
			(end 0.7874 0.4064)
			(stroke
				(width 0.1524)
				(type default)
			)
			(layer "F.SilkS")
		)
		(fp_line
			(start -0.67945 0.3048)
			(end -0.67945 -0.305054)
			(stroke
				(width 0.1)
				(type default)
			)
			(layer "F.Fab")
		)
		(fp_line
			(start -0.12065 0.3048)
			(end -0.67945 0.3048)
			(stroke
				(width 0.1)
				(type default)
			)
			(layer "F.Fab")
		)
		(fp_line
			(start 0.120396 0.3048)
			(end 0.120396 0.2794)
			(stroke
				(width 0.1)
				(type default)
			)
			(layer "F.Fab")
		)
		(fp_line
			(start 0.67945 0.3048)
			(end 0.120396 0.3048)
			(stroke
				(width 0.1)
				(type default)
			)
			(layer "F.Fab")
		)
		(fp_line
			(start -0.12065 0.2794)
			(end -0.12065 0.3048)
			(stroke
				(width 0.1)
				(type default)
			)
			(layer "F.Fab")
		)
		(fp_line
			(start 0.120396 0.2794)
			(end -0.12065 0.2794)
			(stroke
				(width 0.1)
				(type default)
			)
			(layer "F.Fab")
		)
		(fp_line
			(start -0.12065 -0.2794)
			(end 0.12065 -0.2794)
			(stroke
				(width 0.1)
				(type default)
			)
			(layer "F.Fab")
		)
		(fp_line
			(start 0.12065 -0.2794)
			(end 0.12065 -0.3048)
			(stroke
				(width 0.1)
				(type default)
			)
			(layer "F.Fab")
		)
		(fp_line
			(start 0.12065 -0.3048)
			(end 0.67945 -0.3048)
			(stroke
				(width 0.1)
				(type default)
			)
			(layer "F.Fab")
		)
		(fp_line
			(start 0.67945 -0.3048)
			(end 0.67945 0.3048)
			(stroke
				(width 0.1)
				(type default)
			)
			(layer "F.Fab")
		)
		(fp_line
			(start -0.67945 -0.305054)
			(end -0.12065 -0.305054)
			(stroke
				(width 0.1)
				(type default)
			)
			(layer "F.Fab")
		)
		(fp_line
			(start -0.12065 -0.305054)
			(end -0.12065 -0.2794)
			(stroke
				(width 0.1)
				(type default)
			)
			(layer "F.Fab")
		)
		(pad "1" smd circle
			(at -0.40005 0 270)
			(size 0 0)
			(layers "F.Cu" "F.Mask" "F.Paste")
			(net "SW_PVDDIO_P1_BOOT4_R")
		)
		(pad "2" smd circle
			(at 0.40005 0 270)
			(size 0 0)
			(layers "F.Cu" "F.Mask" "F.Paste")
			(net "SW_PVDDIO_P1_BOOTR4")
		)
	)
	(footprint ""
		(layer "F.Cu")
		(at 28.600654 -346.721176)
		(property "Reference" "PU53"
			(at -3.073654 -7.709154 0)
			(unlocked yes)
			(layer "F.SilkS")
			(effects
				(font
					(size 0.7874 0.5842)
					(thickness 0.1524)
				)
				(justify left)
			)
		)
		(property "Value" ""
			(at 0 0 0)
			(layer "F.Fab")
			(effects
				(font
					(size 1.27 1.27)
				)
			)
		)
		(duplicate_pad_numbers_are_jumpers no)
		(fp_line
			(start -2.500122 -2.999994)
			(end -2.24409 -2.999994)
			(stroke
				(width 0.1524)
				(type default)
			)
			(layer "F.SilkS")
		)
		(fp_line
			(start -2.500122 -2.529078)
			(end -2.500122 -2.999994)
			(stroke
				(width 0.1524)
				(type default)
			)
			(layer "F.SilkS")
		)
		(fp_line
			(start -2.500122 0.6604)
			(end -2.500122 0.229108)
			(stroke
				(width 0.1524)
				(type default)
			)
			(layer "F.SilkS")
		)
		(fp_line
			(start -2.500122 2.999994)
			(end -2.500122 2.339594)
			(stroke
				(width 0.1524)
				(type default)
			)
			(layer "F.SilkS")
		)
		(fp_line
			(start -2.2987 2.999994)
			(end -2.500122 2.999994)
			(stroke
				(width 0.1524)
				(type default)
			)
			(layer "F.SilkS")
		)
		(fp_line
			(start 2.31394 -2.999994)
			(end 2.500122 -2.999994)
			(stroke
				(width 0.1524)
				(type default)
			)
			(layer "F.SilkS")
		)
		(fp_line
			(start 2.500122 -2.999994)
			(end 2.500122 -2.44348)
			(stroke
				(width 0.1524)
				(type default)
			)
			(layer "F.SilkS")
		)
		(fp_line
			(start 2.500122 2.339594)
			(end 2.500122 2.999994)
			(stroke
				(width 0.1524)
				(type default)
			)
			(layer "F.SilkS")
		)
		(fp_line
			(start 2.500122 2.999994)
			(end 2.2987 2.999994)
			(stroke
				(width 0.1524)
				(type default)
			)
			(layer "F.SilkS")
		)
		(fp_poly
			(pts
				(xy -2.758948 -2.432558) (xy -3.432556 -2.657094) (xy -2.983484 -3.105912)
			)
			(stroke
				(width 0)
				(type default)
			)
			(fill yes)
			(layer "F.SilkS")
		)
		(fp_line
			(start -2.500122 -2.999994)
			(end 2.500122 -2.999994)
			(stroke
				(width 0.1)
				(type default)
			)
			(layer "F.Fab")
		)
		(fp_line
			(start -2.500122 2.999994)
			(end -2.500122 -2.999994)
			(stroke
				(width 0.1)
				(type default)
			)
			(layer "F.Fab")
		)
		(fp_line
			(start 2.500122 -2.999994)
			(end 2.500122 2.999994)
			(stroke
				(width 0.1)
				(type default)
			)
			(layer "F.Fab")
		)
		(fp_line
			(start 2.500122 2.999994)
			(end -2.500122 2.999994)
			(stroke
				(width 0.1)
				(type default)
			)
			(layer "F.Fab")
		)
		(fp_poly
			(pts
				(xy -4.218432 -2.783078) (xy -4.218432 -1.767078) (xy -3.202432 -2.275078)
			)
			(stroke
				(width 0)
				(type default)
			)
			(fill yes)
			(layer "F.Fab")
		)
		(pad "1" smd rect
			(at -2.400046 -2.275078 90)
			(size 0.2286 0.6096)
			(layers "F.Cu" "F.Mask" "F.Paste")
			(net "PVDDIO_P1_VOS4")
		)
		(pad "2" smd rect
			(at -2.400046 -1.82499 90)
			(size 0.2286 0.6096)
			(layers "F.Cu" "F.Mask" "F.Paste")
			(net "GND")
		)
		(pad "3" smd rect
			(at -2.400046 -1.374902 90)
			(size 0.2286 0.6096)
			(layers "F.Cu" "F.Mask" "F.Paste")
			(net "PVDDIO_P1_VCC4")
		)
		(pad "4" smd rect
			(at -2.400046 -0.925068 90)
			(size 0.2286 0.6096)
			(layers "F.Cu" "F.Mask" "F.Paste")
			(net "PVDDCR_CPU1_P1_PVCC")
		)
		(pad "5" smd rect
			(at -2.400046 -0.47498 90)
			(size 0.2286 0.6096)
			(layers "F.Cu" "F.Mask" "F.Paste")
			(net "GND")
		)
		(pad "6" smd rect
			(at -2.400046 -0.024892 90)
			(size 0.2286 0.6096)
			(layers "F.Cu" "F.Mask" "F.Paste")
			(net "NC_PVDDIO_P1_GL1_4")
		)
		(pad "7_9-20_24" smd circle
			(at 0 1.150112 90)
			(size 0 0)
			(layers "F.Cu" "F.Mask" "F.Paste")
			(net "GND")
		)
		(pad "10_19" smd rect
			(at 0 2.899918 90)
			(size 0.6096 4.318)
			(layers "F.Cu" "F.Mask" "F.Paste")
			(net "SW_PVDDIO_P1_SW4")
		)
		(pad "25_29" smd rect
			(at 1.549908 -1.279906 270)
			(size 2.0574 2.3114)
			(layers "F.Cu" "F.Mask" "F.Paste")
			(net "SW_P12V_AUX_PVDDIO_P1_FLT")
		)
		(pad "30" smd rect
			(at 2.05994 -2.899918)
			(size 0.2286 0.6096)
			(layers "F.Cu" "F.Mask" "F.Paste")
			(net "SW_P12V_AUX_PVDDIO_P1_FLT")
		)
		(pad "31" smd rect
			(at 1.610106 -2.899918)
			(size 0.2286 0.6096)
			(layers "F.Cu" "F.Mask" "F.Paste")
			(net "NC_PVDDIO_P1_DNC4")
		)
		(pad "32" smd rect
			(at 1.160018 -2.899918)
			(size 0.2286 0.6096)
			(layers "F.Cu" "F.Mask" "F.Paste")
			(net "SW_PVDDIO_P1_BOOTR4")
		)
		(pad "33" smd rect
			(at 0.70993 -2.899918)
			(size 0.2286 0.6096)
			(layers "F.Cu" "F.Mask" "F.Paste")
			(net "SW_PVDDIO_P1_BOOT4")
		)
		(pad "34" smd rect
			(at 0.260096 -2.899918)
			(size 0.2286 0.6096)
			(layers "F.Cu" "F.Mask" "F.Paste")
			(net "PVDDIO_P1_PWM4")
		)
		(pad "35" smd rect
			(at -0.189992 -2.899918)
			(size 0.2286 0.6096)
			(layers "F.Cu" "F.Mask" "F.Paste")
			(net "PVDDIO_P1_VCC4")
		)
		(pad "36" smd rect
			(at -0.64008 -2.899918)
			(size 0.2286 0.6096)
			(layers "F.Cu" "F.Mask" "F.Paste")
			(net "PVDDIO_P1_TEMP1")
		)
		(pad "37" smd rect
			(at -1.089914 -2.899918)
			(size 0.2286 0.6096)
			(layers "F.Cu" "F.Mask" "F.Paste")
			(net "PVDDIO_P1_LSET4")
		)
		(pad "38" smd rect
			(at -1.540002 -2.899918)
			(size 0.2286 0.6096)
			(layers "F.Cu" "F.Mask" "F.Paste")
			(net "PVDDIO_P1_IMON4")
		)
		(pad "39" smd rect
			(at -1.99009 -2.899918)
			(size 0.2286 0.6096)
			(layers "F.Cu" "F.Mask" "F.Paste")
			(net "PVDDCR_CPU1_P1_VCCS")
		)
		(pad "40" smd rect
			(at -0.87503 -1.27508)
			(size 1.7526 1.9558)
			(layers "F.Cu" "F.Mask" "F.Paste")
			(net "GND")
		)
		(pad "41" smd rect
			(at -1.525016 0.249936 270)
			(size 0.3048 0.4572)
			(layers "F.Cu" "F.Mask" "F.Paste")
			(net "NC_PVDDIO_P1_GL2_4")
		)
		(zone
			(layer "F.Cu")
			(hatch none 0.5)
			(connect_pads
				(clearance 0)
			)
			(min_thickness 0.25)
			(keepout
				(tracks not_allowed)
				(vias allowed)
				(pads allowed)
				(copperpour not_allowed)
				(footprints allowed)
			)
			(placement
				(enabled no)
				(sheetname "")
			)
			(fill
				(thermal_gap 0.5)
				(thermal_bridge_width 0.5)
				(island_removal_mode 0)
			)
			(polygon
				(pts
					(xy 26.100532 -344.470482) (xy 31.100776 -344.470482) (xy 31.100776 -344.176858) (xy 26.100532 -344.176858)
				)
			)
		)
		(zone
			(layer "F.Cu")
			(hatch none 0.5)
			(connect_pads
				(clearance 0)
			)
			(min_thickness 0.25)
			(keepout
				(tracks not_allowed)
				(vias allowed)
				(pads allowed)
				(copperpour not_allowed)
				(footprints allowed)
			)
			(placement
				(enabled no)
				(sheetname "")
			)
			(fill
				(thermal_gap 0.5)
				(thermal_bridge_width 0.5)
				(island_removal_mode 0)
			)
			(polygon
				(pts
					(xy 26.556208 -348.381066) (xy 26.655014 -348.381066) (xy 26.798524 -348.237556) (xy 26.798524 -347.504512)
					(xy 26.655268 -347.361256) (xy 26.556208 -347.361256)
				)
			)
		)
	)
	(footprint ""
		(layer "F.Cu")
		(at 166.074344 -344.153998 -90)
		(property "Reference" "PR408"
			(at 0 0 270)
			(layer "F.SilkS")
			(hide yes)
			(effects
				(font
					(size 1.27 1.27)
				)
			)
		)
		(property "Value" ""
			(at 0 0 270)
			(layer "F.Fab")
			(effects
				(font
					(size 1.27 1.27)
				)
			)
		)
		(duplicate_pad_numbers_are_jumpers no)
		(fp_line
			(start -0.7874 0.4064)
			(end -0.7874 -0.4064)
			(stroke
				(width 0.1524)
				(type default)
			)
			(layer "F.SilkS")
		)
		(fp_line
			(start 0.7874 0.4064)
			(end -0.7874 0.4064)
			(stroke
				(width 0.1524)
				(type default)
			)
			(layer "F.SilkS")
		)
		(fp_line
			(start -0.7874 -0.4064)
			(end 0.7874 -0.4064)
			(stroke
				(width 0.1524)
				(type default)
			)
			(layer "F.SilkS")
		)
		(fp_line
			(start 0.7874 -0.4064)
			(end 0.7874 0.4064)
			(stroke
				(width 0.1524)
				(type default)
			)
			(layer "F.SilkS")
		)
		(fp_line
			(start -0.67945 0.3048)
			(end -0.67945 -0.305054)
			(stroke
				(width 0.1)
				(type default)
			)
			(layer "F.Fab")
		)
		(fp_line
			(start -0.12065 0.3048)
			(end -0.67945 0.3048)
			(stroke
				(width 0.1)
				(type default)
			)
			(layer "F.Fab")
		)
		(fp_line
			(start 0.120396 0.3048)
			(end 0.120396 0.2794)
			(stroke
				(width 0.1)
				(type default)
			)
			(layer "F.Fab")
		)
		(fp_line
			(start 0.67945 0.3048)
			(end 0.120396 0.3048)
			(stroke
				(width 0.1)
				(type default)
			)
			(layer "F.Fab")
		)
		(fp_line
			(start -0.12065 0.2794)
			(end -0.12065 0.3048)
			(stroke
				(width 0.1)
				(type default)
			)
			(layer "F.Fab")
		)
		(fp_line
			(start 0.120396 0.2794)
			(end -0.12065 0.2794)
			(stroke
				(width 0.1)
				(type default)
			)
			(layer "F.Fab")
		)
		(fp_line
			(start -0.12065 -0.2794)
			(end 0.12065 -0.2794)
			(stroke
				(width 0.1)
				(type default)
			)
			(layer "F.Fab")
		)
		(fp_line
			(start 0.12065 -0.2794)
			(end 0.12065 -0.3048)
			(stroke
				(width 0.1)
				(type default)
			)
			(layer "F.Fab")
		)
		(fp_line
			(start 0.12065 -0.3048)
			(end 0.67945 -0.3048)
			(stroke
				(width 0.1)
				(type default)
			)
			(layer "F.Fab")
		)
		(fp_line
			(start 0.67945 -0.3048)
			(end 0.67945 0.3048)
			(stroke
				(width 0.1)
				(type default)
			)
			(layer "F.Fab")
		)
		(fp_line
			(start -0.67945 -0.305054)
			(end -0.12065 -0.305054)
			(stroke
				(width 0.1)
				(type default)
			)
			(layer "F.Fab")
		)
		(fp_line
			(start -0.12065 -0.305054)
			(end -0.12065 -0.2794)
			(stroke
				(width 0.1)
				(type default)
			)
			(layer "F.Fab")
		)
		(pad "1" smd circle
			(at -0.40005 0 270)
			(size 0 0)
			(layers "F.Cu" "F.Mask" "F.Paste")
			(net "NC_PVDD11_S3_P1_IMON7")
		)
		(pad "2" smd circle
			(at 0.40005 0 270)
			(size 0 0)
			(layers "F.Cu" "F.Mask" "F.Paste")
			(net "GND")
		)
	)
	(footprint ""
		(layer "F.Cu")
		(at 72.463914 -144.881092)
		(property "Reference" "PR400"
			(at 0 0 0)
			(layer "F.SilkS")
			(hide yes)
			(effects
				(font
					(size 1.27 1.27)
				)
			)
		)
		(property "Value" ""
			(at 0 0 0)
			(layer "F.Fab")
			(effects
				(font
					(size 1.27 1.27)
				)
			)
		)
		(duplicate_pad_numbers_are_jumpers no)
		(fp_line
			(start -0.7874 -0.4064)
			(end 0.7874 -0.4064)
			(stroke
				(width 0.1524)
				(type default)
			)
			(layer "F.SilkS")
		)
		(fp_line
			(start -0.7874 0.4064)
			(end -0.7874 -0.4064)
			(stroke
				(width 0.1524)
				(type default)
			)
			(layer "F.SilkS")
		)
		(fp_line
			(start 0.7874 -0.4064)
			(end 0.7874 0.4064)
			(stroke
				(width 0.1524)
				(type default)
			)
			(layer "F.SilkS")
		)
		(fp_line
			(start 0.7874 0.4064)
			(end -0.7874 0.4064)
			(stroke
				(width 0.1524)
				(type default)
			)
			(layer "F.SilkS")
		)
		(fp_line
			(start -0.67945 -0.305054)
			(end -0.12065 -0.305054)
			(stroke
				(width 0.1)
				(type default)
			)
			(layer "F.Fab")
		)
		(fp_line
			(start -0.67945 0.3048)
			(end -0.67945 -0.305054)
			(stroke
				(width 0.1)
				(type default)
			)
			(layer "F.Fab")
		)
		(fp_line
			(start -0.12065 -0.305054)
			(end -0.12065 -0.2794)
			(stroke
				(width 0.1)
				(type default)
			)
			(layer "F.Fab")
		)
		(fp_line
			(start -0.12065 -0.2794)
			(end 0.12065 -0.2794)
			(stroke
				(width 0.1)
				(type default)
			)
			(layer "F.Fab")
		)
		(fp_line
			(start -0.12065 0.2794)
			(end -0.12065 0.3048)
			(stroke
				(width 0.1)
				(type default)
			)
			(layer "F.Fab")
		)
		(fp_line
			(start -0.12065 0.3048)
			(end -0.67945 0.3048)
			(stroke
				(width 0.1)
				(type default)
			)
			(layer "F.Fab")
		)
		(fp_line
			(start 0.120396 0.2794)
			(end -0.12065 0.2794)
			(stroke
				(width 0.1)
				(type default)
			)
			(layer "F.Fab")
		)
		(fp_line
			(start 0.120396 0.3048)
			(end 0.120396 0.2794)
			(stroke
				(width 0.1)
				(type default)
			)
			(layer "F.Fab")
		)
		(fp_line
			(start 0.12065 -0.3048)
			(end 0.67945 -0.3048)
			(stroke
				(width 0.1)
				(type default)
			)
			(layer "F.Fab")
		)
		(fp_line
			(start 0.12065 -0.2794)
			(end 0.12065 -0.3048)
			(stroke
				(width 0.1)
				(type default)
			)
			(layer "F.Fab")
		)
		(fp_line
			(start 0.67945 -0.3048)
			(end 0.67945 0.3048)
			(stroke
				(width 0.1)
				(type default)
			)
			(layer "F.Fab")
		)
		(fp_line
			(start 0.67945 0.3048)
			(end 0.120396 0.3048)
			(stroke
				(width 0.1)
				(type default)
			)
			(layer "F.Fab")
		)
		(pad "1" smd circle
			(at -0.40005 0)
			(size 0 0)
			(layers "F.Cu" "F.Mask" "F.Paste")
			(net "PVDD18_S5_P1_FB_RC")
		)
		(pad "2" smd circle
			(at 0.40005 0)
			(size 0 0)
			(layers "F.Cu" "F.Mask" "F.Paste")
			(net "VSENSE_PVDD18_S5_P1_DP")
		)
	)
	(footprint ""
		(layer "F.Cu")
		(at 50.072544 -41.99255 180)
		(property "Reference" "R1164"
			(at 0 0 180)
			(layer "F.SilkS")
			(hide yes)
			(effects
				(font
					(size 1.27 1.27)
				)
			)
		)
		(property "Value" ""
			(at 0 0 180)
			(layer "F.Fab")
			(effects
				(font
					(size 1.27 1.27)
				)
			)
		)
		(duplicate_pad_numbers_are_jumpers no)
		(fp_line
			(start 0.7874 0.4064)
			(end -0.7874 0.4064)
			(stroke
				(width 0.1524)
				(type default)
			)
			(layer "F.SilkS")
		)
		(fp_line
			(start 0.7874 -0.4064)
			(end 0.7874 0.4064)
			(stroke
				(width 0.1524)
				(type default)
			)
			(layer "F.SilkS")
		)
		(fp_line
			(start -0.7874 0.4064)
			(end -0.7874 -0.4064)
			(stroke
				(width 0.1524)
				(type default)
			)
			(layer "F.SilkS")
		)
		(fp_line
			(start -0.7874 -0.4064)
			(end 0.7874 -0.4064)
			(stroke
				(width 0.1524)
				(type default)
			)
			(layer "F.SilkS")
		)
		(fp_line
			(start 0.67945 0.3048)
			(end 0.120396 0.3048)
			(stroke
				(width 0.1)
				(type default)
			)
			(layer "F.Fab")
		)
		(fp_line
			(start 0.67945 -0.3048)
			(end 0.67945 0.3048)
			(stroke
				(width 0.1)
				(type default)
			)
			(layer "F.Fab")
		)
		(fp_line
			(start 0.12065 -0.2794)
			(end 0.12065 -0.3048)
			(stroke
				(width 0.1)
				(type default)
			)
			(layer "F.Fab")
		)
		(fp_line
			(start 0.12065 -0.3048)
			(end 0.67945 -0.3048)
			(stroke
				(width 0.1)
				(type default)
			)
			(layer "F.Fab")
		)
		(fp_line
			(start 0.120396 0.3048)
			(end 0.120396 0.2794)
			(stroke
				(width 0.1)
				(type default)
			)
			(layer "F.Fab")
		)
		(fp_line
			(start 0.120396 0.2794)
			(end -0.12065 0.2794)
			(stroke
				(width 0.1)
				(type default)
			)
			(layer "F.Fab")
		)
		(fp_line
			(start -0.12065 0.3048)
			(end -0.67945 0.3048)
			(stroke
				(width 0.1)
				(type default)
			)
			(layer "F.Fab")
		)
		(fp_line
			(start -0.12065 0.2794)
			(end -0.12065 0.3048)
			(stroke
				(width 0.1)
				(type default)
			)
			(layer "F.Fab")
		)
		(fp_line
			(start -0.12065 -0.2794)
			(end 0.12065 -0.2794)
			(stroke
				(width 0.1)
				(type default)
			)
			(layer "F.Fab")
		)
		(fp_line
			(start -0.12065 -0.305054)
			(end -0.12065 -0.2794)
			(stroke
				(width 0.1)
				(type default)
			)
			(layer "F.Fab")
		)
		(fp_line
			(start -0.67945 0.3048)
			(end -0.67945 -0.305054)
			(stroke
				(width 0.1)
				(type default)
			)
			(layer "F.Fab")
		)
		(fp_line
			(start -0.67945 -0.305054)
			(end -0.12065 -0.305054)
			(stroke
				(width 0.1)
				(type default)
			)
			(layer "F.Fab")
		)
		(pad "1" smd circle
			(at -0.40005 0 180)
			(size 0 0)
			(layers "F.Cu" "F.Mask" "F.Paste")
			(net "P12V_OCP_V3_2_EN_R")
		)
		(pad "2" smd circle
			(at 0.40005 0 180)
			(size 0 0)
			(layers "F.Cu" "F.Mask" "F.Paste")
			(net "P12V_OCP_V3_2_EN_R3")
		)
	)
	(footprint ""
		(layer "F.Cu")
		(at 319.940178 -43.700954)
		(property "Reference" "C2049"
			(at 0 0 0)
			(layer "F.SilkS")
			(hide yes)
			(effects
				(font
					(size 1.27 1.27)
				)
			)
		)
		(property "Value" ""
			(at 0 0 0)
			(layer "F.Fab")
			(effects
				(font
					(size 1.27 1.27)
				)
			)
		)
		(duplicate_pad_numbers_are_jumpers no)
		(fp_line
			(start -0.7874 -0.4064)
			(end 0.7874 -0.4064)
			(stroke
				(width 0.1524)
				(type default)
			)
			(layer "F.SilkS")
		)
		(fp_line
			(start -0.7874 0.4064)
			(end -0.7874 -0.4064)
			(stroke
				(width 0.1524)
				(type default)
			)
			(layer "F.SilkS")
		)
		(fp_line
			(start 0.7874 -0.4064)
			(end 0.7874 0.4064)
			(stroke
				(width 0.1524)
				(type default)
			)
			(layer "F.SilkS")
		)
		(fp_line
			(start 0.7874 0.4064)
			(end -0.7874 0.4064)
			(stroke
				(width 0.1524)
				(type default)
			)
			(layer "F.SilkS")
		)
		(fp_line
			(start -0.67945 -0.305054)
			(end -0.12065 -0.305054)
			(stroke
				(width 0.1)
				(type default)
			)
			(layer "F.Fab")
		)
		(fp_line
			(start -0.67945 0.3048)
			(end -0.67945 -0.305054)
			(stroke
				(width 0.1)
				(type default)
			)
			(layer "F.Fab")
		)
		(fp_line
			(start -0.12065 -0.305054)
			(end -0.12065 -0.2794)
			(stroke
				(width 0.1)
				(type default)
			)
			(layer "F.Fab")
		)
		(fp_line
			(start -0.12065 -0.2794)
			(end 0.12065 -0.2794)
			(stroke
				(width 0.1)
				(type default)
			)
			(layer "F.Fab")
		)
		(fp_line
			(start -0.12065 0.2794)
			(end -0.12065 0.3048)
			(stroke
				(width 0.1)
				(type default)
			)
			(layer "F.Fab")
		)
		(fp_line
			(start -0.12065 0.3048)
			(end -0.67945 0.3048)
			(stroke
				(width 0.1)
				(type default)
			)
			(layer "F.Fab")
		)
		(fp_line
			(start 0.120396 0.2794)
			(end -0.12065 0.2794)
			(stroke
				(width 0.1)
				(type default)
			)
			(layer "F.Fab")
		)
		(fp_line
			(start 0.120396 0.3048)
			(end 0.120396 0.2794)
			(stroke
				(width 0.1)
				(type default)
			)
			(layer "F.Fab")
		)
		(fp_line
			(start 0.12065 -0.3048)
			(end 0.67945 -0.3048)
			(stroke
				(width 0.1)
				(type default)
			)
			(layer "F.Fab")
		)
		(fp_line
			(start 0.12065 -0.2794)
			(end 0.12065 -0.3048)
			(stroke
				(width 0.1)
				(type default)
			)
			(layer "F.Fab")
		)
		(fp_line
			(start 0.67945 -0.3048)
			(end 0.67945 0.3048)
			(stroke
				(width 0.1)
				(type default)
			)
			(layer "F.Fab")
		)
		(fp_line
			(start 0.67945 0.3048)
			(end 0.120396 0.3048)
			(stroke
				(width 0.1)
				(type default)
			)
			(layer "F.Fab")
		)
		(pad "1" smd circle
			(at -0.40005 0)
			(size 0 0)
			(layers "F.Cu" "F.Mask" "F.Paste")
			(net "P5V_ADC_TIC")
		)
		(pad "2" smd circle
			(at 0.40005 0)
			(size 0 0)
			(layers "F.Cu" "F.Mask" "F.Paste")
			(net "GND")
		)
	)
	(footprint ""
		(layer "F.Cu")
		(at 419.58514 -58.797698 90)
		(property "Reference" "C1874"
			(at 0 0 90)
			(layer "F.SilkS")
			(hide yes)
			(effects
				(font
					(size 1.27 1.27)
				)
			)
		)
		(property "Value" ""
			(at 0 0 90)
			(layer "F.Fab")
			(effects
				(font
					(size 1.27 1.27)
				)
			)
		)
		(duplicate_pad_numbers_are_jumpers no)
		(fp_line
			(start 0.7874 -0.4064)
			(end 0.7874 0.4064)
			(stroke
				(width 0.1524)
				(type default)
			)
			(layer "F.SilkS")
		)
		(fp_line
			(start -0.7874 -0.4064)
			(end 0.7874 -0.4064)
			(stroke
				(width 0.1524)
				(type default)
			)
			(layer "F.SilkS")
		)
		(fp_line
			(start 0.7874 0.4064)
			(end -0.7874 0.4064)
			(stroke
				(width 0.1524)
				(type default)
			)
			(layer "F.SilkS")
		)
		(fp_line
			(start -0.7874 0.4064)
			(end -0.7874 -0.4064)
			(stroke
				(width 0.1524)
				(type default)
			)
			(layer "F.SilkS")
		)
		(fp_line
			(start -0.12065 -0.305054)
			(end -0.12065 -0.2794)
			(stroke
				(width 0.1)
				(type default)
			)
			(layer "F.Fab")
		)
		(fp_line
			(start -0.67945 -0.305054)
			(end -0.12065 -0.305054)
			(stroke
				(width 0.1)
				(type default)
			)
			(layer "F.Fab")
		)
		(fp_line
			(start 0.67945 -0.3048)
			(end 0.67945 0.3048)
			(stroke
				(width 0.1)
				(type default)
			)
			(layer "F.Fab")
		)
		(fp_line
			(start 0.12065 -0.3048)
			(end 0.67945 -0.3048)
			(stroke
				(width 0.1)
				(type default)
			)
			(layer "F.Fab")
		)
		(fp_line
			(start 0.12065 -0.2794)
			(end 0.12065 -0.3048)
			(stroke
				(width 0.1)
				(type default)
			)
			(layer "F.Fab")
		)
		(fp_line
			(start -0.12065 -0.2794)
			(end 0.12065 -0.2794)
			(stroke
				(width 0.1)
				(type default)
			)
			(layer "F.Fab")
		)
		(fp_line
			(start 0.120396 0.2794)
			(end -0.12065 0.2794)
			(stroke
				(width 0.1)
				(type default)
			)
			(layer "F.Fab")
		)
		(fp_line
			(start -0.12065 0.2794)
			(end -0.12065 0.3048)
			(stroke
				(width 0.1)
				(type default)
			)
			(layer "F.Fab")
		)
		(fp_line
			(start 0.67945 0.3048)
			(end 0.120396 0.3048)
			(stroke
				(width 0.1)
				(type default)
			)
			(layer "F.Fab")
		)
		(fp_line
			(start 0.120396 0.3048)
			(end 0.120396 0.2794)
			(stroke
				(width 0.1)
				(type default)
			)
			(layer "F.Fab")
		)
		(fp_line
			(start -0.12065 0.3048)
			(end -0.67945 0.3048)
			(stroke
				(width 0.1)
				(type default)
			)
			(layer "F.Fab")
		)
		(fp_line
			(start -0.67945 0.3048)
			(end -0.67945 -0.305054)
			(stroke
				(width 0.1)
				(type default)
			)
			(layer "F.Fab")
		)
		(pad "1" smd circle
			(at -0.40005 0 90)
			(size 0 0)
			(layers "F.Cu" "F.Mask" "F.Paste")
			(net "P3V3_AUX")
		)
		(pad "2" smd circle
			(at 0.40005 0 90)
			(size 0 0)
			(layers "F.Cu" "F.Mask" "F.Paste")
			(net "GND")
		)
	)
	(footprint ""
		(layer "F.Cu")
		(at 205.365604 -342.075262 -90)
		(property "Reference" "PR455"
			(at 0 0 270)
			(layer "F.SilkS")
			(hide yes)
			(effects
				(font
					(size 1.27 1.27)
				)
			)
		)
		(property "Value" ""
			(at 0 0 270)
			(layer "F.Fab")
			(effects
				(font
					(size 1.27 1.27)
				)
			)
		)
		(duplicate_pad_numbers_are_jumpers no)
		(fp_line
			(start -0.7874 0.4064)
			(end -0.7874 -0.4064)
			(stroke
				(width 0.1524)
				(type default)
			)
			(layer "F.SilkS")
		)
		(fp_line
			(start 0.7874 0.4064)
			(end -0.7874 0.4064)
			(stroke
				(width 0.1524)
				(type default)
			)
			(layer "F.SilkS")
		)
		(fp_line
			(start -0.7874 -0.4064)
			(end 0.7874 -0.4064)
			(stroke
				(width 0.1524)
				(type default)
			)
			(layer "F.SilkS")
		)
		(fp_line
			(start 0.7874 -0.4064)
			(end 0.7874 0.4064)
			(stroke
				(width 0.1524)
				(type default)
			)
			(layer "F.SilkS")
		)
		(fp_line
			(start -0.67945 0.3048)
			(end -0.67945 -0.305054)
			(stroke
				(width 0.1)
				(type default)
			)
			(layer "F.Fab")
		)
		(fp_line
			(start -0.12065 0.3048)
			(end -0.67945 0.3048)
			(stroke
				(width 0.1)
				(type default)
			)
			(layer "F.Fab")
		)
		(fp_line
			(start 0.120396 0.3048)
			(end 0.120396 0.2794)
			(stroke
				(width 0.1)
				(type default)
			)
			(layer "F.Fab")
		)
		(fp_line
			(start 0.67945 0.3048)
			(end 0.120396 0.3048)
			(stroke
				(width 0.1)
				(type default)
			)
			(layer "F.Fab")
		)
		(fp_line
			(start -0.12065 0.2794)
			(end -0.12065 0.3048)
			(stroke
				(width 0.1)
				(type default)
			)
			(layer "F.Fab")
		)
		(fp_line
			(start 0.120396 0.2794)
			(end -0.12065 0.2794)
			(stroke
				(width 0.1)
				(type default)
			)
			(layer "F.Fab")
		)
		(fp_line
			(start -0.12065 -0.2794)
			(end 0.12065 -0.2794)
			(stroke
				(width 0.1)
				(type default)
			)
			(layer "F.Fab")
		)
		(fp_line
			(start 0.12065 -0.2794)
			(end 0.12065 -0.3048)
			(stroke
				(width 0.1)
				(type default)
			)
			(layer "F.Fab")
		)
		(fp_line
			(start 0.12065 -0.3048)
			(end 0.67945 -0.3048)
			(stroke
				(width 0.1)
				(type default)
			)
			(layer "F.Fab")
		)
		(fp_line
			(start 0.67945 -0.3048)
			(end 0.67945 0.3048)
			(stroke
				(width 0.1)
				(type default)
			)
			(layer "F.Fab")
		)
		(fp_line
			(start -0.67945 -0.305054)
			(end -0.12065 -0.305054)
			(stroke
				(width 0.1)
				(type default)
			)
			(layer "F.Fab")
		)
		(fp_line
			(start -0.12065 -0.305054)
			(end -0.12065 -0.2794)
			(stroke
				(width 0.1)
				(type default)
			)
			(layer "F.Fab")
		)
		(pad "1" smd circle
			(at -0.40005 0 270)
			(size 0 0)
			(layers "F.Cu" "F.Mask" "F.Paste")
			(net "PVDD_33_S5_FB")
		)
		(pad "2" smd circle
			(at 0.40005 0 270)
			(size 0 0)
			(layers "F.Cu" "F.Mask" "F.Paste")
			(net "PVDD_33_S5")
		)
	)
	(footprint ""
		(layer "F.Cu")
		(at 164.283136 -423.816526 -90)
		(property "Reference" "U20"
			(at -0.383286 -3.052826 90)
			(unlocked yes)
			(layer "F.SilkS")
			(effects
				(font
					(size 0.7874 0.5842)
					(thickness 0.1524)
				)
				(justify left)
			)
		)
		(property "Value" ""
			(at 0 0 270)
			(layer "F.Fab")
			(effects
				(font
					(size 1.27 1.27)
				)
			)
		)
		(duplicate_pad_numbers_are_jumpers no)
		(fp_line
			(start -1.8288 2.500122)
			(end 1.8288 2.500122)
			(stroke
				(width 0.1524)
				(type default)
			)
			(layer "F.SilkS")
		)
		(fp_line
			(start 1.8288 2.500122)
			(end 1.8288 -2.500122)
			(stroke
				(width 0.1524)
				(type default)
			)
			(layer "F.SilkS")
		)
		(fp_line
			(start 0 -1.4224)
			(end -1.077722 -2.500122)
			(stroke
				(width 0.1524)
				(type default)
			)
			(layer "F.SilkS")
		)
		(fp_line
			(start -1.8288 -2.500122)
			(end -1.8288 2.500122)
			(stroke
				(width 0.1524)
				(type default)
			)
			(layer "F.SilkS")
		)
		(fp_line
			(start -1.077722 -2.500122)
			(end -1.8288 -2.500122)
			(stroke
				(width 0.1524)
				(type default)
			)
			(layer "F.SilkS")
		)
		(fp_line
			(start 1.077722 -2.500122)
			(end 0 -1.4224)
			(stroke
				(width 0.1524)
				(type default)
			)
			(layer "F.SilkS")
		)
		(fp_line
			(start 1.8288 -2.500122)
			(end 1.077722 -2.500122)
			(stroke
				(width 0.1524)
				(type default)
			)
			(layer "F.SilkS")
		)
		(fp_poly
			(pts
				(xy -3.64236 -3.590036) (xy -4.309364 -2.823718) (xy -3.209544 -2.54)
			)
			(stroke
				(width 0)
				(type default)
			)
			(fill yes)
			(layer "F.SilkS")
		)
		(fp_line
			(start -1.999996 2.500122)
			(end 1.999996 2.500122)
			(stroke
				(width 0.1)
				(type default)
			)
			(layer "F.Fab")
		)
		(fp_line
			(start 1.999996 2.500122)
			(end 1.999996 -2.500122)
			(stroke
				(width 0.1)
				(type default)
			)
			(layer "F.Fab")
		)
		(fp_line
			(start -1.999996 -2.500122)
			(end -1.999996 2.500122)
			(stroke
				(width 0.1)
				(type default)
			)
			(layer "F.Fab")
		)
		(fp_line
			(start 1.999996 -2.500122)
			(end -1.999996 -2.500122)
			(stroke
				(width 0.1)
				(type default)
			)
			(layer "F.Fab")
		)
		(fp_poly
			(pts
				(xy -4.5085 -2.413) (xy -4.5085 -1.397) (xy -3.4925 -1.905)
			)
			(stroke
				(width 0)
				(type default)
			)
			(fill yes)
			(layer "F.Fab")
		)
		(pad "1" smd rect
			(at -2.599944 -1.905 180)
			(size 0.889 1.27)
			(layers "F.Cu" "F.Mask" "F.Paste")
			(net "Net_10835")
		)
		(pad "2" smd rect
			(at -2.599944 -0.635 180)
			(size 0.889 1.27)
			(layers "F.Cu" "F.Mask" "F.Paste")
			(net "Net_10834")
		)
		(pad "3" smd rect
			(at -2.599944 0.635 180)
			(size 0.889 1.27)
			(layers "F.Cu" "F.Mask" "F.Paste")
			(net "U20_E2")
		)
		(pad "4" smd rect
			(at -2.599944 1.905 180)
			(size 0.889 1.27)
			(layers "F.Cu" "F.Mask" "F.Paste")
			(net "GND")
		)
		(pad "5" smd rect
			(at 2.599944 1.905 180)
			(size 0.889 1.27)
			(layers "F.Cu" "F.Mask" "F.Paste")
			(net "SMB_RT_CPU1_P2_ROM_SDA")
		)
		(pad "6" smd rect
			(at 2.599944 0.635 180)
			(size 0.889 1.27)
			(layers "F.Cu" "F.Mask" "F.Paste")
			(net "SMB_RT_CPU1_P2_ROM_SCL")
		)
		(pad "7" smd rect
			(at 2.599944 -0.635 180)
			(size 0.889 1.27)
			(layers "F.Cu" "F.Mask" "F.Paste")
			(net "GND")
		)
		(pad "8" smd rect
			(at 2.599944 -1.905 180)
			(size 0.889 1.27)
			(layers "F.Cu" "F.Mask" "F.Paste")
			(net "P1V8_CPU1_RT_1D")
		)
	)
	(footprint ""
		(layer "F.Cu")
		(at 134.189216 -53.974238 -90)
		(property "Reference" "R1637"
			(at 0 0 270)
			(layer "F.SilkS")
			(hide yes)
			(effects
				(font
					(size 1.27 1.27)
				)
			)
		)
		(property "Value" ""
			(at 0 0 270)
			(layer "F.Fab")
			(effects
				(font
					(size 1.27 1.27)
				)
			)
		)
		(duplicate_pad_numbers_are_jumpers no)
		(fp_line
			(start -0.7874 0.4064)
			(end -0.7874 -0.4064)
			(stroke
				(width 0.1524)
				(type default)
			)
			(layer "F.SilkS")
		)
		(fp_line
			(start 0.7874 0.4064)
			(end -0.7874 0.4064)
			(stroke
				(width 0.1524)
				(type default)
			)
			(layer "F.SilkS")
		)
		(fp_line
			(start -0.7874 -0.4064)
			(end 0.7874 -0.4064)
			(stroke
				(width 0.1524)
				(type default)
			)
			(layer "F.SilkS")
		)
		(fp_line
			(start 0.7874 -0.4064)
			(end 0.7874 0.4064)
			(stroke
				(width 0.1524)
				(type default)
			)
			(layer "F.SilkS")
		)
		(fp_line
			(start -0.67945 0.3048)
			(end -0.67945 -0.305054)
			(stroke
				(width 0.1)
				(type default)
			)
			(layer "F.Fab")
		)
		(fp_line
			(start -0.12065 0.3048)
			(end -0.67945 0.3048)
			(stroke
				(width 0.1)
				(type default)
			)
			(layer "F.Fab")
		)
		(fp_line
			(start 0.120396 0.3048)
			(end 0.120396 0.2794)
			(stroke
				(width 0.1)
				(type default)
			)
			(layer "F.Fab")
		)
		(fp_line
			(start 0.67945 0.3048)
			(end 0.120396 0.3048)
			(stroke
				(width 0.1)
				(type default)
			)
			(layer "F.Fab")
		)
		(fp_line
			(start -0.12065 0.2794)
			(end -0.12065 0.3048)
			(stroke
				(width 0.1)
				(type default)
			)
			(layer "F.Fab")
		)
		(fp_line
			(start 0.120396 0.2794)
			(end -0.12065 0.2794)
			(stroke
				(width 0.1)
				(type default)
			)
			(layer "F.Fab")
		)
		(fp_line
			(start -0.12065 -0.2794)
			(end 0.12065 -0.2794)
			(stroke
				(width 0.1)
				(type default)
			)
			(layer "F.Fab")
		)
		(fp_line
			(start 0.12065 -0.2794)
			(end 0.12065 -0.3048)
			(stroke
				(width 0.1)
				(type default)
			)
			(layer "F.Fab")
		)
		(fp_line
			(start 0.12065 -0.3048)
			(end 0.67945 -0.3048)
			(stroke
				(width 0.1)
				(type default)
			)
			(layer "F.Fab")
		)
		(fp_line
			(start 0.67945 -0.3048)
			(end 0.67945 0.3048)
			(stroke
				(width 0.1)
				(type default)
			)
			(layer "F.Fab")
		)
		(fp_line
			(start -0.67945 -0.305054)
			(end -0.12065 -0.305054)
			(stroke
				(width 0.1)
				(type default)
			)
			(layer "F.Fab")
		)
		(fp_line
			(start -0.12065 -0.305054)
			(end -0.12065 -0.2794)
			(stroke
				(width 0.1)
				(type default)
			)
			(layer "F.Fab")
		)
		(pad "1" smd circle
			(at -0.40005 0 270)
			(size 0 0)
			(layers "F.Cu" "F.Mask" "F.Paste")
			(net "U152_OE_N")
		)
		(pad "2" smd circle
			(at 0.40005 0 270)
			(size 0 0)
			(layers "F.Cu" "F.Mask" "F.Paste")
			(net "GND")
		)
	)
	(footprint ""
		(layer "F.Cu")
		(at 200.600564 -71.582788)
		(property "Reference" "PC2201"
			(at 0 0 0)
			(layer "F.SilkS")
			(hide yes)
			(effects
				(font
					(size 1.27 1.27)
				)
			)
		)
		(property "Value" ""
			(at 0 0 0)
			(layer "F.Fab")
			(effects
				(font
					(size 1.27 1.27)
				)
			)
		)
		(duplicate_pad_numbers_are_jumpers no)
		(fp_line
			(start -0.7874 -0.4064)
			(end 0.7874 -0.4064)
			(stroke
				(width 0.1524)
				(type default)
			)
			(layer "F.SilkS")
		)
		(fp_line
			(start -0.7874 0.4064)
			(end -0.7874 -0.4064)
			(stroke
				(width 0.1524)
				(type default)
			)
			(layer "F.SilkS")
		)
		(fp_line
			(start 0.7874 -0.4064)
			(end 0.7874 0.4064)
			(stroke
				(width 0.1524)
				(type default)
			)
			(layer "F.SilkS")
		)
		(fp_line
			(start 0.7874 0.4064)
			(end -0.7874 0.4064)
			(stroke
				(width 0.1524)
				(type default)
			)
			(layer "F.SilkS")
		)
		(fp_line
			(start -0.67945 -0.305054)
			(end -0.12065 -0.305054)
			(stroke
				(width 0.1)
				(type default)
			)
			(layer "F.Fab")
		)
		(fp_line
			(start -0.67945 0.3048)
			(end -0.67945 -0.305054)
			(stroke
				(width 0.1)
				(type default)
			)
			(layer "F.Fab")
		)
		(fp_line
			(start -0.12065 -0.305054)
			(end -0.12065 -0.2794)
			(stroke
				(width 0.1)
				(type default)
			)
			(layer "F.Fab")
		)
		(fp_line
			(start -0.12065 -0.2794)
			(end 0.12065 -0.2794)
			(stroke
				(width 0.1)
				(type default)
			)
			(layer "F.Fab")
		)
		(fp_line
			(start -0.12065 0.2794)
			(end -0.12065 0.3048)
			(stroke
				(width 0.1)
				(type default)
			)
			(layer "F.Fab")
		)
		(fp_line
			(start -0.12065 0.3048)
			(end -0.67945 0.3048)
			(stroke
				(width 0.1)
				(type default)
			)
			(layer "F.Fab")
		)
		(fp_line
			(start 0.120396 0.2794)
			(end -0.12065 0.2794)
			(stroke
				(width 0.1)
				(type default)
			)
			(layer "F.Fab")
		)
		(fp_line
			(start 0.120396 0.3048)
			(end 0.120396 0.2794)
			(stroke
				(width 0.1)
				(type default)
			)
			(layer "F.Fab")
		)
		(fp_line
			(start 0.12065 -0.3048)
			(end 0.67945 -0.3048)
			(stroke
				(width 0.1)
				(type default)
			)
			(layer "F.Fab")
		)
		(fp_line
			(start 0.12065 -0.2794)
			(end 0.12065 -0.3048)
			(stroke
				(width 0.1)
				(type default)
			)
			(layer "F.Fab")
		)
		(fp_line
			(start 0.67945 -0.3048)
			(end 0.67945 0.3048)
			(stroke
				(width 0.1)
				(type default)
			)
			(layer "F.Fab")
		)
		(fp_line
			(start 0.67945 0.3048)
			(end 0.120396 0.3048)
			(stroke
				(width 0.1)
				(type default)
			)
			(layer "F.Fab")
		)
		(pad "1" smd circle
			(at -0.40005 0)
			(size 0 0)
			(layers "F.Cu" "F.Mask" "F.Paste")
			(net "P3V3_E1S_DVDT_0")
		)
		(pad "2" smd circle
			(at 0.40005 0)
			(size 0 0)
			(layers "F.Cu" "F.Mask" "F.Paste")
			(net "GND")
		)
	)
	(footprint ""
		(layer "F.Cu")
		(at 277.352252 -113.31067)
		(property "Reference" "R3536"
			(at 0 0 0)
			(layer "F.SilkS")
			(hide yes)
			(effects
				(font
					(size 1.27 1.27)
				)
			)
		)
		(property "Value" ""
			(at 0 0 0)
			(layer "F.Fab")
			(effects
				(font
					(size 1.27 1.27)
				)
			)
		)
		(duplicate_pad_numbers_are_jumpers no)
		(fp_line
			(start -0.7874 -0.4064)
			(end 0.7874 -0.4064)
			(stroke
				(width 0.1524)
				(type default)
			)
			(layer "F.SilkS")
		)
		(fp_line
			(start -0.7874 0.4064)
			(end -0.7874 -0.4064)
			(stroke
				(width 0.1524)
				(type default)
			)
			(layer "F.SilkS")
		)
		(fp_line
			(start 0.7874 -0.4064)
			(end 0.7874 0.4064)
			(stroke
				(width 0.1524)
				(type default)
			)
			(layer "F.SilkS")
		)
		(fp_line
			(start 0.7874 0.4064)
			(end -0.7874 0.4064)
			(stroke
				(width 0.1524)
				(type default)
			)
			(layer "F.SilkS")
		)
		(fp_line
			(start -0.67945 -0.305054)
			(end -0.12065 -0.305054)
			(stroke
				(width 0.1)
				(type default)
			)
			(layer "F.Fab")
		)
		(fp_line
			(start -0.67945 0.3048)
			(end -0.67945 -0.305054)
			(stroke
				(width 0.1)
				(type default)
			)
			(layer "F.Fab")
		)
		(fp_line
			(start -0.12065 -0.305054)
			(end -0.12065 -0.2794)
			(stroke
				(width 0.1)
				(type default)
			)
			(layer "F.Fab")
		)
		(fp_line
			(start -0.12065 -0.2794)
			(end 0.12065 -0.2794)
			(stroke
				(width 0.1)
				(type default)
			)
			(layer "F.Fab")
		)
		(fp_line
			(start -0.12065 0.2794)
			(end -0.12065 0.3048)
			(stroke
				(width 0.1)
				(type default)
			)
			(layer "F.Fab")
		)
		(fp_line
			(start -0.12065 0.3048)
			(end -0.67945 0.3048)
			(stroke
				(width 0.1)
				(type default)
			)
			(layer "F.Fab")
		)
		(fp_line
			(start 0.120396 0.2794)
			(end -0.12065 0.2794)
			(stroke
				(width 0.1)
				(type default)
			)
			(layer "F.Fab")
		)
		(fp_line
			(start 0.120396 0.3048)
			(end 0.120396 0.2794)
			(stroke
				(width 0.1)
				(type default)
			)
			(layer "F.Fab")
		)
		(fp_line
			(start 0.12065 -0.3048)
			(end 0.67945 -0.3048)
			(stroke
				(width 0.1)
				(type default)
			)
			(layer "F.Fab")
		)
		(fp_line
			(start 0.12065 -0.2794)
			(end 0.12065 -0.3048)
			(stroke
				(width 0.1)
				(type default)
			)
			(layer "F.Fab")
		)
		(fp_line
			(start 0.67945 -0.3048)
			(end 0.67945 0.3048)
			(stroke
				(width 0.1)
				(type default)
			)
			(layer "F.Fab")
		)
		(fp_line
			(start 0.67945 0.3048)
			(end 0.120396 0.3048)
			(stroke
				(width 0.1)
				(type default)
			)
			(layer "F.Fab")
		)
		(pad "1" smd circle
			(at -0.40005 0)
			(size 0 0)
			(layers "F.Cu" "F.Mask" "F.Paste")
			(net "P3V3_AUX")
		)
		(pad "2" smd circle
			(at 0.40005 0)
			(size 0 0)
			(layers "F.Cu" "F.Mask" "F.Paste")
			(net "SMB_SENSOR_E1S_3V3AUX_SDA")
		)
	)
	(footprint ""
		(layer "F.Cu")
		(at 340.026244 -378.95403 -90)
		(property "Reference" "C953"
			(at 0 0 270)
			(layer "F.SilkS")
			(hide yes)
			(effects
				(font
					(size 1.27 1.27)
				)
			)
		)
		(property "Value" ""
			(at 0 0 270)
			(layer "F.Fab")
			(effects
				(font
					(size 1.27 1.27)
				)
			)
		)
		(duplicate_pad_numbers_are_jumpers no)
		(fp_line
			(start -0.299974 0.150114)
			(end -0.299974 -0.150114)
			(stroke
				(width 0.1)
				(type default)
			)
			(layer "F.Fab")
		)
		(fp_line
			(start 0.299974 0.150114)
			(end -0.299974 0.150114)
			(stroke
				(width 0.1)
				(type default)
			)
			(layer "F.Fab")
		)
		(fp_line
			(start -0.299974 -0.150114)
			(end 0.299974 -0.150114)
			(stroke
				(width 0.1)
				(type default)
			)
			(layer "F.Fab")
		)
		(fp_line
			(start 0.299974 -0.150114)
			(end 0.299974 0.150114)
			(stroke
				(width 0.1)
				(type default)
			)
			(layer "F.Fab")
		)
		(pad "1" smd rect
			(at -0.2667 0 270)
			(size 0.3048 0.381)
			(layers "F.Cu" "F.Mask" "F.Paste")
			(net "P5E_CPU0_P1_TX_C_DP<6>")
		)
		(pad "2" smd rect
			(at 0.2667 0 270)
			(size 0.3048 0.381)
			(layers "F.Cu" "F.Mask" "F.Paste")
			(net "P5E_CPU0_P1_TX_DP<6>")
		)
	)
	(footprint ""
		(layer "F.Cu")
		(at 148.637244 -375.49963 -90)
		(property "Reference" "C764"
			(at 0 0 270)
			(layer "F.SilkS")
			(hide yes)
			(effects
				(font
					(size 1.27 1.27)
				)
			)
		)
		(property "Value" ""
			(at 0 0 270)
			(layer "F.Fab")
			(effects
				(font
					(size 1.27 1.27)
				)
			)
		)
		(duplicate_pad_numbers_are_jumpers no)
		(fp_line
			(start -0.299974 0.150114)
			(end -0.299974 -0.150114)
			(stroke
				(width 0.1)
				(type default)
			)
			(layer "F.Fab")
		)
		(fp_line
			(start 0.299974 0.150114)
			(end -0.299974 0.150114)
			(stroke
				(width 0.1)
				(type default)
			)
			(layer "F.Fab")
		)
		(fp_line
			(start -0.299974 -0.150114)
			(end 0.299974 -0.150114)
			(stroke
				(width 0.1)
				(type default)
			)
			(layer "F.Fab")
		)
		(fp_line
			(start 0.299974 -0.150114)
			(end 0.299974 0.150114)
			(stroke
				(width 0.1)
				(type default)
			)
			(layer "F.Fab")
		)
		(pad "1" smd rect
			(at -0.2667 0 270)
			(size 0.3048 0.381)
			(layers "F.Cu" "F.Mask" "F.Paste")
			(net "P5E_CPU1_P2_TX_C_DN<4>")
		)
		(pad "2" smd rect
			(at 0.2667 0 270)
			(size 0.3048 0.381)
			(layers "F.Cu" "F.Mask" "F.Paste")
			(net "P5E_CPU1_P2_TX_DN<4>")
		)
	)
	(footprint ""
		(layer "F.Cu")
		(at 113.440718 -401.280122)
		(property "Reference" "R1199"
			(at 0 0 0)
			(layer "F.SilkS")
			(hide yes)
			(effects
				(font
					(size 1.27 1.27)
				)
			)
		)
		(property "Value" ""
			(at 0 0 0)
			(layer "F.Fab")
			(effects
				(font
					(size 1.27 1.27)
				)
			)
		)
		(duplicate_pad_numbers_are_jumpers no)
		(fp_line
			(start -0.32512 -0.175006)
			(end 0.32512 -0.175006)
			(stroke
				(width 0.1)
				(type default)
			)
			(layer "F.Fab")
		)
		(fp_line
			(start -0.32512 0.175006)
			(end -0.32512 -0.175006)
			(stroke
				(width 0.1)
				(type default)
			)
			(layer "F.Fab")
		)
		(fp_line
			(start 0.32512 -0.175006)
			(end 0.32512 0.175006)
			(stroke
				(width 0.1)
				(type default)
			)
			(layer "F.Fab")
		)
		(fp_line
			(start 0.32512 0.175006)
			(end -0.32512 0.175006)
			(stroke
				(width 0.1)
				(type default)
			)
			(layer "F.Fab")
		)
		(pad "1" smd rect
			(at -0.2667 0)
			(size 0.3048 0.381)
			(layers "F.Cu" "F.Mask" "F.Paste")
			(net "RST_SMB_RT_ROM_R1_N")
		)
		(pad "2" smd rect
			(at 0.2667 0 180)
			(size 0.3048 0.381)
			(layers "F.Cu" "F.Mask" "F.Paste")
			(net "FM_SMB_RT_ROM_MUX2_SEL")
		)
	)
	(footprint ""
		(layer "F.Cu")
		(at 439.029602 -424.80611)
		(property "Reference" "R655"
			(at 0 0 0)
			(layer "F.SilkS")
			(hide yes)
			(effects
				(font
					(size 1.27 1.27)
				)
			)
		)
		(property "Value" ""
			(at 0 0 0)
			(layer "F.Fab")
			(effects
				(font
					(size 1.27 1.27)
				)
			)
		)
		(duplicate_pad_numbers_are_jumpers no)
		(fp_line
			(start -0.7874 -0.4064)
			(end 0.7874 -0.4064)
			(stroke
				(width 0.1524)
				(type default)
			)
			(layer "F.SilkS")
		)
		(fp_line
			(start -0.7874 0.4064)
			(end -0.7874 -0.4064)
			(stroke
				(width 0.1524)
				(type default)
			)
			(layer "F.SilkS")
		)
		(fp_line
			(start 0.7874 -0.4064)
			(end 0.7874 0.4064)
			(stroke
				(width 0.1524)
				(type default)
			)
			(layer "F.SilkS")
		)
		(fp_line
			(start 0.7874 0.4064)
			(end -0.7874 0.4064)
			(stroke
				(width 0.1524)
				(type default)
			)
			(layer "F.SilkS")
		)
		(fp_line
			(start -0.67945 -0.305054)
			(end -0.12065 -0.305054)
			(stroke
				(width 0.1)
				(type default)
			)
			(layer "F.Fab")
		)
		(fp_line
			(start -0.67945 0.3048)
			(end -0.67945 -0.305054)
			(stroke
				(width 0.1)
				(type default)
			)
			(layer "F.Fab")
		)
		(fp_line
			(start -0.12065 -0.305054)
			(end -0.12065 -0.2794)
			(stroke
				(width 0.1)
				(type default)
			)
			(layer "F.Fab")
		)
		(fp_line
			(start -0.12065 -0.2794)
			(end 0.12065 -0.2794)
			(stroke
				(width 0.1)
				(type default)
			)
			(layer "F.Fab")
		)
		(fp_line
			(start -0.12065 0.2794)
			(end -0.12065 0.3048)
			(stroke
				(width 0.1)
				(type default)
			)
			(layer "F.Fab")
		)
		(fp_line
			(start -0.12065 0.3048)
			(end -0.67945 0.3048)
			(stroke
				(width 0.1)
				(type default)
			)
			(layer "F.Fab")
		)
		(fp_line
			(start 0.120396 0.2794)
			(end -0.12065 0.2794)
			(stroke
				(width 0.1)
				(type default)
			)
			(layer "F.Fab")
		)
		(fp_line
			(start 0.120396 0.3048)
			(end 0.120396 0.2794)
			(stroke
				(width 0.1)
				(type default)
			)
			(layer "F.Fab")
		)
		(fp_line
			(start 0.12065 -0.3048)
			(end 0.67945 -0.3048)
			(stroke
				(width 0.1)
				(type default)
			)
			(layer "F.Fab")
		)
		(fp_line
			(start 0.12065 -0.2794)
			(end 0.12065 -0.3048)
			(stroke
				(width 0.1)
				(type default)
			)
			(layer "F.Fab")
		)
		(fp_line
			(start 0.67945 -0.3048)
			(end 0.67945 0.3048)
			(stroke
				(width 0.1)
				(type default)
			)
			(layer "F.Fab")
		)
		(fp_line
			(start 0.67945 0.3048)
			(end 0.120396 0.3048)
			(stroke
				(width 0.1)
				(type default)
			)
			(layer "F.Fab")
		)
		(pad "1" smd circle
			(at -0.40005 0)
			(size 0 0)
			(layers "F.Cu" "F.Mask" "F.Paste")
			(net "P3V3_AUX")
		)
		(pad "2" smd circle
			(at 0.40005 0)
			(size 0 0)
			(layers "F.Cu" "F.Mask" "F.Paste")
			(net "P0V9_RETIMER_CPU0_INALERT")
		)
	)
	(footprint ""
		(layer "F.Cu")
		(at 403.5552 -77.513434 90)
		(property "Reference" "C1860"
			(at 0 0 90)
			(layer "F.SilkS")
			(hide yes)
			(effects
				(font
					(size 1.27 1.27)
				)
			)
		)
		(property "Value" ""
			(at 0 0 90)
			(layer "F.Fab")
			(effects
				(font
					(size 1.27 1.27)
				)
			)
		)
		(duplicate_pad_numbers_are_jumpers no)
		(fp_line
			(start 0.7874 -0.4064)
			(end 0.7874 0.4064)
			(stroke
				(width 0.1524)
				(type default)
			)
			(layer "F.SilkS")
		)
		(fp_line
			(start -0.7874 -0.4064)
			(end 0.7874 -0.4064)
			(stroke
				(width 0.1524)
				(type default)
			)
			(layer "F.SilkS")
		)
		(fp_line
			(start 0.7874 0.4064)
			(end -0.7874 0.4064)
			(stroke
				(width 0.1524)
				(type default)
			)
			(layer "F.SilkS")
		)
		(fp_line
			(start -0.7874 0.4064)
			(end -0.7874 -0.4064)
			(stroke
				(width 0.1524)
				(type default)
			)
			(layer "F.SilkS")
		)
		(fp_line
			(start -0.12065 -0.305054)
			(end -0.12065 -0.2794)
			(stroke
				(width 0.1)
				(type default)
			)
			(layer "F.Fab")
		)
		(fp_line
			(start -0.67945 -0.305054)
			(end -0.12065 -0.305054)
			(stroke
				(width 0.1)
				(type default)
			)
			(layer "F.Fab")
		)
		(fp_line
			(start 0.67945 -0.3048)
			(end 0.67945 0.3048)
			(stroke
				(width 0.1)
				(type default)
			)
			(layer "F.Fab")
		)
		(fp_line
			(start 0.12065 -0.3048)
			(end 0.67945 -0.3048)
			(stroke
				(width 0.1)
				(type default)
			)
			(layer "F.Fab")
		)
		(fp_line
			(start 0.12065 -0.2794)
			(end 0.12065 -0.3048)
			(stroke
				(width 0.1)
				(type default)
			)
			(layer "F.Fab")
		)
		(fp_line
			(start -0.12065 -0.2794)
			(end 0.12065 -0.2794)
			(stroke
				(width 0.1)
				(type default)
			)
			(layer "F.Fab")
		)
		(fp_line
			(start 0.120396 0.2794)
			(end -0.12065 0.2794)
			(stroke
				(width 0.1)
				(type default)
			)
			(layer "F.Fab")
		)
		(fp_line
			(start -0.12065 0.2794)
			(end -0.12065 0.3048)
			(stroke
				(width 0.1)
				(type default)
			)
			(layer "F.Fab")
		)
		(fp_line
			(start 0.67945 0.3048)
			(end 0.120396 0.3048)
			(stroke
				(width 0.1)
				(type default)
			)
			(layer "F.Fab")
		)
		(fp_line
			(start 0.120396 0.3048)
			(end 0.120396 0.2794)
			(stroke
				(width 0.1)
				(type default)
			)
			(layer "F.Fab")
		)
		(fp_line
			(start -0.12065 0.3048)
			(end -0.67945 0.3048)
			(stroke
				(width 0.1)
				(type default)
			)
			(layer "F.Fab")
		)
		(fp_line
			(start -0.67945 0.3048)
			(end -0.67945 -0.305054)
			(stroke
				(width 0.1)
				(type default)
			)
			(layer "F.Fab")
		)
		(pad "1" smd circle
			(at -0.40005 0 90)
			(size 0 0)
			(layers "F.Cu" "F.Mask" "F.Paste")
			(net "P3V3_AUX")
		)
		(pad "2" smd circle
			(at 0.40005 0 90)
			(size 0 0)
			(layers "F.Cu" "F.Mask" "F.Paste")
			(net "GND")
		)
	)
	(footprint ""
		(layer "F.Cu")
		(at 305.819048 -41.906698 180)
		(property "Reference" "R3670"
			(at 0 0 180)
			(layer "F.SilkS")
			(hide yes)
			(effects
				(font
					(size 1.27 1.27)
				)
			)
		)
		(property "Value" ""
			(at 0 0 180)
			(layer "F.Fab")
			(effects
				(font
					(size 1.27 1.27)
				)
			)
		)
		(duplicate_pad_numbers_are_jumpers no)
		(fp_line
			(start 0.7874 0.4064)
			(end -0.7874 0.4064)
			(stroke
				(width 0.1524)
				(type default)
			)
			(layer "F.SilkS")
		)
		(fp_line
			(start 0.7874 -0.4064)
			(end 0.7874 0.4064)
			(stroke
				(width 0.1524)
				(type default)
			)
			(layer "F.SilkS")
		)
		(fp_line
			(start -0.7874 0.4064)
			(end -0.7874 -0.4064)
			(stroke
				(width 0.1524)
				(type default)
			)
			(layer "F.SilkS")
		)
		(fp_line
			(start -0.7874 -0.4064)
			(end 0.7874 -0.4064)
			(stroke
				(width 0.1524)
				(type default)
			)
			(layer "F.SilkS")
		)
		(fp_line
			(start 0.67945 0.3048)
			(end 0.120396 0.3048)
			(stroke
				(width 0.1)
				(type default)
			)
			(layer "F.Fab")
		)
		(fp_line
			(start 0.67945 -0.3048)
			(end 0.67945 0.3048)
			(stroke
				(width 0.1)
				(type default)
			)
			(layer "F.Fab")
		)
		(fp_line
			(start 0.12065 -0.2794)
			(end 0.12065 -0.3048)
			(stroke
				(width 0.1)
				(type default)
			)
			(layer "F.Fab")
		)
		(fp_line
			(start 0.12065 -0.3048)
			(end 0.67945 -0.3048)
			(stroke
				(width 0.1)
				(type default)
			)
			(layer "F.Fab")
		)
		(fp_line
			(start 0.120396 0.3048)
			(end 0.120396 0.2794)
			(stroke
				(width 0.1)
				(type default)
			)
			(layer "F.Fab")
		)
		(fp_line
			(start 0.120396 0.2794)
			(end -0.12065 0.2794)
			(stroke
				(width 0.1)
				(type default)
			)
			(layer "F.Fab")
		)
		(fp_line
			(start -0.12065 0.3048)
			(end -0.67945 0.3048)
			(stroke
				(width 0.1)
				(type default)
			)
			(layer "F.Fab")
		)
		(fp_line
			(start -0.12065 0.2794)
			(end -0.12065 0.3048)
			(stroke
				(width 0.1)
				(type default)
			)
			(layer "F.Fab")
		)
		(fp_line
			(start -0.12065 -0.2794)
			(end 0.12065 -0.2794)
			(stroke
				(width 0.1)
				(type default)
			)
			(layer "F.Fab")
		)
		(fp_line
			(start -0.12065 -0.305054)
			(end -0.12065 -0.2794)
			(stroke
				(width 0.1)
				(type default)
			)
			(layer "F.Fab")
		)
		(fp_line
			(start -0.67945 0.3048)
			(end -0.67945 -0.305054)
			(stroke
				(width 0.1)
				(type default)
			)
			(layer "F.Fab")
		)
		(fp_line
			(start -0.67945 -0.305054)
			(end -0.12065 -0.305054)
			(stroke
				(width 0.1)
				(type default)
			)
			(layer "F.Fab")
		)
		(pad "1" smd circle
			(at -0.40005 0 180)
			(size 0 0)
			(layers "F.Cu" "F.Mask" "F.Paste")
			(net "ADC128_A0")
		)
		(pad "2" smd circle
			(at 0.40005 0 180)
			(size 0 0)
			(layers "F.Cu" "F.Mask" "F.Paste")
			(net "GND")
		)
	)
	(footprint ""
		(layer "F.Cu")
		(at 284.317694 -436.304436 90)
		(property "Reference" "R4553"
			(at 0 0 90)
			(layer "F.SilkS")
			(hide yes)
			(effects
				(font
					(size 1.27 1.27)
				)
			)
		)
		(property "Value" ""
			(at 0 0 90)
			(layer "F.Fab")
			(effects
				(font
					(size 1.27 1.27)
				)
			)
		)
		(duplicate_pad_numbers_are_jumpers no)
		(fp_line
			(start 0.7874 -0.4064)
			(end 0.7874 0.4064)
			(stroke
				(width 0.1524)
				(type default)
			)
			(layer "F.SilkS")
		)
		(fp_line
			(start -0.7874 -0.4064)
			(end 0.7874 -0.4064)
			(stroke
				(width 0.1524)
				(type default)
			)
			(layer "F.SilkS")
		)
		(fp_line
			(start 0.7874 0.4064)
			(end -0.7874 0.4064)
			(stroke
				(width 0.1524)
				(type default)
			)
			(layer "F.SilkS")
		)
		(fp_line
			(start -0.7874 0.4064)
			(end -0.7874 -0.4064)
			(stroke
				(width 0.1524)
				(type default)
			)
			(layer "F.SilkS")
		)
		(fp_line
			(start -0.12065 -0.305054)
			(end -0.12065 -0.2794)
			(stroke
				(width 0.1)
				(type default)
			)
			(layer "F.Fab")
		)
		(fp_line
			(start -0.67945 -0.305054)
			(end -0.12065 -0.305054)
			(stroke
				(width 0.1)
				(type default)
			)
			(layer "F.Fab")
		)
		(fp_line
			(start 0.67945 -0.3048)
			(end 0.67945 0.3048)
			(stroke
				(width 0.1)
				(type default)
			)
			(layer "F.Fab")
		)
		(fp_line
			(start 0.12065 -0.3048)
			(end 0.67945 -0.3048)
			(stroke
				(width 0.1)
				(type default)
			)
			(layer "F.Fab")
		)
		(fp_line
			(start 0.12065 -0.2794)
			(end 0.12065 -0.3048)
			(stroke
				(width 0.1)
				(type default)
			)
			(layer "F.Fab")
		)
		(fp_line
			(start -0.12065 -0.2794)
			(end 0.12065 -0.2794)
			(stroke
				(width 0.1)
				(type default)
			)
			(layer "F.Fab")
		)
		(fp_line
			(start 0.120396 0.2794)
			(end -0.12065 0.2794)
			(stroke
				(width 0.1)
				(type default)
			)
			(layer "F.Fab")
		)
		(fp_line
			(start -0.12065 0.2794)
			(end -0.12065 0.3048)
			(stroke
				(width 0.1)
				(type default)
			)
			(layer "F.Fab")
		)
		(fp_line
			(start 0.67945 0.3048)
			(end 0.120396 0.3048)
			(stroke
				(width 0.1)
				(type default)
			)
			(layer "F.Fab")
		)
		(fp_line
			(start 0.120396 0.3048)
			(end 0.120396 0.2794)
			(stroke
				(width 0.1)
				(type default)
			)
			(layer "F.Fab")
		)
		(fp_line
			(start -0.12065 0.3048)
			(end -0.67945 0.3048)
			(stroke
				(width 0.1)
				(type default)
			)
			(layer "F.Fab")
		)
		(fp_line
			(start -0.67945 0.3048)
			(end -0.67945 -0.305054)
			(stroke
				(width 0.1)
				(type default)
			)
			(layer "F.Fab")
		)
		(pad "1" smd circle
			(at -0.40005 0 90)
			(size 0 0)
			(layers "F.Cu" "F.Mask" "F.Paste")
			(net "P3V3_AUX")
		)
		(pad "2" smd circle
			(at 0.40005 0 90)
			(size 0 0)
			(layers "F.Cu" "F.Mask" "F.Paste")
			(net "HPDB_HSC_PWRGD_N")
		)
	)
	(footprint ""
		(layer "F.Cu")
		(at 180.772308 -165.292024 90)
		(property "Reference" "C1339"
			(at 0 0 90)
			(layer "F.SilkS")
			(hide yes)
			(effects
				(font
					(size 1.27 1.27)
				)
			)
		)
		(property "Value" ""
			(at 0 0 90)
			(layer "F.Fab")
			(effects
				(font
					(size 1.27 1.27)
				)
			)
		)
		(duplicate_pad_numbers_are_jumpers no)
		(fp_line
			(start 0.7874 -0.4064)
			(end 0.7874 0.4064)
			(stroke
				(width 0.1524)
				(type default)
			)
			(layer "F.SilkS")
		)
		(fp_line
			(start -0.7874 -0.4064)
			(end 0.7874 -0.4064)
			(stroke
				(width 0.1524)
				(type default)
			)
			(layer "F.SilkS")
		)
		(fp_line
			(start 0.7874 0.4064)
			(end -0.7874 0.4064)
			(stroke
				(width 0.1524)
				(type default)
			)
			(layer "F.SilkS")
		)
		(fp_line
			(start -0.7874 0.4064)
			(end -0.7874 -0.4064)
			(stroke
				(width 0.1524)
				(type default)
			)
			(layer "F.SilkS")
		)
		(fp_line
			(start -0.12065 -0.305054)
			(end -0.12065 -0.2794)
			(stroke
				(width 0.1)
				(type default)
			)
			(layer "F.Fab")
		)
		(fp_line
			(start -0.67945 -0.305054)
			(end -0.12065 -0.305054)
			(stroke
				(width 0.1)
				(type default)
			)
			(layer "F.Fab")
		)
		(fp_line
			(start 0.67945 -0.3048)
			(end 0.67945 0.3048)
			(stroke
				(width 0.1)
				(type default)
			)
			(layer "F.Fab")
		)
		(fp_line
			(start 0.12065 -0.3048)
			(end 0.67945 -0.3048)
			(stroke
				(width 0.1)
				(type default)
			)
			(layer "F.Fab")
		)
		(fp_line
			(start 0.12065 -0.2794)
			(end 0.12065 -0.3048)
			(stroke
				(width 0.1)
				(type default)
			)
			(layer "F.Fab")
		)
		(fp_line
			(start -0.12065 -0.2794)
			(end 0.12065 -0.2794)
			(stroke
				(width 0.1)
				(type default)
			)
			(layer "F.Fab")
		)
		(fp_line
			(start 0.120396 0.2794)
			(end -0.12065 0.2794)
			(stroke
				(width 0.1)
				(type default)
			)
			(layer "F.Fab")
		)
		(fp_line
			(start -0.12065 0.2794)
			(end -0.12065 0.3048)
			(stroke
				(width 0.1)
				(type default)
			)
			(layer "F.Fab")
		)
		(fp_line
			(start 0.67945 0.3048)
			(end 0.120396 0.3048)
			(stroke
				(width 0.1)
				(type default)
			)
			(layer "F.Fab")
		)
		(fp_line
			(start 0.120396 0.3048)
			(end 0.120396 0.2794)
			(stroke
				(width 0.1)
				(type default)
			)
			(layer "F.Fab")
		)
		(fp_line
			(start -0.12065 0.3048)
			(end -0.67945 0.3048)
			(stroke
				(width 0.1)
				(type default)
			)
			(layer "F.Fab")
		)
		(fp_line
			(start -0.67945 0.3048)
			(end -0.67945 -0.305054)
			(stroke
				(width 0.1)
				(type default)
			)
			(layer "F.Fab")
		)
		(pad "1" smd circle
			(at -0.40005 0 90)
			(size 0 0)
			(layers "F.Cu" "F.Mask" "F.Paste")
			(net "P3V3_AUX")
		)
		(pad "2" smd circle
			(at 0.40005 0 90)
			(size 0 0)
			(layers "F.Cu" "F.Mask" "F.Paste")
			(net "GND")
		)
	)
	(footprint ""
		(layer "F.Cu")
		(at 66.027554 -370.57203 -90)
		(property "Reference" "C812"
			(at 0 0 270)
			(layer "F.SilkS")
			(hide yes)
			(effects
				(font
					(size 1.27 1.27)
				)
			)
		)
		(property "Value" ""
			(at 0 0 270)
			(layer "F.Fab")
			(effects
				(font
					(size 1.27 1.27)
				)
			)
		)
		(duplicate_pad_numbers_are_jumpers no)
		(fp_line
			(start -0.299974 0.150114)
			(end -0.299974 -0.150114)
			(stroke
				(width 0.1)
				(type default)
			)
			(layer "F.Fab")
		)
		(fp_line
			(start 0.299974 0.150114)
			(end -0.299974 0.150114)
			(stroke
				(width 0.1)
				(type default)
			)
			(layer "F.Fab")
		)
		(fp_line
			(start -0.299974 -0.150114)
			(end 0.299974 -0.150114)
			(stroke
				(width 0.1)
				(type default)
			)
			(layer "F.Fab")
		)
		(fp_line
			(start 0.299974 -0.150114)
			(end 0.299974 0.150114)
			(stroke
				(width 0.1)
				(type default)
			)
			(layer "F.Fab")
		)
		(pad "1" smd rect
			(at -0.2667 0 270)
			(size 0.3048 0.381)
			(layers "F.Cu" "F.Mask" "F.Paste")
			(net "P5E_CPU1_P0_TX_C_DN<12>")
		)
		(pad "2" smd rect
			(at 0.2667 0 270)
			(size 0.3048 0.381)
			(layers "F.Cu" "F.Mask" "F.Paste")
			(net "P5E_CPU1_P0_TX_DN<12>")
		)
	)
	(footprint ""
		(layer "F.Cu")
		(at 332.431644 -381.41783 -90)
		(property "Reference" "C960"
			(at 0 0 270)
			(layer "F.SilkS")
			(hide yes)
			(effects
				(font
					(size 1.27 1.27)
				)
			)
		)
		(property "Value" ""
			(at 0 0 270)
			(layer "F.Fab")
			(effects
				(font
					(size 1.27 1.27)
				)
			)
		)
		(duplicate_pad_numbers_are_jumpers no)
		(fp_line
			(start -0.299974 0.150114)
			(end -0.299974 -0.150114)
			(stroke
				(width 0.1)
				(type default)
			)
			(layer "F.Fab")
		)
		(fp_line
			(start 0.299974 0.150114)
			(end -0.299974 0.150114)
			(stroke
				(width 0.1)
				(type default)
			)
			(layer "F.Fab")
		)
		(fp_line
			(start -0.299974 -0.150114)
			(end 0.299974 -0.150114)
			(stroke
				(width 0.1)
				(type default)
			)
			(layer "F.Fab")
		)
		(fp_line
			(start 0.299974 -0.150114)
			(end 0.299974 0.150114)
			(stroke
				(width 0.1)
				(type default)
			)
			(layer "F.Fab")
		)
		(pad "1" smd rect
			(at -0.2667 0 270)
			(size 0.3048 0.381)
			(layers "F.Cu" "F.Mask" "F.Paste")
			(net "P5E_CPU0_P1_TX_C_DN<2>")
		)
		(pad "2" smd rect
			(at 0.2667 0 270)
			(size 0.3048 0.381)
			(layers "F.Cu" "F.Mask" "F.Paste")
			(net "P5E_CPU0_P1_TX_DN<2>")
		)
	)
	(footprint ""
		(layer "F.Cu")
		(at 64.63538 -394.78966 -90)
		(property "Reference" "R701"
			(at 0 0 270)
			(layer "F.SilkS")
			(hide yes)
			(effects
				(font
					(size 1.27 1.27)
				)
			)
		)
		(property "Value" ""
			(at 0 0 270)
			(layer "F.Fab")
			(effects
				(font
					(size 1.27 1.27)
				)
			)
		)
		(duplicate_pad_numbers_are_jumpers no)
		(fp_line
			(start -0.32512 0.175006)
			(end -0.32512 -0.175006)
			(stroke
				(width 0.1)
				(type default)
			)
			(layer "F.Fab")
		)
		(fp_line
			(start 0.32512 0.175006)
			(end -0.32512 0.175006)
			(stroke
				(width 0.1)
				(type default)
			)
			(layer "F.Fab")
		)
		(fp_line
			(start -0.32512 -0.175006)
			(end 0.32512 -0.175006)
			(stroke
				(width 0.1)
				(type default)
			)
			(layer "F.Fab")
		)
		(fp_line
			(start 0.32512 -0.175006)
			(end 0.32512 0.175006)
			(stroke
				(width 0.1)
				(type default)
			)
			(layer "F.Fab")
		)
		(pad "1" smd rect
			(at -0.2667 0 270)
			(size 0.3048 0.381)
			(layers "F.Cu" "F.Mask" "F.Paste")
			(net "RT_CPU1_P0_VQPS")
		)
		(pad "2" smd rect
			(at 0.2667 0 90)
			(size 0.3048 0.381)
			(layers "F.Cu" "F.Mask" "F.Paste")
			(net "GND")
		)
	)
	(footprint ""
		(layer "F.Cu")
		(at 70.720204 -144.881092 180)
		(property "Reference" "PR401"
			(at 0 0 180)
			(layer "F.SilkS")
			(hide yes)
			(effects
				(font
					(size 1.27 1.27)
				)
			)
		)
		(property "Value" ""
			(at 0 0 180)
			(layer "F.Fab")
			(effects
				(font
					(size 1.27 1.27)
				)
			)
		)
		(duplicate_pad_numbers_are_jumpers no)
		(fp_line
			(start 0.7874 0.4064)
			(end -0.7874 0.4064)
			(stroke
				(width 0.1524)
				(type default)
			)
			(layer "F.SilkS")
		)
		(fp_line
			(start 0.7874 -0.4064)
			(end 0.7874 0.4064)
			(stroke
				(width 0.1524)
				(type default)
			)
			(layer "F.SilkS")
		)
		(fp_line
			(start -0.7874 0.4064)
			(end -0.7874 -0.4064)
			(stroke
				(width 0.1524)
				(type default)
			)
			(layer "F.SilkS")
		)
		(fp_line
			(start -0.7874 -0.4064)
			(end 0.7874 -0.4064)
			(stroke
				(width 0.1524)
				(type default)
			)
			(layer "F.SilkS")
		)
		(fp_line
			(start 0.67945 0.3048)
			(end 0.120396 0.3048)
			(stroke
				(width 0.1)
				(type default)
			)
			(layer "F.Fab")
		)
		(fp_line
			(start 0.67945 -0.3048)
			(end 0.67945 0.3048)
			(stroke
				(width 0.1)
				(type default)
			)
			(layer "F.Fab")
		)
		(fp_line
			(start 0.12065 -0.2794)
			(end 0.12065 -0.3048)
			(stroke
				(width 0.1)
				(type default)
			)
			(layer "F.Fab")
		)
		(fp_line
			(start 0.12065 -0.3048)
			(end 0.67945 -0.3048)
			(stroke
				(width 0.1)
				(type default)
			)
			(layer "F.Fab")
		)
		(fp_line
			(start 0.120396 0.3048)
			(end 0.120396 0.2794)
			(stroke
				(width 0.1)
				(type default)
			)
			(layer "F.Fab")
		)
		(fp_line
			(start 0.120396 0.2794)
			(end -0.12065 0.2794)
			(stroke
				(width 0.1)
				(type default)
			)
			(layer "F.Fab")
		)
		(fp_line
			(start -0.12065 0.3048)
			(end -0.67945 0.3048)
			(stroke
				(width 0.1)
				(type default)
			)
			(layer "F.Fab")
		)
		(fp_line
			(start -0.12065 0.2794)
			(end -0.12065 0.3048)
			(stroke
				(width 0.1)
				(type default)
			)
			(layer "F.Fab")
		)
		(fp_line
			(start -0.12065 -0.2794)
			(end 0.12065 -0.2794)
			(stroke
				(width 0.1)
				(type default)
			)
			(layer "F.Fab")
		)
		(fp_line
			(start -0.12065 -0.305054)
			(end -0.12065 -0.2794)
			(stroke
				(width 0.1)
				(type default)
			)
			(layer "F.Fab")
		)
		(fp_line
			(start -0.67945 0.3048)
			(end -0.67945 -0.305054)
			(stroke
				(width 0.1)
				(type default)
			)
			(layer "F.Fab")
		)
		(fp_line
			(start -0.67945 -0.305054)
			(end -0.12065 -0.305054)
			(stroke
				(width 0.1)
				(type default)
			)
			(layer "F.Fab")
		)
		(pad "1" smd circle
			(at -0.40005 0 180)
			(size 0 0)
			(layers "F.Cu" "F.Mask" "F.Paste")
			(net "PVDD18_SS_P1_RGND")
		)
		(pad "2" smd circle
			(at 0.40005 0 180)
			(size 0 0)
			(layers "F.Cu" "F.Mask" "F.Paste")
			(net "VSENSE_PVDD18_S5_P1_DN")
		)
	)
	(footprint ""
		(layer "F.Cu")
		(at 377.417838 -182.661052 90)
		(property "Reference" "PC550_3"
			(at 0 0 90)
			(layer "F.SilkS")
			(hide yes)
			(effects
				(font
					(size 1.27 1.27)
				)
			)
		)
		(property "Value" ""
			(at 0 0 90)
			(layer "F.Fab")
			(effects
				(font
					(size 1.27 1.27)
				)
			)
		)
		(duplicate_pad_numbers_are_jumpers no)
		(fp_line
			(start 0.7874 -0.4064)
			(end 0.7874 0.4064)
			(stroke
				(width 0.1524)
				(type default)
			)
			(layer "F.SilkS")
		)
		(fp_line
			(start -0.7874 -0.4064)
			(end 0.7874 -0.4064)
			(stroke
				(width 0.1524)
				(type default)
			)
			(layer "F.SilkS")
		)
		(fp_line
			(start 0.7874 0.4064)
			(end -0.7874 0.4064)
			(stroke
				(width 0.1524)
				(type default)
			)
			(layer "F.SilkS")
		)
		(fp_line
			(start -0.7874 0.4064)
			(end -0.7874 -0.4064)
			(stroke
				(width 0.1524)
				(type default)
			)
			(layer "F.SilkS")
		)
		(fp_line
			(start -0.12065 -0.305054)
			(end -0.12065 -0.2794)
			(stroke
				(width 0.1)
				(type default)
			)
			(layer "F.Fab")
		)
		(fp_line
			(start -0.67945 -0.305054)
			(end -0.12065 -0.305054)
			(stroke
				(width 0.1)
				(type default)
			)
			(layer "F.Fab")
		)
		(fp_line
			(start 0.67945 -0.3048)
			(end 0.67945 0.3048)
			(stroke
				(width 0.1)
				(type default)
			)
			(layer "F.Fab")
		)
		(fp_line
			(start 0.12065 -0.3048)
			(end 0.67945 -0.3048)
			(stroke
				(width 0.1)
				(type default)
			)
			(layer "F.Fab")
		)
		(fp_line
			(start 0.12065 -0.2794)
			(end 0.12065 -0.3048)
			(stroke
				(width 0.1)
				(type default)
			)
			(layer "F.Fab")
		)
		(fp_line
			(start -0.12065 -0.2794)
			(end 0.12065 -0.2794)
			(stroke
				(width 0.1)
				(type default)
			)
			(layer "F.Fab")
		)
		(fp_line
			(start 0.120396 0.2794)
			(end -0.12065 0.2794)
			(stroke
				(width 0.1)
				(type default)
			)
			(layer "F.Fab")
		)
		(fp_line
			(start -0.12065 0.2794)
			(end -0.12065 0.3048)
			(stroke
				(width 0.1)
				(type default)
			)
			(layer "F.Fab")
		)
		(fp_line
			(start 0.67945 0.3048)
			(end 0.120396 0.3048)
			(stroke
				(width 0.1)
				(type default)
			)
			(layer "F.Fab")
		)
		(fp_line
			(start 0.120396 0.3048)
			(end 0.120396 0.2794)
			(stroke
				(width 0.1)
				(type default)
			)
			(layer "F.Fab")
		)
		(fp_line
			(start -0.12065 0.3048)
			(end -0.67945 0.3048)
			(stroke
				(width 0.1)
				(type default)
			)
			(layer "F.Fab")
		)
		(fp_line
			(start -0.67945 0.3048)
			(end -0.67945 -0.305054)
			(stroke
				(width 0.1)
				(type default)
			)
			(layer "F.Fab")
		)
		(pad "1" smd circle
			(at -0.40005 0 90)
			(size 0 0)
			(layers "F.Cu" "F.Mask" "F.Paste")
			(net "SW_P12V_AUX_PVDDCR_CPU0_P0_FLT")
		)
		(pad "2" smd circle
			(at 0.40005 0 90)
			(size 0 0)
			(layers "F.Cu" "F.Mask" "F.Paste")
			(net "GND")
		)
	)
	(footprint ""
		(layer "F.Cu")
		(at 351.410778 -161.141156 90)
		(property "Reference" "PC152_C0P0_6"
			(at 0 0 90)
			(layer "F.SilkS")
			(hide yes)
			(effects
				(font
					(size 1.27 1.27)
				)
			)
		)
		(property "Value" ""
			(at 0 0 90)
			(layer "F.Fab")
			(effects
				(font
					(size 1.27 1.27)
				)
			)
		)
		(duplicate_pad_numbers_are_jumpers no)
		(fp_line
			(start 0.7874 -0.4064)
			(end 0.7874 0.4064)
			(stroke
				(width 0.1524)
				(type default)
			)
			(layer "F.SilkS")
		)
		(fp_line
			(start -0.7874 -0.4064)
			(end 0.7874 -0.4064)
			(stroke
				(width 0.1524)
				(type default)
			)
			(layer "F.SilkS")
		)
		(fp_line
			(start 0.7874 0.4064)
			(end -0.7874 0.4064)
			(stroke
				(width 0.1524)
				(type default)
			)
			(layer "F.SilkS")
		)
		(fp_line
			(start -0.7874 0.4064)
			(end -0.7874 -0.4064)
			(stroke
				(width 0.1524)
				(type default)
			)
			(layer "F.SilkS")
		)
		(fp_line
			(start -0.12065 -0.305054)
			(end -0.12065 -0.2794)
			(stroke
				(width 0.1)
				(type default)
			)
			(layer "F.Fab")
		)
		(fp_line
			(start -0.67945 -0.305054)
			(end -0.12065 -0.305054)
			(stroke
				(width 0.1)
				(type default)
			)
			(layer "F.Fab")
		)
		(fp_line
			(start 0.67945 -0.3048)
			(end 0.67945 0.3048)
			(stroke
				(width 0.1)
				(type default)
			)
			(layer "F.Fab")
		)
		(fp_line
			(start 0.12065 -0.3048)
			(end 0.67945 -0.3048)
			(stroke
				(width 0.1)
				(type default)
			)
			(layer "F.Fab")
		)
		(fp_line
			(start 0.12065 -0.2794)
			(end 0.12065 -0.3048)
			(stroke
				(width 0.1)
				(type default)
			)
			(layer "F.Fab")
		)
		(fp_line
			(start -0.12065 -0.2794)
			(end 0.12065 -0.2794)
			(stroke
				(width 0.1)
				(type default)
			)
			(layer "F.Fab")
		)
		(fp_line
			(start 0.120396 0.2794)
			(end -0.12065 0.2794)
			(stroke
				(width 0.1)
				(type default)
			)
			(layer "F.Fab")
		)
		(fp_line
			(start -0.12065 0.2794)
			(end -0.12065 0.3048)
			(stroke
				(width 0.1)
				(type default)
			)
			(layer "F.Fab")
		)
		(fp_line
			(start 0.67945 0.3048)
			(end 0.120396 0.3048)
			(stroke
				(width 0.1)
				(type default)
			)
			(layer "F.Fab")
		)
		(fp_line
			(start 0.120396 0.3048)
			(end 0.120396 0.2794)
			(stroke
				(width 0.1)
				(type default)
			)
			(layer "F.Fab")
		)
		(fp_line
			(start -0.12065 0.3048)
			(end -0.67945 0.3048)
			(stroke
				(width 0.1)
				(type default)
			)
			(layer "F.Fab")
		)
		(fp_line
			(start -0.67945 0.3048)
			(end -0.67945 -0.305054)
			(stroke
				(width 0.1)
				(type default)
			)
			(layer "F.Fab")
		)
		(pad "1" smd circle
			(at -0.40005 0 90)
			(size 0 0)
			(layers "F.Cu" "F.Mask" "F.Paste")
			(net "PVDDCR_CPU0_P0_PVCC")
		)
		(pad "2" smd circle
			(at 0.40005 0 90)
			(size 0 0)
			(layers "F.Cu" "F.Mask" "F.Paste")
			(net "GND")
		)
	)
	(footprint ""
		(layer "F.Cu")
		(at 157.018228 -23.284942 -90)
		(property "Reference" "R6010"
			(at 0 0 270)
			(layer "F.SilkS")
			(hide yes)
			(effects
				(font
					(size 1.27 1.27)
				)
			)
		)
		(property "Value" ""
			(at 0 0 270)
			(layer "F.Fab")
			(effects
				(font
					(size 1.27 1.27)
				)
			)
		)
		(duplicate_pad_numbers_are_jumpers no)
		(fp_line
			(start -0.7874 0.4064)
			(end -0.7874 -0.4064)
			(stroke
				(width 0.1524)
				(type default)
			)
			(layer "F.SilkS")
		)
		(fp_line
			(start 0.7874 0.4064)
			(end -0.7874 0.4064)
			(stroke
				(width 0.1524)
				(type default)
			)
			(layer "F.SilkS")
		)
		(fp_line
			(start -0.7874 -0.4064)
			(end 0.7874 -0.4064)
			(stroke
				(width 0.1524)
				(type default)
			)
			(layer "F.SilkS")
		)
		(fp_line
			(start 0.7874 -0.4064)
			(end 0.7874 0.4064)
			(stroke
				(width 0.1524)
				(type default)
			)
			(layer "F.SilkS")
		)
		(fp_line
			(start -0.67945 0.3048)
			(end -0.67945 -0.305054)
			(stroke
				(width 0.1)
				(type default)
			)
			(layer "F.Fab")
		)
		(fp_line
			(start -0.12065 0.3048)
			(end -0.67945 0.3048)
			(stroke
				(width 0.1)
				(type default)
			)
			(layer "F.Fab")
		)
		(fp_line
			(start 0.120396 0.3048)
			(end 0.120396 0.2794)
			(stroke
				(width 0.1)
				(type default)
			)
			(layer "F.Fab")
		)
		(fp_line
			(start 0.67945 0.3048)
			(end 0.120396 0.3048)
			(stroke
				(width 0.1)
				(type default)
			)
			(layer "F.Fab")
		)
		(fp_line
			(start -0.12065 0.2794)
			(end -0.12065 0.3048)
			(stroke
				(width 0.1)
				(type default)
			)
			(layer "F.Fab")
		)
		(fp_line
			(start 0.120396 0.2794)
			(end -0.12065 0.2794)
			(stroke
				(width 0.1)
				(type default)
			)
			(layer "F.Fab")
		)
		(fp_line
			(start -0.12065 -0.2794)
			(end 0.12065 -0.2794)
			(stroke
				(width 0.1)
				(type default)
			)
			(layer "F.Fab")
		)
		(fp_line
			(start 0.12065 -0.2794)
			(end 0.12065 -0.3048)
			(stroke
				(width 0.1)
				(type default)
			)
			(layer "F.Fab")
		)
		(fp_line
			(start 0.12065 -0.3048)
			(end 0.67945 -0.3048)
			(stroke
				(width 0.1)
				(type default)
			)
			(layer "F.Fab")
		)
		(fp_line
			(start 0.67945 -0.3048)
			(end 0.67945 0.3048)
			(stroke
				(width 0.1)
				(type default)
			)
			(layer "F.Fab")
		)
		(fp_line
			(start -0.67945 -0.305054)
			(end -0.12065 -0.305054)
			(stroke
				(width 0.1)
				(type default)
			)
			(layer "F.Fab")
		)
		(fp_line
			(start -0.12065 -0.305054)
			(end -0.12065 -0.2794)
			(stroke
				(width 0.1)
				(type default)
			)
			(layer "F.Fab")
		)
		(pad "1" smd circle
			(at -0.40005 0 270)
			(size 0 0)
			(layers "F.Cu" "F.Mask" "F.Paste")
			(net "SGPIO_SCM_DI_<0>")
		)
		(pad "2" smd circle
			(at 0.40005 0 270)
			(size 0 0)
			(layers "F.Cu" "F.Mask" "F.Paste")
			(net "SGPIO_SCM_DI_R_<0>")
		)
	)
	(footprint ""
		(layer "F.Cu")
		(at 157.81274 -44.985686 -90)
		(property "Reference" "R1700"
			(at 0 0 270)
			(layer "F.SilkS")
			(hide yes)
			(effects
				(font
					(size 1.27 1.27)
				)
			)
		)
		(property "Value" ""
			(at 0 0 270)
			(layer "F.Fab")
			(effects
				(font
					(size 1.27 1.27)
				)
			)
		)
		(duplicate_pad_numbers_are_jumpers no)
		(fp_line
			(start -0.7874 0.4064)
			(end -0.7874 -0.4064)
			(stroke
				(width 0.1524)
				(type default)
			)
			(layer "F.SilkS")
		)
		(fp_line
			(start 0.7874 0.4064)
			(end -0.7874 0.4064)
			(stroke
				(width 0.1524)
				(type default)
			)
			(layer "F.SilkS")
		)
		(fp_line
			(start -0.7874 -0.4064)
			(end 0.7874 -0.4064)
			(stroke
				(width 0.1524)
				(type default)
			)
			(layer "F.SilkS")
		)
		(fp_line
			(start 0.7874 -0.4064)
			(end 0.7874 0.4064)
			(stroke
				(width 0.1524)
				(type default)
			)
			(layer "F.SilkS")
		)
		(fp_line
			(start -0.67945 0.3048)
			(end -0.67945 -0.305054)
			(stroke
				(width 0.1)
				(type default)
			)
			(layer "F.Fab")
		)
		(fp_line
			(start -0.12065 0.3048)
			(end -0.67945 0.3048)
			(stroke
				(width 0.1)
				(type default)
			)
			(layer "F.Fab")
		)
		(fp_line
			(start 0.120396 0.3048)
			(end 0.120396 0.2794)
			(stroke
				(width 0.1)
				(type default)
			)
			(layer "F.Fab")
		)
		(fp_line
			(start 0.67945 0.3048)
			(end 0.120396 0.3048)
			(stroke
				(width 0.1)
				(type default)
			)
			(layer "F.Fab")
		)
		(fp_line
			(start -0.12065 0.2794)
			(end -0.12065 0.3048)
			(stroke
				(width 0.1)
				(type default)
			)
			(layer "F.Fab")
		)
		(fp_line
			(start 0.120396 0.2794)
			(end -0.12065 0.2794)
			(stroke
				(width 0.1)
				(type default)
			)
			(layer "F.Fab")
		)
		(fp_line
			(start -0.12065 -0.2794)
			(end 0.12065 -0.2794)
			(stroke
				(width 0.1)
				(type default)
			)
			(layer "F.Fab")
		)
		(fp_line
			(start 0.12065 -0.2794)
			(end 0.12065 -0.3048)
			(stroke
				(width 0.1)
				(type default)
			)
			(layer "F.Fab")
		)
		(fp_line
			(start 0.12065 -0.3048)
			(end 0.67945 -0.3048)
			(stroke
				(width 0.1)
				(type default)
			)
			(layer "F.Fab")
		)
		(fp_line
			(start 0.67945 -0.3048)
			(end 0.67945 0.3048)
			(stroke
				(width 0.1)
				(type default)
			)
			(layer "F.Fab")
		)
		(fp_line
			(start -0.67945 -0.305054)
			(end -0.12065 -0.305054)
			(stroke
				(width 0.1)
				(type default)
			)
			(layer "F.Fab")
		)
		(fp_line
			(start -0.12065 -0.305054)
			(end -0.12065 -0.2794)
			(stroke
				(width 0.1)
				(type default)
			)
			(layer "F.Fab")
		)
		(pad "1" smd circle
			(at -0.40005 0 270)
			(size 0 0)
			(layers "F.Cu" "F.Mask" "F.Paste")
			(net "P3V3_AUX")
		)
		(pad "2" smd circle
			(at 0.40005 0 270)
			(size 0 0)
			(layers "F.Cu" "F.Mask" "F.Paste")
			(net "SMB_PCIE_M2_0_EN")
		)
	)
	(footprint ""
		(layer "F.Cu")
		(at 92.75953 -339.886798 90)
		(property "Reference" "PC422_5"
			(at 0 0 90)
			(layer "F.SilkS")
			(hide yes)
			(effects
				(font
					(size 1.27 1.27)
				)
			)
		)
		(property "Value" ""
			(at 0 0 90)
			(layer "F.Fab")
			(effects
				(font
					(size 1.27 1.27)
				)
			)
		)
		(duplicate_pad_numbers_are_jumpers no)
		(fp_line
			(start 0.7874 -0.4064)
			(end 0.7874 0.4064)
			(stroke
				(width 0.1524)
				(type default)
			)
			(layer "F.SilkS")
		)
		(fp_line
			(start -0.7874 -0.4064)
			(end 0.7874 -0.4064)
			(stroke
				(width 0.1524)
				(type default)
			)
			(layer "F.SilkS")
		)
		(fp_line
			(start 0.7874 0.4064)
			(end -0.7874 0.4064)
			(stroke
				(width 0.1524)
				(type default)
			)
			(layer "F.SilkS")
		)
		(fp_line
			(start -0.7874 0.4064)
			(end -0.7874 -0.4064)
			(stroke
				(width 0.1524)
				(type default)
			)
			(layer "F.SilkS")
		)
		(fp_line
			(start -0.12065 -0.305054)
			(end -0.12065 -0.2794)
			(stroke
				(width 0.1)
				(type default)
			)
			(layer "F.Fab")
		)
		(fp_line
			(start -0.67945 -0.305054)
			(end -0.12065 -0.305054)
			(stroke
				(width 0.1)
				(type default)
			)
			(layer "F.Fab")
		)
		(fp_line
			(start 0.67945 -0.3048)
			(end 0.67945 0.3048)
			(stroke
				(width 0.1)
				(type default)
			)
			(layer "F.Fab")
		)
		(fp_line
			(start 0.12065 -0.3048)
			(end 0.67945 -0.3048)
			(stroke
				(width 0.1)
				(type default)
			)
			(layer "F.Fab")
		)
		(fp_line
			(start 0.12065 -0.2794)
			(end 0.12065 -0.3048)
			(stroke
				(width 0.1)
				(type default)
			)
			(layer "F.Fab")
		)
		(fp_line
			(start -0.12065 -0.2794)
			(end 0.12065 -0.2794)
			(stroke
				(width 0.1)
				(type default)
			)
			(layer "F.Fab")
		)
		(fp_line
			(start 0.120396 0.2794)
			(end -0.12065 0.2794)
			(stroke
				(width 0.1)
				(type default)
			)
			(layer "F.Fab")
		)
		(fp_line
			(start -0.12065 0.2794)
			(end -0.12065 0.3048)
			(stroke
				(width 0.1)
				(type default)
			)
			(layer "F.Fab")
		)
		(fp_line
			(start 0.67945 0.3048)
			(end 0.120396 0.3048)
			(stroke
				(width 0.1)
				(type default)
			)
			(layer "F.Fab")
		)
		(fp_line
			(start 0.120396 0.3048)
			(end 0.120396 0.2794)
			(stroke
				(width 0.1)
				(type default)
			)
			(layer "F.Fab")
		)
		(fp_line
			(start -0.12065 0.3048)
			(end -0.67945 0.3048)
			(stroke
				(width 0.1)
				(type default)
			)
			(layer "F.Fab")
		)
		(fp_line
			(start -0.67945 0.3048)
			(end -0.67945 -0.305054)
			(stroke
				(width 0.1)
				(type default)
			)
			(layer "F.Fab")
		)
		(pad "1" smd circle
			(at -0.40005 0 90)
			(size 0 0)
			(layers "F.Cu" "F.Mask" "F.Paste")
			(net "PVDDCR_CPU1_P1_VCCS")
		)
		(pad "2" smd circle
			(at 0.40005 0 90)
			(size 0 0)
			(layers "F.Cu" "F.Mask" "F.Paste")
			(net "GND")
		)
	)
	(footprint ""
		(layer "F.Cu")
		(at 446.776602 -428.61611 90)
		(property "Reference" "PC6606"
			(at 0 0 90)
			(layer "F.SilkS")
			(hide yes)
			(effects
				(font
					(size 1.27 1.27)
				)
			)
		)
		(property "Value" ""
			(at 0 0 90)
			(layer "F.Fab")
			(effects
				(font
					(size 1.27 1.27)
				)
			)
		)
		(duplicate_pad_numbers_are_jumpers no)
		(fp_line
			(start 0.7874 -0.4064)
			(end 0.7874 0.4064)
			(stroke
				(width 0.1524)
				(type default)
			)
			(layer "F.SilkS")
		)
		(fp_line
			(start -0.7874 -0.4064)
			(end 0.7874 -0.4064)
			(stroke
				(width 0.1524)
				(type default)
			)
			(layer "F.SilkS")
		)
		(fp_line
			(start 0.7874 0.4064)
			(end -0.7874 0.4064)
			(stroke
				(width 0.1524)
				(type default)
			)
			(layer "F.SilkS")
		)
		(fp_line
			(start -0.7874 0.4064)
			(end -0.7874 -0.4064)
			(stroke
				(width 0.1524)
				(type default)
			)
			(layer "F.SilkS")
		)
		(fp_line
			(start -0.12065 -0.305054)
			(end -0.12065 -0.2794)
			(stroke
				(width 0.1)
				(type default)
			)
			(layer "F.Fab")
		)
		(fp_line
			(start -0.67945 -0.305054)
			(end -0.12065 -0.305054)
			(stroke
				(width 0.1)
				(type default)
			)
			(layer "F.Fab")
		)
		(fp_line
			(start 0.67945 -0.3048)
			(end 0.67945 0.3048)
			(stroke
				(width 0.1)
				(type default)
			)
			(layer "F.Fab")
		)
		(fp_line
			(start 0.12065 -0.3048)
			(end 0.67945 -0.3048)
			(stroke
				(width 0.1)
				(type default)
			)
			(layer "F.Fab")
		)
		(fp_line
			(start 0.12065 -0.2794)
			(end 0.12065 -0.3048)
			(stroke
				(width 0.1)
				(type default)
			)
			(layer "F.Fab")
		)
		(fp_line
			(start -0.12065 -0.2794)
			(end 0.12065 -0.2794)
			(stroke
				(width 0.1)
				(type default)
			)
			(layer "F.Fab")
		)
		(fp_line
			(start 0.120396 0.2794)
			(end -0.12065 0.2794)
			(stroke
				(width 0.1)
				(type default)
			)
			(layer "F.Fab")
		)
		(fp_line
			(start -0.12065 0.2794)
			(end -0.12065 0.3048)
			(stroke
				(width 0.1)
				(type default)
			)
			(layer "F.Fab")
		)
		(fp_line
			(start 0.67945 0.3048)
			(end 0.120396 0.3048)
			(stroke
				(width 0.1)
				(type default)
			)
			(layer "F.Fab")
		)
		(fp_line
			(start 0.120396 0.3048)
			(end 0.120396 0.2794)
			(stroke
				(width 0.1)
				(type default)
			)
			(layer "F.Fab")
		)
		(fp_line
			(start -0.12065 0.3048)
			(end -0.67945 0.3048)
			(stroke
				(width 0.1)
				(type default)
			)
			(layer "F.Fab")
		)
		(fp_line
			(start -0.67945 0.3048)
			(end -0.67945 -0.305054)
			(stroke
				(width 0.1)
				(type default)
			)
			(layer "F.Fab")
		)
		(pad "1" smd circle
			(at -0.40005 0 90)
			(size 0 0)
			(layers "F.Cu" "F.Mask" "F.Paste")
			(net "PV09_RETIMER_CPU0_VCCS")
		)
		(pad "2" smd circle
			(at 0.40005 0 90)
			(size 0 0)
			(layers "F.Cu" "F.Mask" "F.Paste")
			(net "GND")
		)
	)
	(footprint ""
		(layer "F.Cu")
		(at 111.251238 -41.17975 -90)
		(property "Reference" "R6294"
			(at 0 0 270)
			(layer "F.SilkS")
			(hide yes)
			(effects
				(font
					(size 1.27 1.27)
				)
			)
		)
		(property "Value" ""
			(at 0 0 270)
			(layer "F.Fab")
			(effects
				(font
					(size 1.27 1.27)
				)
			)
		)
		(duplicate_pad_numbers_are_jumpers no)
		(fp_line
			(start -0.7874 0.4064)
			(end -0.7874 -0.4064)
			(stroke
				(width 0.1524)
				(type default)
			)
			(layer "F.SilkS")
		)
		(fp_line
			(start 0.7874 0.4064)
			(end -0.7874 0.4064)
			(stroke
				(width 0.1524)
				(type default)
			)
			(layer "F.SilkS")
		)
		(fp_line
			(start -0.7874 -0.4064)
			(end 0.7874 -0.4064)
			(stroke
				(width 0.1524)
				(type default)
			)
			(layer "F.SilkS")
		)
		(fp_line
			(start 0.7874 -0.4064)
			(end 0.7874 0.4064)
			(stroke
				(width 0.1524)
				(type default)
			)
			(layer "F.SilkS")
		)
		(fp_line
			(start -0.67945 0.3048)
			(end -0.67945 -0.305054)
			(stroke
				(width 0.1)
				(type default)
			)
			(layer "F.Fab")
		)
		(fp_line
			(start -0.12065 0.3048)
			(end -0.67945 0.3048)
			(stroke
				(width 0.1)
				(type default)
			)
			(layer "F.Fab")
		)
		(fp_line
			(start 0.120396 0.3048)
			(end 0.120396 0.2794)
			(stroke
				(width 0.1)
				(type default)
			)
			(layer "F.Fab")
		)
		(fp_line
			(start 0.67945 0.3048)
			(end 0.120396 0.3048)
			(stroke
				(width 0.1)
				(type default)
			)
			(layer "F.Fab")
		)
		(fp_line
			(start -0.12065 0.2794)
			(end -0.12065 0.3048)
			(stroke
				(width 0.1)
				(type default)
			)
			(layer "F.Fab")
		)
		(fp_line
			(start 0.120396 0.2794)
			(end -0.12065 0.2794)
			(stroke
				(width 0.1)
				(type default)
			)
			(layer "F.Fab")
		)
		(fp_line
			(start -0.12065 -0.2794)
			(end 0.12065 -0.2794)
			(stroke
				(width 0.1)
				(type default)
			)
			(layer "F.Fab")
		)
		(fp_line
			(start 0.12065 -0.2794)
			(end 0.12065 -0.3048)
			(stroke
				(width 0.1)
				(type default)
			)
			(layer "F.Fab")
		)
		(fp_line
			(start 0.12065 -0.3048)
			(end 0.67945 -0.3048)
			(stroke
				(width 0.1)
				(type default)
			)
			(layer "F.Fab")
		)
		(fp_line
			(start 0.67945 -0.3048)
			(end 0.67945 0.3048)
			(stroke
				(width 0.1)
				(type default)
			)
			(layer "F.Fab")
		)
		(fp_line
			(start -0.67945 -0.305054)
			(end -0.12065 -0.305054)
			(stroke
				(width 0.1)
				(type default)
			)
			(layer "F.Fab")
		)
		(fp_line
			(start -0.12065 -0.305054)
			(end -0.12065 -0.2794)
			(stroke
				(width 0.1)
				(type default)
			)
			(layer "F.Fab")
		)
		(pad "1" smd circle
			(at -0.40005 0 270)
			(size 0 0)
			(layers "F.Cu" "F.Mask" "F.Paste")
			(net "P3V3_AUX")
		)
		(pad "2" smd circle
			(at 0.40005 0 270)
			(size 0 0)
			(layers "F.Cu" "F.Mask" "F.Paste")
			(net "USB_HUB2_MRP_I2C_SLV_CFG0")
		)
	)
	(footprint ""
		(layer "F.Cu")
		(at 272.507202 -363.010704)
		(property "Reference" "JP6500"
			(at -1.4097 -2.009648 0)
			(unlocked yes)
			(layer "F.SilkS")
			(effects
				(font
					(size 0.7874 0.5842)
					(thickness 0.1524)
				)
				(justify left)
			)
		)
		(property "Value" ""
			(at 0 0 0)
			(layer "F.Fab")
			(effects
				(font
					(size 1.27 1.27)
				)
			)
		)
		(duplicate_pad_numbers_are_jumpers no)
		(fp_line
			(start -1.249934 -1.320038)
			(end 1.249934 -1.320038)
			(stroke
				(width 0.1524)
				(type default)
			)
			(layer "F.SilkS")
		)
		(fp_line
			(start -1.249934 6.400038)
			(end -1.249934 -1.320038)
			(stroke
				(width 0.1524)
				(type default)
			)
			(layer "F.SilkS")
		)
		(fp_line
			(start 1.249934 -1.320038)
			(end 1.249934 6.400038)
			(stroke
				(width 0.1524)
				(type default)
			)
			(layer "F.SilkS")
		)
		(fp_line
			(start 1.249934 6.400038)
			(end -1.249934 6.400038)
			(stroke
				(width 0.1524)
				(type default)
			)
			(layer "F.SilkS")
		)
		(fp_poly
			(pts
				(xy -2.5654 -0.556514) (xy -1.452372 0) (xy -2.5654 0.556514)
			)
			(stroke
				(width 0)
				(type default)
			)
			(fill yes)
			(layer "F.SilkS")
		)
		(fp_line
			(start -1.249934 -1.320038)
			(end 1.249934 -1.320038)
			(stroke
				(width 0.1)
				(type default)
			)
			(layer "F.Fab")
		)
		(fp_line
			(start -1.249934 6.400038)
			(end -1.249934 -1.320038)
			(stroke
				(width 0.1)
				(type default)
			)
			(layer "F.Fab")
		)
		(fp_line
			(start 1.249934 -1.320038)
			(end 1.249934 6.400038)
			(stroke
				(width 0.1)
				(type default)
			)
			(layer "F.Fab")
		)
		(fp_line
			(start 1.249934 6.400038)
			(end -1.249934 6.400038)
			(stroke
				(width 0.1)
				(type default)
			)
			(layer "F.Fab")
		)
		(fp_poly
			(pts
				(xy -2.5654 -0.556514) (xy -1.452372 0) (xy -2.5654 0.556514)
			)
			(stroke
				(width 0)
				(type default)
			)
			(fill yes)
			(layer "F.Fab")
		)
		(fp_text user "3"
			(at -1.778 5.13207 0)
			(unlocked yes)
			(layer "F.SilkS")
			(effects
				(font
					(size 0.7874 0.5842)
					(thickness 0.1524)
				)
			)
		)
		(fp_text user "3"
			(at -1.1557 5.18287 0)
			(unlocked yes)
			(layer "B.SilkS")
			(effects
				(font
					(size 0.7874 0.5842)
					(thickness 0.1524)
				)
				(justify mirror)
			)
		)
		(fp_text user "1"
			(at -1.143 0.02667 0)
			(unlocked yes)
			(layer "B.SilkS")
			(effects
				(font
					(size 0.7874 0.5842)
					(thickness 0.1524)
				)
				(justify mirror)
			)
		)
		(fp_text user "3"
			(at -1.1557 5.18287 0)
			(unlocked yes)
			(layer "B.Fab")
			(effects
				(font
					(size 0.7874 0.5842)
					(thickness 0.1524)
				)
				(justify mirror)
			)
		)
		(fp_text user "1"
			(at -1.143 0.02667 0)
			(unlocked yes)
			(layer "B.Fab")
			(effects
				(font
					(size 0.7874 0.5842)
					(thickness 0.1524)
				)
				(justify mirror)
			)
		)
		(fp_text user "3"
			(at -1.778 5.13207 0)
			(unlocked yes)
			(layer "F.Fab")
			(effects
				(font
					(size 0.7874 0.5842)
					(thickness 0.1524)
				)
			)
		)
		(pad "1" thru_hole rect
			(at 0 0)
			(size 1.5494 1.5494)
			(drill 1.0414)
			(layers "*.Cu" "*.Mask")
			(remove_unused_layers no)
			(net "SMB_MUX_RT_R2_SCL")
			(clearance 0)
			(padstack
				(mode front_inner_back)
				(layer "Inner"
					(shape circle)
					(size 1.5494 1.5494)
					(clearance 0)
				)
				(layer "B.Cu"
					(shape rect)
					(size 1.5494 1.5494)
					(clearance 0)
				)
			)
		)
		(pad "2" thru_hole circle
			(at 0 2.54)
			(size 1.5494 1.5494)
			(drill 1.0414)
			(layers "*.Cu" "*.Mask")
			(remove_unused_layers no)
			(net "SMB_MUX_RT_R2_SDA")
			(clearance 0)
		)
		(pad "3" thru_hole circle
			(at 0 5.08)
			(size 1.5494 1.5494)
			(drill 1.0414)
			(layers "*.Cu" "*.Mask")
			(remove_unused_layers no)
			(net "GND")
			(clearance 0)
		)
	)
	(footprint ""
		(layer "F.Cu")
		(at 358.268524 -388.767828)
		(property "Reference" "C934"
			(at 0 0 0)
			(layer "F.SilkS")
			(hide yes)
			(effects
				(font
					(size 1.27 1.27)
				)
			)
		)
		(property "Value" ""
			(at 0 0 0)
			(layer "F.Fab")
			(effects
				(font
					(size 1.27 1.27)
				)
			)
		)
		(duplicate_pad_numbers_are_jumpers no)
		(fp_line
			(start -0.299974 -0.150114)
			(end 0.299974 -0.150114)
			(stroke
				(width 0.1)
				(type default)
			)
			(layer "F.Fab")
		)
		(fp_line
			(start -0.299974 0.150114)
			(end -0.299974 -0.150114)
			(stroke
				(width 0.1)
				(type default)
			)
			(layer "F.Fab")
		)
		(fp_line
			(start 0.299974 -0.150114)
			(end 0.299974 0.150114)
			(stroke
				(width 0.1)
				(type default)
			)
			(layer "F.Fab")
		)
		(fp_line
			(start 0.299974 0.150114)
			(end -0.299974 0.150114)
			(stroke
				(width 0.1)
				(type default)
			)
			(layer "F.Fab")
		)
		(pad "1" smd rect
			(at -0.2667 0)
			(size 0.3048 0.381)
			(layers "F.Cu" "F.Mask" "F.Paste")
			(net "P5E_CPU0_P1_TX_C_DN<15>")
		)
		(pad "2" smd rect
			(at 0.2667 0)
			(size 0.3048 0.381)
			(layers "F.Cu" "F.Mask" "F.Paste")
			(net "P5E_CPU0_P1_TX_DN<15>")
		)
	)
	(footprint ""
		(layer "F.Cu")
		(at 310.809386 -416.899344 -90)
		(property "Reference" "C6505"
			(at 0 0 270)
			(layer "F.SilkS")
			(hide yes)
			(effects
				(font
					(size 1.27 1.27)
				)
			)
		)
		(property "Value" ""
			(at 0 0 270)
			(layer "F.Fab")
			(effects
				(font
					(size 1.27 1.27)
				)
			)
		)
		(duplicate_pad_numbers_are_jumpers no)
		(fp_line
			(start -0.299974 0.150114)
			(end -0.299974 -0.150114)
			(stroke
				(width 0.1)
				(type default)
			)
			(layer "F.Fab")
		)
		(fp_line
			(start 0.299974 0.150114)
			(end -0.299974 0.150114)
			(stroke
				(width 0.1)
				(type default)
			)
			(layer "F.Fab")
		)
		(fp_line
			(start -0.299974 -0.150114)
			(end 0.299974 -0.150114)
			(stroke
				(width 0.1)
				(type default)
			)
			(layer "F.Fab")
		)
		(fp_line
			(start 0.299974 -0.150114)
			(end 0.299974 0.150114)
			(stroke
				(width 0.1)
				(type default)
			)
			(layer "F.Fab")
		)
		(pad "1" smd rect
			(at -0.2667 0 270)
			(size 0.3048 0.381)
			(layers "F.Cu" "F.Mask" "F.Paste")
			(net "P5E_CPU0_P0_TX_BUF_C_DP<2>")
		)
		(pad "2" smd rect
			(at 0.2667 0 270)
			(size 0.3048 0.381)
			(layers "F.Cu" "F.Mask" "F.Paste")
			(net "P5E_CPU0_P0_TX_BUF_DP<2>")
		)
	)
	(footprint ""
		(layer "F.Cu")
		(at 283.265118 -426.20565 -90)
		(property "Reference" "R4493"
			(at 0 0 270)
			(layer "F.SilkS")
			(hide yes)
			(effects
				(font
					(size 1.27 1.27)
				)
			)
		)
		(property "Value" ""
			(at 0 0 270)
			(layer "F.Fab")
			(effects
				(font
					(size 1.27 1.27)
				)
			)
		)
		(duplicate_pad_numbers_are_jumpers no)
		(fp_line
			(start -1.2954 0.5842)
			(end -1.2954 -0.5842)
			(stroke
				(width 0.1524)
				(type default)
			)
			(layer "F.SilkS")
		)
		(fp_line
			(start 1.2954 0.5842)
			(end -1.2954 0.5842)
			(stroke
				(width 0.1524)
				(type default)
			)
			(layer "F.SilkS")
		)
		(fp_line
			(start -1.2954 -0.5842)
			(end 1.2954 -0.5842)
			(stroke
				(width 0.1524)
				(type default)
			)
			(layer "F.SilkS")
		)
		(fp_line
			(start 1.2954 -0.5842)
			(end 1.2954 0.5842)
			(stroke
				(width 0.1524)
				(type default)
			)
			(layer "F.SilkS")
		)
		(fp_line
			(start -0.8636 0.4572)
			(end -0.8636 0.4318)
			(stroke
				(width 0.1)
				(type default)
			)
			(layer "F.Fab")
		)
		(fp_line
			(start 0.8636 0.4572)
			(end -0.8636 0.4572)
			(stroke
				(width 0.1)
				(type default)
			)
			(layer "F.Fab")
		)
		(fp_line
			(start -0.8636 0.4318)
			(end -0.8636 0.4064)
			(stroke
				(width 0.1)
				(type default)
			)
			(layer "F.Fab")
		)
		(fp_line
			(start -1.1938 0.4064)
			(end -1.1938 -0.406654)
			(stroke
				(width 0.1)
				(type default)
			)
			(layer "F.Fab")
		)
		(fp_line
			(start -0.8636 0.4064)
			(end -1.1938 0.4064)
			(stroke
				(width 0.1)
				(type default)
			)
			(layer "F.Fab")
		)
		(fp_line
			(start 0.8636 0.4064)
			(end 0.8636 0.4572)
			(stroke
				(width 0.1)
				(type default)
			)
			(layer "F.Fab")
		)
		(fp_line
			(start 1.1938 0.4064)
			(end 0.8636 0.4064)
			(stroke
				(width 0.1)
				(type default)
			)
			(layer "F.Fab")
		)
		(fp_line
			(start -1.1938 -0.406654)
			(end -0.8636 -0.406654)
			(stroke
				(width 0.1)
				(type default)
			)
			(layer "F.Fab")
		)
		(fp_line
			(start -0.8636 -0.406654)
			(end -0.8636 -0.4572)
			(stroke
				(width 0.1)
				(type default)
			)
			(layer "F.Fab")
		)
		(fp_line
			(start 0.8636 -0.406654)
			(end 1.1938 -0.406654)
			(stroke
				(width 0.1)
				(type default)
			)
			(layer "F.Fab")
		)
		(fp_line
			(start 1.1938 -0.406654)
			(end 1.1938 0.4064)
			(stroke
				(width 0.1)
				(type default)
			)
			(layer "F.Fab")
		)
		(fp_line
			(start -0.8636 -0.4572)
			(end 0.8636 -0.4572)
			(stroke
				(width 0.1)
				(type default)
			)
			(layer "F.Fab")
		)
		(fp_line
			(start 0.8636 -0.4572)
			(end 0.8636 -0.406654)
			(stroke
				(width 0.1)
				(type default)
			)
			(layer "F.Fab")
		)
		(pad "1" smd rect
			(at -0.7366 0 180)
			(size 0.7112 0.8128)
			(layers "F.Cu" "F.Mask" "F.Paste")
			(net "P3V3_9ZXL045_P0")
		)
		(pad "2" smd rect
			(at 0.7366 0 180)
			(size 0.7112 0.8128)
			(layers "F.Cu" "F.Mask" "F.Paste")
			(net "P3V3_9ZXL045_P0_VDDA")
		)
	)
	(footprint ""
		(layer "F.Cu")
		(at 332.25994 -15.979394 -90)
		(property "Reference" "R1266"
			(at 0 0 270)
			(layer "F.SilkS")
			(hide yes)
			(effects
				(font
					(size 1.27 1.27)
				)
			)
		)
		(property "Value" ""
			(at 0 0 270)
			(layer "F.Fab")
			(effects
				(font
					(size 1.27 1.27)
				)
			)
		)
		(duplicate_pad_numbers_are_jumpers no)
		(fp_line
			(start -0.7874 0.4064)
			(end -0.7874 -0.4064)
			(stroke
				(width 0.1524)
				(type default)
			)
			(layer "F.SilkS")
		)
		(fp_line
			(start 0.7874 0.4064)
			(end -0.7874 0.4064)
			(stroke
				(width 0.1524)
				(type default)
			)
			(layer "F.SilkS")
		)
		(fp_line
			(start -0.7874 -0.4064)
			(end 0.7874 -0.4064)
			(stroke
				(width 0.1524)
				(type default)
			)
			(layer "F.SilkS")
		)
		(fp_line
			(start 0.7874 -0.4064)
			(end 0.7874 0.4064)
			(stroke
				(width 0.1524)
				(type default)
			)
			(layer "F.SilkS")
		)
		(fp_line
			(start -0.67945 0.3048)
			(end -0.67945 -0.305054)
			(stroke
				(width 0.1)
				(type default)
			)
			(layer "F.Fab")
		)
		(fp_line
			(start -0.12065 0.3048)
			(end -0.67945 0.3048)
			(stroke
				(width 0.1)
				(type default)
			)
			(layer "F.Fab")
		)
		(fp_line
			(start 0.120396 0.3048)
			(end 0.120396 0.2794)
			(stroke
				(width 0.1)
				(type default)
			)
			(layer "F.Fab")
		)
		(fp_line
			(start 0.67945 0.3048)
			(end 0.120396 0.3048)
			(stroke
				(width 0.1)
				(type default)
			)
			(layer "F.Fab")
		)
		(fp_line
			(start -0.12065 0.2794)
			(end -0.12065 0.3048)
			(stroke
				(width 0.1)
				(type default)
			)
			(layer "F.Fab")
		)
		(fp_line
			(start 0.120396 0.2794)
			(end -0.12065 0.2794)
			(stroke
				(width 0.1)
				(type default)
			)
			(layer "F.Fab")
		)
		(fp_line
			(start -0.12065 -0.2794)
			(end 0.12065 -0.2794)
			(stroke
				(width 0.1)
				(type default)
			)
			(layer "F.Fab")
		)
		(fp_line
			(start 0.12065 -0.2794)
			(end 0.12065 -0.3048)
			(stroke
				(width 0.1)
				(type default)
			)
			(layer "F.Fab")
		)
		(fp_line
			(start 0.12065 -0.3048)
			(end 0.67945 -0.3048)
			(stroke
				(width 0.1)
				(type default)
			)
			(layer "F.Fab")
		)
		(fp_line
			(start 0.67945 -0.3048)
			(end 0.67945 0.3048)
			(stroke
				(width 0.1)
				(type default)
			)
			(layer "F.Fab")
		)
		(fp_line
			(start -0.67945 -0.305054)
			(end -0.12065 -0.305054)
			(stroke
				(width 0.1)
				(type default)
			)
			(layer "F.Fab")
		)
		(fp_line
			(start -0.12065 -0.305054)
			(end -0.12065 -0.2794)
			(stroke
				(width 0.1)
				(type default)
			)
			(layer "F.Fab")
		)
		(pad "1" smd circle
			(at -0.40005 0 270)
			(size 0 0)
			(layers "F.Cu" "F.Mask" "F.Paste")
			(net "P3V3_AUX")
		)
		(pad "2" smd circle
			(at 0.40005 0 270)
			(size 0 0)
			(layers "F.Cu" "F.Mask" "F.Paste")
			(net "BMC_FPGA_LED1_R_N")
		)
	)
	(footprint ""
		(layer "F.Cu")
		(at 127.761492 -156.441902 90)
		(property "Reference" "PC348_3"
			(at 0 0 90)
			(layer "F.SilkS")
			(hide yes)
			(effects
				(font
					(size 1.27 1.27)
				)
			)
		)
		(property "Value" ""
			(at 0 0 90)
			(layer "F.Fab")
			(effects
				(font
					(size 1.27 1.27)
				)
			)
		)
		(duplicate_pad_numbers_are_jumpers no)
		(fp_line
			(start 0.7874 -0.4064)
			(end 0.7874 0.4064)
			(stroke
				(width 0.1524)
				(type default)
			)
			(layer "F.SilkS")
		)
		(fp_line
			(start -0.7874 -0.4064)
			(end 0.7874 -0.4064)
			(stroke
				(width 0.1524)
				(type default)
			)
			(layer "F.SilkS")
		)
		(fp_line
			(start 0.7874 0.4064)
			(end -0.7874 0.4064)
			(stroke
				(width 0.1524)
				(type default)
			)
			(layer "F.SilkS")
		)
		(fp_line
			(start -0.7874 0.4064)
			(end -0.7874 -0.4064)
			(stroke
				(width 0.1524)
				(type default)
			)
			(layer "F.SilkS")
		)
		(fp_line
			(start -0.12065 -0.305054)
			(end -0.12065 -0.2794)
			(stroke
				(width 0.1)
				(type default)
			)
			(layer "F.Fab")
		)
		(fp_line
			(start -0.67945 -0.305054)
			(end -0.12065 -0.305054)
			(stroke
				(width 0.1)
				(type default)
			)
			(layer "F.Fab")
		)
		(fp_line
			(start 0.67945 -0.3048)
			(end 0.67945 0.3048)
			(stroke
				(width 0.1)
				(type default)
			)
			(layer "F.Fab")
		)
		(fp_line
			(start 0.12065 -0.3048)
			(end 0.67945 -0.3048)
			(stroke
				(width 0.1)
				(type default)
			)
			(layer "F.Fab")
		)
		(fp_line
			(start 0.12065 -0.2794)
			(end 0.12065 -0.3048)
			(stroke
				(width 0.1)
				(type default)
			)
			(layer "F.Fab")
		)
		(fp_line
			(start -0.12065 -0.2794)
			(end 0.12065 -0.2794)
			(stroke
				(width 0.1)
				(type default)
			)
			(layer "F.Fab")
		)
		(fp_line
			(start 0.120396 0.2794)
			(end -0.12065 0.2794)
			(stroke
				(width 0.1)
				(type default)
			)
			(layer "F.Fab")
		)
		(fp_line
			(start -0.12065 0.2794)
			(end -0.12065 0.3048)
			(stroke
				(width 0.1)
				(type default)
			)
			(layer "F.Fab")
		)
		(fp_line
			(start 0.67945 0.3048)
			(end 0.120396 0.3048)
			(stroke
				(width 0.1)
				(type default)
			)
			(layer "F.Fab")
		)
		(fp_line
			(start 0.120396 0.3048)
			(end 0.120396 0.2794)
			(stroke
				(width 0.1)
				(type default)
			)
			(layer "F.Fab")
		)
		(fp_line
			(start -0.12065 0.3048)
			(end -0.67945 0.3048)
			(stroke
				(width 0.1)
				(type default)
			)
			(layer "F.Fab")
		)
		(fp_line
			(start -0.67945 0.3048)
			(end -0.67945 -0.305054)
			(stroke
				(width 0.1)
				(type default)
			)
			(layer "F.Fab")
		)
		(pad "1" smd circle
			(at -0.40005 0 90)
			(size 0 0)
			(layers "F.Cu" "F.Mask" "F.Paste")
			(net "SW_P12V_AUX_PVDDCR_SOC_P1_FLT")
		)
		(pad "2" smd circle
			(at 0.40005 0 90)
			(size 0 0)
			(layers "F.Cu" "F.Mask" "F.Paste")
			(net "GND")
		)
	)
	(footprint ""
		(layer "F.Cu")
		(at 138.143234 -79.288894 90)
		(property "Reference" "PC6012"
			(at 0 0 90)
			(layer "F.SilkS")
			(hide yes)
			(effects
				(font
					(size 1.27 1.27)
				)
			)
		)
		(property "Value" ""
			(at 0 0 90)
			(layer "F.Fab")
			(effects
				(font
					(size 1.27 1.27)
				)
			)
		)
		(duplicate_pad_numbers_are_jumpers no)
		(fp_line
			(start 1.524 -0.762)
			(end 1.524 0.762)
			(stroke
				(width 0.1524)
				(type default)
			)
			(layer "F.SilkS")
		)
		(fp_line
			(start -1.524 -0.762)
			(end 1.524 -0.762)
			(stroke
				(width 0.1524)
				(type default)
			)
			(layer "F.SilkS")
		)
		(fp_line
			(start 1.524 0.762)
			(end -1.524 0.762)
			(stroke
				(width 0.1524)
				(type default)
			)
			(layer "F.SilkS")
		)
		(fp_line
			(start -1.524 0.762)
			(end -1.524 -0.762)
			(stroke
				(width 0.1524)
				(type default)
			)
			(layer "F.SilkS")
		)
		(fp_line
			(start 1.1049 -0.724916)
			(end -1.1049 -0.724916)
			(stroke
				(width 0.1)
				(type default)
			)
			(layer "F.Fab")
		)
		(fp_line
			(start -1.1049 -0.724916)
			(end -1.1049 0.724916)
			(stroke
				(width 0.1)
				(type default)
			)
			(layer "F.Fab")
		)
		(fp_line
			(start 1.1049 0.724916)
			(end 1.1049 -0.724916)
			(stroke
				(width 0.1)
				(type default)
			)
			(layer "F.Fab")
		)
		(fp_line
			(start -1.1049 0.724916)
			(end 1.1049 0.724916)
			(stroke
				(width 0.1)
				(type default)
			)
			(layer "F.Fab")
		)
		(pad "1" smd rect
			(at -0.889 0 270)
			(size 1.016 1.27)
			(layers "F.Cu" "F.Mask" "F.Paste")
			(net "SW_P12V_AUX_P1V8_AUX_FLT")
		)
		(pad "2" smd rect
			(at 0.889 0 270)
			(size 1.016 1.27)
			(layers "F.Cu" "F.Mask" "F.Paste")
			(net "GND")
		)
	)
	(footprint ""
		(layer "F.Cu")
		(at 154.277822 -66.04254 180)
		(property "Reference" "C20"
			(at 0 0 180)
			(layer "F.SilkS")
			(hide yes)
			(effects
				(font
					(size 1.27 1.27)
				)
			)
		)
		(property "Value" ""
			(at 0 0 180)
			(layer "F.Fab")
			(effects
				(font
					(size 1.27 1.27)
				)
			)
		)
		(duplicate_pad_numbers_are_jumpers no)
		(fp_line
			(start 0.7874 0.4064)
			(end -0.7874 0.4064)
			(stroke
				(width 0.1524)
				(type default)
			)
			(layer "F.SilkS")
		)
		(fp_line
			(start 0.7874 -0.4064)
			(end 0.7874 0.4064)
			(stroke
				(width 0.1524)
				(type default)
			)
			(layer "F.SilkS")
		)
		(fp_line
			(start -0.7874 0.4064)
			(end -0.7874 -0.4064)
			(stroke
				(width 0.1524)
				(type default)
			)
			(layer "F.SilkS")
		)
		(fp_line
			(start -0.7874 -0.4064)
			(end 0.7874 -0.4064)
			(stroke
				(width 0.1524)
				(type default)
			)
			(layer "F.SilkS")
		)
		(fp_line
			(start 0.67945 0.3048)
			(end 0.120396 0.3048)
			(stroke
				(width 0.1)
				(type default)
			)
			(layer "F.Fab")
		)
		(fp_line
			(start 0.67945 -0.3048)
			(end 0.67945 0.3048)
			(stroke
				(width 0.1)
				(type default)
			)
			(layer "F.Fab")
		)
		(fp_line
			(start 0.12065 -0.2794)
			(end 0.12065 -0.3048)
			(stroke
				(width 0.1)
				(type default)
			)
			(layer "F.Fab")
		)
		(fp_line
			(start 0.12065 -0.3048)
			(end 0.67945 -0.3048)
			(stroke
				(width 0.1)
				(type default)
			)
			(layer "F.Fab")
		)
		(fp_line
			(start 0.120396 0.3048)
			(end 0.120396 0.2794)
			(stroke
				(width 0.1)
				(type default)
			)
			(layer "F.Fab")
		)
		(fp_line
			(start 0.120396 0.2794)
			(end -0.12065 0.2794)
			(stroke
				(width 0.1)
				(type default)
			)
			(layer "F.Fab")
		)
		(fp_line
			(start -0.12065 0.3048)
			(end -0.67945 0.3048)
			(stroke
				(width 0.1)
				(type default)
			)
			(layer "F.Fab")
		)
		(fp_line
			(start -0.12065 0.2794)
			(end -0.12065 0.3048)
			(stroke
				(width 0.1)
				(type default)
			)
			(layer "F.Fab")
		)
		(fp_line
			(start -0.12065 -0.2794)
			(end 0.12065 -0.2794)
			(stroke
				(width 0.1)
				(type default)
			)
			(layer "F.Fab")
		)
		(fp_line
			(start -0.12065 -0.305054)
			(end -0.12065 -0.2794)
			(stroke
				(width 0.1)
				(type default)
			)
			(layer "F.Fab")
		)
		(fp_line
			(start -0.67945 0.3048)
			(end -0.67945 -0.305054)
			(stroke
				(width 0.1)
				(type default)
			)
			(layer "F.Fab")
		)
		(fp_line
			(start -0.67945 -0.305054)
			(end -0.12065 -0.305054)
			(stroke
				(width 0.1)
				(type default)
			)
			(layer "F.Fab")
		)
		(pad "1" smd circle
			(at -0.40005 0 180)
			(size 0 0)
			(layers "F.Cu" "F.Mask" "F.Paste")
			(net "P3V3_AUX")
		)
		(pad "2" smd circle
			(at 0.40005 0 180)
			(size 0 0)
			(layers "F.Cu" "F.Mask" "F.Paste")
			(net "GND")
		)
	)
	(footprint ""
		(layer "F.Cu")
		(at 317.896748 -116.378228 180)
		(property "Reference" "R85"
			(at 0 0 180)
			(layer "F.SilkS")
			(hide yes)
			(effects
				(font
					(size 1.27 1.27)
				)
			)
		)
		(property "Value" ""
			(at 0 0 180)
			(layer "F.Fab")
			(effects
				(font
					(size 1.27 1.27)
				)
			)
		)
		(duplicate_pad_numbers_are_jumpers no)
		(fp_line
			(start 0.7874 0.4064)
			(end -0.7874 0.4064)
			(stroke
				(width 0.1524)
				(type default)
			)
			(layer "F.SilkS")
		)
		(fp_line
			(start 0.7874 -0.4064)
			(end 0.7874 0.4064)
			(stroke
				(width 0.1524)
				(type default)
			)
			(layer "F.SilkS")
		)
		(fp_line
			(start -0.7874 0.4064)
			(end -0.7874 -0.4064)
			(stroke
				(width 0.1524)
				(type default)
			)
			(layer "F.SilkS")
		)
		(fp_line
			(start -0.7874 -0.4064)
			(end 0.7874 -0.4064)
			(stroke
				(width 0.1524)
				(type default)
			)
			(layer "F.SilkS")
		)
		(fp_line
			(start 0.67945 0.3048)
			(end 0.120396 0.3048)
			(stroke
				(width 0.1)
				(type default)
			)
			(layer "F.Fab")
		)
		(fp_line
			(start 0.67945 -0.3048)
			(end 0.67945 0.3048)
			(stroke
				(width 0.1)
				(type default)
			)
			(layer "F.Fab")
		)
		(fp_line
			(start 0.12065 -0.2794)
			(end 0.12065 -0.3048)
			(stroke
				(width 0.1)
				(type default)
			)
			(layer "F.Fab")
		)
		(fp_line
			(start 0.12065 -0.3048)
			(end 0.67945 -0.3048)
			(stroke
				(width 0.1)
				(type default)
			)
			(layer "F.Fab")
		)
		(fp_line
			(start 0.120396 0.3048)
			(end 0.120396 0.2794)
			(stroke
				(width 0.1)
				(type default)
			)
			(layer "F.Fab")
		)
		(fp_line
			(start 0.120396 0.2794)
			(end -0.12065 0.2794)
			(stroke
				(width 0.1)
				(type default)
			)
			(layer "F.Fab")
		)
		(fp_line
			(start -0.12065 0.3048)
			(end -0.67945 0.3048)
			(stroke
				(width 0.1)
				(type default)
			)
			(layer "F.Fab")
		)
		(fp_line
			(start -0.12065 0.2794)
			(end -0.12065 0.3048)
			(stroke
				(width 0.1)
				(type default)
			)
			(layer "F.Fab")
		)
		(fp_line
			(start -0.12065 -0.2794)
			(end 0.12065 -0.2794)
			(stroke
				(width 0.1)
				(type default)
			)
			(layer "F.Fab")
		)
		(fp_line
			(start -0.12065 -0.305054)
			(end -0.12065 -0.2794)
			(stroke
				(width 0.1)
				(type default)
			)
			(layer "F.Fab")
		)
		(fp_line
			(start -0.67945 0.3048)
			(end -0.67945 -0.305054)
			(stroke
				(width 0.1)
				(type default)
			)
			(layer "F.Fab")
		)
		(fp_line
			(start -0.67945 -0.305054)
			(end -0.12065 -0.305054)
			(stroke
				(width 0.1)
				(type default)
			)
			(layer "F.Fab")
		)
		(pad "1" smd circle
			(at -0.40005 0 180)
			(size 0 0)
			(layers "F.Cu" "F.Mask" "F.Paste")
			(net "SMB_FRU_3V3AUX_SCL")
		)
		(pad "2" smd circle
			(at 0.40005 0 180)
			(size 0 0)
			(layers "F.Cu" "F.Mask" "F.Paste")
			(net "SMB_FRU_3V3AUX_R1_SCL")
		)
	)
	(footprint ""
		(layer "F.Cu")
		(at 107.895136 -127.748538 -90)
		(property "Reference" "R1493"
			(at 0 0 270)
			(layer "F.SilkS")
			(hide yes)
			(effects
				(font
					(size 1.27 1.27)
				)
			)
		)
		(property "Value" ""
			(at 0 0 270)
			(layer "F.Fab")
			(effects
				(font
					(size 1.27 1.27)
				)
			)
		)
		(duplicate_pad_numbers_are_jumpers no)
		(fp_line
			(start -0.7874 0.4064)
			(end -0.7874 -0.4064)
			(stroke
				(width 0.1524)
				(type default)
			)
			(layer "F.SilkS")
		)
		(fp_line
			(start 0.7874 0.4064)
			(end -0.7874 0.4064)
			(stroke
				(width 0.1524)
				(type default)
			)
			(layer "F.SilkS")
		)
		(fp_line
			(start -0.7874 -0.4064)
			(end 0.7874 -0.4064)
			(stroke
				(width 0.1524)
				(type default)
			)
			(layer "F.SilkS")
		)
		(fp_line
			(start 0.7874 -0.4064)
			(end 0.7874 0.4064)
			(stroke
				(width 0.1524)
				(type default)
			)
			(layer "F.SilkS")
		)
		(fp_line
			(start -0.67945 0.3048)
			(end -0.67945 -0.305054)
			(stroke
				(width 0.1)
				(type default)
			)
			(layer "F.Fab")
		)
		(fp_line
			(start -0.12065 0.3048)
			(end -0.67945 0.3048)
			(stroke
				(width 0.1)
				(type default)
			)
			(layer "F.Fab")
		)
		(fp_line
			(start 0.120396 0.3048)
			(end 0.120396 0.2794)
			(stroke
				(width 0.1)
				(type default)
			)
			(layer "F.Fab")
		)
		(fp_line
			(start 0.67945 0.3048)
			(end 0.120396 0.3048)
			(stroke
				(width 0.1)
				(type default)
			)
			(layer "F.Fab")
		)
		(fp_line
			(start -0.12065 0.2794)
			(end -0.12065 0.3048)
			(stroke
				(width 0.1)
				(type default)
			)
			(layer "F.Fab")
		)
		(fp_line
			(start 0.120396 0.2794)
			(end -0.12065 0.2794)
			(stroke
				(width 0.1)
				(type default)
			)
			(layer "F.Fab")
		)
		(fp_line
			(start -0.12065 -0.2794)
			(end 0.12065 -0.2794)
			(stroke
				(width 0.1)
				(type default)
			)
			(layer "F.Fab")
		)
		(fp_line
			(start 0.12065 -0.2794)
			(end 0.12065 -0.3048)
			(stroke
				(width 0.1)
				(type default)
			)
			(layer "F.Fab")
		)
		(fp_line
			(start 0.12065 -0.3048)
			(end 0.67945 -0.3048)
			(stroke
				(width 0.1)
				(type default)
			)
			(layer "F.Fab")
		)
		(fp_line
			(start 0.67945 -0.3048)
			(end 0.67945 0.3048)
			(stroke
				(width 0.1)
				(type default)
			)
			(layer "F.Fab")
		)
		(fp_line
			(start -0.67945 -0.305054)
			(end -0.12065 -0.305054)
			(stroke
				(width 0.1)
				(type default)
			)
			(layer "F.Fab")
		)
		(fp_line
			(start -0.12065 -0.305054)
			(end -0.12065 -0.2794)
			(stroke
				(width 0.1)
				(type default)
			)
			(layer "F.Fab")
		)
		(pad "1" smd circle
			(at -0.40005 0 270)
			(size 0 0)
			(layers "F.Cu" "F.Mask" "F.Paste")
			(net "P1V8_AUX")
		)
		(pad "2" smd circle
			(at 0.40005 0 270)
			(size 0 0)
			(layers "F.Cu" "F.Mask" "F.Paste")
			(net "PWRGD_P3V3_R1")
		)
	)
	(footprint ""
		(layer "F.Cu")
		(at 318.463676 -325.678038)
		(property "Reference" "PL14"
			(at 3.234944 -15.887446 0)
			(unlocked yes)
			(layer "F.SilkS")
			(effects
				(font
					(size 0.7874 0.5842)
					(thickness 0.1524)
				)
				(justify left)
			)
		)
		(property "Value" ""
			(at 0 0 0)
			(layer "F.Fab")
			(effects
				(font
					(size 1.27 1.27)
				)
			)
		)
		(duplicate_pad_numbers_are_jumpers no)
		(fp_line
			(start -3.750056 -5.500116)
			(end -2.393442 -5.500116)
			(stroke
				(width 0.1524)
				(type default)
			)
			(layer "F.SilkS")
		)
		(fp_line
			(start -3.750056 5.500116)
			(end -3.750056 -5.500116)
			(stroke
				(width 0.1524)
				(type default)
			)
			(layer "F.SilkS")
		)
		(fp_line
			(start -2.393442 5.500116)
			(end -3.750056 5.500116)
			(stroke
				(width 0.1524)
				(type default)
			)
			(layer "F.SilkS")
		)
		(fp_line
			(start 2.393442 5.500116)
			(end 3.750056 5.500116)
			(stroke
				(width 0.1524)
				(type default)
			)
			(layer "F.SilkS")
		)
		(fp_line
			(start 3.750056 -5.500116)
			(end 2.393442 -5.500116)
			(stroke
				(width 0.1524)
				(type default)
			)
			(layer "F.SilkS")
		)
		(fp_line
			(start 3.750056 5.500116)
			(end 3.750056 -5.500116)
			(stroke
				(width 0.1524)
				(type default)
			)
			(layer "F.SilkS")
		)
		(fp_poly
			(pts
				(xy -3.9116 -4.249928) (xy -4.9276 -3.741928) (xy -4.9276 -4.757928)
			)
			(stroke
				(width 0)
				(type default)
			)
			(fill yes)
			(layer "F.SilkS")
		)
		(fp_line
			(start -3.750056 -5.500116)
			(end -3.750056 5.500116)
			(stroke
				(width 0.1)
				(type default)
			)
			(layer "F.Fab")
		)
		(fp_line
			(start -3.750056 5.500116)
			(end 3.750056 5.500116)
			(stroke
				(width 0.1)
				(type default)
			)
			(layer "F.Fab")
		)
		(fp_line
			(start 3.750056 -5.500116)
			(end -3.750056 -5.500116)
			(stroke
				(width 0.1)
				(type default)
			)
			(layer "F.Fab")
		)
		(fp_line
			(start 3.750056 5.500116)
			(end 3.750056 -5.500116)
			(stroke
				(width 0.1)
				(type default)
			)
			(layer "F.Fab")
		)
		(fp_poly
			(pts
				(xy -4.9276 -4.757928) (xy -4.9276 -3.741928) (xy -3.9116 -4.249928)
			)
			(stroke
				(width 0)
				(type default)
			)
			(fill yes)
			(layer "F.Fab")
		)
		(pad "1" smd rect
			(at 0 -4.249928 270)
			(size 2.413 4.5212)
			(layers "F.Cu" "F.Mask" "F.Paste")
			(net "SW_PVDDCR_CPU1_P0_SW3")
		)
		(pad "2" smd rect
			(at 0 -1.175004 270)
			(size 1.3716 4.5212)
			(layers "F.Cu" "F.Mask" "F.Paste")
			(net "IND_CPU1_P0_CPL2")
		)
		(pad "3" smd rect
			(at 0 1.175004 270)
			(size 1.3716 4.5212)
			(layers "F.Cu" "F.Mask" "F.Paste")
			(net "IND_CPU1_P0_CPL3")
		)
		(pad "4" smd rect
			(at 0 4.249928 270)
			(size 2.413 4.5212)
			(layers "F.Cu" "F.Mask" "F.Paste")
			(net "PVDDCR_CPU1_P0")
		)
	)
	(footprint ""
		(layer "F.Cu")
		(at 72.708262 -39.319962)
		(property "Reference" "U263"
			(at 3.21056 -1.763268 0)
			(unlocked yes)
			(layer "F.SilkS")
			(effects
				(font
					(size 0.7874 0.5842)
					(thickness 0.1524)
				)
			)
		)
		(property "Value" ""
			(at 0 0 0)
			(layer "F.Fab")
			(effects
				(font
					(size 1.27 1.27)
				)
			)
		)
		(duplicate_pad_numbers_are_jumpers no)
		(fp_line
			(start -1.500124 -1.500124)
			(end -1.004062 -1.500124)
			(stroke
				(width 0.1524)
				(type default)
			)
			(layer "F.SilkS")
		)
		(fp_line
			(start -1.500124 -1.004062)
			(end -1.500124 -1.500124)
			(stroke
				(width 0.1524)
				(type default)
			)
			(layer "F.SilkS")
		)
		(fp_line
			(start -1.500124 1.500124)
			(end -1.500124 1.004062)
			(stroke
				(width 0.1524)
				(type default)
			)
			(layer "F.SilkS")
		)
		(fp_line
			(start -1.004062 1.500124)
			(end -1.500124 1.500124)
			(stroke
				(width 0.1524)
				(type default)
			)
			(layer "F.SilkS")
		)
		(fp_line
			(start 1.004062 -1.500124)
			(end 1.500124 -1.500124)
			(stroke
				(width 0.1524)
				(type default)
			)
			(layer "F.SilkS")
		)
		(fp_line
			(start 1.500124 -1.500124)
			(end 1.500124 -1.004062)
			(stroke
				(width 0.1524)
				(type default)
			)
			(layer "F.SilkS")
		)
		(fp_line
			(start 1.500124 1.004062)
			(end 1.500124 1.500124)
			(stroke
				(width 0.1524)
				(type default)
			)
			(layer "F.SilkS")
		)
		(fp_line
			(start 1.500124 1.500124)
			(end 1.004062 1.500124)
			(stroke
				(width 0.1524)
				(type default)
			)
			(layer "F.SilkS")
		)
		(fp_poly
			(pts
				(xy -2.343912 -2.40284) (xy -3.062224 -1.684274) (xy -1.984502 -1.325118)
			)
			(stroke
				(width 0)
				(type default)
			)
			(fill yes)
			(layer "F.SilkS")
		)
		(fp_line
			(start -1.500124 -1.500124)
			(end 1.500124 -1.500124)
			(stroke
				(width 0.1)
				(type default)
			)
			(layer "F.Fab")
		)
		(fp_line
			(start -1.500124 1.500124)
			(end -1.500124 -1.500124)
			(stroke
				(width 0.1)
				(type default)
			)
			(layer "F.Fab")
		)
		(fp_line
			(start 1.500124 -1.500124)
			(end 1.500124 1.500124)
			(stroke
				(width 0.1)
				(type default)
			)
			(layer "F.Fab")
		)
		(fp_line
			(start 1.500124 1.500124)
			(end -1.500124 1.500124)
			(stroke
				(width 0.1)
				(type default)
			)
			(layer "F.Fab")
		)
		(fp_poly
			(pts
				(xy -2.847848 -1.258062) (xy -2.847848 -0.242062) (xy -1.831848 -0.750062)
			)
			(stroke
				(width 0)
				(type default)
			)
			(fill yes)
			(layer "F.Fab")
		)
		(pad "1" smd rect
			(at -1.400048 -0.750062 270)
			(size 0.2286 0.6096)
			(layers "F.Cu" "F.Mask" "F.Paste")
			(net "INA230_3_A1")
		)
		(pad "2" smd rect
			(at -1.400048 -0.249936 270)
			(size 0.2286 0.6096)
			(layers "F.Cu" "F.Mask" "F.Paste")
			(net "INA230_3_A0")
		)
		(pad "3" smd rect
			(at -1.400048 0.249936 270)
			(size 0.2286 0.6096)
			(layers "F.Cu" "F.Mask" "F.Paste")
			(net "OCP_V3_2_P3V3_ADC_ALERT_R")
		)
		(pad "4" smd rect
			(at -1.400048 0.750062 270)
			(size 0.2286 0.6096)
			(layers "F.Cu" "F.Mask" "F.Paste")
			(net "SMB_INA230_3_3V3AUX_SDA_R1")
		)
		(pad "5" smd rect
			(at -0.750062 1.400048)
			(size 0.2286 0.6096)
			(layers "F.Cu" "F.Mask" "F.Paste")
			(net "SMB_INA230_3_3V3AUX_SCL_R1")
		)
		(pad "6" smd rect
			(at -0.249936 1.400048)
			(size 0.2286 0.6096)
			(layers "F.Cu" "F.Mask" "F.Paste")
			(net "NC_INA230_3_NC0")
		)
		(pad "7" smd rect
			(at 0.249936 1.400048)
			(size 0.2286 0.6096)
			(layers "F.Cu" "F.Mask" "F.Paste")
			(net "NC_INA230_3_NC1")
		)
		(pad "8" smd rect
			(at 0.750062 1.400048)
			(size 0.2286 0.6096)
			(layers "F.Cu" "F.Mask" "F.Paste")
			(net "NC_INA230_3_NC2")
		)
		(pad "9" smd rect
			(at 1.400048 0.750062 270)
			(size 0.2286 0.6096)
			(layers "F.Cu" "F.Mask" "F.Paste")
			(net "P3V3_AUX")
		)
		(pad "10" smd rect
			(at 1.400048 0.249936 270)
			(size 0.2286 0.6096)
			(layers "F.Cu" "F.Mask" "F.Paste")
			(net "GND")
		)
		(pad "11" smd rect
			(at 1.400048 -0.249936 270)
			(size 0.2286 0.6096)
			(layers "F.Cu" "F.Mask" "F.Paste")
			(net "P3V3_OCP_V3_2_R")
		)
		(pad "12" smd rect
			(at 1.400048 -0.750062 270)
			(size 0.2286 0.6096)
			(layers "F.Cu" "F.Mask" "F.Paste")
			(net "VSENSE_P12V_INA230_3_INN")
		)
		(pad "13" smd rect
			(at 0.750062 -1.400048)
			(size 0.2286 0.6096)
			(layers "F.Cu" "F.Mask" "F.Paste")
			(net "VSENSE_P12V_INA230_3_INP")
		)
		(pad "14" smd rect
			(at 0.249936 -1.400048)
			(size 0.2286 0.6096)
			(layers "F.Cu" "F.Mask" "F.Paste")
			(net "NC_INA230_3_NC3")
		)
		(pad "15" smd rect
			(at -0.249936 -1.400048)
			(size 0.2286 0.6096)
			(layers "F.Cu" "F.Mask" "F.Paste")
			(net "NC_INA230_3_NC4")
		)
		(pad "16" smd rect
			(at -0.750062 -1.400048)
			(size 0.2286 0.6096)
			(layers "F.Cu" "F.Mask" "F.Paste")
			(net "NC_INA230_3_NC5")
		)
		(pad "TH" smd rect
			(at 0 0)
			(size 1.7018 1.7018)
			(layers "F.Cu" "F.Mask" "F.Paste")
			(net "GND")
		)
		(zone
			(layer "F.Cu")
			(hatch none 0.5)
			(connect_pads
				(clearance 0)
			)
			(min_thickness 0.25)
			(keepout
				(tracks not_allowed)
				(vias allowed)
				(pads allowed)
				(copperpour not_allowed)
				(footprints allowed)
			)
			(placement
				(enabled no)
				(sheetname "")
			)
			(fill
				(thermal_gap 0.5)
				(thermal_bridge_width 0.5)
				(island_removal_mode 0)
			)
			(polygon
				(pts
					(xy 71.663814 -39.345362) (xy 71.663814 -40.36441) (xy 73.75271 -40.36441) (xy 73.75271 -38.275514)
					(xy 71.663814 -38.275514) (xy 71.663814 -39.319962) (xy 71.806562 -39.319962) (xy 71.806562 -38.418262)
					(xy 73.609962 -38.418262) (xy 73.609962 -40.221662) (xy 71.806562 -40.221662) (xy 71.806562 -39.345362)
				)
			)
		)
	)
	(footprint ""
		(layer "F.Cu")
		(at 429.276764 -355.997764 90)
		(property "Reference" "PC9"
			(at 0 0 90)
			(layer "F.SilkS")
			(hide yes)
			(effects
				(font
					(size 1.27 1.27)
				)
			)
		)
		(property "Value" ""
			(at 0 0 90)
			(layer "F.Fab")
			(effects
				(font
					(size 1.27 1.27)
				)
			)
		)
		(duplicate_pad_numbers_are_jumpers no)
		(fp_line
			(start 0.7874 -0.4064)
			(end 0.7874 0.4064)
			(stroke
				(width 0.1524)
				(type default)
			)
			(layer "F.SilkS")
		)
		(fp_line
			(start -0.7874 -0.4064)
			(end 0.7874 -0.4064)
			(stroke
				(width 0.1524)
				(type default)
			)
			(layer "F.SilkS")
		)
		(fp_line
			(start 0.7874 0.4064)
			(end -0.7874 0.4064)
			(stroke
				(width 0.1524)
				(type default)
			)
			(layer "F.SilkS")
		)
		(fp_line
			(start -0.7874 0.4064)
			(end -0.7874 -0.4064)
			(stroke
				(width 0.1524)
				(type default)
			)
			(layer "F.SilkS")
		)
		(fp_line
			(start -0.12065 -0.305054)
			(end -0.12065 -0.2794)
			(stroke
				(width 0.1)
				(type default)
			)
			(layer "F.Fab")
		)
		(fp_line
			(start -0.67945 -0.305054)
			(end -0.12065 -0.305054)
			(stroke
				(width 0.1)
				(type default)
			)
			(layer "F.Fab")
		)
		(fp_line
			(start 0.67945 -0.3048)
			(end 0.67945 0.3048)
			(stroke
				(width 0.1)
				(type default)
			)
			(layer "F.Fab")
		)
		(fp_line
			(start 0.12065 -0.3048)
			(end 0.67945 -0.3048)
			(stroke
				(width 0.1)
				(type default)
			)
			(layer "F.Fab")
		)
		(fp_line
			(start 0.12065 -0.2794)
			(end 0.12065 -0.3048)
			(stroke
				(width 0.1)
				(type default)
			)
			(layer "F.Fab")
		)
		(fp_line
			(start -0.12065 -0.2794)
			(end 0.12065 -0.2794)
			(stroke
				(width 0.1)
				(type default)
			)
			(layer "F.Fab")
		)
		(fp_line
			(start 0.120396 0.2794)
			(end -0.12065 0.2794)
			(stroke
				(width 0.1)
				(type default)
			)
			(layer "F.Fab")
		)
		(fp_line
			(start -0.12065 0.2794)
			(end -0.12065 0.3048)
			(stroke
				(width 0.1)
				(type default)
			)
			(layer "F.Fab")
		)
		(fp_line
			(start 0.67945 0.3048)
			(end 0.120396 0.3048)
			(stroke
				(width 0.1)
				(type default)
			)
			(layer "F.Fab")
		)
		(fp_line
			(start 0.120396 0.3048)
			(end 0.120396 0.2794)
			(stroke
				(width 0.1)
				(type default)
			)
			(layer "F.Fab")
		)
		(fp_line
			(start -0.12065 0.3048)
			(end -0.67945 0.3048)
			(stroke
				(width 0.1)
				(type default)
			)
			(layer "F.Fab")
		)
		(fp_line
			(start -0.67945 0.3048)
			(end -0.67945 -0.305054)
			(stroke
				(width 0.1)
				(type default)
			)
			(layer "F.Fab")
		)
		(pad "1" smd circle
			(at -0.40005 0 90)
			(size 0 0)
			(layers "F.Cu" "F.Mask" "F.Paste")
			(net "PVDD11_S3_P0_VCCS")
		)
		(pad "2" smd circle
			(at 0.40005 0 90)
			(size 0 0)
			(layers "F.Cu" "F.Mask" "F.Paste")
			(net "GND")
		)
	)
	(footprint ""
		(layer "F.Cu")
		(at 318.300608 -22.57933 90)
		(property "Reference" "R1343"
			(at 0 0 90)
			(layer "F.SilkS")
			(hide yes)
			(effects
				(font
					(size 1.27 1.27)
				)
			)
		)
		(property "Value" ""
			(at 0 0 90)
			(layer "F.Fab")
			(effects
				(font
					(size 1.27 1.27)
				)
			)
		)
		(duplicate_pad_numbers_are_jumpers no)
		(fp_line
			(start 0.7874 -0.4064)
			(end 0.7874 0.4064)
			(stroke
				(width 0.1524)
				(type default)
			)
			(layer "F.SilkS")
		)
		(fp_line
			(start -0.7874 -0.4064)
			(end 0.7874 -0.4064)
			(stroke
				(width 0.1524)
				(type default)
			)
			(layer "F.SilkS")
		)
		(fp_line
			(start 0.7874 0.4064)
			(end -0.7874 0.4064)
			(stroke
				(width 0.1524)
				(type default)
			)
			(layer "F.SilkS")
		)
		(fp_line
			(start -0.7874 0.4064)
			(end -0.7874 -0.4064)
			(stroke
				(width 0.1524)
				(type default)
			)
			(layer "F.SilkS")
		)
		(fp_line
			(start -0.12065 -0.305054)
			(end -0.12065 -0.2794)
			(stroke
				(width 0.1)
				(type default)
			)
			(layer "F.Fab")
		)
		(fp_line
			(start -0.67945 -0.305054)
			(end -0.12065 -0.305054)
			(stroke
				(width 0.1)
				(type default)
			)
			(layer "F.Fab")
		)
		(fp_line
			(start 0.67945 -0.3048)
			(end 0.67945 0.3048)
			(stroke
				(width 0.1)
				(type default)
			)
			(layer "F.Fab")
		)
		(fp_line
			(start 0.12065 -0.3048)
			(end 0.67945 -0.3048)
			(stroke
				(width 0.1)
				(type default)
			)
			(layer "F.Fab")
		)
		(fp_line
			(start 0.12065 -0.2794)
			(end 0.12065 -0.3048)
			(stroke
				(width 0.1)
				(type default)
			)
			(layer "F.Fab")
		)
		(fp_line
			(start -0.12065 -0.2794)
			(end 0.12065 -0.2794)
			(stroke
				(width 0.1)
				(type default)
			)
			(layer "F.Fab")
		)
		(fp_line
			(start 0.120396 0.2794)
			(end -0.12065 0.2794)
			(stroke
				(width 0.1)
				(type default)
			)
			(layer "F.Fab")
		)
		(fp_line
			(start -0.12065 0.2794)
			(end -0.12065 0.3048)
			(stroke
				(width 0.1)
				(type default)
			)
			(layer "F.Fab")
		)
		(fp_line
			(start 0.67945 0.3048)
			(end 0.120396 0.3048)
			(stroke
				(width 0.1)
				(type default)
			)
			(layer "F.Fab")
		)
		(fp_line
			(start 0.120396 0.3048)
			(end 0.120396 0.2794)
			(stroke
				(width 0.1)
				(type default)
			)
			(layer "F.Fab")
		)
		(fp_line
			(start -0.12065 0.3048)
			(end -0.67945 0.3048)
			(stroke
				(width 0.1)
				(type default)
			)
			(layer "F.Fab")
		)
		(fp_line
			(start -0.67945 0.3048)
			(end -0.67945 -0.305054)
			(stroke
				(width 0.1)
				(type default)
			)
			(layer "F.Fab")
		)
		(pad "1" smd circle
			(at -0.40005 0 90)
			(size 0 0)
			(layers "F.Cu" "F.Mask" "F.Paste")
			(net "P3V3_AUX")
		)
		(pad "2" smd circle
			(at 0.40005 0 90)
			(size 0 0)
			(layers "F.Cu" "F.Mask" "F.Paste")
			(net "SCM_JTAG_MUX_S1")
		)
	)
	(footprint ""
		(layer "F.Cu")
		(at 205.214982 -119.721376)
		(property "Reference" "R3066"
			(at 0 0 0)
			(layer "F.SilkS")
			(hide yes)
			(effects
				(font
					(size 1.27 1.27)
				)
			)
		)
		(property "Value" ""
			(at 0 0 0)
			(layer "F.Fab")
			(effects
				(font
					(size 1.27 1.27)
				)
			)
		)
		(duplicate_pad_numbers_are_jumpers no)
		(fp_line
			(start -0.7874 -0.4064)
			(end 0.7874 -0.4064)
			(stroke
				(width 0.1524)
				(type default)
			)
			(layer "F.SilkS")
		)
		(fp_line
			(start -0.7874 0.4064)
			(end -0.7874 -0.4064)
			(stroke
				(width 0.1524)
				(type default)
			)
			(layer "F.SilkS")
		)
		(fp_line
			(start 0.7874 -0.4064)
			(end 0.7874 0.4064)
			(stroke
				(width 0.1524)
				(type default)
			)
			(layer "F.SilkS")
		)
		(fp_line
			(start 0.7874 0.4064)
			(end -0.7874 0.4064)
			(stroke
				(width 0.1524)
				(type default)
			)
			(layer "F.SilkS")
		)
		(fp_line
			(start -0.67945 -0.305054)
			(end -0.12065 -0.305054)
			(stroke
				(width 0.1)
				(type default)
			)
			(layer "F.Fab")
		)
		(fp_line
			(start -0.67945 0.3048)
			(end -0.67945 -0.305054)
			(stroke
				(width 0.1)
				(type default)
			)
			(layer "F.Fab")
		)
		(fp_line
			(start -0.12065 -0.305054)
			(end -0.12065 -0.2794)
			(stroke
				(width 0.1)
				(type default)
			)
			(layer "F.Fab")
		)
		(fp_line
			(start -0.12065 -0.2794)
			(end 0.12065 -0.2794)
			(stroke
				(width 0.1)
				(type default)
			)
			(layer "F.Fab")
		)
		(fp_line
			(start -0.12065 0.2794)
			(end -0.12065 0.3048)
			(stroke
				(width 0.1)
				(type default)
			)
			(layer "F.Fab")
		)
		(fp_line
			(start -0.12065 0.3048)
			(end -0.67945 0.3048)
			(stroke
				(width 0.1)
				(type default)
			)
			(layer "F.Fab")
		)
		(fp_line
			(start 0.120396 0.2794)
			(end -0.12065 0.2794)
			(stroke
				(width 0.1)
				(type default)
			)
			(layer "F.Fab")
		)
		(fp_line
			(start 0.120396 0.3048)
			(end 0.120396 0.2794)
			(stroke
				(width 0.1)
				(type default)
			)
			(layer "F.Fab")
		)
		(fp_line
			(start 0.12065 -0.3048)
			(end 0.67945 -0.3048)
			(stroke
				(width 0.1)
				(type default)
			)
			(layer "F.Fab")
		)
		(fp_line
			(start 0.12065 -0.2794)
			(end 0.12065 -0.3048)
			(stroke
				(width 0.1)
				(type default)
			)
			(layer "F.Fab")
		)
		(fp_line
			(start 0.67945 -0.3048)
			(end 0.67945 0.3048)
			(stroke
				(width 0.1)
				(type default)
			)
			(layer "F.Fab")
		)
		(fp_line
			(start 0.67945 0.3048)
			(end 0.120396 0.3048)
			(stroke
				(width 0.1)
				(type default)
			)
			(layer "F.Fab")
		)
		(pad "1" smd circle
			(at -0.40005 0)
			(size 0 0)
			(layers "F.Cu" "F.Mask" "F.Paste")
			(net "FM_SMB_1_ALERT_GPU_ISO_R_N")
		)
		(pad "2" smd circle
			(at 0.40005 0)
			(size 0 0)
			(layers "F.Cu" "F.Mask" "F.Paste")
			(net "FM_SMB_1_ALERT_GPU_ISO_N")
		)
	)
	(footprint ""
		(layer "F.Cu")
		(at 329.360022 -31.937706)
		(property "Reference" "C2043"
			(at 0 0 0)
			(layer "F.SilkS")
			(hide yes)
			(effects
				(font
					(size 1.27 1.27)
				)
			)
		)
		(property "Value" ""
			(at 0 0 0)
			(layer "F.Fab")
			(effects
				(font
					(size 1.27 1.27)
				)
			)
		)
		(duplicate_pad_numbers_are_jumpers no)
		(fp_line
			(start -0.7874 -0.4064)
			(end 0.7874 -0.4064)
			(stroke
				(width 0.1524)
				(type default)
			)
			(layer "F.SilkS")
		)
		(fp_line
			(start -0.7874 0.4064)
			(end -0.7874 -0.4064)
			(stroke
				(width 0.1524)
				(type default)
			)
			(layer "F.SilkS")
		)
		(fp_line
			(start 0.7874 -0.4064)
			(end 0.7874 0.4064)
			(stroke
				(width 0.1524)
				(type default)
			)
			(layer "F.SilkS")
		)
		(fp_line
			(start 0.7874 0.4064)
			(end -0.7874 0.4064)
			(stroke
				(width 0.1524)
				(type default)
			)
			(layer "F.SilkS")
		)
		(fp_line
			(start -0.67945 -0.305054)
			(end -0.12065 -0.305054)
			(stroke
				(width 0.1)
				(type default)
			)
			(layer "F.Fab")
		)
		(fp_line
			(start -0.67945 0.3048)
			(end -0.67945 -0.305054)
			(stroke
				(width 0.1)
				(type default)
			)
			(layer "F.Fab")
		)
		(fp_line
			(start -0.12065 -0.305054)
			(end -0.12065 -0.2794)
			(stroke
				(width 0.1)
				(type default)
			)
			(layer "F.Fab")
		)
		(fp_line
			(start -0.12065 -0.2794)
			(end 0.12065 -0.2794)
			(stroke
				(width 0.1)
				(type default)
			)
			(layer "F.Fab")
		)
		(fp_line
			(start -0.12065 0.2794)
			(end -0.12065 0.3048)
			(stroke
				(width 0.1)
				(type default)
			)
			(layer "F.Fab")
		)
		(fp_line
			(start -0.12065 0.3048)
			(end -0.67945 0.3048)
			(stroke
				(width 0.1)
				(type default)
			)
			(layer "F.Fab")
		)
		(fp_line
			(start 0.120396 0.2794)
			(end -0.12065 0.2794)
			(stroke
				(width 0.1)
				(type default)
			)
			(layer "F.Fab")
		)
		(fp_line
			(start 0.120396 0.3048)
			(end 0.120396 0.2794)
			(stroke
				(width 0.1)
				(type default)
			)
			(layer "F.Fab")
		)
		(fp_line
			(start 0.12065 -0.3048)
			(end 0.67945 -0.3048)
			(stroke
				(width 0.1)
				(type default)
			)
			(layer "F.Fab")
		)
		(fp_line
			(start 0.12065 -0.2794)
			(end 0.12065 -0.3048)
			(stroke
				(width 0.1)
				(type default)
			)
			(layer "F.Fab")
		)
		(fp_line
			(start 0.67945 -0.3048)
			(end 0.67945 0.3048)
			(stroke
				(width 0.1)
				(type default)
			)
			(layer "F.Fab")
		)
		(fp_line
			(start 0.67945 0.3048)
			(end 0.120396 0.3048)
			(stroke
				(width 0.1)
				(type default)
			)
			(layer "F.Fab")
		)
		(pad "1" smd circle
			(at -0.40005 0)
			(size 0 0)
			(layers "F.Cu" "F.Mask" "F.Paste")
			(net "P3V3_ADC_MAM")
		)
		(pad "2" smd circle
			(at 0.40005 0)
			(size 0 0)
			(layers "F.Cu" "F.Mask" "F.Paste")
			(net "GND")
		)
	)
	(footprint ""
		(layer "F.Cu")
		(at 88.908128 -339.630258 -90)
		(property "Reference" "PC383"
			(at 0 0 270)
			(layer "F.SilkS")
			(hide yes)
			(effects
				(font
					(size 1.27 1.27)
				)
			)
		)
		(property "Value" ""
			(at 0 0 270)
			(layer "F.Fab")
			(effects
				(font
					(size 1.27 1.27)
				)
			)
		)
		(duplicate_pad_numbers_are_jumpers no)
		(fp_line
			(start -0.7874 0.4064)
			(end -0.7874 -0.4064)
			(stroke
				(width 0.1524)
				(type default)
			)
			(layer "F.SilkS")
		)
		(fp_line
			(start 0.7874 0.4064)
			(end -0.7874 0.4064)
			(stroke
				(width 0.1524)
				(type default)
			)
			(layer "F.SilkS")
		)
		(fp_line
			(start -0.7874 -0.4064)
			(end 0.7874 -0.4064)
			(stroke
				(width 0.1524)
				(type default)
			)
			(layer "F.SilkS")
		)
		(fp_line
			(start 0.7874 -0.4064)
			(end 0.7874 0.4064)
			(stroke
				(width 0.1524)
				(type default)
			)
			(layer "F.SilkS")
		)
		(fp_line
			(start -0.67945 0.3048)
			(end -0.67945 -0.305054)
			(stroke
				(width 0.1)
				(type default)
			)
			(layer "F.Fab")
		)
		(fp_line
			(start -0.12065 0.3048)
			(end -0.67945 0.3048)
			(stroke
				(width 0.1)
				(type default)
			)
			(layer "F.Fab")
		)
		(fp_line
			(start 0.120396 0.3048)
			(end 0.120396 0.2794)
			(stroke
				(width 0.1)
				(type default)
			)
			(layer "F.Fab")
		)
		(fp_line
			(start 0.67945 0.3048)
			(end 0.120396 0.3048)
			(stroke
				(width 0.1)
				(type default)
			)
			(layer "F.Fab")
		)
		(fp_line
			(start -0.12065 0.2794)
			(end -0.12065 0.3048)
			(stroke
				(width 0.1)
				(type default)
			)
			(layer "F.Fab")
		)
		(fp_line
			(start 0.120396 0.2794)
			(end -0.12065 0.2794)
			(stroke
				(width 0.1)
				(type default)
			)
			(layer "F.Fab")
		)
		(fp_line
			(start -0.12065 -0.2794)
			(end 0.12065 -0.2794)
			(stroke
				(width 0.1)
				(type default)
			)
			(layer "F.Fab")
		)
		(fp_line
			(start 0.12065 -0.2794)
			(end 0.12065 -0.3048)
			(stroke
				(width 0.1)
				(type default)
			)
			(layer "F.Fab")
		)
		(fp_line
			(start 0.12065 -0.3048)
			(end 0.67945 -0.3048)
			(stroke
				(width 0.1)
				(type default)
			)
			(layer "F.Fab")
		)
		(fp_line
			(start 0.67945 -0.3048)
			(end 0.67945 0.3048)
			(stroke
				(width 0.1)
				(type default)
			)
			(layer "F.Fab")
		)
		(fp_line
			(start -0.67945 -0.305054)
			(end -0.12065 -0.305054)
			(stroke
				(width 0.1)
				(type default)
			)
			(layer "F.Fab")
		)
		(fp_line
			(start -0.12065 -0.305054)
			(end -0.12065 -0.2794)
			(stroke
				(width 0.1)
				(type default)
			)
			(layer "F.Fab")
		)
		(pad "1" smd circle
			(at -0.40005 0 270)
			(size 0 0)
			(layers "F.Cu" "F.Mask" "F.Paste")
			(net "SW_PVDDCR_CPU1_P1_BOOT1_R")
		)
		(pad "2" smd circle
			(at 0.40005 0 270)
			(size 0 0)
			(layers "F.Cu" "F.Mask" "F.Paste")
			(net "SW_PVDDCR_CPU1_P1_BOOTR1")
		)
	)
	(footprint ""
		(layer "F.Cu")
		(at 457.314046 -32.053276)
		(property "Reference" "H29"
			(at -5.8166 -5.552948 0)
			(unlocked yes)
			(layer "F.SilkS")
			(effects
				(font
					(size 0.7874 0.5842)
					(thickness 0.1524)
				)
				(justify left)
			)
		)
		(property "Value" ""
			(at 0 0 0)
			(layer "F.Fab")
			(effects
				(font
					(size 1.27 1.27)
				)
			)
		)
		(duplicate_pad_numbers_are_jumpers no)
		(fp_circle
			(center 0 0)
			(end 2.4003 0)
			(stroke
				(width 0.1524)
				(type default)
			)
			(fill no)
			(layer "F.SilkS")
		)
		(fp_circle
			(center 0 0)
			(end 6.5913 0)
			(stroke
				(width 0.1524)
				(type default)
			)
			(fill no)
			(layer "B.SilkS")
		)
		(fp_circle
			(center 0 0)
			(end 6.5913 0)
			(stroke
				(width 0.1)
				(type default)
			)
			(fill no)
			(layer "B.Fab")
		)
		(fp_circle
			(center 0 0)
			(end 2.4003 0)
			(stroke
				(width 0.1)
				(type default)
			)
			(fill no)
			(layer "F.Fab")
		)
		(pad "" np_thru_hole circle
			(at 0 0)
			(size 3.175 3.175)
			(drill 3.175)
			(layers "*.Cu" "*.Mask")
			(clearance 0.381)
			(thermal_gap 0.381)
		)
		(zone
			(layers "F.Cu" "B.Cu" "In1.Cu" "In2.Cu" "In3.Cu" "In4.Cu" "In5.Cu" "In6.Cu"
				"In7.Cu" "In8.Cu" "In9.Cu" "In10.Cu" "In11.Cu" "In12.Cu" "In13.Cu" "In14.Cu"
				"In15.Cu" "In16.Cu"
			)
			(hatch none 0.5)
			(connect_pads
				(clearance 0)
			)
			(min_thickness 0.25)
			(keepout
				(tracks not_allowed)
				(vias allowed)
				(pads allowed)
				(copperpour not_allowed)
				(footprints allowed)
			)
			(placement
				(enabled no)
				(sheetname "")
			)
			(fill
				(thermal_gap 0.5)
				(thermal_bridge_width 0.5)
				(island_removal_mode 0)
			)
			(polygon
				(pts
					(arc
						(start 459.409546 -32.053276)
						(mid 455.218546 -32.053276)
						(end 459.409546 -32.053276)
					)
				)
			)
		)
	)
	(footprint ""
		(layer "F.Cu")
		(at 29.464 -434.9623)
		(property "Reference" "R4603"
			(at 0 0 0)
			(layer "F.SilkS")
			(hide yes)
			(effects
				(font
					(size 1.27 1.27)
				)
			)
		)
		(property "Value" ""
			(at 0 0 0)
			(layer "F.Fab")
			(effects
				(font
					(size 1.27 1.27)
				)
			)
		)
		(duplicate_pad_numbers_are_jumpers no)
		(fp_line
			(start -0.7874 -0.4064)
			(end 0.7874 -0.4064)
			(stroke
				(width 0.1524)
				(type default)
			)
			(layer "F.SilkS")
		)
		(fp_line
			(start -0.7874 0.4064)
			(end -0.7874 -0.4064)
			(stroke
				(width 0.1524)
				(type default)
			)
			(layer "F.SilkS")
		)
		(fp_line
			(start 0.7874 -0.4064)
			(end 0.7874 0.4064)
			(stroke
				(width 0.1524)
				(type default)
			)
			(layer "F.SilkS")
		)
		(fp_line
			(start 0.7874 0.4064)
			(end -0.7874 0.4064)
			(stroke
				(width 0.1524)
				(type default)
			)
			(layer "F.SilkS")
		)
		(fp_line
			(start -0.67945 -0.305054)
			(end -0.12065 -0.305054)
			(stroke
				(width 0.1)
				(type default)
			)
			(layer "F.Fab")
		)
		(fp_line
			(start -0.67945 0.3048)
			(end -0.67945 -0.305054)
			(stroke
				(width 0.1)
				(type default)
			)
			(layer "F.Fab")
		)
		(fp_line
			(start -0.12065 -0.305054)
			(end -0.12065 -0.2794)
			(stroke
				(width 0.1)
				(type default)
			)
			(layer "F.Fab")
		)
		(fp_line
			(start -0.12065 -0.2794)
			(end 0.12065 -0.2794)
			(stroke
				(width 0.1)
				(type default)
			)
			(layer "F.Fab")
		)
		(fp_line
			(start -0.12065 0.2794)
			(end -0.12065 0.3048)
			(stroke
				(width 0.1)
				(type default)
			)
			(layer "F.Fab")
		)
		(fp_line
			(start -0.12065 0.3048)
			(end -0.67945 0.3048)
			(stroke
				(width 0.1)
				(type default)
			)
			(layer "F.Fab")
		)
		(fp_line
			(start 0.120396 0.2794)
			(end -0.12065 0.2794)
			(stroke
				(width 0.1)
				(type default)
			)
			(layer "F.Fab")
		)
		(fp_line
			(start 0.120396 0.3048)
			(end 0.120396 0.2794)
			(stroke
				(width 0.1)
				(type default)
			)
			(layer "F.Fab")
		)
		(fp_line
			(start 0.12065 -0.3048)
			(end 0.67945 -0.3048)
			(stroke
				(width 0.1)
				(type default)
			)
			(layer "F.Fab")
		)
		(fp_line
			(start 0.12065 -0.2794)
			(end 0.12065 -0.3048)
			(stroke
				(width 0.1)
				(type default)
			)
			(layer "F.Fab")
		)
		(fp_line
			(start 0.67945 -0.3048)
			(end 0.67945 0.3048)
			(stroke
				(width 0.1)
				(type default)
			)
			(layer "F.Fab")
		)
		(fp_line
			(start 0.67945 0.3048)
			(end 0.120396 0.3048)
			(stroke
				(width 0.1)
				(type default)
			)
			(layer "F.Fab")
		)
		(pad "1" smd circle
			(at -0.40005 0)
			(size 0 0)
			(layers "F.Cu" "F.Mask" "F.Paste")
			(net "SMB_BMC_GPU_EN")
		)
		(pad "2" smd circle
			(at 0.40005 0)
			(size 0 0)
			(layers "F.Cu" "F.Mask" "F.Paste")
			(net "GND")
		)
	)
	(footprint ""
		(layer "F.Cu")
		(at 117.347238 -41.17975 -90)
		(property "Reference" "R6282"
			(at 0 0 270)
			(layer "F.SilkS")
			(hide yes)
			(effects
				(font
					(size 1.27 1.27)
				)
			)
		)
		(property "Value" ""
			(at 0 0 270)
			(layer "F.Fab")
			(effects
				(font
					(size 1.27 1.27)
				)
			)
		)
		(duplicate_pad_numbers_are_jumpers no)
		(fp_line
			(start -0.7874 0.4064)
			(end -0.7874 -0.4064)
			(stroke
				(width 0.1524)
				(type default)
			)
			(layer "F.SilkS")
		)
		(fp_line
			(start 0.7874 0.4064)
			(end -0.7874 0.4064)
			(stroke
				(width 0.1524)
				(type default)
			)
			(layer "F.SilkS")
		)
		(fp_line
			(start -0.7874 -0.4064)
			(end 0.7874 -0.4064)
			(stroke
				(width 0.1524)
				(type default)
			)
			(layer "F.SilkS")
		)
		(fp_line
			(start 0.7874 -0.4064)
			(end 0.7874 0.4064)
			(stroke
				(width 0.1524)
				(type default)
			)
			(layer "F.SilkS")
		)
		(fp_line
			(start -0.67945 0.3048)
			(end -0.67945 -0.305054)
			(stroke
				(width 0.1)
				(type default)
			)
			(layer "F.Fab")
		)
		(fp_line
			(start -0.12065 0.3048)
			(end -0.67945 0.3048)
			(stroke
				(width 0.1)
				(type default)
			)
			(layer "F.Fab")
		)
		(fp_line
			(start 0.120396 0.3048)
			(end 0.120396 0.2794)
			(stroke
				(width 0.1)
				(type default)
			)
			(layer "F.Fab")
		)
		(fp_line
			(start 0.67945 0.3048)
			(end 0.120396 0.3048)
			(stroke
				(width 0.1)
				(type default)
			)
			(layer "F.Fab")
		)
		(fp_line
			(start -0.12065 0.2794)
			(end -0.12065 0.3048)
			(stroke
				(width 0.1)
				(type default)
			)
			(layer "F.Fab")
		)
		(fp_line
			(start 0.120396 0.2794)
			(end -0.12065 0.2794)
			(stroke
				(width 0.1)
				(type default)
			)
			(layer "F.Fab")
		)
		(fp_line
			(start -0.12065 -0.2794)
			(end 0.12065 -0.2794)
			(stroke
				(width 0.1)
				(type default)
			)
			(layer "F.Fab")
		)
		(fp_line
			(start 0.12065 -0.2794)
			(end 0.12065 -0.3048)
			(stroke
				(width 0.1)
				(type default)
			)
			(layer "F.Fab")
		)
		(fp_line
			(start 0.12065 -0.3048)
			(end 0.67945 -0.3048)
			(stroke
				(width 0.1)
				(type default)
			)
			(layer "F.Fab")
		)
		(fp_line
			(start 0.67945 -0.3048)
			(end 0.67945 0.3048)
			(stroke
				(width 0.1)
				(type default)
			)
			(layer "F.Fab")
		)
		(fp_line
			(start -0.67945 -0.305054)
			(end -0.12065 -0.305054)
			(stroke
				(width 0.1)
				(type default)
			)
			(layer "F.Fab")
		)
		(fp_line
			(start -0.12065 -0.305054)
			(end -0.12065 -0.2794)
			(stroke
				(width 0.1)
				(type default)
			)
			(layer "F.Fab")
		)
		(pad "1" smd circle
			(at -0.40005 0 270)
			(size 0 0)
			(layers "F.Cu" "F.Mask" "F.Paste")
			(net "P3V3_AUX")
		)
		(pad "2" smd circle
			(at 0.40005 0 270)
			(size 0 0)
			(layers "F.Cu" "F.Mask" "F.Paste")
			(net "USB_HUB2_TI_SMBUSZ_MRP_PROG_FUNC2")
		)
	)
	(footprint ""
		(layer "F.Cu")
		(at 178.851814 -410.630624)
		(property "Reference" "R348"
			(at 0 0 0)
			(layer "F.SilkS")
			(hide yes)
			(effects
				(font
					(size 1.27 1.27)
				)
			)
		)
		(property "Value" ""
			(at 0 0 0)
			(layer "F.Fab")
			(effects
				(font
					(size 1.27 1.27)
				)
			)
		)
		(duplicate_pad_numbers_are_jumpers no)
		(fp_line
			(start -0.7874 -0.4064)
			(end 0.7874 -0.4064)
			(stroke
				(width 0.1524)
				(type default)
			)
			(layer "F.SilkS")
		)
		(fp_line
			(start -0.7874 0.4064)
			(end -0.7874 -0.4064)
			(stroke
				(width 0.1524)
				(type default)
			)
			(layer "F.SilkS")
		)
		(fp_line
			(start 0.7874 -0.4064)
			(end 0.7874 0.4064)
			(stroke
				(width 0.1524)
				(type default)
			)
			(layer "F.SilkS")
		)
		(fp_line
			(start 0.7874 0.4064)
			(end -0.7874 0.4064)
			(stroke
				(width 0.1524)
				(type default)
			)
			(layer "F.SilkS")
		)
		(fp_line
			(start -0.67945 -0.305054)
			(end -0.12065 -0.305054)
			(stroke
				(width 0.1)
				(type default)
			)
			(layer "F.Fab")
		)
		(fp_line
			(start -0.67945 0.3048)
			(end -0.67945 -0.305054)
			(stroke
				(width 0.1)
				(type default)
			)
			(layer "F.Fab")
		)
		(fp_line
			(start -0.12065 -0.305054)
			(end -0.12065 -0.2794)
			(stroke
				(width 0.1)
				(type default)
			)
			(layer "F.Fab")
		)
		(fp_line
			(start -0.12065 -0.2794)
			(end 0.12065 -0.2794)
			(stroke
				(width 0.1)
				(type default)
			)
			(layer "F.Fab")
		)
		(fp_line
			(start -0.12065 0.2794)
			(end -0.12065 0.3048)
			(stroke
				(width 0.1)
				(type default)
			)
			(layer "F.Fab")
		)
		(fp_line
			(start -0.12065 0.3048)
			(end -0.67945 0.3048)
			(stroke
				(width 0.1)
				(type default)
			)
			(layer "F.Fab")
		)
		(fp_line
			(start 0.120396 0.2794)
			(end -0.12065 0.2794)
			(stroke
				(width 0.1)
				(type default)
			)
			(layer "F.Fab")
		)
		(fp_line
			(start 0.120396 0.3048)
			(end 0.120396 0.2794)
			(stroke
				(width 0.1)
				(type default)
			)
			(layer "F.Fab")
		)
		(fp_line
			(start 0.12065 -0.3048)
			(end 0.67945 -0.3048)
			(stroke
				(width 0.1)
				(type default)
			)
			(layer "F.Fab")
		)
		(fp_line
			(start 0.12065 -0.2794)
			(end 0.12065 -0.3048)
			(stroke
				(width 0.1)
				(type default)
			)
			(layer "F.Fab")
		)
		(fp_line
			(start 0.67945 -0.3048)
			(end 0.67945 0.3048)
			(stroke
				(width 0.1)
				(type default)
			)
			(layer "F.Fab")
		)
		(fp_line
			(start 0.67945 0.3048)
			(end 0.120396 0.3048)
			(stroke
				(width 0.1)
				(type default)
			)
			(layer "F.Fab")
		)
		(pad "1" smd circle
			(at -0.40005 0)
			(size 0 0)
			(layers "F.Cu" "F.Mask" "F.Paste")
			(net "SMB_SML1_PMBUS_HSC_SDA")
		)
		(pad "2" smd circle
			(at 0.40005 0)
			(size 0 0)
			(layers "F.Cu" "F.Mask" "F.Paste")
			(net "SMB_SML1_PMBUS_HSC_R1_SDA")
		)
	)
	(footprint ""
		(layer "F.Cu")
		(at 108.3564 -397.03248 90)
		(property "Reference" "R690"
			(at 0 0 90)
			(layer "F.SilkS")
			(hide yes)
			(effects
				(font
					(size 1.27 1.27)
				)
			)
		)
		(property "Value" ""
			(at 0 0 90)
			(layer "F.Fab")
			(effects
				(font
					(size 1.27 1.27)
				)
			)
		)
		(duplicate_pad_numbers_are_jumpers no)
		(fp_line
			(start 0.32512 -0.175006)
			(end 0.32512 0.175006)
			(stroke
				(width 0.1)
				(type default)
			)
			(layer "F.Fab")
		)
		(fp_line
			(start -0.32512 -0.175006)
			(end 0.32512 -0.175006)
			(stroke
				(width 0.1)
				(type default)
			)
			(layer "F.Fab")
		)
		(fp_line
			(start 0.32512 0.175006)
			(end -0.32512 0.175006)
			(stroke
				(width 0.1)
				(type default)
			)
			(layer "F.Fab")
		)
		(fp_line
			(start -0.32512 0.175006)
			(end -0.32512 -0.175006)
			(stroke
				(width 0.1)
				(type default)
			)
			(layer "F.Fab")
		)
		(pad "1" smd rect
			(at -0.2667 0 90)
			(size 0.3048 0.381)
			(layers "F.Cu" "F.Mask" "F.Paste")
			(net "SMB_RT_CPU1_P1_ROM_R_SDA")
		)
		(pad "2" smd rect
			(at 0.2667 0 270)
			(size 0.3048 0.381)
			(layers "F.Cu" "F.Mask" "F.Paste")
			(net "SMB_RT_CPU1_P1_ROM_SDA")
		)
	)
	(footprint ""
		(layer "F.Cu")
		(at 150.31974 -101.672898)
		(property "Reference" "R3294"
			(at 0 0 0)
			(layer "F.SilkS")
			(hide yes)
			(effects
				(font
					(size 1.27 1.27)
				)
			)
		)
		(property "Value" ""
			(at 0 0 0)
			(layer "F.Fab")
			(effects
				(font
					(size 1.27 1.27)
				)
			)
		)
		(duplicate_pad_numbers_are_jumpers no)
		(fp_line
			(start -0.7874 -0.4064)
			(end 0.7874 -0.4064)
			(stroke
				(width 0.1524)
				(type default)
			)
			(layer "F.SilkS")
		)
		(fp_line
			(start -0.7874 0.4064)
			(end -0.7874 -0.4064)
			(stroke
				(width 0.1524)
				(type default)
			)
			(layer "F.SilkS")
		)
		(fp_line
			(start 0.7874 -0.4064)
			(end 0.7874 0.4064)
			(stroke
				(width 0.1524)
				(type default)
			)
			(layer "F.SilkS")
		)
		(fp_line
			(start 0.7874 0.4064)
			(end -0.7874 0.4064)
			(stroke
				(width 0.1524)
				(type default)
			)
			(layer "F.SilkS")
		)
		(fp_line
			(start -0.67945 -0.305054)
			(end -0.12065 -0.305054)
			(stroke
				(width 0.1)
				(type default)
			)
			(layer "F.Fab")
		)
		(fp_line
			(start -0.67945 0.3048)
			(end -0.67945 -0.305054)
			(stroke
				(width 0.1)
				(type default)
			)
			(layer "F.Fab")
		)
		(fp_line
			(start -0.12065 -0.305054)
			(end -0.12065 -0.2794)
			(stroke
				(width 0.1)
				(type default)
			)
			(layer "F.Fab")
		)
		(fp_line
			(start -0.12065 -0.2794)
			(end 0.12065 -0.2794)
			(stroke
				(width 0.1)
				(type default)
			)
			(layer "F.Fab")
		)
		(fp_line
			(start -0.12065 0.2794)
			(end -0.12065 0.3048)
			(stroke
				(width 0.1)
				(type default)
			)
			(layer "F.Fab")
		)
		(fp_line
			(start -0.12065 0.3048)
			(end -0.67945 0.3048)
			(stroke
				(width 0.1)
				(type default)
			)
			(layer "F.Fab")
		)
		(fp_line
			(start 0.120396 0.2794)
			(end -0.12065 0.2794)
			(stroke
				(width 0.1)
				(type default)
			)
			(layer "F.Fab")
		)
		(fp_line
			(start 0.120396 0.3048)
			(end 0.120396 0.2794)
			(stroke
				(width 0.1)
				(type default)
			)
			(layer "F.Fab")
		)
		(fp_line
			(start 0.12065 -0.3048)
			(end 0.67945 -0.3048)
			(stroke
				(width 0.1)
				(type default)
			)
			(layer "F.Fab")
		)
		(fp_line
			(start 0.12065 -0.2794)
			(end 0.12065 -0.3048)
			(stroke
				(width 0.1)
				(type default)
			)
			(layer "F.Fab")
		)
		(fp_line
			(start 0.67945 -0.3048)
			(end 0.67945 0.3048)
			(stroke
				(width 0.1)
				(type default)
			)
			(layer "F.Fab")
		)
		(fp_line
			(start 0.67945 0.3048)
			(end 0.120396 0.3048)
			(stroke
				(width 0.1)
				(type default)
			)
			(layer "F.Fab")
		)
		(pad "1" smd circle
			(at -0.40005 0)
			(size 0 0)
			(layers "F.Cu" "F.Mask" "F.Paste")
			(net "LED_M2_SSD_0_ACT_N")
		)
		(pad "2" smd circle
			(at 0.40005 0)
			(size 0 0)
			(layers "F.Cu" "F.Mask" "F.Paste")
			(net "LED_HDD_ACTIVITY_N")
		)
	)
	(footprint ""
		(layer "F.Cu")
		(at 302.241458 -113.843308 180)
		(property "Reference" "R69"
			(at 0 0 180)
			(layer "F.SilkS")
			(hide yes)
			(effects
				(font
					(size 1.27 1.27)
				)
			)
		)
		(property "Value" ""
			(at 0 0 180)
			(layer "F.Fab")
			(effects
				(font
					(size 1.27 1.27)
				)
			)
		)
		(duplicate_pad_numbers_are_jumpers no)
		(fp_line
			(start 0.7874 0.4064)
			(end -0.7874 0.4064)
			(stroke
				(width 0.1524)
				(type default)
			)
			(layer "F.SilkS")
		)
		(fp_line
			(start 0.7874 -0.4064)
			(end 0.7874 0.4064)
			(stroke
				(width 0.1524)
				(type default)
			)
			(layer "F.SilkS")
		)
		(fp_line
			(start -0.7874 0.4064)
			(end -0.7874 -0.4064)
			(stroke
				(width 0.1524)
				(type default)
			)
			(layer "F.SilkS")
		)
		(fp_line
			(start -0.7874 -0.4064)
			(end 0.7874 -0.4064)
			(stroke
				(width 0.1524)
				(type default)
			)
			(layer "F.SilkS")
		)
		(fp_line
			(start 0.67945 0.3048)
			(end 0.120396 0.3048)
			(stroke
				(width 0.1)
				(type default)
			)
			(layer "F.Fab")
		)
		(fp_line
			(start 0.67945 -0.3048)
			(end 0.67945 0.3048)
			(stroke
				(width 0.1)
				(type default)
			)
			(layer "F.Fab")
		)
		(fp_line
			(start 0.12065 -0.2794)
			(end 0.12065 -0.3048)
			(stroke
				(width 0.1)
				(type default)
			)
			(layer "F.Fab")
		)
		(fp_line
			(start 0.12065 -0.3048)
			(end 0.67945 -0.3048)
			(stroke
				(width 0.1)
				(type default)
			)
			(layer "F.Fab")
		)
		(fp_line
			(start 0.120396 0.3048)
			(end 0.120396 0.2794)
			(stroke
				(width 0.1)
				(type default)
			)
			(layer "F.Fab")
		)
		(fp_line
			(start 0.120396 0.2794)
			(end -0.12065 0.2794)
			(stroke
				(width 0.1)
				(type default)
			)
			(layer "F.Fab")
		)
		(fp_line
			(start -0.12065 0.3048)
			(end -0.67945 0.3048)
			(stroke
				(width 0.1)
				(type default)
			)
			(layer "F.Fab")
		)
		(fp_line
			(start -0.12065 0.2794)
			(end -0.12065 0.3048)
			(stroke
				(width 0.1)
				(type default)
			)
			(layer "F.Fab")
		)
		(fp_line
			(start -0.12065 -0.2794)
			(end 0.12065 -0.2794)
			(stroke
				(width 0.1)
				(type default)
			)
			(layer "F.Fab")
		)
		(fp_line
			(start -0.12065 -0.305054)
			(end -0.12065 -0.2794)
			(stroke
				(width 0.1)
				(type default)
			)
			(layer "F.Fab")
		)
		(fp_line
			(start -0.67945 0.3048)
			(end -0.67945 -0.305054)
			(stroke
				(width 0.1)
				(type default)
			)
			(layer "F.Fab")
		)
		(fp_line
			(start -0.67945 -0.305054)
			(end -0.12065 -0.305054)
			(stroke
				(width 0.1)
				(type default)
			)
			(layer "F.Fab")
		)
		(pad "1" smd circle
			(at -0.40005 0 180)
			(size 0 0)
			(layers "F.Cu" "F.Mask" "F.Paste")
			(net "CPU_FRU_ADDR0")
		)
		(pad "2" smd circle
			(at 0.40005 0 180)
			(size 0 0)
			(layers "F.Cu" "F.Mask" "F.Paste")
			(net "GND")
		)
	)
	(footprint ""
		(layer "F.Cu")
		(at 347.747844 -378.95403 -90)
		(property "Reference" "C946"
			(at 0 0 270)
			(layer "F.SilkS")
			(hide yes)
			(effects
				(font
					(size 1.27 1.27)
				)
			)
		)
		(property "Value" ""
			(at 0 0 270)
			(layer "F.Fab")
			(effects
				(font
					(size 1.27 1.27)
				)
			)
		)
		(duplicate_pad_numbers_are_jumpers no)
		(fp_line
			(start -0.299974 0.150114)
			(end -0.299974 -0.150114)
			(stroke
				(width 0.1)
				(type default)
			)
			(layer "F.Fab")
		)
		(fp_line
			(start 0.299974 0.150114)
			(end -0.299974 0.150114)
			(stroke
				(width 0.1)
				(type default)
			)
			(layer "F.Fab")
		)
		(fp_line
			(start -0.299974 -0.150114)
			(end 0.299974 -0.150114)
			(stroke
				(width 0.1)
				(type default)
			)
			(layer "F.Fab")
		)
		(fp_line
			(start 0.299974 -0.150114)
			(end 0.299974 0.150114)
			(stroke
				(width 0.1)
				(type default)
			)
			(layer "F.Fab")
		)
		(pad "1" smd rect
			(at -0.2667 0 270)
			(size 0.3048 0.381)
			(layers "F.Cu" "F.Mask" "F.Paste")
			(net "P5E_CPU0_P1_TX_C_DN<9>")
		)
		(pad "2" smd rect
			(at 0.2667 0 270)
			(size 0.3048 0.381)
			(layers "F.Cu" "F.Mask" "F.Paste")
			(net "P5E_CPU0_P1_TX_DN<9>")
		)
	)
	(footprint ""
		(layer "F.Cu")
		(at 94.1832 -401.9804 180)
		(property "Reference" "R1437"
			(at 0 0 180)
			(layer "F.SilkS")
			(hide yes)
			(effects
				(font
					(size 1.27 1.27)
				)
			)
		)
		(property "Value" ""
			(at 0 0 180)
			(layer "F.Fab")
			(effects
				(font
					(size 1.27 1.27)
				)
			)
		)
		(duplicate_pad_numbers_are_jumpers no)
		(fp_line
			(start 0.32512 0.175006)
			(end -0.32512 0.175006)
			(stroke
				(width 0.1)
				(type default)
			)
			(layer "F.Fab")
		)
		(fp_line
			(start 0.32512 -0.175006)
			(end 0.32512 0.175006)
			(stroke
				(width 0.1)
				(type default)
			)
			(layer "F.Fab")
		)
		(fp_line
			(start -0.32512 0.175006)
			(end -0.32512 -0.175006)
			(stroke
				(width 0.1)
				(type default)
			)
			(layer "F.Fab")
		)
		(fp_line
			(start -0.32512 -0.175006)
			(end 0.32512 -0.175006)
			(stroke
				(width 0.1)
				(type default)
			)
			(layer "F.Fab")
		)
		(pad "1" smd rect
			(at -0.2667 0 180)
			(size 0.3048 0.381)
			(layers "F.Cu" "F.Mask" "F.Paste")
			(net "P1V8_CPU1_RT_1D")
		)
		(pad "2" smd rect
			(at 0.2667 0)
			(size 0.3048 0.381)
			(layers "F.Cu" "F.Mask" "F.Paste")
			(net "SMB_RT_CPU1_P0_ROM_MUX_1D_SCL")
		)
	)
	(footprint ""
		(layer "F.Cu")
		(at 149.424644 -373.03583 -90)
		(property "Reference" "C763"
			(at 0 0 270)
			(layer "F.SilkS")
			(hide yes)
			(effects
				(font
					(size 1.27 1.27)
				)
			)
		)
		(property "Value" ""
			(at 0 0 270)
			(layer "F.Fab")
			(effects
				(font
					(size 1.27 1.27)
				)
			)
		)
		(duplicate_pad_numbers_are_jumpers no)
		(fp_line
			(start -0.299974 0.150114)
			(end -0.299974 -0.150114)
			(stroke
				(width 0.1)
				(type default)
			)
			(layer "F.Fab")
		)
		(fp_line
			(start 0.299974 0.150114)
			(end -0.299974 0.150114)
			(stroke
				(width 0.1)
				(type default)
			)
			(layer "F.Fab")
		)
		(fp_line
			(start -0.299974 -0.150114)
			(end 0.299974 -0.150114)
			(stroke
				(width 0.1)
				(type default)
			)
			(layer "F.Fab")
		)
		(fp_line
			(start 0.299974 -0.150114)
			(end 0.299974 0.150114)
			(stroke
				(width 0.1)
				(type default)
			)
			(layer "F.Fab")
		)
		(pad "1" smd rect
			(at -0.2667 0 270)
			(size 0.3048 0.381)
			(layers "F.Cu" "F.Mask" "F.Paste")
			(net "P5E_CPU1_P2_TX_C_DP<5>")
		)
		(pad "2" smd rect
			(at 0.2667 0 270)
			(size 0.3048 0.381)
			(layers "F.Cu" "F.Mask" "F.Paste")
			(net "P5E_CPU1_P2_TX_DP<5>")
		)
	)
	(footprint ""
		(layer "F.Cu")
		(at 171.196 -116.296948)
		(property "Reference" "R51"
			(at 0 0 0)
			(layer "F.SilkS")
			(hide yes)
			(effects
				(font
					(size 1.27 1.27)
				)
			)
		)
		(property "Value" ""
			(at 0 0 0)
			(layer "F.Fab")
			(effects
				(font
					(size 1.27 1.27)
				)
			)
		)
		(duplicate_pad_numbers_are_jumpers no)
		(fp_line
			(start -0.7874 -0.4064)
			(end 0.7874 -0.4064)
			(stroke
				(width 0.1524)
				(type default)
			)
			(layer "F.SilkS")
		)
		(fp_line
			(start -0.7874 0.4064)
			(end -0.7874 -0.4064)
			(stroke
				(width 0.1524)
				(type default)
			)
			(layer "F.SilkS")
		)
		(fp_line
			(start 0.7874 -0.4064)
			(end 0.7874 0.4064)
			(stroke
				(width 0.1524)
				(type default)
			)
			(layer "F.SilkS")
		)
		(fp_line
			(start 0.7874 0.4064)
			(end -0.7874 0.4064)
			(stroke
				(width 0.1524)
				(type default)
			)
			(layer "F.SilkS")
		)
		(fp_line
			(start -0.67945 -0.305054)
			(end -0.12065 -0.305054)
			(stroke
				(width 0.1)
				(type default)
			)
			(layer "F.Fab")
		)
		(fp_line
			(start -0.67945 0.3048)
			(end -0.67945 -0.305054)
			(stroke
				(width 0.1)
				(type default)
			)
			(layer "F.Fab")
		)
		(fp_line
			(start -0.12065 -0.305054)
			(end -0.12065 -0.2794)
			(stroke
				(width 0.1)
				(type default)
			)
			(layer "F.Fab")
		)
		(fp_line
			(start -0.12065 -0.2794)
			(end 0.12065 -0.2794)
			(stroke
				(width 0.1)
				(type default)
			)
			(layer "F.Fab")
		)
		(fp_line
			(start -0.12065 0.2794)
			(end -0.12065 0.3048)
			(stroke
				(width 0.1)
				(type default)
			)
			(layer "F.Fab")
		)
		(fp_line
			(start -0.12065 0.3048)
			(end -0.67945 0.3048)
			(stroke
				(width 0.1)
				(type default)
			)
			(layer "F.Fab")
		)
		(fp_line
			(start 0.120396 0.2794)
			(end -0.12065 0.2794)
			(stroke
				(width 0.1)
				(type default)
			)
			(layer "F.Fab")
		)
		(fp_line
			(start 0.120396 0.3048)
			(end 0.120396 0.2794)
			(stroke
				(width 0.1)
				(type default)
			)
			(layer "F.Fab")
		)
		(fp_line
			(start 0.12065 -0.3048)
			(end 0.67945 -0.3048)
			(stroke
				(width 0.1)
				(type default)
			)
			(layer "F.Fab")
		)
		(fp_line
			(start 0.12065 -0.2794)
			(end 0.12065 -0.3048)
			(stroke
				(width 0.1)
				(type default)
			)
			(layer "F.Fab")
		)
		(fp_line
			(start 0.67945 -0.3048)
			(end 0.67945 0.3048)
			(stroke
				(width 0.1)
				(type default)
			)
			(layer "F.Fab")
		)
		(fp_line
			(start 0.67945 0.3048)
			(end 0.120396 0.3048)
			(stroke
				(width 0.1)
				(type default)
			)
			(layer "F.Fab")
		)
		(pad "1" smd circle
			(at -0.40005 0)
			(size 0 0)
			(layers "F.Cu" "F.Mask" "F.Paste")
			(net "SMB_1_PLD_3V3AUX_SCL_R1")
		)
		(pad "2" smd circle
			(at 0.40005 0)
			(size 0 0)
			(layers "F.Cu" "F.Mask" "F.Paste")
			(net "SMB_1_PLD_3V3AUX_SCL_R2")
		)
	)
	(footprint ""
		(layer "F.Cu")
		(at 204.792834 -343.404952)
		(property "Reference" "C348"
			(at 0 0 0)
			(layer "F.SilkS")
			(hide yes)
			(effects
				(font
					(size 1.27 1.27)
				)
			)
		)
		(property "Value" ""
			(at 0 0 0)
			(layer "F.Fab")
			(effects
				(font
					(size 1.27 1.27)
				)
			)
		)
		(duplicate_pad_numbers_are_jumpers no)
		(fp_line
			(start -0.7874 -0.4064)
			(end 0.7874 -0.4064)
			(stroke
				(width 0.1524)
				(type default)
			)
			(layer "F.SilkS")
		)
		(fp_line
			(start -0.7874 0.4064)
			(end -0.7874 -0.4064)
			(stroke
				(width 0.1524)
				(type default)
			)
			(layer "F.SilkS")
		)
		(fp_line
			(start 0.7874 -0.4064)
			(end 0.7874 0.4064)
			(stroke
				(width 0.1524)
				(type default)
			)
			(layer "F.SilkS")
		)
		(fp_line
			(start 0.7874 0.4064)
			(end -0.7874 0.4064)
			(stroke
				(width 0.1524)
				(type default)
			)
			(layer "F.SilkS")
		)
		(fp_line
			(start -0.67945 -0.305054)
			(end -0.12065 -0.305054)
			(stroke
				(width 0.1)
				(type default)
			)
			(layer "F.Fab")
		)
		(fp_line
			(start -0.67945 0.3048)
			(end -0.67945 -0.305054)
			(stroke
				(width 0.1)
				(type default)
			)
			(layer "F.Fab")
		)
		(fp_line
			(start -0.12065 -0.305054)
			(end -0.12065 -0.2794)
			(stroke
				(width 0.1)
				(type default)
			)
			(layer "F.Fab")
		)
		(fp_line
			(start -0.12065 -0.2794)
			(end 0.12065 -0.2794)
			(stroke
				(width 0.1)
				(type default)
			)
			(layer "F.Fab")
		)
		(fp_line
			(start -0.12065 0.2794)
			(end -0.12065 0.3048)
			(stroke
				(width 0.1)
				(type default)
			)
			(layer "F.Fab")
		)
		(fp_line
			(start -0.12065 0.3048)
			(end -0.67945 0.3048)
			(stroke
				(width 0.1)
				(type default)
			)
			(layer "F.Fab")
		)
		(fp_line
			(start 0.120396 0.2794)
			(end -0.12065 0.2794)
			(stroke
				(width 0.1)
				(type default)
			)
			(layer "F.Fab")
		)
		(fp_line
			(start 0.120396 0.3048)
			(end 0.120396 0.2794)
			(stroke
				(width 0.1)
				(type default)
			)
			(layer "F.Fab")
		)
		(fp_line
			(start 0.12065 -0.3048)
			(end 0.67945 -0.3048)
			(stroke
				(width 0.1)
				(type default)
			)
			(layer "F.Fab")
		)
		(fp_line
			(start 0.12065 -0.2794)
			(end 0.12065 -0.3048)
			(stroke
				(width 0.1)
				(type default)
			)
			(layer "F.Fab")
		)
		(fp_line
			(start 0.67945 -0.3048)
			(end 0.67945 0.3048)
			(stroke
				(width 0.1)
				(type default)
			)
			(layer "F.Fab")
		)
		(fp_line
			(start 0.67945 0.3048)
			(end 0.120396 0.3048)
			(stroke
				(width 0.1)
				(type default)
			)
			(layer "F.Fab")
		)
		(pad "1" smd circle
			(at -0.40005 0)
			(size 0 0)
			(layers "F.Cu" "F.Mask" "F.Paste")
			(net "PVDD33_S5_EN")
		)
		(pad "2" smd circle
			(at 0.40005 0)
			(size 0 0)
			(layers "F.Cu" "F.Mask" "F.Paste")
			(net "GND")
		)
	)
	(footprint ""
		(layer "F.Cu")
		(at 304.419 -355.854)
		(property "Reference" "R61"
			(at 0 0 0)
			(layer "F.SilkS")
			(hide yes)
			(effects
				(font
					(size 1.27 1.27)
				)
			)
		)
		(property "Value" ""
			(at 0 0 0)
			(layer "F.Fab")
			(effects
				(font
					(size 1.27 1.27)
				)
			)
		)
		(duplicate_pad_numbers_are_jumpers no)
		(fp_line
			(start -0.7874 -0.4064)
			(end 0.7874 -0.4064)
			(stroke
				(width 0.1524)
				(type default)
			)
			(layer "F.SilkS")
		)
		(fp_line
			(start -0.7874 0.4064)
			(end -0.7874 -0.4064)
			(stroke
				(width 0.1524)
				(type default)
			)
			(layer "F.SilkS")
		)
		(fp_line
			(start 0.7874 -0.4064)
			(end 0.7874 0.4064)
			(stroke
				(width 0.1524)
				(type default)
			)
			(layer "F.SilkS")
		)
		(fp_line
			(start 0.7874 0.4064)
			(end -0.7874 0.4064)
			(stroke
				(width 0.1524)
				(type default)
			)
			(layer "F.SilkS")
		)
		(fp_line
			(start -0.67945 -0.305054)
			(end -0.12065 -0.305054)
			(stroke
				(width 0.1)
				(type default)
			)
			(layer "F.Fab")
		)
		(fp_line
			(start -0.67945 0.3048)
			(end -0.67945 -0.305054)
			(stroke
				(width 0.1)
				(type default)
			)
			(layer "F.Fab")
		)
		(fp_line
			(start -0.12065 -0.305054)
			(end -0.12065 -0.2794)
			(stroke
				(width 0.1)
				(type default)
			)
			(layer "F.Fab")
		)
		(fp_line
			(start -0.12065 -0.2794)
			(end 0.12065 -0.2794)
			(stroke
				(width 0.1)
				(type default)
			)
			(layer "F.Fab")
		)
		(fp_line
			(start -0.12065 0.2794)
			(end -0.12065 0.3048)
			(stroke
				(width 0.1)
				(type default)
			)
			(layer "F.Fab")
		)
		(fp_line
			(start -0.12065 0.3048)
			(end -0.67945 0.3048)
			(stroke
				(width 0.1)
				(type default)
			)
			(layer "F.Fab")
		)
		(fp_line
			(start 0.120396 0.2794)
			(end -0.12065 0.2794)
			(stroke
				(width 0.1)
				(type default)
			)
			(layer "F.Fab")
		)
		(fp_line
			(start 0.120396 0.3048)
			(end 0.120396 0.2794)
			(stroke
				(width 0.1)
				(type default)
			)
			(layer "F.Fab")
		)
		(fp_line
			(start 0.12065 -0.3048)
			(end 0.67945 -0.3048)
			(stroke
				(width 0.1)
				(type default)
			)
			(layer "F.Fab")
		)
		(fp_line
			(start 0.12065 -0.2794)
			(end 0.12065 -0.3048)
			(stroke
				(width 0.1)
				(type default)
			)
			(layer "F.Fab")
		)
		(fp_line
			(start 0.67945 -0.3048)
			(end 0.67945 0.3048)
			(stroke
				(width 0.1)
				(type default)
			)
			(layer "F.Fab")
		)
		(fp_line
			(start 0.67945 0.3048)
			(end 0.120396 0.3048)
			(stroke
				(width 0.1)
				(type default)
			)
			(layer "F.Fab")
		)
		(pad "1" smd circle
			(at -0.40005 0)
			(size 0 0)
			(layers "F.Cu" "F.Mask" "F.Paste")
			(net "SVID_PVDDCR_CPU1_P0_SVTO")
		)
		(pad "2" smd circle
			(at 0.40005 0)
			(size 0 0)
			(layers "F.Cu" "F.Mask" "F.Paste")
			(net "SVID_PVDDCR_CPU1_P0_SVTO_R")
		)
	)
	(footprint ""
		(layer "F.Cu")
		(at 21.096478 -16.099536 90)
		(property "Reference" "C682"
			(at 0 0 90)
			(layer "F.SilkS")
			(hide yes)
			(effects
				(font
					(size 1.27 1.27)
				)
			)
		)
		(property "Value" ""
			(at 0 0 90)
			(layer "F.Fab")
			(effects
				(font
					(size 1.27 1.27)
				)
			)
		)
		(duplicate_pad_numbers_are_jumpers no)
		(fp_line
			(start 0.299974 -0.150114)
			(end 0.299974 0.150114)
			(stroke
				(width 0.1)
				(type default)
			)
			(layer "F.Fab")
		)
		(fp_line
			(start -0.299974 -0.150114)
			(end 0.299974 -0.150114)
			(stroke
				(width 0.1)
				(type default)
			)
			(layer "F.Fab")
		)
		(fp_line
			(start 0.299974 0.150114)
			(end -0.299974 0.150114)
			(stroke
				(width 0.1)
				(type default)
			)
			(layer "F.Fab")
		)
		(fp_line
			(start -0.299974 0.150114)
			(end -0.299974 -0.150114)
			(stroke
				(width 0.1)
				(type default)
			)
			(layer "F.Fab")
		)
		(pad "1" smd rect
			(at -0.2667 0 90)
			(size 0.3048 0.381)
			(layers "F.Cu" "F.Mask" "F.Paste")
			(net "P5E_CPU1_G1_TX_C_DN<13>")
		)
		(pad "2" smd rect
			(at 0.2667 0 90)
			(size 0.3048 0.381)
			(layers "F.Cu" "F.Mask" "F.Paste")
			(net "P5E_CPU1_G1_TX_DN<13>")
		)
	)
	(footprint ""
		(layer "F.Cu")
		(at 248.210578 -277.433532)
		(property "Reference" "PC6800"
			(at -1.068578 -4.352798 0)
			(unlocked yes)
			(layer "F.SilkS")
			(effects
				(font
					(size 0.7874 0.5842)
					(thickness 0.1524)
				)
				(justify left)
			)
		)
		(property "Value" ""
			(at 0 0 0)
			(layer "F.Fab")
			(effects
				(font
					(size 1.27 1.27)
				)
			)
		)
		(duplicate_pad_numbers_are_jumpers no)
		(fp_line
			(start -3.400044 -2.146046)
			(end -3.400044 -0.9398)
			(stroke
				(width 0.1524)
				(type default)
			)
			(layer "F.SilkS")
		)
		(fp_line
			(start -3.400044 2.146046)
			(end -3.400044 0.9398)
			(stroke
				(width 0.1524)
				(type default)
			)
			(layer "F.SilkS")
		)
		(fp_line
			(start -2.146046 -3.400044)
			(end -3.400044 -2.146046)
			(stroke
				(width 0.1524)
				(type default)
			)
			(layer "F.SilkS")
		)
		(fp_line
			(start -2.146046 3.400044)
			(end -3.400044 2.146046)
			(stroke
				(width 0.1524)
				(type default)
			)
			(layer "F.SilkS")
		)
		(fp_line
			(start 3.400044 -3.400044)
			(end -2.146046 -3.400044)
			(stroke
				(width 0.1524)
				(type default)
			)
			(layer "F.SilkS")
		)
		(fp_line
			(start 3.400044 -0.9398)
			(end 3.400044 -3.400044)
			(stroke
				(width 0.1524)
				(type default)
			)
			(layer "F.SilkS")
		)
		(fp_line
			(start 3.400044 0.9398)
			(end 3.400044 3.400044)
			(stroke
				(width 0.1524)
				(type default)
			)
			(layer "F.SilkS")
		)
		(fp_line
			(start 3.400044 3.400044)
			(end -2.146046 3.400044)
			(stroke
				(width 0.1524)
				(type default)
			)
			(layer "F.SilkS")
		)
		(fp_line
			(start -3.400044 -3.400044)
			(end -3.400044 3.400044)
			(stroke
				(width 0.1)
				(type default)
			)
			(layer "F.Fab")
		)
		(fp_line
			(start -3.400044 3.400044)
			(end 3.400044 3.400044)
			(stroke
				(width 0.1)
				(type default)
			)
			(layer "F.Fab")
		)
		(fp_line
			(start 3.400044 -3.400044)
			(end -3.400044 -3.400044)
			(stroke
				(width 0.1)
				(type default)
			)
			(layer "F.Fab")
		)
		(fp_line
			(start 3.400044 3.400044)
			(end 3.400044 -3.400044)
			(stroke
				(width 0.1)
				(type default)
			)
			(layer "F.Fab")
		)
		(pad "1" smd rect
			(at -2.70002 0 270)
			(size 1.6002 3.5052)
			(layers "F.Cu" "F.Mask" "F.Paste")
			(net "SW_P12V_AUX_P1V8_RETIMER_CPU0_FLT")
		)
		(pad "2" smd rect
			(at 2.70002 0 270)
			(size 1.6002 3.5052)
			(layers "F.Cu" "F.Mask" "F.Paste")
			(net "GND")
		)
	)
	(footprint ""
		(layer "F.Cu")
		(at 178.71694 -399.420842 180)
		(property "Reference" "PR1131"
			(at 0 0 180)
			(layer "F.SilkS")
			(hide yes)
			(effects
				(font
					(size 1.27 1.27)
				)
			)
		)
		(property "Value" ""
			(at 0 0 180)
			(layer "F.Fab")
			(effects
				(font
					(size 1.27 1.27)
				)
			)
		)
		(duplicate_pad_numbers_are_jumpers no)
		(fp_line
			(start 0.7874 0.4064)
			(end -0.7874 0.4064)
			(stroke
				(width 0.1524)
				(type default)
			)
			(layer "F.SilkS")
		)
		(fp_line
			(start 0.7874 -0.4064)
			(end 0.7874 0.4064)
			(stroke
				(width 0.1524)
				(type default)
			)
			(layer "F.SilkS")
		)
		(fp_line
			(start -0.7874 0.4064)
			(end -0.7874 -0.4064)
			(stroke
				(width 0.1524)
				(type default)
			)
			(layer "F.SilkS")
		)
		(fp_line
			(start -0.7874 -0.4064)
			(end 0.7874 -0.4064)
			(stroke
				(width 0.1524)
				(type default)
			)
			(layer "F.SilkS")
		)
		(fp_line
			(start 0.67945 0.3048)
			(end 0.120396 0.3048)
			(stroke
				(width 0.1)
				(type default)
			)
			(layer "F.Fab")
		)
		(fp_line
			(start 0.67945 -0.3048)
			(end 0.67945 0.3048)
			(stroke
				(width 0.1)
				(type default)
			)
			(layer "F.Fab")
		)
		(fp_line
			(start 0.12065 -0.2794)
			(end 0.12065 -0.3048)
			(stroke
				(width 0.1)
				(type default)
			)
			(layer "F.Fab")
		)
		(fp_line
			(start 0.12065 -0.3048)
			(end 0.67945 -0.3048)
			(stroke
				(width 0.1)
				(type default)
			)
			(layer "F.Fab")
		)
		(fp_line
			(start 0.120396 0.3048)
			(end 0.120396 0.2794)
			(stroke
				(width 0.1)
				(type default)
			)
			(layer "F.Fab")
		)
		(fp_line
			(start 0.120396 0.2794)
			(end -0.12065 0.2794)
			(stroke
				(width 0.1)
				(type default)
			)
			(layer "F.Fab")
		)
		(fp_line
			(start -0.12065 0.3048)
			(end -0.67945 0.3048)
			(stroke
				(width 0.1)
				(type default)
			)
			(layer "F.Fab")
		)
		(fp_line
			(start -0.12065 0.2794)
			(end -0.12065 0.3048)
			(stroke
				(width 0.1)
				(type default)
			)
			(layer "F.Fab")
		)
		(fp_line
			(start -0.12065 -0.2794)
			(end 0.12065 -0.2794)
			(stroke
				(width 0.1)
				(type default)
			)
			(layer "F.Fab")
		)
		(fp_line
			(start -0.12065 -0.305054)
			(end -0.12065 -0.2794)
			(stroke
				(width 0.1)
				(type default)
			)
			(layer "F.Fab")
		)
		(fp_line
			(start -0.67945 0.3048)
			(end -0.67945 -0.305054)
			(stroke
				(width 0.1)
				(type default)
			)
			(layer "F.Fab")
		)
		(fp_line
			(start -0.67945 -0.305054)
			(end -0.12065 -0.305054)
			(stroke
				(width 0.1)
				(type default)
			)
			(layer "F.Fab")
		)
		(pad "1" smd circle
			(at -0.40005 0 180)
			(size 0 0)
			(layers "F.Cu" "F.Mask" "F.Paste")
			(net "HSC_CS")
		)
		(pad "2" smd circle
			(at 0.40005 0 180)
			(size 0 0)
			(layers "F.Cu" "F.Mask" "F.Paste")
			(net "AGND_HSC")
		)
	)
	(footprint ""
		(layer "F.Cu")
		(at 150.502366 -54.172358 180)
		(property "Reference" "R3560"
			(at 0 0 180)
			(layer "F.SilkS")
			(hide yes)
			(effects
				(font
					(size 1.27 1.27)
				)
			)
		)
		(property "Value" ""
			(at 0 0 180)
			(layer "F.Fab")
			(effects
				(font
					(size 1.27 1.27)
				)
			)
		)
		(duplicate_pad_numbers_are_jumpers no)
		(fp_line
			(start 0.7874 0.4064)
			(end -0.7874 0.4064)
			(stroke
				(width 0.1524)
				(type default)
			)
			(layer "F.SilkS")
		)
		(fp_line
			(start 0.7874 -0.4064)
			(end 0.7874 0.4064)
			(stroke
				(width 0.1524)
				(type default)
			)
			(layer "F.SilkS")
		)
		(fp_line
			(start -0.7874 0.4064)
			(end -0.7874 -0.4064)
			(stroke
				(width 0.1524)
				(type default)
			)
			(layer "F.SilkS")
		)
		(fp_line
			(start -0.7874 -0.4064)
			(end 0.7874 -0.4064)
			(stroke
				(width 0.1524)
				(type default)
			)
			(layer "F.SilkS")
		)
		(fp_line
			(start 0.67945 0.3048)
			(end 0.120396 0.3048)
			(stroke
				(width 0.1)
				(type default)
			)
			(layer "F.Fab")
		)
		(fp_line
			(start 0.67945 -0.3048)
			(end 0.67945 0.3048)
			(stroke
				(width 0.1)
				(type default)
			)
			(layer "F.Fab")
		)
		(fp_line
			(start 0.12065 -0.2794)
			(end 0.12065 -0.3048)
			(stroke
				(width 0.1)
				(type default)
			)
			(layer "F.Fab")
		)
		(fp_line
			(start 0.12065 -0.3048)
			(end 0.67945 -0.3048)
			(stroke
				(width 0.1)
				(type default)
			)
			(layer "F.Fab")
		)
		(fp_line
			(start 0.120396 0.3048)
			(end 0.120396 0.2794)
			(stroke
				(width 0.1)
				(type default)
			)
			(layer "F.Fab")
		)
		(fp_line
			(start 0.120396 0.2794)
			(end -0.12065 0.2794)
			(stroke
				(width 0.1)
				(type default)
			)
			(layer "F.Fab")
		)
		(fp_line
			(start -0.12065 0.3048)
			(end -0.67945 0.3048)
			(stroke
				(width 0.1)
				(type default)
			)
			(layer "F.Fab")
		)
		(fp_line
			(start -0.12065 0.2794)
			(end -0.12065 0.3048)
			(stroke
				(width 0.1)
				(type default)
			)
			(layer "F.Fab")
		)
		(fp_line
			(start -0.12065 -0.2794)
			(end 0.12065 -0.2794)
			(stroke
				(width 0.1)
				(type default)
			)
			(layer "F.Fab")
		)
		(fp_line
			(start -0.12065 -0.305054)
			(end -0.12065 -0.2794)
			(stroke
				(width 0.1)
				(type default)
			)
			(layer "F.Fab")
		)
		(fp_line
			(start -0.67945 0.3048)
			(end -0.67945 -0.305054)
			(stroke
				(width 0.1)
				(type default)
			)
			(layer "F.Fab")
		)
		(fp_line
			(start -0.67945 -0.305054)
			(end -0.12065 -0.305054)
			(stroke
				(width 0.1)
				(type default)
			)
			(layer "F.Fab")
		)
		(pad "1" smd circle
			(at -0.40005 0 180)
			(size 0 0)
			(layers "F.Cu" "F.Mask" "F.Paste")
			(net "M2_0_P3V3_ADC_ALERT_R")
		)
		(pad "2" smd circle
			(at 0.40005 0 180)
			(size 0 0)
			(layers "F.Cu" "F.Mask" "F.Paste")
			(net "M2_0_P3V3_ADC_ALERT")
		)
	)
	(footprint ""
		(layer "F.Cu")
		(at 69.977 -59.055 90)
		(property "Reference" "C1062"
			(at 0 0 90)
			(layer "F.SilkS")
			(hide yes)
			(effects
				(font
					(size 1.27 1.27)
				)
			)
		)
		(property "Value" ""
			(at 0 0 90)
			(layer "F.Fab")
			(effects
				(font
					(size 1.27 1.27)
				)
			)
		)
		(duplicate_pad_numbers_are_jumpers no)
		(fp_line
			(start 0.7874 -0.4064)
			(end 0.7874 0.4064)
			(stroke
				(width 0.1524)
				(type default)
			)
			(layer "F.SilkS")
		)
		(fp_line
			(start -0.7874 -0.4064)
			(end 0.7874 -0.4064)
			(stroke
				(width 0.1524)
				(type default)
			)
			(layer "F.SilkS")
		)
		(fp_line
			(start 0.7874 0.4064)
			(end -0.7874 0.4064)
			(stroke
				(width 0.1524)
				(type default)
			)
			(layer "F.SilkS")
		)
		(fp_line
			(start -0.7874 0.4064)
			(end -0.7874 -0.4064)
			(stroke
				(width 0.1524)
				(type default)
			)
			(layer "F.SilkS")
		)
		(fp_line
			(start -0.12065 -0.305054)
			(end -0.12065 -0.2794)
			(stroke
				(width 0.1)
				(type default)
			)
			(layer "F.Fab")
		)
		(fp_line
			(start -0.67945 -0.305054)
			(end -0.12065 -0.305054)
			(stroke
				(width 0.1)
				(type default)
			)
			(layer "F.Fab")
		)
		(fp_line
			(start 0.67945 -0.3048)
			(end 0.67945 0.3048)
			(stroke
				(width 0.1)
				(type default)
			)
			(layer "F.Fab")
		)
		(fp_line
			(start 0.12065 -0.3048)
			(end 0.67945 -0.3048)
			(stroke
				(width 0.1)
				(type default)
			)
			(layer "F.Fab")
		)
		(fp_line
			(start 0.12065 -0.2794)
			(end 0.12065 -0.3048)
			(stroke
				(width 0.1)
				(type default)
			)
			(layer "F.Fab")
		)
		(fp_line
			(start -0.12065 -0.2794)
			(end 0.12065 -0.2794)
			(stroke
				(width 0.1)
				(type default)
			)
			(layer "F.Fab")
		)
		(fp_line
			(start 0.120396 0.2794)
			(end -0.12065 0.2794)
			(stroke
				(width 0.1)
				(type default)
			)
			(layer "F.Fab")
		)
		(fp_line
			(start -0.12065 0.2794)
			(end -0.12065 0.3048)
			(stroke
				(width 0.1)
				(type default)
			)
			(layer "F.Fab")
		)
		(fp_line
			(start 0.67945 0.3048)
			(end 0.120396 0.3048)
			(stroke
				(width 0.1)
				(type default)
			)
			(layer "F.Fab")
		)
		(fp_line
			(start 0.120396 0.3048)
			(end 0.120396 0.2794)
			(stroke
				(width 0.1)
				(type default)
			)
			(layer "F.Fab")
		)
		(fp_line
			(start -0.12065 0.3048)
			(end -0.67945 0.3048)
			(stroke
				(width 0.1)
				(type default)
			)
			(layer "F.Fab")
		)
		(fp_line
			(start -0.67945 0.3048)
			(end -0.67945 -0.305054)
			(stroke
				(width 0.1)
				(type default)
			)
			(layer "F.Fab")
		)
		(pad "1" smd circle
			(at -0.40005 0 90)
			(size 0 0)
			(layers "F.Cu" "F.Mask" "F.Paste")
			(net "P3V3_AUX")
		)
		(pad "2" smd circle
			(at 0.40005 0 90)
			(size 0 0)
			(layers "F.Cu" "F.Mask" "F.Paste")
			(net "GND")
		)
	)
	(footprint ""
		(layer "F.Cu")
		(at 193.929 -96.103948 -90)
		(property "Reference" "R271"
			(at 0 0 270)
			(layer "F.SilkS")
			(hide yes)
			(effects
				(font
					(size 1.27 1.27)
				)
			)
		)
		(property "Value" ""
			(at 0 0 270)
			(layer "F.Fab")
			(effects
				(font
					(size 1.27 1.27)
				)
			)
		)
		(duplicate_pad_numbers_are_jumpers no)
		(fp_line
			(start -0.7874 0.4064)
			(end -0.7874 -0.4064)
			(stroke
				(width 0.1524)
				(type default)
			)
			(layer "F.SilkS")
		)
		(fp_line
			(start 0.7874 0.4064)
			(end -0.7874 0.4064)
			(stroke
				(width 0.1524)
				(type default)
			)
			(layer "F.SilkS")
		)
		(fp_line
			(start -0.7874 -0.4064)
			(end 0.7874 -0.4064)
			(stroke
				(width 0.1524)
				(type default)
			)
			(layer "F.SilkS")
		)
		(fp_line
			(start 0.7874 -0.4064)
			(end 0.7874 0.4064)
			(stroke
				(width 0.1524)
				(type default)
			)
			(layer "F.SilkS")
		)
		(fp_line
			(start -0.67945 0.3048)
			(end -0.67945 -0.305054)
			(stroke
				(width 0.1)
				(type default)
			)
			(layer "F.Fab")
		)
		(fp_line
			(start -0.12065 0.3048)
			(end -0.67945 0.3048)
			(stroke
				(width 0.1)
				(type default)
			)
			(layer "F.Fab")
		)
		(fp_line
			(start 0.120396 0.3048)
			(end 0.120396 0.2794)
			(stroke
				(width 0.1)
				(type default)
			)
			(layer "F.Fab")
		)
		(fp_line
			(start 0.67945 0.3048)
			(end 0.120396 0.3048)
			(stroke
				(width 0.1)
				(type default)
			)
			(layer "F.Fab")
		)
		(fp_line
			(start -0.12065 0.2794)
			(end -0.12065 0.3048)
			(stroke
				(width 0.1)
				(type default)
			)
			(layer "F.Fab")
		)
		(fp_line
			(start 0.120396 0.2794)
			(end -0.12065 0.2794)
			(stroke
				(width 0.1)
				(type default)
			)
			(layer "F.Fab")
		)
		(fp_line
			(start -0.12065 -0.2794)
			(end 0.12065 -0.2794)
			(stroke
				(width 0.1)
				(type default)
			)
			(layer "F.Fab")
		)
		(fp_line
			(start 0.12065 -0.2794)
			(end 0.12065 -0.3048)
			(stroke
				(width 0.1)
				(type default)
			)
			(layer "F.Fab")
		)
		(fp_line
			(start 0.12065 -0.3048)
			(end 0.67945 -0.3048)
			(stroke
				(width 0.1)
				(type default)
			)
			(layer "F.Fab")
		)
		(fp_line
			(start 0.67945 -0.3048)
			(end 0.67945 0.3048)
			(stroke
				(width 0.1)
				(type default)
			)
			(layer "F.Fab")
		)
		(fp_line
			(start -0.67945 -0.305054)
			(end -0.12065 -0.305054)
			(stroke
				(width 0.1)
				(type default)
			)
			(layer "F.Fab")
		)
		(fp_line
			(start -0.12065 -0.305054)
			(end -0.12065 -0.2794)
			(stroke
				(width 0.1)
				(type default)
			)
			(layer "F.Fab")
		)
		(pad "1" smd circle
			(at -0.40005 0 270)
			(size 0 0)
			(layers "F.Cu" "F.Mask" "F.Paste")
			(net "FM_PRSNT_CPU1_R_N")
		)
		(pad "2" smd circle
			(at 0.40005 0 270)
			(size 0 0)
			(layers "F.Cu" "F.Mask" "F.Paste")
			(net "FM_PRSNT_CPU1_N")
		)
	)
	(footprint ""
		(layer "F.Cu")
		(at 45.25391 -337.403948)
		(property "Reference" "PL48"
			(at -3.115056 -15.887446 0)
			(unlocked yes)
			(layer "F.SilkS")
			(effects
				(font
					(size 0.7874 0.5842)
					(thickness 0.1524)
				)
				(justify left)
			)
		)
		(property "Value" ""
			(at 0 0 0)
			(layer "F.Fab")
			(effects
				(font
					(size 1.27 1.27)
				)
			)
		)
		(duplicate_pad_numbers_are_jumpers no)
		(fp_line
			(start -3.750056 -5.500116)
			(end -2.393442 -5.500116)
			(stroke
				(width 0.1524)
				(type default)
			)
			(layer "F.SilkS")
		)
		(fp_line
			(start -3.750056 5.500116)
			(end -3.750056 -5.500116)
			(stroke
				(width 0.1524)
				(type default)
			)
			(layer "F.SilkS")
		)
		(fp_line
			(start -2.393442 5.500116)
			(end -3.750056 5.500116)
			(stroke
				(width 0.1524)
				(type default)
			)
			(layer "F.SilkS")
		)
		(fp_line
			(start 2.393442 5.500116)
			(end 3.750056 5.500116)
			(stroke
				(width 0.1524)
				(type default)
			)
			(layer "F.SilkS")
		)
		(fp_line
			(start 3.750056 -5.500116)
			(end 2.393442 -5.500116)
			(stroke
				(width 0.1524)
				(type default)
			)
			(layer "F.SilkS")
		)
		(fp_line
			(start 3.750056 5.500116)
			(end 3.750056 -5.500116)
			(stroke
				(width 0.1524)
				(type default)
			)
			(layer "F.SilkS")
		)
		(fp_poly
			(pts
				(xy -3.9116 -4.249928) (xy -4.35991 -4.0259) (xy -4.35991 -4.473956)
			)
			(stroke
				(width 0)
				(type default)
			)
			(fill yes)
			(layer "F.SilkS")
		)
		(fp_line
			(start -3.750056 -5.500116)
			(end -3.750056 5.500116)
			(stroke
				(width 0.1)
				(type default)
			)
			(layer "F.Fab")
		)
		(fp_line
			(start -3.750056 5.500116)
			(end 3.750056 5.500116)
			(stroke
				(width 0.1)
				(type default)
			)
			(layer "F.Fab")
		)
		(fp_line
			(start 3.750056 -5.500116)
			(end -3.750056 -5.500116)
			(stroke
				(width 0.1)
				(type default)
			)
			(layer "F.Fab")
		)
		(fp_line
			(start 3.750056 5.500116)
			(end 3.750056 -5.500116)
			(stroke
				(width 0.1)
				(type default)
			)
			(layer "F.Fab")
		)
		(fp_poly
			(pts
				(xy -4.9276 -4.757928) (xy -4.9276 -3.741928) (xy -3.9116 -4.249928)
			)
			(stroke
				(width 0)
				(type default)
			)
			(fill yes)
			(layer "F.Fab")
		)
		(pad "1" smd rect
			(at 0 -4.249928 270)
			(size 2.413 4.5212)
			(layers "F.Cu" "F.Mask" "F.Paste")
			(net "SW_PVDDIO_P1_SW2")
		)
		(pad "2" smd rect
			(at 0 -1.175004 270)
			(size 1.3716 4.5212)
			(layers "F.Cu" "F.Mask" "F.Paste")
			(net "IND_PVDDIO_P1_CPL3")
		)
		(pad "3" smd rect
			(at 0 1.175004 270)
			(size 1.3716 4.5212)
			(layers "F.Cu" "F.Mask" "F.Paste")
			(net "IND_PVDDIO_P1_CPL2")
		)
		(pad "4" smd rect
			(at 0 4.249928 270)
			(size 2.413 4.5212)
			(layers "F.Cu" "F.Mask" "F.Paste")
			(net "PVDDIO_P1")
		)
	)
	(footprint ""
		(layer "F.Cu")
		(at 15.58417 -78.830678)
		(property "Reference" "C1809"
			(at 0 0 0)
			(layer "F.SilkS")
			(hide yes)
			(effects
				(font
					(size 1.27 1.27)
				)
			)
		)
		(property "Value" ""
			(at 0 0 0)
			(layer "F.Fab")
			(effects
				(font
					(size 1.27 1.27)
				)
			)
		)
		(duplicate_pad_numbers_are_jumpers no)
		(fp_line
			(start -0.7874 -0.4064)
			(end 0.7874 -0.4064)
			(stroke
				(width 0.1524)
				(type default)
			)
			(layer "F.SilkS")
		)
		(fp_line
			(start -0.7874 0.4064)
			(end -0.7874 -0.4064)
			(stroke
				(width 0.1524)
				(type default)
			)
			(layer "F.SilkS")
		)
		(fp_line
			(start 0.7874 -0.4064)
			(end 0.7874 0.4064)
			(stroke
				(width 0.1524)
				(type default)
			)
			(layer "F.SilkS")
		)
		(fp_line
			(start 0.7874 0.4064)
			(end -0.7874 0.4064)
			(stroke
				(width 0.1524)
				(type default)
			)
			(layer "F.SilkS")
		)
		(fp_line
			(start -0.67945 -0.305054)
			(end -0.12065 -0.305054)
			(stroke
				(width 0.1)
				(type default)
			)
			(layer "F.Fab")
		)
		(fp_line
			(start -0.67945 0.3048)
			(end -0.67945 -0.305054)
			(stroke
				(width 0.1)
				(type default)
			)
			(layer "F.Fab")
		)
		(fp_line
			(start -0.12065 -0.305054)
			(end -0.12065 -0.2794)
			(stroke
				(width 0.1)
				(type default)
			)
			(layer "F.Fab")
		)
		(fp_line
			(start -0.12065 -0.2794)
			(end 0.12065 -0.2794)
			(stroke
				(width 0.1)
				(type default)
			)
			(layer "F.Fab")
		)
		(fp_line
			(start -0.12065 0.2794)
			(end -0.12065 0.3048)
			(stroke
				(width 0.1)
				(type default)
			)
			(layer "F.Fab")
		)
		(fp_line
			(start -0.12065 0.3048)
			(end -0.67945 0.3048)
			(stroke
				(width 0.1)
				(type default)
			)
			(layer "F.Fab")
		)
		(fp_line
			(start 0.120396 0.2794)
			(end -0.12065 0.2794)
			(stroke
				(width 0.1)
				(type default)
			)
			(layer "F.Fab")
		)
		(fp_line
			(start 0.120396 0.3048)
			(end 0.120396 0.2794)
			(stroke
				(width 0.1)
				(type default)
			)
			(layer "F.Fab")
		)
		(fp_line
			(start 0.12065 -0.3048)
			(end 0.67945 -0.3048)
			(stroke
				(width 0.1)
				(type default)
			)
			(layer "F.Fab")
		)
		(fp_line
			(start 0.12065 -0.2794)
			(end 0.12065 -0.3048)
			(stroke
				(width 0.1)
				(type default)
			)
			(layer "F.Fab")
		)
		(fp_line
			(start 0.67945 -0.3048)
			(end 0.67945 0.3048)
			(stroke
				(width 0.1)
				(type default)
			)
			(layer "F.Fab")
		)
		(fp_line
			(start 0.67945 0.3048)
			(end 0.120396 0.3048)
			(stroke
				(width 0.1)
				(type default)
			)
			(layer "F.Fab")
		)
		(pad "1" smd circle
			(at -0.40005 0)
			(size 0 0)
			(layers "F.Cu" "F.Mask" "F.Paste")
			(net "P3V3_AUX")
		)
		(pad "2" smd circle
			(at 0.40005 0)
			(size 0 0)
			(layers "F.Cu" "F.Mask" "F.Paste")
			(net "GND")
		)
	)
	(footprint ""
		(layer "F.Cu")
		(at 12.786106 -106.30408 -90)
		(property "Reference" "R2789"
			(at 0 0 270)
			(layer "F.SilkS")
			(hide yes)
			(effects
				(font
					(size 1.27 1.27)
				)
			)
		)
		(property "Value" ""
			(at 0 0 270)
			(layer "F.Fab")
			(effects
				(font
					(size 1.27 1.27)
				)
			)
		)
		(duplicate_pad_numbers_are_jumpers no)
		(fp_line
			(start -0.7874 0.4064)
			(end -0.7874 -0.4064)
			(stroke
				(width 0.1524)
				(type default)
			)
			(layer "F.SilkS")
		)
		(fp_line
			(start 0.7874 0.4064)
			(end -0.7874 0.4064)
			(stroke
				(width 0.1524)
				(type default)
			)
			(layer "F.SilkS")
		)
		(fp_line
			(start -0.7874 -0.4064)
			(end 0.7874 -0.4064)
			(stroke
				(width 0.1524)
				(type default)
			)
			(layer "F.SilkS")
		)
		(fp_line
			(start 0.7874 -0.4064)
			(end 0.7874 0.4064)
			(stroke
				(width 0.1524)
				(type default)
			)
			(layer "F.SilkS")
		)
		(fp_line
			(start -0.67945 0.3048)
			(end -0.67945 -0.305054)
			(stroke
				(width 0.1)
				(type default)
			)
			(layer "F.Fab")
		)
		(fp_line
			(start -0.12065 0.3048)
			(end -0.67945 0.3048)
			(stroke
				(width 0.1)
				(type default)
			)
			(layer "F.Fab")
		)
		(fp_line
			(start 0.120396 0.3048)
			(end 0.120396 0.2794)
			(stroke
				(width 0.1)
				(type default)
			)
			(layer "F.Fab")
		)
		(fp_line
			(start 0.67945 0.3048)
			(end 0.120396 0.3048)
			(stroke
				(width 0.1)
				(type default)
			)
			(layer "F.Fab")
		)
		(fp_line
			(start -0.12065 0.2794)
			(end -0.12065 0.3048)
			(stroke
				(width 0.1)
				(type default)
			)
			(layer "F.Fab")
		)
		(fp_line
			(start 0.120396 0.2794)
			(end -0.12065 0.2794)
			(stroke
				(width 0.1)
				(type default)
			)
			(layer "F.Fab")
		)
		(fp_line
			(start -0.12065 -0.2794)
			(end 0.12065 -0.2794)
			(stroke
				(width 0.1)
				(type default)
			)
			(layer "F.Fab")
		)
		(fp_line
			(start 0.12065 -0.2794)
			(end 0.12065 -0.3048)
			(stroke
				(width 0.1)
				(type default)
			)
			(layer "F.Fab")
		)
		(fp_line
			(start 0.12065 -0.3048)
			(end 0.67945 -0.3048)
			(stroke
				(width 0.1)
				(type default)
			)
			(layer "F.Fab")
		)
		(fp_line
			(start 0.67945 -0.3048)
			(end 0.67945 0.3048)
			(stroke
				(width 0.1)
				(type default)
			)
			(layer "F.Fab")
		)
		(fp_line
			(start -0.67945 -0.305054)
			(end -0.12065 -0.305054)
			(stroke
				(width 0.1)
				(type default)
			)
			(layer "F.Fab")
		)
		(fp_line
			(start -0.12065 -0.305054)
			(end -0.12065 -0.2794)
			(stroke
				(width 0.1)
				(type default)
			)
			(layer "F.Fab")
		)
		(pad "1" smd rect
			(at -0.40005 0 90)
			(size 0.4572 0.508)
			(layers "F.Cu" "F.Mask" "F.Paste")
			(net "USB2_HOST_BMC_B_BUF_DN")
		)
		(pad "2" smd rect
			(at 0.40005 0 90)
			(size 0.4572 0.508)
			(layers "F.Cu" "F.Mask" "F.Paste")
			(net "USB2_HUB_BUF_SWB_R_DN")
		)
	)
	(footprint ""
		(layer "F.Cu")
		(at 409.830778 -165.928548 -90)
		(property "Reference" "PC580"
			(at 0 0 270)
			(layer "F.SilkS")
			(hide yes)
			(effects
				(font
					(size 1.27 1.27)
				)
			)
		)
		(property "Value" ""
			(at 0 0 270)
			(layer "F.Fab")
			(effects
				(font
					(size 1.27 1.27)
				)
			)
		)
		(duplicate_pad_numbers_are_jumpers no)
		(fp_line
			(start -0.7874 0.4064)
			(end -0.7874 -0.4064)
			(stroke
				(width 0.1524)
				(type default)
			)
			(layer "F.SilkS")
		)
		(fp_line
			(start -0.289052 0.4064)
			(end -0.7874 0.4064)
			(stroke
				(width 0.1524)
				(type default)
			)
			(layer "F.SilkS")
		)
		(fp_line
			(start 0.7874 0.4064)
			(end 0.447548 0.4064)
			(stroke
				(width 0.1524)
				(type default)
			)
			(layer "F.SilkS")
		)
		(fp_line
			(start -0.7874 -0.4064)
			(end 0.7874 -0.4064)
			(stroke
				(width 0.1524)
				(type default)
			)
			(layer "F.SilkS")
		)
		(fp_line
			(start 0.7874 -0.4064)
			(end 0.7874 0.4064)
			(stroke
				(width 0.1524)
				(type default)
			)
			(layer "F.SilkS")
		)
		(fp_line
			(start -0.67945 0.3048)
			(end -0.67945 -0.305054)
			(stroke
				(width 0.1)
				(type default)
			)
			(layer "F.Fab")
		)
		(fp_line
			(start -0.12065 0.3048)
			(end -0.67945 0.3048)
			(stroke
				(width 0.1)
				(type default)
			)
			(layer "F.Fab")
		)
		(fp_line
			(start 0.120396 0.3048)
			(end 0.120396 0.2794)
			(stroke
				(width 0.1)
				(type default)
			)
			(layer "F.Fab")
		)
		(fp_line
			(start 0.67945 0.3048)
			(end 0.120396 0.3048)
			(stroke
				(width 0.1)
				(type default)
			)
			(layer "F.Fab")
		)
		(fp_line
			(start -0.12065 0.2794)
			(end -0.12065 0.3048)
			(stroke
				(width 0.1)
				(type default)
			)
			(layer "F.Fab")
		)
		(fp_line
			(start 0.120396 0.2794)
			(end -0.12065 0.2794)
			(stroke
				(width 0.1)
				(type default)
			)
			(layer "F.Fab")
		)
		(fp_line
			(start -0.12065 -0.2794)
			(end 0.12065 -0.2794)
			(stroke
				(width 0.1)
				(type default)
			)
			(layer "F.Fab")
		)
		(fp_line
			(start 0.12065 -0.2794)
			(end 0.12065 -0.3048)
			(stroke
				(width 0.1)
				(type default)
			)
			(layer "F.Fab")
		)
		(fp_line
			(start 0.12065 -0.3048)
			(end 0.67945 -0.3048)
			(stroke
				(width 0.1)
				(type default)
			)
			(layer "F.Fab")
		)
		(fp_line
			(start 0.67945 -0.3048)
			(end 0.67945 0.3048)
			(stroke
				(width 0.1)
				(type default)
			)
			(layer "F.Fab")
		)
		(fp_line
			(start -0.67945 -0.305054)
			(end -0.12065 -0.305054)
			(stroke
				(width 0.1)
				(type default)
			)
			(layer "F.Fab")
		)
		(fp_line
			(start -0.12065 -0.305054)
			(end -0.12065 -0.2794)
			(stroke
				(width 0.1)
				(type default)
			)
			(layer "F.Fab")
		)
		(pad "1" smd circle
			(at -0.40005 0 270)
			(size 0 0)
			(layers "F.Cu" "F.Mask" "F.Paste")
			(net "PVDDCR_SOC_P0_VCC2")
		)
		(pad "2" smd circle
			(at 0.40005 0 270)
			(size 0 0)
			(layers "F.Cu" "F.Mask" "F.Paste")
			(net "GND")
		)
	)
	(footprint ""
		(layer "F.Cu")
		(at 120.68175 -24.275796)
		(property "Reference" "R6263"
			(at 0 0 0)
			(layer "F.SilkS")
			(hide yes)
			(effects
				(font
					(size 1.27 1.27)
				)
			)
		)
		(property "Value" ""
			(at 0 0 0)
			(layer "F.Fab")
			(effects
				(font
					(size 1.27 1.27)
				)
			)
		)
		(duplicate_pad_numbers_are_jumpers no)
		(fp_line
			(start -0.7874 -0.4064)
			(end 0.7874 -0.4064)
			(stroke
				(width 0.1524)
				(type default)
			)
			(layer "F.SilkS")
		)
		(fp_line
			(start -0.7874 0.4064)
			(end -0.7874 -0.4064)
			(stroke
				(width 0.1524)
				(type default)
			)
			(layer "F.SilkS")
		)
		(fp_line
			(start 0.7874 -0.4064)
			(end 0.7874 0.4064)
			(stroke
				(width 0.1524)
				(type default)
			)
			(layer "F.SilkS")
		)
		(fp_line
			(start 0.7874 0.4064)
			(end -0.7874 0.4064)
			(stroke
				(width 0.1524)
				(type default)
			)
			(layer "F.SilkS")
		)
		(fp_line
			(start -0.67945 -0.305054)
			(end -0.12065 -0.305054)
			(stroke
				(width 0.1)
				(type default)
			)
			(layer "F.Fab")
		)
		(fp_line
			(start -0.67945 0.3048)
			(end -0.67945 -0.305054)
			(stroke
				(width 0.1)
				(type default)
			)
			(layer "F.Fab")
		)
		(fp_line
			(start -0.12065 -0.305054)
			(end -0.12065 -0.2794)
			(stroke
				(width 0.1)
				(type default)
			)
			(layer "F.Fab")
		)
		(fp_line
			(start -0.12065 -0.2794)
			(end 0.12065 -0.2794)
			(stroke
				(width 0.1)
				(type default)
			)
			(layer "F.Fab")
		)
		(fp_line
			(start -0.12065 0.2794)
			(end -0.12065 0.3048)
			(stroke
				(width 0.1)
				(type default)
			)
			(layer "F.Fab")
		)
		(fp_line
			(start -0.12065 0.3048)
			(end -0.67945 0.3048)
			(stroke
				(width 0.1)
				(type default)
			)
			(layer "F.Fab")
		)
		(fp_line
			(start 0.120396 0.2794)
			(end -0.12065 0.2794)
			(stroke
				(width 0.1)
				(type default)
			)
			(layer "F.Fab")
		)
		(fp_line
			(start 0.120396 0.3048)
			(end 0.120396 0.2794)
			(stroke
				(width 0.1)
				(type default)
			)
			(layer "F.Fab")
		)
		(fp_line
			(start 0.12065 -0.3048)
			(end 0.67945 -0.3048)
			(stroke
				(width 0.1)
				(type default)
			)
			(layer "F.Fab")
		)
		(fp_line
			(start 0.12065 -0.2794)
			(end 0.12065 -0.3048)
			(stroke
				(width 0.1)
				(type default)
			)
			(layer "F.Fab")
		)
		(fp_line
			(start 0.67945 -0.3048)
			(end 0.67945 0.3048)
			(stroke
				(width 0.1)
				(type default)
			)
			(layer "F.Fab")
		)
		(fp_line
			(start 0.67945 0.3048)
			(end 0.120396 0.3048)
			(stroke
				(width 0.1)
				(type default)
			)
			(layer "F.Fab")
		)
		(pad "1" smd circle
			(at -0.40005 0)
			(size 0 0)
			(layers "F.Cu" "F.Mask" "F.Paste")
			(net "USB_HUB2_TI_USB_DP_DN3_MRP_VDD12")
		)
		(pad "2" smd circle
			(at 0.40005 0)
			(size 0 0)
			(layers "F.Cu" "F.Mask" "F.Paste")
			(net "P1V2_CPU0_USB2_DVDD12")
		)
	)
	(footprint ""
		(layer "F.Cu")
		(at 100.052124 -338.205064 90)
		(property "Reference" "PR518"
			(at 0 0 90)
			(layer "F.SilkS")
			(hide yes)
			(effects
				(font
					(size 1.27 1.27)
				)
			)
		)
		(property "Value" ""
			(at 0 0 90)
			(layer "F.Fab")
			(effects
				(font
					(size 1.27 1.27)
				)
			)
		)
		(duplicate_pad_numbers_are_jumpers no)
		(fp_line
			(start 0.7874 -0.4064)
			(end 0.7874 0.4064)
			(stroke
				(width 0.1524)
				(type default)
			)
			(layer "F.SilkS")
		)
		(fp_line
			(start -0.7874 -0.4064)
			(end 0.7874 -0.4064)
			(stroke
				(width 0.1524)
				(type default)
			)
			(layer "F.SilkS")
		)
		(fp_line
			(start 0.7874 0.4064)
			(end -0.7874 0.4064)
			(stroke
				(width 0.1524)
				(type default)
			)
			(layer "F.SilkS")
		)
		(fp_line
			(start -0.7874 0.4064)
			(end -0.7874 -0.4064)
			(stroke
				(width 0.1524)
				(type default)
			)
			(layer "F.SilkS")
		)
		(fp_line
			(start -0.12065 -0.305054)
			(end -0.12065 -0.2794)
			(stroke
				(width 0.1)
				(type default)
			)
			(layer "F.Fab")
		)
		(fp_line
			(start -0.67945 -0.305054)
			(end -0.12065 -0.305054)
			(stroke
				(width 0.1)
				(type default)
			)
			(layer "F.Fab")
		)
		(fp_line
			(start 0.67945 -0.3048)
			(end 0.67945 0.3048)
			(stroke
				(width 0.1)
				(type default)
			)
			(layer "F.Fab")
		)
		(fp_line
			(start 0.12065 -0.3048)
			(end 0.67945 -0.3048)
			(stroke
				(width 0.1)
				(type default)
			)
			(layer "F.Fab")
		)
		(fp_line
			(start 0.12065 -0.2794)
			(end 0.12065 -0.3048)
			(stroke
				(width 0.1)
				(type default)
			)
			(layer "F.Fab")
		)
		(fp_line
			(start -0.12065 -0.2794)
			(end 0.12065 -0.2794)
			(stroke
				(width 0.1)
				(type default)
			)
			(layer "F.Fab")
		)
		(fp_line
			(start 0.120396 0.2794)
			(end -0.12065 0.2794)
			(stroke
				(width 0.1)
				(type default)
			)
			(layer "F.Fab")
		)
		(fp_line
			(start -0.12065 0.2794)
			(end -0.12065 0.3048)
			(stroke
				(width 0.1)
				(type default)
			)
			(layer "F.Fab")
		)
		(fp_line
			(start 0.67945 0.3048)
			(end 0.120396 0.3048)
			(stroke
				(width 0.1)
				(type default)
			)
			(layer "F.Fab")
		)
		(fp_line
			(start 0.120396 0.3048)
			(end 0.120396 0.2794)
			(stroke
				(width 0.1)
				(type default)
			)
			(layer "F.Fab")
		)
		(fp_line
			(start -0.12065 0.3048)
			(end -0.67945 0.3048)
			(stroke
				(width 0.1)
				(type default)
			)
			(layer "F.Fab")
		)
		(fp_line
			(start -0.67945 0.3048)
			(end -0.67945 -0.305054)
			(stroke
				(width 0.1)
				(type default)
			)
			(layer "F.Fab")
		)
		(pad "1" smd circle
			(at -0.40005 0 90)
			(size 0 0)
			(layers "F.Cu" "F.Mask" "F.Paste")
			(net "SW_PVDDCR_CPU1_P1_SW6_RC")
		)
		(pad "2" smd circle
			(at 0.40005 0 90)
			(size 0 0)
			(layers "F.Cu" "F.Mask" "F.Paste")
			(net "GND")
		)
	)
	(footprint ""
		(layer "F.Cu")
		(at 204.978 -99.695 180)
		(property "Reference" "R8083"
			(at 0 0 180)
			(layer "F.SilkS")
			(hide yes)
			(effects
				(font
					(size 1.27 1.27)
				)
			)
		)
		(property "Value" ""
			(at 0 0 180)
			(layer "F.Fab")
			(effects
				(font
					(size 1.27 1.27)
				)
			)
		)
		(duplicate_pad_numbers_are_jumpers no)
		(fp_line
			(start 0.7874 0.4064)
			(end -0.7874 0.4064)
			(stroke
				(width 0.1524)
				(type default)
			)
			(layer "F.SilkS")
		)
		(fp_line
			(start 0.7874 -0.4064)
			(end 0.7874 0.4064)
			(stroke
				(width 0.1524)
				(type default)
			)
			(layer "F.SilkS")
		)
		(fp_line
			(start -0.7874 0.4064)
			(end -0.7874 -0.4064)
			(stroke
				(width 0.1524)
				(type default)
			)
			(layer "F.SilkS")
		)
		(fp_line
			(start -0.7874 -0.4064)
			(end 0.7874 -0.4064)
			(stroke
				(width 0.1524)
				(type default)
			)
			(layer "F.SilkS")
		)
		(fp_line
			(start 0.67945 0.3048)
			(end 0.120396 0.3048)
			(stroke
				(width 0.1)
				(type default)
			)
			(layer "F.Fab")
		)
		(fp_line
			(start 0.67945 -0.3048)
			(end 0.67945 0.3048)
			(stroke
				(width 0.1)
				(type default)
			)
			(layer "F.Fab")
		)
		(fp_line
			(start 0.12065 -0.2794)
			(end 0.12065 -0.3048)
			(stroke
				(width 0.1)
				(type default)
			)
			(layer "F.Fab")
		)
		(fp_line
			(start 0.12065 -0.3048)
			(end 0.67945 -0.3048)
			(stroke
				(width 0.1)
				(type default)
			)
			(layer "F.Fab")
		)
		(fp_line
			(start 0.120396 0.3048)
			(end 0.120396 0.2794)
			(stroke
				(width 0.1)
				(type default)
			)
			(layer "F.Fab")
		)
		(fp_line
			(start 0.120396 0.2794)
			(end -0.12065 0.2794)
			(stroke
				(width 0.1)
				(type default)
			)
			(layer "F.Fab")
		)
		(fp_line
			(start -0.12065 0.3048)
			(end -0.67945 0.3048)
			(stroke
				(width 0.1)
				(type default)
			)
			(layer "F.Fab")
		)
		(fp_line
			(start -0.12065 0.2794)
			(end -0.12065 0.3048)
			(stroke
				(width 0.1)
				(type default)
			)
			(layer "F.Fab")
		)
		(fp_line
			(start -0.12065 -0.2794)
			(end 0.12065 -0.2794)
			(stroke
				(width 0.1)
				(type default)
			)
			(layer "F.Fab")
		)
		(fp_line
			(start -0.12065 -0.305054)
			(end -0.12065 -0.2794)
			(stroke
				(width 0.1)
				(type default)
			)
			(layer "F.Fab")
		)
		(fp_line
			(start -0.67945 0.3048)
			(end -0.67945 -0.305054)
			(stroke
				(width 0.1)
				(type default)
			)
			(layer "F.Fab")
		)
		(fp_line
			(start -0.67945 -0.305054)
			(end -0.12065 -0.305054)
			(stroke
				(width 0.1)
				(type default)
			)
			(layer "F.Fab")
		)
		(pad "1" smd circle
			(at -0.40005 0 180)
			(size 0 0)
			(layers "F.Cu" "F.Mask" "F.Paste")
			(net "PWRGD_CHGL_CPU0")
		)
		(pad "2" smd circle
			(at 0.40005 0 180)
			(size 0 0)
			(layers "F.Cu" "F.Mask" "F.Paste")
			(net "PWRGD_CHGL_CPU0_R1")
		)
	)
	(footprint ""
		(layer "F.Cu")
		(at 215.4301 -408.084782)
		(property "Reference" "PR3988"
			(at 0 0 0)
			(layer "F.SilkS")
			(hide yes)
			(effects
				(font
					(size 1.27 1.27)
				)
			)
		)
		(property "Value" ""
			(at 0 0 0)
			(layer "F.Fab")
			(effects
				(font
					(size 1.27 1.27)
				)
			)
		)
		(duplicate_pad_numbers_are_jumpers no)
		(fp_line
			(start -0.7874 -0.4064)
			(end 0.7874 -0.4064)
			(stroke
				(width 0.1524)
				(type default)
			)
			(layer "F.SilkS")
		)
		(fp_line
			(start -0.7874 0.4064)
			(end -0.7874 -0.4064)
			(stroke
				(width 0.1524)
				(type default)
			)
			(layer "F.SilkS")
		)
		(fp_line
			(start 0.7874 -0.4064)
			(end 0.7874 0.4064)
			(stroke
				(width 0.1524)
				(type default)
			)
			(layer "F.SilkS")
		)
		(fp_line
			(start 0.7874 0.4064)
			(end -0.7874 0.4064)
			(stroke
				(width 0.1524)
				(type default)
			)
			(layer "F.SilkS")
		)
		(fp_line
			(start -0.67945 -0.305054)
			(end -0.12065 -0.305054)
			(stroke
				(width 0.1)
				(type default)
			)
			(layer "F.Fab")
		)
		(fp_line
			(start -0.67945 0.3048)
			(end -0.67945 -0.305054)
			(stroke
				(width 0.1)
				(type default)
			)
			(layer "F.Fab")
		)
		(fp_line
			(start -0.12065 -0.305054)
			(end -0.12065 -0.2794)
			(stroke
				(width 0.1)
				(type default)
			)
			(layer "F.Fab")
		)
		(fp_line
			(start -0.12065 -0.2794)
			(end 0.12065 -0.2794)
			(stroke
				(width 0.1)
				(type default)
			)
			(layer "F.Fab")
		)
		(fp_line
			(start -0.12065 0.2794)
			(end -0.12065 0.3048)
			(stroke
				(width 0.1)
				(type default)
			)
			(layer "F.Fab")
		)
		(fp_line
			(start -0.12065 0.3048)
			(end -0.67945 0.3048)
			(stroke
				(width 0.1)
				(type default)
			)
			(layer "F.Fab")
		)
		(fp_line
			(start 0.120396 0.2794)
			(end -0.12065 0.2794)
			(stroke
				(width 0.1)
				(type default)
			)
			(layer "F.Fab")
		)
		(fp_line
			(start 0.120396 0.3048)
			(end 0.120396 0.2794)
			(stroke
				(width 0.1)
				(type default)
			)
			(layer "F.Fab")
		)
		(fp_line
			(start 0.12065 -0.3048)
			(end 0.67945 -0.3048)
			(stroke
				(width 0.1)
				(type default)
			)
			(layer "F.Fab")
		)
		(fp_line
			(start 0.12065 -0.2794)
			(end 0.12065 -0.3048)
			(stroke
				(width 0.1)
				(type default)
			)
			(layer "F.Fab")
		)
		(fp_line
			(start 0.67945 -0.3048)
			(end 0.67945 0.3048)
			(stroke
				(width 0.1)
				(type default)
			)
			(layer "F.Fab")
		)
		(fp_line
			(start 0.67945 0.3048)
			(end 0.120396 0.3048)
			(stroke
				(width 0.1)
				(type default)
			)
			(layer "F.Fab")
		)
		(pad "1" smd circle
			(at -0.40005 0)
			(size 0 0)
			(layers "F.Cu" "F.Mask" "F.Paste")
			(net "HSC_SCREF")
		)
		(pad "2" smd circle
			(at 0.40005 0)
			(size 0 0)
			(layers "F.Cu" "F.Mask" "F.Paste")
			(net "HSC_SCREF_3")
		)
	)
	(footprint ""
		(layer "F.Cu")
		(at 161.337244 -375.49963 -90)
		(property "Reference" "C753"
			(at 0 0 270)
			(layer "F.SilkS")
			(hide yes)
			(effects
				(font
					(size 1.27 1.27)
				)
			)
		)
		(property "Value" ""
			(at 0 0 270)
			(layer "F.Fab")
			(effects
				(font
					(size 1.27 1.27)
				)
			)
		)
		(duplicate_pad_numbers_are_jumpers no)
		(fp_line
			(start -0.299974 0.150114)
			(end -0.299974 -0.150114)
			(stroke
				(width 0.1)
				(type default)
			)
			(layer "F.Fab")
		)
		(fp_line
			(start 0.299974 0.150114)
			(end -0.299974 0.150114)
			(stroke
				(width 0.1)
				(type default)
			)
			(layer "F.Fab")
		)
		(fp_line
			(start -0.299974 -0.150114)
			(end 0.299974 -0.150114)
			(stroke
				(width 0.1)
				(type default)
			)
			(layer "F.Fab")
		)
		(fp_line
			(start 0.299974 -0.150114)
			(end 0.299974 0.150114)
			(stroke
				(width 0.1)
				(type default)
			)
			(layer "F.Fab")
		)
		(pad "1" smd rect
			(at -0.2667 0 270)
			(size 0.3048 0.381)
			(layers "F.Cu" "F.Mask" "F.Paste")
			(net "P5E_CPU1_P2_TX_C_DP<10>")
		)
		(pad "2" smd rect
			(at 0.2667 0 270)
			(size 0.3048 0.381)
			(layers "F.Cu" "F.Mask" "F.Paste")
			(net "P5E_CPU1_P2_TX_DP<10>")
		)
	)
	(footprint ""
		(layer "F.Cu")
		(at 421.961564 -17.624298 90)
		(property "Reference" "C1571"
			(at 0 0 90)
			(layer "F.SilkS")
			(hide yes)
			(effects
				(font
					(size 1.27 1.27)
				)
			)
		)
		(property "Value" ""
			(at 0 0 90)
			(layer "F.Fab")
			(effects
				(font
					(size 1.27 1.27)
				)
			)
		)
		(duplicate_pad_numbers_are_jumpers no)
		(fp_line
			(start 0.299974 -0.150114)
			(end 0.299974 0.150114)
			(stroke
				(width 0.1)
				(type default)
			)
			(layer "F.Fab")
		)
		(fp_line
			(start -0.299974 -0.150114)
			(end 0.299974 -0.150114)
			(stroke
				(width 0.1)
				(type default)
			)
			(layer "F.Fab")
		)
		(fp_line
			(start 0.299974 0.150114)
			(end -0.299974 0.150114)
			(stroke
				(width 0.1)
				(type default)
			)
			(layer "F.Fab")
		)
		(fp_line
			(start -0.299974 0.150114)
			(end -0.299974 -0.150114)
			(stroke
				(width 0.1)
				(type default)
			)
			(layer "F.Fab")
		)
		(pad "1" smd rect
			(at -0.2667 0 90)
			(size 0.3048 0.381)
			(layers "F.Cu" "F.Mask" "F.Paste")
			(net "P5E_CPU0_G3_TX_C_DP<4>")
		)
		(pad "2" smd rect
			(at 0.2667 0 90)
			(size 0.3048 0.381)
			(layers "F.Cu" "F.Mask" "F.Paste")
			(net "P5E_CPU0_G3_TX_DP<4>")
		)
	)
	(footprint ""
		(layer "F.Cu")
		(at 234.739688 -159.997648 180)
		(property "Reference" "U154"
			(at -4.057904 -1.950212 0)
			(unlocked yes)
			(layer "F.SilkS")
			(effects
				(font
					(size 0.7874 0.5842)
					(thickness 0.1524)
				)
				(justify left)
			)
		)
		(property "Value" ""
			(at 0 0 180)
			(layer "F.Fab")
			(effects
				(font
					(size 1.27 1.27)
				)
			)
		)
		(duplicate_pad_numbers_are_jumpers no)
		(fp_line
			(start 1.0414 1.575054)
			(end -1.0414 1.575054)
			(stroke
				(width 0.1524)
				(type default)
			)
			(layer "F.SilkS")
		)
		(fp_line
			(start 1.0414 -1.575054)
			(end 1.0414 1.575054)
			(stroke
				(width 0.1524)
				(type default)
			)
			(layer "F.SilkS")
		)
		(fp_line
			(start 0.254 -1.575054)
			(end 1.0414 -1.575054)
			(stroke
				(width 0.1524)
				(type default)
			)
			(layer "F.SilkS")
		)
		(fp_line
			(start 0.2286 -1.575054)
			(end 0 -1.272032)
			(stroke
				(width 0.1524)
				(type default)
			)
			(layer "F.SilkS")
		)
		(fp_line
			(start 0 -1.272032)
			(end -0.254 -1.575054)
			(stroke
				(width 0.1524)
				(type default)
			)
			(layer "F.SilkS")
		)
		(fp_line
			(start -1.0414 1.575054)
			(end -1.0414 -1.575054)
			(stroke
				(width 0.1524)
				(type default)
			)
			(layer "F.SilkS")
		)
		(fp_line
			(start -1.0414 -1.575054)
			(end -0.254 -1.575054)
			(stroke
				(width 0.1524)
				(type default)
			)
			(layer "F.SilkS")
		)
		(fp_poly
			(pts
				(xy -3.443224 -1.397254) (xy -2.598928 -0.975106) (xy -3.443224 -0.552958)
			)
			(stroke
				(width 0)
				(type default)
			)
			(fill yes)
			(layer "F.SilkS")
		)
		(fp_line
			(start 2.5654 1.2192)
			(end 1.4478 1.2192)
			(stroke
				(width 0.1)
				(type default)
			)
			(layer "F.Fab")
		)
		(fp_line
			(start 2.5654 -1.2192)
			(end 2.5654 1.2192)
			(stroke
				(width 0.1)
				(type default)
			)
			(layer "F.Fab")
		)
		(fp_line
			(start 1.4478 1.5748)
			(end -1.4478 1.5748)
			(stroke
				(width 0.1)
				(type default)
			)
			(layer "F.Fab")
		)
		(fp_line
			(start 1.4478 1.2192)
			(end 1.4478 1.5748)
			(stroke
				(width 0.1)
				(type default)
			)
			(layer "F.Fab")
		)
		(fp_line
			(start 1.4478 -1.2192)
			(end 2.5654 -1.2192)
			(stroke
				(width 0.1)
				(type default)
			)
			(layer "F.Fab")
		)
		(fp_line
			(start 1.4478 -1.5748)
			(end 1.4478 -1.2192)
			(stroke
				(width 0.1)
				(type default)
			)
			(layer "F.Fab")
		)
		(fp_line
			(start -1.4478 1.5748)
			(end -1.4478 1.2192)
			(stroke
				(width 0.1)
				(type default)
			)
			(layer "F.Fab")
		)
		(fp_line
			(start -1.4478 1.2192)
			(end -2.5654 1.2192)
			(stroke
				(width 0.1)
				(type default)
			)
			(layer "F.Fab")
		)
		(fp_line
			(start -1.4478 -1.2192)
			(end -1.4478 -1.5748)
			(stroke
				(width 0.1)
				(type default)
			)
			(layer "F.Fab")
		)
		(fp_line
			(start -1.4478 -1.5748)
			(end 1.4478 -1.5748)
			(stroke
				(width 0.1)
				(type default)
			)
			(layer "F.Fab")
		)
		(fp_line
			(start -2.5654 1.2192)
			(end -2.5654 -1.2192)
			(stroke
				(width 0.1)
				(type default)
			)
			(layer "F.Fab")
		)
		(fp_line
			(start -2.5654 -1.2192)
			(end -1.4478 -1.2192)
			(stroke
				(width 0.1)
				(type default)
			)
			(layer "F.Fab")
		)
		(fp_poly
			(pts
				(xy -2.710688 -0.975106) (xy -3.726688 -1.483106) (xy -3.726688 -0.467106)
			)
			(stroke
				(width 0)
				(type default)
			)
			(fill yes)
			(layer "F.Fab")
		)
		(pad "1" smd rect
			(at -1.849882 -0.975106 90)
			(size 0.3556 1.3208)
			(layers "F.Cu" "F.Mask" "F.Paste")
			(net "JTAG_CPU1_TDO")
		)
		(pad "2" smd rect
			(at -1.849882 -0.32512 90)
			(size 0.3556 1.3208)
			(layers "F.Cu" "F.Mask" "F.Paste")
			(net "JTAG_CPUX_TDO_R")
		)
		(pad "3" smd rect
			(at -1.849882 0.32512 90)
			(size 0.3556 1.3208)
			(layers "F.Cu" "F.Mask" "F.Paste")
			(net "FM_PLD_CPU1_PRSNT_HDT_N")
		)
		(pad "4" smd rect
			(at -1.849882 0.975106 90)
			(size 0.3556 1.3208)
			(layers "F.Cu" "F.Mask" "F.Paste")
			(net "GND")
		)
		(pad "5" smd rect
			(at 1.849882 0.975106 90)
			(size 0.3556 1.3208)
			(layers "F.Cu" "F.Mask" "F.Paste")
			(net "JTAG_CPU1_BYPASS")
		)
		(pad "6" smd rect
			(at 1.849882 0.32512 90)
			(size 0.3556 1.3208)
			(layers "F.Cu" "F.Mask" "F.Paste")
			(net "JTAG_CPUX_TDO_R")
		)
		(pad "7" smd rect
			(at 1.849882 -0.32512 90)
			(size 0.3556 1.3208)
			(layers "F.Cu" "F.Mask" "F.Paste")
			(net "CPU1_HDT_BYPASS_SEL")
		)
		(pad "8" smd rect
			(at 1.849882 -0.975106 90)
			(size 0.3556 1.3208)
			(layers "F.Cu" "F.Mask" "F.Paste")
			(net "PVDD18_S5_P0")
		)
	)
	(footprint ""
		(layer "F.Cu")
		(at 272.728182 -351.573846 90)
		(property "Reference" "PC176_10"
			(at 0 0 90)
			(layer "F.SilkS")
			(hide yes)
			(effects
				(font
					(size 1.27 1.27)
				)
			)
		)
		(property "Value" ""
			(at 0 0 90)
			(layer "F.Fab")
			(effects
				(font
					(size 1.27 1.27)
				)
			)
		)
		(duplicate_pad_numbers_are_jumpers no)
		(fp_line
			(start 0.7874 -0.4064)
			(end 0.7874 0.4064)
			(stroke
				(width 0.1524)
				(type default)
			)
			(layer "F.SilkS")
		)
		(fp_line
			(start -0.7874 -0.4064)
			(end 0.7874 -0.4064)
			(stroke
				(width 0.1524)
				(type default)
			)
			(layer "F.SilkS")
		)
		(fp_line
			(start 0.7874 0.4064)
			(end -0.7874 0.4064)
			(stroke
				(width 0.1524)
				(type default)
			)
			(layer "F.SilkS")
		)
		(fp_line
			(start -0.7874 0.4064)
			(end -0.7874 -0.4064)
			(stroke
				(width 0.1524)
				(type default)
			)
			(layer "F.SilkS")
		)
		(fp_line
			(start -0.12065 -0.305054)
			(end -0.12065 -0.2794)
			(stroke
				(width 0.1)
				(type default)
			)
			(layer "F.Fab")
		)
		(fp_line
			(start -0.67945 -0.305054)
			(end -0.12065 -0.305054)
			(stroke
				(width 0.1)
				(type default)
			)
			(layer "F.Fab")
		)
		(fp_line
			(start 0.67945 -0.3048)
			(end 0.67945 0.3048)
			(stroke
				(width 0.1)
				(type default)
			)
			(layer "F.Fab")
		)
		(fp_line
			(start 0.12065 -0.3048)
			(end 0.67945 -0.3048)
			(stroke
				(width 0.1)
				(type default)
			)
			(layer "F.Fab")
		)
		(fp_line
			(start 0.12065 -0.2794)
			(end 0.12065 -0.3048)
			(stroke
				(width 0.1)
				(type default)
			)
			(layer "F.Fab")
		)
		(fp_line
			(start -0.12065 -0.2794)
			(end 0.12065 -0.2794)
			(stroke
				(width 0.1)
				(type default)
			)
			(layer "F.Fab")
		)
		(fp_line
			(start 0.120396 0.2794)
			(end -0.12065 0.2794)
			(stroke
				(width 0.1)
				(type default)
			)
			(layer "F.Fab")
		)
		(fp_line
			(start -0.12065 0.2794)
			(end -0.12065 0.3048)
			(stroke
				(width 0.1)
				(type default)
			)
			(layer "F.Fab")
		)
		(fp_line
			(start 0.67945 0.3048)
			(end 0.120396 0.3048)
			(stroke
				(width 0.1)
				(type default)
			)
			(layer "F.Fab")
		)
		(fp_line
			(start 0.120396 0.3048)
			(end 0.120396 0.2794)
			(stroke
				(width 0.1)
				(type default)
			)
			(layer "F.Fab")
		)
		(fp_line
			(start -0.12065 0.3048)
			(end -0.67945 0.3048)
			(stroke
				(width 0.1)
				(type default)
			)
			(layer "F.Fab")
		)
		(fp_line
			(start -0.67945 0.3048)
			(end -0.67945 -0.305054)
			(stroke
				(width 0.1)
				(type default)
			)
			(layer "F.Fab")
		)
		(pad "1" smd circle
			(at -0.40005 0 90)
			(size 0 0)
			(layers "F.Cu" "F.Mask" "F.Paste")
			(net "PVDDCR_CPU1_P0_VCCS")
		)
		(pad "2" smd circle
			(at 0.40005 0 90)
			(size 0 0)
			(layers "F.Cu" "F.Mask" "F.Paste")
			(net "GND")
		)
	)
	(footprint ""
		(layer "F.Cu")
		(at 187.071 -129.377948 90)
		(property "Reference" "R1203"
			(at 0 0 90)
			(layer "F.SilkS")
			(hide yes)
			(effects
				(font
					(size 1.27 1.27)
				)
			)
		)
		(property "Value" ""
			(at 0 0 90)
			(layer "F.Fab")
			(effects
				(font
					(size 1.27 1.27)
				)
			)
		)
		(duplicate_pad_numbers_are_jumpers no)
		(fp_line
			(start 0.7874 -0.4064)
			(end 0.7874 0.4064)
			(stroke
				(width 0.1524)
				(type default)
			)
			(layer "F.SilkS")
		)
		(fp_line
			(start -0.7874 -0.4064)
			(end 0.7874 -0.4064)
			(stroke
				(width 0.1524)
				(type default)
			)
			(layer "F.SilkS")
		)
		(fp_line
			(start 0.7874 0.4064)
			(end -0.7874 0.4064)
			(stroke
				(width 0.1524)
				(type default)
			)
			(layer "F.SilkS")
		)
		(fp_line
			(start -0.7874 0.4064)
			(end -0.7874 -0.4064)
			(stroke
				(width 0.1524)
				(type default)
			)
			(layer "F.SilkS")
		)
		(fp_line
			(start -0.12065 -0.305054)
			(end -0.12065 -0.2794)
			(stroke
				(width 0.1)
				(type default)
			)
			(layer "F.Fab")
		)
		(fp_line
			(start -0.67945 -0.305054)
			(end -0.12065 -0.305054)
			(stroke
				(width 0.1)
				(type default)
			)
			(layer "F.Fab")
		)
		(fp_line
			(start 0.67945 -0.3048)
			(end 0.67945 0.3048)
			(stroke
				(width 0.1)
				(type default)
			)
			(layer "F.Fab")
		)
		(fp_line
			(start 0.12065 -0.3048)
			(end 0.67945 -0.3048)
			(stroke
				(width 0.1)
				(type default)
			)
			(layer "F.Fab")
		)
		(fp_line
			(start 0.12065 -0.2794)
			(end 0.12065 -0.3048)
			(stroke
				(width 0.1)
				(type default)
			)
			(layer "F.Fab")
		)
		(fp_line
			(start -0.12065 -0.2794)
			(end 0.12065 -0.2794)
			(stroke
				(width 0.1)
				(type default)
			)
			(layer "F.Fab")
		)
		(fp_line
			(start 0.120396 0.2794)
			(end -0.12065 0.2794)
			(stroke
				(width 0.1)
				(type default)
			)
			(layer "F.Fab")
		)
		(fp_line
			(start -0.12065 0.2794)
			(end -0.12065 0.3048)
			(stroke
				(width 0.1)
				(type default)
			)
			(layer "F.Fab")
		)
		(fp_line
			(start 0.67945 0.3048)
			(end 0.120396 0.3048)
			(stroke
				(width 0.1)
				(type default)
			)
			(layer "F.Fab")
		)
		(fp_line
			(start 0.120396 0.3048)
			(end 0.120396 0.2794)
			(stroke
				(width 0.1)
				(type default)
			)
			(layer "F.Fab")
		)
		(fp_line
			(start -0.12065 0.3048)
			(end -0.67945 0.3048)
			(stroke
				(width 0.1)
				(type default)
			)
			(layer "F.Fab")
		)
		(fp_line
			(start -0.67945 0.3048)
			(end -0.67945 -0.305054)
			(stroke
				(width 0.1)
				(type default)
			)
			(layer "F.Fab")
		)
		(pad "1" smd circle
			(at -0.40005 0 90)
			(size 0 0)
			(layers "F.Cu" "F.Mask" "F.Paste")
			(net "BIOS_DEBUG_MODE_R")
		)
		(pad "2" smd circle
			(at 0.40005 0 90)
			(size 0 0)
			(layers "F.Cu" "F.Mask" "F.Paste")
			(net "BIOS_DEBUG_MODE")
		)
	)
	(footprint ""
		(layer "F.Cu")
		(at 22.010878 -16.099536 90)
		(property "Reference" "C683"
			(at 0 0 90)
			(layer "F.SilkS")
			(hide yes)
			(effects
				(font
					(size 1.27 1.27)
				)
			)
		)
		(property "Value" ""
			(at 0 0 90)
			(layer "F.Fab")
			(effects
				(font
					(size 1.27 1.27)
				)
			)
		)
		(duplicate_pad_numbers_are_jumpers no)
		(fp_line
			(start 0.299974 -0.150114)
			(end 0.299974 0.150114)
			(stroke
				(width 0.1)
				(type default)
			)
			(layer "F.Fab")
		)
		(fp_line
			(start -0.299974 -0.150114)
			(end 0.299974 -0.150114)
			(stroke
				(width 0.1)
				(type default)
			)
			(layer "F.Fab")
		)
		(fp_line
			(start 0.299974 0.150114)
			(end -0.299974 0.150114)
			(stroke
				(width 0.1)
				(type default)
			)
			(layer "F.Fab")
		)
		(fp_line
			(start -0.299974 0.150114)
			(end -0.299974 -0.150114)
			(stroke
				(width 0.1)
				(type default)
			)
			(layer "F.Fab")
		)
		(pad "1" smd rect
			(at -0.2667 0 90)
			(size 0.3048 0.381)
			(layers "F.Cu" "F.Mask" "F.Paste")
			(net "P5E_CPU1_G1_TX_C_DP<13>")
		)
		(pad "2" smd rect
			(at 0.2667 0 90)
			(size 0.3048 0.381)
			(layers "F.Cu" "F.Mask" "F.Paste")
			(net "P5E_CPU1_G1_TX_DP<13>")
		)
	)
	(footprint ""
		(layer "F.Cu")
		(at 437.875172 -28.668218)
		(property "Reference" "R4532"
			(at 0 0 0)
			(layer "F.SilkS")
			(hide yes)
			(effects
				(font
					(size 1.27 1.27)
				)
			)
		)
		(property "Value" ""
			(at 0 0 0)
			(layer "F.Fab")
			(effects
				(font
					(size 1.27 1.27)
				)
			)
		)
		(duplicate_pad_numbers_are_jumpers no)
		(fp_line
			(start -0.7874 -0.4064)
			(end 0.7874 -0.4064)
			(stroke
				(width 0.1524)
				(type default)
			)
			(layer "F.SilkS")
		)
		(fp_line
			(start -0.7874 0.4064)
			(end -0.7874 -0.4064)
			(stroke
				(width 0.1524)
				(type default)
			)
			(layer "F.SilkS")
		)
		(fp_line
			(start 0.7874 -0.4064)
			(end 0.7874 0.4064)
			(stroke
				(width 0.1524)
				(type default)
			)
			(layer "F.SilkS")
		)
		(fp_line
			(start 0.7874 0.4064)
			(end -0.7874 0.4064)
			(stroke
				(width 0.1524)
				(type default)
			)
			(layer "F.SilkS")
		)
		(fp_line
			(start -0.67945 -0.305054)
			(end -0.12065 -0.305054)
			(stroke
				(width 0.1)
				(type default)
			)
			(layer "F.Fab")
		)
		(fp_line
			(start -0.67945 0.3048)
			(end -0.67945 -0.305054)
			(stroke
				(width 0.1)
				(type default)
			)
			(layer "F.Fab")
		)
		(fp_line
			(start -0.12065 -0.305054)
			(end -0.12065 -0.2794)
			(stroke
				(width 0.1)
				(type default)
			)
			(layer "F.Fab")
		)
		(fp_line
			(start -0.12065 -0.2794)
			(end 0.12065 -0.2794)
			(stroke
				(width 0.1)
				(type default)
			)
			(layer "F.Fab")
		)
		(fp_line
			(start -0.12065 0.2794)
			(end -0.12065 0.3048)
			(stroke
				(width 0.1)
				(type default)
			)
			(layer "F.Fab")
		)
		(fp_line
			(start -0.12065 0.3048)
			(end -0.67945 0.3048)
			(stroke
				(width 0.1)
				(type default)
			)
			(layer "F.Fab")
		)
		(fp_line
			(start 0.120396 0.2794)
			(end -0.12065 0.2794)
			(stroke
				(width 0.1)
				(type default)
			)
			(layer "F.Fab")
		)
		(fp_line
			(start 0.120396 0.3048)
			(end 0.120396 0.2794)
			(stroke
				(width 0.1)
				(type default)
			)
			(layer "F.Fab")
		)
		(fp_line
			(start 0.12065 -0.3048)
			(end 0.67945 -0.3048)
			(stroke
				(width 0.1)
				(type default)
			)
			(layer "F.Fab")
		)
		(fp_line
			(start 0.12065 -0.2794)
			(end 0.12065 -0.3048)
			(stroke
				(width 0.1)
				(type default)
			)
			(layer "F.Fab")
		)
		(fp_line
			(start 0.67945 -0.3048)
			(end 0.67945 0.3048)
			(stroke
				(width 0.1)
				(type default)
			)
			(layer "F.Fab")
		)
		(fp_line
			(start 0.67945 0.3048)
			(end 0.120396 0.3048)
			(stroke
				(width 0.1)
				(type default)
			)
			(layer "F.Fab")
		)
		(pad "1" smd circle
			(at -0.40005 0)
			(size 0 0)
			(layers "F.Cu" "F.Mask" "F.Paste")
			(net "P3V3_AUX")
		)
		(pad "2" smd circle
			(at 0.40005 0)
			(size 0 0)
			(layers "F.Cu" "F.Mask" "F.Paste")
			(net "HP_LVC3_OCP_V3_1_P12V_PWRGD")
		)
	)
	(footprint ""
		(layer "F.Cu")
		(at 257.894836 -74.373994 90)
		(property "Reference" "C1592"
			(at 0 0 90)
			(layer "F.SilkS")
			(hide yes)
			(effects
				(font
					(size 1.27 1.27)
				)
			)
		)
		(property "Value" ""
			(at 0 0 90)
			(layer "F.Fab")
			(effects
				(font
					(size 1.27 1.27)
				)
			)
		)
		(duplicate_pad_numbers_are_jumpers no)
		(fp_line
			(start 0.7874 -0.4064)
			(end 0.7874 0.4064)
			(stroke
				(width 0.1524)
				(type default)
			)
			(layer "F.SilkS")
		)
		(fp_line
			(start -0.7874 -0.4064)
			(end 0.7874 -0.4064)
			(stroke
				(width 0.1524)
				(type default)
			)
			(layer "F.SilkS")
		)
		(fp_line
			(start 0.7874 0.4064)
			(end -0.7874 0.4064)
			(stroke
				(width 0.1524)
				(type default)
			)
			(layer "F.SilkS")
		)
		(fp_line
			(start -0.7874 0.4064)
			(end -0.7874 -0.4064)
			(stroke
				(width 0.1524)
				(type default)
			)
			(layer "F.SilkS")
		)
		(fp_line
			(start -0.12065 -0.305054)
			(end -0.12065 -0.2794)
			(stroke
				(width 0.1)
				(type default)
			)
			(layer "F.Fab")
		)
		(fp_line
			(start -0.67945 -0.305054)
			(end -0.12065 -0.305054)
			(stroke
				(width 0.1)
				(type default)
			)
			(layer "F.Fab")
		)
		(fp_line
			(start 0.67945 -0.3048)
			(end 0.67945 0.3048)
			(stroke
				(width 0.1)
				(type default)
			)
			(layer "F.Fab")
		)
		(fp_line
			(start 0.12065 -0.3048)
			(end 0.67945 -0.3048)
			(stroke
				(width 0.1)
				(type default)
			)
			(layer "F.Fab")
		)
		(fp_line
			(start 0.12065 -0.2794)
			(end 0.12065 -0.3048)
			(stroke
				(width 0.1)
				(type default)
			)
			(layer "F.Fab")
		)
		(fp_line
			(start -0.12065 -0.2794)
			(end 0.12065 -0.2794)
			(stroke
				(width 0.1)
				(type default)
			)
			(layer "F.Fab")
		)
		(fp_line
			(start 0.120396 0.2794)
			(end -0.12065 0.2794)
			(stroke
				(width 0.1)
				(type default)
			)
			(layer "F.Fab")
		)
		(fp_line
			(start -0.12065 0.2794)
			(end -0.12065 0.3048)
			(stroke
				(width 0.1)
				(type default)
			)
			(layer "F.Fab")
		)
		(fp_line
			(start 0.67945 0.3048)
			(end 0.120396 0.3048)
			(stroke
				(width 0.1)
				(type default)
			)
			(layer "F.Fab")
		)
		(fp_line
			(start 0.120396 0.3048)
			(end 0.120396 0.2794)
			(stroke
				(width 0.1)
				(type default)
			)
			(layer "F.Fab")
		)
		(fp_line
			(start -0.12065 0.3048)
			(end -0.67945 0.3048)
			(stroke
				(width 0.1)
				(type default)
			)
			(layer "F.Fab")
		)
		(fp_line
			(start -0.67945 0.3048)
			(end -0.67945 -0.305054)
			(stroke
				(width 0.1)
				(type default)
			)
			(layer "F.Fab")
		)
		(pad "1" smd circle
			(at -0.40005 0 90)
			(size 0 0)
			(layers "F.Cu" "F.Mask" "F.Paste")
			(net "P3V3_AUX")
		)
		(pad "2" smd circle
			(at 0.40005 0 90)
			(size 0 0)
			(layers "F.Cu" "F.Mask" "F.Paste")
			(net "GND")
		)
	)
	(footprint ""
		(layer "F.Cu")
		(at 21.176996 -100.54971 180)
		(property "Reference" "R3656"
			(at 0 0 180)
			(layer "F.SilkS")
			(hide yes)
			(effects
				(font
					(size 1.27 1.27)
				)
			)
		)
		(property "Value" ""
			(at 0 0 180)
			(layer "F.Fab")
			(effects
				(font
					(size 1.27 1.27)
				)
			)
		)
		(duplicate_pad_numbers_are_jumpers no)
		(fp_line
			(start 0.7874 0.4064)
			(end -0.7874 0.4064)
			(stroke
				(width 0.1524)
				(type default)
			)
			(layer "F.SilkS")
		)
		(fp_line
			(start 0.7874 -0.4064)
			(end 0.7874 0.4064)
			(stroke
				(width 0.1524)
				(type default)
			)
			(layer "F.SilkS")
		)
		(fp_line
			(start -0.7874 0.4064)
			(end -0.7874 -0.4064)
			(stroke
				(width 0.1524)
				(type default)
			)
			(layer "F.SilkS")
		)
		(fp_line
			(start -0.7874 -0.4064)
			(end 0.7874 -0.4064)
			(stroke
				(width 0.1524)
				(type default)
			)
			(layer "F.SilkS")
		)
		(fp_line
			(start 0.67945 0.3048)
			(end 0.120396 0.3048)
			(stroke
				(width 0.1)
				(type default)
			)
			(layer "F.Fab")
		)
		(fp_line
			(start 0.67945 -0.3048)
			(end 0.67945 0.3048)
			(stroke
				(width 0.1)
				(type default)
			)
			(layer "F.Fab")
		)
		(fp_line
			(start 0.12065 -0.2794)
			(end 0.12065 -0.3048)
			(stroke
				(width 0.1)
				(type default)
			)
			(layer "F.Fab")
		)
		(fp_line
			(start 0.12065 -0.3048)
			(end 0.67945 -0.3048)
			(stroke
				(width 0.1)
				(type default)
			)
			(layer "F.Fab")
		)
		(fp_line
			(start 0.120396 0.3048)
			(end 0.120396 0.2794)
			(stroke
				(width 0.1)
				(type default)
			)
			(layer "F.Fab")
		)
		(fp_line
			(start 0.120396 0.2794)
			(end -0.12065 0.2794)
			(stroke
				(width 0.1)
				(type default)
			)
			(layer "F.Fab")
		)
		(fp_line
			(start -0.12065 0.3048)
			(end -0.67945 0.3048)
			(stroke
				(width 0.1)
				(type default)
			)
			(layer "F.Fab")
		)
		(fp_line
			(start -0.12065 0.2794)
			(end -0.12065 0.3048)
			(stroke
				(width 0.1)
				(type default)
			)
			(layer "F.Fab")
		)
		(fp_line
			(start -0.12065 -0.2794)
			(end 0.12065 -0.2794)
			(stroke
				(width 0.1)
				(type default)
			)
			(layer "F.Fab")
		)
		(fp_line
			(start -0.12065 -0.305054)
			(end -0.12065 -0.2794)
			(stroke
				(width 0.1)
				(type default)
			)
			(layer "F.Fab")
		)
		(fp_line
			(start -0.67945 0.3048)
			(end -0.67945 -0.305054)
			(stroke
				(width 0.1)
				(type default)
			)
			(layer "F.Fab")
		)
		(fp_line
			(start -0.67945 -0.305054)
			(end -0.12065 -0.305054)
			(stroke
				(width 0.1)
				(type default)
			)
			(layer "F.Fab")
		)
		(pad "1" smd circle
			(at -0.40005 0 180)
			(size 0 0)
			(layers "F.Cu" "F.Mask" "F.Paste")
			(net "P3V3_AUX")
		)
		(pad "2" smd circle
			(at 0.40005 0 180)
			(size 0 0)
			(layers "F.Cu" "F.Mask" "F.Paste")
			(net "USB_HUB_OVCUR1")
		)
	)
	(footprint ""
		(layer "F.Cu")
		(at 406.475946 -134.931404 180)
		(property "Reference" "R2343"
			(at 0 0 180)
			(layer "F.SilkS")
			(hide yes)
			(effects
				(font
					(size 1.27 1.27)
				)
			)
		)
		(property "Value" ""
			(at 0 0 180)
			(layer "F.Fab")
			(effects
				(font
					(size 1.27 1.27)
				)
			)
		)
		(duplicate_pad_numbers_are_jumpers no)
		(fp_line
			(start 0.7874 0.4064)
			(end -0.7874 0.4064)
			(stroke
				(width 0.1524)
				(type default)
			)
			(layer "F.SilkS")
		)
		(fp_line
			(start 0.7874 -0.4064)
			(end 0.7874 0.4064)
			(stroke
				(width 0.1524)
				(type default)
			)
			(layer "F.SilkS")
		)
		(fp_line
			(start -0.7874 0.4064)
			(end -0.7874 -0.4064)
			(stroke
				(width 0.1524)
				(type default)
			)
			(layer "F.SilkS")
		)
		(fp_line
			(start -0.7874 -0.4064)
			(end 0.7874 -0.4064)
			(stroke
				(width 0.1524)
				(type default)
			)
			(layer "F.SilkS")
		)
		(fp_line
			(start 0.67945 0.3048)
			(end 0.120396 0.3048)
			(stroke
				(width 0.1)
				(type default)
			)
			(layer "F.Fab")
		)
		(fp_line
			(start 0.67945 -0.3048)
			(end 0.67945 0.3048)
			(stroke
				(width 0.1)
				(type default)
			)
			(layer "F.Fab")
		)
		(fp_line
			(start 0.12065 -0.2794)
			(end 0.12065 -0.3048)
			(stroke
				(width 0.1)
				(type default)
			)
			(layer "F.Fab")
		)
		(fp_line
			(start 0.12065 -0.3048)
			(end 0.67945 -0.3048)
			(stroke
				(width 0.1)
				(type default)
			)
			(layer "F.Fab")
		)
		(fp_line
			(start 0.120396 0.3048)
			(end 0.120396 0.2794)
			(stroke
				(width 0.1)
				(type default)
			)
			(layer "F.Fab")
		)
		(fp_line
			(start 0.120396 0.2794)
			(end -0.12065 0.2794)
			(stroke
				(width 0.1)
				(type default)
			)
			(layer "F.Fab")
		)
		(fp_line
			(start -0.12065 0.3048)
			(end -0.67945 0.3048)
			(stroke
				(width 0.1)
				(type default)
			)
			(layer "F.Fab")
		)
		(fp_line
			(start -0.12065 0.2794)
			(end -0.12065 0.3048)
			(stroke
				(width 0.1)
				(type default)
			)
			(layer "F.Fab")
		)
		(fp_line
			(start -0.12065 -0.2794)
			(end 0.12065 -0.2794)
			(stroke
				(width 0.1)
				(type default)
			)
			(layer "F.Fab")
		)
		(fp_line
			(start -0.12065 -0.305054)
			(end -0.12065 -0.2794)
			(stroke
				(width 0.1)
				(type default)
			)
			(layer "F.Fab")
		)
		(fp_line
			(start -0.67945 0.3048)
			(end -0.67945 -0.305054)
			(stroke
				(width 0.1)
				(type default)
			)
			(layer "F.Fab")
		)
		(fp_line
			(start -0.67945 -0.305054)
			(end -0.12065 -0.305054)
			(stroke
				(width 0.1)
				(type default)
			)
			(layer "F.Fab")
		)
		(pad "1" smd circle
			(at -0.40005 0 180)
			(size 0 0)
			(layers "F.Cu" "F.Mask" "F.Paste")
			(net "P5V_AUX_VCC")
		)
		(pad "2" smd circle
			(at 0.40005 0 180)
			(size 0 0)
			(layers "F.Cu" "F.Mask" "F.Paste")
			(net "PWRGD_P5V_AUX")
		)
	)
	(footprint ""
		(layer "F.Cu")
		(at 152.991312 -26.68778 -90)
		(property "Reference" "R6022"
			(at 0 0 270)
			(layer "F.SilkS")
			(hide yes)
			(effects
				(font
					(size 1.27 1.27)
				)
			)
		)
		(property "Value" ""
			(at 0 0 270)
			(layer "F.Fab")
			(effects
				(font
					(size 1.27 1.27)
				)
			)
		)
		(duplicate_pad_numbers_are_jumpers no)
		(fp_line
			(start -0.7874 0.4064)
			(end -0.7874 -0.4064)
			(stroke
				(width 0.1524)
				(type default)
			)
			(layer "F.SilkS")
		)
		(fp_line
			(start 0.7874 0.4064)
			(end -0.7874 0.4064)
			(stroke
				(width 0.1524)
				(type default)
			)
			(layer "F.SilkS")
		)
		(fp_line
			(start -0.7874 -0.4064)
			(end 0.7874 -0.4064)
			(stroke
				(width 0.1524)
				(type default)
			)
			(layer "F.SilkS")
		)
		(fp_line
			(start 0.7874 -0.4064)
			(end 0.7874 0.4064)
			(stroke
				(width 0.1524)
				(type default)
			)
			(layer "F.SilkS")
		)
		(fp_line
			(start -0.67945 0.3048)
			(end -0.67945 -0.305054)
			(stroke
				(width 0.1)
				(type default)
			)
			(layer "F.Fab")
		)
		(fp_line
			(start -0.12065 0.3048)
			(end -0.67945 0.3048)
			(stroke
				(width 0.1)
				(type default)
			)
			(layer "F.Fab")
		)
		(fp_line
			(start 0.120396 0.3048)
			(end 0.120396 0.2794)
			(stroke
				(width 0.1)
				(type default)
			)
			(layer "F.Fab")
		)
		(fp_line
			(start 0.67945 0.3048)
			(end 0.120396 0.3048)
			(stroke
				(width 0.1)
				(type default)
			)
			(layer "F.Fab")
		)
		(fp_line
			(start -0.12065 0.2794)
			(end -0.12065 0.3048)
			(stroke
				(width 0.1)
				(type default)
			)
			(layer "F.Fab")
		)
		(fp_line
			(start 0.120396 0.2794)
			(end -0.12065 0.2794)
			(stroke
				(width 0.1)
				(type default)
			)
			(layer "F.Fab")
		)
		(fp_line
			(start -0.12065 -0.2794)
			(end 0.12065 -0.2794)
			(stroke
				(width 0.1)
				(type default)
			)
			(layer "F.Fab")
		)
		(fp_line
			(start 0.12065 -0.2794)
			(end 0.12065 -0.3048)
			(stroke
				(width 0.1)
				(type default)
			)
			(layer "F.Fab")
		)
		(fp_line
			(start 0.12065 -0.3048)
			(end 0.67945 -0.3048)
			(stroke
				(width 0.1)
				(type default)
			)
			(layer "F.Fab")
		)
		(fp_line
			(start 0.67945 -0.3048)
			(end 0.67945 0.3048)
			(stroke
				(width 0.1)
				(type default)
			)
			(layer "F.Fab")
		)
		(fp_line
			(start -0.67945 -0.305054)
			(end -0.12065 -0.305054)
			(stroke
				(width 0.1)
				(type default)
			)
			(layer "F.Fab")
		)
		(fp_line
			(start -0.12065 -0.305054)
			(end -0.12065 -0.2794)
			(stroke
				(width 0.1)
				(type default)
			)
			(layer "F.Fab")
		)
		(pad "1" smd circle
			(at -0.40005 0 270)
			(size 0 0)
			(layers "F.Cu" "F.Mask" "F.Paste")
			(net "P3V3_AUX")
		)
		(pad "2" smd circle
			(at 0.40005 0 270)
			(size 0 0)
			(layers "F.Cu" "F.Mask" "F.Paste")
			(net "SGPIO_SCM_DI_<1>")
		)
	)
	(footprint ""
		(layer "F.Cu")
		(at 305.002184 -343.712038 180)
		(property "Reference" "PC191"
			(at 0 0 180)
			(layer "F.SilkS")
			(hide yes)
			(effects
				(font
					(size 1.27 1.27)
				)
			)
		)
		(property "Value" ""
			(at 0 0 180)
			(layer "F.Fab")
			(effects
				(font
					(size 1.27 1.27)
				)
			)
		)
		(duplicate_pad_numbers_are_jumpers no)
		(fp_line
			(start 0.7874 0.4064)
			(end -0.7874 0.4064)
			(stroke
				(width 0.1524)
				(type default)
			)
			(layer "F.SilkS")
		)
		(fp_line
			(start 0.7874 -0.4064)
			(end 0.7874 0.4064)
			(stroke
				(width 0.1524)
				(type default)
			)
			(layer "F.SilkS")
		)
		(fp_line
			(start -0.7874 0.4064)
			(end -0.7874 -0.4064)
			(stroke
				(width 0.1524)
				(type default)
			)
			(layer "F.SilkS")
		)
		(fp_line
			(start -0.7874 -0.4064)
			(end 0.7874 -0.4064)
			(stroke
				(width 0.1524)
				(type default)
			)
			(layer "F.SilkS")
		)
		(fp_line
			(start 0.67945 0.3048)
			(end 0.120396 0.3048)
			(stroke
				(width 0.1)
				(type default)
			)
			(layer "F.Fab")
		)
		(fp_line
			(start 0.67945 -0.3048)
			(end 0.67945 0.3048)
			(stroke
				(width 0.1)
				(type default)
			)
			(layer "F.Fab")
		)
		(fp_line
			(start 0.12065 -0.2794)
			(end 0.12065 -0.3048)
			(stroke
				(width 0.1)
				(type default)
			)
			(layer "F.Fab")
		)
		(fp_line
			(start 0.12065 -0.3048)
			(end 0.67945 -0.3048)
			(stroke
				(width 0.1)
				(type default)
			)
			(layer "F.Fab")
		)
		(fp_line
			(start 0.120396 0.3048)
			(end 0.120396 0.2794)
			(stroke
				(width 0.1)
				(type default)
			)
			(layer "F.Fab")
		)
		(fp_line
			(start 0.120396 0.2794)
			(end -0.12065 0.2794)
			(stroke
				(width 0.1)
				(type default)
			)
			(layer "F.Fab")
		)
		(fp_line
			(start -0.12065 0.3048)
			(end -0.67945 0.3048)
			(stroke
				(width 0.1)
				(type default)
			)
			(layer "F.Fab")
		)
		(fp_line
			(start -0.12065 0.2794)
			(end -0.12065 0.3048)
			(stroke
				(width 0.1)
				(type default)
			)
			(layer "F.Fab")
		)
		(fp_line
			(start -0.12065 -0.2794)
			(end 0.12065 -0.2794)
			(stroke
				(width 0.1)
				(type default)
			)
			(layer "F.Fab")
		)
		(fp_line
			(start -0.12065 -0.305054)
			(end -0.12065 -0.2794)
			(stroke
				(width 0.1)
				(type default)
			)
			(layer "F.Fab")
		)
		(fp_line
			(start -0.67945 0.3048)
			(end -0.67945 -0.305054)
			(stroke
				(width 0.1)
				(type default)
			)
			(layer "F.Fab")
		)
		(fp_line
			(start -0.67945 -0.305054)
			(end -0.12065 -0.305054)
			(stroke
				(width 0.1)
				(type default)
			)
			(layer "F.Fab")
		)
		(pad "1" smd circle
			(at -0.40005 0 180)
			(size 0 0)
			(layers "F.Cu" "F.Mask" "F.Paste")
			(net "SW_PVDDCR_CPU1_P0_SW4")
		)
		(pad "2" smd circle
			(at 0.40005 0 180)
			(size 0 0)
			(layers "F.Cu" "F.Mask" "F.Paste")
			(net "SW_PVDDCR_CPU1_P0_SW4_RC")
		)
	)
	(footprint ""
		(layer "F.Cu")
		(at 46.16704 -438.753504 90)
		(property "Reference" "R3508"
			(at 0 0 90)
			(layer "F.SilkS")
			(hide yes)
			(effects
				(font
					(size 1.27 1.27)
				)
			)
		)
		(property "Value" ""
			(at 0 0 90)
			(layer "F.Fab")
			(effects
				(font
					(size 1.27 1.27)
				)
			)
		)
		(duplicate_pad_numbers_are_jumpers no)
		(fp_line
			(start 0.7874 -0.4064)
			(end 0.7874 0.4064)
			(stroke
				(width 0.1524)
				(type default)
			)
			(layer "F.SilkS")
		)
		(fp_line
			(start -0.7874 -0.4064)
			(end 0.7874 -0.4064)
			(stroke
				(width 0.1524)
				(type default)
			)
			(layer "F.SilkS")
		)
		(fp_line
			(start 0.7874 0.4064)
			(end -0.7874 0.4064)
			(stroke
				(width 0.1524)
				(type default)
			)
			(layer "F.SilkS")
		)
		(fp_line
			(start -0.7874 0.4064)
			(end -0.7874 -0.4064)
			(stroke
				(width 0.1524)
				(type default)
			)
			(layer "F.SilkS")
		)
		(fp_line
			(start -0.12065 -0.305054)
			(end -0.12065 -0.2794)
			(stroke
				(width 0.1)
				(type default)
			)
			(layer "F.Fab")
		)
		(fp_line
			(start -0.67945 -0.305054)
			(end -0.12065 -0.305054)
			(stroke
				(width 0.1)
				(type default)
			)
			(layer "F.Fab")
		)
		(fp_line
			(start 0.67945 -0.3048)
			(end 0.67945 0.3048)
			(stroke
				(width 0.1)
				(type default)
			)
			(layer "F.Fab")
		)
		(fp_line
			(start 0.12065 -0.3048)
			(end 0.67945 -0.3048)
			(stroke
				(width 0.1)
				(type default)
			)
			(layer "F.Fab")
		)
		(fp_line
			(start 0.12065 -0.2794)
			(end 0.12065 -0.3048)
			(stroke
				(width 0.1)
				(type default)
			)
			(layer "F.Fab")
		)
		(fp_line
			(start -0.12065 -0.2794)
			(end 0.12065 -0.2794)
			(stroke
				(width 0.1)
				(type default)
			)
			(layer "F.Fab")
		)
		(fp_line
			(start 0.120396 0.2794)
			(end -0.12065 0.2794)
			(stroke
				(width 0.1)
				(type default)
			)
			(layer "F.Fab")
		)
		(fp_line
			(start -0.12065 0.2794)
			(end -0.12065 0.3048)
			(stroke
				(width 0.1)
				(type default)
			)
			(layer "F.Fab")
		)
		(fp_line
			(start 0.67945 0.3048)
			(end 0.120396 0.3048)
			(stroke
				(width 0.1)
				(type default)
			)
			(layer "F.Fab")
		)
		(fp_line
			(start 0.120396 0.3048)
			(end 0.120396 0.2794)
			(stroke
				(width 0.1)
				(type default)
			)
			(layer "F.Fab")
		)
		(fp_line
			(start -0.12065 0.3048)
			(end -0.67945 0.3048)
			(stroke
				(width 0.1)
				(type default)
			)
			(layer "F.Fab")
		)
		(fp_line
			(start -0.67945 0.3048)
			(end -0.67945 -0.305054)
			(stroke
				(width 0.1)
				(type default)
			)
			(layer "F.Fab")
		)
		(pad "1" smd circle
			(at -0.40005 0 90)
			(size 0 0)
			(layers "F.Cu" "F.Mask" "F.Paste")
			(net "FM_GPU_PWR_EN_R1")
		)
		(pad "2" smd circle
			(at 0.40005 0 90)
			(size 0 0)
			(layers "F.Cu" "F.Mask" "F.Paste")
			(net "GND")
		)
	)
	(footprint ""
		(layer "F.Cu")
		(at 290.703762 -351.927922)
		(property "Reference" "PR97"
			(at 0 0 0)
			(layer "F.SilkS")
			(hide yes)
			(effects
				(font
					(size 1.27 1.27)
				)
			)
		)
		(property "Value" ""
			(at 0 0 0)
			(layer "F.Fab")
			(effects
				(font
					(size 1.27 1.27)
				)
			)
		)
		(duplicate_pad_numbers_are_jumpers no)
		(fp_line
			(start -0.7874 -0.4064)
			(end 0.7874 -0.4064)
			(stroke
				(width 0.1524)
				(type default)
			)
			(layer "F.SilkS")
		)
		(fp_line
			(start -0.7874 0.4064)
			(end -0.7874 -0.4064)
			(stroke
				(width 0.1524)
				(type default)
			)
			(layer "F.SilkS")
		)
		(fp_line
			(start 0.7874 -0.4064)
			(end 0.7874 0.4064)
			(stroke
				(width 0.1524)
				(type default)
			)
			(layer "F.SilkS")
		)
		(fp_line
			(start 0.7874 0.4064)
			(end -0.7874 0.4064)
			(stroke
				(width 0.1524)
				(type default)
			)
			(layer "F.SilkS")
		)
		(fp_line
			(start -0.67945 -0.305054)
			(end -0.12065 -0.305054)
			(stroke
				(width 0.1)
				(type default)
			)
			(layer "F.Fab")
		)
		(fp_line
			(start -0.67945 0.3048)
			(end -0.67945 -0.305054)
			(stroke
				(width 0.1)
				(type default)
			)
			(layer "F.Fab")
		)
		(fp_line
			(start -0.12065 -0.305054)
			(end -0.12065 -0.2794)
			(stroke
				(width 0.1)
				(type default)
			)
			(layer "F.Fab")
		)
		(fp_line
			(start -0.12065 -0.2794)
			(end 0.12065 -0.2794)
			(stroke
				(width 0.1)
				(type default)
			)
			(layer "F.Fab")
		)
		(fp_line
			(start -0.12065 0.2794)
			(end -0.12065 0.3048)
			(stroke
				(width 0.1)
				(type default)
			)
			(layer "F.Fab")
		)
		(fp_line
			(start -0.12065 0.3048)
			(end -0.67945 0.3048)
			(stroke
				(width 0.1)
				(type default)
			)
			(layer "F.Fab")
		)
		(fp_line
			(start 0.120396 0.2794)
			(end -0.12065 0.2794)
			(stroke
				(width 0.1)
				(type default)
			)
			(layer "F.Fab")
		)
		(fp_line
			(start 0.120396 0.3048)
			(end 0.120396 0.2794)
			(stroke
				(width 0.1)
				(type default)
			)
			(layer "F.Fab")
		)
		(fp_line
			(start 0.12065 -0.3048)
			(end 0.67945 -0.3048)
			(stroke
				(width 0.1)
				(type default)
			)
			(layer "F.Fab")
		)
		(fp_line
			(start 0.12065 -0.2794)
			(end 0.12065 -0.3048)
			(stroke
				(width 0.1)
				(type default)
			)
			(layer "F.Fab")
		)
		(fp_line
			(start 0.67945 -0.3048)
			(end 0.67945 0.3048)
			(stroke
				(width 0.1)
				(type default)
			)
			(layer "F.Fab")
		)
		(fp_line
			(start 0.67945 0.3048)
			(end 0.120396 0.3048)
			(stroke
				(width 0.1)
				(type default)
			)
			(layer "F.Fab")
		)
		(pad "1" smd circle
			(at -0.40005 0)
			(size 0 0)
			(layers "F.Cu" "F.Mask" "F.Paste")
			(net "PVDDIO_P0_LSET2")
		)
		(pad "2" smd circle
			(at 0.40005 0)
			(size 0 0)
			(layers "F.Cu" "F.Mask" "F.Paste")
			(net "GND")
		)
	)
	(footprint ""
		(layer "F.Cu")
		(at 124.088652 -76.251562 90)
		(property "Reference" "PC6017"
			(at 0 0 90)
			(layer "F.SilkS")
			(hide yes)
			(effects
				(font
					(size 1.27 1.27)
				)
			)
		)
		(property "Value" ""
			(at 0 0 90)
			(layer "F.Fab")
			(effects
				(font
					(size 1.27 1.27)
				)
			)
		)
		(duplicate_pad_numbers_are_jumpers no)
		(fp_line
			(start 0.7874 -0.4064)
			(end 0.7874 0.4064)
			(stroke
				(width 0.1524)
				(type default)
			)
			(layer "F.SilkS")
		)
		(fp_line
			(start -0.7874 -0.4064)
			(end 0.7874 -0.4064)
			(stroke
				(width 0.1524)
				(type default)
			)
			(layer "F.SilkS")
		)
		(fp_line
			(start 0.7874 0.4064)
			(end -0.7874 0.4064)
			(stroke
				(width 0.1524)
				(type default)
			)
			(layer "F.SilkS")
		)
		(fp_line
			(start -0.7874 0.4064)
			(end -0.7874 -0.4064)
			(stroke
				(width 0.1524)
				(type default)
			)
			(layer "F.SilkS")
		)
		(fp_line
			(start -0.12065 -0.305054)
			(end -0.12065 -0.2794)
			(stroke
				(width 0.1)
				(type default)
			)
			(layer "F.Fab")
		)
		(fp_line
			(start -0.67945 -0.305054)
			(end -0.12065 -0.305054)
			(stroke
				(width 0.1)
				(type default)
			)
			(layer "F.Fab")
		)
		(fp_line
			(start 0.67945 -0.3048)
			(end 0.67945 0.3048)
			(stroke
				(width 0.1)
				(type default)
			)
			(layer "F.Fab")
		)
		(fp_line
			(start 0.12065 -0.3048)
			(end 0.67945 -0.3048)
			(stroke
				(width 0.1)
				(type default)
			)
			(layer "F.Fab")
		)
		(fp_line
			(start 0.12065 -0.2794)
			(end 0.12065 -0.3048)
			(stroke
				(width 0.1)
				(type default)
			)
			(layer "F.Fab")
		)
		(fp_line
			(start -0.12065 -0.2794)
			(end 0.12065 -0.2794)
			(stroke
				(width 0.1)
				(type default)
			)
			(layer "F.Fab")
		)
		(fp_line
			(start 0.120396 0.2794)
			(end -0.12065 0.2794)
			(stroke
				(width 0.1)
				(type default)
			)
			(layer "F.Fab")
		)
		(fp_line
			(start -0.12065 0.2794)
			(end -0.12065 0.3048)
			(stroke
				(width 0.1)
				(type default)
			)
			(layer "F.Fab")
		)
		(fp_line
			(start 0.67945 0.3048)
			(end 0.120396 0.3048)
			(stroke
				(width 0.1)
				(type default)
			)
			(layer "F.Fab")
		)
		(fp_line
			(start 0.120396 0.3048)
			(end 0.120396 0.2794)
			(stroke
				(width 0.1)
				(type default)
			)
			(layer "F.Fab")
		)
		(fp_line
			(start -0.12065 0.3048)
			(end -0.67945 0.3048)
			(stroke
				(width 0.1)
				(type default)
			)
			(layer "F.Fab")
		)
		(fp_line
			(start -0.67945 0.3048)
			(end -0.67945 -0.305054)
			(stroke
				(width 0.1)
				(type default)
			)
			(layer "F.Fab")
		)
		(pad "1" smd circle
			(at -0.40005 0 90)
			(size 0 0)
			(layers "F.Cu" "F.Mask" "F.Paste")
			(net "SW_P1V2_AUX_BT_R")
		)
		(pad "2" smd circle
			(at 0.40005 0 90)
			(size 0 0)
			(layers "F.Cu" "F.Mask" "F.Paste")
			(net "SW_P1V2_AUX_PH")
		)
	)
	(footprint ""
		(layer "F.Cu")
		(at 413.951928 -351.414842)
		(property "Reference" "H33"
			(at -4.175506 -4.435348 0)
			(unlocked yes)
			(layer "F.SilkS")
			(effects
				(font
					(size 0.7874 0.5842)
					(thickness 0.1524)
				)
				(justify left)
			)
		)
		(property "Value" ""
			(at 0 0 0)
			(layer "F.Fab")
			(effects
				(font
					(size 1.27 1.27)
				)
			)
		)
		(duplicate_pad_numbers_are_jumpers no)
		(pad "1" thru_hole circle
			(at 0 0)
			(size 6.1976 6.1976)
			(drill 3.7338)
			(layers "*.Cu" "*.Mask")
			(remove_unused_layers no)
			(net "GND")
			(clearance -0.9779)
			(padstack
				(mode front_inner_back)
				(layer "Inner"
					(shape circle)
					(size 5.5372 5.5372)
					(clearance -0.6477)
				)
				(layer "B.Cu"
					(shape circle)
					(size 6.1976 6.1976)
					(clearance -0.9779)
				)
			)
		)
	)
	(footprint ""
		(layer "F.Cu")
		(at 114.52987 -68.811394)
		(property "Reference" "C6083"
			(at 0 0 0)
			(layer "F.SilkS")
			(hide yes)
			(effects
				(font
					(size 1.27 1.27)
				)
			)
		)
		(property "Value" ""
			(at 0 0 0)
			(layer "F.Fab")
			(effects
				(font
					(size 1.27 1.27)
				)
			)
		)
		(duplicate_pad_numbers_are_jumpers no)
		(fp_line
			(start -0.7874 -0.4064)
			(end 0.7874 -0.4064)
			(stroke
				(width 0.1524)
				(type default)
			)
			(layer "F.SilkS")
		)
		(fp_line
			(start -0.7874 0.4064)
			(end -0.7874 -0.4064)
			(stroke
				(width 0.1524)
				(type default)
			)
			(layer "F.SilkS")
		)
		(fp_line
			(start 0.7874 -0.4064)
			(end 0.7874 0.4064)
			(stroke
				(width 0.1524)
				(type default)
			)
			(layer "F.SilkS")
		)
		(fp_line
			(start 0.7874 0.4064)
			(end -0.7874 0.4064)
			(stroke
				(width 0.1524)
				(type default)
			)
			(layer "F.SilkS")
		)
		(fp_line
			(start -0.67945 -0.305054)
			(end -0.12065 -0.305054)
			(stroke
				(width 0.1)
				(type default)
			)
			(layer "F.Fab")
		)
		(fp_line
			(start -0.67945 0.3048)
			(end -0.67945 -0.305054)
			(stroke
				(width 0.1)
				(type default)
			)
			(layer "F.Fab")
		)
		(fp_line
			(start -0.12065 -0.305054)
			(end -0.12065 -0.2794)
			(stroke
				(width 0.1)
				(type default)
			)
			(layer "F.Fab")
		)
		(fp_line
			(start -0.12065 -0.2794)
			(end 0.12065 -0.2794)
			(stroke
				(width 0.1)
				(type default)
			)
			(layer "F.Fab")
		)
		(fp_line
			(start -0.12065 0.2794)
			(end -0.12065 0.3048)
			(stroke
				(width 0.1)
				(type default)
			)
			(layer "F.Fab")
		)
		(fp_line
			(start -0.12065 0.3048)
			(end -0.67945 0.3048)
			(stroke
				(width 0.1)
				(type default)
			)
			(layer "F.Fab")
		)
		(fp_line
			(start 0.120396 0.2794)
			(end -0.12065 0.2794)
			(stroke
				(width 0.1)
				(type default)
			)
			(layer "F.Fab")
		)
		(fp_line
			(start 0.120396 0.3048)
			(end 0.120396 0.2794)
			(stroke
				(width 0.1)
				(type default)
			)
			(layer "F.Fab")
		)
		(fp_line
			(start 0.12065 -0.3048)
			(end 0.67945 -0.3048)
			(stroke
				(width 0.1)
				(type default)
			)
			(layer "F.Fab")
		)
		(fp_line
			(start 0.12065 -0.2794)
			(end 0.12065 -0.3048)
			(stroke
				(width 0.1)
				(type default)
			)
			(layer "F.Fab")
		)
		(fp_line
			(start 0.67945 -0.3048)
			(end 0.67945 0.3048)
			(stroke
				(width 0.1)
				(type default)
			)
			(layer "F.Fab")
		)
		(fp_line
			(start 0.67945 0.3048)
			(end 0.120396 0.3048)
			(stroke
				(width 0.1)
				(type default)
			)
			(layer "F.Fab")
		)
		(pad "1" smd circle
			(at -0.40005 0)
			(size 0 0)
			(layers "F.Cu" "F.Mask" "F.Paste")
			(net "P3V3_AUX")
		)
		(pad "2" smd circle
			(at 0.40005 0)
			(size 0 0)
			(layers "F.Cu" "F.Mask" "F.Paste")
			(net "GND")
		)
	)
	(footprint ""
		(layer "F.Cu")
		(at 168.513506 -416.929316 90)
		(property "Reference" "R810"
			(at 0 0 90)
			(layer "F.SilkS")
			(hide yes)
			(effects
				(font
					(size 1.27 1.27)
				)
			)
		)
		(property "Value" ""
			(at 0 0 90)
			(layer "F.Fab")
			(effects
				(font
					(size 1.27 1.27)
				)
			)
		)
		(duplicate_pad_numbers_are_jumpers no)
		(fp_line
			(start 0.32512 -0.175006)
			(end 0.32512 0.175006)
			(stroke
				(width 0.1)
				(type default)
			)
			(layer "F.Fab")
		)
		(fp_line
			(start -0.32512 -0.175006)
			(end 0.32512 -0.175006)
			(stroke
				(width 0.1)
				(type default)
			)
			(layer "F.Fab")
		)
		(fp_line
			(start 0.32512 0.175006)
			(end -0.32512 0.175006)
			(stroke
				(width 0.1)
				(type default)
			)
			(layer "F.Fab")
		)
		(fp_line
			(start -0.32512 0.175006)
			(end -0.32512 -0.175006)
			(stroke
				(width 0.1)
				(type default)
			)
			(layer "F.Fab")
		)
		(pad "1" smd rect
			(at -0.2667 0 90)
			(size 0.3048 0.381)
			(layers "F.Cu" "F.Mask" "F.Paste")
			(net "P1V8_CPU1_RT_1D")
		)
		(pad "2" smd rect
			(at 0.2667 0 270)
			(size 0.3048 0.381)
			(layers "F.Cu" "F.Mask" "F.Paste")
			(net "SMB_RT_CPU1_P3_ROM_R_SDA")
		)
	)
	(footprint ""
		(layer "F.Cu")
		(at 123.35637 -35.430968 180)
		(property "Reference" "C6024"
			(at 0 0 180)
			(layer "F.SilkS")
			(hide yes)
			(effects
				(font
					(size 1.27 1.27)
				)
			)
		)
		(property "Value" ""
			(at 0 0 180)
			(layer "F.Fab")
			(effects
				(font
					(size 1.27 1.27)
				)
			)
		)
		(duplicate_pad_numbers_are_jumpers no)
		(fp_line
			(start 0.7874 0.4064)
			(end -0.7874 0.4064)
			(stroke
				(width 0.1524)
				(type default)
			)
			(layer "F.SilkS")
		)
		(fp_line
			(start 0.7874 -0.4064)
			(end 0.7874 0.4064)
			(stroke
				(width 0.1524)
				(type default)
			)
			(layer "F.SilkS")
		)
		(fp_line
			(start -0.7874 0.4064)
			(end -0.7874 -0.4064)
			(stroke
				(width 0.1524)
				(type default)
			)
			(layer "F.SilkS")
		)
		(fp_line
			(start -0.7874 -0.4064)
			(end 0.7874 -0.4064)
			(stroke
				(width 0.1524)
				(type default)
			)
			(layer "F.SilkS")
		)
		(fp_line
			(start 0.6858 0.3048)
			(end 0.1016 0.3048)
			(stroke
				(width 0.1)
				(type default)
			)
			(layer "F.Fab")
		)
		(fp_line
			(start 0.6858 -0.3048)
			(end 0.6858 0.3048)
			(stroke
				(width 0.1)
				(type default)
			)
			(layer "F.Fab")
		)
		(fp_line
			(start 0.1016 0.3048)
			(end 0.1016 0.2794)
			(stroke
				(width 0.1)
				(type default)
			)
			(layer "F.Fab")
		)
		(fp_line
			(start 0.1016 0.2794)
			(end -0.1016 0.2794)
			(stroke
				(width 0.1)
				(type default)
			)
			(layer "F.Fab")
		)
		(fp_line
			(start 0.1016 -0.2794)
			(end 0.1016 -0.3048)
			(stroke
				(width 0.1)
				(type default)
			)
			(layer "F.Fab")
		)
		(fp_line
			(start 0.1016 -0.3048)
			(end 0.6858 -0.3048)
			(stroke
				(width 0.1)
				(type default)
			)
			(layer "F.Fab")
		)
		(fp_line
			(start -0.1016 0.3048)
			(end -0.6858 0.3048)
			(stroke
				(width 0.1)
				(type default)
			)
			(layer "F.Fab")
		)
		(fp_line
			(start -0.1016 0.2794)
			(end -0.1016 0.3048)
			(stroke
				(width 0.1)
				(type default)
			)
			(layer "F.Fab")
		)
		(fp_line
			(start -0.1016 -0.2794)
			(end 0.1016 -0.2794)
			(stroke
				(width 0.1)
				(type default)
			)
			(layer "F.Fab")
		)
		(fp_line
			(start -0.1016 -0.3048)
			(end -0.1016 -0.2794)
			(stroke
				(width 0.1)
				(type default)
			)
			(layer "F.Fab")
		)
		(fp_line
			(start -0.6858 0.3048)
			(end -0.6858 -0.3048)
			(stroke
				(width 0.1)
				(type default)
			)
			(layer "F.Fab")
		)
		(fp_line
			(start -0.6858 -0.3048)
			(end -0.1016 -0.3048)
			(stroke
				(width 0.1)
				(type default)
			)
			(layer "F.Fab")
		)
		(pad "1" smd rect
			(at -0.40005 0)
			(size 0.4572 0.508)
			(layers "F.Cu" "F.Mask" "F.Paste")
			(net "USB3_CPU0_BMC_HUB1_TX_DN")
		)
		(pad "2" smd rect
			(at 0.40005 0)
			(size 0.4572 0.508)
			(layers "F.Cu" "F.Mask" "F.Paste")
			(net "USB3_CPU0_BMC_TX_BUF_C_DN")
		)
	)
	(footprint ""
		(layer "F.Cu")
		(at 212.725 -99.822)
		(property "Reference" "R9032"
			(at 0 0 0)
			(layer "F.SilkS")
			(hide yes)
			(effects
				(font
					(size 1.27 1.27)
				)
			)
		)
		(property "Value" ""
			(at 0 0 0)
			(layer "F.Fab")
			(effects
				(font
					(size 1.27 1.27)
				)
			)
		)
		(duplicate_pad_numbers_are_jumpers no)
		(fp_line
			(start -0.7874 -0.4064)
			(end 0.7874 -0.4064)
			(stroke
				(width 0.1524)
				(type default)
			)
			(layer "F.SilkS")
		)
		(fp_line
			(start -0.7874 0.4064)
			(end -0.7874 -0.4064)
			(stroke
				(width 0.1524)
				(type default)
			)
			(layer "F.SilkS")
		)
		(fp_line
			(start 0.7874 -0.4064)
			(end 0.7874 0.4064)
			(stroke
				(width 0.1524)
				(type default)
			)
			(layer "F.SilkS")
		)
		(fp_line
			(start 0.7874 0.4064)
			(end -0.7874 0.4064)
			(stroke
				(width 0.1524)
				(type default)
			)
			(layer "F.SilkS")
		)
		(fp_line
			(start -0.67945 -0.305054)
			(end -0.12065 -0.305054)
			(stroke
				(width 0.1)
				(type default)
			)
			(layer "F.Fab")
		)
		(fp_line
			(start -0.67945 0.3048)
			(end -0.67945 -0.305054)
			(stroke
				(width 0.1)
				(type default)
			)
			(layer "F.Fab")
		)
		(fp_line
			(start -0.12065 -0.305054)
			(end -0.12065 -0.2794)
			(stroke
				(width 0.1)
				(type default)
			)
			(layer "F.Fab")
		)
		(fp_line
			(start -0.12065 -0.2794)
			(end 0.12065 -0.2794)
			(stroke
				(width 0.1)
				(type default)
			)
			(layer "F.Fab")
		)
		(fp_line
			(start -0.12065 0.2794)
			(end -0.12065 0.3048)
			(stroke
				(width 0.1)
				(type default)
			)
			(layer "F.Fab")
		)
		(fp_line
			(start -0.12065 0.3048)
			(end -0.67945 0.3048)
			(stroke
				(width 0.1)
				(type default)
			)
			(layer "F.Fab")
		)
		(fp_line
			(start 0.120396 0.2794)
			(end -0.12065 0.2794)
			(stroke
				(width 0.1)
				(type default)
			)
			(layer "F.Fab")
		)
		(fp_line
			(start 0.120396 0.3048)
			(end 0.120396 0.2794)
			(stroke
				(width 0.1)
				(type default)
			)
			(layer "F.Fab")
		)
		(fp_line
			(start 0.12065 -0.3048)
			(end 0.67945 -0.3048)
			(stroke
				(width 0.1)
				(type default)
			)
			(layer "F.Fab")
		)
		(fp_line
			(start 0.12065 -0.2794)
			(end 0.12065 -0.3048)
			(stroke
				(width 0.1)
				(type default)
			)
			(layer "F.Fab")
		)
		(fp_line
			(start 0.67945 -0.3048)
			(end 0.67945 0.3048)
			(stroke
				(width 0.1)
				(type default)
			)
			(layer "F.Fab")
		)
		(fp_line
			(start 0.67945 0.3048)
			(end 0.120396 0.3048)
			(stroke
				(width 0.1)
				(type default)
			)
			(layer "F.Fab")
		)
		(pad "1" smd circle
			(at -0.40005 0)
			(size 0 0)
			(layers "F.Cu" "F.Mask" "F.Paste")
			(net "P3V3_AUX")
		)
		(pad "2" smd circle
			(at 0.40005 0)
			(size 0 0)
			(layers "F.Cu" "F.Mask" "F.Paste")
			(net "FM_PLD_OCP_SFF_AUX_PWR_EN")
		)
	)
	(footprint ""
		(layer "F.Cu")
		(at 372.937278 -139.440158)
		(property "Reference" "R8311"
			(at 0 0 0)
			(layer "F.SilkS")
			(hide yes)
			(effects
				(font
					(size 1.27 1.27)
				)
			)
		)
		(property "Value" ""
			(at 0 0 0)
			(layer "F.Fab")
			(effects
				(font
					(size 1.27 1.27)
				)
			)
		)
		(duplicate_pad_numbers_are_jumpers no)
		(fp_line
			(start -0.7874 -0.4064)
			(end 0.7874 -0.4064)
			(stroke
				(width 0.1524)
				(type default)
			)
			(layer "F.SilkS")
		)
		(fp_line
			(start -0.7874 0.4064)
			(end -0.7874 -0.4064)
			(stroke
				(width 0.1524)
				(type default)
			)
			(layer "F.SilkS")
		)
		(fp_line
			(start 0.7874 -0.4064)
			(end 0.7874 0.4064)
			(stroke
				(width 0.1524)
				(type default)
			)
			(layer "F.SilkS")
		)
		(fp_line
			(start 0.7874 0.4064)
			(end -0.7874 0.4064)
			(stroke
				(width 0.1524)
				(type default)
			)
			(layer "F.SilkS")
		)
		(fp_line
			(start -0.67945 -0.305054)
			(end -0.12065 -0.305054)
			(stroke
				(width 0.1)
				(type default)
			)
			(layer "F.Fab")
		)
		(fp_line
			(start -0.67945 0.3048)
			(end -0.67945 -0.305054)
			(stroke
				(width 0.1)
				(type default)
			)
			(layer "F.Fab")
		)
		(fp_line
			(start -0.12065 -0.305054)
			(end -0.12065 -0.2794)
			(stroke
				(width 0.1)
				(type default)
			)
			(layer "F.Fab")
		)
		(fp_line
			(start -0.12065 -0.2794)
			(end 0.12065 -0.2794)
			(stroke
				(width 0.1)
				(type default)
			)
			(layer "F.Fab")
		)
		(fp_line
			(start -0.12065 0.2794)
			(end -0.12065 0.3048)
			(stroke
				(width 0.1)
				(type default)
			)
			(layer "F.Fab")
		)
		(fp_line
			(start -0.12065 0.3048)
			(end -0.67945 0.3048)
			(stroke
				(width 0.1)
				(type default)
			)
			(layer "F.Fab")
		)
		(fp_line
			(start 0.120396 0.2794)
			(end -0.12065 0.2794)
			(stroke
				(width 0.1)
				(type default)
			)
			(layer "F.Fab")
		)
		(fp_line
			(start 0.120396 0.3048)
			(end 0.120396 0.2794)
			(stroke
				(width 0.1)
				(type default)
			)
			(layer "F.Fab")
		)
		(fp_line
			(start 0.12065 -0.3048)
			(end 0.67945 -0.3048)
			(stroke
				(width 0.1)
				(type default)
			)
			(layer "F.Fab")
		)
		(fp_line
			(start 0.12065 -0.2794)
			(end 0.12065 -0.3048)
			(stroke
				(width 0.1)
				(type default)
			)
			(layer "F.Fab")
		)
		(fp_line
			(start 0.67945 -0.3048)
			(end 0.67945 0.3048)
			(stroke
				(width 0.1)
				(type default)
			)
			(layer "F.Fab")
		)
		(fp_line
			(start 0.67945 0.3048)
			(end 0.120396 0.3048)
			(stroke
				(width 0.1)
				(type default)
			)
			(layer "F.Fab")
		)
		(pad "1" smd circle
			(at -0.40005 0)
			(size 0 0)
			(layers "F.Cu" "F.Mask" "F.Paste")
			(net "PWRGD_PVDDCR_CPU0_P0")
		)
		(pad "2" smd circle
			(at 0.40005 0)
			(size 0 0)
			(layers "F.Cu" "F.Mask" "F.Paste")
			(net "PWRGD_PVDDCR_CPU0_P0_R")
		)
	)
	(footprint ""
		(layer "F.Cu")
		(at 419.868096 -357.688134 -90)
		(property "Reference" "PR33"
			(at 0 0 270)
			(layer "F.SilkS")
			(hide yes)
			(effects
				(font
					(size 1.27 1.27)
				)
			)
		)
		(property "Value" ""
			(at 0 0 270)
			(layer "F.Fab")
			(effects
				(font
					(size 1.27 1.27)
				)
			)
		)
		(duplicate_pad_numbers_are_jumpers no)
		(fp_line
			(start -0.7874 0.4064)
			(end -0.7874 -0.4064)
			(stroke
				(width 0.1524)
				(type default)
			)
			(layer "F.SilkS")
		)
		(fp_line
			(start 0.7874 0.4064)
			(end -0.7874 0.4064)
			(stroke
				(width 0.1524)
				(type default)
			)
			(layer "F.SilkS")
		)
		(fp_line
			(start -0.7874 -0.4064)
			(end 0.7874 -0.4064)
			(stroke
				(width 0.1524)
				(type default)
			)
			(layer "F.SilkS")
		)
		(fp_line
			(start 0.7874 -0.4064)
			(end 0.7874 0.4064)
			(stroke
				(width 0.1524)
				(type default)
			)
			(layer "F.SilkS")
		)
		(fp_line
			(start -0.67945 0.3048)
			(end -0.67945 -0.305054)
			(stroke
				(width 0.1)
				(type default)
			)
			(layer "F.Fab")
		)
		(fp_line
			(start -0.12065 0.3048)
			(end -0.67945 0.3048)
			(stroke
				(width 0.1)
				(type default)
			)
			(layer "F.Fab")
		)
		(fp_line
			(start 0.120396 0.3048)
			(end 0.120396 0.2794)
			(stroke
				(width 0.1)
				(type default)
			)
			(layer "F.Fab")
		)
		(fp_line
			(start 0.67945 0.3048)
			(end 0.120396 0.3048)
			(stroke
				(width 0.1)
				(type default)
			)
			(layer "F.Fab")
		)
		(fp_line
			(start -0.12065 0.2794)
			(end -0.12065 0.3048)
			(stroke
				(width 0.1)
				(type default)
			)
			(layer "F.Fab")
		)
		(fp_line
			(start 0.120396 0.2794)
			(end -0.12065 0.2794)
			(stroke
				(width 0.1)
				(type default)
			)
			(layer "F.Fab")
		)
		(fp_line
			(start -0.12065 -0.2794)
			(end 0.12065 -0.2794)
			(stroke
				(width 0.1)
				(type default)
			)
			(layer "F.Fab")
		)
		(fp_line
			(start 0.12065 -0.2794)
			(end 0.12065 -0.3048)
			(stroke
				(width 0.1)
				(type default)
			)
			(layer "F.Fab")
		)
		(fp_line
			(start 0.12065 -0.3048)
			(end 0.67945 -0.3048)
			(stroke
				(width 0.1)
				(type default)
			)
			(layer "F.Fab")
		)
		(fp_line
			(start 0.67945 -0.3048)
			(end 0.67945 0.3048)
			(stroke
				(width 0.1)
				(type default)
			)
			(layer "F.Fab")
		)
		(fp_line
			(start -0.67945 -0.305054)
			(end -0.12065 -0.305054)
			(stroke
				(width 0.1)
				(type default)
			)
			(layer "F.Fab")
		)
		(fp_line
			(start -0.12065 -0.305054)
			(end -0.12065 -0.2794)
			(stroke
				(width 0.1)
				(type default)
			)
			(layer "F.Fab")
		)
		(pad "1" smd circle
			(at -0.40005 0 270)
			(size 0 0)
			(layers "F.Cu" "F.Mask" "F.Paste")
			(net "NC_PVDD11_S3_P0_IMON4")
		)
		(pad "2" smd circle
			(at 0.40005 0 270)
			(size 0 0)
			(layers "F.Cu" "F.Mask" "F.Paste")
			(net "GND")
		)
	)
	(footprint ""
		(layer "F.Cu")
		(at 41.874694 -17.623536 90)
		(property "Reference" "C697"
			(at 0 0 90)
			(layer "F.SilkS")
			(hide yes)
			(effects
				(font
					(size 1.27 1.27)
				)
			)
		)
		(property "Value" ""
			(at 0 0 90)
			(layer "F.Fab")
			(effects
				(font
					(size 1.27 1.27)
				)
			)
		)
		(duplicate_pad_numbers_are_jumpers no)
		(fp_line
			(start 0.299974 -0.150114)
			(end 0.299974 0.150114)
			(stroke
				(width 0.1)
				(type default)
			)
			(layer "F.Fab")
		)
		(fp_line
			(start -0.299974 -0.150114)
			(end 0.299974 -0.150114)
			(stroke
				(width 0.1)
				(type default)
			)
			(layer "F.Fab")
		)
		(fp_line
			(start 0.299974 0.150114)
			(end -0.299974 0.150114)
			(stroke
				(width 0.1)
				(type default)
			)
			(layer "F.Fab")
		)
		(fp_line
			(start -0.299974 0.150114)
			(end -0.299974 -0.150114)
			(stroke
				(width 0.1)
				(type default)
			)
			(layer "F.Fab")
		)
		(pad "1" smd rect
			(at -0.2667 0 90)
			(size 0.3048 0.381)
			(layers "F.Cu" "F.Mask" "F.Paste")
			(net "P5E_CPU1_G1_TX_C_DP<6>")
		)
		(pad "2" smd rect
			(at 0.2667 0 90)
			(size 0.3048 0.381)
			(layers "F.Cu" "F.Mask" "F.Paste")
			(net "P5E_CPU1_G1_TX_DP<6>")
		)
	)
	(footprint ""
		(layer "F.Cu")
		(at 111.791496 -370.57203 -90)
		(property "Reference" "C1541"
			(at 0 0 270)
			(layer "F.SilkS")
			(hide yes)
			(effects
				(font
					(size 1.27 1.27)
				)
			)
		)
		(property "Value" ""
			(at 0 0 270)
			(layer "F.Fab")
			(effects
				(font
					(size 1.27 1.27)
				)
			)
		)
		(duplicate_pad_numbers_are_jumpers no)
		(fp_line
			(start -0.299974 0.150114)
			(end -0.299974 -0.150114)
			(stroke
				(width 0.1)
				(type default)
			)
			(layer "F.Fab")
		)
		(fp_line
			(start 0.299974 0.150114)
			(end -0.299974 0.150114)
			(stroke
				(width 0.1)
				(type default)
			)
			(layer "F.Fab")
		)
		(fp_line
			(start -0.299974 -0.150114)
			(end 0.299974 -0.150114)
			(stroke
				(width 0.1)
				(type default)
			)
			(layer "F.Fab")
		)
		(fp_line
			(start 0.299974 -0.150114)
			(end 0.299974 0.150114)
			(stroke
				(width 0.1)
				(type default)
			)
			(layer "F.Fab")
		)
		(pad "1" smd rect
			(at -0.2667 0 270)
			(size 0.3048 0.381)
			(layers "F.Cu" "F.Mask" "F.Paste")
			(net "P5E_CPU1_P3_TX_C_DP<3>")
		)
		(pad "2" smd rect
			(at 0.2667 0 270)
			(size 0.3048 0.381)
			(layers "F.Cu" "F.Mask" "F.Paste")
			(net "P5E_CPU1_P3_TX_DP<3>")
		)
	)
	(footprint ""
		(layer "F.Cu")
		(at 136.803638 -391.051288)
		(property "Reference" "R6902"
			(at 0 0 0)
			(layer "F.SilkS")
			(hide yes)
			(effects
				(font
					(size 1.27 1.27)
				)
			)
		)
		(property "Value" ""
			(at 0 0 0)
			(layer "F.Fab")
			(effects
				(font
					(size 1.27 1.27)
				)
			)
		)
		(duplicate_pad_numbers_are_jumpers no)
		(fp_line
			(start -0.32512 -0.175006)
			(end 0.32512 -0.175006)
			(stroke
				(width 0.1)
				(type default)
			)
			(layer "F.Fab")
		)
		(fp_line
			(start -0.32512 0.175006)
			(end -0.32512 -0.175006)
			(stroke
				(width 0.1)
				(type default)
			)
			(layer "F.Fab")
		)
		(fp_line
			(start 0.32512 -0.175006)
			(end 0.32512 0.175006)
			(stroke
				(width 0.1)
				(type default)
			)
			(layer "F.Fab")
		)
		(fp_line
			(start 0.32512 0.175006)
			(end -0.32512 0.175006)
			(stroke
				(width 0.1)
				(type default)
			)
			(layer "F.Fab")
		)
		(pad "1" smd rect
			(at -0.2667 0)
			(size 0.3048 0.381)
			(layers "F.Cu" "F.Mask" "F.Paste")
			(net "NCF_A1_CPU1_P3_GND")
		)
		(pad "2" smd rect
			(at 0.2667 0 180)
			(size 0.3048 0.381)
			(layers "F.Cu" "F.Mask" "F.Paste")
			(net "GND")
		)
	)
	(footprint ""
		(layer "F.Cu")
		(at 189.110112 -255.560322 180)
		(property "Reference" "J29"
			(at -2.7178 -81.857088 0)
			(unlocked yes)
			(layer "F.SilkS")
			(effects
				(font
					(size 0.7874 0.5842)
					(thickness 0.1524)
				)
			)
		)
		(property "Value" ""
			(at 0 0 180)
			(layer "F.Fab")
			(effects
				(font
					(size 1.27 1.27)
				)
			)
		)
		(duplicate_pad_numbers_are_jumpers no)
		(fp_line
			(start 3.24993 81.000092)
			(end -3.24993 81.000092)
			(stroke
				(width 0.1524)
				(type default)
			)
			(layer "F.SilkS")
		)
		(fp_line
			(start 3.24993 80.583278)
			(end 3.24993 81.000092)
			(stroke
				(width 0.1524)
				(type default)
			)
			(layer "F.SilkS")
		)
		(fp_line
			(start 3.24993 -81.000092)
			(end 3.24993 73.928478)
			(stroke
				(width 0.1524)
				(type default)
			)
			(layer "F.SilkS")
		)
		(fp_line
			(start -3.24993 81.000092)
			(end -3.24993 80.532478)
			(stroke
				(width 0.1524)
				(type default)
			)
			(layer "F.SilkS")
		)
		(fp_line
			(start -3.24993 73.928478)
			(end -3.24993 -81.000092)
			(stroke
				(width 0.1524)
				(type default)
			)
			(layer "F.SilkS")
		)
		(fp_line
			(start -3.24993 72.499982)
			(end 3.24993 72.499982)
			(stroke
				(width 0.1524)
				(type default)
			)
			(layer "F.SilkS")
		)
		(fp_line
			(start -3.24993 -72.499982)
			(end 3.24993 -72.499982)
			(stroke
				(width 0.1524)
				(type default)
			)
			(layer "F.SilkS")
		)
		(fp_line
			(start -3.24993 -81.000092)
			(end 3.24993 -81.000092)
			(stroke
				(width 0.1524)
				(type default)
			)
			(layer "F.SilkS")
		)
		(fp_poly
			(pts
				(xy -3.734816 -64.758316) (xy -3.064764 -63.841122) (xy -4.200398 -63.855346)
			)
			(stroke
				(width 0)
				(type default)
			)
			(fill yes)
			(layer "F.SilkS")
		)
		(fp_line
			(start 3.24993 81.000092)
			(end -3.24993 81.000092)
			(stroke
				(width 0.1)
				(type default)
			)
			(layer "F.Fab")
		)
		(fp_line
			(start 3.24993 -81.000092)
			(end 3.24993 81.000092)
			(stroke
				(width 0.1)
				(type default)
			)
			(layer "F.Fab")
		)
		(fp_line
			(start -3.24993 81.000092)
			(end -3.24993 -81.000092)
			(stroke
				(width 0.1)
				(type default)
			)
			(layer "F.Fab")
		)
		(fp_line
			(start -3.24993 72.499982)
			(end 3.24993 72.499982)
			(stroke
				(width 0.1)
				(type default)
			)
			(layer "F.Fab")
		)
		(fp_line
			(start -3.24993 71.000112)
			(end 3.24993 71.000112)
			(stroke
				(width 0.1)
				(type default)
			)
			(layer "F.Fab")
		)
		(fp_line
			(start -3.24993 -71.000112)
			(end 3.24993 -71.000112)
			(stroke
				(width 0.1)
				(type default)
			)
			(layer "F.Fab")
		)
		(fp_line
			(start -3.24993 -72.499982)
			(end 3.24993 -72.499982)
			(stroke
				(width 0.1)
				(type default)
			)
			(layer "F.Fab")
		)
		(fp_line
			(start -3.24993 -81.000092)
			(end 3.24993 -81.000092)
			(stroke
				(width 0.1)
				(type default)
			)
			(layer "F.Fab")
		)
		(fp_poly
			(pts
				(xy -3.41503 -63.324994) (xy -4.43103 -62.816994) (xy -4.43103 -63.832994)
			)
			(stroke
				(width 0)
				(type default)
			)
			(fill yes)
			(layer "F.Fab")
		)
		(pad "1" smd rect
			(at -2.050034 -63.324994 90)
			(size 0.519938 1.4986)
			(layers "F.Cu" "F.Mask" "F.Paste")
			(net "P12V_MEM_CPU1")
		)
		(pad "2" smd rect
			(at -2.050034 -62.47511 90)
			(size 0.519938 1.4986)
			(layers "F.Cu" "F.Mask" "F.Paste")
			(net "Net_2382")
		)
		(pad "3" smd rect
			(at -2.050034 -61.624972 90)
			(size 0.519938 1.4986)
			(layers "F.Cu" "F.Mask" "F.Paste")
			(net "P3V3_AUX")
		)
		(pad "4" smd rect
			(at -2.050034 -60.775088 90)
			(size 0.519938 1.4986)
			(layers "F.Cu" "F.Mask" "F.Paste")
			(net "I3C_SPD_DDRJ_CPU1_SCL")
		)
		(pad "5" smd rect
			(at -2.050034 -59.92495 90)
			(size 0.519938 1.4986)
			(layers "F.Cu" "F.Mask" "F.Paste")
			(net "I3C_SPD_DDRJ_CPU1_SDA")
		)
		(pad "6" smd rect
			(at -2.050034 -59.075066 90)
			(size 0.519938 1.4986)
			(layers "F.Cu" "F.Mask" "F.Paste")
			(net "GND")
		)
		(pad "7" smd rect
			(at -2.050034 -58.224928 90)
			(size 0.519938 1.4986)
			(layers "F.Cu" "F.Mask" "F.Paste")
			(net "M_J_CPU1_SA_DQ<0>")
		)
		(pad "8" smd rect
			(at -2.050034 -57.375044 90)
			(size 0.519938 1.4986)
			(layers "F.Cu" "F.Mask" "F.Paste")
			(net "GND")
		)
		(pad "9" smd rect
			(at -2.050034 -56.524906 90)
			(size 0.519938 1.4986)
			(layers "F.Cu" "F.Mask" "F.Paste")
			(net "M_J_CPU1_SA_DQ<1>")
		)
		(pad "10" smd rect
			(at -2.050034 -55.675022 90)
			(size 0.519938 1.4986)
			(layers "F.Cu" "F.Mask" "F.Paste")
			(net "GND")
		)
		(pad "11" smd rect
			(at -2.050034 -54.824884 90)
			(size 0.519938 1.4986)
			(layers "F.Cu" "F.Mask" "F.Paste")
			(net "M_J_CPU1_SA_DQS_DP<0>")
		)
		(pad "12" smd rect
			(at -2.050034 -53.975 90)
			(size 0.519938 1.4986)
			(layers "F.Cu" "F.Mask" "F.Paste")
			(net "M_J_CPU1_SA_DQS_DN<0>")
		)
		(pad "13" smd rect
			(at -2.050034 -53.125116 90)
			(size 0.519938 1.4986)
			(layers "F.Cu" "F.Mask" "F.Paste")
			(net "GND")
		)
		(pad "14" smd rect
			(at -2.050034 -52.274978 90)
			(size 0.519938 1.4986)
			(layers "F.Cu" "F.Mask" "F.Paste")
			(net "M_J_CPU1_SA_DQ<4>")
		)
		(pad "15" smd rect
			(at -2.050034 -51.425094 90)
			(size 0.519938 1.4986)
			(layers "F.Cu" "F.Mask" "F.Paste")
			(net "GND")
		)
		(pad "16" smd rect
			(at -2.050034 -50.574956 90)
			(size 0.519938 1.4986)
			(layers "F.Cu" "F.Mask" "F.Paste")
			(net "M_J_CPU1_SA_DQ<5>")
		)
		(pad "17" smd rect
			(at -2.050034 -49.725072 90)
			(size 0.519938 1.4986)
			(layers "F.Cu" "F.Mask" "F.Paste")
			(net "GND")
		)
		(pad "18" smd rect
			(at -2.050034 -48.874934 90)
			(size 0.519938 1.4986)
			(layers "F.Cu" "F.Mask" "F.Paste")
			(net "M_J_CPU1_SA_DQ<8>")
		)
		(pad "19" smd rect
			(at -2.050034 -48.02505 90)
			(size 0.519938 1.4986)
			(layers "F.Cu" "F.Mask" "F.Paste")
			(net "GND")
		)
		(pad "20" smd rect
			(at -2.050034 -47.174912 90)
			(size 0.519938 1.4986)
			(layers "F.Cu" "F.Mask" "F.Paste")
			(net "M_J_CPU1_SA_DQ<9>")
		)
		(pad "21" smd rect
			(at -2.050034 -46.325028 90)
			(size 0.519938 1.4986)
			(layers "F.Cu" "F.Mask" "F.Paste")
			(net "GND")
		)
		(pad "22" smd rect
			(at -2.050034 -45.47489 90)
			(size 0.519938 1.4986)
			(layers "F.Cu" "F.Mask" "F.Paste")
			(net "M_J_CPU1_SA_DQS_DP<1>")
		)
		(pad "23" smd rect
			(at -2.050034 -44.625006 90)
			(size 0.519938 1.4986)
			(layers "F.Cu" "F.Mask" "F.Paste")
			(net "M_J_CPU1_SA_DQS_DN<1>")
		)
		(pad "24" smd rect
			(at -2.050034 -43.775122 90)
			(size 0.519938 1.4986)
			(layers "F.Cu" "F.Mask" "F.Paste")
			(net "GND")
		)
		(pad "25" smd rect
			(at -2.050034 -42.924984 90)
			(size 0.519938 1.4986)
			(layers "F.Cu" "F.Mask" "F.Paste")
			(net "M_J_CPU1_SA_DQ<12>")
		)
		(pad "26" smd rect
			(at -2.050034 -42.0751 90)
			(size 0.519938 1.4986)
			(layers "F.Cu" "F.Mask" "F.Paste")
			(net "GND")
		)
		(pad "27" smd rect
			(at -2.050034 -41.224962 90)
			(size 0.519938 1.4986)
			(layers "F.Cu" "F.Mask" "F.Paste")
			(net "M_J_CPU1_SA_DQ<13>")
		)
		(pad "28" smd rect
			(at -2.050034 -40.375078 90)
			(size 0.519938 1.4986)
			(layers "F.Cu" "F.Mask" "F.Paste")
			(net "GND")
		)
		(pad "29" smd rect
			(at -2.050034 -39.52494 90)
			(size 0.519938 1.4986)
			(layers "F.Cu" "F.Mask" "F.Paste")
			(net "M_J_CPU1_SA_DQ<16>")
		)
		(pad "30" smd rect
			(at -2.050034 -38.675056 90)
			(size 0.519938 1.4986)
			(layers "F.Cu" "F.Mask" "F.Paste")
			(net "GND")
		)
		(pad "31" smd rect
			(at -2.050034 -37.824918 90)
			(size 0.519938 1.4986)
			(layers "F.Cu" "F.Mask" "F.Paste")
			(net "M_J_CPU1_SA_DQ<17>")
		)
		(pad "32" smd rect
			(at -2.050034 -36.975034 90)
			(size 0.519938 1.4986)
			(layers "F.Cu" "F.Mask" "F.Paste")
			(net "GND")
		)
		(pad "33" smd rect
			(at -2.050034 -36.124896 90)
			(size 0.519938 1.4986)
			(layers "F.Cu" "F.Mask" "F.Paste")
			(net "M_J_CPU1_SA_DQS_DP<2>")
		)
		(pad "34" smd rect
			(at -2.050034 -35.275012 90)
			(size 0.519938 1.4986)
			(layers "F.Cu" "F.Mask" "F.Paste")
			(net "M_J_CPU1_SA_DQS_DN<2>")
		)
		(pad "35" smd rect
			(at -2.050034 -34.425128 90)
			(size 0.519938 1.4986)
			(layers "F.Cu" "F.Mask" "F.Paste")
			(net "GND")
		)
		(pad "36" smd rect
			(at -2.050034 -33.57499 90)
			(size 0.519938 1.4986)
			(layers "F.Cu" "F.Mask" "F.Paste")
			(net "M_J_CPU1_SA_DQ<20>")
		)
		(pad "37" smd rect
			(at -2.050034 -32.725106 90)
			(size 0.519938 1.4986)
			(layers "F.Cu" "F.Mask" "F.Paste")
			(net "GND")
		)
		(pad "38" smd rect
			(at -2.050034 -31.874968 90)
			(size 0.519938 1.4986)
			(layers "F.Cu" "F.Mask" "F.Paste")
			(net "M_J_CPU1_SA_DQ<21>")
		)
		(pad "39" smd rect
			(at -2.050034 -31.025084 90)
			(size 0.519938 1.4986)
			(layers "F.Cu" "F.Mask" "F.Paste")
			(net "GND")
		)
		(pad "40" smd rect
			(at -2.050034 -30.174946 90)
			(size 0.519938 1.4986)
			(layers "F.Cu" "F.Mask" "F.Paste")
			(net "M_J_CPU1_SA_DQ<24>")
		)
		(pad "41" smd rect
			(at -2.050034 -29.325062 90)
			(size 0.519938 1.4986)
			(layers "F.Cu" "F.Mask" "F.Paste")
			(net "GND")
		)
		(pad "42" smd rect
			(at -2.050034 -28.474924 90)
			(size 0.519938 1.4986)
			(layers "F.Cu" "F.Mask" "F.Paste")
			(net "M_J_CPU1_SA_DQ<25>")
		)
		(pad "43" smd rect
			(at -2.050034 -27.62504 90)
			(size 0.519938 1.4986)
			(layers "F.Cu" "F.Mask" "F.Paste")
			(net "GND")
		)
		(pad "44" smd rect
			(at -2.050034 -26.774902 90)
			(size 0.519938 1.4986)
			(layers "F.Cu" "F.Mask" "F.Paste")
			(net "M_J_CPU1_SA_DQS_DP<3>")
		)
		(pad "45" smd rect
			(at -2.050034 -25.925018 90)
			(size 0.519938 1.4986)
			(layers "F.Cu" "F.Mask" "F.Paste")
			(net "M_J_CPU1_SA_DQS_DN<3>")
		)
		(pad "46" smd rect
			(at -2.050034 -25.07488 90)
			(size 0.519938 1.4986)
			(layers "F.Cu" "F.Mask" "F.Paste")
			(net "GND")
		)
		(pad "47" smd rect
			(at -2.050034 -24.224996 90)
			(size 0.519938 1.4986)
			(layers "F.Cu" "F.Mask" "F.Paste")
			(net "M_J_CPU1_SA_DQ<28>")
		)
		(pad "48" smd rect
			(at -2.050034 -23.375112 90)
			(size 0.519938 1.4986)
			(layers "F.Cu" "F.Mask" "F.Paste")
			(net "GND")
		)
		(pad "49" smd rect
			(at -2.050034 -22.524974 90)
			(size 0.519938 1.4986)
			(layers "F.Cu" "F.Mask" "F.Paste")
			(net "M_J_CPU1_SA_DQ<29>")
		)
		(pad "50" smd rect
			(at -2.050034 -21.67509 90)
			(size 0.519938 1.4986)
			(layers "F.Cu" "F.Mask" "F.Paste")
			(net "GND")
		)
		(pad "51" smd rect
			(at -2.050034 -20.824952 90)
			(size 0.519938 1.4986)
			(layers "F.Cu" "F.Mask" "F.Paste")
			(net "M_J_CPU1_SA_CB<0>")
		)
		(pad "52" smd rect
			(at -2.050034 -19.975068 90)
			(size 0.519938 1.4986)
			(layers "F.Cu" "F.Mask" "F.Paste")
			(net "GND")
		)
		(pad "53" smd rect
			(at -2.050034 -19.12493 90)
			(size 0.519938 1.4986)
			(layers "F.Cu" "F.Mask" "F.Paste")
			(net "M_J_CPU1_SA_CB<1>")
		)
		(pad "54" smd rect
			(at -2.050034 -18.275046 90)
			(size 0.519938 1.4986)
			(layers "F.Cu" "F.Mask" "F.Paste")
			(net "GND")
		)
		(pad "55" smd rect
			(at -2.050034 -17.424908 90)
			(size 0.519938 1.4986)
			(layers "F.Cu" "F.Mask" "F.Paste")
			(net "M_J_CPU1_SA_DQS_DP<4>")
		)
		(pad "56" smd rect
			(at -2.050034 -16.575024 90)
			(size 0.519938 1.4986)
			(layers "F.Cu" "F.Mask" "F.Paste")
			(net "M_J_CPU1_SA_DQS_DN<4>")
		)
		(pad "57" smd rect
			(at -2.050034 -15.724886 90)
			(size 0.519938 1.4986)
			(layers "F.Cu" "F.Mask" "F.Paste")
			(net "GND")
		)
		(pad "58" smd rect
			(at -2.050034 -14.875002 90)
			(size 0.519938 1.4986)
			(layers "F.Cu" "F.Mask" "F.Paste")
			(net "M_J_CPU1_SA_CB<4>")
		)
		(pad "59" smd rect
			(at -2.050034 -14.025118 90)
			(size 0.519938 1.4986)
			(layers "F.Cu" "F.Mask" "F.Paste")
			(net "GND")
		)
		(pad "60" smd rect
			(at -2.050034 -13.17498 90)
			(size 0.519938 1.4986)
			(layers "F.Cu" "F.Mask" "F.Paste")
			(net "M_J_CPU1_SA_CB<5>")
		)
		(pad "61" smd rect
			(at -2.050034 -12.325096 90)
			(size 0.519938 1.4986)
			(layers "F.Cu" "F.Mask" "F.Paste")
			(net "GND")
		)
		(pad "62" smd rect
			(at -2.050034 -11.474958 90)
			(size 0.519938 1.4986)
			(layers "F.Cu" "F.Mask" "F.Paste")
			(net "M_J_CPU1_ALERT_N")
		)
		(pad "63" smd rect
			(at -2.050034 -10.625074 90)
			(size 0.519938 1.4986)
			(layers "F.Cu" "F.Mask" "F.Paste")
			(net "GND")
		)
		(pad "64" smd rect
			(at -2.050034 -9.774936 90)
			(size 0.519938 1.4986)
			(layers "F.Cu" "F.Mask" "F.Paste")
			(net "M_J_CPU1_SA_CS_N<0>")
		)
		(pad "65" smd rect
			(at -2.050034 -8.925052 90)
			(size 0.519938 1.4986)
			(layers "F.Cu" "F.Mask" "F.Paste")
			(net "GND")
		)
		(pad "66" smd rect
			(at -2.050034 -8.074914 90)
			(size 0.519938 1.4986)
			(layers "F.Cu" "F.Mask" "F.Paste")
			(net "M_J_CPU1_SA_CA<0>")
		)
		(pad "67" smd rect
			(at -2.050034 -7.22503 90)
			(size 0.519938 1.4986)
			(layers "F.Cu" "F.Mask" "F.Paste")
			(net "GND")
		)
		(pad "68" smd rect
			(at -2.050034 -6.374892 90)
			(size 0.519938 1.4986)
			(layers "F.Cu" "F.Mask" "F.Paste")
			(net "M_J_CPU1_SA_CA<2>")
		)
		(pad "69" smd rect
			(at -2.050034 -5.525008 90)
			(size 0.519938 1.4986)
			(layers "F.Cu" "F.Mask" "F.Paste")
			(net "GND")
		)
		(pad "70" smd rect
			(at -2.050034 -4.675124 90)
			(size 0.519938 1.4986)
			(layers "F.Cu" "F.Mask" "F.Paste")
			(net "M_J_CPU1_SA_CA<4>")
		)
		(pad "71" smd rect
			(at -2.050034 -3.824986 90)
			(size 0.519938 1.4986)
			(layers "F.Cu" "F.Mask" "F.Paste")
			(net "GND")
		)
		(pad "72" smd rect
			(at -2.050034 -2.975102 90)
			(size 0.519938 1.4986)
			(layers "F.Cu" "F.Mask" "F.Paste")
			(net "M_J_CPU1_SA_CA<6>")
		)
		(pad "73" smd rect
			(at -2.050034 -2.124964 90)
			(size 0.519938 1.4986)
			(layers "F.Cu" "F.Mask" "F.Paste")
			(net "GND")
		)
		(pad "74" smd rect
			(at -2.050034 -1.27508 90)
			(size 0.519938 1.4986)
			(layers "F.Cu" "F.Mask" "F.Paste")
			(net "M_J_CPU1_SA_PAR")
		)
		(pad "75" smd rect
			(at -2.050034 -0.424942 90)
			(size 0.519938 1.4986)
			(layers "F.Cu" "F.Mask" "F.Paste")
			(net "GND")
		)
		(pad "76" smd rect
			(at -2.050034 5.525008 90)
			(size 0.519938 1.4986)
			(layers "F.Cu" "F.Mask" "F.Paste")
			(net "M_J_CPU1_SB_CA<0>")
		)
		(pad "77" smd rect
			(at -2.050034 6.374892 90)
			(size 0.519938 1.4986)
			(layers "F.Cu" "F.Mask" "F.Paste")
			(net "GND")
		)
		(pad "78" smd rect
			(at -2.050034 7.22503 90)
			(size 0.519938 1.4986)
			(layers "F.Cu" "F.Mask" "F.Paste")
			(net "M_J_CPU1_SB_CA<2>")
		)
		(pad "79" smd rect
			(at -2.050034 8.074914 90)
			(size 0.519938 1.4986)
			(layers "F.Cu" "F.Mask" "F.Paste")
			(net "GND")
		)
		(pad "80" smd rect
			(at -2.050034 8.925052 90)
			(size 0.519938 1.4986)
			(layers "F.Cu" "F.Mask" "F.Paste")
			(net "M_J_CPU1_SB_CA<4>")
		)
		(pad "81" smd rect
			(at -2.050034 9.774936 90)
			(size 0.519938 1.4986)
			(layers "F.Cu" "F.Mask" "F.Paste")
			(net "GND")
		)
		(pad "82" smd rect
			(at -2.050034 10.625074 90)
			(size 0.519938 1.4986)
			(layers "F.Cu" "F.Mask" "F.Paste")
			(net "M_J_CPU1_SB_CA<6>")
		)
		(pad "83" smd rect
			(at -2.050034 11.474958 90)
			(size 0.519938 1.4986)
			(layers "F.Cu" "F.Mask" "F.Paste")
			(net "GND")
		)
		(pad "84" smd rect
			(at -2.050034 12.325096 90)
			(size 0.519938 1.4986)
			(layers "F.Cu" "F.Mask" "F.Paste")
			(net "M_J_CPU1_SB_CS_N<0>")
		)
		(pad "85" smd rect
			(at -2.050034 13.17498 90)
			(size 0.519938 1.4986)
			(layers "F.Cu" "F.Mask" "F.Paste")
			(net "GND")
		)
		(pad "86" smd rect
			(at -2.050034 14.025118 90)
			(size 0.519938 1.4986)
			(layers "F.Cu" "F.Mask" "F.Paste")
			(net "M_J_CPU1_SA_RSP<0>")
		)
		(pad "87" smd rect
			(at -2.050034 14.875002 90)
			(size 0.519938 1.4986)
			(layers "F.Cu" "F.Mask" "F.Paste")
			(net "M_J_CPU1_SB_RSP<0>")
		)
		(pad "88" smd rect
			(at -2.050034 15.724886 90)
			(size 0.519938 1.4986)
			(layers "F.Cu" "F.Mask" "F.Paste")
			(net "GND")
		)
		(pad "89" smd rect
			(at -2.050034 16.575024 90)
			(size 0.519938 1.4986)
			(layers "F.Cu" "F.Mask" "F.Paste")
			(net "M_J_CPU1_SB_CB<4>")
		)
		(pad "90" smd rect
			(at -2.050034 17.424908 90)
			(size 0.519938 1.4986)
			(layers "F.Cu" "F.Mask" "F.Paste")
			(net "GND")
		)
		(pad "91" smd rect
			(at -2.050034 18.275046 90)
			(size 0.519938 1.4986)
			(layers "F.Cu" "F.Mask" "F.Paste")
			(net "M_J_CPU1_SB_CB<5>")
		)
		(pad "92" smd rect
			(at -2.050034 19.12493 90)
			(size 0.519938 1.4986)
			(layers "F.Cu" "F.Mask" "F.Paste")
			(net "GND")
		)
		(pad "93" smd rect
			(at -2.050034 19.975068 90)
			(size 0.519938 1.4986)
			(layers "F.Cu" "F.Mask" "F.Paste")
			(net "M_J_CPU1_SB_DQS_DP<9>")
		)
		(pad "94" smd rect
			(at -2.050034 20.824952 90)
			(size 0.519938 1.4986)
			(layers "F.Cu" "F.Mask" "F.Paste")
			(net "M_J_CPU1_SB_DQS_DN<9>")
		)
		(pad "95" smd rect
			(at -2.050034 21.67509 90)
			(size 0.519938 1.4986)
			(layers "F.Cu" "F.Mask" "F.Paste")
			(net "GND")
		)
		(pad "96" smd rect
			(at -2.050034 22.524974 90)
			(size 0.519938 1.4986)
			(layers "F.Cu" "F.Mask" "F.Paste")
			(net "M_J_CPU1_SB_CB<0>")
		)
		(pad "97" smd rect
			(at -2.050034 23.375112 90)
			(size 0.519938 1.4986)
			(layers "F.Cu" "F.Mask" "F.Paste")
			(net "GND")
		)
		(pad "98" smd rect
			(at -2.050034 24.224996 90)
			(size 0.519938 1.4986)
			(layers "F.Cu" "F.Mask" "F.Paste")
			(net "M_J_CPU1_SB_CB<1>")
		)
		(pad "99" smd rect
			(at -2.050034 25.07488 90)
			(size 0.519938 1.4986)
			(layers "F.Cu" "F.Mask" "F.Paste")
			(net "GND")
		)
		(pad "100" smd rect
			(at -2.050034 25.925018 90)
			(size 0.519938 1.4986)
			(layers "F.Cu" "F.Mask" "F.Paste")
			(net "M_J_CPU1_SB_DQ<0>")
		)
		(pad "101" smd rect
			(at -2.050034 26.774902 90)
			(size 0.519938 1.4986)
			(layers "F.Cu" "F.Mask" "F.Paste")
			(net "GND")
		)
		(pad "102" smd rect
			(at -2.050034 27.62504 90)
			(size 0.519938 1.4986)
			(layers "F.Cu" "F.Mask" "F.Paste")
			(net "M_J_CPU1_SB_DQ<1>")
		)
		(pad "103" smd rect
			(at -2.050034 28.474924 90)
			(size 0.519938 1.4986)
			(layers "F.Cu" "F.Mask" "F.Paste")
			(net "GND")
		)
		(pad "104" smd rect
			(at -2.050034 29.325062 90)
			(size 0.519938 1.4986)
			(layers "F.Cu" "F.Mask" "F.Paste")
			(net "M_J_CPU1_SB_DQS_DP<0>")
		)
		(pad "105" smd rect
			(at -2.050034 30.174946 90)
			(size 0.519938 1.4986)
			(layers "F.Cu" "F.Mask" "F.Paste")
			(net "M_J_CPU1_SB_DQS_DN<0>")
		)
		(pad "106" smd rect
			(at -2.050034 31.025084 90)
			(size 0.519938 1.4986)
			(layers "F.Cu" "F.Mask" "F.Paste")
			(net "GND")
		)
		(pad "107" smd rect
			(at -2.050034 31.874968 90)
			(size 0.519938 1.4986)
			(layers "F.Cu" "F.Mask" "F.Paste")
			(net "M_J_CPU1_SB_DQ<4>")
		)
		(pad "108" smd rect
			(at -2.050034 32.725106 90)
			(size 0.519938 1.4986)
			(layers "F.Cu" "F.Mask" "F.Paste")
			(net "GND")
		)
		(pad "109" smd rect
			(at -2.050034 33.57499 90)
			(size 0.519938 1.4986)
			(layers "F.Cu" "F.Mask" "F.Paste")
			(net "M_J_CPU1_SB_DQ<5>")
		)
		(pad "110" smd rect
			(at -2.050034 34.425128 90)
			(size 0.519938 1.4986)
			(layers "F.Cu" "F.Mask" "F.Paste")
			(net "GND")
		)
		(pad "111" smd rect
			(at -2.050034 35.275012 90)
			(size 0.519938 1.4986)
			(layers "F.Cu" "F.Mask" "F.Paste")
			(net "M_J_CPU1_SB_DQ<8>")
		)
		(pad "112" smd rect
			(at -2.050034 36.124896 90)
			(size 0.519938 1.4986)
			(layers "F.Cu" "F.Mask" "F.Paste")
			(net "GND")
		)
		(pad "113" smd rect
			(at -2.050034 36.975034 90)
			(size 0.519938 1.4986)
			(layers "F.Cu" "F.Mask" "F.Paste")
			(net "M_J_CPU1_SB_DQ<9>")
		)
		(pad "114" smd rect
			(at -2.050034 37.824918 90)
			(size 0.519938 1.4986)
			(layers "F.Cu" "F.Mask" "F.Paste")
			(net "GND")
		)
		(pad "115" smd rect
			(at -2.050034 38.675056 90)
			(size 0.519938 1.4986)
			(layers "F.Cu" "F.Mask" "F.Paste")
			(net "M_J_CPU1_SB_DQS_DP<1>")
		)
		(pad "116" smd rect
			(at -2.050034 39.52494 90)
			(size 0.519938 1.4986)
			(layers "F.Cu" "F.Mask" "F.Paste")
			(net "M_J_CPU1_SB_DQS_DN<1>")
		)
		(pad "117" smd rect
			(at -2.050034 40.375078 90)
			(size 0.519938 1.4986)
			(layers "F.Cu" "F.Mask" "F.Paste")
			(net "GND")
		)
		(pad "118" smd rect
			(at -2.050034 41.224962 90)
			(size 0.519938 1.4986)
			(layers "F.Cu" "F.Mask" "F.Paste")
			(net "M_J_CPU1_SB_DQ<12>")
		)
		(pad "119" smd rect
			(at -2.050034 42.0751 90)
			(size 0.519938 1.4986)
			(layers "F.Cu" "F.Mask" "F.Paste")
			(net "GND")
		)
		(pad "120" smd rect
			(at -2.050034 42.924984 90)
			(size 0.519938 1.4986)
			(layers "F.Cu" "F.Mask" "F.Paste")
			(net "M_J_CPU1_SB_DQ<13>")
		)
		(pad "121" smd rect
			(at -2.050034 43.775122 90)
			(size 0.519938 1.4986)
			(layers "F.Cu" "F.Mask" "F.Paste")
			(net "GND")
		)
		(pad "122" smd rect
			(at -2.050034 44.625006 90)
			(size 0.519938 1.4986)
			(layers "F.Cu" "F.Mask" "F.Paste")
			(net "M_J_CPU1_SB_DQ<16>")
		)
		(pad "123" smd rect
			(at -2.050034 45.47489 90)
			(size 0.519938 1.4986)
			(layers "F.Cu" "F.Mask" "F.Paste")
			(net "GND")
		)
		(pad "124" smd rect
			(at -2.050034 46.325028 90)
			(size 0.519938 1.4986)
			(layers "F.Cu" "F.Mask" "F.Paste")
			(net "M_J_CPU1_SB_DQ<17>")
		)
		(pad "125" smd rect
			(at -2.050034 47.174912 90)
			(size 0.519938 1.4986)
			(layers "F.Cu" "F.Mask" "F.Paste")
			(net "GND")
		)
		(pad "126" smd rect
			(at -2.050034 48.02505 90)
			(size 0.519938 1.4986)
			(layers "F.Cu" "F.Mask" "F.Paste")
			(net "M_J_CPU1_SB_DQS_DP<2>")
		)
		(pad "127" smd rect
			(at -2.050034 48.874934 90)
			(size 0.519938 1.4986)
			(layers "F.Cu" "F.Mask" "F.Paste")
			(net "M_J_CPU1_SB_DQS_DN<2>")
		)
		(pad "128" smd rect
			(at -2.050034 49.725072 90)
			(size 0.519938 1.4986)
			(layers "F.Cu" "F.Mask" "F.Paste")
			(net "GND")
		)
		(pad "129" smd rect
			(at -2.050034 50.574956 90)
			(size 0.519938 1.4986)
			(layers "F.Cu" "F.Mask" "F.Paste")
			(net "M_J_CPU1_SB_DQ<20>")
		)
		(pad "130" smd rect
			(at -2.050034 51.425094 90)
			(size 0.519938 1.4986)
			(layers "F.Cu" "F.Mask" "F.Paste")
			(net "GND")
		)
		(pad "131" smd rect
			(at -2.050034 52.274978 90)
			(size 0.519938 1.4986)
			(layers "F.Cu" "F.Mask" "F.Paste")
			(net "M_J_CPU1_SB_DQ<21>")
		)
		(pad "132" smd rect
			(at -2.050034 53.125116 90)
			(size 0.519938 1.4986)
			(layers "F.Cu" "F.Mask" "F.Paste")
			(net "GND")
		)
		(pad "133" smd rect
			(at -2.050034 53.975 90)
			(size 0.519938 1.4986)
			(layers "F.Cu" "F.Mask" "F.Paste")
			(net "M_J_CPU1_SB_DQ<24>")
		)
		(pad "134" smd rect
			(at -2.050034 54.824884 90)
			(size 0.519938 1.4986)
			(layers "F.Cu" "F.Mask" "F.Paste")
			(net "GND")
		)
		(pad "135" smd rect
			(at -2.050034 55.675022 90)
			(size 0.519938 1.4986)
			(layers "F.Cu" "F.Mask" "F.Paste")
			(net "M_J_CPU1_SB_DQ<25>")
		)
		(pad "136" smd rect
			(at -2.050034 56.524906 90)
			(size 0.519938 1.4986)
			(layers "F.Cu" "F.Mask" "F.Paste")
			(net "GND")
		)
		(pad "137" smd rect
			(at -2.050034 57.375044 90)
			(size 0.519938 1.4986)
			(layers "F.Cu" "F.Mask" "F.Paste")
			(net "M_J_CPU1_SB_DQS_DP<3>")
		)
		(pad "138" smd rect
			(at -2.050034 58.224928 90)
			(size 0.519938 1.4986)
			(layers "F.Cu" "F.Mask" "F.Paste")
			(net "M_J_CPU1_SB_DQS_DN<3>")
		)
		(pad "139" smd rect
			(at -2.050034 59.075066 90)
			(size 0.519938 1.4986)
			(layers "F.Cu" "F.Mask" "F.Paste")
			(net "GND")
		)
		(pad "140" smd rect
			(at -2.050034 59.92495 90)
			(size 0.519938 1.4986)
			(layers "F.Cu" "F.Mask" "F.Paste")
			(net "M_J_CPU1_SB_DQ<28>")
		)
		(pad "141" smd rect
			(at -2.050034 60.775088 90)
			(size 0.519938 1.4986)
			(layers "F.Cu" "F.Mask" "F.Paste")
			(net "GND")
		)
		(pad "142" smd rect
			(at -2.050034 61.624972 90)
			(size 0.519938 1.4986)
			(layers "F.Cu" "F.Mask" "F.Paste")
			(net "M_J_CPU1_SB_DQ<29>")
		)
		(pad "143" smd rect
			(at -2.050034 62.47511 90)
			(size 0.519938 1.4986)
			(layers "F.Cu" "F.Mask" "F.Paste")
			(net "GND")
		)
		(pad "144" smd rect
			(at -2.050034 63.324994 90)
			(size 0.519938 1.4986)
			(layers "F.Cu" "F.Mask" "F.Paste")
			(net "Net_2383")
		)
		(pad "145" smd rect
			(at 2.050034 -63.324994 90)
			(size 0.519938 1.4986)
			(layers "F.Cu" "F.Mask" "F.Paste")
			(net "P12V_MEM_CPU1")
		)
		(pad "146" smd rect
			(at 2.050034 -62.47511 90)
			(size 0.519938 1.4986)
			(layers "F.Cu" "F.Mask" "F.Paste")
			(net "P12V_MEM_CPU1")
		)
		(pad "147" smd rect
			(at 2.050034 -61.624972 90)
			(size 0.519938 1.4986)
			(layers "F.Cu" "F.Mask" "F.Paste")
			(net "PWRGD_CHJ_CPU1_DIMM")
		)
		(pad "148" smd rect
			(at 2.050034 -60.775088 90)
			(size 0.519938 1.4986)
			(layers "F.Cu" "F.Mask" "F.Paste")
			(net "PD_CHJ_CPU1_DIMM_SAA")
		)
		(pad "149" smd rect
			(at 2.050034 -59.92495 90)
			(size 0.519938 1.4986)
			(layers "F.Cu" "F.Mask" "F.Paste")
			(net "Net_2384")
		)
		(pad "150" smd rect
			(at 2.050034 -59.075066 90)
			(size 0.519938 1.4986)
			(layers "F.Cu" "F.Mask" "F.Paste")
			(net "Net_2385")
		)
		(pad "151" smd rect
			(at 2.050034 -58.224928 90)
			(size 0.519938 1.4986)
			(layers "F.Cu" "F.Mask" "F.Paste")
			(net "GND")
		)
		(pad "152" smd rect
			(at 2.050034 -57.375044 90)
			(size 0.519938 1.4986)
			(layers "F.Cu" "F.Mask" "F.Paste")
			(net "M_J_CPU1_SA_DQ<2>")
		)
		(pad "153" smd rect
			(at 2.050034 -56.524906 90)
			(size 0.519938 1.4986)
			(layers "F.Cu" "F.Mask" "F.Paste")
			(net "GND")
		)
		(pad "154" smd rect
			(at 2.050034 -55.675022 90)
			(size 0.519938 1.4986)
			(layers "F.Cu" "F.Mask" "F.Paste")
			(net "M_J_CPU1_SA_DQ<3>")
		)
		(pad "155" smd rect
			(at 2.050034 -54.824884 90)
			(size 0.519938 1.4986)
			(layers "F.Cu" "F.Mask" "F.Paste")
			(net "GND")
		)
		(pad "156" smd rect
			(at 2.050034 -53.975 90)
			(size 0.519938 1.4986)
			(layers "F.Cu" "F.Mask" "F.Paste")
			(net "M_J_CPU1_SA_DQS_DN<5>")
		)
		(pad "157" smd rect
			(at 2.050034 -53.125116 90)
			(size 0.519938 1.4986)
			(layers "F.Cu" "F.Mask" "F.Paste")
			(net "M_J_CPU1_SA_DQS_DP<5>")
		)
		(pad "158" smd rect
			(at 2.050034 -52.274978 90)
			(size 0.519938 1.4986)
			(layers "F.Cu" "F.Mask" "F.Paste")
			(net "GND")
		)
		(pad "159" smd rect
			(at 2.050034 -51.425094 90)
			(size 0.519938 1.4986)
			(layers "F.Cu" "F.Mask" "F.Paste")
			(net "M_J_CPU1_SA_DQ<6>")
		)
		(pad "160" smd rect
			(at 2.050034 -50.574956 90)
			(size 0.519938 1.4986)
			(layers "F.Cu" "F.Mask" "F.Paste")
			(net "GND")
		)
		(pad "161" smd rect
			(at 2.050034 -49.725072 90)
			(size 0.519938 1.4986)
			(layers "F.Cu" "F.Mask" "F.Paste")
			(net "M_J_CPU1_SA_DQ<7>")
		)
		(pad "162" smd rect
			(at 2.050034 -48.874934 90)
			(size 0.519938 1.4986)
			(layers "F.Cu" "F.Mask" "F.Paste")
			(net "GND")
		)
		(pad "163" smd rect
			(at 2.050034 -48.02505 90)
			(size 0.519938 1.4986)
			(layers "F.Cu" "F.Mask" "F.Paste")
			(net "M_J_CPU1_SA_DQ<10>")
		)
		(pad "164" smd rect
			(at 2.050034 -47.174912 90)
			(size 0.519938 1.4986)
			(layers "F.Cu" "F.Mask" "F.Paste")
			(net "GND")
		)
		(pad "165" smd rect
			(at 2.050034 -46.325028 90)
			(size 0.519938 1.4986)
			(layers "F.Cu" "F.Mask" "F.Paste")
			(net "M_J_CPU1_SA_DQ<11>")
		)
		(pad "166" smd rect
			(at 2.050034 -45.47489 90)
			(size 0.519938 1.4986)
			(layers "F.Cu" "F.Mask" "F.Paste")
			(net "GND")
		)
		(pad "167" smd rect
			(at 2.050034 -44.625006 90)
			(size 0.519938 1.4986)
			(layers "F.Cu" "F.Mask" "F.Paste")
			(net "M_J_CPU1_SA_DQS_DN<6>")
		)
		(pad "168" smd rect
			(at 2.050034 -43.775122 90)
			(size 0.519938 1.4986)
			(layers "F.Cu" "F.Mask" "F.Paste")
			(net "M_J_CPU1_SA_DQS_DP<6>")
		)
		(pad "169" smd rect
			(at 2.050034 -42.924984 90)
			(size 0.519938 1.4986)
			(layers "F.Cu" "F.Mask" "F.Paste")
			(net "GND")
		)
		(pad "170" smd rect
			(at 2.050034 -42.0751 90)
			(size 0.519938 1.4986)
			(layers "F.Cu" "F.Mask" "F.Paste")
			(net "M_J_CPU1_SA_DQ<14>")
		)
		(pad "171" smd rect
			(at 2.050034 -41.224962 90)
			(size 0.519938 1.4986)
			(layers "F.Cu" "F.Mask" "F.Paste")
			(net "GND")
		)
		(pad "172" smd rect
			(at 2.050034 -40.375078 90)
			(size 0.519938 1.4986)
			(layers "F.Cu" "F.Mask" "F.Paste")
			(net "M_J_CPU1_SA_DQ<15>")
		)
		(pad "173" smd rect
			(at 2.050034 -39.52494 90)
			(size 0.519938 1.4986)
			(layers "F.Cu" "F.Mask" "F.Paste")
			(net "GND")
		)
		(pad "174" smd rect
			(at 2.050034 -38.675056 90)
			(size 0.519938 1.4986)
			(layers "F.Cu" "F.Mask" "F.Paste")
			(net "M_J_CPU1_SA_DQ<18>")
		)
		(pad "175" smd rect
			(at 2.050034 -37.824918 90)
			(size 0.519938 1.4986)
			(layers "F.Cu" "F.Mask" "F.Paste")
			(net "GND")
		)
		(pad "176" smd rect
			(at 2.050034 -36.975034 90)
			(size 0.519938 1.4986)
			(layers "F.Cu" "F.Mask" "F.Paste")
			(net "M_J_CPU1_SA_DQ<19>")
		)
		(pad "177" smd rect
			(at 2.050034 -36.124896 90)
			(size 0.519938 1.4986)
			(layers "F.Cu" "F.Mask" "F.Paste")
			(net "GND")
		)
		(pad "178" smd rect
			(at 2.050034 -35.275012 90)
			(size 0.519938 1.4986)
			(layers "F.Cu" "F.Mask" "F.Paste")
			(net "M_J_CPU1_SA_DQS_DN<7>")
		)
		(pad "179" smd rect
			(at 2.050034 -34.425128 90)
			(size 0.519938 1.4986)
			(layers "F.Cu" "F.Mask" "F.Paste")
			(net "M_J_CPU1_SA_DQS_DP<7>")
		)
		(pad "180" smd rect
			(at 2.050034 -33.57499 90)
			(size 0.519938 1.4986)
			(layers "F.Cu" "F.Mask" "F.Paste")
			(net "GND")
		)
		(pad "181" smd rect
			(at 2.050034 -32.725106 90)
			(size 0.519938 1.4986)
			(layers "F.Cu" "F.Mask" "F.Paste")
			(net "M_J_CPU1_SA_DQ<22>")
		)
		(pad "182" smd rect
			(at 2.050034 -31.874968 90)
			(size 0.519938 1.4986)
			(layers "F.Cu" "F.Mask" "F.Paste")
			(net "GND")
		)
		(pad "183" smd rect
			(at 2.050034 -31.025084 90)
			(size 0.519938 1.4986)
			(layers "F.Cu" "F.Mask" "F.Paste")
			(net "M_J_CPU1_SA_DQ<23>")
		)
		(pad "184" smd rect
			(at 2.050034 -30.174946 90)
			(size 0.519938 1.4986)
			(layers "F.Cu" "F.Mask" "F.Paste")
			(net "GND")
		)
		(pad "185" smd rect
			(at 2.050034 -29.325062 90)
			(size 0.519938 1.4986)
			(layers "F.Cu" "F.Mask" "F.Paste")
			(net "M_J_CPU1_SA_DQ<26>")
		)
		(pad "186" smd rect
			(at 2.050034 -28.474924 90)
			(size 0.519938 1.4986)
			(layers "F.Cu" "F.Mask" "F.Paste")
			(net "GND")
		)
		(pad "187" smd rect
			(at 2.050034 -27.62504 90)
			(size 0.519938 1.4986)
			(layers "F.Cu" "F.Mask" "F.Paste")
			(net "M_J_CPU1_SA_DQ<27>")
		)
		(pad "188" smd rect
			(at 2.050034 -26.774902 90)
			(size 0.519938 1.4986)
			(layers "F.Cu" "F.Mask" "F.Paste")
			(net "GND")
		)
		(pad "189" smd rect
			(at 2.050034 -25.925018 90)
			(size 0.519938 1.4986)
			(layers "F.Cu" "F.Mask" "F.Paste")
			(net "M_J_CPU1_SA_DQS_DN<8>")
		)
		(pad "190" smd rect
			(at 2.050034 -25.07488 90)
			(size 0.519938 1.4986)
			(layers "F.Cu" "F.Mask" "F.Paste")
			(net "M_J_CPU1_SA_DQS_DP<8>")
		)
		(pad "191" smd rect
			(at 2.050034 -24.224996 90)
			(size 0.519938 1.4986)
			(layers "F.Cu" "F.Mask" "F.Paste")
			(net "GND")
		)
		(pad "192" smd rect
			(at 2.050034 -23.375112 90)
			(size 0.519938 1.4986)
			(layers "F.Cu" "F.Mask" "F.Paste")
			(net "M_J_CPU1_SA_DQ<30>")
		)
		(pad "193" smd rect
			(at 2.050034 -22.524974 90)
			(size 0.519938 1.4986)
			(layers "F.Cu" "F.Mask" "F.Paste")
			(net "GND")
		)
		(pad "194" smd rect
			(at 2.050034 -21.67509 90)
			(size 0.519938 1.4986)
			(layers "F.Cu" "F.Mask" "F.Paste")
			(net "M_J_CPU1_SA_DQ<31>")
		)
		(pad "195" smd rect
			(at 2.050034 -20.824952 90)
			(size 0.519938 1.4986)
			(layers "F.Cu" "F.Mask" "F.Paste")
			(net "GND")
		)
		(pad "196" smd rect
			(at 2.050034 -19.975068 90)
			(size 0.519938 1.4986)
			(layers "F.Cu" "F.Mask" "F.Paste")
			(net "M_J_CPU1_SA_CB<2>")
		)
		(pad "197" smd rect
			(at 2.050034 -19.12493 90)
			(size 0.519938 1.4986)
			(layers "F.Cu" "F.Mask" "F.Paste")
			(net "GND")
		)
		(pad "198" smd rect
			(at 2.050034 -18.275046 90)
			(size 0.519938 1.4986)
			(layers "F.Cu" "F.Mask" "F.Paste")
			(net "M_J_CPU1_SA_CB<3>")
		)
		(pad "199" smd rect
			(at 2.050034 -17.424908 90)
			(size 0.519938 1.4986)
			(layers "F.Cu" "F.Mask" "F.Paste")
			(net "GND")
		)
		(pad "200" smd rect
			(at 2.050034 -16.575024 90)
			(size 0.519938 1.4986)
			(layers "F.Cu" "F.Mask" "F.Paste")
			(net "M_J_CPU1_SA_DQS_DN<9>")
		)
		(pad "201" smd rect
			(at 2.050034 -15.724886 90)
			(size 0.519938 1.4986)
			(layers "F.Cu" "F.Mask" "F.Paste")
			(net "M_J_CPU1_SA_DQS_DP<9>")
		)
		(pad "202" smd rect
			(at 2.050034 -14.875002 90)
			(size 0.519938 1.4986)
			(layers "F.Cu" "F.Mask" "F.Paste")
			(net "GND")
		)
		(pad "203" smd rect
			(at 2.050034 -14.025118 90)
			(size 0.519938 1.4986)
			(layers "F.Cu" "F.Mask" "F.Paste")
			(net "M_J_CPU1_SA_CB<6>")
		)
		(pad "204" smd rect
			(at 2.050034 -13.17498 90)
			(size 0.519938 1.4986)
			(layers "F.Cu" "F.Mask" "F.Paste")
			(net "GND")
		)
		(pad "205" smd rect
			(at 2.050034 -12.325096 90)
			(size 0.519938 1.4986)
			(layers "F.Cu" "F.Mask" "F.Paste")
			(net "M_J_CPU1_SA_CB<7>")
		)
		(pad "206" smd rect
			(at 2.050034 -11.474958 90)
			(size 0.519938 1.4986)
			(layers "F.Cu" "F.Mask" "F.Paste")
			(net "GND")
		)
		(pad "207" smd rect
			(at 2.050034 -10.625074 90)
			(size 0.519938 1.4986)
			(layers "F.Cu" "F.Mask" "F.Paste")
			(net "M_J_CPU1_RESET_N")
		)
		(pad "208" smd rect
			(at 2.050034 -9.774936 90)
			(size 0.519938 1.4986)
			(layers "F.Cu" "F.Mask" "F.Paste")
			(net "GND")
		)
		(pad "209" smd rect
			(at 2.050034 -8.925052 90)
			(size 0.519938 1.4986)
			(layers "F.Cu" "F.Mask" "F.Paste")
			(net "M_J_CPU1_SA_CS_N<1>")
		)
		(pad "210" smd rect
			(at 2.050034 -8.074914 90)
			(size 0.519938 1.4986)
			(layers "F.Cu" "F.Mask" "F.Paste")
			(net "GND")
		)
		(pad "211" smd rect
			(at 2.050034 -7.22503 90)
			(size 0.519938 1.4986)
			(layers "F.Cu" "F.Mask" "F.Paste")
			(net "M_J_CPU1_SA_CA<1>")
		)
		(pad "212" smd rect
			(at 2.050034 -6.374892 90)
			(size 0.519938 1.4986)
			(layers "F.Cu" "F.Mask" "F.Paste")
			(net "GND")
		)
		(pad "213" smd rect
			(at 2.050034 -5.525008 90)
			(size 0.519938 1.4986)
			(layers "F.Cu" "F.Mask" "F.Paste")
			(net "M_J_CPU1_SA_CA<3>")
		)
		(pad "214" smd rect
			(at 2.050034 -4.675124 90)
			(size 0.519938 1.4986)
			(layers "F.Cu" "F.Mask" "F.Paste")
			(net "GND")
		)
		(pad "215" smd rect
			(at 2.050034 -3.824986 90)
			(size 0.519938 1.4986)
			(layers "F.Cu" "F.Mask" "F.Paste")
			(net "M_J_CPU1_SA_CA<5>")
		)
		(pad "216" smd rect
			(at 2.050034 -2.975102 90)
			(size 0.519938 1.4986)
			(layers "F.Cu" "F.Mask" "F.Paste")
			(net "GND")
		)
		(pad "217" smd rect
			(at 2.050034 -2.124964 90)
			(size 0.519938 1.4986)
			(layers "F.Cu" "F.Mask" "F.Paste")
			(net "M_J_CPU1_CLK_DP<0>")
		)
		(pad "218" smd rect
			(at 2.050034 -1.27508 90)
			(size 0.519938 1.4986)
			(layers "F.Cu" "F.Mask" "F.Paste")
			(net "M_J_CPU1_CLK_DN<0>")
		)
		(pad "219" smd rect
			(at 2.050034 -0.424942 90)
			(size 0.519938 1.4986)
			(layers "F.Cu" "F.Mask" "F.Paste")
			(net "GND")
		)
		(pad "220" smd rect
			(at 2.050034 5.525008 90)
			(size 0.519938 1.4986)
			(layers "F.Cu" "F.Mask" "F.Paste")
			(net "Net_2386")
		)
		(pad "221" smd rect
			(at 2.050034 6.374892 90)
			(size 0.519938 1.4986)
			(layers "F.Cu" "F.Mask" "F.Paste")
			(net "M_J_CPU1_SB_CA<1>")
		)
		(pad "222" smd rect
			(at 2.050034 7.22503 90)
			(size 0.519938 1.4986)
			(layers "F.Cu" "F.Mask" "F.Paste")
			(net "GND")
		)
		(pad "223" smd rect
			(at 2.050034 8.074914 90)
			(size 0.519938 1.4986)
			(layers "F.Cu" "F.Mask" "F.Paste")
			(net "M_J_CPU1_SB_CA<3>")
		)
		(pad "224" smd rect
			(at 2.050034 8.925052 90)
			(size 0.519938 1.4986)
			(layers "F.Cu" "F.Mask" "F.Paste")
			(net "GND")
		)
		(pad "225" smd rect
			(at 2.050034 9.774936 90)
			(size 0.519938 1.4986)
			(layers "F.Cu" "F.Mask" "F.Paste")
			(net "M_J_CPU1_SB_CA<5>")
		)
		(pad "226" smd rect
			(at 2.050034 10.625074 90)
			(size 0.519938 1.4986)
			(layers "F.Cu" "F.Mask" "F.Paste")
			(net "GND")
		)
		(pad "227" smd rect
			(at 2.050034 11.474958 90)
			(size 0.519938 1.4986)
			(layers "F.Cu" "F.Mask" "F.Paste")
			(net "M_J_CPU1_SB_PAR")
		)
		(pad "228" smd rect
			(at 2.050034 12.325096 90)
			(size 0.519938 1.4986)
			(layers "F.Cu" "F.Mask" "F.Paste")
			(net "GND")
		)
		(pad "229" smd rect
			(at 2.050034 13.17498 90)
			(size 0.519938 1.4986)
			(layers "F.Cu" "F.Mask" "F.Paste")
			(net "M_J_CPU1_SB_CS_N<1>")
		)
		(pad "230" smd rect
			(at 2.050034 14.025118 90)
			(size 0.519938 1.4986)
			(layers "F.Cu" "F.Mask" "F.Paste")
			(net "GND")
		)
		(pad "231" smd rect
			(at 2.050034 14.875002 90)
			(size 0.519938 1.4986)
			(layers "F.Cu" "F.Mask" "F.Paste")
			(net "Net_2387")
		)
		(pad "232" smd rect
			(at 2.050034 15.724886 90)
			(size 0.519938 1.4986)
			(layers "F.Cu" "F.Mask" "F.Paste")
			(net "Net_2388")
		)
		(pad "233" smd rect
			(at 2.050034 16.575024 90)
			(size 0.519938 1.4986)
			(layers "F.Cu" "F.Mask" "F.Paste")
			(net "GND")
		)
		(pad "234" smd rect
			(at 2.050034 17.424908 90)
			(size 0.519938 1.4986)
			(layers "F.Cu" "F.Mask" "F.Paste")
			(net "M_J_CPU1_SB_CB<6>")
		)
		(pad "235" smd rect
			(at 2.050034 18.275046 90)
			(size 0.519938 1.4986)
			(layers "F.Cu" "F.Mask" "F.Paste")
			(net "GND")
		)
		(pad "236" smd rect
			(at 2.050034 19.12493 90)
			(size 0.519938 1.4986)
			(layers "F.Cu" "F.Mask" "F.Paste")
			(net "M_J_CPU1_SB_CB<7>")
		)
		(pad "237" smd rect
			(at 2.050034 19.975068 90)
			(size 0.519938 1.4986)
			(layers "F.Cu" "F.Mask" "F.Paste")
			(net "GND")
		)
		(pad "238" smd rect
			(at 2.050034 20.824952 90)
			(size 0.519938 1.4986)
			(layers "F.Cu" "F.Mask" "F.Paste")
			(net "M_J_CPU1_SB_DQS_DN<4>")
		)
		(pad "239" smd rect
			(at 2.050034 21.67509 90)
			(size 0.519938 1.4986)
			(layers "F.Cu" "F.Mask" "F.Paste")
			(net "M_J_CPU1_SB_DQS_DP<4>")
		)
		(pad "240" smd rect
			(at 2.050034 22.524974 90)
			(size 0.519938 1.4986)
			(layers "F.Cu" "F.Mask" "F.Paste")
			(net "GND")
		)
		(pad "241" smd rect
			(at 2.050034 23.375112 90)
			(size 0.519938 1.4986)
			(layers "F.Cu" "F.Mask" "F.Paste")
			(net "M_J_CPU1_SB_CB<2>")
		)
		(pad "242" smd rect
			(at 2.050034 24.224996 90)
			(size 0.519938 1.4986)
			(layers "F.Cu" "F.Mask" "F.Paste")
			(net "GND")
		)
		(pad "243" smd rect
			(at 2.050034 25.07488 90)
			(size 0.519938 1.4986)
			(layers "F.Cu" "F.Mask" "F.Paste")
			(net "M_J_CPU1_SB_CB<3>")
		)
		(pad "244" smd rect
			(at 2.050034 25.925018 90)
			(size 0.519938 1.4986)
			(layers "F.Cu" "F.Mask" "F.Paste")
			(net "GND")
		)
		(pad "245" smd rect
			(at 2.050034 26.774902 90)
			(size 0.519938 1.4986)
			(layers "F.Cu" "F.Mask" "F.Paste")
			(net "M_J_CPU1_SB_DQ<2>")
		)
		(pad "246" smd rect
			(at 2.050034 27.62504 90)
			(size 0.519938 1.4986)
			(layers "F.Cu" "F.Mask" "F.Paste")
			(net "GND")
		)
		(pad "247" smd rect
			(at 2.050034 28.474924 90)
			(size 0.519938 1.4986)
			(layers "F.Cu" "F.Mask" "F.Paste")
			(net "M_J_CPU1_SB_DQ<3>")
		)
		(pad "248" smd rect
			(at 2.050034 29.325062 90)
			(size 0.519938 1.4986)
			(layers "F.Cu" "F.Mask" "F.Paste")
			(net "GND")
		)
		(pad "249" smd rect
			(at 2.050034 30.174946 90)
			(size 0.519938 1.4986)
			(layers "F.Cu" "F.Mask" "F.Paste")
			(net "M_J_CPU1_SB_DQS_DN<5>")
		)
		(pad "250" smd rect
			(at 2.050034 31.025084 90)
			(size 0.519938 1.4986)
			(layers "F.Cu" "F.Mask" "F.Paste")
			(net "M_J_CPU1_SB_DQS_DP<5>")
		)
		(pad "251" smd rect
			(at 2.050034 31.874968 90)
			(size 0.519938 1.4986)
			(layers "F.Cu" "F.Mask" "F.Paste")
			(net "GND")
		)
		(pad "252" smd rect
			(at 2.050034 32.725106 90)
			(size 0.519938 1.4986)
			(layers "F.Cu" "F.Mask" "F.Paste")
			(net "M_J_CPU1_SB_DQ<6>")
		)
		(pad "253" smd rect
			(at 2.050034 33.57499 90)
			(size 0.519938 1.4986)
			(layers "F.Cu" "F.Mask" "F.Paste")
			(net "GND")
		)
		(pad "254" smd rect
			(at 2.050034 34.425128 90)
			(size 0.519938 1.4986)
			(layers "F.Cu" "F.Mask" "F.Paste")
			(net "M_J_CPU1_SB_DQ<7>")
		)
		(pad "255" smd rect
			(at 2.050034 35.275012 90)
			(size 0.519938 1.4986)
			(layers "F.Cu" "F.Mask" "F.Paste")
			(net "GND")
		)
		(pad "256" smd rect
			(at 2.050034 36.124896 90)
			(size 0.519938 1.4986)
			(layers "F.Cu" "F.Mask" "F.Paste")
			(net "M_J_CPU1_SB_DQ<10>")
		)
		(pad "257" smd rect
			(at 2.050034 36.975034 90)
			(size 0.519938 1.4986)
			(layers "F.Cu" "F.Mask" "F.Paste")
			(net "GND")
		)
		(pad "258" smd rect
			(at 2.050034 37.824918 90)
			(size 0.519938 1.4986)
			(layers "F.Cu" "F.Mask" "F.Paste")
			(net "M_J_CPU1_SB_DQ<11>")
		)
		(pad "259" smd rect
			(at 2.050034 38.675056 90)
			(size 0.519938 1.4986)
			(layers "F.Cu" "F.Mask" "F.Paste")
			(net "GND")
		)
		(pad "260" smd rect
			(at 2.050034 39.52494 90)
			(size 0.519938 1.4986)
			(layers "F.Cu" "F.Mask" "F.Paste")
			(net "M_J_CPU1_SB_DQS_DN<6>")
		)
		(pad "261" smd rect
			(at 2.050034 40.375078 90)
			(size 0.519938 1.4986)
			(layers "F.Cu" "F.Mask" "F.Paste")
			(net "M_J_CPU1_SB_DQS_DP<6>")
		)
		(pad "262" smd rect
			(at 2.050034 41.224962 90)
			(size 0.519938 1.4986)
			(layers "F.Cu" "F.Mask" "F.Paste")
			(net "GND")
		)
		(pad "263" smd rect
			(at 2.050034 42.0751 90)
			(size 0.519938 1.4986)
			(layers "F.Cu" "F.Mask" "F.Paste")
			(net "M_J_CPU1_SB_DQ<14>")
		)
		(pad "264" smd rect
			(at 2.050034 42.924984 90)
			(size 0.519938 1.4986)
			(layers "F.Cu" "F.Mask" "F.Paste")
			(net "GND")
		)
		(pad "265" smd rect
			(at 2.050034 43.775122 90)
			(size 0.519938 1.4986)
			(layers "F.Cu" "F.Mask" "F.Paste")
			(net "M_J_CPU1_SB_DQ<15>")
		)
		(pad "266" smd rect
			(at 2.050034 44.625006 90)
			(size 0.519938 1.4986)
			(layers "F.Cu" "F.Mask" "F.Paste")
			(net "GND")
		)
		(pad "267" smd rect
			(at 2.050034 45.47489 90)
			(size 0.519938 1.4986)
			(layers "F.Cu" "F.Mask" "F.Paste")
			(net "M_J_CPU1_SB_DQ<18>")
		)
		(pad "268" smd rect
			(at 2.050034 46.325028 90)
			(size 0.519938 1.4986)
			(layers "F.Cu" "F.Mask" "F.Paste")
			(net "GND")
		)
		(pad "269" smd rect
			(at 2.050034 47.174912 90)
			(size 0.519938 1.4986)
			(layers "F.Cu" "F.Mask" "F.Paste")
			(net "M_J_CPU1_SB_DQ<19>")
		)
		(pad "270" smd rect
			(at 2.050034 48.02505 90)
			(size 0.519938 1.4986)
			(layers "F.Cu" "F.Mask" "F.Paste")
			(net "GND")
		)
		(pad "271" smd rect
			(at 2.050034 48.874934 90)
			(size 0.519938 1.4986)
			(layers "F.Cu" "F.Mask" "F.Paste")
			(net "M_J_CPU1_SB_DQS_DN<7>")
		)
		(pad "272" smd rect
			(at 2.050034 49.725072 90)
			(size 0.519938 1.4986)
			(layers "F.Cu" "F.Mask" "F.Paste")
			(net "M_J_CPU1_SB_DQS_DP<7>")
		)
		(pad "273" smd rect
			(at 2.050034 50.574956 90)
			(size 0.519938 1.4986)
			(layers "F.Cu" "F.Mask" "F.Paste")
			(net "GND")
		)
		(pad "274" smd rect
			(at 2.050034 51.425094 90)
			(size 0.519938 1.4986)
			(layers "F.Cu" "F.Mask" "F.Paste")
			(net "M_J_CPU1_SB_DQ<22>")
		)
		(pad "275" smd rect
			(at 2.050034 52.274978 90)
			(size 0.519938 1.4986)
			(layers "F.Cu" "F.Mask" "F.Paste")
			(net "GND")
		)
		(pad "276" smd rect
			(at 2.050034 53.125116 90)
			(size 0.519938 1.4986)
			(layers "F.Cu" "F.Mask" "F.Paste")
			(net "M_J_CPU1_SB_DQ<23>")
		)
		(pad "277" smd rect
			(at 2.050034 53.975 90)
			(size 0.519938 1.4986)
			(layers "F.Cu" "F.Mask" "F.Paste")
			(net "GND")
		)
		(pad "278" smd rect
			(at 2.050034 54.824884 90)
			(size 0.519938 1.4986)
			(layers "F.Cu" "F.Mask" "F.Paste")
			(net "M_J_CPU1_SB_DQ<26>")
		)
		(pad "279" smd rect
			(at 2.050034 55.675022 90)
			(size 0.519938 1.4986)
			(layers "F.Cu" "F.Mask" "F.Paste")
			(net "GND")
		)
		(pad "280" smd rect
			(at 2.050034 56.524906 90)
			(size 0.519938 1.4986)
			(layers "F.Cu" "F.Mask" "F.Paste")
			(net "M_J_CPU1_SB_DQ<27>")
		)
		(pad "281" smd rect
			(at 2.050034 57.375044 90)
			(size 0.519938 1.4986)
			(layers "F.Cu" "F.Mask" "F.Paste")
			(net "GND")
		)
		(pad "282" smd rect
			(at 2.050034 58.224928 90)
			(size 0.519938 1.4986)
			(layers "F.Cu" "F.Mask" "F.Paste")
			(net "M_J_CPU1_SB_DQS_DN<8>")
		)
		(pad "283" smd rect
			(at 2.050034 59.075066 90)
			(size 0.519938 1.4986)
			(layers "F.Cu" "F.Mask" "F.Paste")
			(net "M_J_CPU1_SB_DQS_DP<8>")
		)
		(pad "284" smd rect
			(at 2.050034 59.92495 90)
			(size 0.519938 1.4986)
			(layers "F.Cu" "F.Mask" "F.Paste")
			(net "GND")
		)
		(pad "285" smd rect
			(at 2.050034 60.775088 90)
			(size 0.519938 1.4986)
			(layers "F.Cu" "F.Mask" "F.Paste")
			(net "M_J_CPU1_SB_DQ<30>")
		)
		(pad "286" smd rect
			(at 2.050034 61.624972 90)
			(size 0.519938 1.4986)
			(layers "F.Cu" "F.Mask" "F.Paste")
			(net "GND")
		)
		(pad "287" smd rect
			(at 2.050034 62.47511 90)
			(size 0.519938 1.4986)
			(layers "F.Cu" "F.Mask" "F.Paste")
			(net "M_J_CPU1_SB_DQ<31>")
		)
		(pad "288" smd rect
			(at 2.050034 63.324994 90)
			(size 0.519938 1.4986)
			(layers "F.Cu" "F.Mask" "F.Paste")
			(net "GND")
		)
		(pad "G1" thru_hole oval
			(at 0 -68.97497 90)
			(size 1.7272 3.4798)
			(drill oval 1.2192 2.4638)
			(layers "*.Cu" "*.Mask")
			(remove_unused_layers no)
			(net "GND")
			(clearance 0.127)
			(thermal_gap 0.127)
		)
		(pad "G2" thru_hole oval
			(at 0 3.875024 90)
			(size 1.7272 3.4798)
			(drill oval 1.2192 2.4638)
			(layers "*.Cu" "*.Mask")
			(remove_unused_layers no)
			(net "GND")
			(clearance 0.127)
			(thermal_gap 0.127)
		)
		(pad "G3" thru_hole oval
			(at 0 68.97497 90)
			(size 1.7272 3.4798)
			(drill oval 1.2192 2.4638)
			(layers "*.Cu" "*.Mask")
			(remove_unused_layers no)
			(net "GND")
			(clearance 0.127)
			(thermal_gap 0.127)
		)
	)
	(footprint ""
		(layer "F.Cu")
		(at 21.512784 -392.396726 180)
		(property "Reference" "PR6631"
			(at 0 0 180)
			(layer "F.SilkS")
			(hide yes)
			(effects
				(font
					(size 1.27 1.27)
				)
			)
		)
		(property "Value" ""
			(at 0 0 180)
			(layer "F.Fab")
			(effects
				(font
					(size 1.27 1.27)
				)
			)
		)
		(duplicate_pad_numbers_are_jumpers no)
		(fp_line
			(start 0.7874 0.4064)
			(end -0.7874 0.4064)
			(stroke
				(width 0.1524)
				(type default)
			)
			(layer "F.SilkS")
		)
		(fp_line
			(start 0.7874 -0.4064)
			(end 0.7874 0.4064)
			(stroke
				(width 0.1524)
				(type default)
			)
			(layer "F.SilkS")
		)
		(fp_line
			(start -0.356616 -0.4064)
			(end 0.7874 -0.4064)
			(stroke
				(width 0.1524)
				(type default)
			)
			(layer "F.SilkS")
		)
		(fp_line
			(start -0.7874 0.4064)
			(end -0.7874 0.033274)
			(stroke
				(width 0.1524)
				(type default)
			)
			(layer "F.SilkS")
		)
		(fp_line
			(start 0.67945 0.3048)
			(end 0.120396 0.3048)
			(stroke
				(width 0.1)
				(type default)
			)
			(layer "F.Fab")
		)
		(fp_line
			(start 0.67945 -0.3048)
			(end 0.67945 0.3048)
			(stroke
				(width 0.1)
				(type default)
			)
			(layer "F.Fab")
		)
		(fp_line
			(start 0.12065 -0.2794)
			(end 0.12065 -0.3048)
			(stroke
				(width 0.1)
				(type default)
			)
			(layer "F.Fab")
		)
		(fp_line
			(start 0.12065 -0.3048)
			(end 0.67945 -0.3048)
			(stroke
				(width 0.1)
				(type default)
			)
			(layer "F.Fab")
		)
		(fp_line
			(start 0.120396 0.3048)
			(end 0.120396 0.2794)
			(stroke
				(width 0.1)
				(type default)
			)
			(layer "F.Fab")
		)
		(fp_line
			(start 0.120396 0.2794)
			(end -0.12065 0.2794)
			(stroke
				(width 0.1)
				(type default)
			)
			(layer "F.Fab")
		)
		(fp_line
			(start -0.12065 0.3048)
			(end -0.67945 0.3048)
			(stroke
				(width 0.1)
				(type default)
			)
			(layer "F.Fab")
		)
		(fp_line
			(start -0.12065 0.2794)
			(end -0.12065 0.3048)
			(stroke
				(width 0.1)
				(type default)
			)
			(layer "F.Fab")
		)
		(fp_line
			(start -0.12065 -0.2794)
			(end 0.12065 -0.2794)
			(stroke
				(width 0.1)
				(type default)
			)
			(layer "F.Fab")
		)
		(fp_line
			(start -0.12065 -0.305054)
			(end -0.12065 -0.2794)
			(stroke
				(width 0.1)
				(type default)
			)
			(layer "F.Fab")
		)
		(fp_line
			(start -0.67945 0.3048)
			(end -0.67945 -0.305054)
			(stroke
				(width 0.1)
				(type default)
			)
			(layer "F.Fab")
		)
		(fp_line
			(start -0.67945 -0.305054)
			(end -0.12065 -0.305054)
			(stroke
				(width 0.1)
				(type default)
			)
			(layer "F.Fab")
		)
		(pad "1" smd circle
			(at -0.40005 0 180)
			(size 0 0)
			(layers "F.Cu" "F.Mask" "F.Paste")
			(net "P0V9_RETIMER_CPU1_VOS2")
		)
		(pad "2" smd circle
			(at 0.40005 0 180)
			(size 0 0)
			(layers "F.Cu" "F.Mask" "F.Paste")
			(net "P0V9_CPU1_RT_2D")
		)
	)
	(footprint ""
		(layer "F.Cu")
		(at 123.127262 -52.534058)
		(property "Reference" "R617"
			(at 0 0 0)
			(layer "F.SilkS")
			(hide yes)
			(effects
				(font
					(size 1.27 1.27)
				)
			)
		)
		(property "Value" ""
			(at 0 0 0)
			(layer "F.Fab")
			(effects
				(font
					(size 1.27 1.27)
				)
			)
		)
		(duplicate_pad_numbers_are_jumpers no)
		(fp_line
			(start -0.7874 -0.4064)
			(end -0.623062 -0.4064)
			(stroke
				(width 0.1524)
				(type default)
			)
			(layer "F.SilkS")
		)
		(fp_line
			(start -0.7874 0.4064)
			(end -0.7874 -0.4064)
			(stroke
				(width 0.1524)
				(type default)
			)
			(layer "F.SilkS")
		)
		(fp_line
			(start 0.189738 -0.4064)
			(end 0.7874 -0.4064)
			(stroke
				(width 0.1524)
				(type default)
			)
			(layer "F.SilkS")
		)
		(fp_line
			(start 0.7874 -0.4064)
			(end 0.7874 0.4064)
			(stroke
				(width 0.1524)
				(type default)
			)
			(layer "F.SilkS")
		)
		(fp_line
			(start 0.7874 0.4064)
			(end -0.7874 0.4064)
			(stroke
				(width 0.1524)
				(type default)
			)
			(layer "F.SilkS")
		)
		(fp_line
			(start -0.67945 -0.305054)
			(end -0.12065 -0.305054)
			(stroke
				(width 0.1)
				(type default)
			)
			(layer "F.Fab")
		)
		(fp_line
			(start -0.67945 0.3048)
			(end -0.67945 -0.305054)
			(stroke
				(width 0.1)
				(type default)
			)
			(layer "F.Fab")
		)
		(fp_line
			(start -0.12065 -0.305054)
			(end -0.12065 -0.2794)
			(stroke
				(width 0.1)
				(type default)
			)
			(layer "F.Fab")
		)
		(fp_line
			(start -0.12065 -0.2794)
			(end 0.12065 -0.2794)
			(stroke
				(width 0.1)
				(type default)
			)
			(layer "F.Fab")
		)
		(fp_line
			(start -0.12065 0.2794)
			(end -0.12065 0.3048)
			(stroke
				(width 0.1)
				(type default)
			)
			(layer "F.Fab")
		)
		(fp_line
			(start -0.12065 0.3048)
			(end -0.67945 0.3048)
			(stroke
				(width 0.1)
				(type default)
			)
			(layer "F.Fab")
		)
		(fp_line
			(start 0.120396 0.2794)
			(end -0.12065 0.2794)
			(stroke
				(width 0.1)
				(type default)
			)
			(layer "F.Fab")
		)
		(fp_line
			(start 0.120396 0.3048)
			(end 0.120396 0.2794)
			(stroke
				(width 0.1)
				(type default)
			)
			(layer "F.Fab")
		)
		(fp_line
			(start 0.12065 -0.3048)
			(end 0.67945 -0.3048)
			(stroke
				(width 0.1)
				(type default)
			)
			(layer "F.Fab")
		)
		(fp_line
			(start 0.12065 -0.2794)
			(end 0.12065 -0.3048)
			(stroke
				(width 0.1)
				(type default)
			)
			(layer "F.Fab")
		)
		(fp_line
			(start 0.67945 -0.3048)
			(end 0.67945 0.3048)
			(stroke
				(width 0.1)
				(type default)
			)
			(layer "F.Fab")
		)
		(fp_line
			(start 0.67945 0.3048)
			(end 0.120396 0.3048)
			(stroke
				(width 0.1)
				(type default)
			)
			(layer "F.Fab")
		)
		(pad "1" smd circle
			(at -0.40005 0)
			(size 0 0)
			(layers "F.Cu" "F.Mask" "F.Paste")
			(net "PVDD18_S5_P0")
		)
		(pad "2" smd circle
			(at 0.40005 0)
			(size 0 0)
			(layers "F.Cu" "F.Mask" "F.Paste")
			(net "JTAG_BMC_R_D_OE")
		)
	)
	(footprint ""
		(layer "F.Cu")
		(at 109.13999 -23.534878 -90)
		(property "Reference" "R6331"
			(at 0 0 270)
			(layer "F.SilkS")
			(hide yes)
			(effects
				(font
					(size 1.27 1.27)
				)
			)
		)
		(property "Value" ""
			(at 0 0 270)
			(layer "F.Fab")
			(effects
				(font
					(size 1.27 1.27)
				)
			)
		)
		(duplicate_pad_numbers_are_jumpers no)
		(fp_line
			(start -0.7874 0.4064)
			(end -0.7874 -0.4064)
			(stroke
				(width 0.1524)
				(type default)
			)
			(layer "F.SilkS")
		)
		(fp_line
			(start 0.7874 0.4064)
			(end -0.7874 0.4064)
			(stroke
				(width 0.1524)
				(type default)
			)
			(layer "F.SilkS")
		)
		(fp_line
			(start -0.7874 -0.4064)
			(end 0.7874 -0.4064)
			(stroke
				(width 0.1524)
				(type default)
			)
			(layer "F.SilkS")
		)
		(fp_line
			(start 0.7874 -0.4064)
			(end 0.7874 0.4064)
			(stroke
				(width 0.1524)
				(type default)
			)
			(layer "F.SilkS")
		)
		(fp_line
			(start -0.67945 0.3048)
			(end -0.67945 -0.305054)
			(stroke
				(width 0.1)
				(type default)
			)
			(layer "F.Fab")
		)
		(fp_line
			(start -0.12065 0.3048)
			(end -0.67945 0.3048)
			(stroke
				(width 0.1)
				(type default)
			)
			(layer "F.Fab")
		)
		(fp_line
			(start 0.120396 0.3048)
			(end 0.120396 0.2794)
			(stroke
				(width 0.1)
				(type default)
			)
			(layer "F.Fab")
		)
		(fp_line
			(start 0.67945 0.3048)
			(end 0.120396 0.3048)
			(stroke
				(width 0.1)
				(type default)
			)
			(layer "F.Fab")
		)
		(fp_line
			(start -0.12065 0.2794)
			(end -0.12065 0.3048)
			(stroke
				(width 0.1)
				(type default)
			)
			(layer "F.Fab")
		)
		(fp_line
			(start 0.120396 0.2794)
			(end -0.12065 0.2794)
			(stroke
				(width 0.1)
				(type default)
			)
			(layer "F.Fab")
		)
		(fp_line
			(start -0.12065 -0.2794)
			(end 0.12065 -0.2794)
			(stroke
				(width 0.1)
				(type default)
			)
			(layer "F.Fab")
		)
		(fp_line
			(start 0.12065 -0.2794)
			(end 0.12065 -0.3048)
			(stroke
				(width 0.1)
				(type default)
			)
			(layer "F.Fab")
		)
		(fp_line
			(start 0.12065 -0.3048)
			(end 0.67945 -0.3048)
			(stroke
				(width 0.1)
				(type default)
			)
			(layer "F.Fab")
		)
		(fp_line
			(start 0.67945 -0.3048)
			(end 0.67945 0.3048)
			(stroke
				(width 0.1)
				(type default)
			)
			(layer "F.Fab")
		)
		(fp_line
			(start -0.67945 -0.305054)
			(end -0.12065 -0.305054)
			(stroke
				(width 0.1)
				(type default)
			)
			(layer "F.Fab")
		)
		(fp_line
			(start -0.12065 -0.305054)
			(end -0.12065 -0.2794)
			(stroke
				(width 0.1)
				(type default)
			)
			(layer "F.Fab")
		)
		(pad "1" smd circle
			(at -0.40005 0 270)
			(size 0 0)
			(layers "F.Cu" "F.Mask" "F.Paste")
			(net "USB_HUB2_TI_USB_R1_MRP_RBIAS")
		)
		(pad "2" smd circle
			(at 0.40005 0 270)
			(size 0 0)
			(layers "F.Cu" "F.Mask" "F.Paste")
			(net "GND")
		)
	)
	(footprint ""
		(layer "F.Cu")
		(at 120.142 -418.338 -90)
		(property "Reference" "Q103"
			(at 4.610862 -0.59436 90)
			(unlocked yes)
			(layer "F.SilkS")
			(effects
				(font
					(size 0.7874 0.5842)
					(thickness 0.1524)
				)
				(justify left)
			)
		)
		(property "Value" ""
			(at 0 0 270)
			(layer "F.Fab")
			(effects
				(font
					(size 1.27 1.27)
				)
			)
		)
		(duplicate_pad_numbers_are_jumpers no)
		(fp_line
			(start -1.332738 1.100074)
			(end -1.332738 -1.100074)
			(stroke
				(width 0.1524)
				(type default)
			)
			(layer "F.SilkS")
		)
		(fp_line
			(start 1.332738 1.100074)
			(end -1.332738 1.100074)
			(stroke
				(width 0.1524)
				(type default)
			)
			(layer "F.SilkS")
		)
		(fp_line
			(start 0 -0.541274)
			(end 0.4826 -1.100074)
			(stroke
				(width 0.1524)
				(type default)
			)
			(layer "F.SilkS")
		)
		(fp_line
			(start -1.332738 -1.100074)
			(end -0.4826 -1.100074)
			(stroke
				(width 0.1524)
				(type default)
			)
			(layer "F.SilkS")
		)
		(fp_line
			(start -0.4826 -1.100074)
			(end 0 -0.541274)
			(stroke
				(width 0.1524)
				(type default)
			)
			(layer "F.SilkS")
		)
		(fp_line
			(start 0.4826 -1.100074)
			(end 1.332738 -1.100074)
			(stroke
				(width 0.1524)
				(type default)
			)
			(layer "F.SilkS")
		)
		(fp_line
			(start 1.332738 -1.100074)
			(end 1.332738 1.100074)
			(stroke
				(width 0.1524)
				(type default)
			)
			(layer "F.SilkS")
		)
		(fp_poly
			(pts
				(xy -1.696974 -1.588262) (xy -2.438908 -1.844548) (xy -1.937258 -2.33553)
			)
			(stroke
				(width 0)
				(type default)
			)
			(fill yes)
			(layer "F.SilkS")
		)
		(fp_line
			(start -0.674878 1.100074)
			(end -0.674878 -1.100074)
			(stroke
				(width 0.1)
				(type default)
			)
			(layer "F.Fab")
		)
		(fp_line
			(start 0.674878 1.100074)
			(end -0.674878 1.100074)
			(stroke
				(width 0.1)
				(type default)
			)
			(layer "F.Fab")
		)
		(fp_line
			(start -0.674878 -1.100074)
			(end 0.674878 -1.100074)
			(stroke
				(width 0.1)
				(type default)
			)
			(layer "F.Fab")
		)
		(fp_line
			(start 0.674878 -1.100074)
			(end 0.674878 1.100074)
			(stroke
				(width 0.1)
				(type default)
			)
			(layer "F.Fab")
		)
		(fp_poly
			(pts
				(xy -2.2352 -0.298958) (xy -2.2352 -1.001014) (xy -1.533144 -0.649986)
			)
			(stroke
				(width 0)
				(type default)
			)
			(fill yes)
			(layer "F.Fab")
		)
		(pad "1" smd rect
			(at -0.94996 -0.649986)
			(size 0.4318 0.508)
			(layers "F.Cu" "F.Mask" "F.Paste")
			(net "GND")
		)
		(pad "2" smd rect
			(at -0.94996 0)
			(size 0.4318 0.508)
			(layers "F.Cu" "F.Mask" "F.Paste")
			(net "GPU_HMC_PRSNT_N")
		)
		(pad "3" smd rect
			(at -0.94996 0.649986)
			(size 0.4318 0.508)
			(layers "F.Cu" "F.Mask" "F.Paste")
			(net "GPU_HMC_PRSNT_ISO_N")
		)
		(pad "4" smd rect
			(at 0.94996 0.649986)
			(size 0.4318 0.508)
			(layers "F.Cu" "F.Mask" "F.Paste")
			(net "GND")
		)
		(pad "5" smd rect
			(at 0.94996 0)
			(size 0.4318 0.508)
			(layers "F.Cu" "F.Mask" "F.Paste")
			(net "GPU_HMC_PRSNT")
		)
		(pad "6" smd rect
			(at 0.94996 -0.649986)
			(size 0.4318 0.508)
			(layers "F.Cu" "F.Mask" "F.Paste")
			(net "GPU_HMC_PRSNT")
		)
	)
	(footprint ""
		(layer "F.Cu")
		(at 314.965588 5.082794)
		(property "Reference" "J71"
			(at -4.421886 0.954786 90)
			(unlocked yes)
			(layer "F.SilkS")
			(effects
				(font
					(size 0.7874 0.5842)
					(thickness 0.1524)
				)
				(justify left)
			)
		)
		(property "Value" ""
			(at 0 0 0)
			(layer "F.Fab")
			(effects
				(font
					(size 1.27 1.27)
				)
			)
		)
		(duplicate_pad_numbers_are_jumpers no)
		(fp_line
			(start -1.2192 -2.06756)
			(end 1.2192 -2.06756)
			(stroke
				(width 0.1524)
				(type default)
			)
			(layer "F.SilkS")
		)
		(fp_line
			(start -1.2192 2.06756)
			(end -1.2192 -2.06756)
			(stroke
				(width 0.1524)
				(type default)
			)
			(layer "F.SilkS")
		)
		(fp_line
			(start 1.2192 -2.06756)
			(end 1.2192 2.06756)
			(stroke
				(width 0.1524)
				(type default)
			)
			(layer "F.SilkS")
		)
		(fp_line
			(start 1.2192 2.06756)
			(end -1.2192 2.06756)
			(stroke
				(width 0.1524)
				(type default)
			)
			(layer "F.SilkS")
		)
		(pad "" np_thru_hole circle
			(at -2.8829 -1.27 270)
			(size 1.0414 1.0414)
			(drill 1.0414)
			(layers "*.Cu" "*.Mask")
			(clearance 0.381)
			(thermal_gap 0.381)
		)
		(pad "" np_thru_hole circle
			(at -2.8829 1.27 270)
			(size 1.0414 1.0414)
			(drill 1.0414)
			(layers "*.Cu" "*.Mask")
			(clearance 0.381)
			(thermal_gap 0.381)
		)
		(pad "" np_thru_hole circle
			(at 3.4671 -1.27 270)
			(size 1.0414 1.0414)
			(drill 1.0414)
			(layers "*.Cu" "*.Mask")
			(clearance 0.381)
			(thermal_gap 0.381)
		)
		(pad "" np_thru_hole circle
			(at 3.4671 1.27 270)
			(size 1.0414 1.0414)
			(drill 1.0414)
			(layers "*.Cu" "*.Mask")
			(clearance 0.381)
			(thermal_gap 0.381)
		)
		(pad "1" smd rect
			(at 0.8255 -0.249936 270)
			(size 0.3048 0.508)
			(layers "F.Cu" "F.Mask" "F.Paste")
			(net "DELTA_L_85_5INCH_IN1_DN")
		)
		(pad "2" smd rect
			(at 0.8255 0.249936 270)
			(size 0.3048 0.508)
			(layers "F.Cu" "F.Mask" "F.Paste")
			(net "DELTA_L_85_5INCH_IN1_DP")
		)
		(pad "3" smd circle
			(at 0 0)
			(size 0 0)
			(layers "F.Cu" "F.Mask" "F.Paste")
			(net "DELTA_L_GND_1")
		)
		(zone
			(layer "F.Cu")
			(hatch none 0.5)
			(connect_pads
				(clearance 0)
			)
			(min_thickness 0.25)
			(keepout
				(tracks not_allowed)
				(vias allowed)
				(pads allowed)
				(copperpour not_allowed)
				(footprints allowed)
			)
			(placement
				(enabled no)
				(sheetname "")
			)
			(fill
				(thermal_gap 0.5)
				(thermal_bridge_width 0.5)
				(island_removal_mode 0)
			)
			(polygon
				(pts
					(xy 316.083188 4.534154) (xy 316.083188 4.629658) (xy 315.486288 4.629658) (xy 315.486288 5.036058)
					(xy 316.083188 5.036058) (xy 316.083188 5.12953) (xy 315.486288 5.12953) (xy 315.486288 5.53593)
					(xy 316.083188 5.53593) (xy 316.083188 5.631434) (xy 315.384688 5.631434) (xy 315.384688 4.534154)
				)
			)
		)
		(zone
			(layers "F.Cu" "B.Cu" "In1.Cu" "In2.Cu" "In3.Cu" "In4.Cu" "In5.Cu" "In6.Cu"
				"In7.Cu" "In8.Cu" "In9.Cu" "In10.Cu" "In11.Cu" "In12.Cu" "In13.Cu" "In14.Cu"
				"In15.Cu" "In16.Cu"
			)
			(hatch none 0.5)
			(connect_pads
				(clearance 0)
			)
			(min_thickness 0.25)
			(keepout
				(tracks not_allowed)
				(vias allowed)
				(pads allowed)
				(copperpour not_allowed)
				(footprints allowed)
			)
			(placement
				(enabled no)
				(sheetname "")
			)
			(fill
				(thermal_gap 0.5)
				(thermal_bridge_width 0.5)
				(island_removal_mode 0)
			)
			(polygon
				(pts
					(arc
						(start 313.009788 3.812794)
						(mid 311.155588 3.812794)
						(end 313.009788 3.812794)
					)
				)
			)
		)
		(zone
			(layers "F.Cu" "B.Cu" "In1.Cu" "In2.Cu" "In3.Cu" "In4.Cu" "In5.Cu" "In6.Cu"
				"In7.Cu" "In8.Cu" "In9.Cu" "In10.Cu" "In11.Cu" "In12.Cu" "In13.Cu" "In14.Cu"
				"In15.Cu" "In16.Cu"
			)
			(hatch none 0.5)
			(connect_pads
				(clearance 0)
			)
			(min_thickness 0.25)
			(keepout
				(tracks not_allowed)
				(vias allowed)
				(pads allowed)
				(copperpour not_allowed)
				(footprints allowed)
			)
			(placement
				(enabled no)
				(sheetname "")
			)
			(fill
				(thermal_gap 0.5)
				(thermal_bridge_width 0.5)
				(island_removal_mode 0)
			)
			(polygon
				(pts
					(arc
						(start 313.009788 6.352794)
						(mid 311.155588 6.352794)
						(end 313.009788 6.352794)
					)
				)
			)
		)
		(zone
			(layers "F.Cu" "B.Cu" "In1.Cu" "In2.Cu" "In3.Cu" "In4.Cu" "In5.Cu" "In6.Cu"
				"In7.Cu" "In8.Cu" "In9.Cu" "In10.Cu" "In11.Cu" "In12.Cu" "In13.Cu" "In14.Cu"
				"In15.Cu" "In16.Cu"
			)
			(hatch none 0.5)
			(connect_pads
				(clearance 0)
			)
			(min_thickness 0.25)
			(keepout
				(tracks not_allowed)
				(vias allowed)
				(pads allowed)
				(copperpour not_allowed)
				(footprints allowed)
			)
			(placement
				(enabled no)
				(sheetname "")
			)
			(fill
				(thermal_gap 0.5)
				(thermal_bridge_width 0.5)
				(island_removal_mode 0)
			)
			(polygon
				(pts
					(arc
						(start 319.359788 3.812794)
						(mid 317.505588 3.812794)
						(end 319.359788 3.812794)
					)
				)
			)
		)
		(zone
			(layers "F.Cu" "B.Cu" "In1.Cu" "In2.Cu" "In3.Cu" "In4.Cu" "In5.Cu" "In6.Cu"
				"In7.Cu" "In8.Cu" "In9.Cu" "In10.Cu" "In11.Cu" "In12.Cu" "In13.Cu" "In14.Cu"
				"In15.Cu" "In16.Cu"
			)
			(hatch none 0.5)
			(connect_pads
				(clearance 0)
			)
			(min_thickness 0.25)
			(keepout
				(tracks not_allowed)
				(vias allowed)
				(pads allowed)
				(copperpour not_allowed)
				(footprints allowed)
			)
			(placement
				(enabled no)
				(sheetname "")
			)
			(fill
				(thermal_gap 0.5)
				(thermal_bridge_width 0.5)
				(island_removal_mode 0)
			)
			(polygon
				(pts
					(arc
						(start 319.359788 6.352794)
						(mid 317.505588 6.352794)
						(end 319.359788 6.352794)
					)
				)
			)
		)
	)
	(footprint ""
		(layer "F.Cu")
		(at 376.352308 -184.478168 -90)
		(property "Reference" "PR496"
			(at 0 0 270)
			(layer "F.SilkS")
			(hide yes)
			(effects
				(font
					(size 1.27 1.27)
				)
			)
		)
		(property "Value" ""
			(at 0 0 270)
			(layer "F.Fab")
			(effects
				(font
					(size 1.27 1.27)
				)
			)
		)
		(duplicate_pad_numbers_are_jumpers no)
		(fp_line
			(start -0.7874 0.4064)
			(end -0.7874 -0.4064)
			(stroke
				(width 0.1524)
				(type default)
			)
			(layer "F.SilkS")
		)
		(fp_line
			(start 0.7874 0.4064)
			(end -0.7874 0.4064)
			(stroke
				(width 0.1524)
				(type default)
			)
			(layer "F.SilkS")
		)
		(fp_line
			(start -0.7874 -0.4064)
			(end 0.7874 -0.4064)
			(stroke
				(width 0.1524)
				(type default)
			)
			(layer "F.SilkS")
		)
		(fp_line
			(start 0.7874 -0.4064)
			(end 0.7874 0.4064)
			(stroke
				(width 0.1524)
				(type default)
			)
			(layer "F.SilkS")
		)
		(fp_line
			(start -0.67945 0.3048)
			(end -0.67945 -0.305054)
			(stroke
				(width 0.1)
				(type default)
			)
			(layer "F.Fab")
		)
		(fp_line
			(start -0.12065 0.3048)
			(end -0.67945 0.3048)
			(stroke
				(width 0.1)
				(type default)
			)
			(layer "F.Fab")
		)
		(fp_line
			(start 0.120396 0.3048)
			(end 0.120396 0.2794)
			(stroke
				(width 0.1)
				(type default)
			)
			(layer "F.Fab")
		)
		(fp_line
			(start 0.67945 0.3048)
			(end 0.120396 0.3048)
			(stroke
				(width 0.1)
				(type default)
			)
			(layer "F.Fab")
		)
		(fp_line
			(start -0.12065 0.2794)
			(end -0.12065 0.3048)
			(stroke
				(width 0.1)
				(type default)
			)
			(layer "F.Fab")
		)
		(fp_line
			(start 0.120396 0.2794)
			(end -0.12065 0.2794)
			(stroke
				(width 0.1)
				(type default)
			)
			(layer "F.Fab")
		)
		(fp_line
			(start -0.12065 -0.2794)
			(end 0.12065 -0.2794)
			(stroke
				(width 0.1)
				(type default)
			)
			(layer "F.Fab")
		)
		(fp_line
			(start 0.12065 -0.2794)
			(end 0.12065 -0.3048)
			(stroke
				(width 0.1)
				(type default)
			)
			(layer "F.Fab")
		)
		(fp_line
			(start 0.12065 -0.3048)
			(end 0.67945 -0.3048)
			(stroke
				(width 0.1)
				(type default)
			)
			(layer "F.Fab")
		)
		(fp_line
			(start 0.67945 -0.3048)
			(end 0.67945 0.3048)
			(stroke
				(width 0.1)
				(type default)
			)
			(layer "F.Fab")
		)
		(fp_line
			(start -0.67945 -0.305054)
			(end -0.12065 -0.305054)
			(stroke
				(width 0.1)
				(type default)
			)
			(layer "F.Fab")
		)
		(fp_line
			(start -0.12065 -0.305054)
			(end -0.12065 -0.2794)
			(stroke
				(width 0.1)
				(type default)
			)
			(layer "F.Fab")
		)
		(pad "1" smd circle
			(at -0.40005 0 270)
			(size 0 0)
			(layers "F.Cu" "F.Mask" "F.Paste")
			(net "SW_PVDDCR_CPU0_P0_SW2_RC")
		)
		(pad "2" smd circle
			(at 0.40005 0 270)
			(size 0 0)
			(layers "F.Cu" "F.Mask" "F.Paste")
			(net "GND")
		)
	)
	(footprint ""
		(layer "F.Cu")
		(at 142.595092 -376.85726 180)
		(property "Reference" "C770"
			(at 0 0 180)
			(layer "F.SilkS")
			(hide yes)
			(effects
				(font
					(size 1.27 1.27)
				)
			)
		)
		(property "Value" ""
			(at 0 0 180)
			(layer "F.Fab")
			(effects
				(font
					(size 1.27 1.27)
				)
			)
		)
		(duplicate_pad_numbers_are_jumpers no)
		(fp_line
			(start 0.299974 0.150114)
			(end -0.299974 0.150114)
			(stroke
				(width 0.1)
				(type default)
			)
			(layer "F.Fab")
		)
		(fp_line
			(start 0.299974 -0.150114)
			(end 0.299974 0.150114)
			(stroke
				(width 0.1)
				(type default)
			)
			(layer "F.Fab")
		)
		(fp_line
			(start -0.299974 0.150114)
			(end -0.299974 -0.150114)
			(stroke
				(width 0.1)
				(type default)
			)
			(layer "F.Fab")
		)
		(fp_line
			(start -0.299974 -0.150114)
			(end 0.299974 -0.150114)
			(stroke
				(width 0.1)
				(type default)
			)
			(layer "F.Fab")
		)
		(pad "1" smd rect
			(at -0.2667 0 180)
			(size 0.3048 0.381)
			(layers "F.Cu" "F.Mask" "F.Paste")
			(net "P5E_CPU1_P2_TX_C_DN<1>")
		)
		(pad "2" smd rect
			(at 0.2667 0 180)
			(size 0.3048 0.381)
			(layers "F.Cu" "F.Mask" "F.Paste")
			(net "P5E_CPU1_P2_TX_DN<1>")
		)
	)
	(footprint ""
		(layer "F.Cu")
		(at 444.598552 -25.477978)
		(property "Reference" "PC2160"
			(at 0 0 0)
			(layer "F.SilkS")
			(hide yes)
			(effects
				(font
					(size 1.27 1.27)
				)
			)
		)
		(property "Value" ""
			(at 0 0 0)
			(layer "F.Fab")
			(effects
				(font
					(size 1.27 1.27)
				)
			)
		)
		(duplicate_pad_numbers_are_jumpers no)
		(fp_line
			(start -0.7874 -0.4064)
			(end 0.7874 -0.4064)
			(stroke
				(width 0.1524)
				(type default)
			)
			(layer "F.SilkS")
		)
		(fp_line
			(start -0.7874 0.4064)
			(end -0.7874 -0.4064)
			(stroke
				(width 0.1524)
				(type default)
			)
			(layer "F.SilkS")
		)
		(fp_line
			(start 0.7874 -0.4064)
			(end 0.7874 0.4064)
			(stroke
				(width 0.1524)
				(type default)
			)
			(layer "F.SilkS")
		)
		(fp_line
			(start 0.7874 0.4064)
			(end -0.7874 0.4064)
			(stroke
				(width 0.1524)
				(type default)
			)
			(layer "F.SilkS")
		)
		(fp_line
			(start -0.67945 -0.305054)
			(end -0.12065 -0.305054)
			(stroke
				(width 0.1)
				(type default)
			)
			(layer "F.Fab")
		)
		(fp_line
			(start -0.67945 0.3048)
			(end -0.67945 -0.305054)
			(stroke
				(width 0.1)
				(type default)
			)
			(layer "F.Fab")
		)
		(fp_line
			(start -0.12065 -0.305054)
			(end -0.12065 -0.2794)
			(stroke
				(width 0.1)
				(type default)
			)
			(layer "F.Fab")
		)
		(fp_line
			(start -0.12065 -0.2794)
			(end 0.12065 -0.2794)
			(stroke
				(width 0.1)
				(type default)
			)
			(layer "F.Fab")
		)
		(fp_line
			(start -0.12065 0.2794)
			(end -0.12065 0.3048)
			(stroke
				(width 0.1)
				(type default)
			)
			(layer "F.Fab")
		)
		(fp_line
			(start -0.12065 0.3048)
			(end -0.67945 0.3048)
			(stroke
				(width 0.1)
				(type default)
			)
			(layer "F.Fab")
		)
		(fp_line
			(start 0.120396 0.2794)
			(end -0.12065 0.2794)
			(stroke
				(width 0.1)
				(type default)
			)
			(layer "F.Fab")
		)
		(fp_line
			(start 0.120396 0.3048)
			(end 0.120396 0.2794)
			(stroke
				(width 0.1)
				(type default)
			)
			(layer "F.Fab")
		)
		(fp_line
			(start 0.12065 -0.3048)
			(end 0.67945 -0.3048)
			(stroke
				(width 0.1)
				(type default)
			)
			(layer "F.Fab")
		)
		(fp_line
			(start 0.12065 -0.2794)
			(end 0.12065 -0.3048)
			(stroke
				(width 0.1)
				(type default)
			)
			(layer "F.Fab")
		)
		(fp_line
			(start 0.67945 -0.3048)
			(end 0.67945 0.3048)
			(stroke
				(width 0.1)
				(type default)
			)
			(layer "F.Fab")
		)
		(fp_line
			(start 0.67945 0.3048)
			(end 0.120396 0.3048)
			(stroke
				(width 0.1)
				(type default)
			)
			(layer "F.Fab")
		)
		(pad "1" smd circle
			(at -0.40005 0)
			(size 0 0)
			(layers "F.Cu" "F.Mask" "F.Paste")
			(net "P12V_OCP_SFF")
		)
		(pad "2" smd circle
			(at 0.40005 0)
			(size 0 0)
			(layers "F.Cu" "F.Mask" "F.Paste")
			(net "GND")
		)
	)
	(footprint ""
		(layer "F.Cu")
		(at 426.979588 -390.68629)
		(property "Reference" "R1060"
			(at 0 0 0)
			(layer "F.SilkS")
			(hide yes)
			(effects
				(font
					(size 1.27 1.27)
				)
			)
		)
		(property "Value" ""
			(at 0 0 0)
			(layer "F.Fab")
			(effects
				(font
					(size 1.27 1.27)
				)
			)
		)
		(duplicate_pad_numbers_are_jumpers no)
		(fp_line
			(start -0.32512 -0.175006)
			(end 0.32512 -0.175006)
			(stroke
				(width 0.1)
				(type default)
			)
			(layer "F.Fab")
		)
		(fp_line
			(start -0.32512 0.175006)
			(end -0.32512 -0.175006)
			(stroke
				(width 0.1)
				(type default)
			)
			(layer "F.Fab")
		)
		(fp_line
			(start 0.32512 -0.175006)
			(end 0.32512 0.175006)
			(stroke
				(width 0.1)
				(type default)
			)
			(layer "F.Fab")
		)
		(fp_line
			(start 0.32512 0.175006)
			(end -0.32512 0.175006)
			(stroke
				(width 0.1)
				(type default)
			)
			(layer "F.Fab")
		)
		(pad "1" smd rect
			(at -0.2667 0)
			(size 0.3048 0.381)
			(layers "F.Cu" "F.Mask" "F.Paste")
			(net "RT_CPU0_P2_ADDR1")
		)
		(pad "2" smd rect
			(at 0.2667 0 180)
			(size 0.3048 0.381)
			(layers "F.Cu" "F.Mask" "F.Paste")
			(net "GND")
		)
	)
	(footprint ""
		(layer "F.Cu")
		(at 458.244194 -46.264576 -90)
		(property "Reference" "PR832"
			(at 0 0 270)
			(layer "F.SilkS")
			(hide yes)
			(effects
				(font
					(size 1.27 1.27)
				)
			)
		)
		(property "Value" ""
			(at 0 0 270)
			(layer "F.Fab")
			(effects
				(font
					(size 1.27 1.27)
				)
			)
		)
		(duplicate_pad_numbers_are_jumpers no)
		(fp_line
			(start -0.7874 0.4064)
			(end -0.7874 -0.4064)
			(stroke
				(width 0.1524)
				(type default)
			)
			(layer "F.SilkS")
		)
		(fp_line
			(start 0.7874 0.4064)
			(end -0.7874 0.4064)
			(stroke
				(width 0.1524)
				(type default)
			)
			(layer "F.SilkS")
		)
		(fp_line
			(start -0.7874 -0.4064)
			(end 0.7874 -0.4064)
			(stroke
				(width 0.1524)
				(type default)
			)
			(layer "F.SilkS")
		)
		(fp_line
			(start 0.7874 -0.4064)
			(end 0.7874 0.4064)
			(stroke
				(width 0.1524)
				(type default)
			)
			(layer "F.SilkS")
		)
		(fp_line
			(start -0.67945 0.3048)
			(end -0.67945 -0.305054)
			(stroke
				(width 0.1)
				(type default)
			)
			(layer "F.Fab")
		)
		(fp_line
			(start -0.12065 0.3048)
			(end -0.67945 0.3048)
			(stroke
				(width 0.1)
				(type default)
			)
			(layer "F.Fab")
		)
		(fp_line
			(start 0.120396 0.3048)
			(end 0.120396 0.2794)
			(stroke
				(width 0.1)
				(type default)
			)
			(layer "F.Fab")
		)
		(fp_line
			(start 0.67945 0.3048)
			(end 0.120396 0.3048)
			(stroke
				(width 0.1)
				(type default)
			)
			(layer "F.Fab")
		)
		(fp_line
			(start -0.12065 0.2794)
			(end -0.12065 0.3048)
			(stroke
				(width 0.1)
				(type default)
			)
			(layer "F.Fab")
		)
		(fp_line
			(start 0.120396 0.2794)
			(end -0.12065 0.2794)
			(stroke
				(width 0.1)
				(type default)
			)
			(layer "F.Fab")
		)
		(fp_line
			(start -0.12065 -0.2794)
			(end 0.12065 -0.2794)
			(stroke
				(width 0.1)
				(type default)
			)
			(layer "F.Fab")
		)
		(fp_line
			(start 0.12065 -0.2794)
			(end 0.12065 -0.3048)
			(stroke
				(width 0.1)
				(type default)
			)
			(layer "F.Fab")
		)
		(fp_line
			(start 0.12065 -0.3048)
			(end 0.67945 -0.3048)
			(stroke
				(width 0.1)
				(type default)
			)
			(layer "F.Fab")
		)
		(fp_line
			(start 0.67945 -0.3048)
			(end 0.67945 0.3048)
			(stroke
				(width 0.1)
				(type default)
			)
			(layer "F.Fab")
		)
		(fp_line
			(start -0.67945 -0.305054)
			(end -0.12065 -0.305054)
			(stroke
				(width 0.1)
				(type default)
			)
			(layer "F.Fab")
		)
		(fp_line
			(start -0.12065 -0.305054)
			(end -0.12065 -0.2794)
			(stroke
				(width 0.1)
				(type default)
			)
			(layer "F.Fab")
		)
		(pad "1" smd circle
			(at -0.40005 0 270)
			(size 0 0)
			(layers "F.Cu" "F.Mask" "F.Paste")
			(net "P3V3_AUX_MODE")
		)
		(pad "2" smd circle
			(at 0.40005 0 270)
			(size 0 0)
			(layers "F.Cu" "F.Mask" "F.Paste")
			(net "GND")
		)
	)
	(footprint ""
		(layer "F.Cu")
		(at 223.70288 -44.922948)
		(property "Reference" "R3534"
			(at 0 0 0)
			(layer "F.SilkS")
			(hide yes)
			(effects
				(font
					(size 1.27 1.27)
				)
			)
		)
		(property "Value" ""
			(at 0 0 0)
			(layer "F.Fab")
			(effects
				(font
					(size 1.27 1.27)
				)
			)
		)
		(duplicate_pad_numbers_are_jumpers no)
		(fp_line
			(start -0.7874 -0.4064)
			(end 0.7874 -0.4064)
			(stroke
				(width 0.1524)
				(type default)
			)
			(layer "F.SilkS")
		)
		(fp_line
			(start -0.7874 0.4064)
			(end -0.7874 -0.4064)
			(stroke
				(width 0.1524)
				(type default)
			)
			(layer "F.SilkS")
		)
		(fp_line
			(start 0.7874 -0.4064)
			(end 0.7874 0.4064)
			(stroke
				(width 0.1524)
				(type default)
			)
			(layer "F.SilkS")
		)
		(fp_line
			(start 0.7874 0.4064)
			(end -0.7874 0.4064)
			(stroke
				(width 0.1524)
				(type default)
			)
			(layer "F.SilkS")
		)
		(fp_line
			(start -0.67945 -0.305054)
			(end -0.12065 -0.305054)
			(stroke
				(width 0.1)
				(type default)
			)
			(layer "F.Fab")
		)
		(fp_line
			(start -0.67945 0.3048)
			(end -0.67945 -0.305054)
			(stroke
				(width 0.1)
				(type default)
			)
			(layer "F.Fab")
		)
		(fp_line
			(start -0.12065 -0.305054)
			(end -0.12065 -0.2794)
			(stroke
				(width 0.1)
				(type default)
			)
			(layer "F.Fab")
		)
		(fp_line
			(start -0.12065 -0.2794)
			(end 0.12065 -0.2794)
			(stroke
				(width 0.1)
				(type default)
			)
			(layer "F.Fab")
		)
		(fp_line
			(start -0.12065 0.2794)
			(end -0.12065 0.3048)
			(stroke
				(width 0.1)
				(type default)
			)
			(layer "F.Fab")
		)
		(fp_line
			(start -0.12065 0.3048)
			(end -0.67945 0.3048)
			(stroke
				(width 0.1)
				(type default)
			)
			(layer "F.Fab")
		)
		(fp_line
			(start 0.120396 0.2794)
			(end -0.12065 0.2794)
			(stroke
				(width 0.1)
				(type default)
			)
			(layer "F.Fab")
		)
		(fp_line
			(start 0.120396 0.3048)
			(end 0.120396 0.2794)
			(stroke
				(width 0.1)
				(type default)
			)
			(layer "F.Fab")
		)
		(fp_line
			(start 0.12065 -0.3048)
			(end 0.67945 -0.3048)
			(stroke
				(width 0.1)
				(type default)
			)
			(layer "F.Fab")
		)
		(fp_line
			(start 0.12065 -0.2794)
			(end 0.12065 -0.3048)
			(stroke
				(width 0.1)
				(type default)
			)
			(layer "F.Fab")
		)
		(fp_line
			(start 0.67945 -0.3048)
			(end 0.67945 0.3048)
			(stroke
				(width 0.1)
				(type default)
			)
			(layer "F.Fab")
		)
		(fp_line
			(start 0.67945 0.3048)
			(end 0.120396 0.3048)
			(stroke
				(width 0.1)
				(type default)
			)
			(layer "F.Fab")
		)
		(pad "1" smd circle
			(at -0.40005 0)
			(size 0 0)
			(layers "F.Cu" "F.Mask" "F.Paste")
			(net "SMB_E1S_3V3AUX_ISO_SDA_R")
		)
		(pad "2" smd circle
			(at 0.40005 0)
			(size 0 0)
			(layers "F.Cu" "F.Mask" "F.Paste")
			(net "SMB_E1S_3V3AUX_ISO_SDA")
		)
	)
	(footprint ""
		(layer "F.Cu")
		(at 175.4632 -96.103948 90)
		(property "Reference" "R238"
			(at 0 0 90)
			(layer "F.SilkS")
			(hide yes)
			(effects
				(font
					(size 1.27 1.27)
				)
			)
		)
		(property "Value" ""
			(at 0 0 90)
			(layer "F.Fab")
			(effects
				(font
					(size 1.27 1.27)
				)
			)
		)
		(duplicate_pad_numbers_are_jumpers no)
		(fp_line
			(start 0.7874 -0.4064)
			(end 0.7874 0.4064)
			(stroke
				(width 0.1524)
				(type default)
			)
			(layer "F.SilkS")
		)
		(fp_line
			(start -0.7874 -0.4064)
			(end 0.7874 -0.4064)
			(stroke
				(width 0.1524)
				(type default)
			)
			(layer "F.SilkS")
		)
		(fp_line
			(start 0.7874 0.4064)
			(end -0.7874 0.4064)
			(stroke
				(width 0.1524)
				(type default)
			)
			(layer "F.SilkS")
		)
		(fp_line
			(start -0.7874 0.4064)
			(end -0.7874 -0.4064)
			(stroke
				(width 0.1524)
				(type default)
			)
			(layer "F.SilkS")
		)
		(fp_line
			(start -0.12065 -0.305054)
			(end -0.12065 -0.2794)
			(stroke
				(width 0.1)
				(type default)
			)
			(layer "F.Fab")
		)
		(fp_line
			(start -0.67945 -0.305054)
			(end -0.12065 -0.305054)
			(stroke
				(width 0.1)
				(type default)
			)
			(layer "F.Fab")
		)
		(fp_line
			(start 0.67945 -0.3048)
			(end 0.67945 0.3048)
			(stroke
				(width 0.1)
				(type default)
			)
			(layer "F.Fab")
		)
		(fp_line
			(start 0.12065 -0.3048)
			(end 0.67945 -0.3048)
			(stroke
				(width 0.1)
				(type default)
			)
			(layer "F.Fab")
		)
		(fp_line
			(start 0.12065 -0.2794)
			(end 0.12065 -0.3048)
			(stroke
				(width 0.1)
				(type default)
			)
			(layer "F.Fab")
		)
		(fp_line
			(start -0.12065 -0.2794)
			(end 0.12065 -0.2794)
			(stroke
				(width 0.1)
				(type default)
			)
			(layer "F.Fab")
		)
		(fp_line
			(start 0.120396 0.2794)
			(end -0.12065 0.2794)
			(stroke
				(width 0.1)
				(type default)
			)
			(layer "F.Fab")
		)
		(fp_line
			(start -0.12065 0.2794)
			(end -0.12065 0.3048)
			(stroke
				(width 0.1)
				(type default)
			)
			(layer "F.Fab")
		)
		(fp_line
			(start 0.67945 0.3048)
			(end 0.120396 0.3048)
			(stroke
				(width 0.1)
				(type default)
			)
			(layer "F.Fab")
		)
		(fp_line
			(start 0.120396 0.3048)
			(end 0.120396 0.2794)
			(stroke
				(width 0.1)
				(type default)
			)
			(layer "F.Fab")
		)
		(fp_line
			(start -0.12065 0.3048)
			(end -0.67945 0.3048)
			(stroke
				(width 0.1)
				(type default)
			)
			(layer "F.Fab")
		)
		(fp_line
			(start -0.67945 0.3048)
			(end -0.67945 -0.305054)
			(stroke
				(width 0.1)
				(type default)
			)
			(layer "F.Fab")
		)
		(pad "1" smd circle
			(at -0.40005 0 90)
			(size 0 0)
			(layers "F.Cu" "F.Mask" "F.Paste")
			(net "CPU0_XTRIG_L6")
		)
		(pad "2" smd circle
			(at 0.40005 0 90)
			(size 0 0)
			(layers "F.Cu" "F.Mask" "F.Paste")
			(net "FM_CPU0_XTRIG_L6")
		)
	)
	(footprint ""
		(layer "F.Cu")
		(at 259.834126 -97.476056 180)
		(property "Reference" "R1634"
			(at 0 0 180)
			(layer "F.SilkS")
			(hide yes)
			(effects
				(font
					(size 1.27 1.27)
				)
			)
		)
		(property "Value" ""
			(at 0 0 180)
			(layer "F.Fab")
			(effects
				(font
					(size 1.27 1.27)
				)
			)
		)
		(duplicate_pad_numbers_are_jumpers no)
		(fp_line
			(start 0.7874 0.4064)
			(end -0.7874 0.4064)
			(stroke
				(width 0.1524)
				(type default)
			)
			(layer "F.SilkS")
		)
		(fp_line
			(start 0.7874 -0.4064)
			(end 0.7874 0.4064)
			(stroke
				(width 0.1524)
				(type default)
			)
			(layer "F.SilkS")
		)
		(fp_line
			(start -0.7874 0.4064)
			(end -0.7874 -0.4064)
			(stroke
				(width 0.1524)
				(type default)
			)
			(layer "F.SilkS")
		)
		(fp_line
			(start -0.7874 -0.4064)
			(end 0.7874 -0.4064)
			(stroke
				(width 0.1524)
				(type default)
			)
			(layer "F.SilkS")
		)
		(fp_line
			(start 0.67945 0.3048)
			(end 0.120396 0.3048)
			(stroke
				(width 0.1)
				(type default)
			)
			(layer "F.Fab")
		)
		(fp_line
			(start 0.67945 -0.3048)
			(end 0.67945 0.3048)
			(stroke
				(width 0.1)
				(type default)
			)
			(layer "F.Fab")
		)
		(fp_line
			(start 0.12065 -0.2794)
			(end 0.12065 -0.3048)
			(stroke
				(width 0.1)
				(type default)
			)
			(layer "F.Fab")
		)
		(fp_line
			(start 0.12065 -0.3048)
			(end 0.67945 -0.3048)
			(stroke
				(width 0.1)
				(type default)
			)
			(layer "F.Fab")
		)
		(fp_line
			(start 0.120396 0.3048)
			(end 0.120396 0.2794)
			(stroke
				(width 0.1)
				(type default)
			)
			(layer "F.Fab")
		)
		(fp_line
			(start 0.120396 0.2794)
			(end -0.12065 0.2794)
			(stroke
				(width 0.1)
				(type default)
			)
			(layer "F.Fab")
		)
		(fp_line
			(start -0.12065 0.3048)
			(end -0.67945 0.3048)
			(stroke
				(width 0.1)
				(type default)
			)
			(layer "F.Fab")
		)
		(fp_line
			(start -0.12065 0.2794)
			(end -0.12065 0.3048)
			(stroke
				(width 0.1)
				(type default)
			)
			(layer "F.Fab")
		)
		(fp_line
			(start -0.12065 -0.2794)
			(end 0.12065 -0.2794)
			(stroke
				(width 0.1)
				(type default)
			)
			(layer "F.Fab")
		)
		(fp_line
			(start -0.12065 -0.305054)
			(end -0.12065 -0.2794)
			(stroke
				(width 0.1)
				(type default)
			)
			(layer "F.Fab")
		)
		(fp_line
			(start -0.67945 0.3048)
			(end -0.67945 -0.305054)
			(stroke
				(width 0.1)
				(type default)
			)
			(layer "F.Fab")
		)
		(fp_line
			(start -0.67945 -0.305054)
			(end -0.12065 -0.305054)
			(stroke
				(width 0.1)
				(type default)
			)
			(layer "F.Fab")
		)
		(pad "1" smd circle
			(at -0.40005 0 180)
			(size 0 0)
			(layers "F.Cu" "F.Mask" "F.Paste")
			(net "JTAG_TMS_R")
		)
		(pad "2" smd circle
			(at 0.40005 0 180)
			(size 0 0)
			(layers "F.Cu" "F.Mask" "F.Paste")
			(net "JTAG_TMS")
		)
	)
	(footprint ""
		(layer "F.Cu")
		(at 57.872884 -408.517344 -90)
		(property "Reference" "C6635"
			(at 0 0 270)
			(layer "F.SilkS")
			(hide yes)
			(effects
				(font
					(size 1.27 1.27)
				)
			)
		)
		(property "Value" ""
			(at 0 0 270)
			(layer "F.Fab")
			(effects
				(font
					(size 1.27 1.27)
				)
			)
		)
		(duplicate_pad_numbers_are_jumpers no)
		(fp_line
			(start -0.299974 0.150114)
			(end -0.299974 -0.150114)
			(stroke
				(width 0.1)
				(type default)
			)
			(layer "F.Fab")
		)
		(fp_line
			(start 0.299974 0.150114)
			(end -0.299974 0.150114)
			(stroke
				(width 0.1)
				(type default)
			)
			(layer "F.Fab")
		)
		(fp_line
			(start -0.299974 -0.150114)
			(end 0.299974 -0.150114)
			(stroke
				(width 0.1)
				(type default)
			)
			(layer "F.Fab")
		)
		(fp_line
			(start 0.299974 -0.150114)
			(end 0.299974 0.150114)
			(stroke
				(width 0.1)
				(type default)
			)
			(layer "F.Fab")
		)
		(pad "1" smd rect
			(at -0.2667 0 270)
			(size 0.3048 0.381)
			(layers "F.Cu" "F.Mask" "F.Paste")
			(net "P5E_CPU1_P0_TX_BUF_C_DP<3>")
		)
		(pad "2" smd rect
			(at 0.2667 0 270)
			(size 0.3048 0.381)
			(layers "F.Cu" "F.Mask" "F.Paste")
			(net "P5E_CPU1_P0_TX_BUF_DP<3>")
		)
	)
	(footprint ""
		(layer "F.Cu")
		(at 279.513792 -113.62817 180)
		(property "Reference" "R3526"
			(at 0 0 180)
			(layer "F.SilkS")
			(hide yes)
			(effects
				(font
					(size 1.27 1.27)
				)
			)
		)
		(property "Value" ""
			(at 0 0 180)
			(layer "F.Fab")
			(effects
				(font
					(size 1.27 1.27)
				)
			)
		)
		(duplicate_pad_numbers_are_jumpers no)
		(fp_line
			(start 0.7874 0.4064)
			(end -0.7874 0.4064)
			(stroke
				(width 0.1524)
				(type default)
			)
			(layer "F.SilkS")
		)
		(fp_line
			(start 0.7874 -0.4064)
			(end 0.7874 0.4064)
			(stroke
				(width 0.1524)
				(type default)
			)
			(layer "F.SilkS")
		)
		(fp_line
			(start -0.7874 0.4064)
			(end -0.7874 -0.4064)
			(stroke
				(width 0.1524)
				(type default)
			)
			(layer "F.SilkS")
		)
		(fp_line
			(start -0.7874 -0.4064)
			(end 0.7874 -0.4064)
			(stroke
				(width 0.1524)
				(type default)
			)
			(layer "F.SilkS")
		)
		(fp_line
			(start 0.67945 0.3048)
			(end 0.120396 0.3048)
			(stroke
				(width 0.1)
				(type default)
			)
			(layer "F.Fab")
		)
		(fp_line
			(start 0.67945 -0.3048)
			(end 0.67945 0.3048)
			(stroke
				(width 0.1)
				(type default)
			)
			(layer "F.Fab")
		)
		(fp_line
			(start 0.12065 -0.2794)
			(end 0.12065 -0.3048)
			(stroke
				(width 0.1)
				(type default)
			)
			(layer "F.Fab")
		)
		(fp_line
			(start 0.12065 -0.3048)
			(end 0.67945 -0.3048)
			(stroke
				(width 0.1)
				(type default)
			)
			(layer "F.Fab")
		)
		(fp_line
			(start 0.120396 0.3048)
			(end 0.120396 0.2794)
			(stroke
				(width 0.1)
				(type default)
			)
			(layer "F.Fab")
		)
		(fp_line
			(start 0.120396 0.2794)
			(end -0.12065 0.2794)
			(stroke
				(width 0.1)
				(type default)
			)
			(layer "F.Fab")
		)
		(fp_line
			(start -0.12065 0.3048)
			(end -0.67945 0.3048)
			(stroke
				(width 0.1)
				(type default)
			)
			(layer "F.Fab")
		)
		(fp_line
			(start -0.12065 0.2794)
			(end -0.12065 0.3048)
			(stroke
				(width 0.1)
				(type default)
			)
			(layer "F.Fab")
		)
		(fp_line
			(start -0.12065 -0.2794)
			(end 0.12065 -0.2794)
			(stroke
				(width 0.1)
				(type default)
			)
			(layer "F.Fab")
		)
		(fp_line
			(start -0.12065 -0.305054)
			(end -0.12065 -0.2794)
			(stroke
				(width 0.1)
				(type default)
			)
			(layer "F.Fab")
		)
		(fp_line
			(start -0.67945 0.3048)
			(end -0.67945 -0.305054)
			(stroke
				(width 0.1)
				(type default)
			)
			(layer "F.Fab")
		)
		(fp_line
			(start -0.67945 -0.305054)
			(end -0.12065 -0.305054)
			(stroke
				(width 0.1)
				(type default)
			)
			(layer "F.Fab")
		)
		(pad "1" smd circle
			(at -0.40005 0 180)
			(size 0 0)
			(layers "F.Cu" "F.Mask" "F.Paste")
			(net "SMB_PCIE0_3V3AUX_SCL_R5")
		)
		(pad "2" smd circle
			(at 0.40005 0 180)
			(size 0 0)
			(layers "F.Cu" "F.Mask" "F.Paste")
			(net "SMB_SENSOR_E1S_3V3AUX_SCL")
		)
	)
	(footprint ""
		(layer "F.Cu")
		(at 329.592178 -43.573954 180)
		(property "Reference" "R3005"
			(at 0 0 180)
			(layer "F.SilkS")
			(hide yes)
			(effects
				(font
					(size 1.27 1.27)
				)
			)
		)
		(property "Value" ""
			(at 0 0 180)
			(layer "F.Fab")
			(effects
				(font
					(size 1.27 1.27)
				)
			)
		)
		(duplicate_pad_numbers_are_jumpers no)
		(fp_line
			(start 0.7874 0.4064)
			(end -0.7874 0.4064)
			(stroke
				(width 0.1524)
				(type default)
			)
			(layer "F.SilkS")
		)
		(fp_line
			(start 0.7874 -0.4064)
			(end 0.7874 0.4064)
			(stroke
				(width 0.1524)
				(type default)
			)
			(layer "F.SilkS")
		)
		(fp_line
			(start -0.7874 0.4064)
			(end -0.7874 -0.4064)
			(stroke
				(width 0.1524)
				(type default)
			)
			(layer "F.SilkS")
		)
		(fp_line
			(start -0.7874 -0.4064)
			(end 0.7874 -0.4064)
			(stroke
				(width 0.1524)
				(type default)
			)
			(layer "F.SilkS")
		)
		(fp_line
			(start 0.67945 0.3048)
			(end 0.120396 0.3048)
			(stroke
				(width 0.1)
				(type default)
			)
			(layer "F.Fab")
		)
		(fp_line
			(start 0.67945 -0.3048)
			(end 0.67945 0.3048)
			(stroke
				(width 0.1)
				(type default)
			)
			(layer "F.Fab")
		)
		(fp_line
			(start 0.12065 -0.2794)
			(end 0.12065 -0.3048)
			(stroke
				(width 0.1)
				(type default)
			)
			(layer "F.Fab")
		)
		(fp_line
			(start 0.12065 -0.3048)
			(end 0.67945 -0.3048)
			(stroke
				(width 0.1)
				(type default)
			)
			(layer "F.Fab")
		)
		(fp_line
			(start 0.120396 0.3048)
			(end 0.120396 0.2794)
			(stroke
				(width 0.1)
				(type default)
			)
			(layer "F.Fab")
		)
		(fp_line
			(start 0.120396 0.2794)
			(end -0.12065 0.2794)
			(stroke
				(width 0.1)
				(type default)
			)
			(layer "F.Fab")
		)
		(fp_line
			(start -0.12065 0.3048)
			(end -0.67945 0.3048)
			(stroke
				(width 0.1)
				(type default)
			)
			(layer "F.Fab")
		)
		(fp_line
			(start -0.12065 0.2794)
			(end -0.12065 0.3048)
			(stroke
				(width 0.1)
				(type default)
			)
			(layer "F.Fab")
		)
		(fp_line
			(start -0.12065 -0.2794)
			(end 0.12065 -0.2794)
			(stroke
				(width 0.1)
				(type default)
			)
			(layer "F.Fab")
		)
		(fp_line
			(start -0.12065 -0.305054)
			(end -0.12065 -0.2794)
			(stroke
				(width 0.1)
				(type default)
			)
			(layer "F.Fab")
		)
		(fp_line
			(start -0.67945 0.3048)
			(end -0.67945 -0.305054)
			(stroke
				(width 0.1)
				(type default)
			)
			(layer "F.Fab")
		)
		(fp_line
			(start -0.67945 -0.305054)
			(end -0.12065 -0.305054)
			(stroke
				(width 0.1)
				(type default)
			)
			(layer "F.Fab")
		)
		(pad "1" smd circle
			(at -0.40005 0 180)
			(size 0 0)
			(layers "F.Cu" "F.Mask" "F.Paste")
			(net "P5V")
		)
		(pad "2" smd circle
			(at 0.40005 0 180)
			(size 0 0)
			(layers "F.Cu" "F.Mask" "F.Paste")
			(net "P5V_ADC")
		)
	)
	(footprint ""
		(layer "F.Cu")
		(at 353.900232 -257.455162)
		(property "Reference" "C2606"
			(at 0 0 0)
			(layer "F.SilkS")
			(hide yes)
			(effects
				(font
					(size 1.27 1.27)
				)
			)
		)
		(property "Value" ""
			(at 0 0 0)
			(layer "F.Fab")
			(effects
				(font
					(size 1.27 1.27)
				)
			)
		)
		(duplicate_pad_numbers_are_jumpers no)
		(fp_line
			(start -0.7874 -0.4064)
			(end 0.7874 -0.4064)
			(stroke
				(width 0.1524)
				(type default)
			)
			(layer "F.SilkS")
		)
		(fp_line
			(start -0.7874 0.4064)
			(end -0.7874 -0.4064)
			(stroke
				(width 0.1524)
				(type default)
			)
			(layer "F.SilkS")
		)
		(fp_line
			(start 0.7874 -0.4064)
			(end 0.7874 0.4064)
			(stroke
				(width 0.1524)
				(type default)
			)
			(layer "F.SilkS")
		)
		(fp_line
			(start 0.7874 0.4064)
			(end -0.7874 0.4064)
			(stroke
				(width 0.1524)
				(type default)
			)
			(layer "F.SilkS")
		)
		(fp_line
			(start -0.67945 -0.305054)
			(end -0.12065 -0.305054)
			(stroke
				(width 0.1)
				(type default)
			)
			(layer "F.Fab")
		)
		(fp_line
			(start -0.67945 0.3048)
			(end -0.67945 -0.305054)
			(stroke
				(width 0.1)
				(type default)
			)
			(layer "F.Fab")
		)
		(fp_line
			(start -0.12065 -0.305054)
			(end -0.12065 -0.2794)
			(stroke
				(width 0.1)
				(type default)
			)
			(layer "F.Fab")
		)
		(fp_line
			(start -0.12065 -0.2794)
			(end 0.12065 -0.2794)
			(stroke
				(width 0.1)
				(type default)
			)
			(layer "F.Fab")
		)
		(fp_line
			(start -0.12065 0.2794)
			(end -0.12065 0.3048)
			(stroke
				(width 0.1)
				(type default)
			)
			(layer "F.Fab")
		)
		(fp_line
			(start -0.12065 0.3048)
			(end -0.67945 0.3048)
			(stroke
				(width 0.1)
				(type default)
			)
			(layer "F.Fab")
		)
		(fp_line
			(start 0.120396 0.2794)
			(end -0.12065 0.2794)
			(stroke
				(width 0.1)
				(type default)
			)
			(layer "F.Fab")
		)
		(fp_line
			(start 0.120396 0.3048)
			(end 0.120396 0.2794)
			(stroke
				(width 0.1)
				(type default)
			)
			(layer "F.Fab")
		)
		(fp_line
			(start 0.12065 -0.3048)
			(end 0.67945 -0.3048)
			(stroke
				(width 0.1)
				(type default)
			)
			(layer "F.Fab")
		)
		(fp_line
			(start 0.12065 -0.2794)
			(end 0.12065 -0.3048)
			(stroke
				(width 0.1)
				(type default)
			)
			(layer "F.Fab")
		)
		(fp_line
			(start 0.67945 -0.3048)
			(end 0.67945 0.3048)
			(stroke
				(width 0.1)
				(type default)
			)
			(layer "F.Fab")
		)
		(fp_line
			(start 0.67945 0.3048)
			(end 0.120396 0.3048)
			(stroke
				(width 0.1)
				(type default)
			)
			(layer "F.Fab")
		)
		(pad "1" smd circle
			(at -0.40005 0)
			(size 0 0)
			(layers "F.Cu" "F.Mask" "F.Paste")
			(net "PVDDIO_P0")
		)
		(pad "2" smd circle
			(at 0.40005 0)
			(size 0 0)
			(layers "F.Cu" "F.Mask" "F.Paste")
			(net "GND")
		)
	)
	(footprint ""
		(layer "F.Cu")
		(at 57.738518 -351.10547)
		(property "Reference" "PC623_4"
			(at 0 0 0)
			(layer "F.SilkS")
			(hide yes)
			(effects
				(font
					(size 1.27 1.27)
				)
			)
		)
		(property "Value" ""
			(at 0 0 0)
			(layer "F.Fab")
			(effects
				(font
					(size 1.27 1.27)
				)
			)
		)
		(duplicate_pad_numbers_are_jumpers no)
		(fp_line
			(start -0.7874 -0.4064)
			(end 0.7874 -0.4064)
			(stroke
				(width 0.1524)
				(type default)
			)
			(layer "F.SilkS")
		)
		(fp_line
			(start -0.7874 0.4064)
			(end -0.7874 -0.4064)
			(stroke
				(width 0.1524)
				(type default)
			)
			(layer "F.SilkS")
		)
		(fp_line
			(start 0.7874 -0.4064)
			(end 0.7874 0.4064)
			(stroke
				(width 0.1524)
				(type default)
			)
			(layer "F.SilkS")
		)
		(fp_line
			(start 0.7874 0.4064)
			(end -0.7874 0.4064)
			(stroke
				(width 0.1524)
				(type default)
			)
			(layer "F.SilkS")
		)
		(fp_line
			(start -0.67945 -0.305054)
			(end -0.12065 -0.305054)
			(stroke
				(width 0.1)
				(type default)
			)
			(layer "F.Fab")
		)
		(fp_line
			(start -0.67945 0.3048)
			(end -0.67945 -0.305054)
			(stroke
				(width 0.1)
				(type default)
			)
			(layer "F.Fab")
		)
		(fp_line
			(start -0.12065 -0.305054)
			(end -0.12065 -0.2794)
			(stroke
				(width 0.1)
				(type default)
			)
			(layer "F.Fab")
		)
		(fp_line
			(start -0.12065 -0.2794)
			(end 0.12065 -0.2794)
			(stroke
				(width 0.1)
				(type default)
			)
			(layer "F.Fab")
		)
		(fp_line
			(start -0.12065 0.2794)
			(end -0.12065 0.3048)
			(stroke
				(width 0.1)
				(type default)
			)
			(layer "F.Fab")
		)
		(fp_line
			(start -0.12065 0.3048)
			(end -0.67945 0.3048)
			(stroke
				(width 0.1)
				(type default)
			)
			(layer "F.Fab")
		)
		(fp_line
			(start 0.120396 0.2794)
			(end -0.12065 0.2794)
			(stroke
				(width 0.1)
				(type default)
			)
			(layer "F.Fab")
		)
		(fp_line
			(start 0.120396 0.3048)
			(end 0.120396 0.2794)
			(stroke
				(width 0.1)
				(type default)
			)
			(layer "F.Fab")
		)
		(fp_line
			(start 0.12065 -0.3048)
			(end 0.67945 -0.3048)
			(stroke
				(width 0.1)
				(type default)
			)
			(layer "F.Fab")
		)
		(fp_line
			(start 0.12065 -0.2794)
			(end 0.12065 -0.3048)
			(stroke
				(width 0.1)
				(type default)
			)
			(layer "F.Fab")
		)
		(fp_line
			(start 0.67945 -0.3048)
			(end 0.67945 0.3048)
			(stroke
				(width 0.1)
				(type default)
			)
			(layer "F.Fab")
		)
		(fp_line
			(start 0.67945 0.3048)
			(end 0.120396 0.3048)
			(stroke
				(width 0.1)
				(type default)
			)
			(layer "F.Fab")
		)
		(pad "1" smd circle
			(at -0.40005 0)
			(size 0 0)
			(layers "F.Cu" "F.Mask" "F.Paste")
			(net "SW_P12V_AUX_PVDDIO_P1_FLT")
		)
		(pad "2" smd circle
			(at 0.40005 0)
			(size 0 0)
			(layers "F.Cu" "F.Mask" "F.Paste")
			(net "GND")
		)
	)
	(footprint ""
		(layer "F.Cu")
		(at 127.64897 -165.194234 90)
		(property "Reference" "PC322_SOP1_2"
			(at 0 0 90)
			(layer "F.SilkS")
			(hide yes)
			(effects
				(font
					(size 1.27 1.27)
				)
			)
		)
		(property "Value" ""
			(at 0 0 90)
			(layer "F.Fab")
			(effects
				(font
					(size 1.27 1.27)
				)
			)
		)
		(duplicate_pad_numbers_are_jumpers no)
		(fp_line
			(start 0.7874 -0.4064)
			(end 0.7874 0.4064)
			(stroke
				(width 0.1524)
				(type default)
			)
			(layer "F.SilkS")
		)
		(fp_line
			(start -0.7874 -0.4064)
			(end 0.7874 -0.4064)
			(stroke
				(width 0.1524)
				(type default)
			)
			(layer "F.SilkS")
		)
		(fp_line
			(start 0.7874 0.4064)
			(end -0.7874 0.4064)
			(stroke
				(width 0.1524)
				(type default)
			)
			(layer "F.SilkS")
		)
		(fp_line
			(start -0.7874 0.4064)
			(end -0.7874 -0.4064)
			(stroke
				(width 0.1524)
				(type default)
			)
			(layer "F.SilkS")
		)
		(fp_line
			(start -0.12065 -0.305054)
			(end -0.12065 -0.2794)
			(stroke
				(width 0.1)
				(type default)
			)
			(layer "F.Fab")
		)
		(fp_line
			(start -0.67945 -0.305054)
			(end -0.12065 -0.305054)
			(stroke
				(width 0.1)
				(type default)
			)
			(layer "F.Fab")
		)
		(fp_line
			(start 0.67945 -0.3048)
			(end 0.67945 0.3048)
			(stroke
				(width 0.1)
				(type default)
			)
			(layer "F.Fab")
		)
		(fp_line
			(start 0.12065 -0.3048)
			(end 0.67945 -0.3048)
			(stroke
				(width 0.1)
				(type default)
			)
			(layer "F.Fab")
		)
		(fp_line
			(start 0.12065 -0.2794)
			(end 0.12065 -0.3048)
			(stroke
				(width 0.1)
				(type default)
			)
			(layer "F.Fab")
		)
		(fp_line
			(start -0.12065 -0.2794)
			(end 0.12065 -0.2794)
			(stroke
				(width 0.1)
				(type default)
			)
			(layer "F.Fab")
		)
		(fp_line
			(start 0.120396 0.2794)
			(end -0.12065 0.2794)
			(stroke
				(width 0.1)
				(type default)
			)
			(layer "F.Fab")
		)
		(fp_line
			(start -0.12065 0.2794)
			(end -0.12065 0.3048)
			(stroke
				(width 0.1)
				(type default)
			)
			(layer "F.Fab")
		)
		(fp_line
			(start 0.67945 0.3048)
			(end 0.120396 0.3048)
			(stroke
				(width 0.1)
				(type default)
			)
			(layer "F.Fab")
		)
		(fp_line
			(start 0.120396 0.3048)
			(end 0.120396 0.2794)
			(stroke
				(width 0.1)
				(type default)
			)
			(layer "F.Fab")
		)
		(fp_line
			(start -0.12065 0.3048)
			(end -0.67945 0.3048)
			(stroke
				(width 0.1)
				(type default)
			)
			(layer "F.Fab")
		)
		(fp_line
			(start -0.67945 0.3048)
			(end -0.67945 -0.305054)
			(stroke
				(width 0.1)
				(type default)
			)
			(layer "F.Fab")
		)
		(pad "1" smd circle
			(at -0.40005 0 90)
			(size 0 0)
			(layers "F.Cu" "F.Mask" "F.Paste")
			(net "PVDDCR_CPU0_P1_PVCC")
		)
		(pad "2" smd circle
			(at 0.40005 0 90)
			(size 0 0)
			(layers "F.Cu" "F.Mask" "F.Paste")
			(net "GND")
		)
	)
	(footprint ""
		(layer "F.Cu")
		(at 417.731702 -416.899344 -90)
		(property "Reference" "C6595"
			(at 0 0 270)
			(layer "F.SilkS")
			(hide yes)
			(effects
				(font
					(size 1.27 1.27)
				)
			)
		)
		(property "Value" ""
			(at 0 0 270)
			(layer "F.Fab")
			(effects
				(font
					(size 1.27 1.27)
				)
			)
		)
		(duplicate_pad_numbers_are_jumpers no)
		(fp_line
			(start -0.299974 0.150114)
			(end -0.299974 -0.150114)
			(stroke
				(width 0.1)
				(type default)
			)
			(layer "F.Fab")
		)
		(fp_line
			(start 0.299974 0.150114)
			(end -0.299974 0.150114)
			(stroke
				(width 0.1)
				(type default)
			)
			(layer "F.Fab")
		)
		(fp_line
			(start -0.299974 -0.150114)
			(end 0.299974 -0.150114)
			(stroke
				(width 0.1)
				(type default)
			)
			(layer "F.Fab")
		)
		(fp_line
			(start 0.299974 -0.150114)
			(end 0.299974 0.150114)
			(stroke
				(width 0.1)
				(type default)
			)
			(layer "F.Fab")
		)
		(pad "1" smd rect
			(at -0.2667 0 270)
			(size 0.3048 0.381)
			(layers "F.Cu" "F.Mask" "F.Paste")
			(net "P5E_CPU0_P2_TX_BUF_C_DP<15>")
		)
		(pad "2" smd rect
			(at 0.2667 0 270)
			(size 0.3048 0.381)
			(layers "F.Cu" "F.Mask" "F.Paste")
			(net "P5E_CPU0_P2_TX_BUF_DP<15>")
		)
	)
	(footprint ""
		(layer "F.Cu")
		(at 420.591488 -332.63586 -90)
		(property "Reference" "PC228"
			(at -4.97332 -17.659096 90)
			(unlocked yes)
			(layer "F.SilkS")
			(effects
				(font
					(size 0.7874 0.5842)
					(thickness 0.1524)
				)
				(justify left)
			)
		)
		(property "Value" ""
			(at 0 0 270)
			(layer "F.Fab")
			(effects
				(font
					(size 1.27 1.27)
				)
			)
		)
		(duplicate_pad_numbers_are_jumpers no)
		(fp_line
			(start -1.988058 2.750058)
			(end 2.750058 2.750058)
			(stroke
				(width 0.1524)
				(type default)
			)
			(layer "F.SilkS")
		)
		(fp_line
			(start 2.750058 2.750058)
			(end 2.750058 0.9398)
			(stroke
				(width 0.1524)
				(type default)
			)
			(layer "F.SilkS")
		)
		(fp_line
			(start -2.750058 1.988058)
			(end -1.988058 2.750058)
			(stroke
				(width 0.1524)
				(type default)
			)
			(layer "F.SilkS")
		)
		(fp_line
			(start -2.750058 0.9398)
			(end -2.750058 1.988058)
			(stroke
				(width 0.1524)
				(type default)
			)
			(layer "F.SilkS")
		)
		(fp_line
			(start 2.750058 -0.9398)
			(end 2.750058 -2.750058)
			(stroke
				(width 0.1524)
				(type default)
			)
			(layer "F.SilkS")
		)
		(fp_line
			(start -2.750058 -1.988058)
			(end -2.750058 -0.9398)
			(stroke
				(width 0.1524)
				(type default)
			)
			(layer "F.SilkS")
		)
		(fp_line
			(start -1.988058 -2.750058)
			(end -2.750058 -1.988058)
			(stroke
				(width 0.1524)
				(type default)
			)
			(layer "F.SilkS")
		)
		(fp_line
			(start 2.750058 -2.750058)
			(end -1.988058 -2.750058)
			(stroke
				(width 0.1524)
				(type default)
			)
			(layer "F.SilkS")
		)
		(fp_line
			(start -2.750058 2.750058)
			(end 2.750058 2.750058)
			(stroke
				(width 0.1)
				(type default)
			)
			(layer "F.Fab")
		)
		(fp_line
			(start 2.750058 2.750058)
			(end 2.750058 -2.750058)
			(stroke
				(width 0.1)
				(type default)
			)
			(layer "F.Fab")
		)
		(fp_line
			(start -2.750058 -2.750058)
			(end -2.750058 2.750058)
			(stroke
				(width 0.1)
				(type default)
			)
			(layer "F.Fab")
		)
		(fp_line
			(start 2.750058 -2.750058)
			(end -2.750058 -2.750058)
			(stroke
				(width 0.1)
				(type default)
			)
			(layer "F.Fab")
		)
		(pad "1" smd rect
			(at -2.199894 0)
			(size 1.6002 3.0226)
			(layers "F.Cu" "F.Mask" "F.Paste")
			(net "PVDD11_S3_P0")
		)
		(pad "2" smd rect
			(at 2.199894 0)
			(size 1.6002 3.0226)
			(layers "F.Cu" "F.Mask" "F.Paste")
			(net "GND")
		)
	)
	(footprint ""
		(layer "F.Cu")
		(at 350.421702 -156.281882 -90)
		(property "Reference" "PC150_6"
			(at 0 0 270)
			(layer "F.SilkS")
			(hide yes)
			(effects
				(font
					(size 1.27 1.27)
				)
			)
		)
		(property "Value" ""
			(at 0 0 270)
			(layer "F.Fab")
			(effects
				(font
					(size 1.27 1.27)
				)
			)
		)
		(duplicate_pad_numbers_are_jumpers no)
		(fp_line
			(start -0.7874 0.4064)
			(end -0.7874 -0.4064)
			(stroke
				(width 0.1524)
				(type default)
			)
			(layer "F.SilkS")
		)
		(fp_line
			(start 0.7874 0.4064)
			(end -0.7874 0.4064)
			(stroke
				(width 0.1524)
				(type default)
			)
			(layer "F.SilkS")
		)
		(fp_line
			(start -0.7874 -0.4064)
			(end 0.7874 -0.4064)
			(stroke
				(width 0.1524)
				(type default)
			)
			(layer "F.SilkS")
		)
		(fp_line
			(start 0.7874 -0.4064)
			(end 0.7874 0.4064)
			(stroke
				(width 0.1524)
				(type default)
			)
			(layer "F.SilkS")
		)
		(fp_line
			(start -0.67945 0.3048)
			(end -0.67945 -0.305054)
			(stroke
				(width 0.1)
				(type default)
			)
			(layer "F.Fab")
		)
		(fp_line
			(start -0.12065 0.3048)
			(end -0.67945 0.3048)
			(stroke
				(width 0.1)
				(type default)
			)
			(layer "F.Fab")
		)
		(fp_line
			(start 0.120396 0.3048)
			(end 0.120396 0.2794)
			(stroke
				(width 0.1)
				(type default)
			)
			(layer "F.Fab")
		)
		(fp_line
			(start 0.67945 0.3048)
			(end 0.120396 0.3048)
			(stroke
				(width 0.1)
				(type default)
			)
			(layer "F.Fab")
		)
		(fp_line
			(start -0.12065 0.2794)
			(end -0.12065 0.3048)
			(stroke
				(width 0.1)
				(type default)
			)
			(layer "F.Fab")
		)
		(fp_line
			(start 0.120396 0.2794)
			(end -0.12065 0.2794)
			(stroke
				(width 0.1)
				(type default)
			)
			(layer "F.Fab")
		)
		(fp_line
			(start -0.12065 -0.2794)
			(end 0.12065 -0.2794)
			(stroke
				(width 0.1)
				(type default)
			)
			(layer "F.Fab")
		)
		(fp_line
			(start 0.12065 -0.2794)
			(end 0.12065 -0.3048)
			(stroke
				(width 0.1)
				(type default)
			)
			(layer "F.Fab")
		)
		(fp_line
			(start 0.12065 -0.3048)
			(end 0.67945 -0.3048)
			(stroke
				(width 0.1)
				(type default)
			)
			(layer "F.Fab")
		)
		(fp_line
			(start 0.67945 -0.3048)
			(end 0.67945 0.3048)
			(stroke
				(width 0.1)
				(type default)
			)
			(layer "F.Fab")
		)
		(fp_line
			(start -0.67945 -0.305054)
			(end -0.12065 -0.305054)
			(stroke
				(width 0.1)
				(type default)
			)
			(layer "F.Fab")
		)
		(fp_line
			(start -0.12065 -0.305054)
			(end -0.12065 -0.2794)
			(stroke
				(width 0.1)
				(type default)
			)
			(layer "F.Fab")
		)
		(pad "1" smd circle
			(at -0.40005 0 270)
			(size 0 0)
			(layers "F.Cu" "F.Mask" "F.Paste")
			(net "PVDDCR_CPU0_P0_VCCS")
		)
		(pad "2" smd circle
			(at 0.40005 0 270)
			(size 0 0)
			(layers "F.Cu" "F.Mask" "F.Paste")
			(net "GND")
		)
	)
	(footprint ""
		(layer "F.Cu")
		(at 15.58417 -69.178678)
		(property "Reference" "R3147"
			(at 0 0 0)
			(layer "F.SilkS")
			(hide yes)
			(effects
				(font
					(size 1.27 1.27)
				)
			)
		)
		(property "Value" ""
			(at 0 0 0)
			(layer "F.Fab")
			(effects
				(font
					(size 1.27 1.27)
				)
			)
		)
		(duplicate_pad_numbers_are_jumpers no)
		(fp_line
			(start -0.7874 -0.4064)
			(end 0.7874 -0.4064)
			(stroke
				(width 0.1524)
				(type default)
			)
			(layer "F.SilkS")
		)
		(fp_line
			(start -0.7874 0.4064)
			(end -0.7874 -0.4064)
			(stroke
				(width 0.1524)
				(type default)
			)
			(layer "F.SilkS")
		)
		(fp_line
			(start 0.7874 -0.4064)
			(end 0.7874 0.4064)
			(stroke
				(width 0.1524)
				(type default)
			)
			(layer "F.SilkS")
		)
		(fp_line
			(start 0.7874 0.4064)
			(end -0.7874 0.4064)
			(stroke
				(width 0.1524)
				(type default)
			)
			(layer "F.SilkS")
		)
		(fp_line
			(start -0.67945 -0.305054)
			(end -0.12065 -0.305054)
			(stroke
				(width 0.1)
				(type default)
			)
			(layer "F.Fab")
		)
		(fp_line
			(start -0.67945 0.3048)
			(end -0.67945 -0.305054)
			(stroke
				(width 0.1)
				(type default)
			)
			(layer "F.Fab")
		)
		(fp_line
			(start -0.12065 -0.305054)
			(end -0.12065 -0.2794)
			(stroke
				(width 0.1)
				(type default)
			)
			(layer "F.Fab")
		)
		(fp_line
			(start -0.12065 -0.2794)
			(end 0.12065 -0.2794)
			(stroke
				(width 0.1)
				(type default)
			)
			(layer "F.Fab")
		)
		(fp_line
			(start -0.12065 0.2794)
			(end -0.12065 0.3048)
			(stroke
				(width 0.1)
				(type default)
			)
			(layer "F.Fab")
		)
		(fp_line
			(start -0.12065 0.3048)
			(end -0.67945 0.3048)
			(stroke
				(width 0.1)
				(type default)
			)
			(layer "F.Fab")
		)
		(fp_line
			(start 0.120396 0.2794)
			(end -0.12065 0.2794)
			(stroke
				(width 0.1)
				(type default)
			)
			(layer "F.Fab")
		)
		(fp_line
			(start 0.120396 0.3048)
			(end 0.120396 0.2794)
			(stroke
				(width 0.1)
				(type default)
			)
			(layer "F.Fab")
		)
		(fp_line
			(start 0.12065 -0.3048)
			(end 0.67945 -0.3048)
			(stroke
				(width 0.1)
				(type default)
			)
			(layer "F.Fab")
		)
		(fp_line
			(start 0.12065 -0.2794)
			(end 0.12065 -0.3048)
			(stroke
				(width 0.1)
				(type default)
			)
			(layer "F.Fab")
		)
		(fp_line
			(start 0.67945 -0.3048)
			(end 0.67945 0.3048)
			(stroke
				(width 0.1)
				(type default)
			)
			(layer "F.Fab")
		)
		(fp_line
			(start 0.67945 0.3048)
			(end 0.120396 0.3048)
			(stroke
				(width 0.1)
				(type default)
			)
			(layer "F.Fab")
		)
		(pad "1" smd circle
			(at -0.40005 0)
			(size 0 0)
			(layers "F.Cu" "F.Mask" "F.Paste")
			(net "P3V3_AUX")
		)
		(pad "2" smd circle
			(at 0.40005 0)
			(size 0 0)
			(layers "F.Cu" "F.Mask" "F.Paste")
			(net "HP_LVC3_OCP_V3_2_PRSNT2_PLD_N")
		)
	)
	(footprint ""
		(layer "F.Cu")
		(at 190.94958 -413.964882 -90)
		(property "Reference" "R2941"
			(at 0 0 270)
			(layer "F.SilkS")
			(hide yes)
			(effects
				(font
					(size 1.27 1.27)
				)
			)
		)
		(property "Value" ""
			(at 0 0 270)
			(layer "F.Fab")
			(effects
				(font
					(size 1.27 1.27)
				)
			)
		)
		(duplicate_pad_numbers_are_jumpers no)
		(fp_line
			(start -0.7874 0.4064)
			(end -0.7874 -0.4064)
			(stroke
				(width 0.1524)
				(type default)
			)
			(layer "F.SilkS")
		)
		(fp_line
			(start 0.7874 0.4064)
			(end -0.7874 0.4064)
			(stroke
				(width 0.1524)
				(type default)
			)
			(layer "F.SilkS")
		)
		(fp_line
			(start -0.7874 -0.4064)
			(end 0.7874 -0.4064)
			(stroke
				(width 0.1524)
				(type default)
			)
			(layer "F.SilkS")
		)
		(fp_line
			(start 0.7874 -0.4064)
			(end 0.7874 0.4064)
			(stroke
				(width 0.1524)
				(type default)
			)
			(layer "F.SilkS")
		)
		(fp_line
			(start -0.67945 0.3048)
			(end -0.67945 -0.305054)
			(stroke
				(width 0.1)
				(type default)
			)
			(layer "F.Fab")
		)
		(fp_line
			(start -0.12065 0.3048)
			(end -0.67945 0.3048)
			(stroke
				(width 0.1)
				(type default)
			)
			(layer "F.Fab")
		)
		(fp_line
			(start 0.120396 0.3048)
			(end 0.120396 0.2794)
			(stroke
				(width 0.1)
				(type default)
			)
			(layer "F.Fab")
		)
		(fp_line
			(start 0.67945 0.3048)
			(end 0.120396 0.3048)
			(stroke
				(width 0.1)
				(type default)
			)
			(layer "F.Fab")
		)
		(fp_line
			(start -0.12065 0.2794)
			(end -0.12065 0.3048)
			(stroke
				(width 0.1)
				(type default)
			)
			(layer "F.Fab")
		)
		(fp_line
			(start 0.120396 0.2794)
			(end -0.12065 0.2794)
			(stroke
				(width 0.1)
				(type default)
			)
			(layer "F.Fab")
		)
		(fp_line
			(start -0.12065 -0.2794)
			(end 0.12065 -0.2794)
			(stroke
				(width 0.1)
				(type default)
			)
			(layer "F.Fab")
		)
		(fp_line
			(start 0.12065 -0.2794)
			(end 0.12065 -0.3048)
			(stroke
				(width 0.1)
				(type default)
			)
			(layer "F.Fab")
		)
		(fp_line
			(start 0.12065 -0.3048)
			(end 0.67945 -0.3048)
			(stroke
				(width 0.1)
				(type default)
			)
			(layer "F.Fab")
		)
		(fp_line
			(start 0.67945 -0.3048)
			(end 0.67945 0.3048)
			(stroke
				(width 0.1)
				(type default)
			)
			(layer "F.Fab")
		)
		(fp_line
			(start -0.67945 -0.305054)
			(end -0.12065 -0.305054)
			(stroke
				(width 0.1)
				(type default)
			)
			(layer "F.Fab")
		)
		(fp_line
			(start -0.12065 -0.305054)
			(end -0.12065 -0.2794)
			(stroke
				(width 0.1)
				(type default)
			)
			(layer "F.Fab")
		)
		(pad "1" smd circle
			(at -0.40005 0 270)
			(size 0 0)
			(layers "F.Cu" "F.Mask" "F.Paste")
			(net "FM_GPU_HSC_EN")
		)
		(pad "2" smd circle
			(at 0.40005 0 270)
			(size 0 0)
			(layers "F.Cu" "F.Mask" "F.Paste")
			(net "GND")
		)
	)
	(footprint ""
		(layer "F.Cu")
		(at 253.340108 -107.855004)
		(property "Reference" "U218"
			(at -1.4351 2.394712 0)
			(unlocked yes)
			(layer "F.SilkS")
			(effects
				(font
					(size 0.7874 0.5842)
					(thickness 0.1524)
				)
				(justify left)
			)
		)
		(property "Value" ""
			(at 0 0 0)
			(layer "F.Fab")
			(effects
				(font
					(size 1.27 1.27)
				)
			)
		)
		(duplicate_pad_numbers_are_jumpers no)
		(fp_line
			(start -1.733296 -1.549908)
			(end -1.733296 1.549908)
			(stroke
				(width 0.1524)
				(type default)
			)
			(layer "F.SilkS")
		)
		(fp_line
			(start -1.733296 1.549908)
			(end 1.733296 1.549908)
			(stroke
				(width 0.1524)
				(type default)
			)
			(layer "F.SilkS")
		)
		(fp_line
			(start -0.660908 -1.549908)
			(end -1.733296 -1.549908)
			(stroke
				(width 0.1524)
				(type default)
			)
			(layer "F.SilkS")
		)
		(fp_line
			(start 0 -0.889)
			(end -0.660908 -1.549908)
			(stroke
				(width 0.1524)
				(type default)
			)
			(layer "F.SilkS")
		)
		(fp_line
			(start 0.660908 -1.549908)
			(end 0 -0.889)
			(stroke
				(width 0.1524)
				(type default)
			)
			(layer "F.SilkS")
		)
		(fp_line
			(start 1.733296 -1.549908)
			(end 0.660908 -1.549908)
			(stroke
				(width 0.1524)
				(type default)
			)
			(layer "F.SilkS")
		)
		(fp_line
			(start 1.733296 1.549908)
			(end 1.733296 -1.549908)
			(stroke
				(width 0.1524)
				(type default)
			)
			(layer "F.SilkS")
		)
		(fp_poly
			(pts
				(xy -1.172464 -1.626108) (xy -1.426464 -2.134108) (xy -0.918464 -2.134108)
			)
			(stroke
				(width 0)
				(type default)
			)
			(fill yes)
			(layer "F.SilkS")
		)
		(fp_line
			(start -0.849884 -1.549908)
			(end -0.849884 1.549908)
			(stroke
				(width 0.1)
				(type default)
			)
			(layer "F.Fab")
		)
		(fp_line
			(start -0.849884 1.549908)
			(end 0.849884 1.549908)
			(stroke
				(width 0.1)
				(type default)
			)
			(layer "F.Fab")
		)
		(fp_line
			(start 0.849884 -1.549908)
			(end -0.849884 -1.549908)
			(stroke
				(width 0.1)
				(type default)
			)
			(layer "F.Fab")
		)
		(fp_line
			(start 0.849884 1.549908)
			(end 0.849884 -1.549908)
			(stroke
				(width 0.1)
				(type default)
			)
			(layer "F.Fab")
		)
		(fp_poly
			(pts
				(xy -2.4384 -1.20396) (xy -2.4384 -0.69596) (xy -1.9304 -0.94996)
			)
			(stroke
				(width 0)
				(type default)
			)
			(fill yes)
			(layer "F.Fab")
		)
		(pad "1" smd rect
			(at -1.199896 -0.94996 270)
			(size 0.5588 0.8128)
			(layers "F.Cu" "F.Mask" "F.Paste")
			(net "NC_U218_NC1")
		)
		(pad "2" smd rect
			(at -1.199896 0 270)
			(size 0.5588 0.8128)
			(layers "F.Cu" "F.Mask" "F.Paste")
			(net "FM_SYS_THROTTLE_N")
		)
		(pad "3" smd rect
			(at -1.199896 0.94996 270)
			(size 0.5588 0.8128)
			(layers "F.Cu" "F.Mask" "F.Paste")
			(net "GND")
		)
		(pad "4" smd rect
			(at 1.199896 0.94996 270)
			(size 0.5588 0.8128)
			(layers "F.Cu" "F.Mask" "F.Paste")
			(net "OCP_V3_2_PWRBRK_BUFF_N")
		)
		(pad "5" smd rect
			(at 1.199896 -0.94996 270)
			(size 0.5588 0.8128)
			(layers "F.Cu" "F.Mask" "F.Paste")
			(net "P3V3_AUX")
		)
	)
	(footprint ""
		(layer "F.Cu")
		(at 118.999 -435.102 -90)
		(property "Reference" "C1979"
			(at 0 0 270)
			(layer "F.SilkS")
			(hide yes)
			(effects
				(font
					(size 1.27 1.27)
				)
			)
		)
		(property "Value" ""
			(at 0 0 270)
			(layer "F.Fab")
			(effects
				(font
					(size 1.27 1.27)
				)
			)
		)
		(duplicate_pad_numbers_are_jumpers no)
		(fp_line
			(start -0.7874 0.4064)
			(end -0.7874 -0.4064)
			(stroke
				(width 0.1524)
				(type default)
			)
			(layer "F.SilkS")
		)
		(fp_line
			(start 0.7874 0.4064)
			(end -0.7874 0.4064)
			(stroke
				(width 0.1524)
				(type default)
			)
			(layer "F.SilkS")
		)
		(fp_line
			(start -0.7874 -0.4064)
			(end 0.7874 -0.4064)
			(stroke
				(width 0.1524)
				(type default)
			)
			(layer "F.SilkS")
		)
		(fp_line
			(start 0.7874 -0.4064)
			(end 0.7874 0.4064)
			(stroke
				(width 0.1524)
				(type default)
			)
			(layer "F.SilkS")
		)
		(fp_line
			(start -0.67945 0.3048)
			(end -0.67945 -0.305054)
			(stroke
				(width 0.1)
				(type default)
			)
			(layer "F.Fab")
		)
		(fp_line
			(start -0.12065 0.3048)
			(end -0.67945 0.3048)
			(stroke
				(width 0.1)
				(type default)
			)
			(layer "F.Fab")
		)
		(fp_line
			(start 0.120396 0.3048)
			(end 0.120396 0.2794)
			(stroke
				(width 0.1)
				(type default)
			)
			(layer "F.Fab")
		)
		(fp_line
			(start 0.67945 0.3048)
			(end 0.120396 0.3048)
			(stroke
				(width 0.1)
				(type default)
			)
			(layer "F.Fab")
		)
		(fp_line
			(start -0.12065 0.2794)
			(end -0.12065 0.3048)
			(stroke
				(width 0.1)
				(type default)
			)
			(layer "F.Fab")
		)
		(fp_line
			(start 0.120396 0.2794)
			(end -0.12065 0.2794)
			(stroke
				(width 0.1)
				(type default)
			)
			(layer "F.Fab")
		)
		(fp_line
			(start -0.12065 -0.2794)
			(end 0.12065 -0.2794)
			(stroke
				(width 0.1)
				(type default)
			)
			(layer "F.Fab")
		)
		(fp_line
			(start 0.12065 -0.2794)
			(end 0.12065 -0.3048)
			(stroke
				(width 0.1)
				(type default)
			)
			(layer "F.Fab")
		)
		(fp_line
			(start 0.12065 -0.3048)
			(end 0.67945 -0.3048)
			(stroke
				(width 0.1)
				(type default)
			)
			(layer "F.Fab")
		)
		(fp_line
			(start 0.67945 -0.3048)
			(end 0.67945 0.3048)
			(stroke
				(width 0.1)
				(type default)
			)
			(layer "F.Fab")
		)
		(fp_line
			(start -0.67945 -0.305054)
			(end -0.12065 -0.305054)
			(stroke
				(width 0.1)
				(type default)
			)
			(layer "F.Fab")
		)
		(fp_line
			(start -0.12065 -0.305054)
			(end -0.12065 -0.2794)
			(stroke
				(width 0.1)
				(type default)
			)
			(layer "F.Fab")
		)
		(pad "1" smd circle
			(at -0.40005 0 270)
			(size 0 0)
			(layers "F.Cu" "F.Mask" "F.Paste")
			(net "P3V3_AUX")
		)
		(pad "2" smd circle
			(at 0.40005 0 270)
			(size 0 0)
			(layers "F.Cu" "F.Mask" "F.Paste")
			(net "GND")
		)
	)
	(footprint ""
		(layer "F.Cu")
		(at 97.230438 -402.391626)
		(property "Reference" "U45"
			(at -0.31623 -3.169158 0)
			(unlocked yes)
			(layer "F.SilkS")
			(effects
				(font
					(size 0.7874 0.5842)
					(thickness 0.1524)
				)
			)
		)
		(property "Value" ""
			(at 0 0 0)
			(layer "F.Fab")
			(effects
				(font
					(size 1.27 1.27)
				)
			)
		)
		(duplicate_pad_numbers_are_jumpers no)
		(fp_line
			(start -1.03378 -1.284478)
			(end 1.03378 -1.284478)
			(stroke
				(width 0.1524)
				(type default)
			)
			(layer "F.SilkS")
		)
		(fp_line
			(start -1.03378 1.284478)
			(end -1.03378 -1.284478)
			(stroke
				(width 0.1524)
				(type default)
			)
			(layer "F.SilkS")
		)
		(fp_line
			(start 1.03378 -1.284478)
			(end 1.03378 1.284478)
			(stroke
				(width 0.1524)
				(type default)
			)
			(layer "F.SilkS")
		)
		(fp_line
			(start 1.03378 1.284478)
			(end -1.03378 1.284478)
			(stroke
				(width 0.1524)
				(type default)
			)
			(layer "F.SilkS")
		)
		(fp_poly
			(pts
				(xy -1.335278 -1.324102) (xy -2.011426 -1.305306) (xy -1.756156 -1.853692)
			)
			(stroke
				(width 0)
				(type default)
			)
			(fill yes)
			(layer "F.SilkS")
		)
		(fp_line
			(start -0.774954 -1.02489)
			(end 0.774954 -1.02489)
			(stroke
				(width 0.1)
				(type default)
			)
			(layer "F.Fab")
		)
		(fp_line
			(start -0.774954 1.02489)
			(end -0.774954 -1.02489)
			(stroke
				(width 0.1)
				(type default)
			)
			(layer "F.Fab")
		)
		(fp_line
			(start 0.774954 -1.02489)
			(end 0.774954 1.02489)
			(stroke
				(width 0.1)
				(type default)
			)
			(layer "F.Fab")
		)
		(fp_line
			(start 0.774954 1.02489)
			(end -0.774954 1.02489)
			(stroke
				(width 0.1)
				(type default)
			)
			(layer "F.Fab")
		)
		(fp_poly
			(pts
				(xy -1.201674 -0.750062) (xy -1.806702 -0.447548) (xy -1.806702 -1.052576)
			)
			(stroke
				(width 0)
				(type default)
			)
			(fill yes)
			(layer "F.Fab")
		)
		(pad "1" smd rect
			(at -0.64008 -0.750062 90)
			(size 0.3048 0.5334)
			(layers "F.Cu" "F.Mask" "F.Paste")
			(net "SMB_RT_CPU1_P0_ROM_MUX_1D_SCL")
		)
		(pad "2" smd rect
			(at -0.64008 -0.249936 90)
			(size 0.254 0.5334)
			(layers "F.Cu" "F.Mask" "F.Paste")
			(net "SMB_RT_CPU1_P0_ROM_MUX_1D_SDA")
		)
		(pad "3" smd rect
			(at -0.64008 0.249936 90)
			(size 0.254 0.5334)
			(layers "F.Cu" "F.Mask" "F.Paste")
			(net "SMB_RT_CPU1_P0_ROM_MUX_2D_SCL")
		)
		(pad "4" smd rect
			(at -0.64008 0.750062 90)
			(size 0.3048 0.5334)
			(layers "F.Cu" "F.Mask" "F.Paste")
			(net "SMB_RT_CPU1_P0_ROM_MUX_2D_SDA")
		)
		(pad "5" smd rect
			(at 0 0.839978)
			(size 0.3302 0.635)
			(layers "F.Cu" "F.Mask" "F.Paste")
			(net "GND")
		)
		(pad "6" smd rect
			(at 0.64008 0.750062 90)
			(size 0.3048 0.5334)
			(layers "F.Cu" "F.Mask" "F.Paste")
			(net "RT_ROM_MUX1_OE_N")
		)
		(pad "7" smd rect
			(at 0.64008 0.249936 90)
			(size 0.254 0.5334)
			(layers "F.Cu" "F.Mask" "F.Paste")
			(net "SMB_RT_CPU1_P0_ROM_R_SDA")
		)
		(pad "8" smd rect
			(at 0.64008 -0.249936 90)
			(size 0.254 0.5334)
			(layers "F.Cu" "F.Mask" "F.Paste")
			(net "SMB_RT_CPU1_P0_ROM_R_SCL")
		)
		(pad "9" smd rect
			(at 0.64008 -0.750062 90)
			(size 0.3048 0.5334)
			(layers "F.Cu" "F.Mask" "F.Paste")
			(net "FM_SMB_RT_ROM_MUX1_SEL")
		)
		(pad "10" smd rect
			(at 0 -0.839978)
			(size 0.3302 0.635)
			(layers "F.Cu" "F.Mask" "F.Paste")
			(net "P3V3_AUX")
		)
	)
	(footprint ""
		(layer "F.Cu")
		(at 259.131308 -137.103104 -90)
		(property "Reference" "C1105"
			(at 0 0 270)
			(layer "F.SilkS")
			(hide yes)
			(effects
				(font
					(size 1.27 1.27)
				)
			)
		)
		(property "Value" ""
			(at 0 0 270)
			(layer "F.Fab")
			(effects
				(font
					(size 1.27 1.27)
				)
			)
		)
		(duplicate_pad_numbers_are_jumpers no)
		(fp_line
			(start -0.7874 0.4064)
			(end -0.7874 -0.4064)
			(stroke
				(width 0.1524)
				(type default)
			)
			(layer "F.SilkS")
		)
		(fp_line
			(start 0.7874 0.4064)
			(end -0.7874 0.4064)
			(stroke
				(width 0.1524)
				(type default)
			)
			(layer "F.SilkS")
		)
		(fp_line
			(start -0.7874 -0.4064)
			(end 0.7874 -0.4064)
			(stroke
				(width 0.1524)
				(type default)
			)
			(layer "F.SilkS")
		)
		(fp_line
			(start 0.7874 -0.4064)
			(end 0.7874 0.4064)
			(stroke
				(width 0.1524)
				(type default)
			)
			(layer "F.SilkS")
		)
		(fp_line
			(start -0.67945 0.3048)
			(end -0.67945 -0.305054)
			(stroke
				(width 0.1)
				(type default)
			)
			(layer "F.Fab")
		)
		(fp_line
			(start -0.12065 0.3048)
			(end -0.67945 0.3048)
			(stroke
				(width 0.1)
				(type default)
			)
			(layer "F.Fab")
		)
		(fp_line
			(start 0.120396 0.3048)
			(end 0.120396 0.2794)
			(stroke
				(width 0.1)
				(type default)
			)
			(layer "F.Fab")
		)
		(fp_line
			(start 0.67945 0.3048)
			(end 0.120396 0.3048)
			(stroke
				(width 0.1)
				(type default)
			)
			(layer "F.Fab")
		)
		(fp_line
			(start -0.12065 0.2794)
			(end -0.12065 0.3048)
			(stroke
				(width 0.1)
				(type default)
			)
			(layer "F.Fab")
		)
		(fp_line
			(start 0.120396 0.2794)
			(end -0.12065 0.2794)
			(stroke
				(width 0.1)
				(type default)
			)
			(layer "F.Fab")
		)
		(fp_line
			(start -0.12065 -0.2794)
			(end 0.12065 -0.2794)
			(stroke
				(width 0.1)
				(type default)
			)
			(layer "F.Fab")
		)
		(fp_line
			(start 0.12065 -0.2794)
			(end 0.12065 -0.3048)
			(stroke
				(width 0.1)
				(type default)
			)
			(layer "F.Fab")
		)
		(fp_line
			(start 0.12065 -0.3048)
			(end 0.67945 -0.3048)
			(stroke
				(width 0.1)
				(type default)
			)
			(layer "F.Fab")
		)
		(fp_line
			(start 0.67945 -0.3048)
			(end 0.67945 0.3048)
			(stroke
				(width 0.1)
				(type default)
			)
			(layer "F.Fab")
		)
		(fp_line
			(start -0.67945 -0.305054)
			(end -0.12065 -0.305054)
			(stroke
				(width 0.1)
				(type default)
			)
			(layer "F.Fab")
		)
		(fp_line
			(start -0.12065 -0.305054)
			(end -0.12065 -0.2794)
			(stroke
				(width 0.1)
				(type default)
			)
			(layer "F.Fab")
		)
		(pad "1" smd circle
			(at -0.40005 0 270)
			(size 0 0)
			(layers "F.Cu" "F.Mask" "F.Paste")
			(net "P3V3_AUX")
		)
		(pad "2" smd circle
			(at 0.40005 0 270)
			(size 0 0)
			(layers "F.Cu" "F.Mask" "F.Paste")
			(net "GND")
		)
	)
	(footprint ""
		(layer "F.Cu")
		(at 166.929308 -349.265494)
		(property "Reference" "PC638"
			(at 0 0 0)
			(layer "F.SilkS")
			(hide yes)
			(effects
				(font
					(size 1.27 1.27)
				)
			)
		)
		(property "Value" ""
			(at 0 0 0)
			(layer "F.Fab")
			(effects
				(font
					(size 1.27 1.27)
				)
			)
		)
		(duplicate_pad_numbers_are_jumpers no)
		(fp_line
			(start -0.7874 -0.4064)
			(end 0.7874 -0.4064)
			(stroke
				(width 0.1524)
				(type default)
			)
			(layer "F.SilkS")
		)
		(fp_line
			(start -0.7874 0.4064)
			(end -0.7874 -0.4064)
			(stroke
				(width 0.1524)
				(type default)
			)
			(layer "F.SilkS")
		)
		(fp_line
			(start 0.7874 -0.4064)
			(end 0.7874 0.4064)
			(stroke
				(width 0.1524)
				(type default)
			)
			(layer "F.SilkS")
		)
		(fp_line
			(start 0.7874 0.4064)
			(end -0.7874 0.4064)
			(stroke
				(width 0.1524)
				(type default)
			)
			(layer "F.SilkS")
		)
		(fp_line
			(start -0.67945 -0.305054)
			(end -0.12065 -0.305054)
			(stroke
				(width 0.1)
				(type default)
			)
			(layer "F.Fab")
		)
		(fp_line
			(start -0.67945 0.3048)
			(end -0.67945 -0.305054)
			(stroke
				(width 0.1)
				(type default)
			)
			(layer "F.Fab")
		)
		(fp_line
			(start -0.12065 -0.305054)
			(end -0.12065 -0.2794)
			(stroke
				(width 0.1)
				(type default)
			)
			(layer "F.Fab")
		)
		(fp_line
			(start -0.12065 -0.2794)
			(end 0.12065 -0.2794)
			(stroke
				(width 0.1)
				(type default)
			)
			(layer "F.Fab")
		)
		(fp_line
			(start -0.12065 0.2794)
			(end -0.12065 0.3048)
			(stroke
				(width 0.1)
				(type default)
			)
			(layer "F.Fab")
		)
		(fp_line
			(start -0.12065 0.3048)
			(end -0.67945 0.3048)
			(stroke
				(width 0.1)
				(type default)
			)
			(layer "F.Fab")
		)
		(fp_line
			(start 0.120396 0.2794)
			(end -0.12065 0.2794)
			(stroke
				(width 0.1)
				(type default)
			)
			(layer "F.Fab")
		)
		(fp_line
			(start 0.120396 0.3048)
			(end 0.120396 0.2794)
			(stroke
				(width 0.1)
				(type default)
			)
			(layer "F.Fab")
		)
		(fp_line
			(start 0.12065 -0.3048)
			(end 0.67945 -0.3048)
			(stroke
				(width 0.1)
				(type default)
			)
			(layer "F.Fab")
		)
		(fp_line
			(start 0.12065 -0.2794)
			(end 0.12065 -0.3048)
			(stroke
				(width 0.1)
				(type default)
			)
			(layer "F.Fab")
		)
		(fp_line
			(start 0.67945 -0.3048)
			(end 0.67945 0.3048)
			(stroke
				(width 0.1)
				(type default)
			)
			(layer "F.Fab")
		)
		(fp_line
			(start 0.67945 0.3048)
			(end 0.120396 0.3048)
			(stroke
				(width 0.1)
				(type default)
			)
			(layer "F.Fab")
		)
		(pad "1" smd circle
			(at -0.40005 0)
			(size 0 0)
			(layers "F.Cu" "F.Mask" "F.Paste")
			(net "PVDD11_S3_P1_VMON")
		)
		(pad "2" smd circle
			(at 0.40005 0)
			(size 0 0)
			(layers "F.Cu" "F.Mask" "F.Paste")
			(net "GND")
		)
	)
	(footprint ""
		(layer "F.Cu")
		(at 316.021466 -416.899344 -90)
		(property "Reference" "C6510"
			(at 0 0 270)
			(layer "F.SilkS")
			(hide yes)
			(effects
				(font
					(size 1.27 1.27)
				)
			)
		)
		(property "Value" ""
			(at 0 0 270)
			(layer "F.Fab")
			(effects
				(font
					(size 1.27 1.27)
				)
			)
		)
		(duplicate_pad_numbers_are_jumpers no)
		(fp_line
			(start -0.299974 0.150114)
			(end -0.299974 -0.150114)
			(stroke
				(width 0.1)
				(type default)
			)
			(layer "F.Fab")
		)
		(fp_line
			(start 0.299974 0.150114)
			(end -0.299974 0.150114)
			(stroke
				(width 0.1)
				(type default)
			)
			(layer "F.Fab")
		)
		(fp_line
			(start -0.299974 -0.150114)
			(end 0.299974 -0.150114)
			(stroke
				(width 0.1)
				(type default)
			)
			(layer "F.Fab")
		)
		(fp_line
			(start 0.299974 -0.150114)
			(end 0.299974 0.150114)
			(stroke
				(width 0.1)
				(type default)
			)
			(layer "F.Fab")
		)
		(pad "1" smd rect
			(at -0.2667 0 270)
			(size 0.3048 0.381)
			(layers "F.Cu" "F.Mask" "F.Paste")
			(net "P5E_CPU0_P0_TX_BUF_C_DN<4>")
		)
		(pad "2" smd rect
			(at 0.2667 0 270)
			(size 0.3048 0.381)
			(layers "F.Cu" "F.Mask" "F.Paste")
			(net "P5E_CPU0_P0_TX_BUF_DN<4>")
		)
	)
	(footprint ""
		(layer "F.Cu")
		(at 454.847452 -21.302218 90)
		(property "Reference" "R3799"
			(at 0 0 90)
			(layer "F.SilkS")
			(hide yes)
			(effects
				(font
					(size 1.27 1.27)
				)
			)
		)
		(property "Value" ""
			(at 0 0 90)
			(layer "F.Fab")
			(effects
				(font
					(size 1.27 1.27)
				)
			)
		)
		(duplicate_pad_numbers_are_jumpers no)
		(fp_line
			(start 0.7874 -0.4064)
			(end 0.7874 0.4064)
			(stroke
				(width 0.1524)
				(type default)
			)
			(layer "F.SilkS")
		)
		(fp_line
			(start -0.7874 -0.4064)
			(end 0.7874 -0.4064)
			(stroke
				(width 0.1524)
				(type default)
			)
			(layer "F.SilkS")
		)
		(fp_line
			(start 0.7874 0.4064)
			(end -0.7874 0.4064)
			(stroke
				(width 0.1524)
				(type default)
			)
			(layer "F.SilkS")
		)
		(fp_line
			(start -0.7874 0.4064)
			(end -0.7874 -0.4064)
			(stroke
				(width 0.1524)
				(type default)
			)
			(layer "F.SilkS")
		)
		(fp_line
			(start -0.12065 -0.305054)
			(end -0.12065 -0.2794)
			(stroke
				(width 0.1)
				(type default)
			)
			(layer "F.Fab")
		)
		(fp_line
			(start -0.67945 -0.305054)
			(end -0.12065 -0.305054)
			(stroke
				(width 0.1)
				(type default)
			)
			(layer "F.Fab")
		)
		(fp_line
			(start 0.67945 -0.3048)
			(end 0.67945 0.3048)
			(stroke
				(width 0.1)
				(type default)
			)
			(layer "F.Fab")
		)
		(fp_line
			(start 0.12065 -0.3048)
			(end 0.67945 -0.3048)
			(stroke
				(width 0.1)
				(type default)
			)
			(layer "F.Fab")
		)
		(fp_line
			(start 0.12065 -0.2794)
			(end 0.12065 -0.3048)
			(stroke
				(width 0.1)
				(type default)
			)
			(layer "F.Fab")
		)
		(fp_line
			(start -0.12065 -0.2794)
			(end 0.12065 -0.2794)
			(stroke
				(width 0.1)
				(type default)
			)
			(layer "F.Fab")
		)
		(fp_line
			(start 0.120396 0.2794)
			(end -0.12065 0.2794)
			(stroke
				(width 0.1)
				(type default)
			)
			(layer "F.Fab")
		)
		(fp_line
			(start -0.12065 0.2794)
			(end -0.12065 0.3048)
			(stroke
				(width 0.1)
				(type default)
			)
			(layer "F.Fab")
		)
		(fp_line
			(start 0.67945 0.3048)
			(end 0.120396 0.3048)
			(stroke
				(width 0.1)
				(type default)
			)
			(layer "F.Fab")
		)
		(fp_line
			(start 0.120396 0.3048)
			(end 0.120396 0.2794)
			(stroke
				(width 0.1)
				(type default)
			)
			(layer "F.Fab")
		)
		(fp_line
			(start -0.12065 0.3048)
			(end -0.67945 0.3048)
			(stroke
				(width 0.1)
				(type default)
			)
			(layer "F.Fab")
		)
		(fp_line
			(start -0.67945 0.3048)
			(end -0.67945 -0.305054)
			(stroke
				(width 0.1)
				(type default)
			)
			(layer "F.Fab")
		)
		(pad "1" smd circle
			(at -0.40005 0 90)
			(size 0 0)
			(layers "F.Cu" "F.Mask" "F.Paste")
			(net "P3V3_AUX")
		)
		(pad "2" smd circle
			(at 0.40005 0 90)
			(size 0 0)
			(layers "F.Cu" "F.Mask" "F.Paste")
			(net "P12V_OCP_FAULT_1")
		)
	)
	(footprint ""
		(layer "F.Cu")
		(at 164.128704 -51.81473 -90)
		(property "Reference" "C1921"
			(at 0 0 270)
			(layer "F.SilkS")
			(hide yes)
			(effects
				(font
					(size 1.27 1.27)
				)
			)
		)
		(property "Value" ""
			(at 0 0 270)
			(layer "F.Fab")
			(effects
				(font
					(size 1.27 1.27)
				)
			)
		)
		(duplicate_pad_numbers_are_jumpers no)
		(fp_line
			(start -1.2954 0.5842)
			(end -1.2954 -0.5842)
			(stroke
				(width 0.1524)
				(type default)
			)
			(layer "F.SilkS")
		)
		(fp_line
			(start 1.2954 0.5842)
			(end -1.2954 0.5842)
			(stroke
				(width 0.1524)
				(type default)
			)
			(layer "F.SilkS")
		)
		(fp_line
			(start -1.2954 -0.5842)
			(end 1.2954 -0.5842)
			(stroke
				(width 0.1524)
				(type default)
			)
			(layer "F.SilkS")
		)
		(fp_line
			(start 1.2954 -0.5842)
			(end 1.2954 0.5842)
			(stroke
				(width 0.1524)
				(type default)
			)
			(layer "F.SilkS")
		)
		(fp_line
			(start -0.8636 0.4572)
			(end -0.8636 0.4064)
			(stroke
				(width 0.1)
				(type default)
			)
			(layer "F.Fab")
		)
		(fp_line
			(start 0.8636 0.4572)
			(end -0.8636 0.4572)
			(stroke
				(width 0.1)
				(type default)
			)
			(layer "F.Fab")
		)
		(fp_line
			(start -1.1938 0.4064)
			(end -1.1938 -0.4064)
			(stroke
				(width 0.1)
				(type default)
			)
			(layer "F.Fab")
		)
		(fp_line
			(start -0.8636 0.4064)
			(end -1.1938 0.4064)
			(stroke
				(width 0.1)
				(type default)
			)
			(layer "F.Fab")
		)
		(fp_line
			(start 0.8636 0.4064)
			(end 0.8636 0.4572)
			(stroke
				(width 0.1)
				(type default)
			)
			(layer "F.Fab")
		)
		(fp_line
			(start 1.1938 0.4064)
			(end 0.8636 0.4064)
			(stroke
				(width 0.1)
				(type default)
			)
			(layer "F.Fab")
		)
		(fp_line
			(start -1.1938 -0.4064)
			(end -0.8636 -0.4064)
			(stroke
				(width 0.1)
				(type default)
			)
			(layer "F.Fab")
		)
		(fp_line
			(start -0.8636 -0.4064)
			(end -0.8636 -0.4572)
			(stroke
				(width 0.1)
				(type default)
			)
			(layer "F.Fab")
		)
		(fp_line
			(start 0.8636 -0.4064)
			(end 1.1938 -0.4064)
			(stroke
				(width 0.1)
				(type default)
			)
			(layer "F.Fab")
		)
		(fp_line
			(start 1.1938 -0.4064)
			(end 1.1938 0.4064)
			(stroke
				(width 0.1)
				(type default)
			)
			(layer "F.Fab")
		)
		(fp_line
			(start -0.8636 -0.4572)
			(end 0.8636 -0.4572)
			(stroke
				(width 0.1)
				(type default)
			)
			(layer "F.Fab")
		)
		(fp_line
			(start 0.8636 -0.4572)
			(end 0.8636 -0.4064)
			(stroke
				(width 0.1)
				(type default)
			)
			(layer "F.Fab")
		)
		(pad "1" smd rect
			(at -0.7366 0 180)
			(size 0.7112 0.8128)
			(layers "F.Cu" "F.Mask" "F.Paste")
			(net "P3V3_M2_0")
		)
		(pad "2" smd rect
			(at 0.7366 0 180)
			(size 0.7112 0.8128)
			(layers "F.Cu" "F.Mask" "F.Paste")
			(net "GND")
		)
	)
	(footprint ""
		(layer "F.Cu")
		(at 44.21378 -125.24486 -90)
		(property "Reference" "R1481"
			(at -0.3302 2.79781 90)
			(unlocked yes)
			(layer "F.SilkS")
			(effects
				(font
					(size 0.7874 0.5842)
					(thickness 0.1524)
				)
				(justify left)
			)
		)
		(property "Value" ""
			(at 0 0 270)
			(layer "F.Fab")
			(effects
				(font
					(size 1.27 1.27)
				)
			)
		)
		(duplicate_pad_numbers_are_jumpers no)
		(fp_line
			(start -4.18973 1.700022)
			(end 4.18973 1.700022)
			(stroke
				(width 0.1524)
				(type default)
			)
			(layer "F.SilkS")
		)
		(fp_line
			(start 4.18973 1.700022)
			(end 4.18973 -1.700022)
			(stroke
				(width 0.1524)
				(type default)
			)
			(layer "F.SilkS")
		)
		(fp_line
			(start -4.18973 -1.700022)
			(end -4.18973 1.700022)
			(stroke
				(width 0.1524)
				(type default)
			)
			(layer "F.SilkS")
		)
		(fp_line
			(start 4.18973 -1.700022)
			(end -4.18973 -1.700022)
			(stroke
				(width 0.1524)
				(type default)
			)
			(layer "F.SilkS")
		)
		(fp_line
			(start -3.24993 1.700022)
			(end 3.24993 1.700022)
			(stroke
				(width 0.1)
				(type default)
			)
			(layer "F.Fab")
		)
		(fp_line
			(start 3.24993 1.700022)
			(end 3.24993 -1.700022)
			(stroke
				(width 0.1)
				(type default)
			)
			(layer "F.Fab")
		)
		(fp_line
			(start -3.24993 -1.700022)
			(end -3.24993 1.700022)
			(stroke
				(width 0.1)
				(type default)
			)
			(layer "F.Fab")
		)
		(fp_line
			(start 3.24993 -1.700022)
			(end -3.24993 -1.700022)
			(stroke
				(width 0.1)
				(type default)
			)
			(layer "F.Fab")
		)
		(pad "1" smd rect
			(at -2.975102 0 270)
			(size 2.159 2.921)
			(layers "F.Cu" "F.Mask" "F.Paste")
			(net "P3V3_AUX")
		)
		(pad "2" smd rect
			(at 2.975102 0 270)
			(size 2.159 2.921)
			(layers "F.Cu" "F.Mask" "F.Paste")
			(net "P3V3_AUX_DSC")
		)
	)
	(footprint ""
		(layer "F.Cu")
		(at 344.955876 -70.098412 90)
		(property "Reference" "D84"
			(at -3.934714 -0.691642 90)
			(unlocked yes)
			(layer "F.SilkS")
			(effects
				(font
					(size 0.7874 0.5842)
					(thickness 0.1524)
				)
				(justify left)
			)
		)
		(property "Value" ""
			(at 0 0 90)
			(layer "F.Fab")
			(effects
				(font
					(size 1.27 1.27)
				)
			)
		)
		(duplicate_pad_numbers_are_jumpers no)
		(fp_line
			(start 1.16078 -0.4826)
			(end 1.16078 0.4826)
			(stroke
				(width 0.1524)
				(type default)
			)
			(layer "F.SilkS")
		)
		(fp_line
			(start 1.03378 -0.4826)
			(end 1.03378 0.4826)
			(stroke
				(width 0.1524)
				(type default)
			)
			(layer "F.SilkS")
		)
		(fp_line
			(start 0.90678 -0.4826)
			(end 0.90678 0.4826)
			(stroke
				(width 0.1524)
				(type default)
			)
			(layer "F.SilkS")
		)
		(fp_line
			(start -0.64008 -0.4826)
			(end 1.16078 -0.4826)
			(stroke
				(width 0.1524)
				(type default)
			)
			(layer "F.SilkS")
		)
		(fp_line
			(start -0.79248 -0.4826)
			(end 1.03378 -0.4826)
			(stroke
				(width 0.1524)
				(type default)
			)
			(layer "F.SilkS")
		)
		(fp_line
			(start -0.89408 -0.4826)
			(end 0.90678 -0.4826)
			(stroke
				(width 0.1524)
				(type default)
			)
			(layer "F.SilkS")
		)
		(fp_line
			(start 1.16078 0.4826)
			(end -0.64008 0.4826)
			(stroke
				(width 0.1524)
				(type default)
			)
			(layer "F.SilkS")
		)
		(fp_line
			(start 1.03378 0.4826)
			(end -0.79248 0.4826)
			(stroke
				(width 0.1524)
				(type default)
			)
			(layer "F.SilkS")
		)
		(fp_line
			(start 0.90678 0.4826)
			(end -0.90678 0.4826)
			(stroke
				(width 0.1524)
				(type default)
			)
			(layer "F.SilkS")
		)
		(fp_line
			(start -0.90678 0.4826)
			(end -0.90678 -0.4699)
			(stroke
				(width 0.1524)
				(type default)
			)
			(layer "F.SilkS")
		)
		(fp_line
			(start 0.499872 -0.249936)
			(end 0.499872 0.249936)
			(stroke
				(width 0.1)
				(type default)
			)
			(layer "F.Fab")
		)
		(fp_line
			(start -0.499872 -0.249936)
			(end 0.499872 -0.249936)
			(stroke
				(width 0.1)
				(type default)
			)
			(layer "F.Fab")
		)
		(fp_line
			(start 0.499872 0.249936)
			(end -0.499872 0.249936)
			(stroke
				(width 0.1)
				(type default)
			)
			(layer "F.Fab")
		)
		(fp_line
			(start -0.499872 0.249936)
			(end -0.499872 -0.249936)
			(stroke
				(width 0.1)
				(type default)
			)
			(layer "F.Fab")
		)
		(pad "A" smd rect
			(at -0.47498 0 90)
			(size 0.6096 0.7112)
			(layers "F.Cu" "F.Mask" "F.Paste")
			(net "LED_PWRGD_PVDD11_S3_P1_R")
		)
		(pad "C" smd rect
			(at 0.47498 0 90)
			(size 0.6096 0.7112)
			(layers "F.Cu" "F.Mask" "F.Paste")
			(net "LED_PWRGD_PVDD11_S3_P1_D")
		)
	)
	(footprint ""
		(layer "F.Cu")
		(at 125.512576 -55.175658 90)
		(property "Reference" "R6111"
			(at 0 0 90)
			(layer "F.SilkS")
			(hide yes)
			(effects
				(font
					(size 1.27 1.27)
				)
			)
		)
		(property "Value" ""
			(at 0 0 90)
			(layer "F.Fab")
			(effects
				(font
					(size 1.27 1.27)
				)
			)
		)
		(duplicate_pad_numbers_are_jumpers no)
		(fp_line
			(start 0.7874 -0.4064)
			(end 0.7874 0.4064)
			(stroke
				(width 0.1524)
				(type default)
			)
			(layer "F.SilkS")
		)
		(fp_line
			(start -0.7874 -0.4064)
			(end 0.7874 -0.4064)
			(stroke
				(width 0.1524)
				(type default)
			)
			(layer "F.SilkS")
		)
		(fp_line
			(start 0.7874 0.4064)
			(end -0.7874 0.4064)
			(stroke
				(width 0.1524)
				(type default)
			)
			(layer "F.SilkS")
		)
		(fp_line
			(start -0.7874 0.4064)
			(end -0.7874 -0.4064)
			(stroke
				(width 0.1524)
				(type default)
			)
			(layer "F.SilkS")
		)
		(fp_line
			(start -0.12065 -0.305054)
			(end -0.12065 -0.2794)
			(stroke
				(width 0.1)
				(type default)
			)
			(layer "F.Fab")
		)
		(fp_line
			(start -0.67945 -0.305054)
			(end -0.12065 -0.305054)
			(stroke
				(width 0.1)
				(type default)
			)
			(layer "F.Fab")
		)
		(fp_line
			(start 0.67945 -0.3048)
			(end 0.67945 0.3048)
			(stroke
				(width 0.1)
				(type default)
			)
			(layer "F.Fab")
		)
		(fp_line
			(start 0.12065 -0.3048)
			(end 0.67945 -0.3048)
			(stroke
				(width 0.1)
				(type default)
			)
			(layer "F.Fab")
		)
		(fp_line
			(start 0.12065 -0.2794)
			(end 0.12065 -0.3048)
			(stroke
				(width 0.1)
				(type default)
			)
			(layer "F.Fab")
		)
		(fp_line
			(start -0.12065 -0.2794)
			(end 0.12065 -0.2794)
			(stroke
				(width 0.1)
				(type default)
			)
			(layer "F.Fab")
		)
		(fp_line
			(start 0.120396 0.2794)
			(end -0.12065 0.2794)
			(stroke
				(width 0.1)
				(type default)
			)
			(layer "F.Fab")
		)
		(fp_line
			(start -0.12065 0.2794)
			(end -0.12065 0.3048)
			(stroke
				(width 0.1)
				(type default)
			)
			(layer "F.Fab")
		)
		(fp_line
			(start 0.67945 0.3048)
			(end 0.120396 0.3048)
			(stroke
				(width 0.1)
				(type default)
			)
			(layer "F.Fab")
		)
		(fp_line
			(start 0.120396 0.3048)
			(end 0.120396 0.2794)
			(stroke
				(width 0.1)
				(type default)
			)
			(layer "F.Fab")
		)
		(fp_line
			(start -0.12065 0.3048)
			(end -0.67945 0.3048)
			(stroke
				(width 0.1)
				(type default)
			)
			(layer "F.Fab")
		)
		(fp_line
			(start -0.67945 0.3048)
			(end -0.67945 -0.305054)
			(stroke
				(width 0.1)
				(type default)
			)
			(layer "F.Fab")
		)
		(pad "1" smd circle
			(at -0.40005 0 90)
			(size 0 0)
			(layers "F.Cu" "F.Mask" "F.Paste")
			(net "JTAG_TDO_R1")
		)
		(pad "2" smd circle
			(at 0.40005 0 90)
			(size 0 0)
			(layers "F.Cu" "F.Mask" "F.Paste")
			(net "JTAG_TDO")
		)
	)
	(footprint ""
		(layer "F.Cu")
		(at 329.150472 -400.903694)
		(property "Reference" "L14"
			(at -2.3876 -2.969768 0)
			(unlocked yes)
			(layer "F.SilkS")
			(effects
				(font
					(size 0.7874 0.5842)
					(thickness 0.1524)
				)
				(justify left)
			)
		)
		(property "Value" ""
			(at 0 0 0)
			(layer "F.Fab")
			(effects
				(font
					(size 1.27 1.27)
				)
			)
		)
		(duplicate_pad_numbers_are_jumpers no)
		(fp_line
			(start -2.249932 -2.249932)
			(end 2.249932 -2.249932)
			(stroke
				(width 0.1524)
				(type default)
			)
			(layer "F.SilkS")
		)
		(fp_line
			(start -2.249932 -1.3843)
			(end -2.249932 -2.249932)
			(stroke
				(width 0.1524)
				(type default)
			)
			(layer "F.SilkS")
		)
		(fp_line
			(start -2.249932 2.249932)
			(end -2.249932 1.3843)
			(stroke
				(width 0.1524)
				(type default)
			)
			(layer "F.SilkS")
		)
		(fp_line
			(start 2.249932 -2.249932)
			(end 2.249932 -1.3843)
			(stroke
				(width 0.1524)
				(type default)
			)
			(layer "F.SilkS")
		)
		(fp_line
			(start 2.249932 1.3843)
			(end 2.249932 2.249932)
			(stroke
				(width 0.1524)
				(type default)
			)
			(layer "F.SilkS")
		)
		(fp_line
			(start 2.249932 2.249932)
			(end -2.249932 2.249932)
			(stroke
				(width 0.1524)
				(type default)
			)
			(layer "F.SilkS")
		)
		(fp_line
			(start -2.249932 -2.249932)
			(end 2.249932 -2.249932)
			(stroke
				(width 0.1)
				(type default)
			)
			(layer "F.Fab")
		)
		(fp_line
			(start -2.249932 2.249932)
			(end -2.249932 -2.249932)
			(stroke
				(width 0.1)
				(type default)
			)
			(layer "F.Fab")
		)
		(fp_line
			(start 2.249932 -2.249932)
			(end 2.249932 2.249932)
			(stroke
				(width 0.1)
				(type default)
			)
			(layer "F.Fab")
		)
		(fp_line
			(start 2.249932 2.249932)
			(end -2.249932 2.249932)
			(stroke
				(width 0.1)
				(type default)
			)
			(layer "F.Fab")
		)
		(pad "1" smd rect
			(at -1.82499 0)
			(size 1.0668 2.5146)
			(layers "F.Cu" "F.Mask" "F.Paste")
			(net "P0V9_CPU0_RT_2D")
		)
		(pad "2" smd rect
			(at 1.82499 0)
			(size 1.0668 2.5146)
			(layers "F.Cu" "F.Mask" "F.Paste")
			(net "P0V9_CPU0_RT1_2A")
		)
	)
	(footprint ""
		(layer "F.Cu")
		(at 347.4593 -15.979394 90)
		(property "Reference" "R1208"
			(at 0 0 90)
			(layer "F.SilkS")
			(hide yes)
			(effects
				(font
					(size 1.27 1.27)
				)
			)
		)
		(property "Value" ""
			(at 0 0 90)
			(layer "F.Fab")
			(effects
				(font
					(size 1.27 1.27)
				)
			)
		)
		(duplicate_pad_numbers_are_jumpers no)
		(fp_line
			(start 0.7874 -0.4064)
			(end 0.7874 0.4064)
			(stroke
				(width 0.1524)
				(type default)
			)
			(layer "F.SilkS")
		)
		(fp_line
			(start -0.7874 -0.4064)
			(end 0.7874 -0.4064)
			(stroke
				(width 0.1524)
				(type default)
			)
			(layer "F.SilkS")
		)
		(fp_line
			(start 0.7874 0.4064)
			(end -0.7874 0.4064)
			(stroke
				(width 0.1524)
				(type default)
			)
			(layer "F.SilkS")
		)
		(fp_line
			(start -0.7874 0.4064)
			(end -0.7874 -0.4064)
			(stroke
				(width 0.1524)
				(type default)
			)
			(layer "F.SilkS")
		)
		(fp_line
			(start -0.12065 -0.305054)
			(end -0.12065 -0.2794)
			(stroke
				(width 0.1)
				(type default)
			)
			(layer "F.Fab")
		)
		(fp_line
			(start -0.67945 -0.305054)
			(end -0.12065 -0.305054)
			(stroke
				(width 0.1)
				(type default)
			)
			(layer "F.Fab")
		)
		(fp_line
			(start 0.67945 -0.3048)
			(end 0.67945 0.3048)
			(stroke
				(width 0.1)
				(type default)
			)
			(layer "F.Fab")
		)
		(fp_line
			(start 0.12065 -0.3048)
			(end 0.67945 -0.3048)
			(stroke
				(width 0.1)
				(type default)
			)
			(layer "F.Fab")
		)
		(fp_line
			(start 0.12065 -0.2794)
			(end 0.12065 -0.3048)
			(stroke
				(width 0.1)
				(type default)
			)
			(layer "F.Fab")
		)
		(fp_line
			(start -0.12065 -0.2794)
			(end 0.12065 -0.2794)
			(stroke
				(width 0.1)
				(type default)
			)
			(layer "F.Fab")
		)
		(fp_line
			(start 0.120396 0.2794)
			(end -0.12065 0.2794)
			(stroke
				(width 0.1)
				(type default)
			)
			(layer "F.Fab")
		)
		(fp_line
			(start -0.12065 0.2794)
			(end -0.12065 0.3048)
			(stroke
				(width 0.1)
				(type default)
			)
			(layer "F.Fab")
		)
		(fp_line
			(start 0.67945 0.3048)
			(end 0.120396 0.3048)
			(stroke
				(width 0.1)
				(type default)
			)
			(layer "F.Fab")
		)
		(fp_line
			(start 0.120396 0.3048)
			(end 0.120396 0.2794)
			(stroke
				(width 0.1)
				(type default)
			)
			(layer "F.Fab")
		)
		(fp_line
			(start -0.12065 0.3048)
			(end -0.67945 0.3048)
			(stroke
				(width 0.1)
				(type default)
			)
			(layer "F.Fab")
		)
		(fp_line
			(start -0.67945 0.3048)
			(end -0.67945 -0.305054)
			(stroke
				(width 0.1)
				(type default)
			)
			(layer "F.Fab")
		)
		(pad "1" smd circle
			(at -0.40005 0 90)
			(size 0 0)
			(layers "F.Cu" "F.Mask" "F.Paste")
			(net "PU_P12V_ALL_PWROK_LED")
		)
		(pad "2" smd circle
			(at 0.40005 0 90)
			(size 0 0)
			(layers "F.Cu" "F.Mask" "F.Paste")
			(net "P5V_AUX")
		)
	)
	(footprint ""
		(layer "F.Cu")
		(at 157.88259 -95.517208 90)
		(property "Reference" "R3304"
			(at 0 0 90)
			(layer "F.SilkS")
			(hide yes)
			(effects
				(font
					(size 1.27 1.27)
				)
			)
		)
		(property "Value" ""
			(at 0 0 90)
			(layer "F.Fab")
			(effects
				(font
					(size 1.27 1.27)
				)
			)
		)
		(duplicate_pad_numbers_are_jumpers no)
		(fp_line
			(start 0.7874 -0.4064)
			(end 0.7874 0.4064)
			(stroke
				(width 0.1524)
				(type default)
			)
			(layer "F.SilkS")
		)
		(fp_line
			(start -0.7874 -0.4064)
			(end 0.7874 -0.4064)
			(stroke
				(width 0.1524)
				(type default)
			)
			(layer "F.SilkS")
		)
		(fp_line
			(start 0.7874 0.4064)
			(end -0.7874 0.4064)
			(stroke
				(width 0.1524)
				(type default)
			)
			(layer "F.SilkS")
		)
		(fp_line
			(start -0.7874 0.4064)
			(end -0.7874 -0.4064)
			(stroke
				(width 0.1524)
				(type default)
			)
			(layer "F.SilkS")
		)
		(fp_line
			(start -0.12065 -0.305054)
			(end -0.12065 -0.2794)
			(stroke
				(width 0.1)
				(type default)
			)
			(layer "F.Fab")
		)
		(fp_line
			(start -0.67945 -0.305054)
			(end -0.12065 -0.305054)
			(stroke
				(width 0.1)
				(type default)
			)
			(layer "F.Fab")
		)
		(fp_line
			(start 0.67945 -0.3048)
			(end 0.67945 0.3048)
			(stroke
				(width 0.1)
				(type default)
			)
			(layer "F.Fab")
		)
		(fp_line
			(start 0.12065 -0.3048)
			(end 0.67945 -0.3048)
			(stroke
				(width 0.1)
				(type default)
			)
			(layer "F.Fab")
		)
		(fp_line
			(start 0.12065 -0.2794)
			(end 0.12065 -0.3048)
			(stroke
				(width 0.1)
				(type default)
			)
			(layer "F.Fab")
		)
		(fp_line
			(start -0.12065 -0.2794)
			(end 0.12065 -0.2794)
			(stroke
				(width 0.1)
				(type default)
			)
			(layer "F.Fab")
		)
		(fp_line
			(start 0.120396 0.2794)
			(end -0.12065 0.2794)
			(stroke
				(width 0.1)
				(type default)
			)
			(layer "F.Fab")
		)
		(fp_line
			(start -0.12065 0.2794)
			(end -0.12065 0.3048)
			(stroke
				(width 0.1)
				(type default)
			)
			(layer "F.Fab")
		)
		(fp_line
			(start 0.67945 0.3048)
			(end 0.120396 0.3048)
			(stroke
				(width 0.1)
				(type default)
			)
			(layer "F.Fab")
		)
		(fp_line
			(start 0.120396 0.3048)
			(end 0.120396 0.2794)
			(stroke
				(width 0.1)
				(type default)
			)
			(layer "F.Fab")
		)
		(fp_line
			(start -0.12065 0.3048)
			(end -0.67945 0.3048)
			(stroke
				(width 0.1)
				(type default)
			)
			(layer "F.Fab")
		)
		(fp_line
			(start -0.67945 0.3048)
			(end -0.67945 -0.305054)
			(stroke
				(width 0.1)
				(type default)
			)
			(layer "F.Fab")
		)
		(pad "1" smd circle
			(at -0.40005 0 90)
			(size 0 0)
			(layers "F.Cu" "F.Mask" "F.Paste")
			(net "OCP_SFF_PRSNT_ALL_R_N")
		)
		(pad "2" smd circle
			(at 0.40005 0 90)
			(size 0 0)
			(layers "F.Cu" "F.Mask" "F.Paste")
			(net "OCP_SFF_PRSNT_ALL_R3_N")
		)
	)
	(footprint ""
		(layer "F.Cu")
		(at 11.895836 -92.687648 -90)
		(property "Reference" "C2041"
			(at 0 0 270)
			(layer "F.SilkS")
			(hide yes)
			(effects
				(font
					(size 1.27 1.27)
				)
			)
		)
		(property "Value" ""
			(at 0 0 270)
			(layer "F.Fab")
			(effects
				(font
					(size 1.27 1.27)
				)
			)
		)
		(duplicate_pad_numbers_are_jumpers no)
		(fp_line
			(start -0.7874 0.4064)
			(end -0.7874 -0.4064)
			(stroke
				(width 0.1524)
				(type default)
			)
			(layer "F.SilkS")
		)
		(fp_line
			(start 0.7874 0.4064)
			(end -0.7874 0.4064)
			(stroke
				(width 0.1524)
				(type default)
			)
			(layer "F.SilkS")
		)
		(fp_line
			(start -0.7874 -0.4064)
			(end 0.7874 -0.4064)
			(stroke
				(width 0.1524)
				(type default)
			)
			(layer "F.SilkS")
		)
		(fp_line
			(start 0.7874 -0.4064)
			(end 0.7874 0.4064)
			(stroke
				(width 0.1524)
				(type default)
			)
			(layer "F.SilkS")
		)
		(fp_line
			(start -0.67945 0.3048)
			(end -0.67945 -0.305054)
			(stroke
				(width 0.1)
				(type default)
			)
			(layer "F.Fab")
		)
		(fp_line
			(start -0.12065 0.3048)
			(end -0.67945 0.3048)
			(stroke
				(width 0.1)
				(type default)
			)
			(layer "F.Fab")
		)
		(fp_line
			(start 0.120396 0.3048)
			(end 0.120396 0.2794)
			(stroke
				(width 0.1)
				(type default)
			)
			(layer "F.Fab")
		)
		(fp_line
			(start 0.67945 0.3048)
			(end 0.120396 0.3048)
			(stroke
				(width 0.1)
				(type default)
			)
			(layer "F.Fab")
		)
		(fp_line
			(start -0.12065 0.2794)
			(end -0.12065 0.3048)
			(stroke
				(width 0.1)
				(type default)
			)
			(layer "F.Fab")
		)
		(fp_line
			(start 0.120396 0.2794)
			(end -0.12065 0.2794)
			(stroke
				(width 0.1)
				(type default)
			)
			(layer "F.Fab")
		)
		(fp_line
			(start -0.12065 -0.2794)
			(end 0.12065 -0.2794)
			(stroke
				(width 0.1)
				(type default)
			)
			(layer "F.Fab")
		)
		(fp_line
			(start 0.12065 -0.2794)
			(end 0.12065 -0.3048)
			(stroke
				(width 0.1)
				(type default)
			)
			(layer "F.Fab")
		)
		(fp_line
			(start 0.12065 -0.3048)
			(end 0.67945 -0.3048)
			(stroke
				(width 0.1)
				(type default)
			)
			(layer "F.Fab")
		)
		(fp_line
			(start 0.67945 -0.3048)
			(end 0.67945 0.3048)
			(stroke
				(width 0.1)
				(type default)
			)
			(layer "F.Fab")
		)
		(fp_line
			(start -0.67945 -0.305054)
			(end -0.12065 -0.305054)
			(stroke
				(width 0.1)
				(type default)
			)
			(layer "F.Fab")
		)
		(fp_line
			(start -0.12065 -0.305054)
			(end -0.12065 -0.2794)
			(stroke
				(width 0.1)
				(type default)
			)
			(layer "F.Fab")
		)
		(pad "1" smd circle
			(at -0.40005 0 270)
			(size 0 0)
			(layers "F.Cu" "F.Mask" "F.Paste")
			(net "RST_USB_HUB_R_N")
		)
		(pad "2" smd circle
			(at 0.40005 0 270)
			(size 0 0)
			(layers "F.Cu" "F.Mask" "F.Paste")
			(net "GND")
		)
	)
	(footprint ""
		(layer "F.Cu")
		(at 327.179178 -46.748954)
		(property "Reference" "R1800"
			(at 0 0 0)
			(layer "F.SilkS")
			(hide yes)
			(effects
				(font
					(size 1.27 1.27)
				)
			)
		)
		(property "Value" ""
			(at 0 0 0)
			(layer "F.Fab")
			(effects
				(font
					(size 1.27 1.27)
				)
			)
		)
		(duplicate_pad_numbers_are_jumpers no)
		(fp_line
			(start -0.7874 -0.4064)
			(end 0.7874 -0.4064)
			(stroke
				(width 0.1524)
				(type default)
			)
			(layer "F.SilkS")
		)
		(fp_line
			(start -0.7874 0.4064)
			(end -0.7874 -0.4064)
			(stroke
				(width 0.1524)
				(type default)
			)
			(layer "F.SilkS")
		)
		(fp_line
			(start 0.7874 -0.4064)
			(end 0.7874 0.4064)
			(stroke
				(width 0.1524)
				(type default)
			)
			(layer "F.SilkS")
		)
		(fp_line
			(start 0.7874 0.4064)
			(end -0.7874 0.4064)
			(stroke
				(width 0.1524)
				(type default)
			)
			(layer "F.SilkS")
		)
		(fp_line
			(start -0.67945 -0.305054)
			(end -0.12065 -0.305054)
			(stroke
				(width 0.1)
				(type default)
			)
			(layer "F.Fab")
		)
		(fp_line
			(start -0.67945 0.3048)
			(end -0.67945 -0.305054)
			(stroke
				(width 0.1)
				(type default)
			)
			(layer "F.Fab")
		)
		(fp_line
			(start -0.12065 -0.305054)
			(end -0.12065 -0.2794)
			(stroke
				(width 0.1)
				(type default)
			)
			(layer "F.Fab")
		)
		(fp_line
			(start -0.12065 -0.2794)
			(end 0.12065 -0.2794)
			(stroke
				(width 0.1)
				(type default)
			)
			(layer "F.Fab")
		)
		(fp_line
			(start -0.12065 0.2794)
			(end -0.12065 0.3048)
			(stroke
				(width 0.1)
				(type default)
			)
			(layer "F.Fab")
		)
		(fp_line
			(start -0.12065 0.3048)
			(end -0.67945 0.3048)
			(stroke
				(width 0.1)
				(type default)
			)
			(layer "F.Fab")
		)
		(fp_line
			(start 0.120396 0.2794)
			(end -0.12065 0.2794)
			(stroke
				(width 0.1)
				(type default)
			)
			(layer "F.Fab")
		)
		(fp_line
			(start 0.120396 0.3048)
			(end 0.120396 0.2794)
			(stroke
				(width 0.1)
				(type default)
			)
			(layer "F.Fab")
		)
		(fp_line
			(start 0.12065 -0.3048)
			(end 0.67945 -0.3048)
			(stroke
				(width 0.1)
				(type default)
			)
			(layer "F.Fab")
		)
		(fp_line
			(start 0.12065 -0.2794)
			(end 0.12065 -0.3048)
			(stroke
				(width 0.1)
				(type default)
			)
			(layer "F.Fab")
		)
		(fp_line
			(start 0.67945 -0.3048)
			(end 0.67945 0.3048)
			(stroke
				(width 0.1)
				(type default)
			)
			(layer "F.Fab")
		)
		(fp_line
			(start 0.67945 0.3048)
			(end 0.120396 0.3048)
			(stroke
				(width 0.1)
				(type default)
			)
			(layer "F.Fab")
		)
		(pad "1" smd circle
			(at -0.40005 0)
			(size 0 0)
			(layers "F.Cu" "F.Mask" "F.Paste")
			(net "P12V_AUX_ADC")
		)
		(pad "2" smd circle
			(at 0.40005 0)
			(size 0 0)
			(layers "F.Cu" "F.Mask" "F.Paste")
			(net "GND")
		)
	)
	(footprint ""
		(layer "F.Cu")
		(at 76.07173 -386.684774 -90)
		(property "Reference" "R625"
			(at 0 0 270)
			(layer "F.SilkS")
			(hide yes)
			(effects
				(font
					(size 1.27 1.27)
				)
			)
		)
		(property "Value" ""
			(at 0 0 270)
			(layer "F.Fab")
			(effects
				(font
					(size 1.27 1.27)
				)
			)
		)
		(duplicate_pad_numbers_are_jumpers no)
		(fp_line
			(start -0.32512 0.175006)
			(end -0.32512 -0.175006)
			(stroke
				(width 0.1)
				(type default)
			)
			(layer "F.Fab")
		)
		(fp_line
			(start 0.32512 0.175006)
			(end -0.32512 0.175006)
			(stroke
				(width 0.1)
				(type default)
			)
			(layer "F.Fab")
		)
		(fp_line
			(start -0.32512 -0.175006)
			(end 0.32512 -0.175006)
			(stroke
				(width 0.1)
				(type default)
			)
			(layer "F.Fab")
		)
		(fp_line
			(start 0.32512 -0.175006)
			(end 0.32512 0.175006)
			(stroke
				(width 0.1)
				(type default)
			)
			(layer "F.Fab")
		)
		(pad "1" smd rect
			(at -0.2667 0 270)
			(size 0.3048 0.381)
			(layers "F.Cu" "F.Mask" "F.Paste")
			(net "CLK_100M_RETIMER_CPU1_P1_DN")
		)
		(pad "2" smd rect
			(at 0.2667 0 90)
			(size 0.3048 0.381)
			(layers "F.Cu" "F.Mask" "F.Paste")
			(net "GND")
		)
	)
	(footprint ""
		(layer "F.Cu")
		(at 12.319508 -128.593088 90)
		(property "Reference" "R3340"
			(at 0 0 90)
			(layer "F.SilkS")
			(hide yes)
			(effects
				(font
					(size 1.27 1.27)
				)
			)
		)
		(property "Value" ""
			(at 0 0 90)
			(layer "F.Fab")
			(effects
				(font
					(size 1.27 1.27)
				)
			)
		)
		(duplicate_pad_numbers_are_jumpers no)
		(fp_line
			(start 0.7874 -0.4064)
			(end 0.7874 0.4064)
			(stroke
				(width 0.1524)
				(type default)
			)
			(layer "F.SilkS")
		)
		(fp_line
			(start -0.7874 -0.4064)
			(end 0.7874 -0.4064)
			(stroke
				(width 0.1524)
				(type default)
			)
			(layer "F.SilkS")
		)
		(fp_line
			(start 0.7874 0.4064)
			(end -0.7874 0.4064)
			(stroke
				(width 0.1524)
				(type default)
			)
			(layer "F.SilkS")
		)
		(fp_line
			(start -0.7874 0.4064)
			(end -0.7874 -0.4064)
			(stroke
				(width 0.1524)
				(type default)
			)
			(layer "F.SilkS")
		)
		(fp_line
			(start -0.12065 -0.305054)
			(end -0.12065 -0.2794)
			(stroke
				(width 0.1)
				(type default)
			)
			(layer "F.Fab")
		)
		(fp_line
			(start -0.67945 -0.305054)
			(end -0.12065 -0.305054)
			(stroke
				(width 0.1)
				(type default)
			)
			(layer "F.Fab")
		)
		(fp_line
			(start 0.67945 -0.3048)
			(end 0.67945 0.3048)
			(stroke
				(width 0.1)
				(type default)
			)
			(layer "F.Fab")
		)
		(fp_line
			(start 0.12065 -0.3048)
			(end 0.67945 -0.3048)
			(stroke
				(width 0.1)
				(type default)
			)
			(layer "F.Fab")
		)
		(fp_line
			(start 0.12065 -0.2794)
			(end 0.12065 -0.3048)
			(stroke
				(width 0.1)
				(type default)
			)
			(layer "F.Fab")
		)
		(fp_line
			(start -0.12065 -0.2794)
			(end 0.12065 -0.2794)
			(stroke
				(width 0.1)
				(type default)
			)
			(layer "F.Fab")
		)
		(fp_line
			(start 0.120396 0.2794)
			(end -0.12065 0.2794)
			(stroke
				(width 0.1)
				(type default)
			)
			(layer "F.Fab")
		)
		(fp_line
			(start -0.12065 0.2794)
			(end -0.12065 0.3048)
			(stroke
				(width 0.1)
				(type default)
			)
			(layer "F.Fab")
		)
		(fp_line
			(start 0.67945 0.3048)
			(end 0.120396 0.3048)
			(stroke
				(width 0.1)
				(type default)
			)
			(layer "F.Fab")
		)
		(fp_line
			(start 0.120396 0.3048)
			(end 0.120396 0.2794)
			(stroke
				(width 0.1)
				(type default)
			)
			(layer "F.Fab")
		)
		(fp_line
			(start -0.12065 0.3048)
			(end -0.67945 0.3048)
			(stroke
				(width 0.1)
				(type default)
			)
			(layer "F.Fab")
		)
		(fp_line
			(start -0.67945 0.3048)
			(end -0.67945 -0.305054)
			(stroke
				(width 0.1)
				(type default)
			)
			(layer "F.Fab")
		)
		(pad "1" smd circle
			(at -0.40005 0 90)
			(size 0 0)
			(layers "F.Cu" "F.Mask" "F.Paste")
			(net "SMB_HOST_CLK_3V3AUX_SCL")
		)
		(pad "2" smd circle
			(at 0.40005 0 90)
			(size 0 0)
			(layers "F.Cu" "F.Mask" "F.Paste")
			(net "SMB_HOST_CLK_GEN2_3V3AUX_SCL")
		)
	)
	(footprint ""
		(layer "F.Cu")
		(at 139.890754 -79.273654 90)
		(property "Reference" "PC6014"
			(at 0 0 90)
			(layer "F.SilkS")
			(hide yes)
			(effects
				(font
					(size 1.27 1.27)
				)
			)
		)
		(property "Value" ""
			(at 0 0 90)
			(layer "F.Fab")
			(effects
				(font
					(size 1.27 1.27)
				)
			)
		)
		(duplicate_pad_numbers_are_jumpers no)
		(fp_line
			(start 1.524 -0.762)
			(end 1.524 0.762)
			(stroke
				(width 0.1524)
				(type default)
			)
			(layer "F.SilkS")
		)
		(fp_line
			(start -1.524 -0.762)
			(end 1.524 -0.762)
			(stroke
				(width 0.1524)
				(type default)
			)
			(layer "F.SilkS")
		)
		(fp_line
			(start 1.524 0.762)
			(end -1.524 0.762)
			(stroke
				(width 0.1524)
				(type default)
			)
			(layer "F.SilkS")
		)
		(fp_line
			(start -1.524 0.762)
			(end -1.524 -0.762)
			(stroke
				(width 0.1524)
				(type default)
			)
			(layer "F.SilkS")
		)
		(fp_line
			(start 1.1049 -0.724916)
			(end -1.1049 -0.724916)
			(stroke
				(width 0.1)
				(type default)
			)
			(layer "F.Fab")
		)
		(fp_line
			(start -1.1049 -0.724916)
			(end -1.1049 0.724916)
			(stroke
				(width 0.1)
				(type default)
			)
			(layer "F.Fab")
		)
		(fp_line
			(start 1.1049 0.724916)
			(end 1.1049 -0.724916)
			(stroke
				(width 0.1)
				(type default)
			)
			(layer "F.Fab")
		)
		(fp_line
			(start -1.1049 0.724916)
			(end 1.1049 0.724916)
			(stroke
				(width 0.1)
				(type default)
			)
			(layer "F.Fab")
		)
		(pad "1" smd rect
			(at -0.889 0 270)
			(size 1.016 1.27)
			(layers "F.Cu" "F.Mask" "F.Paste")
			(net "SW_P12V_AUX_P1V8_AUX_FLT")
		)
		(pad "2" smd rect
			(at 0.889 0 270)
			(size 1.016 1.27)
			(layers "F.Cu" "F.Mask" "F.Paste")
			(net "GND")
		)
	)
	(footprint ""
		(layer "F.Cu")
		(at 177.927 -129.377948 90)
		(property "Reference" "R191"
			(at 0 0 90)
			(layer "F.SilkS")
			(hide yes)
			(effects
				(font
					(size 1.27 1.27)
				)
			)
		)
		(property "Value" ""
			(at 0 0 90)
			(layer "F.Fab")
			(effects
				(font
					(size 1.27 1.27)
				)
			)
		)
		(duplicate_pad_numbers_are_jumpers no)
		(fp_line
			(start 0.7874 -0.4064)
			(end 0.7874 0.4064)
			(stroke
				(width 0.1524)
				(type default)
			)
			(layer "F.SilkS")
		)
		(fp_line
			(start -0.7874 -0.4064)
			(end 0.7874 -0.4064)
			(stroke
				(width 0.1524)
				(type default)
			)
			(layer "F.SilkS")
		)
		(fp_line
			(start 0.7874 0.4064)
			(end -0.7874 0.4064)
			(stroke
				(width 0.1524)
				(type default)
			)
			(layer "F.SilkS")
		)
		(fp_line
			(start -0.7874 0.4064)
			(end -0.7874 -0.4064)
			(stroke
				(width 0.1524)
				(type default)
			)
			(layer "F.SilkS")
		)
		(fp_line
			(start -0.12065 -0.305054)
			(end -0.12065 -0.2794)
			(stroke
				(width 0.1)
				(type default)
			)
			(layer "F.Fab")
		)
		(fp_line
			(start -0.67945 -0.305054)
			(end -0.12065 -0.305054)
			(stroke
				(width 0.1)
				(type default)
			)
			(layer "F.Fab")
		)
		(fp_line
			(start 0.67945 -0.3048)
			(end 0.67945 0.3048)
			(stroke
				(width 0.1)
				(type default)
			)
			(layer "F.Fab")
		)
		(fp_line
			(start 0.12065 -0.3048)
			(end 0.67945 -0.3048)
			(stroke
				(width 0.1)
				(type default)
			)
			(layer "F.Fab")
		)
		(fp_line
			(start 0.12065 -0.2794)
			(end 0.12065 -0.3048)
			(stroke
				(width 0.1)
				(type default)
			)
			(layer "F.Fab")
		)
		(fp_line
			(start -0.12065 -0.2794)
			(end 0.12065 -0.2794)
			(stroke
				(width 0.1)
				(type default)
			)
			(layer "F.Fab")
		)
		(fp_line
			(start 0.120396 0.2794)
			(end -0.12065 0.2794)
			(stroke
				(width 0.1)
				(type default)
			)
			(layer "F.Fab")
		)
		(fp_line
			(start -0.12065 0.2794)
			(end -0.12065 0.3048)
			(stroke
				(width 0.1)
				(type default)
			)
			(layer "F.Fab")
		)
		(fp_line
			(start 0.67945 0.3048)
			(end 0.120396 0.3048)
			(stroke
				(width 0.1)
				(type default)
			)
			(layer "F.Fab")
		)
		(fp_line
			(start 0.120396 0.3048)
			(end 0.120396 0.2794)
			(stroke
				(width 0.1)
				(type default)
			)
			(layer "F.Fab")
		)
		(fp_line
			(start -0.12065 0.3048)
			(end -0.67945 0.3048)
			(stroke
				(width 0.1)
				(type default)
			)
			(layer "F.Fab")
		)
		(fp_line
			(start -0.67945 0.3048)
			(end -0.67945 -0.305054)
			(stroke
				(width 0.1)
				(type default)
			)
			(layer "F.Fab")
		)
		(pad "1" smd circle
			(at -0.40005 0 90)
			(size 0 0)
			(layers "F.Cu" "F.Mask" "F.Paste")
			(net "FM_CPU1_SLP_S5_N")
		)
		(pad "2" smd circle
			(at 0.40005 0 90)
			(size 0 0)
			(layers "F.Cu" "F.Mask" "F.Paste")
			(net "CPU1_SLP_S5_N")
		)
	)
	(footprint ""
		(layer "F.Cu")
		(at 301.161704 -430.28362 90)
		(property "Reference" "R6822"
			(at 0 0 90)
			(layer "F.SilkS")
			(hide yes)
			(effects
				(font
					(size 1.27 1.27)
				)
			)
		)
		(property "Value" ""
			(at 0 0 90)
			(layer "F.Fab")
			(effects
				(font
					(size 1.27 1.27)
				)
			)
		)
		(duplicate_pad_numbers_are_jumpers no)
		(fp_line
			(start 0.32512 -0.175006)
			(end 0.32512 0.175006)
			(stroke
				(width 0.1)
				(type default)
			)
			(layer "F.Fab")
		)
		(fp_line
			(start -0.32512 -0.175006)
			(end 0.32512 -0.175006)
			(stroke
				(width 0.1)
				(type default)
			)
			(layer "F.Fab")
		)
		(fp_line
			(start 0.32512 0.175006)
			(end -0.32512 0.175006)
			(stroke
				(width 0.1)
				(type default)
			)
			(layer "F.Fab")
		)
		(fp_line
			(start -0.32512 0.175006)
			(end -0.32512 -0.175006)
			(stroke
				(width 0.1)
				(type default)
			)
			(layer "F.Fab")
		)
		(pad "1" smd rect
			(at -0.2667 0 90)
			(size 0.3048 0.381)
			(layers "F.Cu" "F.Mask" "F.Paste")
			(net "U11_E2")
		)
		(pad "2" smd rect
			(at 0.2667 0 270)
			(size 0.3048 0.381)
			(layers "F.Cu" "F.Mask" "F.Paste")
			(net "GND")
		)
	)
	(footprint ""
		(layer "F.Cu")
		(at 118.846346 -408.517344 -90)
		(property "Reference" "C6695"
			(at 0 0 270)
			(layer "F.SilkS")
			(hide yes)
			(effects
				(font
					(size 1.27 1.27)
				)
			)
		)
		(property "Value" ""
			(at 0 0 270)
			(layer "F.Fab")
			(effects
				(font
					(size 1.27 1.27)
				)
			)
		)
		(duplicate_pad_numbers_are_jumpers no)
		(fp_line
			(start -0.299974 0.150114)
			(end -0.299974 -0.150114)
			(stroke
				(width 0.1)
				(type default)
			)
			(layer "F.Fab")
		)
		(fp_line
			(start 0.299974 0.150114)
			(end -0.299974 0.150114)
			(stroke
				(width 0.1)
				(type default)
			)
			(layer "F.Fab")
		)
		(fp_line
			(start -0.299974 -0.150114)
			(end 0.299974 -0.150114)
			(stroke
				(width 0.1)
				(type default)
			)
			(layer "F.Fab")
		)
		(fp_line
			(start 0.299974 -0.150114)
			(end 0.299974 0.150114)
			(stroke
				(width 0.1)
				(type default)
			)
			(layer "F.Fab")
		)
		(pad "1" smd rect
			(at -0.2667 0 270)
			(size 0.3048 0.381)
			(layers "F.Cu" "F.Mask" "F.Paste")
			(net "P5E_CPU1_P2_TX_BUF_C_DP<1>")
		)
		(pad "2" smd rect
			(at 0.2667 0 270)
			(size 0.3048 0.381)
			(layers "F.Cu" "F.Mask" "F.Paste")
			(net "P5E_CPU1_P2_TX_BUF_DP<1>")
		)
	)
	(footprint ""
		(layer "F.Cu")
		(at 114.490246 -399.327116 -90)
		(property "Reference" "C1067"
			(at 0 0 270)
			(layer "F.SilkS")
			(hide yes)
			(effects
				(font
					(size 1.27 1.27)
				)
			)
		)
		(property "Value" ""
			(at 0 0 270)
			(layer "F.Fab")
			(effects
				(font
					(size 1.27 1.27)
				)
			)
		)
		(duplicate_pad_numbers_are_jumpers no)
		(fp_line
			(start -0.299974 0.150114)
			(end -0.299974 -0.150114)
			(stroke
				(width 0.1)
				(type default)
			)
			(layer "F.Fab")
		)
		(fp_line
			(start 0.299974 0.150114)
			(end -0.299974 0.150114)
			(stroke
				(width 0.1)
				(type default)
			)
			(layer "F.Fab")
		)
		(fp_line
			(start -0.299974 -0.150114)
			(end 0.299974 -0.150114)
			(stroke
				(width 0.1)
				(type default)
			)
			(layer "F.Fab")
		)
		(fp_line
			(start 0.299974 -0.150114)
			(end 0.299974 0.150114)
			(stroke
				(width 0.1)
				(type default)
			)
			(layer "F.Fab")
		)
		(pad "1" smd rect
			(at -0.2667 0 270)
			(size 0.3048 0.381)
			(layers "F.Cu" "F.Mask" "F.Paste")
			(net "P3V3_AUX")
		)
		(pad "2" smd rect
			(at 0.2667 0 270)
			(size 0.3048 0.381)
			(layers "F.Cu" "F.Mask" "F.Paste")
			(net "GND")
		)
	)
	(footprint ""
		(layer "F.Cu")
		(at 166.18077 -394.3604 -90)
		(property "Reference" "R6795"
			(at 0 0 270)
			(layer "F.SilkS")
			(hide yes)
			(effects
				(font
					(size 1.27 1.27)
				)
			)
		)
		(property "Value" ""
			(at 0 0 270)
			(layer "F.Fab")
			(effects
				(font
					(size 1.27 1.27)
				)
			)
		)
		(duplicate_pad_numbers_are_jumpers no)
		(fp_line
			(start -0.32512 0.175006)
			(end -0.32512 -0.175006)
			(stroke
				(width 0.1)
				(type default)
			)
			(layer "F.Fab")
		)
		(fp_line
			(start 0.32512 0.175006)
			(end -0.32512 0.175006)
			(stroke
				(width 0.1)
				(type default)
			)
			(layer "F.Fab")
		)
		(fp_line
			(start -0.32512 -0.175006)
			(end 0.32512 -0.175006)
			(stroke
				(width 0.1)
				(type default)
			)
			(layer "F.Fab")
		)
		(fp_line
			(start 0.32512 -0.175006)
			(end 0.32512 0.175006)
			(stroke
				(width 0.1)
				(type default)
			)
			(layer "F.Fab")
		)
		(pad "1" smd rect
			(at -0.2667 0 270)
			(size 0.3048 0.381)
			(layers "F.Cu" "F.Mask" "F.Paste")
			(net "RT_CPU1_P2_VQPS")
		)
		(pad "2" smd rect
			(at 0.2667 0 90)
			(size 0.3048 0.381)
			(layers "F.Cu" "F.Mask" "F.Paste")
			(net "GND")
		)
	)
	(footprint ""
		(layer "F.Cu")
		(at 156.690314 -108.432854 180)
		(property "Reference" "R1130"
			(at 0 0 180)
			(layer "F.SilkS")
			(hide yes)
			(effects
				(font
					(size 1.27 1.27)
				)
			)
		)
		(property "Value" ""
			(at 0 0 180)
			(layer "F.Fab")
			(effects
				(font
					(size 1.27 1.27)
				)
			)
		)
		(duplicate_pad_numbers_are_jumpers no)
		(fp_line
			(start 0.7874 0.4064)
			(end -0.7874 0.4064)
			(stroke
				(width 0.1524)
				(type default)
			)
			(layer "F.SilkS")
		)
		(fp_line
			(start 0.7874 -0.4064)
			(end 0.7874 0.4064)
			(stroke
				(width 0.1524)
				(type default)
			)
			(layer "F.SilkS")
		)
		(fp_line
			(start -0.7874 0.4064)
			(end -0.7874 -0.4064)
			(stroke
				(width 0.1524)
				(type default)
			)
			(layer "F.SilkS")
		)
		(fp_line
			(start -0.7874 -0.4064)
			(end 0.7874 -0.4064)
			(stroke
				(width 0.1524)
				(type default)
			)
			(layer "F.SilkS")
		)
		(fp_line
			(start 0.67945 0.3048)
			(end 0.120396 0.3048)
			(stroke
				(width 0.1)
				(type default)
			)
			(layer "F.Fab")
		)
		(fp_line
			(start 0.67945 -0.3048)
			(end 0.67945 0.3048)
			(stroke
				(width 0.1)
				(type default)
			)
			(layer "F.Fab")
		)
		(fp_line
			(start 0.12065 -0.2794)
			(end 0.12065 -0.3048)
			(stroke
				(width 0.1)
				(type default)
			)
			(layer "F.Fab")
		)
		(fp_line
			(start 0.12065 -0.3048)
			(end 0.67945 -0.3048)
			(stroke
				(width 0.1)
				(type default)
			)
			(layer "F.Fab")
		)
		(fp_line
			(start 0.120396 0.3048)
			(end 0.120396 0.2794)
			(stroke
				(width 0.1)
				(type default)
			)
			(layer "F.Fab")
		)
		(fp_line
			(start 0.120396 0.2794)
			(end -0.12065 0.2794)
			(stroke
				(width 0.1)
				(type default)
			)
			(layer "F.Fab")
		)
		(fp_line
			(start -0.12065 0.3048)
			(end -0.67945 0.3048)
			(stroke
				(width 0.1)
				(type default)
			)
			(layer "F.Fab")
		)
		(fp_line
			(start -0.12065 0.2794)
			(end -0.12065 0.3048)
			(stroke
				(width 0.1)
				(type default)
			)
			(layer "F.Fab")
		)
		(fp_line
			(start -0.12065 -0.2794)
			(end 0.12065 -0.2794)
			(stroke
				(width 0.1)
				(type default)
			)
			(layer "F.Fab")
		)
		(fp_line
			(start -0.12065 -0.305054)
			(end -0.12065 -0.2794)
			(stroke
				(width 0.1)
				(type default)
			)
			(layer "F.Fab")
		)
		(fp_line
			(start -0.67945 0.3048)
			(end -0.67945 -0.305054)
			(stroke
				(width 0.1)
				(type default)
			)
			(layer "F.Fab")
		)
		(fp_line
			(start -0.67945 -0.305054)
			(end -0.12065 -0.305054)
			(stroke
				(width 0.1)
				(type default)
			)
			(layer "F.Fab")
		)
		(pad "1" smd circle
			(at -0.40005 0 180)
			(size 0 0)
			(layers "F.Cu" "F.Mask" "F.Paste")
			(net "P12V_OCP_SFF_EN_R")
		)
		(pad "2" smd circle
			(at 0.40005 0 180)
			(size 0 0)
			(layers "F.Cu" "F.Mask" "F.Paste")
			(net "P12V_OCP_SFF_EN_R3")
		)
	)
	(footprint ""
		(layer "F.Cu")
		(at 428.912782 -107.872276 180)
		(property "Reference" "PR3790"
			(at 0 0 180)
			(layer "F.SilkS")
			(hide yes)
			(effects
				(font
					(size 1.27 1.27)
				)
			)
		)
		(property "Value" ""
			(at 0 0 180)
			(layer "F.Fab")
			(effects
				(font
					(size 1.27 1.27)
				)
			)
		)
		(duplicate_pad_numbers_are_jumpers no)
		(fp_line
			(start 0.7874 0.4064)
			(end -0.7874 0.4064)
			(stroke
				(width 0.1524)
				(type default)
			)
			(layer "F.SilkS")
		)
		(fp_line
			(start 0.7874 -0.4064)
			(end 0.7874 0.4064)
			(stroke
				(width 0.1524)
				(type default)
			)
			(layer "F.SilkS")
		)
		(fp_line
			(start -0.7874 0.4064)
			(end -0.7874 -0.4064)
			(stroke
				(width 0.1524)
				(type default)
			)
			(layer "F.SilkS")
		)
		(fp_line
			(start -0.7874 -0.4064)
			(end 0.7874 -0.4064)
			(stroke
				(width 0.1524)
				(type default)
			)
			(layer "F.SilkS")
		)
		(fp_line
			(start 0.67945 0.3048)
			(end 0.120396 0.3048)
			(stroke
				(width 0.1)
				(type default)
			)
			(layer "F.Fab")
		)
		(fp_line
			(start 0.67945 -0.3048)
			(end 0.67945 0.3048)
			(stroke
				(width 0.1)
				(type default)
			)
			(layer "F.Fab")
		)
		(fp_line
			(start 0.12065 -0.2794)
			(end 0.12065 -0.3048)
			(stroke
				(width 0.1)
				(type default)
			)
			(layer "F.Fab")
		)
		(fp_line
			(start 0.12065 -0.3048)
			(end 0.67945 -0.3048)
			(stroke
				(width 0.1)
				(type default)
			)
			(layer "F.Fab")
		)
		(fp_line
			(start 0.120396 0.3048)
			(end 0.120396 0.2794)
			(stroke
				(width 0.1)
				(type default)
			)
			(layer "F.Fab")
		)
		(fp_line
			(start 0.120396 0.2794)
			(end -0.12065 0.2794)
			(stroke
				(width 0.1)
				(type default)
			)
			(layer "F.Fab")
		)
		(fp_line
			(start -0.12065 0.3048)
			(end -0.67945 0.3048)
			(stroke
				(width 0.1)
				(type default)
			)
			(layer "F.Fab")
		)
		(fp_line
			(start -0.12065 0.2794)
			(end -0.12065 0.3048)
			(stroke
				(width 0.1)
				(type default)
			)
			(layer "F.Fab")
		)
		(fp_line
			(start -0.12065 -0.2794)
			(end 0.12065 -0.2794)
			(stroke
				(width 0.1)
				(type default)
			)
			(layer "F.Fab")
		)
		(fp_line
			(start -0.12065 -0.305054)
			(end -0.12065 -0.2794)
			(stroke
				(width 0.1)
				(type default)
			)
			(layer "F.Fab")
		)
		(fp_line
			(start -0.67945 0.3048)
			(end -0.67945 -0.305054)
			(stroke
				(width 0.1)
				(type default)
			)
			(layer "F.Fab")
		)
		(fp_line
			(start -0.67945 -0.305054)
			(end -0.12065 -0.305054)
			(stroke
				(width 0.1)
				(type default)
			)
			(layer "F.Fab")
		)
		(pad "1" smd circle
			(at -0.40005 0 180)
			(size 0 0)
			(layers "F.Cu" "F.Mask" "F.Paste")
			(net "P3V3_OCP_UV_1")
		)
		(pad "2" smd circle
			(at 0.40005 0 180)
			(size 0 0)
			(layers "F.Cu" "F.Mask" "F.Paste")
			(net "P3V3_OCP_OV_1")
		)
	)
	(footprint ""
		(layer "F.Cu")
		(at 106.892598 -16.98371)
		(property "Reference" "R3553"
			(at 0 0 0)
			(layer "F.SilkS")
			(hide yes)
			(effects
				(font
					(size 1.27 1.27)
				)
			)
		)
		(property "Value" ""
			(at 0 0 0)
			(layer "F.Fab")
			(effects
				(font
					(size 1.27 1.27)
				)
			)
		)
		(duplicate_pad_numbers_are_jumpers no)
		(fp_line
			(start -0.7874 -0.4064)
			(end 0.7874 -0.4064)
			(stroke
				(width 0.1524)
				(type default)
			)
			(layer "F.SilkS")
		)
		(fp_line
			(start -0.7874 0.4064)
			(end -0.7874 -0.4064)
			(stroke
				(width 0.1524)
				(type default)
			)
			(layer "F.SilkS")
		)
		(fp_line
			(start 0.7874 -0.4064)
			(end 0.7874 0.4064)
			(stroke
				(width 0.1524)
				(type default)
			)
			(layer "F.SilkS")
		)
		(fp_line
			(start 0.7874 0.4064)
			(end -0.7874 0.4064)
			(stroke
				(width 0.1524)
				(type default)
			)
			(layer "F.SilkS")
		)
		(fp_line
			(start -0.67945 -0.305054)
			(end -0.12065 -0.305054)
			(stroke
				(width 0.1)
				(type default)
			)
			(layer "F.Fab")
		)
		(fp_line
			(start -0.67945 0.3048)
			(end -0.67945 -0.305054)
			(stroke
				(width 0.1)
				(type default)
			)
			(layer "F.Fab")
		)
		(fp_line
			(start -0.12065 -0.305054)
			(end -0.12065 -0.2794)
			(stroke
				(width 0.1)
				(type default)
			)
			(layer "F.Fab")
		)
		(fp_line
			(start -0.12065 -0.2794)
			(end 0.12065 -0.2794)
			(stroke
				(width 0.1)
				(type default)
			)
			(layer "F.Fab")
		)
		(fp_line
			(start -0.12065 0.2794)
			(end -0.12065 0.3048)
			(stroke
				(width 0.1)
				(type default)
			)
			(layer "F.Fab")
		)
		(fp_line
			(start -0.12065 0.3048)
			(end -0.67945 0.3048)
			(stroke
				(width 0.1)
				(type default)
			)
			(layer "F.Fab")
		)
		(fp_line
			(start 0.120396 0.2794)
			(end -0.12065 0.2794)
			(stroke
				(width 0.1)
				(type default)
			)
			(layer "F.Fab")
		)
		(fp_line
			(start 0.120396 0.3048)
			(end 0.120396 0.2794)
			(stroke
				(width 0.1)
				(type default)
			)
			(layer "F.Fab")
		)
		(fp_line
			(start 0.12065 -0.3048)
			(end 0.67945 -0.3048)
			(stroke
				(width 0.1)
				(type default)
			)
			(layer "F.Fab")
		)
		(fp_line
			(start 0.12065 -0.2794)
			(end 0.12065 -0.3048)
			(stroke
				(width 0.1)
				(type default)
			)
			(layer "F.Fab")
		)
		(fp_line
			(start 0.67945 -0.3048)
			(end 0.67945 0.3048)
			(stroke
				(width 0.1)
				(type default)
			)
			(layer "F.Fab")
		)
		(fp_line
			(start 0.67945 0.3048)
			(end 0.120396 0.3048)
			(stroke
				(width 0.1)
				(type default)
			)
			(layer "F.Fab")
		)
		(pad "1" smd circle
			(at -0.40005 0)
			(size 0 0)
			(layers "F.Cu" "F.Mask" "F.Paste")
			(net "SMB_LM75_3_3V3AUX_SCL")
		)
		(pad "2" smd circle
			(at 0.40005 0)
			(size 0 0)
			(layers "F.Cu" "F.Mask" "F.Paste")
			(net "SMB_LM75_3_3V3AUX_SCL_R1")
		)
	)
	(footprint ""
		(layer "F.Cu")
		(at 362.025438 -412.334964 180)
		(property "Reference" "R9003"
			(at 0 0 180)
			(layer "F.SilkS")
			(hide yes)
			(effects
				(font
					(size 1.27 1.27)
				)
			)
		)
		(property "Value" ""
			(at 0 0 180)
			(layer "F.Fab")
			(effects
				(font
					(size 1.27 1.27)
				)
			)
		)
		(duplicate_pad_numbers_are_jumpers no)
		(fp_line
			(start 0.7874 0.4064)
			(end -0.7874 0.4064)
			(stroke
				(width 0.1524)
				(type default)
			)
			(layer "F.SilkS")
		)
		(fp_line
			(start 0.7874 -0.4064)
			(end 0.7874 0.4064)
			(stroke
				(width 0.1524)
				(type default)
			)
			(layer "F.SilkS")
		)
		(fp_line
			(start -0.7874 0.4064)
			(end -0.7874 -0.4064)
			(stroke
				(width 0.1524)
				(type default)
			)
			(layer "F.SilkS")
		)
		(fp_line
			(start -0.7874 -0.4064)
			(end 0.7874 -0.4064)
			(stroke
				(width 0.1524)
				(type default)
			)
			(layer "F.SilkS")
		)
		(fp_line
			(start 0.67945 0.3048)
			(end 0.120396 0.3048)
			(stroke
				(width 0.1)
				(type default)
			)
			(layer "F.Fab")
		)
		(fp_line
			(start 0.67945 -0.3048)
			(end 0.67945 0.3048)
			(stroke
				(width 0.1)
				(type default)
			)
			(layer "F.Fab")
		)
		(fp_line
			(start 0.12065 -0.2794)
			(end 0.12065 -0.3048)
			(stroke
				(width 0.1)
				(type default)
			)
			(layer "F.Fab")
		)
		(fp_line
			(start 0.12065 -0.3048)
			(end 0.67945 -0.3048)
			(stroke
				(width 0.1)
				(type default)
			)
			(layer "F.Fab")
		)
		(fp_line
			(start 0.120396 0.3048)
			(end 0.120396 0.2794)
			(stroke
				(width 0.1)
				(type default)
			)
			(layer "F.Fab")
		)
		(fp_line
			(start 0.120396 0.2794)
			(end -0.12065 0.2794)
			(stroke
				(width 0.1)
				(type default)
			)
			(layer "F.Fab")
		)
		(fp_line
			(start -0.12065 0.3048)
			(end -0.67945 0.3048)
			(stroke
				(width 0.1)
				(type default)
			)
			(layer "F.Fab")
		)
		(fp_line
			(start -0.12065 0.2794)
			(end -0.12065 0.3048)
			(stroke
				(width 0.1)
				(type default)
			)
			(layer "F.Fab")
		)
		(fp_line
			(start -0.12065 -0.2794)
			(end 0.12065 -0.2794)
			(stroke
				(width 0.1)
				(type default)
			)
			(layer "F.Fab")
		)
		(fp_line
			(start -0.12065 -0.305054)
			(end -0.12065 -0.2794)
			(stroke
				(width 0.1)
				(type default)
			)
			(layer "F.Fab")
		)
		(fp_line
			(start -0.67945 0.3048)
			(end -0.67945 -0.305054)
			(stroke
				(width 0.1)
				(type default)
			)
			(layer "F.Fab")
		)
		(fp_line
			(start -0.67945 -0.305054)
			(end -0.12065 -0.305054)
			(stroke
				(width 0.1)
				(type default)
			)
			(layer "F.Fab")
		)
		(pad "1" smd circle
			(at -0.40005 0 180)
			(size 0 0)
			(layers "F.Cu" "F.Mask" "F.Paste")
			(net "PRSNT_CABLE_SWB_B1_N")
		)
		(pad "2" smd circle
			(at 0.40005 0 180)
			(size 0 0)
			(layers "F.Cu" "F.Mask" "F.Paste")
			(net "GND")
		)
	)
	(footprint ""
		(layer "F.Cu")
		(at 91.317318 -339.413596)
		(property "Reference" "PC425_5"
			(at 0 0 0)
			(layer "F.SilkS")
			(hide yes)
			(effects
				(font
					(size 1.27 1.27)
				)
			)
		)
		(property "Value" ""
			(at 0 0 0)
			(layer "F.Fab")
			(effects
				(font
					(size 1.27 1.27)
				)
			)
		)
		(duplicate_pad_numbers_are_jumpers no)
		(fp_line
			(start -0.7874 -0.4064)
			(end 0.7874 -0.4064)
			(stroke
				(width 0.1524)
				(type default)
			)
			(layer "F.SilkS")
		)
		(fp_line
			(start -0.7874 0.4064)
			(end -0.7874 -0.4064)
			(stroke
				(width 0.1524)
				(type default)
			)
			(layer "F.SilkS")
		)
		(fp_line
			(start 0.7874 -0.4064)
			(end 0.7874 0.4064)
			(stroke
				(width 0.1524)
				(type default)
			)
			(layer "F.SilkS")
		)
		(fp_line
			(start 0.7874 0.4064)
			(end -0.7874 0.4064)
			(stroke
				(width 0.1524)
				(type default)
			)
			(layer "F.SilkS")
		)
		(fp_line
			(start -0.67945 -0.305054)
			(end -0.12065 -0.305054)
			(stroke
				(width 0.1)
				(type default)
			)
			(layer "F.Fab")
		)
		(fp_line
			(start -0.67945 0.3048)
			(end -0.67945 -0.305054)
			(stroke
				(width 0.1)
				(type default)
			)
			(layer "F.Fab")
		)
		(fp_line
			(start -0.12065 -0.305054)
			(end -0.12065 -0.2794)
			(stroke
				(width 0.1)
				(type default)
			)
			(layer "F.Fab")
		)
		(fp_line
			(start -0.12065 -0.2794)
			(end 0.12065 -0.2794)
			(stroke
				(width 0.1)
				(type default)
			)
			(layer "F.Fab")
		)
		(fp_line
			(start -0.12065 0.2794)
			(end -0.12065 0.3048)
			(stroke
				(width 0.1)
				(type default)
			)
			(layer "F.Fab")
		)
		(fp_line
			(start -0.12065 0.3048)
			(end -0.67945 0.3048)
			(stroke
				(width 0.1)
				(type default)
			)
			(layer "F.Fab")
		)
		(fp_line
			(start 0.120396 0.2794)
			(end -0.12065 0.2794)
			(stroke
				(width 0.1)
				(type default)
			)
			(layer "F.Fab")
		)
		(fp_line
			(start 0.120396 0.3048)
			(end 0.120396 0.2794)
			(stroke
				(width 0.1)
				(type default)
			)
			(layer "F.Fab")
		)
		(fp_line
			(start 0.12065 -0.3048)
			(end 0.67945 -0.3048)
			(stroke
				(width 0.1)
				(type default)
			)
			(layer "F.Fab")
		)
		(fp_line
			(start 0.12065 -0.2794)
			(end 0.12065 -0.3048)
			(stroke
				(width 0.1)
				(type default)
			)
			(layer "F.Fab")
		)
		(fp_line
			(start 0.67945 -0.3048)
			(end 0.67945 0.3048)
			(stroke
				(width 0.1)
				(type default)
			)
			(layer "F.Fab")
		)
		(fp_line
			(start 0.67945 0.3048)
			(end 0.120396 0.3048)
			(stroke
				(width 0.1)
				(type default)
			)
			(layer "F.Fab")
		)
		(pad "1" smd circle
			(at -0.40005 0)
			(size 0 0)
			(layers "F.Cu" "F.Mask" "F.Paste")
			(net "SW_P12V_AUX_PVDDCR_CPU1_P1_FLT")
		)
		(pad "2" smd circle
			(at 0.40005 0)
			(size 0 0)
			(layers "F.Cu" "F.Mask" "F.Paste")
			(net "GND")
		)
	)
	(footprint ""
		(layer "F.Cu")
		(at 254.592836 -124.50445)
		(property "Reference" "R3705"
			(at 0 0 0)
			(layer "F.SilkS")
			(hide yes)
			(effects
				(font
					(size 1.27 1.27)
				)
			)
		)
		(property "Value" ""
			(at 0 0 0)
			(layer "F.Fab")
			(effects
				(font
					(size 1.27 1.27)
				)
			)
		)
		(duplicate_pad_numbers_are_jumpers no)
		(fp_line
			(start -0.7874 -0.4064)
			(end 0.7874 -0.4064)
			(stroke
				(width 0.1524)
				(type default)
			)
			(layer "F.SilkS")
		)
		(fp_line
			(start -0.7874 0.4064)
			(end -0.7874 -0.4064)
			(stroke
				(width 0.1524)
				(type default)
			)
			(layer "F.SilkS")
		)
		(fp_line
			(start 0.7874 -0.4064)
			(end 0.7874 0.4064)
			(stroke
				(width 0.1524)
				(type default)
			)
			(layer "F.SilkS")
		)
		(fp_line
			(start 0.7874 0.4064)
			(end -0.7874 0.4064)
			(stroke
				(width 0.1524)
				(type default)
			)
			(layer "F.SilkS")
		)
		(fp_line
			(start -0.67945 -0.305054)
			(end -0.12065 -0.305054)
			(stroke
				(width 0.1)
				(type default)
			)
			(layer "F.Fab")
		)
		(fp_line
			(start -0.67945 0.3048)
			(end -0.67945 -0.305054)
			(stroke
				(width 0.1)
				(type default)
			)
			(layer "F.Fab")
		)
		(fp_line
			(start -0.12065 -0.305054)
			(end -0.12065 -0.2794)
			(stroke
				(width 0.1)
				(type default)
			)
			(layer "F.Fab")
		)
		(fp_line
			(start -0.12065 -0.2794)
			(end 0.12065 -0.2794)
			(stroke
				(width 0.1)
				(type default)
			)
			(layer "F.Fab")
		)
		(fp_line
			(start -0.12065 0.2794)
			(end -0.12065 0.3048)
			(stroke
				(width 0.1)
				(type default)
			)
			(layer "F.Fab")
		)
		(fp_line
			(start -0.12065 0.3048)
			(end -0.67945 0.3048)
			(stroke
				(width 0.1)
				(type default)
			)
			(layer "F.Fab")
		)
		(fp_line
			(start 0.120396 0.2794)
			(end -0.12065 0.2794)
			(stroke
				(width 0.1)
				(type default)
			)
			(layer "F.Fab")
		)
		(fp_line
			(start 0.120396 0.3048)
			(end 0.120396 0.2794)
			(stroke
				(width 0.1)
				(type default)
			)
			(layer "F.Fab")
		)
		(fp_line
			(start 0.12065 -0.3048)
			(end 0.67945 -0.3048)
			(stroke
				(width 0.1)
				(type default)
			)
			(layer "F.Fab")
		)
		(fp_line
			(start 0.12065 -0.2794)
			(end 0.12065 -0.3048)
			(stroke
				(width 0.1)
				(type default)
			)
			(layer "F.Fab")
		)
		(fp_line
			(start 0.67945 -0.3048)
			(end 0.67945 0.3048)
			(stroke
				(width 0.1)
				(type default)
			)
			(layer "F.Fab")
		)
		(fp_line
			(start 0.67945 0.3048)
			(end 0.120396 0.3048)
			(stroke
				(width 0.1)
				(type default)
			)
			(layer "F.Fab")
		)
		(pad "1" smd circle
			(at -0.40005 0)
			(size 0 0)
			(layers "F.Cu" "F.Mask" "F.Paste")
			(net "P3V3_AUX")
		)
		(pad "2" smd circle
			(at 0.40005 0)
			(size 0 0)
			(layers "F.Cu" "F.Mask" "F.Paste")
			(net "RST_SMB_SWITCH_N")
		)
	)
	(footprint ""
		(layer "F.Cu")
		(at 117.330474 -55.036212 90)
		(property "Reference" "R1730"
			(at 0 0 90)
			(layer "F.SilkS")
			(hide yes)
			(effects
				(font
					(size 1.27 1.27)
				)
			)
		)
		(property "Value" ""
			(at 0 0 90)
			(layer "F.Fab")
			(effects
				(font
					(size 1.27 1.27)
				)
			)
		)
		(duplicate_pad_numbers_are_jumpers no)
		(fp_line
			(start 0.7874 -0.4064)
			(end 0.7874 0.4064)
			(stroke
				(width 0.1524)
				(type default)
			)
			(layer "F.SilkS")
		)
		(fp_line
			(start -0.7874 -0.4064)
			(end 0.7874 -0.4064)
			(stroke
				(width 0.1524)
				(type default)
			)
			(layer "F.SilkS")
		)
		(fp_line
			(start 0.7874 0.4064)
			(end -0.7874 0.4064)
			(stroke
				(width 0.1524)
				(type default)
			)
			(layer "F.SilkS")
		)
		(fp_line
			(start -0.7874 0.4064)
			(end -0.7874 -0.4064)
			(stroke
				(width 0.1524)
				(type default)
			)
			(layer "F.SilkS")
		)
		(fp_line
			(start -0.12065 -0.305054)
			(end -0.12065 -0.2794)
			(stroke
				(width 0.1)
				(type default)
			)
			(layer "F.Fab")
		)
		(fp_line
			(start -0.67945 -0.305054)
			(end -0.12065 -0.305054)
			(stroke
				(width 0.1)
				(type default)
			)
			(layer "F.Fab")
		)
		(fp_line
			(start 0.67945 -0.3048)
			(end 0.67945 0.3048)
			(stroke
				(width 0.1)
				(type default)
			)
			(layer "F.Fab")
		)
		(fp_line
			(start 0.12065 -0.3048)
			(end 0.67945 -0.3048)
			(stroke
				(width 0.1)
				(type default)
			)
			(layer "F.Fab")
		)
		(fp_line
			(start 0.12065 -0.2794)
			(end 0.12065 -0.3048)
			(stroke
				(width 0.1)
				(type default)
			)
			(layer "F.Fab")
		)
		(fp_line
			(start -0.12065 -0.2794)
			(end 0.12065 -0.2794)
			(stroke
				(width 0.1)
				(type default)
			)
			(layer "F.Fab")
		)
		(fp_line
			(start 0.120396 0.2794)
			(end -0.12065 0.2794)
			(stroke
				(width 0.1)
				(type default)
			)
			(layer "F.Fab")
		)
		(fp_line
			(start -0.12065 0.2794)
			(end -0.12065 0.3048)
			(stroke
				(width 0.1)
				(type default)
			)
			(layer "F.Fab")
		)
		(fp_line
			(start 0.67945 0.3048)
			(end 0.120396 0.3048)
			(stroke
				(width 0.1)
				(type default)
			)
			(layer "F.Fab")
		)
		(fp_line
			(start 0.120396 0.3048)
			(end 0.120396 0.2794)
			(stroke
				(width 0.1)
				(type default)
			)
			(layer "F.Fab")
		)
		(fp_line
			(start -0.12065 0.3048)
			(end -0.67945 0.3048)
			(stroke
				(width 0.1)
				(type default)
			)
			(layer "F.Fab")
		)
		(fp_line
			(start -0.67945 0.3048)
			(end -0.67945 -0.305054)
			(stroke
				(width 0.1)
				(type default)
			)
			(layer "F.Fab")
		)
		(pad "1" smd circle
			(at -0.40005 0 90)
			(size 0 0)
			(layers "F.Cu" "F.Mask" "F.Paste")
			(net "P3V3_AUX")
		)
		(pad "2" smd circle
			(at 0.40005 0 90)
			(size 0 0)
			(layers "F.Cu" "F.Mask" "F.Paste")
			(net "SCM_JTAG_MUX_S1")
		)
	)
	(footprint ""
		(layer "F.Cu")
		(at 99.080828 -394.3604 -90)
		(property "Reference" "R6731"
			(at 0 0 270)
			(layer "F.SilkS")
			(hide yes)
			(effects
				(font
					(size 1.27 1.27)
				)
			)
		)
		(property "Value" ""
			(at 0 0 270)
			(layer "F.Fab")
			(effects
				(font
					(size 1.27 1.27)
				)
			)
		)
		(duplicate_pad_numbers_are_jumpers no)
		(fp_line
			(start -0.32512 0.175006)
			(end -0.32512 -0.175006)
			(stroke
				(width 0.1)
				(type default)
			)
			(layer "F.Fab")
		)
		(fp_line
			(start 0.32512 0.175006)
			(end -0.32512 0.175006)
			(stroke
				(width 0.1)
				(type default)
			)
			(layer "F.Fab")
		)
		(fp_line
			(start -0.32512 -0.175006)
			(end 0.32512 -0.175006)
			(stroke
				(width 0.1)
				(type default)
			)
			(layer "F.Fab")
		)
		(fp_line
			(start 0.32512 -0.175006)
			(end 0.32512 0.175006)
			(stroke
				(width 0.1)
				(type default)
			)
			(layer "F.Fab")
		)
		(pad "1" smd rect
			(at -0.2667 0 270)
			(size 0.3048 0.381)
			(layers "F.Cu" "F.Mask" "F.Paste")
			(net "RT_CPU1_P1_VQPS")
		)
		(pad "2" smd rect
			(at 0.2667 0 90)
			(size 0.3048 0.381)
			(layers "F.Cu" "F.Mask" "F.Paste")
			(net "GND")
		)
	)
	(footprint ""
		(layer "F.Cu")
		(at 57.40908 -52.53228)
		(property "Reference" "R1523"
			(at 0 0 0)
			(layer "F.SilkS")
			(hide yes)
			(effects
				(font
					(size 1.27 1.27)
				)
			)
		)
		(property "Value" ""
			(at 0 0 0)
			(layer "F.Fab")
			(effects
				(font
					(size 1.27 1.27)
				)
			)
		)
		(duplicate_pad_numbers_are_jumpers no)
		(fp_line
			(start -0.7874 -0.4064)
			(end 0.7874 -0.4064)
			(stroke
				(width 0.1524)
				(type default)
			)
			(layer "F.SilkS")
		)
		(fp_line
			(start -0.7874 0.4064)
			(end -0.7874 -0.4064)
			(stroke
				(width 0.1524)
				(type default)
			)
			(layer "F.SilkS")
		)
		(fp_line
			(start 0.7874 -0.4064)
			(end 0.7874 0.4064)
			(stroke
				(width 0.1524)
				(type default)
			)
			(layer "F.SilkS")
		)
		(fp_line
			(start 0.7874 0.4064)
			(end -0.7874 0.4064)
			(stroke
				(width 0.1524)
				(type default)
			)
			(layer "F.SilkS")
		)
		(fp_line
			(start -0.67945 -0.305054)
			(end -0.12065 -0.305054)
			(stroke
				(width 0.1)
				(type default)
			)
			(layer "F.Fab")
		)
		(fp_line
			(start -0.67945 0.3048)
			(end -0.67945 -0.305054)
			(stroke
				(width 0.1)
				(type default)
			)
			(layer "F.Fab")
		)
		(fp_line
			(start -0.12065 -0.305054)
			(end -0.12065 -0.2794)
			(stroke
				(width 0.1)
				(type default)
			)
			(layer "F.Fab")
		)
		(fp_line
			(start -0.12065 -0.2794)
			(end 0.12065 -0.2794)
			(stroke
				(width 0.1)
				(type default)
			)
			(layer "F.Fab")
		)
		(fp_line
			(start -0.12065 0.2794)
			(end -0.12065 0.3048)
			(stroke
				(width 0.1)
				(type default)
			)
			(layer "F.Fab")
		)
		(fp_line
			(start -0.12065 0.3048)
			(end -0.67945 0.3048)
			(stroke
				(width 0.1)
				(type default)
			)
			(layer "F.Fab")
		)
		(fp_line
			(start 0.120396 0.2794)
			(end -0.12065 0.2794)
			(stroke
				(width 0.1)
				(type default)
			)
			(layer "F.Fab")
		)
		(fp_line
			(start 0.120396 0.3048)
			(end 0.120396 0.2794)
			(stroke
				(width 0.1)
				(type default)
			)
			(layer "F.Fab")
		)
		(fp_line
			(start 0.12065 -0.3048)
			(end 0.67945 -0.3048)
			(stroke
				(width 0.1)
				(type default)
			)
			(layer "F.Fab")
		)
		(fp_line
			(start 0.12065 -0.2794)
			(end 0.12065 -0.3048)
			(stroke
				(width 0.1)
				(type default)
			)
			(layer "F.Fab")
		)
		(fp_line
			(start 0.67945 -0.3048)
			(end 0.67945 0.3048)
			(stroke
				(width 0.1)
				(type default)
			)
			(layer "F.Fab")
		)
		(fp_line
			(start 0.67945 0.3048)
			(end 0.120396 0.3048)
			(stroke
				(width 0.1)
				(type default)
			)
			(layer "F.Fab")
		)
		(pad "1" smd circle
			(at -0.40005 0)
			(size 0 0)
			(layers "F.Cu" "F.Mask" "F.Paste")
			(net "HP_LVC3_OCP_V3_2_P12V_PWRGD")
		)
		(pad "2" smd circle
			(at 0.40005 0)
			(size 0 0)
			(layers "F.Cu" "F.Mask" "F.Paste")
			(net "HP_LVC3_OCP_V3_2_P12V_PWRGD_R2")
		)
	)
	(footprint ""
		(layer "F.Cu")
		(at 347.899736 -25.529286)
		(property "Reference" "C219"
			(at 0 0 0)
			(layer "F.SilkS")
			(hide yes)
			(effects
				(font
					(size 1.27 1.27)
				)
			)
		)
		(property "Value" ""
			(at 0 0 0)
			(layer "F.Fab")
			(effects
				(font
					(size 1.27 1.27)
				)
			)
		)
		(duplicate_pad_numbers_are_jumpers no)
		(fp_line
			(start -0.7874 -0.4064)
			(end 0.7874 -0.4064)
			(stroke
				(width 0.1524)
				(type default)
			)
			(layer "F.SilkS")
		)
		(fp_line
			(start -0.7874 0.4064)
			(end -0.7874 -0.4064)
			(stroke
				(width 0.1524)
				(type default)
			)
			(layer "F.SilkS")
		)
		(fp_line
			(start 0.7874 -0.4064)
			(end 0.7874 0.4064)
			(stroke
				(width 0.1524)
				(type default)
			)
			(layer "F.SilkS")
		)
		(fp_line
			(start 0.7874 0.4064)
			(end -0.7874 0.4064)
			(stroke
				(width 0.1524)
				(type default)
			)
			(layer "F.SilkS")
		)
		(fp_line
			(start -0.67945 -0.305054)
			(end -0.12065 -0.305054)
			(stroke
				(width 0.1)
				(type default)
			)
			(layer "F.Fab")
		)
		(fp_line
			(start -0.67945 0.3048)
			(end -0.67945 -0.305054)
			(stroke
				(width 0.1)
				(type default)
			)
			(layer "F.Fab")
		)
		(fp_line
			(start -0.12065 -0.305054)
			(end -0.12065 -0.2794)
			(stroke
				(width 0.1)
				(type default)
			)
			(layer "F.Fab")
		)
		(fp_line
			(start -0.12065 -0.2794)
			(end 0.12065 -0.2794)
			(stroke
				(width 0.1)
				(type default)
			)
			(layer "F.Fab")
		)
		(fp_line
			(start -0.12065 0.2794)
			(end -0.12065 0.3048)
			(stroke
				(width 0.1)
				(type default)
			)
			(layer "F.Fab")
		)
		(fp_line
			(start -0.12065 0.3048)
			(end -0.67945 0.3048)
			(stroke
				(width 0.1)
				(type default)
			)
			(layer "F.Fab")
		)
		(fp_line
			(start 0.120396 0.2794)
			(end -0.12065 0.2794)
			(stroke
				(width 0.1)
				(type default)
			)
			(layer "F.Fab")
		)
		(fp_line
			(start 0.120396 0.3048)
			(end 0.120396 0.2794)
			(stroke
				(width 0.1)
				(type default)
			)
			(layer "F.Fab")
		)
		(fp_line
			(start 0.12065 -0.3048)
			(end 0.67945 -0.3048)
			(stroke
				(width 0.1)
				(type default)
			)
			(layer "F.Fab")
		)
		(fp_line
			(start 0.12065 -0.2794)
			(end 0.12065 -0.3048)
			(stroke
				(width 0.1)
				(type default)
			)
			(layer "F.Fab")
		)
		(fp_line
			(start 0.67945 -0.3048)
			(end 0.67945 0.3048)
			(stroke
				(width 0.1)
				(type default)
			)
			(layer "F.Fab")
		)
		(fp_line
			(start 0.67945 0.3048)
			(end 0.120396 0.3048)
			(stroke
				(width 0.1)
				(type default)
			)
			(layer "F.Fab")
		)
		(pad "1" smd circle
			(at -0.40005 0)
			(size 0 0)
			(layers "F.Cu" "F.Mask" "F.Paste")
			(net "P1V8_AUX")
		)
		(pad "2" smd circle
			(at 0.40005 0)
			(size 0 0)
			(layers "F.Cu" "F.Mask" "F.Paste")
			(net "GND")
		)
	)
	(footprint ""
		(layer "F.Cu")
		(at 144.834864 -194.567048 90)
		(property "Reference" "PR169"
			(at 0 0 90)
			(layer "F.SilkS")
			(hide yes)
			(effects
				(font
					(size 1.27 1.27)
				)
			)
		)
		(property "Value" ""
			(at 0 0 90)
			(layer "F.Fab")
			(effects
				(font
					(size 1.27 1.27)
				)
			)
		)
		(duplicate_pad_numbers_are_jumpers no)
		(fp_line
			(start 0.7874 -0.4064)
			(end 0.7874 0.4064)
			(stroke
				(width 0.1524)
				(type default)
			)
			(layer "F.SilkS")
		)
		(fp_line
			(start -0.7874 -0.4064)
			(end 0.7874 -0.4064)
			(stroke
				(width 0.1524)
				(type default)
			)
			(layer "F.SilkS")
		)
		(fp_line
			(start 0.7874 0.4064)
			(end -0.7874 0.4064)
			(stroke
				(width 0.1524)
				(type default)
			)
			(layer "F.SilkS")
		)
		(fp_line
			(start -0.7874 0.4064)
			(end -0.7874 -0.4064)
			(stroke
				(width 0.1524)
				(type default)
			)
			(layer "F.SilkS")
		)
		(fp_line
			(start -0.12065 -0.305054)
			(end -0.12065 -0.2794)
			(stroke
				(width 0.1)
				(type default)
			)
			(layer "F.Fab")
		)
		(fp_line
			(start -0.67945 -0.305054)
			(end -0.12065 -0.305054)
			(stroke
				(width 0.1)
				(type default)
			)
			(layer "F.Fab")
		)
		(fp_line
			(start 0.67945 -0.3048)
			(end 0.67945 0.3048)
			(stroke
				(width 0.1)
				(type default)
			)
			(layer "F.Fab")
		)
		(fp_line
			(start 0.12065 -0.3048)
			(end 0.67945 -0.3048)
			(stroke
				(width 0.1)
				(type default)
			)
			(layer "F.Fab")
		)
		(fp_line
			(start 0.12065 -0.2794)
			(end 0.12065 -0.3048)
			(stroke
				(width 0.1)
				(type default)
			)
			(layer "F.Fab")
		)
		(fp_line
			(start -0.12065 -0.2794)
			(end 0.12065 -0.2794)
			(stroke
				(width 0.1)
				(type default)
			)
			(layer "F.Fab")
		)
		(fp_line
			(start 0.120396 0.2794)
			(end -0.12065 0.2794)
			(stroke
				(width 0.1)
				(type default)
			)
			(layer "F.Fab")
		)
		(fp_line
			(start -0.12065 0.2794)
			(end -0.12065 0.3048)
			(stroke
				(width 0.1)
				(type default)
			)
			(layer "F.Fab")
		)
		(fp_line
			(start 0.67945 0.3048)
			(end 0.120396 0.3048)
			(stroke
				(width 0.1)
				(type default)
			)
			(layer "F.Fab")
		)
		(fp_line
			(start 0.120396 0.3048)
			(end 0.120396 0.2794)
			(stroke
				(width 0.1)
				(type default)
			)
			(layer "F.Fab")
		)
		(fp_line
			(start -0.12065 0.3048)
			(end -0.67945 0.3048)
			(stroke
				(width 0.1)
				(type default)
			)
			(layer "F.Fab")
		)
		(fp_line
			(start -0.67945 0.3048)
			(end -0.67945 -0.305054)
			(stroke
				(width 0.1)
				(type default)
			)
			(layer "F.Fab")
		)
		(pad "1" smd circle
			(at -0.40005 0 90)
			(size 0 0)
			(layers "F.Cu" "F.Mask" "F.Paste")
			(net "SVID_PVDDCR_CPU0_P1_SVC_R")
		)
		(pad "2" smd circle
			(at 0.40005 0 90)
			(size 0 0)
			(layers "F.Cu" "F.Mask" "F.Paste")
			(net "SVID_PVDDCR_CPU0_P1_SVC")
		)
	)
	(footprint ""
		(layer "F.Cu")
		(at 200.914 -102.362 180)
		(property "Reference" "R8084"
			(at 0 0 180)
			(layer "F.SilkS")
			(hide yes)
			(effects
				(font
					(size 1.27 1.27)
				)
			)
		)
		(property "Value" ""
			(at 0 0 180)
			(layer "F.Fab")
			(effects
				(font
					(size 1.27 1.27)
				)
			)
		)
		(duplicate_pad_numbers_are_jumpers no)
		(fp_line
			(start 0.7874 0.4064)
			(end -0.7874 0.4064)
			(stroke
				(width 0.1524)
				(type default)
			)
			(layer "F.SilkS")
		)
		(fp_line
			(start 0.7874 -0.4064)
			(end 0.7874 0.4064)
			(stroke
				(width 0.1524)
				(type default)
			)
			(layer "F.SilkS")
		)
		(fp_line
			(start -0.7874 0.4064)
			(end -0.7874 -0.4064)
			(stroke
				(width 0.1524)
				(type default)
			)
			(layer "F.SilkS")
		)
		(fp_line
			(start -0.7874 -0.4064)
			(end 0.7874 -0.4064)
			(stroke
				(width 0.1524)
				(type default)
			)
			(layer "F.SilkS")
		)
		(fp_line
			(start 0.67945 0.3048)
			(end 0.120396 0.3048)
			(stroke
				(width 0.1)
				(type default)
			)
			(layer "F.Fab")
		)
		(fp_line
			(start 0.67945 -0.3048)
			(end 0.67945 0.3048)
			(stroke
				(width 0.1)
				(type default)
			)
			(layer "F.Fab")
		)
		(fp_line
			(start 0.12065 -0.2794)
			(end 0.12065 -0.3048)
			(stroke
				(width 0.1)
				(type default)
			)
			(layer "F.Fab")
		)
		(fp_line
			(start 0.12065 -0.3048)
			(end 0.67945 -0.3048)
			(stroke
				(width 0.1)
				(type default)
			)
			(layer "F.Fab")
		)
		(fp_line
			(start 0.120396 0.3048)
			(end 0.120396 0.2794)
			(stroke
				(width 0.1)
				(type default)
			)
			(layer "F.Fab")
		)
		(fp_line
			(start 0.120396 0.2794)
			(end -0.12065 0.2794)
			(stroke
				(width 0.1)
				(type default)
			)
			(layer "F.Fab")
		)
		(fp_line
			(start -0.12065 0.3048)
			(end -0.67945 0.3048)
			(stroke
				(width 0.1)
				(type default)
			)
			(layer "F.Fab")
		)
		(fp_line
			(start -0.12065 0.2794)
			(end -0.12065 0.3048)
			(stroke
				(width 0.1)
				(type default)
			)
			(layer "F.Fab")
		)
		(fp_line
			(start -0.12065 -0.2794)
			(end 0.12065 -0.2794)
			(stroke
				(width 0.1)
				(type default)
			)
			(layer "F.Fab")
		)
		(fp_line
			(start -0.12065 -0.305054)
			(end -0.12065 -0.2794)
			(stroke
				(width 0.1)
				(type default)
			)
			(layer "F.Fab")
		)
		(fp_line
			(start -0.67945 0.3048)
			(end -0.67945 -0.305054)
			(stroke
				(width 0.1)
				(type default)
			)
			(layer "F.Fab")
		)
		(fp_line
			(start -0.67945 -0.305054)
			(end -0.12065 -0.305054)
			(stroke
				(width 0.1)
				(type default)
			)
			(layer "F.Fab")
		)
		(pad "1" smd circle
			(at -0.40005 0 180)
			(size 0 0)
			(layers "F.Cu" "F.Mask" "F.Paste")
			(net "PWRGD_CHGL_CPU0_R1")
		)
		(pad "2" smd circle
			(at 0.40005 0 180)
			(size 0 0)
			(layers "F.Cu" "F.Mask" "F.Paste")
			(net "PWRGD_CHGL_CPU0_R2")
		)
	)
	(footprint ""
		(layer "F.Cu")
		(at 377.869958 -162.59683 180)
		(property "Reference" "PC491"
			(at 2.807716 -2.902712 0)
			(unlocked yes)
			(layer "F.SilkS")
			(effects
				(font
					(size 0.7874 0.5842)
					(thickness 0.1524)
				)
				(justify left)
			)
		)
		(property "Value" ""
			(at 0 0 180)
			(layer "F.Fab")
			(effects
				(font
					(size 1.27 1.27)
				)
			)
		)
		(duplicate_pad_numbers_are_jumpers no)
		(fp_line
			(start -3.400044 1.249934)
			(end 3.400044 1.249934)
			(stroke
				(width 0.1524)
				(type default)
			)
			(layer "F.SilkS")
		)
		(fp_circle
			(center 0 1.249934)
			(end -3.400044 1.249934)
			(stroke
				(width 0.1524)
				(type default)
			)
			(fill no)
			(layer "F.SilkS")
		)
		(fp_poly
			(pts
				(arc
					(start 3.400044 1.249934)
					(mid 0 4.649978)
					(end -3.400044 1.249934)
				)
			)
			(stroke
				(width 0)
				(type default)
			)
			(fill yes)
			(layer "F.SilkS")
		)
		(fp_circle
			(center 0 1.249934)
			(end -3.400044 1.249934)
			(stroke
				(width 0.1)
				(type default)
			)
			(fill no)
			(layer "F.Fab")
		)
		(pad "1" thru_hole rect
			(at 0 0 180)
			(size 1.524 1.524)
			(drill 1.016)
			(layers "*.Cu" "*.Mask")
			(remove_unused_layers no)
			(net "SW_P12V_AUX_PVDDCR_CPU0_P0_FLT")
			(clearance 0)
			(padstack
				(mode front_inner_back)
				(layer "Inner"
					(shape circle)
					(size 1.524 1.524)
					(clearance 0)
				)
				(layer "B.Cu"
					(shape rect)
					(size 1.524 1.524)
					(clearance 0)
				)
			)
		)
		(pad "2" thru_hole circle
			(at 0 2.500122 180)
			(size 1.524 1.524)
			(drill 1.016)
			(layers "*.Cu" "*.Mask")
			(remove_unused_layers no)
			(net "GND")
			(clearance 0)
		)
	)
	(footprint ""
		(layer "F.Cu")
		(at 37.211 -365.125)
		(property "Reference" "PC357"
			(at 0 0 0)
			(layer "F.SilkS")
			(hide yes)
			(effects
				(font
					(size 1.27 1.27)
				)
			)
		)
		(property "Value" ""
			(at 0 0 0)
			(layer "F.Fab")
			(effects
				(font
					(size 1.27 1.27)
				)
			)
		)
		(duplicate_pad_numbers_are_jumpers no)
		(fp_line
			(start -0.7874 -0.4064)
			(end 0.7874 -0.4064)
			(stroke
				(width 0.1524)
				(type default)
			)
			(layer "F.SilkS")
		)
		(fp_line
			(start -0.7874 0.4064)
			(end -0.7874 -0.4064)
			(stroke
				(width 0.1524)
				(type default)
			)
			(layer "F.SilkS")
		)
		(fp_line
			(start 0.7874 -0.4064)
			(end 0.7874 0.4064)
			(stroke
				(width 0.1524)
				(type default)
			)
			(layer "F.SilkS")
		)
		(fp_line
			(start 0.7874 0.4064)
			(end -0.7874 0.4064)
			(stroke
				(width 0.1524)
				(type default)
			)
			(layer "F.SilkS")
		)
		(fp_line
			(start -0.67945 -0.305054)
			(end -0.12065 -0.305054)
			(stroke
				(width 0.1)
				(type default)
			)
			(layer "F.Fab")
		)
		(fp_line
			(start -0.67945 0.3048)
			(end -0.67945 -0.305054)
			(stroke
				(width 0.1)
				(type default)
			)
			(layer "F.Fab")
		)
		(fp_line
			(start -0.12065 -0.305054)
			(end -0.12065 -0.2794)
			(stroke
				(width 0.1)
				(type default)
			)
			(layer "F.Fab")
		)
		(fp_line
			(start -0.12065 -0.2794)
			(end 0.12065 -0.2794)
			(stroke
				(width 0.1)
				(type default)
			)
			(layer "F.Fab")
		)
		(fp_line
			(start -0.12065 0.2794)
			(end -0.12065 0.3048)
			(stroke
				(width 0.1)
				(type default)
			)
			(layer "F.Fab")
		)
		(fp_line
			(start -0.12065 0.3048)
			(end -0.67945 0.3048)
			(stroke
				(width 0.1)
				(type default)
			)
			(layer "F.Fab")
		)
		(fp_line
			(start 0.120396 0.2794)
			(end -0.12065 0.2794)
			(stroke
				(width 0.1)
				(type default)
			)
			(layer "F.Fab")
		)
		(fp_line
			(start 0.120396 0.3048)
			(end 0.120396 0.2794)
			(stroke
				(width 0.1)
				(type default)
			)
			(layer "F.Fab")
		)
		(fp_line
			(start 0.12065 -0.3048)
			(end 0.67945 -0.3048)
			(stroke
				(width 0.1)
				(type default)
			)
			(layer "F.Fab")
		)
		(fp_line
			(start 0.12065 -0.2794)
			(end 0.12065 -0.3048)
			(stroke
				(width 0.1)
				(type default)
			)
			(layer "F.Fab")
		)
		(fp_line
			(start 0.67945 -0.3048)
			(end 0.67945 0.3048)
			(stroke
				(width 0.1)
				(type default)
			)
			(layer "F.Fab")
		)
		(fp_line
			(start 0.67945 0.3048)
			(end 0.120396 0.3048)
			(stroke
				(width 0.1)
				(type default)
			)
			(layer "F.Fab")
		)
		(pad "1" smd circle
			(at -0.40005 0)
			(size 0 0)
			(layers "F.Cu" "F.Mask" "F.Paste")
			(net "PVDDCR_CPU1_P1_VMON")
		)
		(pad "2" smd circle
			(at 0.40005 0)
			(size 0 0)
			(layers "F.Cu" "F.Mask" "F.Paste")
			(net "GND")
		)
	)
	(footprint ""
		(layer "F.Cu")
		(at 12.876784 -392.650726 90)
		(property "Reference" "PR6626"
			(at 0 0 90)
			(layer "F.SilkS")
			(hide yes)
			(effects
				(font
					(size 1.27 1.27)
				)
			)
		)
		(property "Value" ""
			(at 0 0 90)
			(layer "F.Fab")
			(effects
				(font
					(size 1.27 1.27)
				)
			)
		)
		(duplicate_pad_numbers_are_jumpers no)
		(fp_line
			(start 0.7874 -0.4064)
			(end 0.7874 0.4064)
			(stroke
				(width 0.1524)
				(type default)
			)
			(layer "F.SilkS")
		)
		(fp_line
			(start -0.7874 -0.4064)
			(end 0.7874 -0.4064)
			(stroke
				(width 0.1524)
				(type default)
			)
			(layer "F.SilkS")
		)
		(fp_line
			(start -0.7874 -0.202184)
			(end -0.7874 -0.4064)
			(stroke
				(width 0.1524)
				(type default)
			)
			(layer "F.SilkS")
		)
		(fp_line
			(start 0.7874 0.4064)
			(end -0.271526 0.4064)
			(stroke
				(width 0.1524)
				(type default)
			)
			(layer "F.SilkS")
		)
		(fp_line
			(start -0.12065 -0.305054)
			(end -0.12065 -0.2794)
			(stroke
				(width 0.1)
				(type default)
			)
			(layer "F.Fab")
		)
		(fp_line
			(start -0.67945 -0.305054)
			(end -0.12065 -0.305054)
			(stroke
				(width 0.1)
				(type default)
			)
			(layer "F.Fab")
		)
		(fp_line
			(start 0.67945 -0.3048)
			(end 0.67945 0.3048)
			(stroke
				(width 0.1)
				(type default)
			)
			(layer "F.Fab")
		)
		(fp_line
			(start 0.12065 -0.3048)
			(end 0.67945 -0.3048)
			(stroke
				(width 0.1)
				(type default)
			)
			(layer "F.Fab")
		)
		(fp_line
			(start 0.12065 -0.2794)
			(end 0.12065 -0.3048)
			(stroke
				(width 0.1)
				(type default)
			)
			(layer "F.Fab")
		)
		(fp_line
			(start -0.12065 -0.2794)
			(end 0.12065 -0.2794)
			(stroke
				(width 0.1)
				(type default)
			)
			(layer "F.Fab")
		)
		(fp_line
			(start 0.120396 0.2794)
			(end -0.12065 0.2794)
			(stroke
				(width 0.1)
				(type default)
			)
			(layer "F.Fab")
		)
		(fp_line
			(start -0.12065 0.2794)
			(end -0.12065 0.3048)
			(stroke
				(width 0.1)
				(type default)
			)
			(layer "F.Fab")
		)
		(fp_line
			(start 0.67945 0.3048)
			(end 0.120396 0.3048)
			(stroke
				(width 0.1)
				(type default)
			)
			(layer "F.Fab")
		)
		(fp_line
			(start 0.120396 0.3048)
			(end 0.120396 0.2794)
			(stroke
				(width 0.1)
				(type default)
			)
			(layer "F.Fab")
		)
		(fp_line
			(start -0.12065 0.3048)
			(end -0.67945 0.3048)
			(stroke
				(width 0.1)
				(type default)
			)
			(layer "F.Fab")
		)
		(fp_line
			(start -0.67945 0.3048)
			(end -0.67945 -0.305054)
			(stroke
				(width 0.1)
				(type default)
			)
			(layer "F.Fab")
		)
		(pad "1" smd circle
			(at -0.40005 0 90)
			(size 0 0)
			(layers "F.Cu" "F.Mask" "F.Paste")
			(net "P0V9_RETIMER_CPU1_VOS1")
		)
		(pad "2" smd circle
			(at 0.40005 0 90)
			(size 0 0)
			(layers "F.Cu" "F.Mask" "F.Paste")
			(net "P0V9_CPU1_RT_2D")
		)
	)
	(footprint ""
		(layer "F.Cu")
		(at 403.682962 -54.4195 180)
		(property "Reference" "R1528"
			(at 0 0 180)
			(layer "F.SilkS")
			(hide yes)
			(effects
				(font
					(size 1.27 1.27)
				)
			)
		)
		(property "Value" ""
			(at 0 0 180)
			(layer "F.Fab")
			(effects
				(font
					(size 1.27 1.27)
				)
			)
		)
		(duplicate_pad_numbers_are_jumpers no)
		(fp_line
			(start 0.7874 0.4064)
			(end -0.7874 0.4064)
			(stroke
				(width 0.1524)
				(type default)
			)
			(layer "F.SilkS")
		)
		(fp_line
			(start 0.7874 -0.4064)
			(end 0.7874 0.4064)
			(stroke
				(width 0.1524)
				(type default)
			)
			(layer "F.SilkS")
		)
		(fp_line
			(start -0.7874 0.4064)
			(end -0.7874 -0.4064)
			(stroke
				(width 0.1524)
				(type default)
			)
			(layer "F.SilkS")
		)
		(fp_line
			(start -0.7874 -0.4064)
			(end 0.7874 -0.4064)
			(stroke
				(width 0.1524)
				(type default)
			)
			(layer "F.SilkS")
		)
		(fp_line
			(start 0.67945 0.3048)
			(end 0.120396 0.3048)
			(stroke
				(width 0.1)
				(type default)
			)
			(layer "F.Fab")
		)
		(fp_line
			(start 0.67945 -0.3048)
			(end 0.67945 0.3048)
			(stroke
				(width 0.1)
				(type default)
			)
			(layer "F.Fab")
		)
		(fp_line
			(start 0.12065 -0.2794)
			(end 0.12065 -0.3048)
			(stroke
				(width 0.1)
				(type default)
			)
			(layer "F.Fab")
		)
		(fp_line
			(start 0.12065 -0.3048)
			(end 0.67945 -0.3048)
			(stroke
				(width 0.1)
				(type default)
			)
			(layer "F.Fab")
		)
		(fp_line
			(start 0.120396 0.3048)
			(end 0.120396 0.2794)
			(stroke
				(width 0.1)
				(type default)
			)
			(layer "F.Fab")
		)
		(fp_line
			(start 0.120396 0.2794)
			(end -0.12065 0.2794)
			(stroke
				(width 0.1)
				(type default)
			)
			(layer "F.Fab")
		)
		(fp_line
			(start -0.12065 0.3048)
			(end -0.67945 0.3048)
			(stroke
				(width 0.1)
				(type default)
			)
			(layer "F.Fab")
		)
		(fp_line
			(start -0.12065 0.2794)
			(end -0.12065 0.3048)
			(stroke
				(width 0.1)
				(type default)
			)
			(layer "F.Fab")
		)
		(fp_line
			(start -0.12065 -0.2794)
			(end 0.12065 -0.2794)
			(stroke
				(width 0.1)
				(type default)
			)
			(layer "F.Fab")
		)
		(fp_line
			(start -0.12065 -0.305054)
			(end -0.12065 -0.2794)
			(stroke
				(width 0.1)
				(type default)
			)
			(layer "F.Fab")
		)
		(fp_line
			(start -0.67945 0.3048)
			(end -0.67945 -0.305054)
			(stroke
				(width 0.1)
				(type default)
			)
			(layer "F.Fab")
		)
		(fp_line
			(start -0.67945 -0.305054)
			(end -0.12065 -0.305054)
			(stroke
				(width 0.1)
				(type default)
			)
			(layer "F.Fab")
		)
		(pad "1" smd circle
			(at -0.40005 0 180)
			(size 0 0)
			(layers "F.Cu" "F.Mask" "F.Paste")
			(net "PRSNT_HDT_N")
		)
		(pad "2" smd circle
			(at 0.40005 0 180)
			(size 0 0)
			(layers "F.Cu" "F.Mask" "F.Paste")
			(net "PRSNT_HDT_R_N")
		)
	)
	(footprint ""
		(layer "F.Cu")
		(at 150.31974 -102.688898)
		(property "Reference" "R3295"
			(at 0 0 0)
			(layer "F.SilkS")
			(hide yes)
			(effects
				(font
					(size 1.27 1.27)
				)
			)
		)
		(property "Value" ""
			(at 0 0 0)
			(layer "F.Fab")
			(effects
				(font
					(size 1.27 1.27)
				)
			)
		)
		(duplicate_pad_numbers_are_jumpers no)
		(fp_line
			(start -0.7874 -0.4064)
			(end 0.7874 -0.4064)
			(stroke
				(width 0.1524)
				(type default)
			)
			(layer "F.SilkS")
		)
		(fp_line
			(start -0.7874 0.4064)
			(end -0.7874 -0.4064)
			(stroke
				(width 0.1524)
				(type default)
			)
			(layer "F.SilkS")
		)
		(fp_line
			(start 0.7874 -0.4064)
			(end 0.7874 0.4064)
			(stroke
				(width 0.1524)
				(type default)
			)
			(layer "F.SilkS")
		)
		(fp_line
			(start 0.7874 0.4064)
			(end -0.7874 0.4064)
			(stroke
				(width 0.1524)
				(type default)
			)
			(layer "F.SilkS")
		)
		(fp_line
			(start -0.67945 -0.305054)
			(end -0.12065 -0.305054)
			(stroke
				(width 0.1)
				(type default)
			)
			(layer "F.Fab")
		)
		(fp_line
			(start -0.67945 0.3048)
			(end -0.67945 -0.305054)
			(stroke
				(width 0.1)
				(type default)
			)
			(layer "F.Fab")
		)
		(fp_line
			(start -0.12065 -0.305054)
			(end -0.12065 -0.2794)
			(stroke
				(width 0.1)
				(type default)
			)
			(layer "F.Fab")
		)
		(fp_line
			(start -0.12065 -0.2794)
			(end 0.12065 -0.2794)
			(stroke
				(width 0.1)
				(type default)
			)
			(layer "F.Fab")
		)
		(fp_line
			(start -0.12065 0.2794)
			(end -0.12065 0.3048)
			(stroke
				(width 0.1)
				(type default)
			)
			(layer "F.Fab")
		)
		(fp_line
			(start -0.12065 0.3048)
			(end -0.67945 0.3048)
			(stroke
				(width 0.1)
				(type default)
			)
			(layer "F.Fab")
		)
		(fp_line
			(start 0.120396 0.2794)
			(end -0.12065 0.2794)
			(stroke
				(width 0.1)
				(type default)
			)
			(layer "F.Fab")
		)
		(fp_line
			(start 0.120396 0.3048)
			(end 0.120396 0.2794)
			(stroke
				(width 0.1)
				(type default)
			)
			(layer "F.Fab")
		)
		(fp_line
			(start 0.12065 -0.3048)
			(end 0.67945 -0.3048)
			(stroke
				(width 0.1)
				(type default)
			)
			(layer "F.Fab")
		)
		(fp_line
			(start 0.12065 -0.2794)
			(end 0.12065 -0.3048)
			(stroke
				(width 0.1)
				(type default)
			)
			(layer "F.Fab")
		)
		(fp_line
			(start 0.67945 -0.3048)
			(end 0.67945 0.3048)
			(stroke
				(width 0.1)
				(type default)
			)
			(layer "F.Fab")
		)
		(fp_line
			(start 0.67945 0.3048)
			(end 0.120396 0.3048)
			(stroke
				(width 0.1)
				(type default)
			)
			(layer "F.Fab")
		)
		(pad "1" smd circle
			(at -0.40005 0)
			(size 0 0)
			(layers "F.Cu" "F.Mask" "F.Paste")
			(net "P3V3_M2_0")
		)
		(pad "2" smd circle
			(at 0.40005 0)
			(size 0 0)
			(layers "F.Cu" "F.Mask" "F.Paste")
			(net "LED_HDD_ACTIVITY_N")
		)
	)
	(footprint ""
		(layer "F.Cu")
		(at 166.942516 -347.289882 180)
		(property "Reference" "PR464"
			(at 0 0 180)
			(layer "F.SilkS")
			(hide yes)
			(effects
				(font
					(size 1.27 1.27)
				)
			)
		)
		(property "Value" ""
			(at 0 0 180)
			(layer "F.Fab")
			(effects
				(font
					(size 1.27 1.27)
				)
			)
		)
		(duplicate_pad_numbers_are_jumpers no)
		(fp_line
			(start 0.7874 0.4064)
			(end -0.7874 0.4064)
			(stroke
				(width 0.1524)
				(type default)
			)
			(layer "F.SilkS")
		)
		(fp_line
			(start 0.7874 -0.4064)
			(end 0.7874 0.4064)
			(stroke
				(width 0.1524)
				(type default)
			)
			(layer "F.SilkS")
		)
		(fp_line
			(start -0.7874 0.4064)
			(end -0.7874 -0.4064)
			(stroke
				(width 0.1524)
				(type default)
			)
			(layer "F.SilkS")
		)
		(fp_line
			(start -0.7874 -0.4064)
			(end 0.7874 -0.4064)
			(stroke
				(width 0.1524)
				(type default)
			)
			(layer "F.SilkS")
		)
		(fp_line
			(start 0.67945 0.3048)
			(end 0.120396 0.3048)
			(stroke
				(width 0.1)
				(type default)
			)
			(layer "F.Fab")
		)
		(fp_line
			(start 0.67945 -0.3048)
			(end 0.67945 0.3048)
			(stroke
				(width 0.1)
				(type default)
			)
			(layer "F.Fab")
		)
		(fp_line
			(start 0.12065 -0.2794)
			(end 0.12065 -0.3048)
			(stroke
				(width 0.1)
				(type default)
			)
			(layer "F.Fab")
		)
		(fp_line
			(start 0.12065 -0.3048)
			(end 0.67945 -0.3048)
			(stroke
				(width 0.1)
				(type default)
			)
			(layer "F.Fab")
		)
		(fp_line
			(start 0.120396 0.3048)
			(end 0.120396 0.2794)
			(stroke
				(width 0.1)
				(type default)
			)
			(layer "F.Fab")
		)
		(fp_line
			(start 0.120396 0.2794)
			(end -0.12065 0.2794)
			(stroke
				(width 0.1)
				(type default)
			)
			(layer "F.Fab")
		)
		(fp_line
			(start -0.12065 0.3048)
			(end -0.67945 0.3048)
			(stroke
				(width 0.1)
				(type default)
			)
			(layer "F.Fab")
		)
		(fp_line
			(start -0.12065 0.2794)
			(end -0.12065 0.3048)
			(stroke
				(width 0.1)
				(type default)
			)
			(layer "F.Fab")
		)
		(fp_line
			(start -0.12065 -0.2794)
			(end 0.12065 -0.2794)
			(stroke
				(width 0.1)
				(type default)
			)
			(layer "F.Fab")
		)
		(fp_line
			(start -0.12065 -0.305054)
			(end -0.12065 -0.2794)
			(stroke
				(width 0.1)
				(type default)
			)
			(layer "F.Fab")
		)
		(fp_line
			(start -0.67945 0.3048)
			(end -0.67945 -0.305054)
			(stroke
				(width 0.1)
				(type default)
			)
			(layer "F.Fab")
		)
		(fp_line
			(start -0.67945 -0.305054)
			(end -0.12065 -0.305054)
			(stroke
				(width 0.1)
				(type default)
			)
			(layer "F.Fab")
		)
		(pad "1" smd circle
			(at -0.40005 0 180)
			(size 0 0)
			(layers "F.Cu" "F.Mask" "F.Paste")
			(net "GND")
		)
		(pad "2" smd circle
			(at 0.40005 0 180)
			(size 0 0)
			(layers "F.Cu" "F.Mask" "F.Paste")
			(net "PVDD11_S3_P1_ADDR_CFG")
		)
	)
	(footprint ""
		(layer "F.Cu")
		(at 305.819048 -40.890698 180)
		(property "Reference" "R3668"
			(at 0 0 180)
			(layer "F.SilkS")
			(hide yes)
			(effects
				(font
					(size 1.27 1.27)
				)
			)
		)
		(property "Value" ""
			(at 0 0 180)
			(layer "F.Fab")
			(effects
				(font
					(size 1.27 1.27)
				)
			)
		)
		(duplicate_pad_numbers_are_jumpers no)
		(fp_line
			(start 0.7874 0.4064)
			(end -0.7874 0.4064)
			(stroke
				(width 0.1524)
				(type default)
			)
			(layer "F.SilkS")
		)
		(fp_line
			(start 0.7874 -0.4064)
			(end 0.7874 0.4064)
			(stroke
				(width 0.1524)
				(type default)
			)
			(layer "F.SilkS")
		)
		(fp_line
			(start -0.7874 0.4064)
			(end -0.7874 -0.4064)
			(stroke
				(width 0.1524)
				(type default)
			)
			(layer "F.SilkS")
		)
		(fp_line
			(start -0.7874 -0.4064)
			(end 0.7874 -0.4064)
			(stroke
				(width 0.1524)
				(type default)
			)
			(layer "F.SilkS")
		)
		(fp_line
			(start 0.67945 0.3048)
			(end 0.120396 0.3048)
			(stroke
				(width 0.1)
				(type default)
			)
			(layer "F.Fab")
		)
		(fp_line
			(start 0.67945 -0.3048)
			(end 0.67945 0.3048)
			(stroke
				(width 0.1)
				(type default)
			)
			(layer "F.Fab")
		)
		(fp_line
			(start 0.12065 -0.2794)
			(end 0.12065 -0.3048)
			(stroke
				(width 0.1)
				(type default)
			)
			(layer "F.Fab")
		)
		(fp_line
			(start 0.12065 -0.3048)
			(end 0.67945 -0.3048)
			(stroke
				(width 0.1)
				(type default)
			)
			(layer "F.Fab")
		)
		(fp_line
			(start 0.120396 0.3048)
			(end 0.120396 0.2794)
			(stroke
				(width 0.1)
				(type default)
			)
			(layer "F.Fab")
		)
		(fp_line
			(start 0.120396 0.2794)
			(end -0.12065 0.2794)
			(stroke
				(width 0.1)
				(type default)
			)
			(layer "F.Fab")
		)
		(fp_line
			(start -0.12065 0.3048)
			(end -0.67945 0.3048)
			(stroke
				(width 0.1)
				(type default)
			)
			(layer "F.Fab")
		)
		(fp_line
			(start -0.12065 0.2794)
			(end -0.12065 0.3048)
			(stroke
				(width 0.1)
				(type default)
			)
			(layer "F.Fab")
		)
		(fp_line
			(start -0.12065 -0.2794)
			(end 0.12065 -0.2794)
			(stroke
				(width 0.1)
				(type default)
			)
			(layer "F.Fab")
		)
		(fp_line
			(start -0.12065 -0.305054)
			(end -0.12065 -0.2794)
			(stroke
				(width 0.1)
				(type default)
			)
			(layer "F.Fab")
		)
		(fp_line
			(start -0.67945 0.3048)
			(end -0.67945 -0.305054)
			(stroke
				(width 0.1)
				(type default)
			)
			(layer "F.Fab")
		)
		(fp_line
			(start -0.67945 -0.305054)
			(end -0.12065 -0.305054)
			(stroke
				(width 0.1)
				(type default)
			)
			(layer "F.Fab")
		)
		(pad "1" smd circle
			(at -0.40005 0 180)
			(size 0 0)
			(layers "F.Cu" "F.Mask" "F.Paste")
			(net "ADC128_A1")
		)
		(pad "2" smd circle
			(at 0.40005 0 180)
			(size 0 0)
			(layers "F.Cu" "F.Mask" "F.Paste")
			(net "GND")
		)
	)
	(footprint ""
		(layer "F.Cu")
		(at 139.374626 -408.517344 -90)
		(property "Reference" "C6710"
			(at 0 0 270)
			(layer "F.SilkS")
			(hide yes)
			(effects
				(font
					(size 1.27 1.27)
				)
			)
		)
		(property "Value" ""
			(at 0 0 270)
			(layer "F.Fab")
			(effects
				(font
					(size 1.27 1.27)
				)
			)
		)
		(duplicate_pad_numbers_are_jumpers no)
		(fp_line
			(start -0.299974 0.150114)
			(end -0.299974 -0.150114)
			(stroke
				(width 0.1)
				(type default)
			)
			(layer "F.Fab")
		)
		(fp_line
			(start 0.299974 0.150114)
			(end -0.299974 0.150114)
			(stroke
				(width 0.1)
				(type default)
			)
			(layer "F.Fab")
		)
		(fp_line
			(start -0.299974 -0.150114)
			(end 0.299974 -0.150114)
			(stroke
				(width 0.1)
				(type default)
			)
			(layer "F.Fab")
		)
		(fp_line
			(start 0.299974 -0.150114)
			(end 0.299974 0.150114)
			(stroke
				(width 0.1)
				(type default)
			)
			(layer "F.Fab")
		)
		(pad "1" smd rect
			(at -0.2667 0 270)
			(size 0.3048 0.381)
			(layers "F.Cu" "F.Mask" "F.Paste")
			(net "P5E_CPU1_P2_TX_BUF_C_DN<8>")
		)
		(pad "2" smd rect
			(at 0.2667 0 270)
			(size 0.3048 0.381)
			(layers "F.Cu" "F.Mask" "F.Paste")
			(net "P5E_CPU1_P2_TX_BUF_DN<8>")
		)
	)
	(footprint ""
		(layer "F.Cu")
		(at 95.494094 -325.675752)
		(property "Reference" "PL45"
			(at -2.657094 -16.689578 0)
			(unlocked yes)
			(layer "F.SilkS")
			(effects
				(font
					(size 0.7874 0.5842)
					(thickness 0.1524)
				)
				(justify left)
			)
		)
		(property "Value" ""
			(at 0 0 0)
			(layer "F.Fab")
			(effects
				(font
					(size 1.27 1.27)
				)
			)
		)
		(duplicate_pad_numbers_are_jumpers no)
		(fp_line
			(start -3.750056 -5.500116)
			(end -2.393442 -5.500116)
			(stroke
				(width 0.1524)
				(type default)
			)
			(layer "F.SilkS")
		)
		(fp_line
			(start -3.750056 5.500116)
			(end -3.750056 -5.500116)
			(stroke
				(width 0.1524)
				(type default)
			)
			(layer "F.SilkS")
		)
		(fp_line
			(start -2.393442 5.500116)
			(end -3.750056 5.500116)
			(stroke
				(width 0.1524)
				(type default)
			)
			(layer "F.SilkS")
		)
		(fp_line
			(start 2.393442 5.500116)
			(end 3.750056 5.500116)
			(stroke
				(width 0.1524)
				(type default)
			)
			(layer "F.SilkS")
		)
		(fp_line
			(start 3.750056 -5.500116)
			(end 2.393442 -5.500116)
			(stroke
				(width 0.1524)
				(type default)
			)
			(layer "F.SilkS")
		)
		(fp_line
			(start 3.750056 5.500116)
			(end 3.750056 -5.500116)
			(stroke
				(width 0.1524)
				(type default)
			)
			(layer "F.SilkS")
		)
		(fp_poly
			(pts
				(xy -3.9116 -4.249928) (xy -4.3434 -4.034028) (xy -4.3434 -4.465828)
			)
			(stroke
				(width 0)
				(type default)
			)
			(fill yes)
			(layer "F.SilkS")
		)
		(fp_line
			(start -3.750056 -5.500116)
			(end -3.750056 5.500116)
			(stroke
				(width 0.1)
				(type default)
			)
			(layer "F.Fab")
		)
		(fp_line
			(start -3.750056 5.500116)
			(end 3.750056 5.500116)
			(stroke
				(width 0.1)
				(type default)
			)
			(layer "F.Fab")
		)
		(fp_line
			(start 3.750056 -5.500116)
			(end -3.750056 -5.500116)
			(stroke
				(width 0.1)
				(type default)
			)
			(layer "F.Fab")
		)
		(fp_line
			(start 3.750056 5.500116)
			(end 3.750056 -5.500116)
			(stroke
				(width 0.1)
				(type default)
			)
			(layer "F.Fab")
		)
		(fp_poly
			(pts
				(xy -4.9276 -4.757928) (xy -4.9276 -3.741928) (xy -3.9116 -4.249928)
			)
			(stroke
				(width 0)
				(type default)
			)
			(fill yes)
			(layer "F.Fab")
		)
		(pad "1" smd rect
			(at 0 -4.249928 270)
			(size 2.413 4.5212)
			(layers "F.Cu" "F.Mask" "F.Paste")
			(net "SW_PVDDCR_CPU1_P1_SW5")
		)
		(pad "2" smd rect
			(at 0 -1.175004 270)
			(size 1.3716 4.5212)
			(layers "F.Cu" "F.Mask" "F.Paste")
			(net "IND_CPU1_P1_CPL6")
		)
		(pad "3" smd rect
			(at 0 1.175004 270)
			(size 1.3716 4.5212)
			(layers "F.Cu" "F.Mask" "F.Paste")
			(net "IND_CPU1_P1_CPL5")
		)
		(pad "4" smd rect
			(at 0 4.249928 270)
			(size 2.413 4.5212)
			(layers "F.Cu" "F.Mask" "F.Paste")
			(net "PVDDCR_CPU1_P1")
		)
	)
	(footprint ""
		(layer "F.Cu")
		(at 450.717666 -401.93087 180)
		(property "Reference" "PC6576"
			(at 0 0 180)
			(layer "F.SilkS")
			(hide yes)
			(effects
				(font
					(size 1.27 1.27)
				)
			)
		)
		(property "Value" ""
			(at 0 0 180)
			(layer "F.Fab")
			(effects
				(font
					(size 1.27 1.27)
				)
			)
		)
		(duplicate_pad_numbers_are_jumpers no)
		(fp_line
			(start 0.7874 0.4064)
			(end -0.7874 0.4064)
			(stroke
				(width 0.1524)
				(type default)
			)
			(layer "F.SilkS")
		)
		(fp_line
			(start 0.7874 -0.4064)
			(end 0.7874 0.4064)
			(stroke
				(width 0.1524)
				(type default)
			)
			(layer "F.SilkS")
		)
		(fp_line
			(start -0.7874 0.4064)
			(end -0.7874 -0.4064)
			(stroke
				(width 0.1524)
				(type default)
			)
			(layer "F.SilkS")
		)
		(fp_line
			(start -0.7874 -0.4064)
			(end 0.7874 -0.4064)
			(stroke
				(width 0.1524)
				(type default)
			)
			(layer "F.SilkS")
		)
		(fp_line
			(start 0.67945 0.3048)
			(end 0.120396 0.3048)
			(stroke
				(width 0.1)
				(type default)
			)
			(layer "F.Fab")
		)
		(fp_line
			(start 0.67945 -0.3048)
			(end 0.67945 0.3048)
			(stroke
				(width 0.1)
				(type default)
			)
			(layer "F.Fab")
		)
		(fp_line
			(start 0.12065 -0.2794)
			(end 0.12065 -0.3048)
			(stroke
				(width 0.1)
				(type default)
			)
			(layer "F.Fab")
		)
		(fp_line
			(start 0.12065 -0.3048)
			(end 0.67945 -0.3048)
			(stroke
				(width 0.1)
				(type default)
			)
			(layer "F.Fab")
		)
		(fp_line
			(start 0.120396 0.3048)
			(end 0.120396 0.2794)
			(stroke
				(width 0.1)
				(type default)
			)
			(layer "F.Fab")
		)
		(fp_line
			(start 0.120396 0.2794)
			(end -0.12065 0.2794)
			(stroke
				(width 0.1)
				(type default)
			)
			(layer "F.Fab")
		)
		(fp_line
			(start -0.12065 0.3048)
			(end -0.67945 0.3048)
			(stroke
				(width 0.1)
				(type default)
			)
			(layer "F.Fab")
		)
		(fp_line
			(start -0.12065 0.2794)
			(end -0.12065 0.3048)
			(stroke
				(width 0.1)
				(type default)
			)
			(layer "F.Fab")
		)
		(fp_line
			(start -0.12065 -0.2794)
			(end 0.12065 -0.2794)
			(stroke
				(width 0.1)
				(type default)
			)
			(layer "F.Fab")
		)
		(fp_line
			(start -0.12065 -0.305054)
			(end -0.12065 -0.2794)
			(stroke
				(width 0.1)
				(type default)
			)
			(layer "F.Fab")
		)
		(fp_line
			(start -0.67945 0.3048)
			(end -0.67945 -0.305054)
			(stroke
				(width 0.1)
				(type default)
			)
			(layer "F.Fab")
		)
		(fp_line
			(start -0.67945 -0.305054)
			(end -0.12065 -0.305054)
			(stroke
				(width 0.1)
				(type default)
			)
			(layer "F.Fab")
		)
		(pad "1" smd circle
			(at -0.40005 0 180)
			(size 0 0)
			(layers "F.Cu" "F.Mask" "F.Paste")
			(net "PV09_RETIMER_CPU0_VCCS")
		)
		(pad "2" smd circle
			(at 0.40005 0 180)
			(size 0 0)
			(layers "F.Cu" "F.Mask" "F.Paste")
			(net "GND")
		)
	)
	(footprint ""
		(layer "F.Cu")
		(at 357.515922 -256.012188 90)
		(property "Reference" "C3930"
			(at 0 0 90)
			(layer "F.SilkS")
			(hide yes)
			(effects
				(font
					(size 1.27 1.27)
				)
			)
		)
		(property "Value" ""
			(at 0 0 90)
			(layer "F.Fab")
			(effects
				(font
					(size 1.27 1.27)
				)
			)
		)
		(duplicate_pad_numbers_are_jumpers no)
		(fp_line
			(start 0.7874 -0.4064)
			(end 0.7874 0.4064)
			(stroke
				(width 0.1524)
				(type default)
			)
			(layer "F.SilkS")
		)
		(fp_line
			(start -0.7874 -0.4064)
			(end 0.7874 -0.4064)
			(stroke
				(width 0.1524)
				(type default)
			)
			(layer "F.SilkS")
		)
		(fp_line
			(start 0.7874 0.4064)
			(end -0.7874 0.4064)
			(stroke
				(width 0.1524)
				(type default)
			)
			(layer "F.SilkS")
		)
		(fp_line
			(start -0.7874 0.4064)
			(end -0.7874 -0.4064)
			(stroke
				(width 0.1524)
				(type default)
			)
			(layer "F.SilkS")
		)
		(fp_line
			(start -0.12065 -0.305054)
			(end -0.12065 -0.2794)
			(stroke
				(width 0.1)
				(type default)
			)
			(layer "F.Fab")
		)
		(fp_line
			(start -0.67945 -0.305054)
			(end -0.12065 -0.305054)
			(stroke
				(width 0.1)
				(type default)
			)
			(layer "F.Fab")
		)
		(fp_line
			(start 0.67945 -0.3048)
			(end 0.67945 0.3048)
			(stroke
				(width 0.1)
				(type default)
			)
			(layer "F.Fab")
		)
		(fp_line
			(start 0.12065 -0.3048)
			(end 0.67945 -0.3048)
			(stroke
				(width 0.1)
				(type default)
			)
			(layer "F.Fab")
		)
		(fp_line
			(start 0.12065 -0.2794)
			(end 0.12065 -0.3048)
			(stroke
				(width 0.1)
				(type default)
			)
			(layer "F.Fab")
		)
		(fp_line
			(start -0.12065 -0.2794)
			(end 0.12065 -0.2794)
			(stroke
				(width 0.1)
				(type default)
			)
			(layer "F.Fab")
		)
		(fp_line
			(start 0.120396 0.2794)
			(end -0.12065 0.2794)
			(stroke
				(width 0.1)
				(type default)
			)
			(layer "F.Fab")
		)
		(fp_line
			(start -0.12065 0.2794)
			(end -0.12065 0.3048)
			(stroke
				(width 0.1)
				(type default)
			)
			(layer "F.Fab")
		)
		(fp_line
			(start 0.67945 0.3048)
			(end 0.120396 0.3048)
			(stroke
				(width 0.1)
				(type default)
			)
			(layer "F.Fab")
		)
		(fp_line
			(start 0.120396 0.3048)
			(end 0.120396 0.2794)
			(stroke
				(width 0.1)
				(type default)
			)
			(layer "F.Fab")
		)
		(fp_line
			(start -0.12065 0.3048)
			(end -0.67945 0.3048)
			(stroke
				(width 0.1)
				(type default)
			)
			(layer "F.Fab")
		)
		(fp_line
			(start -0.67945 0.3048)
			(end -0.67945 -0.305054)
			(stroke
				(width 0.1)
				(type default)
			)
			(layer "F.Fab")
		)
		(pad "1" smd circle
			(at -0.40005 0 90)
			(size 0 0)
			(layers "F.Cu" "F.Mask" "F.Paste")
			(net "PVDDCR_SOC_P0")
		)
		(pad "2" smd circle
			(at 0.40005 0 90)
			(size 0 0)
			(layers "F.Cu" "F.Mask" "F.Paste")
			(net "GND")
		)
	)
	(footprint ""
		(layer "F.Cu")
		(at 75.05573 -387.764274)
		(property "Reference" "R597"
			(at 0 0 0)
			(layer "F.SilkS")
			(hide yes)
			(effects
				(font
					(size 1.27 1.27)
				)
			)
		)
		(property "Value" ""
			(at 0 0 0)
			(layer "F.Fab")
			(effects
				(font
					(size 1.27 1.27)
				)
			)
		)
		(duplicate_pad_numbers_are_jumpers no)
		(fp_line
			(start -0.32512 -0.175006)
			(end 0.32512 -0.175006)
			(stroke
				(width 0.1)
				(type default)
			)
			(layer "F.Fab")
		)
		(fp_line
			(start -0.32512 0.175006)
			(end -0.32512 -0.175006)
			(stroke
				(width 0.1)
				(type default)
			)
			(layer "F.Fab")
		)
		(fp_line
			(start 0.32512 -0.175006)
			(end 0.32512 0.175006)
			(stroke
				(width 0.1)
				(type default)
			)
			(layer "F.Fab")
		)
		(fp_line
			(start 0.32512 0.175006)
			(end -0.32512 0.175006)
			(stroke
				(width 0.1)
				(type default)
			)
			(layer "F.Fab")
		)
		(pad "1" smd rect
			(at -0.2667 0)
			(size 0.3048 0.381)
			(layers "F.Cu" "F.Mask" "F.Paste")
			(net "CLK_100M_RETIMER_CPU1_P1_R_DP")
		)
		(pad "2" smd rect
			(at 0.2667 0 180)
			(size 0.3048 0.381)
			(layers "F.Cu" "F.Mask" "F.Paste")
			(net "CLK_100M_RETIMER_CPU1_P1_DP")
		)
	)
	(footprint ""
		(layer "F.Cu")
		(at 239.50803 -48.019208 180)
		(property "Reference" "R3779"
			(at 0 0 180)
			(layer "F.SilkS")
			(hide yes)
			(effects
				(font
					(size 1.27 1.27)
				)
			)
		)
		(property "Value" ""
			(at 0 0 180)
			(layer "F.Fab")
			(effects
				(font
					(size 1.27 1.27)
				)
			)
		)
		(duplicate_pad_numbers_are_jumpers no)
		(fp_line
			(start 0.7874 0.4064)
			(end -0.7874 0.4064)
			(stroke
				(width 0.1524)
				(type default)
			)
			(layer "F.SilkS")
		)
		(fp_line
			(start 0.7874 -0.4064)
			(end 0.7874 0.4064)
			(stroke
				(width 0.1524)
				(type default)
			)
			(layer "F.SilkS")
		)
		(fp_line
			(start -0.7874 0.4064)
			(end -0.7874 -0.4064)
			(stroke
				(width 0.1524)
				(type default)
			)
			(layer "F.SilkS")
		)
		(fp_line
			(start -0.7874 -0.4064)
			(end 0.7874 -0.4064)
			(stroke
				(width 0.1524)
				(type default)
			)
			(layer "F.SilkS")
		)
		(fp_line
			(start 0.67945 0.3048)
			(end 0.120396 0.3048)
			(stroke
				(width 0.1)
				(type default)
			)
			(layer "F.Fab")
		)
		(fp_line
			(start 0.67945 -0.3048)
			(end 0.67945 0.3048)
			(stroke
				(width 0.1)
				(type default)
			)
			(layer "F.Fab")
		)
		(fp_line
			(start 0.12065 -0.2794)
			(end 0.12065 -0.3048)
			(stroke
				(width 0.1)
				(type default)
			)
			(layer "F.Fab")
		)
		(fp_line
			(start 0.12065 -0.3048)
			(end 0.67945 -0.3048)
			(stroke
				(width 0.1)
				(type default)
			)
			(layer "F.Fab")
		)
		(fp_line
			(start 0.120396 0.3048)
			(end 0.120396 0.2794)
			(stroke
				(width 0.1)
				(type default)
			)
			(layer "F.Fab")
		)
		(fp_line
			(start 0.120396 0.2794)
			(end -0.12065 0.2794)
			(stroke
				(width 0.1)
				(type default)
			)
			(layer "F.Fab")
		)
		(fp_line
			(start -0.12065 0.3048)
			(end -0.67945 0.3048)
			(stroke
				(width 0.1)
				(type default)
			)
			(layer "F.Fab")
		)
		(fp_line
			(start -0.12065 0.2794)
			(end -0.12065 0.3048)
			(stroke
				(width 0.1)
				(type default)
			)
			(layer "F.Fab")
		)
		(fp_line
			(start -0.12065 -0.2794)
			(end 0.12065 -0.2794)
			(stroke
				(width 0.1)
				(type default)
			)
			(layer "F.Fab")
		)
		(fp_line
			(start -0.12065 -0.305054)
			(end -0.12065 -0.2794)
			(stroke
				(width 0.1)
				(type default)
			)
			(layer "F.Fab")
		)
		(fp_line
			(start -0.67945 0.3048)
			(end -0.67945 -0.305054)
			(stroke
				(width 0.1)
				(type default)
			)
			(layer "F.Fab")
		)
		(fp_line
			(start -0.67945 -0.305054)
			(end -0.12065 -0.305054)
			(stroke
				(width 0.1)
				(type default)
			)
			(layer "F.Fab")
		)
		(pad "1" smd circle
			(at -0.40005 0 180)
			(size 0 0)
			(layers "F.Cu" "F.Mask" "F.Paste")
			(net "RST_PERST_E1S_0_N")
		)
		(pad "2" smd circle
			(at 0.40005 0 180)
			(size 0 0)
			(layers "F.Cu" "F.Mask" "F.Paste")
			(net "RST_PCIE_E1S_PERST_N")
		)
	)
	(footprint ""
		(layer "F.Cu")
		(at 60.012834 -150.979632 180)
		(property "Reference" "PL57"
			(at -1.85674 -6.476746 0)
			(unlocked yes)
			(layer "F.SilkS")
			(effects
				(font
					(size 0.7874 0.5842)
					(thickness 0.1524)
				)
				(justify left)
			)
		)
		(property "Value" ""
			(at 0 0 180)
			(layer "F.Fab")
			(effects
				(font
					(size 1.27 1.27)
				)
			)
		)
		(duplicate_pad_numbers_are_jumpers no)
		(fp_line
			(start 5.1054 5.100066)
			(end 5.1054 1.8796)
			(stroke
				(width 0.1524)
				(type default)
			)
			(layer "F.SilkS")
		)
		(fp_line
			(start 5.1054 -1.8796)
			(end 5.1054 -5.100066)
			(stroke
				(width 0.1524)
				(type default)
			)
			(layer "F.SilkS")
		)
		(fp_line
			(start 5.1054 -5.100066)
			(end -5.1054 -5.100066)
			(stroke
				(width 0.1524)
				(type default)
			)
			(layer "F.SilkS")
		)
		(fp_line
			(start -5.1054 5.100066)
			(end 5.1054 5.100066)
			(stroke
				(width 0.1524)
				(type default)
			)
			(layer "F.SilkS")
		)
		(fp_line
			(start -5.1054 1.8796)
			(end -5.1054 5.100066)
			(stroke
				(width 0.1524)
				(type default)
			)
			(layer "F.SilkS")
		)
		(fp_line
			(start -5.1054 -5.100066)
			(end -5.1054 -1.8796)
			(stroke
				(width 0.1524)
				(type default)
			)
			(layer "F.SilkS")
		)
		(fp_line
			(start 5.1054 5.100066)
			(end -5.1054 5.100066)
			(stroke
				(width 0.1)
				(type default)
			)
			(layer "F.Fab")
		)
		(fp_line
			(start 5.1054 -5.100066)
			(end 5.1054 5.100066)
			(stroke
				(width 0.1)
				(type default)
			)
			(layer "F.Fab")
		)
		(fp_line
			(start -5.1054 5.100066)
			(end -5.1054 -5.100066)
			(stroke
				(width 0.1)
				(type default)
			)
			(layer "F.Fab")
		)
		(fp_line
			(start -5.1054 -5.100066)
			(end 5.1054 -5.100066)
			(stroke
				(width 0.1)
				(type default)
			)
			(layer "F.Fab")
		)
		(pad "1" smd rect
			(at -3.999992 0 180)
			(size 3.5052 3.5052)
			(layers "F.Cu" "F.Mask" "F.Paste")
			(net "SW_PVDD18_S5_P1_SW")
		)
		(pad "2" smd rect
			(at 3.999992 0 180)
			(size 3.5052 3.5052)
			(layers "F.Cu" "F.Mask" "F.Paste")
			(net "PVDD18_S5_P1")
		)
	)
	(footprint ""
		(layer "F.Cu")
		(at 215.4301 -399.956782)
		(property "Reference" "PR3921"
			(at 0 0 0)
			(layer "F.SilkS")
			(hide yes)
			(effects
				(font
					(size 1.27 1.27)
				)
			)
		)
		(property "Value" ""
			(at 0 0 0)
			(layer "F.Fab")
			(effects
				(font
					(size 1.27 1.27)
				)
			)
		)
		(duplicate_pad_numbers_are_jumpers no)
		(fp_line
			(start -0.7874 -0.4064)
			(end 0.7874 -0.4064)
			(stroke
				(width 0.1524)
				(type default)
			)
			(layer "F.SilkS")
		)
		(fp_line
			(start -0.7874 0.4064)
			(end -0.7874 -0.4064)
			(stroke
				(width 0.1524)
				(type default)
			)
			(layer "F.SilkS")
		)
		(fp_line
			(start 0.7874 -0.4064)
			(end 0.7874 0.4064)
			(stroke
				(width 0.1524)
				(type default)
			)
			(layer "F.SilkS")
		)
		(fp_line
			(start 0.7874 0.4064)
			(end -0.7874 0.4064)
			(stroke
				(width 0.1524)
				(type default)
			)
			(layer "F.SilkS")
		)
		(fp_line
			(start -0.67945 -0.305054)
			(end -0.12065 -0.305054)
			(stroke
				(width 0.1)
				(type default)
			)
			(layer "F.Fab")
		)
		(fp_line
			(start -0.67945 0.3048)
			(end -0.67945 -0.305054)
			(stroke
				(width 0.1)
				(type default)
			)
			(layer "F.Fab")
		)
		(fp_line
			(start -0.12065 -0.305054)
			(end -0.12065 -0.2794)
			(stroke
				(width 0.1)
				(type default)
			)
			(layer "F.Fab")
		)
		(fp_line
			(start -0.12065 -0.2794)
			(end 0.12065 -0.2794)
			(stroke
				(width 0.1)
				(type default)
			)
			(layer "F.Fab")
		)
		(fp_line
			(start -0.12065 0.2794)
			(end -0.12065 0.3048)
			(stroke
				(width 0.1)
				(type default)
			)
			(layer "F.Fab")
		)
		(fp_line
			(start -0.12065 0.3048)
			(end -0.67945 0.3048)
			(stroke
				(width 0.1)
				(type default)
			)
			(layer "F.Fab")
		)
		(fp_line
			(start 0.120396 0.2794)
			(end -0.12065 0.2794)
			(stroke
				(width 0.1)
				(type default)
			)
			(layer "F.Fab")
		)
		(fp_line
			(start 0.120396 0.3048)
			(end 0.120396 0.2794)
			(stroke
				(width 0.1)
				(type default)
			)
			(layer "F.Fab")
		)
		(fp_line
			(start 0.12065 -0.3048)
			(end 0.67945 -0.3048)
			(stroke
				(width 0.1)
				(type default)
			)
			(layer "F.Fab")
		)
		(fp_line
			(start 0.12065 -0.2794)
			(end 0.12065 -0.3048)
			(stroke
				(width 0.1)
				(type default)
			)
			(layer "F.Fab")
		)
		(fp_line
			(start 0.67945 -0.3048)
			(end 0.67945 0.3048)
			(stroke
				(width 0.1)
				(type default)
			)
			(layer "F.Fab")
		)
		(fp_line
			(start 0.67945 0.3048)
			(end 0.120396 0.3048)
			(stroke
				(width 0.1)
				(type default)
			)
			(layer "F.Fab")
		)
		(pad "1" smd circle
			(at -0.40005 0)
			(size 0 0)
			(layers "F.Cu" "F.Mask" "F.Paste")
			(net "HSC_D_OC_2")
		)
		(pad "2" smd circle
			(at 0.40005 0)
			(size 0 0)
			(layers "F.Cu" "F.Mask" "F.Paste")
			(net "HSC_D_OC_R")
		)
	)
	(footprint ""
		(layer "F.Cu")
		(at 344.505026 -416.899344 -90)
		(property "Reference" "C6527"
			(at 0 0 270)
			(layer "F.SilkS")
			(hide yes)
			(effects
				(font
					(size 1.27 1.27)
				)
			)
		)
		(property "Value" ""
			(at 0 0 270)
			(layer "F.Fab")
			(effects
				(font
					(size 1.27 1.27)
				)
			)
		)
		(duplicate_pad_numbers_are_jumpers no)
		(fp_line
			(start -0.299974 0.150114)
			(end -0.299974 -0.150114)
			(stroke
				(width 0.1)
				(type default)
			)
			(layer "F.Fab")
		)
		(fp_line
			(start 0.299974 0.150114)
			(end -0.299974 0.150114)
			(stroke
				(width 0.1)
				(type default)
			)
			(layer "F.Fab")
		)
		(fp_line
			(start -0.299974 -0.150114)
			(end 0.299974 -0.150114)
			(stroke
				(width 0.1)
				(type default)
			)
			(layer "F.Fab")
		)
		(fp_line
			(start 0.299974 -0.150114)
			(end 0.299974 0.150114)
			(stroke
				(width 0.1)
				(type default)
			)
			(layer "F.Fab")
		)
		(pad "1" smd rect
			(at -0.2667 0 270)
			(size 0.3048 0.381)
			(layers "F.Cu" "F.Mask" "F.Paste")
			(net "P5E_CPU0_P0_TX_BUF_C_DP<13>")
		)
		(pad "2" smd rect
			(at 0.2667 0 270)
			(size 0.3048 0.381)
			(layers "F.Cu" "F.Mask" "F.Paste")
			(net "P5E_CPU0_P0_TX_BUF_DP<13>")
		)
	)
	(footprint ""
		(layer "F.Cu")
		(at 102.390194 -385.09448 180)
		(property "Reference" "R664"
			(at 0 0 180)
			(layer "F.SilkS")
			(hide yes)
			(effects
				(font
					(size 1.27 1.27)
				)
			)
		)
		(property "Value" ""
			(at 0 0 180)
			(layer "F.Fab")
			(effects
				(font
					(size 1.27 1.27)
				)
			)
		)
		(duplicate_pad_numbers_are_jumpers no)
		(fp_line
			(start 0.7874 0.4064)
			(end -0.7874 0.4064)
			(stroke
				(width 0.1524)
				(type default)
			)
			(layer "F.SilkS")
		)
		(fp_line
			(start 0.7874 -0.4064)
			(end 0.7874 0.4064)
			(stroke
				(width 0.1524)
				(type default)
			)
			(layer "F.SilkS")
		)
		(fp_line
			(start -0.7874 0.4064)
			(end -0.7874 -0.4064)
			(stroke
				(width 0.1524)
				(type default)
			)
			(layer "F.SilkS")
		)
		(fp_line
			(start -0.7874 -0.4064)
			(end 0.7874 -0.4064)
			(stroke
				(width 0.1524)
				(type default)
			)
			(layer "F.SilkS")
		)
		(fp_line
			(start 0.67945 0.3048)
			(end 0.120396 0.3048)
			(stroke
				(width 0.1)
				(type default)
			)
			(layer "F.Fab")
		)
		(fp_line
			(start 0.67945 -0.3048)
			(end 0.67945 0.3048)
			(stroke
				(width 0.1)
				(type default)
			)
			(layer "F.Fab")
		)
		(fp_line
			(start 0.12065 -0.2794)
			(end 0.12065 -0.3048)
			(stroke
				(width 0.1)
				(type default)
			)
			(layer "F.Fab")
		)
		(fp_line
			(start 0.12065 -0.3048)
			(end 0.67945 -0.3048)
			(stroke
				(width 0.1)
				(type default)
			)
			(layer "F.Fab")
		)
		(fp_line
			(start 0.120396 0.3048)
			(end 0.120396 0.2794)
			(stroke
				(width 0.1)
				(type default)
			)
			(layer "F.Fab")
		)
		(fp_line
			(start 0.120396 0.2794)
			(end -0.12065 0.2794)
			(stroke
				(width 0.1)
				(type default)
			)
			(layer "F.Fab")
		)
		(fp_line
			(start -0.12065 0.3048)
			(end -0.67945 0.3048)
			(stroke
				(width 0.1)
				(type default)
			)
			(layer "F.Fab")
		)
		(fp_line
			(start -0.12065 0.2794)
			(end -0.12065 0.3048)
			(stroke
				(width 0.1)
				(type default)
			)
			(layer "F.Fab")
		)
		(fp_line
			(start -0.12065 -0.2794)
			(end 0.12065 -0.2794)
			(stroke
				(width 0.1)
				(type default)
			)
			(layer "F.Fab")
		)
		(fp_line
			(start -0.12065 -0.305054)
			(end -0.12065 -0.2794)
			(stroke
				(width 0.1)
				(type default)
			)
			(layer "F.Fab")
		)
		(fp_line
			(start -0.67945 0.3048)
			(end -0.67945 -0.305054)
			(stroke
				(width 0.1)
				(type default)
			)
			(layer "F.Fab")
		)
		(fp_line
			(start -0.67945 -0.305054)
			(end -0.12065 -0.305054)
			(stroke
				(width 0.1)
				(type default)
			)
			(layer "F.Fab")
		)
		(pad "1" smd rect
			(at -0.40005 0)
			(size 0.4572 0.508)
			(layers "F.Cu" "F.Mask" "F.Paste")
			(net "P1V8_CPU1_RT1_1A_1D")
		)
		(pad "2" smd rect
			(at 0.40005 0)
			(size 0.4572 0.508)
			(layers "F.Cu" "F.Mask" "F.Paste")
			(net "P1V8_CPU1_RT1_1A")
		)
	)
	(footprint ""
		(layer "F.Cu")
		(at 367.157 -413.639 90)
		(property "Reference" "R4180"
			(at 0 0 90)
			(layer "F.SilkS")
			(hide yes)
			(effects
				(font
					(size 1.27 1.27)
				)
			)
		)
		(property "Value" ""
			(at 0 0 90)
			(layer "F.Fab")
			(effects
				(font
					(size 1.27 1.27)
				)
			)
		)
		(duplicate_pad_numbers_are_jumpers no)
		(fp_line
			(start 0.7874 -0.4064)
			(end 0.7874 0.4064)
			(stroke
				(width 0.1524)
				(type default)
			)
			(layer "F.SilkS")
		)
		(fp_line
			(start -0.7874 -0.4064)
			(end 0.7874 -0.4064)
			(stroke
				(width 0.1524)
				(type default)
			)
			(layer "F.SilkS")
		)
		(fp_line
			(start 0.7874 0.4064)
			(end -0.7874 0.4064)
			(stroke
				(width 0.1524)
				(type default)
			)
			(layer "F.SilkS")
		)
		(fp_line
			(start -0.7874 0.4064)
			(end -0.7874 -0.4064)
			(stroke
				(width 0.1524)
				(type default)
			)
			(layer "F.SilkS")
		)
		(fp_line
			(start -0.12065 -0.305054)
			(end -0.12065 -0.2794)
			(stroke
				(width 0.1)
				(type default)
			)
			(layer "F.Fab")
		)
		(fp_line
			(start -0.67945 -0.305054)
			(end -0.12065 -0.305054)
			(stroke
				(width 0.1)
				(type default)
			)
			(layer "F.Fab")
		)
		(fp_line
			(start 0.67945 -0.3048)
			(end 0.67945 0.3048)
			(stroke
				(width 0.1)
				(type default)
			)
			(layer "F.Fab")
		)
		(fp_line
			(start 0.12065 -0.3048)
			(end 0.67945 -0.3048)
			(stroke
				(width 0.1)
				(type default)
			)
			(layer "F.Fab")
		)
		(fp_line
			(start 0.12065 -0.2794)
			(end 0.12065 -0.3048)
			(stroke
				(width 0.1)
				(type default)
			)
			(layer "F.Fab")
		)
		(fp_line
			(start -0.12065 -0.2794)
			(end 0.12065 -0.2794)
			(stroke
				(width 0.1)
				(type default)
			)
			(layer "F.Fab")
		)
		(fp_line
			(start 0.120396 0.2794)
			(end -0.12065 0.2794)
			(stroke
				(width 0.1)
				(type default)
			)
			(layer "F.Fab")
		)
		(fp_line
			(start -0.12065 0.2794)
			(end -0.12065 0.3048)
			(stroke
				(width 0.1)
				(type default)
			)
			(layer "F.Fab")
		)
		(fp_line
			(start 0.67945 0.3048)
			(end 0.120396 0.3048)
			(stroke
				(width 0.1)
				(type default)
			)
			(layer "F.Fab")
		)
		(fp_line
			(start 0.120396 0.3048)
			(end 0.120396 0.2794)
			(stroke
				(width 0.1)
				(type default)
			)
			(layer "F.Fab")
		)
		(fp_line
			(start -0.12065 0.3048)
			(end -0.67945 0.3048)
			(stroke
				(width 0.1)
				(type default)
			)
			(layer "F.Fab")
		)
		(fp_line
			(start -0.67945 0.3048)
			(end -0.67945 -0.305054)
			(stroke
				(width 0.1)
				(type default)
			)
			(layer "F.Fab")
		)
		(pad "1" smd circle
			(at -0.40005 0 90)
			(size 0 0)
			(layers "F.Cu" "F.Mask" "F.Paste")
			(net "SMB_LM75_0_3V3AUX_SCL")
		)
		(pad "2" smd circle
			(at 0.40005 0 90)
			(size 0 0)
			(layers "F.Cu" "F.Mask" "F.Paste")
			(net "SMB_LM75_0_3V3AUX_SCL_R1")
		)
	)
	(footprint ""
		(layer "F.Cu")
		(at 8.324596 -133.95198 -90)
		(property "Reference" "C94"
			(at 0 0 270)
			(layer "F.SilkS")
			(hide yes)
			(effects
				(font
					(size 1.27 1.27)
				)
			)
		)
		(property "Value" ""
			(at 0 0 270)
			(layer "F.Fab")
			(effects
				(font
					(size 1.27 1.27)
				)
			)
		)
		(duplicate_pad_numbers_are_jumpers no)
		(fp_line
			(start -0.7874 0.4064)
			(end -0.7874 -0.4064)
			(stroke
				(width 0.1524)
				(type default)
			)
			(layer "F.SilkS")
		)
		(fp_line
			(start 0.7874 0.4064)
			(end -0.7874 0.4064)
			(stroke
				(width 0.1524)
				(type default)
			)
			(layer "F.SilkS")
		)
		(fp_line
			(start -0.7874 -0.4064)
			(end 0.7874 -0.4064)
			(stroke
				(width 0.1524)
				(type default)
			)
			(layer "F.SilkS")
		)
		(fp_line
			(start 0.7874 -0.4064)
			(end 0.7874 0.4064)
			(stroke
				(width 0.1524)
				(type default)
			)
			(layer "F.SilkS")
		)
		(fp_line
			(start -0.67945 0.3048)
			(end -0.67945 -0.305054)
			(stroke
				(width 0.1)
				(type default)
			)
			(layer "F.Fab")
		)
		(fp_line
			(start -0.12065 0.3048)
			(end -0.67945 0.3048)
			(stroke
				(width 0.1)
				(type default)
			)
			(layer "F.Fab")
		)
		(fp_line
			(start 0.120396 0.3048)
			(end 0.120396 0.2794)
			(stroke
				(width 0.1)
				(type default)
			)
			(layer "F.Fab")
		)
		(fp_line
			(start 0.67945 0.3048)
			(end 0.120396 0.3048)
			(stroke
				(width 0.1)
				(type default)
			)
			(layer "F.Fab")
		)
		(fp_line
			(start -0.12065 0.2794)
			(end -0.12065 0.3048)
			(stroke
				(width 0.1)
				(type default)
			)
			(layer "F.Fab")
		)
		(fp_line
			(start 0.120396 0.2794)
			(end -0.12065 0.2794)
			(stroke
				(width 0.1)
				(type default)
			)
			(layer "F.Fab")
		)
		(fp_line
			(start -0.12065 -0.2794)
			(end 0.12065 -0.2794)
			(stroke
				(width 0.1)
				(type default)
			)
			(layer "F.Fab")
		)
		(fp_line
			(start 0.12065 -0.2794)
			(end 0.12065 -0.3048)
			(stroke
				(width 0.1)
				(type default)
			)
			(layer "F.Fab")
		)
		(fp_line
			(start 0.12065 -0.3048)
			(end 0.67945 -0.3048)
			(stroke
				(width 0.1)
				(type default)
			)
			(layer "F.Fab")
		)
		(fp_line
			(start 0.67945 -0.3048)
			(end 0.67945 0.3048)
			(stroke
				(width 0.1)
				(type default)
			)
			(layer "F.Fab")
		)
		(fp_line
			(start -0.67945 -0.305054)
			(end -0.12065 -0.305054)
			(stroke
				(width 0.1)
				(type default)
			)
			(layer "F.Fab")
		)
		(fp_line
			(start -0.12065 -0.305054)
			(end -0.12065 -0.2794)
			(stroke
				(width 0.1)
				(type default)
			)
			(layer "F.Fab")
		)
		(pad "1" smd circle
			(at -0.40005 0 270)
			(size 0 0)
			(layers "F.Cu" "F.Mask" "F.Paste")
			(net "CLK_GEN2_XTAL_OUT")
		)
		(pad "2" smd circle
			(at 0.40005 0 270)
			(size 0 0)
			(layers "F.Cu" "F.Mask" "F.Paste")
			(net "GND")
		)
	)
	(footprint ""
		(layer "F.Cu")
		(at 317.284608 -15.337536 -90)
		(property "Reference" "J8"
			(at -4.073398 -0.944118 0)
			(unlocked yes)
			(layer "F.SilkS")
			(effects
				(font
					(size 0.7874 0.5842)
					(thickness 0.1524)
				)
				(justify left)
			)
		)
		(property "Value" ""
			(at 0 0 270)
			(layer "F.Fab")
			(effects
				(font
					(size 1.27 1.27)
				)
			)
		)
		(duplicate_pad_numbers_are_jumpers no)
		(fp_line
			(start -2.999994 7.999984)
			(end -0.899922 7.999984)
			(stroke
				(width 0.1524)
				(type default)
			)
			(layer "F.SilkS")
		)
		(fp_line
			(start -0.899922 7.999984)
			(end 1.700022 7.999984)
			(stroke
				(width 0.1524)
				(type default)
			)
			(layer "F.SilkS")
		)
		(fp_line
			(start 1.700022 7.999984)
			(end 1.700022 -1.999996)
			(stroke
				(width 0.1524)
				(type default)
			)
			(layer "F.SilkS")
		)
		(fp_line
			(start -2.500122 7.500112)
			(end -2.500122 6.568694)
			(stroke
				(width 0.1524)
				(type default)
			)
			(layer "F.SilkS")
		)
		(fp_line
			(start 1.199896 7.500112)
			(end -2.500122 7.500112)
			(stroke
				(width 0.1524)
				(type default)
			)
			(layer "F.SilkS")
		)
		(fp_line
			(start -2.500122 5.425694)
			(end -2.500122 -1.500124)
			(stroke
				(width 0.1524)
				(type default)
			)
			(layer "F.SilkS")
		)
		(fp_line
			(start 1.199896 4.99999)
			(end 1.199896 7.500112)
			(stroke
				(width 0.1524)
				(type default)
			)
			(layer "F.SilkS")
		)
		(fp_line
			(start 1.700022 4.99999)
			(end 1.199896 4.99999)
			(stroke
				(width 0.1524)
				(type default)
			)
			(layer "F.SilkS")
		)
		(fp_line
			(start 1.199896 0.999998)
			(end 1.700022 0.999998)
			(stroke
				(width 0.1524)
				(type default)
			)
			(layer "F.SilkS")
		)
		(fp_line
			(start -2.500122 -1.500124)
			(end 1.199896 -1.500124)
			(stroke
				(width 0.1524)
				(type default)
			)
			(layer "F.SilkS")
		)
		(fp_line
			(start 1.199896 -1.500124)
			(end 1.199896 0.999998)
			(stroke
				(width 0.1524)
				(type default)
			)
			(layer "F.SilkS")
		)
		(fp_line
			(start -2.999994 -1.999996)
			(end -2.999994 7.999984)
			(stroke
				(width 0.1524)
				(type default)
			)
			(layer "F.SilkS")
		)
		(fp_line
			(start 1.700022 -1.999996)
			(end -2.999994 -1.999996)
			(stroke
				(width 0.1524)
				(type default)
			)
			(layer "F.SilkS")
		)
		(fp_poly
			(pts
				(xy 0.762 -3.731006) (xy 0 -2.207006) (xy -0.762 -3.731006)
			)
			(stroke
				(width 0)
				(type default)
			)
			(fill yes)
			(layer "F.SilkS")
		)
		(fp_line
			(start -2.999994 7.999984)
			(end -0.899922 7.999984)
			(stroke
				(width 0.1)
				(type default)
			)
			(layer "F.Fab")
		)
		(fp_line
			(start -0.899922 7.999984)
			(end 1.700022 7.999984)
			(stroke
				(width 0.1)
				(type default)
			)
			(layer "F.Fab")
		)
		(fp_line
			(start 1.700022 7.999984)
			(end 1.700022 -1.999996)
			(stroke
				(width 0.1)
				(type default)
			)
			(layer "F.Fab")
		)
		(fp_line
			(start -2.500122 7.500112)
			(end -2.500122 6.606794)
			(stroke
				(width 0.1)
				(type default)
			)
			(layer "F.Fab")
		)
		(fp_line
			(start 1.199896 7.500112)
			(end -2.500122 7.500112)
			(stroke
				(width 0.1)
				(type default)
			)
			(layer "F.Fab")
		)
		(fp_line
			(start -2.500122 6.657594)
			(end -2.500122 -1.500124)
			(stroke
				(width 0.1)
				(type default)
			)
			(layer "F.Fab")
		)
		(fp_line
			(start 1.199896 4.99999)
			(end 1.199896 7.500112)
			(stroke
				(width 0.1)
				(type default)
			)
			(layer "F.Fab")
		)
		(fp_line
			(start 1.700022 4.99999)
			(end 1.199896 4.99999)
			(stroke
				(width 0.1)
				(type default)
			)
			(layer "F.Fab")
		)
		(fp_line
			(start 1.199896 0.999998)
			(end 1.700022 0.999998)
			(stroke
				(width 0.1)
				(type default)
			)
			(layer "F.Fab")
		)
		(fp_line
			(start -2.500122 -1.500124)
			(end 1.199896 -1.500124)
			(stroke
				(width 0.1)
				(type default)
			)
			(layer "F.Fab")
		)
		(fp_line
			(start 1.199896 -1.500124)
			(end 1.199896 0.999998)
			(stroke
				(width 0.1)
				(type default)
			)
			(layer "F.Fab")
		)
		(fp_line
			(start -2.999994 -1.999996)
			(end -2.999994 7.999984)
			(stroke
				(width 0.1)
				(type default)
			)
			(layer "F.Fab")
		)
		(fp_line
			(start 1.700022 -1.999996)
			(end -2.999994 -1.999996)
			(stroke
				(width 0.1)
				(type default)
			)
			(layer "F.Fab")
		)
		(fp_poly
			(pts
				(xy 0 -2.207006) (xy -0.762 -3.731006) (xy 0.762 -3.731006)
			)
			(stroke
				(width 0)
				(type default)
			)
			(fill yes)
			(layer "F.Fab")
		)
		(pad "" np_thru_hole circle
			(at -1.800098 5.999988)
			(size 1.143 1.143)
			(drill 1.143)
			(layers "*.Cu" "*.Mask")
			(clearance 0.381)
			(thermal_gap 0.381)
		)
		(pad "1" thru_hole rect
			(at 0 0)
			(size 1.2192 1.2192)
			(drill 0.8128)
			(layers "*.Cu" "*.Mask")
			(remove_unused_layers no)
			(net "UART_VCC_J8")
			(clearance 0.0508)
			(thermal_gap 0.0508)
			(padstack
				(mode front_inner_back)
				(layer "Inner"
					(shape circle)
					(size 1.2192 1.2192)
					(clearance 0.0508)
				)
				(layer "B.Cu"
					(shape rect)
					(size 1.2192 1.2192)
					(clearance 0.0508)
				)
			)
		)
		(pad "2" thru_hole circle
			(at 0 1.999996)
			(size 1.2192 1.2192)
			(drill 0.8128)
			(layers "*.Cu" "*.Mask")
			(remove_unused_layers no)
			(net "UART_CPU0_SCM_LVC3_UART1_R_RX")
			(clearance 0.0508)
			(thermal_gap 0.0508)
		)
		(pad "3" thru_hole circle
			(at 0 3.999992)
			(size 1.2192 1.2192)
			(drill 0.8128)
			(layers "*.Cu" "*.Mask")
			(remove_unused_layers no)
			(net "UART_CPU0_SCM_LVC3_UART1_TX")
			(clearance 0.0508)
			(thermal_gap 0.0508)
		)
		(pad "4" thru_hole circle
			(at 0 5.999988)
			(size 1.2192 1.2192)
			(drill 0.8128)
			(layers "*.Cu" "*.Mask")
			(remove_unused_layers no)
			(net "GND")
			(clearance 0.0508)
			(thermal_gap 0.0508)
		)
		(zone
			(layers "F.Cu" "B.Cu" "In1.Cu" "In2.Cu" "In3.Cu" "In4.Cu" "In5.Cu" "In6.Cu"
				"In7.Cu" "In8.Cu" "In9.Cu" "In10.Cu" "In11.Cu" "In12.Cu" "In13.Cu" "In14.Cu"
				"In15.Cu" "In16.Cu"
			)
			(hatch none 0.5)
			(connect_pads
				(clearance 0)
			)
			(min_thickness 0.25)
			(keepout
				(tracks not_allowed)
				(vias allowed)
				(pads allowed)
				(copperpour not_allowed)
				(footprints allowed)
			)
			(placement
				(enabled no)
				(sheetname "")
			)
			(fill
				(thermal_gap 0.5)
				(thermal_bridge_width 0.5)
				(island_removal_mode 0)
			)
			(polygon
				(pts
					(arc
						(start 310.266334 -17.126458)
						(mid 310.565401 -17.848471)
						(end 311.287414 -18.147538)
					)
					(arc
						(start 311.287414 -18.147538)
						(mid 312.295794 -17.139158)
						(end 311.287414 -16.130778)
					)
					(arc
						(start 311.262014 -16.130778)
						(mid 310.557962 -16.422406)
						(end 310.266334 -17.126458)
					)
				)
			)
		)
	)
	(footprint ""
		(layer "F.Cu")
		(at 429.024542 -428.30623 90)
		(property "Reference" "U6005"
			(at -0.025908 5.518658 90)
			(unlocked yes)
			(layer "F.SilkS")
			(effects
				(font
					(size 0.7874 0.5842)
					(thickness 0.1524)
				)
			)
		)
		(property "Value" ""
			(at 0 0 90)
			(layer "F.Fab")
			(effects
				(font
					(size 1.27 1.27)
				)
			)
		)
		(duplicate_pad_numbers_are_jumpers no)
		(fp_line
			(start 1.500124 -1.500124)
			(end 1.500124 -1.004062)
			(stroke
				(width 0.1524)
				(type default)
			)
			(layer "F.SilkS")
		)
		(fp_line
			(start 1.004062 -1.500124)
			(end 1.500124 -1.500124)
			(stroke
				(width 0.1524)
				(type default)
			)
			(layer "F.SilkS")
		)
		(fp_line
			(start -1.500124 -1.500124)
			(end -1.004062 -1.500124)
			(stroke
				(width 0.1524)
				(type default)
			)
			(layer "F.SilkS")
		)
		(fp_line
			(start -1.500124 -1.004062)
			(end -1.500124 -1.500124)
			(stroke
				(width 0.1524)
				(type default)
			)
			(layer "F.SilkS")
		)
		(fp_line
			(start 1.500124 1.004062)
			(end 1.500124 1.500124)
			(stroke
				(width 0.1524)
				(type default)
			)
			(layer "F.SilkS")
		)
		(fp_line
			(start 1.500124 1.500124)
			(end 1.004062 1.500124)
			(stroke
				(width 0.1524)
				(type default)
			)
			(layer "F.SilkS")
		)
		(fp_line
			(start -1.004062 1.500124)
			(end -1.500124 1.500124)
			(stroke
				(width 0.1524)
				(type default)
			)
			(layer "F.SilkS")
		)
		(fp_line
			(start -1.500124 1.500124)
			(end -1.500124 1.004062)
			(stroke
				(width 0.1524)
				(type default)
			)
			(layer "F.SilkS")
		)
		(fp_poly
			(pts
				(xy -1.862328 -1.148588) (xy -2.88036 -1.652778) (xy -2.069592 -2.265426)
			)
			(stroke
				(width 0)
				(type default)
			)
			(fill yes)
			(layer "F.SilkS")
		)
		(fp_line
			(start 1.500124 -1.500124)
			(end 1.500124 1.500124)
			(stroke
				(width 0.1)
				(type default)
			)
			(layer "F.Fab")
		)
		(fp_line
			(start -1.500124 -1.500124)
			(end 1.500124 -1.500124)
			(stroke
				(width 0.1)
				(type default)
			)
			(layer "F.Fab")
		)
		(fp_line
			(start 1.500124 1.500124)
			(end -1.500124 1.500124)
			(stroke
				(width 0.1)
				(type default)
			)
			(layer "F.Fab")
		)
		(fp_line
			(start -1.500124 1.500124)
			(end -1.500124 -1.500124)
			(stroke
				(width 0.1)
				(type default)
			)
			(layer "F.Fab")
		)
		(fp_poly
			(pts
				(xy -2.847848 -1.258062) (xy -2.847848 -0.242062) (xy -1.831848 -0.750062)
			)
			(stroke
				(width 0)
				(type default)
			)
			(fill yes)
			(layer "F.Fab")
		)
		(pad "1" smd rect
			(at -1.400048 -0.750062)
			(size 0.2286 0.6096)
			(layers "F.Cu" "F.Mask" "F.Paste")
			(net "HSC_TYPE_ADC_A1")
		)
		(pad "2" smd rect
			(at -1.400048 -0.249936)
			(size 0.2286 0.6096)
			(layers "F.Cu" "F.Mask" "F.Paste")
			(net "HSC_TYPE_ADC_A0")
		)
		(pad "3" smd rect
			(at -1.400048 0.249936)
			(size 0.2286 0.6096)
			(layers "F.Cu" "F.Mask" "F.Paste")
			(net "HSC_TYPE_ADC_ALERT")
		)
		(pad "4" smd rect
			(at -1.400048 0.750062)
			(size 0.2286 0.6096)
			(layers "F.Cu" "F.Mask" "F.Paste")
			(net "SMB_HSC_TYPE_ADC_SDA")
		)
		(pad "5" smd rect
			(at -0.750062 1.400048 90)
			(size 0.2286 0.6096)
			(layers "F.Cu" "F.Mask" "F.Paste")
			(net "SMB_HSC_TYPE_ADC_SCL")
		)
		(pad "6" smd rect
			(at -0.249936 1.400048 90)
			(size 0.2286 0.6096)
			(layers "F.Cu" "F.Mask" "F.Paste")
			(net "NC_HSC_TYPE_NC0")
		)
		(pad "7" smd rect
			(at 0.249936 1.400048 90)
			(size 0.2286 0.6096)
			(layers "F.Cu" "F.Mask" "F.Paste")
			(net "NC_HSC_TYPE_NC1")
		)
		(pad "8" smd rect
			(at 0.750062 1.400048 90)
			(size 0.2286 0.6096)
			(layers "F.Cu" "F.Mask" "F.Paste")
			(net "NC_HSC_TYPE_NC2")
		)
		(pad "9" smd rect
			(at 1.400048 0.750062)
			(size 0.2286 0.6096)
			(layers "F.Cu" "F.Mask" "F.Paste")
			(net "P3V3_AUX")
		)
		(pad "10" smd rect
			(at 1.400048 0.249936)
			(size 0.2286 0.6096)
			(layers "F.Cu" "F.Mask" "F.Paste")
			(net "GND")
		)
		(pad "11" smd rect
			(at 1.400048 -0.249936)
			(size 0.2286 0.6096)
			(layers "F.Cu" "F.Mask" "F.Paste")
			(net "HSC_TYPE_ADC")
		)
		(pad "12" smd rect
			(at 1.400048 -0.750062)
			(size 0.2286 0.6096)
			(layers "F.Cu" "F.Mask" "F.Paste")
			(net "NC_HSC_TYPE_VINM")
		)
		(pad "13" smd rect
			(at 0.750062 -1.400048 90)
			(size 0.2286 0.6096)
			(layers "F.Cu" "F.Mask" "F.Paste")
			(net "NC_HSC_TYPE_VINP")
		)
		(pad "14" smd rect
			(at 0.249936 -1.400048 90)
			(size 0.2286 0.6096)
			(layers "F.Cu" "F.Mask" "F.Paste")
			(net "NC_HSC_TYPE_NC3")
		)
		(pad "15" smd rect
			(at -0.249936 -1.400048 90)
			(size 0.2286 0.6096)
			(layers "F.Cu" "F.Mask" "F.Paste")
			(net "NC_HSC_TYPE_NC4")
		)
		(pad "16" smd rect
			(at -0.750062 -1.400048 90)
			(size 0.2286 0.6096)
			(layers "F.Cu" "F.Mask" "F.Paste")
			(net "NC_HSC_TYPE_NC5")
		)
		(pad "TH" smd rect
			(at 0 0 90)
			(size 1.7018 1.7018)
			(layers "F.Cu" "F.Mask" "F.Paste")
			(net "GND")
		)
		(zone
			(layer "F.Cu")
			(hatch none 0.5)
			(connect_pads
				(clearance 0)
			)
			(min_thickness 0.25)
			(keepout
				(tracks not_allowed)
				(vias allowed)
				(pads allowed)
				(copperpour not_allowed)
				(footprints allowed)
			)
			(placement
				(enabled no)
				(sheetname "")
			)
			(fill
				(thermal_gap 0.5)
				(thermal_bridge_width 0.5)
				(island_removal_mode 0)
			)
			(polygon
				(pts
					(xy 429.024542 -427.261782) (xy 429.024542 -427.40453) (xy 429.926242 -427.40453) (xy 429.926242 -429.20793)
					(xy 429.538638 -429.20793) (xy 429.538638 -429.350678) (xy 430.06899 -429.350678) (xy 430.06899 -427.261782)
				)
			)
		)
	)
	(footprint ""
		(layer "F.Cu")
		(at 193.809366 -37.43325 90)
		(property "Reference" "Q39"
			(at -2.361946 -0.526796 0)
			(unlocked yes)
			(layer "F.SilkS")
			(effects
				(font
					(size 0.7874 0.5842)
					(thickness 0.1524)
				)
				(justify left)
			)
		)
		(property "Value" ""
			(at 0 0 90)
			(layer "F.Fab")
			(effects
				(font
					(size 1.27 1.27)
				)
			)
		)
		(duplicate_pad_numbers_are_jumpers no)
		(fp_line
			(start 1.603248 -1.500124)
			(end 1.603248 1.500124)
			(stroke
				(width 0.1524)
				(type default)
			)
			(layer "F.SilkS")
		)
		(fp_line
			(start -1.603248 -1.500124)
			(end 1.603248 -1.500124)
			(stroke
				(width 0.1524)
				(type default)
			)
			(layer "F.SilkS")
		)
		(fp_line
			(start 1.603248 1.500124)
			(end -1.603248 1.500124)
			(stroke
				(width 0.1524)
				(type default)
			)
			(layer "F.SilkS")
		)
		(fp_line
			(start -1.603248 1.500124)
			(end -1.603248 -1.500124)
			(stroke
				(width 0.1524)
				(type default)
			)
			(layer "F.SilkS")
		)
		(fp_line
			(start 0.700024 -1.500124)
			(end -0.700024 -1.500124)
			(stroke
				(width 0.1)
				(type default)
			)
			(layer "F.Fab")
		)
		(fp_line
			(start -0.700024 -1.500124)
			(end -0.700024 -1.169924)
			(stroke
				(width 0.1)
				(type default)
			)
			(layer "F.Fab")
		)
		(fp_line
			(start -0.700024 -1.169924)
			(end -1.249934 -1.169924)
			(stroke
				(width 0.1)
				(type default)
			)
			(layer "F.Fab")
		)
		(fp_line
			(start -1.249934 -1.169924)
			(end -1.249934 -0.729996)
			(stroke
				(width 0.1)
				(type default)
			)
			(layer "F.Fab")
		)
		(fp_line
			(start -0.6985 -0.729996)
			(end -0.6985 0.729996)
			(stroke
				(width 0.1)
				(type default)
			)
			(layer "F.Fab")
		)
		(fp_line
			(start -1.249934 -0.729996)
			(end -0.6985 -0.729996)
			(stroke
				(width 0.1)
				(type default)
			)
			(layer "F.Fab")
		)
		(fp_line
			(start 1.249934 -0.219964)
			(end 0.700024 -0.219964)
			(stroke
				(width 0.1)
				(type default)
			)
			(layer "F.Fab")
		)
		(fp_line
			(start 0.700024 -0.219964)
			(end 0.700024 -1.500124)
			(stroke
				(width 0.1)
				(type default)
			)
			(layer "F.Fab")
		)
		(fp_line
			(start 1.249934 0.219964)
			(end 1.249934 -0.219964)
			(stroke
				(width 0.1)
				(type default)
			)
			(layer "F.Fab")
		)
		(fp_line
			(start 0.700024 0.219964)
			(end 1.249934 0.219964)
			(stroke
				(width 0.1)
				(type default)
			)
			(layer "F.Fab")
		)
		(fp_line
			(start -0.6985 0.729996)
			(end -1.249934 0.729996)
			(stroke
				(width 0.1)
				(type default)
			)
			(layer "F.Fab")
		)
		(fp_line
			(start -1.249934 0.729996)
			(end -1.249934 1.169924)
			(stroke
				(width 0.1)
				(type default)
			)
			(layer "F.Fab")
		)
		(fp_line
			(start -0.700024 1.169924)
			(end -0.700024 1.500124)
			(stroke
				(width 0.1)
				(type default)
			)
			(layer "F.Fab")
		)
		(fp_line
			(start -1.249934 1.169924)
			(end -0.700024 1.169924)
			(stroke
				(width 0.1)
				(type default)
			)
			(layer "F.Fab")
		)
		(fp_line
			(start 0.700024 1.500124)
			(end 0.700024 0.219964)
			(stroke
				(width 0.1)
				(type default)
			)
			(layer "F.Fab")
		)
		(fp_line
			(start -0.700024 1.500124)
			(end 0.700024 1.500124)
			(stroke
				(width 0.1)
				(type default)
			)
			(layer "F.Fab")
		)
		(fp_rect
			(start -0.700024 1.500124)
			(end 0.700024 -1.500124)
			(stroke
				(width 0)
				(type default)
			)
			(fill no)
			(layer "F.Fab")
		)
		(pad "D" smd rect
			(at 0.999998 0)
			(size 0.8128 0.9144)
			(layers "F.Cu" "F.Mask" "F.Paste")
			(net "P12V_SCM_EN")
		)
		(pad "G" smd rect
			(at -0.999998 -0.94996)
			(size 0.8128 0.9144)
			(layers "F.Cu" "F.Mask" "F.Paste")
			(net "FM_SCM_PRSNT1_R_N")
		)
		(pad "S" smd rect
			(at -0.999998 0.94996)
			(size 0.8128 0.9144)
			(layers "F.Cu" "F.Mask" "F.Paste")
			(net "GND")
		)
	)
	(footprint ""
		(layer "F.Cu")
		(at 463.18932 -38.565836 180)
		(property "Reference" "R2488"
			(at 0 0 180)
			(layer "F.SilkS")
			(hide yes)
			(effects
				(font
					(size 1.27 1.27)
				)
			)
		)
		(property "Value" ""
			(at 0 0 180)
			(layer "F.Fab")
			(effects
				(font
					(size 1.27 1.27)
				)
			)
		)
		(duplicate_pad_numbers_are_jumpers no)
		(fp_line
			(start 0.7874 0.4064)
			(end -0.7874 0.4064)
			(stroke
				(width 0.1524)
				(type default)
			)
			(layer "F.SilkS")
		)
		(fp_line
			(start 0.7874 -0.4064)
			(end 0.7874 0.4064)
			(stroke
				(width 0.1524)
				(type default)
			)
			(layer "F.SilkS")
		)
		(fp_line
			(start -0.7874 0.4064)
			(end -0.7874 -0.4064)
			(stroke
				(width 0.1524)
				(type default)
			)
			(layer "F.SilkS")
		)
		(fp_line
			(start -0.7874 -0.4064)
			(end 0.7874 -0.4064)
			(stroke
				(width 0.1524)
				(type default)
			)
			(layer "F.SilkS")
		)
		(fp_line
			(start 0.67945 0.3048)
			(end 0.120396 0.3048)
			(stroke
				(width 0.1)
				(type default)
			)
			(layer "F.Fab")
		)
		(fp_line
			(start 0.67945 -0.3048)
			(end 0.67945 0.3048)
			(stroke
				(width 0.1)
				(type default)
			)
			(layer "F.Fab")
		)
		(fp_line
			(start 0.12065 -0.2794)
			(end 0.12065 -0.3048)
			(stroke
				(width 0.1)
				(type default)
			)
			(layer "F.Fab")
		)
		(fp_line
			(start 0.12065 -0.3048)
			(end 0.67945 -0.3048)
			(stroke
				(width 0.1)
				(type default)
			)
			(layer "F.Fab")
		)
		(fp_line
			(start 0.120396 0.3048)
			(end 0.120396 0.2794)
			(stroke
				(width 0.1)
				(type default)
			)
			(layer "F.Fab")
		)
		(fp_line
			(start 0.120396 0.2794)
			(end -0.12065 0.2794)
			(stroke
				(width 0.1)
				(type default)
			)
			(layer "F.Fab")
		)
		(fp_line
			(start -0.12065 0.3048)
			(end -0.67945 0.3048)
			(stroke
				(width 0.1)
				(type default)
			)
			(layer "F.Fab")
		)
		(fp_line
			(start -0.12065 0.2794)
			(end -0.12065 0.3048)
			(stroke
				(width 0.1)
				(type default)
			)
			(layer "F.Fab")
		)
		(fp_line
			(start -0.12065 -0.2794)
			(end 0.12065 -0.2794)
			(stroke
				(width 0.1)
				(type default)
			)
			(layer "F.Fab")
		)
		(fp_line
			(start -0.12065 -0.305054)
			(end -0.12065 -0.2794)
			(stroke
				(width 0.1)
				(type default)
			)
			(layer "F.Fab")
		)
		(fp_line
			(start -0.67945 0.3048)
			(end -0.67945 -0.305054)
			(stroke
				(width 0.1)
				(type default)
			)
			(layer "F.Fab")
		)
		(fp_line
			(start -0.67945 -0.305054)
			(end -0.12065 -0.305054)
			(stroke
				(width 0.1)
				(type default)
			)
			(layer "F.Fab")
		)
		(pad "1" smd circle
			(at -0.40005 0 180)
			(size 0 0)
			(layers "F.Cu" "F.Mask" "F.Paste")
			(net "P3V3_AUX")
		)
		(pad "2" smd circle
			(at 0.40005 0 180)
			(size 0 0)
			(layers "F.Cu" "F.Mask" "F.Paste")
			(net "OCP_SFF_WAKE_BUFF_N")
		)
	)
	(footprint ""
		(layer "F.Cu")
		(at 205.232 -128.016)
		(property "Reference" "R6050"
			(at 0 0 0)
			(layer "F.SilkS")
			(hide yes)
			(effects
				(font
					(size 1.27 1.27)
				)
			)
		)
		(property "Value" ""
			(at 0 0 0)
			(layer "F.Fab")
			(effects
				(font
					(size 1.27 1.27)
				)
			)
		)
		(duplicate_pad_numbers_are_jumpers no)
		(fp_line
			(start -0.7874 -0.4064)
			(end 0.7874 -0.4064)
			(stroke
				(width 0.1524)
				(type default)
			)
			(layer "F.SilkS")
		)
		(fp_line
			(start -0.7874 0.4064)
			(end -0.7874 -0.4064)
			(stroke
				(width 0.1524)
				(type default)
			)
			(layer "F.SilkS")
		)
		(fp_line
			(start 0.7874 -0.4064)
			(end 0.7874 0.4064)
			(stroke
				(width 0.1524)
				(type default)
			)
			(layer "F.SilkS")
		)
		(fp_line
			(start 0.7874 0.4064)
			(end -0.7874 0.4064)
			(stroke
				(width 0.1524)
				(type default)
			)
			(layer "F.SilkS")
		)
		(fp_line
			(start -0.67945 -0.305054)
			(end -0.12065 -0.305054)
			(stroke
				(width 0.1)
				(type default)
			)
			(layer "F.Fab")
		)
		(fp_line
			(start -0.67945 0.3048)
			(end -0.67945 -0.305054)
			(stroke
				(width 0.1)
				(type default)
			)
			(layer "F.Fab")
		)
		(fp_line
			(start -0.12065 -0.305054)
			(end -0.12065 -0.2794)
			(stroke
				(width 0.1)
				(type default)
			)
			(layer "F.Fab")
		)
		(fp_line
			(start -0.12065 -0.2794)
			(end 0.12065 -0.2794)
			(stroke
				(width 0.1)
				(type default)
			)
			(layer "F.Fab")
		)
		(fp_line
			(start -0.12065 0.2794)
			(end -0.12065 0.3048)
			(stroke
				(width 0.1)
				(type default)
			)
			(layer "F.Fab")
		)
		(fp_line
			(start -0.12065 0.3048)
			(end -0.67945 0.3048)
			(stroke
				(width 0.1)
				(type default)
			)
			(layer "F.Fab")
		)
		(fp_line
			(start 0.120396 0.2794)
			(end -0.12065 0.2794)
			(stroke
				(width 0.1)
				(type default)
			)
			(layer "F.Fab")
		)
		(fp_line
			(start 0.120396 0.3048)
			(end 0.120396 0.2794)
			(stroke
				(width 0.1)
				(type default)
			)
			(layer "F.Fab")
		)
		(fp_line
			(start 0.12065 -0.3048)
			(end 0.67945 -0.3048)
			(stroke
				(width 0.1)
				(type default)
			)
			(layer "F.Fab")
		)
		(fp_line
			(start 0.12065 -0.2794)
			(end 0.12065 -0.3048)
			(stroke
				(width 0.1)
				(type default)
			)
			(layer "F.Fab")
		)
		(fp_line
			(start 0.67945 -0.3048)
			(end 0.67945 0.3048)
			(stroke
				(width 0.1)
				(type default)
			)
			(layer "F.Fab")
		)
		(fp_line
			(start 0.67945 0.3048)
			(end 0.120396 0.3048)
			(stroke
				(width 0.1)
				(type default)
			)
			(layer "F.Fab")
		)
		(pad "1" smd circle
			(at -0.40005 0)
			(size 0 0)
			(layers "F.Cu" "F.Mask" "F.Paste")
			(net "SW_P3V3_EN")
		)
		(pad "2" smd circle
			(at 0.40005 0)
			(size 0 0)
			(layers "F.Cu" "F.Mask" "F.Paste")
			(net "GND")
		)
	)
	(footprint ""
		(layer "F.Cu")
		(at 402.253958 -328.418952 180)
		(property "Reference" "R467"
			(at 0 0 180)
			(layer "F.SilkS")
			(hide yes)
			(effects
				(font
					(size 1.27 1.27)
				)
			)
		)
		(property "Value" ""
			(at 0 0 180)
			(layer "F.Fab")
			(effects
				(font
					(size 1.27 1.27)
				)
			)
		)
		(duplicate_pad_numbers_are_jumpers no)
		(fp_line
			(start 0.7874 0.4064)
			(end -0.7874 0.4064)
			(stroke
				(width 0.1524)
				(type default)
			)
			(layer "F.SilkS")
		)
		(fp_line
			(start 0.7874 -0.4064)
			(end 0.7874 0.4064)
			(stroke
				(width 0.1524)
				(type default)
			)
			(layer "F.SilkS")
		)
		(fp_line
			(start -0.7874 0.4064)
			(end -0.7874 -0.4064)
			(stroke
				(width 0.1524)
				(type default)
			)
			(layer "F.SilkS")
		)
		(fp_line
			(start -0.7874 -0.4064)
			(end 0.7874 -0.4064)
			(stroke
				(width 0.1524)
				(type default)
			)
			(layer "F.SilkS")
		)
		(fp_line
			(start 0.67945 0.3048)
			(end 0.120396 0.3048)
			(stroke
				(width 0.1)
				(type default)
			)
			(layer "F.Fab")
		)
		(fp_line
			(start 0.67945 -0.3048)
			(end 0.67945 0.3048)
			(stroke
				(width 0.1)
				(type default)
			)
			(layer "F.Fab")
		)
		(fp_line
			(start 0.12065 -0.2794)
			(end 0.12065 -0.3048)
			(stroke
				(width 0.1)
				(type default)
			)
			(layer "F.Fab")
		)
		(fp_line
			(start 0.12065 -0.3048)
			(end 0.67945 -0.3048)
			(stroke
				(width 0.1)
				(type default)
			)
			(layer "F.Fab")
		)
		(fp_line
			(start 0.120396 0.3048)
			(end 0.120396 0.2794)
			(stroke
				(width 0.1)
				(type default)
			)
			(layer "F.Fab")
		)
		(fp_line
			(start 0.120396 0.2794)
			(end -0.12065 0.2794)
			(stroke
				(width 0.1)
				(type default)
			)
			(layer "F.Fab")
		)
		(fp_line
			(start -0.12065 0.3048)
			(end -0.67945 0.3048)
			(stroke
				(width 0.1)
				(type default)
			)
			(layer "F.Fab")
		)
		(fp_line
			(start -0.12065 0.2794)
			(end -0.12065 0.3048)
			(stroke
				(width 0.1)
				(type default)
			)
			(layer "F.Fab")
		)
		(fp_line
			(start -0.12065 -0.2794)
			(end 0.12065 -0.2794)
			(stroke
				(width 0.1)
				(type default)
			)
			(layer "F.Fab")
		)
		(fp_line
			(start -0.12065 -0.305054)
			(end -0.12065 -0.2794)
			(stroke
				(width 0.1)
				(type default)
			)
			(layer "F.Fab")
		)
		(fp_line
			(start -0.67945 0.3048)
			(end -0.67945 -0.305054)
			(stroke
				(width 0.1)
				(type default)
			)
			(layer "F.Fab")
		)
		(fp_line
			(start -0.67945 -0.305054)
			(end -0.12065 -0.305054)
			(stroke
				(width 0.1)
				(type default)
			)
			(layer "F.Fab")
		)
		(pad "1" smd circle
			(at -0.40005 0 180)
			(size 0 0)
			(layers "F.Cu" "F.Mask" "F.Paste")
			(net "SPI_CPU0_D3")
		)
		(pad "2" smd circle
			(at 0.40005 0 180)
			(size 0 0)
			(layers "F.Cu" "F.Mask" "F.Paste")
			(net "SPI_CPU0_R_D3")
		)
	)
	(footprint ""
		(layer "F.Cu")
		(at 329.188826 -416.899344 -90)
		(property "Reference" "C6517"
			(at 0 0 270)
			(layer "F.SilkS")
			(hide yes)
			(effects
				(font
					(size 1.27 1.27)
				)
			)
		)
		(property "Value" ""
			(at 0 0 270)
			(layer "F.Fab")
			(effects
				(font
					(size 1.27 1.27)
				)
			)
		)
		(duplicate_pad_numbers_are_jumpers no)
		(fp_line
			(start -0.299974 0.150114)
			(end -0.299974 -0.150114)
			(stroke
				(width 0.1)
				(type default)
			)
			(layer "F.Fab")
		)
		(fp_line
			(start 0.299974 0.150114)
			(end -0.299974 0.150114)
			(stroke
				(width 0.1)
				(type default)
			)
			(layer "F.Fab")
		)
		(fp_line
			(start -0.299974 -0.150114)
			(end 0.299974 -0.150114)
			(stroke
				(width 0.1)
				(type default)
			)
			(layer "F.Fab")
		)
		(fp_line
			(start 0.299974 -0.150114)
			(end 0.299974 0.150114)
			(stroke
				(width 0.1)
				(type default)
			)
			(layer "F.Fab")
		)
		(pad "1" smd rect
			(at -0.2667 0 270)
			(size 0.3048 0.381)
			(layers "F.Cu" "F.Mask" "F.Paste")
			(net "P5E_CPU0_P0_TX_BUF_C_DP<8>")
		)
		(pad "2" smd rect
			(at 0.2667 0 270)
			(size 0.3048 0.381)
			(layers "F.Cu" "F.Mask" "F.Paste")
			(net "P5E_CPU0_P0_TX_BUF_DP<8>")
		)
	)
	(footprint ""
		(layer "F.Cu")
		(at 75.424538 -19.220942)
		(property "Reference" "PC2146"
			(at 0 0 0)
			(layer "F.SilkS")
			(hide yes)
			(effects
				(font
					(size 1.27 1.27)
				)
			)
		)
		(property "Value" ""
			(at 0 0 0)
			(layer "F.Fab")
			(effects
				(font
					(size 1.27 1.27)
				)
			)
		)
		(duplicate_pad_numbers_are_jumpers no)
		(fp_line
			(start -0.7874 -0.4064)
			(end 0.7874 -0.4064)
			(stroke
				(width 0.1524)
				(type default)
			)
			(layer "F.SilkS")
		)
		(fp_line
			(start -0.7874 0.4064)
			(end -0.7874 -0.4064)
			(stroke
				(width 0.1524)
				(type default)
			)
			(layer "F.SilkS")
		)
		(fp_line
			(start 0.7874 -0.4064)
			(end 0.7874 0.4064)
			(stroke
				(width 0.1524)
				(type default)
			)
			(layer "F.SilkS")
		)
		(fp_line
			(start 0.7874 0.4064)
			(end -0.7874 0.4064)
			(stroke
				(width 0.1524)
				(type default)
			)
			(layer "F.SilkS")
		)
		(fp_line
			(start -0.67945 -0.305054)
			(end -0.12065 -0.305054)
			(stroke
				(width 0.1)
				(type default)
			)
			(layer "F.Fab")
		)
		(fp_line
			(start -0.67945 0.3048)
			(end -0.67945 -0.305054)
			(stroke
				(width 0.1)
				(type default)
			)
			(layer "F.Fab")
		)
		(fp_line
			(start -0.12065 -0.305054)
			(end -0.12065 -0.2794)
			(stroke
				(width 0.1)
				(type default)
			)
			(layer "F.Fab")
		)
		(fp_line
			(start -0.12065 -0.2794)
			(end 0.12065 -0.2794)
			(stroke
				(width 0.1)
				(type default)
			)
			(layer "F.Fab")
		)
		(fp_line
			(start -0.12065 0.2794)
			(end -0.12065 0.3048)
			(stroke
				(width 0.1)
				(type default)
			)
			(layer "F.Fab")
		)
		(fp_line
			(start -0.12065 0.3048)
			(end -0.67945 0.3048)
			(stroke
				(width 0.1)
				(type default)
			)
			(layer "F.Fab")
		)
		(fp_line
			(start 0.120396 0.2794)
			(end -0.12065 0.2794)
			(stroke
				(width 0.1)
				(type default)
			)
			(layer "F.Fab")
		)
		(fp_line
			(start 0.120396 0.3048)
			(end 0.120396 0.2794)
			(stroke
				(width 0.1)
				(type default)
			)
			(layer "F.Fab")
		)
		(fp_line
			(start 0.12065 -0.3048)
			(end 0.67945 -0.3048)
			(stroke
				(width 0.1)
				(type default)
			)
			(layer "F.Fab")
		)
		(fp_line
			(start 0.12065 -0.2794)
			(end 0.12065 -0.3048)
			(stroke
				(width 0.1)
				(type default)
			)
			(layer "F.Fab")
		)
		(fp_line
			(start 0.67945 -0.3048)
			(end 0.67945 0.3048)
			(stroke
				(width 0.1)
				(type default)
			)
			(layer "F.Fab")
		)
		(fp_line
			(start 0.67945 0.3048)
			(end 0.120396 0.3048)
			(stroke
				(width 0.1)
				(type default)
			)
			(layer "F.Fab")
		)
		(pad "1" smd circle
			(at -0.40005 0)
			(size 0 0)
			(layers "F.Cu" "F.Mask" "F.Paste")
			(net "GND")
		)
		(pad "2" smd circle
			(at 0.40005 0)
			(size 0 0)
			(layers "F.Cu" "F.Mask" "F.Paste")
			(net "P12V_OCP_REG_2")
		)
	)
	(footprint ""
		(layer "F.Cu")
		(at 171.196 -112.359948 180)
		(property "Reference" "R23"
			(at 0 0 180)
			(layer "F.SilkS")
			(hide yes)
			(effects
				(font
					(size 1.27 1.27)
				)
			)
		)
		(property "Value" ""
			(at 0 0 180)
			(layer "F.Fab")
			(effects
				(font
					(size 1.27 1.27)
				)
			)
		)
		(duplicate_pad_numbers_are_jumpers no)
		(fp_line
			(start 0.7874 0.4064)
			(end -0.7874 0.4064)
			(stroke
				(width 0.1524)
				(type default)
			)
			(layer "F.SilkS")
		)
		(fp_line
			(start 0.7874 -0.4064)
			(end 0.7874 0.4064)
			(stroke
				(width 0.1524)
				(type default)
			)
			(layer "F.SilkS")
		)
		(fp_line
			(start -0.7874 0.4064)
			(end -0.7874 -0.4064)
			(stroke
				(width 0.1524)
				(type default)
			)
			(layer "F.SilkS")
		)
		(fp_line
			(start -0.7874 -0.4064)
			(end 0.7874 -0.4064)
			(stroke
				(width 0.1524)
				(type default)
			)
			(layer "F.SilkS")
		)
		(fp_line
			(start 0.67945 0.3048)
			(end 0.120396 0.3048)
			(stroke
				(width 0.1)
				(type default)
			)
			(layer "F.Fab")
		)
		(fp_line
			(start 0.67945 -0.3048)
			(end 0.67945 0.3048)
			(stroke
				(width 0.1)
				(type default)
			)
			(layer "F.Fab")
		)
		(fp_line
			(start 0.12065 -0.2794)
			(end 0.12065 -0.3048)
			(stroke
				(width 0.1)
				(type default)
			)
			(layer "F.Fab")
		)
		(fp_line
			(start 0.12065 -0.3048)
			(end 0.67945 -0.3048)
			(stroke
				(width 0.1)
				(type default)
			)
			(layer "F.Fab")
		)
		(fp_line
			(start 0.120396 0.3048)
			(end 0.120396 0.2794)
			(stroke
				(width 0.1)
				(type default)
			)
			(layer "F.Fab")
		)
		(fp_line
			(start 0.120396 0.2794)
			(end -0.12065 0.2794)
			(stroke
				(width 0.1)
				(type default)
			)
			(layer "F.Fab")
		)
		(fp_line
			(start -0.12065 0.3048)
			(end -0.67945 0.3048)
			(stroke
				(width 0.1)
				(type default)
			)
			(layer "F.Fab")
		)
		(fp_line
			(start -0.12065 0.2794)
			(end -0.12065 0.3048)
			(stroke
				(width 0.1)
				(type default)
			)
			(layer "F.Fab")
		)
		(fp_line
			(start -0.12065 -0.2794)
			(end 0.12065 -0.2794)
			(stroke
				(width 0.1)
				(type default)
			)
			(layer "F.Fab")
		)
		(fp_line
			(start -0.12065 -0.305054)
			(end -0.12065 -0.2794)
			(stroke
				(width 0.1)
				(type default)
			)
			(layer "F.Fab")
		)
		(fp_line
			(start -0.67945 0.3048)
			(end -0.67945 -0.305054)
			(stroke
				(width 0.1)
				(type default)
			)
			(layer "F.Fab")
		)
		(fp_line
			(start -0.67945 -0.305054)
			(end -0.12065 -0.305054)
			(stroke
				(width 0.1)
				(type default)
			)
			(layer "F.Fab")
		)
		(pad "1" smd circle
			(at -0.40005 0 180)
			(size 0 0)
			(layers "F.Cu" "F.Mask" "F.Paste")
			(net "P3V3_OCP_SFF_EN")
		)
		(pad "2" smd circle
			(at 0.40005 0 180)
			(size 0 0)
			(layers "F.Cu" "F.Mask" "F.Paste")
			(net "P3V3_OCP_SFF_EN_R")
		)
	)
	(footprint ""
		(layer "F.Cu")
		(at 153.88463 -98.355658)
		(property "Reference" "U243"
			(at -3.017774 -1.730502 0)
			(unlocked yes)
			(layer "F.SilkS")
			(effects
				(font
					(size 0.7874 0.5842)
					(thickness 0.1524)
				)
			)
		)
		(property "Value" ""
			(at 0 0 0)
			(layer "F.Fab")
			(effects
				(font
					(size 1.27 1.27)
				)
			)
		)
		(duplicate_pad_numbers_are_jumpers no)
		(fp_line
			(start -1.7272 1.1176)
			(end -1.7272 -1.1176)
			(stroke
				(width 0.1524)
				(type default)
			)
			(layer "F.SilkS")
		)
		(fp_line
			(start -0.254 -1.1176)
			(end -1.7272 -1.1176)
			(stroke
				(width 0.1524)
				(type default)
			)
			(layer "F.SilkS")
		)
		(fp_line
			(start 0 -0.7366)
			(end -0.254 -1.1176)
			(stroke
				(width 0.1524)
				(type default)
			)
			(layer "F.SilkS")
		)
		(fp_line
			(start 0.254 -1.1176)
			(end 0 -0.7366)
			(stroke
				(width 0.1524)
				(type default)
			)
			(layer "F.SilkS")
		)
		(fp_line
			(start 1.7272 -1.1176)
			(end 0.254 -1.1176)
			(stroke
				(width 0.1524)
				(type default)
			)
			(layer "F.SilkS")
		)
		(fp_line
			(start 1.7272 -1.1176)
			(end 1.7272 1.1176)
			(stroke
				(width 0.1524)
				(type default)
			)
			(layer "F.SilkS")
		)
		(fp_line
			(start 1.7272 1.1176)
			(end -1.7272 1.1176)
			(stroke
				(width 0.1524)
				(type default)
			)
			(layer "F.SilkS")
		)
		(fp_poly
			(pts
				(xy -2.7178 -1.030986) (xy -1.9558 -0.649986) (xy -2.7178 -0.268986)
			)
			(stroke
				(width 0)
				(type default)
			)
			(fill yes)
			(layer "F.SilkS")
		)
		(fp_line
			(start -1.5748 -1.1176)
			(end -1.5748 1.1176)
			(stroke
				(width 0.1)
				(type default)
			)
			(layer "F.Fab")
		)
		(fp_line
			(start -1.5748 1.1176)
			(end 1.5748 1.1176)
			(stroke
				(width 0.1)
				(type default)
			)
			(layer "F.Fab")
		)
		(fp_line
			(start 1.5748 -1.1176)
			(end -1.5748 -1.1176)
			(stroke
				(width 0.1)
				(type default)
			)
			(layer "F.Fab")
		)
		(fp_line
			(start 1.5748 1.1176)
			(end 1.5748 -1.1176)
			(stroke
				(width 0.1)
				(type default)
			)
			(layer "F.Fab")
		)
		(fp_poly
			(pts
				(xy -1.9558 -0.649986) (xy -2.7178 -0.268986) (xy -2.7178 -1.030986)
			)
			(stroke
				(width 0)
				(type default)
			)
			(fill yes)
			(layer "F.Fab")
		)
		(pad "1" smd rect
			(at -0.999998 -0.649986 270)
			(size 0.3556 1.1176)
			(layers "F.Cu" "F.Mask" "F.Paste")
			(net "OCP_SFF_NOT_PRSNT_RBT_ARB_IN")
		)
		(pad "2" smd rect
			(at -0.999998 0 270)
			(size 0.3556 1.1176)
			(layers "F.Cu" "F.Mask" "F.Paste")
			(net "GND")
		)
		(pad "3" smd rect
			(at -0.999998 0.649986 270)
			(size 0.3556 1.1176)
			(layers "F.Cu" "F.Mask" "F.Paste")
			(net "OCP_SFF_RBT_ARB_OUT")
		)
		(pad "4" smd rect
			(at 0.999998 0.649986 270)
			(size 0.3556 1.1176)
			(layers "F.Cu" "F.Mask" "F.Paste")
			(net "OCP_SFF_RBT_ARB_IN_MUX2")
		)
		(pad "5" smd rect
			(at 0.999998 0 270)
			(size 0.3556 1.1176)
			(layers "F.Cu" "F.Mask" "F.Paste")
			(net "P3V3_AUX")
		)
		(pad "6" smd rect
			(at 0.999998 -0.649986 270)
			(size 0.3556 1.1176)
			(layers "F.Cu" "F.Mask" "F.Paste")
			(net "OCP_SFF_PRSNT_ALL_R1_N")
		)
	)
	(footprint ""
		(layer "F.Cu")
		(at 14.834108 -128.54559 90)
		(property "Reference" "R4075"
			(at 0 0 90)
			(layer "F.SilkS")
			(hide yes)
			(effects
				(font
					(size 1.27 1.27)
				)
			)
		)
		(property "Value" ""
			(at 0 0 90)
			(layer "F.Fab")
			(effects
				(font
					(size 1.27 1.27)
				)
			)
		)
		(duplicate_pad_numbers_are_jumpers no)
		(fp_line
			(start 0.7874 -0.4064)
			(end 0.7874 0.4064)
			(stroke
				(width 0.1524)
				(type default)
			)
			(layer "F.SilkS")
		)
		(fp_line
			(start -0.7874 -0.4064)
			(end 0.7874 -0.4064)
			(stroke
				(width 0.1524)
				(type default)
			)
			(layer "F.SilkS")
		)
		(fp_line
			(start 0.7874 0.4064)
			(end -0.7874 0.4064)
			(stroke
				(width 0.1524)
				(type default)
			)
			(layer "F.SilkS")
		)
		(fp_line
			(start -0.7874 0.4064)
			(end -0.7874 -0.4064)
			(stroke
				(width 0.1524)
				(type default)
			)
			(layer "F.SilkS")
		)
		(fp_line
			(start -0.12065 -0.305054)
			(end -0.12065 -0.2794)
			(stroke
				(width 0.1)
				(type default)
			)
			(layer "F.Fab")
		)
		(fp_line
			(start -0.67945 -0.305054)
			(end -0.12065 -0.305054)
			(stroke
				(width 0.1)
				(type default)
			)
			(layer "F.Fab")
		)
		(fp_line
			(start 0.67945 -0.3048)
			(end 0.67945 0.3048)
			(stroke
				(width 0.1)
				(type default)
			)
			(layer "F.Fab")
		)
		(fp_line
			(start 0.12065 -0.3048)
			(end 0.67945 -0.3048)
			(stroke
				(width 0.1)
				(type default)
			)
			(layer "F.Fab")
		)
		(fp_line
			(start 0.12065 -0.2794)
			(end 0.12065 -0.3048)
			(stroke
				(width 0.1)
				(type default)
			)
			(layer "F.Fab")
		)
		(fp_line
			(start -0.12065 -0.2794)
			(end 0.12065 -0.2794)
			(stroke
				(width 0.1)
				(type default)
			)
			(layer "F.Fab")
		)
		(fp_line
			(start 0.120396 0.2794)
			(end -0.12065 0.2794)
			(stroke
				(width 0.1)
				(type default)
			)
			(layer "F.Fab")
		)
		(fp_line
			(start -0.12065 0.2794)
			(end -0.12065 0.3048)
			(stroke
				(width 0.1)
				(type default)
			)
			(layer "F.Fab")
		)
		(fp_line
			(start 0.67945 0.3048)
			(end 0.120396 0.3048)
			(stroke
				(width 0.1)
				(type default)
			)
			(layer "F.Fab")
		)
		(fp_line
			(start 0.120396 0.3048)
			(end 0.120396 0.2794)
			(stroke
				(width 0.1)
				(type default)
			)
			(layer "F.Fab")
		)
		(fp_line
			(start -0.12065 0.3048)
			(end -0.67945 0.3048)
			(stroke
				(width 0.1)
				(type default)
			)
			(layer "F.Fab")
		)
		(fp_line
			(start -0.67945 0.3048)
			(end -0.67945 -0.305054)
			(stroke
				(width 0.1)
				(type default)
			)
			(layer "F.Fab")
		)
		(pad "1" smd circle
			(at -0.40005 0 90)
			(size 0 0)
			(layers "F.Cu" "F.Mask" "F.Paste")
			(net "CLK_GEN2_BMC_RC_OE_N")
		)
		(pad "2" smd circle
			(at 0.40005 0 90)
			(size 0 0)
			(layers "F.Cu" "F.Mask" "F.Paste")
			(net "CLK_GEN2_BMC_RC_OE_R3_N")
		)
	)
	(footprint ""
		(layer "F.Cu")
		(at 87.922862 -69.059044 90)
		(property "Reference" "R1170"
			(at 0 0 90)
			(layer "F.SilkS")
			(hide yes)
			(effects
				(font
					(size 1.27 1.27)
				)
			)
		)
		(property "Value" ""
			(at 0 0 90)
			(layer "F.Fab")
			(effects
				(font
					(size 1.27 1.27)
				)
			)
		)
		(duplicate_pad_numbers_are_jumpers no)
		(fp_line
			(start 0.7874 -0.4064)
			(end 0.7874 0.4064)
			(stroke
				(width 0.1524)
				(type default)
			)
			(layer "F.SilkS")
		)
		(fp_line
			(start -0.7874 -0.4064)
			(end 0.7874 -0.4064)
			(stroke
				(width 0.1524)
				(type default)
			)
			(layer "F.SilkS")
		)
		(fp_line
			(start 0.7874 0.4064)
			(end -0.7874 0.4064)
			(stroke
				(width 0.1524)
				(type default)
			)
			(layer "F.SilkS")
		)
		(fp_line
			(start -0.7874 0.4064)
			(end -0.7874 -0.4064)
			(stroke
				(width 0.1524)
				(type default)
			)
			(layer "F.SilkS")
		)
		(fp_line
			(start -0.12065 -0.305054)
			(end -0.12065 -0.2794)
			(stroke
				(width 0.1)
				(type default)
			)
			(layer "F.Fab")
		)
		(fp_line
			(start -0.67945 -0.305054)
			(end -0.12065 -0.305054)
			(stroke
				(width 0.1)
				(type default)
			)
			(layer "F.Fab")
		)
		(fp_line
			(start 0.67945 -0.3048)
			(end 0.67945 0.3048)
			(stroke
				(width 0.1)
				(type default)
			)
			(layer "F.Fab")
		)
		(fp_line
			(start 0.12065 -0.3048)
			(end 0.67945 -0.3048)
			(stroke
				(width 0.1)
				(type default)
			)
			(layer "F.Fab")
		)
		(fp_line
			(start 0.12065 -0.2794)
			(end 0.12065 -0.3048)
			(stroke
				(width 0.1)
				(type default)
			)
			(layer "F.Fab")
		)
		(fp_line
			(start -0.12065 -0.2794)
			(end 0.12065 -0.2794)
			(stroke
				(width 0.1)
				(type default)
			)
			(layer "F.Fab")
		)
		(fp_line
			(start 0.120396 0.2794)
			(end -0.12065 0.2794)
			(stroke
				(width 0.1)
				(type default)
			)
			(layer "F.Fab")
		)
		(fp_line
			(start -0.12065 0.2794)
			(end -0.12065 0.3048)
			(stroke
				(width 0.1)
				(type default)
			)
			(layer "F.Fab")
		)
		(fp_line
			(start 0.67945 0.3048)
			(end 0.120396 0.3048)
			(stroke
				(width 0.1)
				(type default)
			)
			(layer "F.Fab")
		)
		(fp_line
			(start 0.120396 0.3048)
			(end 0.120396 0.2794)
			(stroke
				(width 0.1)
				(type default)
			)
			(layer "F.Fab")
		)
		(fp_line
			(start -0.12065 0.3048)
			(end -0.67945 0.3048)
			(stroke
				(width 0.1)
				(type default)
			)
			(layer "F.Fab")
		)
		(fp_line
			(start -0.67945 0.3048)
			(end -0.67945 -0.305054)
			(stroke
				(width 0.1)
				(type default)
			)
			(layer "F.Fab")
		)
		(pad "1" smd circle
			(at -0.40005 0 90)
			(size 0 0)
			(layers "F.Cu" "F.Mask" "F.Paste")
			(net "OCP_V3_2_P3V3_PLD_PWRGD")
		)
		(pad "2" smd circle
			(at 0.40005 0 90)
			(size 0 0)
			(layers "F.Cu" "F.Mask" "F.Paste")
			(net "OCP_V3_2_P3V3_PLD_R_PWRGD")
		)
	)
	(footprint ""
		(layer "F.Cu")
		(at 229.87 -287.376362 180)
		(property "Reference" "PC6904"
			(at 0 0 180)
			(layer "F.SilkS")
			(hide yes)
			(effects
				(font
					(size 1.27 1.27)
				)
			)
		)
		(property "Value" ""
			(at 0 0 180)
			(layer "F.Fab")
			(effects
				(font
					(size 1.27 1.27)
				)
			)
		)
		(duplicate_pad_numbers_are_jumpers no)
		(fp_line
			(start 1.524 0.762)
			(end -1.524 0.762)
			(stroke
				(width 0.1524)
				(type default)
			)
			(layer "F.SilkS")
		)
		(fp_line
			(start 1.524 -0.762)
			(end 1.524 0.762)
			(stroke
				(width 0.1524)
				(type default)
			)
			(layer "F.SilkS")
		)
		(fp_line
			(start -1.524 0.762)
			(end -1.524 -0.762)
			(stroke
				(width 0.1524)
				(type default)
			)
			(layer "F.SilkS")
		)
		(fp_line
			(start -1.524 -0.762)
			(end 1.524 -0.762)
			(stroke
				(width 0.1524)
				(type default)
			)
			(layer "F.SilkS")
		)
		(fp_line
			(start 1.1049 0.724916)
			(end 1.1049 -0.724916)
			(stroke
				(width 0.1)
				(type default)
			)
			(layer "F.Fab")
		)
		(fp_line
			(start 1.1049 -0.724916)
			(end -1.1049 -0.724916)
			(stroke
				(width 0.1)
				(type default)
			)
			(layer "F.Fab")
		)
		(fp_line
			(start -1.1049 0.724916)
			(end 1.1049 0.724916)
			(stroke
				(width 0.1)
				(type default)
			)
			(layer "F.Fab")
		)
		(fp_line
			(start -1.1049 -0.724916)
			(end -1.1049 0.724916)
			(stroke
				(width 0.1)
				(type default)
			)
			(layer "F.Fab")
		)
		(pad "1" smd rect
			(at -0.889 0)
			(size 1.016 1.27)
			(layers "F.Cu" "F.Mask" "F.Paste")
			(net "SW_P12V_AUX_P1V8_RETIMER_CPU1_FLT")
		)
		(pad "2" smd rect
			(at 0.889 0)
			(size 1.016 1.27)
			(layers "F.Cu" "F.Mask" "F.Paste")
			(net "GND")
		)
	)
	(footprint ""
		(layer "F.Cu")
		(at 389.409178 -182.743856 180)
		(property "Reference" "PU47"
			(at 4.140454 -6.180582 0)
			(unlocked yes)
			(layer "F.SilkS")
			(effects
				(font
					(size 0.7874 0.5842)
					(thickness 0.1524)
				)
				(justify left)
			)
		)
		(property "Value" ""
			(at 0 0 180)
			(layer "F.Fab")
			(effects
				(font
					(size 1.27 1.27)
				)
			)
		)
		(duplicate_pad_numbers_are_jumpers no)
		(fp_line
			(start 2.500122 2.999994)
			(end 2.2987 2.999994)
			(stroke
				(width 0.1524)
				(type default)
			)
			(layer "F.SilkS")
		)
		(fp_line
			(start 2.500122 2.339594)
			(end 2.500122 2.999994)
			(stroke
				(width 0.1524)
				(type default)
			)
			(layer "F.SilkS")
		)
		(fp_line
			(start 2.500122 -2.999994)
			(end 2.500122 -2.44348)
			(stroke
				(width 0.1524)
				(type default)
			)
			(layer "F.SilkS")
		)
		(fp_line
			(start 2.31394 -2.999994)
			(end 2.500122 -2.999994)
			(stroke
				(width 0.1524)
				(type default)
			)
			(layer "F.SilkS")
		)
		(fp_line
			(start -2.2987 2.999994)
			(end -2.500122 2.999994)
			(stroke
				(width 0.1524)
				(type default)
			)
			(layer "F.SilkS")
		)
		(fp_line
			(start -2.500122 2.999994)
			(end -2.500122 2.339594)
			(stroke
				(width 0.1524)
				(type default)
			)
			(layer "F.SilkS")
		)
		(fp_line
			(start -2.500122 0.6604)
			(end -2.500122 0.229108)
			(stroke
				(width 0.1524)
				(type default)
			)
			(layer "F.SilkS")
		)
		(fp_line
			(start -2.500122 -2.529078)
			(end -2.500122 -2.999994)
			(stroke
				(width 0.1524)
				(type default)
			)
			(layer "F.SilkS")
		)
		(fp_line
			(start -2.500122 -2.999994)
			(end -2.24409 -2.999994)
			(stroke
				(width 0.1524)
				(type default)
			)
			(layer "F.SilkS")
		)
		(fp_poly
			(pts
				(xy -2.700274 -2.537206) (xy -3.385312 -2.765806) (xy -2.928874 -3.222244)
			)
			(stroke
				(width 0)
				(type default)
			)
			(fill yes)
			(layer "F.SilkS")
		)
		(fp_line
			(start 2.500122 2.999994)
			(end -2.500122 2.999994)
			(stroke
				(width 0.1)
				(type default)
			)
			(layer "F.Fab")
		)
		(fp_line
			(start 2.500122 -2.999994)
			(end 2.500122 2.999994)
			(stroke
				(width 0.1)
				(type default)
			)
			(layer "F.Fab")
		)
		(fp_line
			(start -2.500122 2.999994)
			(end -2.500122 -2.999994)
			(stroke
				(width 0.1)
				(type default)
			)
			(layer "F.Fab")
		)
		(fp_line
			(start -2.500122 -2.999994)
			(end 2.500122 -2.999994)
			(stroke
				(width 0.1)
				(type default)
			)
			(layer "F.Fab")
		)
		(fp_poly
			(pts
				(xy -4.218432 -2.783078) (xy -4.218432 -1.767078) (xy -3.202432 -2.275078)
			)
			(stroke
				(width 0)
				(type default)
			)
			(fill yes)
			(layer "F.Fab")
		)
		(pad "1" smd rect
			(at -2.400046 -2.275078 270)
			(size 0.2286 0.6096)
			(layers "F.Cu" "F.Mask" "F.Paste")
			(net "PVDDCR_CPU0_P0_VOS4")
		)
		(pad "2" smd rect
			(at -2.400046 -1.82499 270)
			(size 0.2286 0.6096)
			(layers "F.Cu" "F.Mask" "F.Paste")
			(net "GND")
		)
		(pad "3" smd rect
			(at -2.400046 -1.374902 270)
			(size 0.2286 0.6096)
			(layers "F.Cu" "F.Mask" "F.Paste")
			(net "PVDDCR_CPU0_P0_VCC4")
		)
		(pad "4" smd rect
			(at -2.400046 -0.925068 270)
			(size 0.2286 0.6096)
			(layers "F.Cu" "F.Mask" "F.Paste")
			(net "PVDDCR_CPU0_P0_PVCC")
		)
		(pad "5" smd rect
			(at -2.400046 -0.47498 270)
			(size 0.2286 0.6096)
			(layers "F.Cu" "F.Mask" "F.Paste")
			(net "GND")
		)
		(pad "6" smd rect
			(at -2.400046 -0.024892 270)
			(size 0.2286 0.6096)
			(layers "F.Cu" "F.Mask" "F.Paste")
			(net "NC_PVDDCR_CPU0_P0_GL1_4")
		)
		(pad "7_9-20_24" smd circle
			(at 0 1.150112 270)
			(size 0 0)
			(layers "F.Cu" "F.Mask" "F.Paste")
			(net "GND")
		)
		(pad "10_19" smd rect
			(at 0 2.899918 270)
			(size 0.6096 4.318)
			(layers "F.Cu" "F.Mask" "F.Paste")
			(net "SW_PVDDCR_CPU0_P0_SW4")
		)
		(pad "25_29" smd rect
			(at 1.549908 -1.279906 90)
			(size 2.0574 2.3114)
			(layers "F.Cu" "F.Mask" "F.Paste")
			(net "SW_P12V_AUX_PVDDCR_CPU0_P0_FLT")
		)
		(pad "30" smd rect
			(at 2.05994 -2.899918 180)
			(size 0.2286 0.6096)
			(layers "F.Cu" "F.Mask" "F.Paste")
			(net "SW_P12V_AUX_PVDDCR_CPU0_P0_FLT")
		)
		(pad "31" smd rect
			(at 1.610106 -2.899918 180)
			(size 0.2286 0.6096)
			(layers "F.Cu" "F.Mask" "F.Paste")
			(net "NC_PVDDCR_CPU0_P0_DNC4")
		)
		(pad "32" smd rect
			(at 1.160018 -2.899918 180)
			(size 0.2286 0.6096)
			(layers "F.Cu" "F.Mask" "F.Paste")
			(net "SW_PVDDCR_CPU0_P0_PH4")
		)
		(pad "33" smd rect
			(at 0.70993 -2.899918 180)
			(size 0.2286 0.6096)
			(layers "F.Cu" "F.Mask" "F.Paste")
			(net "SW_PVDDCR_CPU0_P0_BOOT4")
		)
		(pad "34" smd rect
			(at 0.260096 -2.899918 180)
			(size 0.2286 0.6096)
			(layers "F.Cu" "F.Mask" "F.Paste")
			(net "PVDDCR_CPU0_P0_PWM4")
		)
		(pad "35" smd rect
			(at -0.189992 -2.899918 180)
			(size 0.2286 0.6096)
			(layers "F.Cu" "F.Mask" "F.Paste")
			(net "PVDDCR_CPU0_P0_VCC4")
		)
		(pad "36" smd rect
			(at -0.64008 -2.899918 180)
			(size 0.2286 0.6096)
			(layers "F.Cu" "F.Mask" "F.Paste")
			(net "PVDDCR_CPU0_P0_TEMP0")
		)
		(pad "37" smd rect
			(at -1.089914 -2.899918 180)
			(size 0.2286 0.6096)
			(layers "F.Cu" "F.Mask" "F.Paste")
			(net "PVDDCR_CPU0_P0_LSET4")
		)
		(pad "38" smd rect
			(at -1.540002 -2.899918 180)
			(size 0.2286 0.6096)
			(layers "F.Cu" "F.Mask" "F.Paste")
			(net "PVDDCR_CPU0_P0_IMON4")
		)
		(pad "39" smd rect
			(at -1.99009 -2.899918 180)
			(size 0.2286 0.6096)
			(layers "F.Cu" "F.Mask" "F.Paste")
			(net "PVDDCR_CPU0_P0_VCCS")
		)
		(pad "40" smd rect
			(at -0.87503 -1.27508 180)
			(size 1.7526 1.9558)
			(layers "F.Cu" "F.Mask" "F.Paste")
			(net "GND")
		)
		(pad "41" smd rect
			(at -1.525016 0.249936 90)
			(size 0.3048 0.4572)
			(layers "F.Cu" "F.Mask" "F.Paste")
			(net "NC_PVDDCR_CPU0_P0_GL2_4")
		)
		(zone
			(layer "F.Cu")
			(hatch none 0.5)
			(connect_pads
				(clearance 0)
			)
			(min_thickness 0.25)
			(keepout
				(tracks not_allowed)
				(vias allowed)
				(pads allowed)
				(copperpour not_allowed)
				(footprints allowed)
			)
			(placement
				(enabled no)
				(sheetname "")
			)
			(fill
				(thermal_gap 0.5)
				(thermal_bridge_width 0.5)
				(island_removal_mode 0)
			)
			(polygon
				(pts
					(xy 391.9093 -185.321702) (xy 391.9093 -184.99455) (xy 386.909056 -184.99455) (xy 386.909056 -185.322972)
					(xy 387.199378 -185.322972) (xy 387.199378 -185.288174) (xy 391.618978 -185.288174) (xy 391.618978 -185.321702)
				)
			)
		)
		(zone
			(layer "F.Cu")
			(hatch none 0.5)
			(connect_pads
				(clearance 0)
			)
			(min_thickness 0.25)
			(keepout
				(tracks not_allowed)
				(vias allowed)
				(pads allowed)
				(copperpour not_allowed)
				(footprints allowed)
			)
			(placement
				(enabled no)
				(sheetname "")
			)
			(fill
				(thermal_gap 0.5)
				(thermal_bridge_width 0.5)
				(island_removal_mode 0)
			)
			(polygon
				(pts
					(xy 389.357108 -182.497476) (xy 389.357108 -180.440076) (xy 391.211308 -180.440076) (xy 391.211308 -180.681122)
					(xy 391.453624 -180.681122) (xy 391.453624 -180.199538) (xy 387.624066 -180.199538) (xy 387.624066 -180.38445)
					(xy 389.06577 -180.38445) (xy 389.06577 -182.54345) (xy 386.909056 -182.54345) (xy 386.909056 -182.793132)
					(xy 389.061452 -182.793132)
				)
			)
		)
	)
	(footprint ""
		(layer "F.Cu")
		(at 197.273926 -106.543856)
		(property "Reference" "C5002"
			(at 0 0 0)
			(layer "F.SilkS")
			(hide yes)
			(effects
				(font
					(size 1.27 1.27)
				)
			)
		)
		(property "Value" ""
			(at 0 0 0)
			(layer "F.Fab")
			(effects
				(font
					(size 1.27 1.27)
				)
			)
		)
		(duplicate_pad_numbers_are_jumpers no)
		(fp_line
			(start -0.7874 -0.4064)
			(end 0.7874 -0.4064)
			(stroke
				(width 0.1524)
				(type default)
			)
			(layer "F.SilkS")
		)
		(fp_line
			(start -0.7874 0.4064)
			(end -0.7874 -0.4064)
			(stroke
				(width 0.1524)
				(type default)
			)
			(layer "F.SilkS")
		)
		(fp_line
			(start 0.7874 -0.4064)
			(end 0.7874 0.4064)
			(stroke
				(width 0.1524)
				(type default)
			)
			(layer "F.SilkS")
		)
		(fp_line
			(start 0.7874 0.4064)
			(end -0.7874 0.4064)
			(stroke
				(width 0.1524)
				(type default)
			)
			(layer "F.SilkS")
		)
		(fp_line
			(start -0.67945 -0.305054)
			(end -0.12065 -0.305054)
			(stroke
				(width 0.1)
				(type default)
			)
			(layer "F.Fab")
		)
		(fp_line
			(start -0.67945 0.3048)
			(end -0.67945 -0.305054)
			(stroke
				(width 0.1)
				(type default)
			)
			(layer "F.Fab")
		)
		(fp_line
			(start -0.12065 -0.305054)
			(end -0.12065 -0.2794)
			(stroke
				(width 0.1)
				(type default)
			)
			(layer "F.Fab")
		)
		(fp_line
			(start -0.12065 -0.2794)
			(end 0.12065 -0.2794)
			(stroke
				(width 0.1)
				(type default)
			)
			(layer "F.Fab")
		)
		(fp_line
			(start -0.12065 0.2794)
			(end -0.12065 0.3048)
			(stroke
				(width 0.1)
				(type default)
			)
			(layer "F.Fab")
		)
		(fp_line
			(start -0.12065 0.3048)
			(end -0.67945 0.3048)
			(stroke
				(width 0.1)
				(type default)
			)
			(layer "F.Fab")
		)
		(fp_line
			(start 0.120396 0.2794)
			(end -0.12065 0.2794)
			(stroke
				(width 0.1)
				(type default)
			)
			(layer "F.Fab")
		)
		(fp_line
			(start 0.120396 0.3048)
			(end 0.120396 0.2794)
			(stroke
				(width 0.1)
				(type default)
			)
			(layer "F.Fab")
		)
		(fp_line
			(start 0.12065 -0.3048)
			(end 0.67945 -0.3048)
			(stroke
				(width 0.1)
				(type default)
			)
			(layer "F.Fab")
		)
		(fp_line
			(start 0.12065 -0.2794)
			(end 0.12065 -0.3048)
			(stroke
				(width 0.1)
				(type default)
			)
			(layer "F.Fab")
		)
		(fp_line
			(start 0.67945 -0.3048)
			(end 0.67945 0.3048)
			(stroke
				(width 0.1)
				(type default)
			)
			(layer "F.Fab")
		)
		(fp_line
			(start 0.67945 0.3048)
			(end 0.120396 0.3048)
			(stroke
				(width 0.1)
				(type default)
			)
			(layer "F.Fab")
		)
		(pad "1" smd circle
			(at -0.40005 0)
			(size 0 0)
			(layers "F.Cu" "F.Mask" "F.Paste")
			(net "FM_PWRGD_PVDD33_S5")
		)
		(pad "2" smd circle
			(at 0.40005 0)
			(size 0 0)
			(layers "F.Cu" "F.Mask" "F.Paste")
			(net "GND")
		)
	)
	(footprint ""
		(layer "F.Cu")
		(at 344.474546 -23.8887 -90)
		(property "Reference" "R936"
			(at 0 0 270)
			(layer "F.SilkS")
			(hide yes)
			(effects
				(font
					(size 1.27 1.27)
				)
			)
		)
		(property "Value" ""
			(at 0 0 270)
			(layer "F.Fab")
			(effects
				(font
					(size 1.27 1.27)
				)
			)
		)
		(duplicate_pad_numbers_are_jumpers no)
		(fp_line
			(start -0.7874 0.4064)
			(end -0.7874 -0.4064)
			(stroke
				(width 0.1524)
				(type default)
			)
			(layer "F.SilkS")
		)
		(fp_line
			(start 0.7874 0.4064)
			(end -0.7874 0.4064)
			(stroke
				(width 0.1524)
				(type default)
			)
			(layer "F.SilkS")
		)
		(fp_line
			(start -0.7874 -0.4064)
			(end 0.7874 -0.4064)
			(stroke
				(width 0.1524)
				(type default)
			)
			(layer "F.SilkS")
		)
		(fp_line
			(start 0.7874 -0.4064)
			(end 0.7874 0.4064)
			(stroke
				(width 0.1524)
				(type default)
			)
			(layer "F.SilkS")
		)
		(fp_line
			(start -0.67945 0.3048)
			(end -0.67945 -0.305054)
			(stroke
				(width 0.1)
				(type default)
			)
			(layer "F.Fab")
		)
		(fp_line
			(start -0.12065 0.3048)
			(end -0.67945 0.3048)
			(stroke
				(width 0.1)
				(type default)
			)
			(layer "F.Fab")
		)
		(fp_line
			(start 0.120396 0.3048)
			(end 0.120396 0.2794)
			(stroke
				(width 0.1)
				(type default)
			)
			(layer "F.Fab")
		)
		(fp_line
			(start 0.67945 0.3048)
			(end 0.120396 0.3048)
			(stroke
				(width 0.1)
				(type default)
			)
			(layer "F.Fab")
		)
		(fp_line
			(start -0.12065 0.2794)
			(end -0.12065 0.3048)
			(stroke
				(width 0.1)
				(type default)
			)
			(layer "F.Fab")
		)
		(fp_line
			(start 0.120396 0.2794)
			(end -0.12065 0.2794)
			(stroke
				(width 0.1)
				(type default)
			)
			(layer "F.Fab")
		)
		(fp_line
			(start -0.12065 -0.2794)
			(end 0.12065 -0.2794)
			(stroke
				(width 0.1)
				(type default)
			)
			(layer "F.Fab")
		)
		(fp_line
			(start 0.12065 -0.2794)
			(end 0.12065 -0.3048)
			(stroke
				(width 0.1)
				(type default)
			)
			(layer "F.Fab")
		)
		(fp_line
			(start 0.12065 -0.3048)
			(end 0.67945 -0.3048)
			(stroke
				(width 0.1)
				(type default)
			)
			(layer "F.Fab")
		)
		(fp_line
			(start 0.67945 -0.3048)
			(end 0.67945 0.3048)
			(stroke
				(width 0.1)
				(type default)
			)
			(layer "F.Fab")
		)
		(fp_line
			(start -0.67945 -0.305054)
			(end -0.12065 -0.305054)
			(stroke
				(width 0.1)
				(type default)
			)
			(layer "F.Fab")
		)
		(fp_line
			(start -0.12065 -0.305054)
			(end -0.12065 -0.2794)
			(stroke
				(width 0.1)
				(type default)
			)
			(layer "F.Fab")
		)
		(pad "1" smd circle
			(at -0.40005 0 270)
			(size 0 0)
			(layers "F.Cu" "F.Mask" "F.Paste")
			(net "FM_SMERR_BUF_LED_N")
		)
		(pad "2" smd circle
			(at 0.40005 0 270)
			(size 0 0)
			(layers "F.Cu" "F.Mask" "F.Paste")
			(net "FM_SMERR_BUF_R_LED_N")
		)
	)
	(footprint ""
		(layer "F.Cu")
		(at 5.164328 -131.305554 180)
		(property "Reference" "R4082"
			(at 0 0 180)
			(layer "F.SilkS")
			(hide yes)
			(effects
				(font
					(size 1.27 1.27)
				)
			)
		)
		(property "Value" ""
			(at 0 0 180)
			(layer "F.Fab")
			(effects
				(font
					(size 1.27 1.27)
				)
			)
		)
		(duplicate_pad_numbers_are_jumpers no)
		(fp_line
			(start 0.7874 0.4064)
			(end -0.7874 0.4064)
			(stroke
				(width 0.1524)
				(type default)
			)
			(layer "F.SilkS")
		)
		(fp_line
			(start 0.7874 -0.4064)
			(end 0.7874 0.4064)
			(stroke
				(width 0.1524)
				(type default)
			)
			(layer "F.SilkS")
		)
		(fp_line
			(start -0.7874 0.4064)
			(end -0.7874 -0.4064)
			(stroke
				(width 0.1524)
				(type default)
			)
			(layer "F.SilkS")
		)
		(fp_line
			(start -0.7874 -0.4064)
			(end 0.7874 -0.4064)
			(stroke
				(width 0.1524)
				(type default)
			)
			(layer "F.SilkS")
		)
		(fp_line
			(start 0.67945 0.3048)
			(end 0.120396 0.3048)
			(stroke
				(width 0.1)
				(type default)
			)
			(layer "F.Fab")
		)
		(fp_line
			(start 0.67945 -0.3048)
			(end 0.67945 0.3048)
			(stroke
				(width 0.1)
				(type default)
			)
			(layer "F.Fab")
		)
		(fp_line
			(start 0.12065 -0.2794)
			(end 0.12065 -0.3048)
			(stroke
				(width 0.1)
				(type default)
			)
			(layer "F.Fab")
		)
		(fp_line
			(start 0.12065 -0.3048)
			(end 0.67945 -0.3048)
			(stroke
				(width 0.1)
				(type default)
			)
			(layer "F.Fab")
		)
		(fp_line
			(start 0.120396 0.3048)
			(end 0.120396 0.2794)
			(stroke
				(width 0.1)
				(type default)
			)
			(layer "F.Fab")
		)
		(fp_line
			(start 0.120396 0.2794)
			(end -0.12065 0.2794)
			(stroke
				(width 0.1)
				(type default)
			)
			(layer "F.Fab")
		)
		(fp_line
			(start -0.12065 0.3048)
			(end -0.67945 0.3048)
			(stroke
				(width 0.1)
				(type default)
			)
			(layer "F.Fab")
		)
		(fp_line
			(start -0.12065 0.2794)
			(end -0.12065 0.3048)
			(stroke
				(width 0.1)
				(type default)
			)
			(layer "F.Fab")
		)
		(fp_line
			(start -0.12065 -0.2794)
			(end 0.12065 -0.2794)
			(stroke
				(width 0.1)
				(type default)
			)
			(layer "F.Fab")
		)
		(fp_line
			(start -0.12065 -0.305054)
			(end -0.12065 -0.2794)
			(stroke
				(width 0.1)
				(type default)
			)
			(layer "F.Fab")
		)
		(fp_line
			(start -0.67945 0.3048)
			(end -0.67945 -0.305054)
			(stroke
				(width 0.1)
				(type default)
			)
			(layer "F.Fab")
		)
		(fp_line
			(start -0.67945 -0.305054)
			(end -0.12065 -0.305054)
			(stroke
				(width 0.1)
				(type default)
			)
			(layer "F.Fab")
		)
		(pad "1" smd circle
			(at -0.40005 0 180)
			(size 0 0)
			(layers "F.Cu" "F.Mask" "F.Paste")
			(net "CLK_GEN2_SMB_SADR")
		)
		(pad "2" smd circle
			(at 0.40005 0 180)
			(size 0 0)
			(layers "F.Cu" "F.Mask" "F.Paste")
			(net "GND")
		)
	)
	(footprint ""
		(layer "F.Cu")
		(at 10.066782 -410.818584 180)
		(property "Reference" "PC523"
			(at 0 0 180)
			(layer "F.SilkS")
			(hide yes)
			(effects
				(font
					(size 1.27 1.27)
				)
			)
		)
		(property "Value" ""
			(at 0 0 180)
			(layer "F.Fab")
			(effects
				(font
					(size 1.27 1.27)
				)
			)
		)
		(duplicate_pad_numbers_are_jumpers no)
		(fp_line
			(start 0.7874 0.4064)
			(end -0.7874 0.4064)
			(stroke
				(width 0.1524)
				(type default)
			)
			(layer "F.SilkS")
		)
		(fp_line
			(start 0.7874 -0.4064)
			(end 0.7874 0.4064)
			(stroke
				(width 0.1524)
				(type default)
			)
			(layer "F.SilkS")
		)
		(fp_line
			(start -0.7874 0.4064)
			(end -0.7874 -0.4064)
			(stroke
				(width 0.1524)
				(type default)
			)
			(layer "F.SilkS")
		)
		(fp_line
			(start -0.7874 -0.4064)
			(end 0.7874 -0.4064)
			(stroke
				(width 0.1524)
				(type default)
			)
			(layer "F.SilkS")
		)
		(fp_line
			(start 0.67945 0.3048)
			(end 0.120396 0.3048)
			(stroke
				(width 0.1)
				(type default)
			)
			(layer "F.Fab")
		)
		(fp_line
			(start 0.67945 -0.3048)
			(end 0.67945 0.3048)
			(stroke
				(width 0.1)
				(type default)
			)
			(layer "F.Fab")
		)
		(fp_line
			(start 0.12065 -0.2794)
			(end 0.12065 -0.3048)
			(stroke
				(width 0.1)
				(type default)
			)
			(layer "F.Fab")
		)
		(fp_line
			(start 0.12065 -0.3048)
			(end 0.67945 -0.3048)
			(stroke
				(width 0.1)
				(type default)
			)
			(layer "F.Fab")
		)
		(fp_line
			(start 0.120396 0.3048)
			(end 0.120396 0.2794)
			(stroke
				(width 0.1)
				(type default)
			)
			(layer "F.Fab")
		)
		(fp_line
			(start 0.120396 0.2794)
			(end -0.12065 0.2794)
			(stroke
				(width 0.1)
				(type default)
			)
			(layer "F.Fab")
		)
		(fp_line
			(start -0.12065 0.3048)
			(end -0.67945 0.3048)
			(stroke
				(width 0.1)
				(type default)
			)
			(layer "F.Fab")
		)
		(fp_line
			(start -0.12065 0.2794)
			(end -0.12065 0.3048)
			(stroke
				(width 0.1)
				(type default)
			)
			(layer "F.Fab")
		)
		(fp_line
			(start -0.12065 -0.2794)
			(end 0.12065 -0.2794)
			(stroke
				(width 0.1)
				(type default)
			)
			(layer "F.Fab")
		)
		(fp_line
			(start -0.12065 -0.305054)
			(end -0.12065 -0.2794)
			(stroke
				(width 0.1)
				(type default)
			)
			(layer "F.Fab")
		)
		(fp_line
			(start -0.67945 0.3048)
			(end -0.67945 -0.305054)
			(stroke
				(width 0.1)
				(type default)
			)
			(layer "F.Fab")
		)
		(fp_line
			(start -0.67945 -0.305054)
			(end -0.12065 -0.305054)
			(stroke
				(width 0.1)
				(type default)
			)
			(layer "F.Fab")
		)
		(pad "1" smd circle
			(at -0.40005 0 180)
			(size 0 0)
			(layers "F.Cu" "F.Mask" "F.Paste")
			(net "P0V9_RETIMER_CPU1_TEMP0")
		)
		(pad "2" smd circle
			(at 0.40005 0 180)
			(size 0 0)
			(layers "F.Cu" "F.Mask" "F.Paste")
			(net "GND")
		)
	)
	(footprint ""
		(layer "F.Cu")
		(at 414.331912 -364.781592 180)
		(property "Reference" "C196"
			(at 0 0 180)
			(layer "F.SilkS")
			(hide yes)
			(effects
				(font
					(size 1.27 1.27)
				)
			)
		)
		(property "Value" ""
			(at 0 0 180)
			(layer "F.Fab")
			(effects
				(font
					(size 1.27 1.27)
				)
			)
		)
		(duplicate_pad_numbers_are_jumpers no)
		(fp_line
			(start 0.7874 0.4064)
			(end -0.7874 0.4064)
			(stroke
				(width 0.1524)
				(type default)
			)
			(layer "F.SilkS")
		)
		(fp_line
			(start 0.7874 -0.4064)
			(end 0.7874 0.4064)
			(stroke
				(width 0.1524)
				(type default)
			)
			(layer "F.SilkS")
		)
		(fp_line
			(start -0.7874 0.4064)
			(end -0.7874 -0.4064)
			(stroke
				(width 0.1524)
				(type default)
			)
			(layer "F.SilkS")
		)
		(fp_line
			(start -0.7874 -0.4064)
			(end 0.7874 -0.4064)
			(stroke
				(width 0.1524)
				(type default)
			)
			(layer "F.SilkS")
		)
		(fp_line
			(start 0.67945 0.3048)
			(end 0.120396 0.3048)
			(stroke
				(width 0.1)
				(type default)
			)
			(layer "F.Fab")
		)
		(fp_line
			(start 0.67945 -0.3048)
			(end 0.67945 0.3048)
			(stroke
				(width 0.1)
				(type default)
			)
			(layer "F.Fab")
		)
		(fp_line
			(start 0.12065 -0.2794)
			(end 0.12065 -0.3048)
			(stroke
				(width 0.1)
				(type default)
			)
			(layer "F.Fab")
		)
		(fp_line
			(start 0.12065 -0.3048)
			(end 0.67945 -0.3048)
			(stroke
				(width 0.1)
				(type default)
			)
			(layer "F.Fab")
		)
		(fp_line
			(start 0.120396 0.3048)
			(end 0.120396 0.2794)
			(stroke
				(width 0.1)
				(type default)
			)
			(layer "F.Fab")
		)
		(fp_line
			(start 0.120396 0.2794)
			(end -0.12065 0.2794)
			(stroke
				(width 0.1)
				(type default)
			)
			(layer "F.Fab")
		)
		(fp_line
			(start -0.12065 0.3048)
			(end -0.67945 0.3048)
			(stroke
				(width 0.1)
				(type default)
			)
			(layer "F.Fab")
		)
		(fp_line
			(start -0.12065 0.2794)
			(end -0.12065 0.3048)
			(stroke
				(width 0.1)
				(type default)
			)
			(layer "F.Fab")
		)
		(fp_line
			(start -0.12065 -0.2794)
			(end 0.12065 -0.2794)
			(stroke
				(width 0.1)
				(type default)
			)
			(layer "F.Fab")
		)
		(fp_line
			(start -0.12065 -0.305054)
			(end -0.12065 -0.2794)
			(stroke
				(width 0.1)
				(type default)
			)
			(layer "F.Fab")
		)
		(fp_line
			(start -0.67945 0.3048)
			(end -0.67945 -0.305054)
			(stroke
				(width 0.1)
				(type default)
			)
			(layer "F.Fab")
		)
		(fp_line
			(start -0.67945 -0.305054)
			(end -0.12065 -0.305054)
			(stroke
				(width 0.1)
				(type default)
			)
			(layer "F.Fab")
		)
		(pad "1" smd circle
			(at -0.40005 0 180)
			(size 0 0)
			(layers "F.Cu" "F.Mask" "F.Paste")
			(net "PWRGD_PVDD11_S3_P0_R")
		)
		(pad "2" smd circle
			(at 0.40005 0 180)
			(size 0 0)
			(layers "F.Cu" "F.Mask" "F.Paste")
			(net "GND")
		)
	)
	(footprint ""
		(layer "F.Cu")
		(at 336.827876 -70.098412 90)
		(property "Reference" "D80"
			(at -3.934714 -0.691642 90)
			(unlocked yes)
			(layer "F.SilkS")
			(effects
				(font
					(size 0.7874 0.5842)
					(thickness 0.1524)
				)
				(justify left)
			)
		)
		(property "Value" ""
			(at 0 0 90)
			(layer "F.Fab")
			(effects
				(font
					(size 1.27 1.27)
				)
			)
		)
		(duplicate_pad_numbers_are_jumpers no)
		(fp_line
			(start 1.16078 -0.4826)
			(end 1.16078 0.4826)
			(stroke
				(width 0.1524)
				(type default)
			)
			(layer "F.SilkS")
		)
		(fp_line
			(start 1.03378 -0.4826)
			(end 1.03378 0.4826)
			(stroke
				(width 0.1524)
				(type default)
			)
			(layer "F.SilkS")
		)
		(fp_line
			(start 0.90678 -0.4826)
			(end 0.90678 0.4826)
			(stroke
				(width 0.1524)
				(type default)
			)
			(layer "F.SilkS")
		)
		(fp_line
			(start -0.64008 -0.4826)
			(end 1.16078 -0.4826)
			(stroke
				(width 0.1524)
				(type default)
			)
			(layer "F.SilkS")
		)
		(fp_line
			(start -0.79248 -0.4826)
			(end 1.03378 -0.4826)
			(stroke
				(width 0.1524)
				(type default)
			)
			(layer "F.SilkS")
		)
		(fp_line
			(start -0.89408 -0.4826)
			(end 0.90678 -0.4826)
			(stroke
				(width 0.1524)
				(type default)
			)
			(layer "F.SilkS")
		)
		(fp_line
			(start 1.16078 0.4826)
			(end -0.64008 0.4826)
			(stroke
				(width 0.1524)
				(type default)
			)
			(layer "F.SilkS")
		)
		(fp_line
			(start 1.03378 0.4826)
			(end -0.79248 0.4826)
			(stroke
				(width 0.1524)
				(type default)
			)
			(layer "F.SilkS")
		)
		(fp_line
			(start 0.90678 0.4826)
			(end -0.90678 0.4826)
			(stroke
				(width 0.1524)
				(type default)
			)
			(layer "F.SilkS")
		)
		(fp_line
			(start -0.90678 0.4826)
			(end -0.90678 -0.4699)
			(stroke
				(width 0.1524)
				(type default)
			)
			(layer "F.SilkS")
		)
		(fp_line
			(start 0.499872 -0.249936)
			(end 0.499872 0.249936)
			(stroke
				(width 0.1)
				(type default)
			)
			(layer "F.Fab")
		)
		(fp_line
			(start -0.499872 -0.249936)
			(end 0.499872 -0.249936)
			(stroke
				(width 0.1)
				(type default)
			)
			(layer "F.Fab")
		)
		(fp_line
			(start 0.499872 0.249936)
			(end -0.499872 0.249936)
			(stroke
				(width 0.1)
				(type default)
			)
			(layer "F.Fab")
		)
		(fp_line
			(start -0.499872 0.249936)
			(end -0.499872 -0.249936)
			(stroke
				(width 0.1)
				(type default)
			)
			(layer "F.Fab")
		)
		(pad "A" smd rect
			(at -0.47498 0 90)
			(size 0.6096 0.7112)
			(layers "F.Cu" "F.Mask" "F.Paste")
			(net "LED_PWRGD_PVDDCR_CPU0_P1_R")
		)
		(pad "C" smd rect
			(at 0.47498 0 90)
			(size 0.6096 0.7112)
			(layers "F.Cu" "F.Mask" "F.Paste")
			(net "LED_PWRGD_PVDDCR_CPU0_P1_D")
		)
	)
	(footprint ""
		(layer "F.Cu")
		(at 392.801348 -17.624298 90)
		(property "Reference" "C1550"
			(at 0 0 90)
			(layer "F.SilkS")
			(hide yes)
			(effects
				(font
					(size 1.27 1.27)
				)
			)
		)
		(property "Value" ""
			(at 0 0 90)
			(layer "F.Fab")
			(effects
				(font
					(size 1.27 1.27)
				)
			)
		)
		(duplicate_pad_numbers_are_jumpers no)
		(fp_line
			(start 0.299974 -0.150114)
			(end 0.299974 0.150114)
			(stroke
				(width 0.1)
				(type default)
			)
			(layer "F.Fab")
		)
		(fp_line
			(start -0.299974 -0.150114)
			(end 0.299974 -0.150114)
			(stroke
				(width 0.1)
				(type default)
			)
			(layer "F.Fab")
		)
		(fp_line
			(start 0.299974 0.150114)
			(end -0.299974 0.150114)
			(stroke
				(width 0.1)
				(type default)
			)
			(layer "F.Fab")
		)
		(fp_line
			(start -0.299974 0.150114)
			(end -0.299974 -0.150114)
			(stroke
				(width 0.1)
				(type default)
			)
			(layer "F.Fab")
		)
		(pad "1" smd rect
			(at -0.2667 0 90)
			(size 0.3048 0.381)
			(layers "F.Cu" "F.Mask" "F.Paste")
			(net "P5E_CPU0_G3_TX_C_DN<14>")
		)
		(pad "2" smd rect
			(at 0.2667 0 90)
			(size 0.3048 0.381)
			(layers "F.Cu" "F.Mask" "F.Paste")
			(net "P5E_CPU0_G3_TX_DN<14>")
		)
	)
	(footprint ""
		(layer "F.Cu")
		(at 107.722924 -392.521694)
		(property "Reference" "L10"
			(at -4.85648 -0.739648 0)
			(unlocked yes)
			(layer "F.SilkS")
			(effects
				(font
					(size 0.7874 0.5842)
					(thickness 0.1524)
				)
				(justify left)
			)
		)
		(property "Value" ""
			(at 0 0 0)
			(layer "F.Fab")
			(effects
				(font
					(size 1.27 1.27)
				)
			)
		)
		(duplicate_pad_numbers_are_jumpers no)
		(fp_line
			(start -2.249932 -2.249932)
			(end 2.249932 -2.249932)
			(stroke
				(width 0.1524)
				(type default)
			)
			(layer "F.SilkS")
		)
		(fp_line
			(start -2.249932 -1.3843)
			(end -2.249932 -2.249932)
			(stroke
				(width 0.1524)
				(type default)
			)
			(layer "F.SilkS")
		)
		(fp_line
			(start -2.249932 2.249932)
			(end -2.249932 1.3843)
			(stroke
				(width 0.1524)
				(type default)
			)
			(layer "F.SilkS")
		)
		(fp_line
			(start 2.249932 -2.249932)
			(end 2.249932 -1.3843)
			(stroke
				(width 0.1524)
				(type default)
			)
			(layer "F.SilkS")
		)
		(fp_line
			(start 2.249932 1.3843)
			(end 2.249932 2.249932)
			(stroke
				(width 0.1524)
				(type default)
			)
			(layer "F.SilkS")
		)
		(fp_line
			(start 2.249932 2.249932)
			(end -2.249932 2.249932)
			(stroke
				(width 0.1524)
				(type default)
			)
			(layer "F.SilkS")
		)
		(fp_line
			(start -2.249932 -2.249932)
			(end 2.249932 -2.249932)
			(stroke
				(width 0.1)
				(type default)
			)
			(layer "F.Fab")
		)
		(fp_line
			(start -2.249932 2.249932)
			(end -2.249932 -2.249932)
			(stroke
				(width 0.1)
				(type default)
			)
			(layer "F.Fab")
		)
		(fp_line
			(start 2.249932 -2.249932)
			(end 2.249932 2.249932)
			(stroke
				(width 0.1)
				(type default)
			)
			(layer "F.Fab")
		)
		(fp_line
			(start 2.249932 2.249932)
			(end -2.249932 2.249932)
			(stroke
				(width 0.1)
				(type default)
			)
			(layer "F.Fab")
		)
		(pad "1" smd rect
			(at -1.82499 0)
			(size 1.0668 2.5146)
			(layers "F.Cu" "F.Mask" "F.Paste")
			(net "P0V9_CPU1_RT_2D")
		)
		(pad "2" smd rect
			(at 1.82499 0)
			(size 1.0668 2.5146)
			(layers "F.Cu" "F.Mask" "F.Paste")
			(net "P0V9_CPU1_RT3_2A")
		)
	)
	(footprint ""
		(layer "F.Cu")
		(at 398.155668 -396.146274)
		(property "Reference" "R613"
			(at 0 0 0)
			(layer "F.SilkS")
			(hide yes)
			(effects
				(font
					(size 1.27 1.27)
				)
			)
		)
		(property "Value" ""
			(at 0 0 0)
			(layer "F.Fab")
			(effects
				(font
					(size 1.27 1.27)
				)
			)
		)
		(duplicate_pad_numbers_are_jumpers no)
		(fp_line
			(start -0.32512 -0.175006)
			(end 0.32512 -0.175006)
			(stroke
				(width 0.1)
				(type default)
			)
			(layer "F.Fab")
		)
		(fp_line
			(start -0.32512 0.175006)
			(end -0.32512 -0.175006)
			(stroke
				(width 0.1)
				(type default)
			)
			(layer "F.Fab")
		)
		(fp_line
			(start 0.32512 -0.175006)
			(end 0.32512 0.175006)
			(stroke
				(width 0.1)
				(type default)
			)
			(layer "F.Fab")
		)
		(fp_line
			(start 0.32512 0.175006)
			(end -0.32512 0.175006)
			(stroke
				(width 0.1)
				(type default)
			)
			(layer "F.Fab")
		)
		(pad "1" smd rect
			(at -0.2667 0)
			(size 0.3048 0.381)
			(layers "F.Cu" "F.Mask" "F.Paste")
			(net "CLK_100M_RETIMER_CPU0_P2_R_DP")
		)
		(pad "2" smd rect
			(at 0.2667 0 180)
			(size 0.3048 0.381)
			(layers "F.Cu" "F.Mask" "F.Paste")
			(net "CLK_100M_RETIMER_CPU0_P2_DP")
		)
	)
	(footprint ""
		(layer "F.Cu")
		(at 75.337924 -408.517344 -90)
		(property "Reference" "C6648"
			(at 0 0 270)
			(layer "F.SilkS")
			(hide yes)
			(effects
				(font
					(size 1.27 1.27)
				)
			)
		)
		(property "Value" ""
			(at 0 0 270)
			(layer "F.Fab")
			(effects
				(font
					(size 1.27 1.27)
				)
			)
		)
		(duplicate_pad_numbers_are_jumpers no)
		(fp_line
			(start -0.299974 0.150114)
			(end -0.299974 -0.150114)
			(stroke
				(width 0.1)
				(type default)
			)
			(layer "F.Fab")
		)
		(fp_line
			(start 0.299974 0.150114)
			(end -0.299974 0.150114)
			(stroke
				(width 0.1)
				(type default)
			)
			(layer "F.Fab")
		)
		(fp_line
			(start -0.299974 -0.150114)
			(end 0.299974 -0.150114)
			(stroke
				(width 0.1)
				(type default)
			)
			(layer "F.Fab")
		)
		(fp_line
			(start 0.299974 -0.150114)
			(end 0.299974 0.150114)
			(stroke
				(width 0.1)
				(type default)
			)
			(layer "F.Fab")
		)
		(pad "1" smd rect
			(at -0.2667 0 270)
			(size 0.3048 0.381)
			(layers "F.Cu" "F.Mask" "F.Paste")
			(net "P5E_CPU1_P0_TX_BUF_C_DN<9>")
		)
		(pad "2" smd rect
			(at 0.2667 0 270)
			(size 0.3048 0.381)
			(layers "F.Cu" "F.Mask" "F.Paste")
			(net "P5E_CPU1_P0_TX_BUF_DN<9>")
		)
	)
	(footprint ""
		(layer "F.Cu")
		(at 189.941962 -356.532434 180)
		(property "Reference" "PR329"
			(at 0 0 180)
			(layer "F.SilkS")
			(hide yes)
			(effects
				(font
					(size 1.27 1.27)
				)
			)
		)
		(property "Value" ""
			(at 0 0 180)
			(layer "F.Fab")
			(effects
				(font
					(size 1.27 1.27)
				)
			)
		)
		(duplicate_pad_numbers_are_jumpers no)
		(fp_line
			(start 0.7874 0.4064)
			(end -0.7874 0.4064)
			(stroke
				(width 0.1524)
				(type default)
			)
			(layer "F.SilkS")
		)
		(fp_line
			(start 0.7874 -0.4064)
			(end 0.7874 0.4064)
			(stroke
				(width 0.1524)
				(type default)
			)
			(layer "F.SilkS")
		)
		(fp_line
			(start -0.7874 0.4064)
			(end -0.7874 -0.4064)
			(stroke
				(width 0.1524)
				(type default)
			)
			(layer "F.SilkS")
		)
		(fp_line
			(start -0.7874 -0.4064)
			(end 0.7874 -0.4064)
			(stroke
				(width 0.1524)
				(type default)
			)
			(layer "F.SilkS")
		)
		(fp_line
			(start 0.67945 0.3048)
			(end 0.120396 0.3048)
			(stroke
				(width 0.1)
				(type default)
			)
			(layer "F.Fab")
		)
		(fp_line
			(start 0.67945 -0.3048)
			(end 0.67945 0.3048)
			(stroke
				(width 0.1)
				(type default)
			)
			(layer "F.Fab")
		)
		(fp_line
			(start 0.12065 -0.2794)
			(end 0.12065 -0.3048)
			(stroke
				(width 0.1)
				(type default)
			)
			(layer "F.Fab")
		)
		(fp_line
			(start 0.12065 -0.3048)
			(end 0.67945 -0.3048)
			(stroke
				(width 0.1)
				(type default)
			)
			(layer "F.Fab")
		)
		(fp_line
			(start 0.120396 0.3048)
			(end 0.120396 0.2794)
			(stroke
				(width 0.1)
				(type default)
			)
			(layer "F.Fab")
		)
		(fp_line
			(start 0.120396 0.2794)
			(end -0.12065 0.2794)
			(stroke
				(width 0.1)
				(type default)
			)
			(layer "F.Fab")
		)
		(fp_line
			(start -0.12065 0.3048)
			(end -0.67945 0.3048)
			(stroke
				(width 0.1)
				(type default)
			)
			(layer "F.Fab")
		)
		(fp_line
			(start -0.12065 0.2794)
			(end -0.12065 0.3048)
			(stroke
				(width 0.1)
				(type default)
			)
			(layer "F.Fab")
		)
		(fp_line
			(start -0.12065 -0.2794)
			(end 0.12065 -0.2794)
			(stroke
				(width 0.1)
				(type default)
			)
			(layer "F.Fab")
		)
		(fp_line
			(start -0.12065 -0.305054)
			(end -0.12065 -0.2794)
			(stroke
				(width 0.1)
				(type default)
			)
			(layer "F.Fab")
		)
		(fp_line
			(start -0.67945 0.3048)
			(end -0.67945 -0.305054)
			(stroke
				(width 0.1)
				(type default)
			)
			(layer "F.Fab")
		)
		(fp_line
			(start -0.67945 -0.305054)
			(end -0.12065 -0.305054)
			(stroke
				(width 0.1)
				(type default)
			)
			(layer "F.Fab")
		)
		(pad "1" smd circle
			(at -0.40005 0 180)
			(size 0 0)
			(layers "F.Cu" "F.Mask" "F.Paste")
			(net "GND")
		)
		(pad "2" smd circle
			(at 0.40005 0 180)
			(size 0 0)
			(layers "F.Cu" "F.Mask" "F.Paste")
			(net "PVDD11_S3_P1_LSET2")
		)
	)
	(footprint ""
		(layer "F.Cu")
		(at 80.645 -66.802)
		(property "Reference" "R8097"
			(at 0 0 0)
			(layer "F.SilkS")
			(hide yes)
			(effects
				(font
					(size 1.27 1.27)
				)
			)
		)
		(property "Value" ""
			(at 0 0 0)
			(layer "F.Fab")
			(effects
				(font
					(size 1.27 1.27)
				)
			)
		)
		(duplicate_pad_numbers_are_jumpers no)
		(fp_line
			(start -0.7874 -0.4064)
			(end 0.7874 -0.4064)
			(stroke
				(width 0.1524)
				(type default)
			)
			(layer "F.SilkS")
		)
		(fp_line
			(start -0.7874 0.4064)
			(end -0.7874 -0.4064)
			(stroke
				(width 0.1524)
				(type default)
			)
			(layer "F.SilkS")
		)
		(fp_line
			(start 0.7874 -0.4064)
			(end 0.7874 0.4064)
			(stroke
				(width 0.1524)
				(type default)
			)
			(layer "F.SilkS")
		)
		(fp_line
			(start 0.7874 0.4064)
			(end -0.7874 0.4064)
			(stroke
				(width 0.1524)
				(type default)
			)
			(layer "F.SilkS")
		)
		(fp_line
			(start -0.67945 -0.305054)
			(end -0.12065 -0.305054)
			(stroke
				(width 0.1)
				(type default)
			)
			(layer "F.Fab")
		)
		(fp_line
			(start -0.67945 0.3048)
			(end -0.67945 -0.305054)
			(stroke
				(width 0.1)
				(type default)
			)
			(layer "F.Fab")
		)
		(fp_line
			(start -0.12065 -0.305054)
			(end -0.12065 -0.2794)
			(stroke
				(width 0.1)
				(type default)
			)
			(layer "F.Fab")
		)
		(fp_line
			(start -0.12065 -0.2794)
			(end 0.12065 -0.2794)
			(stroke
				(width 0.1)
				(type default)
			)
			(layer "F.Fab")
		)
		(fp_line
			(start -0.12065 0.2794)
			(end -0.12065 0.3048)
			(stroke
				(width 0.1)
				(type default)
			)
			(layer "F.Fab")
		)
		(fp_line
			(start -0.12065 0.3048)
			(end -0.67945 0.3048)
			(stroke
				(width 0.1)
				(type default)
			)
			(layer "F.Fab")
		)
		(fp_line
			(start 0.120396 0.2794)
			(end -0.12065 0.2794)
			(stroke
				(width 0.1)
				(type default)
			)
			(layer "F.Fab")
		)
		(fp_line
			(start 0.120396 0.3048)
			(end 0.120396 0.2794)
			(stroke
				(width 0.1)
				(type default)
			)
			(layer "F.Fab")
		)
		(fp_line
			(start 0.12065 -0.3048)
			(end 0.67945 -0.3048)
			(stroke
				(width 0.1)
				(type default)
			)
			(layer "F.Fab")
		)
		(fp_line
			(start 0.12065 -0.2794)
			(end 0.12065 -0.3048)
			(stroke
				(width 0.1)
				(type default)
			)
			(layer "F.Fab")
		)
		(fp_line
			(start 0.67945 -0.3048)
			(end 0.67945 0.3048)
			(stroke
				(width 0.1)
				(type default)
			)
			(layer "F.Fab")
		)
		(fp_line
			(start 0.67945 0.3048)
			(end 0.120396 0.3048)
			(stroke
				(width 0.1)
				(type default)
			)
			(layer "F.Fab")
		)
		(pad "1" smd circle
			(at -0.40005 0)
			(size 0 0)
			(layers "F.Cu" "F.Mask" "F.Paste")
			(net "OCP_V3_2_P3V3_R1_PWRGD")
		)
		(pad "2" smd circle
			(at 0.40005 0)
			(size 0 0)
			(layers "F.Cu" "F.Mask" "F.Paste")
			(net "OCP_V3_2_P3V3_PWRGD")
		)
	)
	(footprint ""
		(layer "F.Cu")
		(at 420.75735 -36.007548)
		(property "Reference" "R1508"
			(at 0 0 0)
			(layer "F.SilkS")
			(hide yes)
			(effects
				(font
					(size 1.27 1.27)
				)
			)
		)
		(property "Value" ""
			(at 0 0 0)
			(layer "F.Fab")
			(effects
				(font
					(size 1.27 1.27)
				)
			)
		)
		(duplicate_pad_numbers_are_jumpers no)
		(fp_line
			(start -0.7874 -0.406146)
			(end 0.7874 -0.406146)
			(stroke
				(width 0.1524)
				(type default)
			)
			(layer "F.SilkS")
		)
		(fp_line
			(start -0.7874 0.406146)
			(end -0.7874 -0.406146)
			(stroke
				(width 0.1524)
				(type default)
			)
			(layer "F.SilkS")
		)
		(fp_line
			(start 0.7874 -0.406146)
			(end 0.7874 0.406146)
			(stroke
				(width 0.1524)
				(type default)
			)
			(layer "F.SilkS")
		)
		(fp_line
			(start 0.7874 0.406146)
			(end -0.7874 0.406146)
			(stroke
				(width 0.1524)
				(type default)
			)
			(layer "F.SilkS")
		)
		(fp_line
			(start -0.67945 -0.305054)
			(end -0.12065 -0.305054)
			(stroke
				(width 0.1)
				(type default)
			)
			(layer "F.Fab")
		)
		(fp_line
			(start -0.67945 0.3048)
			(end -0.67945 -0.305054)
			(stroke
				(width 0.1)
				(type default)
			)
			(layer "F.Fab")
		)
		(fp_line
			(start -0.12065 -0.305054)
			(end -0.12065 -0.2794)
			(stroke
				(width 0.1)
				(type default)
			)
			(layer "F.Fab")
		)
		(fp_line
			(start -0.12065 -0.2794)
			(end 0.12065 -0.2794)
			(stroke
				(width 0.1)
				(type default)
			)
			(layer "F.Fab")
		)
		(fp_line
			(start -0.12065 0.2794)
			(end -0.120396 0.3048)
			(stroke
				(width 0.1)
				(type default)
			)
			(layer "F.Fab")
		)
		(fp_line
			(start -0.120396 0.3048)
			(end -0.67945 0.3048)
			(stroke
				(width 0.1)
				(type default)
			)
			(layer "F.Fab")
		)
		(fp_line
			(start 0.120396 -0.3048)
			(end 0.67945 -0.3048)
			(stroke
				(width 0.1)
				(type default)
			)
			(layer "F.Fab")
		)
		(fp_line
			(start 0.120396 0.2794)
			(end -0.12065 0.2794)
			(stroke
				(width 0.1)
				(type default)
			)
			(layer "F.Fab")
		)
		(fp_line
			(start 0.120396 0.3048)
			(end 0.120396 0.2794)
			(stroke
				(width 0.1)
				(type default)
			)
			(layer "F.Fab")
		)
		(fp_line
			(start 0.12065 -0.2794)
			(end 0.120396 -0.3048)
			(stroke
				(width 0.1)
				(type default)
			)
			(layer "F.Fab")
		)
		(fp_line
			(start 0.67945 -0.3048)
			(end 0.67945 0.3048)
			(stroke
				(width 0.1)
				(type default)
			)
			(layer "F.Fab")
		)
		(fp_line
			(start 0.67945 0.3048)
			(end 0.120396 0.3048)
			(stroke
				(width 0.1)
				(type default)
			)
			(layer "F.Fab")
		)
		(pad "1" smd circle
			(at -0.40005 0)
			(size 0 0)
			(layers "F.Cu" "F.Mask" "F.Paste")
			(net "GND")
		)
		(pad "2" smd circle
			(at 0.40005 0)
			(size 0 0)
			(layers "F.Cu" "F.Mask" "F.Paste")
			(net "PD_BIOS_DEBUG_MODE")
		)
	)
	(footprint ""
		(layer "F.Cu")
		(at 44.069 -438.15 180)
		(property "Reference" "R2937"
			(at 0 0 180)
			(layer "F.SilkS")
			(hide yes)
			(effects
				(font
					(size 1.27 1.27)
				)
			)
		)
		(property "Value" ""
			(at 0 0 180)
			(layer "F.Fab")
			(effects
				(font
					(size 1.27 1.27)
				)
			)
		)
		(duplicate_pad_numbers_are_jumpers no)
		(fp_line
			(start 0.7874 0.4064)
			(end -0.7874 0.4064)
			(stroke
				(width 0.1524)
				(type default)
			)
			(layer "F.SilkS")
		)
		(fp_line
			(start 0.7874 -0.4064)
			(end 0.7874 0.4064)
			(stroke
				(width 0.1524)
				(type default)
			)
			(layer "F.SilkS")
		)
		(fp_line
			(start -0.7874 0.4064)
			(end -0.7874 -0.4064)
			(stroke
				(width 0.1524)
				(type default)
			)
			(layer "F.SilkS")
		)
		(fp_line
			(start -0.7874 -0.4064)
			(end 0.7874 -0.4064)
			(stroke
				(width 0.1524)
				(type default)
			)
			(layer "F.SilkS")
		)
		(fp_line
			(start 0.67945 0.3048)
			(end 0.120396 0.3048)
			(stroke
				(width 0.1)
				(type default)
			)
			(layer "F.Fab")
		)
		(fp_line
			(start 0.67945 -0.3048)
			(end 0.67945 0.3048)
			(stroke
				(width 0.1)
				(type default)
			)
			(layer "F.Fab")
		)
		(fp_line
			(start 0.12065 -0.2794)
			(end 0.12065 -0.3048)
			(stroke
				(width 0.1)
				(type default)
			)
			(layer "F.Fab")
		)
		(fp_line
			(start 0.12065 -0.3048)
			(end 0.67945 -0.3048)
			(stroke
				(width 0.1)
				(type default)
			)
			(layer "F.Fab")
		)
		(fp_line
			(start 0.120396 0.3048)
			(end 0.120396 0.2794)
			(stroke
				(width 0.1)
				(type default)
			)
			(layer "F.Fab")
		)
		(fp_line
			(start 0.120396 0.2794)
			(end -0.12065 0.2794)
			(stroke
				(width 0.1)
				(type default)
			)
			(layer "F.Fab")
		)
		(fp_line
			(start -0.12065 0.3048)
			(end -0.67945 0.3048)
			(stroke
				(width 0.1)
				(type default)
			)
			(layer "F.Fab")
		)
		(fp_line
			(start -0.12065 0.2794)
			(end -0.12065 0.3048)
			(stroke
				(width 0.1)
				(type default)
			)
			(layer "F.Fab")
		)
		(fp_line
			(start -0.12065 -0.2794)
			(end 0.12065 -0.2794)
			(stroke
				(width 0.1)
				(type default)
			)
			(layer "F.Fab")
		)
		(fp_line
			(start -0.12065 -0.305054)
			(end -0.12065 -0.2794)
			(stroke
				(width 0.1)
				(type default)
			)
			(layer "F.Fab")
		)
		(fp_line
			(start -0.67945 0.3048)
			(end -0.67945 -0.305054)
			(stroke
				(width 0.1)
				(type default)
			)
			(layer "F.Fab")
		)
		(fp_line
			(start -0.67945 -0.305054)
			(end -0.12065 -0.305054)
			(stroke
				(width 0.1)
				(type default)
			)
			(layer "F.Fab")
		)
		(pad "1" smd circle
			(at -0.40005 0 180)
			(size 0 0)
			(layers "F.Cu" "F.Mask" "F.Paste")
			(net "FM_GPU_PWR_EN_R")
		)
		(pad "2" smd circle
			(at 0.40005 0 180)
			(size 0 0)
			(layers "F.Cu" "F.Mask" "F.Paste")
			(net "GND")
		)
	)
	(footprint ""
		(layer "F.Cu")
		(at 104.902 -426.466 -90)
		(property "Reference" "R3459"
			(at 0 0 270)
			(layer "F.SilkS")
			(hide yes)
			(effects
				(font
					(size 1.27 1.27)
				)
			)
		)
		(property "Value" ""
			(at 0 0 270)
			(layer "F.Fab")
			(effects
				(font
					(size 1.27 1.27)
				)
			)
		)
		(duplicate_pad_numbers_are_jumpers no)
		(fp_line
			(start -0.7874 0.4064)
			(end -0.7874 -0.4064)
			(stroke
				(width 0.1524)
				(type default)
			)
			(layer "F.SilkS")
		)
		(fp_line
			(start 0.7874 0.4064)
			(end -0.7874 0.4064)
			(stroke
				(width 0.1524)
				(type default)
			)
			(layer "F.SilkS")
		)
		(fp_line
			(start -0.7874 -0.4064)
			(end 0.7874 -0.4064)
			(stroke
				(width 0.1524)
				(type default)
			)
			(layer "F.SilkS")
		)
		(fp_line
			(start 0.7874 -0.4064)
			(end 0.7874 0.4064)
			(stroke
				(width 0.1524)
				(type default)
			)
			(layer "F.SilkS")
		)
		(fp_line
			(start -0.67945 0.3048)
			(end -0.67945 -0.305054)
			(stroke
				(width 0.1)
				(type default)
			)
			(layer "F.Fab")
		)
		(fp_line
			(start -0.12065 0.3048)
			(end -0.67945 0.3048)
			(stroke
				(width 0.1)
				(type default)
			)
			(layer "F.Fab")
		)
		(fp_line
			(start 0.120396 0.3048)
			(end 0.120396 0.2794)
			(stroke
				(width 0.1)
				(type default)
			)
			(layer "F.Fab")
		)
		(fp_line
			(start 0.67945 0.3048)
			(end 0.120396 0.3048)
			(stroke
				(width 0.1)
				(type default)
			)
			(layer "F.Fab")
		)
		(fp_line
			(start -0.12065 0.2794)
			(end -0.12065 0.3048)
			(stroke
				(width 0.1)
				(type default)
			)
			(layer "F.Fab")
		)
		(fp_line
			(start 0.120396 0.2794)
			(end -0.12065 0.2794)
			(stroke
				(width 0.1)
				(type default)
			)
			(layer "F.Fab")
		)
		(fp_line
			(start -0.12065 -0.2794)
			(end 0.12065 -0.2794)
			(stroke
				(width 0.1)
				(type default)
			)
			(layer "F.Fab")
		)
		(fp_line
			(start 0.12065 -0.2794)
			(end 0.12065 -0.3048)
			(stroke
				(width 0.1)
				(type default)
			)
			(layer "F.Fab")
		)
		(fp_line
			(start 0.12065 -0.3048)
			(end 0.67945 -0.3048)
			(stroke
				(width 0.1)
				(type default)
			)
			(layer "F.Fab")
		)
		(fp_line
			(start 0.67945 -0.3048)
			(end 0.67945 0.3048)
			(stroke
				(width 0.1)
				(type default)
			)
			(layer "F.Fab")
		)
		(fp_line
			(start -0.67945 -0.305054)
			(end -0.12065 -0.305054)
			(stroke
				(width 0.1)
				(type default)
			)
			(layer "F.Fab")
		)
		(fp_line
			(start -0.12065 -0.305054)
			(end -0.12065 -0.2794)
			(stroke
				(width 0.1)
				(type default)
			)
			(layer "F.Fab")
		)
		(pad "1" smd circle
			(at -0.40005 0 270)
			(size 0 0)
			(layers "F.Cu" "F.Mask" "F.Paste")
			(net "P3V3_AUX")
		)
		(pad "2" smd circle
			(at 0.40005 0 270)
			(size 0 0)
			(layers "F.Cu" "F.Mask" "F.Paste")
			(net "GPU_NVS_PWR_BRAKE_N")
		)
	)
	(footprint ""
		(layer "F.Cu")
		(at 42.545 -436.118 -90)
		(property "Reference" "C1977"
			(at 0 0 270)
			(layer "F.SilkS")
			(hide yes)
			(effects
				(font
					(size 1.27 1.27)
				)
			)
		)
		(property "Value" ""
			(at 0 0 270)
			(layer "F.Fab")
			(effects
				(font
					(size 1.27 1.27)
				)
			)
		)
		(duplicate_pad_numbers_are_jumpers no)
		(fp_line
			(start -0.7874 0.4064)
			(end -0.7874 -0.4064)
			(stroke
				(width 0.1524)
				(type default)
			)
			(layer "F.SilkS")
		)
		(fp_line
			(start 0.7874 0.4064)
			(end -0.7874 0.4064)
			(stroke
				(width 0.1524)
				(type default)
			)
			(layer "F.SilkS")
		)
		(fp_line
			(start -0.7874 -0.4064)
			(end 0.7874 -0.4064)
			(stroke
				(width 0.1524)
				(type default)
			)
			(layer "F.SilkS")
		)
		(fp_line
			(start 0.7874 -0.4064)
			(end 0.7874 0.4064)
			(stroke
				(width 0.1524)
				(type default)
			)
			(layer "F.SilkS")
		)
		(fp_line
			(start -0.67945 0.3048)
			(end -0.67945 -0.305054)
			(stroke
				(width 0.1)
				(type default)
			)
			(layer "F.Fab")
		)
		(fp_line
			(start -0.12065 0.3048)
			(end -0.67945 0.3048)
			(stroke
				(width 0.1)
				(type default)
			)
			(layer "F.Fab")
		)
		(fp_line
			(start 0.120396 0.3048)
			(end 0.120396 0.2794)
			(stroke
				(width 0.1)
				(type default)
			)
			(layer "F.Fab")
		)
		(fp_line
			(start 0.67945 0.3048)
			(end 0.120396 0.3048)
			(stroke
				(width 0.1)
				(type default)
			)
			(layer "F.Fab")
		)
		(fp_line
			(start -0.12065 0.2794)
			(end -0.12065 0.3048)
			(stroke
				(width 0.1)
				(type default)
			)
			(layer "F.Fab")
		)
		(fp_line
			(start 0.120396 0.2794)
			(end -0.12065 0.2794)
			(stroke
				(width 0.1)
				(type default)
			)
			(layer "F.Fab")
		)
		(fp_line
			(start -0.12065 -0.2794)
			(end 0.12065 -0.2794)
			(stroke
				(width 0.1)
				(type default)
			)
			(layer "F.Fab")
		)
		(fp_line
			(start 0.12065 -0.2794)
			(end 0.12065 -0.3048)
			(stroke
				(width 0.1)
				(type default)
			)
			(layer "F.Fab")
		)
		(fp_line
			(start 0.12065 -0.3048)
			(end 0.67945 -0.3048)
			(stroke
				(width 0.1)
				(type default)
			)
			(layer "F.Fab")
		)
		(fp_line
			(start 0.67945 -0.3048)
			(end 0.67945 0.3048)
			(stroke
				(width 0.1)
				(type default)
			)
			(layer "F.Fab")
		)
		(fp_line
			(start -0.67945 -0.305054)
			(end -0.12065 -0.305054)
			(stroke
				(width 0.1)
				(type default)
			)
			(layer "F.Fab")
		)
		(fp_line
			(start -0.12065 -0.305054)
			(end -0.12065 -0.2794)
			(stroke
				(width 0.1)
				(type default)
			)
			(layer "F.Fab")
		)
		(pad "1" smd circle
			(at -0.40005 0 270)
			(size 0 0)
			(layers "F.Cu" "F.Mask" "F.Paste")
			(net "P3V3_AUX")
		)
		(pad "2" smd circle
			(at 0.40005 0 270)
			(size 0 0)
			(layers "F.Cu" "F.Mask" "F.Paste")
			(net "GND")
		)
	)
	(footprint ""
		(layer "F.Cu")
		(at 120.396 -440.309 180)
		(property "Reference" "R3490"
			(at 0 0 180)
			(layer "F.SilkS")
			(hide yes)
			(effects
				(font
					(size 1.27 1.27)
				)
			)
		)
		(property "Value" ""
			(at 0 0 180)
			(layer "F.Fab")
			(effects
				(font
					(size 1.27 1.27)
				)
			)
		)
		(duplicate_pad_numbers_are_jumpers no)
		(fp_line
			(start 0.7874 0.4064)
			(end -0.7874 0.4064)
			(stroke
				(width 0.1524)
				(type default)
			)
			(layer "F.SilkS")
		)
		(fp_line
			(start 0.7874 -0.4064)
			(end 0.7874 0.4064)
			(stroke
				(width 0.1524)
				(type default)
			)
			(layer "F.SilkS")
		)
		(fp_line
			(start -0.7874 0.4064)
			(end -0.7874 -0.4064)
			(stroke
				(width 0.1524)
				(type default)
			)
			(layer "F.SilkS")
		)
		(fp_line
			(start -0.7874 -0.4064)
			(end 0.7874 -0.4064)
			(stroke
				(width 0.1524)
				(type default)
			)
			(layer "F.SilkS")
		)
		(fp_line
			(start 0.67945 0.3048)
			(end 0.120396 0.3048)
			(stroke
				(width 0.1)
				(type default)
			)
			(layer "F.Fab")
		)
		(fp_line
			(start 0.67945 -0.3048)
			(end 0.67945 0.3048)
			(stroke
				(width 0.1)
				(type default)
			)
			(layer "F.Fab")
		)
		(fp_line
			(start 0.12065 -0.2794)
			(end 0.12065 -0.3048)
			(stroke
				(width 0.1)
				(type default)
			)
			(layer "F.Fab")
		)
		(fp_line
			(start 0.12065 -0.3048)
			(end 0.67945 -0.3048)
			(stroke
				(width 0.1)
				(type default)
			)
			(layer "F.Fab")
		)
		(fp_line
			(start 0.120396 0.3048)
			(end 0.120396 0.2794)
			(stroke
				(width 0.1)
				(type default)
			)
			(layer "F.Fab")
		)
		(fp_line
			(start 0.120396 0.2794)
			(end -0.12065 0.2794)
			(stroke
				(width 0.1)
				(type default)
			)
			(layer "F.Fab")
		)
		(fp_line
			(start -0.12065 0.3048)
			(end -0.67945 0.3048)
			(stroke
				(width 0.1)
				(type default)
			)
			(layer "F.Fab")
		)
		(fp_line
			(start -0.12065 0.2794)
			(end -0.12065 0.3048)
			(stroke
				(width 0.1)
				(type default)
			)
			(layer "F.Fab")
		)
		(fp_line
			(start -0.12065 -0.2794)
			(end 0.12065 -0.2794)
			(stroke
				(width 0.1)
				(type default)
			)
			(layer "F.Fab")
		)
		(fp_line
			(start -0.12065 -0.305054)
			(end -0.12065 -0.2794)
			(stroke
				(width 0.1)
				(type default)
			)
			(layer "F.Fab")
		)
		(fp_line
			(start -0.67945 0.3048)
			(end -0.67945 -0.305054)
			(stroke
				(width 0.1)
				(type default)
			)
			(layer "F.Fab")
		)
		(fp_line
			(start -0.67945 -0.305054)
			(end -0.12065 -0.305054)
			(stroke
				(width 0.1)
				(type default)
			)
			(layer "F.Fab")
		)
		(pad "1" smd circle
			(at -0.40005 0 180)
			(size 0 0)
			(layers "F.Cu" "F.Mask" "F.Paste")
			(net "P3V3_AUX")
		)
		(pad "2" smd circle
			(at 0.40005 0 180)
			(size 0 0)
			(layers "F.Cu" "F.Mask" "F.Paste")
			(net "GPU_FPGA_EROT_RECOV_N")
		)
	)
	(footprint ""
		(layer "F.Cu")
		(at 426.1612 -421.64 90)
		(property "Reference" "R1484"
			(at 0 0 90)
			(layer "F.SilkS")
			(hide yes)
			(effects
				(font
					(size 1.27 1.27)
				)
			)
		)
		(property "Value" ""
			(at 0 0 90)
			(layer "F.Fab")
			(effects
				(font
					(size 1.27 1.27)
				)
			)
		)
		(duplicate_pad_numbers_are_jumpers no)
		(fp_line
			(start 0.32512 -0.175006)
			(end 0.32512 0.175006)
			(stroke
				(width 0.1)
				(type default)
			)
			(layer "F.Fab")
		)
		(fp_line
			(start -0.32512 -0.175006)
			(end 0.32512 -0.175006)
			(stroke
				(width 0.1)
				(type default)
			)
			(layer "F.Fab")
		)
		(fp_line
			(start 0.32512 0.175006)
			(end -0.32512 0.175006)
			(stroke
				(width 0.1)
				(type default)
			)
			(layer "F.Fab")
		)
		(fp_line
			(start -0.32512 0.175006)
			(end -0.32512 -0.175006)
			(stroke
				(width 0.1)
				(type default)
			)
			(layer "F.Fab")
		)
		(pad "1" smd rect
			(at -0.2667 0 90)
			(size 0.3048 0.381)
			(layers "F.Cu" "F.Mask" "F.Paste")
			(net "P1V8_CPU0_RT_1D")
		)
		(pad "2" smd rect
			(at 0.2667 0 270)
			(size 0.3048 0.381)
			(layers "F.Cu" "F.Mask" "F.Paste")
			(net "JTAG_TDO_RT_CPU0_P3")
		)
	)
	(footprint ""
		(layer "F.Cu")
		(at 47.18304 -434.057552 90)
		(property "Reference" "R3317"
			(at 0 0 90)
			(layer "F.SilkS")
			(hide yes)
			(effects
				(font
					(size 1.27 1.27)
				)
			)
		)
		(property "Value" ""
			(at 0 0 90)
			(layer "F.Fab")
			(effects
				(font
					(size 1.27 1.27)
				)
			)
		)
		(duplicate_pad_numbers_are_jumpers no)
		(fp_line
			(start 0.7874 -0.4064)
			(end 0.7874 0.4064)
			(stroke
				(width 0.1524)
				(type default)
			)
			(layer "F.SilkS")
		)
		(fp_line
			(start -0.7874 -0.4064)
			(end 0.7874 -0.4064)
			(stroke
				(width 0.1524)
				(type default)
			)
			(layer "F.SilkS")
		)
		(fp_line
			(start 0.7874 0.4064)
			(end -0.7874 0.4064)
			(stroke
				(width 0.1524)
				(type default)
			)
			(layer "F.SilkS")
		)
		(fp_line
			(start -0.7874 0.4064)
			(end -0.7874 -0.4064)
			(stroke
				(width 0.1524)
				(type default)
			)
			(layer "F.SilkS")
		)
		(fp_line
			(start -0.12065 -0.305054)
			(end -0.12065 -0.2794)
			(stroke
				(width 0.1)
				(type default)
			)
			(layer "F.Fab")
		)
		(fp_line
			(start -0.67945 -0.305054)
			(end -0.12065 -0.305054)
			(stroke
				(width 0.1)
				(type default)
			)
			(layer "F.Fab")
		)
		(fp_line
			(start 0.67945 -0.3048)
			(end 0.67945 0.3048)
			(stroke
				(width 0.1)
				(type default)
			)
			(layer "F.Fab")
		)
		(fp_line
			(start 0.12065 -0.3048)
			(end 0.67945 -0.3048)
			(stroke
				(width 0.1)
				(type default)
			)
			(layer "F.Fab")
		)
		(fp_line
			(start 0.12065 -0.2794)
			(end 0.12065 -0.3048)
			(stroke
				(width 0.1)
				(type default)
			)
			(layer "F.Fab")
		)
		(fp_line
			(start -0.12065 -0.2794)
			(end 0.12065 -0.2794)
			(stroke
				(width 0.1)
				(type default)
			)
			(layer "F.Fab")
		)
		(fp_line
			(start 0.120396 0.2794)
			(end -0.12065 0.2794)
			(stroke
				(width 0.1)
				(type default)
			)
			(layer "F.Fab")
		)
		(fp_line
			(start -0.12065 0.2794)
			(end -0.12065 0.3048)
			(stroke
				(width 0.1)
				(type default)
			)
			(layer "F.Fab")
		)
		(fp_line
			(start 0.67945 0.3048)
			(end 0.120396 0.3048)
			(stroke
				(width 0.1)
				(type default)
			)
			(layer "F.Fab")
		)
		(fp_line
			(start 0.120396 0.3048)
			(end 0.120396 0.2794)
			(stroke
				(width 0.1)
				(type default)
			)
			(layer "F.Fab")
		)
		(fp_line
			(start -0.12065 0.3048)
			(end -0.67945 0.3048)
			(stroke
				(width 0.1)
				(type default)
			)
			(layer "F.Fab")
		)
		(fp_line
			(start -0.67945 0.3048)
			(end -0.67945 -0.305054)
			(stroke
				(width 0.1)
				(type default)
			)
			(layer "F.Fab")
		)
		(pad "1" smd circle
			(at -0.40005 0 90)
			(size 0 0)
			(layers "F.Cu" "F.Mask" "F.Paste")
			(net "P3V3_AUX")
		)
		(pad "2" smd circle
			(at 0.40005 0 90)
			(size 0 0)
			(layers "F.Cu" "F.Mask" "F.Paste")
			(net "GPU_FPGA_RST_R1_BUF_N")
		)
	)
	(footprint ""
		(layer "F.Cu")
		(at 325.9074 -363.22)
		(property "Reference" "R352"
			(at 0 0 0)
			(layer "F.SilkS")
			(hide yes)
			(effects
				(font
					(size 1.27 1.27)
				)
			)
		)
		(property "Value" ""
			(at 0 0 0)
			(layer "F.Fab")
			(effects
				(font
					(size 1.27 1.27)
				)
			)
		)
		(duplicate_pad_numbers_are_jumpers no)
		(fp_line
			(start -0.7874 -0.4064)
			(end 0.7874 -0.4064)
			(stroke
				(width 0.1524)
				(type default)
			)
			(layer "F.SilkS")
		)
		(fp_line
			(start -0.7874 0.4064)
			(end -0.7874 -0.4064)
			(stroke
				(width 0.1524)
				(type default)
			)
			(layer "F.SilkS")
		)
		(fp_line
			(start 0.7874 -0.4064)
			(end 0.7874 0.4064)
			(stroke
				(width 0.1524)
				(type default)
			)
			(layer "F.SilkS")
		)
		(fp_line
			(start 0.7874 0.4064)
			(end -0.7874 0.4064)
			(stroke
				(width 0.1524)
				(type default)
			)
			(layer "F.SilkS")
		)
		(fp_line
			(start -0.67945 -0.305054)
			(end -0.12065 -0.305054)
			(stroke
				(width 0.1)
				(type default)
			)
			(layer "F.Fab")
		)
		(fp_line
			(start -0.67945 0.3048)
			(end -0.67945 -0.305054)
			(stroke
				(width 0.1)
				(type default)
			)
			(layer "F.Fab")
		)
		(fp_line
			(start -0.12065 -0.305054)
			(end -0.12065 -0.2794)
			(stroke
				(width 0.1)
				(type default)
			)
			(layer "F.Fab")
		)
		(fp_line
			(start -0.12065 -0.2794)
			(end 0.12065 -0.2794)
			(stroke
				(width 0.1)
				(type default)
			)
			(layer "F.Fab")
		)
		(fp_line
			(start -0.12065 0.2794)
			(end -0.12065 0.3048)
			(stroke
				(width 0.1)
				(type default)
			)
			(layer "F.Fab")
		)
		(fp_line
			(start -0.12065 0.3048)
			(end -0.67945 0.3048)
			(stroke
				(width 0.1)
				(type default)
			)
			(layer "F.Fab")
		)
		(fp_line
			(start 0.120396 0.2794)
			(end -0.12065 0.2794)
			(stroke
				(width 0.1)
				(type default)
			)
			(layer "F.Fab")
		)
		(fp_line
			(start 0.120396 0.3048)
			(end 0.120396 0.2794)
			(stroke
				(width 0.1)
				(type default)
			)
			(layer "F.Fab")
		)
		(fp_line
			(start 0.12065 -0.3048)
			(end 0.67945 -0.3048)
			(stroke
				(width 0.1)
				(type default)
			)
			(layer "F.Fab")
		)
		(fp_line
			(start 0.12065 -0.2794)
			(end 0.12065 -0.3048)
			(stroke
				(width 0.1)
				(type default)
			)
			(layer "F.Fab")
		)
		(fp_line
			(start 0.67945 -0.3048)
			(end 0.67945 0.3048)
			(stroke
				(width 0.1)
				(type default)
			)
			(layer "F.Fab")
		)
		(fp_line
			(start 0.67945 0.3048)
			(end 0.120396 0.3048)
			(stroke
				(width 0.1)
				(type default)
			)
			(layer "F.Fab")
		)
		(pad "1" smd circle
			(at -0.40005 0)
			(size 0 0)
			(layers "F.Cu" "F.Mask" "F.Paste")
			(net "SMB_SCM_2_R5_SDA")
		)
		(pad "2" smd circle
			(at 0.40005 0)
			(size 0 0)
			(layers "F.Cu" "F.Mask" "F.Paste")
			(net "SMB_SCM_2_R6_SDA")
		)
	)
	(footprint ""
		(layer "F.Cu")
		(at 111.13897 -175.506634 -90)
		(property "Reference" "PC287"
			(at 0 0 270)
			(layer "F.SilkS")
			(hide yes)
			(effects
				(font
					(size 1.27 1.27)
				)
			)
		)
		(property "Value" ""
			(at 0 0 270)
			(layer "F.Fab")
			(effects
				(font
					(size 1.27 1.27)
				)
			)
		)
		(duplicate_pad_numbers_are_jumpers no)
		(fp_line
			(start -0.7874 0.4064)
			(end -0.7874 -0.4064)
			(stroke
				(width 0.1524)
				(type default)
			)
			(layer "F.SilkS")
		)
		(fp_line
			(start -0.362966 0.4064)
			(end -0.7874 0.4064)
			(stroke
				(width 0.1524)
				(type default)
			)
			(layer "F.SilkS")
		)
		(fp_line
			(start 0.7874 0.4064)
			(end 0.373634 0.4064)
			(stroke
				(width 0.1524)
				(type default)
			)
			(layer "F.SilkS")
		)
		(fp_line
			(start -0.7874 -0.4064)
			(end 0.7874 -0.4064)
			(stroke
				(width 0.1524)
				(type default)
			)
			(layer "F.SilkS")
		)
		(fp_line
			(start 0.7874 -0.4064)
			(end 0.7874 0.4064)
			(stroke
				(width 0.1524)
				(type default)
			)
			(layer "F.SilkS")
		)
		(fp_line
			(start -0.67945 0.3048)
			(end -0.67945 -0.305054)
			(stroke
				(width 0.1)
				(type default)
			)
			(layer "F.Fab")
		)
		(fp_line
			(start -0.12065 0.3048)
			(end -0.67945 0.3048)
			(stroke
				(width 0.1)
				(type default)
			)
			(layer "F.Fab")
		)
		(fp_line
			(start 0.120396 0.3048)
			(end 0.120396 0.2794)
			(stroke
				(width 0.1)
				(type default)
			)
			(layer "F.Fab")
		)
		(fp_line
			(start 0.67945 0.3048)
			(end 0.120396 0.3048)
			(stroke
				(width 0.1)
				(type default)
			)
			(layer "F.Fab")
		)
		(fp_line
			(start -0.12065 0.2794)
			(end -0.12065 0.3048)
			(stroke
				(width 0.1)
				(type default)
			)
			(layer "F.Fab")
		)
		(fp_line
			(start 0.120396 0.2794)
			(end -0.12065 0.2794)
			(stroke
				(width 0.1)
				(type default)
			)
			(layer "F.Fab")
		)
		(fp_line
			(start -0.12065 -0.2794)
			(end 0.12065 -0.2794)
			(stroke
				(width 0.1)
				(type default)
			)
			(layer "F.Fab")
		)
		(fp_line
			(start 0.12065 -0.2794)
			(end 0.12065 -0.3048)
			(stroke
				(width 0.1)
				(type default)
			)
			(layer "F.Fab")
		)
		(fp_line
			(start 0.12065 -0.3048)
			(end 0.67945 -0.3048)
			(stroke
				(width 0.1)
				(type default)
			)
			(layer "F.Fab")
		)
		(fp_line
			(start 0.67945 -0.3048)
			(end 0.67945 0.3048)
			(stroke
				(width 0.1)
				(type default)
			)
			(layer "F.Fab")
		)
		(fp_line
			(start -0.67945 -0.305054)
			(end -0.12065 -0.305054)
			(stroke
				(width 0.1)
				(type default)
			)
			(layer "F.Fab")
		)
		(fp_line
			(start -0.12065 -0.305054)
			(end -0.12065 -0.2794)
			(stroke
				(width 0.1)
				(type default)
			)
			(layer "F.Fab")
		)
		(pad "1" smd circle
			(at -0.40005 0 270)
			(size 0 0)
			(layers "F.Cu" "F.Mask" "F.Paste")
			(net "PVDDCR_CPU0_P1_VCC4")
		)
		(pad "2" smd circle
			(at 0.40005 0 270)
			(size 0 0)
			(layers "F.Cu" "F.Mask" "F.Paste")
			(net "GND")
		)
	)
	(footprint ""
		(layer "F.Cu")
		(at 88.344502 -375.49963 -90)
		(property "Reference" "C726"
			(at 0 0 270)
			(layer "F.SilkS")
			(hide yes)
			(effects
				(font
					(size 1.27 1.27)
				)
			)
		)
		(property "Value" ""
			(at 0 0 270)
			(layer "F.Fab")
			(effects
				(font
					(size 1.27 1.27)
				)
			)
		)
		(duplicate_pad_numbers_are_jumpers no)
		(fp_line
			(start -0.299974 0.150114)
			(end -0.299974 -0.150114)
			(stroke
				(width 0.1)
				(type default)
			)
			(layer "F.Fab")
		)
		(fp_line
			(start 0.299974 0.150114)
			(end -0.299974 0.150114)
			(stroke
				(width 0.1)
				(type default)
			)
			(layer "F.Fab")
		)
		(fp_line
			(start -0.299974 -0.150114)
			(end 0.299974 -0.150114)
			(stroke
				(width 0.1)
				(type default)
			)
			(layer "F.Fab")
		)
		(fp_line
			(start 0.299974 -0.150114)
			(end 0.299974 0.150114)
			(stroke
				(width 0.1)
				(type default)
			)
			(layer "F.Fab")
		)
		(pad "1" smd rect
			(at -0.2667 0 270)
			(size 0.3048 0.381)
			(layers "F.Cu" "F.Mask" "F.Paste")
			(net "P5E_CPU1_P1_TX_C_DN<7>")
		)
		(pad "2" smd rect
			(at 0.2667 0 270)
			(size 0.3048 0.381)
			(layers "F.Cu" "F.Mask" "F.Paste")
			(net "P5E_CPU1_P1_TX_DN<7>")
		)
	)
	(footprint ""
		(layer "F.Cu")
		(at 150.47722 -65.387474)
		(property "Reference" "Q62"
			(at -1.4224 -2.327148 0)
			(unlocked yes)
			(layer "F.SilkS")
			(effects
				(font
					(size 0.7874 0.5842)
					(thickness 0.1524)
				)
			)
		)
		(property "Value" ""
			(at 0 0 0)
			(layer "F.Fab")
			(effects
				(font
					(size 1.27 1.27)
				)
			)
		)
		(duplicate_pad_numbers_are_jumpers no)
		(fp_line
			(start -1.949958 -1.610106)
			(end 1.949958 -1.610106)
			(stroke
				(width 0.1524)
				(type default)
			)
			(layer "F.SilkS")
		)
		(fp_line
			(start -1.949958 1.610106)
			(end -1.949958 -1.610106)
			(stroke
				(width 0.1524)
				(type default)
			)
			(layer "F.SilkS")
		)
		(fp_line
			(start 1.949958 -1.560068)
			(end 1.949958 1.610106)
			(stroke
				(width 0.1524)
				(type default)
			)
			(layer "F.SilkS")
		)
		(fp_line
			(start 1.949958 1.610106)
			(end -1.949958 1.610106)
			(stroke
				(width 0.1524)
				(type default)
			)
			(layer "F.SilkS")
		)
		(fp_line
			(start -0.750062 -1.560068)
			(end 0.750062 -1.560068)
			(stroke
				(width 0.1)
				(type default)
			)
			(layer "F.Fab")
		)
		(fp_line
			(start -0.750062 1.560068)
			(end -0.750062 -1.560068)
			(stroke
				(width 0.1)
				(type default)
			)
			(layer "F.Fab")
		)
		(fp_line
			(start 0.750062 -1.560068)
			(end 0.750062 1.560068)
			(stroke
				(width 0.1)
				(type default)
			)
			(layer "F.Fab")
		)
		(fp_line
			(start 0.750062 1.560068)
			(end -0.750062 1.560068)
			(stroke
				(width 0.1)
				(type default)
			)
			(layer "F.Fab")
		)
		(pad "D" smd rect
			(at 1.100074 0 270)
			(size 1.016 1.4224)
			(layers "F.Cu" "F.Mask" "F.Paste")
			(net "JTAG_BMC_OE_N")
		)
		(pad "G" smd rect
			(at -1.100074 -0.94996 270)
			(size 1.016 1.4224)
			(layers "F.Cu" "F.Mask" "F.Paste")
			(net "JTAG_BMC_OE")
		)
		(pad "S" smd rect
			(at -1.100074 0.94996 270)
			(size 1.016 1.4224)
			(layers "F.Cu" "F.Mask" "F.Paste")
			(net "GND")
		)
	)
	(footprint ""
		(layer "F.Cu")
		(at 306.002182 -351.573846 90)
		(property "Reference" "PC113_4"
			(at 0 0 90)
			(layer "F.SilkS")
			(hide yes)
			(effects
				(font
					(size 1.27 1.27)
				)
			)
		)
		(property "Value" ""
			(at 0 0 90)
			(layer "F.Fab")
			(effects
				(font
					(size 1.27 1.27)
				)
			)
		)
		(duplicate_pad_numbers_are_jumpers no)
		(fp_line
			(start 0.7874 -0.4064)
			(end 0.7874 0.4064)
			(stroke
				(width 0.1524)
				(type default)
			)
			(layer "F.SilkS")
		)
		(fp_line
			(start -0.7874 -0.4064)
			(end 0.7874 -0.4064)
			(stroke
				(width 0.1524)
				(type default)
			)
			(layer "F.SilkS")
		)
		(fp_line
			(start 0.7874 0.4064)
			(end -0.7874 0.4064)
			(stroke
				(width 0.1524)
				(type default)
			)
			(layer "F.SilkS")
		)
		(fp_line
			(start -0.7874 0.4064)
			(end -0.7874 -0.4064)
			(stroke
				(width 0.1524)
				(type default)
			)
			(layer "F.SilkS")
		)
		(fp_line
			(start -0.12065 -0.305054)
			(end -0.12065 -0.2794)
			(stroke
				(width 0.1)
				(type default)
			)
			(layer "F.Fab")
		)
		(fp_line
			(start -0.67945 -0.305054)
			(end -0.12065 -0.305054)
			(stroke
				(width 0.1)
				(type default)
			)
			(layer "F.Fab")
		)
		(fp_line
			(start 0.67945 -0.3048)
			(end 0.67945 0.3048)
			(stroke
				(width 0.1)
				(type default)
			)
			(layer "F.Fab")
		)
		(fp_line
			(start 0.12065 -0.3048)
			(end 0.67945 -0.3048)
			(stroke
				(width 0.1)
				(type default)
			)
			(layer "F.Fab")
		)
		(fp_line
			(start 0.12065 -0.2794)
			(end 0.12065 -0.3048)
			(stroke
				(width 0.1)
				(type default)
			)
			(layer "F.Fab")
		)
		(fp_line
			(start -0.12065 -0.2794)
			(end 0.12065 -0.2794)
			(stroke
				(width 0.1)
				(type default)
			)
			(layer "F.Fab")
		)
		(fp_line
			(start 0.120396 0.2794)
			(end -0.12065 0.2794)
			(stroke
				(width 0.1)
				(type default)
			)
			(layer "F.Fab")
		)
		(fp_line
			(start -0.12065 0.2794)
			(end -0.12065 0.3048)
			(stroke
				(width 0.1)
				(type default)
			)
			(layer "F.Fab")
		)
		(fp_line
			(start 0.67945 0.3048)
			(end 0.120396 0.3048)
			(stroke
				(width 0.1)
				(type default)
			)
			(layer "F.Fab")
		)
		(fp_line
			(start 0.120396 0.3048)
			(end 0.120396 0.2794)
			(stroke
				(width 0.1)
				(type default)
			)
			(layer "F.Fab")
		)
		(fp_line
			(start -0.12065 0.3048)
			(end -0.67945 0.3048)
			(stroke
				(width 0.1)
				(type default)
			)
			(layer "F.Fab")
		)
		(fp_line
			(start -0.67945 0.3048)
			(end -0.67945 -0.305054)
			(stroke
				(width 0.1)
				(type default)
			)
			(layer "F.Fab")
		)
		(pad "1" smd circle
			(at -0.40005 0 90)
			(size 0 0)
			(layers "F.Cu" "F.Mask" "F.Paste")
			(net "PVDDCR_CPU1_P0_VCCS")
		)
		(pad "2" smd circle
			(at 0.40005 0 90)
			(size 0 0)
			(layers "F.Cu" "F.Mask" "F.Paste")
			(net "GND")
		)
	)
	(footprint ""
		(layer "F.Cu")
		(at 258.25958 -58.927492 90)
		(property "Reference" "R3975"
			(at 0 0 90)
			(layer "F.SilkS")
			(hide yes)
			(effects
				(font
					(size 1.27 1.27)
				)
			)
		)
		(property "Value" ""
			(at 0 0 90)
			(layer "F.Fab")
			(effects
				(font
					(size 1.27 1.27)
				)
			)
		)
		(duplicate_pad_numbers_are_jumpers no)
		(fp_line
			(start 0.7874 -0.4064)
			(end 0.7874 0.4064)
			(stroke
				(width 0.1524)
				(type default)
			)
			(layer "F.SilkS")
		)
		(fp_line
			(start -0.7874 -0.4064)
			(end 0.7874 -0.4064)
			(stroke
				(width 0.1524)
				(type default)
			)
			(layer "F.SilkS")
		)
		(fp_line
			(start 0.7874 0.4064)
			(end -0.7874 0.4064)
			(stroke
				(width 0.1524)
				(type default)
			)
			(layer "F.SilkS")
		)
		(fp_line
			(start -0.7874 0.4064)
			(end -0.7874 -0.4064)
			(stroke
				(width 0.1524)
				(type default)
			)
			(layer "F.SilkS")
		)
		(fp_line
			(start -0.12065 -0.305054)
			(end -0.12065 -0.2794)
			(stroke
				(width 0.1)
				(type default)
			)
			(layer "F.Fab")
		)
		(fp_line
			(start -0.67945 -0.305054)
			(end -0.12065 -0.305054)
			(stroke
				(width 0.1)
				(type default)
			)
			(layer "F.Fab")
		)
		(fp_line
			(start 0.67945 -0.3048)
			(end 0.67945 0.3048)
			(stroke
				(width 0.1)
				(type default)
			)
			(layer "F.Fab")
		)
		(fp_line
			(start 0.12065 -0.3048)
			(end 0.67945 -0.3048)
			(stroke
				(width 0.1)
				(type default)
			)
			(layer "F.Fab")
		)
		(fp_line
			(start 0.12065 -0.2794)
			(end 0.12065 -0.3048)
			(stroke
				(width 0.1)
				(type default)
			)
			(layer "F.Fab")
		)
		(fp_line
			(start -0.12065 -0.2794)
			(end 0.12065 -0.2794)
			(stroke
				(width 0.1)
				(type default)
			)
			(layer "F.Fab")
		)
		(fp_line
			(start 0.120396 0.2794)
			(end -0.12065 0.2794)
			(stroke
				(width 0.1)
				(type default)
			)
			(layer "F.Fab")
		)
		(fp_line
			(start -0.12065 0.2794)
			(end -0.12065 0.3048)
			(stroke
				(width 0.1)
				(type default)
			)
			(layer "F.Fab")
		)
		(fp_line
			(start 0.67945 0.3048)
			(end 0.120396 0.3048)
			(stroke
				(width 0.1)
				(type default)
			)
			(layer "F.Fab")
		)
		(fp_line
			(start 0.120396 0.3048)
			(end 0.120396 0.2794)
			(stroke
				(width 0.1)
				(type default)
			)
			(layer "F.Fab")
		)
		(fp_line
			(start -0.12065 0.3048)
			(end -0.67945 0.3048)
			(stroke
				(width 0.1)
				(type default)
			)
			(layer "F.Fab")
		)
		(fp_line
			(start -0.67945 0.3048)
			(end -0.67945 -0.305054)
			(stroke
				(width 0.1)
				(type default)
			)
			(layer "F.Fab")
		)
		(pad "1" smd rect
			(at -0.40005 0 270)
			(size 0.4572 0.508)
			(layers "F.Cu" "F.Mask" "F.Paste")
			(net "P12V_E1S_SENSE_0")
		)
		(pad "2" smd rect
			(at 0.40005 0 270)
			(size 0.4572 0.508)
			(layers "F.Cu" "F.Mask" "F.Paste")
			(net "P12V_E1S_0_ISENSE_MAM_TIC")
		)
	)
	(footprint ""
		(layer "F.Cu")
		(at 171.598844 -419.800786 180)
		(property "Reference" "C7504"
			(at 0 0 180)
			(layer "F.SilkS")
			(hide yes)
			(effects
				(font
					(size 1.27 1.27)
				)
			)
		)
		(property "Value" ""
			(at 0 0 180)
			(layer "F.Fab")
			(effects
				(font
					(size 1.27 1.27)
				)
			)
		)
		(duplicate_pad_numbers_are_jumpers no)
		(fp_line
			(start 0.299974 0.150114)
			(end -0.299974 0.150114)
			(stroke
				(width 0.1)
				(type default)
			)
			(layer "F.Fab")
		)
		(fp_line
			(start 0.299974 -0.150114)
			(end 0.299974 0.150114)
			(stroke
				(width 0.1)
				(type default)
			)
			(layer "F.Fab")
		)
		(fp_line
			(start -0.299974 0.150114)
			(end -0.299974 -0.150114)
			(stroke
				(width 0.1)
				(type default)
			)
			(layer "F.Fab")
		)
		(fp_line
			(start -0.299974 -0.150114)
			(end 0.299974 -0.150114)
			(stroke
				(width 0.1)
				(type default)
			)
			(layer "F.Fab")
		)
		(pad "1" smd rect
			(at -0.2667 0 180)
			(size 0.3048 0.381)
			(layers "F.Cu" "F.Mask" "F.Paste")
			(net "P1V8_CPU1_RT_1D")
		)
		(pad "2" smd rect
			(at 0.2667 0 180)
			(size 0.3048 0.381)
			(layers "F.Cu" "F.Mask" "F.Paste")
			(net "GND")
		)
	)
	(footprint ""
		(layer "F.Cu")
		(at 352.373438 -169.413174 90)
		(property "Reference" "PC569_5"
			(at 0 0 90)
			(layer "F.SilkS")
			(hide yes)
			(effects
				(font
					(size 1.27 1.27)
				)
			)
		)
		(property "Value" ""
			(at 0 0 90)
			(layer "F.Fab")
			(effects
				(font
					(size 1.27 1.27)
				)
			)
		)
		(duplicate_pad_numbers_are_jumpers no)
		(fp_line
			(start 0.7874 -0.4064)
			(end 0.7874 0.4064)
			(stroke
				(width 0.1524)
				(type default)
			)
			(layer "F.SilkS")
		)
		(fp_line
			(start -0.7874 -0.4064)
			(end 0.7874 -0.4064)
			(stroke
				(width 0.1524)
				(type default)
			)
			(layer "F.SilkS")
		)
		(fp_line
			(start 0.7874 0.4064)
			(end -0.7874 0.4064)
			(stroke
				(width 0.1524)
				(type default)
			)
			(layer "F.SilkS")
		)
		(fp_line
			(start -0.7874 0.4064)
			(end -0.7874 -0.4064)
			(stroke
				(width 0.1524)
				(type default)
			)
			(layer "F.SilkS")
		)
		(fp_line
			(start -0.12065 -0.305054)
			(end -0.12065 -0.2794)
			(stroke
				(width 0.1)
				(type default)
			)
			(layer "F.Fab")
		)
		(fp_line
			(start -0.67945 -0.305054)
			(end -0.12065 -0.305054)
			(stroke
				(width 0.1)
				(type default)
			)
			(layer "F.Fab")
		)
		(fp_line
			(start 0.67945 -0.3048)
			(end 0.67945 0.3048)
			(stroke
				(width 0.1)
				(type default)
			)
			(layer "F.Fab")
		)
		(fp_line
			(start 0.12065 -0.3048)
			(end 0.67945 -0.3048)
			(stroke
				(width 0.1)
				(type default)
			)
			(layer "F.Fab")
		)
		(fp_line
			(start 0.12065 -0.2794)
			(end 0.12065 -0.3048)
			(stroke
				(width 0.1)
				(type default)
			)
			(layer "F.Fab")
		)
		(fp_line
			(start -0.12065 -0.2794)
			(end 0.12065 -0.2794)
			(stroke
				(width 0.1)
				(type default)
			)
			(layer "F.Fab")
		)
		(fp_line
			(start 0.120396 0.2794)
			(end -0.12065 0.2794)
			(stroke
				(width 0.1)
				(type default)
			)
			(layer "F.Fab")
		)
		(fp_line
			(start -0.12065 0.2794)
			(end -0.12065 0.3048)
			(stroke
				(width 0.1)
				(type default)
			)
			(layer "F.Fab")
		)
		(fp_line
			(start 0.67945 0.3048)
			(end 0.120396 0.3048)
			(stroke
				(width 0.1)
				(type default)
			)
			(layer "F.Fab")
		)
		(fp_line
			(start 0.120396 0.3048)
			(end 0.120396 0.2794)
			(stroke
				(width 0.1)
				(type default)
			)
			(layer "F.Fab")
		)
		(fp_line
			(start -0.12065 0.3048)
			(end -0.67945 0.3048)
			(stroke
				(width 0.1)
				(type default)
			)
			(layer "F.Fab")
		)
		(fp_line
			(start -0.67945 0.3048)
			(end -0.67945 -0.305054)
			(stroke
				(width 0.1)
				(type default)
			)
			(layer "F.Fab")
		)
		(pad "1" smd circle
			(at -0.40005 0 90)
			(size 0 0)
			(layers "F.Cu" "F.Mask" "F.Paste")
			(net "SW_P12V_AUX_PVDDCR_CPU0_P0_FLT")
		)
		(pad "2" smd circle
			(at 0.40005 0 90)
			(size 0 0)
			(layers "F.Cu" "F.Mask" "F.Paste")
			(net "GND")
		)
	)
	(footprint ""
		(layer "F.Cu")
		(at 439.821066 -388.8613)
		(property "Reference" "PR6530"
			(at 0 0 0)
			(layer "F.SilkS")
			(hide yes)
			(effects
				(font
					(size 1.27 1.27)
				)
			)
		)
		(property "Value" ""
			(at 0 0 0)
			(layer "F.Fab")
			(effects
				(font
					(size 1.27 1.27)
				)
			)
		)
		(duplicate_pad_numbers_are_jumpers no)
		(fp_line
			(start -0.7874 -0.4064)
			(end 0.7874 -0.4064)
			(stroke
				(width 0.1524)
				(type default)
			)
			(layer "F.SilkS")
		)
		(fp_line
			(start -0.7874 0.4064)
			(end -0.7874 -0.4064)
			(stroke
				(width 0.1524)
				(type default)
			)
			(layer "F.SilkS")
		)
		(fp_line
			(start 0.7874 -0.4064)
			(end 0.7874 0.4064)
			(stroke
				(width 0.1524)
				(type default)
			)
			(layer "F.SilkS")
		)
		(fp_line
			(start 0.7874 0.4064)
			(end -0.7874 0.4064)
			(stroke
				(width 0.1524)
				(type default)
			)
			(layer "F.SilkS")
		)
		(fp_line
			(start -0.67945 -0.305054)
			(end -0.12065 -0.305054)
			(stroke
				(width 0.1)
				(type default)
			)
			(layer "F.Fab")
		)
		(fp_line
			(start -0.67945 0.3048)
			(end -0.67945 -0.305054)
			(stroke
				(width 0.1)
				(type default)
			)
			(layer "F.Fab")
		)
		(fp_line
			(start -0.12065 -0.305054)
			(end -0.12065 -0.2794)
			(stroke
				(width 0.1)
				(type default)
			)
			(layer "F.Fab")
		)
		(fp_line
			(start -0.12065 -0.2794)
			(end 0.12065 -0.2794)
			(stroke
				(width 0.1)
				(type default)
			)
			(layer "F.Fab")
		)
		(fp_line
			(start -0.12065 0.2794)
			(end -0.12065 0.3048)
			(stroke
				(width 0.1)
				(type default)
			)
			(layer "F.Fab")
		)
		(fp_line
			(start -0.12065 0.3048)
			(end -0.67945 0.3048)
			(stroke
				(width 0.1)
				(type default)
			)
			(layer "F.Fab")
		)
		(fp_line
			(start 0.120396 0.2794)
			(end -0.12065 0.2794)
			(stroke
				(width 0.1)
				(type default)
			)
			(layer "F.Fab")
		)
		(fp_line
			(start 0.120396 0.3048)
			(end 0.120396 0.2794)
			(stroke
				(width 0.1)
				(type default)
			)
			(layer "F.Fab")
		)
		(fp_line
			(start 0.12065 -0.3048)
			(end 0.67945 -0.3048)
			(stroke
				(width 0.1)
				(type default)
			)
			(layer "F.Fab")
		)
		(fp_line
			(start 0.12065 -0.2794)
			(end 0.12065 -0.3048)
			(stroke
				(width 0.1)
				(type default)
			)
			(layer "F.Fab")
		)
		(fp_line
			(start 0.67945 -0.3048)
			(end 0.67945 0.3048)
			(stroke
				(width 0.1)
				(type default)
			)
			(layer "F.Fab")
		)
		(fp_line
			(start 0.67945 0.3048)
			(end 0.120396 0.3048)
			(stroke
				(width 0.1)
				(type default)
			)
			(layer "F.Fab")
		)
		(pad "1" smd circle
			(at -0.40005 0)
			(size 0 0)
			(layers "F.Cu" "F.Mask" "F.Paste")
			(net "P0V9_RETIMER_CPU0_SENSE_SH_P")
		)
		(pad "2" smd circle
			(at 0.40005 0)
			(size 0 0)
			(layers "F.Cu" "F.Mask" "F.Paste")
			(net "P0V9_CPU0_RT_2D")
		)
	)
	(footprint ""
		(layer "F.Cu")
		(at 396.125192 -330.862686 180)
		(property "Reference" "R464"
			(at 0 0 180)
			(layer "F.SilkS")
			(hide yes)
			(effects
				(font
					(size 1.27 1.27)
				)
			)
		)
		(property "Value" ""
			(at 0 0 180)
			(layer "F.Fab")
			(effects
				(font
					(size 1.27 1.27)
				)
			)
		)
		(duplicate_pad_numbers_are_jumpers no)
		(fp_line
			(start 0.7874 0.4064)
			(end -0.7874 0.4064)
			(stroke
				(width 0.1524)
				(type default)
			)
			(layer "F.SilkS")
		)
		(fp_line
			(start 0.7874 -0.4064)
			(end 0.7874 0.4064)
			(stroke
				(width 0.1524)
				(type default)
			)
			(layer "F.SilkS")
		)
		(fp_line
			(start -0.7874 0.4064)
			(end -0.7874 -0.4064)
			(stroke
				(width 0.1524)
				(type default)
			)
			(layer "F.SilkS")
		)
		(fp_line
			(start -0.7874 -0.4064)
			(end 0.7874 -0.4064)
			(stroke
				(width 0.1524)
				(type default)
			)
			(layer "F.SilkS")
		)
		(fp_line
			(start 0.67945 0.3048)
			(end 0.120396 0.3048)
			(stroke
				(width 0.1)
				(type default)
			)
			(layer "F.Fab")
		)
		(fp_line
			(start 0.67945 -0.3048)
			(end 0.67945 0.3048)
			(stroke
				(width 0.1)
				(type default)
			)
			(layer "F.Fab")
		)
		(fp_line
			(start 0.12065 -0.2794)
			(end 0.12065 -0.3048)
			(stroke
				(width 0.1)
				(type default)
			)
			(layer "F.Fab")
		)
		(fp_line
			(start 0.12065 -0.3048)
			(end 0.67945 -0.3048)
			(stroke
				(width 0.1)
				(type default)
			)
			(layer "F.Fab")
		)
		(fp_line
			(start 0.120396 0.3048)
			(end 0.120396 0.2794)
			(stroke
				(width 0.1)
				(type default)
			)
			(layer "F.Fab")
		)
		(fp_line
			(start 0.120396 0.2794)
			(end -0.12065 0.2794)
			(stroke
				(width 0.1)
				(type default)
			)
			(layer "F.Fab")
		)
		(fp_line
			(start -0.12065 0.3048)
			(end -0.67945 0.3048)
			(stroke
				(width 0.1)
				(type default)
			)
			(layer "F.Fab")
		)
		(fp_line
			(start -0.12065 0.2794)
			(end -0.12065 0.3048)
			(stroke
				(width 0.1)
				(type default)
			)
			(layer "F.Fab")
		)
		(fp_line
			(start -0.12065 -0.2794)
			(end 0.12065 -0.2794)
			(stroke
				(width 0.1)
				(type default)
			)
			(layer "F.Fab")
		)
		(fp_line
			(start -0.12065 -0.305054)
			(end -0.12065 -0.2794)
			(stroke
				(width 0.1)
				(type default)
			)
			(layer "F.Fab")
		)
		(fp_line
			(start -0.67945 0.3048)
			(end -0.67945 -0.305054)
			(stroke
				(width 0.1)
				(type default)
			)
			(layer "F.Fab")
		)
		(fp_line
			(start -0.67945 -0.305054)
			(end -0.12065 -0.305054)
			(stroke
				(width 0.1)
				(type default)
			)
			(layer "F.Fab")
		)
		(pad "1" smd circle
			(at -0.40005 0 180)
			(size 0 0)
			(layers "F.Cu" "F.Mask" "F.Paste")
			(net "SPI_CPU0_D0")
		)
		(pad "2" smd circle
			(at 0.40005 0 180)
			(size 0 0)
			(layers "F.Cu" "F.Mask" "F.Paste")
			(net "SPI_CPU0_R_D0")
		)
	)
	(footprint ""
		(layer "F.Cu")
		(at 205.181708 -117.748812)
		(property "Reference" "R3480"
			(at 0 0 0)
			(layer "F.SilkS")
			(hide yes)
			(effects
				(font
					(size 1.27 1.27)
				)
			)
		)
		(property "Value" ""
			(at 0 0 0)
			(layer "F.Fab")
			(effects
				(font
					(size 1.27 1.27)
				)
			)
		)
		(duplicate_pad_numbers_are_jumpers no)
		(fp_line
			(start -0.7874 -0.4064)
			(end 0.7874 -0.4064)
			(stroke
				(width 0.1524)
				(type default)
			)
			(layer "F.SilkS")
		)
		(fp_line
			(start -0.7874 0.4064)
			(end -0.7874 -0.4064)
			(stroke
				(width 0.1524)
				(type default)
			)
			(layer "F.SilkS")
		)
		(fp_line
			(start 0.7874 -0.4064)
			(end 0.7874 0.4064)
			(stroke
				(width 0.1524)
				(type default)
			)
			(layer "F.SilkS")
		)
		(fp_line
			(start 0.7874 0.4064)
			(end -0.7874 0.4064)
			(stroke
				(width 0.1524)
				(type default)
			)
			(layer "F.SilkS")
		)
		(fp_line
			(start -0.67945 -0.305054)
			(end -0.12065 -0.305054)
			(stroke
				(width 0.1)
				(type default)
			)
			(layer "F.Fab")
		)
		(fp_line
			(start -0.67945 0.3048)
			(end -0.67945 -0.305054)
			(stroke
				(width 0.1)
				(type default)
			)
			(layer "F.Fab")
		)
		(fp_line
			(start -0.12065 -0.305054)
			(end -0.12065 -0.2794)
			(stroke
				(width 0.1)
				(type default)
			)
			(layer "F.Fab")
		)
		(fp_line
			(start -0.12065 -0.2794)
			(end 0.12065 -0.2794)
			(stroke
				(width 0.1)
				(type default)
			)
			(layer "F.Fab")
		)
		(fp_line
			(start -0.12065 0.2794)
			(end -0.12065 0.3048)
			(stroke
				(width 0.1)
				(type default)
			)
			(layer "F.Fab")
		)
		(fp_line
			(start -0.12065 0.3048)
			(end -0.67945 0.3048)
			(stroke
				(width 0.1)
				(type default)
			)
			(layer "F.Fab")
		)
		(fp_line
			(start 0.120396 0.2794)
			(end -0.12065 0.2794)
			(stroke
				(width 0.1)
				(type default)
			)
			(layer "F.Fab")
		)
		(fp_line
			(start 0.120396 0.3048)
			(end 0.120396 0.2794)
			(stroke
				(width 0.1)
				(type default)
			)
			(layer "F.Fab")
		)
		(fp_line
			(start 0.12065 -0.3048)
			(end 0.67945 -0.3048)
			(stroke
				(width 0.1)
				(type default)
			)
			(layer "F.Fab")
		)
		(fp_line
			(start 0.12065 -0.2794)
			(end 0.12065 -0.3048)
			(stroke
				(width 0.1)
				(type default)
			)
			(layer "F.Fab")
		)
		(fp_line
			(start 0.67945 -0.3048)
			(end 0.67945 0.3048)
			(stroke
				(width 0.1)
				(type default)
			)
			(layer "F.Fab")
		)
		(fp_line
			(start 0.67945 0.3048)
			(end 0.120396 0.3048)
			(stroke
				(width 0.1)
				(type default)
			)
			(layer "F.Fab")
		)
		(pad "1" smd circle
			(at -0.40005 0)
			(size 0 0)
			(layers "F.Cu" "F.Mask" "F.Paste")
			(net "GPU_BASE_HMC_READY_ISO_R")
		)
		(pad "2" smd circle
			(at 0.40005 0)
			(size 0 0)
			(layers "F.Cu" "F.Mask" "F.Paste")
			(net "GPU_BASE_HMC_READY_ISO")
		)
	)
	(footprint ""
		(layer "F.Cu")
		(at 209.959956 -37.769292 90)
		(property "Reference" "C2014"
			(at 0 0 90)
			(layer "F.SilkS")
			(hide yes)
			(effects
				(font
					(size 1.27 1.27)
				)
			)
		)
		(property "Value" ""
			(at 0 0 90)
			(layer "F.Fab")
			(effects
				(font
					(size 1.27 1.27)
				)
			)
		)
		(duplicate_pad_numbers_are_jumpers no)
		(fp_line
			(start 0.7874 -0.4064)
			(end 0.7874 0.4064)
			(stroke
				(width 0.1524)
				(type default)
			)
			(layer "F.SilkS")
		)
		(fp_line
			(start -0.7874 -0.4064)
			(end 0.7874 -0.4064)
			(stroke
				(width 0.1524)
				(type default)
			)
			(layer "F.SilkS")
		)
		(fp_line
			(start 0.7874 0.4064)
			(end -0.7874 0.4064)
			(stroke
				(width 0.1524)
				(type default)
			)
			(layer "F.SilkS")
		)
		(fp_line
			(start -0.7874 0.4064)
			(end -0.7874 -0.4064)
			(stroke
				(width 0.1524)
				(type default)
			)
			(layer "F.SilkS")
		)
		(fp_line
			(start -0.12065 -0.305054)
			(end -0.12065 -0.2794)
			(stroke
				(width 0.1)
				(type default)
			)
			(layer "F.Fab")
		)
		(fp_line
			(start -0.67945 -0.305054)
			(end -0.12065 -0.305054)
			(stroke
				(width 0.1)
				(type default)
			)
			(layer "F.Fab")
		)
		(fp_line
			(start 0.67945 -0.3048)
			(end 0.67945 0.3048)
			(stroke
				(width 0.1)
				(type default)
			)
			(layer "F.Fab")
		)
		(fp_line
			(start 0.12065 -0.3048)
			(end 0.67945 -0.3048)
			(stroke
				(width 0.1)
				(type default)
			)
			(layer "F.Fab")
		)
		(fp_line
			(start 0.12065 -0.2794)
			(end 0.12065 -0.3048)
			(stroke
				(width 0.1)
				(type default)
			)
			(layer "F.Fab")
		)
		(fp_line
			(start -0.12065 -0.2794)
			(end 0.12065 -0.2794)
			(stroke
				(width 0.1)
				(type default)
			)
			(layer "F.Fab")
		)
		(fp_line
			(start 0.120396 0.2794)
			(end -0.12065 0.2794)
			(stroke
				(width 0.1)
				(type default)
			)
			(layer "F.Fab")
		)
		(fp_line
			(start -0.12065 0.2794)
			(end -0.12065 0.3048)
			(stroke
				(width 0.1)
				(type default)
			)
			(layer "F.Fab")
		)
		(fp_line
			(start 0.67945 0.3048)
			(end 0.120396 0.3048)
			(stroke
				(width 0.1)
				(type default)
			)
			(layer "F.Fab")
		)
		(fp_line
			(start 0.120396 0.3048)
			(end 0.120396 0.2794)
			(stroke
				(width 0.1)
				(type default)
			)
			(layer "F.Fab")
		)
		(fp_line
			(start -0.12065 0.3048)
			(end -0.67945 0.3048)
			(stroke
				(width 0.1)
				(type default)
			)
			(layer "F.Fab")
		)
		(fp_line
			(start -0.67945 0.3048)
			(end -0.67945 -0.305054)
			(stroke
				(width 0.1)
				(type default)
			)
			(layer "F.Fab")
		)
		(pad "1" smd circle
			(at -0.40005 0 90)
			(size 0 0)
			(layers "F.Cu" "F.Mask" "F.Paste")
			(net "P3V3_AUX")
		)
		(pad "2" smd circle
			(at 0.40005 0 90)
			(size 0 0)
			(layers "F.Cu" "F.Mask" "F.Paste")
			(net "GND")
		)
	)
	(footprint ""
		(layer "F.Cu")
		(at 427.5836 -17.624298 90)
		(property "Reference" "C1575"
			(at 0 0 90)
			(layer "F.SilkS")
			(hide yes)
			(effects
				(font
					(size 1.27 1.27)
				)
			)
		)
		(property "Value" ""
			(at 0 0 90)
			(layer "F.Fab")
			(effects
				(font
					(size 1.27 1.27)
				)
			)
		)
		(duplicate_pad_numbers_are_jumpers no)
		(fp_line
			(start 0.299974 -0.150114)
			(end 0.299974 0.150114)
			(stroke
				(width 0.1)
				(type default)
			)
			(layer "F.Fab")
		)
		(fp_line
			(start -0.299974 -0.150114)
			(end 0.299974 -0.150114)
			(stroke
				(width 0.1)
				(type default)
			)
			(layer "F.Fab")
		)
		(fp_line
			(start 0.299974 0.150114)
			(end -0.299974 0.150114)
			(stroke
				(width 0.1)
				(type default)
			)
			(layer "F.Fab")
		)
		(fp_line
			(start -0.299974 0.150114)
			(end -0.299974 -0.150114)
			(stroke
				(width 0.1)
				(type default)
			)
			(layer "F.Fab")
		)
		(pad "1" smd rect
			(at -0.2667 0 90)
			(size 0.3048 0.381)
			(layers "F.Cu" "F.Mask" "F.Paste")
			(net "P5E_CPU0_G3_TX_C_DP<2>")
		)
		(pad "2" smd rect
			(at 0.2667 0 90)
			(size 0.3048 0.381)
			(layers "F.Cu" "F.Mask" "F.Paste")
			(net "P5E_CPU0_G3_TX_DP<2>")
		)
	)
	(footprint ""
		(layer "F.Cu")
		(at 177.544984 -147.086574 90)
		(property "Reference" "R590"
			(at 0 0 90)
			(layer "F.SilkS")
			(hide yes)
			(effects
				(font
					(size 1.27 1.27)
				)
			)
		)
		(property "Value" ""
			(at 0 0 90)
			(layer "F.Fab")
			(effects
				(font
					(size 1.27 1.27)
				)
			)
		)
		(duplicate_pad_numbers_are_jumpers no)
		(fp_line
			(start 0.7874 -0.4064)
			(end 0.7874 0.4064)
			(stroke
				(width 0.1524)
				(type default)
			)
			(layer "F.SilkS")
		)
		(fp_line
			(start -0.7874 -0.4064)
			(end 0.7874 -0.4064)
			(stroke
				(width 0.1524)
				(type default)
			)
			(layer "F.SilkS")
		)
		(fp_line
			(start 0.7874 0.4064)
			(end -0.7874 0.4064)
			(stroke
				(width 0.1524)
				(type default)
			)
			(layer "F.SilkS")
		)
		(fp_line
			(start -0.7874 0.4064)
			(end -0.7874 -0.4064)
			(stroke
				(width 0.1524)
				(type default)
			)
			(layer "F.SilkS")
		)
		(fp_line
			(start -0.12065 -0.305054)
			(end -0.12065 -0.2794)
			(stroke
				(width 0.1)
				(type default)
			)
			(layer "F.Fab")
		)
		(fp_line
			(start -0.67945 -0.305054)
			(end -0.12065 -0.305054)
			(stroke
				(width 0.1)
				(type default)
			)
			(layer "F.Fab")
		)
		(fp_line
			(start 0.67945 -0.3048)
			(end 0.67945 0.3048)
			(stroke
				(width 0.1)
				(type default)
			)
			(layer "F.Fab")
		)
		(fp_line
			(start 0.12065 -0.3048)
			(end 0.67945 -0.3048)
			(stroke
				(width 0.1)
				(type default)
			)
			(layer "F.Fab")
		)
		(fp_line
			(start 0.12065 -0.2794)
			(end 0.12065 -0.3048)
			(stroke
				(width 0.1)
				(type default)
			)
			(layer "F.Fab")
		)
		(fp_line
			(start -0.12065 -0.2794)
			(end 0.12065 -0.2794)
			(stroke
				(width 0.1)
				(type default)
			)
			(layer "F.Fab")
		)
		(fp_line
			(start 0.120396 0.2794)
			(end -0.12065 0.2794)
			(stroke
				(width 0.1)
				(type default)
			)
			(layer "F.Fab")
		)
		(fp_line
			(start -0.12065 0.2794)
			(end -0.12065 0.3048)
			(stroke
				(width 0.1)
				(type default)
			)
			(layer "F.Fab")
		)
		(fp_line
			(start 0.67945 0.3048)
			(end 0.120396 0.3048)
			(stroke
				(width 0.1)
				(type default)
			)
			(layer "F.Fab")
		)
		(fp_line
			(start 0.120396 0.3048)
			(end 0.120396 0.2794)
			(stroke
				(width 0.1)
				(type default)
			)
			(layer "F.Fab")
		)
		(fp_line
			(start -0.12065 0.3048)
			(end -0.67945 0.3048)
			(stroke
				(width 0.1)
				(type default)
			)
			(layer "F.Fab")
		)
		(fp_line
			(start -0.67945 0.3048)
			(end -0.67945 -0.305054)
			(stroke
				(width 0.1)
				(type default)
			)
			(layer "F.Fab")
		)
		(pad "1" smd circle
			(at -0.40005 0 90)
			(size 0 0)
			(layers "F.Cu" "F.Mask" "F.Paste")
			(net "P3V3_AUX")
		)
		(pad "2" smd circle
			(at 0.40005 0 90)
			(size 0 0)
			(layers "F.Cu" "F.Mask" "F.Paste")
			(net "SMB_CPU0_4_XLTR_SDA")
		)
	)
	(footprint ""
		(layer "F.Cu")
		(at 40.116506 19.444716 -90)
		(property "Reference" "U25_BP"
			(at 0 0 270)
			(layer "F.SilkS")
			(hide yes)
			(effects
				(font
					(size 1.27 1.27)
				)
			)
		)
		(property "Value" ""
			(at 0 0 270)
			(layer "F.Fab")
			(effects
				(font
					(size 1.27 1.27)
				)
			)
		)
		(duplicate_pad_numbers_are_jumpers no)
		(pad "1" smd circle
			(at 0 0 270)
			(size 0.762 0.762)
			(layers "F.Cu" "F.Mask" "F.Paste")
			(net "Net_10789")
		)
	)
	(footprint ""
		(layer "F.Cu")
		(at 184.3405 -397.848582 180)
		(property "Reference" "R2586"
			(at 0 0 180)
			(layer "F.SilkS")
			(hide yes)
			(effects
				(font
					(size 1.27 1.27)
				)
			)
		)
		(property "Value" ""
			(at 0 0 180)
			(layer "F.Fab")
			(effects
				(font
					(size 1.27 1.27)
				)
			)
		)
		(duplicate_pad_numbers_are_jumpers no)
		(fp_line
			(start 0.7874 0.4064)
			(end -0.7874 0.4064)
			(stroke
				(width 0.1524)
				(type default)
			)
			(layer "F.SilkS")
		)
		(fp_line
			(start 0.7874 -0.4064)
			(end 0.7874 0.4064)
			(stroke
				(width 0.1524)
				(type default)
			)
			(layer "F.SilkS")
		)
		(fp_line
			(start -0.7874 0.4064)
			(end -0.7874 -0.4064)
			(stroke
				(width 0.1524)
				(type default)
			)
			(layer "F.SilkS")
		)
		(fp_line
			(start -0.7874 -0.4064)
			(end 0.7874 -0.4064)
			(stroke
				(width 0.1524)
				(type default)
			)
			(layer "F.SilkS")
		)
		(fp_line
			(start 0.67945 0.3048)
			(end 0.120396 0.3048)
			(stroke
				(width 0.1)
				(type default)
			)
			(layer "F.Fab")
		)
		(fp_line
			(start 0.67945 -0.3048)
			(end 0.67945 0.3048)
			(stroke
				(width 0.1)
				(type default)
			)
			(layer "F.Fab")
		)
		(fp_line
			(start 0.12065 -0.2794)
			(end 0.12065 -0.3048)
			(stroke
				(width 0.1)
				(type default)
			)
			(layer "F.Fab")
		)
		(fp_line
			(start 0.12065 -0.3048)
			(end 0.67945 -0.3048)
			(stroke
				(width 0.1)
				(type default)
			)
			(layer "F.Fab")
		)
		(fp_line
			(start 0.120396 0.3048)
			(end 0.120396 0.2794)
			(stroke
				(width 0.1)
				(type default)
			)
			(layer "F.Fab")
		)
		(fp_line
			(start 0.120396 0.2794)
			(end -0.12065 0.2794)
			(stroke
				(width 0.1)
				(type default)
			)
			(layer "F.Fab")
		)
		(fp_line
			(start -0.12065 0.3048)
			(end -0.67945 0.3048)
			(stroke
				(width 0.1)
				(type default)
			)
			(layer "F.Fab")
		)
		(fp_line
			(start -0.12065 0.2794)
			(end -0.12065 0.3048)
			(stroke
				(width 0.1)
				(type default)
			)
			(layer "F.Fab")
		)
		(fp_line
			(start -0.12065 -0.2794)
			(end 0.12065 -0.2794)
			(stroke
				(width 0.1)
				(type default)
			)
			(layer "F.Fab")
		)
		(fp_line
			(start -0.12065 -0.305054)
			(end -0.12065 -0.2794)
			(stroke
				(width 0.1)
				(type default)
			)
			(layer "F.Fab")
		)
		(fp_line
			(start -0.67945 0.3048)
			(end -0.67945 -0.305054)
			(stroke
				(width 0.1)
				(type default)
			)
			(layer "F.Fab")
		)
		(fp_line
			(start -0.67945 -0.305054)
			(end -0.12065 -0.305054)
			(stroke
				(width 0.1)
				(type default)
			)
			(layer "F.Fab")
		)
		(pad "1" smd circle
			(at -0.40005 0 180)
			(size 0 0)
			(layers "F.Cu" "F.Mask" "F.Paste")
			(net "HSC_EN")
		)
		(pad "2" smd circle
			(at 0.40005 0 180)
			(size 0 0)
			(layers "F.Cu" "F.Mask" "F.Paste")
			(net "HSC_EN_R")
		)
	)
	(footprint ""
		(layer "F.Cu")
		(at 435.997858 -107.78236 180)
		(property "Reference" "PC5328"
			(at 0 0 180)
			(layer "F.SilkS")
			(hide yes)
			(effects
				(font
					(size 1.27 1.27)
				)
			)
		)
		(property "Value" ""
			(at 0 0 180)
			(layer "F.Fab")
			(effects
				(font
					(size 1.27 1.27)
				)
			)
		)
		(duplicate_pad_numbers_are_jumpers no)
		(fp_line
			(start 0.7874 0.4064)
			(end -0.7874 0.4064)
			(stroke
				(width 0.1524)
				(type default)
			)
			(layer "F.SilkS")
		)
		(fp_line
			(start 0.7874 -0.4064)
			(end 0.7874 0.4064)
			(stroke
				(width 0.1524)
				(type default)
			)
			(layer "F.SilkS")
		)
		(fp_line
			(start -0.7874 0.4064)
			(end -0.7874 -0.4064)
			(stroke
				(width 0.1524)
				(type default)
			)
			(layer "F.SilkS")
		)
		(fp_line
			(start -0.7874 -0.4064)
			(end 0.7874 -0.4064)
			(stroke
				(width 0.1524)
				(type default)
			)
			(layer "F.SilkS")
		)
		(fp_line
			(start 0.67945 0.3048)
			(end 0.120396 0.3048)
			(stroke
				(width 0.1)
				(type default)
			)
			(layer "F.Fab")
		)
		(fp_line
			(start 0.67945 -0.3048)
			(end 0.67945 0.3048)
			(stroke
				(width 0.1)
				(type default)
			)
			(layer "F.Fab")
		)
		(fp_line
			(start 0.12065 -0.2794)
			(end 0.12065 -0.3048)
			(stroke
				(width 0.1)
				(type default)
			)
			(layer "F.Fab")
		)
		(fp_line
			(start 0.12065 -0.3048)
			(end 0.67945 -0.3048)
			(stroke
				(width 0.1)
				(type default)
			)
			(layer "F.Fab")
		)
		(fp_line
			(start 0.120396 0.3048)
			(end 0.120396 0.2794)
			(stroke
				(width 0.1)
				(type default)
			)
			(layer "F.Fab")
		)
		(fp_line
			(start 0.120396 0.2794)
			(end -0.12065 0.2794)
			(stroke
				(width 0.1)
				(type default)
			)
			(layer "F.Fab")
		)
		(fp_line
			(start -0.12065 0.3048)
			(end -0.67945 0.3048)
			(stroke
				(width 0.1)
				(type default)
			)
			(layer "F.Fab")
		)
		(fp_line
			(start -0.12065 0.2794)
			(end -0.12065 0.3048)
			(stroke
				(width 0.1)
				(type default)
			)
			(layer "F.Fab")
		)
		(fp_line
			(start -0.12065 -0.2794)
			(end 0.12065 -0.2794)
			(stroke
				(width 0.1)
				(type default)
			)
			(layer "F.Fab")
		)
		(fp_line
			(start -0.12065 -0.305054)
			(end -0.12065 -0.2794)
			(stroke
				(width 0.1)
				(type default)
			)
			(layer "F.Fab")
		)
		(fp_line
			(start -0.67945 0.3048)
			(end -0.67945 -0.305054)
			(stroke
				(width 0.1)
				(type default)
			)
			(layer "F.Fab")
		)
		(fp_line
			(start -0.67945 -0.305054)
			(end -0.12065 -0.305054)
			(stroke
				(width 0.1)
				(type default)
			)
			(layer "F.Fab")
		)
		(pad "1" smd circle
			(at -0.40005 0 180)
			(size 0 0)
			(layers "F.Cu" "F.Mask" "F.Paste")
			(net "P3V3_AUX")
		)
		(pad "2" smd circle
			(at 0.40005 0 180)
			(size 0 0)
			(layers "F.Cu" "F.Mask" "F.Paste")
			(net "GND")
		)
	)
	(footprint ""
		(layer "F.Cu")
		(at 6.870192 -389.439912)
		(property "Reference" "H3"
			(at -2.5146 -3.58013 0)
			(unlocked yes)
			(layer "F.SilkS")
			(effects
				(font
					(size 0.7874 0.5842)
					(thickness 0.1524)
				)
				(justify left)
			)
		)
		(property "Value" ""
			(at 0 0 0)
			(layer "F.Fab")
			(effects
				(font
					(size 1.27 1.27)
				)
			)
		)
		(duplicate_pad_numbers_are_jumpers no)
		(pad "1" thru_hole circle
			(at 0 0)
			(size 6.1976 6.1976)
			(drill 3.7338)
			(layers "*.Cu" "*.Mask")
			(remove_unused_layers no)
			(net "GND")
			(clearance -0.9779)
			(padstack
				(mode front_inner_back)
				(layer "Inner"
					(shape circle)
					(size 5.5372 5.5372)
					(clearance -0.6477)
				)
				(layer "B.Cu"
					(shape circle)
					(size 6.1976 6.1976)
					(clearance -0.9779)
				)
			)
		)
	)
	(footprint ""
		(layer "F.Cu")
		(at 322.837048 -41.160954 180)
		(property "Reference" "R3682"
			(at 0 0 180)
			(layer "F.SilkS")
			(hide yes)
			(effects
				(font
					(size 1.27 1.27)
				)
			)
		)
		(property "Value" ""
			(at 0 0 180)
			(layer "F.Fab")
			(effects
				(font
					(size 1.27 1.27)
				)
			)
		)
		(duplicate_pad_numbers_are_jumpers no)
		(fp_line
			(start 0.7874 0.4064)
			(end -0.7874 0.4064)
			(stroke
				(width 0.1524)
				(type default)
			)
			(layer "F.SilkS")
		)
		(fp_line
			(start 0.7874 -0.4064)
			(end 0.7874 0.4064)
			(stroke
				(width 0.1524)
				(type default)
			)
			(layer "F.SilkS")
		)
		(fp_line
			(start -0.7874 0.4064)
			(end -0.7874 -0.4064)
			(stroke
				(width 0.1524)
				(type default)
			)
			(layer "F.SilkS")
		)
		(fp_line
			(start -0.7874 -0.4064)
			(end 0.7874 -0.4064)
			(stroke
				(width 0.1524)
				(type default)
			)
			(layer "F.SilkS")
		)
		(fp_line
			(start 0.67945 0.3048)
			(end 0.120396 0.3048)
			(stroke
				(width 0.1)
				(type default)
			)
			(layer "F.Fab")
		)
		(fp_line
			(start 0.67945 -0.3048)
			(end 0.67945 0.3048)
			(stroke
				(width 0.1)
				(type default)
			)
			(layer "F.Fab")
		)
		(fp_line
			(start 0.12065 -0.2794)
			(end 0.12065 -0.3048)
			(stroke
				(width 0.1)
				(type default)
			)
			(layer "F.Fab")
		)
		(fp_line
			(start 0.12065 -0.3048)
			(end 0.67945 -0.3048)
			(stroke
				(width 0.1)
				(type default)
			)
			(layer "F.Fab")
		)
		(fp_line
			(start 0.120396 0.3048)
			(end 0.120396 0.2794)
			(stroke
				(width 0.1)
				(type default)
			)
			(layer "F.Fab")
		)
		(fp_line
			(start 0.120396 0.2794)
			(end -0.12065 0.2794)
			(stroke
				(width 0.1)
				(type default)
			)
			(layer "F.Fab")
		)
		(fp_line
			(start -0.12065 0.3048)
			(end -0.67945 0.3048)
			(stroke
				(width 0.1)
				(type default)
			)
			(layer "F.Fab")
		)
		(fp_line
			(start -0.12065 0.2794)
			(end -0.12065 0.3048)
			(stroke
				(width 0.1)
				(type default)
			)
			(layer "F.Fab")
		)
		(fp_line
			(start -0.12065 -0.2794)
			(end 0.12065 -0.2794)
			(stroke
				(width 0.1)
				(type default)
			)
			(layer "F.Fab")
		)
		(fp_line
			(start -0.12065 -0.305054)
			(end -0.12065 -0.2794)
			(stroke
				(width 0.1)
				(type default)
			)
			(layer "F.Fab")
		)
		(fp_line
			(start -0.67945 0.3048)
			(end -0.67945 -0.305054)
			(stroke
				(width 0.1)
				(type default)
			)
			(layer "F.Fab")
		)
		(fp_line
			(start -0.67945 -0.305054)
			(end -0.12065 -0.305054)
			(stroke
				(width 0.1)
				(type default)
			)
			(layer "F.Fab")
		)
		(pad "1" smd rect
			(at -0.40005 0)
			(size 0.4572 0.508)
			(layers "F.Cu" "F.Mask" "F.Paste")
			(net "P3V3_AUX_ADC")
		)
		(pad "2" smd rect
			(at 0.40005 0)
			(size 0.4572 0.508)
			(layers "F.Cu" "F.Mask" "F.Paste")
			(net "P3V3_AUX_ADC_TIC")
		)
	)
	(footprint ""
		(layer "F.Cu")
		(at 302.15078 -351.368106 -90)
		(property "Reference" "PC155"
			(at 0 0 270)
			(layer "F.SilkS")
			(hide yes)
			(effects
				(font
					(size 1.27 1.27)
				)
			)
		)
		(property "Value" ""
			(at 0 0 270)
			(layer "F.Fab")
			(effects
				(font
					(size 1.27 1.27)
				)
			)
		)
		(duplicate_pad_numbers_are_jumpers no)
		(fp_line
			(start -0.7874 0.4064)
			(end -0.7874 -0.4064)
			(stroke
				(width 0.1524)
				(type default)
			)
			(layer "F.SilkS")
		)
		(fp_line
			(start 0.7874 0.4064)
			(end -0.7874 0.4064)
			(stroke
				(width 0.1524)
				(type default)
			)
			(layer "F.SilkS")
		)
		(fp_line
			(start -0.7874 -0.4064)
			(end 0.7874 -0.4064)
			(stroke
				(width 0.1524)
				(type default)
			)
			(layer "F.SilkS")
		)
		(fp_line
			(start 0.7874 -0.4064)
			(end 0.7874 0.4064)
			(stroke
				(width 0.1524)
				(type default)
			)
			(layer "F.SilkS")
		)
		(fp_line
			(start -0.67945 0.3048)
			(end -0.67945 -0.305054)
			(stroke
				(width 0.1)
				(type default)
			)
			(layer "F.Fab")
		)
		(fp_line
			(start -0.12065 0.3048)
			(end -0.67945 0.3048)
			(stroke
				(width 0.1)
				(type default)
			)
			(layer "F.Fab")
		)
		(fp_line
			(start 0.120396 0.3048)
			(end 0.120396 0.2794)
			(stroke
				(width 0.1)
				(type default)
			)
			(layer "F.Fab")
		)
		(fp_line
			(start 0.67945 0.3048)
			(end 0.120396 0.3048)
			(stroke
				(width 0.1)
				(type default)
			)
			(layer "F.Fab")
		)
		(fp_line
			(start -0.12065 0.2794)
			(end -0.12065 0.3048)
			(stroke
				(width 0.1)
				(type default)
			)
			(layer "F.Fab")
		)
		(fp_line
			(start 0.120396 0.2794)
			(end -0.12065 0.2794)
			(stroke
				(width 0.1)
				(type default)
			)
			(layer "F.Fab")
		)
		(fp_line
			(start -0.12065 -0.2794)
			(end 0.12065 -0.2794)
			(stroke
				(width 0.1)
				(type default)
			)
			(layer "F.Fab")
		)
		(fp_line
			(start 0.12065 -0.2794)
			(end 0.12065 -0.3048)
			(stroke
				(width 0.1)
				(type default)
			)
			(layer "F.Fab")
		)
		(fp_line
			(start 0.12065 -0.3048)
			(end 0.67945 -0.3048)
			(stroke
				(width 0.1)
				(type default)
			)
			(layer "F.Fab")
		)
		(fp_line
			(start 0.67945 -0.3048)
			(end 0.67945 0.3048)
			(stroke
				(width 0.1)
				(type default)
			)
			(layer "F.Fab")
		)
		(fp_line
			(start -0.67945 -0.305054)
			(end -0.12065 -0.305054)
			(stroke
				(width 0.1)
				(type default)
			)
			(layer "F.Fab")
		)
		(fp_line
			(start -0.12065 -0.305054)
			(end -0.12065 -0.2794)
			(stroke
				(width 0.1)
				(type default)
			)
			(layer "F.Fab")
		)
		(pad "1" smd circle
			(at -0.40005 0 270)
			(size 0 0)
			(layers "F.Cu" "F.Mask" "F.Paste")
			(net "SW_PVDDIO_P0_BOOT1_R")
		)
		(pad "2" smd circle
			(at 0.40005 0 270)
			(size 0 0)
			(layers "F.Cu" "F.Mask" "F.Paste")
			(net "SW_PVDDIO_P0_BOOTR1")
		)
	)
	(footprint ""
		(layer "F.Cu")
		(at 296.29989 -358.769666 180)
		(property "Reference" "PC164"
			(at 1.78689 5.439664 0)
			(unlocked yes)
			(layer "F.SilkS")
			(effects
				(font
					(size 0.7874 0.5842)
					(thickness 0.1524)
				)
				(justify left)
			)
		)
		(property "Value" ""
			(at 0 0 180)
			(layer "F.Fab")
			(effects
				(font
					(size 1.27 1.27)
				)
			)
		)
		(duplicate_pad_numbers_are_jumpers no)
		(fp_line
			(start -3.400044 1.249934)
			(end 3.400044 1.249934)
			(stroke
				(width 0.1524)
				(type default)
			)
			(layer "F.SilkS")
		)
		(fp_circle
			(center 0 1.249934)
			(end -3.400044 1.249934)
			(stroke
				(width 0.1524)
				(type default)
			)
			(fill no)
			(layer "F.SilkS")
		)
		(fp_poly
			(pts
				(arc
					(start 3.400044 1.249934)
					(mid 0 4.649978)
					(end -3.400044 1.249934)
				)
			)
			(stroke
				(width 0)
				(type default)
			)
			(fill yes)
			(layer "F.SilkS")
		)
		(fp_circle
			(center 0 1.249934)
			(end -3.400044 1.249934)
			(stroke
				(width 0.1)
				(type default)
			)
			(fill no)
			(layer "F.Fab")
		)
		(pad "1" thru_hole rect
			(at 0 0 180)
			(size 1.524 1.524)
			(drill 1.016)
			(layers "*.Cu" "*.Mask")
			(remove_unused_layers no)
			(net "SW_P12V_AUX_PVDDIO_P0_FLT")
			(clearance 0)
			(padstack
				(mode front_inner_back)
				(layer "Inner"
					(shape circle)
					(size 1.524 1.524)
					(clearance 0)
				)
				(layer "B.Cu"
					(shape rect)
					(size 1.524 1.524)
					(clearance 0)
				)
			)
		)
		(pad "2" thru_hole circle
			(at 0 2.500122 180)
			(size 1.524 1.524)
			(drill 1.016)
			(layers "*.Cu" "*.Mask")
			(remove_unused_layers no)
			(net "GND")
			(clearance 0)
		)
	)
	(footprint ""
		(layer "F.Cu")
		(at 213.835488 -136.31799 90)
		(property "Reference" "R1649"
			(at 0 0 90)
			(layer "F.SilkS")
			(hide yes)
			(effects
				(font
					(size 1.27 1.27)
				)
			)
		)
		(property "Value" ""
			(at 0 0 90)
			(layer "F.Fab")
			(effects
				(font
					(size 1.27 1.27)
				)
			)
		)
		(duplicate_pad_numbers_are_jumpers no)
		(fp_line
			(start 0.7874 -0.4064)
			(end 0.7874 0.4064)
			(stroke
				(width 0.1524)
				(type default)
			)
			(layer "F.SilkS")
		)
		(fp_line
			(start -0.7874 -0.4064)
			(end 0.7874 -0.4064)
			(stroke
				(width 0.1524)
				(type default)
			)
			(layer "F.SilkS")
		)
		(fp_line
			(start 0.7874 0.4064)
			(end -0.7874 0.4064)
			(stroke
				(width 0.1524)
				(type default)
			)
			(layer "F.SilkS")
		)
		(fp_line
			(start -0.7874 0.4064)
			(end -0.7874 -0.4064)
			(stroke
				(width 0.1524)
				(type default)
			)
			(layer "F.SilkS")
		)
		(fp_line
			(start -0.12065 -0.305054)
			(end -0.12065 -0.2794)
			(stroke
				(width 0.1)
				(type default)
			)
			(layer "F.Fab")
		)
		(fp_line
			(start -0.67945 -0.305054)
			(end -0.12065 -0.305054)
			(stroke
				(width 0.1)
				(type default)
			)
			(layer "F.Fab")
		)
		(fp_line
			(start 0.67945 -0.3048)
			(end 0.67945 0.3048)
			(stroke
				(width 0.1)
				(type default)
			)
			(layer "F.Fab")
		)
		(fp_line
			(start 0.12065 -0.3048)
			(end 0.67945 -0.3048)
			(stroke
				(width 0.1)
				(type default)
			)
			(layer "F.Fab")
		)
		(fp_line
			(start 0.12065 -0.2794)
			(end 0.12065 -0.3048)
			(stroke
				(width 0.1)
				(type default)
			)
			(layer "F.Fab")
		)
		(fp_line
			(start -0.12065 -0.2794)
			(end 0.12065 -0.2794)
			(stroke
				(width 0.1)
				(type default)
			)
			(layer "F.Fab")
		)
		(fp_line
			(start 0.120396 0.2794)
			(end -0.12065 0.2794)
			(stroke
				(width 0.1)
				(type default)
			)
			(layer "F.Fab")
		)
		(fp_line
			(start -0.12065 0.2794)
			(end -0.12065 0.3048)
			(stroke
				(width 0.1)
				(type default)
			)
			(layer "F.Fab")
		)
		(fp_line
			(start 0.67945 0.3048)
			(end 0.120396 0.3048)
			(stroke
				(width 0.1)
				(type default)
			)
			(layer "F.Fab")
		)
		(fp_line
			(start 0.120396 0.3048)
			(end 0.120396 0.2794)
			(stroke
				(width 0.1)
				(type default)
			)
			(layer "F.Fab")
		)
		(fp_line
			(start -0.12065 0.3048)
			(end -0.67945 0.3048)
			(stroke
				(width 0.1)
				(type default)
			)
			(layer "F.Fab")
		)
		(fp_line
			(start -0.67945 0.3048)
			(end -0.67945 -0.305054)
			(stroke
				(width 0.1)
				(type default)
			)
			(layer "F.Fab")
		)
		(pad "1" smd circle
			(at -0.40005 0 90)
			(size 0 0)
			(layers "F.Cu" "F.Mask" "F.Paste")
			(net "PVDD18_S5_P0")
		)
		(pad "2" smd circle
			(at 0.40005 0 90)
			(size 0 0)
			(layers "F.Cu" "F.Mask" "F.Paste")
			(net "CPU1_HDT_BYPASS_SEL")
		)
	)
	(footprint ""
		(layer "F.Cu")
		(at 163.703 -114.264948 180)
		(property "Reference" "R6039"
			(at 0 0 180)
			(layer "F.SilkS")
			(hide yes)
			(effects
				(font
					(size 1.27 1.27)
				)
			)
		)
		(property "Value" ""
			(at 0 0 180)
			(layer "F.Fab")
			(effects
				(font
					(size 1.27 1.27)
				)
			)
		)
		(duplicate_pad_numbers_are_jumpers no)
		(fp_line
			(start 0.7874 0.4064)
			(end -0.7874 0.4064)
			(stroke
				(width 0.1524)
				(type default)
			)
			(layer "F.SilkS")
		)
		(fp_line
			(start 0.7874 -0.4064)
			(end 0.7874 0.4064)
			(stroke
				(width 0.1524)
				(type default)
			)
			(layer "F.SilkS")
		)
		(fp_line
			(start -0.7874 0.4064)
			(end -0.7874 -0.4064)
			(stroke
				(width 0.1524)
				(type default)
			)
			(layer "F.SilkS")
		)
		(fp_line
			(start -0.7874 -0.4064)
			(end 0.7874 -0.4064)
			(stroke
				(width 0.1524)
				(type default)
			)
			(layer "F.SilkS")
		)
		(fp_line
			(start 0.67945 0.3048)
			(end 0.120396 0.3048)
			(stroke
				(width 0.1)
				(type default)
			)
			(layer "F.Fab")
		)
		(fp_line
			(start 0.67945 -0.3048)
			(end 0.67945 0.3048)
			(stroke
				(width 0.1)
				(type default)
			)
			(layer "F.Fab")
		)
		(fp_line
			(start 0.12065 -0.2794)
			(end 0.12065 -0.3048)
			(stroke
				(width 0.1)
				(type default)
			)
			(layer "F.Fab")
		)
		(fp_line
			(start 0.12065 -0.3048)
			(end 0.67945 -0.3048)
			(stroke
				(width 0.1)
				(type default)
			)
			(layer "F.Fab")
		)
		(fp_line
			(start 0.120396 0.3048)
			(end 0.120396 0.2794)
			(stroke
				(width 0.1)
				(type default)
			)
			(layer "F.Fab")
		)
		(fp_line
			(start 0.120396 0.2794)
			(end -0.12065 0.2794)
			(stroke
				(width 0.1)
				(type default)
			)
			(layer "F.Fab")
		)
		(fp_line
			(start -0.12065 0.3048)
			(end -0.67945 0.3048)
			(stroke
				(width 0.1)
				(type default)
			)
			(layer "F.Fab")
		)
		(fp_line
			(start -0.12065 0.2794)
			(end -0.12065 0.3048)
			(stroke
				(width 0.1)
				(type default)
			)
			(layer "F.Fab")
		)
		(fp_line
			(start -0.12065 -0.2794)
			(end 0.12065 -0.2794)
			(stroke
				(width 0.1)
				(type default)
			)
			(layer "F.Fab")
		)
		(fp_line
			(start -0.12065 -0.305054)
			(end -0.12065 -0.2794)
			(stroke
				(width 0.1)
				(type default)
			)
			(layer "F.Fab")
		)
		(fp_line
			(start -0.67945 0.3048)
			(end -0.67945 -0.305054)
			(stroke
				(width 0.1)
				(type default)
			)
			(layer "F.Fab")
		)
		(fp_line
			(start -0.67945 -0.305054)
			(end -0.12065 -0.305054)
			(stroke
				(width 0.1)
				(type default)
			)
			(layer "F.Fab")
		)
		(pad "1" smd circle
			(at -0.40005 0 180)
			(size 0 0)
			(layers "F.Cu" "F.Mask" "F.Paste")
			(net "OC_ALERT_N")
		)
		(pad "2" smd circle
			(at 0.40005 0 180)
			(size 0 0)
			(layers "F.Cu" "F.Mask" "F.Paste")
			(net "HSC_D_OC")
		)
	)
	(footprint ""
		(layer "F.Cu")
		(at 313.104022 -36.890706 180)
		(property "Reference" "C1347"
			(at 0 0 180)
			(layer "F.SilkS")
			(hide yes)
			(effects
				(font
					(size 1.27 1.27)
				)
			)
		)
		(property "Value" ""
			(at 0 0 180)
			(layer "F.Fab")
			(effects
				(font
					(size 1.27 1.27)
				)
			)
		)
		(duplicate_pad_numbers_are_jumpers no)
		(fp_line
			(start 0.7874 0.4064)
			(end -0.7874 0.4064)
			(stroke
				(width 0.1524)
				(type default)
			)
			(layer "F.SilkS")
		)
		(fp_line
			(start 0.7874 -0.4064)
			(end 0.7874 0.4064)
			(stroke
				(width 0.1524)
				(type default)
			)
			(layer "F.SilkS")
		)
		(fp_line
			(start -0.7874 0.4064)
			(end -0.7874 -0.4064)
			(stroke
				(width 0.1524)
				(type default)
			)
			(layer "F.SilkS")
		)
		(fp_line
			(start -0.7874 -0.4064)
			(end 0.7874 -0.4064)
			(stroke
				(width 0.1524)
				(type default)
			)
			(layer "F.SilkS")
		)
		(fp_line
			(start 0.67945 0.3048)
			(end 0.120396 0.3048)
			(stroke
				(width 0.1)
				(type default)
			)
			(layer "F.Fab")
		)
		(fp_line
			(start 0.67945 -0.3048)
			(end 0.67945 0.3048)
			(stroke
				(width 0.1)
				(type default)
			)
			(layer "F.Fab")
		)
		(fp_line
			(start 0.12065 -0.2794)
			(end 0.12065 -0.3048)
			(stroke
				(width 0.1)
				(type default)
			)
			(layer "F.Fab")
		)
		(fp_line
			(start 0.12065 -0.3048)
			(end 0.67945 -0.3048)
			(stroke
				(width 0.1)
				(type default)
			)
			(layer "F.Fab")
		)
		(fp_line
			(start 0.120396 0.3048)
			(end 0.120396 0.2794)
			(stroke
				(width 0.1)
				(type default)
			)
			(layer "F.Fab")
		)
		(fp_line
			(start 0.120396 0.2794)
			(end -0.12065 0.2794)
			(stroke
				(width 0.1)
				(type default)
			)
			(layer "F.Fab")
		)
		(fp_line
			(start -0.12065 0.3048)
			(end -0.67945 0.3048)
			(stroke
				(width 0.1)
				(type default)
			)
			(layer "F.Fab")
		)
		(fp_line
			(start -0.12065 0.2794)
			(end -0.12065 0.3048)
			(stroke
				(width 0.1)
				(type default)
			)
			(layer "F.Fab")
		)
		(fp_line
			(start -0.12065 -0.2794)
			(end 0.12065 -0.2794)
			(stroke
				(width 0.1)
				(type default)
			)
			(layer "F.Fab")
		)
		(fp_line
			(start -0.12065 -0.305054)
			(end -0.12065 -0.2794)
			(stroke
				(width 0.1)
				(type default)
			)
			(layer "F.Fab")
		)
		(fp_line
			(start -0.67945 0.3048)
			(end -0.67945 -0.305054)
			(stroke
				(width 0.1)
				(type default)
			)
			(layer "F.Fab")
		)
		(fp_line
			(start -0.67945 -0.305054)
			(end -0.12065 -0.305054)
			(stroke
				(width 0.1)
				(type default)
			)
			(layer "F.Fab")
		)
		(pad "1" smd circle
			(at -0.40005 0 180)
			(size 0 0)
			(layers "F.Cu" "F.Mask" "F.Paste")
			(net "MAX11617_VREF")
		)
		(pad "2" smd circle
			(at 0.40005 0 180)
			(size 0 0)
			(layers "F.Cu" "F.Mask" "F.Paste")
			(net "GND")
		)
	)
	(footprint ""
		(layer "F.Cu")
		(at 2.992628 -44.062904 90)
		(property "Reference" "R931"
			(at 0 0 90)
			(layer "F.SilkS")
			(hide yes)
			(effects
				(font
					(size 1.27 1.27)
				)
			)
		)
		(property "Value" ""
			(at 0 0 90)
			(layer "F.Fab")
			(effects
				(font
					(size 1.27 1.27)
				)
			)
		)
		(duplicate_pad_numbers_are_jumpers no)
		(fp_line
			(start 0.7874 -0.4064)
			(end 0.7874 0.4064)
			(stroke
				(width 0.1524)
				(type default)
			)
			(layer "F.SilkS")
		)
		(fp_line
			(start -0.7874 -0.4064)
			(end 0.7874 -0.4064)
			(stroke
				(width 0.1524)
				(type default)
			)
			(layer "F.SilkS")
		)
		(fp_line
			(start 0.7874 0.4064)
			(end -0.7874 0.4064)
			(stroke
				(width 0.1524)
				(type default)
			)
			(layer "F.SilkS")
		)
		(fp_line
			(start -0.7874 0.4064)
			(end -0.7874 -0.4064)
			(stroke
				(width 0.1524)
				(type default)
			)
			(layer "F.SilkS")
		)
		(fp_line
			(start -0.12065 -0.305054)
			(end -0.12065 -0.2794)
			(stroke
				(width 0.1)
				(type default)
			)
			(layer "F.Fab")
		)
		(fp_line
			(start -0.67945 -0.305054)
			(end -0.12065 -0.305054)
			(stroke
				(width 0.1)
				(type default)
			)
			(layer "F.Fab")
		)
		(fp_line
			(start 0.67945 -0.3048)
			(end 0.67945 0.3048)
			(stroke
				(width 0.1)
				(type default)
			)
			(layer "F.Fab")
		)
		(fp_line
			(start 0.12065 -0.3048)
			(end 0.67945 -0.3048)
			(stroke
				(width 0.1)
				(type default)
			)
			(layer "F.Fab")
		)
		(fp_line
			(start 0.12065 -0.2794)
			(end 0.12065 -0.3048)
			(stroke
				(width 0.1)
				(type default)
			)
			(layer "F.Fab")
		)
		(fp_line
			(start -0.12065 -0.2794)
			(end 0.12065 -0.2794)
			(stroke
				(width 0.1)
				(type default)
			)
			(layer "F.Fab")
		)
		(fp_line
			(start 0.120396 0.2794)
			(end -0.12065 0.2794)
			(stroke
				(width 0.1)
				(type default)
			)
			(layer "F.Fab")
		)
		(fp_line
			(start -0.12065 0.2794)
			(end -0.12065 0.3048)
			(stroke
				(width 0.1)
				(type default)
			)
			(layer "F.Fab")
		)
		(fp_line
			(start 0.67945 0.3048)
			(end 0.120396 0.3048)
			(stroke
				(width 0.1)
				(type default)
			)
			(layer "F.Fab")
		)
		(fp_line
			(start 0.120396 0.3048)
			(end 0.120396 0.2794)
			(stroke
				(width 0.1)
				(type default)
			)
			(layer "F.Fab")
		)
		(fp_line
			(start -0.12065 0.3048)
			(end -0.67945 0.3048)
			(stroke
				(width 0.1)
				(type default)
			)
			(layer "F.Fab")
		)
		(fp_line
			(start -0.67945 0.3048)
			(end -0.67945 -0.305054)
			(stroke
				(width 0.1)
				(type default)
			)
			(layer "F.Fab")
		)
		(pad "1" smd circle
			(at -0.40005 0 90)
			(size 0 0)
			(layers "F.Cu" "F.Mask" "F.Paste")
			(net "CPU1_XTRIG_L6")
		)
		(pad "2" smd circle
			(at 0.40005 0 90)
			(size 0 0)
			(layers "F.Cu" "F.Mask" "F.Paste")
			(net "CPU1_XTRIG_R1_L6")
		)
	)
	(footprint ""
		(layer "F.Cu")
		(at 343.994486 -20.08505 -90)
		(property "Reference" "Q11"
			(at -1.866138 -2.810002 90)
			(unlocked yes)
			(layer "F.SilkS")
			(effects
				(font
					(size 0.7874 0.5842)
					(thickness 0.1524)
				)
				(justify left)
			)
		)
		(property "Value" ""
			(at 0 0 270)
			(layer "F.Fab")
			(effects
				(font
					(size 1.27 1.27)
				)
			)
		)
		(duplicate_pad_numbers_are_jumpers no)
		(fp_line
			(start -1.332738 1.100074)
			(end -1.332738 -1.100074)
			(stroke
				(width 0.1524)
				(type default)
			)
			(layer "F.SilkS")
		)
		(fp_line
			(start 1.332738 1.100074)
			(end -1.332738 1.100074)
			(stroke
				(width 0.1524)
				(type default)
			)
			(layer "F.SilkS")
		)
		(fp_line
			(start 0 -0.541274)
			(end 0.4826 -1.100074)
			(stroke
				(width 0.1524)
				(type default)
			)
			(layer "F.SilkS")
		)
		(fp_line
			(start -1.332738 -1.100074)
			(end -0.4826 -1.100074)
			(stroke
				(width 0.1524)
				(type default)
			)
			(layer "F.SilkS")
		)
		(fp_line
			(start -0.4826 -1.100074)
			(end 0 -0.541274)
			(stroke
				(width 0.1524)
				(type default)
			)
			(layer "F.SilkS")
		)
		(fp_line
			(start 0.4826 -1.100074)
			(end 1.332738 -1.100074)
			(stroke
				(width 0.1524)
				(type default)
			)
			(layer "F.SilkS")
		)
		(fp_line
			(start 1.332738 -1.100074)
			(end 1.332738 1.100074)
			(stroke
				(width 0.1524)
				(type default)
			)
			(layer "F.SilkS")
		)
		(fp_poly
			(pts
				(xy -2.009902 -0.663702) (xy -2.711958 -0.312674) (xy -2.711958 -1.01473)
			)
			(stroke
				(width 0)
				(type default)
			)
			(fill yes)
			(layer "F.SilkS")
		)
		(fp_line
			(start -0.674878 1.100074)
			(end -0.674878 -1.100074)
			(stroke
				(width 0.1)
				(type default)
			)
			(layer "F.Fab")
		)
		(fp_line
			(start 0.674878 1.100074)
			(end -0.674878 1.100074)
			(stroke
				(width 0.1)
				(type default)
			)
			(layer "F.Fab")
		)
		(fp_line
			(start -0.674878 -1.100074)
			(end 0.674878 -1.100074)
			(stroke
				(width 0.1)
				(type default)
			)
			(layer "F.Fab")
		)
		(fp_line
			(start 0.674878 -1.100074)
			(end 0.674878 1.100074)
			(stroke
				(width 0.1)
				(type default)
			)
			(layer "F.Fab")
		)
		(fp_poly
			(pts
				(xy -2.2352 -0.298958) (xy -2.2352 -1.001014) (xy -1.533144 -0.649986)
			)
			(stroke
				(width 0)
				(type default)
			)
			(fill yes)
			(layer "F.Fab")
		)
		(pad "1" smd rect
			(at -0.94996 -0.649986)
			(size 0.4318 0.508)
			(layers "F.Cu" "F.Mask" "F.Paste")
			(net "GND")
		)
		(pad "2" smd rect
			(at -0.94996 0)
			(size 0.4318 0.508)
			(layers "F.Cu" "F.Mask" "F.Paste")
			(net "FM_SMERR_BUF_R_LED_N")
		)
		(pad "3" smd rect
			(at -0.94996 0.649986)
			(size 0.4318 0.508)
			(layers "F.Cu" "F.Mask" "F.Paste")
			(net "SMERR_LED_N")
		)
		(pad "4" smd rect
			(at 0.94996 0.649986)
			(size 0.4318 0.508)
			(layers "F.Cu" "F.Mask" "F.Paste")
			(net "GND")
		)
		(pad "5" smd rect
			(at 0.94996 0)
			(size 0.4318 0.508)
			(layers "F.Cu" "F.Mask" "F.Paste")
			(net "SMERR_LED")
		)
		(pad "6" smd rect
			(at 0.94996 -0.649986)
			(size 0.4318 0.508)
			(layers "F.Cu" "F.Mask" "F.Paste")
			(net "SMERR_LED")
		)
	)
	(footprint ""
		(layer "F.Cu")
		(at 395.388084 -390.652)
		(property "Reference" "R1102"
			(at 0 0 0)
			(layer "F.SilkS")
			(hide yes)
			(effects
				(font
					(size 1.27 1.27)
				)
			)
		)
		(property "Value" ""
			(at 0 0 0)
			(layer "F.Fab")
			(effects
				(font
					(size 1.27 1.27)
				)
			)
		)
		(duplicate_pad_numbers_are_jumpers no)
		(fp_line
			(start -0.32512 -0.175006)
			(end 0.32512 -0.175006)
			(stroke
				(width 0.1)
				(type default)
			)
			(layer "F.Fab")
		)
		(fp_line
			(start -0.32512 0.175006)
			(end -0.32512 -0.175006)
			(stroke
				(width 0.1)
				(type default)
			)
			(layer "F.Fab")
		)
		(fp_line
			(start 0.32512 -0.175006)
			(end 0.32512 0.175006)
			(stroke
				(width 0.1)
				(type default)
			)
			(layer "F.Fab")
		)
		(fp_line
			(start 0.32512 0.175006)
			(end -0.32512 0.175006)
			(stroke
				(width 0.1)
				(type default)
			)
			(layer "F.Fab")
		)
		(pad "1" smd rect
			(at -0.2667 0)
			(size 0.3048 0.381)
			(layers "F.Cu" "F.Mask" "F.Paste")
			(net "RT_CPU0_P3_ADDR1")
		)
		(pad "2" smd rect
			(at 0.2667 0 180)
			(size 0.3048 0.381)
			(layers "F.Cu" "F.Mask" "F.Paste")
			(net "GND")
		)
	)
	(footprint ""
		(layer "F.Cu")
		(at 226.915472 -290.341812 90)
		(property "Reference" "PR6524"
			(at 0 0 90)
			(layer "F.SilkS")
			(hide yes)
			(effects
				(font
					(size 1.27 1.27)
				)
			)
		)
		(property "Value" ""
			(at 0 0 90)
			(layer "F.Fab")
			(effects
				(font
					(size 1.27 1.27)
				)
			)
		)
		(duplicate_pad_numbers_are_jumpers no)
		(fp_line
			(start 0.7874 -0.4064)
			(end 0.7874 0.4064)
			(stroke
				(width 0.1524)
				(type default)
			)
			(layer "F.SilkS")
		)
		(fp_line
			(start -0.7874 -0.4064)
			(end 0.7874 -0.4064)
			(stroke
				(width 0.1524)
				(type default)
			)
			(layer "F.SilkS")
		)
		(fp_line
			(start 0.7874 0.4064)
			(end -0.7874 0.4064)
			(stroke
				(width 0.1524)
				(type default)
			)
			(layer "F.SilkS")
		)
		(fp_line
			(start -0.7874 0.4064)
			(end -0.7874 -0.4064)
			(stroke
				(width 0.1524)
				(type default)
			)
			(layer "F.SilkS")
		)
		(fp_line
			(start -0.12065 -0.305054)
			(end -0.12065 -0.2794)
			(stroke
				(width 0.1)
				(type default)
			)
			(layer "F.Fab")
		)
		(fp_line
			(start -0.67945 -0.305054)
			(end -0.12065 -0.305054)
			(stroke
				(width 0.1)
				(type default)
			)
			(layer "F.Fab")
		)
		(fp_line
			(start 0.67945 -0.3048)
			(end 0.67945 0.3048)
			(stroke
				(width 0.1)
				(type default)
			)
			(layer "F.Fab")
		)
		(fp_line
			(start 0.12065 -0.3048)
			(end 0.67945 -0.3048)
			(stroke
				(width 0.1)
				(type default)
			)
			(layer "F.Fab")
		)
		(fp_line
			(start 0.12065 -0.2794)
			(end 0.12065 -0.3048)
			(stroke
				(width 0.1)
				(type default)
			)
			(layer "F.Fab")
		)
		(fp_line
			(start -0.12065 -0.2794)
			(end 0.12065 -0.2794)
			(stroke
				(width 0.1)
				(type default)
			)
			(layer "F.Fab")
		)
		(fp_line
			(start 0.120396 0.2794)
			(end -0.12065 0.2794)
			(stroke
				(width 0.1)
				(type default)
			)
			(layer "F.Fab")
		)
		(fp_line
			(start -0.12065 0.2794)
			(end -0.12065 0.3048)
			(stroke
				(width 0.1)
				(type default)
			)
			(layer "F.Fab")
		)
		(fp_line
			(start 0.67945 0.3048)
			(end 0.120396 0.3048)
			(stroke
				(width 0.1)
				(type default)
			)
			(layer "F.Fab")
		)
		(fp_line
			(start 0.120396 0.3048)
			(end 0.120396 0.2794)
			(stroke
				(width 0.1)
				(type default)
			)
			(layer "F.Fab")
		)
		(fp_line
			(start -0.12065 0.3048)
			(end -0.67945 0.3048)
			(stroke
				(width 0.1)
				(type default)
			)
			(layer "F.Fab")
		)
		(fp_line
			(start -0.67945 0.3048)
			(end -0.67945 -0.305054)
			(stroke
				(width 0.1)
				(type default)
			)
			(layer "F.Fab")
		)
		(pad "1" smd circle
			(at -0.40005 0 90)
			(size 0 0)
			(layers "F.Cu" "F.Mask" "F.Paste")
			(net "P1V8_RETIMER_CPU1_FB")
		)
		(pad "2" smd circle
			(at 0.40005 0 90)
			(size 0 0)
			(layers "F.Cu" "F.Mask" "F.Paste")
			(net "P1V8_CPU1_RT_1D")
		)
	)
	(footprint ""
		(layer "F.Cu")
		(at 448.939666 -401.93087)
		(property "Reference" "PC6555_1"
			(at 0 0 0)
			(layer "F.SilkS")
			(hide yes)
			(effects
				(font
					(size 1.27 1.27)
				)
			)
		)
		(property "Value" ""
			(at 0 0 0)
			(layer "F.Fab")
			(effects
				(font
					(size 1.27 1.27)
				)
			)
		)
		(duplicate_pad_numbers_are_jumpers no)
		(fp_line
			(start -0.7874 -0.4064)
			(end 0.7874 -0.4064)
			(stroke
				(width 0.1524)
				(type default)
			)
			(layer "F.SilkS")
		)
		(fp_line
			(start -0.7874 0.4064)
			(end -0.7874 -0.4064)
			(stroke
				(width 0.1524)
				(type default)
			)
			(layer "F.SilkS")
		)
		(fp_line
			(start 0.7874 -0.4064)
			(end 0.7874 0.4064)
			(stroke
				(width 0.1524)
				(type default)
			)
			(layer "F.SilkS")
		)
		(fp_line
			(start 0.7874 0.4064)
			(end -0.7874 0.4064)
			(stroke
				(width 0.1524)
				(type default)
			)
			(layer "F.SilkS")
		)
		(fp_line
			(start -0.67945 -0.305054)
			(end -0.12065 -0.305054)
			(stroke
				(width 0.1)
				(type default)
			)
			(layer "F.Fab")
		)
		(fp_line
			(start -0.67945 0.3048)
			(end -0.67945 -0.305054)
			(stroke
				(width 0.1)
				(type default)
			)
			(layer "F.Fab")
		)
		(fp_line
			(start -0.12065 -0.305054)
			(end -0.12065 -0.2794)
			(stroke
				(width 0.1)
				(type default)
			)
			(layer "F.Fab")
		)
		(fp_line
			(start -0.12065 -0.2794)
			(end 0.12065 -0.2794)
			(stroke
				(width 0.1)
				(type default)
			)
			(layer "F.Fab")
		)
		(fp_line
			(start -0.12065 0.2794)
			(end -0.12065 0.3048)
			(stroke
				(width 0.1)
				(type default)
			)
			(layer "F.Fab")
		)
		(fp_line
			(start -0.12065 0.3048)
			(end -0.67945 0.3048)
			(stroke
				(width 0.1)
				(type default)
			)
			(layer "F.Fab")
		)
		(fp_line
			(start 0.120396 0.2794)
			(end -0.12065 0.2794)
			(stroke
				(width 0.1)
				(type default)
			)
			(layer "F.Fab")
		)
		(fp_line
			(start 0.120396 0.3048)
			(end 0.120396 0.2794)
			(stroke
				(width 0.1)
				(type default)
			)
			(layer "F.Fab")
		)
		(fp_line
			(start 0.12065 -0.3048)
			(end 0.67945 -0.3048)
			(stroke
				(width 0.1)
				(type default)
			)
			(layer "F.Fab")
		)
		(fp_line
			(start 0.12065 -0.2794)
			(end 0.12065 -0.3048)
			(stroke
				(width 0.1)
				(type default)
			)
			(layer "F.Fab")
		)
		(fp_line
			(start 0.67945 -0.3048)
			(end 0.67945 0.3048)
			(stroke
				(width 0.1)
				(type default)
			)
			(layer "F.Fab")
		)
		(fp_line
			(start 0.67945 0.3048)
			(end 0.120396 0.3048)
			(stroke
				(width 0.1)
				(type default)
			)
			(layer "F.Fab")
		)
		(pad "1" smd circle
			(at -0.40005 0)
			(size 0 0)
			(layers "F.Cu" "F.Mask" "F.Paste")
			(net "SW_P12V_AUX_P0V9_RETIMER_CPU0_FLT")
		)
		(pad "2" smd circle
			(at 0.40005 0)
			(size 0 0)
			(layers "F.Cu" "F.Mask" "F.Paste")
			(net "GND")
		)
	)
	(footprint ""
		(layer "F.Cu")
		(at 350.631506 -416.899344 -90)
		(property "Reference" "C6531"
			(at 0 0 270)
			(layer "F.SilkS")
			(hide yes)
			(effects
				(font
					(size 1.27 1.27)
				)
			)
		)
		(property "Value" ""
			(at 0 0 270)
			(layer "F.Fab")
			(effects
				(font
					(size 1.27 1.27)
				)
			)
		)
		(duplicate_pad_numbers_are_jumpers no)
		(fp_line
			(start -0.299974 0.150114)
			(end -0.299974 -0.150114)
			(stroke
				(width 0.1)
				(type default)
			)
			(layer "F.Fab")
		)
		(fp_line
			(start 0.299974 0.150114)
			(end -0.299974 0.150114)
			(stroke
				(width 0.1)
				(type default)
			)
			(layer "F.Fab")
		)
		(fp_line
			(start -0.299974 -0.150114)
			(end 0.299974 -0.150114)
			(stroke
				(width 0.1)
				(type default)
			)
			(layer "F.Fab")
		)
		(fp_line
			(start 0.299974 -0.150114)
			(end 0.299974 0.150114)
			(stroke
				(width 0.1)
				(type default)
			)
			(layer "F.Fab")
		)
		(pad "1" smd rect
			(at -0.2667 0 270)
			(size 0.3048 0.381)
			(layers "F.Cu" "F.Mask" "F.Paste")
			(net "P5E_CPU0_P0_TX_BUF_C_DP<15>")
		)
		(pad "2" smd rect
			(at 0.2667 0 270)
			(size 0.3048 0.381)
			(layers "F.Cu" "F.Mask" "F.Paste")
			(net "P5E_CPU0_P0_TX_BUF_DP<15>")
		)
	)
	(footprint ""
		(layer "F.Cu")
		(at 47.45482 -102.41534 90)
		(property "Reference" "U60"
			(at -1.25476 -1.89357 90)
			(unlocked yes)
			(layer "F.SilkS")
			(effects
				(font
					(size 0.7874 0.5842)
					(thickness 0.1524)
				)
				(justify left)
			)
		)
		(property "Value" ""
			(at 0 0 90)
			(layer "F.Fab")
			(effects
				(font
					(size 1.27 1.27)
				)
			)
		)
		(duplicate_pad_numbers_are_jumpers no)
		(fp_line
			(start 1.335278 -1.100074)
			(end -1.335278 -1.100074)
			(stroke
				(width 0.1524)
				(type default)
			)
			(layer "F.SilkS")
		)
		(fp_line
			(start -1.335278 -1.100074)
			(end -1.335278 1.100074)
			(stroke
				(width 0.1524)
				(type default)
			)
			(layer "F.SilkS")
		)
		(fp_line
			(start 1.335278 1.100074)
			(end 1.335278 -1.100074)
			(stroke
				(width 0.1524)
				(type default)
			)
			(layer "F.SilkS")
		)
		(fp_line
			(start -1.335278 1.100074)
			(end 1.335278 1.100074)
			(stroke
				(width 0.1524)
				(type default)
			)
			(layer "F.SilkS")
		)
		(fp_line
			(start 0.674878 -1.100074)
			(end -0.674878 -1.100074)
			(stroke
				(width 0.1)
				(type default)
			)
			(layer "F.Fab")
		)
		(fp_line
			(start -0.674878 -1.100074)
			(end -0.674878 1.100074)
			(stroke
				(width 0.1)
				(type default)
			)
			(layer "F.Fab")
		)
		(fp_line
			(start 0.674878 1.100074)
			(end 0.674878 -1.100074)
			(stroke
				(width 0.1)
				(type default)
			)
			(layer "F.Fab")
		)
		(fp_line
			(start -0.674878 1.100074)
			(end 0.674878 1.100074)
			(stroke
				(width 0.1)
				(type default)
			)
			(layer "F.Fab")
		)
		(pad "1" smd rect
			(at -0.8001 0.649986)
			(size 0.6096 0.8128)
			(layers "F.Cu" "F.Mask" "F.Paste")
			(net "P3V3_AUX_DSC_VOL")
		)
		(pad "2" smd rect
			(at -0.8001 -0.649986)
			(size 0.6096 0.8128)
			(layers "F.Cu" "F.Mask" "F.Paste")
			(net "Net_10856")
		)
		(pad "3" smd rect
			(at 0.8001 0)
			(size 0.6096 0.8128)
			(layers "F.Cu" "F.Mask" "F.Paste")
			(net "P3V3_AUX_DSC_S1")
		)
	)
	(footprint ""
		(layer "F.Cu")
		(at 25.640792 -388.854188)
		(property "Reference" "PU6512"
			(at 2.525014 -4.833874 0)
			(unlocked yes)
			(layer "F.SilkS")
			(effects
				(font
					(size 0.7874 0.5842)
					(thickness 0.1524)
				)
				(justify left)
			)
		)
		(property "Value" ""
			(at 0 0 0)
			(layer "F.Fab")
			(effects
				(font
					(size 1.27 1.27)
				)
			)
		)
		(duplicate_pad_numbers_are_jumpers no)
		(fp_line
			(start -2.500122 -2.999994)
			(end -2.24409 -2.999994)
			(stroke
				(width 0.1524)
				(type default)
			)
			(layer "F.SilkS")
		)
		(fp_line
			(start -2.500122 -2.529078)
			(end -2.500122 -2.999994)
			(stroke
				(width 0.1524)
				(type default)
			)
			(layer "F.SilkS")
		)
		(fp_line
			(start -2.500122 0.6604)
			(end -2.500122 0.229108)
			(stroke
				(width 0.1524)
				(type default)
			)
			(layer "F.SilkS")
		)
		(fp_line
			(start -2.500122 2.999994)
			(end -2.500122 2.339594)
			(stroke
				(width 0.1524)
				(type default)
			)
			(layer "F.SilkS")
		)
		(fp_line
			(start -2.2987 2.999994)
			(end -2.500122 2.999994)
			(stroke
				(width 0.1524)
				(type default)
			)
			(layer "F.SilkS")
		)
		(fp_line
			(start 2.31394 -2.999994)
			(end 2.500122 -2.999994)
			(stroke
				(width 0.1524)
				(type default)
			)
			(layer "F.SilkS")
		)
		(fp_line
			(start 2.500122 -2.999994)
			(end 2.500122 -2.44348)
			(stroke
				(width 0.1524)
				(type default)
			)
			(layer "F.SilkS")
		)
		(fp_line
			(start 2.500122 2.339594)
			(end 2.500122 2.999994)
			(stroke
				(width 0.1524)
				(type default)
			)
			(layer "F.SilkS")
		)
		(fp_line
			(start 2.500122 2.999994)
			(end 2.2987 2.999994)
			(stroke
				(width 0.1524)
				(type default)
			)
			(layer "F.SilkS")
		)
		(fp_poly
			(pts
				(xy -3.14071 -3.573272) (xy -3.853942 -2.84988) (xy -2.773426 -2.498344)
			)
			(stroke
				(width 0)
				(type default)
			)
			(fill yes)
			(layer "F.SilkS")
		)
		(fp_line
			(start -2.500122 -2.999994)
			(end 2.500122 -2.999994)
			(stroke
				(width 0.1)
				(type default)
			)
			(layer "F.Fab")
		)
		(fp_line
			(start -2.500122 2.999994)
			(end -2.500122 -2.999994)
			(stroke
				(width 0.1)
				(type default)
			)
			(layer "F.Fab")
		)
		(fp_line
			(start 2.500122 -2.999994)
			(end 2.500122 2.999994)
			(stroke
				(width 0.1)
				(type default)
			)
			(layer "F.Fab")
		)
		(fp_line
			(start 2.500122 2.999994)
			(end -2.500122 2.999994)
			(stroke
				(width 0.1)
				(type default)
			)
			(layer "F.Fab")
		)
		(fp_poly
			(pts
				(xy -4.218432 -2.783078) (xy -4.218432 -1.767078) (xy -3.202432 -2.275078)
			)
			(stroke
				(width 0)
				(type default)
			)
			(fill yes)
			(layer "F.Fab")
		)
		(pad "1" smd rect
			(at -2.400046 -2.275078 90)
			(size 0.2286 0.6096)
			(layers "F.Cu" "F.Mask" "F.Paste")
			(net "P0V9_RETIMER_CPU1_VOS2")
		)
		(pad "2" smd rect
			(at -2.400046 -1.82499 90)
			(size 0.2286 0.6096)
			(layers "F.Cu" "F.Mask" "F.Paste")
			(net "GND")
		)
		(pad "3" smd rect
			(at -2.400046 -1.374902 90)
			(size 0.2286 0.6096)
			(layers "F.Cu" "F.Mask" "F.Paste")
			(net "P0V9_RETIMER_CPU1_VCC2")
		)
		(pad "4" smd rect
			(at -2.400046 -0.925068 90)
			(size 0.2286 0.6096)
			(layers "F.Cu" "F.Mask" "F.Paste")
			(net "P0V9_RETIMER_CPU1_PVCC")
		)
		(pad "5" smd rect
			(at -2.400046 -0.47498 90)
			(size 0.2286 0.6096)
			(layers "F.Cu" "F.Mask" "F.Paste")
			(net "GND")
		)
		(pad "6" smd rect
			(at -2.400046 -0.024892 90)
			(size 0.2286 0.6096)
			(layers "F.Cu" "F.Mask" "F.Paste")
			(net "NC_PV09_RETIMER_CPU1_GL1_2")
		)
		(pad "7_9-20_24" smd circle
			(at 0 1.150112 90)
			(size 0 0)
			(layers "F.Cu" "F.Mask" "F.Paste")
			(net "GND")
		)
		(pad "10_19" smd rect
			(at 0 2.899918 90)
			(size 0.6096 4.318)
			(layers "F.Cu" "F.Mask" "F.Paste")
			(net "SW_P0V9_RETIMER_CPU1_SW2")
		)
		(pad "25_29" smd rect
			(at 1.549908 -1.279906 270)
			(size 2.0574 2.3114)
			(layers "F.Cu" "F.Mask" "F.Paste")
			(net "SW_P12V_AUX_P0V9_RETIMER_CPU1_FLT")
		)
		(pad "30" smd rect
			(at 2.05994 -2.899918)
			(size 0.2286 0.6096)
			(layers "F.Cu" "F.Mask" "F.Paste")
			(net "SW_P12V_AUX_P0V9_RETIMER_CPU1_FLT")
		)
		(pad "31" smd rect
			(at 1.610106 -2.899918)
			(size 0.2286 0.6096)
			(layers "F.Cu" "F.Mask" "F.Paste")
			(net "NC_PV09_RETIMER_CPU1_DNC2")
		)
		(pad "32" smd rect
			(at 1.160018 -2.899918)
			(size 0.2286 0.6096)
			(layers "F.Cu" "F.Mask" "F.Paste")
			(net "SW_P0V9_RETIMER_CPU1_PH2")
		)
		(pad "33" smd rect
			(at 0.70993 -2.899918)
			(size 0.2286 0.6096)
			(layers "F.Cu" "F.Mask" "F.Paste")
			(net "SW_P0V9_RETIMER_CPU1_BOOT2")
		)
		(pad "34" smd rect
			(at 0.260096 -2.899918)
			(size 0.2286 0.6096)
			(layers "F.Cu" "F.Mask" "F.Paste")
			(net "P0V9_RETIMER_CPU1_PWM2")
		)
		(pad "35" smd rect
			(at -0.189992 -2.899918)
			(size 0.2286 0.6096)
			(layers "F.Cu" "F.Mask" "F.Paste")
			(net "P0V9_RETIMER_CPU1_VCC2")
		)
		(pad "36" smd rect
			(at -0.64008 -2.899918)
			(size 0.2286 0.6096)
			(layers "F.Cu" "F.Mask" "F.Paste")
			(net "P0V9_RETIMER_CPU1_TEMP0")
		)
		(pad "37" smd rect
			(at -1.089914 -2.899918)
			(size 0.2286 0.6096)
			(layers "F.Cu" "F.Mask" "F.Paste")
			(net "P0V9_RETIMER_CPU1_LSET2")
		)
		(pad "38" smd rect
			(at -1.540002 -2.899918)
			(size 0.2286 0.6096)
			(layers "F.Cu" "F.Mask" "F.Paste")
			(net "P0V9_RETIMER_CPU1_IMON2")
		)
		(pad "39" smd rect
			(at -1.99009 -2.899918)
			(size 0.2286 0.6096)
			(layers "F.Cu" "F.Mask" "F.Paste")
			(net "PV09_RETIMER_CPU1_VCCS")
		)
		(pad "40" smd rect
			(at -0.87503 -1.27508)
			(size 1.7526 1.9558)
			(layers "F.Cu" "F.Mask" "F.Paste")
			(net "GND")
		)
		(pad "41" smd rect
			(at -1.525016 0.249936 270)
			(size 0.3048 0.4572)
			(layers "F.Cu" "F.Mask" "F.Paste")
			(net "NC_PV09_RETIMER_CPU1_GL2_2")
		)
		(zone
			(layer "F.Cu")
			(hatch none 0.5)
			(connect_pads
				(clearance 0)
			)
			(min_thickness 0.25)
			(keepout
				(tracks not_allowed)
				(vias allowed)
				(pads allowed)
				(copperpour not_allowed)
				(footprints allowed)
			)
			(placement
				(enabled no)
				(sheetname "")
			)
			(fill
				(thermal_gap 0.5)
				(thermal_bridge_width 0.5)
				(island_removal_mode 0)
			)
			(polygon
				(pts
					(xy 23.14067 -385.854194) (xy 23.14067 -386.603494) (xy 28.140914 -386.603494) (xy 28.140914 -385.854194)
					(xy 27.850592 -385.854194) (xy 27.850592 -386.30987) (xy 23.430992 -386.30987) (xy 23.430992 -385.854194)
				)
			)
		)
		(zone
			(layer "F.Cu")
			(hatch none 0.5)
			(connect_pads
				(clearance 0)
			)
			(min_thickness 0.25)
			(keepout
				(tracks not_allowed)
				(vias allowed)
				(pads allowed)
				(copperpour not_allowed)
				(footprints allowed)
			)
			(placement
				(enabled no)
				(sheetname "")
			)
			(fill
				(thermal_gap 0.5)
				(thermal_bridge_width 0.5)
				(island_removal_mode 0)
			)
			(polygon
				(pts
					(xy 23.14067 -388.104888) (xy 23.14067 -388.56158) (xy 23.836376 -388.56158) (xy 23.836376 -388.401052)
					(xy 24.395176 -388.401052) (xy 24.395176 -388.807452) (xy 23.836376 -388.807452) (xy 23.836376 -388.58698)
					(xy 23.14067 -388.58698) (xy 23.14067 -388.71398) (xy 23.596346 -388.71398) (xy 23.596346 -390.891522)
					(xy 23.838662 -390.891522) (xy 23.838662 -389.100568) (xy 25.692862 -389.100568) (xy 25.692862 -391.157968)
					(xy 23.838662 -391.157968) (xy 23.838662 -390.916922) (xy 23.596346 -390.916922) (xy 23.596346 -391.398506)
					(xy 28.140914 -391.398506) (xy 28.140914 -391.213594) (xy 25.9842 -391.213594) (xy 25.9842 -389.054594)
					(xy 28.140914 -389.054594) (xy 28.140914 -388.804912) (xy 24.69007 -388.804912) (xy 24.69007 -388.104888)
				)
			)
		)
	)
	(footprint ""
		(layer "F.Cu")
		(at 117.895624 -261.255256 180)
		(property "Reference" "C2273"
			(at 0 0 180)
			(layer "F.SilkS")
			(hide yes)
			(effects
				(font
					(size 1.27 1.27)
				)
			)
		)
		(property "Value" ""
			(at 0 0 180)
			(layer "F.Fab")
			(effects
				(font
					(size 1.27 1.27)
				)
			)
		)
		(duplicate_pad_numbers_are_jumpers no)
		(fp_line
			(start 0.7874 0.4064)
			(end -0.7874 0.4064)
			(stroke
				(width 0.1524)
				(type default)
			)
			(layer "F.SilkS")
		)
		(fp_line
			(start 0.7874 -0.4064)
			(end 0.7874 0.4064)
			(stroke
				(width 0.1524)
				(type default)
			)
			(layer "F.SilkS")
		)
		(fp_line
			(start -0.7874 0.4064)
			(end -0.7874 -0.4064)
			(stroke
				(width 0.1524)
				(type default)
			)
			(layer "F.SilkS")
		)
		(fp_line
			(start -0.7874 -0.4064)
			(end 0.7874 -0.4064)
			(stroke
				(width 0.1524)
				(type default)
			)
			(layer "F.SilkS")
		)
		(fp_line
			(start 0.67945 0.3048)
			(end 0.120396 0.3048)
			(stroke
				(width 0.1)
				(type default)
			)
			(layer "F.Fab")
		)
		(fp_line
			(start 0.67945 -0.3048)
			(end 0.67945 0.3048)
			(stroke
				(width 0.1)
				(type default)
			)
			(layer "F.Fab")
		)
		(fp_line
			(start 0.12065 -0.2794)
			(end 0.12065 -0.3048)
			(stroke
				(width 0.1)
				(type default)
			)
			(layer "F.Fab")
		)
		(fp_line
			(start 0.12065 -0.3048)
			(end 0.67945 -0.3048)
			(stroke
				(width 0.1)
				(type default)
			)
			(layer "F.Fab")
		)
		(fp_line
			(start 0.120396 0.3048)
			(end 0.120396 0.2794)
			(stroke
				(width 0.1)
				(type default)
			)
			(layer "F.Fab")
		)
		(fp_line
			(start 0.120396 0.2794)
			(end -0.12065 0.2794)
			(stroke
				(width 0.1)
				(type default)
			)
			(layer "F.Fab")
		)
		(fp_line
			(start -0.12065 0.3048)
			(end -0.67945 0.3048)
			(stroke
				(width 0.1)
				(type default)
			)
			(layer "F.Fab")
		)
		(fp_line
			(start -0.12065 0.2794)
			(end -0.12065 0.3048)
			(stroke
				(width 0.1)
				(type default)
			)
			(layer "F.Fab")
		)
		(fp_line
			(start -0.12065 -0.2794)
			(end 0.12065 -0.2794)
			(stroke
				(width 0.1)
				(type default)
			)
			(layer "F.Fab")
		)
		(fp_line
			(start -0.12065 -0.305054)
			(end -0.12065 -0.2794)
			(stroke
				(width 0.1)
				(type default)
			)
			(layer "F.Fab")
		)
		(fp_line
			(start -0.67945 0.3048)
			(end -0.67945 -0.305054)
			(stroke
				(width 0.1)
				(type default)
			)
			(layer "F.Fab")
		)
		(fp_line
			(start -0.67945 -0.305054)
			(end -0.12065 -0.305054)
			(stroke
				(width 0.1)
				(type default)
			)
			(layer "F.Fab")
		)
		(pad "1" smd circle
			(at -0.40005 0 180)
			(size 0 0)
			(layers "F.Cu" "F.Mask" "F.Paste")
			(net "PVDDCR_SOC_P1")
		)
		(pad "2" smd circle
			(at 0.40005 0 180)
			(size 0 0)
			(layers "F.Cu" "F.Mask" "F.Paste")
			(net "GND")
		)
	)
	(footprint ""
		(layer "F.Cu")
		(at 208.407 -129.54 90)
		(property "Reference" "R569"
			(at 0 0 90)
			(layer "F.SilkS")
			(hide yes)
			(effects
				(font
					(size 1.27 1.27)
				)
			)
		)
		(property "Value" ""
			(at 0 0 90)
			(layer "F.Fab")
			(effects
				(font
					(size 1.27 1.27)
				)
			)
		)
		(duplicate_pad_numbers_are_jumpers no)
		(fp_line
			(start 0.7874 -0.4064)
			(end 0.7874 0.4064)
			(stroke
				(width 0.1524)
				(type default)
			)
			(layer "F.SilkS")
		)
		(fp_line
			(start -0.7874 -0.4064)
			(end 0.7874 -0.4064)
			(stroke
				(width 0.1524)
				(type default)
			)
			(layer "F.SilkS")
		)
		(fp_line
			(start 0.7874 0.4064)
			(end -0.7874 0.4064)
			(stroke
				(width 0.1524)
				(type default)
			)
			(layer "F.SilkS")
		)
		(fp_line
			(start -0.7874 0.4064)
			(end -0.7874 -0.4064)
			(stroke
				(width 0.1524)
				(type default)
			)
			(layer "F.SilkS")
		)
		(fp_line
			(start -0.12065 -0.305054)
			(end -0.12065 -0.2794)
			(stroke
				(width 0.1)
				(type default)
			)
			(layer "F.Fab")
		)
		(fp_line
			(start -0.67945 -0.305054)
			(end -0.12065 -0.305054)
			(stroke
				(width 0.1)
				(type default)
			)
			(layer "F.Fab")
		)
		(fp_line
			(start 0.67945 -0.3048)
			(end 0.67945 0.3048)
			(stroke
				(width 0.1)
				(type default)
			)
			(layer "F.Fab")
		)
		(fp_line
			(start 0.12065 -0.3048)
			(end 0.67945 -0.3048)
			(stroke
				(width 0.1)
				(type default)
			)
			(layer "F.Fab")
		)
		(fp_line
			(start 0.12065 -0.2794)
			(end 0.12065 -0.3048)
			(stroke
				(width 0.1)
				(type default)
			)
			(layer "F.Fab")
		)
		(fp_line
			(start -0.12065 -0.2794)
			(end 0.12065 -0.2794)
			(stroke
				(width 0.1)
				(type default)
			)
			(layer "F.Fab")
		)
		(fp_line
			(start 0.120396 0.2794)
			(end -0.12065 0.2794)
			(stroke
				(width 0.1)
				(type default)
			)
			(layer "F.Fab")
		)
		(fp_line
			(start -0.12065 0.2794)
			(end -0.12065 0.3048)
			(stroke
				(width 0.1)
				(type default)
			)
			(layer "F.Fab")
		)
		(fp_line
			(start 0.67945 0.3048)
			(end 0.120396 0.3048)
			(stroke
				(width 0.1)
				(type default)
			)
			(layer "F.Fab")
		)
		(fp_line
			(start 0.120396 0.3048)
			(end 0.120396 0.2794)
			(stroke
				(width 0.1)
				(type default)
			)
			(layer "F.Fab")
		)
		(fp_line
			(start -0.12065 0.3048)
			(end -0.67945 0.3048)
			(stroke
				(width 0.1)
				(type default)
			)
			(layer "F.Fab")
		)
		(fp_line
			(start -0.67945 0.3048)
			(end -0.67945 -0.305054)
			(stroke
				(width 0.1)
				(type default)
			)
			(layer "F.Fab")
		)
		(pad "1" smd circle
			(at -0.40005 0 90)
			(size 0 0)
			(layers "F.Cu" "F.Mask" "F.Paste")
			(net "SW_P3V3_EN_ISO_R")
		)
		(pad "2" smd circle
			(at 0.40005 0 90)
			(size 0 0)
			(layers "F.Cu" "F.Mask" "F.Paste")
			(net "SW_P3V3_EN_ISO")
		)
	)
	(footprint ""
		(layer "F.Cu")
		(at 324.168262 -402.7424 -90)
		(property "Reference" "R970"
			(at 0 0 270)
			(layer "F.SilkS")
			(hide yes)
			(effects
				(font
					(size 1.27 1.27)
				)
			)
		)
		(property "Value" ""
			(at 0 0 270)
			(layer "F.Fab")
			(effects
				(font
					(size 1.27 1.27)
				)
			)
		)
		(duplicate_pad_numbers_are_jumpers no)
		(fp_line
			(start -0.32512 0.175006)
			(end -0.32512 -0.175006)
			(stroke
				(width 0.1)
				(type default)
			)
			(layer "F.Fab")
		)
		(fp_line
			(start 0.32512 0.175006)
			(end -0.32512 0.175006)
			(stroke
				(width 0.1)
				(type default)
			)
			(layer "F.Fab")
		)
		(fp_line
			(start -0.32512 -0.175006)
			(end 0.32512 -0.175006)
			(stroke
				(width 0.1)
				(type default)
			)
			(layer "F.Fab")
		)
		(fp_line
			(start 0.32512 -0.175006)
			(end 0.32512 0.175006)
			(stroke
				(width 0.1)
				(type default)
			)
			(layer "F.Fab")
		)
		(pad "1" smd rect
			(at -0.2667 0 270)
			(size 0.3048 0.381)
			(layers "F.Cu" "F.Mask" "F.Paste")
			(net "RST_RT_CPU0_P0_PERST_R_N")
		)
		(pad "2" smd rect
			(at 0.2667 0 90)
			(size 0.3048 0.381)
			(layers "F.Cu" "F.Mask" "F.Paste")
			(net "GND")
		)
	)
	(footprint ""
		(layer "F.Cu")
		(at 39.15029 -426.563536)
		(property "Reference" "C1868"
			(at 0 0 0)
			(layer "F.SilkS")
			(hide yes)
			(effects
				(font
					(size 1.27 1.27)
				)
			)
		)
		(property "Value" ""
			(at 0 0 0)
			(layer "F.Fab")
			(effects
				(font
					(size 1.27 1.27)
				)
			)
		)
		(duplicate_pad_numbers_are_jumpers no)
		(fp_line
			(start -0.7874 -0.4064)
			(end 0.7874 -0.4064)
			(stroke
				(width 0.1524)
				(type default)
			)
			(layer "F.SilkS")
		)
		(fp_line
			(start -0.33909 0.4064)
			(end -0.7874 0.4064)
			(stroke
				(width 0.1524)
				(type default)
			)
			(layer "F.SilkS")
		)
		(fp_line
			(start 0.7874 -0.4064)
			(end 0.7874 0.275336)
			(stroke
				(width 0.1524)
				(type default)
			)
			(layer "F.SilkS")
		)
		(fp_line
			(start -0.6858 -0.3048)
			(end -0.1016 -0.3048)
			(stroke
				(width 0.1)
				(type default)
			)
			(layer "F.Fab")
		)
		(fp_line
			(start -0.6858 0.3048)
			(end -0.6858 -0.3048)
			(stroke
				(width 0.1)
				(type default)
			)
			(layer "F.Fab")
		)
		(fp_line
			(start -0.1016 -0.3048)
			(end -0.1016 -0.2794)
			(stroke
				(width 0.1)
				(type default)
			)
			(layer "F.Fab")
		)
		(fp_line
			(start -0.1016 -0.2794)
			(end 0.1016 -0.2794)
			(stroke
				(width 0.1)
				(type default)
			)
			(layer "F.Fab")
		)
		(fp_line
			(start -0.1016 0.2794)
			(end -0.1016 0.3048)
			(stroke
				(width 0.1)
				(type default)
			)
			(layer "F.Fab")
		)
		(fp_line
			(start -0.1016 0.3048)
			(end -0.6858 0.3048)
			(stroke
				(width 0.1)
				(type default)
			)
			(layer "F.Fab")
		)
		(fp_line
			(start 0.1016 -0.3048)
			(end 0.6858 -0.3048)
			(stroke
				(width 0.1)
				(type default)
			)
			(layer "F.Fab")
		)
		(fp_line
			(start 0.1016 -0.2794)
			(end 0.1016 -0.3048)
			(stroke
				(width 0.1)
				(type default)
			)
			(layer "F.Fab")
		)
		(fp_line
			(start 0.1016 0.2794)
			(end -0.1016 0.2794)
			(stroke
				(width 0.1)
				(type default)
			)
			(layer "F.Fab")
		)
		(fp_line
			(start 0.1016 0.3048)
			(end 0.1016 0.2794)
			(stroke
				(width 0.1)
				(type default)
			)
			(layer "F.Fab")
		)
		(fp_line
			(start 0.6858 -0.3048)
			(end 0.6858 0.3048)
			(stroke
				(width 0.1)
				(type default)
			)
			(layer "F.Fab")
		)
		(fp_line
			(start 0.6858 0.3048)
			(end 0.1016 0.3048)
			(stroke
				(width 0.1)
				(type default)
			)
			(layer "F.Fab")
		)
		(pad "1" smd rect
			(at -0.40005 0 180)
			(size 0.4572 0.508)
			(layers "F.Cu" "F.Mask" "F.Paste")
			(net "P2E_MB_BMC_RX_BUF_C_DP<0>")
		)
		(pad "2" smd rect
			(at 0.40005 0 180)
			(size 0.4572 0.508)
			(layers "F.Cu" "F.Mask" "F.Paste")
			(net "P2E_MB_BMC_RX_BUF_DP<0>")
		)
	)
	(footprint ""
		(layer "F.Cu")
		(at 366.36579 -393.04468)
		(property "Reference" "R1113"
			(at 0 0 0)
			(layer "F.SilkS")
			(hide yes)
			(effects
				(font
					(size 1.27 1.27)
				)
			)
		)
		(property "Value" ""
			(at 0 0 0)
			(layer "F.Fab")
			(effects
				(font
					(size 1.27 1.27)
				)
			)
		)
		(duplicate_pad_numbers_are_jumpers no)
		(fp_line
			(start -0.32512 -0.175006)
			(end 0.32512 -0.175006)
			(stroke
				(width 0.1)
				(type default)
			)
			(layer "F.Fab")
		)
		(fp_line
			(start -0.32512 0.175006)
			(end -0.32512 -0.175006)
			(stroke
				(width 0.1)
				(type default)
			)
			(layer "F.Fab")
		)
		(fp_line
			(start 0.32512 -0.175006)
			(end 0.32512 0.175006)
			(stroke
				(width 0.1)
				(type default)
			)
			(layer "F.Fab")
		)
		(fp_line
			(start 0.32512 0.175006)
			(end -0.32512 0.175006)
			(stroke
				(width 0.1)
				(type default)
			)
			(layer "F.Fab")
		)
		(pad "1" smd rect
			(at -0.2667 0)
			(size 0.3048 0.381)
			(layers "F.Cu" "F.Mask" "F.Paste")
			(net "GPIO3_RT_CPU0_P3")
		)
		(pad "2" smd rect
			(at 0.2667 0 180)
			(size 0.3048 0.381)
			(layers "F.Cu" "F.Mask" "F.Paste")
			(net "GND")
		)
	)
	(footprint ""
		(layer "F.Cu")
		(at 321.107308 -104.42575)
		(property "Reference" "R1305"
			(at 0 0 0)
			(layer "F.SilkS")
			(hide yes)
			(effects
				(font
					(size 1.27 1.27)
				)
			)
		)
		(property "Value" ""
			(at 0 0 0)
			(layer "F.Fab")
			(effects
				(font
					(size 1.27 1.27)
				)
			)
		)
		(duplicate_pad_numbers_are_jumpers no)
		(fp_line
			(start -0.7874 -0.4064)
			(end 0.7874 -0.4064)
			(stroke
				(width 0.1524)
				(type default)
			)
			(layer "F.SilkS")
		)
		(fp_line
			(start -0.7874 0.4064)
			(end -0.7874 -0.4064)
			(stroke
				(width 0.1524)
				(type default)
			)
			(layer "F.SilkS")
		)
		(fp_line
			(start 0.7874 -0.4064)
			(end 0.7874 0.4064)
			(stroke
				(width 0.1524)
				(type default)
			)
			(layer "F.SilkS")
		)
		(fp_line
			(start 0.7874 0.4064)
			(end -0.7874 0.4064)
			(stroke
				(width 0.1524)
				(type default)
			)
			(layer "F.SilkS")
		)
		(fp_line
			(start -0.67945 -0.305054)
			(end -0.12065 -0.305054)
			(stroke
				(width 0.1)
				(type default)
			)
			(layer "F.Fab")
		)
		(fp_line
			(start -0.67945 0.3048)
			(end -0.67945 -0.305054)
			(stroke
				(width 0.1)
				(type default)
			)
			(layer "F.Fab")
		)
		(fp_line
			(start -0.12065 -0.305054)
			(end -0.12065 -0.2794)
			(stroke
				(width 0.1)
				(type default)
			)
			(layer "F.Fab")
		)
		(fp_line
			(start -0.12065 -0.2794)
			(end 0.12065 -0.2794)
			(stroke
				(width 0.1)
				(type default)
			)
			(layer "F.Fab")
		)
		(fp_line
			(start -0.12065 0.2794)
			(end -0.12065 0.3048)
			(stroke
				(width 0.1)
				(type default)
			)
			(layer "F.Fab")
		)
		(fp_line
			(start -0.12065 0.3048)
			(end -0.67945 0.3048)
			(stroke
				(width 0.1)
				(type default)
			)
			(layer "F.Fab")
		)
		(fp_line
			(start 0.120396 0.2794)
			(end -0.12065 0.2794)
			(stroke
				(width 0.1)
				(type default)
			)
			(layer "F.Fab")
		)
		(fp_line
			(start 0.120396 0.3048)
			(end 0.120396 0.2794)
			(stroke
				(width 0.1)
				(type default)
			)
			(layer "F.Fab")
		)
		(fp_line
			(start 0.12065 -0.3048)
			(end 0.67945 -0.3048)
			(stroke
				(width 0.1)
				(type default)
			)
			(layer "F.Fab")
		)
		(fp_line
			(start 0.12065 -0.2794)
			(end 0.12065 -0.3048)
			(stroke
				(width 0.1)
				(type default)
			)
			(layer "F.Fab")
		)
		(fp_line
			(start 0.67945 -0.3048)
			(end 0.67945 0.3048)
			(stroke
				(width 0.1)
				(type default)
			)
			(layer "F.Fab")
		)
		(fp_line
			(start 0.67945 0.3048)
			(end 0.120396 0.3048)
			(stroke
				(width 0.1)
				(type default)
			)
			(layer "F.Fab")
		)
		(pad "1" smd circle
			(at -0.40005 0)
			(size 0 0)
			(layers "F.Cu" "F.Mask" "F.Paste")
			(net "GND")
		)
		(pad "2" smd circle
			(at 0.40005 0)
			(size 0 0)
			(layers "F.Cu" "F.Mask" "F.Paste")
			(net "INA230_8_A1")
		)
	)
	(footprint ""
		(layer "F.Cu")
		(at 56.858408 -36.75634 180)
		(property "Reference" "R1521"
			(at 0 0 180)
			(layer "F.SilkS")
			(hide yes)
			(effects
				(font
					(size 1.27 1.27)
				)
			)
		)
		(property "Value" ""
			(at 0 0 180)
			(layer "F.Fab")
			(effects
				(font
					(size 1.27 1.27)
				)
			)
		)
		(duplicate_pad_numbers_are_jumpers no)
		(fp_line
			(start 0.7874 0.4064)
			(end -0.7874 0.4064)
			(stroke
				(width 0.1524)
				(type default)
			)
			(layer "F.SilkS")
		)
		(fp_line
			(start 0.7874 -0.4064)
			(end 0.7874 0.4064)
			(stroke
				(width 0.1524)
				(type default)
			)
			(layer "F.SilkS")
		)
		(fp_line
			(start -0.7874 0.4064)
			(end -0.7874 -0.4064)
			(stroke
				(width 0.1524)
				(type default)
			)
			(layer "F.SilkS")
		)
		(fp_line
			(start -0.7874 -0.4064)
			(end 0.7874 -0.4064)
			(stroke
				(width 0.1524)
				(type default)
			)
			(layer "F.SilkS")
		)
		(fp_line
			(start 0.67945 0.3048)
			(end 0.120396 0.3048)
			(stroke
				(width 0.1)
				(type default)
			)
			(layer "F.Fab")
		)
		(fp_line
			(start 0.67945 -0.3048)
			(end 0.67945 0.3048)
			(stroke
				(width 0.1)
				(type default)
			)
			(layer "F.Fab")
		)
		(fp_line
			(start 0.12065 -0.2794)
			(end 0.12065 -0.3048)
			(stroke
				(width 0.1)
				(type default)
			)
			(layer "F.Fab")
		)
		(fp_line
			(start 0.12065 -0.3048)
			(end 0.67945 -0.3048)
			(stroke
				(width 0.1)
				(type default)
			)
			(layer "F.Fab")
		)
		(fp_line
			(start 0.120396 0.3048)
			(end 0.120396 0.2794)
			(stroke
				(width 0.1)
				(type default)
			)
			(layer "F.Fab")
		)
		(fp_line
			(start 0.120396 0.2794)
			(end -0.12065 0.2794)
			(stroke
				(width 0.1)
				(type default)
			)
			(layer "F.Fab")
		)
		(fp_line
			(start -0.12065 0.3048)
			(end -0.67945 0.3048)
			(stroke
				(width 0.1)
				(type default)
			)
			(layer "F.Fab")
		)
		(fp_line
			(start -0.12065 0.2794)
			(end -0.12065 0.3048)
			(stroke
				(width 0.1)
				(type default)
			)
			(layer "F.Fab")
		)
		(fp_line
			(start -0.12065 -0.2794)
			(end 0.12065 -0.2794)
			(stroke
				(width 0.1)
				(type default)
			)
			(layer "F.Fab")
		)
		(fp_line
			(start -0.12065 -0.305054)
			(end -0.12065 -0.2794)
			(stroke
				(width 0.1)
				(type default)
			)
			(layer "F.Fab")
		)
		(fp_line
			(start -0.67945 0.3048)
			(end -0.67945 -0.305054)
			(stroke
				(width 0.1)
				(type default)
			)
			(layer "F.Fab")
		)
		(fp_line
			(start -0.67945 -0.305054)
			(end -0.12065 -0.305054)
			(stroke
				(width 0.1)
				(type default)
			)
			(layer "F.Fab")
		)
		(pad "1" smd circle
			(at -0.40005 0 180)
			(size 0 0)
			(layers "F.Cu" "F.Mask" "F.Paste")
			(net "P12V_OCP_V3_2_BUF_EN_R")
		)
		(pad "2" smd circle
			(at 0.40005 0 180)
			(size 0 0)
			(layers "F.Cu" "F.Mask" "F.Paste")
			(net "P3V3_OCP_EN_2")
		)
	)
	(footprint ""
		(layer "F.Cu")
		(at 42.3164 -396.0368 -90)
		(property "Reference" "L4"
			(at -3.60553 2.3114 0)
			(unlocked yes)
			(layer "F.SilkS")
			(effects
				(font
					(size 0.7874 0.5842)
					(thickness 0.1524)
				)
				(justify left)
			)
		)
		(property "Value" ""
			(at 0 0 270)
			(layer "F.Fab")
			(effects
				(font
					(size 1.27 1.27)
				)
			)
		)
		(duplicate_pad_numbers_are_jumpers no)
		(fp_line
			(start -2.249932 2.249932)
			(end -2.249932 1.3843)
			(stroke
				(width 0.1524)
				(type default)
			)
			(layer "F.SilkS")
		)
		(fp_line
			(start 2.249932 2.249932)
			(end -2.249932 2.249932)
			(stroke
				(width 0.1524)
				(type default)
			)
			(layer "F.SilkS")
		)
		(fp_line
			(start 2.249932 1.3843)
			(end 2.249932 2.249932)
			(stroke
				(width 0.1524)
				(type default)
			)
			(layer "F.SilkS")
		)
		(fp_line
			(start -2.249932 -1.3843)
			(end -2.249932 -2.249932)
			(stroke
				(width 0.1524)
				(type default)
			)
			(layer "F.SilkS")
		)
		(fp_line
			(start -2.249932 -2.249932)
			(end 2.249932 -2.249932)
			(stroke
				(width 0.1524)
				(type default)
			)
			(layer "F.SilkS")
		)
		(fp_line
			(start 2.249932 -2.249932)
			(end 2.249932 -1.3843)
			(stroke
				(width 0.1524)
				(type default)
			)
			(layer "F.SilkS")
		)
		(fp_line
			(start -2.249932 2.249932)
			(end -2.249932 -2.249932)
			(stroke
				(width 0.1)
				(type default)
			)
			(layer "F.Fab")
		)
		(fp_line
			(start 2.249932 2.249932)
			(end -2.249932 2.249932)
			(stroke
				(width 0.1)
				(type default)
			)
			(layer "F.Fab")
		)
		(fp_line
			(start -2.249932 -2.249932)
			(end 2.249932 -2.249932)
			(stroke
				(width 0.1)
				(type default)
			)
			(layer "F.Fab")
		)
		(fp_line
			(start 2.249932 -2.249932)
			(end 2.249932 2.249932)
			(stroke
				(width 0.1)
				(type default)
			)
			(layer "F.Fab")
		)
		(pad "1" smd rect
			(at -1.82499 0 270)
			(size 1.0668 2.5146)
			(layers "F.Cu" "F.Mask" "F.Paste")
			(net "P0V9_CPU1_RT_2D")
		)
		(pad "2" smd rect
			(at 1.82499 0 270)
			(size 1.0668 2.5146)
			(layers "F.Cu" "F.Mask" "F.Paste")
			(net "P0V9_CPU1_RT0_2A")
		)
	)
	(footprint ""
		(layer "F.Cu")
		(at 187.563506 -351.319084 -90)
		(property "Reference" "PC508_11P1_2"
			(at 0 0 270)
			(layer "F.SilkS")
			(hide yes)
			(effects
				(font
					(size 1.27 1.27)
				)
			)
		)
		(property "Value" ""
			(at 0 0 270)
			(layer "F.Fab")
			(effects
				(font
					(size 1.27 1.27)
				)
			)
		)
		(duplicate_pad_numbers_are_jumpers no)
		(fp_line
			(start -0.7874 0.4064)
			(end -0.7874 -0.4064)
			(stroke
				(width 0.1524)
				(type default)
			)
			(layer "F.SilkS")
		)
		(fp_line
			(start 0.7874 0.4064)
			(end -0.7874 0.4064)
			(stroke
				(width 0.1524)
				(type default)
			)
			(layer "F.SilkS")
		)
		(fp_line
			(start -0.7874 -0.4064)
			(end 0.7874 -0.4064)
			(stroke
				(width 0.1524)
				(type default)
			)
			(layer "F.SilkS")
		)
		(fp_line
			(start 0.7874 -0.4064)
			(end 0.7874 0.4064)
			(stroke
				(width 0.1524)
				(type default)
			)
			(layer "F.SilkS")
		)
		(fp_line
			(start -0.67945 0.3048)
			(end -0.67945 -0.305054)
			(stroke
				(width 0.1)
				(type default)
			)
			(layer "F.Fab")
		)
		(fp_line
			(start -0.12065 0.3048)
			(end -0.67945 0.3048)
			(stroke
				(width 0.1)
				(type default)
			)
			(layer "F.Fab")
		)
		(fp_line
			(start 0.120396 0.3048)
			(end 0.120396 0.2794)
			(stroke
				(width 0.1)
				(type default)
			)
			(layer "F.Fab")
		)
		(fp_line
			(start 0.67945 0.3048)
			(end 0.120396 0.3048)
			(stroke
				(width 0.1)
				(type default)
			)
			(layer "F.Fab")
		)
		(fp_line
			(start -0.12065 0.2794)
			(end -0.12065 0.3048)
			(stroke
				(width 0.1)
				(type default)
			)
			(layer "F.Fab")
		)
		(fp_line
			(start 0.120396 0.2794)
			(end -0.12065 0.2794)
			(stroke
				(width 0.1)
				(type default)
			)
			(layer "F.Fab")
		)
		(fp_line
			(start -0.12065 -0.2794)
			(end 0.12065 -0.2794)
			(stroke
				(width 0.1)
				(type default)
			)
			(layer "F.Fab")
		)
		(fp_line
			(start 0.12065 -0.2794)
			(end 0.12065 -0.3048)
			(stroke
				(width 0.1)
				(type default)
			)
			(layer "F.Fab")
		)
		(fp_line
			(start 0.12065 -0.3048)
			(end 0.67945 -0.3048)
			(stroke
				(width 0.1)
				(type default)
			)
			(layer "F.Fab")
		)
		(fp_line
			(start 0.67945 -0.3048)
			(end 0.67945 0.3048)
			(stroke
				(width 0.1)
				(type default)
			)
			(layer "F.Fab")
		)
		(fp_line
			(start -0.67945 -0.305054)
			(end -0.12065 -0.305054)
			(stroke
				(width 0.1)
				(type default)
			)
			(layer "F.Fab")
		)
		(fp_line
			(start -0.12065 -0.305054)
			(end -0.12065 -0.2794)
			(stroke
				(width 0.1)
				(type default)
			)
			(layer "F.Fab")
		)
		(pad "1" smd circle
			(at -0.40005 0 270)
			(size 0 0)
			(layers "F.Cu" "F.Mask" "F.Paste")
			(net "PVDD11_S3_P1_PVCC")
		)
		(pad "2" smd circle
			(at 0.40005 0 270)
			(size 0 0)
			(layers "F.Cu" "F.Mask" "F.Paste")
			(net "GND")
		)
	)
	(footprint ""
		(layer "F.Cu")
		(at 65.3796 -14.8336 180)
		(property "Reference" "C1833"
			(at 0 0 180)
			(layer "F.SilkS")
			(hide yes)
			(effects
				(font
					(size 1.27 1.27)
				)
			)
		)
		(property "Value" ""
			(at 0 0 180)
			(layer "F.Fab")
			(effects
				(font
					(size 1.27 1.27)
				)
			)
		)
		(duplicate_pad_numbers_are_jumpers no)
		(fp_line
			(start 0.7874 0.4064)
			(end -0.7874 0.4064)
			(stroke
				(width 0.1524)
				(type default)
			)
			(layer "F.SilkS")
		)
		(fp_line
			(start 0.7874 -0.4064)
			(end 0.7874 0.4064)
			(stroke
				(width 0.1524)
				(type default)
			)
			(layer "F.SilkS")
		)
		(fp_line
			(start -0.7874 0.4064)
			(end -0.7874 -0.4064)
			(stroke
				(width 0.1524)
				(type default)
			)
			(layer "F.SilkS")
		)
		(fp_line
			(start -0.7874 -0.4064)
			(end 0.7874 -0.4064)
			(stroke
				(width 0.1524)
				(type default)
			)
			(layer "F.SilkS")
		)
		(fp_line
			(start 0.67945 0.3048)
			(end 0.120396 0.3048)
			(stroke
				(width 0.1)
				(type default)
			)
			(layer "F.Fab")
		)
		(fp_line
			(start 0.67945 -0.3048)
			(end 0.67945 0.3048)
			(stroke
				(width 0.1)
				(type default)
			)
			(layer "F.Fab")
		)
		(fp_line
			(start 0.12065 -0.2794)
			(end 0.12065 -0.3048)
			(stroke
				(width 0.1)
				(type default)
			)
			(layer "F.Fab")
		)
		(fp_line
			(start 0.12065 -0.3048)
			(end 0.67945 -0.3048)
			(stroke
				(width 0.1)
				(type default)
			)
			(layer "F.Fab")
		)
		(fp_line
			(start 0.120396 0.3048)
			(end 0.120396 0.2794)
			(stroke
				(width 0.1)
				(type default)
			)
			(layer "F.Fab")
		)
		(fp_line
			(start 0.120396 0.2794)
			(end -0.12065 0.2794)
			(stroke
				(width 0.1)
				(type default)
			)
			(layer "F.Fab")
		)
		(fp_line
			(start -0.12065 0.3048)
			(end -0.67945 0.3048)
			(stroke
				(width 0.1)
				(type default)
			)
			(layer "F.Fab")
		)
		(fp_line
			(start -0.12065 0.2794)
			(end -0.12065 0.3048)
			(stroke
				(width 0.1)
				(type default)
			)
			(layer "F.Fab")
		)
		(fp_line
			(start -0.12065 -0.2794)
			(end 0.12065 -0.2794)
			(stroke
				(width 0.1)
				(type default)
			)
			(layer "F.Fab")
		)
		(fp_line
			(start -0.12065 -0.305054)
			(end -0.12065 -0.2794)
			(stroke
				(width 0.1)
				(type default)
			)
			(layer "F.Fab")
		)
		(fp_line
			(start -0.67945 0.3048)
			(end -0.67945 -0.305054)
			(stroke
				(width 0.1)
				(type default)
			)
			(layer "F.Fab")
		)
		(fp_line
			(start -0.67945 -0.305054)
			(end -0.12065 -0.305054)
			(stroke
				(width 0.1)
				(type default)
			)
			(layer "F.Fab")
		)
		(pad "1" smd circle
			(at -0.40005 0 180)
			(size 0 0)
			(layers "F.Cu" "F.Mask" "F.Paste")
			(net "P12V_OCP_V3_2_R")
		)
		(pad "2" smd circle
			(at 0.40005 0 180)
			(size 0 0)
			(layers "F.Cu" "F.Mask" "F.Paste")
			(net "GND")
		)
	)
	(footprint ""
		(layer "F.Cu")
		(at 204.992986 -98.244914)
		(property "Reference" "C1059"
			(at 0 0 0)
			(layer "F.SilkS")
			(hide yes)
			(effects
				(font
					(size 1.27 1.27)
				)
			)
		)
		(property "Value" ""
			(at 0 0 0)
			(layer "F.Fab")
			(effects
				(font
					(size 1.27 1.27)
				)
			)
		)
		(duplicate_pad_numbers_are_jumpers no)
		(fp_line
			(start -0.7874 -0.4064)
			(end 0.7874 -0.4064)
			(stroke
				(width 0.1524)
				(type default)
			)
			(layer "F.SilkS")
		)
		(fp_line
			(start -0.7874 0.4064)
			(end -0.7874 -0.4064)
			(stroke
				(width 0.1524)
				(type default)
			)
			(layer "F.SilkS")
		)
		(fp_line
			(start 0.7874 -0.4064)
			(end 0.7874 0.4064)
			(stroke
				(width 0.1524)
				(type default)
			)
			(layer "F.SilkS")
		)
		(fp_line
			(start 0.7874 0.4064)
			(end -0.7874 0.4064)
			(stroke
				(width 0.1524)
				(type default)
			)
			(layer "F.SilkS")
		)
		(fp_line
			(start -0.67945 -0.305054)
			(end -0.12065 -0.305054)
			(stroke
				(width 0.1)
				(type default)
			)
			(layer "F.Fab")
		)
		(fp_line
			(start -0.67945 0.3048)
			(end -0.67945 -0.305054)
			(stroke
				(width 0.1)
				(type default)
			)
			(layer "F.Fab")
		)
		(fp_line
			(start -0.12065 -0.305054)
			(end -0.12065 -0.2794)
			(stroke
				(width 0.1)
				(type default)
			)
			(layer "F.Fab")
		)
		(fp_line
			(start -0.12065 -0.2794)
			(end 0.12065 -0.2794)
			(stroke
				(width 0.1)
				(type default)
			)
			(layer "F.Fab")
		)
		(fp_line
			(start -0.12065 0.2794)
			(end -0.12065 0.3048)
			(stroke
				(width 0.1)
				(type default)
			)
			(layer "F.Fab")
		)
		(fp_line
			(start -0.12065 0.3048)
			(end -0.67945 0.3048)
			(stroke
				(width 0.1)
				(type default)
			)
			(layer "F.Fab")
		)
		(fp_line
			(start 0.120396 0.2794)
			(end -0.12065 0.2794)
			(stroke
				(width 0.1)
				(type default)
			)
			(layer "F.Fab")
		)
		(fp_line
			(start 0.120396 0.3048)
			(end 0.120396 0.2794)
			(stroke
				(width 0.1)
				(type default)
			)
			(layer "F.Fab")
		)
		(fp_line
			(start 0.12065 -0.3048)
			(end 0.67945 -0.3048)
			(stroke
				(width 0.1)
				(type default)
			)
			(layer "F.Fab")
		)
		(fp_line
			(start 0.12065 -0.2794)
			(end 0.12065 -0.3048)
			(stroke
				(width 0.1)
				(type default)
			)
			(layer "F.Fab")
		)
		(fp_line
			(start 0.67945 -0.3048)
			(end 0.67945 0.3048)
			(stroke
				(width 0.1)
				(type default)
			)
			(layer "F.Fab")
		)
		(fp_line
			(start 0.67945 0.3048)
			(end 0.120396 0.3048)
			(stroke
				(width 0.1)
				(type default)
			)
			(layer "F.Fab")
		)
		(pad "1" smd circle
			(at -0.40005 0)
			(size 0 0)
			(layers "F.Cu" "F.Mask" "F.Paste")
			(net "P3V3_AUX")
		)
		(pad "2" smd circle
			(at 0.40005 0)
			(size 0 0)
			(layers "F.Cu" "F.Mask" "F.Paste")
			(net "GND")
		)
	)
	(footprint ""
		(layer "F.Cu")
		(at 179.71643 -92.664534 90)
		(property "Reference" "R6146"
			(at 0 0 90)
			(layer "F.SilkS")
			(hide yes)
			(effects
				(font
					(size 1.27 1.27)
				)
			)
		)
		(property "Value" ""
			(at 0 0 90)
			(layer "F.Fab")
			(effects
				(font
					(size 1.27 1.27)
				)
			)
		)
		(duplicate_pad_numbers_are_jumpers no)
		(fp_line
			(start 0.7874 -0.4064)
			(end 0.7874 0.4064)
			(stroke
				(width 0.1524)
				(type default)
			)
			(layer "F.SilkS")
		)
		(fp_line
			(start -0.7874 -0.4064)
			(end 0.7874 -0.4064)
			(stroke
				(width 0.1524)
				(type default)
			)
			(layer "F.SilkS")
		)
		(fp_line
			(start 0.7874 0.4064)
			(end -0.7874 0.4064)
			(stroke
				(width 0.1524)
				(type default)
			)
			(layer "F.SilkS")
		)
		(fp_line
			(start -0.7874 0.4064)
			(end -0.7874 -0.4064)
			(stroke
				(width 0.1524)
				(type default)
			)
			(layer "F.SilkS")
		)
		(fp_line
			(start -0.12065 -0.305054)
			(end -0.12065 -0.2794)
			(stroke
				(width 0.1)
				(type default)
			)
			(layer "F.Fab")
		)
		(fp_line
			(start -0.67945 -0.305054)
			(end -0.12065 -0.305054)
			(stroke
				(width 0.1)
				(type default)
			)
			(layer "F.Fab")
		)
		(fp_line
			(start 0.67945 -0.3048)
			(end 0.67945 0.3048)
			(stroke
				(width 0.1)
				(type default)
			)
			(layer "F.Fab")
		)
		(fp_line
			(start 0.12065 -0.3048)
			(end 0.67945 -0.3048)
			(stroke
				(width 0.1)
				(type default)
			)
			(layer "F.Fab")
		)
		(fp_line
			(start 0.12065 -0.2794)
			(end 0.12065 -0.3048)
			(stroke
				(width 0.1)
				(type default)
			)
			(layer "F.Fab")
		)
		(fp_line
			(start -0.12065 -0.2794)
			(end 0.12065 -0.2794)
			(stroke
				(width 0.1)
				(type default)
			)
			(layer "F.Fab")
		)
		(fp_line
			(start 0.120396 0.2794)
			(end -0.12065 0.2794)
			(stroke
				(width 0.1)
				(type default)
			)
			(layer "F.Fab")
		)
		(fp_line
			(start -0.12065 0.2794)
			(end -0.12065 0.3048)
			(stroke
				(width 0.1)
				(type default)
			)
			(layer "F.Fab")
		)
		(fp_line
			(start 0.67945 0.3048)
			(end 0.120396 0.3048)
			(stroke
				(width 0.1)
				(type default)
			)
			(layer "F.Fab")
		)
		(fp_line
			(start 0.120396 0.3048)
			(end 0.120396 0.2794)
			(stroke
				(width 0.1)
				(type default)
			)
			(layer "F.Fab")
		)
		(fp_line
			(start -0.12065 0.3048)
			(end -0.67945 0.3048)
			(stroke
				(width 0.1)
				(type default)
			)
			(layer "F.Fab")
		)
		(fp_line
			(start -0.67945 0.3048)
			(end -0.67945 -0.305054)
			(stroke
				(width 0.1)
				(type default)
			)
			(layer "F.Fab")
		)
		(pad "1" smd circle
			(at -0.40005 0 90)
			(size 0 0)
			(layers "F.Cu" "F.Mask" "F.Paste")
			(net "P1V8_AUX")
		)
		(pad "2" smd circle
			(at 0.40005 0 90)
			(size 0 0)
			(layers "F.Cu" "F.Mask" "F.Paste")
			(net "FAB_BMC_REV_ID2")
		)
	)
	(footprint ""
		(layer "F.Cu")
		(at 78.724506 -152.990804 90)
		(property "Reference" "PC152"
			(at 0 0 90)
			(layer "F.SilkS")
			(hide yes)
			(effects
				(font
					(size 1.27 1.27)
				)
			)
		)
		(property "Value" ""
			(at 0 0 90)
			(layer "F.Fab")
			(effects
				(font
					(size 1.27 1.27)
				)
			)
		)
		(duplicate_pad_numbers_are_jumpers no)
		(fp_line
			(start 1.524 -0.762)
			(end 1.524 0.762)
			(stroke
				(width 0.1524)
				(type default)
			)
			(layer "F.SilkS")
		)
		(fp_line
			(start -1.524 -0.762)
			(end 1.524 -0.762)
			(stroke
				(width 0.1524)
				(type default)
			)
			(layer "F.SilkS")
		)
		(fp_line
			(start 1.524 0.762)
			(end -1.524 0.762)
			(stroke
				(width 0.1524)
				(type default)
			)
			(layer "F.SilkS")
		)
		(fp_line
			(start -1.524 0.762)
			(end -1.524 -0.762)
			(stroke
				(width 0.1524)
				(type default)
			)
			(layer "F.SilkS")
		)
		(fp_line
			(start 1.1049 -0.724916)
			(end -1.1049 -0.724916)
			(stroke
				(width 0.1)
				(type default)
			)
			(layer "F.Fab")
		)
		(fp_line
			(start -1.1049 -0.724916)
			(end -1.1049 0.724916)
			(stroke
				(width 0.1)
				(type default)
			)
			(layer "F.Fab")
		)
		(fp_line
			(start 1.1049 0.724916)
			(end 1.1049 -0.724916)
			(stroke
				(width 0.1)
				(type default)
			)
			(layer "F.Fab")
		)
		(fp_line
			(start -1.1049 0.724916)
			(end 1.1049 0.724916)
			(stroke
				(width 0.1)
				(type default)
			)
			(layer "F.Fab")
		)
		(pad "1" smd rect
			(at -0.889 0 270)
			(size 1.016 1.27)
			(layers "F.Cu" "F.Mask" "F.Paste")
			(net "SW_P12V_AUX_PVDD18_S5_P1_FLT")
		)
		(pad "2" smd rect
			(at 0.889 0 270)
			(size 1.016 1.27)
			(layers "F.Cu" "F.Mask" "F.Paste")
			(net "GND")
		)
	)
	(footprint ""
		(layer "F.Cu")
		(at 382.320292 -378.95403 -90)
		(property "Reference" "C882"
			(at 0 0 270)
			(layer "F.SilkS")
			(hide yes)
			(effects
				(font
					(size 1.27 1.27)
				)
			)
		)
		(property "Value" ""
			(at 0 0 270)
			(layer "F.Fab")
			(effects
				(font
					(size 1.27 1.27)
				)
			)
		)
		(duplicate_pad_numbers_are_jumpers no)
		(fp_line
			(start -0.299974 0.150114)
			(end -0.299974 -0.150114)
			(stroke
				(width 0.1)
				(type default)
			)
			(layer "F.Fab")
		)
		(fp_line
			(start 0.299974 0.150114)
			(end -0.299974 0.150114)
			(stroke
				(width 0.1)
				(type default)
			)
			(layer "F.Fab")
		)
		(fp_line
			(start -0.299974 -0.150114)
			(end 0.299974 -0.150114)
			(stroke
				(width 0.1)
				(type default)
			)
			(layer "F.Fab")
		)
		(fp_line
			(start 0.299974 -0.150114)
			(end 0.299974 0.150114)
			(stroke
				(width 0.1)
				(type default)
			)
			(layer "F.Fab")
		)
		(pad "1" smd rect
			(at -0.2667 0 270)
			(size 0.3048 0.381)
			(layers "F.Cu" "F.Mask" "F.Paste")
			(net "P5E_CPU0_P3_TX_C_DN<9>")
		)
		(pad "2" smd rect
			(at 0.2667 0 270)
			(size 0.3048 0.381)
			(layers "F.Cu" "F.Mask" "F.Paste")
			(net "P5E_CPU0_P3_TX_DN<9>")
		)
	)
	(footprint ""
		(layer "F.Cu")
		(at 294.421052 -114.221514)
		(property "Reference" "R2704"
			(at 0 0 0)
			(layer "F.SilkS")
			(hide yes)
			(effects
				(font
					(size 1.27 1.27)
				)
			)
		)
		(property "Value" ""
			(at 0 0 0)
			(layer "F.Fab")
			(effects
				(font
					(size 1.27 1.27)
				)
			)
		)
		(duplicate_pad_numbers_are_jumpers no)
		(fp_line
			(start -0.7874 -0.4064)
			(end 0.7874 -0.4064)
			(stroke
				(width 0.1524)
				(type default)
			)
			(layer "F.SilkS")
		)
		(fp_line
			(start -0.7874 0.4064)
			(end -0.7874 -0.4064)
			(stroke
				(width 0.1524)
				(type default)
			)
			(layer "F.SilkS")
		)
		(fp_line
			(start 0.7874 -0.4064)
			(end 0.7874 0.4064)
			(stroke
				(width 0.1524)
				(type default)
			)
			(layer "F.SilkS")
		)
		(fp_line
			(start 0.7874 0.4064)
			(end -0.7874 0.4064)
			(stroke
				(width 0.1524)
				(type default)
			)
			(layer "F.SilkS")
		)
		(fp_line
			(start -0.67945 -0.305054)
			(end -0.12065 -0.305054)
			(stroke
				(width 0.1)
				(type default)
			)
			(layer "F.Fab")
		)
		(fp_line
			(start -0.67945 0.3048)
			(end -0.67945 -0.305054)
			(stroke
				(width 0.1)
				(type default)
			)
			(layer "F.Fab")
		)
		(fp_line
			(start -0.12065 -0.305054)
			(end -0.12065 -0.2794)
			(stroke
				(width 0.1)
				(type default)
			)
			(layer "F.Fab")
		)
		(fp_line
			(start -0.12065 -0.2794)
			(end 0.12065 -0.2794)
			(stroke
				(width 0.1)
				(type default)
			)
			(layer "F.Fab")
		)
		(fp_line
			(start -0.12065 0.2794)
			(end -0.12065 0.3048)
			(stroke
				(width 0.1)
				(type default)
			)
			(layer "F.Fab")
		)
		(fp_line
			(start -0.12065 0.3048)
			(end -0.67945 0.3048)
			(stroke
				(width 0.1)
				(type default)
			)
			(layer "F.Fab")
		)
		(fp_line
			(start 0.120396 0.2794)
			(end -0.12065 0.2794)
			(stroke
				(width 0.1)
				(type default)
			)
			(layer "F.Fab")
		)
		(fp_line
			(start 0.120396 0.3048)
			(end 0.120396 0.2794)
			(stroke
				(width 0.1)
				(type default)
			)
			(layer "F.Fab")
		)
		(fp_line
			(start 0.12065 -0.3048)
			(end 0.67945 -0.3048)
			(stroke
				(width 0.1)
				(type default)
			)
			(layer "F.Fab")
		)
		(fp_line
			(start 0.12065 -0.2794)
			(end 0.12065 -0.3048)
			(stroke
				(width 0.1)
				(type default)
			)
			(layer "F.Fab")
		)
		(fp_line
			(start 0.67945 -0.3048)
			(end 0.67945 0.3048)
			(stroke
				(width 0.1)
				(type default)
			)
			(layer "F.Fab")
		)
		(fp_line
			(start 0.67945 0.3048)
			(end 0.120396 0.3048)
			(stroke
				(width 0.1)
				(type default)
			)
			(layer "F.Fab")
		)
		(pad "1" smd circle
			(at -0.40005 0)
			(size 0 0)
			(layers "F.Cu" "F.Mask" "F.Paste")
			(net "SMB_BMC_SWB_SDA_R4")
		)
		(pad "2" smd circle
			(at 0.40005 0)
			(size 0 0)
			(layers "F.Cu" "F.Mask" "F.Paste")
			(net "SMB_BMC_SWB_SDA")
		)
	)
	(footprint ""
		(layer "F.Cu")
		(at 66.148204 -408.517344 -90)
		(property "Reference" "C6642"
			(at 0 0 270)
			(layer "F.SilkS")
			(hide yes)
			(effects
				(font
					(size 1.27 1.27)
				)
			)
		)
		(property "Value" ""
			(at 0 0 270)
			(layer "F.Fab")
			(effects
				(font
					(size 1.27 1.27)
				)
			)
		)
		(duplicate_pad_numbers_are_jumpers no)
		(fp_line
			(start -0.299974 0.150114)
			(end -0.299974 -0.150114)
			(stroke
				(width 0.1)
				(type default)
			)
			(layer "F.Fab")
		)
		(fp_line
			(start 0.299974 0.150114)
			(end -0.299974 0.150114)
			(stroke
				(width 0.1)
				(type default)
			)
			(layer "F.Fab")
		)
		(fp_line
			(start -0.299974 -0.150114)
			(end 0.299974 -0.150114)
			(stroke
				(width 0.1)
				(type default)
			)
			(layer "F.Fab")
		)
		(fp_line
			(start 0.299974 -0.150114)
			(end 0.299974 0.150114)
			(stroke
				(width 0.1)
				(type default)
			)
			(layer "F.Fab")
		)
		(pad "1" smd rect
			(at -0.2667 0 270)
			(size 0.3048 0.381)
			(layers "F.Cu" "F.Mask" "F.Paste")
			(net "P5E_CPU1_P0_TX_BUF_C_DN<6>")
		)
		(pad "2" smd rect
			(at 0.2667 0 270)
			(size 0.3048 0.381)
			(layers "F.Cu" "F.Mask" "F.Paste")
			(net "P5E_CPU1_P0_TX_BUF_DN<6>")
		)
	)
	(footprint ""
		(layer "F.Cu")
		(at 225.899472 -290.341812 90)
		(property "Reference" "PC6534"
			(at 0 0 90)
			(layer "F.SilkS")
			(hide yes)
			(effects
				(font
					(size 1.27 1.27)
				)
			)
		)
		(property "Value" ""
			(at 0 0 90)
			(layer "F.Fab")
			(effects
				(font
					(size 1.27 1.27)
				)
			)
		)
		(duplicate_pad_numbers_are_jumpers no)
		(fp_line
			(start 0.7874 -0.4064)
			(end 0.7874 0.4064)
			(stroke
				(width 0.1524)
				(type default)
			)
			(layer "F.SilkS")
		)
		(fp_line
			(start -0.7874 -0.4064)
			(end 0.7874 -0.4064)
			(stroke
				(width 0.1524)
				(type default)
			)
			(layer "F.SilkS")
		)
		(fp_line
			(start 0.7874 0.4064)
			(end -0.7874 0.4064)
			(stroke
				(width 0.1524)
				(type default)
			)
			(layer "F.SilkS")
		)
		(fp_line
			(start -0.7874 0.4064)
			(end -0.7874 -0.4064)
			(stroke
				(width 0.1524)
				(type default)
			)
			(layer "F.SilkS")
		)
		(fp_line
			(start -0.12065 -0.305054)
			(end -0.12065 -0.2794)
			(stroke
				(width 0.1)
				(type default)
			)
			(layer "F.Fab")
		)
		(fp_line
			(start -0.67945 -0.305054)
			(end -0.12065 -0.305054)
			(stroke
				(width 0.1)
				(type default)
			)
			(layer "F.Fab")
		)
		(fp_line
			(start 0.67945 -0.3048)
			(end 0.67945 0.3048)
			(stroke
				(width 0.1)
				(type default)
			)
			(layer "F.Fab")
		)
		(fp_line
			(start 0.12065 -0.3048)
			(end 0.67945 -0.3048)
			(stroke
				(width 0.1)
				(type default)
			)
			(layer "F.Fab")
		)
		(fp_line
			(start 0.12065 -0.2794)
			(end 0.12065 -0.3048)
			(stroke
				(width 0.1)
				(type default)
			)
			(layer "F.Fab")
		)
		(fp_line
			(start -0.12065 -0.2794)
			(end 0.12065 -0.2794)
			(stroke
				(width 0.1)
				(type default)
			)
			(layer "F.Fab")
		)
		(fp_line
			(start 0.120396 0.2794)
			(end -0.12065 0.2794)
			(stroke
				(width 0.1)
				(type default)
			)
			(layer "F.Fab")
		)
		(fp_line
			(start -0.12065 0.2794)
			(end -0.12065 0.3048)
			(stroke
				(width 0.1)
				(type default)
			)
			(layer "F.Fab")
		)
		(fp_line
			(start 0.67945 0.3048)
			(end 0.120396 0.3048)
			(stroke
				(width 0.1)
				(type default)
			)
			(layer "F.Fab")
		)
		(fp_line
			(start 0.120396 0.3048)
			(end 0.120396 0.2794)
			(stroke
				(width 0.1)
				(type default)
			)
			(layer "F.Fab")
		)
		(fp_line
			(start -0.12065 0.3048)
			(end -0.67945 0.3048)
			(stroke
				(width 0.1)
				(type default)
			)
			(layer "F.Fab")
		)
		(fp_line
			(start -0.67945 0.3048)
			(end -0.67945 -0.305054)
			(stroke
				(width 0.1)
				(type default)
			)
			(layer "F.Fab")
		)
		(pad "1" smd circle
			(at -0.40005 0 90)
			(size 0 0)
			(layers "F.Cu" "F.Mask" "F.Paste")
			(net "P1V8_RETIMER_CPU1_FB")
		)
		(pad "2" smd circle
			(at 0.40005 0 90)
			(size 0 0)
			(layers "F.Cu" "F.Mask" "F.Paste")
			(net "P1V8_CPU1_RT_1D")
		)
	)
	(footprint ""
		(layer "F.Cu")
		(at 113.684304 -418.079428 -90)
		(property "Reference" "R3510"
			(at 0 0 270)
			(layer "F.SilkS")
			(hide yes)
			(effects
				(font
					(size 1.27 1.27)
				)
			)
		)
		(property "Value" ""
			(at 0 0 270)
			(layer "F.Fab")
			(effects
				(font
					(size 1.27 1.27)
				)
			)
		)
		(duplicate_pad_numbers_are_jumpers no)
		(fp_line
			(start -0.7874 0.4064)
			(end -0.7874 -0.4064)
			(stroke
				(width 0.1524)
				(type default)
			)
			(layer "F.SilkS")
		)
		(fp_line
			(start 0.7874 0.4064)
			(end -0.7874 0.4064)
			(stroke
				(width 0.1524)
				(type default)
			)
			(layer "F.SilkS")
		)
		(fp_line
			(start -0.7874 -0.4064)
			(end 0.7874 -0.4064)
			(stroke
				(width 0.1524)
				(type default)
			)
			(layer "F.SilkS")
		)
		(fp_line
			(start 0.7874 -0.4064)
			(end 0.7874 0.4064)
			(stroke
				(width 0.1524)
				(type default)
			)
			(layer "F.SilkS")
		)
		(fp_line
			(start -0.67945 0.3048)
			(end -0.67945 -0.305054)
			(stroke
				(width 0.1)
				(type default)
			)
			(layer "F.Fab")
		)
		(fp_line
			(start -0.12065 0.3048)
			(end -0.67945 0.3048)
			(stroke
				(width 0.1)
				(type default)
			)
			(layer "F.Fab")
		)
		(fp_line
			(start 0.120396 0.3048)
			(end 0.120396 0.2794)
			(stroke
				(width 0.1)
				(type default)
			)
			(layer "F.Fab")
		)
		(fp_line
			(start 0.67945 0.3048)
			(end 0.120396 0.3048)
			(stroke
				(width 0.1)
				(type default)
			)
			(layer "F.Fab")
		)
		(fp_line
			(start -0.12065 0.2794)
			(end -0.12065 0.3048)
			(stroke
				(width 0.1)
				(type default)
			)
			(layer "F.Fab")
		)
		(fp_line
			(start 0.120396 0.2794)
			(end -0.12065 0.2794)
			(stroke
				(width 0.1)
				(type default)
			)
			(layer "F.Fab")
		)
		(fp_line
			(start -0.12065 -0.2794)
			(end 0.12065 -0.2794)
			(stroke
				(width 0.1)
				(type default)
			)
			(layer "F.Fab")
		)
		(fp_line
			(start 0.12065 -0.2794)
			(end 0.12065 -0.3048)
			(stroke
				(width 0.1)
				(type default)
			)
			(layer "F.Fab")
		)
		(fp_line
			(start 0.12065 -0.3048)
			(end 0.67945 -0.3048)
			(stroke
				(width 0.1)
				(type default)
			)
			(layer "F.Fab")
		)
		(fp_line
			(start 0.67945 -0.3048)
			(end 0.67945 0.3048)
			(stroke
				(width 0.1)
				(type default)
			)
			(layer "F.Fab")
		)
		(fp_line
			(start -0.67945 -0.305054)
			(end -0.12065 -0.305054)
			(stroke
				(width 0.1)
				(type default)
			)
			(layer "F.Fab")
		)
		(fp_line
			(start -0.12065 -0.305054)
			(end -0.12065 -0.2794)
			(stroke
				(width 0.1)
				(type default)
			)
			(layer "F.Fab")
		)
		(pad "1" smd circle
			(at -0.40005 0 270)
			(size 0 0)
			(layers "F.Cu" "F.Mask" "F.Paste")
			(net "P3V3_AUX")
		)
		(pad "2" smd circle
			(at 0.40005 0 270)
			(size 0 0)
			(layers "F.Cu" "F.Mask" "F.Paste")
			(net "FM_SMB_1_ALERT_GPU_N")
		)
	)
	(footprint ""
		(layer "F.Cu")
		(at 392.797284 -399.12798)
		(property "Reference" "R1408"
			(at 0 0 0)
			(layer "F.SilkS")
			(hide yes)
			(effects
				(font
					(size 1.27 1.27)
				)
			)
		)
		(property "Value" ""
			(at 0 0 0)
			(layer "F.Fab")
			(effects
				(font
					(size 1.27 1.27)
				)
			)
		)
		(duplicate_pad_numbers_are_jumpers no)
		(fp_line
			(start -0.32512 -0.175006)
			(end 0.32512 -0.175006)
			(stroke
				(width 0.1)
				(type default)
			)
			(layer "F.Fab")
		)
		(fp_line
			(start -0.32512 0.175006)
			(end -0.32512 -0.175006)
			(stroke
				(width 0.1)
				(type default)
			)
			(layer "F.Fab")
		)
		(fp_line
			(start 0.32512 -0.175006)
			(end 0.32512 0.175006)
			(stroke
				(width 0.1)
				(type default)
			)
			(layer "F.Fab")
		)
		(fp_line
			(start 0.32512 0.175006)
			(end -0.32512 0.175006)
			(stroke
				(width 0.1)
				(type default)
			)
			(layer "F.Fab")
		)
		(pad "1" smd rect
			(at -0.2667 0)
			(size 0.3048 0.381)
			(layers "F.Cu" "F.Mask" "F.Paste")
			(net "JTAG_TRST_RT_CPU0_P3_N")
		)
		(pad "2" smd rect
			(at 0.2667 0 180)
			(size 0.3048 0.381)
			(layers "F.Cu" "F.Mask" "F.Paste")
			(net "GND")
		)
	)
	(footprint ""
		(layer "F.Cu")
		(at 323.513958 -193.925952 -90)
		(property "Reference" "R412"
			(at 0 0 270)
			(layer "F.SilkS")
			(hide yes)
			(effects
				(font
					(size 1.27 1.27)
				)
			)
		)
		(property "Value" ""
			(at 0 0 270)
			(layer "F.Fab")
			(effects
				(font
					(size 1.27 1.27)
				)
			)
		)
		(duplicate_pad_numbers_are_jumpers no)
		(fp_line
			(start -0.7874 0.4064)
			(end -0.7874 -0.4064)
			(stroke
				(width 0.1524)
				(type default)
			)
			(layer "F.SilkS")
		)
		(fp_line
			(start 0.7874 0.4064)
			(end -0.7874 0.4064)
			(stroke
				(width 0.1524)
				(type default)
			)
			(layer "F.SilkS")
		)
		(fp_line
			(start -0.7874 -0.4064)
			(end 0.7874 -0.4064)
			(stroke
				(width 0.1524)
				(type default)
			)
			(layer "F.SilkS")
		)
		(fp_line
			(start 0.7874 -0.4064)
			(end 0.7874 0.4064)
			(stroke
				(width 0.1524)
				(type default)
			)
			(layer "F.SilkS")
		)
		(fp_line
			(start -0.67945 0.3048)
			(end -0.67945 -0.305054)
			(stroke
				(width 0.1)
				(type default)
			)
			(layer "F.Fab")
		)
		(fp_line
			(start -0.12065 0.3048)
			(end -0.67945 0.3048)
			(stroke
				(width 0.1)
				(type default)
			)
			(layer "F.Fab")
		)
		(fp_line
			(start 0.120396 0.3048)
			(end 0.120396 0.2794)
			(stroke
				(width 0.1)
				(type default)
			)
			(layer "F.Fab")
		)
		(fp_line
			(start 0.67945 0.3048)
			(end 0.120396 0.3048)
			(stroke
				(width 0.1)
				(type default)
			)
			(layer "F.Fab")
		)
		(fp_line
			(start -0.12065 0.2794)
			(end -0.12065 0.3048)
			(stroke
				(width 0.1)
				(type default)
			)
			(layer "F.Fab")
		)
		(fp_line
			(start 0.120396 0.2794)
			(end -0.12065 0.2794)
			(stroke
				(width 0.1)
				(type default)
			)
			(layer "F.Fab")
		)
		(fp_line
			(start -0.12065 -0.2794)
			(end 0.12065 -0.2794)
			(stroke
				(width 0.1)
				(type default)
			)
			(layer "F.Fab")
		)
		(fp_line
			(start 0.12065 -0.2794)
			(end 0.12065 -0.3048)
			(stroke
				(width 0.1)
				(type default)
			)
			(layer "F.Fab")
		)
		(fp_line
			(start 0.12065 -0.3048)
			(end 0.67945 -0.3048)
			(stroke
				(width 0.1)
				(type default)
			)
			(layer "F.Fab")
		)
		(fp_line
			(start 0.67945 -0.3048)
			(end 0.67945 0.3048)
			(stroke
				(width 0.1)
				(type default)
			)
			(layer "F.Fab")
		)
		(fp_line
			(start -0.67945 -0.305054)
			(end -0.12065 -0.305054)
			(stroke
				(width 0.1)
				(type default)
			)
			(layer "F.Fab")
		)
		(fp_line
			(start -0.12065 -0.305054)
			(end -0.12065 -0.2794)
			(stroke
				(width 0.1)
				(type default)
			)
			(layer "F.Fab")
		)
		(pad "1" smd circle
			(at -0.40005 0 270)
			(size 0 0)
			(layers "F.Cu" "F.Mask" "F.Paste")
			(net "CPU0_PROCHOT_N")
		)
		(pad "2" smd circle
			(at 0.40005 0 270)
			(size 0 0)
			(layers "F.Cu" "F.Mask" "F.Paste")
			(net "PVDD18_S5_P0")
		)
	)
	(footprint ""
		(layer "F.Cu")
		(at 280.008584 -343.712038 180)
		(property "Reference" "PC166"
			(at 0 0 180)
			(layer "F.SilkS")
			(hide yes)
			(effects
				(font
					(size 1.27 1.27)
				)
			)
		)
		(property "Value" ""
			(at 0 0 180)
			(layer "F.Fab")
			(effects
				(font
					(size 1.27 1.27)
				)
			)
		)
		(duplicate_pad_numbers_are_jumpers no)
		(fp_line
			(start 0.7874 0.4064)
			(end -0.7874 0.4064)
			(stroke
				(width 0.1524)
				(type default)
			)
			(layer "F.SilkS")
		)
		(fp_line
			(start 0.7874 -0.4064)
			(end 0.7874 0.4064)
			(stroke
				(width 0.1524)
				(type default)
			)
			(layer "F.SilkS")
		)
		(fp_line
			(start -0.7874 0.4064)
			(end -0.7874 -0.4064)
			(stroke
				(width 0.1524)
				(type default)
			)
			(layer "F.SilkS")
		)
		(fp_line
			(start -0.7874 -0.4064)
			(end 0.7874 -0.4064)
			(stroke
				(width 0.1524)
				(type default)
			)
			(layer "F.SilkS")
		)
		(fp_line
			(start 0.67945 0.3048)
			(end 0.120396 0.3048)
			(stroke
				(width 0.1)
				(type default)
			)
			(layer "F.Fab")
		)
		(fp_line
			(start 0.67945 -0.3048)
			(end 0.67945 0.3048)
			(stroke
				(width 0.1)
				(type default)
			)
			(layer "F.Fab")
		)
		(fp_line
			(start 0.12065 -0.2794)
			(end 0.12065 -0.3048)
			(stroke
				(width 0.1)
				(type default)
			)
			(layer "F.Fab")
		)
		(fp_line
			(start 0.12065 -0.3048)
			(end 0.67945 -0.3048)
			(stroke
				(width 0.1)
				(type default)
			)
			(layer "F.Fab")
		)
		(fp_line
			(start 0.120396 0.3048)
			(end 0.120396 0.2794)
			(stroke
				(width 0.1)
				(type default)
			)
			(layer "F.Fab")
		)
		(fp_line
			(start 0.120396 0.2794)
			(end -0.12065 0.2794)
			(stroke
				(width 0.1)
				(type default)
			)
			(layer "F.Fab")
		)
		(fp_line
			(start -0.12065 0.3048)
			(end -0.67945 0.3048)
			(stroke
				(width 0.1)
				(type default)
			)
			(layer "F.Fab")
		)
		(fp_line
			(start -0.12065 0.2794)
			(end -0.12065 0.3048)
			(stroke
				(width 0.1)
				(type default)
			)
			(layer "F.Fab")
		)
		(fp_line
			(start -0.12065 -0.2794)
			(end 0.12065 -0.2794)
			(stroke
				(width 0.1)
				(type default)
			)
			(layer "F.Fab")
		)
		(fp_line
			(start -0.12065 -0.305054)
			(end -0.12065 -0.2794)
			(stroke
				(width 0.1)
				(type default)
			)
			(layer "F.Fab")
		)
		(fp_line
			(start -0.67945 0.3048)
			(end -0.67945 -0.305054)
			(stroke
				(width 0.1)
				(type default)
			)
			(layer "F.Fab")
		)
		(fp_line
			(start -0.67945 -0.305054)
			(end -0.12065 -0.305054)
			(stroke
				(width 0.1)
				(type default)
			)
			(layer "F.Fab")
		)
		(pad "1" smd circle
			(at -0.40005 0 180)
			(size 0 0)
			(layers "F.Cu" "F.Mask" "F.Paste")
			(net "SW_PVDDIO_P0_SW3")
		)
		(pad "2" smd circle
			(at 0.40005 0 180)
			(size 0 0)
			(layers "F.Cu" "F.Mask" "F.Paste")
			(net "SW_PVDDIO_P0_SW3_RC")
		)
	)
	(footprint ""
		(layer "F.Cu")
		(at 446.493392 -47.506382 -90)
		(property "Reference" "PC2260"
			(at 0 0 270)
			(layer "F.SilkS")
			(hide yes)
			(effects
				(font
					(size 1.27 1.27)
				)
			)
		)
		(property "Value" ""
			(at 0 0 270)
			(layer "F.Fab")
			(effects
				(font
					(size 1.27 1.27)
				)
			)
		)
		(duplicate_pad_numbers_are_jumpers no)
		(fp_line
			(start -1.524 0.762)
			(end -1.524 -0.762)
			(stroke
				(width 0.1524)
				(type default)
			)
			(layer "F.SilkS")
		)
		(fp_line
			(start 1.524 0.762)
			(end -1.524 0.762)
			(stroke
				(width 0.1524)
				(type default)
			)
			(layer "F.SilkS")
		)
		(fp_line
			(start -1.524 -0.762)
			(end 1.524 -0.762)
			(stroke
				(width 0.1524)
				(type default)
			)
			(layer "F.SilkS")
		)
		(fp_line
			(start 1.524 -0.762)
			(end 1.524 0.762)
			(stroke
				(width 0.1524)
				(type default)
			)
			(layer "F.SilkS")
		)
		(fp_line
			(start -1.1049 0.724916)
			(end 1.1049 0.724916)
			(stroke
				(width 0.1)
				(type default)
			)
			(layer "F.Fab")
		)
		(fp_line
			(start 1.1049 0.724916)
			(end 1.1049 -0.724916)
			(stroke
				(width 0.1)
				(type default)
			)
			(layer "F.Fab")
		)
		(fp_line
			(start -1.1049 -0.724916)
			(end -1.1049 0.724916)
			(stroke
				(width 0.1)
				(type default)
			)
			(layer "F.Fab")
		)
		(fp_line
			(start 1.1049 -0.724916)
			(end -1.1049 -0.724916)
			(stroke
				(width 0.1)
				(type default)
			)
			(layer "F.Fab")
		)
		(pad "1" smd rect
			(at -0.889 0 90)
			(size 1.016 1.27)
			(layers "F.Cu" "F.Mask" "F.Paste")
			(net "SW_P3V3_AUX_FLT")
		)
		(pad "2" smd rect
			(at 0.889 0 90)
			(size 1.016 1.27)
			(layers "F.Cu" "F.Mask" "F.Paste")
			(net "GND")
		)
	)
	(footprint ""
		(layer "F.Cu")
		(at 166.1668 -428.5996 180)
		(property "Reference" "R3105"
			(at 0 0 180)
			(layer "F.SilkS")
			(hide yes)
			(effects
				(font
					(size 1.27 1.27)
				)
			)
		)
		(property "Value" ""
			(at 0 0 180)
			(layer "F.Fab")
			(effects
				(font
					(size 1.27 1.27)
				)
			)
		)
		(duplicate_pad_numbers_are_jumpers no)
		(fp_line
			(start 0.7874 0.4064)
			(end -0.7874 0.4064)
			(stroke
				(width 0.1524)
				(type default)
			)
			(layer "F.SilkS")
		)
		(fp_line
			(start 0.7874 -0.4064)
			(end 0.7874 0.4064)
			(stroke
				(width 0.1524)
				(type default)
			)
			(layer "F.SilkS")
		)
		(fp_line
			(start -0.7874 0.4064)
			(end -0.7874 -0.4064)
			(stroke
				(width 0.1524)
				(type default)
			)
			(layer "F.SilkS")
		)
		(fp_line
			(start -0.7874 -0.4064)
			(end 0.7874 -0.4064)
			(stroke
				(width 0.1524)
				(type default)
			)
			(layer "F.SilkS")
		)
		(fp_line
			(start 0.67945 0.3048)
			(end 0.120396 0.3048)
			(stroke
				(width 0.1)
				(type default)
			)
			(layer "F.Fab")
		)
		(fp_line
			(start 0.67945 -0.3048)
			(end 0.67945 0.3048)
			(stroke
				(width 0.1)
				(type default)
			)
			(layer "F.Fab")
		)
		(fp_line
			(start 0.12065 -0.2794)
			(end 0.12065 -0.3048)
			(stroke
				(width 0.1)
				(type default)
			)
			(layer "F.Fab")
		)
		(fp_line
			(start 0.12065 -0.3048)
			(end 0.67945 -0.3048)
			(stroke
				(width 0.1)
				(type default)
			)
			(layer "F.Fab")
		)
		(fp_line
			(start 0.120396 0.3048)
			(end 0.120396 0.2794)
			(stroke
				(width 0.1)
				(type default)
			)
			(layer "F.Fab")
		)
		(fp_line
			(start 0.120396 0.2794)
			(end -0.12065 0.2794)
			(stroke
				(width 0.1)
				(type default)
			)
			(layer "F.Fab")
		)
		(fp_line
			(start -0.12065 0.3048)
			(end -0.67945 0.3048)
			(stroke
				(width 0.1)
				(type default)
			)
			(layer "F.Fab")
		)
		(fp_line
			(start -0.12065 0.2794)
			(end -0.12065 0.3048)
			(stroke
				(width 0.1)
				(type default)
			)
			(layer "F.Fab")
		)
		(fp_line
			(start -0.12065 -0.2794)
			(end 0.12065 -0.2794)
			(stroke
				(width 0.1)
				(type default)
			)
			(layer "F.Fab")
		)
		(fp_line
			(start -0.12065 -0.305054)
			(end -0.12065 -0.2794)
			(stroke
				(width 0.1)
				(type default)
			)
			(layer "F.Fab")
		)
		(fp_line
			(start -0.67945 0.3048)
			(end -0.67945 -0.305054)
			(stroke
				(width 0.1)
				(type default)
			)
			(layer "F.Fab")
		)
		(fp_line
			(start -0.67945 -0.305054)
			(end -0.12065 -0.305054)
			(stroke
				(width 0.1)
				(type default)
			)
			(layer "F.Fab")
		)
		(pad "1" smd circle
			(at -0.40005 0 180)
			(size 0 0)
			(layers "F.Cu" "F.Mask" "F.Paste")
			(net "SMB_BMC_SWB_SCL")
		)
		(pad "2" smd circle
			(at 0.40005 0 180)
			(size 0 0)
			(layers "F.Cu" "F.Mask" "F.Paste")
			(net "SMB_BMC_SWB_R_SCL")
		)
	)
	(footprint ""
		(layer "F.Cu")
		(at 69.036438 -31.887922 90)
		(property "Reference" "PC2164"
			(at 0 0 90)
			(layer "F.SilkS")
			(hide yes)
			(effects
				(font
					(size 1.27 1.27)
				)
			)
		)
		(property "Value" ""
			(at 0 0 90)
			(layer "F.Fab")
			(effects
				(font
					(size 1.27 1.27)
				)
			)
		)
		(duplicate_pad_numbers_are_jumpers no)
		(fp_line
			(start 0.7874 -0.4064)
			(end 0.7874 0.4064)
			(stroke
				(width 0.1524)
				(type default)
			)
			(layer "F.SilkS")
		)
		(fp_line
			(start -0.7874 -0.4064)
			(end 0.7874 -0.4064)
			(stroke
				(width 0.1524)
				(type default)
			)
			(layer "F.SilkS")
		)
		(fp_line
			(start 0.7874 0.4064)
			(end -0.7874 0.4064)
			(stroke
				(width 0.1524)
				(type default)
			)
			(layer "F.SilkS")
		)
		(fp_line
			(start -0.7874 0.4064)
			(end -0.7874 -0.4064)
			(stroke
				(width 0.1524)
				(type default)
			)
			(layer "F.SilkS")
		)
		(fp_line
			(start -0.12065 -0.305054)
			(end -0.12065 -0.2794)
			(stroke
				(width 0.1)
				(type default)
			)
			(layer "F.Fab")
		)
		(fp_line
			(start -0.67945 -0.305054)
			(end -0.12065 -0.305054)
			(stroke
				(width 0.1)
				(type default)
			)
			(layer "F.Fab")
		)
		(fp_line
			(start 0.67945 -0.3048)
			(end 0.67945 0.3048)
			(stroke
				(width 0.1)
				(type default)
			)
			(layer "F.Fab")
		)
		(fp_line
			(start 0.12065 -0.3048)
			(end 0.67945 -0.3048)
			(stroke
				(width 0.1)
				(type default)
			)
			(layer "F.Fab")
		)
		(fp_line
			(start 0.12065 -0.2794)
			(end 0.12065 -0.3048)
			(stroke
				(width 0.1)
				(type default)
			)
			(layer "F.Fab")
		)
		(fp_line
			(start -0.12065 -0.2794)
			(end 0.12065 -0.2794)
			(stroke
				(width 0.1)
				(type default)
			)
			(layer "F.Fab")
		)
		(fp_line
			(start 0.120396 0.2794)
			(end -0.12065 0.2794)
			(stroke
				(width 0.1)
				(type default)
			)
			(layer "F.Fab")
		)
		(fp_line
			(start -0.12065 0.2794)
			(end -0.12065 0.3048)
			(stroke
				(width 0.1)
				(type default)
			)
			(layer "F.Fab")
		)
		(fp_line
			(start 0.67945 0.3048)
			(end 0.120396 0.3048)
			(stroke
				(width 0.1)
				(type default)
			)
			(layer "F.Fab")
		)
		(fp_line
			(start 0.120396 0.3048)
			(end 0.120396 0.2794)
			(stroke
				(width 0.1)
				(type default)
			)
			(layer "F.Fab")
		)
		(fp_line
			(start -0.12065 0.3048)
			(end -0.67945 0.3048)
			(stroke
				(width 0.1)
				(type default)
			)
			(layer "F.Fab")
		)
		(fp_line
			(start -0.67945 0.3048)
			(end -0.67945 -0.305054)
			(stroke
				(width 0.1)
				(type default)
			)
			(layer "F.Fab")
		)
		(pad "1" smd circle
			(at -0.40005 0 90)
			(size 0 0)
			(layers "F.Cu" "F.Mask" "F.Paste")
			(net "P12V_OCP_TIMER_2")
		)
		(pad "2" smd circle
			(at 0.40005 0 90)
			(size 0 0)
			(layers "F.Cu" "F.Mask" "F.Paste")
			(net "GND")
		)
	)
	(footprint ""
		(layer "F.Cu")
		(at 133.653022 -395.6304 -90)
		(property "Reference" "R6900"
			(at 0 0 270)
			(layer "F.SilkS")
			(hide yes)
			(effects
				(font
					(size 1.27 1.27)
				)
			)
		)
		(property "Value" ""
			(at 0 0 270)
			(layer "F.Fab")
			(effects
				(font
					(size 1.27 1.27)
				)
			)
		)
		(duplicate_pad_numbers_are_jumpers no)
		(fp_line
			(start -0.32512 0.175006)
			(end -0.32512 -0.175006)
			(stroke
				(width 0.1)
				(type default)
			)
			(layer "F.Fab")
		)
		(fp_line
			(start 0.32512 0.175006)
			(end -0.32512 0.175006)
			(stroke
				(width 0.1)
				(type default)
			)
			(layer "F.Fab")
		)
		(fp_line
			(start -0.32512 -0.175006)
			(end 0.32512 -0.175006)
			(stroke
				(width 0.1)
				(type default)
			)
			(layer "F.Fab")
		)
		(fp_line
			(start 0.32512 -0.175006)
			(end 0.32512 0.175006)
			(stroke
				(width 0.1)
				(type default)
			)
			(layer "F.Fab")
		)
		(pad "1" smd rect
			(at -0.2667 0 270)
			(size 0.3048 0.381)
			(layers "F.Cu" "F.Mask" "F.Paste")
			(net "P1V8_CPU1_RT_1D")
		)
		(pad "2" smd rect
			(at 0.2667 0 90)
			(size 0.3048 0.381)
			(layers "F.Cu" "F.Mask" "F.Paste")
			(net "RT_CPU1_P3_VQPS")
		)
	)
	(footprint ""
		(layer "F.Cu")
		(at 103.886 -423.164 -90)
		(property "Reference" "U255"
			(at 1.251712 -3.660902 90)
			(unlocked yes)
			(layer "F.SilkS")
			(effects
				(font
					(size 0.7874 0.5842)
					(thickness 0.1524)
				)
				(justify left)
			)
		)
		(property "Value" ""
			(at 0 0 270)
			(layer "F.Fab")
			(effects
				(font
					(size 1.27 1.27)
				)
			)
		)
		(duplicate_pad_numbers_are_jumpers no)
		(fp_line
			(start -1.38176 1.100074)
			(end 1.38176 1.100074)
			(stroke
				(width 0.1524)
				(type default)
			)
			(layer "F.SilkS")
		)
		(fp_line
			(start 1.38176 1.100074)
			(end 1.38176 -1.100074)
			(stroke
				(width 0.1524)
				(type default)
			)
			(layer "F.SilkS")
		)
		(fp_line
			(start 0 -0.508)
			(end -0.592074 -1.100074)
			(stroke
				(width 0.1524)
				(type default)
			)
			(layer "F.SilkS")
		)
		(fp_line
			(start -1.38176 -1.100074)
			(end -1.38176 1.100074)
			(stroke
				(width 0.1524)
				(type default)
			)
			(layer "F.SilkS")
		)
		(fp_line
			(start -0.592074 -1.100074)
			(end -1.38176 -1.100074)
			(stroke
				(width 0.1524)
				(type default)
			)
			(layer "F.SilkS")
		)
		(fp_line
			(start 0.592074 -1.100074)
			(end 0 -0.508)
			(stroke
				(width 0.1524)
				(type default)
			)
			(layer "F.SilkS")
		)
		(fp_line
			(start 1.38176 -1.100074)
			(end 0.592074 -1.100074)
			(stroke
				(width 0.1524)
				(type default)
			)
			(layer "F.SilkS")
		)
		(fp_poly
			(pts
				(xy -1.9431 -0.429768) (xy -1.9431 -0.870204) (xy -1.50241 -0.649986)
			)
			(stroke
				(width 0)
				(type default)
			)
			(fill yes)
			(layer "F.SilkS")
		)
		(fp_line
			(start -0.674878 1.100074)
			(end 0.674878 1.100074)
			(stroke
				(width 0.1)
				(type default)
			)
			(layer "F.Fab")
		)
		(fp_line
			(start 0.674878 1.100074)
			(end 0.674878 -1.100074)
			(stroke
				(width 0.1)
				(type default)
			)
			(layer "F.Fab")
		)
		(fp_line
			(start -0.674878 -1.100074)
			(end -0.674878 1.100074)
			(stroke
				(width 0.1)
				(type default)
			)
			(layer "F.Fab")
		)
		(fp_line
			(start 0.674878 -1.100074)
			(end -0.674878 -1.100074)
			(stroke
				(width 0.1)
				(type default)
			)
			(layer "F.Fab")
		)
		(fp_poly
			(pts
				(xy -1.9431 -0.870204) (xy -1.50241 -0.649986) (xy -1.9431 -0.429768)
			)
			(stroke
				(width 0)
				(type default)
			)
			(fill yes)
			(layer "F.Fab")
		)
		(pad "1" smd rect
			(at -0.94996 -0.649986 180)
			(size 0.4318 0.6096)
			(layers "F.Cu" "F.Mask" "F.Paste")
			(net "GPU_NVS_PWR_BRAKE_N")
		)
		(pad "2" smd rect
			(at -0.94996 0 180)
			(size 0.4318 0.6096)
			(layers "F.Cu" "F.Mask" "F.Paste")
			(net "GND")
		)
		(pad "3" smd rect
			(at -0.94996 0.649986 180)
			(size 0.4318 0.6096)
			(layers "F.Cu" "F.Mask" "F.Paste")
			(net "GPU_FPGA_EROT_RST_N")
		)
		(pad "4" smd rect
			(at 0.94996 0.649986 180)
			(size 0.4318 0.6096)
			(layers "F.Cu" "F.Mask" "F.Paste")
			(net "GPU_FPGA_EROT_RST_BUF_R_N")
		)
		(pad "5" smd rect
			(at 0.94996 0 180)
			(size 0.4318 0.6096)
			(layers "F.Cu" "F.Mask" "F.Paste")
			(net "P3V3_AUX")
		)
		(pad "6" smd rect
			(at 0.94996 -0.649986 180)
			(size 0.4318 0.6096)
			(layers "F.Cu" "F.Mask" "F.Paste")
			(net "GPU_NVS_PWR_BRAKE_N_R")
		)
	)
	(footprint ""
		(layer "F.Cu")
		(at 89.533984 -32.07131)
		(property "Reference" "U321"
			(at -2.2606 -2.352548 0)
			(unlocked yes)
			(layer "F.SilkS")
			(effects
				(font
					(size 0.7874 0.5842)
					(thickness 0.1524)
				)
				(justify left)
			)
		)
		(property "Value" ""
			(at 0 0 0)
			(layer "F.Fab")
			(effects
				(font
					(size 1.27 1.27)
				)
			)
		)
		(duplicate_pad_numbers_are_jumpers no)
		(fp_line
			(start -2.032 -1.549908)
			(end 2.032 -1.549908)
			(stroke
				(width 0.1524)
				(type default)
			)
			(layer "F.SilkS")
		)
		(fp_line
			(start -2.032 1.549908)
			(end -2.032 -1.549908)
			(stroke
				(width 0.1524)
				(type default)
			)
			(layer "F.SilkS")
		)
		(fp_line
			(start 2.032 -1.549908)
			(end 2.032 1.549908)
			(stroke
				(width 0.1524)
				(type default)
			)
			(layer "F.SilkS")
		)
		(fp_line
			(start 2.032 1.549908)
			(end -2.032 1.549908)
			(stroke
				(width 0.1524)
				(type default)
			)
			(layer "F.SilkS")
		)
		(fp_poly
			(pts
				(xy -2.733548 -2.327656) (xy -2.993644 -1.89103) (xy -2.208784 -1.71958)
			)
			(stroke
				(width 0)
				(type default)
			)
			(fill yes)
			(layer "F.SilkS")
		)
		(fp_line
			(start -0.849884 -1.549908)
			(end -0.849884 1.549908)
			(stroke
				(width 0.1)
				(type default)
			)
			(layer "F.Fab")
		)
		(fp_line
			(start -0.849884 1.549908)
			(end 0.849884 1.549908)
			(stroke
				(width 0.1)
				(type default)
			)
			(layer "F.Fab")
		)
		(fp_line
			(start 0.849884 -1.549908)
			(end -0.849884 -1.549908)
			(stroke
				(width 0.1)
				(type default)
			)
			(layer "F.Fab")
		)
		(fp_line
			(start 0.849884 1.549908)
			(end 0.849884 -1.549908)
			(stroke
				(width 0.1)
				(type default)
			)
			(layer "F.Fab")
		)
		(fp_poly
			(pts
				(xy -2.9464 -1.2192) (xy -2.9464 -0.7112) (xy -2.1844 -0.9652)
			)
			(stroke
				(width 0)
				(type default)
			)
			(fill yes)
			(layer "F.Fab")
		)
		(pad "1" smd rect
			(at -1.225042 -0.94996 270)
			(size 0.4572 1.3208)
			(layers "F.Cu" "F.Mask" "F.Paste")
			(net "CLK_50M_NCSI_OCP_V3_2")
		)
		(pad "2" smd rect
			(at -1.225042 0 270)
			(size 0.4572 1.3208)
			(layers "F.Cu" "F.Mask" "F.Paste")
			(net "CLK_50M_NCSI_OCP_V3_2_ISO_R")
		)
		(pad "3" smd rect
			(at -1.225042 0.94996 270)
			(size 0.4572 1.3208)
			(layers "F.Cu" "F.Mask" "F.Paste")
			(net "GND")
		)
		(pad "4" smd rect
			(at 1.225042 0.94996 270)
			(size 0.4572 1.3208)
			(layers "F.Cu" "F.Mask" "F.Paste")
			(net "FB_BMC_ISOLATE1")
		)
		(pad "5" smd rect
			(at 1.225042 -0.94996 270)
			(size 0.4572 1.3208)
			(layers "F.Cu" "F.Mask" "F.Paste")
			(net "P3V3_AUX")
		)
	)
	(footprint ""
		(layer "F.Cu")
		(at 218.011502 -72.015858 180)
		(property "Reference" "PR3971"
			(at 0 0 180)
			(layer "F.SilkS")
			(hide yes)
			(effects
				(font
					(size 1.27 1.27)
				)
			)
		)
		(property "Value" ""
			(at 0 0 180)
			(layer "F.Fab")
			(effects
				(font
					(size 1.27 1.27)
				)
			)
		)
		(duplicate_pad_numbers_are_jumpers no)
		(fp_line
			(start 0.7874 0.4064)
			(end -0.7874 0.4064)
			(stroke
				(width 0.1524)
				(type default)
			)
			(layer "F.SilkS")
		)
		(fp_line
			(start 0.7874 -0.4064)
			(end 0.7874 0.4064)
			(stroke
				(width 0.1524)
				(type default)
			)
			(layer "F.SilkS")
		)
		(fp_line
			(start -0.7874 0.4064)
			(end -0.7874 -0.4064)
			(stroke
				(width 0.1524)
				(type default)
			)
			(layer "F.SilkS")
		)
		(fp_line
			(start -0.7874 -0.4064)
			(end 0.7874 -0.4064)
			(stroke
				(width 0.1524)
				(type default)
			)
			(layer "F.SilkS")
		)
		(fp_line
			(start 0.67945 0.3048)
			(end 0.120396 0.3048)
			(stroke
				(width 0.1)
				(type default)
			)
			(layer "F.Fab")
		)
		(fp_line
			(start 0.67945 -0.3048)
			(end 0.67945 0.3048)
			(stroke
				(width 0.1)
				(type default)
			)
			(layer "F.Fab")
		)
		(fp_line
			(start 0.12065 -0.2794)
			(end 0.12065 -0.3048)
			(stroke
				(width 0.1)
				(type default)
			)
			(layer "F.Fab")
		)
		(fp_line
			(start 0.12065 -0.3048)
			(end 0.67945 -0.3048)
			(stroke
				(width 0.1)
				(type default)
			)
			(layer "F.Fab")
		)
		(fp_line
			(start 0.120396 0.3048)
			(end 0.120396 0.2794)
			(stroke
				(width 0.1)
				(type default)
			)
			(layer "F.Fab")
		)
		(fp_line
			(start 0.120396 0.2794)
			(end -0.12065 0.2794)
			(stroke
				(width 0.1)
				(type default)
			)
			(layer "F.Fab")
		)
		(fp_line
			(start -0.12065 0.3048)
			(end -0.67945 0.3048)
			(stroke
				(width 0.1)
				(type default)
			)
			(layer "F.Fab")
		)
		(fp_line
			(start -0.12065 0.2794)
			(end -0.12065 0.3048)
			(stroke
				(width 0.1)
				(type default)
			)
			(layer "F.Fab")
		)
		(fp_line
			(start -0.12065 -0.2794)
			(end 0.12065 -0.2794)
			(stroke
				(width 0.1)
				(type default)
			)
			(layer "F.Fab")
		)
		(fp_line
			(start -0.12065 -0.305054)
			(end -0.12065 -0.2794)
			(stroke
				(width 0.1)
				(type default)
			)
			(layer "F.Fab")
		)
		(fp_line
			(start -0.67945 0.3048)
			(end -0.67945 -0.305054)
			(stroke
				(width 0.1)
				(type default)
			)
			(layer "F.Fab")
		)
		(fp_line
			(start -0.67945 -0.305054)
			(end -0.12065 -0.305054)
			(stroke
				(width 0.1)
				(type default)
			)
			(layer "F.Fab")
		)
		(pad "1" smd circle
			(at -0.40005 0 180)
			(size 0 0)
			(layers "F.Cu" "F.Mask" "F.Paste")
			(net "P3V3_E1S_SENSE_0")
		)
		(pad "2" smd circle
			(at 0.40005 0 180)
			(size 0 0)
			(layers "F.Cu" "F.Mask" "F.Paste")
			(net "GND")
		)
	)
	(footprint ""
		(layer "F.Cu")
		(at 48.803306 19.444716 -90)
		(property "Reference" "JP6001_23"
			(at 0 0 270)
			(layer "F.SilkS")
			(hide yes)
			(effects
				(font
					(size 1.27 1.27)
				)
			)
		)
		(property "Value" ""
			(at 0 0 270)
			(layer "F.Fab")
			(effects
				(font
					(size 1.27 1.27)
				)
			)
		)
		(duplicate_pad_numbers_are_jumpers no)
		(pad "1" smd circle
			(at 0 0 270)
			(size 0.762 0.762)
			(layers "F.Cu" "F.Mask" "F.Paste")
			(net "Net_10791")
		)
	)
	(footprint ""
		(layer "F.Cu")
		(at 444.59652 -434.799232 90)
		(property "Reference" "R9043"
			(at 0 0 90)
			(layer "F.SilkS")
			(hide yes)
			(effects
				(font
					(size 1.27 1.27)
				)
			)
		)
		(property "Value" ""
			(at 0 0 90)
			(layer "F.Fab")
			(effects
				(font
					(size 1.27 1.27)
				)
			)
		)
		(duplicate_pad_numbers_are_jumpers no)
		(fp_line
			(start 0.7874 -0.4064)
			(end 0.7874 0.4064)
			(stroke
				(width 0.1524)
				(type default)
			)
			(layer "F.SilkS")
		)
		(fp_line
			(start -0.7874 -0.4064)
			(end 0.7874 -0.4064)
			(stroke
				(width 0.1524)
				(type default)
			)
			(layer "F.SilkS")
		)
		(fp_line
			(start 0.7874 0.4064)
			(end -0.7874 0.4064)
			(stroke
				(width 0.1524)
				(type default)
			)
			(layer "F.SilkS")
		)
		(fp_line
			(start -0.7874 0.4064)
			(end -0.7874 -0.4064)
			(stroke
				(width 0.1524)
				(type default)
			)
			(layer "F.SilkS")
		)
		(fp_line
			(start -0.12065 -0.305054)
			(end -0.12065 -0.2794)
			(stroke
				(width 0.1)
				(type default)
			)
			(layer "F.Fab")
		)
		(fp_line
			(start -0.67945 -0.305054)
			(end -0.12065 -0.305054)
			(stroke
				(width 0.1)
				(type default)
			)
			(layer "F.Fab")
		)
		(fp_line
			(start 0.67945 -0.3048)
			(end 0.67945 0.3048)
			(stroke
				(width 0.1)
				(type default)
			)
			(layer "F.Fab")
		)
		(fp_line
			(start 0.12065 -0.3048)
			(end 0.67945 -0.3048)
			(stroke
				(width 0.1)
				(type default)
			)
			(layer "F.Fab")
		)
		(fp_line
			(start 0.12065 -0.2794)
			(end 0.12065 -0.3048)
			(stroke
				(width 0.1)
				(type default)
			)
			(layer "F.Fab")
		)
		(fp_line
			(start -0.12065 -0.2794)
			(end 0.12065 -0.2794)
			(stroke
				(width 0.1)
				(type default)
			)
			(layer "F.Fab")
		)
		(fp_line
			(start 0.120396 0.2794)
			(end -0.12065 0.2794)
			(stroke
				(width 0.1)
				(type default)
			)
			(layer "F.Fab")
		)
		(fp_line
			(start -0.12065 0.2794)
			(end -0.12065 0.3048)
			(stroke
				(width 0.1)
				(type default)
			)
			(layer "F.Fab")
		)
		(fp_line
			(start 0.67945 0.3048)
			(end 0.120396 0.3048)
			(stroke
				(width 0.1)
				(type default)
			)
			(layer "F.Fab")
		)
		(fp_line
			(start 0.120396 0.3048)
			(end 0.120396 0.2794)
			(stroke
				(width 0.1)
				(type default)
			)
			(layer "F.Fab")
		)
		(fp_line
			(start -0.12065 0.3048)
			(end -0.67945 0.3048)
			(stroke
				(width 0.1)
				(type default)
			)
			(layer "F.Fab")
		)
		(fp_line
			(start -0.67945 0.3048)
			(end -0.67945 -0.305054)
			(stroke
				(width 0.1)
				(type default)
			)
			(layer "F.Fab")
		)
		(pad "1" smd circle
			(at -0.40005 0 90)
			(size 0 0)
			(layers "F.Cu" "F.Mask" "F.Paste")
			(net "P3V3_AUX")
		)
		(pad "2" smd circle
			(at 0.40005 0 90)
			(size 0 0)
			(layers "F.Cu" "F.Mask" "F.Paste")
			(net "GPU_WP_HW_CTRL_ISO")
		)
	)
	(footprint ""
		(layer "F.Cu")
		(at 150.246334 -191.371982 -90)
		(property "Reference" "R3196"
			(at 0 0 270)
			(layer "F.SilkS")
			(hide yes)
			(effects
				(font
					(size 1.27 1.27)
				)
			)
		)
		(property "Value" ""
			(at 0 0 270)
			(layer "F.Fab")
			(effects
				(font
					(size 1.27 1.27)
				)
			)
		)
		(duplicate_pad_numbers_are_jumpers no)
		(fp_line
			(start 0.440182 0.4064)
			(end -0.347218 0.4064)
			(stroke
				(width 0.1524)
				(type default)
			)
			(layer "F.SilkS")
		)
		(fp_line
			(start -0.7874 -0.020066)
			(end -0.7874 -0.4064)
			(stroke
				(width 0.1524)
				(type default)
			)
			(layer "F.SilkS")
		)
		(fp_line
			(start -0.7874 -0.4064)
			(end 0.7874 -0.4064)
			(stroke
				(width 0.1524)
				(type default)
			)
			(layer "F.SilkS")
		)
		(fp_line
			(start 0.7874 -0.4064)
			(end 0.7874 -0.020066)
			(stroke
				(width 0.1524)
				(type default)
			)
			(layer "F.SilkS")
		)
		(fp_line
			(start -0.67945 0.3048)
			(end -0.67945 -0.305054)
			(stroke
				(width 0.1)
				(type default)
			)
			(layer "F.Fab")
		)
		(fp_line
			(start -0.12065 0.3048)
			(end -0.67945 0.3048)
			(stroke
				(width 0.1)
				(type default)
			)
			(layer "F.Fab")
		)
		(fp_line
			(start 0.120396 0.3048)
			(end 0.120396 0.2794)
			(stroke
				(width 0.1)
				(type default)
			)
			(layer "F.Fab")
		)
		(fp_line
			(start 0.67945 0.3048)
			(end 0.120396 0.3048)
			(stroke
				(width 0.1)
				(type default)
			)
			(layer "F.Fab")
		)
		(fp_line
			(start -0.12065 0.2794)
			(end -0.12065 0.3048)
			(stroke
				(width 0.1)
				(type default)
			)
			(layer "F.Fab")
		)
		(fp_line
			(start 0.120396 0.2794)
			(end -0.12065 0.2794)
			(stroke
				(width 0.1)
				(type default)
			)
			(layer "F.Fab")
		)
		(fp_line
			(start -0.12065 -0.2794)
			(end 0.12065 -0.2794)
			(stroke
				(width 0.1)
				(type default)
			)
			(layer "F.Fab")
		)
		(fp_line
			(start 0.12065 -0.2794)
			(end 0.12065 -0.3048)
			(stroke
				(width 0.1)
				(type default)
			)
			(layer "F.Fab")
		)
		(fp_line
			(start 0.12065 -0.3048)
			(end 0.67945 -0.3048)
			(stroke
				(width 0.1)
				(type default)
			)
			(layer "F.Fab")
		)
		(fp_line
			(start 0.67945 -0.3048)
			(end 0.67945 0.3048)
			(stroke
				(width 0.1)
				(type default)
			)
			(layer "F.Fab")
		)
		(fp_line
			(start -0.67945 -0.305054)
			(end -0.12065 -0.305054)
			(stroke
				(width 0.1)
				(type default)
			)
			(layer "F.Fab")
		)
		(fp_line
			(start -0.12065 -0.305054)
			(end -0.12065 -0.2794)
			(stroke
				(width 0.1)
				(type default)
			)
			(layer "F.Fab")
		)
		(pad "1" smd circle
			(at -0.40005 0 270)
			(size 0 0)
			(layers "F.Cu" "F.Mask" "F.Paste")
			(net "CLK_100M_CPU1_CLK03_R_DP")
		)
		(pad "2" smd circle
			(at 0.40005 0 270)
			(size 0 0)
			(layers "F.Cu" "F.Mask" "F.Paste")
			(net "CLK_100M_CPU1_CLK03_DP")
		)
	)
	(footprint ""
		(layer "F.Cu")
		(at 426.6819 -109.644688 90)
		(property "Reference" "PC2081"
			(at 0 0 90)
			(layer "F.SilkS")
			(hide yes)
			(effects
				(font
					(size 1.27 1.27)
				)
			)
		)
		(property "Value" ""
			(at 0 0 90)
			(layer "F.Fab")
			(effects
				(font
					(size 1.27 1.27)
				)
			)
		)
		(duplicate_pad_numbers_are_jumpers no)
		(fp_line
			(start 1.524 -0.762)
			(end 1.524 0.762)
			(stroke
				(width 0.1524)
				(type default)
			)
			(layer "F.SilkS")
		)
		(fp_line
			(start -1.524 -0.762)
			(end 1.524 -0.762)
			(stroke
				(width 0.1524)
				(type default)
			)
			(layer "F.SilkS")
		)
		(fp_line
			(start 1.524 0.762)
			(end -1.524 0.762)
			(stroke
				(width 0.1524)
				(type default)
			)
			(layer "F.SilkS")
		)
		(fp_line
			(start -1.524 0.762)
			(end -1.524 -0.762)
			(stroke
				(width 0.1524)
				(type default)
			)
			(layer "F.SilkS")
		)
		(fp_line
			(start 1.1049 -0.724916)
			(end -1.1049 -0.724916)
			(stroke
				(width 0.1)
				(type default)
			)
			(layer "F.Fab")
		)
		(fp_line
			(start -1.1049 -0.724916)
			(end -1.1049 0.724916)
			(stroke
				(width 0.1)
				(type default)
			)
			(layer "F.Fab")
		)
		(fp_line
			(start 1.1049 0.724916)
			(end 1.1049 -0.724916)
			(stroke
				(width 0.1)
				(type default)
			)
			(layer "F.Fab")
		)
		(fp_line
			(start -1.1049 0.724916)
			(end 1.1049 0.724916)
			(stroke
				(width 0.1)
				(type default)
			)
			(layer "F.Fab")
		)
		(pad "1" smd rect
			(at -0.889 0 270)
			(size 1.016 1.27)
			(layers "F.Cu" "F.Mask" "F.Paste")
			(net "P3V3_OCP_SFF_R")
		)
		(pad "2" smd rect
			(at 0.889 0 270)
			(size 1.016 1.27)
			(layers "F.Cu" "F.Mask" "F.Paste")
			(net "GND")
		)
	)
	(footprint ""
		(layer "F.Cu")
		(at 204.689456 -339.428836)
		(property "Reference" "PR452"
			(at 0 0 0)
			(layer "F.SilkS")
			(hide yes)
			(effects
				(font
					(size 1.27 1.27)
				)
			)
		)
		(property "Value" ""
			(at 0 0 0)
			(layer "F.Fab")
			(effects
				(font
					(size 1.27 1.27)
				)
			)
		)
		(duplicate_pad_numbers_are_jumpers no)
		(fp_line
			(start -0.7874 -0.4064)
			(end 0.7874 -0.4064)
			(stroke
				(width 0.1524)
				(type default)
			)
			(layer "F.SilkS")
		)
		(fp_line
			(start -0.7874 0.4064)
			(end -0.7874 -0.4064)
			(stroke
				(width 0.1524)
				(type default)
			)
			(layer "F.SilkS")
		)
		(fp_line
			(start 0.7874 -0.4064)
			(end 0.7874 0.4064)
			(stroke
				(width 0.1524)
				(type default)
			)
			(layer "F.SilkS")
		)
		(fp_line
			(start 0.7874 0.4064)
			(end -0.7874 0.4064)
			(stroke
				(width 0.1524)
				(type default)
			)
			(layer "F.SilkS")
		)
		(fp_line
			(start -0.67945 -0.305054)
			(end -0.12065 -0.305054)
			(stroke
				(width 0.1)
				(type default)
			)
			(layer "F.Fab")
		)
		(fp_line
			(start -0.67945 0.3048)
			(end -0.67945 -0.305054)
			(stroke
				(width 0.1)
				(type default)
			)
			(layer "F.Fab")
		)
		(fp_line
			(start -0.12065 -0.305054)
			(end -0.12065 -0.2794)
			(stroke
				(width 0.1)
				(type default)
			)
			(layer "F.Fab")
		)
		(fp_line
			(start -0.12065 -0.2794)
			(end 0.12065 -0.2794)
			(stroke
				(width 0.1)
				(type default)
			)
			(layer "F.Fab")
		)
		(fp_line
			(start -0.12065 0.2794)
			(end -0.12065 0.3048)
			(stroke
				(width 0.1)
				(type default)
			)
			(layer "F.Fab")
		)
		(fp_line
			(start -0.12065 0.3048)
			(end -0.67945 0.3048)
			(stroke
				(width 0.1)
				(type default)
			)
			(layer "F.Fab")
		)
		(fp_line
			(start 0.120396 0.2794)
			(end -0.12065 0.2794)
			(stroke
				(width 0.1)
				(type default)
			)
			(layer "F.Fab")
		)
		(fp_line
			(start 0.120396 0.3048)
			(end 0.120396 0.2794)
			(stroke
				(width 0.1)
				(type default)
			)
			(layer "F.Fab")
		)
		(fp_line
			(start 0.12065 -0.3048)
			(end 0.67945 -0.3048)
			(stroke
				(width 0.1)
				(type default)
			)
			(layer "F.Fab")
		)
		(fp_line
			(start 0.12065 -0.2794)
			(end 0.12065 -0.3048)
			(stroke
				(width 0.1)
				(type default)
			)
			(layer "F.Fab")
		)
		(fp_line
			(start 0.67945 -0.3048)
			(end 0.67945 0.3048)
			(stroke
				(width 0.1)
				(type default)
			)
			(layer "F.Fab")
		)
		(fp_line
			(start 0.67945 0.3048)
			(end 0.120396 0.3048)
			(stroke
				(width 0.1)
				(type default)
			)
			(layer "F.Fab")
		)
		(pad "1" smd circle
			(at -0.40005 0)
			(size 0 0)
			(layers "F.Cu" "F.Mask" "F.Paste")
			(net "PVDD_33_S5_CS")
		)
		(pad "2" smd circle
			(at 0.40005 0)
			(size 0 0)
			(layers "F.Cu" "F.Mask" "F.Paste")
			(net "GND")
		)
	)
	(footprint ""
		(layer "F.Cu")
		(at 424.5356 -423.2402 90)
		(property "Reference" "R1409"
			(at 0 0 90)
			(layer "F.SilkS")
			(hide yes)
			(effects
				(font
					(size 1.27 1.27)
				)
			)
		)
		(property "Value" ""
			(at 0 0 90)
			(layer "F.Fab")
			(effects
				(font
					(size 1.27 1.27)
				)
			)
		)
		(duplicate_pad_numbers_are_jumpers no)
		(fp_line
			(start 0.32512 -0.175006)
			(end 0.32512 0.175006)
			(stroke
				(width 0.1)
				(type default)
			)
			(layer "F.Fab")
		)
		(fp_line
			(start -0.32512 -0.175006)
			(end 0.32512 -0.175006)
			(stroke
				(width 0.1)
				(type default)
			)
			(layer "F.Fab")
		)
		(fp_line
			(start 0.32512 0.175006)
			(end -0.32512 0.175006)
			(stroke
				(width 0.1)
				(type default)
			)
			(layer "F.Fab")
		)
		(fp_line
			(start -0.32512 0.175006)
			(end -0.32512 -0.175006)
			(stroke
				(width 0.1)
				(type default)
			)
			(layer "F.Fab")
		)
		(pad "1" smd rect
			(at -0.2667 0 90)
			(size 0.3048 0.381)
			(layers "F.Cu" "F.Mask" "F.Paste")
			(net "JTAG_TCK_RT_CPU0_P3")
		)
		(pad "2" smd rect
			(at 0.2667 0 270)
			(size 0.3048 0.381)
			(layers "F.Cu" "F.Mask" "F.Paste")
			(net "GND")
		)
	)
	(footprint ""
		(layer "F.Cu")
		(at 19.241516 -38.910514 180)
		(property "Reference" "R1360"
			(at 0 0 180)
			(layer "F.SilkS")
			(hide yes)
			(effects
				(font
					(size 1.27 1.27)
				)
			)
		)
		(property "Value" ""
			(at 0 0 180)
			(layer "F.Fab")
			(effects
				(font
					(size 1.27 1.27)
				)
			)
		)
		(duplicate_pad_numbers_are_jumpers no)
		(fp_line
			(start 0.7874 0.4064)
			(end -0.7874 0.4064)
			(stroke
				(width 0.1524)
				(type default)
			)
			(layer "F.SilkS")
		)
		(fp_line
			(start 0.7874 -0.4064)
			(end 0.7874 0.4064)
			(stroke
				(width 0.1524)
				(type default)
			)
			(layer "F.SilkS")
		)
		(fp_line
			(start -0.7874 0.4064)
			(end -0.7874 -0.4064)
			(stroke
				(width 0.1524)
				(type default)
			)
			(layer "F.SilkS")
		)
		(fp_line
			(start -0.7874 -0.4064)
			(end 0.7874 -0.4064)
			(stroke
				(width 0.1524)
				(type default)
			)
			(layer "F.SilkS")
		)
		(fp_line
			(start 0.67945 0.3048)
			(end 0.120396 0.3048)
			(stroke
				(width 0.1)
				(type default)
			)
			(layer "F.Fab")
		)
		(fp_line
			(start 0.67945 -0.3048)
			(end 0.67945 0.3048)
			(stroke
				(width 0.1)
				(type default)
			)
			(layer "F.Fab")
		)
		(fp_line
			(start 0.12065 -0.2794)
			(end 0.12065 -0.3048)
			(stroke
				(width 0.1)
				(type default)
			)
			(layer "F.Fab")
		)
		(fp_line
			(start 0.12065 -0.3048)
			(end 0.67945 -0.3048)
			(stroke
				(width 0.1)
				(type default)
			)
			(layer "F.Fab")
		)
		(fp_line
			(start 0.120396 0.3048)
			(end 0.120396 0.2794)
			(stroke
				(width 0.1)
				(type default)
			)
			(layer "F.Fab")
		)
		(fp_line
			(start 0.120396 0.2794)
			(end -0.12065 0.2794)
			(stroke
				(width 0.1)
				(type default)
			)
			(layer "F.Fab")
		)
		(fp_line
			(start -0.12065 0.3048)
			(end -0.67945 0.3048)
			(stroke
				(width 0.1)
				(type default)
			)
			(layer "F.Fab")
		)
		(fp_line
			(start -0.12065 0.2794)
			(end -0.12065 0.3048)
			(stroke
				(width 0.1)
				(type default)
			)
			(layer "F.Fab")
		)
		(fp_line
			(start -0.12065 -0.2794)
			(end 0.12065 -0.2794)
			(stroke
				(width 0.1)
				(type default)
			)
			(layer "F.Fab")
		)
		(fp_line
			(start -0.12065 -0.305054)
			(end -0.12065 -0.2794)
			(stroke
				(width 0.1)
				(type default)
			)
			(layer "F.Fab")
		)
		(fp_line
			(start -0.67945 0.3048)
			(end -0.67945 -0.305054)
			(stroke
				(width 0.1)
				(type default)
			)
			(layer "F.Fab")
		)
		(fp_line
			(start -0.67945 -0.305054)
			(end -0.12065 -0.305054)
			(stroke
				(width 0.1)
				(type default)
			)
			(layer "F.Fab")
		)
		(pad "1" smd circle
			(at -0.40005 0 180)
			(size 0 0)
			(layers "F.Cu" "F.Mask" "F.Paste")
			(net "INA230_7_A0")
		)
		(pad "2" smd circle
			(at 0.40005 0 180)
			(size 0 0)
			(layers "F.Cu" "F.Mask" "F.Paste")
			(net "SMB_INA230_7_3V3AUX_SCL_R1")
		)
	)
	(footprint ""
		(layer "F.Cu")
		(at 200.939908 -107.529376 180)
		(property "Reference" "R208"
			(at 0 0 180)
			(layer "F.SilkS")
			(hide yes)
			(effects
				(font
					(size 1.27 1.27)
				)
			)
		)
		(property "Value" ""
			(at 0 0 180)
			(layer "F.Fab")
			(effects
				(font
					(size 1.27 1.27)
				)
			)
		)
		(duplicate_pad_numbers_are_jumpers no)
		(fp_line
			(start 0.7874 0.4064)
			(end -0.7874 0.4064)
			(stroke
				(width 0.1524)
				(type default)
			)
			(layer "F.SilkS")
		)
		(fp_line
			(start 0.7874 -0.4064)
			(end 0.7874 0.4064)
			(stroke
				(width 0.1524)
				(type default)
			)
			(layer "F.SilkS")
		)
		(fp_line
			(start -0.7874 0.4064)
			(end -0.7874 -0.4064)
			(stroke
				(width 0.1524)
				(type default)
			)
			(layer "F.SilkS")
		)
		(fp_line
			(start -0.7874 -0.4064)
			(end 0.7874 -0.4064)
			(stroke
				(width 0.1524)
				(type default)
			)
			(layer "F.SilkS")
		)
		(fp_line
			(start 0.67945 0.3048)
			(end 0.120396 0.3048)
			(stroke
				(width 0.1)
				(type default)
			)
			(layer "F.Fab")
		)
		(fp_line
			(start 0.67945 -0.3048)
			(end 0.67945 0.3048)
			(stroke
				(width 0.1)
				(type default)
			)
			(layer "F.Fab")
		)
		(fp_line
			(start 0.12065 -0.2794)
			(end 0.12065 -0.3048)
			(stroke
				(width 0.1)
				(type default)
			)
			(layer "F.Fab")
		)
		(fp_line
			(start 0.12065 -0.3048)
			(end 0.67945 -0.3048)
			(stroke
				(width 0.1)
				(type default)
			)
			(layer "F.Fab")
		)
		(fp_line
			(start 0.120396 0.3048)
			(end 0.120396 0.2794)
			(stroke
				(width 0.1)
				(type default)
			)
			(layer "F.Fab")
		)
		(fp_line
			(start 0.120396 0.2794)
			(end -0.12065 0.2794)
			(stroke
				(width 0.1)
				(type default)
			)
			(layer "F.Fab")
		)
		(fp_line
			(start -0.12065 0.3048)
			(end -0.67945 0.3048)
			(stroke
				(width 0.1)
				(type default)
			)
			(layer "F.Fab")
		)
		(fp_line
			(start -0.12065 0.2794)
			(end -0.12065 0.3048)
			(stroke
				(width 0.1)
				(type default)
			)
			(layer "F.Fab")
		)
		(fp_line
			(start -0.12065 -0.2794)
			(end 0.12065 -0.2794)
			(stroke
				(width 0.1)
				(type default)
			)
			(layer "F.Fab")
		)
		(fp_line
			(start -0.12065 -0.305054)
			(end -0.12065 -0.2794)
			(stroke
				(width 0.1)
				(type default)
			)
			(layer "F.Fab")
		)
		(fp_line
			(start -0.67945 0.3048)
			(end -0.67945 -0.305054)
			(stroke
				(width 0.1)
				(type default)
			)
			(layer "F.Fab")
		)
		(fp_line
			(start -0.67945 -0.305054)
			(end -0.12065 -0.305054)
			(stroke
				(width 0.1)
				(type default)
			)
			(layer "F.Fab")
		)
		(pad "1" smd circle
			(at -0.40005 0 180)
			(size 0 0)
			(layers "F.Cu" "F.Mask" "F.Paste")
			(net "PVDDCR_CPU0_P1_EN")
		)
		(pad "2" smd circle
			(at 0.40005 0 180)
			(size 0 0)
			(layers "F.Cu" "F.Mask" "F.Paste")
			(net "FM_PVDDCR_CPU0_P1_R_EN")
		)
	)
	(footprint ""
		(layer "F.Cu")
		(at 62.861698 -26.99004 90)
		(property "Reference" "PR3853"
			(at 0 0 90)
			(layer "F.SilkS")
			(hide yes)
			(effects
				(font
					(size 1.27 1.27)
				)
			)
		)
		(property "Value" ""
			(at 0 0 90)
			(layer "F.Fab")
			(effects
				(font
					(size 1.27 1.27)
				)
			)
		)
		(duplicate_pad_numbers_are_jumpers no)
		(fp_line
			(start 0.7874 -0.4064)
			(end 0.7874 0.4064)
			(stroke
				(width 0.1524)
				(type default)
			)
			(layer "F.SilkS")
		)
		(fp_line
			(start -0.7874 -0.4064)
			(end 0.7874 -0.4064)
			(stroke
				(width 0.1524)
				(type default)
			)
			(layer "F.SilkS")
		)
		(fp_line
			(start 0.7874 0.4064)
			(end -0.7874 0.4064)
			(stroke
				(width 0.1524)
				(type default)
			)
			(layer "F.SilkS")
		)
		(fp_line
			(start -0.7874 0.4064)
			(end -0.7874 -0.4064)
			(stroke
				(width 0.1524)
				(type default)
			)
			(layer "F.SilkS")
		)
		(fp_line
			(start -0.12065 -0.305054)
			(end -0.12065 -0.2794)
			(stroke
				(width 0.1)
				(type default)
			)
			(layer "F.Fab")
		)
		(fp_line
			(start -0.67945 -0.305054)
			(end -0.12065 -0.305054)
			(stroke
				(width 0.1)
				(type default)
			)
			(layer "F.Fab")
		)
		(fp_line
			(start 0.67945 -0.3048)
			(end 0.67945 0.3048)
			(stroke
				(width 0.1)
				(type default)
			)
			(layer "F.Fab")
		)
		(fp_line
			(start 0.12065 -0.3048)
			(end 0.67945 -0.3048)
			(stroke
				(width 0.1)
				(type default)
			)
			(layer "F.Fab")
		)
		(fp_line
			(start 0.12065 -0.2794)
			(end 0.12065 -0.3048)
			(stroke
				(width 0.1)
				(type default)
			)
			(layer "F.Fab")
		)
		(fp_line
			(start -0.12065 -0.2794)
			(end 0.12065 -0.2794)
			(stroke
				(width 0.1)
				(type default)
			)
			(layer "F.Fab")
		)
		(fp_line
			(start 0.120396 0.2794)
			(end -0.12065 0.2794)
			(stroke
				(width 0.1)
				(type default)
			)
			(layer "F.Fab")
		)
		(fp_line
			(start -0.12065 0.2794)
			(end -0.12065 0.3048)
			(stroke
				(width 0.1)
				(type default)
			)
			(layer "F.Fab")
		)
		(fp_line
			(start 0.67945 0.3048)
			(end 0.120396 0.3048)
			(stroke
				(width 0.1)
				(type default)
			)
			(layer "F.Fab")
		)
		(fp_line
			(start 0.120396 0.3048)
			(end 0.120396 0.2794)
			(stroke
				(width 0.1)
				(type default)
			)
			(layer "F.Fab")
		)
		(fp_line
			(start -0.12065 0.3048)
			(end -0.67945 0.3048)
			(stroke
				(width 0.1)
				(type default)
			)
			(layer "F.Fab")
		)
		(fp_line
			(start -0.67945 0.3048)
			(end -0.67945 -0.305054)
			(stroke
				(width 0.1)
				(type default)
			)
			(layer "F.Fab")
		)
		(pad "1" smd circle
			(at -0.40005 0 90)
			(size 0 0)
			(layers "F.Cu" "F.Mask" "F.Paste")
			(net "P12V_AUX")
		)
		(pad "2" smd circle
			(at 0.40005 0 90)
			(size 0 0)
			(layers "F.Cu" "F.Mask" "F.Paste")
			(net "P12V_OCP_OV_FB_2")
		)
	)
	(footprint ""
		(layer "F.Cu")
		(at 76.07173 -388.030974 90)
		(property "Reference" "R626"
			(at 0 0 90)
			(layer "F.SilkS")
			(hide yes)
			(effects
				(font
					(size 1.27 1.27)
				)
			)
		)
		(property "Value" ""
			(at 0 0 90)
			(layer "F.Fab")
			(effects
				(font
					(size 1.27 1.27)
				)
			)
		)
		(duplicate_pad_numbers_are_jumpers no)
		(fp_line
			(start 0.32512 -0.175006)
			(end 0.32512 0.175006)
			(stroke
				(width 0.1)
				(type default)
			)
			(layer "F.Fab")
		)
		(fp_line
			(start -0.32512 -0.175006)
			(end 0.32512 -0.175006)
			(stroke
				(width 0.1)
				(type default)
			)
			(layer "F.Fab")
		)
		(fp_line
			(start 0.32512 0.175006)
			(end -0.32512 0.175006)
			(stroke
				(width 0.1)
				(type default)
			)
			(layer "F.Fab")
		)
		(fp_line
			(start -0.32512 0.175006)
			(end -0.32512 -0.175006)
			(stroke
				(width 0.1)
				(type default)
			)
			(layer "F.Fab")
		)
		(pad "1" smd rect
			(at -0.2667 0 90)
			(size 0.3048 0.381)
			(layers "F.Cu" "F.Mask" "F.Paste")
			(net "CLK_100M_RETIMER_CPU1_P1_DP")
		)
		(pad "2" smd rect
			(at 0.2667 0 270)
			(size 0.3048 0.381)
			(layers "F.Cu" "F.Mask" "F.Paste")
			(net "GND")
		)
	)
	(footprint ""
		(layer "F.Cu")
		(at 136.962388 -384.10388 180)
		(property "Reference" "R893"
			(at 0 0 180)
			(layer "F.SilkS")
			(hide yes)
			(effects
				(font
					(size 1.27 1.27)
				)
			)
		)
		(property "Value" ""
			(at 0 0 180)
			(layer "F.Fab")
			(effects
				(font
					(size 1.27 1.27)
				)
			)
		)
		(duplicate_pad_numbers_are_jumpers no)
		(fp_line
			(start 0.7874 0.4064)
			(end -0.7874 0.4064)
			(stroke
				(width 0.1524)
				(type default)
			)
			(layer "F.SilkS")
		)
		(fp_line
			(start 0.7874 -0.4064)
			(end 0.7874 0.4064)
			(stroke
				(width 0.1524)
				(type default)
			)
			(layer "F.SilkS")
		)
		(fp_line
			(start -0.7874 0.4064)
			(end -0.7874 -0.4064)
			(stroke
				(width 0.1524)
				(type default)
			)
			(layer "F.SilkS")
		)
		(fp_line
			(start -0.7874 -0.4064)
			(end 0.7874 -0.4064)
			(stroke
				(width 0.1524)
				(type default)
			)
			(layer "F.SilkS")
		)
		(fp_line
			(start 0.67945 0.3048)
			(end 0.120396 0.3048)
			(stroke
				(width 0.1)
				(type default)
			)
			(layer "F.Fab")
		)
		(fp_line
			(start 0.67945 -0.3048)
			(end 0.67945 0.3048)
			(stroke
				(width 0.1)
				(type default)
			)
			(layer "F.Fab")
		)
		(fp_line
			(start 0.12065 -0.2794)
			(end 0.12065 -0.3048)
			(stroke
				(width 0.1)
				(type default)
			)
			(layer "F.Fab")
		)
		(fp_line
			(start 0.12065 -0.3048)
			(end 0.67945 -0.3048)
			(stroke
				(width 0.1)
				(type default)
			)
			(layer "F.Fab")
		)
		(fp_line
			(start 0.120396 0.3048)
			(end 0.120396 0.2794)
			(stroke
				(width 0.1)
				(type default)
			)
			(layer "F.Fab")
		)
		(fp_line
			(start 0.120396 0.2794)
			(end -0.12065 0.2794)
			(stroke
				(width 0.1)
				(type default)
			)
			(layer "F.Fab")
		)
		(fp_line
			(start -0.12065 0.3048)
			(end -0.67945 0.3048)
			(stroke
				(width 0.1)
				(type default)
			)
			(layer "F.Fab")
		)
		(fp_line
			(start -0.12065 0.2794)
			(end -0.12065 0.3048)
			(stroke
				(width 0.1)
				(type default)
			)
			(layer "F.Fab")
		)
		(fp_line
			(start -0.12065 -0.2794)
			(end 0.12065 -0.2794)
			(stroke
				(width 0.1)
				(type default)
			)
			(layer "F.Fab")
		)
		(fp_line
			(start -0.12065 -0.305054)
			(end -0.12065 -0.2794)
			(stroke
				(width 0.1)
				(type default)
			)
			(layer "F.Fab")
		)
		(fp_line
			(start -0.67945 0.3048)
			(end -0.67945 -0.305054)
			(stroke
				(width 0.1)
				(type default)
			)
			(layer "F.Fab")
		)
		(fp_line
			(start -0.67945 -0.305054)
			(end -0.12065 -0.305054)
			(stroke
				(width 0.1)
				(type default)
			)
			(layer "F.Fab")
		)
		(pad "1" smd rect
			(at -0.40005 0)
			(size 0.4572 0.508)
			(layers "F.Cu" "F.Mask" "F.Paste")
			(net "P1V8_CPU1_RT3_1A_1D")
		)
		(pad "2" smd rect
			(at 0.40005 0)
			(size 0.4572 0.508)
			(layers "F.Cu" "F.Mask" "F.Paste")
			(net "P1V8_CPU1_RT3_1A")
		)
	)
	(footprint ""
		(layer "F.Cu")
		(at 254.592836 -116.12245)
		(property "Reference" "R3727"
			(at 0 0 0)
			(layer "F.SilkS")
			(hide yes)
			(effects
				(font
					(size 1.27 1.27)
				)
			)
		)
		(property "Value" ""
			(at 0 0 0)
			(layer "F.Fab")
			(effects
				(font
					(size 1.27 1.27)
				)
			)
		)
		(duplicate_pad_numbers_are_jumpers no)
		(fp_line
			(start -0.7874 -0.4064)
			(end 0.7874 -0.4064)
			(stroke
				(width 0.1524)
				(type default)
			)
			(layer "F.SilkS")
		)
		(fp_line
			(start -0.7874 0.4064)
			(end -0.7874 -0.4064)
			(stroke
				(width 0.1524)
				(type default)
			)
			(layer "F.SilkS")
		)
		(fp_line
			(start 0.7874 -0.4064)
			(end 0.7874 0.4064)
			(stroke
				(width 0.1524)
				(type default)
			)
			(layer "F.SilkS")
		)
		(fp_line
			(start 0.7874 0.4064)
			(end -0.7874 0.4064)
			(stroke
				(width 0.1524)
				(type default)
			)
			(layer "F.SilkS")
		)
		(fp_line
			(start -0.67945 -0.305054)
			(end -0.12065 -0.305054)
			(stroke
				(width 0.1)
				(type default)
			)
			(layer "F.Fab")
		)
		(fp_line
			(start -0.67945 0.3048)
			(end -0.67945 -0.305054)
			(stroke
				(width 0.1)
				(type default)
			)
			(layer "F.Fab")
		)
		(fp_line
			(start -0.12065 -0.305054)
			(end -0.12065 -0.2794)
			(stroke
				(width 0.1)
				(type default)
			)
			(layer "F.Fab")
		)
		(fp_line
			(start -0.12065 -0.2794)
			(end 0.12065 -0.2794)
			(stroke
				(width 0.1)
				(type default)
			)
			(layer "F.Fab")
		)
		(fp_line
			(start -0.12065 0.2794)
			(end -0.12065 0.3048)
			(stroke
				(width 0.1)
				(type default)
			)
			(layer "F.Fab")
		)
		(fp_line
			(start -0.12065 0.3048)
			(end -0.67945 0.3048)
			(stroke
				(width 0.1)
				(type default)
			)
			(layer "F.Fab")
		)
		(fp_line
			(start 0.120396 0.2794)
			(end -0.12065 0.2794)
			(stroke
				(width 0.1)
				(type default)
			)
			(layer "F.Fab")
		)
		(fp_line
			(start 0.120396 0.3048)
			(end 0.120396 0.2794)
			(stroke
				(width 0.1)
				(type default)
			)
			(layer "F.Fab")
		)
		(fp_line
			(start 0.12065 -0.3048)
			(end 0.67945 -0.3048)
			(stroke
				(width 0.1)
				(type default)
			)
			(layer "F.Fab")
		)
		(fp_line
			(start 0.12065 -0.2794)
			(end 0.12065 -0.3048)
			(stroke
				(width 0.1)
				(type default)
			)
			(layer "F.Fab")
		)
		(fp_line
			(start 0.67945 -0.3048)
			(end 0.67945 0.3048)
			(stroke
				(width 0.1)
				(type default)
			)
			(layer "F.Fab")
		)
		(fp_line
			(start 0.67945 0.3048)
			(end 0.120396 0.3048)
			(stroke
				(width 0.1)
				(type default)
			)
			(layer "F.Fab")
		)
		(pad "1" smd circle
			(at -0.40005 0)
			(size 0 0)
			(layers "F.Cu" "F.Mask" "F.Paste")
			(net "P3V3_AUX")
		)
		(pad "2" smd circle
			(at 0.40005 0)
			(size 0 0)
			(layers "F.Cu" "F.Mask" "F.Paste")
			(net "SMB_LM75_1_3V3AUX_SCL")
		)
	)
	(footprint ""
		(layer "F.Cu")
		(at 246.22506 -53.997606 90)
		(property "Reference" "PC2219"
			(at 0 0 90)
			(layer "F.SilkS")
			(hide yes)
			(effects
				(font
					(size 1.27 1.27)
				)
			)
		)
		(property "Value" ""
			(at 0 0 90)
			(layer "F.Fab")
			(effects
				(font
					(size 1.27 1.27)
				)
			)
		)
		(duplicate_pad_numbers_are_jumpers no)
		(fp_line
			(start 1.524 -0.762)
			(end 1.524 0.762)
			(stroke
				(width 0.1524)
				(type default)
			)
			(layer "F.SilkS")
		)
		(fp_line
			(start -1.524 -0.762)
			(end 1.524 -0.762)
			(stroke
				(width 0.1524)
				(type default)
			)
			(layer "F.SilkS")
		)
		(fp_line
			(start 1.524 0.762)
			(end -1.524 0.762)
			(stroke
				(width 0.1524)
				(type default)
			)
			(layer "F.SilkS")
		)
		(fp_line
			(start -1.524 0.762)
			(end -1.524 -0.762)
			(stroke
				(width 0.1524)
				(type default)
			)
			(layer "F.SilkS")
		)
		(fp_line
			(start 1.1049 -0.724916)
			(end -1.1049 -0.724916)
			(stroke
				(width 0.1)
				(type default)
			)
			(layer "F.Fab")
		)
		(fp_line
			(start -1.1049 -0.724916)
			(end -1.1049 0.724916)
			(stroke
				(width 0.1)
				(type default)
			)
			(layer "F.Fab")
		)
		(fp_line
			(start 1.1049 0.724916)
			(end 1.1049 -0.724916)
			(stroke
				(width 0.1)
				(type default)
			)
			(layer "F.Fab")
		)
		(fp_line
			(start -1.1049 0.724916)
			(end 1.1049 0.724916)
			(stroke
				(width 0.1)
				(type default)
			)
			(layer "F.Fab")
		)
		(pad "1" smd rect
			(at -0.889 0 270)
			(size 1.016 1.27)
			(layers "F.Cu" "F.Mask" "F.Paste")
			(net "P12V_E1S_0")
		)
		(pad "2" smd rect
			(at 0.889 0 270)
			(size 1.016 1.27)
			(layers "F.Cu" "F.Mask" "F.Paste")
			(net "GND")
		)
	)
	(footprint ""
		(layer "F.Cu")
		(at 400.22272 -330.575666 90)
		(property "Reference" "R459"
			(at 0 0 90)
			(layer "F.SilkS")
			(hide yes)
			(effects
				(font
					(size 1.27 1.27)
				)
			)
		)
		(property "Value" ""
			(at 0 0 90)
			(layer "F.Fab")
			(effects
				(font
					(size 1.27 1.27)
				)
			)
		)
		(duplicate_pad_numbers_are_jumpers no)
		(fp_line
			(start 0.7874 -0.4064)
			(end 0.7874 0.4064)
			(stroke
				(width 0.1524)
				(type default)
			)
			(layer "F.SilkS")
		)
		(fp_line
			(start -0.7874 -0.4064)
			(end 0.7874 -0.4064)
			(stroke
				(width 0.1524)
				(type default)
			)
			(layer "F.SilkS")
		)
		(fp_line
			(start 0.7874 0.4064)
			(end -0.7874 0.4064)
			(stroke
				(width 0.1524)
				(type default)
			)
			(layer "F.SilkS")
		)
		(fp_line
			(start -0.7874 0.4064)
			(end -0.7874 -0.4064)
			(stroke
				(width 0.1524)
				(type default)
			)
			(layer "F.SilkS")
		)
		(fp_line
			(start -0.12065 -0.305054)
			(end -0.12065 -0.2794)
			(stroke
				(width 0.1)
				(type default)
			)
			(layer "F.Fab")
		)
		(fp_line
			(start -0.67945 -0.305054)
			(end -0.12065 -0.305054)
			(stroke
				(width 0.1)
				(type default)
			)
			(layer "F.Fab")
		)
		(fp_line
			(start 0.67945 -0.3048)
			(end 0.67945 0.3048)
			(stroke
				(width 0.1)
				(type default)
			)
			(layer "F.Fab")
		)
		(fp_line
			(start 0.12065 -0.3048)
			(end 0.67945 -0.3048)
			(stroke
				(width 0.1)
				(type default)
			)
			(layer "F.Fab")
		)
		(fp_line
			(start 0.12065 -0.2794)
			(end 0.12065 -0.3048)
			(stroke
				(width 0.1)
				(type default)
			)
			(layer "F.Fab")
		)
		(fp_line
			(start -0.12065 -0.2794)
			(end 0.12065 -0.2794)
			(stroke
				(width 0.1)
				(type default)
			)
			(layer "F.Fab")
		)
		(fp_line
			(start 0.120396 0.2794)
			(end -0.12065 0.2794)
			(stroke
				(width 0.1)
				(type default)
			)
			(layer "F.Fab")
		)
		(fp_line
			(start -0.12065 0.2794)
			(end -0.12065 0.3048)
			(stroke
				(width 0.1)
				(type default)
			)
			(layer "F.Fab")
		)
		(fp_line
			(start 0.67945 0.3048)
			(end 0.120396 0.3048)
			(stroke
				(width 0.1)
				(type default)
			)
			(layer "F.Fab")
		)
		(fp_line
			(start 0.120396 0.3048)
			(end 0.120396 0.2794)
			(stroke
				(width 0.1)
				(type default)
			)
			(layer "F.Fab")
		)
		(fp_line
			(start -0.12065 0.3048)
			(end -0.67945 0.3048)
			(stroke
				(width 0.1)
				(type default)
			)
			(layer "F.Fab")
		)
		(fp_line
			(start -0.67945 0.3048)
			(end -0.67945 -0.305054)
			(stroke
				(width 0.1)
				(type default)
			)
			(layer "F.Fab")
		)
		(pad "1" smd circle
			(at -0.40005 0 90)
			(size 0 0)
			(layers "F.Cu" "F.Mask" "F.Paste")
			(net "SPI_CPU0_CS0_N")
		)
		(pad "2" smd circle
			(at 0.40005 0 90)
			(size 0 0)
			(layers "F.Cu" "F.Mask" "F.Paste")
			(net "SPI_CPU0_R_CS0_N")
		)
	)
	(footprint ""
		(layer "F.Cu")
		(at 327.179178 -41.160954)
		(property "Reference" "R1785"
			(at 0 0 0)
			(layer "F.SilkS")
			(hide yes)
			(effects
				(font
					(size 1.27 1.27)
				)
			)
		)
		(property "Value" ""
			(at 0 0 0)
			(layer "F.Fab")
			(effects
				(font
					(size 1.27 1.27)
				)
			)
		)
		(duplicate_pad_numbers_are_jumpers no)
		(fp_line
			(start -0.7874 -0.4064)
			(end 0.7874 -0.4064)
			(stroke
				(width 0.1524)
				(type default)
			)
			(layer "F.SilkS")
		)
		(fp_line
			(start -0.7874 0.4064)
			(end -0.7874 -0.4064)
			(stroke
				(width 0.1524)
				(type default)
			)
			(layer "F.SilkS")
		)
		(fp_line
			(start 0.7874 -0.4064)
			(end 0.7874 0.4064)
			(stroke
				(width 0.1524)
				(type default)
			)
			(layer "F.SilkS")
		)
		(fp_line
			(start 0.7874 0.4064)
			(end -0.7874 0.4064)
			(stroke
				(width 0.1524)
				(type default)
			)
			(layer "F.SilkS")
		)
		(fp_line
			(start -0.67945 -0.305054)
			(end -0.12065 -0.305054)
			(stroke
				(width 0.1)
				(type default)
			)
			(layer "F.Fab")
		)
		(fp_line
			(start -0.67945 0.3048)
			(end -0.67945 -0.305054)
			(stroke
				(width 0.1)
				(type default)
			)
			(layer "F.Fab")
		)
		(fp_line
			(start -0.12065 -0.305054)
			(end -0.12065 -0.2794)
			(stroke
				(width 0.1)
				(type default)
			)
			(layer "F.Fab")
		)
		(fp_line
			(start -0.12065 -0.2794)
			(end 0.12065 -0.2794)
			(stroke
				(width 0.1)
				(type default)
			)
			(layer "F.Fab")
		)
		(fp_line
			(start -0.12065 0.2794)
			(end -0.12065 0.3048)
			(stroke
				(width 0.1)
				(type default)
			)
			(layer "F.Fab")
		)
		(fp_line
			(start -0.12065 0.3048)
			(end -0.67945 0.3048)
			(stroke
				(width 0.1)
				(type default)
			)
			(layer "F.Fab")
		)
		(fp_line
			(start 0.120396 0.2794)
			(end -0.12065 0.2794)
			(stroke
				(width 0.1)
				(type default)
			)
			(layer "F.Fab")
		)
		(fp_line
			(start 0.120396 0.3048)
			(end 0.120396 0.2794)
			(stroke
				(width 0.1)
				(type default)
			)
			(layer "F.Fab")
		)
		(fp_line
			(start 0.12065 -0.3048)
			(end 0.67945 -0.3048)
			(stroke
				(width 0.1)
				(type default)
			)
			(layer "F.Fab")
		)
		(fp_line
			(start 0.12065 -0.2794)
			(end 0.12065 -0.3048)
			(stroke
				(width 0.1)
				(type default)
			)
			(layer "F.Fab")
		)
		(fp_line
			(start 0.67945 -0.3048)
			(end 0.67945 0.3048)
			(stroke
				(width 0.1)
				(type default)
			)
			(layer "F.Fab")
		)
		(fp_line
			(start 0.67945 0.3048)
			(end 0.120396 0.3048)
			(stroke
				(width 0.1)
				(type default)
			)
			(layer "F.Fab")
		)
		(pad "1" smd circle
			(at -0.40005 0)
			(size 0 0)
			(layers "F.Cu" "F.Mask" "F.Paste")
			(net "P3V3_AUX_ADC")
		)
		(pad "2" smd circle
			(at 0.40005 0)
			(size 0 0)
			(layers "F.Cu" "F.Mask" "F.Paste")
			(net "GND")
		)
	)
	(footprint ""
		(layer "F.Cu")
		(at 323.637148 -45.86351 180)
		(property "Reference" "R3865"
			(at 0 0 180)
			(layer "F.SilkS")
			(hide yes)
			(effects
				(font
					(size 1.27 1.27)
				)
			)
		)
		(property "Value" ""
			(at 0 0 180)
			(layer "F.Fab")
			(effects
				(font
					(size 1.27 1.27)
				)
			)
		)
		(duplicate_pad_numbers_are_jumpers no)
		(fp_line
			(start 0.7874 0.4064)
			(end -0.7874 0.4064)
			(stroke
				(width 0.1524)
				(type default)
			)
			(layer "F.SilkS")
		)
		(fp_line
			(start 0.7874 -0.4064)
			(end 0.7874 0.4064)
			(stroke
				(width 0.1524)
				(type default)
			)
			(layer "F.SilkS")
		)
		(fp_line
			(start -0.7874 0.4064)
			(end -0.7874 -0.4064)
			(stroke
				(width 0.1524)
				(type default)
			)
			(layer "F.SilkS")
		)
		(fp_line
			(start -0.7874 -0.4064)
			(end 0.7874 -0.4064)
			(stroke
				(width 0.1524)
				(type default)
			)
			(layer "F.SilkS")
		)
		(fp_line
			(start 0.67945 0.3048)
			(end 0.120396 0.3048)
			(stroke
				(width 0.1)
				(type default)
			)
			(layer "F.Fab")
		)
		(fp_line
			(start 0.67945 -0.3048)
			(end 0.67945 0.3048)
			(stroke
				(width 0.1)
				(type default)
			)
			(layer "F.Fab")
		)
		(fp_line
			(start 0.12065 -0.2794)
			(end 0.12065 -0.3048)
			(stroke
				(width 0.1)
				(type default)
			)
			(layer "F.Fab")
		)
		(fp_line
			(start 0.12065 -0.3048)
			(end 0.67945 -0.3048)
			(stroke
				(width 0.1)
				(type default)
			)
			(layer "F.Fab")
		)
		(fp_line
			(start 0.120396 0.3048)
			(end 0.120396 0.2794)
			(stroke
				(width 0.1)
				(type default)
			)
			(layer "F.Fab")
		)
		(fp_line
			(start 0.120396 0.2794)
			(end -0.12065 0.2794)
			(stroke
				(width 0.1)
				(type default)
			)
			(layer "F.Fab")
		)
		(fp_line
			(start -0.12065 0.3048)
			(end -0.67945 0.3048)
			(stroke
				(width 0.1)
				(type default)
			)
			(layer "F.Fab")
		)
		(fp_line
			(start -0.12065 0.2794)
			(end -0.12065 0.3048)
			(stroke
				(width 0.1)
				(type default)
			)
			(layer "F.Fab")
		)
		(fp_line
			(start -0.12065 -0.2794)
			(end 0.12065 -0.2794)
			(stroke
				(width 0.1)
				(type default)
			)
			(layer "F.Fab")
		)
		(fp_line
			(start -0.12065 -0.305054)
			(end -0.12065 -0.2794)
			(stroke
				(width 0.1)
				(type default)
			)
			(layer "F.Fab")
		)
		(fp_line
			(start -0.67945 0.3048)
			(end -0.67945 -0.305054)
			(stroke
				(width 0.1)
				(type default)
			)
			(layer "F.Fab")
		)
		(fp_line
			(start -0.67945 -0.305054)
			(end -0.12065 -0.305054)
			(stroke
				(width 0.1)
				(type default)
			)
			(layer "F.Fab")
		)
		(pad "1" smd rect
			(at -0.40005 0)
			(size 0.4572 0.508)
			(layers "F.Cu" "F.Mask" "F.Paste")
			(net "P12V_OCP_SFF_ISENSE_MAM_TIC")
		)
		(pad "2" smd rect
			(at 0.40005 0)
			(size 0.4572 0.508)
			(layers "F.Cu" "F.Mask" "F.Paste")
			(net "P12V_OCP_SFF_ISENSE_TIC")
		)
	)
	(footprint ""
		(layer "F.Cu")
		(at 387.623304 -178.0921 90)
		(property "Reference" "PC561"
			(at 0 0 90)
			(layer "F.SilkS")
			(hide yes)
			(effects
				(font
					(size 1.27 1.27)
				)
			)
		)
		(property "Value" ""
			(at 0 0 90)
			(layer "F.Fab")
			(effects
				(font
					(size 1.27 1.27)
				)
			)
		)
		(duplicate_pad_numbers_are_jumpers no)
		(fp_line
			(start 0.7874 -0.4064)
			(end 0.7874 0.4064)
			(stroke
				(width 0.1524)
				(type default)
			)
			(layer "F.SilkS")
		)
		(fp_line
			(start -0.7874 -0.4064)
			(end 0.7874 -0.4064)
			(stroke
				(width 0.1524)
				(type default)
			)
			(layer "F.SilkS")
		)
		(fp_line
			(start 0.7874 0.4064)
			(end -0.7874 0.4064)
			(stroke
				(width 0.1524)
				(type default)
			)
			(layer "F.SilkS")
		)
		(fp_line
			(start -0.7874 0.4064)
			(end -0.7874 -0.4064)
			(stroke
				(width 0.1524)
				(type default)
			)
			(layer "F.SilkS")
		)
		(fp_line
			(start -0.12065 -0.305054)
			(end -0.12065 -0.2794)
			(stroke
				(width 0.1)
				(type default)
			)
			(layer "F.Fab")
		)
		(fp_line
			(start -0.67945 -0.305054)
			(end -0.12065 -0.305054)
			(stroke
				(width 0.1)
				(type default)
			)
			(layer "F.Fab")
		)
		(fp_line
			(start 0.67945 -0.3048)
			(end 0.67945 0.3048)
			(stroke
				(width 0.1)
				(type default)
			)
			(layer "F.Fab")
		)
		(fp_line
			(start 0.12065 -0.3048)
			(end 0.67945 -0.3048)
			(stroke
				(width 0.1)
				(type default)
			)
			(layer "F.Fab")
		)
		(fp_line
			(start 0.12065 -0.2794)
			(end 0.12065 -0.3048)
			(stroke
				(width 0.1)
				(type default)
			)
			(layer "F.Fab")
		)
		(fp_line
			(start -0.12065 -0.2794)
			(end 0.12065 -0.2794)
			(stroke
				(width 0.1)
				(type default)
			)
			(layer "F.Fab")
		)
		(fp_line
			(start 0.120396 0.2794)
			(end -0.12065 0.2794)
			(stroke
				(width 0.1)
				(type default)
			)
			(layer "F.Fab")
		)
		(fp_line
			(start -0.12065 0.2794)
			(end -0.12065 0.3048)
			(stroke
				(width 0.1)
				(type default)
			)
			(layer "F.Fab")
		)
		(fp_line
			(start 0.67945 0.3048)
			(end 0.120396 0.3048)
			(stroke
				(width 0.1)
				(type default)
			)
			(layer "F.Fab")
		)
		(fp_line
			(start 0.120396 0.3048)
			(end 0.120396 0.2794)
			(stroke
				(width 0.1)
				(type default)
			)
			(layer "F.Fab")
		)
		(fp_line
			(start -0.12065 0.3048)
			(end -0.67945 0.3048)
			(stroke
				(width 0.1)
				(type default)
			)
			(layer "F.Fab")
		)
		(fp_line
			(start -0.67945 0.3048)
			(end -0.67945 -0.305054)
			(stroke
				(width 0.1)
				(type default)
			)
			(layer "F.Fab")
		)
		(pad "1" smd circle
			(at -0.40005 0 90)
			(size 0 0)
			(layers "F.Cu" "F.Mask" "F.Paste")
			(net "SW_PVDDCR_CPU0_P0_BOOT4_RC")
		)
		(pad "2" smd circle
			(at 0.40005 0 90)
			(size 0 0)
			(layers "F.Cu" "F.Mask" "F.Paste")
			(net "SW_PVDDCR_CPU0_P0_PH4")
		)
	)
	(footprint ""
		(layer "F.Cu")
		(at 257.242056 -122.97537)
		(property "Reference" "R3710"
			(at 0 0 0)
			(layer "F.SilkS")
			(hide yes)
			(effects
				(font
					(size 1.27 1.27)
				)
			)
		)
		(property "Value" ""
			(at 0 0 0)
			(layer "F.Fab")
			(effects
				(font
					(size 1.27 1.27)
				)
			)
		)
		(duplicate_pad_numbers_are_jumpers no)
		(fp_line
			(start -0.7874 -0.4064)
			(end 0.7874 -0.4064)
			(stroke
				(width 0.1524)
				(type default)
			)
			(layer "F.SilkS")
		)
		(fp_line
			(start -0.7874 0.4064)
			(end -0.7874 -0.4064)
			(stroke
				(width 0.1524)
				(type default)
			)
			(layer "F.SilkS")
		)
		(fp_line
			(start 0.7874 -0.4064)
			(end 0.7874 0.4064)
			(stroke
				(width 0.1524)
				(type default)
			)
			(layer "F.SilkS")
		)
		(fp_line
			(start 0.7874 0.4064)
			(end -0.7874 0.4064)
			(stroke
				(width 0.1524)
				(type default)
			)
			(layer "F.SilkS")
		)
		(fp_line
			(start -0.67945 -0.305054)
			(end -0.12065 -0.305054)
			(stroke
				(width 0.1)
				(type default)
			)
			(layer "F.Fab")
		)
		(fp_line
			(start -0.67945 0.3048)
			(end -0.67945 -0.305054)
			(stroke
				(width 0.1)
				(type default)
			)
			(layer "F.Fab")
		)
		(fp_line
			(start -0.12065 -0.305054)
			(end -0.12065 -0.2794)
			(stroke
				(width 0.1)
				(type default)
			)
			(layer "F.Fab")
		)
		(fp_line
			(start -0.12065 -0.2794)
			(end 0.12065 -0.2794)
			(stroke
				(width 0.1)
				(type default)
			)
			(layer "F.Fab")
		)
		(fp_line
			(start -0.12065 0.2794)
			(end -0.12065 0.3048)
			(stroke
				(width 0.1)
				(type default)
			)
			(layer "F.Fab")
		)
		(fp_line
			(start -0.12065 0.3048)
			(end -0.67945 0.3048)
			(stroke
				(width 0.1)
				(type default)
			)
			(layer "F.Fab")
		)
		(fp_line
			(start 0.120396 0.2794)
			(end -0.12065 0.2794)
			(stroke
				(width 0.1)
				(type default)
			)
			(layer "F.Fab")
		)
		(fp_line
			(start 0.120396 0.3048)
			(end 0.120396 0.2794)
			(stroke
				(width 0.1)
				(type default)
			)
			(layer "F.Fab")
		)
		(fp_line
			(start 0.12065 -0.3048)
			(end 0.67945 -0.3048)
			(stroke
				(width 0.1)
				(type default)
			)
			(layer "F.Fab")
		)
		(fp_line
			(start 0.12065 -0.2794)
			(end 0.12065 -0.3048)
			(stroke
				(width 0.1)
				(type default)
			)
			(layer "F.Fab")
		)
		(fp_line
			(start 0.67945 -0.3048)
			(end 0.67945 0.3048)
			(stroke
				(width 0.1)
				(type default)
			)
			(layer "F.Fab")
		)
		(fp_line
			(start 0.67945 0.3048)
			(end 0.120396 0.3048)
			(stroke
				(width 0.1)
				(type default)
			)
			(layer "F.Fab")
		)
		(pad "1" smd circle
			(at -0.40005 0)
			(size 0 0)
			(layers "F.Cu" "F.Mask" "F.Paste")
			(net "RST_SMB_SWITCH_N")
		)
		(pad "2" smd circle
			(at 0.40005 0)
			(size 0 0)
			(layers "F.Cu" "F.Mask" "F.Paste")
			(net "PU_RST_SMB_PCIE2_N")
		)
	)
	(footprint ""
		(layer "F.Cu")
		(at 68.212462 -37.389562 180)
		(property "Reference" "R3559"
			(at 0 0 180)
			(layer "F.SilkS")
			(hide yes)
			(effects
				(font
					(size 1.27 1.27)
				)
			)
		)
		(property "Value" ""
			(at 0 0 180)
			(layer "F.Fab")
			(effects
				(font
					(size 1.27 1.27)
				)
			)
		)
		(duplicate_pad_numbers_are_jumpers no)
		(fp_line
			(start 0.7874 0.4064)
			(end -0.7874 0.4064)
			(stroke
				(width 0.1524)
				(type default)
			)
			(layer "F.SilkS")
		)
		(fp_line
			(start 0.7874 -0.4064)
			(end 0.7874 0.4064)
			(stroke
				(width 0.1524)
				(type default)
			)
			(layer "F.SilkS")
		)
		(fp_line
			(start -0.7874 0.4064)
			(end -0.7874 -0.4064)
			(stroke
				(width 0.1524)
				(type default)
			)
			(layer "F.SilkS")
		)
		(fp_line
			(start -0.7874 -0.4064)
			(end 0.7874 -0.4064)
			(stroke
				(width 0.1524)
				(type default)
			)
			(layer "F.SilkS")
		)
		(fp_line
			(start 0.67945 0.3048)
			(end 0.120396 0.3048)
			(stroke
				(width 0.1)
				(type default)
			)
			(layer "F.Fab")
		)
		(fp_line
			(start 0.67945 -0.3048)
			(end 0.67945 0.3048)
			(stroke
				(width 0.1)
				(type default)
			)
			(layer "F.Fab")
		)
		(fp_line
			(start 0.12065 -0.2794)
			(end 0.12065 -0.3048)
			(stroke
				(width 0.1)
				(type default)
			)
			(layer "F.Fab")
		)
		(fp_line
			(start 0.12065 -0.3048)
			(end 0.67945 -0.3048)
			(stroke
				(width 0.1)
				(type default)
			)
			(layer "F.Fab")
		)
		(fp_line
			(start 0.120396 0.3048)
			(end 0.120396 0.2794)
			(stroke
				(width 0.1)
				(type default)
			)
			(layer "F.Fab")
		)
		(fp_line
			(start 0.120396 0.2794)
			(end -0.12065 0.2794)
			(stroke
				(width 0.1)
				(type default)
			)
			(layer "F.Fab")
		)
		(fp_line
			(start -0.12065 0.3048)
			(end -0.67945 0.3048)
			(stroke
				(width 0.1)
				(type default)
			)
			(layer "F.Fab")
		)
		(fp_line
			(start -0.12065 0.2794)
			(end -0.12065 0.3048)
			(stroke
				(width 0.1)
				(type default)
			)
			(layer "F.Fab")
		)
		(fp_line
			(start -0.12065 -0.2794)
			(end 0.12065 -0.2794)
			(stroke
				(width 0.1)
				(type default)
			)
			(layer "F.Fab")
		)
		(fp_line
			(start -0.12065 -0.305054)
			(end -0.12065 -0.2794)
			(stroke
				(width 0.1)
				(type default)
			)
			(layer "F.Fab")
		)
		(fp_line
			(start -0.67945 0.3048)
			(end -0.67945 -0.305054)
			(stroke
				(width 0.1)
				(type default)
			)
			(layer "F.Fab")
		)
		(fp_line
			(start -0.67945 -0.305054)
			(end -0.12065 -0.305054)
			(stroke
				(width 0.1)
				(type default)
			)
			(layer "F.Fab")
		)
		(pad "1" smd circle
			(at -0.40005 0 180)
			(size 0 0)
			(layers "F.Cu" "F.Mask" "F.Paste")
			(net "OCP_V3_2_P3V3_ADC_ALERT_R")
		)
		(pad "2" smd circle
			(at 0.40005 0 180)
			(size 0 0)
			(layers "F.Cu" "F.Mask" "F.Paste")
			(net "OCP_V3_2_P3V3_P12V_ADC_R_ALERT")
		)
	)
	(footprint ""
		(layer "F.Cu")
		(at 359.58526 -152.71242 90)
		(property "Reference" "PC492"
			(at 4.049268 -0.80264 0)
			(unlocked yes)
			(layer "F.SilkS")
			(effects
				(font
					(size 0.7874 0.5842)
					(thickness 0.1524)
				)
				(justify left)
			)
		)
		(property "Value" ""
			(at 0 0 90)
			(layer "F.Fab")
			(effects
				(font
					(size 1.27 1.27)
				)
			)
		)
		(duplicate_pad_numbers_are_jumpers no)
		(fp_line
			(start -3.400044 1.249934)
			(end 3.400044 1.249934)
			(stroke
				(width 0.1524)
				(type default)
			)
			(layer "F.SilkS")
		)
		(fp_circle
			(center 0 1.249934)
			(end 0 4.649978)
			(stroke
				(width 0.1524)
				(type default)
			)
			(fill no)
			(layer "F.SilkS")
		)
		(fp_poly
			(pts
				(arc
					(start 3.400044 1.249934)
					(mid 0 4.649978)
					(end -3.400044 1.249934)
				)
			)
			(stroke
				(width 0)
				(type default)
			)
			(fill yes)
			(layer "F.SilkS")
		)
		(fp_circle
			(center 0 1.249934)
			(end 0 4.649978)
			(stroke
				(width 0.1)
				(type default)
			)
			(fill no)
			(layer "F.Fab")
		)
		(pad "1" thru_hole rect
			(at 0 0 90)
			(size 1.524 1.524)
			(drill 1.016)
			(layers "*.Cu" "*.Mask")
			(remove_unused_layers no)
			(net "SW_P12V_AUX_PVDDCR_CPU0_P0_FLT")
			(clearance 0)
			(padstack
				(mode front_inner_back)
				(layer "Inner"
					(shape circle)
					(size 1.524 1.524)
					(clearance 0)
				)
				(layer "B.Cu"
					(shape rect)
					(size 1.524 1.524)
					(clearance 0)
				)
			)
		)
		(pad "2" thru_hole circle
			(at 0 2.500122 90)
			(size 1.524 1.524)
			(drill 1.016)
			(layers "*.Cu" "*.Mask")
			(remove_unused_layers no)
			(net "GND")
			(clearance 0)
		)
	)
	(footprint ""
		(layer "F.Cu")
		(at 230.644192 -294.936926 180)
		(property "Reference" "PC6524"
			(at 0 0 180)
			(layer "F.SilkS")
			(hide yes)
			(effects
				(font
					(size 1.27 1.27)
				)
			)
		)
		(property "Value" ""
			(at 0 0 180)
			(layer "F.Fab")
			(effects
				(font
					(size 1.27 1.27)
				)
			)
		)
		(duplicate_pad_numbers_are_jumpers no)
		(fp_line
			(start 0.7874 0.4064)
			(end -0.7874 0.4064)
			(stroke
				(width 0.1524)
				(type default)
			)
			(layer "F.SilkS")
		)
		(fp_line
			(start 0.7874 -0.4064)
			(end 0.7874 0.4064)
			(stroke
				(width 0.1524)
				(type default)
			)
			(layer "F.SilkS")
		)
		(fp_line
			(start -0.7874 0.4064)
			(end -0.7874 -0.4064)
			(stroke
				(width 0.1524)
				(type default)
			)
			(layer "F.SilkS")
		)
		(fp_line
			(start -0.7874 -0.4064)
			(end 0.7874 -0.4064)
			(stroke
				(width 0.1524)
				(type default)
			)
			(layer "F.SilkS")
		)
		(fp_line
			(start 0.67945 0.3048)
			(end 0.120396 0.3048)
			(stroke
				(width 0.1)
				(type default)
			)
			(layer "F.Fab")
		)
		(fp_line
			(start 0.67945 -0.3048)
			(end 0.67945 0.3048)
			(stroke
				(width 0.1)
				(type default)
			)
			(layer "F.Fab")
		)
		(fp_line
			(start 0.12065 -0.2794)
			(end 0.12065 -0.3048)
			(stroke
				(width 0.1)
				(type default)
			)
			(layer "F.Fab")
		)
		(fp_line
			(start 0.12065 -0.3048)
			(end 0.67945 -0.3048)
			(stroke
				(width 0.1)
				(type default)
			)
			(layer "F.Fab")
		)
		(fp_line
			(start 0.120396 0.3048)
			(end 0.120396 0.2794)
			(stroke
				(width 0.1)
				(type default)
			)
			(layer "F.Fab")
		)
		(fp_line
			(start 0.120396 0.2794)
			(end -0.12065 0.2794)
			(stroke
				(width 0.1)
				(type default)
			)
			(layer "F.Fab")
		)
		(fp_line
			(start -0.12065 0.3048)
			(end -0.67945 0.3048)
			(stroke
				(width 0.1)
				(type default)
			)
			(layer "F.Fab")
		)
		(fp_line
			(start -0.12065 0.2794)
			(end -0.12065 0.3048)
			(stroke
				(width 0.1)
				(type default)
			)
			(layer "F.Fab")
		)
		(fp_line
			(start -0.12065 -0.2794)
			(end 0.12065 -0.2794)
			(stroke
				(width 0.1)
				(type default)
			)
			(layer "F.Fab")
		)
		(fp_line
			(start -0.12065 -0.305054)
			(end -0.12065 -0.2794)
			(stroke
				(width 0.1)
				(type default)
			)
			(layer "F.Fab")
		)
		(fp_line
			(start -0.67945 0.3048)
			(end -0.67945 -0.305054)
			(stroke
				(width 0.1)
				(type default)
			)
			(layer "F.Fab")
		)
		(fp_line
			(start -0.67945 -0.305054)
			(end -0.12065 -0.305054)
			(stroke
				(width 0.1)
				(type default)
			)
			(layer "F.Fab")
		)
		(pad "1" smd circle
			(at -0.40005 0 180)
			(size 0 0)
			(layers "F.Cu" "F.Mask" "F.Paste")
			(net "SW_P12V_AUX_P1V8_RETIMER_CPU1_FLT")
		)
		(pad "2" smd circle
			(at 0.40005 0 180)
			(size 0 0)
			(layers "F.Cu" "F.Mask" "F.Paste")
			(net "GND")
		)
	)
	(footprint ""
		(layer "F.Cu")
		(at 197.269608 -119.975376)
		(property "Reference" "R798"
			(at 0 0 0)
			(layer "F.SilkS")
			(hide yes)
			(effects
				(font
					(size 1.27 1.27)
				)
			)
		)
		(property "Value" ""
			(at 0 0 0)
			(layer "F.Fab")
			(effects
				(font
					(size 1.27 1.27)
				)
			)
		)
		(duplicate_pad_numbers_are_jumpers no)
		(fp_line
			(start -0.7874 -0.4064)
			(end 0.7874 -0.4064)
			(stroke
				(width 0.1524)
				(type default)
			)
			(layer "F.SilkS")
		)
		(fp_line
			(start -0.7874 0.4064)
			(end -0.7874 -0.4064)
			(stroke
				(width 0.1524)
				(type default)
			)
			(layer "F.SilkS")
		)
		(fp_line
			(start 0.7874 -0.4064)
			(end 0.7874 0.4064)
			(stroke
				(width 0.1524)
				(type default)
			)
			(layer "F.SilkS")
		)
		(fp_line
			(start 0.7874 0.4064)
			(end -0.7874 0.4064)
			(stroke
				(width 0.1524)
				(type default)
			)
			(layer "F.SilkS")
		)
		(fp_line
			(start -0.67945 -0.305054)
			(end -0.12065 -0.305054)
			(stroke
				(width 0.1)
				(type default)
			)
			(layer "F.Fab")
		)
		(fp_line
			(start -0.67945 0.3048)
			(end -0.67945 -0.305054)
			(stroke
				(width 0.1)
				(type default)
			)
			(layer "F.Fab")
		)
		(fp_line
			(start -0.12065 -0.305054)
			(end -0.12065 -0.2794)
			(stroke
				(width 0.1)
				(type default)
			)
			(layer "F.Fab")
		)
		(fp_line
			(start -0.12065 -0.2794)
			(end 0.12065 -0.2794)
			(stroke
				(width 0.1)
				(type default)
			)
			(layer "F.Fab")
		)
		(fp_line
			(start -0.12065 0.2794)
			(end -0.12065 0.3048)
			(stroke
				(width 0.1)
				(type default)
			)
			(layer "F.Fab")
		)
		(fp_line
			(start -0.12065 0.3048)
			(end -0.67945 0.3048)
			(stroke
				(width 0.1)
				(type default)
			)
			(layer "F.Fab")
		)
		(fp_line
			(start 0.120396 0.2794)
			(end -0.12065 0.2794)
			(stroke
				(width 0.1)
				(type default)
			)
			(layer "F.Fab")
		)
		(fp_line
			(start 0.120396 0.3048)
			(end 0.120396 0.2794)
			(stroke
				(width 0.1)
				(type default)
			)
			(layer "F.Fab")
		)
		(fp_line
			(start 0.12065 -0.3048)
			(end 0.67945 -0.3048)
			(stroke
				(width 0.1)
				(type default)
			)
			(layer "F.Fab")
		)
		(fp_line
			(start 0.12065 -0.2794)
			(end 0.12065 -0.3048)
			(stroke
				(width 0.1)
				(type default)
			)
			(layer "F.Fab")
		)
		(fp_line
			(start 0.67945 -0.3048)
			(end 0.67945 0.3048)
			(stroke
				(width 0.1)
				(type default)
			)
			(layer "F.Fab")
		)
		(fp_line
			(start 0.67945 0.3048)
			(end 0.120396 0.3048)
			(stroke
				(width 0.1)
				(type default)
			)
			(layer "F.Fab")
		)
		(pad "1" smd circle
			(at -0.40005 0)
			(size 0 0)
			(layers "F.Cu" "F.Mask" "F.Paste")
			(net "RST_PERST_M2_0_R_N")
		)
		(pad "2" smd circle
			(at 0.40005 0)
			(size 0 0)
			(layers "F.Cu" "F.Mask" "F.Paste")
			(net "RST_PERST_M2_0_N")
		)
	)
	(footprint ""
		(layer "F.Cu")
		(at 314.475876 -70.098412 90)
		(property "Reference" "D98"
			(at -3.934714 -0.691642 90)
			(unlocked yes)
			(layer "F.SilkS")
			(effects
				(font
					(size 0.7874 0.5842)
					(thickness 0.1524)
				)
				(justify left)
			)
		)
		(property "Value" ""
			(at 0 0 90)
			(layer "F.Fab")
			(effects
				(font
					(size 1.27 1.27)
				)
			)
		)
		(duplicate_pad_numbers_are_jumpers no)
		(fp_line
			(start 1.16078 -0.4826)
			(end 1.16078 0.4826)
			(stroke
				(width 0.1524)
				(type default)
			)
			(layer "F.SilkS")
		)
		(fp_line
			(start 1.03378 -0.4826)
			(end 1.03378 0.4826)
			(stroke
				(width 0.1524)
				(type default)
			)
			(layer "F.SilkS")
		)
		(fp_line
			(start 0.90678 -0.4826)
			(end 0.90678 0.4826)
			(stroke
				(width 0.1524)
				(type default)
			)
			(layer "F.SilkS")
		)
		(fp_line
			(start -0.64008 -0.4826)
			(end 1.16078 -0.4826)
			(stroke
				(width 0.1524)
				(type default)
			)
			(layer "F.SilkS")
		)
		(fp_line
			(start -0.79248 -0.4826)
			(end 1.03378 -0.4826)
			(stroke
				(width 0.1524)
				(type default)
			)
			(layer "F.SilkS")
		)
		(fp_line
			(start -0.89408 -0.4826)
			(end 0.90678 -0.4826)
			(stroke
				(width 0.1524)
				(type default)
			)
			(layer "F.SilkS")
		)
		(fp_line
			(start 1.16078 0.4826)
			(end -0.64008 0.4826)
			(stroke
				(width 0.1524)
				(type default)
			)
			(layer "F.SilkS")
		)
		(fp_line
			(start 1.03378 0.4826)
			(end -0.79248 0.4826)
			(stroke
				(width 0.1524)
				(type default)
			)
			(layer "F.SilkS")
		)
		(fp_line
			(start 0.90678 0.4826)
			(end -0.90678 0.4826)
			(stroke
				(width 0.1524)
				(type default)
			)
			(layer "F.SilkS")
		)
		(fp_line
			(start -0.90678 0.4826)
			(end -0.90678 -0.4699)
			(stroke
				(width 0.1524)
				(type default)
			)
			(layer "F.SilkS")
		)
		(fp_line
			(start 0.499872 -0.249936)
			(end 0.499872 0.249936)
			(stroke
				(width 0.1)
				(type default)
			)
			(layer "F.Fab")
		)
		(fp_line
			(start -0.499872 -0.249936)
			(end 0.499872 -0.249936)
			(stroke
				(width 0.1)
				(type default)
			)
			(layer "F.Fab")
		)
		(fp_line
			(start 0.499872 0.249936)
			(end -0.499872 0.249936)
			(stroke
				(width 0.1)
				(type default)
			)
			(layer "F.Fab")
		)
		(fp_line
			(start -0.499872 0.249936)
			(end -0.499872 -0.249936)
			(stroke
				(width 0.1)
				(type default)
			)
			(layer "F.Fab")
		)
		(pad "A" smd rect
			(at -0.47498 0 90)
			(size 0.6096 0.7112)
			(layers "F.Cu" "F.Mask" "F.Paste")
			(net "LED_P5V")
		)
		(pad "C" smd rect
			(at 0.47498 0 90)
			(size 0.6096 0.7112)
			(layers "F.Cu" "F.Mask" "F.Paste")
			(net "GND")
		)
	)
	(footprint ""
		(layer "F.Cu")
		(at 318.262 -362.839 -90)
		(property "Reference" "PR74"
			(at 0 0 270)
			(layer "F.SilkS")
			(hide yes)
			(effects
				(font
					(size 1.27 1.27)
				)
			)
		)
		(property "Value" ""
			(at 0 0 270)
			(layer "F.Fab")
			(effects
				(font
					(size 1.27 1.27)
				)
			)
		)
		(duplicate_pad_numbers_are_jumpers no)
		(fp_line
			(start -0.7874 0.4064)
			(end -0.7874 -0.4064)
			(stroke
				(width 0.1524)
				(type default)
			)
			(layer "F.SilkS")
		)
		(fp_line
			(start 0.7874 0.4064)
			(end -0.7874 0.4064)
			(stroke
				(width 0.1524)
				(type default)
			)
			(layer "F.SilkS")
		)
		(fp_line
			(start -0.7874 -0.4064)
			(end 0.7874 -0.4064)
			(stroke
				(width 0.1524)
				(type default)
			)
			(layer "F.SilkS")
		)
		(fp_line
			(start 0.7874 -0.4064)
			(end 0.7874 0.4064)
			(stroke
				(width 0.1524)
				(type default)
			)
			(layer "F.SilkS")
		)
		(fp_line
			(start -0.67945 0.3048)
			(end -0.67945 -0.305054)
			(stroke
				(width 0.1)
				(type default)
			)
			(layer "F.Fab")
		)
		(fp_line
			(start -0.12065 0.3048)
			(end -0.67945 0.3048)
			(stroke
				(width 0.1)
				(type default)
			)
			(layer "F.Fab")
		)
		(fp_line
			(start 0.120396 0.3048)
			(end 0.120396 0.2794)
			(stroke
				(width 0.1)
				(type default)
			)
			(layer "F.Fab")
		)
		(fp_line
			(start 0.67945 0.3048)
			(end 0.120396 0.3048)
			(stroke
				(width 0.1)
				(type default)
			)
			(layer "F.Fab")
		)
		(fp_line
			(start -0.12065 0.2794)
			(end -0.12065 0.3048)
			(stroke
				(width 0.1)
				(type default)
			)
			(layer "F.Fab")
		)
		(fp_line
			(start 0.120396 0.2794)
			(end -0.12065 0.2794)
			(stroke
				(width 0.1)
				(type default)
			)
			(layer "F.Fab")
		)
		(fp_line
			(start -0.12065 -0.2794)
			(end 0.12065 -0.2794)
			(stroke
				(width 0.1)
				(type default)
			)
			(layer "F.Fab")
		)
		(fp_line
			(start 0.12065 -0.2794)
			(end 0.12065 -0.3048)
			(stroke
				(width 0.1)
				(type default)
			)
			(layer "F.Fab")
		)
		(fp_line
			(start 0.12065 -0.3048)
			(end 0.67945 -0.3048)
			(stroke
				(width 0.1)
				(type default)
			)
			(layer "F.Fab")
		)
		(fp_line
			(start 0.67945 -0.3048)
			(end 0.67945 0.3048)
			(stroke
				(width 0.1)
				(type default)
			)
			(layer "F.Fab")
		)
		(fp_line
			(start -0.67945 -0.305054)
			(end -0.12065 -0.305054)
			(stroke
				(width 0.1)
				(type default)
			)
			(layer "F.Fab")
		)
		(fp_line
			(start -0.12065 -0.305054)
			(end -0.12065 -0.2794)
			(stroke
				(width 0.1)
				(type default)
			)
			(layer "F.Fab")
		)
		(pad "1" smd circle
			(at -0.40005 0 270)
			(size 0 0)
			(layers "F.Cu" "F.Mask" "F.Paste")
			(net "P12V_AUX")
		)
		(pad "2" smd circle
			(at 0.40005 0 270)
			(size 0 0)
			(layers "F.Cu" "F.Mask" "F.Paste")
			(net "PVDDCR_CPU1_P0_VINSEN")
		)
	)
	(footprint ""
		(layer "F.Cu")
		(at 366.06734 -389.86206 180)
		(property "Reference" "C900"
			(at 0 0 180)
			(layer "F.SilkS")
			(hide yes)
			(effects
				(font
					(size 1.27 1.27)
				)
			)
		)
		(property "Value" ""
			(at 0 0 180)
			(layer "F.Fab")
			(effects
				(font
					(size 1.27 1.27)
				)
			)
		)
		(duplicate_pad_numbers_are_jumpers no)
		(fp_line
			(start 0.299974 0.150114)
			(end -0.299974 0.150114)
			(stroke
				(width 0.1)
				(type default)
			)
			(layer "F.Fab")
		)
		(fp_line
			(start 0.299974 -0.150114)
			(end 0.299974 0.150114)
			(stroke
				(width 0.1)
				(type default)
			)
			(layer "F.Fab")
		)
		(fp_line
			(start -0.299974 0.150114)
			(end -0.299974 -0.150114)
			(stroke
				(width 0.1)
				(type default)
			)
			(layer "F.Fab")
		)
		(fp_line
			(start -0.299974 -0.150114)
			(end 0.299974 -0.150114)
			(stroke
				(width 0.1)
				(type default)
			)
			(layer "F.Fab")
		)
		(pad "1" smd rect
			(at -0.2667 0 180)
			(size 0.3048 0.381)
			(layers "F.Cu" "F.Mask" "F.Paste")
			(net "P5E_CPU0_P3_TX_C_DN<0>")
		)
		(pad "2" smd rect
			(at 0.2667 0 180)
			(size 0.3048 0.381)
			(layers "F.Cu" "F.Mask" "F.Paste")
			(net "P5E_CPU0_P3_TX_DN<0>")
		)
	)
	(footprint ""
		(layer "F.Cu")
		(at 273.378676 -118.618 180)
		(property "Reference" "R1341"
			(at 0 0 180)
			(layer "F.SilkS")
			(hide yes)
			(effects
				(font
					(size 1.27 1.27)
				)
			)
		)
		(property "Value" ""
			(at 0 0 180)
			(layer "F.Fab")
			(effects
				(font
					(size 1.27 1.27)
				)
			)
		)
		(duplicate_pad_numbers_are_jumpers no)
		(fp_line
			(start 0.7874 0.4064)
			(end -0.7874 0.4064)
			(stroke
				(width 0.1524)
				(type default)
			)
			(layer "F.SilkS")
		)
		(fp_line
			(start 0.7874 -0.4064)
			(end 0.7874 0.4064)
			(stroke
				(width 0.1524)
				(type default)
			)
			(layer "F.SilkS")
		)
		(fp_line
			(start -0.7874 0.4064)
			(end -0.7874 -0.4064)
			(stroke
				(width 0.1524)
				(type default)
			)
			(layer "F.SilkS")
		)
		(fp_line
			(start -0.7874 -0.4064)
			(end 0.7874 -0.4064)
			(stroke
				(width 0.1524)
				(type default)
			)
			(layer "F.SilkS")
		)
		(fp_line
			(start 0.67945 0.3048)
			(end 0.120396 0.3048)
			(stroke
				(width 0.1)
				(type default)
			)
			(layer "F.Fab")
		)
		(fp_line
			(start 0.67945 -0.3048)
			(end 0.67945 0.3048)
			(stroke
				(width 0.1)
				(type default)
			)
			(layer "F.Fab")
		)
		(fp_line
			(start 0.12065 -0.2794)
			(end 0.12065 -0.3048)
			(stroke
				(width 0.1)
				(type default)
			)
			(layer "F.Fab")
		)
		(fp_line
			(start 0.12065 -0.3048)
			(end 0.67945 -0.3048)
			(stroke
				(width 0.1)
				(type default)
			)
			(layer "F.Fab")
		)
		(fp_line
			(start 0.120396 0.3048)
			(end 0.120396 0.2794)
			(stroke
				(width 0.1)
				(type default)
			)
			(layer "F.Fab")
		)
		(fp_line
			(start 0.120396 0.2794)
			(end -0.12065 0.2794)
			(stroke
				(width 0.1)
				(type default)
			)
			(layer "F.Fab")
		)
		(fp_line
			(start -0.12065 0.3048)
			(end -0.67945 0.3048)
			(stroke
				(width 0.1)
				(type default)
			)
			(layer "F.Fab")
		)
		(fp_line
			(start -0.12065 0.2794)
			(end -0.12065 0.3048)
			(stroke
				(width 0.1)
				(type default)
			)
			(layer "F.Fab")
		)
		(fp_line
			(start -0.12065 -0.2794)
			(end 0.12065 -0.2794)
			(stroke
				(width 0.1)
				(type default)
			)
			(layer "F.Fab")
		)
		(fp_line
			(start -0.12065 -0.305054)
			(end -0.12065 -0.2794)
			(stroke
				(width 0.1)
				(type default)
			)
			(layer "F.Fab")
		)
		(fp_line
			(start -0.67945 0.3048)
			(end -0.67945 -0.305054)
			(stroke
				(width 0.1)
				(type default)
			)
			(layer "F.Fab")
		)
		(fp_line
			(start -0.67945 -0.305054)
			(end -0.12065 -0.305054)
			(stroke
				(width 0.1)
				(type default)
			)
			(layer "F.Fab")
		)
		(pad "1" smd circle
			(at -0.40005 0 180)
			(size 0 0)
			(layers "F.Cu" "F.Mask" "F.Paste")
			(net "P3V3_AUX")
		)
		(pad "2" smd circle
			(at 0.40005 0 180)
			(size 0 0)
			(layers "F.Cu" "F.Mask" "F.Paste")
			(net "SMB_ADC_SDA_R")
		)
	)
	(footprint ""
		(layer "F.Cu")
		(at 164.557964 -44.247054)
		(property "Reference" "R138"
			(at 0 0 0)
			(layer "F.SilkS")
			(hide yes)
			(effects
				(font
					(size 1.27 1.27)
				)
			)
		)
		(property "Value" ""
			(at 0 0 0)
			(layer "F.Fab")
			(effects
				(font
					(size 1.27 1.27)
				)
			)
		)
		(duplicate_pad_numbers_are_jumpers no)
		(fp_line
			(start -0.7874 -0.4064)
			(end 0.7874 -0.4064)
			(stroke
				(width 0.1524)
				(type default)
			)
			(layer "F.SilkS")
		)
		(fp_line
			(start -0.7874 0.4064)
			(end -0.7874 -0.4064)
			(stroke
				(width 0.1524)
				(type default)
			)
			(layer "F.SilkS")
		)
		(fp_line
			(start 0.7874 -0.4064)
			(end 0.7874 0.4064)
			(stroke
				(width 0.1524)
				(type default)
			)
			(layer "F.SilkS")
		)
		(fp_line
			(start 0.7874 0.4064)
			(end -0.7874 0.4064)
			(stroke
				(width 0.1524)
				(type default)
			)
			(layer "F.SilkS")
		)
		(fp_line
			(start -0.67945 -0.305054)
			(end -0.12065 -0.305054)
			(stroke
				(width 0.1)
				(type default)
			)
			(layer "F.Fab")
		)
		(fp_line
			(start -0.67945 0.3048)
			(end -0.67945 -0.305054)
			(stroke
				(width 0.1)
				(type default)
			)
			(layer "F.Fab")
		)
		(fp_line
			(start -0.12065 -0.305054)
			(end -0.12065 -0.2794)
			(stroke
				(width 0.1)
				(type default)
			)
			(layer "F.Fab")
		)
		(fp_line
			(start -0.12065 -0.2794)
			(end 0.12065 -0.2794)
			(stroke
				(width 0.1)
				(type default)
			)
			(layer "F.Fab")
		)
		(fp_line
			(start -0.12065 0.2794)
			(end -0.12065 0.3048)
			(stroke
				(width 0.1)
				(type default)
			)
			(layer "F.Fab")
		)
		(fp_line
			(start -0.12065 0.3048)
			(end -0.67945 0.3048)
			(stroke
				(width 0.1)
				(type default)
			)
			(layer "F.Fab")
		)
		(fp_line
			(start 0.120396 0.2794)
			(end -0.12065 0.2794)
			(stroke
				(width 0.1)
				(type default)
			)
			(layer "F.Fab")
		)
		(fp_line
			(start 0.120396 0.3048)
			(end 0.120396 0.2794)
			(stroke
				(width 0.1)
				(type default)
			)
			(layer "F.Fab")
		)
		(fp_line
			(start 0.12065 -0.3048)
			(end 0.67945 -0.3048)
			(stroke
				(width 0.1)
				(type default)
			)
			(layer "F.Fab")
		)
		(fp_line
			(start 0.12065 -0.2794)
			(end 0.12065 -0.3048)
			(stroke
				(width 0.1)
				(type default)
			)
			(layer "F.Fab")
		)
		(fp_line
			(start 0.67945 -0.3048)
			(end 0.67945 0.3048)
			(stroke
				(width 0.1)
				(type default)
			)
			(layer "F.Fab")
		)
		(fp_line
			(start 0.67945 0.3048)
			(end 0.120396 0.3048)
			(stroke
				(width 0.1)
				(type default)
			)
			(layer "F.Fab")
		)
		(pad "1" smd circle
			(at -0.40005 0)
			(size 0 0)
			(layers "F.Cu" "F.Mask" "F.Paste")
			(net "M2_SSD0_CLKREQ_EN_N")
		)
		(pad "2" smd circle
			(at 0.40005 0)
			(size 0 0)
			(layers "F.Cu" "F.Mask" "F.Paste")
			(net "GND")
		)
	)
	(footprint ""
		(layer "F.Cu")
		(at 120.396 -424.688)
		(property "Reference" "R3453"
			(at 0 0 0)
			(layer "F.SilkS")
			(hide yes)
			(effects
				(font
					(size 1.27 1.27)
				)
			)
		)
		(property "Value" ""
			(at 0 0 0)
			(layer "F.Fab")
			(effects
				(font
					(size 1.27 1.27)
				)
			)
		)
		(duplicate_pad_numbers_are_jumpers no)
		(fp_line
			(start -0.7874 -0.4064)
			(end 0.7874 -0.4064)
			(stroke
				(width 0.1524)
				(type default)
			)
			(layer "F.SilkS")
		)
		(fp_line
			(start -0.7874 0.4064)
			(end -0.7874 -0.4064)
			(stroke
				(width 0.1524)
				(type default)
			)
			(layer "F.SilkS")
		)
		(fp_line
			(start 0.7874 -0.4064)
			(end 0.7874 0.4064)
			(stroke
				(width 0.1524)
				(type default)
			)
			(layer "F.SilkS")
		)
		(fp_line
			(start 0.7874 0.4064)
			(end -0.7874 0.4064)
			(stroke
				(width 0.1524)
				(type default)
			)
			(layer "F.SilkS")
		)
		(fp_line
			(start -0.67945 -0.305054)
			(end -0.12065 -0.305054)
			(stroke
				(width 0.1)
				(type default)
			)
			(layer "F.Fab")
		)
		(fp_line
			(start -0.67945 0.3048)
			(end -0.67945 -0.305054)
			(stroke
				(width 0.1)
				(type default)
			)
			(layer "F.Fab")
		)
		(fp_line
			(start -0.12065 -0.305054)
			(end -0.12065 -0.2794)
			(stroke
				(width 0.1)
				(type default)
			)
			(layer "F.Fab")
		)
		(fp_line
			(start -0.12065 -0.2794)
			(end 0.12065 -0.2794)
			(stroke
				(width 0.1)
				(type default)
			)
			(layer "F.Fab")
		)
		(fp_line
			(start -0.12065 0.2794)
			(end -0.12065 0.3048)
			(stroke
				(width 0.1)
				(type default)
			)
			(layer "F.Fab")
		)
		(fp_line
			(start -0.12065 0.3048)
			(end -0.67945 0.3048)
			(stroke
				(width 0.1)
				(type default)
			)
			(layer "F.Fab")
		)
		(fp_line
			(start 0.120396 0.2794)
			(end -0.12065 0.2794)
			(stroke
				(width 0.1)
				(type default)
			)
			(layer "F.Fab")
		)
		(fp_line
			(start 0.120396 0.3048)
			(end 0.120396 0.2794)
			(stroke
				(width 0.1)
				(type default)
			)
			(layer "F.Fab")
		)
		(fp_line
			(start 0.12065 -0.3048)
			(end 0.67945 -0.3048)
			(stroke
				(width 0.1)
				(type default)
			)
			(layer "F.Fab")
		)
		(fp_line
			(start 0.12065 -0.2794)
			(end 0.12065 -0.3048)
			(stroke
				(width 0.1)
				(type default)
			)
			(layer "F.Fab")
		)
		(fp_line
			(start 0.67945 -0.3048)
			(end 0.67945 0.3048)
			(stroke
				(width 0.1)
				(type default)
			)
			(layer "F.Fab")
		)
		(fp_line
			(start 0.67945 0.3048)
			(end 0.120396 0.3048)
			(stroke
				(width 0.1)
				(type default)
			)
			(layer "F.Fab")
		)
		(pad "1" smd circle
			(at -0.40005 0)
			(size 0 0)
			(layers "F.Cu" "F.Mask" "F.Paste")
			(net "P3V3_AUX")
		)
		(pad "2" smd circle
			(at 0.40005 0)
			(size 0 0)
			(layers "F.Cu" "F.Mask" "F.Paste")
			(net "GPU_FPGA_BOOT_EN_BUF_R")
		)
	)
	(footprint ""
		(layer "F.Cu")
		(at 323.024246 -333.253842 90)
		(property "Reference" "PR507"
			(at 0 0 90)
			(layer "F.SilkS")
			(hide yes)
			(effects
				(font
					(size 1.27 1.27)
				)
			)
		)
		(property "Value" ""
			(at 0 0 90)
			(layer "F.Fab")
			(effects
				(font
					(size 1.27 1.27)
				)
			)
		)
		(duplicate_pad_numbers_are_jumpers no)
		(fp_line
			(start 0.7874 -0.4064)
			(end 0.7874 0.4064)
			(stroke
				(width 0.1524)
				(type default)
			)
			(layer "F.SilkS")
		)
		(fp_line
			(start -0.7874 -0.4064)
			(end 0.7874 -0.4064)
			(stroke
				(width 0.1524)
				(type default)
			)
			(layer "F.SilkS")
		)
		(fp_line
			(start 0.7874 0.4064)
			(end -0.7874 0.4064)
			(stroke
				(width 0.1524)
				(type default)
			)
			(layer "F.SilkS")
		)
		(fp_line
			(start -0.7874 0.4064)
			(end -0.7874 -0.4064)
			(stroke
				(width 0.1524)
				(type default)
			)
			(layer "F.SilkS")
		)
		(fp_line
			(start -0.12065 -0.305054)
			(end -0.12065 -0.2794)
			(stroke
				(width 0.1)
				(type default)
			)
			(layer "F.Fab")
		)
		(fp_line
			(start -0.67945 -0.305054)
			(end -0.12065 -0.305054)
			(stroke
				(width 0.1)
				(type default)
			)
			(layer "F.Fab")
		)
		(fp_line
			(start 0.67945 -0.3048)
			(end 0.67945 0.3048)
			(stroke
				(width 0.1)
				(type default)
			)
			(layer "F.Fab")
		)
		(fp_line
			(start 0.12065 -0.3048)
			(end 0.67945 -0.3048)
			(stroke
				(width 0.1)
				(type default)
			)
			(layer "F.Fab")
		)
		(fp_line
			(start 0.12065 -0.2794)
			(end 0.12065 -0.3048)
			(stroke
				(width 0.1)
				(type default)
			)
			(layer "F.Fab")
		)
		(fp_line
			(start -0.12065 -0.2794)
			(end 0.12065 -0.2794)
			(stroke
				(width 0.1)
				(type default)
			)
			(layer "F.Fab")
		)
		(fp_line
			(start 0.120396 0.2794)
			(end -0.12065 0.2794)
			(stroke
				(width 0.1)
				(type default)
			)
			(layer "F.Fab")
		)
		(fp_line
			(start -0.12065 0.2794)
			(end -0.12065 0.3048)
			(stroke
				(width 0.1)
				(type default)
			)
			(layer "F.Fab")
		)
		(fp_line
			(start 0.67945 0.3048)
			(end 0.120396 0.3048)
			(stroke
				(width 0.1)
				(type default)
			)
			(layer "F.Fab")
		)
		(fp_line
			(start 0.120396 0.3048)
			(end 0.120396 0.2794)
			(stroke
				(width 0.1)
				(type default)
			)
			(layer "F.Fab")
		)
		(fp_line
			(start -0.12065 0.3048)
			(end -0.67945 0.3048)
			(stroke
				(width 0.1)
				(type default)
			)
			(layer "F.Fab")
		)
		(fp_line
			(start -0.67945 0.3048)
			(end -0.67945 -0.305054)
			(stroke
				(width 0.1)
				(type default)
			)
			(layer "F.Fab")
		)
		(pad "1" smd circle
			(at -0.40005 0 90)
			(size 0 0)
			(layers "F.Cu" "F.Mask" "F.Paste")
			(net "SW_PVDDCR_CPU1_P0_SW2_RC")
		)
		(pad "2" smd circle
			(at 0.40005 0 90)
			(size 0 0)
			(layers "F.Cu" "F.Mask" "F.Paste")
			(net "GND")
		)
	)
	(footprint ""
		(layer "F.Cu")
		(at 153.543 -107.061 180)
		(property "Reference" "U23"
			(at -1.447292 2.35839 0)
			(unlocked yes)
			(layer "F.SilkS")
			(effects
				(font
					(size 0.7874 0.5842)
					(thickness 0.1524)
				)
				(justify left)
			)
		)
		(property "Value" ""
			(at 0 0 180)
			(layer "F.Fab")
			(effects
				(font
					(size 1.27 1.27)
				)
			)
		)
		(duplicate_pad_numbers_are_jumpers no)
		(fp_line
			(start 1.733296 1.549908)
			(end 1.733296 -1.549908)
			(stroke
				(width 0.1524)
				(type default)
			)
			(layer "F.SilkS")
		)
		(fp_line
			(start 1.733296 -1.549908)
			(end 0.660908 -1.549908)
			(stroke
				(width 0.1524)
				(type default)
			)
			(layer "F.SilkS")
		)
		(fp_line
			(start 0.660908 -1.549908)
			(end 0 -0.889)
			(stroke
				(width 0.1524)
				(type default)
			)
			(layer "F.SilkS")
		)
		(fp_line
			(start 0 -0.889)
			(end -0.660908 -1.549908)
			(stroke
				(width 0.1524)
				(type default)
			)
			(layer "F.SilkS")
		)
		(fp_line
			(start -0.660908 -1.549908)
			(end -1.733296 -1.549908)
			(stroke
				(width 0.1524)
				(type default)
			)
			(layer "F.SilkS")
		)
		(fp_line
			(start -1.733296 1.549908)
			(end 1.733296 1.549908)
			(stroke
				(width 0.1524)
				(type default)
			)
			(layer "F.SilkS")
		)
		(fp_line
			(start -1.733296 -1.549908)
			(end -1.733296 1.549908)
			(stroke
				(width 0.1524)
				(type default)
			)
			(layer "F.SilkS")
		)
		(fp_poly
			(pts
				(xy -2.17297 -2.058162) (xy -2.488692 -1.660144) (xy -1.932686 -1.543558)
			)
			(stroke
				(width 0)
				(type default)
			)
			(fill yes)
			(layer "F.SilkS")
		)
		(fp_line
			(start 0.849884 1.549908)
			(end 0.849884 -1.549908)
			(stroke
				(width 0.1)
				(type default)
			)
			(layer "F.Fab")
		)
		(fp_line
			(start 0.849884 -1.549908)
			(end -0.849884 -1.549908)
			(stroke
				(width 0.1)
				(type default)
			)
			(layer "F.Fab")
		)
		(fp_line
			(start -0.849884 1.549908)
			(end 0.849884 1.549908)
			(stroke
				(width 0.1)
				(type default)
			)
			(layer "F.Fab")
		)
		(fp_line
			(start -0.849884 -1.549908)
			(end -0.849884 1.549908)
			(stroke
				(width 0.1)
				(type default)
			)
			(layer "F.Fab")
		)
		(fp_poly
			(pts
				(xy -2.4384 -1.20396) (xy -2.4384 -0.69596) (xy -1.9304 -0.94996)
			)
			(stroke
				(width 0)
				(type default)
			)
			(fill yes)
			(layer "F.Fab")
		)
		(pad "1" smd rect
			(at -1.199896 -0.94996 90)
			(size 0.5588 0.8128)
			(layers "F.Cu" "F.Mask" "F.Paste")
			(net "P12V_OCP_SFF_EN_R3")
		)
		(pad "2" smd rect
			(at -1.199896 0 90)
			(size 0.5588 0.8128)
			(layers "F.Cu" "F.Mask" "F.Paste")
			(net "HP_LVC3_OCP_SFF_PRSNT2")
		)
		(pad "3" smd rect
			(at -1.199896 0.94996 90)
			(size 0.5588 0.8128)
			(layers "F.Cu" "F.Mask" "F.Paste")
			(net "GND")
		)
		(pad "4" smd rect
			(at 1.199896 0.94996 90)
			(size 0.5588 0.8128)
			(layers "F.Cu" "F.Mask" "F.Paste")
			(net "P12V_OCP_SFF_BUF_EN")
		)
		(pad "5" smd rect
			(at 1.199896 -0.94996 90)
			(size 0.5588 0.8128)
			(layers "F.Cu" "F.Mask" "F.Paste")
			(net "P3V3_AUX")
		)
	)
	(footprint ""
		(layer "F.Cu")
		(at 200.600564 -68.026788)
		(property "Reference" "PC2203"
			(at 0 0 0)
			(layer "F.SilkS")
			(hide yes)
			(effects
				(font
					(size 1.27 1.27)
				)
			)
		)
		(property "Value" ""
			(at 0 0 0)
			(layer "F.Fab")
			(effects
				(font
					(size 1.27 1.27)
				)
			)
		)
		(duplicate_pad_numbers_are_jumpers no)
		(fp_line
			(start -0.7874 -0.4064)
			(end 0.7874 -0.4064)
			(stroke
				(width 0.1524)
				(type default)
			)
			(layer "F.SilkS")
		)
		(fp_line
			(start -0.7874 0.4064)
			(end -0.7874 -0.4064)
			(stroke
				(width 0.1524)
				(type default)
			)
			(layer "F.SilkS")
		)
		(fp_line
			(start 0.7874 -0.4064)
			(end 0.7874 0.4064)
			(stroke
				(width 0.1524)
				(type default)
			)
			(layer "F.SilkS")
		)
		(fp_line
			(start 0.7874 0.4064)
			(end -0.7874 0.4064)
			(stroke
				(width 0.1524)
				(type default)
			)
			(layer "F.SilkS")
		)
		(fp_line
			(start -0.67945 -0.305054)
			(end -0.12065 -0.305054)
			(stroke
				(width 0.1)
				(type default)
			)
			(layer "F.Fab")
		)
		(fp_line
			(start -0.67945 0.3048)
			(end -0.67945 -0.305054)
			(stroke
				(width 0.1)
				(type default)
			)
			(layer "F.Fab")
		)
		(fp_line
			(start -0.12065 -0.305054)
			(end -0.12065 -0.2794)
			(stroke
				(width 0.1)
				(type default)
			)
			(layer "F.Fab")
		)
		(fp_line
			(start -0.12065 -0.2794)
			(end 0.12065 -0.2794)
			(stroke
				(width 0.1)
				(type default)
			)
			(layer "F.Fab")
		)
		(fp_line
			(start -0.12065 0.2794)
			(end -0.12065 0.3048)
			(stroke
				(width 0.1)
				(type default)
			)
			(layer "F.Fab")
		)
		(fp_line
			(start -0.12065 0.3048)
			(end -0.67945 0.3048)
			(stroke
				(width 0.1)
				(type default)
			)
			(layer "F.Fab")
		)
		(fp_line
			(start 0.120396 0.2794)
			(end -0.12065 0.2794)
			(stroke
				(width 0.1)
				(type default)
			)
			(layer "F.Fab")
		)
		(fp_line
			(start 0.120396 0.3048)
			(end 0.120396 0.2794)
			(stroke
				(width 0.1)
				(type default)
			)
			(layer "F.Fab")
		)
		(fp_line
			(start 0.12065 -0.3048)
			(end 0.67945 -0.3048)
			(stroke
				(width 0.1)
				(type default)
			)
			(layer "F.Fab")
		)
		(fp_line
			(start 0.12065 -0.2794)
			(end 0.12065 -0.3048)
			(stroke
				(width 0.1)
				(type default)
			)
			(layer "F.Fab")
		)
		(fp_line
			(start 0.67945 -0.3048)
			(end 0.67945 0.3048)
			(stroke
				(width 0.1)
				(type default)
			)
			(layer "F.Fab")
		)
		(fp_line
			(start 0.67945 0.3048)
			(end 0.120396 0.3048)
			(stroke
				(width 0.1)
				(type default)
			)
			(layer "F.Fab")
		)
		(pad "1" smd circle
			(at -0.40005 0)
			(size 0 0)
			(layers "F.Cu" "F.Mask" "F.Paste")
			(net "P3V3_E1S_GATE_0_PU293")
		)
		(pad "2" smd circle
			(at 0.40005 0)
			(size 0 0)
			(layers "F.Cu" "F.Mask" "F.Paste")
			(net "GND")
		)
	)
	(footprint ""
		(layer "F.Cu")
		(at 445.157098 -92.468192 180)
		(property "Reference" "R3628"
			(at 0 0 180)
			(layer "F.SilkS")
			(hide yes)
			(effects
				(font
					(size 1.27 1.27)
				)
			)
		)
		(property "Value" ""
			(at 0 0 180)
			(layer "F.Fab")
			(effects
				(font
					(size 1.27 1.27)
				)
			)
		)
		(duplicate_pad_numbers_are_jumpers no)
		(fp_line
			(start 0.7874 0.4064)
			(end -0.7874 0.4064)
			(stroke
				(width 0.1524)
				(type default)
			)
			(layer "F.SilkS")
		)
		(fp_line
			(start 0.7874 -0.4064)
			(end 0.7874 0.4064)
			(stroke
				(width 0.1524)
				(type default)
			)
			(layer "F.SilkS")
		)
		(fp_line
			(start -0.7874 0.4064)
			(end -0.7874 -0.4064)
			(stroke
				(width 0.1524)
				(type default)
			)
			(layer "F.SilkS")
		)
		(fp_line
			(start -0.7874 -0.4064)
			(end 0.7874 -0.4064)
			(stroke
				(width 0.1524)
				(type default)
			)
			(layer "F.SilkS")
		)
		(fp_line
			(start 0.67945 0.3048)
			(end 0.120396 0.3048)
			(stroke
				(width 0.1)
				(type default)
			)
			(layer "F.Fab")
		)
		(fp_line
			(start 0.67945 -0.3048)
			(end 0.67945 0.3048)
			(stroke
				(width 0.1)
				(type default)
			)
			(layer "F.Fab")
		)
		(fp_line
			(start 0.12065 -0.2794)
			(end 0.12065 -0.3048)
			(stroke
				(width 0.1)
				(type default)
			)
			(layer "F.Fab")
		)
		(fp_line
			(start 0.12065 -0.3048)
			(end 0.67945 -0.3048)
			(stroke
				(width 0.1)
				(type default)
			)
			(layer "F.Fab")
		)
		(fp_line
			(start 0.120396 0.3048)
			(end 0.120396 0.2794)
			(stroke
				(width 0.1)
				(type default)
			)
			(layer "F.Fab")
		)
		(fp_line
			(start 0.120396 0.2794)
			(end -0.12065 0.2794)
			(stroke
				(width 0.1)
				(type default)
			)
			(layer "F.Fab")
		)
		(fp_line
			(start -0.12065 0.3048)
			(end -0.67945 0.3048)
			(stroke
				(width 0.1)
				(type default)
			)
			(layer "F.Fab")
		)
		(fp_line
			(start -0.12065 0.2794)
			(end -0.12065 0.3048)
			(stroke
				(width 0.1)
				(type default)
			)
			(layer "F.Fab")
		)
		(fp_line
			(start -0.12065 -0.2794)
			(end 0.12065 -0.2794)
			(stroke
				(width 0.1)
				(type default)
			)
			(layer "F.Fab")
		)
		(fp_line
			(start -0.12065 -0.305054)
			(end -0.12065 -0.2794)
			(stroke
				(width 0.1)
				(type default)
			)
			(layer "F.Fab")
		)
		(fp_line
			(start -0.67945 0.3048)
			(end -0.67945 -0.305054)
			(stroke
				(width 0.1)
				(type default)
			)
			(layer "F.Fab")
		)
		(fp_line
			(start -0.67945 -0.305054)
			(end -0.12065 -0.305054)
			(stroke
				(width 0.1)
				(type default)
			)
			(layer "F.Fab")
		)
		(pad "1" smd circle
			(at -0.40005 0 180)
			(size 0 0)
			(layers "F.Cu" "F.Mask" "F.Paste")
			(net "P3V3_AUX")
		)
		(pad "2" smd circle
			(at 0.40005 0 180)
			(size 0 0)
			(layers "F.Cu" "F.Mask" "F.Paste")
			(net "INA230_1_A1")
		)
	)
	(footprint ""
		(layer "F.Cu")
		(at 176.79162 -413.836358 90)
		(property "Reference" "R2923"
			(at 0 0 90)
			(layer "F.SilkS")
			(hide yes)
			(effects
				(font
					(size 1.27 1.27)
				)
			)
		)
		(property "Value" ""
			(at 0 0 90)
			(layer "F.Fab")
			(effects
				(font
					(size 1.27 1.27)
				)
			)
		)
		(duplicate_pad_numbers_are_jumpers no)
		(fp_line
			(start 0.7874 -0.4064)
			(end 0.7874 0.4064)
			(stroke
				(width 0.1524)
				(type default)
			)
			(layer "F.SilkS")
		)
		(fp_line
			(start -0.7874 -0.4064)
			(end 0.7874 -0.4064)
			(stroke
				(width 0.1524)
				(type default)
			)
			(layer "F.SilkS")
		)
		(fp_line
			(start 0.7874 0.4064)
			(end -0.7874 0.4064)
			(stroke
				(width 0.1524)
				(type default)
			)
			(layer "F.SilkS")
		)
		(fp_line
			(start -0.7874 0.4064)
			(end -0.7874 -0.4064)
			(stroke
				(width 0.1524)
				(type default)
			)
			(layer "F.SilkS")
		)
		(fp_line
			(start -0.12065 -0.305054)
			(end -0.12065 -0.2794)
			(stroke
				(width 0.1)
				(type default)
			)
			(layer "F.Fab")
		)
		(fp_line
			(start -0.67945 -0.305054)
			(end -0.12065 -0.305054)
			(stroke
				(width 0.1)
				(type default)
			)
			(layer "F.Fab")
		)
		(fp_line
			(start 0.67945 -0.3048)
			(end 0.67945 0.3048)
			(stroke
				(width 0.1)
				(type default)
			)
			(layer "F.Fab")
		)
		(fp_line
			(start 0.12065 -0.3048)
			(end 0.67945 -0.3048)
			(stroke
				(width 0.1)
				(type default)
			)
			(layer "F.Fab")
		)
		(fp_line
			(start 0.12065 -0.2794)
			(end 0.12065 -0.3048)
			(stroke
				(width 0.1)
				(type default)
			)
			(layer "F.Fab")
		)
		(fp_line
			(start -0.12065 -0.2794)
			(end 0.12065 -0.2794)
			(stroke
				(width 0.1)
				(type default)
			)
			(layer "F.Fab")
		)
		(fp_line
			(start 0.120396 0.2794)
			(end -0.12065 0.2794)
			(stroke
				(width 0.1)
				(type default)
			)
			(layer "F.Fab")
		)
		(fp_line
			(start -0.12065 0.2794)
			(end -0.12065 0.3048)
			(stroke
				(width 0.1)
				(type default)
			)
			(layer "F.Fab")
		)
		(fp_line
			(start 0.67945 0.3048)
			(end 0.120396 0.3048)
			(stroke
				(width 0.1)
				(type default)
			)
			(layer "F.Fab")
		)
		(fp_line
			(start 0.120396 0.3048)
			(end 0.120396 0.2794)
			(stroke
				(width 0.1)
				(type default)
			)
			(layer "F.Fab")
		)
		(fp_line
			(start -0.12065 0.3048)
			(end -0.67945 0.3048)
			(stroke
				(width 0.1)
				(type default)
			)
			(layer "F.Fab")
		)
		(fp_line
			(start -0.67945 0.3048)
			(end -0.67945 -0.305054)
			(stroke
				(width 0.1)
				(type default)
			)
			(layer "F.Fab")
		)
		(pad "1" smd circle
			(at -0.40005 0 90)
			(size 0 0)
			(layers "F.Cu" "F.Mask" "F.Paste")
			(net "P3V3_AUX")
		)
		(pad "2" smd circle
			(at 0.40005 0 90)
			(size 0 0)
			(layers "F.Cu" "F.Mask" "F.Paste")
			(net "PU_U181_INT")
		)
	)
	(footprint ""
		(layer "F.Cu")
		(at 137.762488 -385.09448 180)
		(property "Reference" "L33"
			(at 0 0 180)
			(layer "F.SilkS")
			(hide yes)
			(effects
				(font
					(size 1.27 1.27)
				)
			)
		)
		(property "Value" ""
			(at 0 0 180)
			(layer "F.Fab")
			(effects
				(font
					(size 1.27 1.27)
				)
			)
		)
		(duplicate_pad_numbers_are_jumpers no)
		(fp_line
			(start 0.762 0.381)
			(end -0.762 0.381)
			(stroke
				(width 0.1524)
				(type default)
			)
			(layer "F.SilkS")
		)
		(fp_line
			(start 0.762 -0.381)
			(end 0.762 0.381)
			(stroke
				(width 0.1524)
				(type default)
			)
			(layer "F.SilkS")
		)
		(fp_line
			(start -0.762 0.381)
			(end -0.762 -0.381)
			(stroke
				(width 0.1524)
				(type default)
			)
			(layer "F.SilkS")
		)
		(fp_line
			(start -0.762 -0.381)
			(end 0.762 -0.381)
			(stroke
				(width 0.1524)
				(type default)
			)
			(layer "F.SilkS")
		)
		(fp_line
			(start 0.680466 0.306324)
			(end 0.118364 0.306324)
			(stroke
				(width 0.1)
				(type default)
			)
			(layer "F.Fab")
		)
		(fp_line
			(start 0.680466 -0.306324)
			(end 0.680466 0.306324)
			(stroke
				(width 0.1)
				(type default)
			)
			(layer "F.Fab")
		)
		(fp_line
			(start 0.118872 -0.2794)
			(end 0.118872 -0.306324)
			(stroke
				(width 0.1)
				(type default)
			)
			(layer "F.Fab")
		)
		(fp_line
			(start 0.118872 -0.306324)
			(end 0.680466 -0.306324)
			(stroke
				(width 0.1)
				(type default)
			)
			(layer "F.Fab")
		)
		(fp_line
			(start 0.118364 0.306324)
			(end 0.118364 0.2794)
			(stroke
				(width 0.1)
				(type default)
			)
			(layer "F.Fab")
		)
		(fp_line
			(start 0.118364 0.2794)
			(end -0.119634 0.2794)
			(stroke
				(width 0.1)
				(type default)
			)
			(layer "F.Fab")
		)
		(fp_line
			(start -0.118364 -0.2794)
			(end 0.118872 -0.2794)
			(stroke
				(width 0.1)
				(type default)
			)
			(layer "F.Fab")
		)
		(fp_line
			(start -0.118364 -0.307086)
			(end -0.118364 -0.2794)
			(stroke
				(width 0.1)
				(type default)
			)
			(layer "F.Fab")
		)
		(fp_line
			(start -0.119634 0.30607)
			(end -0.681736 0.30607)
			(stroke
				(width 0.1)
				(type default)
			)
			(layer "F.Fab")
		)
		(fp_line
			(start -0.119634 0.2794)
			(end -0.119634 0.30607)
			(stroke
				(width 0.1)
				(type default)
			)
			(layer "F.Fab")
		)
		(fp_line
			(start -0.681736 0.30607)
			(end -0.681736 -0.307086)
			(stroke
				(width 0.1)
				(type default)
			)
			(layer "F.Fab")
		)
		(fp_line
			(start -0.681736 -0.307086)
			(end -0.118364 -0.307086)
			(stroke
				(width 0.1)
				(type default)
			)
			(layer "F.Fab")
		)
		(pad "1" smd rect
			(at -0.40005 0)
			(size 0.4572 0.508)
			(layers "F.Cu" "F.Mask" "F.Paste")
			(net "P1V8_CPU1_RT_1D")
		)
		(pad "2" smd rect
			(at 0.40005 0)
			(size 0.4572 0.508)
			(layers "F.Cu" "F.Mask" "F.Paste")
			(net "P1V8_CPU1_RT3_1A_1D")
		)
	)
	(footprint ""
		(layer "F.Cu")
		(at 75.081638 -334.991202 -90)
		(property "Reference" "PC372_C1P1_2"
			(at 0 0 270)
			(layer "F.SilkS")
			(hide yes)
			(effects
				(font
					(size 1.27 1.27)
				)
			)
		)
		(property "Value" ""
			(at 0 0 270)
			(layer "F.Fab")
			(effects
				(font
					(size 1.27 1.27)
				)
			)
		)
		(duplicate_pad_numbers_are_jumpers no)
		(fp_line
			(start -0.7874 0.4064)
			(end -0.7874 -0.4064)
			(stroke
				(width 0.1524)
				(type default)
			)
			(layer "F.SilkS")
		)
		(fp_line
			(start 0.7874 0.4064)
			(end -0.7874 0.4064)
			(stroke
				(width 0.1524)
				(type default)
			)
			(layer "F.SilkS")
		)
		(fp_line
			(start -0.7874 -0.4064)
			(end 0.7874 -0.4064)
			(stroke
				(width 0.1524)
				(type default)
			)
			(layer "F.SilkS")
		)
		(fp_line
			(start 0.7874 -0.4064)
			(end 0.7874 0.4064)
			(stroke
				(width 0.1524)
				(type default)
			)
			(layer "F.SilkS")
		)
		(fp_line
			(start -0.67945 0.3048)
			(end -0.67945 -0.305054)
			(stroke
				(width 0.1)
				(type default)
			)
			(layer "F.Fab")
		)
		(fp_line
			(start -0.12065 0.3048)
			(end -0.67945 0.3048)
			(stroke
				(width 0.1)
				(type default)
			)
			(layer "F.Fab")
		)
		(fp_line
			(start 0.120396 0.3048)
			(end 0.120396 0.2794)
			(stroke
				(width 0.1)
				(type default)
			)
			(layer "F.Fab")
		)
		(fp_line
			(start 0.67945 0.3048)
			(end 0.120396 0.3048)
			(stroke
				(width 0.1)
				(type default)
			)
			(layer "F.Fab")
		)
		(fp_line
			(start -0.12065 0.2794)
			(end -0.12065 0.3048)
			(stroke
				(width 0.1)
				(type default)
			)
			(layer "F.Fab")
		)
		(fp_line
			(start 0.120396 0.2794)
			(end -0.12065 0.2794)
			(stroke
				(width 0.1)
				(type default)
			)
			(layer "F.Fab")
		)
		(fp_line
			(start -0.12065 -0.2794)
			(end 0.12065 -0.2794)
			(stroke
				(width 0.1)
				(type default)
			)
			(layer "F.Fab")
		)
		(fp_line
			(start 0.12065 -0.2794)
			(end 0.12065 -0.3048)
			(stroke
				(width 0.1)
				(type default)
			)
			(layer "F.Fab")
		)
		(fp_line
			(start 0.12065 -0.3048)
			(end 0.67945 -0.3048)
			(stroke
				(width 0.1)
				(type default)
			)
			(layer "F.Fab")
		)
		(fp_line
			(start 0.67945 -0.3048)
			(end 0.67945 0.3048)
			(stroke
				(width 0.1)
				(type default)
			)
			(layer "F.Fab")
		)
		(fp_line
			(start -0.67945 -0.305054)
			(end -0.12065 -0.305054)
			(stroke
				(width 0.1)
				(type default)
			)
			(layer "F.Fab")
		)
		(fp_line
			(start -0.12065 -0.305054)
			(end -0.12065 -0.2794)
			(stroke
				(width 0.1)
				(type default)
			)
			(layer "F.Fab")
		)
		(pad "1" smd circle
			(at -0.40005 0 270)
			(size 0 0)
			(layers "F.Cu" "F.Mask" "F.Paste")
			(net "PVDDCR_CPU1_P1_PVCC")
		)
		(pad "2" smd circle
			(at 0.40005 0 270)
			(size 0 0)
			(layers "F.Cu" "F.Mask" "F.Paste")
			(net "GND")
		)
	)
	(footprint ""
		(layer "F.Cu")
		(at 265.49223 -103.272844 180)
		(property "Reference" "C1508"
			(at 0 0 180)
			(layer "F.SilkS")
			(hide yes)
			(effects
				(font
					(size 1.27 1.27)
				)
			)
		)
		(property "Value" ""
			(at 0 0 180)
			(layer "F.Fab")
			(effects
				(font
					(size 1.27 1.27)
				)
			)
		)
		(duplicate_pad_numbers_are_jumpers no)
		(fp_line
			(start 0.7874 0.4064)
			(end -0.7874 0.4064)
			(stroke
				(width 0.1524)
				(type default)
			)
			(layer "F.SilkS")
		)
		(fp_line
			(start 0.7874 -0.4064)
			(end 0.7874 0.4064)
			(stroke
				(width 0.1524)
				(type default)
			)
			(layer "F.SilkS")
		)
		(fp_line
			(start -0.7874 0.4064)
			(end -0.7874 -0.4064)
			(stroke
				(width 0.1524)
				(type default)
			)
			(layer "F.SilkS")
		)
		(fp_line
			(start -0.7874 -0.4064)
			(end 0.7874 -0.4064)
			(stroke
				(width 0.1524)
				(type default)
			)
			(layer "F.SilkS")
		)
		(fp_line
			(start 0.67945 0.3048)
			(end 0.120396 0.3048)
			(stroke
				(width 0.1)
				(type default)
			)
			(layer "F.Fab")
		)
		(fp_line
			(start 0.67945 -0.3048)
			(end 0.67945 0.3048)
			(stroke
				(width 0.1)
				(type default)
			)
			(layer "F.Fab")
		)
		(fp_line
			(start 0.12065 -0.2794)
			(end 0.12065 -0.3048)
			(stroke
				(width 0.1)
				(type default)
			)
			(layer "F.Fab")
		)
		(fp_line
			(start 0.12065 -0.3048)
			(end 0.67945 -0.3048)
			(stroke
				(width 0.1)
				(type default)
			)
			(layer "F.Fab")
		)
		(fp_line
			(start 0.120396 0.3048)
			(end 0.120396 0.2794)
			(stroke
				(width 0.1)
				(type default)
			)
			(layer "F.Fab")
		)
		(fp_line
			(start 0.120396 0.2794)
			(end -0.12065 0.2794)
			(stroke
				(width 0.1)
				(type default)
			)
			(layer "F.Fab")
		)
		(fp_line
			(start -0.12065 0.3048)
			(end -0.67945 0.3048)
			(stroke
				(width 0.1)
				(type default)
			)
			(layer "F.Fab")
		)
		(fp_line
			(start -0.12065 0.2794)
			(end -0.12065 0.3048)
			(stroke
				(width 0.1)
				(type default)
			)
			(layer "F.Fab")
		)
		(fp_line
			(start -0.12065 -0.2794)
			(end 0.12065 -0.2794)
			(stroke
				(width 0.1)
				(type default)
			)
			(layer "F.Fab")
		)
		(fp_line
			(start -0.12065 -0.305054)
			(end -0.12065 -0.2794)
			(stroke
				(width 0.1)
				(type default)
			)
			(layer "F.Fab")
		)
		(fp_line
			(start -0.67945 0.3048)
			(end -0.67945 -0.305054)
			(stroke
				(width 0.1)
				(type default)
			)
			(layer "F.Fab")
		)
		(fp_line
			(start -0.67945 -0.305054)
			(end -0.12065 -0.305054)
			(stroke
				(width 0.1)
				(type default)
			)
			(layer "F.Fab")
		)
		(pad "1" smd circle
			(at -0.40005 0 180)
			(size 0 0)
			(layers "F.Cu" "F.Mask" "F.Paste")
			(net "PVDD18_S5_P0")
		)
		(pad "2" smd circle
			(at 0.40005 0 180)
			(size 0 0)
			(layers "F.Cu" "F.Mask" "F.Paste")
			(net "GND")
		)
	)
	(footprint ""
		(layer "F.Cu")
		(at 33.198054 -346.719398 -90)
		(property "Reference" "PC619_IOP1_3"
			(at 0 0 270)
			(layer "F.SilkS")
			(hide yes)
			(effects
				(font
					(size 1.27 1.27)
				)
			)
		)
		(property "Value" ""
			(at 0 0 270)
			(layer "F.Fab")
			(effects
				(font
					(size 1.27 1.27)
				)
			)
		)
		(duplicate_pad_numbers_are_jumpers no)
		(fp_line
			(start -0.7874 0.4064)
			(end -0.7874 -0.4064)
			(stroke
				(width 0.1524)
				(type default)
			)
			(layer "F.SilkS")
		)
		(fp_line
			(start 0.7874 0.4064)
			(end -0.7874 0.4064)
			(stroke
				(width 0.1524)
				(type default)
			)
			(layer "F.SilkS")
		)
		(fp_line
			(start -0.7874 -0.4064)
			(end 0.7874 -0.4064)
			(stroke
				(width 0.1524)
				(type default)
			)
			(layer "F.SilkS")
		)
		(fp_line
			(start 0.7874 -0.4064)
			(end 0.7874 0.4064)
			(stroke
				(width 0.1524)
				(type default)
			)
			(layer "F.SilkS")
		)
		(fp_line
			(start -0.67945 0.3048)
			(end -0.67945 -0.305054)
			(stroke
				(width 0.1)
				(type default)
			)
			(layer "F.Fab")
		)
		(fp_line
			(start -0.12065 0.3048)
			(end -0.67945 0.3048)
			(stroke
				(width 0.1)
				(type default)
			)
			(layer "F.Fab")
		)
		(fp_line
			(start 0.120396 0.3048)
			(end 0.120396 0.2794)
			(stroke
				(width 0.1)
				(type default)
			)
			(layer "F.Fab")
		)
		(fp_line
			(start 0.67945 0.3048)
			(end 0.120396 0.3048)
			(stroke
				(width 0.1)
				(type default)
			)
			(layer "F.Fab")
		)
		(fp_line
			(start -0.12065 0.2794)
			(end -0.12065 0.3048)
			(stroke
				(width 0.1)
				(type default)
			)
			(layer "F.Fab")
		)
		(fp_line
			(start 0.120396 0.2794)
			(end -0.12065 0.2794)
			(stroke
				(width 0.1)
				(type default)
			)
			(layer "F.Fab")
		)
		(fp_line
			(start -0.12065 -0.2794)
			(end 0.12065 -0.2794)
			(stroke
				(width 0.1)
				(type default)
			)
			(layer "F.Fab")
		)
		(fp_line
			(start 0.12065 -0.2794)
			(end 0.12065 -0.3048)
			(stroke
				(width 0.1)
				(type default)
			)
			(layer "F.Fab")
		)
		(fp_line
			(start 0.12065 -0.3048)
			(end 0.67945 -0.3048)
			(stroke
				(width 0.1)
				(type default)
			)
			(layer "F.Fab")
		)
		(fp_line
			(start 0.67945 -0.3048)
			(end 0.67945 0.3048)
			(stroke
				(width 0.1)
				(type default)
			)
			(layer "F.Fab")
		)
		(fp_line
			(start -0.67945 -0.305054)
			(end -0.12065 -0.305054)
			(stroke
				(width 0.1)
				(type default)
			)
			(layer "F.Fab")
		)
		(fp_line
			(start -0.12065 -0.305054)
			(end -0.12065 -0.2794)
			(stroke
				(width 0.1)
				(type default)
			)
			(layer "F.Fab")
		)
		(pad "1" smd circle
			(at -0.40005 0 270)
			(size 0 0)
			(layers "F.Cu" "F.Mask" "F.Paste")
			(net "PVDDCR_CPU1_P1_PVCC")
		)
		(pad "2" smd circle
			(at 0.40005 0 270)
			(size 0 0)
			(layers "F.Cu" "F.Mask" "F.Paste")
			(net "GND")
		)
	)
	(footprint ""
		(layer "F.Cu")
		(at 422.55694 -101.270308 -90)
		(property "Reference" "PR3844"
			(at 0 0 270)
			(layer "F.SilkS")
			(hide yes)
			(effects
				(font
					(size 1.27 1.27)
				)
			)
		)
		(property "Value" ""
			(at 0 0 270)
			(layer "F.Fab")
			(effects
				(font
					(size 1.27 1.27)
				)
			)
		)
		(duplicate_pad_numbers_are_jumpers no)
		(fp_line
			(start -0.7874 0.4064)
			(end -0.7874 -0.4064)
			(stroke
				(width 0.1524)
				(type default)
			)
			(layer "F.SilkS")
		)
		(fp_line
			(start 0.7874 0.4064)
			(end -0.7874 0.4064)
			(stroke
				(width 0.1524)
				(type default)
			)
			(layer "F.SilkS")
		)
		(fp_line
			(start -0.7874 -0.4064)
			(end 0.7874 -0.4064)
			(stroke
				(width 0.1524)
				(type default)
			)
			(layer "F.SilkS")
		)
		(fp_line
			(start 0.7874 -0.4064)
			(end 0.7874 0.4064)
			(stroke
				(width 0.1524)
				(type default)
			)
			(layer "F.SilkS")
		)
		(fp_line
			(start -0.67945 0.3048)
			(end -0.67945 -0.305054)
			(stroke
				(width 0.1)
				(type default)
			)
			(layer "F.Fab")
		)
		(fp_line
			(start -0.12065 0.3048)
			(end -0.67945 0.3048)
			(stroke
				(width 0.1)
				(type default)
			)
			(layer "F.Fab")
		)
		(fp_line
			(start 0.120396 0.3048)
			(end 0.120396 0.2794)
			(stroke
				(width 0.1)
				(type default)
			)
			(layer "F.Fab")
		)
		(fp_line
			(start 0.67945 0.3048)
			(end 0.120396 0.3048)
			(stroke
				(width 0.1)
				(type default)
			)
			(layer "F.Fab")
		)
		(fp_line
			(start -0.12065 0.2794)
			(end -0.12065 0.3048)
			(stroke
				(width 0.1)
				(type default)
			)
			(layer "F.Fab")
		)
		(fp_line
			(start 0.120396 0.2794)
			(end -0.12065 0.2794)
			(stroke
				(width 0.1)
				(type default)
			)
			(layer "F.Fab")
		)
		(fp_line
			(start -0.12065 -0.2794)
			(end 0.12065 -0.2794)
			(stroke
				(width 0.1)
				(type default)
			)
			(layer "F.Fab")
		)
		(fp_line
			(start 0.12065 -0.2794)
			(end 0.12065 -0.3048)
			(stroke
				(width 0.1)
				(type default)
			)
			(layer "F.Fab")
		)
		(fp_line
			(start 0.12065 -0.3048)
			(end 0.67945 -0.3048)
			(stroke
				(width 0.1)
				(type default)
			)
			(layer "F.Fab")
		)
		(fp_line
			(start 0.67945 -0.3048)
			(end 0.67945 0.3048)
			(stroke
				(width 0.1)
				(type default)
			)
			(layer "F.Fab")
		)
		(fp_line
			(start -0.67945 -0.305054)
			(end -0.12065 -0.305054)
			(stroke
				(width 0.1)
				(type default)
			)
			(layer "F.Fab")
		)
		(fp_line
			(start -0.12065 -0.305054)
			(end -0.12065 -0.2794)
			(stroke
				(width 0.1)
				(type default)
			)
			(layer "F.Fab")
		)
		(pad "1" smd circle
			(at -0.40005 0 270)
			(size 0 0)
			(layers "F.Cu" "F.Mask" "F.Paste")
			(net "P3V3_OCP_MODE_1")
		)
		(pad "2" smd circle
			(at 0.40005 0 270)
			(size 0 0)
			(layers "F.Cu" "F.Mask" "F.Paste")
			(net "GND")
		)
	)
	(footprint ""
		(layer "F.Cu")
		(at 426.979588 -391.49909 180)
		(property "Reference" "R1059"
			(at 0 0 180)
			(layer "F.SilkS")
			(hide yes)
			(effects
				(font
					(size 1.27 1.27)
				)
			)
		)
		(property "Value" ""
			(at 0 0 180)
			(layer "F.Fab")
			(effects
				(font
					(size 1.27 1.27)
				)
			)
		)
		(duplicate_pad_numbers_are_jumpers no)
		(fp_line
			(start 0.32512 0.175006)
			(end -0.32512 0.175006)
			(stroke
				(width 0.1)
				(type default)
			)
			(layer "F.Fab")
		)
		(fp_line
			(start 0.32512 -0.175006)
			(end 0.32512 0.175006)
			(stroke
				(width 0.1)
				(type default)
			)
			(layer "F.Fab")
		)
		(fp_line
			(start -0.32512 0.175006)
			(end -0.32512 -0.175006)
			(stroke
				(width 0.1)
				(type default)
			)
			(layer "F.Fab")
		)
		(fp_line
			(start -0.32512 -0.175006)
			(end 0.32512 -0.175006)
			(stroke
				(width 0.1)
				(type default)
			)
			(layer "F.Fab")
		)
		(pad "1" smd rect
			(at -0.2667 0 180)
			(size 0.3048 0.381)
			(layers "F.Cu" "F.Mask" "F.Paste")
			(net "P1V8_CPU0_RT_1D")
		)
		(pad "2" smd rect
			(at 0.2667 0)
			(size 0.3048 0.381)
			(layers "F.Cu" "F.Mask" "F.Paste")
			(net "RT_CPU0_P2_ADDR1")
		)
	)
	(footprint ""
		(layer "F.Cu")
		(at 171.20743 -101.998018)
		(property "Reference" "R6184"
			(at 0 0 0)
			(layer "F.SilkS")
			(hide yes)
			(effects
				(font
					(size 1.27 1.27)
				)
			)
		)
		(property "Value" ""
			(at 0 0 0)
			(layer "F.Fab")
			(effects
				(font
					(size 1.27 1.27)
				)
			)
		)
		(duplicate_pad_numbers_are_jumpers no)
		(fp_line
			(start -0.7874 -0.4064)
			(end 0.7874 -0.4064)
			(stroke
				(width 0.1524)
				(type default)
			)
			(layer "F.SilkS")
		)
		(fp_line
			(start -0.7874 0.4064)
			(end -0.7874 -0.4064)
			(stroke
				(width 0.1524)
				(type default)
			)
			(layer "F.SilkS")
		)
		(fp_line
			(start 0.7874 -0.4064)
			(end 0.7874 0.4064)
			(stroke
				(width 0.1524)
				(type default)
			)
			(layer "F.SilkS")
		)
		(fp_line
			(start 0.7874 0.4064)
			(end -0.7874 0.4064)
			(stroke
				(width 0.1524)
				(type default)
			)
			(layer "F.SilkS")
		)
		(fp_line
			(start -0.67945 -0.305054)
			(end -0.12065 -0.305054)
			(stroke
				(width 0.1)
				(type default)
			)
			(layer "F.Fab")
		)
		(fp_line
			(start -0.67945 0.3048)
			(end -0.67945 -0.305054)
			(stroke
				(width 0.1)
				(type default)
			)
			(layer "F.Fab")
		)
		(fp_line
			(start -0.12065 -0.305054)
			(end -0.12065 -0.2794)
			(stroke
				(width 0.1)
				(type default)
			)
			(layer "F.Fab")
		)
		(fp_line
			(start -0.12065 -0.2794)
			(end 0.12065 -0.2794)
			(stroke
				(width 0.1)
				(type default)
			)
			(layer "F.Fab")
		)
		(fp_line
			(start -0.12065 0.2794)
			(end -0.12065 0.3048)
			(stroke
				(width 0.1)
				(type default)
			)
			(layer "F.Fab")
		)
		(fp_line
			(start -0.12065 0.3048)
			(end -0.67945 0.3048)
			(stroke
				(width 0.1)
				(type default)
			)
			(layer "F.Fab")
		)
		(fp_line
			(start 0.120396 0.2794)
			(end -0.12065 0.2794)
			(stroke
				(width 0.1)
				(type default)
			)
			(layer "F.Fab")
		)
		(fp_line
			(start 0.120396 0.3048)
			(end 0.120396 0.2794)
			(stroke
				(width 0.1)
				(type default)
			)
			(layer "F.Fab")
		)
		(fp_line
			(start 0.12065 -0.3048)
			(end 0.67945 -0.3048)
			(stroke
				(width 0.1)
				(type default)
			)
			(layer "F.Fab")
		)
		(fp_line
			(start 0.12065 -0.2794)
			(end 0.12065 -0.3048)
			(stroke
				(width 0.1)
				(type default)
			)
			(layer "F.Fab")
		)
		(fp_line
			(start 0.67945 -0.3048)
			(end 0.67945 0.3048)
			(stroke
				(width 0.1)
				(type default)
			)
			(layer "F.Fab")
		)
		(fp_line
			(start 0.67945 0.3048)
			(end 0.120396 0.3048)
			(stroke
				(width 0.1)
				(type default)
			)
			(layer "F.Fab")
		)
		(pad "1" smd circle
			(at -0.40005 0)
			(size 0 0)
			(layers "F.Cu" "F.Mask" "F.Paste")
			(net "FM_SEC_MUX_SEL")
		)
		(pad "2" smd circle
			(at 0.40005 0)
			(size 0 0)
			(layers "F.Cu" "F.Mask" "F.Paste")
			(net "FM_SEC_MUX_R_SEL")
		)
	)
	(footprint ""
		(layer "F.Cu")
		(at 185.522108 -115.052856 90)
		(property "Reference" "U18"
			(at -10.68451 -12.951206 0)
			(unlocked yes)
			(layer "F.SilkS")
			(effects
				(font
					(size 0.7874 0.5842)
					(thickness 0.1524)
				)
				(justify left)
			)
		)
		(property "Value" ""
			(at 0 0 90)
			(layer "F.Fab")
			(effects
				(font
					(size 1.27 1.27)
				)
			)
		)
		(duplicate_pad_numbers_are_jumpers no)
		(fp_line
			(start 9.500108 -9.500108)
			(end -9.500108 -9.500108)
			(stroke
				(width 0.1524)
				(type default)
			)
			(layer "F.SilkS")
		)
		(fp_line
			(start -9.500108 -9.500108)
			(end -9.500108 9.500108)
			(stroke
				(width 0.1524)
				(type default)
			)
			(layer "F.SilkS")
		)
		(fp_line
			(start 9.500108 9.500108)
			(end 9.500108 -9.500108)
			(stroke
				(width 0.1524)
				(type default)
			)
			(layer "F.SilkS")
		)
		(fp_line
			(start -9.500108 9.500108)
			(end 9.500108 9.500108)
			(stroke
				(width 0.1524)
				(type default)
			)
			(layer "F.SilkS")
		)
		(fp_poly
			(pts
				(xy -7.599934 -9.500108) (xy -9.500108 -9.500108) (xy -9.500108 -7.599934) (xy -10.262108 -7.599934)
				(xy -10.262108 -10.262108) (xy -7.599934 -10.262108)
			)
			(stroke
				(width 0)
				(type default)
			)
			(fill yes)
			(layer "F.SilkS")
		)
		(fp_line
			(start 9.500108 -9.500108)
			(end -9.500108 -9.500108)
			(stroke
				(width 0.1)
				(type default)
			)
			(layer "F.Fab")
		)
		(fp_line
			(start -9.500108 -9.500108)
			(end -9.500108 9.500108)
			(stroke
				(width 0.1)
				(type default)
			)
			(layer "F.Fab")
		)
		(fp_line
			(start 9.500108 9.500108)
			(end 9.500108 -9.500108)
			(stroke
				(width 0.1)
				(type default)
			)
			(layer "F.Fab")
		)
		(fp_line
			(start -9.500108 9.500108)
			(end 9.500108 9.500108)
			(stroke
				(width 0.1)
				(type default)
			)
			(layer "F.Fab")
		)
		(fp_poly
			(pts
				(xy -9.500108 -9.500108) (xy -7.599934 -9.500108) (xy -7.599934 -10.262108) (xy -10.262108 -10.262108)
				(xy -10.262108 -7.599934) (xy -9.500108 -7.599934)
			)
			(stroke
				(width 0)
				(type default)
			)
			(fill yes)
			(layer "F.Fab")
		)
		(pad "A1" smd circle
			(at -8.400034 -8.400034 90)
			(size 0.4064 0.4064)
			(layers "F.Cu" "F.Mask" "F.Paste")
			(net "GND")
		)
		(pad "A2" smd circle
			(at -7.599934 -8.400034 90)
			(size 0.4064 0.4064)
			(layers "F.Cu" "F.Mask" "F.Paste")
			(net "FM_I3C_CPU1_MUX0_R_SEL")
		)
		(pad "A3" smd circle
			(at -6.800088 -8.400034 90)
			(size 0.4064 0.4064)
			(layers "F.Cu" "F.Mask" "F.Paste")
			(net "SCM_JTAG_MUX_R_S1")
		)
		(pad "A4" smd circle
			(at -5.999988 -8.400034 90)
			(size 0.4064 0.4064)
			(layers "F.Cu" "F.Mask" "F.Paste")
			(net "SGPIO_SCM_DI_R<0>")
		)
		(pad "A5" smd circle
			(at -5.199888 -8.400034 90)
			(size 0.4064 0.4064)
			(layers "F.Cu" "F.Mask" "F.Paste")
			(net "SGPIO_SCM_RESET_N")
		)
		(pad "A6" smd circle
			(at -4.400042 -8.400034 90)
			(size 0.4064 0.4064)
			(layers "F.Cu" "F.Mask" "F.Paste")
			(net "E1S_0_PERST1_CLKREQ_R_N")
		)
		(pad "A7" smd circle
			(at -3.599942 -8.400034 90)
			(size 0.4064 0.4064)
			(layers "F.Cu" "F.Mask" "F.Paste")
			(net "FM_UV_ADR_TRIGGER_R_N")
		)
		(pad "A8" smd circle
			(at -2.800096 -8.400034 90)
			(size 0.4064 0.4064)
			(layers "F.Cu" "F.Mask" "F.Paste")
			(net "SGPIO_OCP_SFF_DATAOUT")
		)
		(pad "A9" smd circle
			(at -1.999996 -8.400034 90)
			(size 0.4064 0.4064)
			(layers "F.Cu" "F.Mask" "F.Paste")
			(net "OCP_V3_1_P3V3_PLD_R_PWRGD")
		)
		(pad "A10" smd circle
			(at -1.199896 -8.400034 90)
			(size 0.4064 0.4064)
			(layers "F.Cu" "F.Mask" "F.Paste")
			(net "OC_ALERT_N")
		)
		(pad "A11" smd circle
			(at -0.40005 -8.400034 90)
			(size 0.4064 0.4064)
			(layers "F.Cu" "F.Mask" "F.Paste")
			(net "FM_BOARD_BMC_SKU_ID4")
		)
		(pad "A12" smd circle
			(at 0.40005 -8.400034 90)
			(size 0.4064 0.4064)
			(layers "F.Cu" "F.Mask" "F.Paste")
			(net "SMB_1_PLD_3V3AUX_SDA_R2")
		)
		(pad "A13" smd circle
			(at 1.199896 -8.400034 90)
			(size 0.4064 0.4064)
			(layers "F.Cu" "F.Mask" "F.Paste")
			(net "SMB_2_PLD_3V3AUX_SCL_R2")
		)
		(pad "A14" smd circle
			(at 1.999996 -8.400034 90)
			(size 0.4064 0.4064)
			(layers "F.Cu" "F.Mask" "F.Paste")
			(net "SGPIO_OCP_V3_2_LD_N")
		)
		(pad "A15" smd circle
			(at 2.800096 -8.400034 90)
			(size 0.4064 0.4064)
			(layers "F.Cu" "F.Mask" "F.Paste")
			(net "SCM_SYS_PWROK")
		)
		(pad "A16" smd circle
			(at 3.599942 -8.400034 90)
			(size 0.4064 0.4064)
			(layers "F.Cu" "F.Mask" "F.Paste")
			(net "PWRGD_P5V")
		)
		(pad "A17" smd circle
			(at 4.400042 -8.400034 90)
			(size 0.4064 0.4064)
			(layers "F.Cu" "F.Mask" "F.Paste")
			(net "PWRGD_PVDDCR_SOC_P1")
		)
		(pad "A18" smd circle
			(at 5.199888 -8.400034 90)
			(size 0.4064 0.4064)
			(layers "F.Cu" "F.Mask" "F.Paste")
			(net "FM_LED_PWRGD_PVDDIO_P1")
		)
		(pad "A19" smd circle
			(at 5.999988 -8.400034 90)
			(size 0.4064 0.4064)
			(layers "F.Cu" "F.Mask" "F.Paste")
			(net "FM_LED_PWRGD_PVDD18_S5_P1")
		)
		(pad "A20" smd circle
			(at 6.800088 -8.400034 90)
			(size 0.4064 0.4064)
			(layers "F.Cu" "F.Mask" "F.Paste")
			(net "P1V8_RETIMER_CPU1_R_EN")
		)
		(pad "A21" smd circle
			(at 7.599934 -8.400034 90)
			(size 0.4064 0.4064)
			(layers "F.Cu" "F.Mask" "F.Paste")
			(net "SMB_BMC_SWB_EN")
		)
		(pad "A22" smd circle
			(at 8.400034 -8.400034 90)
			(size 0.4064 0.4064)
			(layers "F.Cu" "F.Mask" "F.Paste")
			(net "GND")
		)
		(pad "AA1" smd circle
			(at -8.400034 7.599934 90)
			(size 0.4064 0.4064)
			(layers "F.Cu" "F.Mask" "F.Paste")
			(net "OCP_SFF_P3V3_P12V_ADC_ALERT")
		)
		(pad "AA2" smd circle
			(at -7.599934 7.599934 90)
			(size 0.4064 0.4064)
			(layers "F.Cu" "F.Mask" "F.Paste")
			(net "FM_SWB_PWR_EN")
		)
		(pad "AA3" smd circle
			(at -6.800088 7.599934 90)
			(size 0.4064 0.4064)
			(layers "F.Cu" "F.Mask" "F.Paste")
			(net "PRSNT_OCP_SFF_N")
		)
		(pad "AA4" smd circle
			(at -5.999988 7.599934 90)
			(size 0.4064 0.4064)
			(layers "F.Cu" "F.Mask" "F.Paste")
			(net "GPU_FPGA_EROT_RST_R_N")
		)
		(pad "AA5" smd circle
			(at -5.199888 7.599934 90)
			(size 0.4064 0.4064)
			(layers "F.Cu" "F.Mask" "F.Paste")
			(net "GPU_FPGA_EROT_RECOV_R_N")
		)
		(pad "AA6" smd circle
			(at -4.400042 7.599934 90)
			(size 0.4064 0.4064)
			(layers "F.Cu" "F.Mask" "F.Paste")
			(net "PWRGD_PVDD18_S5_R_P1")
		)
		(pad "AA7" smd circle
			(at -3.599942 7.599934 90)
			(size 0.4064 0.4064)
			(layers "F.Cu" "F.Mask" "F.Paste")
			(net "FM_PVDD11_S3_P1_EN")
		)
		(pad "AA8" smd circle
			(at -2.800096 7.599934 90)
			(size 0.4064 0.4064)
			(layers "F.Cu" "F.Mask" "F.Paste")
			(net "FM_PVDD18_S5_P0_EN")
		)
		(pad "AA9" smd circle
			(at -1.999996 7.599934 90)
			(size 0.4064 0.4064)
			(layers "F.Cu" "F.Mask" "F.Paste")
			(net "FM_PVDDIO_P1_EN")
		)
		(pad "AA10" smd circle
			(at -1.199896 7.599934 90)
			(size 0.4064 0.4064)
			(layers "F.Cu" "F.Mask" "F.Paste")
			(net "P0V9_RETIMER_CPU0_EN_R2")
		)
		(pad "AA11" smd circle
			(at -0.40005 7.599934 90)
			(size 0.4064 0.4064)
			(layers "F.Cu" "F.Mask" "F.Paste")
			(net "P12V_E1S_0_EN")
		)
		(pad "AA12" smd circle
			(at 0.40005 7.599934 90)
			(size 0.4064 0.4064)
			(layers "F.Cu" "F.Mask" "F.Paste")
			(net "GPU_3V3IO_RSVD3_ISO_R")
		)
		(pad "AA13" smd circle
			(at 1.199896 7.599934 90)
			(size 0.4064 0.4064)
			(layers "F.Cu" "F.Mask" "F.Paste")
			(net "RST_PERST_E1S_0_R_N")
		)
		(pad "AA14" smd circle
			(at 1.999996 7.599934 90)
			(size 0.4064 0.4064)
			(layers "F.Cu" "F.Mask" "F.Paste")
			(net "PRSNT_CABLE_GPU_A1_ISO_R_N")
		)
		(pad "AA15" smd circle
			(at 2.800096 7.599934 90)
			(size 0.4064 0.4064)
			(layers "F.Cu" "F.Mask" "F.Paste")
			(net "GPU_HMC_PRSNT_ISO_R_N")
		)
		(pad "AA16" smd circle
			(at 3.599942 7.599934 90)
			(size 0.4064 0.4064)
			(layers "F.Cu" "F.Mask" "F.Paste")
			(net "GPU_FPGA_EROT_FATALERR_ISO_R_N")
		)
		(pad "AA17" smd circle
			(at 4.400042 7.599934 90)
			(size 0.4064 0.4064)
			(layers "F.Cu" "F.Mask" "F.Paste")
			(net "FM_SMB_1_ALERT_GPU_ISO_R_N")
		)
		(pad "AA18" smd circle
			(at 5.199888 7.599934 90)
			(size 0.4064 0.4064)
			(layers "F.Cu" "F.Mask" "F.Paste")
			(net "FM_GPU_PWRGD_ISO_R")
		)
		(pad "AA19" smd circle
			(at 5.999988 7.599934 90)
			(size 0.4064 0.4064)
			(layers "F.Cu" "F.Mask" "F.Paste")
			(net "RST_PERST_OCP_V3_2_N")
		)
		(pad "AA20" smd circle
			(at 6.800088 7.599934 90)
			(size 0.4064 0.4064)
			(layers "F.Cu" "F.Mask" "F.Paste")
			(net "P12V_OCP_V3_2_EN_R")
		)
		(pad "AA21" smd circle
			(at 7.599934 7.599934 90)
			(size 0.4064 0.4064)
			(layers "F.Cu" "F.Mask" "F.Paste")
			(net "P0V9_RETIMER_CPU1_EN_R2")
		)
		(pad "AA22" smd circle
			(at 8.400034 7.599934 90)
			(size 0.4064 0.4064)
			(layers "F.Cu" "F.Mask" "F.Paste")
			(net "FM_CPU1_PWRGD_OUT")
		)
		(pad "AB1" smd circle
			(at -8.400034 8.400034 90)
			(size 0.4064 0.4064)
			(layers "F.Cu" "F.Mask" "F.Paste")
			(net "GND")
		)
		(pad "AB2" smd circle
			(at -7.599934 8.400034 90)
			(size 0.4064 0.4064)
			(layers "F.Cu" "F.Mask" "F.Paste")
			(net "GPU_NVS_PWR_BRAKE_R_N")
		)
		(pad "AB3" smd circle
			(at -6.800088 8.400034 90)
			(size 0.4064 0.4064)
			(layers "F.Cu" "F.Mask" "F.Paste")
			(net "PVDDCR_CPU0_P0_PMALERT")
		)
		(pad "AB4" smd circle
			(at -5.999988 8.400034 90)
			(size 0.4064 0.4064)
			(layers "F.Cu" "F.Mask" "F.Paste")
			(net "PRSNT_SWB_ISO_R_N")
		)
		(pad "AB5" smd circle
			(at -5.199888 8.400034 90)
			(size 0.4064 0.4064)
			(layers "F.Cu" "F.Mask" "F.Paste")
			(net "BMC_MONITER")
		)
		(pad "AB6" smd circle
			(at -4.400042 8.400034 90)
			(size 0.4064 0.4064)
			(layers "F.Cu" "F.Mask" "F.Paste")
			(net "FM_PWRGD_PVDD33_S5")
		)
		(pad "AB7" smd circle
			(at -3.599942 8.400034 90)
			(size 0.4064 0.4064)
			(layers "F.Cu" "F.Mask" "F.Paste")
			(net "FM_PWRGD_PVDD11_S3_P1")
		)
		(pad "AB8" smd circle
			(at -2.800096 8.400034 90)
			(size 0.4064 0.4064)
			(layers "F.Cu" "F.Mask" "F.Paste")
			(net "FM_PWRGD_PVDD18_S5_P0")
		)
		(pad "AB9" smd circle
			(at -1.999996 8.400034 90)
			(size 0.4064 0.4064)
			(layers "F.Cu" "F.Mask" "F.Paste")
			(net "FM_PWRGD_PVDDIO_P1")
		)
		(pad "AB10" smd circle
			(at -1.199896 8.400034 90)
			(size 0.4064 0.4064)
			(layers "F.Cu" "F.Mask" "F.Paste")
			(net "BMC_FPGA_LED1")
		)
		(pad "AB11" smd circle
			(at -0.40005 8.400034 90)
			(size 0.4064 0.4064)
			(layers "F.Cu" "F.Mask" "F.Paste")
			(net "FM_LED_PWRGD_PVDD18_S5_P0")
		)
		(pad "AB12" smd circle
			(at 0.40005 8.400034 90)
			(size 0.4064 0.4064)
			(layers "F.Cu" "F.Mask" "F.Paste")
			(net "GPU_3V3IO_RSVD1_ISO_R")
		)
		(pad "AB13" smd circle
			(at 1.199896 8.400034 90)
			(size 0.4064 0.4064)
			(layers "F.Cu" "F.Mask" "F.Paste")
			(net "FM_RST_PERST_SCM_R_N")
		)
		(pad "AB14" smd circle
			(at 1.999996 8.400034 90)
			(size 0.4064 0.4064)
			(layers "F.Cu" "F.Mask" "F.Paste")
			(net "GPU_3V3IO_RSVD5_FFU_ISO_R")
		)
		(pad "AB15" smd circle
			(at 2.800096 8.400034 90)
			(size 0.4064 0.4064)
			(layers "F.Cu" "F.Mask" "F.Paste")
			(net "GPU_BASE_HMC_READY_ISO_R")
		)
		(pad "AB16" smd circle
			(at 3.599942 8.400034 90)
			(size 0.4064 0.4064)
			(layers "F.Cu" "F.Mask" "F.Paste")
			(net "GPU_PRSNT_N_ISO_R")
		)
		(pad "AB17" smd circle
			(at 4.400042 8.400034 90)
			(size 0.4064 0.4064)
			(layers "F.Cu" "F.Mask" "F.Paste")
			(net "FM_SWB_BIC_READY_ISO_R_N")
		)
		(pad "AB18" smd circle
			(at 5.199888 8.400034 90)
			(size 0.4064 0.4064)
			(layers "F.Cu" "F.Mask" "F.Paste")
			(net "FM_SWB_PWRGD_ISO_R")
		)
		(pad "AB19" smd circle
			(at 5.999988 8.400034 90)
			(size 0.4064 0.4064)
			(layers "F.Cu" "F.Mask" "F.Paste")
			(net "GPU_FPGA_READY_ISO_R")
		)
		(pad "AB20" smd circle
			(at 6.800088 8.400034 90)
			(size 0.4064 0.4064)
			(layers "F.Cu" "F.Mask" "F.Paste")
			(net "PRSNT_HDT_N")
		)
		(pad "AB21" smd circle
			(at 7.599934 8.400034 90)
			(size 0.4064 0.4064)
			(layers "F.Cu" "F.Mask" "F.Paste")
			(net "PU_SPI_PLD_CS_N")
		)
		(pad "AB22" smd circle
			(at 8.400034 8.400034 90)
			(size 0.4064 0.4064)
			(layers "F.Cu" "F.Mask" "F.Paste")
			(net "GND")
		)
		(pad "B1" smd circle
			(at -8.400034 -7.599934 90)
			(size 0.4064 0.4064)
			(layers "F.Cu" "F.Mask" "F.Paste")
			(net "FM_I3C_CPU0_MUX0_OE_R_N")
		)
		(pad "B2" smd circle
			(at -7.599934 -7.599934 90)
			(size 0.4064 0.4064)
			(layers "F.Cu" "F.Mask" "F.Paste")
			(net "FM_I3C_CPU1_MUX0_OE_R_N")
		)
		(pad "B3" smd circle
			(at -6.800088 -7.599934 90)
			(size 0.4064 0.4064)
			(layers "F.Cu" "F.Mask" "F.Paste")
			(net "SCM_JTAG_MUX_R_S0")
		)
		(pad "B4" smd circle
			(at -5.999988 -7.599934 90)
			(size 0.4064 0.4064)
			(layers "F.Cu" "F.Mask" "F.Paste")
			(net "SGPIO_SCM_DO_<1>")
		)
		(pad "B5" smd circle
			(at -5.199888 -7.599934 90)
			(size 0.4064 0.4064)
			(layers "F.Cu" "F.Mask" "F.Paste")
			(net "SGPIO_SCM_LD_<1>")
		)
		(pad "B6" smd circle
			(at -4.400042 -7.599934 90)
			(size 0.4064 0.4064)
			(layers "F.Cu" "F.Mask" "F.Paste")
			(net "IRQ_HSC_FAULT_BUF_R_N")
		)
		(pad "B7" smd circle
			(at -3.599942 -7.599934 90)
			(size 0.4064 0.4064)
			(layers "F.Cu" "F.Mask" "F.Paste")
			(net "GND")
		)
		(pad "B8" smd circle
			(at -2.800096 -7.599934 90)
			(size 0.4064 0.4064)
			(layers "F.Cu" "F.Mask" "F.Paste")
			(net "SGPIO_OCP_SFF_DATAIN")
		)
		(pad "B9" smd circle
			(at -1.999996 -7.599934 90)
			(size 0.4064 0.4064)
			(layers "F.Cu" "F.Mask" "F.Paste")
			(net "P3V3_OCP_SFF_EN")
		)
		(pad "B10" smd circle
			(at -1.199896 -7.599934 90)
			(size 0.4064 0.4064)
			(layers "F.Cu" "F.Mask" "F.Paste")
			(net "UV_ALERT_N")
		)
		(pad "B11" smd circle
			(at -0.40005 -7.599934 90)
			(size 0.4064 0.4064)
			(layers "F.Cu" "F.Mask" "F.Paste")
			(net "FM_BOARD_BMC_SKU_ID3")
		)
		(pad "B12" smd circle
			(at 0.40005 -7.599934 90)
			(size 0.4064 0.4064)
			(layers "F.Cu" "F.Mask" "F.Paste")
			(net "SMB_1_PLD_3V3AUX_SCL_R2")
		)
		(pad "B13" smd circle
			(at 1.199896 -7.599934 90)
			(size 0.4064 0.4064)
			(layers "F.Cu" "F.Mask" "F.Paste")
			(net "SMB_2_PLD_3V3AUX_SDA_R2")
		)
		(pad "B14" smd circle
			(at 1.999996 -7.599934 90)
			(size 0.4064 0.4064)
			(layers "F.Cu" "F.Mask" "F.Paste")
			(net "SGPIO_OCP_V3_2_DATAIN")
		)
		(pad "B15" smd circle
			(at 2.800096 -7.599934 90)
			(size 0.4064 0.4064)
			(layers "F.Cu" "F.Mask" "F.Paste")
			(net "P1V8_RETIMER_CPU0_R_EN")
		)
		(pad "B16" smd circle
			(at 3.599942 -7.599934 90)
			(size 0.4064 0.4064)
			(layers "F.Cu" "F.Mask" "F.Paste")
			(net "GND")
		)
		(pad "B17" smd circle
			(at 4.400042 -7.599934 90)
			(size 0.4064 0.4064)
			(layers "F.Cu" "F.Mask" "F.Paste")
			(net "PVDDCR_CPU0_P0_EN")
		)
		(pad "B18" smd circle
			(at 5.199888 -7.599934 90)
			(size 0.4064 0.4064)
			(layers "F.Cu" "F.Mask" "F.Paste")
			(net "FM_LED_PWRGD_PVDDCR_SOC_P1")
		)
		(pad "B19" smd circle
			(at 5.999988 -7.599934 90)
			(size 0.4064 0.4064)
			(layers "F.Cu" "F.Mask" "F.Paste")
			(net "FM_LED_PWRGD_PVDD11_S3_P1")
		)
		(pad "B20" smd circle
			(at 6.800088 -7.599934 90)
			(size 0.4064 0.4064)
			(layers "F.Cu" "F.Mask" "F.Paste")
			(net "FM_SOL_UART_CH_SEL")
		)
		(pad "B21" smd circle
			(at 7.599934 -7.599934 90)
			(size 0.4064 0.4064)
			(layers "F.Cu" "F.Mask" "F.Paste")
			(net "IRQ_SML1_PMBUS_ALERT_N")
		)
		(pad "B22" smd circle
			(at 8.400034 -7.599934 90)
			(size 0.4064 0.4064)
			(layers "F.Cu" "F.Mask" "F.Paste")
			(net "FM_OCP_V3_2_PWR_GOOD")
		)
		(pad "C1" smd circle
			(at -8.400034 -6.800088 90)
			(size 0.4064 0.4064)
			(layers "F.Cu" "F.Mask" "F.Paste")
			(net "FM_CPU0_XTRIG_L5")
		)
		(pad "C2" smd circle
			(at -7.599934 -6.800088 90)
			(size 0.4064 0.4064)
			(layers "F.Cu" "F.Mask" "F.Paste")
			(net "GND")
		)
		(pad "C3" smd circle
			(at -6.800088 -6.800088 90)
			(size 0.4064 0.4064)
			(layers "F.Cu" "F.Mask" "F.Paste")
			(net "FM_I3C_CPU0_MUX0_R_SEL")
		)
		(pad "C4" smd circle
			(at -5.999988 -6.800088 90)
			(size 0.4064 0.4064)
			(layers "F.Cu" "F.Mask" "F.Paste")
			(net "FM_I3C_CPU0_MUX1_OE_R_N")
		)
		(pad "C5" smd circle
			(at -5.199888 -6.800088 90)
			(size 0.4064 0.4064)
			(layers "F.Cu" "F.Mask" "F.Paste")
			(net "FM_BOARD_BMC_SKU_ID0")
		)
		(pad "C6" smd circle
			(at -4.400042 -6.800088 90)
			(size 0.4064 0.4064)
			(layers "F.Cu" "F.Mask" "F.Paste")
			(net "SGPIO_SCM_DI_R<1>")
		)
		(pad "C7" smd circle
			(at -3.599942 -6.800088 90)
			(size 0.4064 0.4064)
			(layers "F.Cu" "F.Mask" "F.Paste")
			(net "P3V3_AUX")
		)
		(pad "C8" smd circle
			(at -2.800096 -6.800088 90)
			(size 0.4064 0.4064)
			(layers "F.Cu" "F.Mask" "F.Paste")
			(net "PCIE_M2_SSD0_PRSNT_N")
		)
		(pad "C9" smd circle
			(at -1.999996 -6.800088 90)
			(size 0.4064 0.4064)
			(layers "F.Cu" "F.Mask" "F.Paste")
			(net "SGPIO_OCP_SFF_CLK")
		)
		(pad "C10" smd circle
			(at -1.199896 -6.800088 90)
			(size 0.4064 0.4064)
			(layers "F.Cu" "F.Mask" "F.Paste")
			(net "JTAG_SCM_PLD_TMS")
		)
		(pad "C11" smd circle
			(at -0.40005 -6.800088 90)
			(size 0.4064 0.4064)
			(layers "F.Cu" "F.Mask" "F.Paste")
			(net "GND")
		)
		(pad "C12" smd circle
			(at 0.40005 -6.800088 90)
			(size 0.4064 0.4064)
			(layers "F.Cu" "F.Mask" "F.Paste")
			(net "P3V3_AUX")
		)
		(pad "C13" smd circle
			(at 1.199896 -6.800088 90)
			(size 0.4064 0.4064)
			(layers "F.Cu" "F.Mask" "F.Paste")
			(net "SCM_ROT_CPU_RST_R_N")
		)
		(pad "C14" smd circle
			(at 1.999996 -6.800088 90)
			(size 0.4064 0.4064)
			(layers "F.Cu" "F.Mask" "F.Paste")
			(net "SGPIO_OCP_V3_2_DATAOUT")
		)
		(pad "C15" smd circle
			(at 2.800096 -6.800088 90)
			(size 0.4064 0.4064)
			(layers "F.Cu" "F.Mask" "F.Paste")
			(net "PVDDCR_SOC_P1_EN")
		)
		(pad "C16" smd circle
			(at 3.599942 -6.800088 90)
			(size 0.4064 0.4064)
			(layers "F.Cu" "F.Mask" "F.Paste")
			(net "P3V3_AUX")
		)
		(pad "C17" smd circle
			(at 4.400042 -6.800088 90)
			(size 0.4064 0.4064)
			(layers "F.Cu" "F.Mask" "F.Paste")
			(net "RST_SRST_PLD_BMC_R_N")
		)
		(pad "C18" smd circle
			(at 5.199888 -6.800088 90)
			(size 0.4064 0.4064)
			(layers "F.Cu" "F.Mask" "F.Paste")
			(net "FM_OCP_V3_2_AUX_PWR_EN")
		)
		(pad "C19" smd circle
			(at 5.999988 -6.800088 90)
			(size 0.4064 0.4064)
			(layers "F.Cu" "F.Mask" "F.Paste")
			(net "CLK_GEN2_BMC_RC_OE_R_N")
		)
		(pad "C20" smd circle
			(at 6.800088 -6.800088 90)
			(size 0.4064 0.4064)
			(layers "F.Cu" "F.Mask" "F.Paste")
			(net "CLK_GEN2_GPU_FPGA_OE_R_N")
		)
		(pad "C21" smd circle
			(at 7.599934 -6.800088 90)
			(size 0.4064 0.4064)
			(layers "F.Cu" "F.Mask" "F.Paste")
			(net "FM_CPU0_SLP_S5_N")
		)
		(pad "C22" smd circle
			(at 8.400034 -6.800088 90)
			(size 0.4064 0.4064)
			(layers "F.Cu" "F.Mask" "F.Paste")
			(net "FM_CPU0_SLP_S3_N")
		)
		(pad "D1" smd circle
			(at -8.400034 -5.999988 90)
			(size 0.4064 0.4064)
			(layers "F.Cu" "F.Mask" "F.Paste")
			(net "FM_SMM_CRASHDUMP_R")
		)
		(pad "D2" smd circle
			(at -7.599934 -5.999988 90)
			(size 0.4064 0.4064)
			(layers "F.Cu" "F.Mask" "F.Paste")
			(net "FM_CPU0_XTRIG_L4")
		)
		(pad "D3" smd circle
			(at -6.800088 -5.999988 90)
			(size 0.4064 0.4064)
			(layers "F.Cu" "F.Mask" "F.Paste")
			(net "FM_CPU1_XTRIG_L4")
		)
		(pad "D4" smd circle
			(at -5.999988 -5.999988 90)
			(size 0.4064 0.4064)
			(layers "F.Cu" "F.Mask" "F.Paste")
			(net "FM_CPU1_XTRIG_L5")
		)
		(pad "D5" smd circle
			(at -5.199888 -5.999988 90)
			(size 0.4064 0.4064)
			(layers "F.Cu" "F.Mask" "F.Paste")
			(net "FM_I3C_CPU1_MUX1_R_SEL")
		)
		(pad "D6" smd circle
			(at -4.400042 -5.999988 90)
			(size 0.4064 0.4064)
			(layers "F.Cu" "F.Mask" "F.Paste")
			(net "SGPIO_SCM_CLK_<0>")
		)
		(pad "D7" smd circle
			(at -3.599942 -5.999988 90)
			(size 0.4064 0.4064)
			(layers "F.Cu" "F.Mask" "F.Paste")
			(net "SGPIO_SCM_LD_<0>")
		)
		(pad "D8" smd circle
			(at -2.800096 -5.999988 90)
			(size 0.4064 0.4064)
			(layers "F.Cu" "F.Mask" "F.Paste")
			(net "SGPIO_OCP_SFF_LD_N")
		)
		(pad "D9" smd circle
			(at -1.999996 -5.999988 90)
			(size 0.4064 0.4064)
			(layers "F.Cu" "F.Mask" "F.Paste")
			(net "OCP_V3_2_MAIN_PWR_EN")
		)
		(pad "D10" smd circle
			(at -1.199896 -5.999988 90)
			(size 0.4064 0.4064)
			(layers "F.Cu" "F.Mask" "F.Paste")
			(net "JTAG_SCM_PLD_TCK")
		)
		(pad "D11" smd circle
			(at -0.40005 -5.999988 90)
			(size 0.4064 0.4064)
			(layers "F.Cu" "F.Mask" "F.Paste")
			(net "JTAG_SCM_TRST_R_N")
		)
		(pad "D12" smd circle
			(at 0.40005 -5.999988 90)
			(size 0.4064 0.4064)
			(layers "F.Cu" "F.Mask" "F.Paste")
			(net "FM_FAN_PWR_EN")
		)
		(pad "D13" smd circle
			(at 1.199896 -5.999988 90)
			(size 0.4064 0.4064)
			(layers "F.Cu" "F.Mask" "F.Paste")
			(net "RST_MB_STBY_N")
		)
		(pad "D14" smd circle
			(at 1.999996 -5.999988 90)
			(size 0.4064 0.4064)
			(layers "F.Cu" "F.Mask" "F.Paste")
			(net "SGPIO_OCP_V3_2_CLK")
		)
		(pad "D15" smd circle
			(at 2.800096 -5.999988 90)
			(size 0.4064 0.4064)
			(layers "F.Cu" "F.Mask" "F.Paste")
			(net "PRSNT_OCP_V3_2_N")
		)
		(pad "D16" smd circle
			(at 3.599942 -5.999988 90)
			(size 0.4064 0.4064)
			(layers "F.Cu" "F.Mask" "F.Paste")
			(net "FPGA_IO3V3_RSVD_1")
		)
		(pad "D17" smd circle
			(at 4.400042 -5.999988 90)
			(size 0.4064 0.4064)
			(layers "F.Cu" "F.Mask" "F.Paste")
			(net "RST_SMB_SWITCH_N")
		)
		(pad "D18" smd circle
			(at 5.199888 -5.999988 90)
			(size 0.4064 0.4064)
			(layers "F.Cu" "F.Mask" "F.Paste")
			(net "SGPIO_SCM_CLK_<1>")
		)
		(pad "D19" smd circle
			(at 5.999988 -5.999988 90)
			(size 0.4064 0.4064)
			(layers "F.Cu" "F.Mask" "F.Paste")
			(net "PWRGD_P0V9_RETIMER_CPU0_R2")
		)
		(pad "D20" smd circle
			(at 6.800088 -5.999988 90)
			(size 0.4064 0.4064)
			(layers "F.Cu" "F.Mask" "F.Paste")
			(net "RST_CPU0_PERST1_R_N")
		)
		(pad "D21" smd circle
			(at 7.599934 -5.999988 90)
			(size 0.4064 0.4064)
			(layers "F.Cu" "F.Mask" "F.Paste")
			(net "FM_CPU1_SLP_S3_N")
		)
		(pad "D22" smd circle
			(at 8.400034 -5.999988 90)
			(size 0.4064 0.4064)
			(layers "F.Cu" "F.Mask" "F.Paste")
			(net "FM_CPU1_SLP_S5_N")
		)
		(pad "E1" smd circle
			(at -8.400034 -5.199888 90)
			(size 0.4064 0.4064)
			(layers "F.Cu" "F.Mask" "F.Paste")
			(net "FM_BMC_TPM_PRES_N_R")
		)
		(pad "E2" smd circle
			(at -7.599934 -5.199888 90)
			(size 0.4064 0.4064)
			(layers "F.Cu" "F.Mask" "F.Paste")
			(net "FM_CPU1_BMC_RST_R_N")
		)
		(pad "E3" smd circle
			(at -6.800088 -5.199888 90)
			(size 0.4064 0.4064)
			(layers "F.Cu" "F.Mask" "F.Paste")
			(net "FM_CPU0_XTRIG_L7")
		)
		(pad "E4" smd circle
			(at -5.999988 -5.199888 90)
			(size 0.4064 0.4064)
			(layers "F.Cu" "F.Mask" "F.Paste")
			(net "FM_CPU0_XTRIG_L6")
		)
		(pad "E5" smd circle
			(at -5.199888 -5.199888 90)
			(size 0.4064 0.4064)
			(layers "F.Cu" "F.Mask" "F.Paste")
			(net "GND")
		)
		(pad "E6" smd circle
			(at -4.400042 -5.199888 90)
			(size 0.4064 0.4064)
			(layers "F.Cu" "F.Mask" "F.Paste")
			(net "FM_I3C_CPU1_MUX1_OE_R_N")
		)
		(pad "E7" smd circle
			(at -3.599942 -5.199888 90)
			(size 0.4064 0.4064)
			(layers "F.Cu" "F.Mask" "F.Paste")
			(net "SGPIO_SCM_DO_<0>")
		)
		(pad "E8" smd circle
			(at -2.800096 -5.199888 90)
			(size 0.4064 0.4064)
			(layers "F.Cu" "F.Mask" "F.Paste")
			(net "JTAG_SCM_PLD_TDI")
		)
		(pad "E9" smd circle
			(at -1.999996 -5.199888 90)
			(size 0.4064 0.4064)
			(layers "F.Cu" "F.Mask" "F.Paste")
			(net "JTAG_SCM_PLD_TDO")
		)
		(pad "E10" smd circle
			(at -1.199896 -5.199888 90)
			(size 0.4064 0.4064)
			(layers "F.Cu" "F.Mask" "F.Paste")
			(net "FM_LED_ACTIVE_E1S_0")
		)
		(pad "E11" smd circle
			(at -0.40005 -5.199888 90)
			(size 0.4064 0.4064)
			(layers "F.Cu" "F.Mask" "F.Paste")
			(net "FM_SYS_THROTTLE_R_N")
		)
		(pad "E12" smd circle
			(at 0.40005 -5.199888 90)
			(size 0.4064 0.4064)
			(layers "F.Cu" "F.Mask" "F.Paste")
			(net "SCM_SYS_PWRBTN_N")
		)
		(pad "E13" smd circle
			(at 1.199896 -5.199888 90)
			(size 0.4064 0.4064)
			(layers "F.Cu" "F.Mask" "F.Paste")
			(net "HP_LVC3_OCP_V3_2_P12V_PWRGD_R")
		)
		(pad "E14" smd circle
			(at 1.999996 -5.199888 90)
			(size 0.4064 0.4064)
			(layers "F.Cu" "F.Mask" "F.Paste")
			(net "CPLD_JTAG_EN")
		)
		(pad "E15" smd circle
			(at 2.800096 -5.199888 90)
			(size 0.4064 0.4064)
			(layers "F.Cu" "F.Mask" "F.Paste")
			(net "CPLD_PROGRAMN")
		)
		(pad "E16" smd circle
			(at 3.599942 -5.199888 90)
			(size 0.4064 0.4064)
			(layers "F.Cu" "F.Mask" "F.Paste")
			(net "FM_LED_PWRGD_PVDDCR_CPU1_P1")
		)
		(pad "E17" smd circle
			(at 4.400042 -5.199888 90)
			(size 0.4064 0.4064)
			(layers "F.Cu" "F.Mask" "F.Paste")
			(net "VIRTUAL_RESEAT_FPGA_R_N")
		)
		(pad "E18" smd circle
			(at 5.199888 -5.199888 90)
			(size 0.4064 0.4064)
			(layers "F.Cu" "F.Mask" "F.Paste")
			(net "GND")
		)
		(pad "E19" smd circle
			(at 5.999988 -5.199888 90)
			(size 0.4064 0.4064)
			(layers "F.Cu" "F.Mask" "F.Paste")
			(net "RST_CPU1_PERST0_R_N")
		)
		(pad "E20" smd circle
			(at 6.800088 -5.199888 90)
			(size 0.4064 0.4064)
			(layers "F.Cu" "F.Mask" "F.Paste")
			(net "PWRGD_P0V9_RETIMER_CPU1_R2")
		)
		(pad "E21" smd circle
			(at 7.599934 -5.199888 90)
			(size 0.4064 0.4064)
			(layers "F.Cu" "F.Mask" "F.Paste")
			(net "RST_RT_CPU1_P0_RESET_R2_N")
		)
		(pad "E22" smd circle
			(at 8.400034 -5.199888 90)
			(size 0.4064 0.4064)
			(layers "F.Cu" "F.Mask" "F.Paste")
			(net "RST_RT_CPU1_P0_PERST_R2_N")
		)
		(pad "F1" smd circle
			(at -8.400034 -4.400042 90)
			(size 0.4064 0.4064)
			(layers "F.Cu" "F.Mask" "F.Paste")
			(net "FM_PVDDCR_CPU0_P0_OCP_N")
		)
		(pad "F2" smd circle
			(at -7.599934 -4.400042 90)
			(size 0.4064 0.4064)
			(layers "F.Cu" "F.Mask" "F.Paste")
			(net "GND")
		)
		(pad "F3" smd circle
			(at -6.800088 -4.400042 90)
			(size 0.4064 0.4064)
			(layers "F.Cu" "F.Mask" "F.Paste")
			(net "P1V8_AUX")
		)
		(pad "F4" smd circle
			(at -5.999988 -4.400042 90)
			(size 0.4064 0.4064)
			(layers "F.Cu" "F.Mask" "F.Paste")
			(net "FM_BMC_READY_R_N")
		)
		(pad "F5" smd circle
			(at -5.199888 -4.400042 90)
			(size 0.4064 0.4064)
			(layers "F.Cu" "F.Mask" "F.Paste")
			(net "IRQ_BMC_SMI_R_N")
		)
		(pad "F6" smd circle
			(at -4.400042 -4.400042 90)
			(size 0.4064 0.4064)
			(layers "F.Cu" "F.Mask" "F.Paste")
			(net "FM_CPU1_XTRIG_L6")
		)
		(pad "F7" smd circle
			(at -3.599942 -4.400042 90)
			(size 0.4064 0.4064)
			(layers "F.Cu" "F.Mask" "F.Paste")
			(net "FM_I3C_CPU0_MUX1_R_SEL")
		)
		(pad "F8" smd circle
			(at -2.800096 -4.400042 90)
			(size 0.4064 0.4064)
			(layers "F.Cu" "F.Mask" "F.Paste")
			(net "PWRGD_PS_PWROK_PLD_ISO_R")
		)
		(pad "F9" smd circle
			(at -1.999996 -4.400042 90)
			(size 0.4064 0.4064)
			(layers "F.Cu" "F.Mask" "F.Paste")
			(net "P12V_OCP_SFF_EN")
		)
		(pad "F10" smd circle
			(at -1.199896 -4.400042 90)
			(size 0.4064 0.4064)
			(layers "F.Cu" "F.Mask" "F.Paste")
			(net "FM_BOARD_BMC_SKU_ID2")
		)
		(pad "F11" smd circle
			(at -0.40005 -4.400042 90)
			(size 0.4064 0.4064)
			(layers "F.Cu" "F.Mask" "F.Paste")
			(net "SMB_CPU0_4_XLTR_R_SDA")
		)
		(pad "F12" smd circle
			(at 0.40005 -4.400042 90)
			(size 0.4064 0.4064)
			(layers "F.Cu" "F.Mask" "F.Paste")
			(net "GPU_3V3IO_RSVD3_FFU_ISO_R")
		)
		(pad "F13" smd circle
			(at 1.199896 -4.400042 90)
			(size 0.4064 0.4064)
			(layers "F.Cu" "F.Mask" "F.Paste")
			(net "FM_UARTSW_MSB_N")
		)
		(pad "F14" smd circle
			(at 1.999996 -4.400042 90)
			(size 0.4064 0.4064)
			(layers "F.Cu" "F.Mask" "F.Paste")
			(net "SCM_SPARE_1")
		)
		(pad "F15" smd circle
			(at 2.800096 -4.400042 90)
			(size 0.4064 0.4064)
			(layers "F.Cu" "F.Mask" "F.Paste")
			(net "OCP_V3_2_P3V3_PLD_R_PWRGD")
		)
		(pad "F16" smd circle
			(at 3.599942 -4.400042 90)
			(size 0.4064 0.4064)
			(layers "F.Cu" "F.Mask" "F.Paste")
			(net "VIRTUAL_RESEAT")
		)
		(pad "F17" smd circle
			(at 4.400042 -4.400042 90)
			(size 0.4064 0.4064)
			(layers "F.Cu" "F.Mask" "F.Paste")
			(net "RST_CPU0_PERST0_R_N")
		)
		(pad "F18" smd circle
			(at 5.199888 -4.400042 90)
			(size 0.4064 0.4064)
			(layers "F.Cu" "F.Mask" "F.Paste")
			(net "TP_SLOT1_CLKREQ_0_R_N")
		)
		(pad "F19" smd circle
			(at 5.999988 -4.400042 90)
			(size 0.4064 0.4064)
			(layers "F.Cu" "F.Mask" "F.Paste")
			(net "FM_CPU0_SYS_RESET_N")
		)
		(pad "F20" smd circle
			(at 6.800088 -4.400042 90)
			(size 0.4064 0.4064)
			(layers "F.Cu" "F.Mask" "F.Paste")
			(net "P1V8_AUX")
		)
		(pad "F21" smd circle
			(at 7.599934 -4.400042 90)
			(size 0.4064 0.4064)
			(layers "F.Cu" "F.Mask" "F.Paste")
			(net "GND")
		)
		(pad "F22" smd circle
			(at 8.400034 -4.400042 90)
			(size 0.4064 0.4064)
			(layers "F.Cu" "F.Mask" "F.Paste")
			(net "FM_CPU1_RSMRST_N")
		)
		(pad "G1" smd circle
			(at -8.400034 -3.599942 90)
			(size 0.4064 0.4064)
			(layers "F.Cu" "F.Mask" "F.Paste")
			(net "FM_CPU1_PROCHOT_R_N")
		)
		(pad "G2" smd circle
			(at -7.599934 -3.599942 90)
			(size 0.4064 0.4064)
			(layers "F.Cu" "F.Mask" "F.Paste")
			(net "FM_PVDDCR_CPU0_P1_OCP_N")
		)
		(pad "G3" smd circle
			(at -6.800088 -3.599942 90)
			(size 0.4064 0.4064)
			(layers "F.Cu" "F.Mask" "F.Paste")
			(net "FM_PVDDCR_CPU1_P0_OCP_N")
		)
		(pad "G4" smd circle
			(at -5.999988 -3.599942 90)
			(size 0.4064 0.4064)
			(layers "F.Cu" "F.Mask" "F.Paste")
			(net "FM_PVDDCR_CPU1_P1_OCP_N")
		)
		(pad "G5" smd circle
			(at -5.199888 -3.599942 90)
			(size 0.4064 0.4064)
			(layers "F.Cu" "F.Mask" "F.Paste")
			(net "IRQ_SMI_ACTIVE_N_R")
		)
		(pad "G6" smd circle
			(at -4.400042 -3.599942 90)
			(size 0.4064 0.4064)
			(layers "F.Cu" "F.Mask" "F.Paste")
			(net "FM_CPU1_XTRIG_L7")
		)
		(pad "G7" smd circle
			(at -3.599942 -3.599942 90)
			(size 0.4064 0.4064)
			(layers "F.Cu" "F.Mask" "F.Paste")
			(net "FM_CPU1_SA1")
		)
		(pad "G8" smd circle
			(at -2.800096 -3.599942 90)
			(size 0.4064 0.4064)
			(layers "F.Cu" "F.Mask" "F.Paste")
			(net "SGPIO_SCM_INTR_R_N")
		)
		(pad "G9" smd circle
			(at -1.999996 -3.599942 90)
			(size 0.4064 0.4064)
			(layers "F.Cu" "F.Mask" "F.Paste")
			(net "FM_BOARD_BMC_SKU_ID1")
		)
		(pad "G10" smd circle
			(at -1.199896 -3.599942 90)
			(size 0.4064 0.4064)
			(layers "F.Cu" "F.Mask" "F.Paste")
			(net "P3V3_AUX")
		)
		(pad "G11" smd circle
			(at -0.40005 -3.599942 90)
			(size 0.4064 0.4064)
			(layers "F.Cu" "F.Mask" "F.Paste")
			(net "SMB_CPU0_4_XLTR_R_SCL")
		)
		(pad "G12" smd circle
			(at 0.40005 -3.599942 90)
			(size 0.4064 0.4064)
			(layers "F.Cu" "F.Mask" "F.Paste")
			(net "PRSNT_CABLE_GPU_B3_ISO_R_N")
		)
		(pad "G13" smd circle
			(at 1.199896 -3.599942 90)
			(size 0.4064 0.4064)
			(layers "F.Cu" "F.Mask" "F.Paste")
			(net "P3V3_AUX")
		)
		(pad "G14" smd circle
			(at 1.999996 -3.599942 90)
			(size 0.4064 0.4064)
			(layers "F.Cu" "F.Mask" "F.Paste")
			(net "SCM_SPARE_0")
		)
		(pad "G15" smd circle
			(at 2.800096 -3.599942 90)
			(size 0.4064 0.4064)
			(layers "F.Cu" "F.Mask" "F.Paste")
			(net "FM_UARTSW_LSB_N")
		)
		(pad "G16" smd circle
			(at 3.599942 -3.599942 90)
			(size 0.4064 0.4064)
			(layers "F.Cu" "F.Mask" "F.Paste")
			(net "RST_CPU1_PERST1_R_N")
		)
		(pad "G17" smd circle
			(at 4.400042 -3.599942 90)
			(size 0.4064 0.4064)
			(layers "F.Cu" "F.Mask" "F.Paste")
			(net "RST_CPU0_KBRST_N")
		)
		(pad "G18" smd circle
			(at 5.199888 -3.599942 90)
			(size 0.4064 0.4064)
			(layers "F.Cu" "F.Mask" "F.Paste")
			(net "RST_RT_CPU1_P1_RESET_R2_N")
		)
		(pad "G19" smd circle
			(at 5.999988 -3.599942 90)
			(size 0.4064 0.4064)
			(layers "F.Cu" "F.Mask" "F.Paste")
			(net "RST_RT_CPU1_P1_PERST_R2_N")
		)
		(pad "G20" smd circle
			(at 6.800088 -3.599942 90)
			(size 0.4064 0.4064)
			(layers "F.Cu" "F.Mask" "F.Paste")
			(net "FM_CPU0_NV_SAVE_N")
		)
		(pad "G21" smd circle
			(at 7.599934 -3.599942 90)
			(size 0.4064 0.4064)
			(layers "F.Cu" "F.Mask" "F.Paste")
			(net "FM_CPU1_SYS_RESET_N")
		)
		(pad "G22" smd circle
			(at 8.400034 -3.599942 90)
			(size 0.4064 0.4064)
			(layers "F.Cu" "F.Mask" "F.Paste")
			(net "FM_CPU0_RSMRST_N")
		)
		(pad "H1" smd circle
			(at -8.400034 -2.800096 90)
			(size 0.4064 0.4064)
			(layers "F.Cu" "F.Mask" "F.Paste")
			(net "RT_BOARD_ID_ID1")
		)
		(pad "H2" smd circle
			(at -7.599934 -2.800096 90)
			(size 0.4064 0.4064)
			(layers "F.Cu" "F.Mask" "F.Paste")
			(net "CPU0_THERMTRIP_R_N")
		)
		(pad "H3" smd circle
			(at -6.800088 -2.800096 90)
			(size 0.4064 0.4064)
			(layers "F.Cu" "F.Mask" "F.Paste")
			(net "FM_PVDD11_S3_P0_OCP_N")
		)
		(pad "H4" smd circle
			(at -5.999988 -2.800096 90)
			(size 0.4064 0.4064)
			(layers "F.Cu" "F.Mask" "F.Paste")
			(net "FM_PVDD11_S3_P1_OCP_N")
		)
		(pad "H5" smd circle
			(at -5.199888 -2.800096 90)
			(size 0.4064 0.4064)
			(layers "F.Cu" "F.Mask" "F.Paste")
			(net "FM_CPU0_SA0")
		)
		(pad "H6" smd circle
			(at -4.400042 -2.800096 90)
			(size 0.4064 0.4064)
			(layers "F.Cu" "F.Mask" "F.Paste")
			(net "IRQ_TPM_SPI_R1_N")
		)
		(pad "H7" smd circle
			(at -3.599942 -2.800096 90)
			(size 0.4064 0.4064)
			(layers "F.Cu" "F.Mask" "F.Paste")
			(net "IRQ_CPU_BMC_NMI_R_N")
		)
		(pad "H8" smd circle
			(at -2.800096 -2.800096 90)
			(size 0.4064 0.4064)
			(layers "F.Cu" "F.Mask" "F.Paste")
			(net "GND")
		)
		(pad "H9" smd circle
			(at -1.999996 -2.800096 90)
			(size 0.4064 0.4064)
			(layers "F.Cu" "F.Mask" "F.Paste")
			(net "P3V3_AUX")
		)
		(pad "H10" smd circle
			(at -1.199896 -2.800096 90)
			(size 0.4064 0.4064)
			(layers "F.Cu" "F.Mask" "F.Paste")
			(net "GND")
		)
		(pad "H11" smd circle
			(at -0.40005 -2.800096 90)
			(size 0.4064 0.4064)
			(layers "F.Cu" "F.Mask" "F.Paste")
			(net "P3V3_AUX")
		)
		(pad "H12" smd circle
			(at 0.40005 -2.800096 90)
			(size 0.4064 0.4064)
			(layers "F.Cu" "F.Mask" "F.Paste")
			(net "P3V3_AUX")
		)
		(pad "H13" smd circle
			(at 1.199896 -2.800096 90)
			(size 0.4064 0.4064)
			(layers "F.Cu" "F.Mask" "F.Paste")
			(net "GND")
		)
		(pad "H14" smd circle
			(at 1.999996 -2.800096 90)
			(size 0.4064 0.4064)
			(layers "F.Cu" "F.Mask" "F.Paste")
			(net "P3V3_AUX")
		)
		(pad "H15" smd circle
			(at 2.800096 -2.800096 90)
			(size 0.4064 0.4064)
			(layers "F.Cu" "F.Mask" "F.Paste")
			(net "GND")
		)
		(pad "H16" smd circle
			(at 3.599942 -2.800096 90)
			(size 0.4064 0.4064)
			(layers "F.Cu" "F.Mask" "F.Paste")
			(net "PVDD11_S3_P1_RESET_N")
		)
		(pad "H17" smd circle
			(at 4.400042 -2.800096 90)
			(size 0.4064 0.4064)
			(layers "F.Cu" "F.Mask" "F.Paste")
			(net "PVDD11_S3_P0_RESET_N")
		)
		(pad "H18" smd circle
			(at 5.199888 -2.800096 90)
			(size 0.4064 0.4064)
			(layers "F.Cu" "F.Mask" "F.Paste")
			(net "FM_CPU1_NV_SAVE_N")
		)
		(pad "H19" smd circle
			(at 5.999988 -2.800096 90)
			(size 0.4064 0.4064)
			(layers "F.Cu" "F.Mask" "F.Paste")
			(net "FM_PWRGD_CPU0_PWROK")
		)
		(pad "H20" smd circle
			(at 6.800088 -2.800096 90)
			(size 0.4064 0.4064)
			(layers "F.Cu" "F.Mask" "F.Paste")
			(net "CPU0_JTAG_BUF_R_OE")
		)
		(pad "H21" smd circle
			(at 7.599934 -2.800096 90)
			(size 0.4064 0.4064)
			(layers "F.Cu" "F.Mask" "F.Paste")
			(net "FM_RST_CPU1_RESETL_N")
		)
		(pad "H22" smd circle
			(at 8.400034 -2.800096 90)
			(size 0.4064 0.4064)
			(layers "F.Cu" "F.Mask" "F.Paste")
			(net "FM_RST_CPU0_RESETL_N")
		)
		(pad "J1" smd circle
			(at -8.400034 -1.999996 90)
			(size 0.4064 0.4064)
			(layers "F.Cu" "F.Mask" "F.Paste")
			(net "FAB_BMC_REV_ID0")
		)
		(pad "J2" smd circle
			(at -7.599934 -1.999996 90)
			(size 0.4064 0.4064)
			(layers "F.Cu" "F.Mask" "F.Paste")
			(net "FM_CPU0_SA1")
		)
		(pad "J3" smd circle
			(at -6.800088 -1.999996 90)
			(size 0.4064 0.4064)
			(layers "F.Cu" "F.Mask" "F.Paste")
			(net "FM_INT_CPU0_HP_UBM_R_N")
		)
		(pad "J4" smd circle
			(at -5.999988 -1.999996 90)
			(size 0.4064 0.4064)
			(layers "F.Cu" "F.Mask" "F.Paste")
			(net "RT_BOARD_ID_ID0")
		)
		(pad "J5" smd circle
			(at -5.199888 -1.999996 90)
			(size 0.4064 0.4064)
			(layers "F.Cu" "F.Mask" "F.Paste")
			(net "CPU1_THERMTRIP_R_N")
		)
		(pad "J6" smd circle
			(at -4.400042 -1.999996 90)
			(size 0.4064 0.4064)
			(layers "F.Cu" "F.Mask" "F.Paste")
			(net "FM_CPU0_PROCHOT_R_N")
		)
		(pad "J7" smd circle
			(at -3.599942 -1.999996 90)
			(size 0.4064 0.4064)
			(layers "F.Cu" "F.Mask" "F.Paste")
			(net "FM_CPU1_SA0")
		)
		(pad "J8" smd circle
			(at -2.800096 -1.999996 90)
			(size 0.4064 0.4064)
			(layers "F.Cu" "F.Mask" "F.Paste")
			(net "P1V8_AUX")
		)
		(pad "J9" smd circle
			(at -1.999996 -1.999996 90)
			(size 0.4064 0.4064)
			(layers "F.Cu" "F.Mask" "F.Paste")
			(net "GND")
		)
		(pad "J10" smd circle
			(at -1.199896 -1.999996 90)
			(size 0.4064 0.4064)
			(layers "F.Cu" "F.Mask" "F.Paste")
			(net "GND")
		)
		(pad "J11" smd circle
			(at -0.40005 -1.999996 90)
			(size 0.4064 0.4064)
			(layers "F.Cu" "F.Mask" "F.Paste")
			(net "GND")
		)
		(pad "J12" smd circle
			(at 0.40005 -1.999996 90)
			(size 0.4064 0.4064)
			(layers "F.Cu" "F.Mask" "F.Paste")
			(net "GND")
		)
		(pad "J13" smd circle
			(at 1.199896 -1.999996 90)
			(size 0.4064 0.4064)
			(layers "F.Cu" "F.Mask" "F.Paste")
			(net "GND")
		)
		(pad "J14" smd circle
			(at 1.999996 -1.999996 90)
			(size 0.4064 0.4064)
			(layers "F.Cu" "F.Mask" "F.Paste")
			(net "GND")
		)
		(pad "J15" smd circle
			(at 2.800096 -1.999996 90)
			(size 0.4064 0.4064)
			(layers "F.Cu" "F.Mask" "F.Paste")
			(net "P1V8_AUX")
		)
		(pad "J16" smd circle
			(at 3.599942 -1.999996 90)
			(size 0.4064 0.4064)
			(layers "F.Cu" "F.Mask" "F.Paste")
			(net "FM_CPU0_NMI_SYNC_FLOOD_N")
		)
		(pad "J17" smd circle
			(at 4.400042 -1.999996 90)
			(size 0.4064 0.4064)
			(layers "F.Cu" "F.Mask" "F.Paste")
			(net "FM_FPGA_DEBUG_LED_CTRL")
		)
		(pad "J18" smd circle
			(at 5.199888 -1.999996 90)
			(size 0.4064 0.4064)
			(layers "F.Cu" "F.Mask" "F.Paste")
			(net "FM_PWRGD_CPU1_PWROK")
		)
		(pad "J19" smd circle
			(at 5.999988 -1.999996 90)
			(size 0.4064 0.4064)
			(layers "F.Cu" "F.Mask" "F.Paste")
			(net "FM_P1_PCC0_R_N")
		)
		(pad "J20" smd circle
			(at 6.800088 -1.999996 90)
			(size 0.4064 0.4064)
			(layers "F.Cu" "F.Mask" "F.Paste")
			(net "FM_P1_PCC1_R_N")
		)
		(pad "J21" smd circle
			(at 7.599934 -1.999996 90)
			(size 0.4064 0.4064)
			(layers "F.Cu" "F.Mask" "F.Paste")
			(net "TP_SLOT2_CLKREQ_0_R_N")
		)
		(pad "J22" smd circle
			(at 8.400034 -1.999996 90)
			(size 0.4064 0.4064)
			(layers "F.Cu" "F.Mask" "F.Paste")
			(net "FM_CPU0_PWR_BTN_N")
		)
		(pad "K1" smd circle
			(at -8.400034 -1.199896 90)
			(size 0.4064 0.4064)
			(layers "F.Cu" "F.Mask" "F.Paste")
			(net "FM_SEC_MUX_R_SEL")
		)
		(pad "K2" smd circle
			(at -7.599934 -1.199896 90)
			(size 0.4064 0.4064)
			(layers "F.Cu" "F.Mask" "F.Paste")
			(net "FM_SEC_MUX_OE_R_N")
		)
		(pad "K3" smd circle
			(at -6.800088 -1.199896 90)
			(size 0.4064 0.4064)
			(layers "F.Cu" "F.Mask" "F.Paste")
			(net "E1S_0_P3V3_P12V_ADC_ALERT")
		)
		(pad "K4" smd circle
			(at -5.999988 -1.199896 90)
			(size 0.4064 0.4064)
			(layers "F.Cu" "F.Mask" "F.Paste")
			(net "P12V_HSC_T_CRIT_R_N")
		)
		(pad "K5" smd circle
			(at -5.199888 -1.199896 90)
			(size 0.4064 0.4064)
			(layers "F.Cu" "F.Mask" "F.Paste")
			(net "P12V_SCM_ADC_ALERT")
		)
		(pad "K6" smd circle
			(at -4.400042 -1.199896 90)
			(size 0.4064 0.4064)
			(layers "F.Cu" "F.Mask" "F.Paste")
			(net "FAB_BMC_REV_ID2")
		)
		(pad "K7" smd circle
			(at -3.599942 -1.199896 90)
			(size 0.4064 0.4064)
			(layers "F.Cu" "F.Mask" "F.Paste")
			(net "FAB_BMC_REV_ID1")
		)
		(pad "K8" smd circle
			(at -2.800096 -1.199896 90)
			(size 0.4064 0.4064)
			(layers "F.Cu" "F.Mask" "F.Paste")
			(net "P1V8_AUX")
		)
		(pad "K9" smd circle
			(at -1.999996 -1.199896 90)
			(size 0.4064 0.4064)
			(layers "F.Cu" "F.Mask" "F.Paste")
			(net "GND")
		)
		(pad "K10" smd circle
			(at -1.199896 -1.199896 90)
			(size 0.4064 0.4064)
			(layers "F.Cu" "F.Mask" "F.Paste")
			(net "P3V3_AUX")
		)
		(pad "K11" smd circle
			(at -0.40005 -1.199896 90)
			(size 0.4064 0.4064)
			(layers "F.Cu" "F.Mask" "F.Paste")
			(net "P3V3_AUX")
		)
		(pad "K12" smd circle
			(at 0.40005 -1.199896 90)
			(size 0.4064 0.4064)
			(layers "F.Cu" "F.Mask" "F.Paste")
			(net "P3V3_AUX")
		)
		(pad "K13" smd circle
			(at 1.199896 -1.199896 90)
			(size 0.4064 0.4064)
			(layers "F.Cu" "F.Mask" "F.Paste")
			(net "P3V3_AUX")
		)
		(pad "K14" smd circle
			(at 1.999996 -1.199896 90)
			(size 0.4064 0.4064)
			(layers "F.Cu" "F.Mask" "F.Paste")
			(net "GND")
		)
		(pad "K15" smd circle
			(at 2.800096 -1.199896 90)
			(size 0.4064 0.4064)
			(layers "F.Cu" "F.Mask" "F.Paste")
			(net "P1V8_AUX")
		)
		(pad "K16" smd circle
			(at 3.599942 -1.199896 90)
			(size 0.4064 0.4064)
			(layers "F.Cu" "F.Mask" "F.Paste")
			(net "APML_CPU1_ALERT_R_N")
		)
		(pad "K17" smd circle
			(at 4.400042 -1.199896 90)
			(size 0.4064 0.4064)
			(layers "F.Cu" "F.Mask" "F.Paste")
			(net "FM_P0_PCC0_R_N")
		)
		(pad "K18" smd circle
			(at 5.199888 -1.199896 90)
			(size 0.4064 0.4064)
			(layers "F.Cu" "F.Mask" "F.Paste")
			(net "FM_P0_PCC1_R_N")
		)
		(pad "K19" smd circle
			(at 5.999988 -1.199896 90)
			(size 0.4064 0.4064)
			(layers "F.Cu" "F.Mask" "F.Paste")
			(net "RST_RT_CPU1_P2_RESET_R2_N")
		)
		(pad "K20" smd circle
			(at 6.800088 -1.199896 90)
			(size 0.4064 0.4064)
			(layers "F.Cu" "F.Mask" "F.Paste")
			(net "RST_RT_CPU1_P2_PERST_R2_N")
		)
		(pad "K21" smd circle
			(at 7.599934 -1.199896 90)
			(size 0.4064 0.4064)
			(layers "F.Cu" "F.Mask" "F.Paste")
			(net "GND")
		)
		(pad "K22" smd circle
			(at 8.400034 -1.199896 90)
			(size 0.4064 0.4064)
			(layers "F.Cu" "F.Mask" "F.Paste")
			(net "RST_RT_CPU0_P0_PERST_R2_N")
		)
		(pad "L1" smd circle
			(at -8.400034 -0.40005 90)
			(size 0.4064 0.4064)
			(layers "F.Cu" "F.Mask" "F.Paste")
			(net "LED_HDD_ACTIVITY_B_PLD_N")
		)
		(pad "L2" smd circle
			(at -7.599934 -0.40005 90)
			(size 0.4064 0.4064)
			(layers "F.Cu" "F.Mask" "F.Paste")
			(net "GND")
		)
		(pad "L3" smd circle
			(at -6.800088 -0.40005 90)
			(size 0.4064 0.4064)
			(layers "F.Cu" "F.Mask" "F.Paste")
			(net "FM_THERMAL_ALERT_R_N")
		)
		(pad "L4" smd circle
			(at -5.999988 -0.40005 90)
			(size 0.4064 0.4064)
			(layers "F.Cu" "F.Mask" "F.Paste")
			(net "SMB_BMC_GPU_EN")
		)
		(pad "L5" smd circle
			(at -5.199888 -0.40005 90)
			(size 0.4064 0.4064)
			(layers "F.Cu" "F.Mask" "F.Paste")
			(net "PVDDCR_CPU1_P0_SMB_ALERT")
		)
		(pad "L6" smd circle
			(at -4.400042 -0.40005 90)
			(size 0.4064 0.4064)
			(layers "F.Cu" "F.Mask" "F.Paste")
			(net "PVDDCR_CPU1_P1_SMB_ALERT")
		)
		(pad "L7" smd circle
			(at -3.599942 -0.40005 90)
			(size 0.4064 0.4064)
			(layers "F.Cu" "F.Mask" "F.Paste")
			(net "PVDD11_S3_P0_PMALERT")
		)
		(pad "L8" smd circle
			(at -2.800096 -0.40005 90)
			(size 0.4064 0.4064)
			(layers "F.Cu" "F.Mask" "F.Paste")
			(net "P3V3_AUX")
		)
		(pad "L9" smd circle
			(at -1.999996 -0.40005 90)
			(size 0.4064 0.4064)
			(layers "F.Cu" "F.Mask" "F.Paste")
			(net "GND")
		)
		(pad "L10" smd circle
			(at -1.199896 -0.40005 90)
			(size 0.4064 0.4064)
			(layers "F.Cu" "F.Mask" "F.Paste")
			(net "GND")
		)
		(pad "L11" smd circle
			(at -0.40005 -0.40005 90)
			(size 0.4064 0.4064)
			(layers "F.Cu" "F.Mask" "F.Paste")
			(net "P3V3_AUX")
		)
		(pad "L12" smd circle
			(at 0.40005 -0.40005 90)
			(size 0.4064 0.4064)
			(layers "F.Cu" "F.Mask" "F.Paste")
			(net "P3V3_AUX")
		)
		(pad "L13" smd circle
			(at 1.199896 -0.40005 90)
			(size 0.4064 0.4064)
			(layers "F.Cu" "F.Mask" "F.Paste")
			(net "GND")
		)
		(pad "L14" smd circle
			(at 1.999996 -0.40005 90)
			(size 0.4064 0.4064)
			(layers "F.Cu" "F.Mask" "F.Paste")
			(net "GND")
		)
		(pad "L15" smd circle
			(at 2.800096 -0.40005 90)
			(size 0.4064 0.4064)
			(layers "F.Cu" "F.Mask" "F.Paste")
			(net "P1V8_AUX")
		)
		(pad "L16" smd circle
			(at 3.599942 -0.40005 90)
			(size 0.4064 0.4064)
			(layers "F.Cu" "F.Mask" "F.Paste")
			(net "CPU1_SPD_HOST_CTRL_R1_N")
		)
		(pad "L17" smd circle
			(at 4.400042 -0.40005 90)
			(size 0.4064 0.4064)
			(layers "F.Cu" "F.Mask" "F.Paste")
			(net "APML_CPU0_ALERT_R_N")
		)
		(pad "L18" smd circle
			(at 5.199888 -0.40005 90)
			(size 0.4064 0.4064)
			(layers "F.Cu" "F.Mask" "F.Paste")
			(net "GND")
		)
		(pad "L19" smd circle
			(at 5.999988 -0.40005 90)
			(size 0.4064 0.4064)
			(layers "F.Cu" "F.Mask" "F.Paste")
			(net "RST_RT_CPU1_P3_PERST_R2_N")
		)
		(pad "L20" smd circle
			(at 6.800088 -0.40005 90)
			(size 0.4064 0.4064)
			(layers "F.Cu" "F.Mask" "F.Paste")
			(net "RST_RT_CPU1_P3_RESET_R2_N")
		)
		(pad "L21" smd circle
			(at 7.599934 -0.40005 90)
			(size 0.4064 0.4064)
			(layers "F.Cu" "F.Mask" "F.Paste")
			(net "RST_RT_CPU0_P0_RESET_R2_N")
		)
		(pad "L22" smd circle
			(at 8.400034 -0.40005 90)
			(size 0.4064 0.4064)
			(layers "F.Cu" "F.Mask" "F.Paste")
			(net "RST_RT_CPU0_P1_PERST_R2_N")
		)
		(pad "M1" smd circle
			(at -8.400034 0.40005 90)
			(size 0.4064 0.4064)
			(layers "F.Cu" "F.Mask" "F.Paste")
			(net "M2_0_P3V3_ADC_ALERT")
		)
		(pad "M2" smd circle
			(at -7.599934 0.40005 90)
			(size 0.4064 0.4064)
			(layers "F.Cu" "F.Mask" "F.Paste")
			(net "FM_SCM_PRSNT1_N")
		)
		(pad "M3" smd circle
			(at -6.800088 0.40005 90)
			(size 0.4064 0.4064)
			(layers "F.Cu" "F.Mask" "F.Paste")
			(net "P3V3_AUX")
		)
		(pad "M4" smd circle
			(at -5.999988 0.40005 90)
			(size 0.4064 0.4064)
			(layers "F.Cu" "F.Mask" "F.Paste")
			(net "GND")
		)
		(pad "M5" smd circle
			(at -5.199888 0.40005 90)
			(size 0.4064 0.4064)
			(layers "F.Cu" "F.Mask" "F.Paste")
			(net "PVDDCR_CPU0_P1_PMALERT")
		)
		(pad "M6" smd circle
			(at -4.400042 0.40005 90)
			(size 0.4064 0.4064)
			(layers "F.Cu" "F.Mask" "F.Paste")
			(net "FM_PLD_OCP_SFF_AUX_PWR_R_EN")
		)
		(pad "M7" smd circle
			(at -3.599942 0.40005 90)
			(size 0.4064 0.4064)
			(layers "F.Cu" "F.Mask" "F.Paste")
			(net "FM_PLD_OCP_SFF_MAIN_PWR_EN_R")
		)
		(pad "M8" smd circle
			(at -2.800096 0.40005 90)
			(size 0.4064 0.4064)
			(layers "F.Cu" "F.Mask" "F.Paste")
			(net "P3V3_AUX")
		)
		(pad "M9" smd circle
			(at -1.999996 0.40005 90)
			(size 0.4064 0.4064)
			(layers "F.Cu" "F.Mask" "F.Paste")
			(net "GND")
		)
		(pad "M10" smd circle
			(at -1.199896 0.40005 90)
			(size 0.4064 0.4064)
			(layers "F.Cu" "F.Mask" "F.Paste")
			(net "GND")
		)
		(pad "M11" smd circle
			(at -0.40005 0.40005 90)
			(size 0.4064 0.4064)
			(layers "F.Cu" "F.Mask" "F.Paste")
			(net "P3V3_AUX")
		)
		(pad "M12" smd circle
			(at 0.40005 0.40005 90)
			(size 0.4064 0.4064)
			(layers "F.Cu" "F.Mask" "F.Paste")
			(net "P3V3_AUX")
		)
		(pad "M13" smd circle
			(at 1.199896 0.40005 90)
			(size 0.4064 0.4064)
			(layers "F.Cu" "F.Mask" "F.Paste")
			(net "GND")
		)
		(pad "M14" smd circle
			(at 1.999996 0.40005 90)
			(size 0.4064 0.4064)
			(layers "F.Cu" "F.Mask" "F.Paste")
			(net "GND")
		)
		(pad "M15" smd circle
			(at 2.800096 0.40005 90)
			(size 0.4064 0.4064)
			(layers "F.Cu" "F.Mask" "F.Paste")
			(net "P1V8_AUX")
		)
		(pad "M16" smd circle
			(at 3.599942 0.40005 90)
			(size 0.4064 0.4064)
			(layers "F.Cu" "F.Mask" "F.Paste")
			(net "PWRGD_P3V3_R2")
		)
		(pad "M17" smd circle
			(at 4.400042 0.40005 90)
			(size 0.4064 0.4064)
			(layers "F.Cu" "F.Mask" "F.Paste")
			(net "RST_RT_CPU0_P1_RESET_R2_N")
		)
		(pad "M18" smd circle
			(at 5.199888 0.40005 90)
			(size 0.4064 0.4064)
			(layers "F.Cu" "F.Mask" "F.Paste")
			(net "P1V8_AUX")
		)
		(pad "M19" smd circle
			(at 5.999988 0.40005 90)
			(size 0.4064 0.4064)
			(layers "F.Cu" "F.Mask" "F.Paste")
			(net "SMB_CPU_5_R1_SDA")
		)
		(pad "M20" smd circle
			(at 6.800088 0.40005 90)
			(size 0.4064 0.4064)
			(layers "F.Cu" "F.Mask" "F.Paste")
			(net "SMB_CPU_5_R1_SCL")
		)
		(pad "M21" smd circle
			(at 7.599934 0.40005 90)
			(size 0.4064 0.4064)
			(layers "F.Cu" "F.Mask" "F.Paste")
			(net "FM_CPU0_SMERR_N")
		)
		(pad "M22" smd circle
			(at 8.400034 0.40005 90)
			(size 0.4064 0.4064)
			(layers "F.Cu" "F.Mask" "F.Paste")
			(net "FM_SMERR_LED_R_N")
		)
		(pad "N1" smd circle
			(at -8.400034 1.199896 90)
			(size 0.4064 0.4064)
			(layers "F.Cu" "F.Mask" "F.Paste")
			(net "PVDD11_S3_P1_PMALERT")
		)
		(pad "N2" smd circle
			(at -7.599934 1.199896 90)
			(size 0.4064 0.4064)
			(layers "F.Cu" "F.Mask" "F.Paste")
			(net "FM_CLKREQ_M2_1_N")
		)
		(pad "N3" smd circle
			(at -6.800088 1.199896 90)
			(size 0.4064 0.4064)
			(layers "F.Cu" "F.Mask" "F.Paste")
			(net "FM_CLR_CMOS")
		)
		(pad "N4" smd circle
			(at -5.999988 1.199896 90)
			(size 0.4064 0.4064)
			(layers "F.Cu" "F.Mask" "F.Paste")
			(net "PWRGD_OCP_SFF_PWR_GOOD")
		)
		(pad "N5" smd circle
			(at -5.199888 1.199896 90)
			(size 0.4064 0.4064)
			(layers "F.Cu" "F.Mask" "F.Paste")
			(net "FM_CPU0_SP5R1")
		)
		(pad "N6" smd circle
			(at -4.400042 1.199896 90)
			(size 0.4064 0.4064)
			(layers "F.Cu" "F.Mask" "F.Paste")
			(net "FM_CPU0_SP5R2")
		)
		(pad "N7" smd circle
			(at -3.599942 1.199896 90)
			(size 0.4064 0.4064)
			(layers "F.Cu" "F.Mask" "F.Paste")
			(net "P12V_HSC_TEMP_ALERT_R_N")
		)
		(pad "N8" smd circle
			(at -2.800096 1.199896 90)
			(size 0.4064 0.4064)
			(layers "F.Cu" "F.Mask" "F.Paste")
			(net "P3V3_AUX")
		)
		(pad "N9" smd circle
			(at -1.999996 1.199896 90)
			(size 0.4064 0.4064)
			(layers "F.Cu" "F.Mask" "F.Paste")
			(net "GND")
		)
		(pad "N10" smd circle
			(at -1.199896 1.199896 90)
			(size 0.4064 0.4064)
			(layers "F.Cu" "F.Mask" "F.Paste")
			(net "P3V3_AUX")
		)
		(pad "N11" smd circle
			(at -0.40005 1.199896 90)
			(size 0.4064 0.4064)
			(layers "F.Cu" "F.Mask" "F.Paste")
			(net "P3V3_AUX")
		)
		(pad "N12" smd circle
			(at 0.40005 1.199896 90)
			(size 0.4064 0.4064)
			(layers "F.Cu" "F.Mask" "F.Paste")
			(net "P3V3_AUX")
		)
		(pad "N13" smd circle
			(at 1.199896 1.199896 90)
			(size 0.4064 0.4064)
			(layers "F.Cu" "F.Mask" "F.Paste")
			(net "P3V3_AUX")
		)
		(pad "N14" smd circle
			(at 1.999996 1.199896 90)
			(size 0.4064 0.4064)
			(layers "F.Cu" "F.Mask" "F.Paste")
			(net "GND")
		)
		(pad "N15" smd circle
			(at 2.800096 1.199896 90)
			(size 0.4064 0.4064)
			(layers "F.Cu" "F.Mask" "F.Paste")
			(net "P1V8_AUX")
		)
		(pad "N16" smd circle
			(at 3.599942 1.199896 90)
			(size 0.4064 0.4064)
			(layers "F.Cu" "F.Mask" "F.Paste")
			(net "FM_CPU1_SMERR_N")
		)
		(pad "N17" smd circle
			(at 4.400042 1.199896 90)
			(size 0.4064 0.4064)
			(layers "F.Cu" "F.Mask" "F.Paste")
			(net "FM_ESPI_CPU0_ALERT_SEL")
		)
		(pad "N18" smd circle
			(at 5.199888 1.199896 90)
			(size 0.4064 0.4064)
			(layers "F.Cu" "F.Mask" "F.Paste")
			(net "RST_RT_CPU0_P2_PERST_R2_N")
		)
		(pad "N19" smd circle
			(at 5.999988 1.199896 90)
			(size 0.4064 0.4064)
			(layers "F.Cu" "F.Mask" "F.Paste")
			(net "PWRGD_P12V_MEM_R")
		)
		(pad "N20" smd circle
			(at 6.800088 1.199896 90)
			(size 0.4064 0.4064)
			(layers "F.Cu" "F.Mask" "F.Paste")
			(net "TP_PWRGD_P12V_FAN_DR_R")
		)
		(pad "N21" smd circle
			(at 7.599934 1.199896 90)
			(size 0.4064 0.4064)
			(layers "F.Cu" "F.Mask" "F.Paste")
			(net "GND")
		)
		(pad "N22" smd circle
			(at 8.400034 1.199896 90)
			(size 0.4064 0.4064)
			(layers "F.Cu" "F.Mask" "F.Paste")
			(net "BIOS_DEBUG_MODE_R")
		)
		(pad "P1" smd circle
			(at -8.400034 1.999996 90)
			(size 0.4064 0.4064)
			(layers "F.Cu" "F.Mask" "F.Paste")
			(net "OCP_V3_2_P3V3_P12V_ADC_ALERT")
		)
		(pad "P2" smd circle
			(at -7.599934 1.999996 90)
			(size 0.4064 0.4064)
			(layers "F.Cu" "F.Mask" "F.Paste")
			(net "FM_SMB_RST_E1S_0_N")
		)
		(pad "P3" smd circle
			(at -6.800088 1.999996 90)
			(size 0.4064 0.4064)
			(layers "F.Cu" "F.Mask" "F.Paste")
			(net "FM_CPU0_CORETYPE2")
		)
		(pad "P4" smd circle
			(at -5.999988 1.999996 90)
			(size 0.4064 0.4064)
			(layers "F.Cu" "F.Mask" "F.Paste")
			(net "FM_CPU1_CORETYPE0")
		)
		(pad "P5" smd circle
			(at -5.199888 1.999996 90)
			(size 0.4064 0.4064)
			(layers "F.Cu" "F.Mask" "F.Paste")
			(net "FM_APML_MUX2_SEL_R")
		)
		(pad "P6" smd circle
			(at -4.400042 1.999996 90)
			(size 0.4064 0.4064)
			(layers "F.Cu" "F.Mask" "F.Paste")
			(net "FM_APML_MUX2_OE_R_N")
		)
		(pad "P7" smd circle
			(at -3.599942 1.999996 90)
			(size 0.4064 0.4064)
			(layers "F.Cu" "F.Mask" "F.Paste")
			(net "FM_PVDDCR_CPU1_P0_R_EN")
		)
		(pad "P8" smd circle
			(at -2.800096 1.999996 90)
			(size 0.4064 0.4064)
			(layers "F.Cu" "F.Mask" "F.Paste")
			(net "P3V3_AUX")
		)
		(pad "P9" smd circle
			(at -1.999996 1.999996 90)
			(size 0.4064 0.4064)
			(layers "F.Cu" "F.Mask" "F.Paste")
			(net "GND")
		)
		(pad "P10" smd circle
			(at -1.199896 1.999996 90)
			(size 0.4064 0.4064)
			(layers "F.Cu" "F.Mask" "F.Paste")
			(net "GND")
		)
		(pad "P11" smd circle
			(at -0.40005 1.999996 90)
			(size 0.4064 0.4064)
			(layers "F.Cu" "F.Mask" "F.Paste")
			(net "GND")
		)
		(pad "P12" smd circle
			(at 0.40005 1.999996 90)
			(size 0.4064 0.4064)
			(layers "F.Cu" "F.Mask" "F.Paste")
			(net "GND")
		)
		(pad "P13" smd circle
			(at 1.199896 1.999996 90)
			(size 0.4064 0.4064)
			(layers "F.Cu" "F.Mask" "F.Paste")
			(net "GND")
		)
		(pad "P14" smd circle
			(at 1.999996 1.999996 90)
			(size 0.4064 0.4064)
			(layers "F.Cu" "F.Mask" "F.Paste")
			(net "GND")
		)
		(pad "P15" smd circle
			(at 2.800096 1.999996 90)
			(size 0.4064 0.4064)
			(layers "F.Cu" "F.Mask" "F.Paste")
			(net "P1V8_AUX")
		)
		(pad "P16" smd circle
			(at 3.599942 1.999996 90)
			(size 0.4064 0.4064)
			(layers "F.Cu" "F.Mask" "F.Paste")
			(net "FM_HDT_HDR_PWROK")
		)
		(pad "P17" smd circle
			(at 4.400042 1.999996 90)
			(size 0.4064 0.4064)
			(layers "F.Cu" "F.Mask" "F.Paste")
			(net "ESPI_CPU0_R1_D3")
		)
		(pad "P18" smd circle
			(at 5.199888 1.999996 90)
			(size 0.4064 0.4064)
			(layers "F.Cu" "F.Mask" "F.Paste")
			(net "ESPI_CPU0_R1_D2")
		)
		(pad "P19" smd circle
			(at 5.999988 1.999996 90)
			(size 0.4064 0.4064)
			(layers "F.Cu" "F.Mask" "F.Paste")
			(net "ESPI_CPU0_R1_D1")
		)
		(pad "P20" smd circle
			(at 6.800088 1.999996 90)
			(size 0.4064 0.4064)
			(layers "F.Cu" "F.Mask" "F.Paste")
			(net "ESPI_CPU0_ALERT_R_N")
		)
		(pad "P21" smd circle
			(at 7.599934 1.999996 90)
			(size 0.4064 0.4064)
			(layers "F.Cu" "F.Mask" "F.Paste")
			(net "FM_CPU0_HDT_CONN_TESTEN")
		)
		(pad "P22" smd circle
			(at 8.400034 1.999996 90)
			(size 0.4064 0.4064)
			(layers "F.Cu" "F.Mask" "F.Paste")
			(net "ESPI_CPU0_CS1_R_N")
		)
		(pad "R1" smd circle
			(at -8.400034 2.800096 90)
			(size 0.4064 0.4064)
			(layers "F.Cu" "F.Mask" "F.Paste")
			(net "FM_CPU0_CORETYPE0")
		)
		(pad "R2" smd circle
			(at -7.599934 2.800096 90)
			(size 0.4064 0.4064)
			(layers "F.Cu" "F.Mask" "F.Paste")
			(net "FM_CPU0_CORETYPE1")
		)
		(pad "R3" smd circle
			(at -6.800088 2.800096 90)
			(size 0.4064 0.4064)
			(layers "F.Cu" "F.Mask" "F.Paste")
			(net "FM_CPU1_SP5R1")
		)
		(pad "R4" smd circle
			(at -5.999988 2.800096 90)
			(size 0.4064 0.4064)
			(layers "F.Cu" "F.Mask" "F.Paste")
			(net "FM_CPU1_SP5R2")
		)
		(pad "R5" smd circle
			(at -5.199888 2.800096 90)
			(size 0.4064 0.4064)
			(layers "F.Cu" "F.Mask" "F.Paste")
			(net "FM_LED_PWRGD_PVDDCR_CPU1_P0")
		)
		(pad "R6" smd circle
			(at -4.400042 2.800096 90)
			(size 0.4064 0.4064)
			(layers "F.Cu" "F.Mask" "F.Paste")
			(net "PWRGD_CHAF_CPU1_R2")
		)
		(pad "R7" smd circle
			(at -3.599942 2.800096 90)
			(size 0.4064 0.4064)
			(layers "F.Cu" "F.Mask" "F.Paste")
			(net "FM_PWRGD_PVDDCR_CPU1_P0")
		)
		(pad "R8" smd circle
			(at -2.800096 2.800096 90)
			(size 0.4064 0.4064)
			(layers "F.Cu" "F.Mask" "F.Paste")
			(net "GND")
		)
		(pad "R9" smd circle
			(at -1.999996 2.800096 90)
			(size 0.4064 0.4064)
			(layers "F.Cu" "F.Mask" "F.Paste")
			(net "P3V3_AUX")
		)
		(pad "R10" smd circle
			(at -1.199896 2.800096 90)
			(size 0.4064 0.4064)
			(layers "F.Cu" "F.Mask" "F.Paste")
			(net "P3V3_AUX")
		)
		(pad "R11" smd circle
			(at -0.40005 2.800096 90)
			(size 0.4064 0.4064)
			(layers "F.Cu" "F.Mask" "F.Paste")
			(net "P3V3_AUX")
		)
		(pad "R12" smd circle
			(at 0.40005 2.800096 90)
			(size 0.4064 0.4064)
			(layers "F.Cu" "F.Mask" "F.Paste")
			(net "P3V3_AUX")
		)
		(pad "R13" smd circle
			(at 1.199896 2.800096 90)
			(size 0.4064 0.4064)
			(layers "F.Cu" "F.Mask" "F.Paste")
			(net "P3V3_AUX")
		)
		(pad "R14" smd circle
			(at 1.999996 2.800096 90)
			(size 0.4064 0.4064)
			(layers "F.Cu" "F.Mask" "F.Paste")
			(net "P3V3_AUX")
		)
		(pad "R15" smd circle
			(at 2.800096 2.800096 90)
			(size 0.4064 0.4064)
			(layers "F.Cu" "F.Mask" "F.Paste")
			(net "GND")
		)
		(pad "R16" smd circle
			(at 3.599942 2.800096 90)
			(size 0.4064 0.4064)
			(layers "F.Cu" "F.Mask" "F.Paste")
			(net "CPU1_JTAG_BUF_R_OE")
		)
		(pad "R17" smd circle
			(at 4.400042 2.800096 90)
			(size 0.4064 0.4064)
			(layers "F.Cu" "F.Mask" "F.Paste")
			(net "FM_PLD_CPU1_PRSNT_HDT")
		)
		(pad "R18" smd circle
			(at 5.199888 2.800096 90)
			(size 0.4064 0.4064)
			(layers "F.Cu" "F.Mask" "F.Paste")
			(net "CPU0_SPD_HOST_CTRL_R1_N")
		)
		(pad "R19" smd circle
			(at 5.999988 2.800096 90)
			(size 0.4064 0.4064)
			(layers "F.Cu" "F.Mask" "F.Paste")
			(net "SCM_USB_OC_R_N")
		)
		(pad "R20" smd circle
			(at 6.800088 2.800096 90)
			(size 0.4064 0.4064)
			(layers "F.Cu" "F.Mask" "F.Paste")
			(net "RST_RT_CPU0_P2_RESET_R2_N")
		)
		(pad "R21" smd circle
			(at 7.599934 2.800096 90)
			(size 0.4064 0.4064)
			(layers "F.Cu" "F.Mask" "F.Paste")
			(net "CLK_ESPI_CPU0_R1_CLK1")
		)
		(pad "R22" smd circle
			(at 8.400034 2.800096 90)
			(size 0.4064 0.4064)
			(layers "F.Cu" "F.Mask" "F.Paste")
			(net "FM_JTAG_BMC_OE")
		)
		(pad "T1" smd circle
			(at -8.400034 3.599942 90)
			(size 0.4064 0.4064)
			(layers "F.Cu" "F.Mask" "F.Paste")
			(net "FM_CPU1_CORETYPE1")
		)
		(pad "T2" smd circle
			(at -7.599934 3.599942 90)
			(size 0.4064 0.4064)
			(layers "F.Cu" "F.Mask" "F.Paste")
			(net "FM_CPU1_CORETYPE2")
		)
		(pad "T3" smd circle
			(at -6.800088 3.599942 90)
			(size 0.4064 0.4064)
			(layers "F.Cu" "F.Mask" "F.Paste")
			(net "FM_CPU1_SP5R3")
		)
		(pad "T4" smd circle
			(at -5.999988 3.599942 90)
			(size 0.4064 0.4064)
			(layers "F.Cu" "F.Mask" "F.Paste")
			(net "FM_CPU1_SP5R4")
		)
		(pad "T5" smd circle
			(at -5.199888 3.599942 90)
			(size 0.4064 0.4064)
			(layers "F.Cu" "F.Mask" "F.Paste")
			(net "FM_PDB_BUF_EN_N")
		)
		(pad "T6" smd circle
			(at -4.400042 3.599942 90)
			(size 0.4064 0.4064)
			(layers "F.Cu" "F.Mask" "F.Paste")
			(net "PWRGD_CHGL_CPU1_R2")
		)
		(pad "T7" smd circle
			(at -3.599942 3.599942 90)
			(size 0.4064 0.4064)
			(layers "F.Cu" "F.Mask" "F.Paste")
			(net "FM_PVDDCR_CPU1_P1_R_EN")
		)
		(pad "T8" smd circle
			(at -2.800096 3.599942 90)
			(size 0.4064 0.4064)
			(layers "F.Cu" "F.Mask" "F.Paste")
			(net "FM_PWRGD_PVDDCR_CPU1_P1")
		)
		(pad "T9" smd circle
			(at -1.999996 3.599942 90)
			(size 0.4064 0.4064)
			(layers "F.Cu" "F.Mask" "F.Paste")
			(net "FM_PWRGD_P1V8_RETIMER_CPU0")
		)
		(pad "T10" smd circle
			(at -1.199896 3.599942 90)
			(size 0.4064 0.4064)
			(layers "F.Cu" "F.Mask" "F.Paste")
			(net "FM_GPU_HSC_EN_R")
		)
		(pad "T11" smd circle
			(at -0.40005 3.599942 90)
			(size 0.4064 0.4064)
			(layers "F.Cu" "F.Mask" "F.Paste")
			(net "FM_LED_PWRGD_PVDD33_S5")
		)
		(pad "T12" smd circle
			(at 0.40005 3.599942 90)
			(size 0.4064 0.4064)
			(layers "F.Cu" "F.Mask" "F.Paste")
			(net "HPDB_HSC_PWRGD_ISO_R")
		)
		(pad "T13" smd circle
			(at 1.199896 3.599942 90)
			(size 0.4064 0.4064)
			(layers "F.Cu" "F.Mask" "F.Paste")
			(net "GPU_3V3IO_RSVD1_FFU_ISO_R")
		)
		(pad "T14" smd circle
			(at 1.999996 3.599942 90)
			(size 0.4064 0.4064)
			(layers "F.Cu" "F.Mask" "F.Paste")
			(net "RST_PERST_CPU0_SWB_N")
		)
		(pad "T15" smd circle
			(at 2.800096 3.599942 90)
			(size 0.4064 0.4064)
			(layers "F.Cu" "F.Mask" "F.Paste")
			(net "GPU_FPGA_BOOT_EN_R")
		)
		(pad "T16" smd circle
			(at 3.599942 3.599942 90)
			(size 0.4064 0.4064)
			(layers "F.Cu" "F.Mask" "F.Paste")
			(net "FM_P5V_EN")
		)
		(pad "T17" smd circle
			(at 4.400042 3.599942 90)
			(size 0.4064 0.4064)
			(layers "F.Cu" "F.Mask" "F.Paste")
			(net "RST_RT_CPU0_P3_RESET_R2_N")
		)
		(pad "T18" smd circle
			(at 5.199888 3.599942 90)
			(size 0.4064 0.4064)
			(layers "F.Cu" "F.Mask" "F.Paste")
			(net "P12V_ALL_PWROK_R")
		)
		(pad "T19" smd circle
			(at 5.999988 3.599942 90)
			(size 0.4064 0.4064)
			(layers "F.Cu" "F.Mask" "F.Paste")
			(net "RST_RT_CPU0_P3_PERST_R2_N")
		)
		(pad "T20" smd circle
			(at 6.800088 3.599942 90)
			(size 0.4064 0.4064)
			(layers "F.Cu" "F.Mask" "F.Paste")
			(net "SCM_IRQ_1V8_R_N")
		)
		(pad "T21" smd circle
			(at 7.599934 3.599942 90)
			(size 0.4064 0.4064)
			(layers "F.Cu" "F.Mask" "F.Paste")
			(net "ESPI_CPU0_R1_D0")
		)
		(pad "T22" smd circle
			(at 8.400034 3.599942 90)
			(size 0.4064 0.4064)
			(layers "F.Cu" "F.Mask" "F.Paste")
			(net "RST_ESPI_CPU0_RSTOUT_R_N")
		)
		(pad "U1" smd circle
			(at -8.400034 4.400042 90)
			(size 0.4064 0.4064)
			(layers "F.Cu" "F.Mask" "F.Paste")
			(net "FM_CPU0_SP5R3")
		)
		(pad "U2" smd circle
			(at -7.599934 4.400042 90)
			(size 0.4064 0.4064)
			(layers "F.Cu" "F.Mask" "F.Paste")
			(net "FM_CPU0_SP5R4")
		)
		(pad "U3" smd circle
			(at -6.800088 4.400042 90)
			(size 0.4064 0.4064)
			(layers "F.Cu" "F.Mask" "F.Paste")
			(net "E1S_0_PRSNT_R_N")
		)
		(pad "U4" smd circle
			(at -5.999988 4.400042 90)
			(size 0.4064 0.4064)
			(layers "F.Cu" "F.Mask" "F.Paste")
			(net "PWRGD_P5V_AUX_R3")
		)
		(pad "U5" smd circle
			(at -5.199888 4.400042 90)
			(size 0.4064 0.4064)
			(layers "F.Cu" "F.Mask" "F.Paste")
			(net "FM_LED_PWRGD_PVDDCR_CPU0_P0")
		)
		(pad "U6" smd circle
			(at -4.400042 4.400042 90)
			(size 0.4064 0.4064)
			(layers "F.Cu" "F.Mask" "F.Paste")
			(net "FM_PWRGD_PVDDIO_P0")
		)
		(pad "U7" smd circle
			(at -3.599942 4.400042 90)
			(size 0.4064 0.4064)
			(layers "F.Cu" "F.Mask" "F.Paste")
			(net "FM_UART_LS_EN")
		)
		(pad "U8" smd circle
			(at -2.800096 4.400042 90)
			(size 0.4064 0.4064)
			(layers "F.Cu" "F.Mask" "F.Paste")
			(net "FM_FPGA_DEBUG_SW_SPARE")
		)
		(pad "U9" smd circle
			(at -1.999996 4.400042 90)
			(size 0.4064 0.4064)
			(layers "F.Cu" "F.Mask" "F.Paste")
			(net "FM_PWRGD_P1V8_RETIMER_CPU1")
		)
		(pad "U10" smd circle
			(at -1.199896 4.400042 90)
			(size 0.4064 0.4064)
			(layers "F.Cu" "F.Mask" "F.Paste")
			(net "P12V_E1S_0_PWRGD")
		)
		(pad "U11" smd circle
			(at -0.40005 4.400042 90)
			(size 0.4064 0.4064)
			(layers "F.Cu" "F.Mask" "F.Paste")
			(net "P3V3_E1S_PWRGD_0_R")
		)
		(pad "U12" smd circle
			(at 0.40005 4.400042 90)
			(size 0.4064 0.4064)
			(layers "F.Cu" "F.Mask" "F.Paste")
			(net "Net_19")
		)
		(pad "U13" smd circle
			(at 1.199896 4.400042 90)
			(size 0.4064 0.4064)
			(layers "F.Cu" "F.Mask" "F.Paste")
			(net "HGX_DETECT_N_R")
		)
		(pad "U14" smd circle
			(at 1.999996 4.400042 90)
			(size 0.4064 0.4064)
			(layers "F.Cu" "F.Mask" "F.Paste")
			(net "RST_PERST_CPU1_SWB_N")
		)
		(pad "U15" smd circle
			(at 2.800096 4.400042 90)
			(size 0.4064 0.4064)
			(layers "F.Cu" "F.Mask" "F.Paste")
			(net "RST_BMC_FROM_SWB_ISO_R_N")
		)
		(pad "U16" smd circle
			(at 3.599942 4.400042 90)
			(size 0.4064 0.4064)
			(layers "F.Cu" "F.Mask" "F.Paste")
			(net "FM_NCSI_OCP_V3_2_R_OE")
		)
		(pad "U17" smd circle
			(at 4.400042 4.400042 90)
			(size 0.4064 0.4064)
			(layers "F.Cu" "F.Mask" "F.Paste")
			(net "FM_CPU0_FORCE_SELFREFRESH")
		)
		(pad "U18" smd circle
			(at 5.199888 4.400042 90)
			(size 0.4064 0.4064)
			(layers "F.Cu" "F.Mask" "F.Paste")
			(net "FM_PLD_CPU0_PRSNT_HDT")
		)
		(pad "U19" smd circle
			(at 5.999988 4.400042 90)
			(size 0.4064 0.4064)
			(layers "F.Cu" "F.Mask" "F.Paste")
			(net "FM_SPD_CPU0_SWITCH_CTRL_R_N")
		)
		(pad "U20" smd circle
			(at 6.800088 4.400042 90)
			(size 0.4064 0.4064)
			(layers "F.Cu" "F.Mask" "F.Paste")
			(net "BMC_JTAG_SEL_R")
		)
		(pad "U21" smd circle
			(at 7.599934 4.400042 90)
			(size 0.4064 0.4064)
			(layers "F.Cu" "F.Mask" "F.Paste")
			(net "FM_BIOS_POST_CMPLT_BUF_R_N")
		)
		(pad "U22" smd circle
			(at 8.400034 4.400042 90)
			(size 0.4064 0.4064)
			(layers "F.Cu" "F.Mask" "F.Paste")
			(net "FM_HDT_HDR_RESET_N")
		)
		(pad "V1" smd circle
			(at -8.400034 5.199888 90)
			(size 0.4064 0.4064)
			(layers "F.Cu" "F.Mask" "F.Paste")
			(net "FM_PRSNT_CPU0_R_N")
		)
		(pad "V2" smd circle
			(at -7.599934 5.199888 90)
			(size 0.4064 0.4064)
			(layers "F.Cu" "F.Mask" "F.Paste")
			(net "GND")
		)
		(pad "V3" smd circle
			(at -6.800088 5.199888 90)
			(size 0.4064 0.4064)
			(layers "F.Cu" "F.Mask" "F.Paste")
			(net "P3V3_AUX")
		)
		(pad "V4" smd circle
			(at -5.999988 5.199888 90)
			(size 0.4064 0.4064)
			(layers "F.Cu" "F.Mask" "F.Paste")
			(net "FM_LED_PWRGD_PVDDCR_SOC_P0")
		)
		(pad "V5" smd circle
			(at -5.199888 5.199888 90)
			(size 0.4064 0.4064)
			(layers "F.Cu" "F.Mask" "F.Paste")
			(net "FM_PRSNT_CPU1_R_N")
		)
		(pad "V6" smd circle
			(at -4.400042 5.199888 90)
			(size 0.4064 0.4064)
			(layers "F.Cu" "F.Mask" "F.Paste")
			(net "FM_PVDDIO_P0_EN")
		)
		(pad "V7" smd circle
			(at -3.599942 5.199888 90)
			(size 0.4064 0.4064)
			(layers "F.Cu" "F.Mask" "F.Paste")
			(net "GPU_FPGA_RST_N")
		)
		(pad "V8" smd circle
			(at -2.800096 5.199888 90)
			(size 0.4064 0.4064)
			(layers "F.Cu" "F.Mask" "F.Paste")
			(net "PVDD18_S5_P1_R_EN")
		)
		(pad "V9" smd circle
			(at -1.999996 5.199888 90)
			(size 0.4064 0.4064)
			(layers "F.Cu" "F.Mask" "F.Paste")
			(net "FM_PVDD33_S5_EN")
		)
		(pad "V10" smd circle
			(at -1.199896 5.199888 90)
			(size 0.4064 0.4064)
			(layers "F.Cu" "F.Mask" "F.Paste")
			(net "FM_LED_PWRGD_PVDDCR_CPU0_P1")
		)
		(pad "V11" smd circle
			(at -0.40005 5.199888 90)
			(size 0.4064 0.4064)
			(layers "F.Cu" "F.Mask" "F.Paste")
			(net "RST_PERST_CPU1_SWB_1_N")
		)
		(pad "V12" smd circle
			(at 0.40005 5.199888 90)
			(size 0.4064 0.4064)
			(layers "F.Cu" "F.Mask" "F.Paste")
			(net "P3V3_E1S_0_EN_R")
		)
		(pad "V13" smd circle
			(at 1.199896 5.199888 90)
			(size 0.4064 0.4064)
			(layers "F.Cu" "F.Mask" "F.Paste")
			(net "GPU_3V3IO_RSVD4_ISO_R")
		)
		(pad "V14" smd circle
			(at 1.999996 5.199888 90)
			(size 0.4064 0.4064)
			(layers "F.Cu" "F.Mask" "F.Paste")
			(net "PRSNT_CABLE_GPU_A2_ISO_R_N")
		)
		(pad "V15" smd circle
			(at 2.800096 5.199888 90)
			(size 0.4064 0.4064)
			(layers "F.Cu" "F.Mask" "F.Paste")
			(net "BIC_MONITER_ISO_R")
		)
		(pad "V16" smd circle
			(at 3.599942 5.199888 90)
			(size 0.4064 0.4064)
			(layers "F.Cu" "F.Mask" "F.Paste")
			(net "RST_PERST_M2_0_R_N")
		)
		(pad "V17" smd circle
			(at 4.400042 5.199888 90)
			(size 0.4064 0.4064)
			(layers "F.Cu" "F.Mask" "F.Paste")
			(net "P3V3_OCP_V3_2_EN_R")
		)
		(pad "V18" smd circle
			(at 5.199888 5.199888 90)
			(size 0.4064 0.4064)
			(layers "F.Cu" "F.Mask" "F.Paste")
			(net "RST_SMB_RT_ROM_R2_N")
		)
		(pad "V19" smd circle
			(at 5.999988 5.199888 90)
			(size 0.4064 0.4064)
			(layers "F.Cu" "F.Mask" "F.Paste")
			(net "TP_FM_CLK_BUFFER_EN_R")
		)
		(pad "V20" smd circle
			(at 6.800088 5.199888 90)
			(size 0.4064 0.4064)
			(layers "F.Cu" "F.Mask" "F.Paste")
			(net "P1V8_AUX")
		)
		(pad "V21" smd circle
			(at 7.599934 5.199888 90)
			(size 0.4064 0.4064)
			(layers "F.Cu" "F.Mask" "F.Paste")
			(net "GND")
		)
		(pad "V22" smd circle
			(at 8.400034 5.199888 90)
			(size 0.4064 0.4064)
			(layers "F.Cu" "F.Mask" "F.Paste")
			(net "FM_BIOS_USB_RECOVERY")
		)
		(pad "W1" smd circle
			(at -8.400034 5.999988 90)
			(size 0.4064 0.4064)
			(layers "F.Cu" "F.Mask" "F.Paste")
			(net "PWRGD_CHAF_CPU0_R2")
		)
		(pad "W2" smd circle
			(at -7.599934 5.999988 90)
			(size 0.4064 0.4064)
			(layers "F.Cu" "F.Mask" "F.Paste")
			(net "P12V_OCP_V3_1_PWRGD")
		)
		(pad "W3" smd circle
			(at -6.800088 5.999988 90)
			(size 0.4064 0.4064)
			(layers "F.Cu" "F.Mask" "F.Paste")
			(net "PVDDCR_SOC_P0_EN")
		)
		(pad "W4" smd circle
			(at -5.999988 5.999988 90)
			(size 0.4064 0.4064)
			(layers "F.Cu" "F.Mask" "F.Paste")
			(net "FM_PVDD11_S3_P0_EN")
		)
		(pad "W5" smd circle
			(at -5.199888 5.999988 90)
			(size 0.4064 0.4064)
			(layers "F.Cu" "F.Mask" "F.Paste")
			(net "FM_PVDDCR_CPU0_P1_R_EN")
		)
		(pad "W6" smd circle
			(at -4.400042 5.999988 90)
			(size 0.4064 0.4064)
			(layers "F.Cu" "F.Mask" "F.Paste")
			(net "FM_GPU_PWR_EN")
		)
		(pad "W7" smd circle
			(at -3.599942 5.999988 90)
			(size 0.4064 0.4064)
			(layers "F.Cu" "F.Mask" "F.Paste")
			(net "P3V3_AUX")
		)
		(pad "W8" smd circle
			(at -2.800096 5.999988 90)
			(size 0.4064 0.4064)
			(layers "F.Cu" "F.Mask" "F.Paste")
			(net "PWRGD_P3V3_AUX_R")
		)
		(pad "W9" smd circle
			(at -1.999996 5.999988 90)
			(size 0.4064 0.4064)
			(layers "F.Cu" "F.Mask" "F.Paste")
			(net "FM_CPU0_PWR_GOOD")
		)
		(pad "W10" smd circle
			(at -1.199896 5.999988 90)
			(size 0.4064 0.4064)
			(layers "F.Cu" "F.Mask" "F.Paste")
			(net "FM_PLD_OCP_SFF_PWR_GOOD_R")
		)
		(pad "W11" smd circle
			(at -0.40005 5.999988 90)
			(size 0.4064 0.4064)
			(layers "F.Cu" "F.Mask" "F.Paste")
			(net "P3V3_AUX")
		)
		(pad "W12" smd circle
			(at 0.40005 5.999988 90)
			(size 0.4064 0.4064)
			(layers "F.Cu" "F.Mask" "F.Paste")
			(net "GND")
		)
		(pad "W13" smd circle
			(at 1.199896 5.999988 90)
			(size 0.4064 0.4064)
			(layers "F.Cu" "F.Mask" "F.Paste")
			(net "GPU_3V3IO_RSVD0_FFU_ISO_R")
		)
		(pad "W14" smd circle
			(at 1.999996 5.999988 90)
			(size 0.4064 0.4064)
			(layers "F.Cu" "F.Mask" "F.Paste")
			(net "GPU_FPGA_THERM_OVERT_ISO_R_N")
		)
		(pad "W15" smd circle
			(at 2.800096 5.999988 90)
			(size 0.4064 0.4064)
			(layers "F.Cu" "F.Mask" "F.Paste")
			(net "GPU_WP_HW_CTRL_R_N")
		)
		(pad "W16" smd circle
			(at 3.599942 5.999988 90)
			(size 0.4064 0.4064)
			(layers "F.Cu" "F.Mask" "F.Paste")
			(net "P3V3_AUX")
		)
		(pad "W17" smd circle
			(at 4.400042 5.999988 90)
			(size 0.4064 0.4064)
			(layers "F.Cu" "F.Mask" "F.Paste")
			(net "RST_PERST_OCP_SFF_N")
		)
		(pad "W18" smd circle
			(at 5.199888 5.999988 90)
			(size 0.4064 0.4064)
			(layers "F.Cu" "F.Mask" "F.Paste")
			(net "FM_AC_PWR_BTN_PLD_ISO_N")
		)
		(pad "W19" smd circle
			(at 5.999988 5.999988 90)
			(size 0.4064 0.4064)
			(layers "F.Cu" "F.Mask" "F.Paste")
			(net "FM_CPU1_FORCE_SELFREFRESH")
		)
		(pad "W20" smd circle
			(at 6.800088 5.999988 90)
			(size 0.4064 0.4064)
			(layers "F.Cu" "F.Mask" "F.Paste")
			(net "FM_FORCE_ALL_PWRON_R")
		)
		(pad "W21" smd circle
			(at 7.599934 5.999988 90)
			(size 0.4064 0.4064)
			(layers "F.Cu" "F.Mask" "F.Paste")
			(net "FM_ROM_SD_LS_OE")
		)
		(pad "W22" smd circle
			(at 8.400034 5.999988 90)
			(size 0.4064 0.4064)
			(layers "F.Cu" "F.Mask" "F.Paste")
			(net "FM_CPU1_NMI_SYNC_FLOOD_N")
		)
		(pad "Y1" smd circle
			(at -8.400034 6.800088 90)
			(size 0.4064 0.4064)
			(layers "F.Cu" "F.Mask" "F.Paste")
			(net "PWRGD_CHGL_CPU0_R2")
		)
		(pad "Y2" smd circle
			(at -7.599934 6.800088 90)
			(size 0.4064 0.4064)
			(layers "F.Cu" "F.Mask" "F.Paste")
			(net "PWRGD_PVDDCR_SOC_P0")
		)
		(pad "Y3" smd circle
			(at -6.800088 6.800088 90)
			(size 0.4064 0.4064)
			(layers "F.Cu" "F.Mask" "F.Paste")
			(net "PWRGD_PVDDCR_CPU0_P0")
		)
		(pad "Y4" smd circle
			(at -5.999988 6.800088 90)
			(size 0.4064 0.4064)
			(layers "F.Cu" "F.Mask" "F.Paste")
			(net "FM_PWRGD_PVDD11_S3_P0")
		)
		(pad "Y5" smd circle
			(at -5.199888 6.800088 90)
			(size 0.4064 0.4064)
			(layers "F.Cu" "F.Mask" "F.Paste")
			(net "FM_PWRGD_PVDDCR_CPU0_P1")
		)
		(pad "Y6" smd circle
			(at -4.400042 6.800088 90)
			(size 0.4064 0.4064)
			(layers "F.Cu" "F.Mask" "F.Paste")
			(net "P12V_SCM_PWRGD_R")
		)
		(pad "Y7" smd circle
			(at -3.599942 6.800088 90)
			(size 0.4064 0.4064)
			(layers "F.Cu" "F.Mask" "F.Paste")
			(net "GND")
		)
		(pad "Y8" smd circle
			(at -2.800096 6.800088 90)
			(size 0.4064 0.4064)
			(layers "F.Cu" "F.Mask" "F.Paste")
			(net "PWRGD_P1V8_AUX_R")
		)
		(pad "Y9" smd circle
			(at -1.999996 6.800088 90)
			(size 0.4064 0.4064)
			(layers "F.Cu" "F.Mask" "F.Paste")
			(net "PWRGD_P1V2_AUX_R")
		)
		(pad "Y10" smd circle
			(at -1.199896 6.800088 90)
			(size 0.4064 0.4064)
			(layers "F.Cu" "F.Mask" "F.Paste")
			(net "BMC_FPGA_LED2")
		)
		(pad "Y11" smd circle
			(at -0.40005 6.800088 90)
			(size 0.4064 0.4064)
			(layers "F.Cu" "F.Mask" "F.Paste")
			(net "FM_LED_PWRGD_PVDDIO_P0")
		)
		(pad "Y12" smd circle
			(at 0.40005 6.800088 90)
			(size 0.4064 0.4064)
			(layers "F.Cu" "F.Mask" "F.Paste")
			(net "FM_LED_PWRGD_PVDD11_S3_P0")
		)
		(pad "Y13" smd circle
			(at 1.199896 6.800088 90)
			(size 0.4064 0.4064)
			(layers "F.Cu" "F.Mask" "F.Paste")
			(net "SWB_HSC_EN_R")
		)
		(pad "Y14" smd circle
			(at 1.999996 6.800088 90)
			(size 0.4064 0.4064)
			(layers "F.Cu" "F.Mask" "F.Paste")
			(net "SWB_HSC_PWRGD_ISO_R")
		)
		(pad "Y15" smd circle
			(at 2.800096 6.800088 90)
			(size 0.4064 0.4064)
			(layers "F.Cu" "F.Mask" "F.Paste")
			(net "GPU_FPGA_OVERT_ISO_R_N")
		)
		(pad "Y16" smd circle
			(at 3.599942 6.800088 90)
			(size 0.4064 0.4064)
			(layers "F.Cu" "F.Mask" "F.Paste")
			(net "GND")
		)
		(pad "Y17" smd circle
			(at 4.400042 6.800088 90)
			(size 0.4064 0.4064)
			(layers "F.Cu" "F.Mask" "F.Paste")
			(net "SW_P3V3_EN")
		)
		(pad "Y18" smd circle
			(at 5.199888 6.800088 90)
			(size 0.4064 0.4064)
			(layers "F.Cu" "F.Mask" "F.Paste")
			(net "FM_SMB_2_ALERT_GPU_ISO_R_N")
		)
		(pad "Y19" smd circle
			(at 5.999988 6.800088 90)
			(size 0.4064 0.4064)
			(layers "F.Cu" "F.Mask" "F.Paste")
			(net "GPU_BASE_STBY_EN_R")
		)
		(pad "Y20" smd circle
			(at 6.800088 6.800088 90)
			(size 0.4064 0.4064)
			(layers "F.Cu" "F.Mask" "F.Paste")
			(net "RST_SMB_RT_R2_N")
		)
		(pad "Y21" smd circle
			(at 7.599934 6.800088 90)
			(size 0.4064 0.4064)
			(layers "F.Cu" "F.Mask" "F.Paste")
			(net "FM_CPU1_PWR_GD_IN")
		)
		(pad "Y22" smd circle
			(at 8.400034 6.800088 90)
			(size 0.4064 0.4064)
			(layers "F.Cu" "F.Mask" "F.Paste")
			(net "FM_ROM_LS_EN")
		)
		(zone
			(layer "F.Cu")
			(hatch none 0.5)
			(connect_pads
				(clearance 0)
			)
			(min_thickness 0.25)
			(keepout
				(tracks allowed)
				(vias not_allowed)
				(pads allowed)
				(copperpour not_allowed)
				(footprints allowed)
			)
			(placement
				(enabled no)
				(sheetname "")
			)
			(fill
				(thermal_gap 0.5)
				(thermal_bridge_width 0.5)
				(island_removal_mode 0)
			)
			(polygon
				(pts
					(xy 194.938142 -114.906806) (xy 185.668158 -114.906806) (xy 185.668158 -105.636822) (xy 185.376058 -105.636822)
					(xy 185.376058 -114.906806) (xy 176.106074 -114.906806) (xy 176.106074 -115.198906) (xy 185.376058 -115.198906)
					(xy 185.376058 -124.46889) (xy 185.668158 -124.46889) (xy 185.668158 -115.198906) (xy 194.938142 -115.198906)
				)
			)
		)
	)
	(footprint ""
		(layer "F.Cu")
		(at 359.190036 -393.47648 180)
		(property "Reference" "L28"
			(at 0 0 180)
			(layer "F.SilkS")
			(hide yes)
			(effects
				(font
					(size 1.27 1.27)
				)
			)
		)
		(property "Value" ""
			(at 0 0 180)
			(layer "F.Fab")
			(effects
				(font
					(size 1.27 1.27)
				)
			)
		)
		(duplicate_pad_numbers_are_jumpers no)
		(fp_line
			(start 0.762 0.381)
			(end -0.762 0.381)
			(stroke
				(width 0.1524)
				(type default)
			)
			(layer "F.SilkS")
		)
		(fp_line
			(start 0.762 -0.381)
			(end 0.762 0.381)
			(stroke
				(width 0.1524)
				(type default)
			)
			(layer "F.SilkS")
		)
		(fp_line
			(start -0.762 0.381)
			(end -0.762 -0.381)
			(stroke
				(width 0.1524)
				(type default)
			)
			(layer "F.SilkS")
		)
		(fp_line
			(start -0.762 -0.381)
			(end 0.762 -0.381)
			(stroke
				(width 0.1524)
				(type default)
			)
			(layer "F.SilkS")
		)
		(fp_line
			(start 0.680466 0.306324)
			(end 0.118364 0.306324)
			(stroke
				(width 0.1)
				(type default)
			)
			(layer "F.Fab")
		)
		(fp_line
			(start 0.680466 -0.306324)
			(end 0.680466 0.306324)
			(stroke
				(width 0.1)
				(type default)
			)
			(layer "F.Fab")
		)
		(fp_line
			(start 0.118872 -0.2794)
			(end 0.118872 -0.306324)
			(stroke
				(width 0.1)
				(type default)
			)
			(layer "F.Fab")
		)
		(fp_line
			(start 0.118872 -0.306324)
			(end 0.680466 -0.306324)
			(stroke
				(width 0.1)
				(type default)
			)
			(layer "F.Fab")
		)
		(fp_line
			(start 0.118364 0.306324)
			(end 0.118364 0.2794)
			(stroke
				(width 0.1)
				(type default)
			)
			(layer "F.Fab")
		)
		(fp_line
			(start 0.118364 0.2794)
			(end -0.119634 0.2794)
			(stroke
				(width 0.1)
				(type default)
			)
			(layer "F.Fab")
		)
		(fp_line
			(start -0.118364 -0.2794)
			(end 0.118872 -0.2794)
			(stroke
				(width 0.1)
				(type default)
			)
			(layer "F.Fab")
		)
		(fp_line
			(start -0.118364 -0.307086)
			(end -0.118364 -0.2794)
			(stroke
				(width 0.1)
				(type default)
			)
			(layer "F.Fab")
		)
		(fp_line
			(start -0.119634 0.30607)
			(end -0.681736 0.30607)
			(stroke
				(width 0.1)
				(type default)
			)
			(layer "F.Fab")
		)
		(fp_line
			(start -0.119634 0.2794)
			(end -0.119634 0.30607)
			(stroke
				(width 0.1)
				(type default)
			)
			(layer "F.Fab")
		)
		(fp_line
			(start -0.681736 0.30607)
			(end -0.681736 -0.307086)
			(stroke
				(width 0.1)
				(type default)
			)
			(layer "F.Fab")
		)
		(fp_line
			(start -0.681736 -0.307086)
			(end -0.118364 -0.307086)
			(stroke
				(width 0.1)
				(type default)
			)
			(layer "F.Fab")
		)
		(pad "1" smd rect
			(at -0.40005 0)
			(size 0.4572 0.508)
			(layers "F.Cu" "F.Mask" "F.Paste")
			(net "P1V8_CPU0_RT_1D")
		)
		(pad "2" smd rect
			(at 0.40005 0)
			(size 0.4572 0.508)
			(layers "F.Cu" "F.Mask" "F.Paste")
			(net "P1V8_CPU0_RT1_1A_1D")
		)
	)
	(footprint ""
		(layer "F.Cu")
		(at 117.895624 -262.205216 180)
		(property "Reference" "C2487"
			(at 0 0 180)
			(layer "F.SilkS")
			(hide yes)
			(effects
				(font
					(size 1.27 1.27)
				)
			)
		)
		(property "Value" ""
			(at 0 0 180)
			(layer "F.Fab")
			(effects
				(font
					(size 1.27 1.27)
				)
			)
		)
		(duplicate_pad_numbers_are_jumpers no)
		(fp_line
			(start 0.7874 0.4064)
			(end -0.7874 0.4064)
			(stroke
				(width 0.1524)
				(type default)
			)
			(layer "F.SilkS")
		)
		(fp_line
			(start 0.7874 -0.4064)
			(end 0.7874 0.4064)
			(stroke
				(width 0.1524)
				(type default)
			)
			(layer "F.SilkS")
		)
		(fp_line
			(start -0.7874 0.4064)
			(end -0.7874 -0.4064)
			(stroke
				(width 0.1524)
				(type default)
			)
			(layer "F.SilkS")
		)
		(fp_line
			(start -0.7874 -0.4064)
			(end 0.7874 -0.4064)
			(stroke
				(width 0.1524)
				(type default)
			)
			(layer "F.SilkS")
		)
		(fp_line
			(start 0.67945 0.3048)
			(end 0.120396 0.3048)
			(stroke
				(width 0.1)
				(type default)
			)
			(layer "F.Fab")
		)
		(fp_line
			(start 0.67945 -0.3048)
			(end 0.67945 0.3048)
			(stroke
				(width 0.1)
				(type default)
			)
			(layer "F.Fab")
		)
		(fp_line
			(start 0.12065 -0.2794)
			(end 0.12065 -0.3048)
			(stroke
				(width 0.1)
				(type default)
			)
			(layer "F.Fab")
		)
		(fp_line
			(start 0.12065 -0.3048)
			(end 0.67945 -0.3048)
			(stroke
				(width 0.1)
				(type default)
			)
			(layer "F.Fab")
		)
		(fp_line
			(start 0.120396 0.3048)
			(end 0.120396 0.2794)
			(stroke
				(width 0.1)
				(type default)
			)
			(layer "F.Fab")
		)
		(fp_line
			(start 0.120396 0.2794)
			(end -0.12065 0.2794)
			(stroke
				(width 0.1)
				(type default)
			)
			(layer "F.Fab")
		)
		(fp_line
			(start -0.12065 0.3048)
			(end -0.67945 0.3048)
			(stroke
				(width 0.1)
				(type default)
			)
			(layer "F.Fab")
		)
		(fp_line
			(start -0.12065 0.2794)
			(end -0.12065 0.3048)
			(stroke
				(width 0.1)
				(type default)
			)
			(layer "F.Fab")
		)
		(fp_line
			(start -0.12065 -0.2794)
			(end 0.12065 -0.2794)
			(stroke
				(width 0.1)
				(type default)
			)
			(layer "F.Fab")
		)
		(fp_line
			(start -0.12065 -0.305054)
			(end -0.12065 -0.2794)
			(stroke
				(width 0.1)
				(type default)
			)
			(layer "F.Fab")
		)
		(fp_line
			(start -0.67945 0.3048)
			(end -0.67945 -0.305054)
			(stroke
				(width 0.1)
				(type default)
			)
			(layer "F.Fab")
		)
		(fp_line
			(start -0.67945 -0.305054)
			(end -0.12065 -0.305054)
			(stroke
				(width 0.1)
				(type default)
			)
			(layer "F.Fab")
		)
		(pad "1" smd circle
			(at -0.40005 0 180)
			(size 0 0)
			(layers "F.Cu" "F.Mask" "F.Paste")
			(net "PVDD11_S3_P1")
		)
		(pad "2" smd circle
			(at 0.40005 0 180)
			(size 0 0)
			(layers "F.Cu" "F.Mask" "F.Paste")
			(net "GND")
		)
	)
	(footprint ""
		(layer "F.Cu")
		(at 16.051784 -394.428726)
		(property "Reference" "PR6622"
			(at 0 0 0)
			(layer "F.SilkS")
			(hide yes)
			(effects
				(font
					(size 1.27 1.27)
				)
			)
		)
		(property "Value" ""
			(at 0 0 0)
			(layer "F.Fab")
			(effects
				(font
					(size 1.27 1.27)
				)
			)
		)
		(duplicate_pad_numbers_are_jumpers no)
		(fp_line
			(start -0.7874 -0.4064)
			(end 0.7874 -0.4064)
			(stroke
				(width 0.1524)
				(type default)
			)
			(layer "F.SilkS")
		)
		(fp_line
			(start -0.7874 0.4064)
			(end -0.7874 -0.4064)
			(stroke
				(width 0.1524)
				(type default)
			)
			(layer "F.SilkS")
		)
		(fp_line
			(start 0.7874 -0.4064)
			(end 0.7874 0.4064)
			(stroke
				(width 0.1524)
				(type default)
			)
			(layer "F.SilkS")
		)
		(fp_line
			(start 0.7874 0.4064)
			(end -0.7874 0.4064)
			(stroke
				(width 0.1524)
				(type default)
			)
			(layer "F.SilkS")
		)
		(fp_line
			(start -0.67945 -0.305054)
			(end -0.12065 -0.305054)
			(stroke
				(width 0.1)
				(type default)
			)
			(layer "F.Fab")
		)
		(fp_line
			(start -0.67945 0.3048)
			(end -0.67945 -0.305054)
			(stroke
				(width 0.1)
				(type default)
			)
			(layer "F.Fab")
		)
		(fp_line
			(start -0.12065 -0.305054)
			(end -0.12065 -0.2794)
			(stroke
				(width 0.1)
				(type default)
			)
			(layer "F.Fab")
		)
		(fp_line
			(start -0.12065 -0.2794)
			(end 0.12065 -0.2794)
			(stroke
				(width 0.1)
				(type default)
			)
			(layer "F.Fab")
		)
		(fp_line
			(start -0.12065 0.2794)
			(end -0.12065 0.3048)
			(stroke
				(width 0.1)
				(type default)
			)
			(layer "F.Fab")
		)
		(fp_line
			(start -0.12065 0.3048)
			(end -0.67945 0.3048)
			(stroke
				(width 0.1)
				(type default)
			)
			(layer "F.Fab")
		)
		(fp_line
			(start 0.120396 0.2794)
			(end -0.12065 0.2794)
			(stroke
				(width 0.1)
				(type default)
			)
			(layer "F.Fab")
		)
		(fp_line
			(start 0.120396 0.3048)
			(end 0.120396 0.2794)
			(stroke
				(width 0.1)
				(type default)
			)
			(layer "F.Fab")
		)
		(fp_line
			(start 0.12065 -0.3048)
			(end 0.67945 -0.3048)
			(stroke
				(width 0.1)
				(type default)
			)
			(layer "F.Fab")
		)
		(fp_line
			(start 0.12065 -0.2794)
			(end 0.12065 -0.3048)
			(stroke
				(width 0.1)
				(type default)
			)
			(layer "F.Fab")
		)
		(fp_line
			(start 0.67945 -0.3048)
			(end 0.67945 0.3048)
			(stroke
				(width 0.1)
				(type default)
			)
			(layer "F.Fab")
		)
		(fp_line
			(start 0.67945 0.3048)
			(end 0.120396 0.3048)
			(stroke
				(width 0.1)
				(type default)
			)
			(layer "F.Fab")
		)
		(pad "1" smd circle
			(at -0.40005 0)
			(size 0 0)
			(layers "F.Cu" "F.Mask" "F.Paste")
			(net "P0V9_RETIMER_CPU1_LSET1")
		)
		(pad "2" smd circle
			(at 0.40005 0)
			(size 0 0)
			(layers "F.Cu" "F.Mask" "F.Paste")
			(net "GND")
		)
	)
	(footprint ""
		(layer "F.Cu")
		(at 434.448204 -103.927402 -90)
		(property "Reference" "PC2089"
			(at 0 0 270)
			(layer "F.SilkS")
			(hide yes)
			(effects
				(font
					(size 1.27 1.27)
				)
			)
		)
		(property "Value" ""
			(at 0 0 270)
			(layer "F.Fab")
			(effects
				(font
					(size 1.27 1.27)
				)
			)
		)
		(duplicate_pad_numbers_are_jumpers no)
		(fp_line
			(start -0.7874 0.4064)
			(end -0.7874 -0.4064)
			(stroke
				(width 0.1524)
				(type default)
			)
			(layer "F.SilkS")
		)
		(fp_line
			(start 0.7874 0.4064)
			(end -0.7874 0.4064)
			(stroke
				(width 0.1524)
				(type default)
			)
			(layer "F.SilkS")
		)
		(fp_line
			(start -0.7874 -0.4064)
			(end 0.7874 -0.4064)
			(stroke
				(width 0.1524)
				(type default)
			)
			(layer "F.SilkS")
		)
		(fp_line
			(start 0.7874 -0.4064)
			(end 0.7874 0.4064)
			(stroke
				(width 0.1524)
				(type default)
			)
			(layer "F.SilkS")
		)
		(fp_line
			(start -0.67945 0.3048)
			(end -0.67945 -0.305054)
			(stroke
				(width 0.1)
				(type default)
			)
			(layer "F.Fab")
		)
		(fp_line
			(start -0.12065 0.3048)
			(end -0.67945 0.3048)
			(stroke
				(width 0.1)
				(type default)
			)
			(layer "F.Fab")
		)
		(fp_line
			(start 0.120396 0.3048)
			(end 0.120396 0.2794)
			(stroke
				(width 0.1)
				(type default)
			)
			(layer "F.Fab")
		)
		(fp_line
			(start 0.67945 0.3048)
			(end 0.120396 0.3048)
			(stroke
				(width 0.1)
				(type default)
			)
			(layer "F.Fab")
		)
		(fp_line
			(start -0.12065 0.2794)
			(end -0.12065 0.3048)
			(stroke
				(width 0.1)
				(type default)
			)
			(layer "F.Fab")
		)
		(fp_line
			(start 0.120396 0.2794)
			(end -0.12065 0.2794)
			(stroke
				(width 0.1)
				(type default)
			)
			(layer "F.Fab")
		)
		(fp_line
			(start -0.12065 -0.2794)
			(end 0.12065 -0.2794)
			(stroke
				(width 0.1)
				(type default)
			)
			(layer "F.Fab")
		)
		(fp_line
			(start 0.12065 -0.2794)
			(end 0.12065 -0.3048)
			(stroke
				(width 0.1)
				(type default)
			)
			(layer "F.Fab")
		)
		(fp_line
			(start 0.12065 -0.3048)
			(end 0.67945 -0.3048)
			(stroke
				(width 0.1)
				(type default)
			)
			(layer "F.Fab")
		)
		(fp_line
			(start 0.67945 -0.3048)
			(end 0.67945 0.3048)
			(stroke
				(width 0.1)
				(type default)
			)
			(layer "F.Fab")
		)
		(fp_line
			(start -0.67945 -0.305054)
			(end -0.12065 -0.305054)
			(stroke
				(width 0.1)
				(type default)
			)
			(layer "F.Fab")
		)
		(fp_line
			(start -0.12065 -0.305054)
			(end -0.12065 -0.2794)
			(stroke
				(width 0.1)
				(type default)
			)
			(layer "F.Fab")
		)
		(pad "1" smd circle
			(at -0.40005 0 270)
			(size 0 0)
			(layers "F.Cu" "F.Mask" "F.Paste")
			(net "P3V3_OCP_GATE_PU202_1")
		)
		(pad "2" smd circle
			(at 0.40005 0 270)
			(size 0 0)
			(layers "F.Cu" "F.Mask" "F.Paste")
			(net "GND")
		)
	)
	(footprint ""
		(layer "F.Cu")
		(at 353.10445 -430.590452 180)
		(property "Reference" "R4560"
			(at 0 0 180)
			(layer "F.SilkS")
			(hide yes)
			(effects
				(font
					(size 1.27 1.27)
				)
			)
		)
		(property "Value" ""
			(at 0 0 180)
			(layer "F.Fab")
			(effects
				(font
					(size 1.27 1.27)
				)
			)
		)
		(duplicate_pad_numbers_are_jumpers no)
		(fp_line
			(start 0.7874 0.4064)
			(end -0.7874 0.4064)
			(stroke
				(width 0.1524)
				(type default)
			)
			(layer "F.SilkS")
		)
		(fp_line
			(start 0.7874 -0.4064)
			(end 0.7874 0.4064)
			(stroke
				(width 0.1524)
				(type default)
			)
			(layer "F.SilkS")
		)
		(fp_line
			(start -0.7874 0.4064)
			(end -0.7874 -0.4064)
			(stroke
				(width 0.1524)
				(type default)
			)
			(layer "F.SilkS")
		)
		(fp_line
			(start -0.7874 -0.4064)
			(end 0.7874 -0.4064)
			(stroke
				(width 0.1524)
				(type default)
			)
			(layer "F.SilkS")
		)
		(fp_line
			(start 0.67945 0.3048)
			(end 0.120396 0.3048)
			(stroke
				(width 0.1)
				(type default)
			)
			(layer "F.Fab")
		)
		(fp_line
			(start 0.67945 -0.3048)
			(end 0.67945 0.3048)
			(stroke
				(width 0.1)
				(type default)
			)
			(layer "F.Fab")
		)
		(fp_line
			(start 0.12065 -0.2794)
			(end 0.12065 -0.3048)
			(stroke
				(width 0.1)
				(type default)
			)
			(layer "F.Fab")
		)
		(fp_line
			(start 0.12065 -0.3048)
			(end 0.67945 -0.3048)
			(stroke
				(width 0.1)
				(type default)
			)
			(layer "F.Fab")
		)
		(fp_line
			(start 0.120396 0.3048)
			(end 0.120396 0.2794)
			(stroke
				(width 0.1)
				(type default)
			)
			(layer "F.Fab")
		)
		(fp_line
			(start 0.120396 0.2794)
			(end -0.12065 0.2794)
			(stroke
				(width 0.1)
				(type default)
			)
			(layer "F.Fab")
		)
		(fp_line
			(start -0.12065 0.3048)
			(end -0.67945 0.3048)
			(stroke
				(width 0.1)
				(type default)
			)
			(layer "F.Fab")
		)
		(fp_line
			(start -0.12065 0.2794)
			(end -0.12065 0.3048)
			(stroke
				(width 0.1)
				(type default)
			)
			(layer "F.Fab")
		)
		(fp_line
			(start -0.12065 -0.2794)
			(end 0.12065 -0.2794)
			(stroke
				(width 0.1)
				(type default)
			)
			(layer "F.Fab")
		)
		(fp_line
			(start -0.12065 -0.305054)
			(end -0.12065 -0.2794)
			(stroke
				(width 0.1)
				(type default)
			)
			(layer "F.Fab")
		)
		(fp_line
			(start -0.67945 0.3048)
			(end -0.67945 -0.305054)
			(stroke
				(width 0.1)
				(type default)
			)
			(layer "F.Fab")
		)
		(fp_line
			(start -0.67945 -0.305054)
			(end -0.12065 -0.305054)
			(stroke
				(width 0.1)
				(type default)
			)
			(layer "F.Fab")
		)
		(pad "1" smd circle
			(at -0.40005 0 180)
			(size 0 0)
			(layers "F.Cu" "F.Mask" "F.Paste")
			(net "P3V3_AUX")
		)
		(pad "2" smd circle
			(at 0.40005 0 180)
			(size 0 0)
			(layers "F.Cu" "F.Mask" "F.Paste")
			(net "SWB_HSC_PWRGD_N")
		)
	)
	(footprint ""
		(layer "F.Cu")
		(at 188.18733 -133.573774 90)
		(property "Reference" "R1553"
			(at 0 0 90)
			(layer "F.SilkS")
			(hide yes)
			(effects
				(font
					(size 1.27 1.27)
				)
			)
		)
		(property "Value" ""
			(at 0 0 90)
			(layer "F.Fab")
			(effects
				(font
					(size 1.27 1.27)
				)
			)
		)
		(duplicate_pad_numbers_are_jumpers no)
		(fp_line
			(start 0.7874 -0.4064)
			(end 0.7874 0.4064)
			(stroke
				(width 0.1524)
				(type default)
			)
			(layer "F.SilkS")
		)
		(fp_line
			(start -0.7874 -0.4064)
			(end 0.7874 -0.4064)
			(stroke
				(width 0.1524)
				(type default)
			)
			(layer "F.SilkS")
		)
		(fp_line
			(start 0.7874 0.4064)
			(end -0.7874 0.4064)
			(stroke
				(width 0.1524)
				(type default)
			)
			(layer "F.SilkS")
		)
		(fp_line
			(start -0.7874 0.4064)
			(end -0.7874 -0.4064)
			(stroke
				(width 0.1524)
				(type default)
			)
			(layer "F.SilkS")
		)
		(fp_line
			(start -0.12065 -0.305054)
			(end -0.12065 -0.2794)
			(stroke
				(width 0.1)
				(type default)
			)
			(layer "F.Fab")
		)
		(fp_line
			(start -0.67945 -0.305054)
			(end -0.12065 -0.305054)
			(stroke
				(width 0.1)
				(type default)
			)
			(layer "F.Fab")
		)
		(fp_line
			(start 0.67945 -0.3048)
			(end 0.67945 0.3048)
			(stroke
				(width 0.1)
				(type default)
			)
			(layer "F.Fab")
		)
		(fp_line
			(start 0.12065 -0.3048)
			(end 0.67945 -0.3048)
			(stroke
				(width 0.1)
				(type default)
			)
			(layer "F.Fab")
		)
		(fp_line
			(start 0.12065 -0.2794)
			(end 0.12065 -0.3048)
			(stroke
				(width 0.1)
				(type default)
			)
			(layer "F.Fab")
		)
		(fp_line
			(start -0.12065 -0.2794)
			(end 0.12065 -0.2794)
			(stroke
				(width 0.1)
				(type default)
			)
			(layer "F.Fab")
		)
		(fp_line
			(start 0.120396 0.2794)
			(end -0.12065 0.2794)
			(stroke
				(width 0.1)
				(type default)
			)
			(layer "F.Fab")
		)
		(fp_line
			(start -0.12065 0.2794)
			(end -0.12065 0.3048)
			(stroke
				(width 0.1)
				(type default)
			)
			(layer "F.Fab")
		)
		(fp_line
			(start 0.67945 0.3048)
			(end 0.120396 0.3048)
			(stroke
				(width 0.1)
				(type default)
			)
			(layer "F.Fab")
		)
		(fp_line
			(start 0.120396 0.3048)
			(end 0.120396 0.2794)
			(stroke
				(width 0.1)
				(type default)
			)
			(layer "F.Fab")
		)
		(fp_line
			(start -0.12065 0.3048)
			(end -0.67945 0.3048)
			(stroke
				(width 0.1)
				(type default)
			)
			(layer "F.Fab")
		)
		(fp_line
			(start -0.67945 0.3048)
			(end -0.67945 -0.305054)
			(stroke
				(width 0.1)
				(type default)
			)
			(layer "F.Fab")
		)
		(pad "1" smd circle
			(at -0.40005 0 90)
			(size 0 0)
			(layers "F.Cu" "F.Mask" "F.Paste")
			(net "ESPI_CPU0_CS1_R_N")
		)
		(pad "2" smd circle
			(at 0.40005 0 90)
			(size 0 0)
			(layers "F.Cu" "F.Mask" "F.Paste")
			(net "ESPI_CPU0_CS1_N")
		)
	)
	(footprint ""
		(layer "F.Cu")
		(at 96.0628 -418.846 180)
		(property "Reference" "R1455"
			(at 0 0 180)
			(layer "F.SilkS")
			(hide yes)
			(effects
				(font
					(size 1.27 1.27)
				)
			)
		)
		(property "Value" ""
			(at 0 0 180)
			(layer "F.Fab")
			(effects
				(font
					(size 1.27 1.27)
				)
			)
		)
		(duplicate_pad_numbers_are_jumpers no)
		(fp_line
			(start 0.32512 0.175006)
			(end -0.32512 0.175006)
			(stroke
				(width 0.1)
				(type default)
			)
			(layer "F.Fab")
		)
		(fp_line
			(start 0.32512 -0.175006)
			(end 0.32512 0.175006)
			(stroke
				(width 0.1)
				(type default)
			)
			(layer "F.Fab")
		)
		(fp_line
			(start -0.32512 0.175006)
			(end -0.32512 -0.175006)
			(stroke
				(width 0.1)
				(type default)
			)
			(layer "F.Fab")
		)
		(fp_line
			(start -0.32512 -0.175006)
			(end 0.32512 -0.175006)
			(stroke
				(width 0.1)
				(type default)
			)
			(layer "F.Fab")
		)
		(pad "1" smd rect
			(at -0.2667 0 180)
			(size 0.3048 0.381)
			(layers "F.Cu" "F.Mask" "F.Paste")
			(net "P1V8_CPU1_RT_1D")
		)
		(pad "2" smd rect
			(at 0.2667 0)
			(size 0.3048 0.381)
			(layers "F.Cu" "F.Mask" "F.Paste")
			(net "JTAG_TMS_RT_CPU1_P1")
		)
	)
	(footprint ""
		(layer "F.Cu")
		(at 30.315662 -429.759364 90)
		(property "Reference" "R3281"
			(at 0 0 90)
			(layer "F.SilkS")
			(hide yes)
			(effects
				(font
					(size 1.27 1.27)
				)
			)
		)
		(property "Value" ""
			(at 0 0 90)
			(layer "F.Fab")
			(effects
				(font
					(size 1.27 1.27)
				)
			)
		)
		(duplicate_pad_numbers_are_jumpers no)
		(fp_line
			(start 0.7874 -0.4064)
			(end 0.7874 0.4064)
			(stroke
				(width 0.1524)
				(type default)
			)
			(layer "F.SilkS")
		)
		(fp_line
			(start -0.7874 -0.4064)
			(end 0.7874 -0.4064)
			(stroke
				(width 0.1524)
				(type default)
			)
			(layer "F.SilkS")
		)
		(fp_line
			(start 0.7874 0.4064)
			(end -0.7874 0.4064)
			(stroke
				(width 0.1524)
				(type default)
			)
			(layer "F.SilkS")
		)
		(fp_line
			(start -0.7874 0.4064)
			(end -0.7874 -0.4064)
			(stroke
				(width 0.1524)
				(type default)
			)
			(layer "F.SilkS")
		)
		(fp_line
			(start -0.12065 -0.305054)
			(end -0.12065 -0.2794)
			(stroke
				(width 0.1)
				(type default)
			)
			(layer "F.Fab")
		)
		(fp_line
			(start -0.67945 -0.305054)
			(end -0.12065 -0.305054)
			(stroke
				(width 0.1)
				(type default)
			)
			(layer "F.Fab")
		)
		(fp_line
			(start 0.67945 -0.3048)
			(end 0.67945 0.3048)
			(stroke
				(width 0.1)
				(type default)
			)
			(layer "F.Fab")
		)
		(fp_line
			(start 0.12065 -0.3048)
			(end 0.67945 -0.3048)
			(stroke
				(width 0.1)
				(type default)
			)
			(layer "F.Fab")
		)
		(fp_line
			(start 0.12065 -0.2794)
			(end 0.12065 -0.3048)
			(stroke
				(width 0.1)
				(type default)
			)
			(layer "F.Fab")
		)
		(fp_line
			(start -0.12065 -0.2794)
			(end 0.12065 -0.2794)
			(stroke
				(width 0.1)
				(type default)
			)
			(layer "F.Fab")
		)
		(fp_line
			(start 0.120396 0.2794)
			(end -0.12065 0.2794)
			(stroke
				(width 0.1)
				(type default)
			)
			(layer "F.Fab")
		)
		(fp_line
			(start -0.12065 0.2794)
			(end -0.12065 0.3048)
			(stroke
				(width 0.1)
				(type default)
			)
			(layer "F.Fab")
		)
		(fp_line
			(start 0.67945 0.3048)
			(end 0.120396 0.3048)
			(stroke
				(width 0.1)
				(type default)
			)
			(layer "F.Fab")
		)
		(fp_line
			(start 0.120396 0.3048)
			(end 0.120396 0.2794)
			(stroke
				(width 0.1)
				(type default)
			)
			(layer "F.Fab")
		)
		(fp_line
			(start -0.12065 0.3048)
			(end -0.67945 0.3048)
			(stroke
				(width 0.1)
				(type default)
			)
			(layer "F.Fab")
		)
		(fp_line
			(start -0.67945 0.3048)
			(end -0.67945 -0.305054)
			(stroke
				(width 0.1)
				(type default)
			)
			(layer "F.Fab")
		)
		(pad "1" smd circle
			(at -0.40005 0 90)
			(size 0 0)
			(layers "F.Cu" "F.Mask" "F.Paste")
			(net "FM_P2E_EQB1")
		)
		(pad "2" smd circle
			(at 0.40005 0 90)
			(size 0 0)
			(layers "F.Cu" "F.Mask" "F.Paste")
			(net "GND")
		)
	)
	(footprint ""
		(layer "F.Cu")
		(at 167.79621 -395.6304 -90)
		(property "Reference" "R854"
			(at 0 0 270)
			(layer "F.SilkS")
			(hide yes)
			(effects
				(font
					(size 1.27 1.27)
				)
			)
		)
		(property "Value" ""
			(at 0 0 270)
			(layer "F.Fab")
			(effects
				(font
					(size 1.27 1.27)
				)
			)
		)
		(duplicate_pad_numbers_are_jumpers no)
		(fp_line
			(start -0.32512 0.175006)
			(end -0.32512 -0.175006)
			(stroke
				(width 0.1)
				(type default)
			)
			(layer "F.Fab")
		)
		(fp_line
			(start 0.32512 0.175006)
			(end -0.32512 0.175006)
			(stroke
				(width 0.1)
				(type default)
			)
			(layer "F.Fab")
		)
		(fp_line
			(start -0.32512 -0.175006)
			(end 0.32512 -0.175006)
			(stroke
				(width 0.1)
				(type default)
			)
			(layer "F.Fab")
		)
		(fp_line
			(start 0.32512 -0.175006)
			(end 0.32512 0.175006)
			(stroke
				(width 0.1)
				(type default)
			)
			(layer "F.Fab")
		)
		(pad "1" smd rect
			(at -0.2667 0 270)
			(size 0.3048 0.381)
			(layers "F.Cu" "F.Mask" "F.Paste")
			(net "RST_RT_CPU1_P2_PERST_N")
		)
		(pad "2" smd rect
			(at 0.2667 0 90)
			(size 0.3048 0.381)
			(layers "F.Cu" "F.Mask" "F.Paste")
			(net "RST_RT_CPU1_P2_PERST_R_N")
		)
	)
	(footprint ""
		(layer "F.Cu")
		(at 302.241458 -109.779308 180)
		(property "Reference" "R54"
			(at 0 0 180)
			(layer "F.SilkS")
			(hide yes)
			(effects
				(font
					(size 1.27 1.27)
				)
			)
		)
		(property "Value" ""
			(at 0 0 180)
			(layer "F.Fab")
			(effects
				(font
					(size 1.27 1.27)
				)
			)
		)
		(duplicate_pad_numbers_are_jumpers no)
		(fp_line
			(start 0.7874 0.4064)
			(end -0.7874 0.4064)
			(stroke
				(width 0.1524)
				(type default)
			)
			(layer "F.SilkS")
		)
		(fp_line
			(start 0.7874 -0.4064)
			(end 0.7874 0.4064)
			(stroke
				(width 0.1524)
				(type default)
			)
			(layer "F.SilkS")
		)
		(fp_line
			(start -0.7874 0.4064)
			(end -0.7874 -0.4064)
			(stroke
				(width 0.1524)
				(type default)
			)
			(layer "F.SilkS")
		)
		(fp_line
			(start -0.7874 -0.4064)
			(end 0.7874 -0.4064)
			(stroke
				(width 0.1524)
				(type default)
			)
			(layer "F.SilkS")
		)
		(fp_line
			(start 0.67945 0.3048)
			(end 0.120396 0.3048)
			(stroke
				(width 0.1)
				(type default)
			)
			(layer "F.Fab")
		)
		(fp_line
			(start 0.67945 -0.3048)
			(end 0.67945 0.3048)
			(stroke
				(width 0.1)
				(type default)
			)
			(layer "F.Fab")
		)
		(fp_line
			(start 0.12065 -0.2794)
			(end 0.12065 -0.3048)
			(stroke
				(width 0.1)
				(type default)
			)
			(layer "F.Fab")
		)
		(fp_line
			(start 0.12065 -0.3048)
			(end 0.67945 -0.3048)
			(stroke
				(width 0.1)
				(type default)
			)
			(layer "F.Fab")
		)
		(fp_line
			(start 0.120396 0.3048)
			(end 0.120396 0.2794)
			(stroke
				(width 0.1)
				(type default)
			)
			(layer "F.Fab")
		)
		(fp_line
			(start 0.120396 0.2794)
			(end -0.12065 0.2794)
			(stroke
				(width 0.1)
				(type default)
			)
			(layer "F.Fab")
		)
		(fp_line
			(start -0.12065 0.3048)
			(end -0.67945 0.3048)
			(stroke
				(width 0.1)
				(type default)
			)
			(layer "F.Fab")
		)
		(fp_line
			(start -0.12065 0.2794)
			(end -0.12065 0.3048)
			(stroke
				(width 0.1)
				(type default)
			)
			(layer "F.Fab")
		)
		(fp_line
			(start -0.12065 -0.2794)
			(end 0.12065 -0.2794)
			(stroke
				(width 0.1)
				(type default)
			)
			(layer "F.Fab")
		)
		(fp_line
			(start -0.12065 -0.305054)
			(end -0.12065 -0.2794)
			(stroke
				(width 0.1)
				(type default)
			)
			(layer "F.Fab")
		)
		(fp_line
			(start -0.67945 0.3048)
			(end -0.67945 -0.305054)
			(stroke
				(width 0.1)
				(type default)
			)
			(layer "F.Fab")
		)
		(fp_line
			(start -0.67945 -0.305054)
			(end -0.12065 -0.305054)
			(stroke
				(width 0.1)
				(type default)
			)
			(layer "F.Fab")
		)
		(pad "1" smd circle
			(at -0.40005 0 180)
			(size 0 0)
			(layers "F.Cu" "F.Mask" "F.Paste")
			(net "CPU_FRU_ADDR2")
		)
		(pad "2" smd circle
			(at 0.40005 0 180)
			(size 0 0)
			(layers "F.Cu" "F.Mask" "F.Paste")
			(net "GND")
		)
	)
	(footprint ""
		(layer "F.Cu")
		(at 380.318772 -178.0921 -90)
		(property "Reference" "PR348"
			(at 0 0 270)
			(layer "F.SilkS")
			(hide yes)
			(effects
				(font
					(size 1.27 1.27)
				)
			)
		)
		(property "Value" ""
			(at 0 0 270)
			(layer "F.Fab")
			(effects
				(font
					(size 1.27 1.27)
				)
			)
		)
		(duplicate_pad_numbers_are_jumpers no)
		(fp_line
			(start -0.7874 0.4064)
			(end -0.7874 -0.4064)
			(stroke
				(width 0.1524)
				(type default)
			)
			(layer "F.SilkS")
		)
		(fp_line
			(start 0.7874 0.4064)
			(end -0.7874 0.4064)
			(stroke
				(width 0.1524)
				(type default)
			)
			(layer "F.SilkS")
		)
		(fp_line
			(start -0.7874 -0.4064)
			(end 0.7874 -0.4064)
			(stroke
				(width 0.1524)
				(type default)
			)
			(layer "F.SilkS")
		)
		(fp_line
			(start 0.7874 -0.4064)
			(end 0.7874 0.4064)
			(stroke
				(width 0.1524)
				(type default)
			)
			(layer "F.SilkS")
		)
		(fp_line
			(start -0.67945 0.3048)
			(end -0.67945 -0.305054)
			(stroke
				(width 0.1)
				(type default)
			)
			(layer "F.Fab")
		)
		(fp_line
			(start -0.12065 0.3048)
			(end -0.67945 0.3048)
			(stroke
				(width 0.1)
				(type default)
			)
			(layer "F.Fab")
		)
		(fp_line
			(start 0.120396 0.3048)
			(end 0.120396 0.2794)
			(stroke
				(width 0.1)
				(type default)
			)
			(layer "F.Fab")
		)
		(fp_line
			(start 0.67945 0.3048)
			(end 0.120396 0.3048)
			(stroke
				(width 0.1)
				(type default)
			)
			(layer "F.Fab")
		)
		(fp_line
			(start -0.12065 0.2794)
			(end -0.12065 0.3048)
			(stroke
				(width 0.1)
				(type default)
			)
			(layer "F.Fab")
		)
		(fp_line
			(start 0.120396 0.2794)
			(end -0.12065 0.2794)
			(stroke
				(width 0.1)
				(type default)
			)
			(layer "F.Fab")
		)
		(fp_line
			(start -0.12065 -0.2794)
			(end 0.12065 -0.2794)
			(stroke
				(width 0.1)
				(type default)
			)
			(layer "F.Fab")
		)
		(fp_line
			(start 0.12065 -0.2794)
			(end 0.12065 -0.3048)
			(stroke
				(width 0.1)
				(type default)
			)
			(layer "F.Fab")
		)
		(fp_line
			(start 0.12065 -0.3048)
			(end 0.67945 -0.3048)
			(stroke
				(width 0.1)
				(type default)
			)
			(layer "F.Fab")
		)
		(fp_line
			(start 0.67945 -0.3048)
			(end 0.67945 0.3048)
			(stroke
				(width 0.1)
				(type default)
			)
			(layer "F.Fab")
		)
		(fp_line
			(start -0.67945 -0.305054)
			(end -0.12065 -0.305054)
			(stroke
				(width 0.1)
				(type default)
			)
			(layer "F.Fab")
		)
		(fp_line
			(start -0.12065 -0.305054)
			(end -0.12065 -0.2794)
			(stroke
				(width 0.1)
				(type default)
			)
			(layer "F.Fab")
		)
		(pad "1" smd circle
			(at -0.40005 0 270)
			(size 0 0)
			(layers "F.Cu" "F.Mask" "F.Paste")
			(net "SW_PVDDCR_CPU0_P0_BOOT3")
		)
		(pad "2" smd circle
			(at 0.40005 0 270)
			(size 0 0)
			(layers "F.Cu" "F.Mask" "F.Paste")
			(net "SW_PVDDCR_CPU0_P0_BOOT3_RC")
		)
	)
	(footprint ""
		(layer "F.Cu")
		(at 103.145844 -394.68806 90)
		(property "Reference" "R6706"
			(at 0 0 90)
			(layer "F.SilkS")
			(hide yes)
			(effects
				(font
					(size 1.27 1.27)
				)
			)
		)
		(property "Value" ""
			(at 0 0 90)
			(layer "F.Fab")
			(effects
				(font
					(size 1.27 1.27)
				)
			)
		)
		(duplicate_pad_numbers_are_jumpers no)
		(fp_line
			(start 0.32512 -0.175006)
			(end 0.32512 0.175006)
			(stroke
				(width 0.1)
				(type default)
			)
			(layer "F.Fab")
		)
		(fp_line
			(start -0.32512 -0.175006)
			(end 0.32512 -0.175006)
			(stroke
				(width 0.1)
				(type default)
			)
			(layer "F.Fab")
		)
		(fp_line
			(start 0.32512 0.175006)
			(end -0.32512 0.175006)
			(stroke
				(width 0.1)
				(type default)
			)
			(layer "F.Fab")
		)
		(fp_line
			(start -0.32512 0.175006)
			(end -0.32512 -0.175006)
			(stroke
				(width 0.1)
				(type default)
			)
			(layer "F.Fab")
		)
		(pad "1" smd rect
			(at -0.2667 0 90)
			(size 0.3048 0.381)
			(layers "F.Cu" "F.Mask" "F.Paste")
			(net "P1V8_CPU1_RT_1D")
		)
		(pad "2" smd rect
			(at 0.2667 0 270)
			(size 0.3048 0.381)
			(layers "F.Cu" "F.Mask" "F.Paste")
			(net "SMB_RT_CPU1_P0_ROM_R_SCL")
		)
	)
	(footprint ""
		(layer "F.Cu")
		(at 104.469946 -52.86248 90)
		(property "Reference" "R6318"
			(at 0 0 90)
			(layer "F.SilkS")
			(hide yes)
			(effects
				(font
					(size 1.27 1.27)
				)
			)
		)
		(property "Value" ""
			(at 0 0 90)
			(layer "F.Fab")
			(effects
				(font
					(size 1.27 1.27)
				)
			)
		)
		(duplicate_pad_numbers_are_jumpers no)
		(fp_line
			(start 0.7874 -0.4064)
			(end 0.7874 0.4064)
			(stroke
				(width 0.1524)
				(type default)
			)
			(layer "F.SilkS")
		)
		(fp_line
			(start -0.7874 -0.4064)
			(end 0.7874 -0.4064)
			(stroke
				(width 0.1524)
				(type default)
			)
			(layer "F.SilkS")
		)
		(fp_line
			(start 0.7874 0.4064)
			(end -0.7874 0.4064)
			(stroke
				(width 0.1524)
				(type default)
			)
			(layer "F.SilkS")
		)
		(fp_line
			(start -0.7874 0.4064)
			(end -0.7874 -0.4064)
			(stroke
				(width 0.1524)
				(type default)
			)
			(layer "F.SilkS")
		)
		(fp_line
			(start -0.12065 -0.305054)
			(end -0.12065 -0.2794)
			(stroke
				(width 0.1)
				(type default)
			)
			(layer "F.Fab")
		)
		(fp_line
			(start -0.67945 -0.305054)
			(end -0.12065 -0.305054)
			(stroke
				(width 0.1)
				(type default)
			)
			(layer "F.Fab")
		)
		(fp_line
			(start 0.67945 -0.3048)
			(end 0.67945 0.3048)
			(stroke
				(width 0.1)
				(type default)
			)
			(layer "F.Fab")
		)
		(fp_line
			(start 0.12065 -0.3048)
			(end 0.67945 -0.3048)
			(stroke
				(width 0.1)
				(type default)
			)
			(layer "F.Fab")
		)
		(fp_line
			(start 0.12065 -0.2794)
			(end 0.12065 -0.3048)
			(stroke
				(width 0.1)
				(type default)
			)
			(layer "F.Fab")
		)
		(fp_line
			(start -0.12065 -0.2794)
			(end 0.12065 -0.2794)
			(stroke
				(width 0.1)
				(type default)
			)
			(layer "F.Fab")
		)
		(fp_line
			(start 0.120396 0.2794)
			(end -0.12065 0.2794)
			(stroke
				(width 0.1)
				(type default)
			)
			(layer "F.Fab")
		)
		(fp_line
			(start -0.12065 0.2794)
			(end -0.12065 0.3048)
			(stroke
				(width 0.1)
				(type default)
			)
			(layer "F.Fab")
		)
		(fp_line
			(start 0.67945 0.3048)
			(end 0.120396 0.3048)
			(stroke
				(width 0.1)
				(type default)
			)
			(layer "F.Fab")
		)
		(fp_line
			(start 0.120396 0.3048)
			(end 0.120396 0.2794)
			(stroke
				(width 0.1)
				(type default)
			)
			(layer "F.Fab")
		)
		(fp_line
			(start -0.12065 0.3048)
			(end -0.67945 0.3048)
			(stroke
				(width 0.1)
				(type default)
			)
			(layer "F.Fab")
		)
		(fp_line
			(start -0.67945 0.3048)
			(end -0.67945 -0.305054)
			(stroke
				(width 0.1)
				(type default)
			)
			(layer "F.Fab")
		)
		(pad "1" smd circle
			(at -0.40005 0 90)
			(size 0 0)
			(layers "F.Cu" "F.Mask" "F.Paste")
			(net "P5V_AUX")
		)
		(pad "2" smd circle
			(at 0.40005 0 90)
			(size 0 0)
			(layers "F.Cu" "F.Mask" "F.Paste")
			(net "USB_HUB2_TI_USB_VBUS")
		)
	)
	(footprint ""
		(layer "F.Cu")
		(at 223.266 -82.804 180)
		(property "Reference" "R8099"
			(at 0 0 180)
			(layer "F.SilkS")
			(hide yes)
			(effects
				(font
					(size 1.27 1.27)
				)
			)
		)
		(property "Value" ""
			(at 0 0 180)
			(layer "F.Fab")
			(effects
				(font
					(size 1.27 1.27)
				)
			)
		)
		(duplicate_pad_numbers_are_jumpers no)
		(fp_line
			(start 0.7874 0.4064)
			(end -0.7874 0.4064)
			(stroke
				(width 0.1524)
				(type default)
			)
			(layer "F.SilkS")
		)
		(fp_line
			(start 0.7874 -0.4064)
			(end 0.7874 0.4064)
			(stroke
				(width 0.1524)
				(type default)
			)
			(layer "F.SilkS")
		)
		(fp_line
			(start -0.7874 0.4064)
			(end -0.7874 -0.4064)
			(stroke
				(width 0.1524)
				(type default)
			)
			(layer "F.SilkS")
		)
		(fp_line
			(start -0.7874 -0.4064)
			(end 0.7874 -0.4064)
			(stroke
				(width 0.1524)
				(type default)
			)
			(layer "F.SilkS")
		)
		(fp_line
			(start 0.67945 0.3048)
			(end 0.120396 0.3048)
			(stroke
				(width 0.1)
				(type default)
			)
			(layer "F.Fab")
		)
		(fp_line
			(start 0.67945 -0.3048)
			(end 0.67945 0.3048)
			(stroke
				(width 0.1)
				(type default)
			)
			(layer "F.Fab")
		)
		(fp_line
			(start 0.12065 -0.2794)
			(end 0.12065 -0.3048)
			(stroke
				(width 0.1)
				(type default)
			)
			(layer "F.Fab")
		)
		(fp_line
			(start 0.12065 -0.3048)
			(end 0.67945 -0.3048)
			(stroke
				(width 0.1)
				(type default)
			)
			(layer "F.Fab")
		)
		(fp_line
			(start 0.120396 0.3048)
			(end 0.120396 0.2794)
			(stroke
				(width 0.1)
				(type default)
			)
			(layer "F.Fab")
		)
		(fp_line
			(start 0.120396 0.2794)
			(end -0.12065 0.2794)
			(stroke
				(width 0.1)
				(type default)
			)
			(layer "F.Fab")
		)
		(fp_line
			(start -0.12065 0.3048)
			(end -0.67945 0.3048)
			(stroke
				(width 0.1)
				(type default)
			)
			(layer "F.Fab")
		)
		(fp_line
			(start -0.12065 0.2794)
			(end -0.12065 0.3048)
			(stroke
				(width 0.1)
				(type default)
			)
			(layer "F.Fab")
		)
		(fp_line
			(start -0.12065 -0.2794)
			(end 0.12065 -0.2794)
			(stroke
				(width 0.1)
				(type default)
			)
			(layer "F.Fab")
		)
		(fp_line
			(start -0.12065 -0.305054)
			(end -0.12065 -0.2794)
			(stroke
				(width 0.1)
				(type default)
			)
			(layer "F.Fab")
		)
		(fp_line
			(start -0.67945 0.3048)
			(end -0.67945 -0.305054)
			(stroke
				(width 0.1)
				(type default)
			)
			(layer "F.Fab")
		)
		(fp_line
			(start -0.67945 -0.305054)
			(end -0.12065 -0.305054)
			(stroke
				(width 0.1)
				(type default)
			)
			(layer "F.Fab")
		)
		(pad "1" smd circle
			(at -0.40005 0 180)
			(size 0 0)
			(layers "F.Cu" "F.Mask" "F.Paste")
			(net "P3V3_E1S_PWRGD_0_R1")
		)
		(pad "2" smd circle
			(at 0.40005 0 180)
			(size 0 0)
			(layers "F.Cu" "F.Mask" "F.Paste")
			(net "GND")
		)
	)
	(footprint ""
		(layer "F.Cu")
		(at 190.881 -100.294948 90)
		(property "Reference" "R263"
			(at 0 0 90)
			(layer "F.SilkS")
			(hide yes)
			(effects
				(font
					(size 1.27 1.27)
				)
			)
		)
		(property "Value" ""
			(at 0 0 90)
			(layer "F.Fab")
			(effects
				(font
					(size 1.27 1.27)
				)
			)
		)
		(duplicate_pad_numbers_are_jumpers no)
		(fp_line
			(start 0.7874 -0.4064)
			(end 0.7874 0.4064)
			(stroke
				(width 0.1524)
				(type default)
			)
			(layer "F.SilkS")
		)
		(fp_line
			(start -0.7874 -0.4064)
			(end 0.7874 -0.4064)
			(stroke
				(width 0.1524)
				(type default)
			)
			(layer "F.SilkS")
		)
		(fp_line
			(start 0.7874 0.4064)
			(end -0.7874 0.4064)
			(stroke
				(width 0.1524)
				(type default)
			)
			(layer "F.SilkS")
		)
		(fp_line
			(start -0.7874 0.4064)
			(end -0.7874 -0.4064)
			(stroke
				(width 0.1524)
				(type default)
			)
			(layer "F.SilkS")
		)
		(fp_line
			(start -0.12065 -0.305054)
			(end -0.12065 -0.2794)
			(stroke
				(width 0.1)
				(type default)
			)
			(layer "F.Fab")
		)
		(fp_line
			(start -0.67945 -0.305054)
			(end -0.12065 -0.305054)
			(stroke
				(width 0.1)
				(type default)
			)
			(layer "F.Fab")
		)
		(fp_line
			(start 0.67945 -0.3048)
			(end 0.67945 0.3048)
			(stroke
				(width 0.1)
				(type default)
			)
			(layer "F.Fab")
		)
		(fp_line
			(start 0.12065 -0.3048)
			(end 0.67945 -0.3048)
			(stroke
				(width 0.1)
				(type default)
			)
			(layer "F.Fab")
		)
		(fp_line
			(start 0.12065 -0.2794)
			(end 0.12065 -0.3048)
			(stroke
				(width 0.1)
				(type default)
			)
			(layer "F.Fab")
		)
		(fp_line
			(start -0.12065 -0.2794)
			(end 0.12065 -0.2794)
			(stroke
				(width 0.1)
				(type default)
			)
			(layer "F.Fab")
		)
		(fp_line
			(start 0.120396 0.2794)
			(end -0.12065 0.2794)
			(stroke
				(width 0.1)
				(type default)
			)
			(layer "F.Fab")
		)
		(fp_line
			(start -0.12065 0.2794)
			(end -0.12065 0.3048)
			(stroke
				(width 0.1)
				(type default)
			)
			(layer "F.Fab")
		)
		(fp_line
			(start 0.67945 0.3048)
			(end 0.120396 0.3048)
			(stroke
				(width 0.1)
				(type default)
			)
			(layer "F.Fab")
		)
		(fp_line
			(start 0.120396 0.3048)
			(end 0.120396 0.2794)
			(stroke
				(width 0.1)
				(type default)
			)
			(layer "F.Fab")
		)
		(fp_line
			(start -0.12065 0.3048)
			(end -0.67945 0.3048)
			(stroke
				(width 0.1)
				(type default)
			)
			(layer "F.Fab")
		)
		(fp_line
			(start -0.67945 0.3048)
			(end -0.67945 -0.305054)
			(stroke
				(width 0.1)
				(type default)
			)
			(layer "F.Fab")
		)
		(pad "1" smd circle
			(at -0.40005 0 90)
			(size 0 0)
			(layers "F.Cu" "F.Mask" "F.Paste")
			(net "CPU1_CORETYPE1")
		)
		(pad "2" smd circle
			(at 0.40005 0 90)
			(size 0 0)
			(layers "F.Cu" "F.Mask" "F.Paste")
			(net "FM_CPU1_CORETYPE1")
		)
	)
	(footprint ""
		(layer "F.Cu")
		(at 429.87341 -423.60596 90)
		(property "Reference" "R6247"
			(at 0 0 90)
			(layer "F.SilkS")
			(hide yes)
			(effects
				(font
					(size 1.27 1.27)
				)
			)
		)
		(property "Value" ""
			(at 0 0 90)
			(layer "F.Fab")
			(effects
				(font
					(size 1.27 1.27)
				)
			)
		)
		(duplicate_pad_numbers_are_jumpers no)
		(fp_line
			(start 0.7874 -0.4064)
			(end 0.7874 0.4064)
			(stroke
				(width 0.1524)
				(type default)
			)
			(layer "F.SilkS")
		)
		(fp_line
			(start -0.7874 -0.4064)
			(end 0.7874 -0.4064)
			(stroke
				(width 0.1524)
				(type default)
			)
			(layer "F.SilkS")
		)
		(fp_line
			(start 0.7874 0.4064)
			(end -0.7874 0.4064)
			(stroke
				(width 0.1524)
				(type default)
			)
			(layer "F.SilkS")
		)
		(fp_line
			(start -0.7874 0.4064)
			(end -0.7874 -0.4064)
			(stroke
				(width 0.1524)
				(type default)
			)
			(layer "F.SilkS")
		)
		(fp_line
			(start -0.12065 -0.305054)
			(end -0.12065 -0.2794)
			(stroke
				(width 0.1)
				(type default)
			)
			(layer "F.Fab")
		)
		(fp_line
			(start -0.67945 -0.305054)
			(end -0.12065 -0.305054)
			(stroke
				(width 0.1)
				(type default)
			)
			(layer "F.Fab")
		)
		(fp_line
			(start 0.67945 -0.3048)
			(end 0.67945 0.3048)
			(stroke
				(width 0.1)
				(type default)
			)
			(layer "F.Fab")
		)
		(fp_line
			(start 0.12065 -0.3048)
			(end 0.67945 -0.3048)
			(stroke
				(width 0.1)
				(type default)
			)
			(layer "F.Fab")
		)
		(fp_line
			(start 0.12065 -0.2794)
			(end 0.12065 -0.3048)
			(stroke
				(width 0.1)
				(type default)
			)
			(layer "F.Fab")
		)
		(fp_line
			(start -0.12065 -0.2794)
			(end 0.12065 -0.2794)
			(stroke
				(width 0.1)
				(type default)
			)
			(layer "F.Fab")
		)
		(fp_line
			(start 0.120396 0.2794)
			(end -0.12065 0.2794)
			(stroke
				(width 0.1)
				(type default)
			)
			(layer "F.Fab")
		)
		(fp_line
			(start -0.12065 0.2794)
			(end -0.12065 0.3048)
			(stroke
				(width 0.1)
				(type default)
			)
			(layer "F.Fab")
		)
		(fp_line
			(start 0.67945 0.3048)
			(end 0.120396 0.3048)
			(stroke
				(width 0.1)
				(type default)
			)
			(layer "F.Fab")
		)
		(fp_line
			(start 0.120396 0.3048)
			(end 0.120396 0.2794)
			(stroke
				(width 0.1)
				(type default)
			)
			(layer "F.Fab")
		)
		(fp_line
			(start -0.12065 0.3048)
			(end -0.67945 0.3048)
			(stroke
				(width 0.1)
				(type default)
			)
			(layer "F.Fab")
		)
		(fp_line
			(start -0.67945 0.3048)
			(end -0.67945 -0.305054)
			(stroke
				(width 0.1)
				(type default)
			)
			(layer "F.Fab")
		)
		(pad "1" smd circle
			(at -0.40005 0 90)
			(size 0 0)
			(layers "F.Cu" "F.Mask" "F.Paste")
			(net "P3V3_AUX")
		)
		(pad "2" smd circle
			(at 0.40005 0 90)
			(size 0 0)
			(layers "F.Cu" "F.Mask" "F.Paste")
			(net "HSC_TYPE_ADC_ALERT")
		)
	)
	(footprint ""
		(layer "F.Cu")
		(at 448.051682 -53.20411 90)
		(property "Reference" "PC2342"
			(at 0 0 90)
			(layer "F.SilkS")
			(hide yes)
			(effects
				(font
					(size 1.27 1.27)
				)
			)
		)
		(property "Value" ""
			(at 0 0 90)
			(layer "F.Fab")
			(effects
				(font
					(size 1.27 1.27)
				)
			)
		)
		(duplicate_pad_numbers_are_jumpers no)
		(fp_line
			(start 1.524 -0.762)
			(end 1.524 0.762)
			(stroke
				(width 0.1524)
				(type default)
			)
			(layer "F.SilkS")
		)
		(fp_line
			(start -1.524 -0.762)
			(end 1.524 -0.762)
			(stroke
				(width 0.1524)
				(type default)
			)
			(layer "F.SilkS")
		)
		(fp_line
			(start 1.524 0.762)
			(end -1.524 0.762)
			(stroke
				(width 0.1524)
				(type default)
			)
			(layer "F.SilkS")
		)
		(fp_line
			(start -1.524 0.762)
			(end -1.524 -0.762)
			(stroke
				(width 0.1524)
				(type default)
			)
			(layer "F.SilkS")
		)
		(fp_line
			(start 1.1049 -0.724916)
			(end -1.1049 -0.724916)
			(stroke
				(width 0.1)
				(type default)
			)
			(layer "F.Fab")
		)
		(fp_line
			(start -1.1049 -0.724916)
			(end -1.1049 0.724916)
			(stroke
				(width 0.1)
				(type default)
			)
			(layer "F.Fab")
		)
		(fp_line
			(start 1.1049 0.724916)
			(end 1.1049 -0.724916)
			(stroke
				(width 0.1)
				(type default)
			)
			(layer "F.Fab")
		)
		(fp_line
			(start -1.1049 0.724916)
			(end 1.1049 0.724916)
			(stroke
				(width 0.1)
				(type default)
			)
			(layer "F.Fab")
		)
		(pad "1" smd rect
			(at -0.889 0 270)
			(size 1.016 1.27)
			(layers "F.Cu" "F.Mask" "F.Paste")
			(net "SW_P3V3_AUX_FLT")
		)
		(pad "2" smd rect
			(at 0.889 0 270)
			(size 1.016 1.27)
			(layers "F.Cu" "F.Mask" "F.Paste")
			(net "GND")
		)
	)
	(footprint ""
		(layer "F.Cu")
		(at 36.319968 -135.889238 180)
		(property "Reference" "R3327"
			(at 0 0 180)
			(layer "F.SilkS")
			(hide yes)
			(effects
				(font
					(size 1.27 1.27)
				)
			)
		)
		(property "Value" ""
			(at 0 0 180)
			(layer "F.Fab")
			(effects
				(font
					(size 1.27 1.27)
				)
			)
		)
		(duplicate_pad_numbers_are_jumpers no)
		(fp_line
			(start 0.7874 0.4064)
			(end -0.7874 0.4064)
			(stroke
				(width 0.1524)
				(type default)
			)
			(layer "F.SilkS")
		)
		(fp_line
			(start 0.7874 -0.4064)
			(end 0.7874 0.4064)
			(stroke
				(width 0.1524)
				(type default)
			)
			(layer "F.SilkS")
		)
		(fp_line
			(start -0.7874 0.4064)
			(end -0.7874 -0.4064)
			(stroke
				(width 0.1524)
				(type default)
			)
			(layer "F.SilkS")
		)
		(fp_line
			(start -0.7874 -0.4064)
			(end 0.7874 -0.4064)
			(stroke
				(width 0.1524)
				(type default)
			)
			(layer "F.SilkS")
		)
		(fp_line
			(start 0.67945 0.3048)
			(end 0.120396 0.3048)
			(stroke
				(width 0.1)
				(type default)
			)
			(layer "F.Fab")
		)
		(fp_line
			(start 0.67945 -0.3048)
			(end 0.67945 0.3048)
			(stroke
				(width 0.1)
				(type default)
			)
			(layer "F.Fab")
		)
		(fp_line
			(start 0.12065 -0.2794)
			(end 0.12065 -0.3048)
			(stroke
				(width 0.1)
				(type default)
			)
			(layer "F.Fab")
		)
		(fp_line
			(start 0.12065 -0.3048)
			(end 0.67945 -0.3048)
			(stroke
				(width 0.1)
				(type default)
			)
			(layer "F.Fab")
		)
		(fp_line
			(start 0.120396 0.3048)
			(end 0.120396 0.2794)
			(stroke
				(width 0.1)
				(type default)
			)
			(layer "F.Fab")
		)
		(fp_line
			(start 0.120396 0.2794)
			(end -0.12065 0.2794)
			(stroke
				(width 0.1)
				(type default)
			)
			(layer "F.Fab")
		)
		(fp_line
			(start -0.12065 0.3048)
			(end -0.67945 0.3048)
			(stroke
				(width 0.1)
				(type default)
			)
			(layer "F.Fab")
		)
		(fp_line
			(start -0.12065 0.2794)
			(end -0.12065 0.3048)
			(stroke
				(width 0.1)
				(type default)
			)
			(layer "F.Fab")
		)
		(fp_line
			(start -0.12065 -0.2794)
			(end 0.12065 -0.2794)
			(stroke
				(width 0.1)
				(type default)
			)
			(layer "F.Fab")
		)
		(fp_line
			(start -0.12065 -0.305054)
			(end -0.12065 -0.2794)
			(stroke
				(width 0.1)
				(type default)
			)
			(layer "F.Fab")
		)
		(fp_line
			(start -0.67945 0.3048)
			(end -0.67945 -0.305054)
			(stroke
				(width 0.1)
				(type default)
			)
			(layer "F.Fab")
		)
		(fp_line
			(start -0.67945 -0.305054)
			(end -0.12065 -0.305054)
			(stroke
				(width 0.1)
				(type default)
			)
			(layer "F.Fab")
		)
		(pad "1" smd circle
			(at -0.40005 0 180)
			(size 0 0)
			(layers "F.Cu" "F.Mask" "F.Paste")
			(net "CLK_GEN2_GPU_FPGA_OE_N")
		)
		(pad "2" smd circle
			(at 0.40005 0 180)
			(size 0 0)
			(layers "F.Cu" "F.Mask" "F.Paste")
			(net "CLK_GEN2_GPU_FPGA_OE_R2_N")
		)
	)
	(footprint ""
		(layer "F.Cu")
		(at 180.80863 -149.661118 -90)
		(property "Reference" "C43"
			(at 0 0 270)
			(layer "F.SilkS")
			(hide yes)
			(effects
				(font
					(size 1.27 1.27)
				)
			)
		)
		(property "Value" ""
			(at 0 0 270)
			(layer "F.Fab")
			(effects
				(font
					(size 1.27 1.27)
				)
			)
		)
		(duplicate_pad_numbers_are_jumpers no)
		(fp_line
			(start -0.7874 0.4064)
			(end -0.7874 -0.4064)
			(stroke
				(width 0.1524)
				(type default)
			)
			(layer "F.SilkS")
		)
		(fp_line
			(start 0.7874 0.4064)
			(end -0.7874 0.4064)
			(stroke
				(width 0.1524)
				(type default)
			)
			(layer "F.SilkS")
		)
		(fp_line
			(start -0.7874 -0.4064)
			(end 0.7874 -0.4064)
			(stroke
				(width 0.1524)
				(type default)
			)
			(layer "F.SilkS")
		)
		(fp_line
			(start 0.7874 -0.4064)
			(end 0.7874 0.4064)
			(stroke
				(width 0.1524)
				(type default)
			)
			(layer "F.SilkS")
		)
		(fp_line
			(start -0.67945 0.3048)
			(end -0.67945 -0.305054)
			(stroke
				(width 0.1)
				(type default)
			)
			(layer "F.Fab")
		)
		(fp_line
			(start -0.12065 0.3048)
			(end -0.67945 0.3048)
			(stroke
				(width 0.1)
				(type default)
			)
			(layer "F.Fab")
		)
		(fp_line
			(start 0.120396 0.3048)
			(end 0.120396 0.2794)
			(stroke
				(width 0.1)
				(type default)
			)
			(layer "F.Fab")
		)
		(fp_line
			(start 0.67945 0.3048)
			(end 0.120396 0.3048)
			(stroke
				(width 0.1)
				(type default)
			)
			(layer "F.Fab")
		)
		(fp_line
			(start -0.12065 0.2794)
			(end -0.12065 0.3048)
			(stroke
				(width 0.1)
				(type default)
			)
			(layer "F.Fab")
		)
		(fp_line
			(start 0.120396 0.2794)
			(end -0.12065 0.2794)
			(stroke
				(width 0.1)
				(type default)
			)
			(layer "F.Fab")
		)
		(fp_line
			(start -0.12065 -0.2794)
			(end 0.12065 -0.2794)
			(stroke
				(width 0.1)
				(type default)
			)
			(layer "F.Fab")
		)
		(fp_line
			(start 0.12065 -0.2794)
			(end 0.12065 -0.3048)
			(stroke
				(width 0.1)
				(type default)
			)
			(layer "F.Fab")
		)
		(fp_line
			(start 0.12065 -0.3048)
			(end 0.67945 -0.3048)
			(stroke
				(width 0.1)
				(type default)
			)
			(layer "F.Fab")
		)
		(fp_line
			(start 0.67945 -0.3048)
			(end 0.67945 0.3048)
			(stroke
				(width 0.1)
				(type default)
			)
			(layer "F.Fab")
		)
		(fp_line
			(start -0.67945 -0.305054)
			(end -0.12065 -0.305054)
			(stroke
				(width 0.1)
				(type default)
			)
			(layer "F.Fab")
		)
		(fp_line
			(start -0.12065 -0.305054)
			(end -0.12065 -0.2794)
			(stroke
				(width 0.1)
				(type default)
			)
			(layer "F.Fab")
		)
		(pad "1" smd circle
			(at -0.40005 0 270)
			(size 0 0)
			(layers "F.Cu" "F.Mask" "F.Paste")
			(net "P3V3_AUX")
		)
		(pad "2" smd circle
			(at 0.40005 0 270)
			(size 0 0)
			(layers "F.Cu" "F.Mask" "F.Paste")
			(net "GND")
		)
	)
	(footprint ""
		(layer "F.Cu")
		(at 88.431878 -145.50136 -90)
		(property "Reference" "C5019"
			(at 0 0 270)
			(layer "F.SilkS")
			(hide yes)
			(effects
				(font
					(size 1.27 1.27)
				)
			)
		)
		(property "Value" ""
			(at 0 0 270)
			(layer "F.Fab")
			(effects
				(font
					(size 1.27 1.27)
				)
			)
		)
		(duplicate_pad_numbers_are_jumpers no)
		(fp_line
			(start -0.7874 0.4064)
			(end -0.7874 -0.4064)
			(stroke
				(width 0.1524)
				(type default)
			)
			(layer "F.SilkS")
		)
		(fp_line
			(start 0.7874 0.4064)
			(end -0.7874 0.4064)
			(stroke
				(width 0.1524)
				(type default)
			)
			(layer "F.SilkS")
		)
		(fp_line
			(start -0.7874 -0.4064)
			(end 0.7874 -0.4064)
			(stroke
				(width 0.1524)
				(type default)
			)
			(layer "F.SilkS")
		)
		(fp_line
			(start 0.7874 -0.4064)
			(end 0.7874 0.4064)
			(stroke
				(width 0.1524)
				(type default)
			)
			(layer "F.SilkS")
		)
		(fp_line
			(start -0.67945 0.3048)
			(end -0.67945 -0.305054)
			(stroke
				(width 0.1)
				(type default)
			)
			(layer "F.Fab")
		)
		(fp_line
			(start -0.12065 0.3048)
			(end -0.67945 0.3048)
			(stroke
				(width 0.1)
				(type default)
			)
			(layer "F.Fab")
		)
		(fp_line
			(start 0.120396 0.3048)
			(end 0.120396 0.2794)
			(stroke
				(width 0.1)
				(type default)
			)
			(layer "F.Fab")
		)
		(fp_line
			(start 0.67945 0.3048)
			(end 0.120396 0.3048)
			(stroke
				(width 0.1)
				(type default)
			)
			(layer "F.Fab")
		)
		(fp_line
			(start -0.12065 0.2794)
			(end -0.12065 0.3048)
			(stroke
				(width 0.1)
				(type default)
			)
			(layer "F.Fab")
		)
		(fp_line
			(start 0.120396 0.2794)
			(end -0.12065 0.2794)
			(stroke
				(width 0.1)
				(type default)
			)
			(layer "F.Fab")
		)
		(fp_line
			(start -0.12065 -0.2794)
			(end 0.12065 -0.2794)
			(stroke
				(width 0.1)
				(type default)
			)
			(layer "F.Fab")
		)
		(fp_line
			(start 0.12065 -0.2794)
			(end 0.12065 -0.3048)
			(stroke
				(width 0.1)
				(type default)
			)
			(layer "F.Fab")
		)
		(fp_line
			(start 0.12065 -0.3048)
			(end 0.67945 -0.3048)
			(stroke
				(width 0.1)
				(type default)
			)
			(layer "F.Fab")
		)
		(fp_line
			(start 0.67945 -0.3048)
			(end 0.67945 0.3048)
			(stroke
				(width 0.1)
				(type default)
			)
			(layer "F.Fab")
		)
		(fp_line
			(start -0.67945 -0.305054)
			(end -0.12065 -0.305054)
			(stroke
				(width 0.1)
				(type default)
			)
			(layer "F.Fab")
		)
		(fp_line
			(start -0.12065 -0.305054)
			(end -0.12065 -0.2794)
			(stroke
				(width 0.1)
				(type default)
			)
			(layer "F.Fab")
		)
		(pad "1" smd circle
			(at -0.40005 0 270)
			(size 0 0)
			(layers "F.Cu" "F.Mask" "F.Paste")
			(net "GND")
		)
		(pad "2" smd circle
			(at 0.40005 0 270)
			(size 0 0)
			(layers "F.Cu" "F.Mask" "F.Paste")
			(net "PWRGD_PVDDCR_SOC_P1")
		)
	)
	(footprint ""
		(layer "F.Cu")
		(at 194.217798 -398.940782 180)
		(property "Reference" "PC2347"
			(at 0 0 180)
			(layer "F.SilkS")
			(hide yes)
			(effects
				(font
					(size 1.27 1.27)
				)
			)
		)
		(property "Value" ""
			(at 0 0 180)
			(layer "F.Fab")
			(effects
				(font
					(size 1.27 1.27)
				)
			)
		)
		(duplicate_pad_numbers_are_jumpers no)
		(fp_line
			(start 0.7874 0.4064)
			(end -0.7874 0.4064)
			(stroke
				(width 0.1524)
				(type default)
			)
			(layer "F.SilkS")
		)
		(fp_line
			(start 0.7874 -0.4064)
			(end 0.7874 0.4064)
			(stroke
				(width 0.1524)
				(type default)
			)
			(layer "F.SilkS")
		)
		(fp_line
			(start -0.7874 0.4064)
			(end -0.7874 -0.4064)
			(stroke
				(width 0.1524)
				(type default)
			)
			(layer "F.SilkS")
		)
		(fp_line
			(start -0.7874 -0.4064)
			(end 0.7874 -0.4064)
			(stroke
				(width 0.1524)
				(type default)
			)
			(layer "F.SilkS")
		)
		(fp_line
			(start 0.67945 0.3048)
			(end 0.120396 0.3048)
			(stroke
				(width 0.1)
				(type default)
			)
			(layer "F.Fab")
		)
		(fp_line
			(start 0.67945 -0.3048)
			(end 0.67945 0.3048)
			(stroke
				(width 0.1)
				(type default)
			)
			(layer "F.Fab")
		)
		(fp_line
			(start 0.12065 -0.2794)
			(end 0.12065 -0.3048)
			(stroke
				(width 0.1)
				(type default)
			)
			(layer "F.Fab")
		)
		(fp_line
			(start 0.12065 -0.3048)
			(end 0.67945 -0.3048)
			(stroke
				(width 0.1)
				(type default)
			)
			(layer "F.Fab")
		)
		(fp_line
			(start 0.120396 0.3048)
			(end 0.120396 0.2794)
			(stroke
				(width 0.1)
				(type default)
			)
			(layer "F.Fab")
		)
		(fp_line
			(start 0.120396 0.2794)
			(end -0.12065 0.2794)
			(stroke
				(width 0.1)
				(type default)
			)
			(layer "F.Fab")
		)
		(fp_line
			(start -0.12065 0.3048)
			(end -0.67945 0.3048)
			(stroke
				(width 0.1)
				(type default)
			)
			(layer "F.Fab")
		)
		(fp_line
			(start -0.12065 0.2794)
			(end -0.12065 0.3048)
			(stroke
				(width 0.1)
				(type default)
			)
			(layer "F.Fab")
		)
		(fp_line
			(start -0.12065 -0.2794)
			(end 0.12065 -0.2794)
			(stroke
				(width 0.1)
				(type default)
			)
			(layer "F.Fab")
		)
		(fp_line
			(start -0.12065 -0.305054)
			(end -0.12065 -0.2794)
			(stroke
				(width 0.1)
				(type default)
			)
			(layer "F.Fab")
		)
		(fp_line
			(start -0.67945 0.3048)
			(end -0.67945 -0.305054)
			(stroke
				(width 0.1)
				(type default)
			)
			(layer "F.Fab")
		)
		(fp_line
			(start -0.67945 -0.305054)
			(end -0.12065 -0.305054)
			(stroke
				(width 0.1)
				(type default)
			)
			(layer "F.Fab")
		)
		(pad "1" smd circle
			(at -0.40005 0 180)
			(size 0 0)
			(layers "F.Cu" "F.Mask" "F.Paste")
			(net "HSC_OCREF")
		)
		(pad "2" smd circle
			(at 0.40005 0 180)
			(size 0 0)
			(layers "F.Cu" "F.Mask" "F.Paste")
			(net "AGND_HSC")
		)
	)
	(footprint ""
		(layer "F.Cu")
		(at 235.068872 -67.474338 -90)
		(property "Reference" "C508"
			(at 0 0 270)
			(layer "F.SilkS")
			(hide yes)
			(effects
				(font
					(size 1.27 1.27)
				)
			)
		)
		(property "Value" ""
			(at 0 0 270)
			(layer "F.Fab")
			(effects
				(font
					(size 1.27 1.27)
				)
			)
		)
		(duplicate_pad_numbers_are_jumpers no)
		(fp_line
			(start -0.7874 0.4064)
			(end -0.7874 -0.4064)
			(stroke
				(width 0.1524)
				(type default)
			)
			(layer "F.SilkS")
		)
		(fp_line
			(start 0.7874 0.4064)
			(end -0.7874 0.4064)
			(stroke
				(width 0.1524)
				(type default)
			)
			(layer "F.SilkS")
		)
		(fp_line
			(start -0.7874 -0.4064)
			(end 0.7874 -0.4064)
			(stroke
				(width 0.1524)
				(type default)
			)
			(layer "F.SilkS")
		)
		(fp_line
			(start 0.7874 -0.4064)
			(end 0.7874 0.4064)
			(stroke
				(width 0.1524)
				(type default)
			)
			(layer "F.SilkS")
		)
		(fp_line
			(start -0.67945 0.3048)
			(end -0.67945 -0.305054)
			(stroke
				(width 0.1)
				(type default)
			)
			(layer "F.Fab")
		)
		(fp_line
			(start -0.12065 0.3048)
			(end -0.67945 0.3048)
			(stroke
				(width 0.1)
				(type default)
			)
			(layer "F.Fab")
		)
		(fp_line
			(start 0.120396 0.3048)
			(end 0.120396 0.2794)
			(stroke
				(width 0.1)
				(type default)
			)
			(layer "F.Fab")
		)
		(fp_line
			(start 0.67945 0.3048)
			(end 0.120396 0.3048)
			(stroke
				(width 0.1)
				(type default)
			)
			(layer "F.Fab")
		)
		(fp_line
			(start -0.12065 0.2794)
			(end -0.12065 0.3048)
			(stroke
				(width 0.1)
				(type default)
			)
			(layer "F.Fab")
		)
		(fp_line
			(start 0.120396 0.2794)
			(end -0.12065 0.2794)
			(stroke
				(width 0.1)
				(type default)
			)
			(layer "F.Fab")
		)
		(fp_line
			(start -0.12065 -0.2794)
			(end 0.12065 -0.2794)
			(stroke
				(width 0.1)
				(type default)
			)
			(layer "F.Fab")
		)
		(fp_line
			(start 0.12065 -0.2794)
			(end 0.12065 -0.3048)
			(stroke
				(width 0.1)
				(type default)
			)
			(layer "F.Fab")
		)
		(fp_line
			(start 0.12065 -0.3048)
			(end 0.67945 -0.3048)
			(stroke
				(width 0.1)
				(type default)
			)
			(layer "F.Fab")
		)
		(fp_line
			(start 0.67945 -0.3048)
			(end 0.67945 0.3048)
			(stroke
				(width 0.1)
				(type default)
			)
			(layer "F.Fab")
		)
		(fp_line
			(start -0.67945 -0.305054)
			(end -0.12065 -0.305054)
			(stroke
				(width 0.1)
				(type default)
			)
			(layer "F.Fab")
		)
		(fp_line
			(start -0.12065 -0.305054)
			(end -0.12065 -0.2794)
			(stroke
				(width 0.1)
				(type default)
			)
			(layer "F.Fab")
		)
		(pad "1" smd circle
			(at -0.40005 0 270)
			(size 0 0)
			(layers "F.Cu" "F.Mask" "F.Paste")
			(net "P3V3_E1S_0")
		)
		(pad "2" smd circle
			(at 0.40005 0 270)
			(size 0 0)
			(layers "F.Cu" "F.Mask" "F.Paste")
			(net "GND")
		)
	)
	(footprint ""
		(layer "F.Cu")
		(at 357.284782 -412.030418)
		(property "Reference" "C15"
			(at 0 0 0)
			(layer "F.SilkS")
			(hide yes)
			(effects
				(font
					(size 1.27 1.27)
				)
			)
		)
		(property "Value" ""
			(at 0 0 0)
			(layer "F.Fab")
			(effects
				(font
					(size 1.27 1.27)
				)
			)
		)
		(duplicate_pad_numbers_are_jumpers no)
		(fp_line
			(start -0.7874 -0.4064)
			(end 0.7874 -0.4064)
			(stroke
				(width 0.1524)
				(type default)
			)
			(layer "F.SilkS")
		)
		(fp_line
			(start -0.7874 0.4064)
			(end -0.7874 -0.4064)
			(stroke
				(width 0.1524)
				(type default)
			)
			(layer "F.SilkS")
		)
		(fp_line
			(start 0.7874 -0.4064)
			(end 0.7874 0.4064)
			(stroke
				(width 0.1524)
				(type default)
			)
			(layer "F.SilkS")
		)
		(fp_line
			(start 0.7874 0.4064)
			(end -0.7874 0.4064)
			(stroke
				(width 0.1524)
				(type default)
			)
			(layer "F.SilkS")
		)
		(fp_line
			(start -0.67945 -0.305054)
			(end -0.12065 -0.305054)
			(stroke
				(width 0.1)
				(type default)
			)
			(layer "F.Fab")
		)
		(fp_line
			(start -0.67945 0.3048)
			(end -0.67945 -0.305054)
			(stroke
				(width 0.1)
				(type default)
			)
			(layer "F.Fab")
		)
		(fp_line
			(start -0.12065 -0.305054)
			(end -0.12065 -0.2794)
			(stroke
				(width 0.1)
				(type default)
			)
			(layer "F.Fab")
		)
		(fp_line
			(start -0.12065 -0.2794)
			(end 0.12065 -0.2794)
			(stroke
				(width 0.1)
				(type default)
			)
			(layer "F.Fab")
		)
		(fp_line
			(start -0.12065 0.2794)
			(end -0.12065 0.3048)
			(stroke
				(width 0.1)
				(type default)
			)
			(layer "F.Fab")
		)
		(fp_line
			(start -0.12065 0.3048)
			(end -0.67945 0.3048)
			(stroke
				(width 0.1)
				(type default)
			)
			(layer "F.Fab")
		)
		(fp_line
			(start 0.120396 0.2794)
			(end -0.12065 0.2794)
			(stroke
				(width 0.1)
				(type default)
			)
			(layer "F.Fab")
		)
		(fp_line
			(start 0.120396 0.3048)
			(end 0.120396 0.2794)
			(stroke
				(width 0.1)
				(type default)
			)
			(layer "F.Fab")
		)
		(fp_line
			(start 0.12065 -0.3048)
			(end 0.67945 -0.3048)
			(stroke
				(width 0.1)
				(type default)
			)
			(layer "F.Fab")
		)
		(fp_line
			(start 0.12065 -0.2794)
			(end 0.12065 -0.3048)
			(stroke
				(width 0.1)
				(type default)
			)
			(layer "F.Fab")
		)
		(fp_line
			(start 0.67945 -0.3048)
			(end 0.67945 0.3048)
			(stroke
				(width 0.1)
				(type default)
			)
			(layer "F.Fab")
		)
		(fp_line
			(start 0.67945 0.3048)
			(end 0.120396 0.3048)
			(stroke
				(width 0.1)
				(type default)
			)
			(layer "F.Fab")
		)
		(pad "1" smd circle
			(at -0.40005 0)
			(size 0 0)
			(layers "F.Cu" "F.Mask" "F.Paste")
			(net "PRSNT_CABLE_GPU_A1_ISO_N")
		)
		(pad "2" smd circle
			(at 0.40005 0)
			(size 0 0)
			(layers "F.Cu" "F.Mask" "F.Paste")
			(net "GND")
		)
	)
	(footprint ""
		(layer "F.Cu")
		(at 74.628502 -339.377274)
		(property "Reference" "PC376_2"
			(at 0 0 0)
			(layer "F.SilkS")
			(hide yes)
			(effects
				(font
					(size 1.27 1.27)
				)
			)
		)
		(property "Value" ""
			(at 0 0 0)
			(layer "F.Fab")
			(effects
				(font
					(size 1.27 1.27)
				)
			)
		)
		(duplicate_pad_numbers_are_jumpers no)
		(fp_line
			(start -0.7874 -0.4064)
			(end 0.7874 -0.4064)
			(stroke
				(width 0.1524)
				(type default)
			)
			(layer "F.SilkS")
		)
		(fp_line
			(start -0.7874 0.4064)
			(end -0.7874 -0.4064)
			(stroke
				(width 0.1524)
				(type default)
			)
			(layer "F.SilkS")
		)
		(fp_line
			(start 0.7874 -0.4064)
			(end 0.7874 0.4064)
			(stroke
				(width 0.1524)
				(type default)
			)
			(layer "F.SilkS")
		)
		(fp_line
			(start 0.7874 0.4064)
			(end -0.7874 0.4064)
			(stroke
				(width 0.1524)
				(type default)
			)
			(layer "F.SilkS")
		)
		(fp_line
			(start -0.67945 -0.305054)
			(end -0.12065 -0.305054)
			(stroke
				(width 0.1)
				(type default)
			)
			(layer "F.Fab")
		)
		(fp_line
			(start -0.67945 0.3048)
			(end -0.67945 -0.305054)
			(stroke
				(width 0.1)
				(type default)
			)
			(layer "F.Fab")
		)
		(fp_line
			(start -0.12065 -0.305054)
			(end -0.12065 -0.2794)
			(stroke
				(width 0.1)
				(type default)
			)
			(layer "F.Fab")
		)
		(fp_line
			(start -0.12065 -0.2794)
			(end 0.12065 -0.2794)
			(stroke
				(width 0.1)
				(type default)
			)
			(layer "F.Fab")
		)
		(fp_line
			(start -0.12065 0.2794)
			(end -0.12065 0.3048)
			(stroke
				(width 0.1)
				(type default)
			)
			(layer "F.Fab")
		)
		(fp_line
			(start -0.12065 0.3048)
			(end -0.67945 0.3048)
			(stroke
				(width 0.1)
				(type default)
			)
			(layer "F.Fab")
		)
		(fp_line
			(start 0.120396 0.2794)
			(end -0.12065 0.2794)
			(stroke
				(width 0.1)
				(type default)
			)
			(layer "F.Fab")
		)
		(fp_line
			(start 0.120396 0.3048)
			(end 0.120396 0.2794)
			(stroke
				(width 0.1)
				(type default)
			)
			(layer "F.Fab")
		)
		(fp_line
			(start 0.12065 -0.3048)
			(end 0.67945 -0.3048)
			(stroke
				(width 0.1)
				(type default)
			)
			(layer "F.Fab")
		)
		(fp_line
			(start 0.12065 -0.2794)
			(end 0.12065 -0.3048)
			(stroke
				(width 0.1)
				(type default)
			)
			(layer "F.Fab")
		)
		(fp_line
			(start 0.67945 -0.3048)
			(end 0.67945 0.3048)
			(stroke
				(width 0.1)
				(type default)
			)
			(layer "F.Fab")
		)
		(fp_line
			(start 0.67945 0.3048)
			(end 0.120396 0.3048)
			(stroke
				(width 0.1)
				(type default)
			)
			(layer "F.Fab")
		)
		(pad "1" smd circle
			(at -0.40005 0)
			(size 0 0)
			(layers "F.Cu" "F.Mask" "F.Paste")
			(net "SW_P12V_AUX_PVDDCR_CPU1_P1_FLT")
		)
		(pad "2" smd circle
			(at 0.40005 0)
			(size 0 0)
			(layers "F.Cu" "F.Mask" "F.Paste")
			(net "GND")
		)
	)
	(footprint ""
		(layer "F.Cu")
		(at 76.184252 -401.925536 90)
		(property "Reference" "C7039"
			(at 0 0 90)
			(layer "F.SilkS")
			(hide yes)
			(effects
				(font
					(size 1.27 1.27)
				)
			)
		)
		(property "Value" ""
			(at 0 0 90)
			(layer "F.Fab")
			(effects
				(font
					(size 1.27 1.27)
				)
			)
		)
		(duplicate_pad_numbers_are_jumpers no)
		(fp_line
			(start 1.524 -0.762)
			(end 1.524 0.762)
			(stroke
				(width 0.1524)
				(type default)
			)
			(layer "F.SilkS")
		)
		(fp_line
			(start -1.524 -0.762)
			(end 1.524 -0.762)
			(stroke
				(width 0.1524)
				(type default)
			)
			(layer "F.SilkS")
		)
		(fp_line
			(start 1.524 0.762)
			(end -1.524 0.762)
			(stroke
				(width 0.1524)
				(type default)
			)
			(layer "F.SilkS")
		)
		(fp_line
			(start -1.524 0.762)
			(end -1.524 -0.762)
			(stroke
				(width 0.1524)
				(type default)
			)
			(layer "F.SilkS")
		)
		(fp_line
			(start 1.1049 -0.724916)
			(end -1.1049 -0.724916)
			(stroke
				(width 0.1)
				(type default)
			)
			(layer "F.Fab")
		)
		(fp_line
			(start -1.1049 -0.724916)
			(end -1.1049 0.724916)
			(stroke
				(width 0.1)
				(type default)
			)
			(layer "F.Fab")
		)
		(fp_line
			(start 1.1049 0.724916)
			(end 1.1049 -0.724916)
			(stroke
				(width 0.1)
				(type default)
			)
			(layer "F.Fab")
		)
		(fp_line
			(start -1.1049 0.724916)
			(end 1.1049 0.724916)
			(stroke
				(width 0.1)
				(type default)
			)
			(layer "F.Fab")
		)
		(pad "1" smd rect
			(at -0.889 0 270)
			(size 1.016 1.27)
			(layers "F.Cu" "F.Mask" "F.Paste")
			(net "P0V9_CPU1_RT_2D")
		)
		(pad "2" smd rect
			(at 0.889 0 270)
			(size 1.016 1.27)
			(layers "F.Cu" "F.Mask" "F.Paste")
			(net "GND")
		)
	)
	(footprint ""
		(layer "F.Cu")
		(at 182.404766 -168.317418 -90)
		(property "Reference" "R5012"
			(at 0 0 270)
			(layer "F.SilkS")
			(hide yes)
			(effects
				(font
					(size 1.27 1.27)
				)
			)
		)
		(property "Value" ""
			(at 0 0 270)
			(layer "F.Fab")
			(effects
				(font
					(size 1.27 1.27)
				)
			)
		)
		(duplicate_pad_numbers_are_jumpers no)
		(fp_line
			(start -0.7874 0.4064)
			(end -0.7874 -0.4064)
			(stroke
				(width 0.1524)
				(type default)
			)
			(layer "F.SilkS")
		)
		(fp_line
			(start 0.7874 0.4064)
			(end -0.7874 0.4064)
			(stroke
				(width 0.1524)
				(type default)
			)
			(layer "F.SilkS")
		)
		(fp_line
			(start -0.7874 -0.4064)
			(end 0.7874 -0.4064)
			(stroke
				(width 0.1524)
				(type default)
			)
			(layer "F.SilkS")
		)
		(fp_line
			(start 0.7874 -0.4064)
			(end 0.7874 0.4064)
			(stroke
				(width 0.1524)
				(type default)
			)
			(layer "F.SilkS")
		)
		(fp_line
			(start -0.67945 0.3048)
			(end -0.67945 -0.305054)
			(stroke
				(width 0.1)
				(type default)
			)
			(layer "F.Fab")
		)
		(fp_line
			(start -0.12065 0.3048)
			(end -0.67945 0.3048)
			(stroke
				(width 0.1)
				(type default)
			)
			(layer "F.Fab")
		)
		(fp_line
			(start 0.120396 0.3048)
			(end 0.120396 0.2794)
			(stroke
				(width 0.1)
				(type default)
			)
			(layer "F.Fab")
		)
		(fp_line
			(start 0.67945 0.3048)
			(end 0.120396 0.3048)
			(stroke
				(width 0.1)
				(type default)
			)
			(layer "F.Fab")
		)
		(fp_line
			(start -0.12065 0.2794)
			(end -0.12065 0.3048)
			(stroke
				(width 0.1)
				(type default)
			)
			(layer "F.Fab")
		)
		(fp_line
			(start 0.120396 0.2794)
			(end -0.12065 0.2794)
			(stroke
				(width 0.1)
				(type default)
			)
			(layer "F.Fab")
		)
		(fp_line
			(start -0.12065 -0.2794)
			(end 0.12065 -0.2794)
			(stroke
				(width 0.1)
				(type default)
			)
			(layer "F.Fab")
		)
		(fp_line
			(start 0.12065 -0.2794)
			(end 0.12065 -0.3048)
			(stroke
				(width 0.1)
				(type default)
			)
			(layer "F.Fab")
		)
		(fp_line
			(start 0.12065 -0.3048)
			(end 0.67945 -0.3048)
			(stroke
				(width 0.1)
				(type default)
			)
			(layer "F.Fab")
		)
		(fp_line
			(start 0.67945 -0.3048)
			(end 0.67945 0.3048)
			(stroke
				(width 0.1)
				(type default)
			)
			(layer "F.Fab")
		)
		(fp_line
			(start -0.67945 -0.305054)
			(end -0.12065 -0.305054)
			(stroke
				(width 0.1)
				(type default)
			)
			(layer "F.Fab")
		)
		(fp_line
			(start -0.12065 -0.305054)
			(end -0.12065 -0.2794)
			(stroke
				(width 0.1)
				(type default)
			)
			(layer "F.Fab")
		)
		(pad "1" smd circle
			(at -0.40005 0 270)
			(size 0 0)
			(layers "F.Cu" "F.Mask" "F.Paste")
			(net "PVDD11_S3_P1")
		)
		(pad "2" smd circle
			(at 0.40005 0 270)
			(size 0 0)
			(layers "F.Cu" "F.Mask" "F.Paste")
			(net "I3C_SPD_DDRGL_CPU1_LVC1_SCL")
		)
	)
	(footprint ""
		(layer "F.Cu")
		(at 74.04354 -335.099406 -90)
		(property "Reference" "PC406_3"
			(at 0 0 270)
			(layer "F.SilkS")
			(hide yes)
			(effects
				(font
					(size 1.27 1.27)
				)
			)
		)
		(property "Value" ""
			(at 0 0 270)
			(layer "F.Fab")
			(effects
				(font
					(size 1.27 1.27)
				)
			)
		)
		(duplicate_pad_numbers_are_jumpers no)
		(fp_line
			(start -0.7874 0.4064)
			(end -0.7874 -0.4064)
			(stroke
				(width 0.1524)
				(type default)
			)
			(layer "F.SilkS")
		)
		(fp_line
			(start 0.7874 0.4064)
			(end -0.7874 0.4064)
			(stroke
				(width 0.1524)
				(type default)
			)
			(layer "F.SilkS")
		)
		(fp_line
			(start -0.7874 -0.4064)
			(end 0.7874 -0.4064)
			(stroke
				(width 0.1524)
				(type default)
			)
			(layer "F.SilkS")
		)
		(fp_line
			(start 0.7874 -0.4064)
			(end 0.7874 0.4064)
			(stroke
				(width 0.1524)
				(type default)
			)
			(layer "F.SilkS")
		)
		(fp_line
			(start -0.67945 0.3048)
			(end -0.67945 -0.305054)
			(stroke
				(width 0.1)
				(type default)
			)
			(layer "F.Fab")
		)
		(fp_line
			(start -0.12065 0.3048)
			(end -0.67945 0.3048)
			(stroke
				(width 0.1)
				(type default)
			)
			(layer "F.Fab")
		)
		(fp_line
			(start 0.120396 0.3048)
			(end 0.120396 0.2794)
			(stroke
				(width 0.1)
				(type default)
			)
			(layer "F.Fab")
		)
		(fp_line
			(start 0.67945 0.3048)
			(end 0.120396 0.3048)
			(stroke
				(width 0.1)
				(type default)
			)
			(layer "F.Fab")
		)
		(fp_line
			(start -0.12065 0.2794)
			(end -0.12065 0.3048)
			(stroke
				(width 0.1)
				(type default)
			)
			(layer "F.Fab")
		)
		(fp_line
			(start 0.120396 0.2794)
			(end -0.12065 0.2794)
			(stroke
				(width 0.1)
				(type default)
			)
			(layer "F.Fab")
		)
		(fp_line
			(start -0.12065 -0.2794)
			(end 0.12065 -0.2794)
			(stroke
				(width 0.1)
				(type default)
			)
			(layer "F.Fab")
		)
		(fp_line
			(start 0.12065 -0.2794)
			(end 0.12065 -0.3048)
			(stroke
				(width 0.1)
				(type default)
			)
			(layer "F.Fab")
		)
		(fp_line
			(start 0.12065 -0.3048)
			(end 0.67945 -0.3048)
			(stroke
				(width 0.1)
				(type default)
			)
			(layer "F.Fab")
		)
		(fp_line
			(start 0.67945 -0.3048)
			(end 0.67945 0.3048)
			(stroke
				(width 0.1)
				(type default)
			)
			(layer "F.Fab")
		)
		(fp_line
			(start -0.67945 -0.305054)
			(end -0.12065 -0.305054)
			(stroke
				(width 0.1)
				(type default)
			)
			(layer "F.Fab")
		)
		(fp_line
			(start -0.12065 -0.305054)
			(end -0.12065 -0.2794)
			(stroke
				(width 0.1)
				(type default)
			)
			(layer "F.Fab")
		)
		(pad "1" smd circle
			(at -0.40005 0 270)
			(size 0 0)
			(layers "F.Cu" "F.Mask" "F.Paste")
			(net "SW_P12V_AUX_PVDDCR_CPU1_P1_FLT")
		)
		(pad "2" smd circle
			(at 0.40005 0 270)
			(size 0 0)
			(layers "F.Cu" "F.Mask" "F.Paste")
			(net "GND")
		)
	)
	(footprint ""
		(layer "F.Cu")
		(at 341.648542 -356.05339 90)
		(property "Reference" "PL12"
			(at -1.4224 3.870452 90)
			(unlocked yes)
			(layer "F.SilkS")
			(effects
				(font
					(size 0.7874 0.5842)
					(thickness 0.1524)
				)
				(justify left)
			)
		)
		(property "Value" ""
			(at 0 0 90)
			(layer "F.Fab")
			(effects
				(font
					(size 1.27 1.27)
				)
			)
		)
		(duplicate_pad_numbers_are_jumpers no)
		(fp_line
			(start 3.050032 -2.999994)
			(end -3.050032 -2.999994)
			(stroke
				(width 0.1524)
				(type default)
			)
			(layer "F.SilkS")
		)
		(fp_line
			(start -3.050032 -2.999994)
			(end -3.050032 -1.4478)
			(stroke
				(width 0.1524)
				(type default)
			)
			(layer "F.SilkS")
		)
		(fp_line
			(start 3.050032 -1.4478)
			(end 3.050032 -2.999994)
			(stroke
				(width 0.1524)
				(type default)
			)
			(layer "F.SilkS")
		)
		(fp_line
			(start -3.050032 1.4478)
			(end -3.050032 2.999994)
			(stroke
				(width 0.1524)
				(type default)
			)
			(layer "F.SilkS")
		)
		(fp_line
			(start 3.050032 2.999994)
			(end 3.050032 1.4478)
			(stroke
				(width 0.1524)
				(type default)
			)
			(layer "F.SilkS")
		)
		(fp_line
			(start -3.050032 2.999994)
			(end 3.050032 2.999994)
			(stroke
				(width 0.1524)
				(type default)
			)
			(layer "F.SilkS")
		)
		(fp_line
			(start 3.050032 -2.999994)
			(end -3.050032 -2.999994)
			(stroke
				(width 0.1)
				(type default)
			)
			(layer "F.Fab")
		)
		(fp_line
			(start -3.050032 -2.999994)
			(end -3.050032 2.999994)
			(stroke
				(width 0.1)
				(type default)
			)
			(layer "F.Fab")
		)
		(fp_line
			(start 3.050032 2.999994)
			(end 3.050032 -2.999994)
			(stroke
				(width 0.1)
				(type default)
			)
			(layer "F.Fab")
		)
		(fp_line
			(start -3.050032 2.999994)
			(end 3.050032 2.999994)
			(stroke
				(width 0.1)
				(type default)
			)
			(layer "F.Fab")
		)
		(pad "1" smd rect
			(at -2.525014 0 90)
			(size 1.651 2.6162)
			(layers "F.Cu" "F.Mask" "F.Paste")
			(net "SW_P12V_AUX_PVDDCR_CPU1_P0_FLT")
		)
		(pad "2" smd rect
			(at 2.525014 0 90)
			(size 1.651 2.6162)
			(layers "F.Cu" "F.Mask" "F.Paste")
			(net "P12V_AUX")
		)
	)
	(footprint ""
		(layer "F.Cu")
		(at 179.961286 -133.43763 -90)
		(property "Reference" "R6741"
			(at 0 0 270)
			(layer "F.SilkS")
			(hide yes)
			(effects
				(font
					(size 1.27 1.27)
				)
			)
		)
		(property "Value" ""
			(at 0 0 270)
			(layer "F.Fab")
			(effects
				(font
					(size 1.27 1.27)
				)
			)
		)
		(duplicate_pad_numbers_are_jumpers no)
		(fp_line
			(start -0.7874 0.4064)
			(end -0.7874 -0.4064)
			(stroke
				(width 0.1524)
				(type default)
			)
			(layer "F.SilkS")
		)
		(fp_line
			(start 0.7874 0.4064)
			(end -0.7874 0.4064)
			(stroke
				(width 0.1524)
				(type default)
			)
			(layer "F.SilkS")
		)
		(fp_line
			(start -0.7874 -0.4064)
			(end 0.7874 -0.4064)
			(stroke
				(width 0.1524)
				(type default)
			)
			(layer "F.SilkS")
		)
		(fp_line
			(start 0.7874 -0.4064)
			(end 0.7874 0.4064)
			(stroke
				(width 0.1524)
				(type default)
			)
			(layer "F.SilkS")
		)
		(fp_line
			(start -0.67945 0.3048)
			(end -0.67945 -0.305054)
			(stroke
				(width 0.1)
				(type default)
			)
			(layer "F.Fab")
		)
		(fp_line
			(start -0.12065 0.3048)
			(end -0.67945 0.3048)
			(stroke
				(width 0.1)
				(type default)
			)
			(layer "F.Fab")
		)
		(fp_line
			(start 0.120396 0.3048)
			(end 0.120396 0.2794)
			(stroke
				(width 0.1)
				(type default)
			)
			(layer "F.Fab")
		)
		(fp_line
			(start 0.67945 0.3048)
			(end 0.120396 0.3048)
			(stroke
				(width 0.1)
				(type default)
			)
			(layer "F.Fab")
		)
		(fp_line
			(start -0.12065 0.2794)
			(end -0.12065 0.3048)
			(stroke
				(width 0.1)
				(type default)
			)
			(layer "F.Fab")
		)
		(fp_line
			(start 0.120396 0.2794)
			(end -0.12065 0.2794)
			(stroke
				(width 0.1)
				(type default)
			)
			(layer "F.Fab")
		)
		(fp_line
			(start -0.12065 -0.2794)
			(end 0.12065 -0.2794)
			(stroke
				(width 0.1)
				(type default)
			)
			(layer "F.Fab")
		)
		(fp_line
			(start 0.12065 -0.2794)
			(end 0.12065 -0.3048)
			(stroke
				(width 0.1)
				(type default)
			)
			(layer "F.Fab")
		)
		(fp_line
			(start 0.12065 -0.3048)
			(end 0.67945 -0.3048)
			(stroke
				(width 0.1)
				(type default)
			)
			(layer "F.Fab")
		)
		(fp_line
			(start 0.67945 -0.3048)
			(end 0.67945 0.3048)
			(stroke
				(width 0.1)
				(type default)
			)
			(layer "F.Fab")
		)
		(fp_line
			(start -0.67945 -0.305054)
			(end -0.12065 -0.305054)
			(stroke
				(width 0.1)
				(type default)
			)
			(layer "F.Fab")
		)
		(fp_line
			(start -0.12065 -0.305054)
			(end -0.12065 -0.2794)
			(stroke
				(width 0.1)
				(type default)
			)
			(layer "F.Fab")
		)
		(pad "1" smd circle
			(at -0.40005 0 270)
			(size 0 0)
			(layers "F.Cu" "F.Mask" "F.Paste")
			(net "RST_RT_CPU1_P1_RESET_R_N")
		)
		(pad "2" smd circle
			(at 0.40005 0 270)
			(size 0 0)
			(layers "F.Cu" "F.Mask" "F.Paste")
			(net "RST_RT_CPU1_P1_RESET_R2_N")
		)
	)
	(footprint ""
		(layer "F.Cu")
		(at 123.835922 -13.99413 180)
		(property "Reference" "R4184"
			(at 0 0 180)
			(layer "F.SilkS")
			(hide yes)
			(effects
				(font
					(size 1.27 1.27)
				)
			)
		)
		(property "Value" ""
			(at 0 0 180)
			(layer "F.Fab")
			(effects
				(font
					(size 1.27 1.27)
				)
			)
		)
		(duplicate_pad_numbers_are_jumpers no)
		(fp_line
			(start 0.7874 0.4064)
			(end -0.7874 0.4064)
			(stroke
				(width 0.1524)
				(type default)
			)
			(layer "F.SilkS")
		)
		(fp_line
			(start 0.7874 -0.4064)
			(end 0.7874 0.4064)
			(stroke
				(width 0.1524)
				(type default)
			)
			(layer "F.SilkS")
		)
		(fp_line
			(start -0.7874 0.4064)
			(end -0.7874 -0.4064)
			(stroke
				(width 0.1524)
				(type default)
			)
			(layer "F.SilkS")
		)
		(fp_line
			(start -0.7874 -0.4064)
			(end 0.7874 -0.4064)
			(stroke
				(width 0.1524)
				(type default)
			)
			(layer "F.SilkS")
		)
		(fp_line
			(start 0.67945 0.3048)
			(end 0.120396 0.3048)
			(stroke
				(width 0.1)
				(type default)
			)
			(layer "F.Fab")
		)
		(fp_line
			(start 0.67945 -0.3048)
			(end 0.67945 0.3048)
			(stroke
				(width 0.1)
				(type default)
			)
			(layer "F.Fab")
		)
		(fp_line
			(start 0.12065 -0.2794)
			(end 0.12065 -0.3048)
			(stroke
				(width 0.1)
				(type default)
			)
			(layer "F.Fab")
		)
		(fp_line
			(start 0.12065 -0.3048)
			(end 0.67945 -0.3048)
			(stroke
				(width 0.1)
				(type default)
			)
			(layer "F.Fab")
		)
		(fp_line
			(start 0.120396 0.3048)
			(end 0.120396 0.2794)
			(stroke
				(width 0.1)
				(type default)
			)
			(layer "F.Fab")
		)
		(fp_line
			(start 0.120396 0.2794)
			(end -0.12065 0.2794)
			(stroke
				(width 0.1)
				(type default)
			)
			(layer "F.Fab")
		)
		(fp_line
			(start -0.12065 0.3048)
			(end -0.67945 0.3048)
			(stroke
				(width 0.1)
				(type default)
			)
			(layer "F.Fab")
		)
		(fp_line
			(start -0.12065 0.2794)
			(end -0.12065 0.3048)
			(stroke
				(width 0.1)
				(type default)
			)
			(layer "F.Fab")
		)
		(fp_line
			(start -0.12065 -0.2794)
			(end 0.12065 -0.2794)
			(stroke
				(width 0.1)
				(type default)
			)
			(layer "F.Fab")
		)
		(fp_line
			(start -0.12065 -0.305054)
			(end -0.12065 -0.2794)
			(stroke
				(width 0.1)
				(type default)
			)
			(layer "F.Fab")
		)
		(fp_line
			(start -0.67945 0.3048)
			(end -0.67945 -0.305054)
			(stroke
				(width 0.1)
				(type default)
			)
			(layer "F.Fab")
		)
		(fp_line
			(start -0.67945 -0.305054)
			(end -0.12065 -0.305054)
			(stroke
				(width 0.1)
				(type default)
			)
			(layer "F.Fab")
		)
		(pad "1" smd circle
			(at -0.40005 0 180)
			(size 0 0)
			(layers "F.Cu" "F.Mask" "F.Paste")
			(net "P3V3_AUX")
		)
		(pad "2" smd circle
			(at 0.40005 0 180)
			(size 0 0)
			(layers "F.Cu" "F.Mask" "F.Paste")
			(net "U273_3_ADD2")
		)
	)
	(footprint ""
		(layer "F.Cu")
		(at 166.3192 -431.3936)
		(property "Reference" "R2671"
			(at 0 0 0)
			(layer "F.SilkS")
			(hide yes)
			(effects
				(font
					(size 1.27 1.27)
				)
			)
		)
		(property "Value" ""
			(at 0 0 0)
			(layer "F.Fab")
			(effects
				(font
					(size 1.27 1.27)
				)
			)
		)
		(duplicate_pad_numbers_are_jumpers no)
		(fp_line
			(start -0.7874 -0.4064)
			(end 0.7874 -0.4064)
			(stroke
				(width 0.1524)
				(type default)
			)
			(layer "F.SilkS")
		)
		(fp_line
			(start -0.7874 0.4064)
			(end -0.7874 -0.4064)
			(stroke
				(width 0.1524)
				(type default)
			)
			(layer "F.SilkS")
		)
		(fp_line
			(start 0.7874 -0.4064)
			(end 0.7874 0.4064)
			(stroke
				(width 0.1524)
				(type default)
			)
			(layer "F.SilkS")
		)
		(fp_line
			(start 0.7874 0.4064)
			(end -0.7874 0.4064)
			(stroke
				(width 0.1524)
				(type default)
			)
			(layer "F.SilkS")
		)
		(fp_line
			(start -0.67945 -0.305054)
			(end -0.12065 -0.305054)
			(stroke
				(width 0.1)
				(type default)
			)
			(layer "F.Fab")
		)
		(fp_line
			(start -0.67945 0.3048)
			(end -0.67945 -0.305054)
			(stroke
				(width 0.1)
				(type default)
			)
			(layer "F.Fab")
		)
		(fp_line
			(start -0.12065 -0.305054)
			(end -0.12065 -0.2794)
			(stroke
				(width 0.1)
				(type default)
			)
			(layer "F.Fab")
		)
		(fp_line
			(start -0.12065 -0.2794)
			(end 0.12065 -0.2794)
			(stroke
				(width 0.1)
				(type default)
			)
			(layer "F.Fab")
		)
		(fp_line
			(start -0.12065 0.2794)
			(end -0.12065 0.3048)
			(stroke
				(width 0.1)
				(type default)
			)
			(layer "F.Fab")
		)
		(fp_line
			(start -0.12065 0.3048)
			(end -0.67945 0.3048)
			(stroke
				(width 0.1)
				(type default)
			)
			(layer "F.Fab")
		)
		(fp_line
			(start 0.120396 0.2794)
			(end -0.12065 0.2794)
			(stroke
				(width 0.1)
				(type default)
			)
			(layer "F.Fab")
		)
		(fp_line
			(start 0.120396 0.3048)
			(end 0.120396 0.2794)
			(stroke
				(width 0.1)
				(type default)
			)
			(layer "F.Fab")
		)
		(fp_line
			(start 0.12065 -0.3048)
			(end 0.67945 -0.3048)
			(stroke
				(width 0.1)
				(type default)
			)
			(layer "F.Fab")
		)
		(fp_line
			(start 0.12065 -0.2794)
			(end 0.12065 -0.3048)
			(stroke
				(width 0.1)
				(type default)
			)
			(layer "F.Fab")
		)
		(fp_line
			(start 0.67945 -0.3048)
			(end 0.67945 0.3048)
			(stroke
				(width 0.1)
				(type default)
			)
			(layer "F.Fab")
		)
		(fp_line
			(start 0.67945 0.3048)
			(end 0.120396 0.3048)
			(stroke
				(width 0.1)
				(type default)
			)
			(layer "F.Fab")
		)
		(pad "1" smd circle
			(at -0.40005 0)
			(size 0 0)
			(layers "F.Cu" "F.Mask" "F.Paste")
			(net "SMB_BMC_SWB_BUF_R_SCL")
		)
		(pad "2" smd circle
			(at 0.40005 0)
			(size 0 0)
			(layers "F.Cu" "F.Mask" "F.Paste")
			(net "SMB_BMC_SWB_BUF_SCL")
		)
	)
	(footprint ""
		(layer "F.Cu")
		(at 300.482762 -337.399122)
		(property "Reference" "PL17"
			(at -3.242056 -15.760446 0)
			(unlocked yes)
			(layer "F.SilkS")
			(effects
				(font
					(size 0.7874 0.5842)
					(thickness 0.1524)
				)
				(justify left)
			)
		)
		(property "Value" ""
			(at 0 0 0)
			(layer "F.Fab")
			(effects
				(font
					(size 1.27 1.27)
				)
			)
		)
		(duplicate_pad_numbers_are_jumpers no)
		(fp_line
			(start -3.750056 -5.500116)
			(end -2.393442 -5.500116)
			(stroke
				(width 0.1524)
				(type default)
			)
			(layer "F.SilkS")
		)
		(fp_line
			(start -3.750056 5.500116)
			(end -3.750056 -5.500116)
			(stroke
				(width 0.1524)
				(type default)
			)
			(layer "F.SilkS")
		)
		(fp_line
			(start -2.393442 5.500116)
			(end -3.750056 5.500116)
			(stroke
				(width 0.1524)
				(type default)
			)
			(layer "F.SilkS")
		)
		(fp_line
			(start 2.393442 5.500116)
			(end 3.750056 5.500116)
			(stroke
				(width 0.1524)
				(type default)
			)
			(layer "F.SilkS")
		)
		(fp_line
			(start 3.750056 -5.500116)
			(end 2.393442 -5.500116)
			(stroke
				(width 0.1524)
				(type default)
			)
			(layer "F.SilkS")
		)
		(fp_line
			(start 3.750056 5.500116)
			(end 3.750056 -5.500116)
			(stroke
				(width 0.1524)
				(type default)
			)
			(layer "F.SilkS")
		)
		(fp_poly
			(pts
				(xy -3.9116 -4.249928) (xy -4.3434 -4.034028) (xy -4.3434 -4.465828)
			)
			(stroke
				(width 0)
				(type default)
			)
			(fill yes)
			(layer "F.SilkS")
		)
		(fp_line
			(start -3.750056 -5.500116)
			(end -3.750056 5.500116)
			(stroke
				(width 0.1)
				(type default)
			)
			(layer "F.Fab")
		)
		(fp_line
			(start -3.750056 5.500116)
			(end 3.750056 5.500116)
			(stroke
				(width 0.1)
				(type default)
			)
			(layer "F.Fab")
		)
		(fp_line
			(start 3.750056 -5.500116)
			(end -3.750056 -5.500116)
			(stroke
				(width 0.1)
				(type default)
			)
			(layer "F.Fab")
		)
		(fp_line
			(start 3.750056 5.500116)
			(end 3.750056 -5.500116)
			(stroke
				(width 0.1)
				(type default)
			)
			(layer "F.Fab")
		)
		(fp_poly
			(pts
				(xy -4.9276 -4.757928) (xy -4.9276 -3.741928) (xy -3.9116 -4.249928)
			)
			(stroke
				(width 0)
				(type default)
			)
			(fill yes)
			(layer "F.Fab")
		)
		(pad "1" smd rect
			(at 0 -4.249928 270)
			(size 2.413 4.5212)
			(layers "F.Cu" "F.Mask" "F.Paste")
			(net "SW_PVDDIO_P0_SW1")
		)
		(pad "2" smd rect
			(at 0 -1.175004 270)
			(size 1.3716 4.5212)
			(layers "F.Cu" "F.Mask" "F.Paste")
			(net "IND_PVDDIO_P0_CPL2")
		)
		(pad "3" smd rect
			(at 0 1.175004 270)
			(size 1.3716 4.5212)
			(layers "F.Cu" "F.Mask" "F.Paste")
			(net "GND")
		)
		(pad "4" smd rect
			(at 0 4.249928 270)
			(size 2.413 4.5212)
			(layers "F.Cu" "F.Mask" "F.Paste")
			(net "PVDDIO_P0")
		)
	)
	(footprint ""
		(layer "F.Cu")
		(at 144.690592 -104.974898)
		(property "Reference" "Q95"
			(at -3.91668 -1.633728 0)
			(unlocked yes)
			(layer "F.SilkS")
			(effects
				(font
					(size 0.7874 0.5842)
					(thickness 0.1524)
				)
				(justify left)
			)
		)
		(property "Value" ""
			(at 0 0 0)
			(layer "F.Fab")
			(effects
				(font
					(size 1.27 1.27)
				)
			)
		)
		(duplicate_pad_numbers_are_jumpers no)
		(fp_line
			(start -1.332738 -1.100074)
			(end -0.4826 -1.100074)
			(stroke
				(width 0.1524)
				(type default)
			)
			(layer "F.SilkS")
		)
		(fp_line
			(start -1.332738 1.100074)
			(end -1.332738 -1.100074)
			(stroke
				(width 0.1524)
				(type default)
			)
			(layer "F.SilkS")
		)
		(fp_line
			(start -0.4826 -1.100074)
			(end 0 -0.541274)
			(stroke
				(width 0.1524)
				(type default)
			)
			(layer "F.SilkS")
		)
		(fp_line
			(start 0 -0.541274)
			(end 0.4826 -1.100074)
			(stroke
				(width 0.1524)
				(type default)
			)
			(layer "F.SilkS")
		)
		(fp_line
			(start 0.4826 -1.100074)
			(end 1.332738 -1.100074)
			(stroke
				(width 0.1524)
				(type default)
			)
			(layer "F.SilkS")
		)
		(fp_line
			(start 1.332738 -1.100074)
			(end 1.332738 1.100074)
			(stroke
				(width 0.1524)
				(type default)
			)
			(layer "F.SilkS")
		)
		(fp_line
			(start 1.332738 1.100074)
			(end -1.332738 1.100074)
			(stroke
				(width 0.1524)
				(type default)
			)
			(layer "F.SilkS")
		)
		(fp_poly
			(pts
				(xy -1.533144 -0.649986) (xy -2.1082 -0.362458) (xy -2.1082 -0.937514)
			)
			(stroke
				(width 0)
				(type default)
			)
			(fill yes)
			(layer "F.SilkS")
		)
		(fp_line
			(start -0.674878 -1.100074)
			(end 0.674878 -1.100074)
			(stroke
				(width 0.1)
				(type default)
			)
			(layer "F.Fab")
		)
		(fp_line
			(start -0.674878 1.100074)
			(end -0.674878 -1.100074)
			(stroke
				(width 0.1)
				(type default)
			)
			(layer "F.Fab")
		)
		(fp_line
			(start 0.674878 -1.100074)
			(end 0.674878 1.100074)
			(stroke
				(width 0.1)
				(type default)
			)
			(layer "F.Fab")
		)
		(fp_line
			(start 0.674878 1.100074)
			(end -0.674878 1.100074)
			(stroke
				(width 0.1)
				(type default)
			)
			(layer "F.Fab")
		)
		(fp_poly
			(pts
				(xy -2.2352 -0.298958) (xy -2.2352 -1.001014) (xy -1.533144 -0.649986)
			)
			(stroke
				(width 0)
				(type default)
			)
			(fill yes)
			(layer "F.Fab")
		)
		(pad "1" smd rect
			(at -0.94996 -0.649986 90)
			(size 0.4318 0.508)
			(layers "F.Cu" "F.Mask" "F.Paste")
			(net "GND")
		)
		(pad "2" smd rect
			(at -0.94996 0 90)
			(size 0.4318 0.508)
			(layers "F.Cu" "F.Mask" "F.Paste")
			(net "HDD_ACTIVITY_BUF")
		)
		(pad "3" smd rect
			(at -0.94996 0.649986 90)
			(size 0.4318 0.508)
			(layers "F.Cu" "F.Mask" "F.Paste")
			(net "NC_Q95_D2")
		)
		(pad "4" smd rect
			(at 0.94996 0.649986 90)
			(size 0.4318 0.508)
			(layers "F.Cu" "F.Mask" "F.Paste")
			(net "NC_Q95_S2")
		)
		(pad "5" smd rect
			(at 0.94996 0 90)
			(size 0.4318 0.508)
			(layers "F.Cu" "F.Mask" "F.Paste")
			(net "NC_Q95_G2")
		)
		(pad "6" smd rect
			(at 0.94996 -0.649986 90)
			(size 0.4318 0.508)
			(layers "F.Cu" "F.Mask" "F.Paste")
			(net "HDD_ACTIVITY_BUF_N")
		)
	)
	(footprint ""
		(layer "F.Cu")
		(at 64.888364 -164.276786 -90)
		(property "Reference" "PR424"
			(at 0 0 270)
			(layer "F.SilkS")
			(hide yes)
			(effects
				(font
					(size 1.27 1.27)
				)
			)
		)
		(property "Value" ""
			(at 0 0 270)
			(layer "F.Fab")
			(effects
				(font
					(size 1.27 1.27)
				)
			)
		)
		(duplicate_pad_numbers_are_jumpers no)
		(fp_line
			(start -0.7874 0.4064)
			(end -0.7874 -0.4064)
			(stroke
				(width 0.1524)
				(type default)
			)
			(layer "F.SilkS")
		)
		(fp_line
			(start 0.7874 0.4064)
			(end -0.7874 0.4064)
			(stroke
				(width 0.1524)
				(type default)
			)
			(layer "F.SilkS")
		)
		(fp_line
			(start -0.7874 -0.4064)
			(end 0.7874 -0.4064)
			(stroke
				(width 0.1524)
				(type default)
			)
			(layer "F.SilkS")
		)
		(fp_line
			(start 0.7874 -0.4064)
			(end 0.7874 0.4064)
			(stroke
				(width 0.1524)
				(type default)
			)
			(layer "F.SilkS")
		)
		(fp_line
			(start -0.67945 0.3048)
			(end -0.67945 -0.305054)
			(stroke
				(width 0.1)
				(type default)
			)
			(layer "F.Fab")
		)
		(fp_line
			(start -0.12065 0.3048)
			(end -0.67945 0.3048)
			(stroke
				(width 0.1)
				(type default)
			)
			(layer "F.Fab")
		)
		(fp_line
			(start 0.120396 0.3048)
			(end 0.120396 0.2794)
			(stroke
				(width 0.1)
				(type default)
			)
			(layer "F.Fab")
		)
		(fp_line
			(start 0.67945 0.3048)
			(end 0.120396 0.3048)
			(stroke
				(width 0.1)
				(type default)
			)
			(layer "F.Fab")
		)
		(fp_line
			(start -0.12065 0.2794)
			(end -0.12065 0.3048)
			(stroke
				(width 0.1)
				(type default)
			)
			(layer "F.Fab")
		)
		(fp_line
			(start 0.120396 0.2794)
			(end -0.12065 0.2794)
			(stroke
				(width 0.1)
				(type default)
			)
			(layer "F.Fab")
		)
		(fp_line
			(start -0.12065 -0.2794)
			(end 0.12065 -0.2794)
			(stroke
				(width 0.1)
				(type default)
			)
			(layer "F.Fab")
		)
		(fp_line
			(start 0.12065 -0.2794)
			(end 0.12065 -0.3048)
			(stroke
				(width 0.1)
				(type default)
			)
			(layer "F.Fab")
		)
		(fp_line
			(start 0.12065 -0.3048)
			(end 0.67945 -0.3048)
			(stroke
				(width 0.1)
				(type default)
			)
			(layer "F.Fab")
		)
		(fp_line
			(start 0.67945 -0.3048)
			(end 0.67945 0.3048)
			(stroke
				(width 0.1)
				(type default)
			)
			(layer "F.Fab")
		)
		(fp_line
			(start -0.67945 -0.305054)
			(end -0.12065 -0.305054)
			(stroke
				(width 0.1)
				(type default)
			)
			(layer "F.Fab")
		)
		(fp_line
			(start -0.12065 -0.305054)
			(end -0.12065 -0.2794)
			(stroke
				(width 0.1)
				(type default)
			)
			(layer "F.Fab")
		)
		(pad "1" smd circle
			(at -0.40005 0 270)
			(size 0 0)
			(layers "F.Cu" "F.Mask" "F.Paste")
			(net "SW_PVDDCR_CPU0_P1_BOOT6")
		)
		(pad "2" smd circle
			(at 0.40005 0 270)
			(size 0 0)
			(layers "F.Cu" "F.Mask" "F.Paste")
			(net "SW_PVDDCR_CPU0_P1_BOOT6_RC")
		)
	)
	(footprint ""
		(layer "F.Cu")
		(at 20.00504 -332.004924 180)
		(property "Reference" "TP15"
			(at 6.88848 1.024382 0)
			(unlocked yes)
			(layer "F.SilkS")
			(effects
				(font
					(size 0.7874 0.5842)
					(thickness 0.1524)
				)
				(justify left)
			)
		)
		(property "Value" ""
			(at 0 0 180)
			(layer "F.Fab")
			(effects
				(font
					(size 1.27 1.27)
				)
			)
		)
		(duplicate_pad_numbers_are_jumpers no)
		(pad "1" smd circle
			(at 0 0 180)
			(size 0.762 0.762)
			(layers "F.Cu" "F.Mask" "F.Paste")
			(net "VSENSE_PVDDIO_P1_DP")
		)
	)
	(footprint ""
		(layer "F.Cu")
		(at 304.419 -358.14)
		(property "Reference" "PR8008"
			(at 0 0 0)
			(layer "F.SilkS")
			(hide yes)
			(effects
				(font
					(size 1.27 1.27)
				)
			)
		)
		(property "Value" ""
			(at 0 0 0)
			(layer "F.Fab")
			(effects
				(font
					(size 1.27 1.27)
				)
			)
		)
		(duplicate_pad_numbers_are_jumpers no)
		(fp_line
			(start -0.7874 -0.4064)
			(end 0.7874 -0.4064)
			(stroke
				(width 0.1524)
				(type default)
			)
			(layer "F.SilkS")
		)
		(fp_line
			(start -0.7874 0.4064)
			(end -0.7874 -0.4064)
			(stroke
				(width 0.1524)
				(type default)
			)
			(layer "F.SilkS")
		)
		(fp_line
			(start 0.7874 -0.4064)
			(end 0.7874 0.4064)
			(stroke
				(width 0.1524)
				(type default)
			)
			(layer "F.SilkS")
		)
		(fp_line
			(start 0.7874 0.4064)
			(end -0.7874 0.4064)
			(stroke
				(width 0.1524)
				(type default)
			)
			(layer "F.SilkS")
		)
		(fp_line
			(start -0.67945 -0.305054)
			(end -0.12065 -0.305054)
			(stroke
				(width 0.1)
				(type default)
			)
			(layer "F.Fab")
		)
		(fp_line
			(start -0.67945 0.3048)
			(end -0.67945 -0.305054)
			(stroke
				(width 0.1)
				(type default)
			)
			(layer "F.Fab")
		)
		(fp_line
			(start -0.12065 -0.305054)
			(end -0.12065 -0.2794)
			(stroke
				(width 0.1)
				(type default)
			)
			(layer "F.Fab")
		)
		(fp_line
			(start -0.12065 -0.2794)
			(end 0.12065 -0.2794)
			(stroke
				(width 0.1)
				(type default)
			)
			(layer "F.Fab")
		)
		(fp_line
			(start -0.12065 0.2794)
			(end -0.12065 0.3048)
			(stroke
				(width 0.1)
				(type default)
			)
			(layer "F.Fab")
		)
		(fp_line
			(start -0.12065 0.3048)
			(end -0.67945 0.3048)
			(stroke
				(width 0.1)
				(type default)
			)
			(layer "F.Fab")
		)
		(fp_line
			(start 0.120396 0.2794)
			(end -0.12065 0.2794)
			(stroke
				(width 0.1)
				(type default)
			)
			(layer "F.Fab")
		)
		(fp_line
			(start 0.120396 0.3048)
			(end 0.120396 0.2794)
			(stroke
				(width 0.1)
				(type default)
			)
			(layer "F.Fab")
		)
		(fp_line
			(start 0.12065 -0.3048)
			(end 0.67945 -0.3048)
			(stroke
				(width 0.1)
				(type default)
			)
			(layer "F.Fab")
		)
		(fp_line
			(start 0.12065 -0.2794)
			(end 0.12065 -0.3048)
			(stroke
				(width 0.1)
				(type default)
			)
			(layer "F.Fab")
		)
		(fp_line
			(start 0.67945 -0.3048)
			(end 0.67945 0.3048)
			(stroke
				(width 0.1)
				(type default)
			)
			(layer "F.Fab")
		)
		(fp_line
			(start 0.67945 0.3048)
			(end 0.120396 0.3048)
			(stroke
				(width 0.1)
				(type default)
			)
			(layer "F.Fab")
		)
		(pad "1" smd circle
			(at -0.40005 0)
			(size 0 0)
			(layers "F.Cu" "F.Mask" "F.Paste")
			(net "SVID_PVDDCR_CPU1_P0_SVD_R")
		)
		(pad "2" smd circle
			(at 0.40005 0)
			(size 0 0)
			(layers "F.Cu" "F.Mask" "F.Paste")
			(net "SVID_PVDDCR_CPU1_P0_SVD_R1")
		)
	)
	(footprint ""
		(layer "F.Cu")
		(at 280.019506 -349.381572 90)
		(property "Reference" "PC172"
			(at 0 0 90)
			(layer "F.SilkS")
			(hide yes)
			(effects
				(font
					(size 1.27 1.27)
				)
			)
		)
		(property "Value" ""
			(at 0 0 90)
			(layer "F.Fab")
			(effects
				(font
					(size 1.27 1.27)
				)
			)
		)
		(duplicate_pad_numbers_are_jumpers no)
		(fp_line
			(start 0.7874 -0.4064)
			(end 0.7874 0.4064)
			(stroke
				(width 0.1524)
				(type default)
			)
			(layer "F.SilkS")
		)
		(fp_line
			(start -0.7874 -0.4064)
			(end 0.7874 -0.4064)
			(stroke
				(width 0.1524)
				(type default)
			)
			(layer "F.SilkS")
		)
		(fp_line
			(start 0.7874 0.4064)
			(end 0.452628 0.4064)
			(stroke
				(width 0.1524)
				(type default)
			)
			(layer "F.SilkS")
		)
		(fp_line
			(start -0.258572 0.4064)
			(end -0.7874 0.4064)
			(stroke
				(width 0.1524)
				(type default)
			)
			(layer "F.SilkS")
		)
		(fp_line
			(start -0.7874 0.4064)
			(end -0.7874 -0.4064)
			(stroke
				(width 0.1524)
				(type default)
			)
			(layer "F.SilkS")
		)
		(fp_line
			(start -0.12065 -0.305054)
			(end -0.12065 -0.2794)
			(stroke
				(width 0.1)
				(type default)
			)
			(layer "F.Fab")
		)
		(fp_line
			(start -0.67945 -0.305054)
			(end -0.12065 -0.305054)
			(stroke
				(width 0.1)
				(type default)
			)
			(layer "F.Fab")
		)
		(fp_line
			(start 0.67945 -0.3048)
			(end 0.67945 0.3048)
			(stroke
				(width 0.1)
				(type default)
			)
			(layer "F.Fab")
		)
		(fp_line
			(start 0.12065 -0.3048)
			(end 0.67945 -0.3048)
			(stroke
				(width 0.1)
				(type default)
			)
			(layer "F.Fab")
		)
		(fp_line
			(start 0.12065 -0.2794)
			(end 0.12065 -0.3048)
			(stroke
				(width 0.1)
				(type default)
			)
			(layer "F.Fab")
		)
		(fp_line
			(start -0.12065 -0.2794)
			(end 0.12065 -0.2794)
			(stroke
				(width 0.1)
				(type default)
			)
			(layer "F.Fab")
		)
		(fp_line
			(start 0.120396 0.2794)
			(end -0.12065 0.2794)
			(stroke
				(width 0.1)
				(type default)
			)
			(layer "F.Fab")
		)
		(fp_line
			(start -0.12065 0.2794)
			(end -0.12065 0.3048)
			(stroke
				(width 0.1)
				(type default)
			)
			(layer "F.Fab")
		)
		(fp_line
			(start 0.67945 0.3048)
			(end 0.120396 0.3048)
			(stroke
				(width 0.1)
				(type default)
			)
			(layer "F.Fab")
		)
		(fp_line
			(start 0.120396 0.3048)
			(end 0.120396 0.2794)
			(stroke
				(width 0.1)
				(type default)
			)
			(layer "F.Fab")
		)
		(fp_line
			(start -0.12065 0.3048)
			(end -0.67945 0.3048)
			(stroke
				(width 0.1)
				(type default)
			)
			(layer "F.Fab")
		)
		(fp_line
			(start -0.67945 0.3048)
			(end -0.67945 -0.305054)
			(stroke
				(width 0.1)
				(type default)
			)
			(layer "F.Fab")
		)
		(pad "1" smd circle
			(at -0.40005 0 90)
			(size 0 0)
			(layers "F.Cu" "F.Mask" "F.Paste")
			(net "PVDDIO_P0_VCC3")
		)
		(pad "2" smd circle
			(at 0.40005 0 90)
			(size 0 0)
			(layers "F.Cu" "F.Mask" "F.Paste")
			(net "GND")
		)
	)
	(footprint ""
		(layer "F.Cu")
		(at 430.02835 -398.91208 180)
		(property "Reference" "R1056"
			(at 0 0 180)
			(layer "F.SilkS")
			(hide yes)
			(effects
				(font
					(size 1.27 1.27)
				)
			)
		)
		(property "Value" ""
			(at 0 0 180)
			(layer "F.Fab")
			(effects
				(font
					(size 1.27 1.27)
				)
			)
		)
		(duplicate_pad_numbers_are_jumpers no)
		(fp_line
			(start 0.32512 0.175006)
			(end -0.32512 0.175006)
			(stroke
				(width 0.1)
				(type default)
			)
			(layer "F.Fab")
		)
		(fp_line
			(start 0.32512 -0.175006)
			(end 0.32512 0.175006)
			(stroke
				(width 0.1)
				(type default)
			)
			(layer "F.Fab")
		)
		(fp_line
			(start -0.32512 0.175006)
			(end -0.32512 -0.175006)
			(stroke
				(width 0.1)
				(type default)
			)
			(layer "F.Fab")
		)
		(fp_line
			(start -0.32512 -0.175006)
			(end 0.32512 -0.175006)
			(stroke
				(width 0.1)
				(type default)
			)
			(layer "F.Fab")
		)
		(pad "1" smd rect
			(at -0.2667 0 180)
			(size 0.3048 0.381)
			(layers "F.Cu" "F.Mask" "F.Paste")
			(net "RT_CPU0_P2_ADDR3")
		)
		(pad "2" smd rect
			(at 0.2667 0)
			(size 0.3048 0.381)
			(layers "F.Cu" "F.Mask" "F.Paste")
			(net "GND")
		)
	)
	(footprint ""
		(layer "F.Cu")
		(at 356.484682 -414.062418)
		(property "Reference" "R4574"
			(at 0 0 0)
			(layer "F.SilkS")
			(hide yes)
			(effects
				(font
					(size 1.27 1.27)
				)
			)
		)
		(property "Value" ""
			(at 0 0 0)
			(layer "F.Fab")
			(effects
				(font
					(size 1.27 1.27)
				)
			)
		)
		(duplicate_pad_numbers_are_jumpers no)
		(fp_line
			(start -0.7874 -0.4064)
			(end 0.7874 -0.4064)
			(stroke
				(width 0.1524)
				(type default)
			)
			(layer "F.SilkS")
		)
		(fp_line
			(start -0.7874 0.4064)
			(end -0.7874 -0.4064)
			(stroke
				(width 0.1524)
				(type default)
			)
			(layer "F.SilkS")
		)
		(fp_line
			(start 0.7874 -0.4064)
			(end 0.7874 0.4064)
			(stroke
				(width 0.1524)
				(type default)
			)
			(layer "F.SilkS")
		)
		(fp_line
			(start 0.7874 0.4064)
			(end -0.7874 0.4064)
			(stroke
				(width 0.1524)
				(type default)
			)
			(layer "F.SilkS")
		)
		(fp_line
			(start -0.67945 -0.305054)
			(end -0.12065 -0.305054)
			(stroke
				(width 0.1)
				(type default)
			)
			(layer "F.Fab")
		)
		(fp_line
			(start -0.67945 0.3048)
			(end -0.67945 -0.305054)
			(stroke
				(width 0.1)
				(type default)
			)
			(layer "F.Fab")
		)
		(fp_line
			(start -0.12065 -0.305054)
			(end -0.12065 -0.2794)
			(stroke
				(width 0.1)
				(type default)
			)
			(layer "F.Fab")
		)
		(fp_line
			(start -0.12065 -0.2794)
			(end 0.12065 -0.2794)
			(stroke
				(width 0.1)
				(type default)
			)
			(layer "F.Fab")
		)
		(fp_line
			(start -0.12065 0.2794)
			(end -0.12065 0.3048)
			(stroke
				(width 0.1)
				(type default)
			)
			(layer "F.Fab")
		)
		(fp_line
			(start -0.12065 0.3048)
			(end -0.67945 0.3048)
			(stroke
				(width 0.1)
				(type default)
			)
			(layer "F.Fab")
		)
		(fp_line
			(start 0.120396 0.2794)
			(end -0.12065 0.2794)
			(stroke
				(width 0.1)
				(type default)
			)
			(layer "F.Fab")
		)
		(fp_line
			(start 0.120396 0.3048)
			(end 0.120396 0.2794)
			(stroke
				(width 0.1)
				(type default)
			)
			(layer "F.Fab")
		)
		(fp_line
			(start 0.12065 -0.3048)
			(end 0.67945 -0.3048)
			(stroke
				(width 0.1)
				(type default)
			)
			(layer "F.Fab")
		)
		(fp_line
			(start 0.12065 -0.2794)
			(end 0.12065 -0.3048)
			(stroke
				(width 0.1)
				(type default)
			)
			(layer "F.Fab")
		)
		(fp_line
			(start 0.67945 -0.3048)
			(end 0.67945 0.3048)
			(stroke
				(width 0.1)
				(type default)
			)
			(layer "F.Fab")
		)
		(fp_line
			(start 0.67945 0.3048)
			(end 0.120396 0.3048)
			(stroke
				(width 0.1)
				(type default)
			)
			(layer "F.Fab")
		)
		(pad "1" smd circle
			(at -0.40005 0)
			(size 0 0)
			(layers "F.Cu" "F.Mask" "F.Paste")
			(net "PRSNT_CABLE_GPU_A1_N")
		)
		(pad "2" smd circle
			(at 0.40005 0)
			(size 0 0)
			(layers "F.Cu" "F.Mask" "F.Paste")
			(net "PRSNT_CABLE_GPU_A1_ISO_N")
		)
	)
	(footprint ""
		(layer "F.Cu")
		(at 205.24089 -108.545376 180)
		(property "Reference" "R259"
			(at 0 0 180)
			(layer "F.SilkS")
			(hide yes)
			(effects
				(font
					(size 1.27 1.27)
				)
			)
		)
		(property "Value" ""
			(at 0 0 180)
			(layer "F.Fab")
			(effects
				(font
					(size 1.27 1.27)
				)
			)
		)
		(duplicate_pad_numbers_are_jumpers no)
		(fp_line
			(start 0.7874 0.4064)
			(end -0.7874 0.4064)
			(stroke
				(width 0.1524)
				(type default)
			)
			(layer "F.SilkS")
		)
		(fp_line
			(start 0.7874 -0.4064)
			(end 0.7874 0.4064)
			(stroke
				(width 0.1524)
				(type default)
			)
			(layer "F.SilkS")
		)
		(fp_line
			(start -0.7874 0.4064)
			(end -0.7874 -0.4064)
			(stroke
				(width 0.1524)
				(type default)
			)
			(layer "F.SilkS")
		)
		(fp_line
			(start -0.7874 -0.4064)
			(end 0.7874 -0.4064)
			(stroke
				(width 0.1524)
				(type default)
			)
			(layer "F.SilkS")
		)
		(fp_line
			(start 0.67945 0.3048)
			(end 0.120396 0.3048)
			(stroke
				(width 0.1)
				(type default)
			)
			(layer "F.Fab")
		)
		(fp_line
			(start 0.67945 -0.3048)
			(end 0.67945 0.3048)
			(stroke
				(width 0.1)
				(type default)
			)
			(layer "F.Fab")
		)
		(fp_line
			(start 0.12065 -0.2794)
			(end 0.12065 -0.3048)
			(stroke
				(width 0.1)
				(type default)
			)
			(layer "F.Fab")
		)
		(fp_line
			(start 0.12065 -0.3048)
			(end 0.67945 -0.3048)
			(stroke
				(width 0.1)
				(type default)
			)
			(layer "F.Fab")
		)
		(fp_line
			(start 0.120396 0.3048)
			(end 0.120396 0.2794)
			(stroke
				(width 0.1)
				(type default)
			)
			(layer "F.Fab")
		)
		(fp_line
			(start 0.120396 0.2794)
			(end -0.12065 0.2794)
			(stroke
				(width 0.1)
				(type default)
			)
			(layer "F.Fab")
		)
		(fp_line
			(start -0.12065 0.3048)
			(end -0.67945 0.3048)
			(stroke
				(width 0.1)
				(type default)
			)
			(layer "F.Fab")
		)
		(fp_line
			(start -0.12065 0.2794)
			(end -0.12065 0.3048)
			(stroke
				(width 0.1)
				(type default)
			)
			(layer "F.Fab")
		)
		(fp_line
			(start -0.12065 -0.2794)
			(end 0.12065 -0.2794)
			(stroke
				(width 0.1)
				(type default)
			)
			(layer "F.Fab")
		)
		(fp_line
			(start -0.12065 -0.305054)
			(end -0.12065 -0.2794)
			(stroke
				(width 0.1)
				(type default)
			)
			(layer "F.Fab")
		)
		(fp_line
			(start -0.67945 0.3048)
			(end -0.67945 -0.305054)
			(stroke
				(width 0.1)
				(type default)
			)
			(layer "F.Fab")
		)
		(fp_line
			(start -0.67945 -0.305054)
			(end -0.12065 -0.305054)
			(stroke
				(width 0.1)
				(type default)
			)
			(layer "F.Fab")
		)
		(pad "1" smd circle
			(at -0.40005 0 180)
			(size 0 0)
			(layers "F.Cu" "F.Mask" "F.Paste")
			(net "PWRGD_PVDD18_S5_P1")
		)
		(pad "2" smd circle
			(at 0.40005 0 180)
			(size 0 0)
			(layers "F.Cu" "F.Mask" "F.Paste")
			(net "PWRGD_PVDD18_S5_R_P1")
		)
	)
	(footprint ""
		(layer "F.Cu")
		(at 326.125586 -416.899344 -90)
		(property "Reference" "C6515"
			(at 0 0 270)
			(layer "F.SilkS")
			(hide yes)
			(effects
				(font
					(size 1.27 1.27)
				)
			)
		)
		(property "Value" ""
			(at 0 0 270)
			(layer "F.Fab")
			(effects
				(font
					(size 1.27 1.27)
				)
			)
		)
		(duplicate_pad_numbers_are_jumpers no)
		(fp_line
			(start -0.299974 0.150114)
			(end -0.299974 -0.150114)
			(stroke
				(width 0.1)
				(type default)
			)
			(layer "F.Fab")
		)
		(fp_line
			(start 0.299974 0.150114)
			(end -0.299974 0.150114)
			(stroke
				(width 0.1)
				(type default)
			)
			(layer "F.Fab")
		)
		(fp_line
			(start -0.299974 -0.150114)
			(end 0.299974 -0.150114)
			(stroke
				(width 0.1)
				(type default)
			)
			(layer "F.Fab")
		)
		(fp_line
			(start 0.299974 -0.150114)
			(end 0.299974 0.150114)
			(stroke
				(width 0.1)
				(type default)
			)
			(layer "F.Fab")
		)
		(pad "1" smd rect
			(at -0.2667 0 270)
			(size 0.3048 0.381)
			(layers "F.Cu" "F.Mask" "F.Paste")
			(net "P5E_CPU0_P0_TX_BUF_C_DP<7>")
		)
		(pad "2" smd rect
			(at 0.2667 0 270)
			(size 0.3048 0.381)
			(layers "F.Cu" "F.Mask" "F.Paste")
			(net "P5E_CPU0_P0_TX_BUF_DP<7>")
		)
	)
	(footprint ""
		(layer "F.Cu")
		(at 192.47358 -418.155882 90)
		(property "Reference" "U278"
			(at -1.78562 -2.481834 90)
			(unlocked yes)
			(layer "F.SilkS")
			(effects
				(font
					(size 0.7874 0.5842)
					(thickness 0.1524)
				)
				(justify left)
			)
		)
		(property "Value" ""
			(at 0 0 90)
			(layer "F.Fab")
			(effects
				(font
					(size 1.27 1.27)
				)
			)
		)
		(duplicate_pad_numbers_are_jumpers no)
		(fp_line
			(start 1.733296 -1.549908)
			(end 0.660908 -1.549908)
			(stroke
				(width 0.1524)
				(type default)
			)
			(layer "F.SilkS")
		)
		(fp_line
			(start 0.660908 -1.549908)
			(end 0 -0.889)
			(stroke
				(width 0.1524)
				(type default)
			)
			(layer "F.SilkS")
		)
		(fp_line
			(start -0.660908 -1.549908)
			(end -1.733296 -1.549908)
			(stroke
				(width 0.1524)
				(type default)
			)
			(layer "F.SilkS")
		)
		(fp_line
			(start -1.733296 -1.549908)
			(end -1.733296 1.549908)
			(stroke
				(width 0.1524)
				(type default)
			)
			(layer "F.SilkS")
		)
		(fp_line
			(start 0 -0.889)
			(end -0.660908 -1.549908)
			(stroke
				(width 0.1524)
				(type default)
			)
			(layer "F.SilkS")
		)
		(fp_line
			(start 1.733296 1.549908)
			(end 1.733296 -1.549908)
			(stroke
				(width 0.1524)
				(type default)
			)
			(layer "F.SilkS")
		)
		(fp_line
			(start -1.733296 1.549908)
			(end 1.733296 1.549908)
			(stroke
				(width 0.1524)
				(type default)
			)
			(layer "F.SilkS")
		)
		(fp_poly
			(pts
				(xy -2.505202 -1.550416) (xy -2.166366 -1.92913) (xy -1.95707 -1.401064)
			)
			(stroke
				(width 0)
				(type default)
			)
			(fill yes)
			(layer "F.SilkS")
		)
		(fp_line
			(start 0.849884 -1.549908)
			(end -0.849884 -1.549908)
			(stroke
				(width 0.1)
				(type default)
			)
			(layer "F.Fab")
		)
		(fp_line
			(start -0.849884 -1.549908)
			(end -0.849884 1.549908)
			(stroke
				(width 0.1)
				(type default)
			)
			(layer "F.Fab")
		)
		(fp_line
			(start 0.849884 1.549908)
			(end 0.849884 -1.549908)
			(stroke
				(width 0.1)
				(type default)
			)
			(layer "F.Fab")
		)
		(fp_line
			(start -0.849884 1.549908)
			(end 0.849884 1.549908)
			(stroke
				(width 0.1)
				(type default)
			)
			(layer "F.Fab")
		)
		(fp_poly
			(pts
				(xy -2.4384 -1.20396) (xy -2.4384 -0.69596) (xy -1.9304 -0.94996)
			)
			(stroke
				(width 0)
				(type default)
			)
			(fill yes)
			(layer "F.Fab")
		)
		(pad "1" smd rect
			(at -1.199896 -0.94996)
			(size 0.5588 0.8128)
			(layers "F.Cu" "F.Mask" "F.Paste")
			(net "FM_GPU_HSC_EN")
		)
		(pad "2" smd rect
			(at -1.199896 0)
			(size 0.5588 0.8128)
			(layers "F.Cu" "F.Mask" "F.Paste")
			(net "GPU_PRSNT_R")
		)
		(pad "3" smd rect
			(at -1.199896 0.94996)
			(size 0.5588 0.8128)
			(layers "F.Cu" "F.Mask" "F.Paste")
			(net "GND")
		)
		(pad "4" smd rect
			(at 1.199896 0.94996)
			(size 0.5588 0.8128)
			(layers "F.Cu" "F.Mask" "F.Paste")
			(net "FM_GPU_HSC_EN_BUF_R")
		)
		(pad "5" smd rect
			(at 1.199896 -0.94996)
			(size 0.5588 0.8128)
			(layers "F.Cu" "F.Mask" "F.Paste")
			(net "P3V3_AUX")
		)
	)
	(footprint ""
		(layer "F.Cu")
		(at 65.48882 -68.890388)
		(property "Reference" "ME2"
			(at 0 0 0)
			(layer "F.SilkS")
			(hide yes)
			(effects
				(font
					(size 1.27 1.27)
				)
			)
		)
		(property "Value" ""
			(at 0 0 0)
			(layer "F.Fab")
			(effects
				(font
					(size 1.27 1.27)
				)
			)
		)
		(duplicate_pad_numbers_are_jumpers no)
		(fp_rect
			(start 0 0)
			(end 3.3401 -0.5842)
			(stroke
				(width 0)
				(type default)
			)
			(fill yes)
			(layer "F.SilkS")
		)
		(fp_rect
			(start 1.32715 -3.2512)
			(end 2.01295 -3.4417)
			(stroke
				(width 0)
				(type default)
			)
			(fill yes)
			(layer "F.SilkS")
		)
		(fp_poly
			(pts
				(xy -0.070612 -0.681228) (xy -0.197612 -0.820928) (xy 0.852678 -1.91262) (xy 0.728472 -3.29184)
				(xy -0.248412 -4.300728) (xy -0.184912 -4.478528) (xy -0.007112 -4.503928) (xy 0.684022 -3.785616)
				(xy 0.65659 -4.0894) (xy 0.97155 -4.3434) (xy 1.22555 -4.3561) (xy 1.46685 -4.4704) (xy 2.01295 -4.4704)
				(xy 2.15265 -4.4069) (xy 2.44475 -4.191) (xy 2.49555 -4.191) (xy 2.59715 -4.2926) (xy 2.80035 -4.2672)
				(xy 2.88925 -4.1656) (xy 2.88925 -4.029456) (xy 3.345688 -4.503928) (xy 3.523488 -4.478528) (xy 3.586988 -4.300728)
				(xy 2.88925 -3.58013) (xy 2.88925 -3.3147) (xy 2.82575 -3.2385) (xy 2.67335 -3.2385) (xy 2.521966 -1.875282)
				(xy 2.545842 -1.85039)
				(arc
					(start 2.55905 -1.8415)
					(mid 2.648099 -1.766068)
					(end 2.717292 -1.672082)
				)
				(xy 3.536188 -0.820928) (xy 3.409188 -0.681228) (xy 3.244088 -0.693928)
				(arc
					(start 2.737612 -1.216914)
					(mid 2.31728 -0.925553)
					(end 1.86055 -1.1557)
				)
				(xy 0.92075 -1.1557) (xy 0.888492 -1.51384) (xy 0.094488 -0.693928)
			)
			(stroke
				(width 0)
				(type default)
			)
			(fill yes)
			(layer "F.SilkS")
		)
	)
	(footprint ""
		(layer "F.Cu")
		(at 339.254084 -339.40877)
		(property "Reference" "PC134_5"
			(at 0 0 0)
			(layer "F.SilkS")
			(hide yes)
			(effects
				(font
					(size 1.27 1.27)
				)
			)
		)
		(property "Value" ""
			(at 0 0 0)
			(layer "F.Fab")
			(effects
				(font
					(size 1.27 1.27)
				)
			)
		)
		(duplicate_pad_numbers_are_jumpers no)
		(fp_line
			(start -0.7874 -0.4064)
			(end 0.7874 -0.4064)
			(stroke
				(width 0.1524)
				(type default)
			)
			(layer "F.SilkS")
		)
		(fp_line
			(start -0.7874 0.4064)
			(end -0.7874 -0.4064)
			(stroke
				(width 0.1524)
				(type default)
			)
			(layer "F.SilkS")
		)
		(fp_line
			(start 0.7874 -0.4064)
			(end 0.7874 0.4064)
			(stroke
				(width 0.1524)
				(type default)
			)
			(layer "F.SilkS")
		)
		(fp_line
			(start 0.7874 0.4064)
			(end -0.7874 0.4064)
			(stroke
				(width 0.1524)
				(type default)
			)
			(layer "F.SilkS")
		)
		(fp_line
			(start -0.67945 -0.305054)
			(end -0.12065 -0.305054)
			(stroke
				(width 0.1)
				(type default)
			)
			(layer "F.Fab")
		)
		(fp_line
			(start -0.67945 0.3048)
			(end -0.67945 -0.305054)
			(stroke
				(width 0.1)
				(type default)
			)
			(layer "F.Fab")
		)
		(fp_line
			(start -0.12065 -0.305054)
			(end -0.12065 -0.2794)
			(stroke
				(width 0.1)
				(type default)
			)
			(layer "F.Fab")
		)
		(fp_line
			(start -0.12065 -0.2794)
			(end 0.12065 -0.2794)
			(stroke
				(width 0.1)
				(type default)
			)
			(layer "F.Fab")
		)
		(fp_line
			(start -0.12065 0.2794)
			(end -0.12065 0.3048)
			(stroke
				(width 0.1)
				(type default)
			)
			(layer "F.Fab")
		)
		(fp_line
			(start -0.12065 0.3048)
			(end -0.67945 0.3048)
			(stroke
				(width 0.1)
				(type default)
			)
			(layer "F.Fab")
		)
		(fp_line
			(start 0.120396 0.2794)
			(end -0.12065 0.2794)
			(stroke
				(width 0.1)
				(type default)
			)
			(layer "F.Fab")
		)
		(fp_line
			(start 0.120396 0.3048)
			(end 0.120396 0.2794)
			(stroke
				(width 0.1)
				(type default)
			)
			(layer "F.Fab")
		)
		(fp_line
			(start 0.12065 -0.3048)
			(end 0.67945 -0.3048)
			(stroke
				(width 0.1)
				(type default)
			)
			(layer "F.Fab")
		)
		(fp_line
			(start 0.12065 -0.2794)
			(end 0.12065 -0.3048)
			(stroke
				(width 0.1)
				(type default)
			)
			(layer "F.Fab")
		)
		(fp_line
			(start 0.67945 -0.3048)
			(end 0.67945 0.3048)
			(stroke
				(width 0.1)
				(type default)
			)
			(layer "F.Fab")
		)
		(fp_line
			(start 0.67945 0.3048)
			(end 0.120396 0.3048)
			(stroke
				(width 0.1)
				(type default)
			)
			(layer "F.Fab")
		)
		(pad "1" smd circle
			(at -0.40005 0)
			(size 0 0)
			(layers "F.Cu" "F.Mask" "F.Paste")
			(net "SW_P12V_AUX_PVDDCR_CPU1_P0_FLT")
		)
		(pad "2" smd circle
			(at 0.40005 0)
			(size 0 0)
			(layers "F.Cu" "F.Mask" "F.Paste")
			(net "GND")
		)
	)
	(footprint ""
		(layer "F.Cu")
		(at 332.195678 -27.267662 90)
		(property "Reference" "C1567"
			(at 0 0 90)
			(layer "F.SilkS")
			(hide yes)
			(effects
				(font
					(size 1.27 1.27)
				)
			)
		)
		(property "Value" ""
			(at 0 0 90)
			(layer "F.Fab")
			(effects
				(font
					(size 1.27 1.27)
				)
			)
		)
		(duplicate_pad_numbers_are_jumpers no)
		(fp_line
			(start 0.7874 -0.4064)
			(end 0.7874 0.4064)
			(stroke
				(width 0.1524)
				(type default)
			)
			(layer "F.SilkS")
		)
		(fp_line
			(start -0.7874 -0.4064)
			(end 0.7874 -0.4064)
			(stroke
				(width 0.1524)
				(type default)
			)
			(layer "F.SilkS")
		)
		(fp_line
			(start 0.7874 0.4064)
			(end -0.7874 0.4064)
			(stroke
				(width 0.1524)
				(type default)
			)
			(layer "F.SilkS")
		)
		(fp_line
			(start -0.7874 0.4064)
			(end -0.7874 -0.4064)
			(stroke
				(width 0.1524)
				(type default)
			)
			(layer "F.SilkS")
		)
		(fp_line
			(start -0.12065 -0.305054)
			(end -0.12065 -0.2794)
			(stroke
				(width 0.1)
				(type default)
			)
			(layer "F.Fab")
		)
		(fp_line
			(start -0.67945 -0.305054)
			(end -0.12065 -0.305054)
			(stroke
				(width 0.1)
				(type default)
			)
			(layer "F.Fab")
		)
		(fp_line
			(start 0.67945 -0.3048)
			(end 0.67945 0.3048)
			(stroke
				(width 0.1)
				(type default)
			)
			(layer "F.Fab")
		)
		(fp_line
			(start 0.12065 -0.3048)
			(end 0.67945 -0.3048)
			(stroke
				(width 0.1)
				(type default)
			)
			(layer "F.Fab")
		)
		(fp_line
			(start 0.12065 -0.2794)
			(end 0.12065 -0.3048)
			(stroke
				(width 0.1)
				(type default)
			)
			(layer "F.Fab")
		)
		(fp_line
			(start -0.12065 -0.2794)
			(end 0.12065 -0.2794)
			(stroke
				(width 0.1)
				(type default)
			)
			(layer "F.Fab")
		)
		(fp_line
			(start 0.120396 0.2794)
			(end -0.12065 0.2794)
			(stroke
				(width 0.1)
				(type default)
			)
			(layer "F.Fab")
		)
		(fp_line
			(start -0.12065 0.2794)
			(end -0.12065 0.3048)
			(stroke
				(width 0.1)
				(type default)
			)
			(layer "F.Fab")
		)
		(fp_line
			(start 0.67945 0.3048)
			(end 0.120396 0.3048)
			(stroke
				(width 0.1)
				(type default)
			)
			(layer "F.Fab")
		)
		(fp_line
			(start 0.120396 0.3048)
			(end 0.120396 0.2794)
			(stroke
				(width 0.1)
				(type default)
			)
			(layer "F.Fab")
		)
		(fp_line
			(start -0.12065 0.3048)
			(end -0.67945 0.3048)
			(stroke
				(width 0.1)
				(type default)
			)
			(layer "F.Fab")
		)
		(fp_line
			(start -0.67945 0.3048)
			(end -0.67945 -0.305054)
			(stroke
				(width 0.1)
				(type default)
			)
			(layer "F.Fab")
		)
		(pad "1" smd circle
			(at -0.40005 0 90)
			(size 0 0)
			(layers "F.Cu" "F.Mask" "F.Paste")
			(net "P1V5_BAT")
		)
		(pad "2" smd circle
			(at 0.40005 0 90)
			(size 0 0)
			(layers "F.Cu" "F.Mask" "F.Paste")
			(net "GND")
		)
	)
	(footprint ""
		(layer "F.Cu")
		(at 155.575 -114.554)
		(property "Reference" "U24"
			(at -3.103372 -0.603504 0)
			(unlocked yes)
			(layer "F.SilkS")
			(effects
				(font
					(size 0.7874 0.5842)
					(thickness 0.1524)
				)
			)
		)
		(property "Value" ""
			(at 0 0 0)
			(layer "F.Fab")
			(effects
				(font
					(size 1.27 1.27)
				)
			)
		)
		(duplicate_pad_numbers_are_jumpers no)
		(fp_line
			(start -1.949958 -1.610106)
			(end 1.949958 -1.610106)
			(stroke
				(width 0.1524)
				(type default)
			)
			(layer "F.SilkS")
		)
		(fp_line
			(start -1.949958 1.610106)
			(end -1.949958 -1.610106)
			(stroke
				(width 0.1524)
				(type default)
			)
			(layer "F.SilkS")
		)
		(fp_line
			(start 1.949958 -1.560068)
			(end 1.949958 1.610106)
			(stroke
				(width 0.1524)
				(type default)
			)
			(layer "F.SilkS")
		)
		(fp_line
			(start 1.949958 1.610106)
			(end -1.949958 1.610106)
			(stroke
				(width 0.1524)
				(type default)
			)
			(layer "F.SilkS")
		)
		(fp_line
			(start -0.750062 -1.560068)
			(end 0.750062 -1.560068)
			(stroke
				(width 0.1)
				(type default)
			)
			(layer "F.Fab")
		)
		(fp_line
			(start -0.750062 1.560068)
			(end -0.750062 -1.560068)
			(stroke
				(width 0.1)
				(type default)
			)
			(layer "F.Fab")
		)
		(fp_line
			(start 0.750062 -1.560068)
			(end 0.750062 1.560068)
			(stroke
				(width 0.1)
				(type default)
			)
			(layer "F.Fab")
		)
		(fp_line
			(start 0.750062 1.560068)
			(end -0.750062 1.560068)
			(stroke
				(width 0.1)
				(type default)
			)
			(layer "F.Fab")
		)
		(pad "D" smd rect
			(at 1.100074 0 270)
			(size 1.016 1.4224)
			(layers "F.Cu" "F.Mask" "F.Paste")
			(net "HP_LVC3_OCP_SFF_PRSNT2")
		)
		(pad "G" smd rect
			(at -1.100074 -0.94996 270)
			(size 1.016 1.4224)
			(layers "F.Cu" "F.Mask" "F.Paste")
			(net "HP_LVC3_OCP_SFF_PRSNT2_N")
		)
		(pad "S" smd rect
			(at -1.100074 0.94996 270)
			(size 1.016 1.4224)
			(layers "F.Cu" "F.Mask" "F.Paste")
			(net "GND")
		)
	)
	(footprint ""
		(layer "F.Cu")
		(at 343.429844 -383.88163 -90)
		(property "Reference" "C951"
			(at 0 0 270)
			(layer "F.SilkS")
			(hide yes)
			(effects
				(font
					(size 1.27 1.27)
				)
			)
		)
		(property "Value" ""
			(at 0 0 270)
			(layer "F.Fab")
			(effects
				(font
					(size 1.27 1.27)
				)
			)
		)
		(duplicate_pad_numbers_are_jumpers no)
		(fp_line
			(start -0.299974 0.150114)
			(end -0.299974 -0.150114)
			(stroke
				(width 0.1)
				(type default)
			)
			(layer "F.Fab")
		)
		(fp_line
			(start 0.299974 0.150114)
			(end -0.299974 0.150114)
			(stroke
				(width 0.1)
				(type default)
			)
			(layer "F.Fab")
		)
		(fp_line
			(start -0.299974 -0.150114)
			(end 0.299974 -0.150114)
			(stroke
				(width 0.1)
				(type default)
			)
			(layer "F.Fab")
		)
		(fp_line
			(start 0.299974 -0.150114)
			(end 0.299974 0.150114)
			(stroke
				(width 0.1)
				(type default)
			)
			(layer "F.Fab")
		)
		(pad "1" smd rect
			(at -0.2667 0 270)
			(size 0.3048 0.381)
			(layers "F.Cu" "F.Mask" "F.Paste")
			(net "P5E_CPU0_P1_TX_C_DP<7>")
		)
		(pad "2" smd rect
			(at 0.2667 0 270)
			(size 0.3048 0.381)
			(layers "F.Cu" "F.Mask" "F.Paste")
			(net "P5E_CPU0_P1_TX_DP<7>")
		)
	)
	(footprint ""
		(layer "F.Cu")
		(at 118.511574 -148.291042 -90)
		(property "Reference" "PL37"
			(at -0.575056 -3.974084 90)
			(unlocked yes)
			(layer "F.SilkS")
			(effects
				(font
					(size 0.7874 0.5842)
					(thickness 0.1524)
				)
				(justify left)
			)
		)
		(property "Value" ""
			(at 0 0 270)
			(layer "F.Fab")
			(effects
				(font
					(size 1.27 1.27)
				)
			)
		)
		(duplicate_pad_numbers_are_jumpers no)
		(fp_line
			(start -3.050032 2.999994)
			(end 3.050032 2.999994)
			(stroke
				(width 0.1524)
				(type default)
			)
			(layer "F.SilkS")
		)
		(fp_line
			(start 3.050032 2.999994)
			(end 3.050032 1.4478)
			(stroke
				(width 0.1524)
				(type default)
			)
			(layer "F.SilkS")
		)
		(fp_line
			(start -3.050032 1.4478)
			(end -3.050032 2.999994)
			(stroke
				(width 0.1524)
				(type default)
			)
			(layer "F.SilkS")
		)
		(fp_line
			(start 3.050032 -1.4478)
			(end 3.050032 -2.999994)
			(stroke
				(width 0.1524)
				(type default)
			)
			(layer "F.SilkS")
		)
		(fp_line
			(start -3.050032 -2.999994)
			(end -3.050032 -1.4478)
			(stroke
				(width 0.1524)
				(type default)
			)
			(layer "F.SilkS")
		)
		(fp_line
			(start 3.050032 -2.999994)
			(end -3.050032 -2.999994)
			(stroke
				(width 0.1524)
				(type default)
			)
			(layer "F.SilkS")
		)
		(fp_line
			(start -3.050032 2.999994)
			(end 3.050032 2.999994)
			(stroke
				(width 0.1)
				(type default)
			)
			(layer "F.Fab")
		)
		(fp_line
			(start 3.050032 2.999994)
			(end 3.050032 -2.999994)
			(stroke
				(width 0.1)
				(type default)
			)
			(layer "F.Fab")
		)
		(fp_line
			(start -3.050032 -2.999994)
			(end -3.050032 2.999994)
			(stroke
				(width 0.1)
				(type default)
			)
			(layer "F.Fab")
		)
		(fp_line
			(start 3.050032 -2.999994)
			(end -3.050032 -2.999994)
			(stroke
				(width 0.1)
				(type default)
			)
			(layer "F.Fab")
		)
		(pad "1" smd rect
			(at -2.525014 0 270)
			(size 1.651 2.6162)
			(layers "F.Cu" "F.Mask" "F.Paste")
			(net "SW_P12V_AUX_PVDDCR_SOC_P1_FLT")
		)
		(pad "2" smd rect
			(at 2.525014 0 270)
			(size 1.651 2.6162)
			(layers "F.Cu" "F.Mask" "F.Paste")
			(net "P12V_AUX")
		)
	)
	(footprint ""
		(layer "F.Cu")
		(at 339.70722 -335.022698 -90)
		(property "Reference" "PC133_C1P0_5"
			(at 0 0 270)
			(layer "F.SilkS")
			(hide yes)
			(effects
				(font
					(size 1.27 1.27)
				)
			)
		)
		(property "Value" ""
			(at 0 0 270)
			(layer "F.Fab")
			(effects
				(font
					(size 1.27 1.27)
				)
			)
		)
		(duplicate_pad_numbers_are_jumpers no)
		(fp_line
			(start -0.7874 0.4064)
			(end -0.7874 -0.4064)
			(stroke
				(width 0.1524)
				(type default)
			)
			(layer "F.SilkS")
		)
		(fp_line
			(start 0.7874 0.4064)
			(end -0.7874 0.4064)
			(stroke
				(width 0.1524)
				(type default)
			)
			(layer "F.SilkS")
		)
		(fp_line
			(start -0.7874 -0.4064)
			(end 0.7874 -0.4064)
			(stroke
				(width 0.1524)
				(type default)
			)
			(layer "F.SilkS")
		)
		(fp_line
			(start 0.7874 -0.4064)
			(end 0.7874 0.4064)
			(stroke
				(width 0.1524)
				(type default)
			)
			(layer "F.SilkS")
		)
		(fp_line
			(start -0.67945 0.3048)
			(end -0.67945 -0.305054)
			(stroke
				(width 0.1)
				(type default)
			)
			(layer "F.Fab")
		)
		(fp_line
			(start -0.12065 0.3048)
			(end -0.67945 0.3048)
			(stroke
				(width 0.1)
				(type default)
			)
			(layer "F.Fab")
		)
		(fp_line
			(start 0.120396 0.3048)
			(end 0.120396 0.2794)
			(stroke
				(width 0.1)
				(type default)
			)
			(layer "F.Fab")
		)
		(fp_line
			(start 0.67945 0.3048)
			(end 0.120396 0.3048)
			(stroke
				(width 0.1)
				(type default)
			)
			(layer "F.Fab")
		)
		(fp_line
			(start -0.12065 0.2794)
			(end -0.12065 0.3048)
			(stroke
				(width 0.1)
				(type default)
			)
			(layer "F.Fab")
		)
		(fp_line
			(start 0.120396 0.2794)
			(end -0.12065 0.2794)
			(stroke
				(width 0.1)
				(type default)
			)
			(layer "F.Fab")
		)
		(fp_line
			(start -0.12065 -0.2794)
			(end 0.12065 -0.2794)
			(stroke
				(width 0.1)
				(type default)
			)
			(layer "F.Fab")
		)
		(fp_line
			(start 0.12065 -0.2794)
			(end 0.12065 -0.3048)
			(stroke
				(width 0.1)
				(type default)
			)
			(layer "F.Fab")
		)
		(fp_line
			(start 0.12065 -0.3048)
			(end 0.67945 -0.3048)
			(stroke
				(width 0.1)
				(type default)
			)
			(layer "F.Fab")
		)
		(fp_line
			(start 0.67945 -0.3048)
			(end 0.67945 0.3048)
			(stroke
				(width 0.1)
				(type default)
			)
			(layer "F.Fab")
		)
		(fp_line
			(start -0.67945 -0.305054)
			(end -0.12065 -0.305054)
			(stroke
				(width 0.1)
				(type default)
			)
			(layer "F.Fab")
		)
		(fp_line
			(start -0.12065 -0.305054)
			(end -0.12065 -0.2794)
			(stroke
				(width 0.1)
				(type default)
			)
			(layer "F.Fab")
		)
		(pad "1" smd circle
			(at -0.40005 0 270)
			(size 0 0)
			(layers "F.Cu" "F.Mask" "F.Paste")
			(net "PVDDCR_CPU1_P0_PVCC")
		)
		(pad "2" smd circle
			(at 0.40005 0 270)
			(size 0 0)
			(layers "F.Cu" "F.Mask" "F.Paste")
			(net "GND")
		)
	)
	(footprint ""
		(layer "F.Cu")
		(at 240.792 -283.5148 180)
		(property "Reference" "PC6503"
			(at 0 0 180)
			(layer "F.SilkS")
			(hide yes)
			(effects
				(font
					(size 1.27 1.27)
				)
			)
		)
		(property "Value" ""
			(at 0 0 180)
			(layer "F.Fab")
			(effects
				(font
					(size 1.27 1.27)
				)
			)
		)
		(duplicate_pad_numbers_are_jumpers no)
		(fp_line
			(start 1.524 0.762)
			(end -1.524 0.762)
			(stroke
				(width 0.1524)
				(type default)
			)
			(layer "F.SilkS")
		)
		(fp_line
			(start 1.524 -0.762)
			(end 1.524 0.762)
			(stroke
				(width 0.1524)
				(type default)
			)
			(layer "F.SilkS")
		)
		(fp_line
			(start -1.524 0.762)
			(end -1.524 -0.762)
			(stroke
				(width 0.1524)
				(type default)
			)
			(layer "F.SilkS")
		)
		(fp_line
			(start -1.524 -0.762)
			(end 1.524 -0.762)
			(stroke
				(width 0.1524)
				(type default)
			)
			(layer "F.SilkS")
		)
		(fp_line
			(start 1.1049 0.724916)
			(end 1.1049 -0.724916)
			(stroke
				(width 0.1)
				(type default)
			)
			(layer "F.Fab")
		)
		(fp_line
			(start 1.1049 -0.724916)
			(end -1.1049 -0.724916)
			(stroke
				(width 0.1)
				(type default)
			)
			(layer "F.Fab")
		)
		(fp_line
			(start -1.1049 0.724916)
			(end 1.1049 0.724916)
			(stroke
				(width 0.1)
				(type default)
			)
			(layer "F.Fab")
		)
		(fp_line
			(start -1.1049 -0.724916)
			(end -1.1049 0.724916)
			(stroke
				(width 0.1)
				(type default)
			)
			(layer "F.Fab")
		)
		(pad "1" smd rect
			(at -0.889 0)
			(size 1.016 1.27)
			(layers "F.Cu" "F.Mask" "F.Paste")
			(net "SW_P12V_AUX_P1V8_RETIMER_CPU0_FLT")
		)
		(pad "2" smd rect
			(at 0.889 0)
			(size 1.016 1.27)
			(layers "F.Cu" "F.Mask" "F.Paste")
			(net "GND")
		)
	)
	(footprint ""
		(layer "F.Cu")
		(at 191.41694 -403.611842)
		(property "Reference" "PR3937"
			(at 0 0 0)
			(layer "F.SilkS")
			(hide yes)
			(effects
				(font
					(size 1.27 1.27)
				)
			)
		)
		(property "Value" ""
			(at 0 0 0)
			(layer "F.Fab")
			(effects
				(font
					(size 1.27 1.27)
				)
			)
		)
		(duplicate_pad_numbers_are_jumpers no)
		(fp_line
			(start -0.7874 -0.4064)
			(end 0.7874 -0.4064)
			(stroke
				(width 0.1524)
				(type default)
			)
			(layer "F.SilkS")
		)
		(fp_line
			(start -0.7874 0.4064)
			(end -0.7874 -0.4064)
			(stroke
				(width 0.1524)
				(type default)
			)
			(layer "F.SilkS")
		)
		(fp_line
			(start 0.7874 -0.4064)
			(end 0.7874 0.4064)
			(stroke
				(width 0.1524)
				(type default)
			)
			(layer "F.SilkS")
		)
		(fp_line
			(start 0.7874 0.4064)
			(end -0.7874 0.4064)
			(stroke
				(width 0.1524)
				(type default)
			)
			(layer "F.SilkS")
		)
		(fp_line
			(start -0.67945 -0.305054)
			(end -0.12065 -0.305054)
			(stroke
				(width 0.1)
				(type default)
			)
			(layer "F.Fab")
		)
		(fp_line
			(start -0.67945 0.3048)
			(end -0.67945 -0.305054)
			(stroke
				(width 0.1)
				(type default)
			)
			(layer "F.Fab")
		)
		(fp_line
			(start -0.12065 -0.305054)
			(end -0.12065 -0.2794)
			(stroke
				(width 0.1)
				(type default)
			)
			(layer "F.Fab")
		)
		(fp_line
			(start -0.12065 -0.2794)
			(end 0.12065 -0.2794)
			(stroke
				(width 0.1)
				(type default)
			)
			(layer "F.Fab")
		)
		(fp_line
			(start -0.12065 0.2794)
			(end -0.12065 0.3048)
			(stroke
				(width 0.1)
				(type default)
			)
			(layer "F.Fab")
		)
		(fp_line
			(start -0.12065 0.3048)
			(end -0.67945 0.3048)
			(stroke
				(width 0.1)
				(type default)
			)
			(layer "F.Fab")
		)
		(fp_line
			(start 0.120396 0.2794)
			(end -0.12065 0.2794)
			(stroke
				(width 0.1)
				(type default)
			)
			(layer "F.Fab")
		)
		(fp_line
			(start 0.120396 0.3048)
			(end 0.120396 0.2794)
			(stroke
				(width 0.1)
				(type default)
			)
			(layer "F.Fab")
		)
		(fp_line
			(start 0.12065 -0.3048)
			(end 0.67945 -0.3048)
			(stroke
				(width 0.1)
				(type default)
			)
			(layer "F.Fab")
		)
		(fp_line
			(start 0.12065 -0.2794)
			(end 0.12065 -0.3048)
			(stroke
				(width 0.1)
				(type default)
			)
			(layer "F.Fab")
		)
		(fp_line
			(start 0.67945 -0.3048)
			(end 0.67945 0.3048)
			(stroke
				(width 0.1)
				(type default)
			)
			(layer "F.Fab")
		)
		(fp_line
			(start 0.67945 0.3048)
			(end 0.120396 0.3048)
			(stroke
				(width 0.1)
				(type default)
			)
			(layer "F.Fab")
		)
		(pad "1" smd circle
			(at -0.40005 0)
			(size 0 0)
			(layers "F.Cu" "F.Mask" "F.Paste")
			(net "HSC_MODE")
		)
		(pad "2" smd circle
			(at 0.40005 0)
			(size 0 0)
			(layers "F.Cu" "F.Mask" "F.Paste")
			(net "AGND_HSC")
		)
	)
	(footprint ""
		(layer "F.Cu")
		(at 299.72 -108.966 -90)
		(property "Reference" "R1345"
			(at 0 0 270)
			(layer "F.SilkS")
			(hide yes)
			(effects
				(font
					(size 1.27 1.27)
				)
			)
		)
		(property "Value" ""
			(at 0 0 270)
			(layer "F.Fab")
			(effects
				(font
					(size 1.27 1.27)
				)
			)
		)
		(duplicate_pad_numbers_are_jumpers no)
		(fp_line
			(start -0.7874 0.4064)
			(end -0.7874 -0.4064)
			(stroke
				(width 0.1524)
				(type default)
			)
			(layer "F.SilkS")
		)
		(fp_line
			(start 0.7874 0.4064)
			(end -0.7874 0.4064)
			(stroke
				(width 0.1524)
				(type default)
			)
			(layer "F.SilkS")
		)
		(fp_line
			(start -0.7874 -0.4064)
			(end 0.7874 -0.4064)
			(stroke
				(width 0.1524)
				(type default)
			)
			(layer "F.SilkS")
		)
		(fp_line
			(start 0.7874 -0.4064)
			(end 0.7874 0.4064)
			(stroke
				(width 0.1524)
				(type default)
			)
			(layer "F.SilkS")
		)
		(fp_line
			(start -0.67945 0.3048)
			(end -0.67945 -0.305054)
			(stroke
				(width 0.1)
				(type default)
			)
			(layer "F.Fab")
		)
		(fp_line
			(start -0.12065 0.3048)
			(end -0.67945 0.3048)
			(stroke
				(width 0.1)
				(type default)
			)
			(layer "F.Fab")
		)
		(fp_line
			(start 0.120396 0.3048)
			(end 0.120396 0.2794)
			(stroke
				(width 0.1)
				(type default)
			)
			(layer "F.Fab")
		)
		(fp_line
			(start 0.67945 0.3048)
			(end 0.120396 0.3048)
			(stroke
				(width 0.1)
				(type default)
			)
			(layer "F.Fab")
		)
		(fp_line
			(start -0.12065 0.2794)
			(end -0.12065 0.3048)
			(stroke
				(width 0.1)
				(type default)
			)
			(layer "F.Fab")
		)
		(fp_line
			(start 0.120396 0.2794)
			(end -0.12065 0.2794)
			(stroke
				(width 0.1)
				(type default)
			)
			(layer "F.Fab")
		)
		(fp_line
			(start -0.12065 -0.2794)
			(end 0.12065 -0.2794)
			(stroke
				(width 0.1)
				(type default)
			)
			(layer "F.Fab")
		)
		(fp_line
			(start 0.12065 -0.2794)
			(end 0.12065 -0.3048)
			(stroke
				(width 0.1)
				(type default)
			)
			(layer "F.Fab")
		)
		(fp_line
			(start 0.12065 -0.3048)
			(end 0.67945 -0.3048)
			(stroke
				(width 0.1)
				(type default)
			)
			(layer "F.Fab")
		)
		(fp_line
			(start 0.67945 -0.3048)
			(end 0.67945 0.3048)
			(stroke
				(width 0.1)
				(type default)
			)
			(layer "F.Fab")
		)
		(fp_line
			(start -0.67945 -0.305054)
			(end -0.12065 -0.305054)
			(stroke
				(width 0.1)
				(type default)
			)
			(layer "F.Fab")
		)
		(fp_line
			(start -0.12065 -0.305054)
			(end -0.12065 -0.2794)
			(stroke
				(width 0.1)
				(type default)
			)
			(layer "F.Fab")
		)
		(pad "1" smd circle
			(at -0.40005 0 270)
			(size 0 0)
			(layers "F.Cu" "F.Mask" "F.Paste")
			(net "SMB_INA230_3V3AUX_SDA")
		)
		(pad "2" smd circle
			(at 0.40005 0 270)
			(size 0 0)
			(layers "F.Cu" "F.Mask" "F.Paste")
			(net "SMB_INA230_6_3V3AUX_SDA_R")
		)
	)
	(footprint ""
		(layer "F.Cu")
		(at 167.132 -120.360948 180)
		(property "Reference" "R639"
			(at 0 0 180)
			(layer "F.SilkS")
			(hide yes)
			(effects
				(font
					(size 1.27 1.27)
				)
			)
		)
		(property "Value" ""
			(at 0 0 180)
			(layer "F.Fab")
			(effects
				(font
					(size 1.27 1.27)
				)
			)
		)
		(duplicate_pad_numbers_are_jumpers no)
		(fp_line
			(start 0.7874 0.4064)
			(end -0.7874 0.4064)
			(stroke
				(width 0.1524)
				(type default)
			)
			(layer "F.SilkS")
		)
		(fp_line
			(start 0.7874 -0.4064)
			(end 0.7874 0.4064)
			(stroke
				(width 0.1524)
				(type default)
			)
			(layer "F.SilkS")
		)
		(fp_line
			(start -0.7874 0.4064)
			(end -0.7874 -0.4064)
			(stroke
				(width 0.1524)
				(type default)
			)
			(layer "F.SilkS")
		)
		(fp_line
			(start -0.7874 -0.4064)
			(end 0.7874 -0.4064)
			(stroke
				(width 0.1524)
				(type default)
			)
			(layer "F.SilkS")
		)
		(fp_line
			(start 0.67945 0.3048)
			(end 0.120396 0.3048)
			(stroke
				(width 0.1)
				(type default)
			)
			(layer "F.Fab")
		)
		(fp_line
			(start 0.67945 -0.3048)
			(end 0.67945 0.3048)
			(stroke
				(width 0.1)
				(type default)
			)
			(layer "F.Fab")
		)
		(fp_line
			(start 0.12065 -0.2794)
			(end 0.12065 -0.3048)
			(stroke
				(width 0.1)
				(type default)
			)
			(layer "F.Fab")
		)
		(fp_line
			(start 0.12065 -0.3048)
			(end 0.67945 -0.3048)
			(stroke
				(width 0.1)
				(type default)
			)
			(layer "F.Fab")
		)
		(fp_line
			(start 0.120396 0.3048)
			(end 0.120396 0.2794)
			(stroke
				(width 0.1)
				(type default)
			)
			(layer "F.Fab")
		)
		(fp_line
			(start 0.120396 0.2794)
			(end -0.12065 0.2794)
			(stroke
				(width 0.1)
				(type default)
			)
			(layer "F.Fab")
		)
		(fp_line
			(start -0.12065 0.3048)
			(end -0.67945 0.3048)
			(stroke
				(width 0.1)
				(type default)
			)
			(layer "F.Fab")
		)
		(fp_line
			(start -0.12065 0.2794)
			(end -0.12065 0.3048)
			(stroke
				(width 0.1)
				(type default)
			)
			(layer "F.Fab")
		)
		(fp_line
			(start -0.12065 -0.2794)
			(end 0.12065 -0.2794)
			(stroke
				(width 0.1)
				(type default)
			)
			(layer "F.Fab")
		)
		(fp_line
			(start -0.12065 -0.305054)
			(end -0.12065 -0.2794)
			(stroke
				(width 0.1)
				(type default)
			)
			(layer "F.Fab")
		)
		(fp_line
			(start -0.67945 0.3048)
			(end -0.67945 -0.305054)
			(stroke
				(width 0.1)
				(type default)
			)
			(layer "F.Fab")
		)
		(fp_line
			(start -0.67945 -0.305054)
			(end -0.12065 -0.305054)
			(stroke
				(width 0.1)
				(type default)
			)
			(layer "F.Fab")
		)
		(pad "1" smd circle
			(at -0.40005 0 180)
			(size 0 0)
			(layers "F.Cu" "F.Mask" "F.Paste")
			(net "CPLD_PROGRAMN")
		)
		(pad "2" smd circle
			(at 0.40005 0 180)
			(size 0 0)
			(layers "F.Cu" "F.Mask" "F.Paste")
			(net "P3V3_AUX")
		)
	)
	(footprint ""
		(layer "F.Cu")
		(at 7.124192 -99.42195)
		(property "Reference" "Y8004"
			(at -2.821178 -3.284728 0)
			(unlocked yes)
			(layer "F.SilkS")
			(effects
				(font
					(size 0.7874 0.5842)
					(thickness 0.1524)
				)
				(justify left)
			)
		)
		(property "Value" ""
			(at 0 0 0)
			(layer "F.Fab")
			(effects
				(font
					(size 1.27 1.27)
				)
			)
		)
		(duplicate_pad_numbers_are_jumpers no)
		(fp_line
			(start -1.380236 -1.579372)
			(end -1.380236 1.579372)
			(stroke
				(width 0.1524)
				(type default)
			)
			(layer "F.SilkS")
		)
		(fp_line
			(start -1.380236 1.579372)
			(end 1.380236 1.579372)
			(stroke
				(width 0.1524)
				(type default)
			)
			(layer "F.SilkS")
		)
		(fp_line
			(start 1.380236 -1.579372)
			(end -1.380236 -1.579372)
			(stroke
				(width 0.1524)
				(type default)
			)
			(layer "F.SilkS")
		)
		(fp_line
			(start 1.380236 1.579372)
			(end 1.380236 -1.579372)
			(stroke
				(width 0.1524)
				(type default)
			)
			(layer "F.SilkS")
		)
		(fp_poly
			(pts
				(xy -2.914396 -1.099312) (xy -2.914396 -0.337312) (xy -2.152396 -0.718312)
			)
			(stroke
				(width 0)
				(type default)
			)
			(fill yes)
			(layer "F.SilkS")
		)
		(fp_line
			(start -1.050036 -1.299972)
			(end -1.050036 1.299972)
			(stroke
				(width 0.1)
				(type default)
			)
			(layer "F.Fab")
		)
		(fp_line
			(start -1.050036 1.299972)
			(end 1.050036 1.299972)
			(stroke
				(width 0.1)
				(type default)
			)
			(layer "F.Fab")
		)
		(fp_line
			(start 1.050036 -1.299972)
			(end -1.050036 -1.299972)
			(stroke
				(width 0.1)
				(type default)
			)
			(layer "F.Fab")
		)
		(fp_line
			(start 1.050036 1.299972)
			(end 1.050036 -1.299972)
			(stroke
				(width 0.1)
				(type default)
			)
			(layer "F.Fab")
		)
		(fp_poly
			(pts
				(xy -2.3114 -1.306068) (xy -2.3114 -0.544068) (xy -1.5494 -0.925068)
			)
			(stroke
				(width 0)
				(type default)
			)
			(fill yes)
			(layer "F.Fab")
		)
		(pad "1" smd rect
			(at -0.774954 -0.925068)
			(size 0.9144 1.016)
			(layers "F.Cu" "F.Mask" "F.Paste")
			(net "USB_HUB_XTAL_IN")
		)
		(pad "2" smd rect
			(at -0.774954 0.925068)
			(size 0.9144 1.016)
			(layers "F.Cu" "F.Mask" "F.Paste")
			(net "GND")
		)
		(pad "3" smd rect
			(at 0.774954 0.925068)
			(size 0.9144 1.016)
			(layers "F.Cu" "F.Mask" "F.Paste")
			(net "USB_HUB_XTAL_OUT")
		)
		(pad "4" smd rect
			(at 0.774954 -0.925068)
			(size 0.9144 1.016)
			(layers "F.Cu" "F.Mask" "F.Paste")
			(net "GND")
		)
	)
	(footprint ""
		(layer "F.Cu")
		(at 384.465576 -62.97295 90)
		(property "Reference" "C87"
			(at 0 0 90)
			(layer "F.SilkS")
			(hide yes)
			(effects
				(font
					(size 1.27 1.27)
				)
			)
		)
		(property "Value" ""
			(at 0 0 90)
			(layer "F.Fab")
			(effects
				(font
					(size 1.27 1.27)
				)
			)
		)
		(duplicate_pad_numbers_are_jumpers no)
		(fp_line
			(start 0.7874 -0.4064)
			(end 0.7874 0.4064)
			(stroke
				(width 0.1524)
				(type default)
			)
			(layer "F.SilkS")
		)
		(fp_line
			(start -0.7874 -0.4064)
			(end 0.7874 -0.4064)
			(stroke
				(width 0.1524)
				(type default)
			)
			(layer "F.SilkS")
		)
		(fp_line
			(start 0.7874 0.4064)
			(end -0.7874 0.4064)
			(stroke
				(width 0.1524)
				(type default)
			)
			(layer "F.SilkS")
		)
		(fp_line
			(start -0.7874 0.4064)
			(end -0.7874 -0.4064)
			(stroke
				(width 0.1524)
				(type default)
			)
			(layer "F.SilkS")
		)
		(fp_line
			(start -0.12065 -0.305054)
			(end -0.12065 -0.2794)
			(stroke
				(width 0.1)
				(type default)
			)
			(layer "F.Fab")
		)
		(fp_line
			(start -0.67945 -0.305054)
			(end -0.12065 -0.305054)
			(stroke
				(width 0.1)
				(type default)
			)
			(layer "F.Fab")
		)
		(fp_line
			(start 0.67945 -0.3048)
			(end 0.67945 0.3048)
			(stroke
				(width 0.1)
				(type default)
			)
			(layer "F.Fab")
		)
		(fp_line
			(start 0.12065 -0.3048)
			(end 0.67945 -0.3048)
			(stroke
				(width 0.1)
				(type default)
			)
			(layer "F.Fab")
		)
		(fp_line
			(start 0.12065 -0.2794)
			(end 0.12065 -0.3048)
			(stroke
				(width 0.1)
				(type default)
			)
			(layer "F.Fab")
		)
		(fp_line
			(start -0.12065 -0.2794)
			(end 0.12065 -0.2794)
			(stroke
				(width 0.1)
				(type default)
			)
			(layer "F.Fab")
		)
		(fp_line
			(start 0.120396 0.2794)
			(end -0.12065 0.2794)
			(stroke
				(width 0.1)
				(type default)
			)
			(layer "F.Fab")
		)
		(fp_line
			(start -0.12065 0.2794)
			(end -0.12065 0.3048)
			(stroke
				(width 0.1)
				(type default)
			)
			(layer "F.Fab")
		)
		(fp_line
			(start 0.67945 0.3048)
			(end 0.120396 0.3048)
			(stroke
				(width 0.1)
				(type default)
			)
			(layer "F.Fab")
		)
		(fp_line
			(start 0.120396 0.3048)
			(end 0.120396 0.2794)
			(stroke
				(width 0.1)
				(type default)
			)
			(layer "F.Fab")
		)
		(fp_line
			(start -0.12065 0.3048)
			(end -0.67945 0.3048)
			(stroke
				(width 0.1)
				(type default)
			)
			(layer "F.Fab")
		)
		(fp_line
			(start -0.67945 0.3048)
			(end -0.67945 -0.305054)
			(stroke
				(width 0.1)
				(type default)
			)
			(layer "F.Fab")
		)
		(pad "1" smd circle
			(at -0.40005 0 90)
			(size 0 0)
			(layers "F.Cu" "F.Mask" "F.Paste")
			(net "HDT_HDR_DBREQ_N")
		)
		(pad "2" smd circle
			(at 0.40005 0 90)
			(size 0 0)
			(layers "F.Cu" "F.Mask" "F.Paste")
			(net "GND")
		)
	)
	(footprint ""
		(layer "F.Cu")
		(at 362.267246 -261.747762 -90)
		(property "Reference" "C2622"
			(at 0 0 270)
			(layer "F.SilkS")
			(hide yes)
			(effects
				(font
					(size 1.27 1.27)
				)
			)
		)
		(property "Value" ""
			(at 0 0 270)
			(layer "F.Fab")
			(effects
				(font
					(size 1.27 1.27)
				)
			)
		)
		(duplicate_pad_numbers_are_jumpers no)
		(fp_line
			(start -0.7874 0.4064)
			(end -0.7874 -0.4064)
			(stroke
				(width 0.1524)
				(type default)
			)
			(layer "F.SilkS")
		)
		(fp_line
			(start 0.7874 0.4064)
			(end -0.7874 0.4064)
			(stroke
				(width 0.1524)
				(type default)
			)
			(layer "F.SilkS")
		)
		(fp_line
			(start -0.7874 -0.4064)
			(end 0.7874 -0.4064)
			(stroke
				(width 0.1524)
				(type default)
			)
			(layer "F.SilkS")
		)
		(fp_line
			(start 0.7874 -0.4064)
			(end 0.7874 0.4064)
			(stroke
				(width 0.1524)
				(type default)
			)
			(layer "F.SilkS")
		)
		(fp_line
			(start -0.67945 0.3048)
			(end -0.67945 -0.305054)
			(stroke
				(width 0.1)
				(type default)
			)
			(layer "F.Fab")
		)
		(fp_line
			(start -0.12065 0.3048)
			(end -0.67945 0.3048)
			(stroke
				(width 0.1)
				(type default)
			)
			(layer "F.Fab")
		)
		(fp_line
			(start 0.120396 0.3048)
			(end 0.120396 0.2794)
			(stroke
				(width 0.1)
				(type default)
			)
			(layer "F.Fab")
		)
		(fp_line
			(start 0.67945 0.3048)
			(end 0.120396 0.3048)
			(stroke
				(width 0.1)
				(type default)
			)
			(layer "F.Fab")
		)
		(fp_line
			(start -0.12065 0.2794)
			(end -0.12065 0.3048)
			(stroke
				(width 0.1)
				(type default)
			)
			(layer "F.Fab")
		)
		(fp_line
			(start 0.120396 0.2794)
			(end -0.12065 0.2794)
			(stroke
				(width 0.1)
				(type default)
			)
			(layer "F.Fab")
		)
		(fp_line
			(start -0.12065 -0.2794)
			(end 0.12065 -0.2794)
			(stroke
				(width 0.1)
				(type default)
			)
			(layer "F.Fab")
		)
		(fp_line
			(start 0.12065 -0.2794)
			(end 0.12065 -0.3048)
			(stroke
				(width 0.1)
				(type default)
			)
			(layer "F.Fab")
		)
		(fp_line
			(start 0.12065 -0.3048)
			(end 0.67945 -0.3048)
			(stroke
				(width 0.1)
				(type default)
			)
			(layer "F.Fab")
		)
		(fp_line
			(start 0.67945 -0.3048)
			(end 0.67945 0.3048)
			(stroke
				(width 0.1)
				(type default)
			)
			(layer "F.Fab")
		)
		(fp_line
			(start -0.67945 -0.305054)
			(end -0.12065 -0.305054)
			(stroke
				(width 0.1)
				(type default)
			)
			(layer "F.Fab")
		)
		(fp_line
			(start -0.12065 -0.305054)
			(end -0.12065 -0.2794)
			(stroke
				(width 0.1)
				(type default)
			)
			(layer "F.Fab")
		)
		(pad "1" smd circle
			(at -0.40005 0 270)
			(size 0 0)
			(layers "F.Cu" "F.Mask" "F.Paste")
			(net "PVDD11_S3_P0")
		)
		(pad "2" smd circle
			(at 0.40005 0 270)
			(size 0 0)
			(layers "F.Cu" "F.Mask" "F.Paste")
			(net "GND")
		)
	)
	(footprint ""
		(layer "F.Cu")
		(at 279.513792 -117.69217 180)
		(property "Reference" "R3393"
			(at 0 0 180)
			(layer "F.SilkS")
			(hide yes)
			(effects
				(font
					(size 1.27 1.27)
				)
			)
		)
		(property "Value" ""
			(at 0 0 180)
			(layer "F.Fab")
			(effects
				(font
					(size 1.27 1.27)
				)
			)
		)
		(duplicate_pad_numbers_are_jumpers no)
		(fp_line
			(start 0.7874 0.4064)
			(end -0.7874 0.4064)
			(stroke
				(width 0.1524)
				(type default)
			)
			(layer "F.SilkS")
		)
		(fp_line
			(start 0.7874 -0.4064)
			(end 0.7874 0.4064)
			(stroke
				(width 0.1524)
				(type default)
			)
			(layer "F.SilkS")
		)
		(fp_line
			(start -0.7874 0.4064)
			(end -0.7874 -0.4064)
			(stroke
				(width 0.1524)
				(type default)
			)
			(layer "F.SilkS")
		)
		(fp_line
			(start -0.7874 -0.4064)
			(end 0.7874 -0.4064)
			(stroke
				(width 0.1524)
				(type default)
			)
			(layer "F.SilkS")
		)
		(fp_line
			(start 0.67945 0.3048)
			(end 0.120396 0.3048)
			(stroke
				(width 0.1)
				(type default)
			)
			(layer "F.Fab")
		)
		(fp_line
			(start 0.67945 -0.3048)
			(end 0.67945 0.3048)
			(stroke
				(width 0.1)
				(type default)
			)
			(layer "F.Fab")
		)
		(fp_line
			(start 0.12065 -0.2794)
			(end 0.12065 -0.3048)
			(stroke
				(width 0.1)
				(type default)
			)
			(layer "F.Fab")
		)
		(fp_line
			(start 0.12065 -0.3048)
			(end 0.67945 -0.3048)
			(stroke
				(width 0.1)
				(type default)
			)
			(layer "F.Fab")
		)
		(fp_line
			(start 0.120396 0.3048)
			(end 0.120396 0.2794)
			(stroke
				(width 0.1)
				(type default)
			)
			(layer "F.Fab")
		)
		(fp_line
			(start 0.120396 0.2794)
			(end -0.12065 0.2794)
			(stroke
				(width 0.1)
				(type default)
			)
			(layer "F.Fab")
		)
		(fp_line
			(start -0.12065 0.3048)
			(end -0.67945 0.3048)
			(stroke
				(width 0.1)
				(type default)
			)
			(layer "F.Fab")
		)
		(fp_line
			(start -0.12065 0.2794)
			(end -0.12065 0.3048)
			(stroke
				(width 0.1)
				(type default)
			)
			(layer "F.Fab")
		)
		(fp_line
			(start -0.12065 -0.2794)
			(end 0.12065 -0.2794)
			(stroke
				(width 0.1)
				(type default)
			)
			(layer "F.Fab")
		)
		(fp_line
			(start -0.12065 -0.305054)
			(end -0.12065 -0.2794)
			(stroke
				(width 0.1)
				(type default)
			)
			(layer "F.Fab")
		)
		(fp_line
			(start -0.67945 0.3048)
			(end -0.67945 -0.305054)
			(stroke
				(width 0.1)
				(type default)
			)
			(layer "F.Fab")
		)
		(fp_line
			(start -0.67945 -0.305054)
			(end -0.12065 -0.305054)
			(stroke
				(width 0.1)
				(type default)
			)
			(layer "F.Fab")
		)
		(pad "1" smd circle
			(at -0.40005 0 180)
			(size 0 0)
			(layers "F.Cu" "F.Mask" "F.Paste")
			(net "SMB_IOEXP_3V3AUX_SCL_R")
		)
		(pad "2" smd circle
			(at 0.40005 0 180)
			(size 0 0)
			(layers "F.Cu" "F.Mask" "F.Paste")
			(net "SMB_IOEXP_3V3AUX_SCL")
		)
	)
	(footprint ""
		(layer "F.Cu")
		(at 364.196122 -187.088526 180)
		(property "Reference" "PL51"
			(at 3.7465 7.340854 0)
			(unlocked yes)
			(layer "F.SilkS")
			(effects
				(font
					(size 0.7874 0.5842)
					(thickness 0.1524)
				)
				(justify left)
			)
		)
		(property "Value" ""
			(at 0 0 180)
			(layer "F.Fab")
			(effects
				(font
					(size 1.27 1.27)
				)
			)
		)
		(duplicate_pad_numbers_are_jumpers no)
		(fp_line
			(start 3.750056 5.500116)
			(end 3.750056 -5.500116)
			(stroke
				(width 0.1524)
				(type default)
			)
			(layer "F.SilkS")
		)
		(fp_line
			(start 3.750056 -5.500116)
			(end 2.393442 -5.500116)
			(stroke
				(width 0.1524)
				(type default)
			)
			(layer "F.SilkS")
		)
		(fp_line
			(start 2.393442 5.500116)
			(end 3.750056 5.500116)
			(stroke
				(width 0.1524)
				(type default)
			)
			(layer "F.SilkS")
		)
		(fp_line
			(start -2.393442 5.500116)
			(end -3.750056 5.500116)
			(stroke
				(width 0.1524)
				(type default)
			)
			(layer "F.SilkS")
		)
		(fp_line
			(start -3.750056 5.500116)
			(end -3.750056 -5.500116)
			(stroke
				(width 0.1524)
				(type default)
			)
			(layer "F.SilkS")
		)
		(fp_line
			(start -3.750056 -5.500116)
			(end -2.393442 -5.500116)
			(stroke
				(width 0.1524)
				(type default)
			)
			(layer "F.SilkS")
		)
		(fp_poly
			(pts
				(xy -4.035806 -3.262122) (xy -4.395216 -2.1844) (xy -5.113528 -2.902712)
			)
			(stroke
				(width 0)
				(type default)
			)
			(fill yes)
			(layer "F.SilkS")
		)
		(fp_line
			(start 3.750056 5.500116)
			(end 3.750056 -5.500116)
			(stroke
				(width 0.1)
				(type default)
			)
			(layer "F.Fab")
		)
		(fp_line
			(start 3.750056 -5.500116)
			(end -3.750056 -5.500116)
			(stroke
				(width 0.1)
				(type default)
			)
			(layer "F.Fab")
		)
		(fp_line
			(start -3.750056 5.500116)
			(end 3.750056 5.500116)
			(stroke
				(width 0.1)
				(type default)
			)
			(layer "F.Fab")
		)
		(fp_line
			(start -3.750056 -5.500116)
			(end -3.750056 5.500116)
			(stroke
				(width 0.1)
				(type default)
			)
			(layer "F.Fab")
		)
		(fp_poly
			(pts
				(xy -4.9276 -4.757928) (xy -4.9276 -3.741928) (xy -3.9116 -4.249928)
			)
			(stroke
				(width 0)
				(type default)
			)
			(fill yes)
			(layer "F.Fab")
		)
		(pad "1" smd rect
			(at 0 -4.249928 90)
			(size 2.413 4.5212)
			(layers "F.Cu" "F.Mask" "F.Paste")
			(net "SW_PVDDCR_CPU0_P0_SW1")
		)
		(pad "2" smd rect
			(at 0 -1.175004 90)
			(size 1.3716 4.5212)
			(layers "F.Cu" "F.Mask" "F.Paste")
			(net "IND_CPU0_P0_CPL5")
		)
		(pad "3" smd rect
			(at 0 1.175004 90)
			(size 1.3716 4.5212)
			(layers "F.Cu" "F.Mask" "F.Paste")
			(net "IND_CPU0_P0_CPL1")
		)
		(pad "4" smd rect
			(at 0 4.249928 90)
			(size 2.413 4.5212)
			(layers "F.Cu" "F.Mask" "F.Paste")
			(net "PVDDCR_CPU0_P0")
		)
	)
	(footprint ""
		(layer "F.Cu")
		(at 113.105946 -258.795266)
		(property "Reference" "C2442"
			(at 0 0 0)
			(layer "F.SilkS")
			(hide yes)
			(effects
				(font
					(size 1.27 1.27)
				)
			)
		)
		(property "Value" ""
			(at 0 0 0)
			(layer "F.Fab")
			(effects
				(font
					(size 1.27 1.27)
				)
			)
		)
		(duplicate_pad_numbers_are_jumpers no)
		(fp_line
			(start -0.7874 -0.4064)
			(end 0.7874 -0.4064)
			(stroke
				(width 0.1524)
				(type default)
			)
			(layer "F.SilkS")
		)
		(fp_line
			(start -0.7874 0.4064)
			(end -0.7874 -0.4064)
			(stroke
				(width 0.1524)
				(type default)
			)
			(layer "F.SilkS")
		)
		(fp_line
			(start 0.7874 -0.4064)
			(end 0.7874 0.4064)
			(stroke
				(width 0.1524)
				(type default)
			)
			(layer "F.SilkS")
		)
		(fp_line
			(start 0.7874 0.4064)
			(end -0.7874 0.4064)
			(stroke
				(width 0.1524)
				(type default)
			)
			(layer "F.SilkS")
		)
		(fp_line
			(start -0.67945 -0.305054)
			(end -0.12065 -0.305054)
			(stroke
				(width 0.1)
				(type default)
			)
			(layer "F.Fab")
		)
		(fp_line
			(start -0.67945 0.3048)
			(end -0.67945 -0.305054)
			(stroke
				(width 0.1)
				(type default)
			)
			(layer "F.Fab")
		)
		(fp_line
			(start -0.12065 -0.305054)
			(end -0.12065 -0.2794)
			(stroke
				(width 0.1)
				(type default)
			)
			(layer "F.Fab")
		)
		(fp_line
			(start -0.12065 -0.2794)
			(end 0.12065 -0.2794)
			(stroke
				(width 0.1)
				(type default)
			)
			(layer "F.Fab")
		)
		(fp_line
			(start -0.12065 0.2794)
			(end -0.12065 0.3048)
			(stroke
				(width 0.1)
				(type default)
			)
			(layer "F.Fab")
		)
		(fp_line
			(start -0.12065 0.3048)
			(end -0.67945 0.3048)
			(stroke
				(width 0.1)
				(type default)
			)
			(layer "F.Fab")
		)
		(fp_line
			(start 0.120396 0.2794)
			(end -0.12065 0.2794)
			(stroke
				(width 0.1)
				(type default)
			)
			(layer "F.Fab")
		)
		(fp_line
			(start 0.120396 0.3048)
			(end 0.120396 0.2794)
			(stroke
				(width 0.1)
				(type default)
			)
			(layer "F.Fab")
		)
		(fp_line
			(start 0.12065 -0.3048)
			(end 0.67945 -0.3048)
			(stroke
				(width 0.1)
				(type default)
			)
			(layer "F.Fab")
		)
		(fp_line
			(start 0.12065 -0.2794)
			(end 0.12065 -0.3048)
			(stroke
				(width 0.1)
				(type default)
			)
			(layer "F.Fab")
		)
		(fp_line
			(start 0.67945 -0.3048)
			(end 0.67945 0.3048)
			(stroke
				(width 0.1)
				(type default)
			)
			(layer "F.Fab")
		)
		(fp_line
			(start 0.67945 0.3048)
			(end 0.120396 0.3048)
			(stroke
				(width 0.1)
				(type default)
			)
			(layer "F.Fab")
		)
		(pad "1" smd circle
			(at -0.40005 0)
			(size 0 0)
			(layers "F.Cu" "F.Mask" "F.Paste")
			(net "PVDDCR_SOC_P1")
		)
		(pad "2" smd circle
			(at 0.40005 0)
			(size 0 0)
			(layers "F.Cu" "F.Mask" "F.Paste")
			(net "GND")
		)
	)
	(footprint ""
		(layer "F.Cu")
		(at 308.198266 -431.256186)
		(property "Reference" "R4136"
			(at 0 0 0)
			(layer "F.SilkS")
			(hide yes)
			(effects
				(font
					(size 1.27 1.27)
				)
			)
		)
		(property "Value" ""
			(at 0 0 0)
			(layer "F.Fab")
			(effects
				(font
					(size 1.27 1.27)
				)
			)
		)
		(duplicate_pad_numbers_are_jumpers no)
		(fp_line
			(start -0.7874 -0.4064)
			(end 0.7874 -0.4064)
			(stroke
				(width 0.1524)
				(type default)
			)
			(layer "F.SilkS")
		)
		(fp_line
			(start -0.7874 0.4064)
			(end -0.7874 -0.4064)
			(stroke
				(width 0.1524)
				(type default)
			)
			(layer "F.SilkS")
		)
		(fp_line
			(start 0.7874 -0.4064)
			(end 0.7874 0.4064)
			(stroke
				(width 0.1524)
				(type default)
			)
			(layer "F.SilkS")
		)
		(fp_line
			(start 0.7874 0.4064)
			(end -0.7874 0.4064)
			(stroke
				(width 0.1524)
				(type default)
			)
			(layer "F.SilkS")
		)
		(fp_line
			(start -0.67945 -0.305054)
			(end -0.12065 -0.305054)
			(stroke
				(width 0.1)
				(type default)
			)
			(layer "F.Fab")
		)
		(fp_line
			(start -0.67945 0.3048)
			(end -0.67945 -0.305054)
			(stroke
				(width 0.1)
				(type default)
			)
			(layer "F.Fab")
		)
		(fp_line
			(start -0.12065 -0.305054)
			(end -0.12065 -0.2794)
			(stroke
				(width 0.1)
				(type default)
			)
			(layer "F.Fab")
		)
		(fp_line
			(start -0.12065 -0.2794)
			(end 0.12065 -0.2794)
			(stroke
				(width 0.1)
				(type default)
			)
			(layer "F.Fab")
		)
		(fp_line
			(start -0.12065 0.2794)
			(end -0.12065 0.3048)
			(stroke
				(width 0.1)
				(type default)
			)
			(layer "F.Fab")
		)
		(fp_line
			(start -0.12065 0.3048)
			(end -0.67945 0.3048)
			(stroke
				(width 0.1)
				(type default)
			)
			(layer "F.Fab")
		)
		(fp_line
			(start 0.120396 0.2794)
			(end -0.12065 0.2794)
			(stroke
				(width 0.1)
				(type default)
			)
			(layer "F.Fab")
		)
		(fp_line
			(start 0.120396 0.3048)
			(end 0.120396 0.2794)
			(stroke
				(width 0.1)
				(type default)
			)
			(layer "F.Fab")
		)
		(fp_line
			(start 0.12065 -0.3048)
			(end 0.67945 -0.3048)
			(stroke
				(width 0.1)
				(type default)
			)
			(layer "F.Fab")
		)
		(fp_line
			(start 0.12065 -0.2794)
			(end 0.12065 -0.3048)
			(stroke
				(width 0.1)
				(type default)
			)
			(layer "F.Fab")
		)
		(fp_line
			(start 0.67945 -0.3048)
			(end 0.67945 0.3048)
			(stroke
				(width 0.1)
				(type default)
			)
			(layer "F.Fab")
		)
		(fp_line
			(start 0.67945 0.3048)
			(end 0.120396 0.3048)
			(stroke
				(width 0.1)
				(type default)
			)
			(layer "F.Fab")
		)
		(pad "1" smd circle
			(at -0.40005 0)
			(size 0 0)
			(layers "F.Cu" "F.Mask" "F.Paste")
			(net "PRSNT_CABLE_GPU_A2_N")
		)
		(pad "2" smd circle
			(at 0.40005 0)
			(size 0 0)
			(layers "F.Cu" "F.Mask" "F.Paste")
			(net "GND")
		)
	)
	(footprint ""
		(layer "F.Cu")
		(at 175.641 -100.294948 -90)
		(property "Reference" "R163"
			(at 0 0 270)
			(layer "F.SilkS")
			(hide yes)
			(effects
				(font
					(size 1.27 1.27)
				)
			)
		)
		(property "Value" ""
			(at 0 0 270)
			(layer "F.Fab")
			(effects
				(font
					(size 1.27 1.27)
				)
			)
		)
		(duplicate_pad_numbers_are_jumpers no)
		(fp_line
			(start -0.7874 0.4064)
			(end -0.7874 -0.4064)
			(stroke
				(width 0.1524)
				(type default)
			)
			(layer "F.SilkS")
		)
		(fp_line
			(start 0.7874 0.4064)
			(end -0.7874 0.4064)
			(stroke
				(width 0.1524)
				(type default)
			)
			(layer "F.SilkS")
		)
		(fp_line
			(start -0.7874 -0.4064)
			(end 0.7874 -0.4064)
			(stroke
				(width 0.1524)
				(type default)
			)
			(layer "F.SilkS")
		)
		(fp_line
			(start 0.7874 -0.4064)
			(end 0.7874 0.4064)
			(stroke
				(width 0.1524)
				(type default)
			)
			(layer "F.SilkS")
		)
		(fp_line
			(start -0.67945 0.3048)
			(end -0.67945 -0.305054)
			(stroke
				(width 0.1)
				(type default)
			)
			(layer "F.Fab")
		)
		(fp_line
			(start -0.12065 0.3048)
			(end -0.67945 0.3048)
			(stroke
				(width 0.1)
				(type default)
			)
			(layer "F.Fab")
		)
		(fp_line
			(start 0.120396 0.3048)
			(end 0.120396 0.2794)
			(stroke
				(width 0.1)
				(type default)
			)
			(layer "F.Fab")
		)
		(fp_line
			(start 0.67945 0.3048)
			(end 0.120396 0.3048)
			(stroke
				(width 0.1)
				(type default)
			)
			(layer "F.Fab")
		)
		(fp_line
			(start -0.12065 0.2794)
			(end -0.12065 0.3048)
			(stroke
				(width 0.1)
				(type default)
			)
			(layer "F.Fab")
		)
		(fp_line
			(start 0.120396 0.2794)
			(end -0.12065 0.2794)
			(stroke
				(width 0.1)
				(type default)
			)
			(layer "F.Fab")
		)
		(fp_line
			(start -0.12065 -0.2794)
			(end 0.12065 -0.2794)
			(stroke
				(width 0.1)
				(type default)
			)
			(layer "F.Fab")
		)
		(fp_line
			(start 0.12065 -0.2794)
			(end 0.12065 -0.3048)
			(stroke
				(width 0.1)
				(type default)
			)
			(layer "F.Fab")
		)
		(fp_line
			(start 0.12065 -0.3048)
			(end 0.67945 -0.3048)
			(stroke
				(width 0.1)
				(type default)
			)
			(layer "F.Fab")
		)
		(fp_line
			(start 0.67945 -0.3048)
			(end 0.67945 0.3048)
			(stroke
				(width 0.1)
				(type default)
			)
			(layer "F.Fab")
		)
		(fp_line
			(start -0.67945 -0.305054)
			(end -0.12065 -0.305054)
			(stroke
				(width 0.1)
				(type default)
			)
			(layer "F.Fab")
		)
		(fp_line
			(start -0.12065 -0.305054)
			(end -0.12065 -0.2794)
			(stroke
				(width 0.1)
				(type default)
			)
			(layer "F.Fab")
		)
		(pad "1" smd circle
			(at -0.40005 0 270)
			(size 0 0)
			(layers "F.Cu" "F.Mask" "F.Paste")
			(net "FM_I3C_CPU0_MUX0_OE_R_N")
		)
		(pad "2" smd circle
			(at 0.40005 0 270)
			(size 0 0)
			(layers "F.Cu" "F.Mask" "F.Paste")
			(net "FM_I3C_CPU0_MUX0_OE_N")
		)
	)
	(footprint ""
		(layer "F.Cu")
		(at 419.950138 -348.110556 180)
		(property "Reference" "PC169"
			(at 0 0 180)
			(layer "F.SilkS")
			(hide yes)
			(effects
				(font
					(size 1.27 1.27)
				)
			)
		)
		(property "Value" ""
			(at 0 0 180)
			(layer "F.Fab")
			(effects
				(font
					(size 1.27 1.27)
				)
			)
		)
		(duplicate_pad_numbers_are_jumpers no)
		(fp_line
			(start 0.7874 0.4064)
			(end -0.7874 0.4064)
			(stroke
				(width 0.1524)
				(type default)
			)
			(layer "F.SilkS")
		)
		(fp_line
			(start 0.7874 -0.4064)
			(end 0.7874 0.4064)
			(stroke
				(width 0.1524)
				(type default)
			)
			(layer "F.SilkS")
		)
		(fp_line
			(start -0.7874 0.4064)
			(end -0.7874 -0.4064)
			(stroke
				(width 0.1524)
				(type default)
			)
			(layer "F.SilkS")
		)
		(fp_line
			(start -0.7874 -0.4064)
			(end 0.7874 -0.4064)
			(stroke
				(width 0.1524)
				(type default)
			)
			(layer "F.SilkS")
		)
		(fp_line
			(start 0.67945 0.3048)
			(end 0.120396 0.3048)
			(stroke
				(width 0.1)
				(type default)
			)
			(layer "F.Fab")
		)
		(fp_line
			(start 0.67945 -0.3048)
			(end 0.67945 0.3048)
			(stroke
				(width 0.1)
				(type default)
			)
			(layer "F.Fab")
		)
		(fp_line
			(start 0.12065 -0.2794)
			(end 0.12065 -0.3048)
			(stroke
				(width 0.1)
				(type default)
			)
			(layer "F.Fab")
		)
		(fp_line
			(start 0.12065 -0.3048)
			(end 0.67945 -0.3048)
			(stroke
				(width 0.1)
				(type default)
			)
			(layer "F.Fab")
		)
		(fp_line
			(start 0.120396 0.3048)
			(end 0.120396 0.2794)
			(stroke
				(width 0.1)
				(type default)
			)
			(layer "F.Fab")
		)
		(fp_line
			(start 0.120396 0.2794)
			(end -0.12065 0.2794)
			(stroke
				(width 0.1)
				(type default)
			)
			(layer "F.Fab")
		)
		(fp_line
			(start -0.12065 0.3048)
			(end -0.67945 0.3048)
			(stroke
				(width 0.1)
				(type default)
			)
			(layer "F.Fab")
		)
		(fp_line
			(start -0.12065 0.2794)
			(end -0.12065 0.3048)
			(stroke
				(width 0.1)
				(type default)
			)
			(layer "F.Fab")
		)
		(fp_line
			(start -0.12065 -0.2794)
			(end 0.12065 -0.2794)
			(stroke
				(width 0.1)
				(type default)
			)
			(layer "F.Fab")
		)
		(fp_line
			(start -0.12065 -0.305054)
			(end -0.12065 -0.2794)
			(stroke
				(width 0.1)
				(type default)
			)
			(layer "F.Fab")
		)
		(fp_line
			(start -0.67945 0.3048)
			(end -0.67945 -0.305054)
			(stroke
				(width 0.1)
				(type default)
			)
			(layer "F.Fab")
		)
		(fp_line
			(start -0.67945 -0.305054)
			(end -0.12065 -0.305054)
			(stroke
				(width 0.1)
				(type default)
			)
			(layer "F.Fab")
		)
		(pad "1" smd circle
			(at -0.40005 0 180)
			(size 0 0)
			(layers "F.Cu" "F.Mask" "F.Paste")
			(net "SW_PVDD11_S3_P0_SW1")
		)
		(pad "2" smd circle
			(at 0.40005 0 180)
			(size 0 0)
			(layers "F.Cu" "F.Mask" "F.Paste")
			(net "SW_PVDD11_S3_P0_SW1_RC")
		)
	)
	(footprint ""
		(layer "F.Cu")
		(at 167.894 -99.06 180)
		(property "Reference" "R1143"
			(at 0 0 180)
			(layer "F.SilkS")
			(hide yes)
			(effects
				(font
					(size 1.27 1.27)
				)
			)
		)
		(property "Value" ""
			(at 0 0 180)
			(layer "F.Fab")
			(effects
				(font
					(size 1.27 1.27)
				)
			)
		)
		(duplicate_pad_numbers_are_jumpers no)
		(fp_line
			(start 0.7874 0.4064)
			(end -0.7874 0.4064)
			(stroke
				(width 0.1524)
				(type default)
			)
			(layer "F.SilkS")
		)
		(fp_line
			(start 0.7874 -0.4064)
			(end 0.7874 0.4064)
			(stroke
				(width 0.1524)
				(type default)
			)
			(layer "F.SilkS")
		)
		(fp_line
			(start -0.7874 0.4064)
			(end -0.7874 -0.4064)
			(stroke
				(width 0.1524)
				(type default)
			)
			(layer "F.SilkS")
		)
		(fp_line
			(start -0.7874 -0.4064)
			(end 0.7874 -0.4064)
			(stroke
				(width 0.1524)
				(type default)
			)
			(layer "F.SilkS")
		)
		(fp_line
			(start 0.67945 0.3048)
			(end 0.120396 0.3048)
			(stroke
				(width 0.1)
				(type default)
			)
			(layer "F.Fab")
		)
		(fp_line
			(start 0.67945 -0.3048)
			(end 0.67945 0.3048)
			(stroke
				(width 0.1)
				(type default)
			)
			(layer "F.Fab")
		)
		(fp_line
			(start 0.12065 -0.2794)
			(end 0.12065 -0.3048)
			(stroke
				(width 0.1)
				(type default)
			)
			(layer "F.Fab")
		)
		(fp_line
			(start 0.12065 -0.3048)
			(end 0.67945 -0.3048)
			(stroke
				(width 0.1)
				(type default)
			)
			(layer "F.Fab")
		)
		(fp_line
			(start 0.120396 0.3048)
			(end 0.120396 0.2794)
			(stroke
				(width 0.1)
				(type default)
			)
			(layer "F.Fab")
		)
		(fp_line
			(start 0.120396 0.2794)
			(end -0.12065 0.2794)
			(stroke
				(width 0.1)
				(type default)
			)
			(layer "F.Fab")
		)
		(fp_line
			(start -0.12065 0.3048)
			(end -0.67945 0.3048)
			(stroke
				(width 0.1)
				(type default)
			)
			(layer "F.Fab")
		)
		(fp_line
			(start -0.12065 0.2794)
			(end -0.12065 0.3048)
			(stroke
				(width 0.1)
				(type default)
			)
			(layer "F.Fab")
		)
		(fp_line
			(start -0.12065 -0.2794)
			(end 0.12065 -0.2794)
			(stroke
				(width 0.1)
				(type default)
			)
			(layer "F.Fab")
		)
		(fp_line
			(start -0.12065 -0.305054)
			(end -0.12065 -0.2794)
			(stroke
				(width 0.1)
				(type default)
			)
			(layer "F.Fab")
		)
		(fp_line
			(start -0.67945 0.3048)
			(end -0.67945 -0.305054)
			(stroke
				(width 0.1)
				(type default)
			)
			(layer "F.Fab")
		)
		(fp_line
			(start -0.67945 -0.305054)
			(end -0.12065 -0.305054)
			(stroke
				(width 0.1)
				(type default)
			)
			(layer "F.Fab")
		)
		(pad "1" smd circle
			(at -0.40005 0 180)
			(size 0 0)
			(layers "F.Cu" "F.Mask" "F.Paste")
			(net "OCP_V3_1_P3V3_PLD_PWRGD")
		)
		(pad "2" smd circle
			(at 0.40005 0 180)
			(size 0 0)
			(layers "F.Cu" "F.Mask" "F.Paste")
			(net "OCP_V3_1_P3V3_PLD_R_PWRGD")
		)
	)
	(footprint ""
		(layer "F.Cu")
		(at 361.046014 -257.744976)
		(property "Reference" "C2573"
			(at 0 0 0)
			(layer "F.SilkS")
			(hide yes)
			(effects
				(font
					(size 1.27 1.27)
				)
			)
		)
		(property "Value" ""
			(at 0 0 0)
			(layer "F.Fab")
			(effects
				(font
					(size 1.27 1.27)
				)
			)
		)
		(duplicate_pad_numbers_are_jumpers no)
		(fp_line
			(start -0.7874 -0.4064)
			(end 0.7874 -0.4064)
			(stroke
				(width 0.1524)
				(type default)
			)
			(layer "F.SilkS")
		)
		(fp_line
			(start -0.7874 0.4064)
			(end -0.7874 -0.4064)
			(stroke
				(width 0.1524)
				(type default)
			)
			(layer "F.SilkS")
		)
		(fp_line
			(start 0.7874 -0.4064)
			(end 0.7874 0.4064)
			(stroke
				(width 0.1524)
				(type default)
			)
			(layer "F.SilkS")
		)
		(fp_line
			(start 0.7874 0.4064)
			(end -0.7874 0.4064)
			(stroke
				(width 0.1524)
				(type default)
			)
			(layer "F.SilkS")
		)
		(fp_line
			(start -0.67945 -0.305054)
			(end -0.12065 -0.305054)
			(stroke
				(width 0.1)
				(type default)
			)
			(layer "F.Fab")
		)
		(fp_line
			(start -0.67945 0.3048)
			(end -0.67945 -0.305054)
			(stroke
				(width 0.1)
				(type default)
			)
			(layer "F.Fab")
		)
		(fp_line
			(start -0.12065 -0.305054)
			(end -0.12065 -0.2794)
			(stroke
				(width 0.1)
				(type default)
			)
			(layer "F.Fab")
		)
		(fp_line
			(start -0.12065 -0.2794)
			(end 0.12065 -0.2794)
			(stroke
				(width 0.1)
				(type default)
			)
			(layer "F.Fab")
		)
		(fp_line
			(start -0.12065 0.2794)
			(end -0.12065 0.3048)
			(stroke
				(width 0.1)
				(type default)
			)
			(layer "F.Fab")
		)
		(fp_line
			(start -0.12065 0.3048)
			(end -0.67945 0.3048)
			(stroke
				(width 0.1)
				(type default)
			)
			(layer "F.Fab")
		)
		(fp_line
			(start 0.120396 0.2794)
			(end -0.12065 0.2794)
			(stroke
				(width 0.1)
				(type default)
			)
			(layer "F.Fab")
		)
		(fp_line
			(start 0.120396 0.3048)
			(end 0.120396 0.2794)
			(stroke
				(width 0.1)
				(type default)
			)
			(layer "F.Fab")
		)
		(fp_line
			(start 0.12065 -0.3048)
			(end 0.67945 -0.3048)
			(stroke
				(width 0.1)
				(type default)
			)
			(layer "F.Fab")
		)
		(fp_line
			(start 0.12065 -0.2794)
			(end 0.12065 -0.3048)
			(stroke
				(width 0.1)
				(type default)
			)
			(layer "F.Fab")
		)
		(fp_line
			(start 0.67945 -0.3048)
			(end 0.67945 0.3048)
			(stroke
				(width 0.1)
				(type default)
			)
			(layer "F.Fab")
		)
		(fp_line
			(start 0.67945 0.3048)
			(end 0.120396 0.3048)
			(stroke
				(width 0.1)
				(type default)
			)
			(layer "F.Fab")
		)
		(pad "1" smd circle
			(at -0.40005 0)
			(size 0 0)
			(layers "F.Cu" "F.Mask" "F.Paste")
			(net "PVDDCR_SOC_P0")
		)
		(pad "2" smd circle
			(at 0.40005 0)
			(size 0 0)
			(layers "F.Cu" "F.Mask" "F.Paste")
			(net "GND")
		)
	)
	(footprint ""
		(layer "F.Cu")
		(at 149.401276 -44.8437 90)
		(property "Reference" "C1323"
			(at 0 0 90)
			(layer "F.SilkS")
			(hide yes)
			(effects
				(font
					(size 1.27 1.27)
				)
			)
		)
		(property "Value" ""
			(at 0 0 90)
			(layer "F.Fab")
			(effects
				(font
					(size 1.27 1.27)
				)
			)
		)
		(duplicate_pad_numbers_are_jumpers no)
		(fp_line
			(start 0.7874 -0.4064)
			(end 0.7874 0.4064)
			(stroke
				(width 0.1524)
				(type default)
			)
			(layer "F.SilkS")
		)
		(fp_line
			(start -0.7874 -0.4064)
			(end 0.7874 -0.4064)
			(stroke
				(width 0.1524)
				(type default)
			)
			(layer "F.SilkS")
		)
		(fp_line
			(start 0.7874 0.4064)
			(end -0.7874 0.4064)
			(stroke
				(width 0.1524)
				(type default)
			)
			(layer "F.SilkS")
		)
		(fp_line
			(start -0.7874 0.4064)
			(end -0.7874 -0.4064)
			(stroke
				(width 0.1524)
				(type default)
			)
			(layer "F.SilkS")
		)
		(fp_line
			(start -0.12065 -0.305054)
			(end -0.12065 -0.2794)
			(stroke
				(width 0.1)
				(type default)
			)
			(layer "F.Fab")
		)
		(fp_line
			(start -0.67945 -0.305054)
			(end -0.12065 -0.305054)
			(stroke
				(width 0.1)
				(type default)
			)
			(layer "F.Fab")
		)
		(fp_line
			(start 0.67945 -0.3048)
			(end 0.67945 0.3048)
			(stroke
				(width 0.1)
				(type default)
			)
			(layer "F.Fab")
		)
		(fp_line
			(start 0.12065 -0.3048)
			(end 0.67945 -0.3048)
			(stroke
				(width 0.1)
				(type default)
			)
			(layer "F.Fab")
		)
		(fp_line
			(start 0.12065 -0.2794)
			(end 0.12065 -0.3048)
			(stroke
				(width 0.1)
				(type default)
			)
			(layer "F.Fab")
		)
		(fp_line
			(start -0.12065 -0.2794)
			(end 0.12065 -0.2794)
			(stroke
				(width 0.1)
				(type default)
			)
			(layer "F.Fab")
		)
		(fp_line
			(start 0.120396 0.2794)
			(end -0.12065 0.2794)
			(stroke
				(width 0.1)
				(type default)
			)
			(layer "F.Fab")
		)
		(fp_line
			(start -0.12065 0.2794)
			(end -0.12065 0.3048)
			(stroke
				(width 0.1)
				(type default)
			)
			(layer "F.Fab")
		)
		(fp_line
			(start 0.67945 0.3048)
			(end 0.120396 0.3048)
			(stroke
				(width 0.1)
				(type default)
			)
			(layer "F.Fab")
		)
		(fp_line
			(start 0.120396 0.3048)
			(end 0.120396 0.2794)
			(stroke
				(width 0.1)
				(type default)
			)
			(layer "F.Fab")
		)
		(fp_line
			(start -0.12065 0.3048)
			(end -0.67945 0.3048)
			(stroke
				(width 0.1)
				(type default)
			)
			(layer "F.Fab")
		)
		(fp_line
			(start -0.67945 0.3048)
			(end -0.67945 -0.305054)
			(stroke
				(width 0.1)
				(type default)
			)
			(layer "F.Fab")
		)
		(pad "1" smd circle
			(at -0.40005 0 90)
			(size 0 0)
			(layers "F.Cu" "F.Mask" "F.Paste")
			(net "P1V8_AUX")
		)
		(pad "2" smd circle
			(at 0.40005 0 90)
			(size 0 0)
			(layers "F.Cu" "F.Mask" "F.Paste")
			(net "GND")
		)
	)
	(footprint ""
		(layer "F.Cu")
		(at 77.219302 -370.57203 -90)
		(property "Reference" "C735"
			(at 0 0 270)
			(layer "F.SilkS")
			(hide yes)
			(effects
				(font
					(size 1.27 1.27)
				)
			)
		)
		(property "Value" ""
			(at 0 0 270)
			(layer "F.Fab")
			(effects
				(font
					(size 1.27 1.27)
				)
			)
		)
		(duplicate_pad_numbers_are_jumpers no)
		(fp_line
			(start -0.299974 0.150114)
			(end -0.299974 -0.150114)
			(stroke
				(width 0.1)
				(type default)
			)
			(layer "F.Fab")
		)
		(fp_line
			(start 0.299974 0.150114)
			(end -0.299974 0.150114)
			(stroke
				(width 0.1)
				(type default)
			)
			(layer "F.Fab")
		)
		(fp_line
			(start -0.299974 -0.150114)
			(end 0.299974 -0.150114)
			(stroke
				(width 0.1)
				(type default)
			)
			(layer "F.Fab")
		)
		(fp_line
			(start 0.299974 -0.150114)
			(end 0.299974 0.150114)
			(stroke
				(width 0.1)
				(type default)
			)
			(layer "F.Fab")
		)
		(pad "1" smd rect
			(at -0.2667 0 270)
			(size 0.3048 0.381)
			(layers "F.Cu" "F.Mask" "F.Paste")
			(net "P5E_CPU1_P1_TX_C_DP<3>")
		)
		(pad "2" smd rect
			(at 0.2667 0 270)
			(size 0.3048 0.381)
			(layers "F.Cu" "F.Mask" "F.Paste")
			(net "P5E_CPU1_P1_TX_DP<3>")
		)
	)
	(footprint ""
		(layer "F.Cu")
		(at 66.715132 -331.99578 180)
		(property "Reference" "PC206"
			(at 0 0 180)
			(layer "F.SilkS")
			(hide yes)
			(effects
				(font
					(size 1.27 1.27)
				)
			)
		)
		(property "Value" ""
			(at 0 0 180)
			(layer "F.Fab")
			(effects
				(font
					(size 1.27 1.27)
				)
			)
		)
		(duplicate_pad_numbers_are_jumpers no)
		(fp_line
			(start 0.7874 0.4064)
			(end -0.7874 0.4064)
			(stroke
				(width 0.1524)
				(type default)
			)
			(layer "F.SilkS")
		)
		(fp_line
			(start 0.7874 -0.4064)
			(end 0.7874 0.4064)
			(stroke
				(width 0.1524)
				(type default)
			)
			(layer "F.SilkS")
		)
		(fp_line
			(start -0.7874 0.4064)
			(end -0.7874 -0.4064)
			(stroke
				(width 0.1524)
				(type default)
			)
			(layer "F.SilkS")
		)
		(fp_line
			(start -0.7874 -0.4064)
			(end 0.7874 -0.4064)
			(stroke
				(width 0.1524)
				(type default)
			)
			(layer "F.SilkS")
		)
		(fp_line
			(start 0.67945 0.3048)
			(end 0.120396 0.3048)
			(stroke
				(width 0.1)
				(type default)
			)
			(layer "F.Fab")
		)
		(fp_line
			(start 0.67945 -0.3048)
			(end 0.67945 0.3048)
			(stroke
				(width 0.1)
				(type default)
			)
			(layer "F.Fab")
		)
		(fp_line
			(start 0.12065 -0.2794)
			(end 0.12065 -0.3048)
			(stroke
				(width 0.1)
				(type default)
			)
			(layer "F.Fab")
		)
		(fp_line
			(start 0.12065 -0.3048)
			(end 0.67945 -0.3048)
			(stroke
				(width 0.1)
				(type default)
			)
			(layer "F.Fab")
		)
		(fp_line
			(start 0.120396 0.3048)
			(end 0.120396 0.2794)
			(stroke
				(width 0.1)
				(type default)
			)
			(layer "F.Fab")
		)
		(fp_line
			(start 0.120396 0.2794)
			(end -0.12065 0.2794)
			(stroke
				(width 0.1)
				(type default)
			)
			(layer "F.Fab")
		)
		(fp_line
			(start -0.12065 0.3048)
			(end -0.67945 0.3048)
			(stroke
				(width 0.1)
				(type default)
			)
			(layer "F.Fab")
		)
		(fp_line
			(start -0.12065 0.2794)
			(end -0.12065 0.3048)
			(stroke
				(width 0.1)
				(type default)
			)
			(layer "F.Fab")
		)
		(fp_line
			(start -0.12065 -0.2794)
			(end 0.12065 -0.2794)
			(stroke
				(width 0.1)
				(type default)
			)
			(layer "F.Fab")
		)
		(fp_line
			(start -0.12065 -0.305054)
			(end -0.12065 -0.2794)
			(stroke
				(width 0.1)
				(type default)
			)
			(layer "F.Fab")
		)
		(fp_line
			(start -0.67945 0.3048)
			(end -0.67945 -0.305054)
			(stroke
				(width 0.1)
				(type default)
			)
			(layer "F.Fab")
		)
		(fp_line
			(start -0.67945 -0.305054)
			(end -0.12065 -0.305054)
			(stroke
				(width 0.1)
				(type default)
			)
			(layer "F.Fab")
		)
		(pad "1" smd circle
			(at -0.40005 0 180)
			(size 0 0)
			(layers "F.Cu" "F.Mask" "F.Paste")
			(net "SW_PVDDCR_CPU1_P1_SW3")
		)
		(pad "2" smd circle
			(at 0.40005 0 180)
			(size 0 0)
			(layers "F.Cu" "F.Mask" "F.Paste")
			(net "SW_PVDDCR_CPU1_P1_SW3_RC")
		)
	)
	(footprint ""
		(layer "F.Cu")
		(at 71.064882 -31.894272 -90)
		(property "Reference" "R1193"
			(at 0 0 270)
			(layer "F.SilkS")
			(hide yes)
			(effects
				(font
					(size 1.27 1.27)
				)
			)
		)
		(property "Value" ""
			(at 0 0 270)
			(layer "F.Fab")
			(effects
				(font
					(size 1.27 1.27)
				)
			)
		)
		(duplicate_pad_numbers_are_jumpers no)
		(fp_line
			(start -0.7874 0.4064)
			(end -0.7874 -0.4064)
			(stroke
				(width 0.1524)
				(type default)
			)
			(layer "F.SilkS")
		)
		(fp_line
			(start 0.7874 0.4064)
			(end -0.7874 0.4064)
			(stroke
				(width 0.1524)
				(type default)
			)
			(layer "F.SilkS")
		)
		(fp_line
			(start -0.7874 -0.4064)
			(end 0.7874 -0.4064)
			(stroke
				(width 0.1524)
				(type default)
			)
			(layer "F.SilkS")
		)
		(fp_line
			(start 0.7874 -0.4064)
			(end 0.7874 0.4064)
			(stroke
				(width 0.1524)
				(type default)
			)
			(layer "F.SilkS")
		)
		(fp_line
			(start -0.67945 0.3048)
			(end -0.67945 -0.305054)
			(stroke
				(width 0.1)
				(type default)
			)
			(layer "F.Fab")
		)
		(fp_line
			(start -0.12065 0.3048)
			(end -0.67945 0.3048)
			(stroke
				(width 0.1)
				(type default)
			)
			(layer "F.Fab")
		)
		(fp_line
			(start 0.120396 0.3048)
			(end 0.120396 0.2794)
			(stroke
				(width 0.1)
				(type default)
			)
			(layer "F.Fab")
		)
		(fp_line
			(start 0.67945 0.3048)
			(end 0.120396 0.3048)
			(stroke
				(width 0.1)
				(type default)
			)
			(layer "F.Fab")
		)
		(fp_line
			(start -0.12065 0.2794)
			(end -0.12065 0.3048)
			(stroke
				(width 0.1)
				(type default)
			)
			(layer "F.Fab")
		)
		(fp_line
			(start 0.120396 0.2794)
			(end -0.12065 0.2794)
			(stroke
				(width 0.1)
				(type default)
			)
			(layer "F.Fab")
		)
		(fp_line
			(start -0.12065 -0.2794)
			(end 0.12065 -0.2794)
			(stroke
				(width 0.1)
				(type default)
			)
			(layer "F.Fab")
		)
		(fp_line
			(start 0.12065 -0.2794)
			(end 0.12065 -0.3048)
			(stroke
				(width 0.1)
				(type default)
			)
			(layer "F.Fab")
		)
		(fp_line
			(start 0.12065 -0.3048)
			(end 0.67945 -0.3048)
			(stroke
				(width 0.1)
				(type default)
			)
			(layer "F.Fab")
		)
		(fp_line
			(start 0.67945 -0.3048)
			(end 0.67945 0.3048)
			(stroke
				(width 0.1)
				(type default)
			)
			(layer "F.Fab")
		)
		(fp_line
			(start -0.67945 -0.305054)
			(end -0.12065 -0.305054)
			(stroke
				(width 0.1)
				(type default)
			)
			(layer "F.Fab")
		)
		(fp_line
			(start -0.12065 -0.305054)
			(end -0.12065 -0.2794)
			(stroke
				(width 0.1)
				(type default)
			)
			(layer "F.Fab")
		)
		(pad "1" smd circle
			(at -0.40005 0 270)
			(size 0 0)
			(layers "F.Cu" "F.Mask" "F.Paste")
			(net "P12V_OCP_V3_2_BUF_EN_R")
		)
		(pad "2" smd circle
			(at 0.40005 0 270)
			(size 0 0)
			(layers "F.Cu" "F.Mask" "F.Paste")
			(net "P12V_OCP_V3_2_EN_2_R3")
		)
	)
	(footprint ""
		(layer "F.Cu")
		(at 223.384364 -75.53071 180)
		(property "Reference" "PR4527"
			(at 0 0 180)
			(layer "F.SilkS")
			(hide yes)
			(effects
				(font
					(size 1.27 1.27)
				)
			)
		)
		(property "Value" ""
			(at 0 0 180)
			(layer "F.Fab")
			(effects
				(font
					(size 1.27 1.27)
				)
			)
		)
		(duplicate_pad_numbers_are_jumpers no)
		(fp_line
			(start 0.7874 0.4064)
			(end -0.7874 0.4064)
			(stroke
				(width 0.1524)
				(type default)
			)
			(layer "F.SilkS")
		)
		(fp_line
			(start 0.7874 -0.4064)
			(end 0.7874 0.4064)
			(stroke
				(width 0.1524)
				(type default)
			)
			(layer "F.SilkS")
		)
		(fp_line
			(start -0.7874 0.4064)
			(end -0.7874 -0.4064)
			(stroke
				(width 0.1524)
				(type default)
			)
			(layer "F.SilkS")
		)
		(fp_line
			(start -0.7874 -0.4064)
			(end 0.7874 -0.4064)
			(stroke
				(width 0.1524)
				(type default)
			)
			(layer "F.SilkS")
		)
		(fp_line
			(start 0.67945 0.3048)
			(end 0.120396 0.3048)
			(stroke
				(width 0.1)
				(type default)
			)
			(layer "F.Fab")
		)
		(fp_line
			(start 0.67945 -0.3048)
			(end 0.67945 0.3048)
			(stroke
				(width 0.1)
				(type default)
			)
			(layer "F.Fab")
		)
		(fp_line
			(start 0.12065 -0.2794)
			(end 0.12065 -0.3048)
			(stroke
				(width 0.1)
				(type default)
			)
			(layer "F.Fab")
		)
		(fp_line
			(start 0.12065 -0.3048)
			(end 0.67945 -0.3048)
			(stroke
				(width 0.1)
				(type default)
			)
			(layer "F.Fab")
		)
		(fp_line
			(start 0.120396 0.3048)
			(end 0.120396 0.2794)
			(stroke
				(width 0.1)
				(type default)
			)
			(layer "F.Fab")
		)
		(fp_line
			(start 0.120396 0.2794)
			(end -0.12065 0.2794)
			(stroke
				(width 0.1)
				(type default)
			)
			(layer "F.Fab")
		)
		(fp_line
			(start -0.12065 0.3048)
			(end -0.67945 0.3048)
			(stroke
				(width 0.1)
				(type default)
			)
			(layer "F.Fab")
		)
		(fp_line
			(start -0.12065 0.2794)
			(end -0.12065 0.3048)
			(stroke
				(width 0.1)
				(type default)
			)
			(layer "F.Fab")
		)
		(fp_line
			(start -0.12065 -0.2794)
			(end 0.12065 -0.2794)
			(stroke
				(width 0.1)
				(type default)
			)
			(layer "F.Fab")
		)
		(fp_line
			(start -0.12065 -0.305054)
			(end -0.12065 -0.2794)
			(stroke
				(width 0.1)
				(type default)
			)
			(layer "F.Fab")
		)
		(fp_line
			(start -0.67945 0.3048)
			(end -0.67945 -0.305054)
			(stroke
				(width 0.1)
				(type default)
			)
			(layer "F.Fab")
		)
		(fp_line
			(start -0.67945 -0.305054)
			(end -0.12065 -0.305054)
			(stroke
				(width 0.1)
				(type default)
			)
			(layer "F.Fab")
		)
		(pad "1" smd circle
			(at -0.40005 0 180)
			(size 0 0)
			(layers "F.Cu" "F.Mask" "F.Paste")
			(net "P3V3_E1S_0_R")
		)
		(pad "2" smd circle
			(at 0.40005 0 180)
			(size 0 0)
			(layers "F.Cu" "F.Mask" "F.Paste")
			(net "P3V3_E1S_GATE_0")
		)
	)
	(footprint ""
		(layer "F.Cu")
		(at 215.956134 -32.857948 180)
		(property "Reference" "R3593"
			(at 0 0 180)
			(layer "F.SilkS")
			(hide yes)
			(effects
				(font
					(size 1.27 1.27)
				)
			)
		)
		(property "Value" ""
			(at 0 0 180)
			(layer "F.Fab")
			(effects
				(font
					(size 1.27 1.27)
				)
			)
		)
		(duplicate_pad_numbers_are_jumpers no)
		(fp_line
			(start 0.7874 0.4064)
			(end -0.7874 0.4064)
			(stroke
				(width 0.1524)
				(type default)
			)
			(layer "F.SilkS")
		)
		(fp_line
			(start 0.7874 -0.4064)
			(end 0.7874 0.4064)
			(stroke
				(width 0.1524)
				(type default)
			)
			(layer "F.SilkS")
		)
		(fp_line
			(start -0.7874 0.4064)
			(end -0.7874 -0.4064)
			(stroke
				(width 0.1524)
				(type default)
			)
			(layer "F.SilkS")
		)
		(fp_line
			(start -0.7874 -0.4064)
			(end 0.7874 -0.4064)
			(stroke
				(width 0.1524)
				(type default)
			)
			(layer "F.SilkS")
		)
		(fp_line
			(start 0.67945 0.3048)
			(end 0.120396 0.3048)
			(stroke
				(width 0.1)
				(type default)
			)
			(layer "F.Fab")
		)
		(fp_line
			(start 0.67945 -0.3048)
			(end 0.67945 0.3048)
			(stroke
				(width 0.1)
				(type default)
			)
			(layer "F.Fab")
		)
		(fp_line
			(start 0.12065 -0.2794)
			(end 0.12065 -0.3048)
			(stroke
				(width 0.1)
				(type default)
			)
			(layer "F.Fab")
		)
		(fp_line
			(start 0.12065 -0.3048)
			(end 0.67945 -0.3048)
			(stroke
				(width 0.1)
				(type default)
			)
			(layer "F.Fab")
		)
		(fp_line
			(start 0.120396 0.3048)
			(end 0.120396 0.2794)
			(stroke
				(width 0.1)
				(type default)
			)
			(layer "F.Fab")
		)
		(fp_line
			(start 0.120396 0.2794)
			(end -0.12065 0.2794)
			(stroke
				(width 0.1)
				(type default)
			)
			(layer "F.Fab")
		)
		(fp_line
			(start -0.12065 0.3048)
			(end -0.67945 0.3048)
			(stroke
				(width 0.1)
				(type default)
			)
			(layer "F.Fab")
		)
		(fp_line
			(start -0.12065 0.2794)
			(end -0.12065 0.3048)
			(stroke
				(width 0.1)
				(type default)
			)
			(layer "F.Fab")
		)
		(fp_line
			(start -0.12065 -0.2794)
			(end 0.12065 -0.2794)
			(stroke
				(width 0.1)
				(type default)
			)
			(layer "F.Fab")
		)
		(fp_line
			(start -0.12065 -0.305054)
			(end -0.12065 -0.2794)
			(stroke
				(width 0.1)
				(type default)
			)
			(layer "F.Fab")
		)
		(fp_line
			(start -0.67945 0.3048)
			(end -0.67945 -0.305054)
			(stroke
				(width 0.1)
				(type default)
			)
			(layer "F.Fab")
		)
		(fp_line
			(start -0.67945 -0.305054)
			(end -0.12065 -0.305054)
			(stroke
				(width 0.1)
				(type default)
			)
			(layer "F.Fab")
		)
		(pad "1" smd circle
			(at -0.40005 0 180)
			(size 0 0)
			(layers "F.Cu" "F.Mask" "F.Paste")
			(net "SMB_INA230_3V3AUX_SDA")
		)
		(pad "2" smd circle
			(at 0.40005 0 180)
			(size 0 0)
			(layers "F.Cu" "F.Mask" "F.Paste")
			(net "SMB_INA230_5_3V3AUX_SDA_R")
		)
	)
	(footprint ""
		(layer "F.Cu")
		(at 270.856202 -351.5487 90)
		(property "Reference" "PR443"
			(at 0 0 90)
			(layer "F.SilkS")
			(hide yes)
			(effects
				(font
					(size 1.27 1.27)
				)
			)
		)
		(property "Value" ""
			(at 0 0 90)
			(layer "F.Fab")
			(effects
				(font
					(size 1.27 1.27)
				)
			)
		)
		(duplicate_pad_numbers_are_jumpers no)
		(fp_line
			(start 0.7874 -0.4064)
			(end 0.7874 0.4064)
			(stroke
				(width 0.1524)
				(type default)
			)
			(layer "F.SilkS")
		)
		(fp_line
			(start -0.7874 -0.4064)
			(end 0.7874 -0.4064)
			(stroke
				(width 0.1524)
				(type default)
			)
			(layer "F.SilkS")
		)
		(fp_line
			(start 0.7874 0.4064)
			(end -0.7874 0.4064)
			(stroke
				(width 0.1524)
				(type default)
			)
			(layer "F.SilkS")
		)
		(fp_line
			(start -0.7874 0.4064)
			(end -0.7874 -0.4064)
			(stroke
				(width 0.1524)
				(type default)
			)
			(layer "F.SilkS")
		)
		(fp_line
			(start -0.12065 -0.305054)
			(end -0.12065 -0.2794)
			(stroke
				(width 0.1)
				(type default)
			)
			(layer "F.Fab")
		)
		(fp_line
			(start -0.67945 -0.305054)
			(end -0.12065 -0.305054)
			(stroke
				(width 0.1)
				(type default)
			)
			(layer "F.Fab")
		)
		(fp_line
			(start 0.67945 -0.3048)
			(end 0.67945 0.3048)
			(stroke
				(width 0.1)
				(type default)
			)
			(layer "F.Fab")
		)
		(fp_line
			(start 0.12065 -0.3048)
			(end 0.67945 -0.3048)
			(stroke
				(width 0.1)
				(type default)
			)
			(layer "F.Fab")
		)
		(fp_line
			(start 0.12065 -0.2794)
			(end 0.12065 -0.3048)
			(stroke
				(width 0.1)
				(type default)
			)
			(layer "F.Fab")
		)
		(fp_line
			(start -0.12065 -0.2794)
			(end 0.12065 -0.2794)
			(stroke
				(width 0.1)
				(type default)
			)
			(layer "F.Fab")
		)
		(fp_line
			(start 0.120396 0.2794)
			(end -0.12065 0.2794)
			(stroke
				(width 0.1)
				(type default)
			)
			(layer "F.Fab")
		)
		(fp_line
			(start -0.12065 0.2794)
			(end -0.12065 0.3048)
			(stroke
				(width 0.1)
				(type default)
			)
			(layer "F.Fab")
		)
		(fp_line
			(start 0.67945 0.3048)
			(end 0.120396 0.3048)
			(stroke
				(width 0.1)
				(type default)
			)
			(layer "F.Fab")
		)
		(fp_line
			(start 0.120396 0.3048)
			(end 0.120396 0.2794)
			(stroke
				(width 0.1)
				(type default)
			)
			(layer "F.Fab")
		)
		(fp_line
			(start -0.12065 0.3048)
			(end -0.67945 0.3048)
			(stroke
				(width 0.1)
				(type default)
			)
			(layer "F.Fab")
		)
		(fp_line
			(start -0.67945 0.3048)
			(end -0.67945 -0.305054)
			(stroke
				(width 0.1)
				(type default)
			)
			(layer "F.Fab")
		)
		(pad "1" smd circle
			(at -0.40005 0 90)
			(size 0 0)
			(layers "F.Cu" "F.Mask" "F.Paste")
			(net "PVDDCR_CPU1_P0_PVCC")
		)
		(pad "2" smd circle
			(at 0.40005 0 90)
			(size 0 0)
			(layers "F.Cu" "F.Mask" "F.Paste")
			(net "P3V3_AUX")
		)
	)
	(footprint ""
		(layer "F.Cu")
		(at 108.458 -417.703 180)
		(property "Reference" "R555"
			(at 0 0 180)
			(layer "F.SilkS")
			(hide yes)
			(effects
				(font
					(size 1.27 1.27)
				)
			)
		)
		(property "Value" ""
			(at 0 0 180)
			(layer "F.Fab")
			(effects
				(font
					(size 1.27 1.27)
				)
			)
		)
		(duplicate_pad_numbers_are_jumpers no)
		(fp_line
			(start 1.2954 0.5842)
			(end -1.2954 0.5842)
			(stroke
				(width 0.1524)
				(type default)
			)
			(layer "F.SilkS")
		)
		(fp_line
			(start 1.2954 -0.5842)
			(end 1.2954 0.5842)
			(stroke
				(width 0.1524)
				(type default)
			)
			(layer "F.SilkS")
		)
		(fp_line
			(start -1.2954 0.5842)
			(end -1.2954 -0.5842)
			(stroke
				(width 0.1524)
				(type default)
			)
			(layer "F.SilkS")
		)
		(fp_line
			(start -1.2954 -0.5842)
			(end 1.2954 -0.5842)
			(stroke
				(width 0.1524)
				(type default)
			)
			(layer "F.SilkS")
		)
		(fp_line
			(start 1.1938 0.4064)
			(end 0.8636 0.4064)
			(stroke
				(width 0.1)
				(type default)
			)
			(layer "F.Fab")
		)
		(fp_line
			(start 1.1938 -0.406654)
			(end 1.1938 0.4064)
			(stroke
				(width 0.1)
				(type default)
			)
			(layer "F.Fab")
		)
		(fp_line
			(start 0.8636 0.4572)
			(end -0.8636 0.4572)
			(stroke
				(width 0.1)
				(type default)
			)
			(layer "F.Fab")
		)
		(fp_line
			(start 0.8636 0.4064)
			(end 0.8636 0.4572)
			(stroke
				(width 0.1)
				(type default)
			)
			(layer "F.Fab")
		)
		(fp_line
			(start 0.8636 -0.406654)
			(end 1.1938 -0.406654)
			(stroke
				(width 0.1)
				(type default)
			)
			(layer "F.Fab")
		)
		(fp_line
			(start 0.8636 -0.4572)
			(end 0.8636 -0.406654)
			(stroke
				(width 0.1)
				(type default)
			)
			(layer "F.Fab")
		)
		(fp_line
			(start -0.8636 0.4572)
			(end -0.8636 0.4318)
			(stroke
				(width 0.1)
				(type default)
			)
			(layer "F.Fab")
		)
		(fp_line
			(start -0.8636 0.4318)
			(end -0.8636 0.4064)
			(stroke
				(width 0.1)
				(type default)
			)
			(layer "F.Fab")
		)
		(fp_line
			(start -0.8636 0.4064)
			(end -1.1938 0.4064)
			(stroke
				(width 0.1)
				(type default)
			)
			(layer "F.Fab")
		)
		(fp_line
			(start -0.8636 -0.406654)
			(end -0.8636 -0.4572)
			(stroke
				(width 0.1)
				(type default)
			)
			(layer "F.Fab")
		)
		(fp_line
			(start -0.8636 -0.4572)
			(end 0.8636 -0.4572)
			(stroke
				(width 0.1)
				(type default)
			)
			(layer "F.Fab")
		)
		(fp_line
			(start -1.1938 0.4064)
			(end -1.1938 -0.406654)
			(stroke
				(width 0.1)
				(type default)
			)
			(layer "F.Fab")
		)
		(fp_line
			(start -1.1938 -0.406654)
			(end -0.8636 -0.406654)
			(stroke
				(width 0.1)
				(type default)
			)
			(layer "F.Fab")
		)
		(pad "1" smd rect
			(at -0.7366 0 90)
			(size 0.7112 0.8128)
			(layers "F.Cu" "F.Mask" "F.Paste")
			(net "P3V3_9ZXL045_P1")
		)
		(pad "2" smd rect
			(at 0.7366 0 90)
			(size 0.7112 0.8128)
			(layers "F.Cu" "F.Mask" "F.Paste")
			(net "P3V3_9ZXL045_P1_VDDR")
		)
	)
	(footprint ""
		(layer "F.Cu")
		(at 9.379458 -422.551098)
		(property "Reference" "R6173"
			(at 0 0 0)
			(layer "F.SilkS")
			(hide yes)
			(effects
				(font
					(size 1.27 1.27)
				)
			)
		)
		(property "Value" ""
			(at 0 0 0)
			(layer "F.Fab")
			(effects
				(font
					(size 1.27 1.27)
				)
			)
		)
		(duplicate_pad_numbers_are_jumpers no)
		(fp_line
			(start -0.7874 -0.4064)
			(end 0.7874 -0.4064)
			(stroke
				(width 0.1524)
				(type default)
			)
			(layer "F.SilkS")
		)
		(fp_line
			(start -0.7874 0.4064)
			(end -0.7874 -0.4064)
			(stroke
				(width 0.1524)
				(type default)
			)
			(layer "F.SilkS")
		)
		(fp_line
			(start 0.7874 -0.4064)
			(end 0.7874 0.4064)
			(stroke
				(width 0.1524)
				(type default)
			)
			(layer "F.SilkS")
		)
		(fp_line
			(start 0.7874 0.4064)
			(end -0.7874 0.4064)
			(stroke
				(width 0.1524)
				(type default)
			)
			(layer "F.SilkS")
		)
		(fp_line
			(start -0.67945 -0.305054)
			(end -0.12065 -0.305054)
			(stroke
				(width 0.1)
				(type default)
			)
			(layer "F.Fab")
		)
		(fp_line
			(start -0.67945 0.3048)
			(end -0.67945 -0.305054)
			(stroke
				(width 0.1)
				(type default)
			)
			(layer "F.Fab")
		)
		(fp_line
			(start -0.12065 -0.305054)
			(end -0.12065 -0.2794)
			(stroke
				(width 0.1)
				(type default)
			)
			(layer "F.Fab")
		)
		(fp_line
			(start -0.12065 -0.2794)
			(end 0.12065 -0.2794)
			(stroke
				(width 0.1)
				(type default)
			)
			(layer "F.Fab")
		)
		(fp_line
			(start -0.12065 0.2794)
			(end -0.12065 0.3048)
			(stroke
				(width 0.1)
				(type default)
			)
			(layer "F.Fab")
		)
		(fp_line
			(start -0.12065 0.3048)
			(end -0.67945 0.3048)
			(stroke
				(width 0.1)
				(type default)
			)
			(layer "F.Fab")
		)
		(fp_line
			(start 0.120396 0.2794)
			(end -0.12065 0.2794)
			(stroke
				(width 0.1)
				(type default)
			)
			(layer "F.Fab")
		)
		(fp_line
			(start 0.120396 0.3048)
			(end 0.120396 0.2794)
			(stroke
				(width 0.1)
				(type default)
			)
			(layer "F.Fab")
		)
		(fp_line
			(start 0.12065 -0.3048)
			(end 0.67945 -0.3048)
			(stroke
				(width 0.1)
				(type default)
			)
			(layer "F.Fab")
		)
		(fp_line
			(start 0.12065 -0.2794)
			(end 0.12065 -0.3048)
			(stroke
				(width 0.1)
				(type default)
			)
			(layer "F.Fab")
		)
		(fp_line
			(start 0.67945 -0.3048)
			(end 0.67945 0.3048)
			(stroke
				(width 0.1)
				(type default)
			)
			(layer "F.Fab")
		)
		(fp_line
			(start 0.67945 0.3048)
			(end 0.120396 0.3048)
			(stroke
				(width 0.1)
				(type default)
			)
			(layer "F.Fab")
		)
		(pad "1" smd circle
			(at -0.40005 0)
			(size 0 0)
			(layers "F.Cu" "F.Mask" "F.Paste")
			(net "P3V3_AUX")
		)
		(pad "2" smd circle
			(at 0.40005 0)
			(size 0 0)
			(layers "F.Cu" "F.Mask" "F.Paste")
			(net "FM_P2E_BUF2_EQA0")
		)
	)
	(footprint ""
		(layer "F.Cu")
		(at 439.072782 -437.34736 -90)
		(property "Reference" "C5"
			(at 0 0 270)
			(layer "F.SilkS")
			(hide yes)
			(effects
				(font
					(size 1.27 1.27)
				)
			)
		)
		(property "Value" ""
			(at 0 0 270)
			(layer "F.Fab")
			(effects
				(font
					(size 1.27 1.27)
				)
			)
		)
		(duplicate_pad_numbers_are_jumpers no)
		(fp_line
			(start -0.7874 0.4064)
			(end -0.7874 -0.4064)
			(stroke
				(width 0.1524)
				(type default)
			)
			(layer "F.SilkS")
		)
		(fp_line
			(start 0.7874 0.4064)
			(end -0.7874 0.4064)
			(stroke
				(width 0.1524)
				(type default)
			)
			(layer "F.SilkS")
		)
		(fp_line
			(start -0.7874 -0.4064)
			(end 0.7874 -0.4064)
			(stroke
				(width 0.1524)
				(type default)
			)
			(layer "F.SilkS")
		)
		(fp_line
			(start 0.7874 -0.4064)
			(end 0.7874 0.4064)
			(stroke
				(width 0.1524)
				(type default)
			)
			(layer "F.SilkS")
		)
		(fp_line
			(start -0.67945 0.3048)
			(end -0.67945 -0.305054)
			(stroke
				(width 0.1)
				(type default)
			)
			(layer "F.Fab")
		)
		(fp_line
			(start -0.12065 0.3048)
			(end -0.67945 0.3048)
			(stroke
				(width 0.1)
				(type default)
			)
			(layer "F.Fab")
		)
		(fp_line
			(start 0.120396 0.3048)
			(end 0.120396 0.2794)
			(stroke
				(width 0.1)
				(type default)
			)
			(layer "F.Fab")
		)
		(fp_line
			(start 0.67945 0.3048)
			(end 0.120396 0.3048)
			(stroke
				(width 0.1)
				(type default)
			)
			(layer "F.Fab")
		)
		(fp_line
			(start -0.12065 0.2794)
			(end -0.12065 0.3048)
			(stroke
				(width 0.1)
				(type default)
			)
			(layer "F.Fab")
		)
		(fp_line
			(start 0.120396 0.2794)
			(end -0.12065 0.2794)
			(stroke
				(width 0.1)
				(type default)
			)
			(layer "F.Fab")
		)
		(fp_line
			(start -0.12065 -0.2794)
			(end 0.12065 -0.2794)
			(stroke
				(width 0.1)
				(type default)
			)
			(layer "F.Fab")
		)
		(fp_line
			(start 0.12065 -0.2794)
			(end 0.12065 -0.3048)
			(stroke
				(width 0.1)
				(type default)
			)
			(layer "F.Fab")
		)
		(fp_line
			(start 0.12065 -0.3048)
			(end 0.67945 -0.3048)
			(stroke
				(width 0.1)
				(type default)
			)
			(layer "F.Fab")
		)
		(fp_line
			(start 0.67945 -0.3048)
			(end 0.67945 0.3048)
			(stroke
				(width 0.1)
				(type default)
			)
			(layer "F.Fab")
		)
		(fp_line
			(start -0.67945 -0.305054)
			(end -0.12065 -0.305054)
			(stroke
				(width 0.1)
				(type default)
			)
			(layer "F.Fab")
		)
		(fp_line
			(start -0.12065 -0.305054)
			(end -0.12065 -0.2794)
			(stroke
				(width 0.1)
				(type default)
			)
			(layer "F.Fab")
		)
		(pad "1" smd circle
			(at -0.40005 0 270)
			(size 0 0)
			(layers "F.Cu" "F.Mask" "F.Paste")
			(net "GPU_3V3IO_RSVD4_ISO")
		)
		(pad "2" smd circle
			(at 0.40005 0 270)
			(size 0 0)
			(layers "F.Cu" "F.Mask" "F.Paste")
			(net "GND")
		)
	)
	(footprint ""
		(layer "F.Cu")
		(at 431.970688 -342.307164 -90)
		(property "Reference" "PL22"
			(at -2.116836 -4.808982 90)
			(unlocked yes)
			(layer "F.SilkS")
			(effects
				(font
					(size 0.7874 0.5842)
					(thickness 0.1524)
				)
				(justify left)
			)
		)
		(property "Value" ""
			(at 0 0 270)
			(layer "F.Fab")
			(effects
				(font
					(size 1.27 1.27)
				)
			)
		)
		(duplicate_pad_numbers_are_jumpers no)
		(fp_line
			(start -4.99999 3.849878)
			(end -4.99999 2.23901)
			(stroke
				(width 0.1524)
				(type default)
			)
			(layer "F.SilkS")
		)
		(fp_line
			(start 4.99999 3.849878)
			(end -4.99999 3.849878)
			(stroke
				(width 0.1524)
				(type default)
			)
			(layer "F.SilkS")
		)
		(fp_line
			(start 4.99999 2.23901)
			(end 4.99999 3.849878)
			(stroke
				(width 0.1524)
				(type default)
			)
			(layer "F.SilkS")
		)
		(fp_line
			(start -4.99999 -2.23901)
			(end -4.99999 -3.849878)
			(stroke
				(width 0.1524)
				(type default)
			)
			(layer "F.SilkS")
		)
		(fp_line
			(start -4.99999 -3.849878)
			(end 4.99999 -3.849878)
			(stroke
				(width 0.1524)
				(type default)
			)
			(layer "F.SilkS")
		)
		(fp_line
			(start 4.99999 -3.849878)
			(end 4.99999 -2.23901)
			(stroke
				(width 0.1524)
				(type default)
			)
			(layer "F.SilkS")
		)
		(fp_line
			(start -4.99999 3.849878)
			(end -4.99999 -3.849878)
			(stroke
				(width 0.1)
				(type default)
			)
			(layer "F.Fab")
		)
		(fp_line
			(start 4.99999 3.849878)
			(end -4.99999 3.849878)
			(stroke
				(width 0.1)
				(type default)
			)
			(layer "F.Fab")
		)
		(fp_line
			(start -4.99999 -3.849878)
			(end 4.99999 -3.849878)
			(stroke
				(width 0.1)
				(type default)
			)
			(layer "F.Fab")
		)
		(fp_line
			(start 4.99999 -3.849878)
			(end 4.99999 3.849878)
			(stroke
				(width 0.1)
				(type default)
			)
			(layer "F.Fab")
		)
		(pad "1" smd rect
			(at -3.299968 0 270)
			(size 3.302 4.2164)
			(layers "F.Cu" "F.Mask" "F.Paste")
			(net "SW_PVDD11_S3_P0_SW2")
		)
		(pad "2" smd rect
			(at 3.299968 0 270)
			(size 3.302 4.2164)
			(layers "F.Cu" "F.Mask" "F.Paste")
			(net "PVDD11_S3_P0")
		)
	)
	(footprint ""
		(layer "F.Cu")
		(at 226.0981 -406.052782)
		(property "Reference" "PR3993"
			(at 0 0 0)
			(layer "F.SilkS")
			(hide yes)
			(effects
				(font
					(size 1.27 1.27)
				)
			)
		)
		(property "Value" ""
			(at 0 0 0)
			(layer "F.Fab")
			(effects
				(font
					(size 1.27 1.27)
				)
			)
		)
		(duplicate_pad_numbers_are_jumpers no)
		(fp_line
			(start -0.7874 -0.4064)
			(end 0.7874 -0.4064)
			(stroke
				(width 0.1524)
				(type default)
			)
			(layer "F.SilkS")
		)
		(fp_line
			(start -0.7874 0.4064)
			(end -0.7874 -0.4064)
			(stroke
				(width 0.1524)
				(type default)
			)
			(layer "F.SilkS")
		)
		(fp_line
			(start 0.7874 -0.4064)
			(end 0.7874 0.4064)
			(stroke
				(width 0.1524)
				(type default)
			)
			(layer "F.SilkS")
		)
		(fp_line
			(start 0.7874 0.4064)
			(end -0.7874 0.4064)
			(stroke
				(width 0.1524)
				(type default)
			)
			(layer "F.SilkS")
		)
		(fp_line
			(start -0.67945 -0.305054)
			(end -0.12065 -0.305054)
			(stroke
				(width 0.1)
				(type default)
			)
			(layer "F.Fab")
		)
		(fp_line
			(start -0.67945 0.3048)
			(end -0.67945 -0.305054)
			(stroke
				(width 0.1)
				(type default)
			)
			(layer "F.Fab")
		)
		(fp_line
			(start -0.12065 -0.305054)
			(end -0.12065 -0.2794)
			(stroke
				(width 0.1)
				(type default)
			)
			(layer "F.Fab")
		)
		(fp_line
			(start -0.12065 -0.2794)
			(end 0.12065 -0.2794)
			(stroke
				(width 0.1)
				(type default)
			)
			(layer "F.Fab")
		)
		(fp_line
			(start -0.12065 0.2794)
			(end -0.12065 0.3048)
			(stroke
				(width 0.1)
				(type default)
			)
			(layer "F.Fab")
		)
		(fp_line
			(start -0.12065 0.3048)
			(end -0.67945 0.3048)
			(stroke
				(width 0.1)
				(type default)
			)
			(layer "F.Fab")
		)
		(fp_line
			(start 0.120396 0.2794)
			(end -0.12065 0.2794)
			(stroke
				(width 0.1)
				(type default)
			)
			(layer "F.Fab")
		)
		(fp_line
			(start 0.120396 0.3048)
			(end 0.120396 0.2794)
			(stroke
				(width 0.1)
				(type default)
			)
			(layer "F.Fab")
		)
		(fp_line
			(start 0.12065 -0.3048)
			(end 0.67945 -0.3048)
			(stroke
				(width 0.1)
				(type default)
			)
			(layer "F.Fab")
		)
		(fp_line
			(start 0.12065 -0.2794)
			(end 0.12065 -0.3048)
			(stroke
				(width 0.1)
				(type default)
			)
			(layer "F.Fab")
		)
		(fp_line
			(start 0.67945 -0.3048)
			(end 0.67945 0.3048)
			(stroke
				(width 0.1)
				(type default)
			)
			(layer "F.Fab")
		)
		(fp_line
			(start 0.67945 0.3048)
			(end 0.120396 0.3048)
			(stroke
				(width 0.1)
				(type default)
			)
			(layer "F.Fab")
		)
		(pad "1" smd circle
			(at -0.40005 0)
			(size 0 0)
			(layers "F.Cu" "F.Mask" "F.Paste")
			(net "HSC_FLT_TYPE_3")
		)
		(pad "2" smd circle
			(at 0.40005 0)
			(size 0 0)
			(layers "F.Cu" "F.Mask" "F.Paste")
			(net "HSC_FLT_TYPE")
		)
	)
	(footprint ""
		(layer "F.Cu")
		(at 253.506224 -131.067556 180)
		(property "Reference" "R603"
			(at 0 0 180)
			(layer "F.SilkS")
			(hide yes)
			(effects
				(font
					(size 1.27 1.27)
				)
			)
		)
		(property "Value" ""
			(at 0 0 180)
			(layer "F.Fab")
			(effects
				(font
					(size 1.27 1.27)
				)
			)
		)
		(duplicate_pad_numbers_are_jumpers no)
		(fp_line
			(start 0.7874 0.4064)
			(end -0.7874 0.4064)
			(stroke
				(width 0.1524)
				(type default)
			)
			(layer "F.SilkS")
		)
		(fp_line
			(start 0.7874 -0.4064)
			(end 0.7874 0.4064)
			(stroke
				(width 0.1524)
				(type default)
			)
			(layer "F.SilkS")
		)
		(fp_line
			(start -0.7874 0.4064)
			(end -0.7874 -0.4064)
			(stroke
				(width 0.1524)
				(type default)
			)
			(layer "F.SilkS")
		)
		(fp_line
			(start -0.7874 -0.4064)
			(end 0.7874 -0.4064)
			(stroke
				(width 0.1524)
				(type default)
			)
			(layer "F.SilkS")
		)
		(fp_line
			(start 0.67945 0.3048)
			(end 0.120396 0.3048)
			(stroke
				(width 0.1)
				(type default)
			)
			(layer "F.Fab")
		)
		(fp_line
			(start 0.67945 -0.3048)
			(end 0.67945 0.3048)
			(stroke
				(width 0.1)
				(type default)
			)
			(layer "F.Fab")
		)
		(fp_line
			(start 0.12065 -0.2794)
			(end 0.12065 -0.3048)
			(stroke
				(width 0.1)
				(type default)
			)
			(layer "F.Fab")
		)
		(fp_line
			(start 0.12065 -0.3048)
			(end 0.67945 -0.3048)
			(stroke
				(width 0.1)
				(type default)
			)
			(layer "F.Fab")
		)
		(fp_line
			(start 0.120396 0.3048)
			(end 0.120396 0.2794)
			(stroke
				(width 0.1)
				(type default)
			)
			(layer "F.Fab")
		)
		(fp_line
			(start 0.120396 0.2794)
			(end -0.12065 0.2794)
			(stroke
				(width 0.1)
				(type default)
			)
			(layer "F.Fab")
		)
		(fp_line
			(start -0.12065 0.3048)
			(end -0.67945 0.3048)
			(stroke
				(width 0.1)
				(type default)
			)
			(layer "F.Fab")
		)
		(fp_line
			(start -0.12065 0.2794)
			(end -0.12065 0.3048)
			(stroke
				(width 0.1)
				(type default)
			)
			(layer "F.Fab")
		)
		(fp_line
			(start -0.12065 -0.2794)
			(end 0.12065 -0.2794)
			(stroke
				(width 0.1)
				(type default)
			)
			(layer "F.Fab")
		)
		(fp_line
			(start -0.12065 -0.305054)
			(end -0.12065 -0.2794)
			(stroke
				(width 0.1)
				(type default)
			)
			(layer "F.Fab")
		)
		(fp_line
			(start -0.67945 0.3048)
			(end -0.67945 -0.305054)
			(stroke
				(width 0.1)
				(type default)
			)
			(layer "F.Fab")
		)
		(fp_line
			(start -0.67945 -0.305054)
			(end -0.12065 -0.305054)
			(stroke
				(width 0.1)
				(type default)
			)
			(layer "F.Fab")
		)
		(pad "1" smd circle
			(at -0.40005 0 180)
			(size 0 0)
			(layers "F.Cu" "F.Mask" "F.Paste")
			(net "SPI_CPU0_LVC3_CS0_N")
		)
		(pad "2" smd circle
			(at 0.40005 0 180)
			(size 0 0)
			(layers "F.Cu" "F.Mask" "F.Paste")
			(net "SPI_CPU0_LVC3_SCM_CS0_N")
		)
	)
	(footprint ""
		(layer "F.Cu")
		(at 171.26966 -387.763004 180)
		(property "Reference" "R857"
			(at 0 0 180)
			(layer "F.SilkS")
			(hide yes)
			(effects
				(font
					(size 1.27 1.27)
				)
			)
		)
		(property "Value" ""
			(at 0 0 180)
			(layer "F.Fab")
			(effects
				(font
					(size 1.27 1.27)
				)
			)
		)
		(duplicate_pad_numbers_are_jumpers no)
		(fp_line
			(start 0.7874 0.4064)
			(end -0.7874 0.4064)
			(stroke
				(width 0.1524)
				(type default)
			)
			(layer "F.SilkS")
		)
		(fp_line
			(start 0.7874 -0.4064)
			(end 0.7874 0.4064)
			(stroke
				(width 0.1524)
				(type default)
			)
			(layer "F.SilkS")
		)
		(fp_line
			(start -0.7874 0.4064)
			(end -0.7874 -0.4064)
			(stroke
				(width 0.1524)
				(type default)
			)
			(layer "F.SilkS")
		)
		(fp_line
			(start -0.7874 -0.4064)
			(end 0.7874 -0.4064)
			(stroke
				(width 0.1524)
				(type default)
			)
			(layer "F.SilkS")
		)
		(fp_line
			(start 0.67945 0.3048)
			(end 0.120396 0.3048)
			(stroke
				(width 0.1)
				(type default)
			)
			(layer "F.Fab")
		)
		(fp_line
			(start 0.67945 -0.3048)
			(end 0.67945 0.3048)
			(stroke
				(width 0.1)
				(type default)
			)
			(layer "F.Fab")
		)
		(fp_line
			(start 0.12065 -0.2794)
			(end 0.12065 -0.3048)
			(stroke
				(width 0.1)
				(type default)
			)
			(layer "F.Fab")
		)
		(fp_line
			(start 0.12065 -0.3048)
			(end 0.67945 -0.3048)
			(stroke
				(width 0.1)
				(type default)
			)
			(layer "F.Fab")
		)
		(fp_line
			(start 0.120396 0.3048)
			(end 0.120396 0.2794)
			(stroke
				(width 0.1)
				(type default)
			)
			(layer "F.Fab")
		)
		(fp_line
			(start 0.120396 0.2794)
			(end -0.12065 0.2794)
			(stroke
				(width 0.1)
				(type default)
			)
			(layer "F.Fab")
		)
		(fp_line
			(start -0.12065 0.3048)
			(end -0.67945 0.3048)
			(stroke
				(width 0.1)
				(type default)
			)
			(layer "F.Fab")
		)
		(fp_line
			(start -0.12065 0.2794)
			(end -0.12065 0.3048)
			(stroke
				(width 0.1)
				(type default)
			)
			(layer "F.Fab")
		)
		(fp_line
			(start -0.12065 -0.2794)
			(end 0.12065 -0.2794)
			(stroke
				(width 0.1)
				(type default)
			)
			(layer "F.Fab")
		)
		(fp_line
			(start -0.12065 -0.305054)
			(end -0.12065 -0.2794)
			(stroke
				(width 0.1)
				(type default)
			)
			(layer "F.Fab")
		)
		(fp_line
			(start -0.67945 0.3048)
			(end -0.67945 -0.305054)
			(stroke
				(width 0.1)
				(type default)
			)
			(layer "F.Fab")
		)
		(fp_line
			(start -0.67945 -0.305054)
			(end -0.12065 -0.305054)
			(stroke
				(width 0.1)
				(type default)
			)
			(layer "F.Fab")
		)
		(pad "1" smd rect
			(at -0.40005 0)
			(size 0.4572 0.508)
			(layers "F.Cu" "F.Mask" "F.Paste")
			(net "P1V8_CPU1_RT_1D")
		)
		(pad "2" smd rect
			(at 0.40005 0)
			(size 0.4572 0.508)
			(layers "F.Cu" "F.Mask" "F.Paste")
			(net "P1V8_CPU1_RT2_1A_1D")
		)
	)
	(footprint ""
		(layer "F.Cu")
		(at 376.811286 -178.359562 180)
		(property "Reference" "PC552_3"
			(at 0 0 180)
			(layer "F.SilkS")
			(hide yes)
			(effects
				(font
					(size 1.27 1.27)
				)
			)
		)
		(property "Value" ""
			(at 0 0 180)
			(layer "F.Fab")
			(effects
				(font
					(size 1.27 1.27)
				)
			)
		)
		(duplicate_pad_numbers_are_jumpers no)
		(fp_line
			(start 0.7874 0.4064)
			(end -0.7874 0.4064)
			(stroke
				(width 0.1524)
				(type default)
			)
			(layer "F.SilkS")
		)
		(fp_line
			(start 0.7874 -0.4064)
			(end 0.7874 0.4064)
			(stroke
				(width 0.1524)
				(type default)
			)
			(layer "F.SilkS")
		)
		(fp_line
			(start -0.7874 0.4064)
			(end -0.7874 -0.4064)
			(stroke
				(width 0.1524)
				(type default)
			)
			(layer "F.SilkS")
		)
		(fp_line
			(start -0.7874 -0.4064)
			(end 0.7874 -0.4064)
			(stroke
				(width 0.1524)
				(type default)
			)
			(layer "F.SilkS")
		)
		(fp_line
			(start 0.67945 0.3048)
			(end 0.120396 0.3048)
			(stroke
				(width 0.1)
				(type default)
			)
			(layer "F.Fab")
		)
		(fp_line
			(start 0.67945 -0.3048)
			(end 0.67945 0.3048)
			(stroke
				(width 0.1)
				(type default)
			)
			(layer "F.Fab")
		)
		(fp_line
			(start 0.12065 -0.2794)
			(end 0.12065 -0.3048)
			(stroke
				(width 0.1)
				(type default)
			)
			(layer "F.Fab")
		)
		(fp_line
			(start 0.12065 -0.3048)
			(end 0.67945 -0.3048)
			(stroke
				(width 0.1)
				(type default)
			)
			(layer "F.Fab")
		)
		(fp_line
			(start 0.120396 0.3048)
			(end 0.120396 0.2794)
			(stroke
				(width 0.1)
				(type default)
			)
			(layer "F.Fab")
		)
		(fp_line
			(start 0.120396 0.2794)
			(end -0.12065 0.2794)
			(stroke
				(width 0.1)
				(type default)
			)
			(layer "F.Fab")
		)
		(fp_line
			(start -0.12065 0.3048)
			(end -0.67945 0.3048)
			(stroke
				(width 0.1)
				(type default)
			)
			(layer "F.Fab")
		)
		(fp_line
			(start -0.12065 0.2794)
			(end -0.12065 0.3048)
			(stroke
				(width 0.1)
				(type default)
			)
			(layer "F.Fab")
		)
		(fp_line
			(start -0.12065 -0.2794)
			(end 0.12065 -0.2794)
			(stroke
				(width 0.1)
				(type default)
			)
			(layer "F.Fab")
		)
		(fp_line
			(start -0.12065 -0.305054)
			(end -0.12065 -0.2794)
			(stroke
				(width 0.1)
				(type default)
			)
			(layer "F.Fab")
		)
		(fp_line
			(start -0.67945 0.3048)
			(end -0.67945 -0.305054)
			(stroke
				(width 0.1)
				(type default)
			)
			(layer "F.Fab")
		)
		(fp_line
			(start -0.67945 -0.305054)
			(end -0.12065 -0.305054)
			(stroke
				(width 0.1)
				(type default)
			)
			(layer "F.Fab")
		)
		(pad "1" smd circle
			(at -0.40005 0 180)
			(size 0 0)
			(layers "F.Cu" "F.Mask" "F.Paste")
			(net "SW_P12V_AUX_PVDDCR_CPU0_P0_FLT")
		)
		(pad "2" smd circle
			(at 0.40005 0 180)
			(size 0 0)
			(layers "F.Cu" "F.Mask" "F.Paste")
			(net "GND")
		)
	)
	(footprint ""
		(layer "F.Cu")
		(at 49.860454 -346.719398 -90)
		(property "Reference" "PC437_IOP1_1"
			(at 0 0 270)
			(layer "F.SilkS")
			(hide yes)
			(effects
				(font
					(size 1.27 1.27)
				)
			)
		)
		(property "Value" ""
			(at 0 0 270)
			(layer "F.Fab")
			(effects
				(font
					(size 1.27 1.27)
				)
			)
		)
		(duplicate_pad_numbers_are_jumpers no)
		(fp_line
			(start -0.7874 0.4064)
			(end -0.7874 -0.4064)
			(stroke
				(width 0.1524)
				(type default)
			)
			(layer "F.SilkS")
		)
		(fp_line
			(start 0.7874 0.4064)
			(end -0.7874 0.4064)
			(stroke
				(width 0.1524)
				(type default)
			)
			(layer "F.SilkS")
		)
		(fp_line
			(start -0.7874 -0.4064)
			(end 0.7874 -0.4064)
			(stroke
				(width 0.1524)
				(type default)
			)
			(layer "F.SilkS")
		)
		(fp_line
			(start 0.7874 -0.4064)
			(end 0.7874 0.4064)
			(stroke
				(width 0.1524)
				(type default)
			)
			(layer "F.SilkS")
		)
		(fp_line
			(start -0.67945 0.3048)
			(end -0.67945 -0.305054)
			(stroke
				(width 0.1)
				(type default)
			)
			(layer "F.Fab")
		)
		(fp_line
			(start -0.12065 0.3048)
			(end -0.67945 0.3048)
			(stroke
				(width 0.1)
				(type default)
			)
			(layer "F.Fab")
		)
		(fp_line
			(start 0.120396 0.3048)
			(end 0.120396 0.2794)
			(stroke
				(width 0.1)
				(type default)
			)
			(layer "F.Fab")
		)
		(fp_line
			(start 0.67945 0.3048)
			(end 0.120396 0.3048)
			(stroke
				(width 0.1)
				(type default)
			)
			(layer "F.Fab")
		)
		(fp_line
			(start -0.12065 0.2794)
			(end -0.12065 0.3048)
			(stroke
				(width 0.1)
				(type default)
			)
			(layer "F.Fab")
		)
		(fp_line
			(start 0.120396 0.2794)
			(end -0.12065 0.2794)
			(stroke
				(width 0.1)
				(type default)
			)
			(layer "F.Fab")
		)
		(fp_line
			(start -0.12065 -0.2794)
			(end 0.12065 -0.2794)
			(stroke
				(width 0.1)
				(type default)
			)
			(layer "F.Fab")
		)
		(fp_line
			(start 0.12065 -0.2794)
			(end 0.12065 -0.3048)
			(stroke
				(width 0.1)
				(type default)
			)
			(layer "F.Fab")
		)
		(fp_line
			(start 0.12065 -0.3048)
			(end 0.67945 -0.3048)
			(stroke
				(width 0.1)
				(type default)
			)
			(layer "F.Fab")
		)
		(fp_line
			(start 0.67945 -0.3048)
			(end 0.67945 0.3048)
			(stroke
				(width 0.1)
				(type default)
			)
			(layer "F.Fab")
		)
		(fp_line
			(start -0.67945 -0.305054)
			(end -0.12065 -0.305054)
			(stroke
				(width 0.1)
				(type default)
			)
			(layer "F.Fab")
		)
		(fp_line
			(start -0.12065 -0.305054)
			(end -0.12065 -0.2794)
			(stroke
				(width 0.1)
				(type default)
			)
			(layer "F.Fab")
		)
		(pad "1" smd circle
			(at -0.40005 0 270)
			(size 0 0)
			(layers "F.Cu" "F.Mask" "F.Paste")
			(net "PVDDCR_CPU1_P1_PVCC")
		)
		(pad "2" smd circle
			(at 0.40005 0 270)
			(size 0 0)
			(layers "F.Cu" "F.Mask" "F.Paste")
			(net "GND")
		)
	)
	(footprint ""
		(layer "F.Cu")
		(at 147.09775 -191.35471 -90)
		(property "Reference" "R3198"
			(at 0 0 270)
			(layer "F.SilkS")
			(hide yes)
			(effects
				(font
					(size 1.27 1.27)
				)
			)
		)
		(property "Value" ""
			(at 0 0 270)
			(layer "F.Fab")
			(effects
				(font
					(size 1.27 1.27)
				)
			)
		)
		(duplicate_pad_numbers_are_jumpers no)
		(fp_line
			(start -0.7874 0.4064)
			(end -0.7874 -0.01905)
			(stroke
				(width 0.1524)
				(type default)
			)
			(layer "F.SilkS")
		)
		(fp_line
			(start 0.7874 0.4064)
			(end -0.7874 0.4064)
			(stroke
				(width 0.1524)
				(type default)
			)
			(layer "F.SilkS")
		)
		(fp_line
			(start 0.7874 -0.04445)
			(end 0.7874 0.4064)
			(stroke
				(width 0.1524)
				(type default)
			)
			(layer "F.SilkS")
		)
		(fp_line
			(start -0.33909 -0.4064)
			(end 0.42291 -0.4064)
			(stroke
				(width 0.1524)
				(type default)
			)
			(layer "F.SilkS")
		)
		(fp_line
			(start -0.67945 0.3048)
			(end -0.67945 -0.305054)
			(stroke
				(width 0.1)
				(type default)
			)
			(layer "F.Fab")
		)
		(fp_line
			(start -0.12065 0.3048)
			(end -0.67945 0.3048)
			(stroke
				(width 0.1)
				(type default)
			)
			(layer "F.Fab")
		)
		(fp_line
			(start 0.120396 0.3048)
			(end 0.120396 0.2794)
			(stroke
				(width 0.1)
				(type default)
			)
			(layer "F.Fab")
		)
		(fp_line
			(start 0.67945 0.3048)
			(end 0.120396 0.3048)
			(stroke
				(width 0.1)
				(type default)
			)
			(layer "F.Fab")
		)
		(fp_line
			(start -0.12065 0.2794)
			(end -0.12065 0.3048)
			(stroke
				(width 0.1)
				(type default)
			)
			(layer "F.Fab")
		)
		(fp_line
			(start 0.120396 0.2794)
			(end -0.12065 0.2794)
			(stroke
				(width 0.1)
				(type default)
			)
			(layer "F.Fab")
		)
		(fp_line
			(start -0.12065 -0.2794)
			(end 0.12065 -0.2794)
			(stroke
				(width 0.1)
				(type default)
			)
			(layer "F.Fab")
		)
		(fp_line
			(start 0.12065 -0.2794)
			(end 0.12065 -0.3048)
			(stroke
				(width 0.1)
				(type default)
			)
			(layer "F.Fab")
		)
		(fp_line
			(start 0.12065 -0.3048)
			(end 0.67945 -0.3048)
			(stroke
				(width 0.1)
				(type default)
			)
			(layer "F.Fab")
		)
		(fp_line
			(start 0.67945 -0.3048)
			(end 0.67945 0.3048)
			(stroke
				(width 0.1)
				(type default)
			)
			(layer "F.Fab")
		)
		(fp_line
			(start -0.67945 -0.305054)
			(end -0.12065 -0.305054)
			(stroke
				(width 0.1)
				(type default)
			)
			(layer "F.Fab")
		)
		(fp_line
			(start -0.12065 -0.305054)
			(end -0.12065 -0.2794)
			(stroke
				(width 0.1)
				(type default)
			)
			(layer "F.Fab")
		)
		(pad "1" smd circle
			(at -0.40005 0 270)
			(size 0 0)
			(layers "F.Cu" "F.Mask" "F.Paste")
			(net "CLK_100M_CPU1_CLK04_R_DP")
		)
		(pad "2" smd circle
			(at 0.40005 0 270)
			(size 0 0)
			(layers "F.Cu" "F.Mask" "F.Paste")
			(net "CLK_100M_CPU1_CLK04_DP")
		)
	)
	(footprint ""
		(layer "F.Cu")
		(at 39.30396 -434.086 -90)
		(property "Reference" "R2932"
			(at 0 0 270)
			(layer "F.SilkS")
			(hide yes)
			(effects
				(font
					(size 1.27 1.27)
				)
			)
		)
		(property "Value" ""
			(at 0 0 270)
			(layer "F.Fab")
			(effects
				(font
					(size 1.27 1.27)
				)
			)
		)
		(duplicate_pad_numbers_are_jumpers no)
		(fp_line
			(start -0.7874 0.4064)
			(end -0.7874 -0.4064)
			(stroke
				(width 0.1524)
				(type default)
			)
			(layer "F.SilkS")
		)
		(fp_line
			(start 0.7874 0.4064)
			(end -0.7874 0.4064)
			(stroke
				(width 0.1524)
				(type default)
			)
			(layer "F.SilkS")
		)
		(fp_line
			(start -0.7874 -0.4064)
			(end 0.7874 -0.4064)
			(stroke
				(width 0.1524)
				(type default)
			)
			(layer "F.SilkS")
		)
		(fp_line
			(start 0.7874 -0.4064)
			(end 0.7874 0.4064)
			(stroke
				(width 0.1524)
				(type default)
			)
			(layer "F.SilkS")
		)
		(fp_line
			(start -0.67945 0.3048)
			(end -0.67945 -0.305054)
			(stroke
				(width 0.1)
				(type default)
			)
			(layer "F.Fab")
		)
		(fp_line
			(start -0.12065 0.3048)
			(end -0.67945 0.3048)
			(stroke
				(width 0.1)
				(type default)
			)
			(layer "F.Fab")
		)
		(fp_line
			(start 0.120396 0.3048)
			(end 0.120396 0.2794)
			(stroke
				(width 0.1)
				(type default)
			)
			(layer "F.Fab")
		)
		(fp_line
			(start 0.67945 0.3048)
			(end 0.120396 0.3048)
			(stroke
				(width 0.1)
				(type default)
			)
			(layer "F.Fab")
		)
		(fp_line
			(start -0.12065 0.2794)
			(end -0.12065 0.3048)
			(stroke
				(width 0.1)
				(type default)
			)
			(layer "F.Fab")
		)
		(fp_line
			(start 0.120396 0.2794)
			(end -0.12065 0.2794)
			(stroke
				(width 0.1)
				(type default)
			)
			(layer "F.Fab")
		)
		(fp_line
			(start -0.12065 -0.2794)
			(end 0.12065 -0.2794)
			(stroke
				(width 0.1)
				(type default)
			)
			(layer "F.Fab")
		)
		(fp_line
			(start 0.12065 -0.2794)
			(end 0.12065 -0.3048)
			(stroke
				(width 0.1)
				(type default)
			)
			(layer "F.Fab")
		)
		(fp_line
			(start 0.12065 -0.3048)
			(end 0.67945 -0.3048)
			(stroke
				(width 0.1)
				(type default)
			)
			(layer "F.Fab")
		)
		(fp_line
			(start 0.67945 -0.3048)
			(end 0.67945 0.3048)
			(stroke
				(width 0.1)
				(type default)
			)
			(layer "F.Fab")
		)
		(fp_line
			(start -0.67945 -0.305054)
			(end -0.12065 -0.305054)
			(stroke
				(width 0.1)
				(type default)
			)
			(layer "F.Fab")
		)
		(fp_line
			(start -0.12065 -0.305054)
			(end -0.12065 -0.2794)
			(stroke
				(width 0.1)
				(type default)
			)
			(layer "F.Fab")
		)
		(pad "1" smd circle
			(at -0.40005 0 270)
			(size 0 0)
			(layers "F.Cu" "F.Mask" "F.Paste")
			(net "FM_SWB_PWR_EN_R1_BUF")
		)
		(pad "2" smd circle
			(at 0.40005 0 270)
			(size 0 0)
			(layers "F.Cu" "F.Mask" "F.Paste")
			(net "GND")
		)
	)
	(footprint ""
		(layer "F.Cu")
		(at 240.431574 -149.965918 180)
		(property "Reference" "C1520"
			(at 0 0 180)
			(layer "F.SilkS")
			(hide yes)
			(effects
				(font
					(size 1.27 1.27)
				)
			)
		)
		(property "Value" ""
			(at 0 0 180)
			(layer "F.Fab")
			(effects
				(font
					(size 1.27 1.27)
				)
			)
		)
		(duplicate_pad_numbers_are_jumpers no)
		(fp_line
			(start 0.7874 0.4064)
			(end -0.7874 0.4064)
			(stroke
				(width 0.1524)
				(type default)
			)
			(layer "F.SilkS")
		)
		(fp_line
			(start 0.7874 -0.4064)
			(end 0.7874 0.4064)
			(stroke
				(width 0.1524)
				(type default)
			)
			(layer "F.SilkS")
		)
		(fp_line
			(start -0.7874 0.4064)
			(end -0.7874 -0.4064)
			(stroke
				(width 0.1524)
				(type default)
			)
			(layer "F.SilkS")
		)
		(fp_line
			(start -0.7874 -0.4064)
			(end 0.7874 -0.4064)
			(stroke
				(width 0.1524)
				(type default)
			)
			(layer "F.SilkS")
		)
		(fp_line
			(start 0.67945 0.3048)
			(end 0.120396 0.3048)
			(stroke
				(width 0.1)
				(type default)
			)
			(layer "F.Fab")
		)
		(fp_line
			(start 0.67945 -0.3048)
			(end 0.67945 0.3048)
			(stroke
				(width 0.1)
				(type default)
			)
			(layer "F.Fab")
		)
		(fp_line
			(start 0.12065 -0.2794)
			(end 0.12065 -0.3048)
			(stroke
				(width 0.1)
				(type default)
			)
			(layer "F.Fab")
		)
		(fp_line
			(start 0.12065 -0.3048)
			(end 0.67945 -0.3048)
			(stroke
				(width 0.1)
				(type default)
			)
			(layer "F.Fab")
		)
		(fp_line
			(start 0.120396 0.3048)
			(end 0.120396 0.2794)
			(stroke
				(width 0.1)
				(type default)
			)
			(layer "F.Fab")
		)
		(fp_line
			(start 0.120396 0.2794)
			(end -0.12065 0.2794)
			(stroke
				(width 0.1)
				(type default)
			)
			(layer "F.Fab")
		)
		(fp_line
			(start -0.12065 0.3048)
			(end -0.67945 0.3048)
			(stroke
				(width 0.1)
				(type default)
			)
			(layer "F.Fab")
		)
		(fp_line
			(start -0.12065 0.2794)
			(end -0.12065 0.3048)
			(stroke
				(width 0.1)
				(type default)
			)
			(layer "F.Fab")
		)
		(fp_line
			(start -0.12065 -0.2794)
			(end 0.12065 -0.2794)
			(stroke
				(width 0.1)
				(type default)
			)
			(layer "F.Fab")
		)
		(fp_line
			(start -0.12065 -0.305054)
			(end -0.12065 -0.2794)
			(stroke
				(width 0.1)
				(type default)
			)
			(layer "F.Fab")
		)
		(fp_line
			(start -0.67945 0.3048)
			(end -0.67945 -0.305054)
			(stroke
				(width 0.1)
				(type default)
			)
			(layer "F.Fab")
		)
		(fp_line
			(start -0.67945 -0.305054)
			(end -0.12065 -0.305054)
			(stroke
				(width 0.1)
				(type default)
			)
			(layer "F.Fab")
		)
		(pad "1" smd circle
			(at -0.40005 0 180)
			(size 0 0)
			(layers "F.Cu" "F.Mask" "F.Paste")
			(net "JTAG_CPU0_TDI")
		)
		(pad "2" smd circle
			(at 0.40005 0 180)
			(size 0 0)
			(layers "F.Cu" "F.Mask" "F.Paste")
			(net "GND")
		)
	)
	(footprint ""
		(layer "F.Cu")
		(at 366.288574 0.002794 180)
		(property "Reference" "J8067"
			(at -4.710176 -2.058416 90)
			(unlocked yes)
			(layer "F.SilkS")
			(effects
				(font
					(size 0.7874 0.5842)
					(thickness 0.1524)
				)
				(justify left)
			)
		)
		(property "Value" ""
			(at 0 0 180)
			(layer "F.Fab")
			(effects
				(font
					(size 1.27 1.27)
				)
			)
		)
		(duplicate_pad_numbers_are_jumpers no)
		(fp_line
			(start 1.2192 2.06756)
			(end -1.2192 2.06756)
			(stroke
				(width 0.1524)
				(type default)
			)
			(layer "F.SilkS")
		)
		(fp_line
			(start 1.2192 -2.06756)
			(end 1.2192 2.06756)
			(stroke
				(width 0.1524)
				(type default)
			)
			(layer "F.SilkS")
		)
		(fp_line
			(start -1.2192 2.06756)
			(end -1.2192 -2.06756)
			(stroke
				(width 0.1524)
				(type default)
			)
			(layer "F.SilkS")
		)
		(fp_line
			(start -1.2192 -2.06756)
			(end 1.2192 -2.06756)
			(stroke
				(width 0.1524)
				(type default)
			)
			(layer "F.SilkS")
		)
		(pad "" np_thru_hole circle
			(at -2.8829 -1.27 90)
			(size 1.0414 1.0414)
			(drill 1.0414)
			(layers "*.Cu" "*.Mask")
			(clearance 0.381)
			(thermal_gap 0.381)
		)
		(pad "" np_thru_hole circle
			(at -2.8829 1.27 90)
			(size 1.0414 1.0414)
			(drill 1.0414)
			(layers "*.Cu" "*.Mask")
			(clearance 0.381)
			(thermal_gap 0.381)
		)
		(pad "" np_thru_hole circle
			(at 3.4671 -1.27 90)
			(size 1.0414 1.0414)
			(drill 1.0414)
			(layers "*.Cu" "*.Mask")
			(clearance 0.381)
			(thermal_gap 0.381)
		)
		(pad "" np_thru_hole circle
			(at 3.4671 1.27 90)
			(size 1.0414 1.0414)
			(drill 1.0414)
			(layers "*.Cu" "*.Mask")
			(clearance 0.381)
			(thermal_gap 0.381)
		)
		(pad "1" smd rect
			(at 0.8255 -0.249936 90)
			(size 0.3048 0.508)
			(layers "F.Cu" "F.Mask" "F.Paste")
			(net "DELTA_L_85_5INCH_IN3_DP")
		)
		(pad "2" smd rect
			(at 0.8255 0.249936 90)
			(size 0.3048 0.508)
			(layers "F.Cu" "F.Mask" "F.Paste")
			(net "DELTA_L_85_5INCH_IN3_DN")
		)
		(pad "3" smd circle
			(at 0 0 180)
			(size 0 0)
			(layers "F.Cu" "F.Mask" "F.Paste")
			(net "DELTA_L_GND_1")
		)
		(zone
			(layer "F.Cu")
			(hatch none 0.5)
			(connect_pads
				(clearance 0)
			)
			(min_thickness 0.25)
			(keepout
				(tracks not_allowed)
				(vias allowed)
				(pads allowed)
				(copperpour not_allowed)
				(footprints allowed)
			)
			(placement
				(enabled no)
				(sheetname "")
			)
			(fill
				(thermal_gap 0.5)
				(thermal_bridge_width 0.5)
				(island_removal_mode 0)
			)
			(polygon
				(pts
					(xy 365.170974 0.551434) (xy 365.170974 0.45593) (xy 365.767874 0.45593) (xy 365.767874 0.04953)
					(xy 365.170974 0.04953) (xy 365.170974 -0.043942) (xy 365.767874 -0.043942) (xy 365.767874 -0.450342)
					(xy 365.170974 -0.450342) (xy 365.170974 -0.545846) (xy 365.869474 -0.545846) (xy 365.869474 0.551434)
				)
			)
		)
		(zone
			(layers "F.Cu" "B.Cu" "In1.Cu" "In2.Cu" "In3.Cu" "In4.Cu" "In5.Cu" "In6.Cu"
				"In7.Cu" "In8.Cu" "In9.Cu" "In10.Cu" "In11.Cu" "In12.Cu" "In13.Cu" "In14.Cu"
				"In15.Cu" "In16.Cu"
			)
			(hatch none 0.5)
			(connect_pads
				(clearance 0)
			)
			(min_thickness 0.25)
			(keepout
				(tracks not_allowed)
				(vias allowed)
				(pads allowed)
				(copperpour not_allowed)
				(footprints allowed)
			)
			(placement
				(enabled no)
				(sheetname "")
			)
			(fill
				(thermal_gap 0.5)
				(thermal_bridge_width 0.5)
				(island_removal_mode 0)
			)
			(polygon
				(pts
					(arc
						(start 363.748574 -1.267206)
						(mid 361.894374 -1.267206)
						(end 363.748574 -1.267206)
					)
				)
			)
		)
		(zone
			(layers "F.Cu" "B.Cu" "In1.Cu" "In2.Cu" "In3.Cu" "In4.Cu" "In5.Cu" "In6.Cu"
				"In7.Cu" "In8.Cu" "In9.Cu" "In10.Cu" "In11.Cu" "In12.Cu" "In13.Cu" "In14.Cu"
				"In15.Cu" "In16.Cu"
			)
			(hatch none 0.5)
			(connect_pads
				(clearance 0)
			)
			(min_thickness 0.25)
			(keepout
				(tracks not_allowed)
				(vias allowed)
				(pads allowed)
				(copperpour not_allowed)
				(footprints allowed)
			)
			(placement
				(enabled no)
				(sheetname "")
			)
			(fill
				(thermal_gap 0.5)
				(thermal_bridge_width 0.5)
				(island_removal_mode 0)
			)
			(polygon
				(pts
					(arc
						(start 363.748574 1.272794)
						(mid 361.894374 1.272794)
						(end 363.748574 1.272794)
					)
				)
			)
		)
		(zone
			(layers "F.Cu" "B.Cu" "In1.Cu" "In2.Cu" "In3.Cu" "In4.Cu" "In5.Cu" "In6.Cu"
				"In7.Cu" "In8.Cu" "In9.Cu" "In10.Cu" "In11.Cu" "In12.Cu" "In13.Cu" "In14.Cu"
				"In15.Cu" "In16.Cu"
			)
			(hatch none 0.5)
			(connect_pads
				(clearance 0)
			)
			(min_thickness 0.25)
			(keepout
				(tracks not_allowed)
				(vias allowed)
				(pads allowed)
				(copperpour not_allowed)
				(footprints allowed)
			)
			(placement
				(enabled no)
				(sheetname "")
			)
			(fill
				(thermal_gap 0.5)
				(thermal_bridge_width 0.5)
				(island_removal_mode 0)
			)
			(polygon
				(pts
					(arc
						(start 370.098574 -1.267206)
						(mid 368.244374 -1.267206)
						(end 370.098574 -1.267206)
					)
				)
			)
		)
		(zone
			(layers "F.Cu" "B.Cu" "In1.Cu" "In2.Cu" "In3.Cu" "In4.Cu" "In5.Cu" "In6.Cu"
				"In7.Cu" "In8.Cu" "In9.Cu" "In10.Cu" "In11.Cu" "In12.Cu" "In13.Cu" "In14.Cu"
				"In15.Cu" "In16.Cu"
			)
			(hatch none 0.5)
			(connect_pads
				(clearance 0)
			)
			(min_thickness 0.25)
			(keepout
				(tracks not_allowed)
				(vias allowed)
				(pads allowed)
				(copperpour not_allowed)
				(footprints allowed)
			)
			(placement
				(enabled no)
				(sheetname "")
			)
			(fill
				(thermal_gap 0.5)
				(thermal_bridge_width 0.5)
				(island_removal_mode 0)
			)
			(polygon
				(pts
					(arc
						(start 370.098574 1.272794)
						(mid 368.244374 1.272794)
						(end 370.098574 1.272794)
					)
				)
			)
		)
	)
	(footprint ""
		(layer "F.Cu")
		(at 288.26587 -96.655382)
		(property "Reference" "C1510"
			(at 0 0 0)
			(layer "F.SilkS")
			(hide yes)
			(effects
				(font
					(size 1.27 1.27)
				)
			)
		)
		(property "Value" ""
			(at 0 0 0)
			(layer "F.Fab")
			(effects
				(font
					(size 1.27 1.27)
				)
			)
		)
		(duplicate_pad_numbers_are_jumpers no)
		(fp_line
			(start -0.7874 -0.4064)
			(end 0.7874 -0.4064)
			(stroke
				(width 0.1524)
				(type default)
			)
			(layer "F.SilkS")
		)
		(fp_line
			(start -0.7874 0.4064)
			(end -0.7874 -0.4064)
			(stroke
				(width 0.1524)
				(type default)
			)
			(layer "F.SilkS")
		)
		(fp_line
			(start 0.7874 -0.4064)
			(end 0.7874 0.4064)
			(stroke
				(width 0.1524)
				(type default)
			)
			(layer "F.SilkS")
		)
		(fp_line
			(start 0.7874 0.4064)
			(end -0.7874 0.4064)
			(stroke
				(width 0.1524)
				(type default)
			)
			(layer "F.SilkS")
		)
		(fp_line
			(start -0.67945 -0.305054)
			(end -0.12065 -0.305054)
			(stroke
				(width 0.1)
				(type default)
			)
			(layer "F.Fab")
		)
		(fp_line
			(start -0.67945 0.3048)
			(end -0.67945 -0.305054)
			(stroke
				(width 0.1)
				(type default)
			)
			(layer "F.Fab")
		)
		(fp_line
			(start -0.12065 -0.305054)
			(end -0.12065 -0.2794)
			(stroke
				(width 0.1)
				(type default)
			)
			(layer "F.Fab")
		)
		(fp_line
			(start -0.12065 -0.2794)
			(end 0.12065 -0.2794)
			(stroke
				(width 0.1)
				(type default)
			)
			(layer "F.Fab")
		)
		(fp_line
			(start -0.12065 0.2794)
			(end -0.12065 0.3048)
			(stroke
				(width 0.1)
				(type default)
			)
			(layer "F.Fab")
		)
		(fp_line
			(start -0.12065 0.3048)
			(end -0.67945 0.3048)
			(stroke
				(width 0.1)
				(type default)
			)
			(layer "F.Fab")
		)
		(fp_line
			(start 0.120396 0.2794)
			(end -0.12065 0.2794)
			(stroke
				(width 0.1)
				(type default)
			)
			(layer "F.Fab")
		)
		(fp_line
			(start 0.120396 0.3048)
			(end 0.120396 0.2794)
			(stroke
				(width 0.1)
				(type default)
			)
			(layer "F.Fab")
		)
		(fp_line
			(start 0.12065 -0.3048)
			(end 0.67945 -0.3048)
			(stroke
				(width 0.1)
				(type default)
			)
			(layer "F.Fab")
		)
		(fp_line
			(start 0.12065 -0.2794)
			(end 0.12065 -0.3048)
			(stroke
				(width 0.1)
				(type default)
			)
			(layer "F.Fab")
		)
		(fp_line
			(start 0.67945 -0.3048)
			(end 0.67945 0.3048)
			(stroke
				(width 0.1)
				(type default)
			)
			(layer "F.Fab")
		)
		(fp_line
			(start 0.67945 0.3048)
			(end 0.120396 0.3048)
			(stroke
				(width 0.1)
				(type default)
			)
			(layer "F.Fab")
		)
		(pad "1" smd circle
			(at -0.40005 0)
			(size 0 0)
			(layers "F.Cu" "F.Mask" "F.Paste")
			(net "JTAG_TCK")
		)
		(pad "2" smd circle
			(at 0.40005 0)
			(size 0 0)
			(layers "F.Cu" "F.Mask" "F.Paste")
			(net "GND")
		)
	)
	(footprint ""
		(layer "F.Cu")
		(at 106.250486 -22.271482 180)
		(property "Reference" "Y6000"
			(at 2.285492 -3.005836 0)
			(unlocked yes)
			(layer "F.SilkS")
			(effects
				(font
					(size 0.7874 0.5842)
					(thickness 0.1524)
				)
				(justify left)
			)
		)
		(property "Value" ""
			(at 0 0 180)
			(layer "F.Fab")
			(effects
				(font
					(size 1.27 1.27)
				)
			)
		)
		(duplicate_pad_numbers_are_jumpers no)
		(fp_line
			(start 1.6002 1.9558)
			(end -1.6002 1.9558)
			(stroke
				(width 0.1524)
				(type default)
			)
			(layer "F.SilkS")
		)
		(fp_line
			(start 1.6002 -1.9558)
			(end 1.6002 1.9558)
			(stroke
				(width 0.1524)
				(type default)
			)
			(layer "F.SilkS")
		)
		(fp_line
			(start -1.6002 1.9558)
			(end -1.6002 -1.9558)
			(stroke
				(width 0.1524)
				(type default)
			)
			(layer "F.SilkS")
		)
		(fp_line
			(start -1.6002 -1.9558)
			(end 1.6002 -1.9558)
			(stroke
				(width 0.1524)
				(type default)
			)
			(layer "F.SilkS")
		)
		(fp_poly
			(pts
				(xy -2.88036 -0.26416) (xy -2.88036 -1.33096) (xy -1.78816 -0.74676)
			)
			(stroke
				(width 0)
				(type default)
			)
			(fill yes)
			(layer "F.SilkS")
		)
		(fp_line
			(start 1.299972 1.649984)
			(end -1.299972 1.649984)
			(stroke
				(width 0.1)
				(type default)
			)
			(layer "F.Fab")
		)
		(fp_line
			(start 1.299972 -1.649984)
			(end 1.299972 1.649984)
			(stroke
				(width 0.1)
				(type default)
			)
			(layer "F.Fab")
		)
		(fp_line
			(start -1.299972 1.649984)
			(end -1.299972 -1.649984)
			(stroke
				(width 0.1)
				(type default)
			)
			(layer "F.Fab")
		)
		(fp_line
			(start -1.299972 -1.649984)
			(end 1.299972 -1.649984)
			(stroke
				(width 0.1)
				(type default)
			)
			(layer "F.Fab")
		)
		(fp_poly
			(pts
				(xy -1.7145 -1.0668) (xy -2.8067 -1.651) (xy -2.8067 -0.5842)
			)
			(stroke
				(width 0)
				(type default)
			)
			(fill yes)
			(layer "F.Fab")
		)
		(pad "1" smd rect
			(at -0.849884 -1.100074 180)
			(size 1.2192 1.4224)
			(layers "F.Cu" "F.Mask" "F.Paste")
			(net "XTAL_USB_CPU0_HUB2_XIN")
		)
		(pad "2" smd rect
			(at -0.849884 1.100074 180)
			(size 1.2192 1.4224)
			(layers "F.Cu" "F.Mask" "F.Paste")
			(net "GND")
		)
		(pad "3" smd rect
			(at 0.849884 1.100074 180)
			(size 1.2192 1.4224)
			(layers "F.Cu" "F.Mask" "F.Paste")
			(net "XTAL_USB_CPU0_HUB2_XOUT")
		)
		(pad "4" smd rect
			(at 0.849884 -1.100074 180)
			(size 1.2192 1.4224)
			(layers "F.Cu" "F.Mask" "F.Paste")
			(net "GND")
		)
	)
	(footprint ""
		(layer "F.Cu")
		(at 335.514442 -140.870686)
		(property "Reference" "PU57"
			(at 0.5334 -3.094228 0)
			(unlocked yes)
			(layer "F.SilkS")
			(effects
				(font
					(size 0.7874 0.5842)
					(thickness 0.1524)
				)
				(justify left)
			)
		)
		(property "Value" ""
			(at 0 0 0)
			(layer "F.Fab")
			(effects
				(font
					(size 1.27 1.27)
				)
			)
		)
		(duplicate_pad_numbers_are_jumpers no)
		(fp_line
			(start -1.549908 -2.050034)
			(end -1.549908 -1.9812)
			(stroke
				(width 0.1524)
				(type default)
			)
			(layer "F.SilkS")
		)
		(fp_line
			(start -1.549908 1.9812)
			(end -1.549908 2.050034)
			(stroke
				(width 0.1524)
				(type default)
			)
			(layer "F.SilkS")
		)
		(fp_line
			(start -1.549908 2.050034)
			(end -0.5842 2.050034)
			(stroke
				(width 0.1524)
				(type default)
			)
			(layer "F.SilkS")
		)
		(fp_line
			(start -0.5842 -2.050034)
			(end -1.549908 -2.050034)
			(stroke
				(width 0.1524)
				(type default)
			)
			(layer "F.SilkS")
		)
		(fp_line
			(start 0 2.050034)
			(end 1.549908 2.050034)
			(stroke
				(width 0.1524)
				(type default)
			)
			(layer "F.SilkS")
		)
		(fp_line
			(start 1.549908 -2.050034)
			(end 0.5842 -2.050034)
			(stroke
				(width 0.1524)
				(type default)
			)
			(layer "F.SilkS")
		)
		(fp_line
			(start 1.549908 -1.9812)
			(end 1.549908 -2.050034)
			(stroke
				(width 0.1524)
				(type default)
			)
			(layer "F.SilkS")
		)
		(fp_poly
			(pts
				(xy -1.9304 -1.700022) (xy -2.594864 -1.36779) (xy -2.594864 -2.032254)
			)
			(stroke
				(width 0)
				(type default)
			)
			(fill yes)
			(layer "F.SilkS")
		)
		(fp_line
			(start -1.549908 -2.050034)
			(end -1.549908 2.050034)
			(stroke
				(width 0.1)
				(type default)
			)
			(layer "F.Fab")
		)
		(fp_line
			(start -1.549908 2.050034)
			(end 1.549908 2.050034)
			(stroke
				(width 0.1)
				(type default)
			)
			(layer "F.Fab")
		)
		(fp_line
			(start 1.549908 -2.050034)
			(end -1.549908 -2.050034)
			(stroke
				(width 0.1)
				(type default)
			)
			(layer "F.Fab")
		)
		(fp_line
			(start 1.549908 2.050034)
			(end 1.549908 -2.050034)
			(stroke
				(width 0.1)
				(type default)
			)
			(layer "F.Fab")
		)
		(fp_poly
			(pts
				(xy -2.9464 -2.208022) (xy -2.9464 -1.192022) (xy -1.9304 -1.700022)
			)
			(stroke
				(width 0)
				(type default)
			)
			(fill yes)
			(layer "F.Fab")
		)
		(pad "1" smd circle
			(at -1.35001 -1.700022)
			(size 0 0)
			(layers "F.Cu" "F.Mask" "F.Paste")
			(net "SW_PVDD18_S5_P0_BST")
		)
		(pad "2" smd rect
			(at -1.400048 -1.199896 90)
			(size 0.1778 0.8128)
			(layers "F.Cu" "F.Mask" "F.Paste")
			(net "GND")
		)
		(pad "3" smd rect
			(at -1.400048 -0.8001 90)
			(size 0.1778 0.8128)
			(layers "F.Cu" "F.Mask" "F.Paste")
			(net "PVDD18_S5_P0_CS")
		)
		(pad "4" smd rect
			(at -1.400048 -0.40005 90)
			(size 0.1778 0.8128)
			(layers "F.Cu" "F.Mask" "F.Paste")
			(net "PVDD18_S5_P0_MODE")
		)
		(pad "5" smd rect
			(at -1.400048 0 90)
			(size 0.1778 0.8128)
			(layers "F.Cu" "F.Mask" "F.Paste")
			(net "PVDD18_S5_P0_REF")
		)
		(pad "6" smd rect
			(at -1.400048 0.40005 90)
			(size 0.1778 0.8128)
			(layers "F.Cu" "F.Mask" "F.Paste")
			(net "PVDD18_S5_P0_RGND")
		)
		(pad "7" smd rect
			(at -1.400048 0.8001 90)
			(size 0.1778 0.8128)
			(layers "F.Cu" "F.Mask" "F.Paste")
			(net "PVDD18_S5_P0_FB")
		)
		(pad "8" smd rect
			(at -1.400048 1.199896 90)
			(size 0.1778 0.8128)
			(layers "F.Cu" "F.Mask" "F.Paste")
			(net "PVDD18_S5_P0_EN")
		)
		(pad "9" smd rect
			(at -1.400048 1.700022 90)
			(size 0.3048 0.8128)
			(layers "F.Cu" "F.Mask" "F.Paste")
			(net "PWRGD_PVDD18_S5_P0")
		)
		(pad "10" smd rect
			(at -0.299974 1.299972)
			(size 0.3048 2.0066)
			(layers "F.Cu" "F.Mask" "F.Paste")
			(net "SW_P12V_AUX_PVDD18_S5_P0_FLT")
		)
		(pad "11_18" smd circle
			(at 1.175004 0.275082)
			(size 0 0)
			(layers "F.Cu" "F.Mask" "F.Paste")
			(net "GND")
		)
		(pad "19" smd rect
			(at 1.400048 -1.700022 270)
			(size 0.3048 0.8128)
			(layers "F.Cu" "F.Mask" "F.Paste")
			(net "PVDD18_S5_P0_VCC")
		)
		(pad "20" smd rect
			(at 0.299974 -1.299972)
			(size 0.3048 2.0066)
			(layers "F.Cu" "F.Mask" "F.Paste")
			(net "SW_PVDD18_S5_P0_SW")
		)
		(pad "21" smd rect
			(at -0.299974 -1.299972)
			(size 0.3048 2.0066)
			(layers "F.Cu" "F.Mask" "F.Paste")
			(net "SW_P12V_AUX_PVDD18_S5_P0_FLT")
		)
	)
	(footprint ""
		(layer "F.Cu")
		(at 105.84561 -68.62191 180)
		(property "Reference" "R6217"
			(at 0 0 180)
			(layer "F.SilkS")
			(hide yes)
			(effects
				(font
					(size 1.27 1.27)
				)
			)
		)
		(property "Value" ""
			(at 0 0 180)
			(layer "F.Fab")
			(effects
				(font
					(size 1.27 1.27)
				)
			)
		)
		(duplicate_pad_numbers_are_jumpers no)
		(fp_line
			(start 0.7874 0.4064)
			(end -0.7874 0.4064)
			(stroke
				(width 0.1524)
				(type default)
			)
			(layer "F.SilkS")
		)
		(fp_line
			(start 0.7874 -0.4064)
			(end 0.7874 0.4064)
			(stroke
				(width 0.1524)
				(type default)
			)
			(layer "F.SilkS")
		)
		(fp_line
			(start -0.7874 0.4064)
			(end -0.7874 -0.4064)
			(stroke
				(width 0.1524)
				(type default)
			)
			(layer "F.SilkS")
		)
		(fp_line
			(start -0.7874 -0.4064)
			(end 0.7874 -0.4064)
			(stroke
				(width 0.1524)
				(type default)
			)
			(layer "F.SilkS")
		)
		(fp_line
			(start 0.67945 0.3048)
			(end 0.120396 0.3048)
			(stroke
				(width 0.1)
				(type default)
			)
			(layer "F.Fab")
		)
		(fp_line
			(start 0.67945 -0.3048)
			(end 0.67945 0.3048)
			(stroke
				(width 0.1)
				(type default)
			)
			(layer "F.Fab")
		)
		(fp_line
			(start 0.12065 -0.2794)
			(end 0.12065 -0.3048)
			(stroke
				(width 0.1)
				(type default)
			)
			(layer "F.Fab")
		)
		(fp_line
			(start 0.12065 -0.3048)
			(end 0.67945 -0.3048)
			(stroke
				(width 0.1)
				(type default)
			)
			(layer "F.Fab")
		)
		(fp_line
			(start 0.120396 0.3048)
			(end 0.120396 0.2794)
			(stroke
				(width 0.1)
				(type default)
			)
			(layer "F.Fab")
		)
		(fp_line
			(start 0.120396 0.2794)
			(end -0.12065 0.2794)
			(stroke
				(width 0.1)
				(type default)
			)
			(layer "F.Fab")
		)
		(fp_line
			(start -0.12065 0.3048)
			(end -0.67945 0.3048)
			(stroke
				(width 0.1)
				(type default)
			)
			(layer "F.Fab")
		)
		(fp_line
			(start -0.12065 0.2794)
			(end -0.12065 0.3048)
			(stroke
				(width 0.1)
				(type default)
			)
			(layer "F.Fab")
		)
		(fp_line
			(start -0.12065 -0.2794)
			(end 0.12065 -0.2794)
			(stroke
				(width 0.1)
				(type default)
			)
			(layer "F.Fab")
		)
		(fp_line
			(start -0.12065 -0.305054)
			(end -0.12065 -0.2794)
			(stroke
				(width 0.1)
				(type default)
			)
			(layer "F.Fab")
		)
		(fp_line
			(start -0.67945 0.3048)
			(end -0.67945 -0.305054)
			(stroke
				(width 0.1)
				(type default)
			)
			(layer "F.Fab")
		)
		(fp_line
			(start -0.67945 -0.305054)
			(end -0.12065 -0.305054)
			(stroke
				(width 0.1)
				(type default)
			)
			(layer "F.Fab")
		)
		(pad "1" smd circle
			(at -0.40005 0 180)
			(size 0 0)
			(layers "F.Cu" "F.Mask" "F.Paste")
			(net "USB_CPU0_ADD_A0")
		)
		(pad "2" smd circle
			(at 0.40005 0 180)
			(size 0 0)
			(layers "F.Cu" "F.Mask" "F.Paste")
			(net "GND")
		)
	)
	(footprint ""
		(layer "F.Cu")
		(at 205.243684 -121.960386)
		(property "Reference" "R4146"
			(at 0 0 0)
			(layer "F.SilkS")
			(hide yes)
			(effects
				(font
					(size 1.27 1.27)
				)
			)
		)
		(property "Value" ""
			(at 0 0 0)
			(layer "F.Fab")
			(effects
				(font
					(size 1.27 1.27)
				)
			)
		)
		(duplicate_pad_numbers_are_jumpers no)
		(fp_line
			(start -0.7874 -0.4064)
			(end 0.7874 -0.4064)
			(stroke
				(width 0.1524)
				(type default)
			)
			(layer "F.SilkS")
		)
		(fp_line
			(start -0.7874 0.4064)
			(end -0.7874 -0.4064)
			(stroke
				(width 0.1524)
				(type default)
			)
			(layer "F.SilkS")
		)
		(fp_line
			(start 0.7874 -0.4064)
			(end 0.7874 0.4064)
			(stroke
				(width 0.1524)
				(type default)
			)
			(layer "F.SilkS")
		)
		(fp_line
			(start 0.7874 0.4064)
			(end -0.7874 0.4064)
			(stroke
				(width 0.1524)
				(type default)
			)
			(layer "F.SilkS")
		)
		(fp_line
			(start -0.67945 -0.305054)
			(end -0.12065 -0.305054)
			(stroke
				(width 0.1)
				(type default)
			)
			(layer "F.Fab")
		)
		(fp_line
			(start -0.67945 0.3048)
			(end -0.67945 -0.305054)
			(stroke
				(width 0.1)
				(type default)
			)
			(layer "F.Fab")
		)
		(fp_line
			(start -0.12065 -0.305054)
			(end -0.12065 -0.2794)
			(stroke
				(width 0.1)
				(type default)
			)
			(layer "F.Fab")
		)
		(fp_line
			(start -0.12065 -0.2794)
			(end 0.12065 -0.2794)
			(stroke
				(width 0.1)
				(type default)
			)
			(layer "F.Fab")
		)
		(fp_line
			(start -0.12065 0.2794)
			(end -0.12065 0.3048)
			(stroke
				(width 0.1)
				(type default)
			)
			(layer "F.Fab")
		)
		(fp_line
			(start -0.12065 0.3048)
			(end -0.67945 0.3048)
			(stroke
				(width 0.1)
				(type default)
			)
			(layer "F.Fab")
		)
		(fp_line
			(start 0.120396 0.2794)
			(end -0.12065 0.2794)
			(stroke
				(width 0.1)
				(type default)
			)
			(layer "F.Fab")
		)
		(fp_line
			(start 0.120396 0.3048)
			(end 0.120396 0.2794)
			(stroke
				(width 0.1)
				(type default)
			)
			(layer "F.Fab")
		)
		(fp_line
			(start 0.12065 -0.3048)
			(end 0.67945 -0.3048)
			(stroke
				(width 0.1)
				(type default)
			)
			(layer "F.Fab")
		)
		(fp_line
			(start 0.12065 -0.2794)
			(end 0.12065 -0.3048)
			(stroke
				(width 0.1)
				(type default)
			)
			(layer "F.Fab")
		)
		(fp_line
			(start 0.67945 -0.3048)
			(end 0.67945 0.3048)
			(stroke
				(width 0.1)
				(type default)
			)
			(layer "F.Fab")
		)
		(fp_line
			(start 0.67945 0.3048)
			(end 0.120396 0.3048)
			(stroke
				(width 0.1)
				(type default)
			)
			(layer "F.Fab")
		)
		(pad "1" smd circle
			(at -0.40005 0)
			(size 0 0)
			(layers "F.Cu" "F.Mask" "F.Paste")
			(net "GPU_3V3IO_RSVD3_FFU_ISO_R")
		)
		(pad "2" smd circle
			(at 0.40005 0)
			(size 0 0)
			(layers "F.Cu" "F.Mask" "F.Paste")
			(net "GPU_3V3IO_RSVD3_FFU_ISO")
		)
	)
	(footprint ""
		(layer "F.Cu")
		(at 151.19604 -40.403526 90)
		(property "Reference" "C1861"
			(at 0 0 90)
			(layer "F.SilkS")
			(hide yes)
			(effects
				(font
					(size 1.27 1.27)
				)
			)
		)
		(property "Value" ""
			(at 0 0 90)
			(layer "F.Fab")
			(effects
				(font
					(size 1.27 1.27)
				)
			)
		)
		(duplicate_pad_numbers_are_jumpers no)
		(fp_line
			(start 0.7874 -0.4064)
			(end 0.7874 0.4064)
			(stroke
				(width 0.1524)
				(type default)
			)
			(layer "F.SilkS")
		)
		(fp_line
			(start -0.7874 -0.4064)
			(end 0.7874 -0.4064)
			(stroke
				(width 0.1524)
				(type default)
			)
			(layer "F.SilkS")
		)
		(fp_line
			(start 0.7874 0.4064)
			(end -0.7874 0.4064)
			(stroke
				(width 0.1524)
				(type default)
			)
			(layer "F.SilkS")
		)
		(fp_line
			(start -0.7874 0.4064)
			(end -0.7874 -0.4064)
			(stroke
				(width 0.1524)
				(type default)
			)
			(layer "F.SilkS")
		)
		(fp_line
			(start -0.12065 -0.305054)
			(end -0.12065 -0.2794)
			(stroke
				(width 0.1)
				(type default)
			)
			(layer "F.Fab")
		)
		(fp_line
			(start -0.67945 -0.305054)
			(end -0.12065 -0.305054)
			(stroke
				(width 0.1)
				(type default)
			)
			(layer "F.Fab")
		)
		(fp_line
			(start 0.67945 -0.3048)
			(end 0.67945 0.3048)
			(stroke
				(width 0.1)
				(type default)
			)
			(layer "F.Fab")
		)
		(fp_line
			(start 0.12065 -0.3048)
			(end 0.67945 -0.3048)
			(stroke
				(width 0.1)
				(type default)
			)
			(layer "F.Fab")
		)
		(fp_line
			(start 0.12065 -0.2794)
			(end 0.12065 -0.3048)
			(stroke
				(width 0.1)
				(type default)
			)
			(layer "F.Fab")
		)
		(fp_line
			(start -0.12065 -0.2794)
			(end 0.12065 -0.2794)
			(stroke
				(width 0.1)
				(type default)
			)
			(layer "F.Fab")
		)
		(fp_line
			(start 0.120396 0.2794)
			(end -0.12065 0.2794)
			(stroke
				(width 0.1)
				(type default)
			)
			(layer "F.Fab")
		)
		(fp_line
			(start -0.12065 0.2794)
			(end -0.12065 0.3048)
			(stroke
				(width 0.1)
				(type default)
			)
			(layer "F.Fab")
		)
		(fp_line
			(start 0.67945 0.3048)
			(end 0.120396 0.3048)
			(stroke
				(width 0.1)
				(type default)
			)
			(layer "F.Fab")
		)
		(fp_line
			(start 0.120396 0.3048)
			(end 0.120396 0.2794)
			(stroke
				(width 0.1)
				(type default)
			)
			(layer "F.Fab")
		)
		(fp_line
			(start -0.12065 0.3048)
			(end -0.67945 0.3048)
			(stroke
				(width 0.1)
				(type default)
			)
			(layer "F.Fab")
		)
		(fp_line
			(start -0.67945 0.3048)
			(end -0.67945 -0.305054)
			(stroke
				(width 0.1)
				(type default)
			)
			(layer "F.Fab")
		)
		(pad "1" smd circle
			(at -0.40005 0 90)
			(size 0 0)
			(layers "F.Cu" "F.Mask" "F.Paste")
			(net "P3V3_OCP_V3_2")
		)
		(pad "2" smd circle
			(at 0.40005 0 90)
			(size 0 0)
			(layers "F.Cu" "F.Mask" "F.Paste")
			(net "GND")
		)
	)
	(footprint ""
		(layer "F.Cu")
		(at 359.952036 -340.315042)
		(property "Reference" "H44"
			(at -0.528574 -5.339334 0)
			(unlocked yes)
			(layer "F.SilkS")
			(effects
				(font
					(size 0.7874 0.5842)
					(thickness 0.1524)
				)
				(justify left)
			)
		)
		(property "Value" ""
			(at 0 0 0)
			(layer "F.Fab")
			(effects
				(font
					(size 1.27 1.27)
				)
			)
		)
		(duplicate_pad_numbers_are_jumpers no)
		(pad "1" thru_hole circle
			(at 0 0)
			(size 6.1976 6.1976)
			(drill 3.7338)
			(layers "*.Cu" "*.Mask")
			(remove_unused_layers no)
			(net "GND")
			(clearance -0.9779)
			(padstack
				(mode front_inner_back)
				(layer "Inner"
					(shape circle)
					(size 5.5372 5.5372)
					(clearance -0.6477)
				)
				(layer "B.Cu"
					(shape circle)
					(size 6.1976 6.1976)
					(clearance -0.9779)
				)
			)
		)
	)
	(footprint ""
		(layer "F.Cu")
		(at 163.250118 -432.04003 90)
		(property "Reference" "U175"
			(at -2.29743 5.584952 90)
			(unlocked yes)
			(layer "F.SilkS")
			(effects
				(font
					(size 0.7874 0.5842)
					(thickness 0.1524)
				)
				(justify left)
			)
		)
		(property "Value" ""
			(at 0 0 90)
			(layer "F.Fab")
			(effects
				(font
					(size 1.27 1.27)
				)
			)
		)
		(duplicate_pad_numbers_are_jumpers no)
		(fp_line
			(start 1.3716 -1.524)
			(end 1.3716 1.524)
			(stroke
				(width 0.1524)
				(type default)
			)
			(layer "F.SilkS")
		)
		(fp_line
			(start 0.508 -1.524)
			(end 1.3716 -1.524)
			(stroke
				(width 0.1524)
				(type default)
			)
			(layer "F.SilkS")
		)
		(fp_line
			(start -0.508 -1.524)
			(end 0 -1.016)
			(stroke
				(width 0.1524)
				(type default)
			)
			(layer "F.SilkS")
		)
		(fp_line
			(start -1.3716 -1.524)
			(end -0.508 -1.524)
			(stroke
				(width 0.1524)
				(type default)
			)
			(layer "F.SilkS")
		)
		(fp_line
			(start 0 -1.016)
			(end 0.508 -1.524)
			(stroke
				(width 0.1524)
				(type default)
			)
			(layer "F.SilkS")
		)
		(fp_line
			(start 1.3716 1.524)
			(end -1.3716 1.524)
			(stroke
				(width 0.1524)
				(type default)
			)
			(layer "F.SilkS")
		)
		(fp_line
			(start -1.3716 1.524)
			(end -1.3716 -1.524)
			(stroke
				(width 0.1524)
				(type default)
			)
			(layer "F.SilkS")
		)
		(fp_poly
			(pts
				(xy -3.60172 -0.719328) (xy -3.60172 -1.344168) (xy -3.048 -1.016)
			)
			(stroke
				(width 0)
				(type default)
			)
			(fill yes)
			(layer "F.SilkS")
		)
		(fp_line
			(start 1.5494 -1.524)
			(end 1.5494 -1.0668)
			(stroke
				(width 0.1)
				(type default)
			)
			(layer "F.Fab")
		)
		(fp_line
			(start -1.5494 -1.524)
			(end 1.5494 -1.524)
			(stroke
				(width 0.1)
				(type default)
			)
			(layer "F.Fab")
		)
		(fp_line
			(start 2.54 -1.0668)
			(end 2.54 1.0668)
			(stroke
				(width 0.1)
				(type default)
			)
			(layer "F.Fab")
		)
		(fp_line
			(start 1.5494 -1.0668)
			(end 2.54 -1.0668)
			(stroke
				(width 0.1)
				(type default)
			)
			(layer "F.Fab")
		)
		(fp_line
			(start 1.5494 -1.0668)
			(end 1.5494 1.0668)
			(stroke
				(width 0.1)
				(type default)
			)
			(layer "F.Fab")
		)
		(fp_line
			(start -1.5494 -1.0668)
			(end -1.5494 -1.524)
			(stroke
				(width 0.1)
				(type default)
			)
			(layer "F.Fab")
		)
		(fp_line
			(start -2.54 -1.0668)
			(end -1.5494 -1.0668)
			(stroke
				(width 0.1)
				(type default)
			)
			(layer "F.Fab")
		)
		(fp_line
			(start 2.54 1.0668)
			(end 1.5494 1.0668)
			(stroke
				(width 0.1)
				(type default)
			)
			(layer "F.Fab")
		)
		(fp_line
			(start 1.5494 1.0668)
			(end 1.5494 1.524)
			(stroke
				(width 0.1)
				(type default)
			)
			(layer "F.Fab")
		)
		(fp_line
			(start -1.5494 1.0668)
			(end -1.5494 -1.0668)
			(stroke
				(width 0.1)
				(type default)
			)
			(layer "F.Fab")
		)
		(fp_line
			(start -1.5494 1.0668)
			(end -2.54 1.0668)
			(stroke
				(width 0.1)
				(type default)
			)
			(layer "F.Fab")
		)
		(fp_line
			(start -2.54 1.0668)
			(end -2.54 -1.0668)
			(stroke
				(width 0.1)
				(type default)
			)
			(layer "F.Fab")
		)
		(fp_line
			(start 1.5494 1.524)
			(end -1.5494 1.524)
			(stroke
				(width 0.1)
				(type default)
			)
			(layer "F.Fab")
		)
		(fp_line
			(start -1.5494 1.524)
			(end -1.5494 1.0668)
			(stroke
				(width 0.1)
				(type default)
			)
			(layer "F.Fab")
		)
		(fp_poly
			(pts
				(xy -3.60172 -0.719328) (xy -3.60172 -1.344168) (xy -3.048 -1.016)
			)
			(stroke
				(width 0)
				(type default)
			)
			(fill yes)
			(layer "F.Fab")
		)
		(pad "1" smd rect
			(at -2.232406 -0.975106)
			(size 0.3556 1.4224)
			(layers "F.Cu" "F.Mask" "F.Paste")
			(net "SMB_BMC_SWB_EN_R")
		)
		(pad "2" smd rect
			(at -2.232406 -0.32512)
			(size 0.3556 1.4224)
			(layers "F.Cu" "F.Mask" "F.Paste")
			(net "SMB_BMC_SWB_BUF_R_SCL")
		)
		(pad "3" smd rect
			(at -2.232406 0.32512)
			(size 0.3556 1.4224)
			(layers "F.Cu" "F.Mask" "F.Paste")
			(net "SMB_BMC_SWB_R_SCL")
		)
		(pad "4" smd rect
			(at -2.232406 0.975106)
			(size 0.3556 1.4224)
			(layers "F.Cu" "F.Mask" "F.Paste")
			(net "GND")
		)
		(pad "5" smd rect
			(at 2.232406 0.975106)
			(size 0.3556 1.4224)
			(layers "F.Cu" "F.Mask" "F.Paste")
			(net "Net_10761")
		)
		(pad "6" smd rect
			(at 2.232406 0.32512)
			(size 0.3556 1.4224)
			(layers "F.Cu" "F.Mask" "F.Paste")
			(net "SMB_BMC_SWB_R_SDA")
		)
		(pad "7" smd rect
			(at 2.232406 -0.32512)
			(size 0.3556 1.4224)
			(layers "F.Cu" "F.Mask" "F.Paste")
			(net "SMB_BMC_SWB_BUF_R_SDA")
		)
		(pad "8" smd rect
			(at 2.232406 -0.975106)
			(size 0.3556 1.4224)
			(layers "F.Cu" "F.Mask" "F.Paste")
			(net "P3V3_AUX")
		)
	)
	(footprint ""
		(layer "F.Cu")
		(at 428.29353 -349.405956 90)
		(property "Reference" "PR389"
			(at 0 0 90)
			(layer "F.SilkS")
			(hide yes)
			(effects
				(font
					(size 1.27 1.27)
				)
			)
		)
		(property "Value" ""
			(at 0 0 90)
			(layer "F.Fab")
			(effects
				(font
					(size 1.27 1.27)
				)
			)
		)
		(duplicate_pad_numbers_are_jumpers no)
		(fp_line
			(start 0.7874 -0.4064)
			(end 0.7874 0.4064)
			(stroke
				(width 0.1524)
				(type default)
			)
			(layer "F.SilkS")
		)
		(fp_line
			(start -0.7874 -0.4064)
			(end 0.7874 -0.4064)
			(stroke
				(width 0.1524)
				(type default)
			)
			(layer "F.SilkS")
		)
		(fp_line
			(start 0.7874 0.4064)
			(end -0.7874 0.4064)
			(stroke
				(width 0.1524)
				(type default)
			)
			(layer "F.SilkS")
		)
		(fp_line
			(start -0.7874 0.4064)
			(end -0.7874 -0.4064)
			(stroke
				(width 0.1524)
				(type default)
			)
			(layer "F.SilkS")
		)
		(fp_line
			(start -0.12065 -0.305054)
			(end -0.12065 -0.2794)
			(stroke
				(width 0.1)
				(type default)
			)
			(layer "F.Fab")
		)
		(fp_line
			(start -0.67945 -0.305054)
			(end -0.12065 -0.305054)
			(stroke
				(width 0.1)
				(type default)
			)
			(layer "F.Fab")
		)
		(fp_line
			(start 0.67945 -0.3048)
			(end 0.67945 0.3048)
			(stroke
				(width 0.1)
				(type default)
			)
			(layer "F.Fab")
		)
		(fp_line
			(start 0.12065 -0.3048)
			(end 0.67945 -0.3048)
			(stroke
				(width 0.1)
				(type default)
			)
			(layer "F.Fab")
		)
		(fp_line
			(start 0.12065 -0.2794)
			(end 0.12065 -0.3048)
			(stroke
				(width 0.1)
				(type default)
			)
			(layer "F.Fab")
		)
		(fp_line
			(start -0.12065 -0.2794)
			(end 0.12065 -0.2794)
			(stroke
				(width 0.1)
				(type default)
			)
			(layer "F.Fab")
		)
		(fp_line
			(start 0.120396 0.2794)
			(end -0.12065 0.2794)
			(stroke
				(width 0.1)
				(type default)
			)
			(layer "F.Fab")
		)
		(fp_line
			(start -0.12065 0.2794)
			(end -0.12065 0.3048)
			(stroke
				(width 0.1)
				(type default)
			)
			(layer "F.Fab")
		)
		(fp_line
			(start 0.67945 0.3048)
			(end 0.120396 0.3048)
			(stroke
				(width 0.1)
				(type default)
			)
			(layer "F.Fab")
		)
		(fp_line
			(start 0.120396 0.3048)
			(end 0.120396 0.2794)
			(stroke
				(width 0.1)
				(type default)
			)
			(layer "F.Fab")
		)
		(fp_line
			(start -0.12065 0.3048)
			(end -0.67945 0.3048)
			(stroke
				(width 0.1)
				(type default)
			)
			(layer "F.Fab")
		)
		(fp_line
			(start -0.67945 0.3048)
			(end -0.67945 -0.305054)
			(stroke
				(width 0.1)
				(type default)
			)
			(layer "F.Fab")
		)
		(pad "1" smd circle
			(at -0.40005 0 90)
			(size 0 0)
			(layers "F.Cu" "F.Mask" "F.Paste")
			(net "SW_PVDD11_S3_P0_SW2_RC")
		)
		(pad "2" smd circle
			(at 0.40005 0 90)
			(size 0 0)
			(layers "F.Cu" "F.Mask" "F.Paste")
			(net "GND")
		)
	)
	(footprint ""
		(layer "F.Cu")
		(at 360.367072 -261.747762 -90)
		(property "Reference" "C2146"
			(at 0 0 270)
			(layer "F.SilkS")
			(hide yes)
			(effects
				(font
					(size 1.27 1.27)
				)
			)
		)
		(property "Value" ""
			(at 0 0 270)
			(layer "F.Fab")
			(effects
				(font
					(size 1.27 1.27)
				)
			)
		)
		(duplicate_pad_numbers_are_jumpers no)
		(fp_line
			(start -0.7874 0.4064)
			(end -0.7874 -0.4064)
			(stroke
				(width 0.1524)
				(type default)
			)
			(layer "F.SilkS")
		)
		(fp_line
			(start 0.7874 0.4064)
			(end -0.7874 0.4064)
			(stroke
				(width 0.1524)
				(type default)
			)
			(layer "F.SilkS")
		)
		(fp_line
			(start -0.7874 -0.4064)
			(end 0.7874 -0.4064)
			(stroke
				(width 0.1524)
				(type default)
			)
			(layer "F.SilkS")
		)
		(fp_line
			(start 0.7874 -0.4064)
			(end 0.7874 0.4064)
			(stroke
				(width 0.1524)
				(type default)
			)
			(layer "F.SilkS")
		)
		(fp_line
			(start -0.67945 0.3048)
			(end -0.67945 -0.305054)
			(stroke
				(width 0.1)
				(type default)
			)
			(layer "F.Fab")
		)
		(fp_line
			(start -0.12065 0.3048)
			(end -0.67945 0.3048)
			(stroke
				(width 0.1)
				(type default)
			)
			(layer "F.Fab")
		)
		(fp_line
			(start 0.120396 0.3048)
			(end 0.120396 0.2794)
			(stroke
				(width 0.1)
				(type default)
			)
			(layer "F.Fab")
		)
		(fp_line
			(start 0.67945 0.3048)
			(end 0.120396 0.3048)
			(stroke
				(width 0.1)
				(type default)
			)
			(layer "F.Fab")
		)
		(fp_line
			(start -0.12065 0.2794)
			(end -0.12065 0.3048)
			(stroke
				(width 0.1)
				(type default)
			)
			(layer "F.Fab")
		)
		(fp_line
			(start 0.120396 0.2794)
			(end -0.12065 0.2794)
			(stroke
				(width 0.1)
				(type default)
			)
			(layer "F.Fab")
		)
		(fp_line
			(start -0.12065 -0.2794)
			(end 0.12065 -0.2794)
			(stroke
				(width 0.1)
				(type default)
			)
			(layer "F.Fab")
		)
		(fp_line
			(start 0.12065 -0.2794)
			(end 0.12065 -0.3048)
			(stroke
				(width 0.1)
				(type default)
			)
			(layer "F.Fab")
		)
		(fp_line
			(start 0.12065 -0.3048)
			(end 0.67945 -0.3048)
			(stroke
				(width 0.1)
				(type default)
			)
			(layer "F.Fab")
		)
		(fp_line
			(start 0.67945 -0.3048)
			(end 0.67945 0.3048)
			(stroke
				(width 0.1)
				(type default)
			)
			(layer "F.Fab")
		)
		(fp_line
			(start -0.67945 -0.305054)
			(end -0.12065 -0.305054)
			(stroke
				(width 0.1)
				(type default)
			)
			(layer "F.Fab")
		)
		(fp_line
			(start -0.12065 -0.305054)
			(end -0.12065 -0.2794)
			(stroke
				(width 0.1)
				(type default)
			)
			(layer "F.Fab")
		)
		(pad "1" smd circle
			(at -0.40005 0 270)
			(size 0 0)
			(layers "F.Cu" "F.Mask" "F.Paste")
			(net "PVDD11_S3_P0")
		)
		(pad "2" smd circle
			(at 0.40005 0 270)
			(size 0 0)
			(layers "F.Cu" "F.Mask" "F.Paste")
			(net "GND")
		)
	)
	(footprint ""
		(layer "F.Cu")
		(at 252.961648 -57.209182)
		(property "Reference" "PR3952"
			(at 0 0 0)
			(layer "F.SilkS")
			(hide yes)
			(effects
				(font
					(size 1.27 1.27)
				)
			)
		)
		(property "Value" ""
			(at 0 0 0)
			(layer "F.Fab")
			(effects
				(font
					(size 1.27 1.27)
				)
			)
		)
		(duplicate_pad_numbers_are_jumpers no)
		(fp_line
			(start -0.7874 -0.4064)
			(end 0.7874 -0.4064)
			(stroke
				(width 0.1524)
				(type default)
			)
			(layer "F.SilkS")
		)
		(fp_line
			(start -0.7874 0.4064)
			(end -0.7874 -0.4064)
			(stroke
				(width 0.1524)
				(type default)
			)
			(layer "F.SilkS")
		)
		(fp_line
			(start 0.7874 -0.4064)
			(end 0.7874 0.4064)
			(stroke
				(width 0.1524)
				(type default)
			)
			(layer "F.SilkS")
		)
		(fp_line
			(start 0.7874 0.4064)
			(end -0.7874 0.4064)
			(stroke
				(width 0.1524)
				(type default)
			)
			(layer "F.SilkS")
		)
		(fp_line
			(start -0.67945 -0.305054)
			(end -0.12065 -0.305054)
			(stroke
				(width 0.1)
				(type default)
			)
			(layer "F.Fab")
		)
		(fp_line
			(start -0.67945 0.3048)
			(end -0.67945 -0.305054)
			(stroke
				(width 0.1)
				(type default)
			)
			(layer "F.Fab")
		)
		(fp_line
			(start -0.12065 -0.305054)
			(end -0.12065 -0.2794)
			(stroke
				(width 0.1)
				(type default)
			)
			(layer "F.Fab")
		)
		(fp_line
			(start -0.12065 -0.2794)
			(end 0.12065 -0.2794)
			(stroke
				(width 0.1)
				(type default)
			)
			(layer "F.Fab")
		)
		(fp_line
			(start -0.12065 0.2794)
			(end -0.12065 0.3048)
			(stroke
				(width 0.1)
				(type default)
			)
			(layer "F.Fab")
		)
		(fp_line
			(start -0.12065 0.3048)
			(end -0.67945 0.3048)
			(stroke
				(width 0.1)
				(type default)
			)
			(layer "F.Fab")
		)
		(fp_line
			(start 0.120396 0.2794)
			(end -0.12065 0.2794)
			(stroke
				(width 0.1)
				(type default)
			)
			(layer "F.Fab")
		)
		(fp_line
			(start 0.120396 0.3048)
			(end 0.120396 0.2794)
			(stroke
				(width 0.1)
				(type default)
			)
			(layer "F.Fab")
		)
		(fp_line
			(start 0.12065 -0.3048)
			(end 0.67945 -0.3048)
			(stroke
				(width 0.1)
				(type default)
			)
			(layer "F.Fab")
		)
		(fp_line
			(start 0.12065 -0.2794)
			(end 0.12065 -0.3048)
			(stroke
				(width 0.1)
				(type default)
			)
			(layer "F.Fab")
		)
		(fp_line
			(start 0.67945 -0.3048)
			(end 0.67945 0.3048)
			(stroke
				(width 0.1)
				(type default)
			)
			(layer "F.Fab")
		)
		(fp_line
			(start 0.67945 0.3048)
			(end 0.120396 0.3048)
			(stroke
				(width 0.1)
				(type default)
			)
			(layer "F.Fab")
		)
		(pad "1" smd circle
			(at -0.40005 0)
			(size 0 0)
			(layers "F.Cu" "F.Mask" "F.Paste")
			(net "P12V_E1S_0")
		)
		(pad "2" smd circle
			(at 0.40005 0)
			(size 0 0)
			(layers "F.Cu" "F.Mask" "F.Paste")
			(net "P12V_E1S_OV_FB_0")
		)
	)
	(footprint ""
		(layer "F.Cu")
		(at 172.593 -100.294948 -90)
		(property "Reference" "R6012"
			(at 0 0 270)
			(layer "F.SilkS")
			(hide yes)
			(effects
				(font
					(size 1.27 1.27)
				)
			)
		)
		(property "Value" ""
			(at 0 0 270)
			(layer "F.Fab")
			(effects
				(font
					(size 1.27 1.27)
				)
			)
		)
		(duplicate_pad_numbers_are_jumpers no)
		(fp_line
			(start -0.7874 0.4064)
			(end -0.7874 -0.4064)
			(stroke
				(width 0.1524)
				(type default)
			)
			(layer "F.SilkS")
		)
		(fp_line
			(start 0.7874 0.4064)
			(end -0.7874 0.4064)
			(stroke
				(width 0.1524)
				(type default)
			)
			(layer "F.SilkS")
		)
		(fp_line
			(start -0.7874 -0.4064)
			(end 0.7874 -0.4064)
			(stroke
				(width 0.1524)
				(type default)
			)
			(layer "F.SilkS")
		)
		(fp_line
			(start 0.7874 -0.4064)
			(end 0.7874 0.4064)
			(stroke
				(width 0.1524)
				(type default)
			)
			(layer "F.SilkS")
		)
		(fp_line
			(start -0.67945 0.3048)
			(end -0.67945 -0.305054)
			(stroke
				(width 0.1)
				(type default)
			)
			(layer "F.Fab")
		)
		(fp_line
			(start -0.12065 0.3048)
			(end -0.67945 0.3048)
			(stroke
				(width 0.1)
				(type default)
			)
			(layer "F.Fab")
		)
		(fp_line
			(start 0.120396 0.3048)
			(end 0.120396 0.2794)
			(stroke
				(width 0.1)
				(type default)
			)
			(layer "F.Fab")
		)
		(fp_line
			(start 0.67945 0.3048)
			(end 0.120396 0.3048)
			(stroke
				(width 0.1)
				(type default)
			)
			(layer "F.Fab")
		)
		(fp_line
			(start -0.12065 0.2794)
			(end -0.12065 0.3048)
			(stroke
				(width 0.1)
				(type default)
			)
			(layer "F.Fab")
		)
		(fp_line
			(start 0.120396 0.2794)
			(end -0.12065 0.2794)
			(stroke
				(width 0.1)
				(type default)
			)
			(layer "F.Fab")
		)
		(fp_line
			(start -0.12065 -0.2794)
			(end 0.12065 -0.2794)
			(stroke
				(width 0.1)
				(type default)
			)
			(layer "F.Fab")
		)
		(fp_line
			(start 0.12065 -0.2794)
			(end 0.12065 -0.3048)
			(stroke
				(width 0.1)
				(type default)
			)
			(layer "F.Fab")
		)
		(fp_line
			(start 0.12065 -0.3048)
			(end 0.67945 -0.3048)
			(stroke
				(width 0.1)
				(type default)
			)
			(layer "F.Fab")
		)
		(fp_line
			(start 0.67945 -0.3048)
			(end 0.67945 0.3048)
			(stroke
				(width 0.1)
				(type default)
			)
			(layer "F.Fab")
		)
		(fp_line
			(start -0.67945 -0.305054)
			(end -0.12065 -0.305054)
			(stroke
				(width 0.1)
				(type default)
			)
			(layer "F.Fab")
		)
		(fp_line
			(start -0.12065 -0.305054)
			(end -0.12065 -0.2794)
			(stroke
				(width 0.1)
				(type default)
			)
			(layer "F.Fab")
		)
		(pad "1" smd circle
			(at -0.40005 0 270)
			(size 0 0)
			(layers "F.Cu" "F.Mask" "F.Paste")
			(net "SGPIO_SCM_DO_<1>")
		)
		(pad "2" smd circle
			(at 0.40005 0 270)
			(size 0 0)
			(layers "F.Cu" "F.Mask" "F.Paste")
			(net "SGPIO_SCM_DO_R_<1>")
		)
	)
	(footprint ""
		(layer "F.Cu")
		(at 192.688972 -22.694392)
		(property "Reference" "PR4012"
			(at 0 0 0)
			(layer "F.SilkS")
			(hide yes)
			(effects
				(font
					(size 1.27 1.27)
				)
			)
		)
		(property "Value" ""
			(at 0 0 0)
			(layer "F.Fab")
			(effects
				(font
					(size 1.27 1.27)
				)
			)
		)
		(duplicate_pad_numbers_are_jumpers no)
		(fp_line
			(start -0.7874 -0.4064)
			(end 0.7874 -0.4064)
			(stroke
				(width 0.1524)
				(type default)
			)
			(layer "F.SilkS")
		)
		(fp_line
			(start -0.7874 0.4064)
			(end -0.7874 -0.4064)
			(stroke
				(width 0.1524)
				(type default)
			)
			(layer "F.SilkS")
		)
		(fp_line
			(start 0.7874 -0.4064)
			(end 0.7874 0.4064)
			(stroke
				(width 0.1524)
				(type default)
			)
			(layer "F.SilkS")
		)
		(fp_line
			(start 0.7874 0.4064)
			(end -0.7874 0.4064)
			(stroke
				(width 0.1524)
				(type default)
			)
			(layer "F.SilkS")
		)
		(fp_line
			(start -0.67945 -0.305054)
			(end -0.12065 -0.305054)
			(stroke
				(width 0.1)
				(type default)
			)
			(layer "F.Fab")
		)
		(fp_line
			(start -0.67945 0.3048)
			(end -0.67945 -0.305054)
			(stroke
				(width 0.1)
				(type default)
			)
			(layer "F.Fab")
		)
		(fp_line
			(start -0.12065 -0.305054)
			(end -0.12065 -0.2794)
			(stroke
				(width 0.1)
				(type default)
			)
			(layer "F.Fab")
		)
		(fp_line
			(start -0.12065 -0.2794)
			(end 0.12065 -0.2794)
			(stroke
				(width 0.1)
				(type default)
			)
			(layer "F.Fab")
		)
		(fp_line
			(start -0.12065 0.2794)
			(end -0.12065 0.3048)
			(stroke
				(width 0.1)
				(type default)
			)
			(layer "F.Fab")
		)
		(fp_line
			(start -0.12065 0.3048)
			(end -0.67945 0.3048)
			(stroke
				(width 0.1)
				(type default)
			)
			(layer "F.Fab")
		)
		(fp_line
			(start 0.120396 0.2794)
			(end -0.12065 0.2794)
			(stroke
				(width 0.1)
				(type default)
			)
			(layer "F.Fab")
		)
		(fp_line
			(start 0.120396 0.3048)
			(end 0.120396 0.2794)
			(stroke
				(width 0.1)
				(type default)
			)
			(layer "F.Fab")
		)
		(fp_line
			(start 0.12065 -0.3048)
			(end 0.67945 -0.3048)
			(stroke
				(width 0.1)
				(type default)
			)
			(layer "F.Fab")
		)
		(fp_line
			(start 0.12065 -0.2794)
			(end 0.12065 -0.3048)
			(stroke
				(width 0.1)
				(type default)
			)
			(layer "F.Fab")
		)
		(fp_line
			(start 0.67945 -0.3048)
			(end 0.67945 0.3048)
			(stroke
				(width 0.1)
				(type default)
			)
			(layer "F.Fab")
		)
		(fp_line
			(start 0.67945 0.3048)
			(end 0.120396 0.3048)
			(stroke
				(width 0.1)
				(type default)
			)
			(layer "F.Fab")
		)
		(pad "1" smd circle
			(at -0.40005 0)
			(size 0 0)
			(layers "F.Cu" "F.Mask" "F.Paste")
			(net "P12V_SCM_PWRGD")
		)
		(pad "2" smd circle
			(at 0.40005 0)
			(size 0 0)
			(layers "F.Cu" "F.Mask" "F.Paste")
			(net "HP_LVC3_SCM_HSC_PWRGD")
		)
	)
	(footprint ""
		(layer "F.Cu")
		(at 123.127516 -54.775608 90)
		(property "Reference" "U146"
			(at 0.67818 -2.174748 90)
			(unlocked yes)
			(layer "F.SilkS")
			(effects
				(font
					(size 0.7874 0.5842)
					(thickness 0.1524)
				)
				(justify left)
			)
		)
		(property "Value" ""
			(at 0 0 90)
			(layer "F.Fab")
			(effects
				(font
					(size 1.27 1.27)
				)
			)
		)
		(duplicate_pad_numbers_are_jumpers no)
		(fp_line
			(start 1.245616 -1.445768)
			(end 1.245616 1.445768)
			(stroke
				(width 0.1524)
				(type default)
			)
			(layer "F.SilkS")
		)
		(fp_line
			(start -1.245616 -1.445768)
			(end 1.245616 -1.445768)
			(stroke
				(width 0.1524)
				(type default)
			)
			(layer "F.SilkS")
		)
		(fp_line
			(start 1.245616 1.445768)
			(end -1.245616 1.445768)
			(stroke
				(width 0.1524)
				(type default)
			)
			(layer "F.SilkS")
		)
		(fp_line
			(start -1.245616 1.445768)
			(end -1.245616 -1.445768)
			(stroke
				(width 0.1524)
				(type default)
			)
			(layer "F.SilkS")
		)
		(fp_poly
			(pts
				(xy -1.371346 -0.199136) (xy -1.879346 0.054864) (xy -1.879346 -0.453136)
			)
			(stroke
				(width 0)
				(type default)
			)
			(fill yes)
			(layer "F.SilkS")
		)
		(fp_line
			(start 0.724916 -0.925068)
			(end 0.724916 0.925068)
			(stroke
				(width 0.1)
				(type default)
			)
			(layer "F.Fab")
		)
		(fp_line
			(start -0.724916 -0.925068)
			(end 0.724916 -0.925068)
			(stroke
				(width 0.1)
				(type default)
			)
			(layer "F.Fab")
		)
		(fp_line
			(start 0.724916 0.925068)
			(end -0.724916 0.925068)
			(stroke
				(width 0.1)
				(type default)
			)
			(layer "F.Fab")
		)
		(fp_line
			(start -0.724916 0.925068)
			(end -0.724916 -0.925068)
			(stroke
				(width 0.1)
				(type default)
			)
			(layer "F.Fab")
		)
		(fp_poly
			(pts
				(xy -1.894586 -0.453898) (xy -1.894586 0.054102) (xy -1.386586 -0.199898)
			)
			(stroke
				(width 0)
				(type default)
			)
			(fill yes)
			(layer "F.Fab")
		)
		(pad "1" smd circle
			(at -0.649986 -0.199898)
			(size 0 0)
			(layers "F.Cu" "F.Mask" "F.Paste")
			(net "GND")
		)
		(pad "2" smd rect
			(at -0.700024 0.199898 180)
			(size 0.1778 0.8128)
			(layers "F.Cu" "F.Mask" "F.Paste")
			(net "JTAG_BMC_R_D_OE")
		)
		(pad "3" smd rect
			(at -0.40005 0.899922 90)
			(size 0.1778 0.8128)
			(layers "F.Cu" "F.Mask" "F.Paste")
			(net "GND")
		)
		(pad "4" smd rect
			(at 0 0.899922 90)
			(size 0.1778 0.8128)
			(layers "F.Cu" "F.Mask" "F.Paste")
			(net "JTAG_TDO_R1")
		)
		(pad "5" smd rect
			(at 0.40005 0.899922 90)
			(size 0.1778 0.8128)
			(layers "F.Cu" "F.Mask" "F.Paste")
			(net "JTAG_TDI_R")
		)
		(pad "6" smd rect
			(at 0.700024 0.199898)
			(size 0.1778 0.8128)
			(layers "F.Cu" "F.Mask" "F.Paste")
			(net "PVDD18_S5_P0")
		)
		(pad "7" smd rect
			(at 0.700024 -0.199898)
			(size 0.1778 0.8128)
			(layers "F.Cu" "F.Mask" "F.Paste")
			(net "PVDD18_S5_P0")
		)
		(pad "8" smd rect
			(at 0.40005 -0.899922 90)
			(size 0.1778 0.8128)
			(layers "F.Cu" "F.Mask" "F.Paste")
			(net "HDT_HDR_TDI")
		)
		(pad "9" smd rect
			(at 0 -0.899922 90)
			(size 0.1778 0.8128)
			(layers "F.Cu" "F.Mask" "F.Paste")
			(net "HDT_HDR_TDO_R")
		)
		(pad "10" smd rect
			(at -0.40005 -0.912622 90)
			(size 0.1778 0.7874)
			(layers "F.Cu" "F.Mask" "F.Paste")
			(net "PVDD18_S5_P0")
		)
	)
	(footprint ""
		(layer "F.Cu")
		(at 428.813722 -423.621708 90)
		(property "Reference" "R6251"
			(at 0 0 90)
			(layer "F.SilkS")
			(hide yes)
			(effects
				(font
					(size 1.27 1.27)
				)
			)
		)
		(property "Value" ""
			(at 0 0 90)
			(layer "F.Fab")
			(effects
				(font
					(size 1.27 1.27)
				)
			)
		)
		(duplicate_pad_numbers_are_jumpers no)
		(fp_line
			(start 0.7874 -0.4064)
			(end 0.7874 0.4064)
			(stroke
				(width 0.1524)
				(type default)
			)
			(layer "F.SilkS")
		)
		(fp_line
			(start -0.7874 -0.4064)
			(end 0.7874 -0.4064)
			(stroke
				(width 0.1524)
				(type default)
			)
			(layer "F.SilkS")
		)
		(fp_line
			(start 0.7874 0.4064)
			(end -0.7874 0.4064)
			(stroke
				(width 0.1524)
				(type default)
			)
			(layer "F.SilkS")
		)
		(fp_line
			(start -0.7874 0.4064)
			(end -0.7874 -0.4064)
			(stroke
				(width 0.1524)
				(type default)
			)
			(layer "F.SilkS")
		)
		(fp_line
			(start -0.12065 -0.305054)
			(end -0.12065 -0.2794)
			(stroke
				(width 0.1)
				(type default)
			)
			(layer "F.Fab")
		)
		(fp_line
			(start -0.67945 -0.305054)
			(end -0.12065 -0.305054)
			(stroke
				(width 0.1)
				(type default)
			)
			(layer "F.Fab")
		)
		(fp_line
			(start 0.67945 -0.3048)
			(end 0.67945 0.3048)
			(stroke
				(width 0.1)
				(type default)
			)
			(layer "F.Fab")
		)
		(fp_line
			(start 0.12065 -0.3048)
			(end 0.67945 -0.3048)
			(stroke
				(width 0.1)
				(type default)
			)
			(layer "F.Fab")
		)
		(fp_line
			(start 0.12065 -0.2794)
			(end 0.12065 -0.3048)
			(stroke
				(width 0.1)
				(type default)
			)
			(layer "F.Fab")
		)
		(fp_line
			(start -0.12065 -0.2794)
			(end 0.12065 -0.2794)
			(stroke
				(width 0.1)
				(type default)
			)
			(layer "F.Fab")
		)
		(fp_line
			(start 0.120396 0.2794)
			(end -0.12065 0.2794)
			(stroke
				(width 0.1)
				(type default)
			)
			(layer "F.Fab")
		)
		(fp_line
			(start -0.12065 0.2794)
			(end -0.12065 0.3048)
			(stroke
				(width 0.1)
				(type default)
			)
			(layer "F.Fab")
		)
		(fp_line
			(start 0.67945 0.3048)
			(end 0.120396 0.3048)
			(stroke
				(width 0.1)
				(type default)
			)
			(layer "F.Fab")
		)
		(fp_line
			(start 0.120396 0.3048)
			(end 0.120396 0.2794)
			(stroke
				(width 0.1)
				(type default)
			)
			(layer "F.Fab")
		)
		(fp_line
			(start -0.12065 0.3048)
			(end -0.67945 0.3048)
			(stroke
				(width 0.1)
				(type default)
			)
			(layer "F.Fab")
		)
		(fp_line
			(start -0.67945 0.3048)
			(end -0.67945 -0.305054)
			(stroke
				(width 0.1)
				(type default)
			)
			(layer "F.Fab")
		)
		(pad "1" smd circle
			(at -0.40005 0 90)
			(size 0 0)
			(layers "F.Cu" "F.Mask" "F.Paste")
			(net "GND")
		)
		(pad "2" smd circle
			(at 0.40005 0 90)
			(size 0 0)
			(layers "F.Cu" "F.Mask" "F.Paste")
			(net "HSC_TYPE_ADC_A0")
		)
	)
	(footprint ""
		(layer "F.Cu")
		(at 271.093184 -116.321586)
		(property "Reference" "R3731"
			(at 0 0 0)
			(layer "F.SilkS")
			(hide yes)
			(effects
				(font
					(size 1.27 1.27)
				)
			)
		)
		(property "Value" ""
			(at 0 0 0)
			(layer "F.Fab")
			(effects
				(font
					(size 1.27 1.27)
				)
			)
		)
		(duplicate_pad_numbers_are_jumpers no)
		(fp_line
			(start -0.7874 -0.4064)
			(end 0.7874 -0.4064)
			(stroke
				(width 0.1524)
				(type default)
			)
			(layer "F.SilkS")
		)
		(fp_line
			(start -0.7874 0.4064)
			(end -0.7874 -0.4064)
			(stroke
				(width 0.1524)
				(type default)
			)
			(layer "F.SilkS")
		)
		(fp_line
			(start 0.7874 -0.4064)
			(end 0.7874 0.4064)
			(stroke
				(width 0.1524)
				(type default)
			)
			(layer "F.SilkS")
		)
		(fp_line
			(start 0.7874 0.4064)
			(end -0.7874 0.4064)
			(stroke
				(width 0.1524)
				(type default)
			)
			(layer "F.SilkS")
		)
		(fp_line
			(start -0.67945 -0.305054)
			(end -0.12065 -0.305054)
			(stroke
				(width 0.1)
				(type default)
			)
			(layer "F.Fab")
		)
		(fp_line
			(start -0.67945 0.3048)
			(end -0.67945 -0.305054)
			(stroke
				(width 0.1)
				(type default)
			)
			(layer "F.Fab")
		)
		(fp_line
			(start -0.12065 -0.305054)
			(end -0.12065 -0.2794)
			(stroke
				(width 0.1)
				(type default)
			)
			(layer "F.Fab")
		)
		(fp_line
			(start -0.12065 -0.2794)
			(end 0.12065 -0.2794)
			(stroke
				(width 0.1)
				(type default)
			)
			(layer "F.Fab")
		)
		(fp_line
			(start -0.12065 0.2794)
			(end -0.12065 0.3048)
			(stroke
				(width 0.1)
				(type default)
			)
			(layer "F.Fab")
		)
		(fp_line
			(start -0.12065 0.3048)
			(end -0.67945 0.3048)
			(stroke
				(width 0.1)
				(type default)
			)
			(layer "F.Fab")
		)
		(fp_line
			(start 0.120396 0.2794)
			(end -0.12065 0.2794)
			(stroke
				(width 0.1)
				(type default)
			)
			(layer "F.Fab")
		)
		(fp_line
			(start 0.120396 0.3048)
			(end 0.120396 0.2794)
			(stroke
				(width 0.1)
				(type default)
			)
			(layer "F.Fab")
		)
		(fp_line
			(start 0.12065 -0.3048)
			(end 0.67945 -0.3048)
			(stroke
				(width 0.1)
				(type default)
			)
			(layer "F.Fab")
		)
		(fp_line
			(start 0.12065 -0.2794)
			(end 0.12065 -0.3048)
			(stroke
				(width 0.1)
				(type default)
			)
			(layer "F.Fab")
		)
		(fp_line
			(start 0.67945 -0.3048)
			(end 0.67945 0.3048)
			(stroke
				(width 0.1)
				(type default)
			)
			(layer "F.Fab")
		)
		(fp_line
			(start 0.67945 0.3048)
			(end 0.120396 0.3048)
			(stroke
				(width 0.1)
				(type default)
			)
			(layer "F.Fab")
		)
		(pad "1" smd circle
			(at -0.40005 0)
			(size 0 0)
			(layers "F.Cu" "F.Mask" "F.Paste")
			(net "P3V3_AUX")
		)
		(pad "2" smd circle
			(at 0.40005 0)
			(size 0 0)
			(layers "F.Cu" "F.Mask" "F.Paste")
			(net "SMB_LM75_3_3V3AUX_SCL")
		)
	)
	(footprint ""
		(layer "F.Cu")
		(at 118.718584 -62.932056)
		(property "Reference" "R1747"
			(at 0 0 0)
			(layer "F.SilkS")
			(hide yes)
			(effects
				(font
					(size 1.27 1.27)
				)
			)
		)
		(property "Value" ""
			(at 0 0 0)
			(layer "F.Fab")
			(effects
				(font
					(size 1.27 1.27)
				)
			)
		)
		(duplicate_pad_numbers_are_jumpers no)
		(fp_line
			(start -0.7874 -0.4064)
			(end 0.7874 -0.4064)
			(stroke
				(width 0.1524)
				(type default)
			)
			(layer "F.SilkS")
		)
		(fp_line
			(start -0.7874 0.4064)
			(end -0.7874 -0.4064)
			(stroke
				(width 0.1524)
				(type default)
			)
			(layer "F.SilkS")
		)
		(fp_line
			(start 0.7874 -0.4064)
			(end 0.7874 0.4064)
			(stroke
				(width 0.1524)
				(type default)
			)
			(layer "F.SilkS")
		)
		(fp_line
			(start 0.7874 0.4064)
			(end -0.7874 0.4064)
			(stroke
				(width 0.1524)
				(type default)
			)
			(layer "F.SilkS")
		)
		(fp_line
			(start -0.67945 -0.305054)
			(end -0.12065 -0.305054)
			(stroke
				(width 0.1)
				(type default)
			)
			(layer "F.Fab")
		)
		(fp_line
			(start -0.67945 0.3048)
			(end -0.67945 -0.305054)
			(stroke
				(width 0.1)
				(type default)
			)
			(layer "F.Fab")
		)
		(fp_line
			(start -0.12065 -0.305054)
			(end -0.12065 -0.2794)
			(stroke
				(width 0.1)
				(type default)
			)
			(layer "F.Fab")
		)
		(fp_line
			(start -0.12065 -0.2794)
			(end 0.12065 -0.2794)
			(stroke
				(width 0.1)
				(type default)
			)
			(layer "F.Fab")
		)
		(fp_line
			(start -0.12065 0.2794)
			(end -0.12065 0.3048)
			(stroke
				(width 0.1)
				(type default)
			)
			(layer "F.Fab")
		)
		(fp_line
			(start -0.12065 0.3048)
			(end -0.67945 0.3048)
			(stroke
				(width 0.1)
				(type default)
			)
			(layer "F.Fab")
		)
		(fp_line
			(start 0.120396 0.2794)
			(end -0.12065 0.2794)
			(stroke
				(width 0.1)
				(type default)
			)
			(layer "F.Fab")
		)
		(fp_line
			(start 0.120396 0.3048)
			(end 0.120396 0.2794)
			(stroke
				(width 0.1)
				(type default)
			)
			(layer "F.Fab")
		)
		(fp_line
			(start 0.12065 -0.3048)
			(end 0.67945 -0.3048)
			(stroke
				(width 0.1)
				(type default)
			)
			(layer "F.Fab")
		)
		(fp_line
			(start 0.12065 -0.2794)
			(end 0.12065 -0.3048)
			(stroke
				(width 0.1)
				(type default)
			)
			(layer "F.Fab")
		)
		(fp_line
			(start 0.67945 -0.3048)
			(end 0.67945 0.3048)
			(stroke
				(width 0.1)
				(type default)
			)
			(layer "F.Fab")
		)
		(fp_line
			(start 0.67945 0.3048)
			(end 0.120396 0.3048)
			(stroke
				(width 0.1)
				(type default)
			)
			(layer "F.Fab")
		)
		(pad "1" smd circle
			(at -0.40005 0)
			(size 0 0)
			(layers "F.Cu" "F.Mask" "F.Paste")
			(net "P3V3_AUX")
		)
		(pad "2" smd circle
			(at 0.40005 0)
			(size 0 0)
			(layers "F.Cu" "F.Mask" "F.Paste")
			(net "JTAG_SCM_MUX_TCK")
		)
	)
	(footprint ""
		(layer "F.Cu")
		(at 283.464 -423.418 90)
		(property "Reference" "R4492"
			(at 0 0 90)
			(layer "F.SilkS")
			(hide yes)
			(effects
				(font
					(size 1.27 1.27)
				)
			)
		)
		(property "Value" ""
			(at 0 0 90)
			(layer "F.Fab")
			(effects
				(font
					(size 1.27 1.27)
				)
			)
		)
		(duplicate_pad_numbers_are_jumpers no)
		(fp_line
			(start 0.7874 -0.4064)
			(end 0.7874 0.4064)
			(stroke
				(width 0.1524)
				(type default)
			)
			(layer "F.SilkS")
		)
		(fp_line
			(start -0.7874 -0.4064)
			(end 0.7874 -0.4064)
			(stroke
				(width 0.1524)
				(type default)
			)
			(layer "F.SilkS")
		)
		(fp_line
			(start 0.7874 0.4064)
			(end -0.7874 0.4064)
			(stroke
				(width 0.1524)
				(type default)
			)
			(layer "F.SilkS")
		)
		(fp_line
			(start -0.7874 0.4064)
			(end -0.7874 -0.4064)
			(stroke
				(width 0.1524)
				(type default)
			)
			(layer "F.SilkS")
		)
		(fp_line
			(start -0.12065 -0.305054)
			(end -0.12065 -0.2794)
			(stroke
				(width 0.1)
				(type default)
			)
			(layer "F.Fab")
		)
		(fp_line
			(start -0.67945 -0.305054)
			(end -0.12065 -0.305054)
			(stroke
				(width 0.1)
				(type default)
			)
			(layer "F.Fab")
		)
		(fp_line
			(start 0.67945 -0.3048)
			(end 0.67945 0.3048)
			(stroke
				(width 0.1)
				(type default)
			)
			(layer "F.Fab")
		)
		(fp_line
			(start 0.12065 -0.3048)
			(end 0.67945 -0.3048)
			(stroke
				(width 0.1)
				(type default)
			)
			(layer "F.Fab")
		)
		(fp_line
			(start 0.12065 -0.2794)
			(end 0.12065 -0.3048)
			(stroke
				(width 0.1)
				(type default)
			)
			(layer "F.Fab")
		)
		(fp_line
			(start -0.12065 -0.2794)
			(end 0.12065 -0.2794)
			(stroke
				(width 0.1)
				(type default)
			)
			(layer "F.Fab")
		)
		(fp_line
			(start 0.120396 0.2794)
			(end -0.12065 0.2794)
			(stroke
				(width 0.1)
				(type default)
			)
			(layer "F.Fab")
		)
		(fp_line
			(start -0.12065 0.2794)
			(end -0.12065 0.3048)
			(stroke
				(width 0.1)
				(type default)
			)
			(layer "F.Fab")
		)
		(fp_line
			(start 0.67945 0.3048)
			(end 0.120396 0.3048)
			(stroke
				(width 0.1)
				(type default)
			)
			(layer "F.Fab")
		)
		(fp_line
			(start 0.120396 0.3048)
			(end 0.120396 0.2794)
			(stroke
				(width 0.1)
				(type default)
			)
			(layer "F.Fab")
		)
		(fp_line
			(start -0.12065 0.3048)
			(end -0.67945 0.3048)
			(stroke
				(width 0.1)
				(type default)
			)
			(layer "F.Fab")
		)
		(fp_line
			(start -0.67945 0.3048)
			(end -0.67945 -0.305054)
			(stroke
				(width 0.1)
				(type default)
			)
			(layer "F.Fab")
		)
		(pad "1" smd circle
			(at -0.40005 0 90)
			(size 0 0)
			(layers "F.Cu" "F.Mask" "F.Paste")
			(net "CLK_9ZXL045_P0_HIBW")
		)
		(pad "2" smd circle
			(at 0.40005 0 90)
			(size 0 0)
			(layers "F.Cu" "F.Mask" "F.Paste")
			(net "GND")
		)
	)
	(footprint ""
		(layer "F.Cu")
		(at 319.940178 -44.716954)
		(property "Reference" "C33"
			(at 0 0 0)
			(layer "F.SilkS")
			(hide yes)
			(effects
				(font
					(size 1.27 1.27)
				)
			)
		)
		(property "Value" ""
			(at 0 0 0)
			(layer "F.Fab")
			(effects
				(font
					(size 1.27 1.27)
				)
			)
		)
		(duplicate_pad_numbers_are_jumpers no)
		(fp_line
			(start -0.7874 -0.4064)
			(end 0.7874 -0.4064)
			(stroke
				(width 0.1524)
				(type default)
			)
			(layer "F.SilkS")
		)
		(fp_line
			(start -0.7874 0.4064)
			(end -0.7874 -0.4064)
			(stroke
				(width 0.1524)
				(type default)
			)
			(layer "F.SilkS")
		)
		(fp_line
			(start 0.7874 -0.4064)
			(end 0.7874 0.4064)
			(stroke
				(width 0.1524)
				(type default)
			)
			(layer "F.SilkS")
		)
		(fp_line
			(start 0.7874 0.4064)
			(end -0.7874 0.4064)
			(stroke
				(width 0.1524)
				(type default)
			)
			(layer "F.SilkS")
		)
		(fp_line
			(start -0.67945 -0.305054)
			(end -0.12065 -0.305054)
			(stroke
				(width 0.1)
				(type default)
			)
			(layer "F.Fab")
		)
		(fp_line
			(start -0.67945 0.3048)
			(end -0.67945 -0.305054)
			(stroke
				(width 0.1)
				(type default)
			)
			(layer "F.Fab")
		)
		(fp_line
			(start -0.12065 -0.305054)
			(end -0.12065 -0.2794)
			(stroke
				(width 0.1)
				(type default)
			)
			(layer "F.Fab")
		)
		(fp_line
			(start -0.12065 -0.2794)
			(end 0.12065 -0.2794)
			(stroke
				(width 0.1)
				(type default)
			)
			(layer "F.Fab")
		)
		(fp_line
			(start -0.12065 0.2794)
			(end -0.12065 0.3048)
			(stroke
				(width 0.1)
				(type default)
			)
			(layer "F.Fab")
		)
		(fp_line
			(start -0.12065 0.3048)
			(end -0.67945 0.3048)
			(stroke
				(width 0.1)
				(type default)
			)
			(layer "F.Fab")
		)
		(fp_line
			(start 0.120396 0.2794)
			(end -0.12065 0.2794)
			(stroke
				(width 0.1)
				(type default)
			)
			(layer "F.Fab")
		)
		(fp_line
			(start 0.120396 0.3048)
			(end 0.120396 0.2794)
			(stroke
				(width 0.1)
				(type default)
			)
			(layer "F.Fab")
		)
		(fp_line
			(start 0.12065 -0.3048)
			(end 0.67945 -0.3048)
			(stroke
				(width 0.1)
				(type default)
			)
			(layer "F.Fab")
		)
		(fp_line
			(start 0.12065 -0.2794)
			(end 0.12065 -0.3048)
			(stroke
				(width 0.1)
				(type default)
			)
			(layer "F.Fab")
		)
		(fp_line
			(start 0.67945 -0.3048)
			(end 0.67945 0.3048)
			(stroke
				(width 0.1)
				(type default)
			)
			(layer "F.Fab")
		)
		(fp_line
			(start 0.67945 0.3048)
			(end 0.120396 0.3048)
			(stroke
				(width 0.1)
				(type default)
			)
			(layer "F.Fab")
		)
		(pad "1" smd circle
			(at -0.40005 0)
			(size 0 0)
			(layers "F.Cu" "F.Mask" "F.Paste")
			(net "P12V_OCP_V3_2_ISENSE_TIC")
		)
		(pad "2" smd circle
			(at 0.40005 0)
			(size 0 0)
			(layers "F.Cu" "F.Mask" "F.Paste")
			(net "GND")
		)
	)
	(footprint ""
		(layer "F.Cu")
		(at 167.527986 -352.26371 90)
		(property "Reference" "PC645"
			(at 0 0 90)
			(layer "F.SilkS")
			(hide yes)
			(effects
				(font
					(size 1.27 1.27)
				)
			)
		)
		(property "Value" ""
			(at 0 0 90)
			(layer "F.Fab")
			(effects
				(font
					(size 1.27 1.27)
				)
			)
		)
		(duplicate_pad_numbers_are_jumpers no)
		(fp_line
			(start 0.7874 -0.4064)
			(end 0.7874 0.4064)
			(stroke
				(width 0.1524)
				(type default)
			)
			(layer "F.SilkS")
		)
		(fp_line
			(start -0.7874 -0.4064)
			(end 0.7874 -0.4064)
			(stroke
				(width 0.1524)
				(type default)
			)
			(layer "F.SilkS")
		)
		(fp_line
			(start 0.7874 0.4064)
			(end -0.7874 0.4064)
			(stroke
				(width 0.1524)
				(type default)
			)
			(layer "F.SilkS")
		)
		(fp_line
			(start -0.7874 0.4064)
			(end -0.7874 -0.4064)
			(stroke
				(width 0.1524)
				(type default)
			)
			(layer "F.SilkS")
		)
		(fp_line
			(start -0.12065 -0.305054)
			(end -0.12065 -0.2794)
			(stroke
				(width 0.1)
				(type default)
			)
			(layer "F.Fab")
		)
		(fp_line
			(start -0.67945 -0.305054)
			(end -0.12065 -0.305054)
			(stroke
				(width 0.1)
				(type default)
			)
			(layer "F.Fab")
		)
		(fp_line
			(start 0.67945 -0.3048)
			(end 0.67945 0.3048)
			(stroke
				(width 0.1)
				(type default)
			)
			(layer "F.Fab")
		)
		(fp_line
			(start 0.12065 -0.3048)
			(end 0.67945 -0.3048)
			(stroke
				(width 0.1)
				(type default)
			)
			(layer "F.Fab")
		)
		(fp_line
			(start 0.12065 -0.2794)
			(end 0.12065 -0.3048)
			(stroke
				(width 0.1)
				(type default)
			)
			(layer "F.Fab")
		)
		(fp_line
			(start -0.12065 -0.2794)
			(end 0.12065 -0.2794)
			(stroke
				(width 0.1)
				(type default)
			)
			(layer "F.Fab")
		)
		(fp_line
			(start 0.120396 0.2794)
			(end -0.12065 0.2794)
			(stroke
				(width 0.1)
				(type default)
			)
			(layer "F.Fab")
		)
		(fp_line
			(start -0.12065 0.2794)
			(end -0.12065 0.3048)
			(stroke
				(width 0.1)
				(type default)
			)
			(layer "F.Fab")
		)
		(fp_line
			(start 0.67945 0.3048)
			(end 0.120396 0.3048)
			(stroke
				(width 0.1)
				(type default)
			)
			(layer "F.Fab")
		)
		(fp_line
			(start 0.120396 0.3048)
			(end 0.120396 0.2794)
			(stroke
				(width 0.1)
				(type default)
			)
			(layer "F.Fab")
		)
		(fp_line
			(start -0.12065 0.3048)
			(end -0.67945 0.3048)
			(stroke
				(width 0.1)
				(type default)
			)
			(layer "F.Fab")
		)
		(fp_line
			(start -0.67945 0.3048)
			(end -0.67945 -0.305054)
			(stroke
				(width 0.1)
				(type default)
			)
			(layer "F.Fab")
		)
		(pad "1" smd circle
			(at -0.40005 0 90)
			(size 0 0)
			(layers "F.Cu" "F.Mask" "F.Paste")
			(net "PVDD11_S3_P1_VCC")
		)
		(pad "2" smd circle
			(at 0.40005 0 90)
			(size 0 0)
			(layers "F.Cu" "F.Mask" "F.Paste")
			(net "GND")
		)
	)
	(footprint ""
		(layer "F.Cu")
		(at 117.895624 -256.505456 180)
		(property "Reference" "C2290"
			(at 0 0 180)
			(layer "F.SilkS")
			(hide yes)
			(effects
				(font
					(size 1.27 1.27)
				)
			)
		)
		(property "Value" ""
			(at 0 0 180)
			(layer "F.Fab")
			(effects
				(font
					(size 1.27 1.27)
				)
			)
		)
		(duplicate_pad_numbers_are_jumpers no)
		(fp_line
			(start 0.7874 0.4064)
			(end -0.7874 0.4064)
			(stroke
				(width 0.1524)
				(type default)
			)
			(layer "F.SilkS")
		)
		(fp_line
			(start 0.7874 -0.4064)
			(end 0.7874 0.4064)
			(stroke
				(width 0.1524)
				(type default)
			)
			(layer "F.SilkS")
		)
		(fp_line
			(start -0.7874 0.4064)
			(end -0.7874 -0.4064)
			(stroke
				(width 0.1524)
				(type default)
			)
			(layer "F.SilkS")
		)
		(fp_line
			(start -0.7874 -0.4064)
			(end 0.7874 -0.4064)
			(stroke
				(width 0.1524)
				(type default)
			)
			(layer "F.SilkS")
		)
		(fp_line
			(start 0.67945 0.3048)
			(end 0.120396 0.3048)
			(stroke
				(width 0.1)
				(type default)
			)
			(layer "F.Fab")
		)
		(fp_line
			(start 0.67945 -0.3048)
			(end 0.67945 0.3048)
			(stroke
				(width 0.1)
				(type default)
			)
			(layer "F.Fab")
		)
		(fp_line
			(start 0.12065 -0.2794)
			(end 0.12065 -0.3048)
			(stroke
				(width 0.1)
				(type default)
			)
			(layer "F.Fab")
		)
		(fp_line
			(start 0.12065 -0.3048)
			(end 0.67945 -0.3048)
			(stroke
				(width 0.1)
				(type default)
			)
			(layer "F.Fab")
		)
		(fp_line
			(start 0.120396 0.3048)
			(end 0.120396 0.2794)
			(stroke
				(width 0.1)
				(type default)
			)
			(layer "F.Fab")
		)
		(fp_line
			(start 0.120396 0.2794)
			(end -0.12065 0.2794)
			(stroke
				(width 0.1)
				(type default)
			)
			(layer "F.Fab")
		)
		(fp_line
			(start -0.12065 0.3048)
			(end -0.67945 0.3048)
			(stroke
				(width 0.1)
				(type default)
			)
			(layer "F.Fab")
		)
		(fp_line
			(start -0.12065 0.2794)
			(end -0.12065 0.3048)
			(stroke
				(width 0.1)
				(type default)
			)
			(layer "F.Fab")
		)
		(fp_line
			(start -0.12065 -0.2794)
			(end 0.12065 -0.2794)
			(stroke
				(width 0.1)
				(type default)
			)
			(layer "F.Fab")
		)
		(fp_line
			(start -0.12065 -0.305054)
			(end -0.12065 -0.2794)
			(stroke
				(width 0.1)
				(type default)
			)
			(layer "F.Fab")
		)
		(fp_line
			(start -0.67945 0.3048)
			(end -0.67945 -0.305054)
			(stroke
				(width 0.1)
				(type default)
			)
			(layer "F.Fab")
		)
		(fp_line
			(start -0.67945 -0.305054)
			(end -0.12065 -0.305054)
			(stroke
				(width 0.1)
				(type default)
			)
			(layer "F.Fab")
		)
		(pad "1" smd circle
			(at -0.40005 0 180)
			(size 0 0)
			(layers "F.Cu" "F.Mask" "F.Paste")
			(net "PVDDCR_SOC_P1")
		)
		(pad "2" smd circle
			(at 0.40005 0 180)
			(size 0 0)
			(layers "F.Cu" "F.Mask" "F.Paste")
			(net "GND")
		)
	)
	(footprint ""
		(layer "F.Cu")
		(at 131.699 -109.474 -90)
		(property "Reference" "C8018"
			(at 0 0 270)
			(layer "F.SilkS")
			(hide yes)
			(effects
				(font
					(size 1.27 1.27)
				)
			)
		)
		(property "Value" ""
			(at 0 0 270)
			(layer "F.Fab")
			(effects
				(font
					(size 1.27 1.27)
				)
			)
		)
		(duplicate_pad_numbers_are_jumpers no)
		(fp_line
			(start -0.7874 0.4064)
			(end -0.7874 -0.4064)
			(stroke
				(width 0.1524)
				(type default)
			)
			(layer "F.SilkS")
		)
		(fp_line
			(start 0.7874 0.4064)
			(end -0.7874 0.4064)
			(stroke
				(width 0.1524)
				(type default)
			)
			(layer "F.SilkS")
		)
		(fp_line
			(start -0.7874 -0.4064)
			(end 0.7874 -0.4064)
			(stroke
				(width 0.1524)
				(type default)
			)
			(layer "F.SilkS")
		)
		(fp_line
			(start 0.7874 -0.4064)
			(end 0.7874 0.4064)
			(stroke
				(width 0.1524)
				(type default)
			)
			(layer "F.SilkS")
		)
		(fp_line
			(start -0.67945 0.3048)
			(end -0.67945 -0.305054)
			(stroke
				(width 0.1)
				(type default)
			)
			(layer "F.Fab")
		)
		(fp_line
			(start -0.12065 0.3048)
			(end -0.67945 0.3048)
			(stroke
				(width 0.1)
				(type default)
			)
			(layer "F.Fab")
		)
		(fp_line
			(start 0.120396 0.3048)
			(end 0.120396 0.2794)
			(stroke
				(width 0.1)
				(type default)
			)
			(layer "F.Fab")
		)
		(fp_line
			(start 0.67945 0.3048)
			(end 0.120396 0.3048)
			(stroke
				(width 0.1)
				(type default)
			)
			(layer "F.Fab")
		)
		(fp_line
			(start -0.12065 0.2794)
			(end -0.12065 0.3048)
			(stroke
				(width 0.1)
				(type default)
			)
			(layer "F.Fab")
		)
		(fp_line
			(start 0.120396 0.2794)
			(end -0.12065 0.2794)
			(stroke
				(width 0.1)
				(type default)
			)
			(layer "F.Fab")
		)
		(fp_line
			(start -0.12065 -0.2794)
			(end 0.12065 -0.2794)
			(stroke
				(width 0.1)
				(type default)
			)
			(layer "F.Fab")
		)
		(fp_line
			(start 0.12065 -0.2794)
			(end 0.12065 -0.3048)
			(stroke
				(width 0.1)
				(type default)
			)
			(layer "F.Fab")
		)
		(fp_line
			(start 0.12065 -0.3048)
			(end 0.67945 -0.3048)
			(stroke
				(width 0.1)
				(type default)
			)
			(layer "F.Fab")
		)
		(fp_line
			(start 0.67945 -0.3048)
			(end 0.67945 0.3048)
			(stroke
				(width 0.1)
				(type default)
			)
			(layer "F.Fab")
		)
		(fp_line
			(start -0.67945 -0.305054)
			(end -0.12065 -0.305054)
			(stroke
				(width 0.1)
				(type default)
			)
			(layer "F.Fab")
		)
		(fp_line
			(start -0.12065 -0.305054)
			(end -0.12065 -0.2794)
			(stroke
				(width 0.1)
				(type default)
			)
			(layer "F.Fab")
		)
		(pad "1" smd circle
			(at -0.40005 0 270)
			(size 0 0)
			(layers "F.Cu" "F.Mask" "F.Paste")
			(net "P12V_AUX_UV_ADR_TRIGGER")
		)
		(pad "2" smd circle
			(at 0.40005 0 270)
			(size 0 0)
			(layers "F.Cu" "F.Mask" "F.Paste")
			(net "GND")
		)
	)
	(footprint ""
		(layer "F.Cu")
		(at 160.02 -356.362 90)
		(property "Reference" "R349"
			(at 0 0 90)
			(layer "F.SilkS")
			(hide yes)
			(effects
				(font
					(size 1.27 1.27)
				)
			)
		)
		(property "Value" ""
			(at 0 0 90)
			(layer "F.Fab")
			(effects
				(font
					(size 1.27 1.27)
				)
			)
		)
		(duplicate_pad_numbers_are_jumpers no)
		(fp_line
			(start 0.7874 -0.4064)
			(end 0.7874 0.4064)
			(stroke
				(width 0.1524)
				(type default)
			)
			(layer "F.SilkS")
		)
		(fp_line
			(start -0.7874 -0.4064)
			(end 0.7874 -0.4064)
			(stroke
				(width 0.1524)
				(type default)
			)
			(layer "F.SilkS")
		)
		(fp_line
			(start 0.7874 0.4064)
			(end -0.7874 0.4064)
			(stroke
				(width 0.1524)
				(type default)
			)
			(layer "F.SilkS")
		)
		(fp_line
			(start -0.7874 0.4064)
			(end -0.7874 -0.4064)
			(stroke
				(width 0.1524)
				(type default)
			)
			(layer "F.SilkS")
		)
		(fp_line
			(start -0.12065 -0.305054)
			(end -0.12065 -0.2794)
			(stroke
				(width 0.1)
				(type default)
			)
			(layer "F.Fab")
		)
		(fp_line
			(start -0.67945 -0.305054)
			(end -0.12065 -0.305054)
			(stroke
				(width 0.1)
				(type default)
			)
			(layer "F.Fab")
		)
		(fp_line
			(start 0.67945 -0.3048)
			(end 0.67945 0.3048)
			(stroke
				(width 0.1)
				(type default)
			)
			(layer "F.Fab")
		)
		(fp_line
			(start 0.12065 -0.3048)
			(end 0.67945 -0.3048)
			(stroke
				(width 0.1)
				(type default)
			)
			(layer "F.Fab")
		)
		(fp_line
			(start 0.12065 -0.2794)
			(end 0.12065 -0.3048)
			(stroke
				(width 0.1)
				(type default)
			)
			(layer "F.Fab")
		)
		(fp_line
			(start -0.12065 -0.2794)
			(end 0.12065 -0.2794)
			(stroke
				(width 0.1)
				(type default)
			)
			(layer "F.Fab")
		)
		(fp_line
			(start 0.120396 0.2794)
			(end -0.12065 0.2794)
			(stroke
				(width 0.1)
				(type default)
			)
			(layer "F.Fab")
		)
		(fp_line
			(start -0.12065 0.2794)
			(end -0.12065 0.3048)
			(stroke
				(width 0.1)
				(type default)
			)
			(layer "F.Fab")
		)
		(fp_line
			(start 0.67945 0.3048)
			(end 0.120396 0.3048)
			(stroke
				(width 0.1)
				(type default)
			)
			(layer "F.Fab")
		)
		(fp_line
			(start 0.120396 0.3048)
			(end 0.120396 0.2794)
			(stroke
				(width 0.1)
				(type default)
			)
			(layer "F.Fab")
		)
		(fp_line
			(start -0.12065 0.3048)
			(end -0.67945 0.3048)
			(stroke
				(width 0.1)
				(type default)
			)
			(layer "F.Fab")
		)
		(fp_line
			(start -0.67945 0.3048)
			(end -0.67945 -0.305054)
			(stroke
				(width 0.1)
				(type default)
			)
			(layer "F.Fab")
		)
		(pad "1" smd circle
			(at -0.40005 0 90)
			(size 0 0)
			(layers "F.Cu" "F.Mask" "F.Paste")
			(net "SMB_SCM_2_R2_SCL")
		)
		(pad "2" smd circle
			(at 0.40005 0 90)
			(size 0 0)
			(layers "F.Cu" "F.Mask" "F.Paste")
			(net "SMB_SCM_2_R5_SCL")
		)
	)
	(footprint ""
		(layer "F.Cu")
		(at 407.742644 -139.362942 -90)
		(property "Reference" "PC1877"
			(at 0 0 270)
			(layer "F.SilkS")
			(hide yes)
			(effects
				(font
					(size 1.27 1.27)
				)
			)
		)
		(property "Value" ""
			(at 0 0 270)
			(layer "F.Fab")
			(effects
				(font
					(size 1.27 1.27)
				)
			)
		)
		(duplicate_pad_numbers_are_jumpers no)
		(fp_line
			(start -0.7874 0.4064)
			(end -0.7874 -0.4064)
			(stroke
				(width 0.1524)
				(type default)
			)
			(layer "F.SilkS")
		)
		(fp_line
			(start 0.7874 0.4064)
			(end -0.7874 0.4064)
			(stroke
				(width 0.1524)
				(type default)
			)
			(layer "F.SilkS")
		)
		(fp_line
			(start -0.7874 -0.4064)
			(end 0.7874 -0.4064)
			(stroke
				(width 0.1524)
				(type default)
			)
			(layer "F.SilkS")
		)
		(fp_line
			(start 0.7874 -0.4064)
			(end 0.7874 0.4064)
			(stroke
				(width 0.1524)
				(type default)
			)
			(layer "F.SilkS")
		)
		(fp_line
			(start -0.67945 0.3048)
			(end -0.67945 -0.305054)
			(stroke
				(width 0.1)
				(type default)
			)
			(layer "F.Fab")
		)
		(fp_line
			(start -0.12065 0.3048)
			(end -0.67945 0.3048)
			(stroke
				(width 0.1)
				(type default)
			)
			(layer "F.Fab")
		)
		(fp_line
			(start 0.120396 0.3048)
			(end 0.120396 0.2794)
			(stroke
				(width 0.1)
				(type default)
			)
			(layer "F.Fab")
		)
		(fp_line
			(start 0.67945 0.3048)
			(end 0.120396 0.3048)
			(stroke
				(width 0.1)
				(type default)
			)
			(layer "F.Fab")
		)
		(fp_line
			(start -0.12065 0.2794)
			(end -0.12065 0.3048)
			(stroke
				(width 0.1)
				(type default)
			)
			(layer "F.Fab")
		)
		(fp_line
			(start 0.120396 0.2794)
			(end -0.12065 0.2794)
			(stroke
				(width 0.1)
				(type default)
			)
			(layer "F.Fab")
		)
		(fp_line
			(start -0.12065 -0.2794)
			(end 0.12065 -0.2794)
			(stroke
				(width 0.1)
				(type default)
			)
			(layer "F.Fab")
		)
		(fp_line
			(start 0.12065 -0.2794)
			(end 0.12065 -0.3048)
			(stroke
				(width 0.1)
				(type default)
			)
			(layer "F.Fab")
		)
		(fp_line
			(start 0.12065 -0.3048)
			(end 0.67945 -0.3048)
			(stroke
				(width 0.1)
				(type default)
			)
			(layer "F.Fab")
		)
		(fp_line
			(start 0.67945 -0.3048)
			(end 0.67945 0.3048)
			(stroke
				(width 0.1)
				(type default)
			)
			(layer "F.Fab")
		)
		(fp_line
			(start -0.67945 -0.305054)
			(end -0.12065 -0.305054)
			(stroke
				(width 0.1)
				(type default)
			)
			(layer "F.Fab")
		)
		(fp_line
			(start -0.12065 -0.305054)
			(end -0.12065 -0.2794)
			(stroke
				(width 0.1)
				(type default)
			)
			(layer "F.Fab")
		)
		(pad "1" smd circle
			(at -0.40005 0 270)
			(size 0 0)
			(layers "F.Cu" "F.Mask" "F.Paste")
			(net "P5V_AUX_FB")
		)
		(pad "2" smd circle
			(at 0.40005 0 270)
			(size 0 0)
			(layers "F.Cu" "F.Mask" "F.Paste")
			(net "P5V_AUX")
		)
	)
	(footprint ""
		(layer "F.Cu")
		(at 142.729712 -75.582272 -0.054)
		(property "Reference" "PR6010"
			(at 0 0 359.946)
			(layer "F.SilkS")
			(hide yes)
			(effects
				(font
					(size 1.27 1.27)
				)
			)
		)
		(property "Value" ""
			(at 0 0 359.946)
			(layer "F.Fab")
			(effects
				(font
					(size 1.27 1.27)
				)
			)
		)
		(duplicate_pad_numbers_are_jumpers no)
		(fp_line
			(start -0.787525 0.40638)
			(end -0.787275 -0.40642)
			(stroke
				(width 0.1524)
				(type default)
			)
			(layer "F.SilkS")
		)
		(fp_line
			(start -0.787275 -0.40642)
			(end 0.787525 -0.40638)
			(stroke
				(width 0.1524)
				(type default)
			)
			(layer "F.SilkS")
		)
		(fp_line
			(start 0.787275 0.40642)
			(end -0.787525 0.40638)
			(stroke
				(width 0.1524)
				(type default)
			)
			(layer "F.SilkS")
		)
		(fp_line
			(start 0.787525 -0.40638)
			(end 0.787275 0.40642)
			(stroke
				(width 0.1524)
				(type default)
			)
			(layer "F.SilkS")
		)
		(fp_line
			(start -0.679417 0.304678)
			(end -0.679484 -0.305176)
			(stroke
				(width 0.1)
				(type default)
			)
			(layer "F.Fab")
		)
		(fp_line
			(start -0.679484 -0.305176)
			(end -0.120683 -0.30494)
			(stroke
				(width 0.1)
				(type default)
			)
			(layer "F.Fab")
		)
		(fp_line
			(start -0.120641 0.279514)
			(end -0.120617 0.304914)
			(stroke
				(width 0.1)
				(type default)
			)
			(layer "F.Fab")
		)
		(fp_line
			(start -0.120617 0.304914)
			(end -0.679417 0.304678)
			(stroke
				(width 0.1)
				(type default)
			)
			(layer "F.Fab")
		)
		(fp_line
			(start -0.120683 -0.30494)
			(end -0.120659 -0.279286)
			(stroke
				(width 0.1)
				(type default)
			)
			(layer "F.Fab")
		)
		(fp_line
			(start -0.120659 -0.279286)
			(end 0.120641 -0.279514)
			(stroke
				(width 0.1)
				(type default)
			)
			(layer "F.Fab")
		)
		(fp_line
			(start 0.120405 0.279287)
			(end -0.120641 0.279514)
			(stroke
				(width 0.1)
				(type default)
			)
			(layer "F.Fab")
		)
		(fp_line
			(start 0.120429 0.304687)
			(end 0.120405 0.279287)
			(stroke
				(width 0.1)
				(type default)
			)
			(layer "F.Fab")
		)
		(fp_line
			(start 0.120617 -0.304914)
			(end 0.679417 -0.304678)
			(stroke
				(width 0.1)
				(type default)
			)
			(layer "F.Fab")
		)
		(fp_line
			(start 0.120641 -0.279514)
			(end 0.120617 -0.304914)
			(stroke
				(width 0.1)
				(type default)
			)
			(layer "F.Fab")
		)
		(fp_line
			(start 0.679484 0.304922)
			(end 0.120429 0.304687)
			(stroke
				(width 0.1)
				(type default)
			)
			(layer "F.Fab")
		)
		(fp_line
			(start 0.679417 -0.304678)
			(end 0.679484 0.304922)
			(stroke
				(width 0.1)
				(type default)
			)
			(layer "F.Fab")
		)
		(pad "1" smd circle
			(at -0.40005 0 359.946)
			(size 0 0)
			(layers "F.Cu" "F.Mask" "F.Paste")
			(net "P1V8_AUX_FB")
		)
		(pad "2" smd circle
			(at 0.40005 0 359.946)
			(size 0 0)
			(layers "F.Cu" "F.Mask" "F.Paste")
			(net "GND")
		)
	)
	(footprint ""
		(layer "F.Cu")
		(at 374.24487 -15.637002)
		(property "Reference" "R1595"
			(at 0 0 0)
			(layer "F.SilkS")
			(hide yes)
			(effects
				(font
					(size 1.27 1.27)
				)
			)
		)
		(property "Value" ""
			(at 0 0 0)
			(layer "F.Fab")
			(effects
				(font
					(size 1.27 1.27)
				)
			)
		)
		(duplicate_pad_numbers_are_jumpers no)
		(fp_line
			(start -0.7874 -0.4064)
			(end 0.7874 -0.4064)
			(stroke
				(width 0.1524)
				(type default)
			)
			(layer "F.SilkS")
		)
		(fp_line
			(start -0.7874 0.4064)
			(end -0.7874 -0.4064)
			(stroke
				(width 0.1524)
				(type default)
			)
			(layer "F.SilkS")
		)
		(fp_line
			(start 0.7874 -0.4064)
			(end 0.7874 0.4064)
			(stroke
				(width 0.1524)
				(type default)
			)
			(layer "F.SilkS")
		)
		(fp_line
			(start 0.7874 0.4064)
			(end -0.7874 0.4064)
			(stroke
				(width 0.1524)
				(type default)
			)
			(layer "F.SilkS")
		)
		(fp_line
			(start -0.67945 -0.305054)
			(end -0.12065 -0.305054)
			(stroke
				(width 0.1)
				(type default)
			)
			(layer "F.Fab")
		)
		(fp_line
			(start -0.67945 0.3048)
			(end -0.67945 -0.305054)
			(stroke
				(width 0.1)
				(type default)
			)
			(layer "F.Fab")
		)
		(fp_line
			(start -0.12065 -0.305054)
			(end -0.12065 -0.2794)
			(stroke
				(width 0.1)
				(type default)
			)
			(layer "F.Fab")
		)
		(fp_line
			(start -0.12065 -0.2794)
			(end 0.12065 -0.2794)
			(stroke
				(width 0.1)
				(type default)
			)
			(layer "F.Fab")
		)
		(fp_line
			(start -0.12065 0.2794)
			(end -0.12065 0.3048)
			(stroke
				(width 0.1)
				(type default)
			)
			(layer "F.Fab")
		)
		(fp_line
			(start -0.12065 0.3048)
			(end -0.67945 0.3048)
			(stroke
				(width 0.1)
				(type default)
			)
			(layer "F.Fab")
		)
		(fp_line
			(start 0.120396 0.2794)
			(end -0.12065 0.2794)
			(stroke
				(width 0.1)
				(type default)
			)
			(layer "F.Fab")
		)
		(fp_line
			(start 0.120396 0.3048)
			(end 0.120396 0.2794)
			(stroke
				(width 0.1)
				(type default)
			)
			(layer "F.Fab")
		)
		(fp_line
			(start 0.12065 -0.3048)
			(end 0.67945 -0.3048)
			(stroke
				(width 0.1)
				(type default)
			)
			(layer "F.Fab")
		)
		(fp_line
			(start 0.12065 -0.2794)
			(end 0.12065 -0.3048)
			(stroke
				(width 0.1)
				(type default)
			)
			(layer "F.Fab")
		)
		(fp_line
			(start 0.67945 -0.3048)
			(end 0.67945 0.3048)
			(stroke
				(width 0.1)
				(type default)
			)
			(layer "F.Fab")
		)
		(fp_line
			(start 0.67945 0.3048)
			(end 0.120396 0.3048)
			(stroke
				(width 0.1)
				(type default)
			)
			(layer "F.Fab")
		)
		(pad "1" smd circle
			(at -0.40005 0)
			(size 0 0)
			(layers "F.Cu" "F.Mask" "F.Paste")
			(net "OCP_SFF_PWRBRK_BUFF_N")
		)
		(pad "2" smd circle
			(at 0.40005 0)
			(size 0 0)
			(layers "F.Cu" "F.Mask" "F.Paste")
			(net "OCP_SFF_PWRBRK_N")
		)
	)
	(footprint ""
		(layer "F.Cu")
		(at 304.419 -361.696)
		(property "Reference" "R8063"
			(at 0 0 0)
			(layer "F.SilkS")
			(hide yes)
			(effects
				(font
					(size 1.27 1.27)
				)
			)
		)
		(property "Value" ""
			(at 0 0 0)
			(layer "F.Fab")
			(effects
				(font
					(size 1.27 1.27)
				)
			)
		)
		(duplicate_pad_numbers_are_jumpers no)
		(fp_line
			(start -0.7874 -0.4064)
			(end 0.7874 -0.4064)
			(stroke
				(width 0.1524)
				(type default)
			)
			(layer "F.SilkS")
		)
		(fp_line
			(start -0.7874 0.4064)
			(end -0.7874 -0.4064)
			(stroke
				(width 0.1524)
				(type default)
			)
			(layer "F.SilkS")
		)
		(fp_line
			(start 0.7874 -0.4064)
			(end 0.7874 0.4064)
			(stroke
				(width 0.1524)
				(type default)
			)
			(layer "F.SilkS")
		)
		(fp_line
			(start 0.7874 0.4064)
			(end -0.7874 0.4064)
			(stroke
				(width 0.1524)
				(type default)
			)
			(layer "F.SilkS")
		)
		(fp_line
			(start -0.67945 -0.305054)
			(end -0.12065 -0.305054)
			(stroke
				(width 0.1)
				(type default)
			)
			(layer "F.Fab")
		)
		(fp_line
			(start -0.67945 0.3048)
			(end -0.67945 -0.305054)
			(stroke
				(width 0.1)
				(type default)
			)
			(layer "F.Fab")
		)
		(fp_line
			(start -0.12065 -0.305054)
			(end -0.12065 -0.2794)
			(stroke
				(width 0.1)
				(type default)
			)
			(layer "F.Fab")
		)
		(fp_line
			(start -0.12065 -0.2794)
			(end 0.12065 -0.2794)
			(stroke
				(width 0.1)
				(type default)
			)
			(layer "F.Fab")
		)
		(fp_line
			(start -0.12065 0.2794)
			(end -0.12065 0.3048)
			(stroke
				(width 0.1)
				(type default)
			)
			(layer "F.Fab")
		)
		(fp_line
			(start -0.12065 0.3048)
			(end -0.67945 0.3048)
			(stroke
				(width 0.1)
				(type default)
			)
			(layer "F.Fab")
		)
		(fp_line
			(start 0.120396 0.2794)
			(end -0.12065 0.2794)
			(stroke
				(width 0.1)
				(type default)
			)
			(layer "F.Fab")
		)
		(fp_line
			(start 0.120396 0.3048)
			(end 0.120396 0.2794)
			(stroke
				(width 0.1)
				(type default)
			)
			(layer "F.Fab")
		)
		(fp_line
			(start 0.12065 -0.3048)
			(end 0.67945 -0.3048)
			(stroke
				(width 0.1)
				(type default)
			)
			(layer "F.Fab")
		)
		(fp_line
			(start 0.12065 -0.2794)
			(end 0.12065 -0.3048)
			(stroke
				(width 0.1)
				(type default)
			)
			(layer "F.Fab")
		)
		(fp_line
			(start 0.67945 -0.3048)
			(end 0.67945 0.3048)
			(stroke
				(width 0.1)
				(type default)
			)
			(layer "F.Fab")
		)
		(fp_line
			(start 0.67945 0.3048)
			(end 0.120396 0.3048)
			(stroke
				(width 0.1)
				(type default)
			)
			(layer "F.Fab")
		)
		(pad "1" smd circle
			(at -0.40005 0)
			(size 0 0)
			(layers "F.Cu" "F.Mask" "F.Paste")
			(net "PVDDCR_CPU1_P0_RESET_N")
		)
		(pad "2" smd circle
			(at 0.40005 0)
			(size 0 0)
			(layers "F.Cu" "F.Mask" "F.Paste")
			(net "PVDDCR_CPU1_P0_RESET_N_R")
		)
	)
	(footprint ""
		(layer "F.Cu")
		(at 281.686 -423.418 -90)
		(property "Reference" "R4476"
			(at 0 0 270)
			(layer "F.SilkS")
			(hide yes)
			(effects
				(font
					(size 1.27 1.27)
				)
			)
		)
		(property "Value" ""
			(at 0 0 270)
			(layer "F.Fab")
			(effects
				(font
					(size 1.27 1.27)
				)
			)
		)
		(duplicate_pad_numbers_are_jumpers no)
		(fp_line
			(start -0.7874 0.4064)
			(end -0.7874 -0.4064)
			(stroke
				(width 0.1524)
				(type default)
			)
			(layer "F.SilkS")
		)
		(fp_line
			(start 0.7874 0.4064)
			(end -0.7874 0.4064)
			(stroke
				(width 0.1524)
				(type default)
			)
			(layer "F.SilkS")
		)
		(fp_line
			(start -0.7874 -0.4064)
			(end 0.7874 -0.4064)
			(stroke
				(width 0.1524)
				(type default)
			)
			(layer "F.SilkS")
		)
		(fp_line
			(start 0.7874 -0.4064)
			(end 0.7874 0.4064)
			(stroke
				(width 0.1524)
				(type default)
			)
			(layer "F.SilkS")
		)
		(fp_line
			(start -0.67945 0.3048)
			(end -0.67945 -0.305054)
			(stroke
				(width 0.1)
				(type default)
			)
			(layer "F.Fab")
		)
		(fp_line
			(start -0.12065 0.3048)
			(end -0.67945 0.3048)
			(stroke
				(width 0.1)
				(type default)
			)
			(layer "F.Fab")
		)
		(fp_line
			(start 0.120396 0.3048)
			(end 0.120396 0.2794)
			(stroke
				(width 0.1)
				(type default)
			)
			(layer "F.Fab")
		)
		(fp_line
			(start 0.67945 0.3048)
			(end 0.120396 0.3048)
			(stroke
				(width 0.1)
				(type default)
			)
			(layer "F.Fab")
		)
		(fp_line
			(start -0.12065 0.2794)
			(end -0.12065 0.3048)
			(stroke
				(width 0.1)
				(type default)
			)
			(layer "F.Fab")
		)
		(fp_line
			(start 0.120396 0.2794)
			(end -0.12065 0.2794)
			(stroke
				(width 0.1)
				(type default)
			)
			(layer "F.Fab")
		)
		(fp_line
			(start -0.12065 -0.2794)
			(end 0.12065 -0.2794)
			(stroke
				(width 0.1)
				(type default)
			)
			(layer "F.Fab")
		)
		(fp_line
			(start 0.12065 -0.2794)
			(end 0.12065 -0.3048)
			(stroke
				(width 0.1)
				(type default)
			)
			(layer "F.Fab")
		)
		(fp_line
			(start 0.12065 -0.3048)
			(end 0.67945 -0.3048)
			(stroke
				(width 0.1)
				(type default)
			)
			(layer "F.Fab")
		)
		(fp_line
			(start 0.67945 -0.3048)
			(end 0.67945 0.3048)
			(stroke
				(width 0.1)
				(type default)
			)
			(layer "F.Fab")
		)
		(fp_line
			(start -0.67945 -0.305054)
			(end -0.12065 -0.305054)
			(stroke
				(width 0.1)
				(type default)
			)
			(layer "F.Fab")
		)
		(fp_line
			(start -0.12065 -0.305054)
			(end -0.12065 -0.2794)
			(stroke
				(width 0.1)
				(type default)
			)
			(layer "F.Fab")
		)
		(pad "1" smd circle
			(at -0.40005 0 270)
			(size 0 0)
			(layers "F.Cu" "F.Mask" "F.Paste")
			(net "P3V3_AUX")
		)
		(pad "2" smd circle
			(at 0.40005 0 270)
			(size 0 0)
			(layers "F.Cu" "F.Mask" "F.Paste")
			(net "FM_9ZXL045_P0_DEV_EN")
		)
	)
	(footprint ""
		(layer "F.Cu")
		(at 271.739106 -346.714572 -90)
		(property "Reference" "PC173_IOP0_4"
			(at 0 0 270)
			(layer "F.SilkS")
			(hide yes)
			(effects
				(font
					(size 1.27 1.27)
				)
			)
		)
		(property "Value" ""
			(at 0 0 270)
			(layer "F.Fab")
			(effects
				(font
					(size 1.27 1.27)
				)
			)
		)
		(duplicate_pad_numbers_are_jumpers no)
		(fp_line
			(start -0.7874 0.4064)
			(end -0.7874 -0.4064)
			(stroke
				(width 0.1524)
				(type default)
			)
			(layer "F.SilkS")
		)
		(fp_line
			(start 0.7874 0.4064)
			(end -0.7874 0.4064)
			(stroke
				(width 0.1524)
				(type default)
			)
			(layer "F.SilkS")
		)
		(fp_line
			(start -0.7874 -0.4064)
			(end 0.7874 -0.4064)
			(stroke
				(width 0.1524)
				(type default)
			)
			(layer "F.SilkS")
		)
		(fp_line
			(start 0.7874 -0.4064)
			(end 0.7874 0.4064)
			(stroke
				(width 0.1524)
				(type default)
			)
			(layer "F.SilkS")
		)
		(fp_line
			(start -0.67945 0.3048)
			(end -0.67945 -0.305054)
			(stroke
				(width 0.1)
				(type default)
			)
			(layer "F.Fab")
		)
		(fp_line
			(start -0.12065 0.3048)
			(end -0.67945 0.3048)
			(stroke
				(width 0.1)
				(type default)
			)
			(layer "F.Fab")
		)
		(fp_line
			(start 0.120396 0.3048)
			(end 0.120396 0.2794)
			(stroke
				(width 0.1)
				(type default)
			)
			(layer "F.Fab")
		)
		(fp_line
			(start 0.67945 0.3048)
			(end 0.120396 0.3048)
			(stroke
				(width 0.1)
				(type default)
			)
			(layer "F.Fab")
		)
		(fp_line
			(start -0.12065 0.2794)
			(end -0.12065 0.3048)
			(stroke
				(width 0.1)
				(type default)
			)
			(layer "F.Fab")
		)
		(fp_line
			(start 0.120396 0.2794)
			(end -0.12065 0.2794)
			(stroke
				(width 0.1)
				(type default)
			)
			(layer "F.Fab")
		)
		(fp_line
			(start -0.12065 -0.2794)
			(end 0.12065 -0.2794)
			(stroke
				(width 0.1)
				(type default)
			)
			(layer "F.Fab")
		)
		(fp_line
			(start 0.12065 -0.2794)
			(end 0.12065 -0.3048)
			(stroke
				(width 0.1)
				(type default)
			)
			(layer "F.Fab")
		)
		(fp_line
			(start 0.12065 -0.3048)
			(end 0.67945 -0.3048)
			(stroke
				(width 0.1)
				(type default)
			)
			(layer "F.Fab")
		)
		(fp_line
			(start 0.67945 -0.3048)
			(end 0.67945 0.3048)
			(stroke
				(width 0.1)
				(type default)
			)
			(layer "F.Fab")
		)
		(fp_line
			(start -0.67945 -0.305054)
			(end -0.12065 -0.305054)
			(stroke
				(width 0.1)
				(type default)
			)
			(layer "F.Fab")
		)
		(fp_line
			(start -0.12065 -0.305054)
			(end -0.12065 -0.2794)
			(stroke
				(width 0.1)
				(type default)
			)
			(layer "F.Fab")
		)
		(pad "1" smd circle
			(at -0.40005 0 270)
			(size 0 0)
			(layers "F.Cu" "F.Mask" "F.Paste")
			(net "PVDDCR_CPU1_P0_PVCC")
		)
		(pad "2" smd circle
			(at 0.40005 0 270)
			(size 0 0)
			(layers "F.Cu" "F.Mask" "F.Paste")
			(net "GND")
		)
	)
	(footprint ""
		(layer "F.Cu")
		(at 65.3796 -13.8176 180)
		(property "Reference" "C1832"
			(at 0 0 180)
			(layer "F.SilkS")
			(hide yes)
			(effects
				(font
					(size 1.27 1.27)
				)
			)
		)
		(property "Value" ""
			(at 0 0 180)
			(layer "F.Fab")
			(effects
				(font
					(size 1.27 1.27)
				)
			)
		)
		(duplicate_pad_numbers_are_jumpers no)
		(fp_line
			(start 0.7874 0.4064)
			(end -0.7874 0.4064)
			(stroke
				(width 0.1524)
				(type default)
			)
			(layer "F.SilkS")
		)
		(fp_line
			(start 0.7874 -0.4064)
			(end 0.7874 0.4064)
			(stroke
				(width 0.1524)
				(type default)
			)
			(layer "F.SilkS")
		)
		(fp_line
			(start -0.7874 0.4064)
			(end -0.7874 -0.4064)
			(stroke
				(width 0.1524)
				(type default)
			)
			(layer "F.SilkS")
		)
		(fp_line
			(start -0.7874 -0.4064)
			(end 0.7874 -0.4064)
			(stroke
				(width 0.1524)
				(type default)
			)
			(layer "F.SilkS")
		)
		(fp_line
			(start 0.67945 0.3048)
			(end 0.120396 0.3048)
			(stroke
				(width 0.1)
				(type default)
			)
			(layer "F.Fab")
		)
		(fp_line
			(start 0.67945 -0.3048)
			(end 0.67945 0.3048)
			(stroke
				(width 0.1)
				(type default)
			)
			(layer "F.Fab")
		)
		(fp_line
			(start 0.12065 -0.2794)
			(end 0.12065 -0.3048)
			(stroke
				(width 0.1)
				(type default)
			)
			(layer "F.Fab")
		)
		(fp_line
			(start 0.12065 -0.3048)
			(end 0.67945 -0.3048)
			(stroke
				(width 0.1)
				(type default)
			)
			(layer "F.Fab")
		)
		(fp_line
			(start 0.120396 0.3048)
			(end 0.120396 0.2794)
			(stroke
				(width 0.1)
				(type default)
			)
			(layer "F.Fab")
		)
		(fp_line
			(start 0.120396 0.2794)
			(end -0.12065 0.2794)
			(stroke
				(width 0.1)
				(type default)
			)
			(layer "F.Fab")
		)
		(fp_line
			(start -0.12065 0.3048)
			(end -0.67945 0.3048)
			(stroke
				(width 0.1)
				(type default)
			)
			(layer "F.Fab")
		)
		(fp_line
			(start -0.12065 0.2794)
			(end -0.12065 0.3048)
			(stroke
				(width 0.1)
				(type default)
			)
			(layer "F.Fab")
		)
		(fp_line
			(start -0.12065 -0.2794)
			(end 0.12065 -0.2794)
			(stroke
				(width 0.1)
				(type default)
			)
			(layer "F.Fab")
		)
		(fp_line
			(start -0.12065 -0.305054)
			(end -0.12065 -0.2794)
			(stroke
				(width 0.1)
				(type default)
			)
			(layer "F.Fab")
		)
		(fp_line
			(start -0.67945 0.3048)
			(end -0.67945 -0.305054)
			(stroke
				(width 0.1)
				(type default)
			)
			(layer "F.Fab")
		)
		(fp_line
			(start -0.67945 -0.305054)
			(end -0.12065 -0.305054)
			(stroke
				(width 0.1)
				(type default)
			)
			(layer "F.Fab")
		)
		(pad "1" smd circle
			(at -0.40005 0 180)
			(size 0 0)
			(layers "F.Cu" "F.Mask" "F.Paste")
			(net "P12V_OCP_V3_2_R")
		)
		(pad "2" smd circle
			(at 0.40005 0 180)
			(size 0 0)
			(layers "F.Cu" "F.Mask" "F.Paste")
			(net "GND")
		)
	)
	(footprint ""
		(layer "F.Cu")
		(at 303.200308 -40.890698)
		(property "Reference" "R3667"
			(at 0 0 0)
			(layer "F.SilkS")
			(hide yes)
			(effects
				(font
					(size 1.27 1.27)
				)
			)
		)
		(property "Value" ""
			(at 0 0 0)
			(layer "F.Fab")
			(effects
				(font
					(size 1.27 1.27)
				)
			)
		)
		(duplicate_pad_numbers_are_jumpers no)
		(fp_line
			(start -0.7874 -0.4064)
			(end 0.7874 -0.4064)
			(stroke
				(width 0.1524)
				(type default)
			)
			(layer "F.SilkS")
		)
		(fp_line
			(start -0.7874 0.4064)
			(end -0.7874 -0.4064)
			(stroke
				(width 0.1524)
				(type default)
			)
			(layer "F.SilkS")
		)
		(fp_line
			(start 0.7874 -0.4064)
			(end 0.7874 0.4064)
			(stroke
				(width 0.1524)
				(type default)
			)
			(layer "F.SilkS")
		)
		(fp_line
			(start 0.7874 0.4064)
			(end -0.7874 0.4064)
			(stroke
				(width 0.1524)
				(type default)
			)
			(layer "F.SilkS")
		)
		(fp_line
			(start -0.67945 -0.305054)
			(end -0.12065 -0.305054)
			(stroke
				(width 0.1)
				(type default)
			)
			(layer "F.Fab")
		)
		(fp_line
			(start -0.67945 0.3048)
			(end -0.67945 -0.305054)
			(stroke
				(width 0.1)
				(type default)
			)
			(layer "F.Fab")
		)
		(fp_line
			(start -0.12065 -0.305054)
			(end -0.12065 -0.2794)
			(stroke
				(width 0.1)
				(type default)
			)
			(layer "F.Fab")
		)
		(fp_line
			(start -0.12065 -0.2794)
			(end 0.12065 -0.2794)
			(stroke
				(width 0.1)
				(type default)
			)
			(layer "F.Fab")
		)
		(fp_line
			(start -0.12065 0.2794)
			(end -0.12065 0.3048)
			(stroke
				(width 0.1)
				(type default)
			)
			(layer "F.Fab")
		)
		(fp_line
			(start -0.12065 0.3048)
			(end -0.67945 0.3048)
			(stroke
				(width 0.1)
				(type default)
			)
			(layer "F.Fab")
		)
		(fp_line
			(start 0.120396 0.2794)
			(end -0.12065 0.2794)
			(stroke
				(width 0.1)
				(type default)
			)
			(layer "F.Fab")
		)
		(fp_line
			(start 0.120396 0.3048)
			(end 0.120396 0.2794)
			(stroke
				(width 0.1)
				(type default)
			)
			(layer "F.Fab")
		)
		(fp_line
			(start 0.12065 -0.3048)
			(end 0.67945 -0.3048)
			(stroke
				(width 0.1)
				(type default)
			)
			(layer "F.Fab")
		)
		(fp_line
			(start 0.12065 -0.2794)
			(end 0.12065 -0.3048)
			(stroke
				(width 0.1)
				(type default)
			)
			(layer "F.Fab")
		)
		(fp_line
			(start 0.67945 -0.3048)
			(end 0.67945 0.3048)
			(stroke
				(width 0.1)
				(type default)
			)
			(layer "F.Fab")
		)
		(fp_line
			(start 0.67945 0.3048)
			(end 0.120396 0.3048)
			(stroke
				(width 0.1)
				(type default)
			)
			(layer "F.Fab")
		)
		(pad "1" smd circle
			(at -0.40005 0)
			(size 0 0)
			(layers "F.Cu" "F.Mask" "F.Paste")
			(net "P3V3_AUX")
		)
		(pad "2" smd circle
			(at 0.40005 0)
			(size 0 0)
			(layers "F.Cu" "F.Mask" "F.Paste")
			(net "ADC128_A1")
		)
	)
	(footprint ""
		(layer "F.Cu")
		(at 281.94 -426.212 -90)
		(property "Reference" "R4475"
			(at 0 0 270)
			(layer "F.SilkS")
			(hide yes)
			(effects
				(font
					(size 1.27 1.27)
				)
			)
		)
		(property "Value" ""
			(at 0 0 270)
			(layer "F.Fab")
			(effects
				(font
					(size 1.27 1.27)
				)
			)
		)
		(duplicate_pad_numbers_are_jumpers no)
		(fp_line
			(start -1.2954 0.5842)
			(end -1.2954 -0.5842)
			(stroke
				(width 0.1524)
				(type default)
			)
			(layer "F.SilkS")
		)
		(fp_line
			(start 1.2954 0.5842)
			(end -1.2954 0.5842)
			(stroke
				(width 0.1524)
				(type default)
			)
			(layer "F.SilkS")
		)
		(fp_line
			(start -1.2954 -0.5842)
			(end 1.2954 -0.5842)
			(stroke
				(width 0.1524)
				(type default)
			)
			(layer "F.SilkS")
		)
		(fp_line
			(start 1.2954 -0.5842)
			(end 1.2954 0.5842)
			(stroke
				(width 0.1524)
				(type default)
			)
			(layer "F.SilkS")
		)
		(fp_line
			(start -0.8636 0.4572)
			(end -0.8636 0.4318)
			(stroke
				(width 0.1)
				(type default)
			)
			(layer "F.Fab")
		)
		(fp_line
			(start 0.8636 0.4572)
			(end -0.8636 0.4572)
			(stroke
				(width 0.1)
				(type default)
			)
			(layer "F.Fab")
		)
		(fp_line
			(start -0.8636 0.4318)
			(end -0.8636 0.4064)
			(stroke
				(width 0.1)
				(type default)
			)
			(layer "F.Fab")
		)
		(fp_line
			(start -1.1938 0.4064)
			(end -1.1938 -0.406654)
			(stroke
				(width 0.1)
				(type default)
			)
			(layer "F.Fab")
		)
		(fp_line
			(start -0.8636 0.4064)
			(end -1.1938 0.4064)
			(stroke
				(width 0.1)
				(type default)
			)
			(layer "F.Fab")
		)
		(fp_line
			(start 0.8636 0.4064)
			(end 0.8636 0.4572)
			(stroke
				(width 0.1)
				(type default)
			)
			(layer "F.Fab")
		)
		(fp_line
			(start 1.1938 0.4064)
			(end 0.8636 0.4064)
			(stroke
				(width 0.1)
				(type default)
			)
			(layer "F.Fab")
		)
		(fp_line
			(start -1.1938 -0.406654)
			(end -0.8636 -0.406654)
			(stroke
				(width 0.1)
				(type default)
			)
			(layer "F.Fab")
		)
		(fp_line
			(start -0.8636 -0.406654)
			(end -0.8636 -0.4572)
			(stroke
				(width 0.1)
				(type default)
			)
			(layer "F.Fab")
		)
		(fp_line
			(start 0.8636 -0.406654)
			(end 1.1938 -0.406654)
			(stroke
				(width 0.1)
				(type default)
			)
			(layer "F.Fab")
		)
		(fp_line
			(start 1.1938 -0.406654)
			(end 1.1938 0.4064)
			(stroke
				(width 0.1)
				(type default)
			)
			(layer "F.Fab")
		)
		(fp_line
			(start -0.8636 -0.4572)
			(end 0.8636 -0.4572)
			(stroke
				(width 0.1)
				(type default)
			)
			(layer "F.Fab")
		)
		(fp_line
			(start 0.8636 -0.4572)
			(end 0.8636 -0.406654)
			(stroke
				(width 0.1)
				(type default)
			)
			(layer "F.Fab")
		)
		(pad "1" smd rect
			(at -0.7366 0 180)
			(size 0.7112 0.8128)
			(layers "F.Cu" "F.Mask" "F.Paste")
			(net "P3V3_9ZXL045_P0")
		)
		(pad "2" smd rect
			(at 0.7366 0 180)
			(size 0.7112 0.8128)
			(layers "F.Cu" "F.Mask" "F.Paste")
			(net "P3V3_9ZXL045_P0_VDDR")
		)
	)
	(footprint ""
		(layer "F.Cu")
		(at 152.849834 -323.747892 180)
		(property "Reference" "R760"
			(at 0 0 180)
			(layer "F.SilkS")
			(hide yes)
			(effects
				(font
					(size 1.27 1.27)
				)
			)
		)
		(property "Value" ""
			(at 0 0 180)
			(layer "F.Fab")
			(effects
				(font
					(size 1.27 1.27)
				)
			)
		)
		(duplicate_pad_numbers_are_jumpers no)
		(fp_line
			(start 0.7874 0.4064)
			(end -0.7874 0.4064)
			(stroke
				(width 0.1524)
				(type default)
			)
			(layer "F.SilkS")
		)
		(fp_line
			(start 0.7874 -0.4064)
			(end 0.7874 0.4064)
			(stroke
				(width 0.1524)
				(type default)
			)
			(layer "F.SilkS")
		)
		(fp_line
			(start -0.7874 0.4064)
			(end -0.7874 -0.4064)
			(stroke
				(width 0.1524)
				(type default)
			)
			(layer "F.SilkS")
		)
		(fp_line
			(start -0.7874 -0.4064)
			(end 0.7874 -0.4064)
			(stroke
				(width 0.1524)
				(type default)
			)
			(layer "F.SilkS")
		)
		(fp_line
			(start 0.67945 0.3048)
			(end 0.120396 0.3048)
			(stroke
				(width 0.1)
				(type default)
			)
			(layer "F.Fab")
		)
		(fp_line
			(start 0.67945 -0.3048)
			(end 0.67945 0.3048)
			(stroke
				(width 0.1)
				(type default)
			)
			(layer "F.Fab")
		)
		(fp_line
			(start 0.12065 -0.2794)
			(end 0.12065 -0.3048)
			(stroke
				(width 0.1)
				(type default)
			)
			(layer "F.Fab")
		)
		(fp_line
			(start 0.12065 -0.3048)
			(end 0.67945 -0.3048)
			(stroke
				(width 0.1)
				(type default)
			)
			(layer "F.Fab")
		)
		(fp_line
			(start 0.120396 0.3048)
			(end 0.120396 0.2794)
			(stroke
				(width 0.1)
				(type default)
			)
			(layer "F.Fab")
		)
		(fp_line
			(start 0.120396 0.2794)
			(end -0.12065 0.2794)
			(stroke
				(width 0.1)
				(type default)
			)
			(layer "F.Fab")
		)
		(fp_line
			(start -0.12065 0.3048)
			(end -0.67945 0.3048)
			(stroke
				(width 0.1)
				(type default)
			)
			(layer "F.Fab")
		)
		(fp_line
			(start -0.12065 0.2794)
			(end -0.12065 0.3048)
			(stroke
				(width 0.1)
				(type default)
			)
			(layer "F.Fab")
		)
		(fp_line
			(start -0.12065 -0.2794)
			(end 0.12065 -0.2794)
			(stroke
				(width 0.1)
				(type default)
			)
			(layer "F.Fab")
		)
		(fp_line
			(start -0.12065 -0.305054)
			(end -0.12065 -0.2794)
			(stroke
				(width 0.1)
				(type default)
			)
			(layer "F.Fab")
		)
		(fp_line
			(start -0.67945 0.3048)
			(end -0.67945 -0.305054)
			(stroke
				(width 0.1)
				(type default)
			)
			(layer "F.Fab")
		)
		(fp_line
			(start -0.67945 -0.305054)
			(end -0.12065 -0.305054)
			(stroke
				(width 0.1)
				(type default)
			)
			(layer "F.Fab")
		)
		(pad "1" smd circle
			(at -0.40005 0 180)
			(size 0 0)
			(layers "F.Cu" "F.Mask" "F.Paste")
			(net "GND")
		)
		(pad "2" smd circle
			(at 0.40005 0 180)
			(size 0 0)
			(layers "F.Cu" "F.Mask" "F.Paste")
			(net "PD_ESPI_CPU1_CLK2")
		)
	)
	(footprint ""
		(layer "F.Cu")
		(at 112.425988 -256.012442 90)
		(property "Reference" "C2446"
			(at 0 0 90)
			(layer "F.SilkS")
			(hide yes)
			(effects
				(font
					(size 1.27 1.27)
				)
			)
		)
		(property "Value" ""
			(at 0 0 90)
			(layer "F.Fab")
			(effects
				(font
					(size 1.27 1.27)
				)
			)
		)
		(duplicate_pad_numbers_are_jumpers no)
		(fp_line
			(start 0.7874 -0.4064)
			(end 0.7874 0.4064)
			(stroke
				(width 0.1524)
				(type default)
			)
			(layer "F.SilkS")
		)
		(fp_line
			(start -0.7874 -0.4064)
			(end 0.7874 -0.4064)
			(stroke
				(width 0.1524)
				(type default)
			)
			(layer "F.SilkS")
		)
		(fp_line
			(start 0.7874 0.4064)
			(end -0.7874 0.4064)
			(stroke
				(width 0.1524)
				(type default)
			)
			(layer "F.SilkS")
		)
		(fp_line
			(start -0.7874 0.4064)
			(end -0.7874 -0.4064)
			(stroke
				(width 0.1524)
				(type default)
			)
			(layer "F.SilkS")
		)
		(fp_line
			(start -0.12065 -0.305054)
			(end -0.12065 -0.2794)
			(stroke
				(width 0.1)
				(type default)
			)
			(layer "F.Fab")
		)
		(fp_line
			(start -0.67945 -0.305054)
			(end -0.12065 -0.305054)
			(stroke
				(width 0.1)
				(type default)
			)
			(layer "F.Fab")
		)
		(fp_line
			(start 0.67945 -0.3048)
			(end 0.67945 0.3048)
			(stroke
				(width 0.1)
				(type default)
			)
			(layer "F.Fab")
		)
		(fp_line
			(start 0.12065 -0.3048)
			(end 0.67945 -0.3048)
			(stroke
				(width 0.1)
				(type default)
			)
			(layer "F.Fab")
		)
		(fp_line
			(start 0.12065 -0.2794)
			(end 0.12065 -0.3048)
			(stroke
				(width 0.1)
				(type default)
			)
			(layer "F.Fab")
		)
		(fp_line
			(start -0.12065 -0.2794)
			(end 0.12065 -0.2794)
			(stroke
				(width 0.1)
				(type default)
			)
			(layer "F.Fab")
		)
		(fp_line
			(start 0.120396 0.2794)
			(end -0.12065 0.2794)
			(stroke
				(width 0.1)
				(type default)
			)
			(layer "F.Fab")
		)
		(fp_line
			(start -0.12065 0.2794)
			(end -0.12065 0.3048)
			(stroke
				(width 0.1)
				(type default)
			)
			(layer "F.Fab")
		)
		(fp_line
			(start 0.67945 0.3048)
			(end 0.120396 0.3048)
			(stroke
				(width 0.1)
				(type default)
			)
			(layer "F.Fab")
		)
		(fp_line
			(start 0.120396 0.3048)
			(end 0.120396 0.2794)
			(stroke
				(width 0.1)
				(type default)
			)
			(layer "F.Fab")
		)
		(fp_line
			(start -0.12065 0.3048)
			(end -0.67945 0.3048)
			(stroke
				(width 0.1)
				(type default)
			)
			(layer "F.Fab")
		)
		(fp_line
			(start -0.67945 0.3048)
			(end -0.67945 -0.305054)
			(stroke
				(width 0.1)
				(type default)
			)
			(layer "F.Fab")
		)
		(pad "1" smd circle
			(at -0.40005 0 90)
			(size 0 0)
			(layers "F.Cu" "F.Mask" "F.Paste")
			(net "PVDDCR_SOC_P1")
		)
		(pad "2" smd circle
			(at 0.40005 0 90)
			(size 0 0)
			(layers "F.Cu" "F.Mask" "F.Paste")
			(net "GND")
		)
	)
	(footprint ""
		(layer "F.Cu")
		(at 371.681502 -414.636458 -90)
		(property "Reference" "C6565"
			(at 0 0 270)
			(layer "F.SilkS")
			(hide yes)
			(effects
				(font
					(size 1.27 1.27)
				)
			)
		)
		(property "Value" ""
			(at 0 0 270)
			(layer "F.Fab")
			(effects
				(font
					(size 1.27 1.27)
				)
			)
		)
		(duplicate_pad_numbers_are_jumpers no)
		(fp_line
			(start -0.299974 0.150114)
			(end -0.299974 -0.150114)
			(stroke
				(width 0.1)
				(type default)
			)
			(layer "F.Fab")
		)
		(fp_line
			(start 0.299974 0.150114)
			(end -0.299974 0.150114)
			(stroke
				(width 0.1)
				(type default)
			)
			(layer "F.Fab")
		)
		(fp_line
			(start -0.299974 -0.150114)
			(end 0.299974 -0.150114)
			(stroke
				(width 0.1)
				(type default)
			)
			(layer "F.Fab")
		)
		(fp_line
			(start 0.299974 -0.150114)
			(end 0.299974 0.150114)
			(stroke
				(width 0.1)
				(type default)
			)
			(layer "F.Fab")
		)
		(pad "1" smd rect
			(at -0.2667 0 270)
			(size 0.3048 0.381)
			(layers "F.Cu" "F.Mask" "F.Paste")
			(net "P5E_CPU0_P2_TX_BUF_C_DP<0>")
		)
		(pad "2" smd rect
			(at 0.2667 0 270)
			(size 0.3048 0.381)
			(layers "F.Cu" "F.Mask" "F.Paste")
			(net "P5E_CPU0_P2_TX_BUF_DP<0>")
		)
	)
	(footprint ""
		(layer "F.Cu")
		(at 250.55957 -66.238374)
		(property "Reference" "R4064"
			(at 0 0 0)
			(layer "F.SilkS")
			(hide yes)
			(effects
				(font
					(size 1.27 1.27)
				)
			)
		)
		(property "Value" ""
			(at 0 0 0)
			(layer "F.Fab")
			(effects
				(font
					(size 1.27 1.27)
				)
			)
		)
		(duplicate_pad_numbers_are_jumpers no)
		(fp_line
			(start -0.7874 -0.4064)
			(end 0.7874 -0.4064)
			(stroke
				(width 0.1524)
				(type default)
			)
			(layer "F.SilkS")
		)
		(fp_line
			(start -0.7874 0.4064)
			(end -0.7874 -0.4064)
			(stroke
				(width 0.1524)
				(type default)
			)
			(layer "F.SilkS")
		)
		(fp_line
			(start 0.7874 -0.4064)
			(end 0.7874 0.4064)
			(stroke
				(width 0.1524)
				(type default)
			)
			(layer "F.SilkS")
		)
		(fp_line
			(start 0.7874 0.4064)
			(end -0.7874 0.4064)
			(stroke
				(width 0.1524)
				(type default)
			)
			(layer "F.SilkS")
		)
		(fp_line
			(start -0.67945 -0.305054)
			(end -0.12065 -0.305054)
			(stroke
				(width 0.1)
				(type default)
			)
			(layer "F.Fab")
		)
		(fp_line
			(start -0.67945 0.3048)
			(end -0.67945 -0.305054)
			(stroke
				(width 0.1)
				(type default)
			)
			(layer "F.Fab")
		)
		(fp_line
			(start -0.12065 -0.305054)
			(end -0.12065 -0.2794)
			(stroke
				(width 0.1)
				(type default)
			)
			(layer "F.Fab")
		)
		(fp_line
			(start -0.12065 -0.2794)
			(end 0.12065 -0.2794)
			(stroke
				(width 0.1)
				(type default)
			)
			(layer "F.Fab")
		)
		(fp_line
			(start -0.12065 0.2794)
			(end -0.12065 0.3048)
			(stroke
				(width 0.1)
				(type default)
			)
			(layer "F.Fab")
		)
		(fp_line
			(start -0.12065 0.3048)
			(end -0.67945 0.3048)
			(stroke
				(width 0.1)
				(type default)
			)
			(layer "F.Fab")
		)
		(fp_line
			(start 0.120396 0.2794)
			(end -0.12065 0.2794)
			(stroke
				(width 0.1)
				(type default)
			)
			(layer "F.Fab")
		)
		(fp_line
			(start 0.120396 0.3048)
			(end 0.120396 0.2794)
			(stroke
				(width 0.1)
				(type default)
			)
			(layer "F.Fab")
		)
		(fp_line
			(start 0.12065 -0.3048)
			(end 0.67945 -0.3048)
			(stroke
				(width 0.1)
				(type default)
			)
			(layer "F.Fab")
		)
		(fp_line
			(start 0.12065 -0.2794)
			(end 0.12065 -0.3048)
			(stroke
				(width 0.1)
				(type default)
			)
			(layer "F.Fab")
		)
		(fp_line
			(start 0.67945 -0.3048)
			(end 0.67945 0.3048)
			(stroke
				(width 0.1)
				(type default)
			)
			(layer "F.Fab")
		)
		(fp_line
			(start 0.67945 0.3048)
			(end 0.120396 0.3048)
			(stroke
				(width 0.1)
				(type default)
			)
			(layer "F.Fab")
		)
		(pad "1" smd circle
			(at -0.40005 0)
			(size 0 0)
			(layers "F.Cu" "F.Mask" "F.Paste")
			(net "E1S_0_P12V_EN")
		)
		(pad "2" smd circle
			(at 0.40005 0)
			(size 0 0)
			(layers "F.Cu" "F.Mask" "F.Paste")
			(net "P12V_E1S_EN_0_R")
		)
	)
	(footprint ""
		(layer "F.Cu")
		(at 171.196 -109.184948 180)
		(property "Reference" "R167"
			(at 0 0 180)
			(layer "F.SilkS")
			(hide yes)
			(effects
				(font
					(size 1.27 1.27)
				)
			)
		)
		(property "Value" ""
			(at 0 0 180)
			(layer "F.Fab")
			(effects
				(font
					(size 1.27 1.27)
				)
			)
		)
		(duplicate_pad_numbers_are_jumpers no)
		(fp_line
			(start 0.7874 0.4064)
			(end -0.7874 0.4064)
			(stroke
				(width 0.1524)
				(type default)
			)
			(layer "F.SilkS")
		)
		(fp_line
			(start 0.7874 -0.4064)
			(end 0.7874 0.4064)
			(stroke
				(width 0.1524)
				(type default)
			)
			(layer "F.SilkS")
		)
		(fp_line
			(start -0.7874 0.4064)
			(end -0.7874 -0.4064)
			(stroke
				(width 0.1524)
				(type default)
			)
			(layer "F.SilkS")
		)
		(fp_line
			(start -0.7874 -0.4064)
			(end 0.7874 -0.4064)
			(stroke
				(width 0.1524)
				(type default)
			)
			(layer "F.SilkS")
		)
		(fp_line
			(start 0.67945 0.3048)
			(end 0.120396 0.3048)
			(stroke
				(width 0.1)
				(type default)
			)
			(layer "F.Fab")
		)
		(fp_line
			(start 0.67945 -0.3048)
			(end 0.67945 0.3048)
			(stroke
				(width 0.1)
				(type default)
			)
			(layer "F.Fab")
		)
		(fp_line
			(start 0.12065 -0.2794)
			(end 0.12065 -0.3048)
			(stroke
				(width 0.1)
				(type default)
			)
			(layer "F.Fab")
		)
		(fp_line
			(start 0.12065 -0.3048)
			(end 0.67945 -0.3048)
			(stroke
				(width 0.1)
				(type default)
			)
			(layer "F.Fab")
		)
		(fp_line
			(start 0.120396 0.3048)
			(end 0.120396 0.2794)
			(stroke
				(width 0.1)
				(type default)
			)
			(layer "F.Fab")
		)
		(fp_line
			(start 0.120396 0.2794)
			(end -0.12065 0.2794)
			(stroke
				(width 0.1)
				(type default)
			)
			(layer "F.Fab")
		)
		(fp_line
			(start -0.12065 0.3048)
			(end -0.67945 0.3048)
			(stroke
				(width 0.1)
				(type default)
			)
			(layer "F.Fab")
		)
		(fp_line
			(start -0.12065 0.2794)
			(end -0.12065 0.3048)
			(stroke
				(width 0.1)
				(type default)
			)
			(layer "F.Fab")
		)
		(fp_line
			(start -0.12065 -0.2794)
			(end 0.12065 -0.2794)
			(stroke
				(width 0.1)
				(type default)
			)
			(layer "F.Fab")
		)
		(fp_line
			(start -0.12065 -0.305054)
			(end -0.12065 -0.2794)
			(stroke
				(width 0.1)
				(type default)
			)
			(layer "F.Fab")
		)
		(fp_line
			(start -0.67945 0.3048)
			(end -0.67945 -0.305054)
			(stroke
				(width 0.1)
				(type default)
			)
			(layer "F.Fab")
		)
		(fp_line
			(start -0.67945 -0.305054)
			(end -0.12065 -0.305054)
			(stroke
				(width 0.1)
				(type default)
			)
			(layer "F.Fab")
		)
		(pad "1" smd circle
			(at -0.40005 0 180)
			(size 0 0)
			(layers "F.Cu" "F.Mask" "F.Paste")
			(net "SGPIO_SCM_DI_R<0>")
		)
		(pad "2" smd circle
			(at 0.40005 0 180)
			(size 0 0)
			(layers "F.Cu" "F.Mask" "F.Paste")
			(net "SGPIO_SCM_DI_<0>")
		)
	)
	(footprint ""
		(layer "F.Cu")
		(at 102.437946 -54.882034 -90)
		(property "Reference" "R6322"
			(at 0 0 270)
			(layer "F.SilkS")
			(hide yes)
			(effects
				(font
					(size 1.27 1.27)
				)
			)
		)
		(property "Value" ""
			(at 0 0 270)
			(layer "F.Fab")
			(effects
				(font
					(size 1.27 1.27)
				)
			)
		)
		(duplicate_pad_numbers_are_jumpers no)
		(fp_line
			(start -0.7874 0.4064)
			(end -0.7874 -0.4064)
			(stroke
				(width 0.1524)
				(type default)
			)
			(layer "F.SilkS")
		)
		(fp_line
			(start 0.7874 0.4064)
			(end -0.7874 0.4064)
			(stroke
				(width 0.1524)
				(type default)
			)
			(layer "F.SilkS")
		)
		(fp_line
			(start -0.7874 -0.4064)
			(end 0.7874 -0.4064)
			(stroke
				(width 0.1524)
				(type default)
			)
			(layer "F.SilkS")
		)
		(fp_line
			(start 0.7874 -0.4064)
			(end 0.7874 0.4064)
			(stroke
				(width 0.1524)
				(type default)
			)
			(layer "F.SilkS")
		)
		(fp_line
			(start -0.67945 0.3048)
			(end -0.67945 -0.305054)
			(stroke
				(width 0.1)
				(type default)
			)
			(layer "F.Fab")
		)
		(fp_line
			(start -0.12065 0.3048)
			(end -0.67945 0.3048)
			(stroke
				(width 0.1)
				(type default)
			)
			(layer "F.Fab")
		)
		(fp_line
			(start 0.120396 0.3048)
			(end 0.120396 0.2794)
			(stroke
				(width 0.1)
				(type default)
			)
			(layer "F.Fab")
		)
		(fp_line
			(start 0.67945 0.3048)
			(end 0.120396 0.3048)
			(stroke
				(width 0.1)
				(type default)
			)
			(layer "F.Fab")
		)
		(fp_line
			(start -0.12065 0.2794)
			(end -0.12065 0.3048)
			(stroke
				(width 0.1)
				(type default)
			)
			(layer "F.Fab")
		)
		(fp_line
			(start 0.120396 0.2794)
			(end -0.12065 0.2794)
			(stroke
				(width 0.1)
				(type default)
			)
			(layer "F.Fab")
		)
		(fp_line
			(start -0.12065 -0.2794)
			(end 0.12065 -0.2794)
			(stroke
				(width 0.1)
				(type default)
			)
			(layer "F.Fab")
		)
		(fp_line
			(start 0.12065 -0.2794)
			(end 0.12065 -0.3048)
			(stroke
				(width 0.1)
				(type default)
			)
			(layer "F.Fab")
		)
		(fp_line
			(start 0.12065 -0.3048)
			(end 0.67945 -0.3048)
			(stroke
				(width 0.1)
				(type default)
			)
			(layer "F.Fab")
		)
		(fp_line
			(start 0.67945 -0.3048)
			(end 0.67945 0.3048)
			(stroke
				(width 0.1)
				(type default)
			)
			(layer "F.Fab")
		)
		(fp_line
			(start -0.67945 -0.305054)
			(end -0.12065 -0.305054)
			(stroke
				(width 0.1)
				(type default)
			)
			(layer "F.Fab")
		)
		(fp_line
			(start -0.12065 -0.305054)
			(end -0.12065 -0.2794)
			(stroke
				(width 0.1)
				(type default)
			)
			(layer "F.Fab")
		)
		(pad "1" smd circle
			(at -0.40005 0 270)
			(size 0 0)
			(layers "F.Cu" "F.Mask" "F.Paste")
			(net "RST_USB_HUB_N")
		)
		(pad "2" smd circle
			(at 0.40005 0 270)
			(size 0 0)
			(layers "F.Cu" "F.Mask" "F.Paste")
			(net "USB_HUB2_MRP_RESET_N")
		)
	)
	(footprint ""
		(layer "F.Cu")
		(at 365.887 -413.639 90)
		(property "Reference" "R4183"
			(at 0 0 90)
			(layer "F.SilkS")
			(hide yes)
			(effects
				(font
					(size 1.27 1.27)
				)
			)
		)
		(property "Value" ""
			(at 0 0 90)
			(layer "F.Fab")
			(effects
				(font
					(size 1.27 1.27)
				)
			)
		)
		(duplicate_pad_numbers_are_jumpers no)
		(fp_line
			(start 0.7874 -0.4064)
			(end 0.7874 0.4064)
			(stroke
				(width 0.1524)
				(type default)
			)
			(layer "F.SilkS")
		)
		(fp_line
			(start -0.7874 -0.4064)
			(end 0.7874 -0.4064)
			(stroke
				(width 0.1524)
				(type default)
			)
			(layer "F.SilkS")
		)
		(fp_line
			(start 0.7874 0.4064)
			(end -0.7874 0.4064)
			(stroke
				(width 0.1524)
				(type default)
			)
			(layer "F.SilkS")
		)
		(fp_line
			(start -0.7874 0.4064)
			(end -0.7874 -0.4064)
			(stroke
				(width 0.1524)
				(type default)
			)
			(layer "F.SilkS")
		)
		(fp_line
			(start -0.12065 -0.305054)
			(end -0.12065 -0.2794)
			(stroke
				(width 0.1)
				(type default)
			)
			(layer "F.Fab")
		)
		(fp_line
			(start -0.67945 -0.305054)
			(end -0.12065 -0.305054)
			(stroke
				(width 0.1)
				(type default)
			)
			(layer "F.Fab")
		)
		(fp_line
			(start 0.67945 -0.3048)
			(end 0.67945 0.3048)
			(stroke
				(width 0.1)
				(type default)
			)
			(layer "F.Fab")
		)
		(fp_line
			(start 0.12065 -0.3048)
			(end 0.67945 -0.3048)
			(stroke
				(width 0.1)
				(type default)
			)
			(layer "F.Fab")
		)
		(fp_line
			(start 0.12065 -0.2794)
			(end 0.12065 -0.3048)
			(stroke
				(width 0.1)
				(type default)
			)
			(layer "F.Fab")
		)
		(fp_line
			(start -0.12065 -0.2794)
			(end 0.12065 -0.2794)
			(stroke
				(width 0.1)
				(type default)
			)
			(layer "F.Fab")
		)
		(fp_line
			(start 0.120396 0.2794)
			(end -0.12065 0.2794)
			(stroke
				(width 0.1)
				(type default)
			)
			(layer "F.Fab")
		)
		(fp_line
			(start -0.12065 0.2794)
			(end -0.12065 0.3048)
			(stroke
				(width 0.1)
				(type default)
			)
			(layer "F.Fab")
		)
		(fp_line
			(start 0.67945 0.3048)
			(end 0.120396 0.3048)
			(stroke
				(width 0.1)
				(type default)
			)
			(layer "F.Fab")
		)
		(fp_line
			(start 0.120396 0.3048)
			(end 0.120396 0.2794)
			(stroke
				(width 0.1)
				(type default)
			)
			(layer "F.Fab")
		)
		(fp_line
			(start -0.12065 0.3048)
			(end -0.67945 0.3048)
			(stroke
				(width 0.1)
				(type default)
			)
			(layer "F.Fab")
		)
		(fp_line
			(start -0.67945 0.3048)
			(end -0.67945 -0.305054)
			(stroke
				(width 0.1)
				(type default)
			)
			(layer "F.Fab")
		)
		(pad "1" smd circle
			(at -0.40005 0 90)
			(size 0 0)
			(layers "F.Cu" "F.Mask" "F.Paste")
			(net "SMB_LM75_0_3V3AUX_SDA")
		)
		(pad "2" smd circle
			(at 0.40005 0 90)
			(size 0 0)
			(layers "F.Cu" "F.Mask" "F.Paste")
			(net "SMB_LM75_0_3V3AUX_SDA_R1")
		)
	)
	(footprint ""
		(layer "F.Cu")
		(at 20.981924 -407.976578 90)
		(property "Reference" "R662"
			(at 0 0 90)
			(layer "F.SilkS")
			(hide yes)
			(effects
				(font
					(size 1.27 1.27)
				)
			)
		)
		(property "Value" ""
			(at 0 0 90)
			(layer "F.Fab")
			(effects
				(font
					(size 1.27 1.27)
				)
			)
		)
		(duplicate_pad_numbers_are_jumpers no)
		(fp_line
			(start 0.7874 -0.4064)
			(end 0.7874 0.4064)
			(stroke
				(width 0.1524)
				(type default)
			)
			(layer "F.SilkS")
		)
		(fp_line
			(start -0.7874 -0.4064)
			(end 0.7874 -0.4064)
			(stroke
				(width 0.1524)
				(type default)
			)
			(layer "F.SilkS")
		)
		(fp_line
			(start 0.7874 0.4064)
			(end -0.7874 0.4064)
			(stroke
				(width 0.1524)
				(type default)
			)
			(layer "F.SilkS")
		)
		(fp_line
			(start -0.7874 0.4064)
			(end -0.7874 -0.4064)
			(stroke
				(width 0.1524)
				(type default)
			)
			(layer "F.SilkS")
		)
		(fp_line
			(start -0.12065 -0.305054)
			(end -0.12065 -0.2794)
			(stroke
				(width 0.1)
				(type default)
			)
			(layer "F.Fab")
		)
		(fp_line
			(start -0.67945 -0.305054)
			(end -0.12065 -0.305054)
			(stroke
				(width 0.1)
				(type default)
			)
			(layer "F.Fab")
		)
		(fp_line
			(start 0.67945 -0.3048)
			(end 0.67945 0.3048)
			(stroke
				(width 0.1)
				(type default)
			)
			(layer "F.Fab")
		)
		(fp_line
			(start 0.12065 -0.3048)
			(end 0.67945 -0.3048)
			(stroke
				(width 0.1)
				(type default)
			)
			(layer "F.Fab")
		)
		(fp_line
			(start 0.12065 -0.2794)
			(end 0.12065 -0.3048)
			(stroke
				(width 0.1)
				(type default)
			)
			(layer "F.Fab")
		)
		(fp_line
			(start -0.12065 -0.2794)
			(end 0.12065 -0.2794)
			(stroke
				(width 0.1)
				(type default)
			)
			(layer "F.Fab")
		)
		(fp_line
			(start 0.120396 0.2794)
			(end -0.12065 0.2794)
			(stroke
				(width 0.1)
				(type default)
			)
			(layer "F.Fab")
		)
		(fp_line
			(start -0.12065 0.2794)
			(end -0.12065 0.3048)
			(stroke
				(width 0.1)
				(type default)
			)
			(layer "F.Fab")
		)
		(fp_line
			(start 0.67945 0.3048)
			(end 0.120396 0.3048)
			(stroke
				(width 0.1)
				(type default)
			)
			(layer "F.Fab")
		)
		(fp_line
			(start 0.120396 0.3048)
			(end 0.120396 0.2794)
			(stroke
				(width 0.1)
				(type default)
			)
			(layer "F.Fab")
		)
		(fp_line
			(start -0.12065 0.3048)
			(end -0.67945 0.3048)
			(stroke
				(width 0.1)
				(type default)
			)
			(layer "F.Fab")
		)
		(fp_line
			(start -0.67945 0.3048)
			(end -0.67945 -0.305054)
			(stroke
				(width 0.1)
				(type default)
			)
			(layer "F.Fab")
		)
		(pad "1" smd circle
			(at -0.40005 0 90)
			(size 0 0)
			(layers "F.Cu" "F.Mask" "F.Paste")
			(net "P0V9_RETIMER_CPU1_EN")
		)
		(pad "2" smd circle
			(at 0.40005 0 90)
			(size 0 0)
			(layers "F.Cu" "F.Mask" "F.Paste")
			(net "P0V9_RETIMER_CPU1_EN0_R")
		)
	)
	(footprint ""
		(layer "F.Cu")
		(at 436.224172 -32.173418 90)
		(property "Reference" "R3872"
			(at 0 0 90)
			(layer "F.SilkS")
			(hide yes)
			(effects
				(font
					(size 1.27 1.27)
				)
			)
		)
		(property "Value" ""
			(at 0 0 90)
			(layer "F.Fab")
			(effects
				(font
					(size 1.27 1.27)
				)
			)
		)
		(duplicate_pad_numbers_are_jumpers no)
		(fp_line
			(start 0.7874 -0.4064)
			(end 0.7874 0.4064)
			(stroke
				(width 0.1524)
				(type default)
			)
			(layer "F.SilkS")
		)
		(fp_line
			(start -0.7874 -0.4064)
			(end 0.7874 -0.4064)
			(stroke
				(width 0.1524)
				(type default)
			)
			(layer "F.SilkS")
		)
		(fp_line
			(start 0.7874 0.4064)
			(end -0.7874 0.4064)
			(stroke
				(width 0.1524)
				(type default)
			)
			(layer "F.SilkS")
		)
		(fp_line
			(start -0.7874 0.4064)
			(end -0.7874 -0.4064)
			(stroke
				(width 0.1524)
				(type default)
			)
			(layer "F.SilkS")
		)
		(fp_line
			(start -0.12065 -0.305054)
			(end -0.12065 -0.2794)
			(stroke
				(width 0.1)
				(type default)
			)
			(layer "F.Fab")
		)
		(fp_line
			(start -0.67945 -0.305054)
			(end -0.12065 -0.305054)
			(stroke
				(width 0.1)
				(type default)
			)
			(layer "F.Fab")
		)
		(fp_line
			(start 0.67945 -0.3048)
			(end 0.67945 0.3048)
			(stroke
				(width 0.1)
				(type default)
			)
			(layer "F.Fab")
		)
		(fp_line
			(start 0.12065 -0.3048)
			(end 0.67945 -0.3048)
			(stroke
				(width 0.1)
				(type default)
			)
			(layer "F.Fab")
		)
		(fp_line
			(start 0.12065 -0.2794)
			(end 0.12065 -0.3048)
			(stroke
				(width 0.1)
				(type default)
			)
			(layer "F.Fab")
		)
		(fp_line
			(start -0.12065 -0.2794)
			(end 0.12065 -0.2794)
			(stroke
				(width 0.1)
				(type default)
			)
			(layer "F.Fab")
		)
		(fp_line
			(start 0.120396 0.2794)
			(end -0.12065 0.2794)
			(stroke
				(width 0.1)
				(type default)
			)
			(layer "F.Fab")
		)
		(fp_line
			(start -0.12065 0.2794)
			(end -0.12065 0.3048)
			(stroke
				(width 0.1)
				(type default)
			)
			(layer "F.Fab")
		)
		(fp_line
			(start 0.67945 0.3048)
			(end 0.120396 0.3048)
			(stroke
				(width 0.1)
				(type default)
			)
			(layer "F.Fab")
		)
		(fp_line
			(start 0.120396 0.3048)
			(end 0.120396 0.2794)
			(stroke
				(width 0.1)
				(type default)
			)
			(layer "F.Fab")
		)
		(fp_line
			(start -0.12065 0.3048)
			(end -0.67945 0.3048)
			(stroke
				(width 0.1)
				(type default)
			)
			(layer "F.Fab")
		)
		(fp_line
			(start -0.67945 0.3048)
			(end -0.67945 -0.305054)
			(stroke
				(width 0.1)
				(type default)
			)
			(layer "F.Fab")
		)
		(pad "1" smd circle
			(at -0.40005 0 90)
			(size 0 0)
			(layers "F.Cu" "F.Mask" "F.Paste")
			(net "P12V_OCP_IMON_1")
		)
		(pad "2" smd circle
			(at 0.40005 0 90)
			(size 0 0)
			(layers "F.Cu" "F.Mask" "F.Paste")
			(net "P12V_OCP_SFF_ISENSE_MPS_TIC")
		)
	)
	(footprint ""
		(layer "F.Cu")
		(at 428.276766 -348.135956 180)
		(property "Reference" "PC168"
			(at 0 0 180)
			(layer "F.SilkS")
			(hide yes)
			(effects
				(font
					(size 1.27 1.27)
				)
			)
		)
		(property "Value" ""
			(at 0 0 180)
			(layer "F.Fab")
			(effects
				(font
					(size 1.27 1.27)
				)
			)
		)
		(duplicate_pad_numbers_are_jumpers no)
		(fp_line
			(start 0.7874 0.4064)
			(end -0.7874 0.4064)
			(stroke
				(width 0.1524)
				(type default)
			)
			(layer "F.SilkS")
		)
		(fp_line
			(start 0.7874 -0.4064)
			(end 0.7874 0.4064)
			(stroke
				(width 0.1524)
				(type default)
			)
			(layer "F.SilkS")
		)
		(fp_line
			(start -0.7874 0.4064)
			(end -0.7874 -0.4064)
			(stroke
				(width 0.1524)
				(type default)
			)
			(layer "F.SilkS")
		)
		(fp_line
			(start -0.7874 -0.4064)
			(end 0.7874 -0.4064)
			(stroke
				(width 0.1524)
				(type default)
			)
			(layer "F.SilkS")
		)
		(fp_line
			(start 0.67945 0.3048)
			(end 0.120396 0.3048)
			(stroke
				(width 0.1)
				(type default)
			)
			(layer "F.Fab")
		)
		(fp_line
			(start 0.67945 -0.3048)
			(end 0.67945 0.3048)
			(stroke
				(width 0.1)
				(type default)
			)
			(layer "F.Fab")
		)
		(fp_line
			(start 0.12065 -0.2794)
			(end 0.12065 -0.3048)
			(stroke
				(width 0.1)
				(type default)
			)
			(layer "F.Fab")
		)
		(fp_line
			(start 0.12065 -0.3048)
			(end 0.67945 -0.3048)
			(stroke
				(width 0.1)
				(type default)
			)
			(layer "F.Fab")
		)
		(fp_line
			(start 0.120396 0.3048)
			(end 0.120396 0.2794)
			(stroke
				(width 0.1)
				(type default)
			)
			(layer "F.Fab")
		)
		(fp_line
			(start 0.120396 0.2794)
			(end -0.12065 0.2794)
			(stroke
				(width 0.1)
				(type default)
			)
			(layer "F.Fab")
		)
		(fp_line
			(start -0.12065 0.3048)
			(end -0.67945 0.3048)
			(stroke
				(width 0.1)
				(type default)
			)
			(layer "F.Fab")
		)
		(fp_line
			(start -0.12065 0.2794)
			(end -0.12065 0.3048)
			(stroke
				(width 0.1)
				(type default)
			)
			(layer "F.Fab")
		)
		(fp_line
			(start -0.12065 -0.2794)
			(end 0.12065 -0.2794)
			(stroke
				(width 0.1)
				(type default)
			)
			(layer "F.Fab")
		)
		(fp_line
			(start -0.12065 -0.305054)
			(end -0.12065 -0.2794)
			(stroke
				(width 0.1)
				(type default)
			)
			(layer "F.Fab")
		)
		(fp_line
			(start -0.67945 0.3048)
			(end -0.67945 -0.305054)
			(stroke
				(width 0.1)
				(type default)
			)
			(layer "F.Fab")
		)
		(fp_line
			(start -0.67945 -0.305054)
			(end -0.12065 -0.305054)
			(stroke
				(width 0.1)
				(type default)
			)
			(layer "F.Fab")
		)
		(pad "1" smd circle
			(at -0.40005 0 180)
			(size 0 0)
			(layers "F.Cu" "F.Mask" "F.Paste")
			(net "SW_PVDD11_S3_P0_SW2")
		)
		(pad "2" smd circle
			(at 0.40005 0 180)
			(size 0 0)
			(layers "F.Cu" "F.Mask" "F.Paste")
			(net "SW_PVDD11_S3_P0_SW2_RC")
		)
	)
	(footprint ""
		(layer "F.Cu")
		(at 255.37033 -55.860442 90)
		(property "Reference" "PR3951"
			(at 0 0 90)
			(layer "F.SilkS")
			(hide yes)
			(effects
				(font
					(size 1.27 1.27)
				)
			)
		)
		(property "Value" ""
			(at 0 0 90)
			(layer "F.Fab")
			(effects
				(font
					(size 1.27 1.27)
				)
			)
		)
		(duplicate_pad_numbers_are_jumpers no)
		(fp_line
			(start 0.7874 -0.4064)
			(end 0.7874 0.4064)
			(stroke
				(width 0.1524)
				(type default)
			)
			(layer "F.SilkS")
		)
		(fp_line
			(start -0.7874 -0.4064)
			(end 0.7874 -0.4064)
			(stroke
				(width 0.1524)
				(type default)
			)
			(layer "F.SilkS")
		)
		(fp_line
			(start 0.7874 0.4064)
			(end -0.7874 0.4064)
			(stroke
				(width 0.1524)
				(type default)
			)
			(layer "F.SilkS")
		)
		(fp_line
			(start -0.7874 0.4064)
			(end -0.7874 -0.4064)
			(stroke
				(width 0.1524)
				(type default)
			)
			(layer "F.SilkS")
		)
		(fp_line
			(start -0.12065 -0.305054)
			(end -0.12065 -0.2794)
			(stroke
				(width 0.1)
				(type default)
			)
			(layer "F.Fab")
		)
		(fp_line
			(start -0.67945 -0.305054)
			(end -0.12065 -0.305054)
			(stroke
				(width 0.1)
				(type default)
			)
			(layer "F.Fab")
		)
		(fp_line
			(start 0.67945 -0.3048)
			(end 0.67945 0.3048)
			(stroke
				(width 0.1)
				(type default)
			)
			(layer "F.Fab")
		)
		(fp_line
			(start 0.12065 -0.3048)
			(end 0.67945 -0.3048)
			(stroke
				(width 0.1)
				(type default)
			)
			(layer "F.Fab")
		)
		(fp_line
			(start 0.12065 -0.2794)
			(end 0.12065 -0.3048)
			(stroke
				(width 0.1)
				(type default)
			)
			(layer "F.Fab")
		)
		(fp_line
			(start -0.12065 -0.2794)
			(end 0.12065 -0.2794)
			(stroke
				(width 0.1)
				(type default)
			)
			(layer "F.Fab")
		)
		(fp_line
			(start 0.120396 0.2794)
			(end -0.12065 0.2794)
			(stroke
				(width 0.1)
				(type default)
			)
			(layer "F.Fab")
		)
		(fp_line
			(start -0.12065 0.2794)
			(end -0.12065 0.3048)
			(stroke
				(width 0.1)
				(type default)
			)
			(layer "F.Fab")
		)
		(fp_line
			(start 0.67945 0.3048)
			(end 0.120396 0.3048)
			(stroke
				(width 0.1)
				(type default)
			)
			(layer "F.Fab")
		)
		(fp_line
			(start 0.120396 0.3048)
			(end 0.120396 0.2794)
			(stroke
				(width 0.1)
				(type default)
			)
			(layer "F.Fab")
		)
		(fp_line
			(start -0.12065 0.3048)
			(end -0.67945 0.3048)
			(stroke
				(width 0.1)
				(type default)
			)
			(layer "F.Fab")
		)
		(fp_line
			(start -0.67945 0.3048)
			(end -0.67945 -0.305054)
			(stroke
				(width 0.1)
				(type default)
			)
			(layer "F.Fab")
		)
		(pad "1" smd circle
			(at -0.40005 0 90)
			(size 0 0)
			(layers "F.Cu" "F.Mask" "F.Paste")
			(net "P12V_E1S_FLTB_0")
		)
		(pad "2" smd circle
			(at 0.40005 0 90)
			(size 0 0)
			(layers "F.Cu" "F.Mask" "F.Paste")
			(net "P3V3_AUX")
		)
	)
	(footprint ""
		(layer "F.Cu")
		(at 331.37602 -337.638898 90)
		(property "Reference" "PC79"
			(at 0 0 90)
			(layer "F.SilkS")
			(hide yes)
			(effects
				(font
					(size 1.27 1.27)
				)
			)
		)
		(property "Value" ""
			(at 0 0 90)
			(layer "F.Fab")
			(effects
				(font
					(size 1.27 1.27)
				)
			)
		)
		(duplicate_pad_numbers_are_jumpers no)
		(fp_line
			(start 0.7874 -0.4064)
			(end 0.7874 0.4064)
			(stroke
				(width 0.1524)
				(type default)
			)
			(layer "F.SilkS")
		)
		(fp_line
			(start -0.7874 -0.4064)
			(end 0.7874 -0.4064)
			(stroke
				(width 0.1524)
				(type default)
			)
			(layer "F.SilkS")
		)
		(fp_line
			(start 0.7874 0.4064)
			(end 0.435102 0.4064)
			(stroke
				(width 0.1524)
				(type default)
			)
			(layer "F.SilkS")
		)
		(fp_line
			(start -0.225298 0.4064)
			(end -0.7874 0.4064)
			(stroke
				(width 0.1524)
				(type default)
			)
			(layer "F.SilkS")
		)
		(fp_line
			(start -0.7874 0.4064)
			(end -0.7874 -0.4064)
			(stroke
				(width 0.1524)
				(type default)
			)
			(layer "F.SilkS")
		)
		(fp_line
			(start -0.12065 -0.305054)
			(end -0.12065 -0.2794)
			(stroke
				(width 0.1)
				(type default)
			)
			(layer "F.Fab")
		)
		(fp_line
			(start -0.67945 -0.305054)
			(end -0.12065 -0.305054)
			(stroke
				(width 0.1)
				(type default)
			)
			(layer "F.Fab")
		)
		(fp_line
			(start 0.67945 -0.3048)
			(end 0.67945 0.3048)
			(stroke
				(width 0.1)
				(type default)
			)
			(layer "F.Fab")
		)
		(fp_line
			(start 0.12065 -0.3048)
			(end 0.67945 -0.3048)
			(stroke
				(width 0.1)
				(type default)
			)
			(layer "F.Fab")
		)
		(fp_line
			(start 0.12065 -0.2794)
			(end 0.12065 -0.3048)
			(stroke
				(width 0.1)
				(type default)
			)
			(layer "F.Fab")
		)
		(fp_line
			(start -0.12065 -0.2794)
			(end 0.12065 -0.2794)
			(stroke
				(width 0.1)
				(type default)
			)
			(layer "F.Fab")
		)
		(fp_line
			(start 0.120396 0.2794)
			(end -0.12065 0.2794)
			(stroke
				(width 0.1)
				(type default)
			)
			(layer "F.Fab")
		)
		(fp_line
			(start -0.12065 0.2794)
			(end -0.12065 0.3048)
			(stroke
				(width 0.1)
				(type default)
			)
			(layer "F.Fab")
		)
		(fp_line
			(start 0.67945 0.3048)
			(end 0.120396 0.3048)
			(stroke
				(width 0.1)
				(type default)
			)
			(layer "F.Fab")
		)
		(fp_line
			(start 0.120396 0.3048)
			(end 0.120396 0.2794)
			(stroke
				(width 0.1)
				(type default)
			)
			(layer "F.Fab")
		)
		(fp_line
			(start -0.12065 0.3048)
			(end -0.67945 0.3048)
			(stroke
				(width 0.1)
				(type default)
			)
			(layer "F.Fab")
		)
		(fp_line
			(start -0.67945 0.3048)
			(end -0.67945 -0.305054)
			(stroke
				(width 0.1)
				(type default)
			)
			(layer "F.Fab")
		)
		(pad "1" smd circle
			(at -0.40005 0 90)
			(size 0 0)
			(layers "F.Cu" "F.Mask" "F.Paste")
			(net "PVDDCR_CPU1_P0_VCC1")
		)
		(pad "2" smd circle
			(at 0.40005 0 90)
			(size 0 0)
			(layers "F.Cu" "F.Mask" "F.Paste")
			(net "GND")
		)
	)
	(footprint ""
		(layer "F.Cu")
		(at 43.265852 -384.66268)
		(property "Reference" "R715"
			(at 0 0 0)
			(layer "F.SilkS")
			(hide yes)
			(effects
				(font
					(size 1.27 1.27)
				)
			)
		)
		(property "Value" ""
			(at 0 0 0)
			(layer "F.Fab")
			(effects
				(font
					(size 1.27 1.27)
				)
			)
		)
		(duplicate_pad_numbers_are_jumpers no)
		(fp_line
			(start -0.32512 -0.175006)
			(end 0.32512 -0.175006)
			(stroke
				(width 0.1)
				(type default)
			)
			(layer "F.Fab")
		)
		(fp_line
			(start -0.32512 0.175006)
			(end -0.32512 -0.175006)
			(stroke
				(width 0.1)
				(type default)
			)
			(layer "F.Fab")
		)
		(fp_line
			(start 0.32512 -0.175006)
			(end 0.32512 0.175006)
			(stroke
				(width 0.1)
				(type default)
			)
			(layer "F.Fab")
		)
		(fp_line
			(start 0.32512 0.175006)
			(end -0.32512 0.175006)
			(stroke
				(width 0.1)
				(type default)
			)
			(layer "F.Fab")
		)
		(pad "1" smd rect
			(at -0.2667 0)
			(size 0.3048 0.381)
			(layers "F.Cu" "F.Mask" "F.Paste")
			(net "GPIO3_RT_CPU1_P0")
		)
		(pad "2" smd rect
			(at 0.2667 0 180)
			(size 0.3048 0.381)
			(layers "F.Cu" "F.Mask" "F.Paste")
			(net "GND")
		)
	)
	(footprint ""
		(layer "F.Cu")
		(at 46.548294 -17.623536 90)
		(property "Reference" "C700"
			(at 0 0 90)
			(layer "F.SilkS")
			(hide yes)
			(effects
				(font
					(size 1.27 1.27)
				)
			)
		)
		(property "Value" ""
			(at 0 0 90)
			(layer "F.Fab")
			(effects
				(font
					(size 1.27 1.27)
				)
			)
		)
		(duplicate_pad_numbers_are_jumpers no)
		(fp_line
			(start 0.299974 -0.150114)
			(end 0.299974 0.150114)
			(stroke
				(width 0.1)
				(type default)
			)
			(layer "F.Fab")
		)
		(fp_line
			(start -0.299974 -0.150114)
			(end 0.299974 -0.150114)
			(stroke
				(width 0.1)
				(type default)
			)
			(layer "F.Fab")
		)
		(fp_line
			(start 0.299974 0.150114)
			(end -0.299974 0.150114)
			(stroke
				(width 0.1)
				(type default)
			)
			(layer "F.Fab")
		)
		(fp_line
			(start -0.299974 0.150114)
			(end -0.299974 -0.150114)
			(stroke
				(width 0.1)
				(type default)
			)
			(layer "F.Fab")
		)
		(pad "1" smd rect
			(at -0.2667 0 90)
			(size 0.3048 0.381)
			(layers "F.Cu" "F.Mask" "F.Paste")
			(net "P5E_CPU1_G1_TX_C_DN<4>")
		)
		(pad "2" smd rect
			(at 0.2667 0 90)
			(size 0.3048 0.381)
			(layers "F.Cu" "F.Mask" "F.Paste")
			(net "P5E_CPU1_G1_TX_DN<4>")
		)
	)
	(footprint ""
		(layer "F.Cu")
		(at 216.9668 -101.92512 180)
		(property "Reference" "C9050"
			(at 0 0 180)
			(layer "F.SilkS")
			(hide yes)
			(effects
				(font
					(size 1.27 1.27)
				)
			)
		)
		(property "Value" ""
			(at 0 0 180)
			(layer "F.Fab")
			(effects
				(font
					(size 1.27 1.27)
				)
			)
		)
		(duplicate_pad_numbers_are_jumpers no)
		(fp_line
			(start 0.7874 0.4064)
			(end -0.7874 0.4064)
			(stroke
				(width 0.1524)
				(type default)
			)
			(layer "F.SilkS")
		)
		(fp_line
			(start 0.7874 -0.4064)
			(end 0.7874 0.4064)
			(stroke
				(width 0.1524)
				(type default)
			)
			(layer "F.SilkS")
		)
		(fp_line
			(start -0.7874 0.4064)
			(end -0.7874 -0.4064)
			(stroke
				(width 0.1524)
				(type default)
			)
			(layer "F.SilkS")
		)
		(fp_line
			(start -0.7874 -0.4064)
			(end 0.7874 -0.4064)
			(stroke
				(width 0.1524)
				(type default)
			)
			(layer "F.SilkS")
		)
		(fp_line
			(start 0.67945 0.3048)
			(end 0.120396 0.3048)
			(stroke
				(width 0.1)
				(type default)
			)
			(layer "F.Fab")
		)
		(fp_line
			(start 0.67945 -0.3048)
			(end 0.67945 0.3048)
			(stroke
				(width 0.1)
				(type default)
			)
			(layer "F.Fab")
		)
		(fp_line
			(start 0.12065 -0.2794)
			(end 0.12065 -0.3048)
			(stroke
				(width 0.1)
				(type default)
			)
			(layer "F.Fab")
		)
		(fp_line
			(start 0.12065 -0.3048)
			(end 0.67945 -0.3048)
			(stroke
				(width 0.1)
				(type default)
			)
			(layer "F.Fab")
		)
		(fp_line
			(start 0.120396 0.3048)
			(end 0.120396 0.2794)
			(stroke
				(width 0.1)
				(type default)
			)
			(layer "F.Fab")
		)
		(fp_line
			(start 0.120396 0.2794)
			(end -0.12065 0.2794)
			(stroke
				(width 0.1)
				(type default)
			)
			(layer "F.Fab")
		)
		(fp_line
			(start -0.12065 0.3048)
			(end -0.67945 0.3048)
			(stroke
				(width 0.1)
				(type default)
			)
			(layer "F.Fab")
		)
		(fp_line
			(start -0.12065 0.2794)
			(end -0.12065 0.3048)
			(stroke
				(width 0.1)
				(type default)
			)
			(layer "F.Fab")
		)
		(fp_line
			(start -0.12065 -0.2794)
			(end 0.12065 -0.2794)
			(stroke
				(width 0.1)
				(type default)
			)
			(layer "F.Fab")
		)
		(fp_line
			(start -0.12065 -0.305054)
			(end -0.12065 -0.2794)
			(stroke
				(width 0.1)
				(type default)
			)
			(layer "F.Fab")
		)
		(fp_line
			(start -0.67945 0.3048)
			(end -0.67945 -0.305054)
			(stroke
				(width 0.1)
				(type default)
			)
			(layer "F.Fab")
		)
		(fp_line
			(start -0.67945 -0.305054)
			(end -0.12065 -0.305054)
			(stroke
				(width 0.1)
				(type default)
			)
			(layer "F.Fab")
		)
		(pad "1" smd circle
			(at -0.40005 0 180)
			(size 0 0)
			(layers "F.Cu" "F.Mask" "F.Paste")
			(net "P3V3_AUX")
		)
		(pad "2" smd circle
			(at 0.40005 0 180)
			(size 0 0)
			(layers "F.Cu" "F.Mask" "F.Paste")
			(net "GND")
		)
	)
	(footprint ""
		(layer "F.Cu")
		(at 302.241458 -114.859308)
		(property "Reference" "R68"
			(at 0 0 0)
			(layer "F.SilkS")
			(hide yes)
			(effects
				(font
					(size 1.27 1.27)
				)
			)
		)
		(property "Value" ""
			(at 0 0 0)
			(layer "F.Fab")
			(effects
				(font
					(size 1.27 1.27)
				)
			)
		)
		(duplicate_pad_numbers_are_jumpers no)
		(fp_line
			(start -0.7874 -0.4064)
			(end 0.7874 -0.4064)
			(stroke
				(width 0.1524)
				(type default)
			)
			(layer "F.SilkS")
		)
		(fp_line
			(start -0.7874 0.4064)
			(end -0.7874 -0.4064)
			(stroke
				(width 0.1524)
				(type default)
			)
			(layer "F.SilkS")
		)
		(fp_line
			(start 0.7874 -0.4064)
			(end 0.7874 0.4064)
			(stroke
				(width 0.1524)
				(type default)
			)
			(layer "F.SilkS")
		)
		(fp_line
			(start 0.7874 0.4064)
			(end -0.7874 0.4064)
			(stroke
				(width 0.1524)
				(type default)
			)
			(layer "F.SilkS")
		)
		(fp_line
			(start -0.67945 -0.305054)
			(end -0.12065 -0.305054)
			(stroke
				(width 0.1)
				(type default)
			)
			(layer "F.Fab")
		)
		(fp_line
			(start -0.67945 0.3048)
			(end -0.67945 -0.305054)
			(stroke
				(width 0.1)
				(type default)
			)
			(layer "F.Fab")
		)
		(fp_line
			(start -0.12065 -0.305054)
			(end -0.12065 -0.2794)
			(stroke
				(width 0.1)
				(type default)
			)
			(layer "F.Fab")
		)
		(fp_line
			(start -0.12065 -0.2794)
			(end 0.12065 -0.2794)
			(stroke
				(width 0.1)
				(type default)
			)
			(layer "F.Fab")
		)
		(fp_line
			(start -0.12065 0.2794)
			(end -0.12065 0.3048)
			(stroke
				(width 0.1)
				(type default)
			)
			(layer "F.Fab")
		)
		(fp_line
			(start -0.12065 0.3048)
			(end -0.67945 0.3048)
			(stroke
				(width 0.1)
				(type default)
			)
			(layer "F.Fab")
		)
		(fp_line
			(start 0.120396 0.2794)
			(end -0.12065 0.2794)
			(stroke
				(width 0.1)
				(type default)
			)
			(layer "F.Fab")
		)
		(fp_line
			(start 0.120396 0.3048)
			(end 0.120396 0.2794)
			(stroke
				(width 0.1)
				(type default)
			)
			(layer "F.Fab")
		)
		(fp_line
			(start 0.12065 -0.3048)
			(end 0.67945 -0.3048)
			(stroke
				(width 0.1)
				(type default)
			)
			(layer "F.Fab")
		)
		(fp_line
			(start 0.12065 -0.2794)
			(end 0.12065 -0.3048)
			(stroke
				(width 0.1)
				(type default)
			)
			(layer "F.Fab")
		)
		(fp_line
			(start 0.67945 -0.3048)
			(end 0.67945 0.3048)
			(stroke
				(width 0.1)
				(type default)
			)
			(layer "F.Fab")
		)
		(fp_line
			(start 0.67945 0.3048)
			(end 0.120396 0.3048)
			(stroke
				(width 0.1)
				(type default)
			)
			(layer "F.Fab")
		)
		(pad "1" smd circle
			(at -0.40005 0)
			(size 0 0)
			(layers "F.Cu" "F.Mask" "F.Paste")
			(net "P3V3_AUX")
		)
		(pad "2" smd circle
			(at 0.40005 0)
			(size 0 0)
			(layers "F.Cu" "F.Mask" "F.Paste")
			(net "CPU_FRU_ADDR0")
		)
	)
	(footprint ""
		(layer "F.Cu")
		(at 188.849 -100.294948 90)
		(property "Reference" "R183"
			(at 0 0 90)
			(layer "F.SilkS")
			(hide yes)
			(effects
				(font
					(size 1.27 1.27)
				)
			)
		)
		(property "Value" ""
			(at 0 0 90)
			(layer "F.Fab")
			(effects
				(font
					(size 1.27 1.27)
				)
			)
		)
		(duplicate_pad_numbers_are_jumpers no)
		(fp_line
			(start 0.7874 -0.4064)
			(end 0.7874 0.4064)
			(stroke
				(width 0.1524)
				(type default)
			)
			(layer "F.SilkS")
		)
		(fp_line
			(start -0.7874 -0.4064)
			(end 0.7874 -0.4064)
			(stroke
				(width 0.1524)
				(type default)
			)
			(layer "F.SilkS")
		)
		(fp_line
			(start 0.7874 0.4064)
			(end -0.7874 0.4064)
			(stroke
				(width 0.1524)
				(type default)
			)
			(layer "F.SilkS")
		)
		(fp_line
			(start -0.7874 0.4064)
			(end -0.7874 -0.4064)
			(stroke
				(width 0.1524)
				(type default)
			)
			(layer "F.SilkS")
		)
		(fp_line
			(start -0.12065 -0.305054)
			(end -0.12065 -0.2794)
			(stroke
				(width 0.1)
				(type default)
			)
			(layer "F.Fab")
		)
		(fp_line
			(start -0.67945 -0.305054)
			(end -0.12065 -0.305054)
			(stroke
				(width 0.1)
				(type default)
			)
			(layer "F.Fab")
		)
		(fp_line
			(start 0.67945 -0.3048)
			(end 0.67945 0.3048)
			(stroke
				(width 0.1)
				(type default)
			)
			(layer "F.Fab")
		)
		(fp_line
			(start 0.12065 -0.3048)
			(end 0.67945 -0.3048)
			(stroke
				(width 0.1)
				(type default)
			)
			(layer "F.Fab")
		)
		(fp_line
			(start 0.12065 -0.2794)
			(end 0.12065 -0.3048)
			(stroke
				(width 0.1)
				(type default)
			)
			(layer "F.Fab")
		)
		(fp_line
			(start -0.12065 -0.2794)
			(end 0.12065 -0.2794)
			(stroke
				(width 0.1)
				(type default)
			)
			(layer "F.Fab")
		)
		(fp_line
			(start 0.120396 0.2794)
			(end -0.12065 0.2794)
			(stroke
				(width 0.1)
				(type default)
			)
			(layer "F.Fab")
		)
		(fp_line
			(start -0.12065 0.2794)
			(end -0.12065 0.3048)
			(stroke
				(width 0.1)
				(type default)
			)
			(layer "F.Fab")
		)
		(fp_line
			(start 0.67945 0.3048)
			(end 0.120396 0.3048)
			(stroke
				(width 0.1)
				(type default)
			)
			(layer "F.Fab")
		)
		(fp_line
			(start 0.120396 0.3048)
			(end 0.120396 0.2794)
			(stroke
				(width 0.1)
				(type default)
			)
			(layer "F.Fab")
		)
		(fp_line
			(start -0.12065 0.3048)
			(end -0.67945 0.3048)
			(stroke
				(width 0.1)
				(type default)
			)
			(layer "F.Fab")
		)
		(fp_line
			(start -0.67945 0.3048)
			(end -0.67945 -0.305054)
			(stroke
				(width 0.1)
				(type default)
			)
			(layer "F.Fab")
		)
		(pad "1" smd circle
			(at -0.40005 0 90)
			(size 0 0)
			(layers "F.Cu" "F.Mask" "F.Paste")
			(net "CPU0_CORETYPE0")
		)
		(pad "2" smd circle
			(at 0.40005 0 90)
			(size 0 0)
			(layers "F.Cu" "F.Mask" "F.Paste")
			(net "FM_CPU0_CORETYPE0")
		)
	)
	(footprint ""
		(layer "F.Cu")
		(at 171.196 -122.646948)
		(property "Reference" "R6030"
			(at 0 0 0)
			(layer "F.SilkS")
			(hide yes)
			(effects
				(font
					(size 1.27 1.27)
				)
			)
		)
		(property "Value" ""
			(at 0 0 0)
			(layer "F.Fab")
			(effects
				(font
					(size 1.27 1.27)
				)
			)
		)
		(duplicate_pad_numbers_are_jumpers no)
		(fp_line
			(start -0.7874 -0.4064)
			(end 0.7874 -0.4064)
			(stroke
				(width 0.1524)
				(type default)
			)
			(layer "F.SilkS")
		)
		(fp_line
			(start -0.7874 0.4064)
			(end -0.7874 -0.4064)
			(stroke
				(width 0.1524)
				(type default)
			)
			(layer "F.SilkS")
		)
		(fp_line
			(start 0.7874 -0.4064)
			(end 0.7874 0.4064)
			(stroke
				(width 0.1524)
				(type default)
			)
			(layer "F.SilkS")
		)
		(fp_line
			(start 0.7874 0.4064)
			(end -0.7874 0.4064)
			(stroke
				(width 0.1524)
				(type default)
			)
			(layer "F.SilkS")
		)
		(fp_line
			(start -0.67945 -0.305054)
			(end -0.12065 -0.305054)
			(stroke
				(width 0.1)
				(type default)
			)
			(layer "F.Fab")
		)
		(fp_line
			(start -0.67945 0.3048)
			(end -0.67945 -0.305054)
			(stroke
				(width 0.1)
				(type default)
			)
			(layer "F.Fab")
		)
		(fp_line
			(start -0.12065 -0.305054)
			(end -0.12065 -0.2794)
			(stroke
				(width 0.1)
				(type default)
			)
			(layer "F.Fab")
		)
		(fp_line
			(start -0.12065 -0.2794)
			(end 0.12065 -0.2794)
			(stroke
				(width 0.1)
				(type default)
			)
			(layer "F.Fab")
		)
		(fp_line
			(start -0.12065 0.2794)
			(end -0.12065 0.3048)
			(stroke
				(width 0.1)
				(type default)
			)
			(layer "F.Fab")
		)
		(fp_line
			(start -0.12065 0.3048)
			(end -0.67945 0.3048)
			(stroke
				(width 0.1)
				(type default)
			)
			(layer "F.Fab")
		)
		(fp_line
			(start 0.120396 0.2794)
			(end -0.12065 0.2794)
			(stroke
				(width 0.1)
				(type default)
			)
			(layer "F.Fab")
		)
		(fp_line
			(start 0.120396 0.3048)
			(end 0.120396 0.2794)
			(stroke
				(width 0.1)
				(type default)
			)
			(layer "F.Fab")
		)
		(fp_line
			(start 0.12065 -0.3048)
			(end 0.67945 -0.3048)
			(stroke
				(width 0.1)
				(type default)
			)
			(layer "F.Fab")
		)
		(fp_line
			(start 0.12065 -0.2794)
			(end 0.12065 -0.3048)
			(stroke
				(width 0.1)
				(type default)
			)
			(layer "F.Fab")
		)
		(fp_line
			(start 0.67945 -0.3048)
			(end 0.67945 0.3048)
			(stroke
				(width 0.1)
				(type default)
			)
			(layer "F.Fab")
		)
		(fp_line
			(start 0.67945 0.3048)
			(end 0.120396 0.3048)
			(stroke
				(width 0.1)
				(type default)
			)
			(layer "F.Fab")
		)
		(pad "1" smd circle
			(at -0.40005 0)
			(size 0 0)
			(layers "F.Cu" "F.Mask" "F.Paste")
			(net "CLK_GEN2_GPU_FPGA_OE_N")
		)
		(pad "2" smd circle
			(at 0.40005 0)
			(size 0 0)
			(layers "F.Cu" "F.Mask" "F.Paste")
			(net "CLK_GEN2_GPU_FPGA_OE_R_N")
		)
	)
	(footprint ""
		(layer "F.Cu")
		(at 327.323958 -193.163952 -90)
		(property "Reference" "R415"
			(at 0 0 270)
			(layer "F.SilkS")
			(hide yes)
			(effects
				(font
					(size 1.27 1.27)
				)
			)
		)
		(property "Value" ""
			(at 0 0 270)
			(layer "F.Fab")
			(effects
				(font
					(size 1.27 1.27)
				)
			)
		)
		(duplicate_pad_numbers_are_jumpers no)
		(fp_line
			(start -0.7874 0.4064)
			(end -0.7874 -0.4064)
			(stroke
				(width 0.1524)
				(type default)
			)
			(layer "F.SilkS")
		)
		(fp_line
			(start 0.7874 0.4064)
			(end -0.7874 0.4064)
			(stroke
				(width 0.1524)
				(type default)
			)
			(layer "F.SilkS")
		)
		(fp_line
			(start -0.7874 -0.4064)
			(end 0.7874 -0.4064)
			(stroke
				(width 0.1524)
				(type default)
			)
			(layer "F.SilkS")
		)
		(fp_line
			(start 0.7874 -0.4064)
			(end 0.7874 0.4064)
			(stroke
				(width 0.1524)
				(type default)
			)
			(layer "F.SilkS")
		)
		(fp_line
			(start -0.67945 0.3048)
			(end -0.67945 -0.305054)
			(stroke
				(width 0.1)
				(type default)
			)
			(layer "F.Fab")
		)
		(fp_line
			(start -0.12065 0.3048)
			(end -0.67945 0.3048)
			(stroke
				(width 0.1)
				(type default)
			)
			(layer "F.Fab")
		)
		(fp_line
			(start 0.120396 0.3048)
			(end 0.120396 0.2794)
			(stroke
				(width 0.1)
				(type default)
			)
			(layer "F.Fab")
		)
		(fp_line
			(start 0.67945 0.3048)
			(end 0.120396 0.3048)
			(stroke
				(width 0.1)
				(type default)
			)
			(layer "F.Fab")
		)
		(fp_line
			(start -0.12065 0.2794)
			(end -0.12065 0.3048)
			(stroke
				(width 0.1)
				(type default)
			)
			(layer "F.Fab")
		)
		(fp_line
			(start 0.120396 0.2794)
			(end -0.12065 0.2794)
			(stroke
				(width 0.1)
				(type default)
			)
			(layer "F.Fab")
		)
		(fp_line
			(start -0.12065 -0.2794)
			(end 0.12065 -0.2794)
			(stroke
				(width 0.1)
				(type default)
			)
			(layer "F.Fab")
		)
		(fp_line
			(start 0.12065 -0.2794)
			(end 0.12065 -0.3048)
			(stroke
				(width 0.1)
				(type default)
			)
			(layer "F.Fab")
		)
		(fp_line
			(start 0.12065 -0.3048)
			(end 0.67945 -0.3048)
			(stroke
				(width 0.1)
				(type default)
			)
			(layer "F.Fab")
		)
		(fp_line
			(start 0.67945 -0.3048)
			(end 0.67945 0.3048)
			(stroke
				(width 0.1)
				(type default)
			)
			(layer "F.Fab")
		)
		(fp_line
			(start -0.67945 -0.305054)
			(end -0.12065 -0.305054)
			(stroke
				(width 0.1)
				(type default)
			)
			(layer "F.Fab")
		)
		(fp_line
			(start -0.12065 -0.305054)
			(end -0.12065 -0.2794)
			(stroke
				(width 0.1)
				(type default)
			)
			(layer "F.Fab")
		)
		(pad "1" smd circle
			(at -0.40005 0 270)
			(size 0 0)
			(layers "F.Cu" "F.Mask" "F.Paste")
			(net "CPU0_XTRIG_L6")
		)
		(pad "2" smd circle
			(at 0.40005 0 270)
			(size 0 0)
			(layers "F.Cu" "F.Mask" "F.Paste")
			(net "PVDD18_S5_P0")
		)
	)
	(footprint ""
		(layer "F.Cu")
		(at 413.928306 -135.41502)
		(property "Reference" "PC1849"
			(at 0 0 0)
			(layer "F.SilkS")
			(hide yes)
			(effects
				(font
					(size 1.27 1.27)
				)
			)
		)
		(property "Value" ""
			(at 0 0 0)
			(layer "F.Fab")
			(effects
				(font
					(size 1.27 1.27)
				)
			)
		)
		(duplicate_pad_numbers_are_jumpers no)
		(fp_line
			(start -1.524 -0.762)
			(end 1.524 -0.762)
			(stroke
				(width 0.1524)
				(type default)
			)
			(layer "F.SilkS")
		)
		(fp_line
			(start -1.524 0.762)
			(end -1.524 -0.762)
			(stroke
				(width 0.1524)
				(type default)
			)
			(layer "F.SilkS")
		)
		(fp_line
			(start 1.524 -0.762)
			(end 1.524 0.762)
			(stroke
				(width 0.1524)
				(type default)
			)
			(layer "F.SilkS")
		)
		(fp_line
			(start 1.524 0.762)
			(end -1.524 0.762)
			(stroke
				(width 0.1524)
				(type default)
			)
			(layer "F.SilkS")
		)
		(fp_line
			(start -1.1049 -0.724916)
			(end -1.1049 0.724916)
			(stroke
				(width 0.1)
				(type default)
			)
			(layer "F.Fab")
		)
		(fp_line
			(start -1.1049 0.724916)
			(end 1.1049 0.724916)
			(stroke
				(width 0.1)
				(type default)
			)
			(layer "F.Fab")
		)
		(fp_line
			(start 1.1049 -0.724916)
			(end -1.1049 -0.724916)
			(stroke
				(width 0.1)
				(type default)
			)
			(layer "F.Fab")
		)
		(fp_line
			(start 1.1049 0.724916)
			(end 1.1049 -0.724916)
			(stroke
				(width 0.1)
				(type default)
			)
			(layer "F.Fab")
		)
		(pad "1" smd rect
			(at -0.889 0 180)
			(size 1.016 1.27)
			(layers "F.Cu" "F.Mask" "F.Paste")
			(net "SW_P5V_AUX_FLT")
		)
		(pad "2" smd rect
			(at 0.889 0 180)
			(size 1.016 1.27)
			(layers "F.Cu" "F.Mask" "F.Paste")
			(net "GND")
		)
	)
	(footprint ""
		(layer "F.Cu")
		(at 69.6976 -390.74598)
		(property "Reference" "R1380"
			(at 0 0 0)
			(layer "F.SilkS")
			(hide yes)
			(effects
				(font
					(size 1.27 1.27)
				)
			)
		)
		(property "Value" ""
			(at 0 0 0)
			(layer "F.Fab")
			(effects
				(font
					(size 1.27 1.27)
				)
			)
		)
		(duplicate_pad_numbers_are_jumpers no)
		(fp_line
			(start -0.32512 -0.175006)
			(end 0.32512 -0.175006)
			(stroke
				(width 0.1)
				(type default)
			)
			(layer "F.Fab")
		)
		(fp_line
			(start -0.32512 0.175006)
			(end -0.32512 -0.175006)
			(stroke
				(width 0.1)
				(type default)
			)
			(layer "F.Fab")
		)
		(fp_line
			(start 0.32512 -0.175006)
			(end 0.32512 0.175006)
			(stroke
				(width 0.1)
				(type default)
			)
			(layer "F.Fab")
		)
		(fp_line
			(start 0.32512 0.175006)
			(end -0.32512 0.175006)
			(stroke
				(width 0.1)
				(type default)
			)
			(layer "F.Fab")
		)
		(pad "1" smd rect
			(at -0.2667 0)
			(size 0.3048 0.381)
			(layers "F.Cu" "F.Mask" "F.Paste")
			(net "JTAG_TRST_RT_CPU1_P0_N")
		)
		(pad "2" smd rect
			(at 0.2667 0 180)
			(size 0.3048 0.381)
			(layers "F.Cu" "F.Mask" "F.Paste")
			(net "GND")
		)
	)
	(footprint ""
		(layer "F.Cu")
		(at 384.7719 -185.748168)
		(property "Reference" "PC180"
			(at 0 0 0)
			(layer "F.SilkS")
			(hide yes)
			(effects
				(font
					(size 1.27 1.27)
				)
			)
		)
		(property "Value" ""
			(at 0 0 0)
			(layer "F.Fab")
			(effects
				(font
					(size 1.27 1.27)
				)
			)
		)
		(duplicate_pad_numbers_are_jumpers no)
		(fp_line
			(start -0.7874 -0.4064)
			(end 0.7874 -0.4064)
			(stroke
				(width 0.1524)
				(type default)
			)
			(layer "F.SilkS")
		)
		(fp_line
			(start -0.7874 0.4064)
			(end -0.7874 -0.4064)
			(stroke
				(width 0.1524)
				(type default)
			)
			(layer "F.SilkS")
		)
		(fp_line
			(start 0.7874 -0.4064)
			(end 0.7874 0.4064)
			(stroke
				(width 0.1524)
				(type default)
			)
			(layer "F.SilkS")
		)
		(fp_line
			(start 0.7874 0.4064)
			(end -0.7874 0.4064)
			(stroke
				(width 0.1524)
				(type default)
			)
			(layer "F.SilkS")
		)
		(fp_line
			(start -0.67945 -0.305054)
			(end -0.12065 -0.305054)
			(stroke
				(width 0.1)
				(type default)
			)
			(layer "F.Fab")
		)
		(fp_line
			(start -0.67945 0.3048)
			(end -0.67945 -0.305054)
			(stroke
				(width 0.1)
				(type default)
			)
			(layer "F.Fab")
		)
		(fp_line
			(start -0.12065 -0.305054)
			(end -0.12065 -0.2794)
			(stroke
				(width 0.1)
				(type default)
			)
			(layer "F.Fab")
		)
		(fp_line
			(start -0.12065 -0.2794)
			(end 0.12065 -0.2794)
			(stroke
				(width 0.1)
				(type default)
			)
			(layer "F.Fab")
		)
		(fp_line
			(start -0.12065 0.2794)
			(end -0.12065 0.3048)
			(stroke
				(width 0.1)
				(type default)
			)
			(layer "F.Fab")
		)
		(fp_line
			(start -0.12065 0.3048)
			(end -0.67945 0.3048)
			(stroke
				(width 0.1)
				(type default)
			)
			(layer "F.Fab")
		)
		(fp_line
			(start 0.120396 0.2794)
			(end -0.12065 0.2794)
			(stroke
				(width 0.1)
				(type default)
			)
			(layer "F.Fab")
		)
		(fp_line
			(start 0.120396 0.3048)
			(end 0.120396 0.2794)
			(stroke
				(width 0.1)
				(type default)
			)
			(layer "F.Fab")
		)
		(fp_line
			(start 0.12065 -0.3048)
			(end 0.67945 -0.3048)
			(stroke
				(width 0.1)
				(type default)
			)
			(layer "F.Fab")
		)
		(fp_line
			(start 0.12065 -0.2794)
			(end 0.12065 -0.3048)
			(stroke
				(width 0.1)
				(type default)
			)
			(layer "F.Fab")
		)
		(fp_line
			(start 0.67945 -0.3048)
			(end 0.67945 0.3048)
			(stroke
				(width 0.1)
				(type default)
			)
			(layer "F.Fab")
		)
		(fp_line
			(start 0.67945 0.3048)
			(end 0.120396 0.3048)
			(stroke
				(width 0.1)
				(type default)
			)
			(layer "F.Fab")
		)
		(pad "1" smd circle
			(at -0.40005 0)
			(size 0 0)
			(layers "F.Cu" "F.Mask" "F.Paste")
			(net "SW_PVDDCR_CPU0_P0_SW3")
		)
		(pad "2" smd circle
			(at 0.40005 0)
			(size 0 0)
			(layers "F.Cu" "F.Mask" "F.Paste")
			(net "SW_PVDDCR_CPU0_P0_SW3_RC")
		)
	)
	(footprint ""
		(layer "F.Cu")
		(at 414.418018 -255.560068 180)
		(property "Reference" "J16"
			(at 1.474216 81.889092 0)
			(unlocked yes)
			(layer "F.SilkS")
			(effects
				(font
					(size 0.7874 0.5842)
					(thickness 0.1524)
				)
			)
		)
		(property "Value" ""
			(at 0 0 180)
			(layer "F.Fab")
			(effects
				(font
					(size 1.27 1.27)
				)
			)
		)
		(duplicate_pad_numbers_are_jumpers no)
		(fp_line
			(start 3.24993 81.000092)
			(end -3.24993 81.000092)
			(stroke
				(width 0.1524)
				(type default)
			)
			(layer "F.SilkS")
		)
		(fp_line
			(start 3.24993 62.574932)
			(end 3.24993 81.000092)
			(stroke
				(width 0.1524)
				(type default)
			)
			(layer "F.SilkS")
		)
		(fp_line
			(start 3.24993 -76.490068)
			(end 3.24993 -58.202068)
			(stroke
				(width 0.1524)
				(type default)
			)
			(layer "F.SilkS")
		)
		(fp_line
			(start -3.24993 81.000092)
			(end -3.24993 80.608932)
			(stroke
				(width 0.1524)
				(type default)
			)
			(layer "F.SilkS")
		)
		(fp_line
			(start -3.24993 72.861932)
			(end -3.24993 -76.490068)
			(stroke
				(width 0.1524)
				(type default)
			)
			(layer "F.SilkS")
		)
		(fp_line
			(start -3.24993 72.499982)
			(end 3.24993 72.499982)
			(stroke
				(width 0.1524)
				(type default)
			)
			(layer "F.SilkS")
		)
		(fp_line
			(start -3.24993 -72.499982)
			(end 3.24993 -72.499982)
			(stroke
				(width 0.1524)
				(type default)
			)
			(layer "F.SilkS")
		)
		(fp_poly
			(pts
				(xy -3.792728 -64.502538) (xy -3.374136 -63.929006) (xy -4.084066 -63.938404)
			)
			(stroke
				(width 0)
				(type default)
			)
			(fill yes)
			(layer "F.SilkS")
		)
		(fp_line
			(start 3.24993 81.000092)
			(end -3.24993 81.000092)
			(stroke
				(width 0.1)
				(type default)
			)
			(layer "F.Fab")
		)
		(fp_line
			(start 3.24993 -81.000092)
			(end 3.24993 81.000092)
			(stroke
				(width 0.1)
				(type default)
			)
			(layer "F.Fab")
		)
		(fp_line
			(start -3.24993 81.000092)
			(end -3.24993 -81.000092)
			(stroke
				(width 0.1)
				(type default)
			)
			(layer "F.Fab")
		)
		(fp_line
			(start -3.24993 72.499982)
			(end 3.24993 72.499982)
			(stroke
				(width 0.1)
				(type default)
			)
			(layer "F.Fab")
		)
		(fp_line
			(start -3.24993 71.000112)
			(end 3.24993 71.000112)
			(stroke
				(width 0.1)
				(type default)
			)
			(layer "F.Fab")
		)
		(fp_line
			(start -3.24993 -71.000112)
			(end 3.24993 -71.000112)
			(stroke
				(width 0.1)
				(type default)
			)
			(layer "F.Fab")
		)
		(fp_line
			(start -3.24993 -72.499982)
			(end 3.24993 -72.499982)
			(stroke
				(width 0.1)
				(type default)
			)
			(layer "F.Fab")
		)
		(fp_line
			(start -3.24993 -81.000092)
			(end 3.24993 -81.000092)
			(stroke
				(width 0.1)
				(type default)
			)
			(layer "F.Fab")
		)
		(fp_poly
			(pts
				(xy -3.41503 -63.324994) (xy -4.43103 -62.816994) (xy -4.43103 -63.832994)
			)
			(stroke
				(width 0)
				(type default)
			)
			(fill yes)
			(layer "F.Fab")
		)
		(pad "1" smd rect
			(at -2.050034 -63.324994 90)
			(size 0.519938 1.4986)
			(layers "F.Cu" "F.Mask" "F.Paste")
			(net "P12V_MEM_CPU0")
		)
		(pad "2" smd rect
			(at -2.050034 -62.47511 90)
			(size 0.519938 1.4986)
			(layers "F.Cu" "F.Mask" "F.Paste")
			(net "Net_2333")
		)
		(pad "3" smd rect
			(at -2.050034 -61.624972 90)
			(size 0.519938 1.4986)
			(layers "F.Cu" "F.Mask" "F.Paste")
			(net "P3V3_AUX")
		)
		(pad "4" smd rect
			(at -2.050034 -60.775088 90)
			(size 0.519938 1.4986)
			(layers "F.Cu" "F.Mask" "F.Paste")
			(net "I3C_SPD_DDRG_CPU0_SCL")
		)
		(pad "5" smd rect
			(at -2.050034 -59.92495 90)
			(size 0.519938 1.4986)
			(layers "F.Cu" "F.Mask" "F.Paste")
			(net "I3C_SPD_DDRG_CPU0_SDA")
		)
		(pad "6" smd rect
			(at -2.050034 -59.075066 90)
			(size 0.519938 1.4986)
			(layers "F.Cu" "F.Mask" "F.Paste")
			(net "GND")
		)
		(pad "7" smd rect
			(at -2.050034 -58.224928 90)
			(size 0.519938 1.4986)
			(layers "F.Cu" "F.Mask" "F.Paste")
			(net "M_G_CPU0_SA_DQ<0>")
		)
		(pad "8" smd rect
			(at -2.050034 -57.375044 90)
			(size 0.519938 1.4986)
			(layers "F.Cu" "F.Mask" "F.Paste")
			(net "GND")
		)
		(pad "9" smd rect
			(at -2.050034 -56.524906 90)
			(size 0.519938 1.4986)
			(layers "F.Cu" "F.Mask" "F.Paste")
			(net "M_G_CPU0_SA_DQ<1>")
		)
		(pad "10" smd rect
			(at -2.050034 -55.675022 90)
			(size 0.519938 1.4986)
			(layers "F.Cu" "F.Mask" "F.Paste")
			(net "GND")
		)
		(pad "11" smd rect
			(at -2.050034 -54.824884 90)
			(size 0.519938 1.4986)
			(layers "F.Cu" "F.Mask" "F.Paste")
			(net "M_G_CPU0_SA_DQS_DP<0>")
		)
		(pad "12" smd rect
			(at -2.050034 -53.975 90)
			(size 0.519938 1.4986)
			(layers "F.Cu" "F.Mask" "F.Paste")
			(net "M_G_CPU0_SA_DQS_DN<0>")
		)
		(pad "13" smd rect
			(at -2.050034 -53.125116 90)
			(size 0.519938 1.4986)
			(layers "F.Cu" "F.Mask" "F.Paste")
			(net "GND")
		)
		(pad "14" smd rect
			(at -2.050034 -52.274978 90)
			(size 0.519938 1.4986)
			(layers "F.Cu" "F.Mask" "F.Paste")
			(net "M_G_CPU0_SA_DQ<4>")
		)
		(pad "15" smd rect
			(at -2.050034 -51.425094 90)
			(size 0.519938 1.4986)
			(layers "F.Cu" "F.Mask" "F.Paste")
			(net "GND")
		)
		(pad "16" smd rect
			(at -2.050034 -50.574956 90)
			(size 0.519938 1.4986)
			(layers "F.Cu" "F.Mask" "F.Paste")
			(net "M_G_CPU0_SA_DQ<5>")
		)
		(pad "17" smd rect
			(at -2.050034 -49.725072 90)
			(size 0.519938 1.4986)
			(layers "F.Cu" "F.Mask" "F.Paste")
			(net "GND")
		)
		(pad "18" smd rect
			(at -2.050034 -48.874934 90)
			(size 0.519938 1.4986)
			(layers "F.Cu" "F.Mask" "F.Paste")
			(net "M_G_CPU0_SA_DQ<8>")
		)
		(pad "19" smd rect
			(at -2.050034 -48.02505 90)
			(size 0.519938 1.4986)
			(layers "F.Cu" "F.Mask" "F.Paste")
			(net "GND")
		)
		(pad "20" smd rect
			(at -2.050034 -47.174912 90)
			(size 0.519938 1.4986)
			(layers "F.Cu" "F.Mask" "F.Paste")
			(net "M_G_CPU0_SA_DQ<9>")
		)
		(pad "21" smd rect
			(at -2.050034 -46.325028 90)
			(size 0.519938 1.4986)
			(layers "F.Cu" "F.Mask" "F.Paste")
			(net "GND")
		)
		(pad "22" smd rect
			(at -2.050034 -45.47489 90)
			(size 0.519938 1.4986)
			(layers "F.Cu" "F.Mask" "F.Paste")
			(net "M_G_CPU0_SA_DQS_DP<1>")
		)
		(pad "23" smd rect
			(at -2.050034 -44.625006 90)
			(size 0.519938 1.4986)
			(layers "F.Cu" "F.Mask" "F.Paste")
			(net "M_G_CPU0_SA_DQS_DN<1>")
		)
		(pad "24" smd rect
			(at -2.050034 -43.775122 90)
			(size 0.519938 1.4986)
			(layers "F.Cu" "F.Mask" "F.Paste")
			(net "GND")
		)
		(pad "25" smd rect
			(at -2.050034 -42.924984 90)
			(size 0.519938 1.4986)
			(layers "F.Cu" "F.Mask" "F.Paste")
			(net "M_G_CPU0_SA_DQ<12>")
		)
		(pad "26" smd rect
			(at -2.050034 -42.0751 90)
			(size 0.519938 1.4986)
			(layers "F.Cu" "F.Mask" "F.Paste")
			(net "GND")
		)
		(pad "27" smd rect
			(at -2.050034 -41.224962 90)
			(size 0.519938 1.4986)
			(layers "F.Cu" "F.Mask" "F.Paste")
			(net "M_G_CPU0_SA_DQ<13>")
		)
		(pad "28" smd rect
			(at -2.050034 -40.375078 90)
			(size 0.519938 1.4986)
			(layers "F.Cu" "F.Mask" "F.Paste")
			(net "GND")
		)
		(pad "29" smd rect
			(at -2.050034 -39.52494 90)
			(size 0.519938 1.4986)
			(layers "F.Cu" "F.Mask" "F.Paste")
			(net "M_G_CPU0_SA_DQ<16>")
		)
		(pad "30" smd rect
			(at -2.050034 -38.675056 90)
			(size 0.519938 1.4986)
			(layers "F.Cu" "F.Mask" "F.Paste")
			(net "GND")
		)
		(pad "31" smd rect
			(at -2.050034 -37.824918 90)
			(size 0.519938 1.4986)
			(layers "F.Cu" "F.Mask" "F.Paste")
			(net "M_G_CPU0_SA_DQ<17>")
		)
		(pad "32" smd rect
			(at -2.050034 -36.975034 90)
			(size 0.519938 1.4986)
			(layers "F.Cu" "F.Mask" "F.Paste")
			(net "GND")
		)
		(pad "33" smd rect
			(at -2.050034 -36.124896 90)
			(size 0.519938 1.4986)
			(layers "F.Cu" "F.Mask" "F.Paste")
			(net "M_G_CPU0_SA_DQS_DP<2>")
		)
		(pad "34" smd rect
			(at -2.050034 -35.275012 90)
			(size 0.519938 1.4986)
			(layers "F.Cu" "F.Mask" "F.Paste")
			(net "M_G_CPU0_SA_DQS_DN<2>")
		)
		(pad "35" smd rect
			(at -2.050034 -34.425128 90)
			(size 0.519938 1.4986)
			(layers "F.Cu" "F.Mask" "F.Paste")
			(net "GND")
		)
		(pad "36" smd rect
			(at -2.050034 -33.57499 90)
			(size 0.519938 1.4986)
			(layers "F.Cu" "F.Mask" "F.Paste")
			(net "M_G_CPU0_SA_DQ<20>")
		)
		(pad "37" smd rect
			(at -2.050034 -32.725106 90)
			(size 0.519938 1.4986)
			(layers "F.Cu" "F.Mask" "F.Paste")
			(net "GND")
		)
		(pad "38" smd rect
			(at -2.050034 -31.874968 90)
			(size 0.519938 1.4986)
			(layers "F.Cu" "F.Mask" "F.Paste")
			(net "M_G_CPU0_SA_DQ<21>")
		)
		(pad "39" smd rect
			(at -2.050034 -31.025084 90)
			(size 0.519938 1.4986)
			(layers "F.Cu" "F.Mask" "F.Paste")
			(net "GND")
		)
		(pad "40" smd rect
			(at -2.050034 -30.174946 90)
			(size 0.519938 1.4986)
			(layers "F.Cu" "F.Mask" "F.Paste")
			(net "M_G_CPU0_SA_DQ<24>")
		)
		(pad "41" smd rect
			(at -2.050034 -29.325062 90)
			(size 0.519938 1.4986)
			(layers "F.Cu" "F.Mask" "F.Paste")
			(net "GND")
		)
		(pad "42" smd rect
			(at -2.050034 -28.474924 90)
			(size 0.519938 1.4986)
			(layers "F.Cu" "F.Mask" "F.Paste")
			(net "M_G_CPU0_SA_DQ<25>")
		)
		(pad "43" smd rect
			(at -2.050034 -27.62504 90)
			(size 0.519938 1.4986)
			(layers "F.Cu" "F.Mask" "F.Paste")
			(net "GND")
		)
		(pad "44" smd rect
			(at -2.050034 -26.774902 90)
			(size 0.519938 1.4986)
			(layers "F.Cu" "F.Mask" "F.Paste")
			(net "M_G_CPU0_SA_DQS_DP<3>")
		)
		(pad "45" smd rect
			(at -2.050034 -25.925018 90)
			(size 0.519938 1.4986)
			(layers "F.Cu" "F.Mask" "F.Paste")
			(net "M_G_CPU0_SA_DQS_DN<3>")
		)
		(pad "46" smd rect
			(at -2.050034 -25.07488 90)
			(size 0.519938 1.4986)
			(layers "F.Cu" "F.Mask" "F.Paste")
			(net "GND")
		)
		(pad "47" smd rect
			(at -2.050034 -24.224996 90)
			(size 0.519938 1.4986)
			(layers "F.Cu" "F.Mask" "F.Paste")
			(net "M_G_CPU0_SA_DQ<28>")
		)
		(pad "48" smd rect
			(at -2.050034 -23.375112 90)
			(size 0.519938 1.4986)
			(layers "F.Cu" "F.Mask" "F.Paste")
			(net "GND")
		)
		(pad "49" smd rect
			(at -2.050034 -22.524974 90)
			(size 0.519938 1.4986)
			(layers "F.Cu" "F.Mask" "F.Paste")
			(net "M_G_CPU0_SA_DQ<29>")
		)
		(pad "50" smd rect
			(at -2.050034 -21.67509 90)
			(size 0.519938 1.4986)
			(layers "F.Cu" "F.Mask" "F.Paste")
			(net "GND")
		)
		(pad "51" smd rect
			(at -2.050034 -20.824952 90)
			(size 0.519938 1.4986)
			(layers "F.Cu" "F.Mask" "F.Paste")
			(net "M_G_CPU0_SA_CB<0>")
		)
		(pad "52" smd rect
			(at -2.050034 -19.975068 90)
			(size 0.519938 1.4986)
			(layers "F.Cu" "F.Mask" "F.Paste")
			(net "GND")
		)
		(pad "53" smd rect
			(at -2.050034 -19.12493 90)
			(size 0.519938 1.4986)
			(layers "F.Cu" "F.Mask" "F.Paste")
			(net "M_G_CPU0_SA_CB<1>")
		)
		(pad "54" smd rect
			(at -2.050034 -18.275046 90)
			(size 0.519938 1.4986)
			(layers "F.Cu" "F.Mask" "F.Paste")
			(net "GND")
		)
		(pad "55" smd rect
			(at -2.050034 -17.424908 90)
			(size 0.519938 1.4986)
			(layers "F.Cu" "F.Mask" "F.Paste")
			(net "M_G_CPU0_SA_DQS_DP<4>")
		)
		(pad "56" smd rect
			(at -2.050034 -16.575024 90)
			(size 0.519938 1.4986)
			(layers "F.Cu" "F.Mask" "F.Paste")
			(net "M_G_CPU0_SA_DQS_DN<4>")
		)
		(pad "57" smd rect
			(at -2.050034 -15.724886 90)
			(size 0.519938 1.4986)
			(layers "F.Cu" "F.Mask" "F.Paste")
			(net "GND")
		)
		(pad "58" smd rect
			(at -2.050034 -14.875002 90)
			(size 0.519938 1.4986)
			(layers "F.Cu" "F.Mask" "F.Paste")
			(net "M_G_CPU0_SA_CB<4>")
		)
		(pad "59" smd rect
			(at -2.050034 -14.025118 90)
			(size 0.519938 1.4986)
			(layers "F.Cu" "F.Mask" "F.Paste")
			(net "GND")
		)
		(pad "60" smd rect
			(at -2.050034 -13.17498 90)
			(size 0.519938 1.4986)
			(layers "F.Cu" "F.Mask" "F.Paste")
			(net "M_G_CPU0_SA_CB<5>")
		)
		(pad "61" smd rect
			(at -2.050034 -12.325096 90)
			(size 0.519938 1.4986)
			(layers "F.Cu" "F.Mask" "F.Paste")
			(net "GND")
		)
		(pad "62" smd rect
			(at -2.050034 -11.474958 90)
			(size 0.519938 1.4986)
			(layers "F.Cu" "F.Mask" "F.Paste")
			(net "M_G_CPU0_ALERT_N")
		)
		(pad "63" smd rect
			(at -2.050034 -10.625074 90)
			(size 0.519938 1.4986)
			(layers "F.Cu" "F.Mask" "F.Paste")
			(net "GND")
		)
		(pad "64" smd rect
			(at -2.050034 -9.774936 90)
			(size 0.519938 1.4986)
			(layers "F.Cu" "F.Mask" "F.Paste")
			(net "M_G_CPU0_SA_CS_N<0>")
		)
		(pad "65" smd rect
			(at -2.050034 -8.925052 90)
			(size 0.519938 1.4986)
			(layers "F.Cu" "F.Mask" "F.Paste")
			(net "GND")
		)
		(pad "66" smd rect
			(at -2.050034 -8.074914 90)
			(size 0.519938 1.4986)
			(layers "F.Cu" "F.Mask" "F.Paste")
			(net "M_G_CPU0_SA_CA<0>")
		)
		(pad "67" smd rect
			(at -2.050034 -7.22503 90)
			(size 0.519938 1.4986)
			(layers "F.Cu" "F.Mask" "F.Paste")
			(net "GND")
		)
		(pad "68" smd rect
			(at -2.050034 -6.374892 90)
			(size 0.519938 1.4986)
			(layers "F.Cu" "F.Mask" "F.Paste")
			(net "M_G_CPU0_SA_CA<2>")
		)
		(pad "69" smd rect
			(at -2.050034 -5.525008 90)
			(size 0.519938 1.4986)
			(layers "F.Cu" "F.Mask" "F.Paste")
			(net "GND")
		)
		(pad "70" smd rect
			(at -2.050034 -4.675124 90)
			(size 0.519938 1.4986)
			(layers "F.Cu" "F.Mask" "F.Paste")
			(net "M_G_CPU0_SA_CA<4>")
		)
		(pad "71" smd rect
			(at -2.050034 -3.824986 90)
			(size 0.519938 1.4986)
			(layers "F.Cu" "F.Mask" "F.Paste")
			(net "GND")
		)
		(pad "72" smd rect
			(at -2.050034 -2.975102 90)
			(size 0.519938 1.4986)
			(layers "F.Cu" "F.Mask" "F.Paste")
			(net "M_G_CPU0_SA_CA<6>")
		)
		(pad "73" smd rect
			(at -2.050034 -2.124964 90)
			(size 0.519938 1.4986)
			(layers "F.Cu" "F.Mask" "F.Paste")
			(net "GND")
		)
		(pad "74" smd rect
			(at -2.050034 -1.27508 90)
			(size 0.519938 1.4986)
			(layers "F.Cu" "F.Mask" "F.Paste")
			(net "M_G_CPU0_SA_PAR")
		)
		(pad "75" smd rect
			(at -2.050034 -0.424942 90)
			(size 0.519938 1.4986)
			(layers "F.Cu" "F.Mask" "F.Paste")
			(net "GND")
		)
		(pad "76" smd rect
			(at -2.050034 5.525008 90)
			(size 0.519938 1.4986)
			(layers "F.Cu" "F.Mask" "F.Paste")
			(net "M_G_CPU0_SB_CA<0>")
		)
		(pad "77" smd rect
			(at -2.050034 6.374892 90)
			(size 0.519938 1.4986)
			(layers "F.Cu" "F.Mask" "F.Paste")
			(net "GND")
		)
		(pad "78" smd rect
			(at -2.050034 7.22503 90)
			(size 0.519938 1.4986)
			(layers "F.Cu" "F.Mask" "F.Paste")
			(net "M_G_CPU0_SB_CA<2>")
		)
		(pad "79" smd rect
			(at -2.050034 8.074914 90)
			(size 0.519938 1.4986)
			(layers "F.Cu" "F.Mask" "F.Paste")
			(net "GND")
		)
		(pad "80" smd rect
			(at -2.050034 8.925052 90)
			(size 0.519938 1.4986)
			(layers "F.Cu" "F.Mask" "F.Paste")
			(net "M_G_CPU0_SB_CA<4>")
		)
		(pad "81" smd rect
			(at -2.050034 9.774936 90)
			(size 0.519938 1.4986)
			(layers "F.Cu" "F.Mask" "F.Paste")
			(net "GND")
		)
		(pad "82" smd rect
			(at -2.050034 10.625074 90)
			(size 0.519938 1.4986)
			(layers "F.Cu" "F.Mask" "F.Paste")
			(net "M_G_CPU0_SB_CA<6>")
		)
		(pad "83" smd rect
			(at -2.050034 11.474958 90)
			(size 0.519938 1.4986)
			(layers "F.Cu" "F.Mask" "F.Paste")
			(net "GND")
		)
		(pad "84" smd rect
			(at -2.050034 12.325096 90)
			(size 0.519938 1.4986)
			(layers "F.Cu" "F.Mask" "F.Paste")
			(net "M_G_CPU0_SB_CS_N<0>")
		)
		(pad "85" smd rect
			(at -2.050034 13.17498 90)
			(size 0.519938 1.4986)
			(layers "F.Cu" "F.Mask" "F.Paste")
			(net "GND")
		)
		(pad "86" smd rect
			(at -2.050034 14.025118 90)
			(size 0.519938 1.4986)
			(layers "F.Cu" "F.Mask" "F.Paste")
			(net "M_G_CPU0_SA_RSP<0>")
		)
		(pad "87" smd rect
			(at -2.050034 14.875002 90)
			(size 0.519938 1.4986)
			(layers "F.Cu" "F.Mask" "F.Paste")
			(net "M_G_CPU0_SB_RSP<0>")
		)
		(pad "88" smd rect
			(at -2.050034 15.724886 90)
			(size 0.519938 1.4986)
			(layers "F.Cu" "F.Mask" "F.Paste")
			(net "GND")
		)
		(pad "89" smd rect
			(at -2.050034 16.575024 90)
			(size 0.519938 1.4986)
			(layers "F.Cu" "F.Mask" "F.Paste")
			(net "M_G_CPU0_SB_CB<4>")
		)
		(pad "90" smd rect
			(at -2.050034 17.424908 90)
			(size 0.519938 1.4986)
			(layers "F.Cu" "F.Mask" "F.Paste")
			(net "GND")
		)
		(pad "91" smd rect
			(at -2.050034 18.275046 90)
			(size 0.519938 1.4986)
			(layers "F.Cu" "F.Mask" "F.Paste")
			(net "M_G_CPU0_SB_CB<5>")
		)
		(pad "92" smd rect
			(at -2.050034 19.12493 90)
			(size 0.519938 1.4986)
			(layers "F.Cu" "F.Mask" "F.Paste")
			(net "GND")
		)
		(pad "93" smd rect
			(at -2.050034 19.975068 90)
			(size 0.519938 1.4986)
			(layers "F.Cu" "F.Mask" "F.Paste")
			(net "M_G_CPU0_SB_DQS_DP<9>")
		)
		(pad "94" smd rect
			(at -2.050034 20.824952 90)
			(size 0.519938 1.4986)
			(layers "F.Cu" "F.Mask" "F.Paste")
			(net "M_G_CPU0_SB_DQS_DN<9>")
		)
		(pad "95" smd rect
			(at -2.050034 21.67509 90)
			(size 0.519938 1.4986)
			(layers "F.Cu" "F.Mask" "F.Paste")
			(net "GND")
		)
		(pad "96" smd rect
			(at -2.050034 22.524974 90)
			(size 0.519938 1.4986)
			(layers "F.Cu" "F.Mask" "F.Paste")
			(net "M_G_CPU0_SB_CB<0>")
		)
		(pad "97" smd rect
			(at -2.050034 23.375112 90)
			(size 0.519938 1.4986)
			(layers "F.Cu" "F.Mask" "F.Paste")
			(net "GND")
		)
		(pad "98" smd rect
			(at -2.050034 24.224996 90)
			(size 0.519938 1.4986)
			(layers "F.Cu" "F.Mask" "F.Paste")
			(net "M_G_CPU0_SB_CB<1>")
		)
		(pad "99" smd rect
			(at -2.050034 25.07488 90)
			(size 0.519938 1.4986)
			(layers "F.Cu" "F.Mask" "F.Paste")
			(net "GND")
		)
		(pad "100" smd rect
			(at -2.050034 25.925018 90)
			(size 0.519938 1.4986)
			(layers "F.Cu" "F.Mask" "F.Paste")
			(net "M_G_CPU0_SB_DQ<0>")
		)
		(pad "101" smd rect
			(at -2.050034 26.774902 90)
			(size 0.519938 1.4986)
			(layers "F.Cu" "F.Mask" "F.Paste")
			(net "GND")
		)
		(pad "102" smd rect
			(at -2.050034 27.62504 90)
			(size 0.519938 1.4986)
			(layers "F.Cu" "F.Mask" "F.Paste")
			(net "M_G_CPU0_SB_DQ<1>")
		)
		(pad "103" smd rect
			(at -2.050034 28.474924 90)
			(size 0.519938 1.4986)
			(layers "F.Cu" "F.Mask" "F.Paste")
			(net "GND")
		)
		(pad "104" smd rect
			(at -2.050034 29.325062 90)
			(size 0.519938 1.4986)
			(layers "F.Cu" "F.Mask" "F.Paste")
			(net "M_G_CPU0_SB_DQS_DP<0>")
		)
		(pad "105" smd rect
			(at -2.050034 30.174946 90)
			(size 0.519938 1.4986)
			(layers "F.Cu" "F.Mask" "F.Paste")
			(net "M_G_CPU0_SB_DQS_DN<0>")
		)
		(pad "106" smd rect
			(at -2.050034 31.025084 90)
			(size 0.519938 1.4986)
			(layers "F.Cu" "F.Mask" "F.Paste")
			(net "GND")
		)
		(pad "107" smd rect
			(at -2.050034 31.874968 90)
			(size 0.519938 1.4986)
			(layers "F.Cu" "F.Mask" "F.Paste")
			(net "M_G_CPU0_SB_DQ<4>")
		)
		(pad "108" smd rect
			(at -2.050034 32.725106 90)
			(size 0.519938 1.4986)
			(layers "F.Cu" "F.Mask" "F.Paste")
			(net "GND")
		)
		(pad "109" smd rect
			(at -2.050034 33.57499 90)
			(size 0.519938 1.4986)
			(layers "F.Cu" "F.Mask" "F.Paste")
			(net "M_G_CPU0_SB_DQ<5>")
		)
		(pad "110" smd rect
			(at -2.050034 34.425128 90)
			(size 0.519938 1.4986)
			(layers "F.Cu" "F.Mask" "F.Paste")
			(net "GND")
		)
		(pad "111" smd rect
			(at -2.050034 35.275012 90)
			(size 0.519938 1.4986)
			(layers "F.Cu" "F.Mask" "F.Paste")
			(net "M_G_CPU0_SB_DQ<8>")
		)
		(pad "112" smd rect
			(at -2.050034 36.124896 90)
			(size 0.519938 1.4986)
			(layers "F.Cu" "F.Mask" "F.Paste")
			(net "GND")
		)
		(pad "113" smd rect
			(at -2.050034 36.975034 90)
			(size 0.519938 1.4986)
			(layers "F.Cu" "F.Mask" "F.Paste")
			(net "M_G_CPU0_SB_DQ<9>")
		)
		(pad "114" smd rect
			(at -2.050034 37.824918 90)
			(size 0.519938 1.4986)
			(layers "F.Cu" "F.Mask" "F.Paste")
			(net "GND")
		)
		(pad "115" smd rect
			(at -2.050034 38.675056 90)
			(size 0.519938 1.4986)
			(layers "F.Cu" "F.Mask" "F.Paste")
			(net "M_G_CPU0_SB_DQS_DP<1>")
		)
		(pad "116" smd rect
			(at -2.050034 39.52494 90)
			(size 0.519938 1.4986)
			(layers "F.Cu" "F.Mask" "F.Paste")
			(net "M_G_CPU0_SB_DQS_DN<1>")
		)
		(pad "117" smd rect
			(at -2.050034 40.375078 90)
			(size 0.519938 1.4986)
			(layers "F.Cu" "F.Mask" "F.Paste")
			(net "GND")
		)
		(pad "118" smd rect
			(at -2.050034 41.224962 90)
			(size 0.519938 1.4986)
			(layers "F.Cu" "F.Mask" "F.Paste")
			(net "M_G_CPU0_SB_DQ<12>")
		)
		(pad "119" smd rect
			(at -2.050034 42.0751 90)
			(size 0.519938 1.4986)
			(layers "F.Cu" "F.Mask" "F.Paste")
			(net "GND")
		)
		(pad "120" smd rect
			(at -2.050034 42.924984 90)
			(size 0.519938 1.4986)
			(layers "F.Cu" "F.Mask" "F.Paste")
			(net "M_G_CPU0_SB_DQ<13>")
		)
		(pad "121" smd rect
			(at -2.050034 43.775122 90)
			(size 0.519938 1.4986)
			(layers "F.Cu" "F.Mask" "F.Paste")
			(net "GND")
		)
		(pad "122" smd rect
			(at -2.050034 44.625006 90)
			(size 0.519938 1.4986)
			(layers "F.Cu" "F.Mask" "F.Paste")
			(net "M_G_CPU0_SB_DQ<16>")
		)
		(pad "123" smd rect
			(at -2.050034 45.47489 90)
			(size 0.519938 1.4986)
			(layers "F.Cu" "F.Mask" "F.Paste")
			(net "GND")
		)
		(pad "124" smd rect
			(at -2.050034 46.325028 90)
			(size 0.519938 1.4986)
			(layers "F.Cu" "F.Mask" "F.Paste")
			(net "M_G_CPU0_SB_DQ<17>")
		)
		(pad "125" smd rect
			(at -2.050034 47.174912 90)
			(size 0.519938 1.4986)
			(layers "F.Cu" "F.Mask" "F.Paste")
			(net "GND")
		)
		(pad "126" smd rect
			(at -2.050034 48.02505 90)
			(size 0.519938 1.4986)
			(layers "F.Cu" "F.Mask" "F.Paste")
			(net "M_G_CPU0_SB_DQS_DP<2>")
		)
		(pad "127" smd rect
			(at -2.050034 48.874934 90)
			(size 0.519938 1.4986)
			(layers "F.Cu" "F.Mask" "F.Paste")
			(net "M_G_CPU0_SB_DQS_DN<2>")
		)
		(pad "128" smd rect
			(at -2.050034 49.725072 90)
			(size 0.519938 1.4986)
			(layers "F.Cu" "F.Mask" "F.Paste")
			(net "GND")
		)
		(pad "129" smd rect
			(at -2.050034 50.574956 90)
			(size 0.519938 1.4986)
			(layers "F.Cu" "F.Mask" "F.Paste")
			(net "M_G_CPU0_SB_DQ<20>")
		)
		(pad "130" smd rect
			(at -2.050034 51.425094 90)
			(size 0.519938 1.4986)
			(layers "F.Cu" "F.Mask" "F.Paste")
			(net "GND")
		)
		(pad "131" smd rect
			(at -2.050034 52.274978 90)
			(size 0.519938 1.4986)
			(layers "F.Cu" "F.Mask" "F.Paste")
			(net "M_G_CPU0_SB_DQ<21>")
		)
		(pad "132" smd rect
			(at -2.050034 53.125116 90)
			(size 0.519938 1.4986)
			(layers "F.Cu" "F.Mask" "F.Paste")
			(net "GND")
		)
		(pad "133" smd rect
			(at -2.050034 53.975 90)
			(size 0.519938 1.4986)
			(layers "F.Cu" "F.Mask" "F.Paste")
			(net "M_G_CPU0_SB_DQ<24>")
		)
		(pad "134" smd rect
			(at -2.050034 54.824884 90)
			(size 0.519938 1.4986)
			(layers "F.Cu" "F.Mask" "F.Paste")
			(net "GND")
		)
		(pad "135" smd rect
			(at -2.050034 55.675022 90)
			(size 0.519938 1.4986)
			(layers "F.Cu" "F.Mask" "F.Paste")
			(net "M_G_CPU0_SB_DQ<25>")
		)
		(pad "136" smd rect
			(at -2.050034 56.524906 90)
			(size 0.519938 1.4986)
			(layers "F.Cu" "F.Mask" "F.Paste")
			(net "GND")
		)
		(pad "137" smd rect
			(at -2.050034 57.375044 90)
			(size 0.519938 1.4986)
			(layers "F.Cu" "F.Mask" "F.Paste")
			(net "M_G_CPU0_SB_DQS_DP<3>")
		)
		(pad "138" smd rect
			(at -2.050034 58.224928 90)
			(size 0.519938 1.4986)
			(layers "F.Cu" "F.Mask" "F.Paste")
			(net "M_G_CPU0_SB_DQS_DN<3>")
		)
		(pad "139" smd rect
			(at -2.050034 59.075066 90)
			(size 0.519938 1.4986)
			(layers "F.Cu" "F.Mask" "F.Paste")
			(net "GND")
		)
		(pad "140" smd rect
			(at -2.050034 59.92495 90)
			(size 0.519938 1.4986)
			(layers "F.Cu" "F.Mask" "F.Paste")
			(net "M_G_CPU0_SB_DQ<28>")
		)
		(pad "141" smd rect
			(at -2.050034 60.775088 90)
			(size 0.519938 1.4986)
			(layers "F.Cu" "F.Mask" "F.Paste")
			(net "GND")
		)
		(pad "142" smd rect
			(at -2.050034 61.624972 90)
			(size 0.519938 1.4986)
			(layers "F.Cu" "F.Mask" "F.Paste")
			(net "M_G_CPU0_SB_DQ<29>")
		)
		(pad "143" smd rect
			(at -2.050034 62.47511 90)
			(size 0.519938 1.4986)
			(layers "F.Cu" "F.Mask" "F.Paste")
			(net "GND")
		)
		(pad "144" smd rect
			(at -2.050034 63.324994 90)
			(size 0.519938 1.4986)
			(layers "F.Cu" "F.Mask" "F.Paste")
			(net "Net_2334")
		)
		(pad "145" smd rect
			(at 2.050034 -63.324994 90)
			(size 0.519938 1.4986)
			(layers "F.Cu" "F.Mask" "F.Paste")
			(net "P12V_MEM_CPU0")
		)
		(pad "146" smd rect
			(at 2.050034 -62.47511 90)
			(size 0.519938 1.4986)
			(layers "F.Cu" "F.Mask" "F.Paste")
			(net "P12V_MEM_CPU0")
		)
		(pad "147" smd rect
			(at 2.050034 -61.624972 90)
			(size 0.519938 1.4986)
			(layers "F.Cu" "F.Mask" "F.Paste")
			(net "PWRGD_CHG_CPU0_DIMM0")
		)
		(pad "148" smd rect
			(at 2.050034 -60.775088 90)
			(size 0.519938 1.4986)
			(layers "F.Cu" "F.Mask" "F.Paste")
			(net "PD_CHG_CPU0_DIMM0_SAA")
		)
		(pad "149" smd rect
			(at 2.050034 -59.92495 90)
			(size 0.519938 1.4986)
			(layers "F.Cu" "F.Mask" "F.Paste")
			(net "Net_2335")
		)
		(pad "150" smd rect
			(at 2.050034 -59.075066 90)
			(size 0.519938 1.4986)
			(layers "F.Cu" "F.Mask" "F.Paste")
			(net "Net_2336")
		)
		(pad "151" smd rect
			(at 2.050034 -58.224928 90)
			(size 0.519938 1.4986)
			(layers "F.Cu" "F.Mask" "F.Paste")
			(net "GND")
		)
		(pad "152" smd rect
			(at 2.050034 -57.375044 90)
			(size 0.519938 1.4986)
			(layers "F.Cu" "F.Mask" "F.Paste")
			(net "M_G_CPU0_SA_DQ<2>")
		)
		(pad "153" smd rect
			(at 2.050034 -56.524906 90)
			(size 0.519938 1.4986)
			(layers "F.Cu" "F.Mask" "F.Paste")
			(net "GND")
		)
		(pad "154" smd rect
			(at 2.050034 -55.675022 90)
			(size 0.519938 1.4986)
			(layers "F.Cu" "F.Mask" "F.Paste")
			(net "M_G_CPU0_SA_DQ<3>")
		)
		(pad "155" smd rect
			(at 2.050034 -54.824884 90)
			(size 0.519938 1.4986)
			(layers "F.Cu" "F.Mask" "F.Paste")
			(net "GND")
		)
		(pad "156" smd rect
			(at 2.050034 -53.975 90)
			(size 0.519938 1.4986)
			(layers "F.Cu" "F.Mask" "F.Paste")
			(net "M_G_CPU0_SA_DQS_DN<5>")
		)
		(pad "157" smd rect
			(at 2.050034 -53.125116 90)
			(size 0.519938 1.4986)
			(layers "F.Cu" "F.Mask" "F.Paste")
			(net "M_G_CPU0_SA_DQS_DP<5>")
		)
		(pad "158" smd rect
			(at 2.050034 -52.274978 90)
			(size 0.519938 1.4986)
			(layers "F.Cu" "F.Mask" "F.Paste")
			(net "GND")
		)
		(pad "159" smd rect
			(at 2.050034 -51.425094 90)
			(size 0.519938 1.4986)
			(layers "F.Cu" "F.Mask" "F.Paste")
			(net "M_G_CPU0_SA_DQ<6>")
		)
		(pad "160" smd rect
			(at 2.050034 -50.574956 90)
			(size 0.519938 1.4986)
			(layers "F.Cu" "F.Mask" "F.Paste")
			(net "GND")
		)
		(pad "161" smd rect
			(at 2.050034 -49.725072 90)
			(size 0.519938 1.4986)
			(layers "F.Cu" "F.Mask" "F.Paste")
			(net "M_G_CPU0_SA_DQ<7>")
		)
		(pad "162" smd rect
			(at 2.050034 -48.874934 90)
			(size 0.519938 1.4986)
			(layers "F.Cu" "F.Mask" "F.Paste")
			(net "GND")
		)
		(pad "163" smd rect
			(at 2.050034 -48.02505 90)
			(size 0.519938 1.4986)
			(layers "F.Cu" "F.Mask" "F.Paste")
			(net "M_G_CPU0_SA_DQ<10>")
		)
		(pad "164" smd rect
			(at 2.050034 -47.174912 90)
			(size 0.519938 1.4986)
			(layers "F.Cu" "F.Mask" "F.Paste")
			(net "GND")
		)
		(pad "165" smd rect
			(at 2.050034 -46.325028 90)
			(size 0.519938 1.4986)
			(layers "F.Cu" "F.Mask" "F.Paste")
			(net "M_G_CPU0_SA_DQ<11>")
		)
		(pad "166" smd rect
			(at 2.050034 -45.47489 90)
			(size 0.519938 1.4986)
			(layers "F.Cu" "F.Mask" "F.Paste")
			(net "GND")
		)
		(pad "167" smd rect
			(at 2.050034 -44.625006 90)
			(size 0.519938 1.4986)
			(layers "F.Cu" "F.Mask" "F.Paste")
			(net "M_G_CPU0_SA_DQS_DN<6>")
		)
		(pad "168" smd rect
			(at 2.050034 -43.775122 90)
			(size 0.519938 1.4986)
			(layers "F.Cu" "F.Mask" "F.Paste")
			(net "M_G_CPU0_SA_DQS_DP<6>")
		)
		(pad "169" smd rect
			(at 2.050034 -42.924984 90)
			(size 0.519938 1.4986)
			(layers "F.Cu" "F.Mask" "F.Paste")
			(net "GND")
		)
		(pad "170" smd rect
			(at 2.050034 -42.0751 90)
			(size 0.519938 1.4986)
			(layers "F.Cu" "F.Mask" "F.Paste")
			(net "M_G_CPU0_SA_DQ<14>")
		)
		(pad "171" smd rect
			(at 2.050034 -41.224962 90)
			(size 0.519938 1.4986)
			(layers "F.Cu" "F.Mask" "F.Paste")
			(net "GND")
		)
		(pad "172" smd rect
			(at 2.050034 -40.375078 90)
			(size 0.519938 1.4986)
			(layers "F.Cu" "F.Mask" "F.Paste")
			(net "M_G_CPU0_SA_DQ<15>")
		)
		(pad "173" smd rect
			(at 2.050034 -39.52494 90)
			(size 0.519938 1.4986)
			(layers "F.Cu" "F.Mask" "F.Paste")
			(net "GND")
		)
		(pad "174" smd rect
			(at 2.050034 -38.675056 90)
			(size 0.519938 1.4986)
			(layers "F.Cu" "F.Mask" "F.Paste")
			(net "M_G_CPU0_SA_DQ<18>")
		)
		(pad "175" smd rect
			(at 2.050034 -37.824918 90)
			(size 0.519938 1.4986)
			(layers "F.Cu" "F.Mask" "F.Paste")
			(net "GND")
		)
		(pad "176" smd rect
			(at 2.050034 -36.975034 90)
			(size 0.519938 1.4986)
			(layers "F.Cu" "F.Mask" "F.Paste")
			(net "M_G_CPU0_SA_DQ<19>")
		)
		(pad "177" smd rect
			(at 2.050034 -36.124896 90)
			(size 0.519938 1.4986)
			(layers "F.Cu" "F.Mask" "F.Paste")
			(net "GND")
		)
		(pad "178" smd rect
			(at 2.050034 -35.275012 90)
			(size 0.519938 1.4986)
			(layers "F.Cu" "F.Mask" "F.Paste")
			(net "M_G_CPU0_SA_DQS_DN<7>")
		)
		(pad "179" smd rect
			(at 2.050034 -34.425128 90)
			(size 0.519938 1.4986)
			(layers "F.Cu" "F.Mask" "F.Paste")
			(net "M_G_CPU0_SA_DQS_DP<7>")
		)
		(pad "180" smd rect
			(at 2.050034 -33.57499 90)
			(size 0.519938 1.4986)
			(layers "F.Cu" "F.Mask" "F.Paste")
			(net "GND")
		)
		(pad "181" smd rect
			(at 2.050034 -32.725106 90)
			(size 0.519938 1.4986)
			(layers "F.Cu" "F.Mask" "F.Paste")
			(net "M_G_CPU0_SA_DQ<22>")
		)
		(pad "182" smd rect
			(at 2.050034 -31.874968 90)
			(size 0.519938 1.4986)
			(layers "F.Cu" "F.Mask" "F.Paste")
			(net "GND")
		)
		(pad "183" smd rect
			(at 2.050034 -31.025084 90)
			(size 0.519938 1.4986)
			(layers "F.Cu" "F.Mask" "F.Paste")
			(net "M_G_CPU0_SA_DQ<23>")
		)
		(pad "184" smd rect
			(at 2.050034 -30.174946 90)
			(size 0.519938 1.4986)
			(layers "F.Cu" "F.Mask" "F.Paste")
			(net "GND")
		)
		(pad "185" smd rect
			(at 2.050034 -29.325062 90)
			(size 0.519938 1.4986)
			(layers "F.Cu" "F.Mask" "F.Paste")
			(net "M_G_CPU0_SA_DQ<26>")
		)
		(pad "186" smd rect
			(at 2.050034 -28.474924 90)
			(size 0.519938 1.4986)
			(layers "F.Cu" "F.Mask" "F.Paste")
			(net "GND")
		)
		(pad "187" smd rect
			(at 2.050034 -27.62504 90)
			(size 0.519938 1.4986)
			(layers "F.Cu" "F.Mask" "F.Paste")
			(net "M_G_CPU0_SA_DQ<27>")
		)
		(pad "188" smd rect
			(at 2.050034 -26.774902 90)
			(size 0.519938 1.4986)
			(layers "F.Cu" "F.Mask" "F.Paste")
			(net "GND")
		)
		(pad "189" smd rect
			(at 2.050034 -25.925018 90)
			(size 0.519938 1.4986)
			(layers "F.Cu" "F.Mask" "F.Paste")
			(net "M_G_CPU0_SA_DQS_DN<8>")
		)
		(pad "190" smd rect
			(at 2.050034 -25.07488 90)
			(size 0.519938 1.4986)
			(layers "F.Cu" "F.Mask" "F.Paste")
			(net "M_G_CPU0_SA_DQS_DP<8>")
		)
		(pad "191" smd rect
			(at 2.050034 -24.224996 90)
			(size 0.519938 1.4986)
			(layers "F.Cu" "F.Mask" "F.Paste")
			(net "GND")
		)
		(pad "192" smd rect
			(at 2.050034 -23.375112 90)
			(size 0.519938 1.4986)
			(layers "F.Cu" "F.Mask" "F.Paste")
			(net "M_G_CPU0_SA_DQ<30>")
		)
		(pad "193" smd rect
			(at 2.050034 -22.524974 90)
			(size 0.519938 1.4986)
			(layers "F.Cu" "F.Mask" "F.Paste")
			(net "GND")
		)
		(pad "194" smd rect
			(at 2.050034 -21.67509 90)
			(size 0.519938 1.4986)
			(layers "F.Cu" "F.Mask" "F.Paste")
			(net "M_G_CPU0_SA_DQ<31>")
		)
		(pad "195" smd rect
			(at 2.050034 -20.824952 90)
			(size 0.519938 1.4986)
			(layers "F.Cu" "F.Mask" "F.Paste")
			(net "GND")
		)
		(pad "196" smd rect
			(at 2.050034 -19.975068 90)
			(size 0.519938 1.4986)
			(layers "F.Cu" "F.Mask" "F.Paste")
			(net "M_G_CPU0_SA_CB<2>")
		)
		(pad "197" smd rect
			(at 2.050034 -19.12493 90)
			(size 0.519938 1.4986)
			(layers "F.Cu" "F.Mask" "F.Paste")
			(net "GND")
		)
		(pad "198" smd rect
			(at 2.050034 -18.275046 90)
			(size 0.519938 1.4986)
			(layers "F.Cu" "F.Mask" "F.Paste")
			(net "M_G_CPU0_SA_CB<3>")
		)
		(pad "199" smd rect
			(at 2.050034 -17.424908 90)
			(size 0.519938 1.4986)
			(layers "F.Cu" "F.Mask" "F.Paste")
			(net "GND")
		)
		(pad "200" smd rect
			(at 2.050034 -16.575024 90)
			(size 0.519938 1.4986)
			(layers "F.Cu" "F.Mask" "F.Paste")
			(net "M_G_CPU0_SA_DQS_DN<9>")
		)
		(pad "201" smd rect
			(at 2.050034 -15.724886 90)
			(size 0.519938 1.4986)
			(layers "F.Cu" "F.Mask" "F.Paste")
			(net "M_G_CPU0_SA_DQS_DP<9>")
		)
		(pad "202" smd rect
			(at 2.050034 -14.875002 90)
			(size 0.519938 1.4986)
			(layers "F.Cu" "F.Mask" "F.Paste")
			(net "GND")
		)
		(pad "203" smd rect
			(at 2.050034 -14.025118 90)
			(size 0.519938 1.4986)
			(layers "F.Cu" "F.Mask" "F.Paste")
			(net "M_G_CPU0_SA_CB<6>")
		)
		(pad "204" smd rect
			(at 2.050034 -13.17498 90)
			(size 0.519938 1.4986)
			(layers "F.Cu" "F.Mask" "F.Paste")
			(net "GND")
		)
		(pad "205" smd rect
			(at 2.050034 -12.325096 90)
			(size 0.519938 1.4986)
			(layers "F.Cu" "F.Mask" "F.Paste")
			(net "M_G_CPU0_SA_CB<7>")
		)
		(pad "206" smd rect
			(at 2.050034 -11.474958 90)
			(size 0.519938 1.4986)
			(layers "F.Cu" "F.Mask" "F.Paste")
			(net "GND")
		)
		(pad "207" smd rect
			(at 2.050034 -10.625074 90)
			(size 0.519938 1.4986)
			(layers "F.Cu" "F.Mask" "F.Paste")
			(net "M_G_CPU0_RESET_N")
		)
		(pad "208" smd rect
			(at 2.050034 -9.774936 90)
			(size 0.519938 1.4986)
			(layers "F.Cu" "F.Mask" "F.Paste")
			(net "GND")
		)
		(pad "209" smd rect
			(at 2.050034 -8.925052 90)
			(size 0.519938 1.4986)
			(layers "F.Cu" "F.Mask" "F.Paste")
			(net "M_G_CPU0_SA_CS_N<1>")
		)
		(pad "210" smd rect
			(at 2.050034 -8.074914 90)
			(size 0.519938 1.4986)
			(layers "F.Cu" "F.Mask" "F.Paste")
			(net "GND")
		)
		(pad "211" smd rect
			(at 2.050034 -7.22503 90)
			(size 0.519938 1.4986)
			(layers "F.Cu" "F.Mask" "F.Paste")
			(net "M_G_CPU0_SA_CA<1>")
		)
		(pad "212" smd rect
			(at 2.050034 -6.374892 90)
			(size 0.519938 1.4986)
			(layers "F.Cu" "F.Mask" "F.Paste")
			(net "GND")
		)
		(pad "213" smd rect
			(at 2.050034 -5.525008 90)
			(size 0.519938 1.4986)
			(layers "F.Cu" "F.Mask" "F.Paste")
			(net "M_G_CPU0_SA_CA<3>")
		)
		(pad "214" smd rect
			(at 2.050034 -4.675124 90)
			(size 0.519938 1.4986)
			(layers "F.Cu" "F.Mask" "F.Paste")
			(net "GND")
		)
		(pad "215" smd rect
			(at 2.050034 -3.824986 90)
			(size 0.519938 1.4986)
			(layers "F.Cu" "F.Mask" "F.Paste")
			(net "M_G_CPU0_SA_CA<5>")
		)
		(pad "216" smd rect
			(at 2.050034 -2.975102 90)
			(size 0.519938 1.4986)
			(layers "F.Cu" "F.Mask" "F.Paste")
			(net "GND")
		)
		(pad "217" smd rect
			(at 2.050034 -2.124964 90)
			(size 0.519938 1.4986)
			(layers "F.Cu" "F.Mask" "F.Paste")
			(net "M_G_CPU0_CLK_DP<0>")
		)
		(pad "218" smd rect
			(at 2.050034 -1.27508 90)
			(size 0.519938 1.4986)
			(layers "F.Cu" "F.Mask" "F.Paste")
			(net "M_G_CPU0_CLK_DN<0>")
		)
		(pad "219" smd rect
			(at 2.050034 -0.424942 90)
			(size 0.519938 1.4986)
			(layers "F.Cu" "F.Mask" "F.Paste")
			(net "GND")
		)
		(pad "220" smd rect
			(at 2.050034 5.525008 90)
			(size 0.519938 1.4986)
			(layers "F.Cu" "F.Mask" "F.Paste")
			(net "Net_2337")
		)
		(pad "221" smd rect
			(at 2.050034 6.374892 90)
			(size 0.519938 1.4986)
			(layers "F.Cu" "F.Mask" "F.Paste")
			(net "M_G_CPU0_SB_CA<1>")
		)
		(pad "222" smd rect
			(at 2.050034 7.22503 90)
			(size 0.519938 1.4986)
			(layers "F.Cu" "F.Mask" "F.Paste")
			(net "GND")
		)
		(pad "223" smd rect
			(at 2.050034 8.074914 90)
			(size 0.519938 1.4986)
			(layers "F.Cu" "F.Mask" "F.Paste")
			(net "M_G_CPU0_SB_CA<3>")
		)
		(pad "224" smd rect
			(at 2.050034 8.925052 90)
			(size 0.519938 1.4986)
			(layers "F.Cu" "F.Mask" "F.Paste")
			(net "GND")
		)
		(pad "225" smd rect
			(at 2.050034 9.774936 90)
			(size 0.519938 1.4986)
			(layers "F.Cu" "F.Mask" "F.Paste")
			(net "M_G_CPU0_SB_CA<5>")
		)
		(pad "226" smd rect
			(at 2.050034 10.625074 90)
			(size 0.519938 1.4986)
			(layers "F.Cu" "F.Mask" "F.Paste")
			(net "GND")
		)
		(pad "227" smd rect
			(at 2.050034 11.474958 90)
			(size 0.519938 1.4986)
			(layers "F.Cu" "F.Mask" "F.Paste")
			(net "M_G_CPU0_SB_PAR")
		)
		(pad "228" smd rect
			(at 2.050034 12.325096 90)
			(size 0.519938 1.4986)
			(layers "F.Cu" "F.Mask" "F.Paste")
			(net "GND")
		)
		(pad "229" smd rect
			(at 2.050034 13.17498 90)
			(size 0.519938 1.4986)
			(layers "F.Cu" "F.Mask" "F.Paste")
			(net "M_G_CPU0_SB_CS_N<1>")
		)
		(pad "230" smd rect
			(at 2.050034 14.025118 90)
			(size 0.519938 1.4986)
			(layers "F.Cu" "F.Mask" "F.Paste")
			(net "GND")
		)
		(pad "231" smd rect
			(at 2.050034 14.875002 90)
			(size 0.519938 1.4986)
			(layers "F.Cu" "F.Mask" "F.Paste")
			(net "Net_2338")
		)
		(pad "232" smd rect
			(at 2.050034 15.724886 90)
			(size 0.519938 1.4986)
			(layers "F.Cu" "F.Mask" "F.Paste")
			(net "Net_2339")
		)
		(pad "233" smd rect
			(at 2.050034 16.575024 90)
			(size 0.519938 1.4986)
			(layers "F.Cu" "F.Mask" "F.Paste")
			(net "GND")
		)
		(pad "234" smd rect
			(at 2.050034 17.424908 90)
			(size 0.519938 1.4986)
			(layers "F.Cu" "F.Mask" "F.Paste")
			(net "M_G_CPU0_SB_CB<6>")
		)
		(pad "235" smd rect
			(at 2.050034 18.275046 90)
			(size 0.519938 1.4986)
			(layers "F.Cu" "F.Mask" "F.Paste")
			(net "GND")
		)
		(pad "236" smd rect
			(at 2.050034 19.12493 90)
			(size 0.519938 1.4986)
			(layers "F.Cu" "F.Mask" "F.Paste")
			(net "M_G_CPU0_SB_CB<7>")
		)
		(pad "237" smd rect
			(at 2.050034 19.975068 90)
			(size 0.519938 1.4986)
			(layers "F.Cu" "F.Mask" "F.Paste")
			(net "GND")
		)
		(pad "238" smd rect
			(at 2.050034 20.824952 90)
			(size 0.519938 1.4986)
			(layers "F.Cu" "F.Mask" "F.Paste")
			(net "M_G_CPU0_SB_DQS_DN<4>")
		)
		(pad "239" smd rect
			(at 2.050034 21.67509 90)
			(size 0.519938 1.4986)
			(layers "F.Cu" "F.Mask" "F.Paste")
			(net "M_G_CPU0_SB_DQS_DP<4>")
		)
		(pad "240" smd rect
			(at 2.050034 22.524974 90)
			(size 0.519938 1.4986)
			(layers "F.Cu" "F.Mask" "F.Paste")
			(net "GND")
		)
		(pad "241" smd rect
			(at 2.050034 23.375112 90)
			(size 0.519938 1.4986)
			(layers "F.Cu" "F.Mask" "F.Paste")
			(net "M_G_CPU0_SB_CB<2>")
		)
		(pad "242" smd rect
			(at 2.050034 24.224996 90)
			(size 0.519938 1.4986)
			(layers "F.Cu" "F.Mask" "F.Paste")
			(net "GND")
		)
		(pad "243" smd rect
			(at 2.050034 25.07488 90)
			(size 0.519938 1.4986)
			(layers "F.Cu" "F.Mask" "F.Paste")
			(net "M_G_CPU0_SB_CB<3>")
		)
		(pad "244" smd rect
			(at 2.050034 25.925018 90)
			(size 0.519938 1.4986)
			(layers "F.Cu" "F.Mask" "F.Paste")
			(net "GND")
		)
		(pad "245" smd rect
			(at 2.050034 26.774902 90)
			(size 0.519938 1.4986)
			(layers "F.Cu" "F.Mask" "F.Paste")
			(net "M_G_CPU0_SB_DQ<2>")
		)
		(pad "246" smd rect
			(at 2.050034 27.62504 90)
			(size 0.519938 1.4986)
			(layers "F.Cu" "F.Mask" "F.Paste")
			(net "GND")
		)
		(pad "247" smd rect
			(at 2.050034 28.474924 90)
			(size 0.519938 1.4986)
			(layers "F.Cu" "F.Mask" "F.Paste")
			(net "M_G_CPU0_SB_DQ<3>")
		)
		(pad "248" smd rect
			(at 2.050034 29.325062 90)
			(size 0.519938 1.4986)
			(layers "F.Cu" "F.Mask" "F.Paste")
			(net "GND")
		)
		(pad "249" smd rect
			(at 2.050034 30.174946 90)
			(size 0.519938 1.4986)
			(layers "F.Cu" "F.Mask" "F.Paste")
			(net "M_G_CPU0_SB_DQS_DN<5>")
		)
		(pad "250" smd rect
			(at 2.050034 31.025084 90)
			(size 0.519938 1.4986)
			(layers "F.Cu" "F.Mask" "F.Paste")
			(net "M_G_CPU0_SB_DQS_DP<5>")
		)
		(pad "251" smd rect
			(at 2.050034 31.874968 90)
			(size 0.519938 1.4986)
			(layers "F.Cu" "F.Mask" "F.Paste")
			(net "GND")
		)
		(pad "252" smd rect
			(at 2.050034 32.725106 90)
			(size 0.519938 1.4986)
			(layers "F.Cu" "F.Mask" "F.Paste")
			(net "M_G_CPU0_SB_DQ<6>")
		)
		(pad "253" smd rect
			(at 2.050034 33.57499 90)
			(size 0.519938 1.4986)
			(layers "F.Cu" "F.Mask" "F.Paste")
			(net "GND")
		)
		(pad "254" smd rect
			(at 2.050034 34.425128 90)
			(size 0.519938 1.4986)
			(layers "F.Cu" "F.Mask" "F.Paste")
			(net "M_G_CPU0_SB_DQ<7>")
		)
		(pad "255" smd rect
			(at 2.050034 35.275012 90)
			(size 0.519938 1.4986)
			(layers "F.Cu" "F.Mask" "F.Paste")
			(net "GND")
		)
		(pad "256" smd rect
			(at 2.050034 36.124896 90)
			(size 0.519938 1.4986)
			(layers "F.Cu" "F.Mask" "F.Paste")
			(net "M_G_CPU0_SB_DQ<10>")
		)
		(pad "257" smd rect
			(at 2.050034 36.975034 90)
			(size 0.519938 1.4986)
			(layers "F.Cu" "F.Mask" "F.Paste")
			(net "GND")
		)
		(pad "258" smd rect
			(at 2.050034 37.824918 90)
			(size 0.519938 1.4986)
			(layers "F.Cu" "F.Mask" "F.Paste")
			(net "M_G_CPU0_SB_DQ<11>")
		)
		(pad "259" smd rect
			(at 2.050034 38.675056 90)
			(size 0.519938 1.4986)
			(layers "F.Cu" "F.Mask" "F.Paste")
			(net "GND")
		)
		(pad "260" smd rect
			(at 2.050034 39.52494 90)
			(size 0.519938 1.4986)
			(layers "F.Cu" "F.Mask" "F.Paste")
			(net "M_G_CPU0_SB_DQS_DN<6>")
		)
		(pad "261" smd rect
			(at 2.050034 40.375078 90)
			(size 0.519938 1.4986)
			(layers "F.Cu" "F.Mask" "F.Paste")
			(net "M_G_CPU0_SB_DQS_DP<6>")
		)
		(pad "262" smd rect
			(at 2.050034 41.224962 90)
			(size 0.519938 1.4986)
			(layers "F.Cu" "F.Mask" "F.Paste")
			(net "GND")
		)
		(pad "263" smd rect
			(at 2.050034 42.0751 90)
			(size 0.519938 1.4986)
			(layers "F.Cu" "F.Mask" "F.Paste")
			(net "M_G_CPU0_SB_DQ<14>")
		)
		(pad "264" smd rect
			(at 2.050034 42.924984 90)
			(size 0.519938 1.4986)
			(layers "F.Cu" "F.Mask" "F.Paste")
			(net "GND")
		)
		(pad "265" smd rect
			(at 2.050034 43.775122 90)
			(size 0.519938 1.4986)
			(layers "F.Cu" "F.Mask" "F.Paste")
			(net "M_G_CPU0_SB_DQ<15>")
		)
		(pad "266" smd rect
			(at 2.050034 44.625006 90)
			(size 0.519938 1.4986)
			(layers "F.Cu" "F.Mask" "F.Paste")
			(net "GND")
		)
		(pad "267" smd rect
			(at 2.050034 45.47489 90)
			(size 0.519938 1.4986)
			(layers "F.Cu" "F.Mask" "F.Paste")
			(net "M_G_CPU0_SB_DQ<18>")
		)
		(pad "268" smd rect
			(at 2.050034 46.325028 90)
			(size 0.519938 1.4986)
			(layers "F.Cu" "F.Mask" "F.Paste")
			(net "GND")
		)
		(pad "269" smd rect
			(at 2.050034 47.174912 90)
			(size 0.519938 1.4986)
			(layers "F.Cu" "F.Mask" "F.Paste")
			(net "M_G_CPU0_SB_DQ<19>")
		)
		(pad "270" smd rect
			(at 2.050034 48.02505 90)
			(size 0.519938 1.4986)
			(layers "F.Cu" "F.Mask" "F.Paste")
			(net "GND")
		)
		(pad "271" smd rect
			(at 2.050034 48.874934 90)
			(size 0.519938 1.4986)
			(layers "F.Cu" "F.Mask" "F.Paste")
			(net "M_G_CPU0_SB_DQS_DN<7>")
		)
		(pad "272" smd rect
			(at 2.050034 49.725072 90)
			(size 0.519938 1.4986)
			(layers "F.Cu" "F.Mask" "F.Paste")
			(net "M_G_CPU0_SB_DQS_DP<7>")
		)
		(pad "273" smd rect
			(at 2.050034 50.574956 90)
			(size 0.519938 1.4986)
			(layers "F.Cu" "F.Mask" "F.Paste")
			(net "GND")
		)
		(pad "274" smd rect
			(at 2.050034 51.425094 90)
			(size 0.519938 1.4986)
			(layers "F.Cu" "F.Mask" "F.Paste")
			(net "M_G_CPU0_SB_DQ<22>")
		)
		(pad "275" smd rect
			(at 2.050034 52.274978 90)
			(size 0.519938 1.4986)
			(layers "F.Cu" "F.Mask" "F.Paste")
			(net "GND")
		)
		(pad "276" smd rect
			(at 2.050034 53.125116 90)
			(size 0.519938 1.4986)
			(layers "F.Cu" "F.Mask" "F.Paste")
			(net "M_G_CPU0_SB_DQ<23>")
		)
		(pad "277" smd rect
			(at 2.050034 53.975 90)
			(size 0.519938 1.4986)
			(layers "F.Cu" "F.Mask" "F.Paste")
			(net "GND")
		)
		(pad "278" smd rect
			(at 2.050034 54.824884 90)
			(size 0.519938 1.4986)
			(layers "F.Cu" "F.Mask" "F.Paste")
			(net "M_G_CPU0_SB_DQ<26>")
		)
		(pad "279" smd rect
			(at 2.050034 55.675022 90)
			(size 0.519938 1.4986)
			(layers "F.Cu" "F.Mask" "F.Paste")
			(net "GND")
		)
		(pad "280" smd rect
			(at 2.050034 56.524906 90)
			(size 0.519938 1.4986)
			(layers "F.Cu" "F.Mask" "F.Paste")
			(net "M_G_CPU0_SB_DQ<27>")
		)
		(pad "281" smd rect
			(at 2.050034 57.375044 90)
			(size 0.519938 1.4986)
			(layers "F.Cu" "F.Mask" "F.Paste")
			(net "GND")
		)
		(pad "282" smd rect
			(at 2.050034 58.224928 90)
			(size 0.519938 1.4986)
			(layers "F.Cu" "F.Mask" "F.Paste")
			(net "M_G_CPU0_SB_DQS_DN<8>")
		)
		(pad "283" smd rect
			(at 2.050034 59.075066 90)
			(size 0.519938 1.4986)
			(layers "F.Cu" "F.Mask" "F.Paste")
			(net "M_G_CPU0_SB_DQS_DP<8>")
		)
		(pad "284" smd rect
			(at 2.050034 59.92495 90)
			(size 0.519938 1.4986)
			(layers "F.Cu" "F.Mask" "F.Paste")
			(net "GND")
		)
		(pad "285" smd rect
			(at 2.050034 60.775088 90)
			(size 0.519938 1.4986)
			(layers "F.Cu" "F.Mask" "F.Paste")
			(net "M_G_CPU0_SB_DQ<30>")
		)
		(pad "286" smd rect
			(at 2.050034 61.624972 90)
			(size 0.519938 1.4986)
			(layers "F.Cu" "F.Mask" "F.Paste")
			(net "GND")
		)
		(pad "287" smd rect
			(at 2.050034 62.47511 90)
			(size 0.519938 1.4986)
			(layers "F.Cu" "F.Mask" "F.Paste")
			(net "M_G_CPU0_SB_DQ<31>")
		)
		(pad "288" smd rect
			(at 2.050034 63.324994 90)
			(size 0.519938 1.4986)
			(layers "F.Cu" "F.Mask" "F.Paste")
			(net "GND")
		)
		(pad "G1" thru_hole oval
			(at 0 -68.97497 90)
			(size 1.7272 3.4798)
			(drill oval 1.2192 2.4638)
			(layers "*.Cu" "*.Mask")
			(remove_unused_layers no)
			(net "GND")
			(clearance 0.127)
			(thermal_gap 0.127)
		)
		(pad "G2" thru_hole oval
			(at 0 3.875024 90)
			(size 1.7272 3.4798)
			(drill oval 1.2192 2.4638)
			(layers "*.Cu" "*.Mask")
			(remove_unused_layers no)
			(net "GND")
			(clearance 0.127)
			(thermal_gap 0.127)
		)
		(pad "G3" thru_hole oval
			(at 0 68.97497 90)
			(size 1.7272 3.4798)
			(drill oval 1.2192 2.4638)
			(layers "*.Cu" "*.Mask")
			(remove_unused_layers no)
			(net "GND")
			(clearance 0.127)
			(thermal_gap 0.127)
		)
	)
	(footprint ""
		(layer "F.Cu")
		(at 440.93003 -395.699234 90)
		(property "Reference" "PR6555"
			(at 0 0 90)
			(layer "F.SilkS")
			(hide yes)
			(effects
				(font
					(size 1.27 1.27)
				)
			)
		)
		(property "Value" ""
			(at 0 0 90)
			(layer "F.Fab")
			(effects
				(font
					(size 1.27 1.27)
				)
			)
		)
		(duplicate_pad_numbers_are_jumpers no)
		(fp_line
			(start 0.7874 -0.4064)
			(end 0.7874 0.4064)
			(stroke
				(width 0.1524)
				(type default)
			)
			(layer "F.SilkS")
		)
		(fp_line
			(start -0.7874 -0.4064)
			(end 0.7874 -0.4064)
			(stroke
				(width 0.1524)
				(type default)
			)
			(layer "F.SilkS")
		)
		(fp_line
			(start 0.7874 0.4064)
			(end -0.7874 0.4064)
			(stroke
				(width 0.1524)
				(type default)
			)
			(layer "F.SilkS")
		)
		(fp_line
			(start -0.7874 0.4064)
			(end -0.7874 -0.4064)
			(stroke
				(width 0.1524)
				(type default)
			)
			(layer "F.SilkS")
		)
		(fp_line
			(start -0.12065 -0.305054)
			(end -0.12065 -0.2794)
			(stroke
				(width 0.1)
				(type default)
			)
			(layer "F.Fab")
		)
		(fp_line
			(start -0.67945 -0.305054)
			(end -0.12065 -0.305054)
			(stroke
				(width 0.1)
				(type default)
			)
			(layer "F.Fab")
		)
		(fp_line
			(start 0.67945 -0.3048)
			(end 0.67945 0.3048)
			(stroke
				(width 0.1)
				(type default)
			)
			(layer "F.Fab")
		)
		(fp_line
			(start 0.12065 -0.3048)
			(end 0.67945 -0.3048)
			(stroke
				(width 0.1)
				(type default)
			)
			(layer "F.Fab")
		)
		(fp_line
			(start 0.12065 -0.2794)
			(end 0.12065 -0.3048)
			(stroke
				(width 0.1)
				(type default)
			)
			(layer "F.Fab")
		)
		(fp_line
			(start -0.12065 -0.2794)
			(end 0.12065 -0.2794)
			(stroke
				(width 0.1)
				(type default)
			)
			(layer "F.Fab")
		)
		(fp_line
			(start 0.120396 0.2794)
			(end -0.12065 0.2794)
			(stroke
				(width 0.1)
				(type default)
			)
			(layer "F.Fab")
		)
		(fp_line
			(start -0.12065 0.2794)
			(end -0.12065 0.3048)
			(stroke
				(width 0.1)
				(type default)
			)
			(layer "F.Fab")
		)
		(fp_line
			(start 0.67945 0.3048)
			(end 0.120396 0.3048)
			(stroke
				(width 0.1)
				(type default)
			)
			(layer "F.Fab")
		)
		(fp_line
			(start 0.120396 0.3048)
			(end 0.120396 0.2794)
			(stroke
				(width 0.1)
				(type default)
			)
			(layer "F.Fab")
		)
		(fp_line
			(start -0.12065 0.3048)
			(end -0.67945 0.3048)
			(stroke
				(width 0.1)
				(type default)
			)
			(layer "F.Fab")
		)
		(fp_line
			(start -0.67945 0.3048)
			(end -0.67945 -0.305054)
			(stroke
				(width 0.1)
				(type default)
			)
			(layer "F.Fab")
		)
		(pad "1" smd circle
			(at -0.40005 0 90)
			(size 0 0)
			(layers "F.Cu" "F.Mask" "F.Paste")
			(net "SW_P0V9_RETIMER_CPU0_SW1_RC")
		)
		(pad "2" smd circle
			(at 0.40005 0 90)
			(size 0 0)
			(layers "F.Cu" "F.Mask" "F.Paste")
			(net "GND")
		)
	)
	(footprint ""
		(layer "F.Cu")
		(at 520.044426 -142.882874 90)
		(property "Reference" "X8007"
			(at -2.028444 2.042922 0)
			(unlocked yes)
			(layer "F.SilkS")
			(effects
				(font
					(size 0.7874 0.5842)
					(thickness 0.1524)
				)
				(justify left)
			)
		)
		(property "Value" ""
			(at 0 0 90)
			(layer "F.Fab")
			(effects
				(font
					(size 1.27 1.27)
				)
			)
		)
		(property "Device Type" "TP_TDR_4P_FTS_TH-TP_TDR_4P_DIP,EMPTY,TP15"
			(at 1.30175 1.27 180)
			(unlocked yes)
			(layer "F.Fab")
			(hide yes)
			(effects
				(font
					(size 0.635 0.4064)
					(thickness 0.1524)
				)
			)
		)
		(property "User Part Number" "N_A"
			(at 1.30175 1.27 180)
			(unlocked yes)
			(layer "Cmts.User")
			(hide yes)
			(effects
				(font
					(size 0.635 0.4064)
					(thickness 0.1524)
				)
			)
		)
		(duplicate_pad_numbers_are_jumpers no)
		(fp_line
			(start 2.54 -1.27)
			(end 0 -1.27)
			(stroke
				(width 0.1524)
				(type default)
			)
			(layer "F.SilkS")
		)
		(fp_line
			(start 0 -1.27)
			(end 0 -0.635)
			(stroke
				(width 0.1524)
				(type default)
			)
			(layer "F.SilkS")
		)
		(fp_line
			(start 2.54 -1.1303)
			(end 2.54 -1.27)
			(stroke
				(width 0.1524)
				(type default)
			)
			(layer "F.SilkS")
		)
		(fp_line
			(start 0 0.635)
			(end 0 1.905)
			(stroke
				(width 0.1524)
				(type default)
			)
			(layer "F.SilkS")
		)
		(fp_line
			(start 2.54 1.4097)
			(end 2.54 1.1303)
			(stroke
				(width 0.1524)
				(type default)
			)
			(layer "F.SilkS")
		)
		(fp_line
			(start 0 3.175)
			(end 0 3.81)
			(stroke
				(width 0.1524)
				(type default)
			)
			(layer "F.SilkS")
		)
		(fp_line
			(start 2.54 3.81)
			(end 2.54 3.6703)
			(stroke
				(width 0.1524)
				(type default)
			)
			(layer "F.SilkS")
		)
		(fp_line
			(start 0 3.81)
			(end 2.54 3.81)
			(stroke
				(width 0.1524)
				(type default)
			)
			(layer "F.SilkS")
		)
		(fp_poly
			(pts
				(xy -2.285746 -0.762) (xy -0.761746 0) (xy -2.285746 0.762)
			)
			(stroke
				(width 0)
				(type default)
			)
			(fill yes)
			(layer "F.SilkS")
		)
		(fp_line
			(start 2.54 -1.27)
			(end 0 -1.27)
			(stroke
				(width 0.1)
				(type default)
			)
			(layer "F.Fab")
		)
		(fp_line
			(start 0 -1.27)
			(end 0 3.81)
			(stroke
				(width 0.1)
				(type default)
			)
			(layer "F.Fab")
		)
		(fp_line
			(start 2.54 3.81)
			(end 2.54 -1.27)
			(stroke
				(width 0.1)
				(type default)
			)
			(layer "F.Fab")
		)
		(fp_line
			(start 0 3.81)
			(end 2.54 3.81)
			(stroke
				(width 0.1)
				(type default)
			)
			(layer "F.Fab")
		)
		(fp_poly
			(pts
				(xy -0.761746 0) (xy -2.285746 -0.762) (xy -2.285746 0.762)
			)
			(stroke
				(width 0)
				(type default)
			)
			(fill yes)
			(layer "F.Fab")
		)
		(pad "1" thru_hole circle
			(at 0 0 90)
			(size 1.0033 1.0033)
			(drill 0.249936)
			(layers "*.Cu" "*.Mask")
			(remove_unused_layers no)
			(net "TDR_DIFF_85_TOP_DN")
			(clearance 0.10795)
			(thermal_gap 0.10795)
			(padstack
				(mode front_inner_back)
				(layer "Inner"
					(shape circle)
					(size 0.8001 0.8001)
					(clearance 0.1524)
				)
				(layer "B.Cu"
					(shape circle)
					(size 1.0033 1.0033)
					(clearance 0.10795)
				)
			)
		)
		(pad "2" thru_hole circle
			(at 2.54 0 90)
			(size 1.9939 1.9939)
			(drill 0.249936)
			(layers "*.Cu" "*.Mask")
			(remove_unused_layers no)
			(net "T1_GND")
			(clearance 0.10795)
			(thermal_gap 0.10795)
			(padstack
				(mode front_inner_back)
				(layer "Inner"
					(shape circle)
					(size 0.8001 0.8001)
					(clearance 0.1524)
				)
				(layer "B.Cu"
					(shape circle)
					(size 1.9939 1.9939)
					(clearance 0.10795)
				)
			)
		)
		(pad "3" thru_hole circle
			(at 2.54 2.54 90)
			(size 1.9939 1.9939)
			(drill 0.249936)
			(layers "*.Cu" "*.Mask")
			(remove_unused_layers no)
			(net "T1_GND")
			(clearance 0.10795)
			(thermal_gap 0.10795)
			(padstack
				(mode front_inner_back)
				(layer "Inner"
					(shape circle)
					(size 0.8001 0.8001)
					(clearance 0.1524)
				)
				(layer "B.Cu"
					(shape circle)
					(size 1.9939 1.9939)
					(clearance 0.10795)
				)
			)
		)
		(pad "4" thru_hole circle
			(at 0 2.54 90)
			(size 1.0033 1.0033)
			(drill 0.249936)
			(layers "*.Cu" "*.Mask")
			(remove_unused_layers no)
			(net "TDR_DIFF_85_TOP_DP")
			(clearance 0.10795)
			(thermal_gap 0.10795)
			(padstack
				(mode front_inner_back)
				(layer "Inner"
					(shape circle)
					(size 0.8001 0.8001)
					(clearance 0.1524)
				)
				(layer "B.Cu"
					(shape circle)
					(size 1.0033 1.0033)
					(clearance 0.10795)
				)
			)
		)
	)
	(footprint ""
		(layer "F.Cu")
		(at 35.980878 -17.623536 90)
		(property "Reference" "C56"
			(at 0 0 90)
			(layer "F.SilkS")
			(hide yes)
			(effects
				(font
					(size 1.27 1.27)
				)
			)
		)
		(property "Value" ""
			(at 0 0 90)
			(layer "F.Fab")
			(effects
				(font
					(size 1.27 1.27)
				)
			)
		)
		(duplicate_pad_numbers_are_jumpers no)
		(fp_line
			(start 0.299974 -0.150114)
			(end 0.299974 0.150114)
			(stroke
				(width 0.1)
				(type default)
			)
			(layer "F.Fab")
		)
		(fp_line
			(start -0.299974 -0.150114)
			(end 0.299974 -0.150114)
			(stroke
				(width 0.1)
				(type default)
			)
			(layer "F.Fab")
		)
		(fp_line
			(start 0.299974 0.150114)
			(end -0.299974 0.150114)
			(stroke
				(width 0.1)
				(type default)
			)
			(layer "F.Fab")
		)
		(fp_line
			(start -0.299974 0.150114)
			(end -0.299974 -0.150114)
			(stroke
				(width 0.1)
				(type default)
			)
			(layer "F.Fab")
		)
		(pad "1" smd rect
			(at -0.2667 0 90)
			(size 0.3048 0.381)
			(layers "F.Cu" "F.Mask" "F.Paste")
			(net "P5E_CPU1_G1_TX_C_DP<8>")
		)
		(pad "2" smd rect
			(at 0.2667 0 90)
			(size 0.3048 0.381)
			(layers "F.Cu" "F.Mask" "F.Paste")
			(net "P5E_CPU1_G1_TX_DP<8>")
		)
	)
	(footprint ""
		(layer "F.Cu")
		(at 68.212462 -39.421562)
		(property "Reference" "R3609"
			(at 0 0 0)
			(layer "F.SilkS")
			(hide yes)
			(effects
				(font
					(size 1.27 1.27)
				)
			)
		)
		(property "Value" ""
			(at 0 0 0)
			(layer "F.Fab")
			(effects
				(font
					(size 1.27 1.27)
				)
			)
		)
		(duplicate_pad_numbers_are_jumpers no)
		(fp_line
			(start -0.7874 -0.4064)
			(end 0.7874 -0.4064)
			(stroke
				(width 0.1524)
				(type default)
			)
			(layer "F.SilkS")
		)
		(fp_line
			(start -0.7874 0.4064)
			(end -0.7874 -0.4064)
			(stroke
				(width 0.1524)
				(type default)
			)
			(layer "F.SilkS")
		)
		(fp_line
			(start 0.7874 -0.4064)
			(end 0.7874 0.4064)
			(stroke
				(width 0.1524)
				(type default)
			)
			(layer "F.SilkS")
		)
		(fp_line
			(start 0.7874 0.4064)
			(end -0.7874 0.4064)
			(stroke
				(width 0.1524)
				(type default)
			)
			(layer "F.SilkS")
		)
		(fp_line
			(start -0.67945 -0.305054)
			(end -0.12065 -0.305054)
			(stroke
				(width 0.1)
				(type default)
			)
			(layer "F.Fab")
		)
		(fp_line
			(start -0.67945 0.3048)
			(end -0.67945 -0.305054)
			(stroke
				(width 0.1)
				(type default)
			)
			(layer "F.Fab")
		)
		(fp_line
			(start -0.12065 -0.305054)
			(end -0.12065 -0.2794)
			(stroke
				(width 0.1)
				(type default)
			)
			(layer "F.Fab")
		)
		(fp_line
			(start -0.12065 -0.2794)
			(end 0.12065 -0.2794)
			(stroke
				(width 0.1)
				(type default)
			)
			(layer "F.Fab")
		)
		(fp_line
			(start -0.12065 0.2794)
			(end -0.12065 0.3048)
			(stroke
				(width 0.1)
				(type default)
			)
			(layer "F.Fab")
		)
		(fp_line
			(start -0.12065 0.3048)
			(end -0.67945 0.3048)
			(stroke
				(width 0.1)
				(type default)
			)
			(layer "F.Fab")
		)
		(fp_line
			(start 0.120396 0.2794)
			(end -0.12065 0.2794)
			(stroke
				(width 0.1)
				(type default)
			)
			(layer "F.Fab")
		)
		(fp_line
			(start 0.120396 0.3048)
			(end 0.120396 0.2794)
			(stroke
				(width 0.1)
				(type default)
			)
			(layer "F.Fab")
		)
		(fp_line
			(start 0.12065 -0.3048)
			(end 0.67945 -0.3048)
			(stroke
				(width 0.1)
				(type default)
			)
			(layer "F.Fab")
		)
		(fp_line
			(start 0.12065 -0.2794)
			(end 0.12065 -0.3048)
			(stroke
				(width 0.1)
				(type default)
			)
			(layer "F.Fab")
		)
		(fp_line
			(start 0.67945 -0.3048)
			(end 0.67945 0.3048)
			(stroke
				(width 0.1)
				(type default)
			)
			(layer "F.Fab")
		)
		(fp_line
			(start 0.67945 0.3048)
			(end 0.120396 0.3048)
			(stroke
				(width 0.1)
				(type default)
			)
			(layer "F.Fab")
		)
		(pad "1" smd circle
			(at -0.40005 0)
			(size 0 0)
			(layers "F.Cu" "F.Mask" "F.Paste")
			(net "GND")
		)
		(pad "2" smd circle
			(at 0.40005 0)
			(size 0 0)
			(layers "F.Cu" "F.Mask" "F.Paste")
			(net "INA230_3_A0")
		)
	)
	(footprint ""
		(layer "F.Cu")
		(at 195.6943 -401.963382 90)
		(property "Reference" "PC1525"
			(at 0 0 90)
			(layer "F.SilkS")
			(hide yes)
			(effects
				(font
					(size 1.27 1.27)
				)
			)
		)
		(property "Value" ""
			(at 0 0 90)
			(layer "F.Fab")
			(effects
				(font
					(size 1.27 1.27)
				)
			)
		)
		(duplicate_pad_numbers_are_jumpers no)
		(fp_line
			(start 0.7874 -0.4064)
			(end 0.7874 0.4064)
			(stroke
				(width 0.1524)
				(type default)
			)
			(layer "F.SilkS")
		)
		(fp_line
			(start -0.7874 -0.4064)
			(end 0.7874 -0.4064)
			(stroke
				(width 0.1524)
				(type default)
			)
			(layer "F.SilkS")
		)
		(fp_line
			(start 0.7874 0.4064)
			(end -0.7874 0.4064)
			(stroke
				(width 0.1524)
				(type default)
			)
			(layer "F.SilkS")
		)
		(fp_line
			(start -0.7874 0.4064)
			(end -0.7874 -0.4064)
			(stroke
				(width 0.1524)
				(type default)
			)
			(layer "F.SilkS")
		)
		(fp_line
			(start -0.12065 -0.305054)
			(end -0.12065 -0.2794)
			(stroke
				(width 0.1)
				(type default)
			)
			(layer "F.Fab")
		)
		(fp_line
			(start -0.67945 -0.305054)
			(end -0.12065 -0.305054)
			(stroke
				(width 0.1)
				(type default)
			)
			(layer "F.Fab")
		)
		(fp_line
			(start 0.67945 -0.3048)
			(end 0.67945 0.3048)
			(stroke
				(width 0.1)
				(type default)
			)
			(layer "F.Fab")
		)
		(fp_line
			(start 0.12065 -0.3048)
			(end 0.67945 -0.3048)
			(stroke
				(width 0.1)
				(type default)
			)
			(layer "F.Fab")
		)
		(fp_line
			(start 0.12065 -0.2794)
			(end 0.12065 -0.3048)
			(stroke
				(width 0.1)
				(type default)
			)
			(layer "F.Fab")
		)
		(fp_line
			(start -0.12065 -0.2794)
			(end 0.12065 -0.2794)
			(stroke
				(width 0.1)
				(type default)
			)
			(layer "F.Fab")
		)
		(fp_line
			(start 0.120396 0.2794)
			(end -0.12065 0.2794)
			(stroke
				(width 0.1)
				(type default)
			)
			(layer "F.Fab")
		)
		(fp_line
			(start -0.12065 0.2794)
			(end -0.12065 0.3048)
			(stroke
				(width 0.1)
				(type default)
			)
			(layer "F.Fab")
		)
		(fp_line
			(start 0.67945 0.3048)
			(end 0.120396 0.3048)
			(stroke
				(width 0.1)
				(type default)
			)
			(layer "F.Fab")
		)
		(fp_line
			(start 0.120396 0.3048)
			(end 0.120396 0.2794)
			(stroke
				(width 0.1)
				(type default)
			)
			(layer "F.Fab")
		)
		(fp_line
			(start -0.12065 0.3048)
			(end -0.67945 0.3048)
			(stroke
				(width 0.1)
				(type default)
			)
			(layer "F.Fab")
		)
		(fp_line
			(start -0.67945 0.3048)
			(end -0.67945 -0.305054)
			(stroke
				(width 0.1)
				(type default)
			)
			(layer "F.Fab")
		)
		(pad "1" smd circle
			(at -0.40005 0 90)
			(size 0 0)
			(layers "F.Cu" "F.Mask" "F.Paste")
			(net "HSC_VDD_R_1")
		)
		(pad "2" smd circle
			(at 0.40005 0 90)
			(size 0 0)
			(layers "F.Cu" "F.Mask" "F.Paste")
			(net "AGND_HSC")
		)
	)
	(footprint ""
		(layer "F.Cu")
		(at 170.8404 -332.232508)
		(property "Reference" "PR288"
			(at 0 0 0)
			(layer "F.SilkS")
			(hide yes)
			(effects
				(font
					(size 1.27 1.27)
				)
			)
		)
		(property "Value" ""
			(at 0 0 0)
			(layer "F.Fab")
			(effects
				(font
					(size 1.27 1.27)
				)
			)
		)
		(duplicate_pad_numbers_are_jumpers no)
		(fp_line
			(start -0.7874 -0.4064)
			(end 0.7874 -0.4064)
			(stroke
				(width 0.1524)
				(type default)
			)
			(layer "F.SilkS")
		)
		(fp_line
			(start -0.7874 0.4064)
			(end -0.7874 -0.4064)
			(stroke
				(width 0.1524)
				(type default)
			)
			(layer "F.SilkS")
		)
		(fp_line
			(start 0.7874 -0.4064)
			(end 0.7874 0.4064)
			(stroke
				(width 0.1524)
				(type default)
			)
			(layer "F.SilkS")
		)
		(fp_line
			(start 0.7874 0.4064)
			(end -0.7874 0.4064)
			(stroke
				(width 0.1524)
				(type default)
			)
			(layer "F.SilkS")
		)
		(fp_line
			(start -0.67945 -0.305054)
			(end -0.12065 -0.305054)
			(stroke
				(width 0.1)
				(type default)
			)
			(layer "F.Fab")
		)
		(fp_line
			(start -0.67945 0.3048)
			(end -0.67945 -0.305054)
			(stroke
				(width 0.1)
				(type default)
			)
			(layer "F.Fab")
		)
		(fp_line
			(start -0.12065 -0.305054)
			(end -0.12065 -0.2794)
			(stroke
				(width 0.1)
				(type default)
			)
			(layer "F.Fab")
		)
		(fp_line
			(start -0.12065 -0.2794)
			(end 0.12065 -0.2794)
			(stroke
				(width 0.1)
				(type default)
			)
			(layer "F.Fab")
		)
		(fp_line
			(start -0.12065 0.2794)
			(end -0.12065 0.3048)
			(stroke
				(width 0.1)
				(type default)
			)
			(layer "F.Fab")
		)
		(fp_line
			(start -0.12065 0.3048)
			(end -0.67945 0.3048)
			(stroke
				(width 0.1)
				(type default)
			)
			(layer "F.Fab")
		)
		(fp_line
			(start 0.120396 0.2794)
			(end -0.12065 0.2794)
			(stroke
				(width 0.1)
				(type default)
			)
			(layer "F.Fab")
		)
		(fp_line
			(start 0.120396 0.3048)
			(end 0.120396 0.2794)
			(stroke
				(width 0.1)
				(type default)
			)
			(layer "F.Fab")
		)
		(fp_line
			(start 0.12065 -0.3048)
			(end 0.67945 -0.3048)
			(stroke
				(width 0.1)
				(type default)
			)
			(layer "F.Fab")
		)
		(fp_line
			(start 0.12065 -0.2794)
			(end 0.12065 -0.3048)
			(stroke
				(width 0.1)
				(type default)
			)
			(layer "F.Fab")
		)
		(fp_line
			(start 0.67945 -0.3048)
			(end 0.67945 0.3048)
			(stroke
				(width 0.1)
				(type default)
			)
			(layer "F.Fab")
		)
		(fp_line
			(start 0.67945 0.3048)
			(end 0.120396 0.3048)
			(stroke
				(width 0.1)
				(type default)
			)
			(layer "F.Fab")
		)
		(pad "1" smd circle
			(at -0.40005 0)
			(size 0 0)
			(layers "F.Cu" "F.Mask" "F.Paste")
			(net "VSENSE_VSS_SENSE_C_P1")
		)
		(pad "2" smd circle
			(at 0.40005 0)
			(size 0 0)
			(layers "F.Cu" "F.Mask" "F.Paste")
			(net "GND")
		)
	)
	(footprint ""
		(layer "F.Cu")
		(at 69.6976 -389.95858)
		(property "Reference" "R1389"
			(at 0 0 0)
			(layer "F.SilkS")
			(hide yes)
			(effects
				(font
					(size 1.27 1.27)
				)
			)
		)
		(property "Value" ""
			(at 0 0 0)
			(layer "F.Fab")
			(effects
				(font
					(size 1.27 1.27)
				)
			)
		)
		(duplicate_pad_numbers_are_jumpers no)
		(fp_line
			(start -0.32512 -0.175006)
			(end 0.32512 -0.175006)
			(stroke
				(width 0.1)
				(type default)
			)
			(layer "F.Fab")
		)
		(fp_line
			(start -0.32512 0.175006)
			(end -0.32512 -0.175006)
			(stroke
				(width 0.1)
				(type default)
			)
			(layer "F.Fab")
		)
		(fp_line
			(start 0.32512 -0.175006)
			(end 0.32512 0.175006)
			(stroke
				(width 0.1)
				(type default)
			)
			(layer "F.Fab")
		)
		(fp_line
			(start 0.32512 0.175006)
			(end -0.32512 0.175006)
			(stroke
				(width 0.1)
				(type default)
			)
			(layer "F.Fab")
		)
		(pad "1" smd rect
			(at -0.2667 0)
			(size 0.3048 0.381)
			(layers "F.Cu" "F.Mask" "F.Paste")
			(net "RXDET_BYP_RT_CPU1_P0")
		)
		(pad "2" smd rect
			(at 0.2667 0 180)
			(size 0.3048 0.381)
			(layers "F.Cu" "F.Mask" "F.Paste")
			(net "GND")
		)
	)
	(footprint ""
		(layer "F.Cu")
		(at 219.347034 -75.02779 -90)
		(property "Reference" "PC2208"
			(at 0 0 270)
			(layer "F.SilkS")
			(hide yes)
			(effects
				(font
					(size 1.27 1.27)
				)
			)
		)
		(property "Value" ""
			(at 0 0 270)
			(layer "F.Fab")
			(effects
				(font
					(size 1.27 1.27)
				)
			)
		)
		(duplicate_pad_numbers_are_jumpers no)
		(fp_line
			(start -0.7874 0.4064)
			(end -0.7874 -0.4064)
			(stroke
				(width 0.1524)
				(type default)
			)
			(layer "F.SilkS")
		)
		(fp_line
			(start 0.7874 0.4064)
			(end -0.7874 0.4064)
			(stroke
				(width 0.1524)
				(type default)
			)
			(layer "F.SilkS")
		)
		(fp_line
			(start -0.7874 -0.4064)
			(end 0.7874 -0.4064)
			(stroke
				(width 0.1524)
				(type default)
			)
			(layer "F.SilkS")
		)
		(fp_line
			(start 0.7874 -0.4064)
			(end 0.7874 0.4064)
			(stroke
				(width 0.1524)
				(type default)
			)
			(layer "F.SilkS")
		)
		(fp_line
			(start -0.67945 0.3048)
			(end -0.67945 -0.305054)
			(stroke
				(width 0.1)
				(type default)
			)
			(layer "F.Fab")
		)
		(fp_line
			(start -0.12065 0.3048)
			(end -0.67945 0.3048)
			(stroke
				(width 0.1)
				(type default)
			)
			(layer "F.Fab")
		)
		(fp_line
			(start 0.120396 0.3048)
			(end 0.120396 0.2794)
			(stroke
				(width 0.1)
				(type default)
			)
			(layer "F.Fab")
		)
		(fp_line
			(start 0.67945 0.3048)
			(end 0.120396 0.3048)
			(stroke
				(width 0.1)
				(type default)
			)
			(layer "F.Fab")
		)
		(fp_line
			(start -0.12065 0.2794)
			(end -0.12065 0.3048)
			(stroke
				(width 0.1)
				(type default)
			)
			(layer "F.Fab")
		)
		(fp_line
			(start 0.120396 0.2794)
			(end -0.12065 0.2794)
			(stroke
				(width 0.1)
				(type default)
			)
			(layer "F.Fab")
		)
		(fp_line
			(start -0.12065 -0.2794)
			(end 0.12065 -0.2794)
			(stroke
				(width 0.1)
				(type default)
			)
			(layer "F.Fab")
		)
		(fp_line
			(start 0.12065 -0.2794)
			(end 0.12065 -0.3048)
			(stroke
				(width 0.1)
				(type default)
			)
			(layer "F.Fab")
		)
		(fp_line
			(start 0.12065 -0.3048)
			(end 0.67945 -0.3048)
			(stroke
				(width 0.1)
				(type default)
			)
			(layer "F.Fab")
		)
		(fp_line
			(start 0.67945 -0.3048)
			(end 0.67945 0.3048)
			(stroke
				(width 0.1)
				(type default)
			)
			(layer "F.Fab")
		)
		(fp_line
			(start -0.67945 -0.305054)
			(end -0.12065 -0.305054)
			(stroke
				(width 0.1)
				(type default)
			)
			(layer "F.Fab")
		)
		(fp_line
			(start -0.12065 -0.305054)
			(end -0.12065 -0.2794)
			(stroke
				(width 0.1)
				(type default)
			)
			(layer "F.Fab")
		)
		(pad "1" smd circle
			(at -0.40005 0 270)
			(size 0 0)
			(layers "F.Cu" "F.Mask" "F.Paste")
			(net "P3V3_AUX")
		)
		(pad "2" smd circle
			(at 0.40005 0 270)
			(size 0 0)
			(layers "F.Cu" "F.Mask" "F.Paste")
			(net "GND")
		)
	)
	(footprint ""
		(layer "F.Cu")
		(at 447.565272 -19.506438)
		(property "Reference" "PC2087"
			(at 0 0 0)
			(layer "F.SilkS")
			(hide yes)
			(effects
				(font
					(size 1.27 1.27)
				)
			)
		)
		(property "Value" ""
			(at 0 0 0)
			(layer "F.Fab")
			(effects
				(font
					(size 1.27 1.27)
				)
			)
		)
		(duplicate_pad_numbers_are_jumpers no)
		(fp_line
			(start -0.7874 -0.4064)
			(end 0.7874 -0.4064)
			(stroke
				(width 0.1524)
				(type default)
			)
			(layer "F.SilkS")
		)
		(fp_line
			(start -0.7874 0.4064)
			(end -0.7874 -0.4064)
			(stroke
				(width 0.1524)
				(type default)
			)
			(layer "F.SilkS")
		)
		(fp_line
			(start 0.7874 -0.4064)
			(end 0.7874 0.4064)
			(stroke
				(width 0.1524)
				(type default)
			)
			(layer "F.SilkS")
		)
		(fp_line
			(start 0.7874 0.4064)
			(end -0.7874 0.4064)
			(stroke
				(width 0.1524)
				(type default)
			)
			(layer "F.SilkS")
		)
		(fp_line
			(start -0.67945 -0.305054)
			(end -0.12065 -0.305054)
			(stroke
				(width 0.1)
				(type default)
			)
			(layer "F.Fab")
		)
		(fp_line
			(start -0.67945 0.3048)
			(end -0.67945 -0.305054)
			(stroke
				(width 0.1)
				(type default)
			)
			(layer "F.Fab")
		)
		(fp_line
			(start -0.12065 -0.305054)
			(end -0.12065 -0.2794)
			(stroke
				(width 0.1)
				(type default)
			)
			(layer "F.Fab")
		)
		(fp_line
			(start -0.12065 -0.2794)
			(end 0.12065 -0.2794)
			(stroke
				(width 0.1)
				(type default)
			)
			(layer "F.Fab")
		)
		(fp_line
			(start -0.12065 0.2794)
			(end -0.12065 0.3048)
			(stroke
				(width 0.1)
				(type default)
			)
			(layer "F.Fab")
		)
		(fp_line
			(start -0.12065 0.3048)
			(end -0.67945 0.3048)
			(stroke
				(width 0.1)
				(type default)
			)
			(layer "F.Fab")
		)
		(fp_line
			(start 0.120396 0.2794)
			(end -0.12065 0.2794)
			(stroke
				(width 0.1)
				(type default)
			)
			(layer "F.Fab")
		)
		(fp_line
			(start 0.120396 0.3048)
			(end 0.120396 0.2794)
			(stroke
				(width 0.1)
				(type default)
			)
			(layer "F.Fab")
		)
		(fp_line
			(start 0.12065 -0.3048)
			(end 0.67945 -0.3048)
			(stroke
				(width 0.1)
				(type default)
			)
			(layer "F.Fab")
		)
		(fp_line
			(start 0.12065 -0.2794)
			(end 0.12065 -0.3048)
			(stroke
				(width 0.1)
				(type default)
			)
			(layer "F.Fab")
		)
		(fp_line
			(start 0.67945 -0.3048)
			(end 0.67945 0.3048)
			(stroke
				(width 0.1)
				(type default)
			)
			(layer "F.Fab")
		)
		(fp_line
			(start 0.67945 0.3048)
			(end 0.120396 0.3048)
			(stroke
				(width 0.1)
				(type default)
			)
			(layer "F.Fab")
		)
		(pad "1" smd circle
			(at -0.40005 0)
			(size 0 0)
			(layers "F.Cu" "F.Mask" "F.Paste")
			(net "GND")
		)
		(pad "2" smd circle
			(at 0.40005 0)
			(size 0 0)
			(layers "F.Cu" "F.Mask" "F.Paste")
			(net "P12V_OCP_REG_1")
		)
	)
	(footprint ""
		(layer "F.Cu")
		(at 187.552584 -348.31655 180)
		(property "Reference" "PC255"
			(at 0 0 180)
			(layer "F.SilkS")
			(hide yes)
			(effects
				(font
					(size 1.27 1.27)
				)
			)
		)
		(property "Value" ""
			(at 0 0 180)
			(layer "F.Fab")
			(effects
				(font
					(size 1.27 1.27)
				)
			)
		)
		(duplicate_pad_numbers_are_jumpers no)
		(fp_line
			(start 0.7874 0.4064)
			(end -0.7874 0.4064)
			(stroke
				(width 0.1524)
				(type default)
			)
			(layer "F.SilkS")
		)
		(fp_line
			(start 0.7874 -0.4064)
			(end 0.7874 0.4064)
			(stroke
				(width 0.1524)
				(type default)
			)
			(layer "F.SilkS")
		)
		(fp_line
			(start -0.7874 0.4064)
			(end -0.7874 -0.4064)
			(stroke
				(width 0.1524)
				(type default)
			)
			(layer "F.SilkS")
		)
		(fp_line
			(start -0.7874 -0.4064)
			(end 0.7874 -0.4064)
			(stroke
				(width 0.1524)
				(type default)
			)
			(layer "F.SilkS")
		)
		(fp_line
			(start 0.67945 0.3048)
			(end 0.120396 0.3048)
			(stroke
				(width 0.1)
				(type default)
			)
			(layer "F.Fab")
		)
		(fp_line
			(start 0.67945 -0.3048)
			(end 0.67945 0.3048)
			(stroke
				(width 0.1)
				(type default)
			)
			(layer "F.Fab")
		)
		(fp_line
			(start 0.12065 -0.2794)
			(end 0.12065 -0.3048)
			(stroke
				(width 0.1)
				(type default)
			)
			(layer "F.Fab")
		)
		(fp_line
			(start 0.12065 -0.3048)
			(end 0.67945 -0.3048)
			(stroke
				(width 0.1)
				(type default)
			)
			(layer "F.Fab")
		)
		(fp_line
			(start 0.120396 0.3048)
			(end 0.120396 0.2794)
			(stroke
				(width 0.1)
				(type default)
			)
			(layer "F.Fab")
		)
		(fp_line
			(start 0.120396 0.2794)
			(end -0.12065 0.2794)
			(stroke
				(width 0.1)
				(type default)
			)
			(layer "F.Fab")
		)
		(fp_line
			(start -0.12065 0.3048)
			(end -0.67945 0.3048)
			(stroke
				(width 0.1)
				(type default)
			)
			(layer "F.Fab")
		)
		(fp_line
			(start -0.12065 0.2794)
			(end -0.12065 0.3048)
			(stroke
				(width 0.1)
				(type default)
			)
			(layer "F.Fab")
		)
		(fp_line
			(start -0.12065 -0.2794)
			(end 0.12065 -0.2794)
			(stroke
				(width 0.1)
				(type default)
			)
			(layer "F.Fab")
		)
		(fp_line
			(start -0.12065 -0.305054)
			(end -0.12065 -0.2794)
			(stroke
				(width 0.1)
				(type default)
			)
			(layer "F.Fab")
		)
		(fp_line
			(start -0.67945 0.3048)
			(end -0.67945 -0.305054)
			(stroke
				(width 0.1)
				(type default)
			)
			(layer "F.Fab")
		)
		(fp_line
			(start -0.67945 -0.305054)
			(end -0.12065 -0.305054)
			(stroke
				(width 0.1)
				(type default)
			)
			(layer "F.Fab")
		)
		(pad "1" smd circle
			(at -0.40005 0 180)
			(size 0 0)
			(layers "F.Cu" "F.Mask" "F.Paste")
			(net "SW_PVDD11_S3_P1_SW2")
		)
		(pad "2" smd circle
			(at 0.40005 0 180)
			(size 0 0)
			(layers "F.Cu" "F.Mask" "F.Paste")
			(net "SW_PVDD11_S3_P1_SW2_RC")
		)
	)
	(footprint ""
		(layer "F.Cu")
		(at 441.446666 -401.04187 90)
		(property "Reference" "PR6556"
			(at 0 0 90)
			(layer "F.SilkS")
			(hide yes)
			(effects
				(font
					(size 1.27 1.27)
				)
			)
		)
		(property "Value" ""
			(at 0 0 90)
			(layer "F.Fab")
			(effects
				(font
					(size 1.27 1.27)
				)
			)
		)
		(duplicate_pad_numbers_are_jumpers no)
		(fp_line
			(start 0.7874 -0.4064)
			(end 0.7874 0.4064)
			(stroke
				(width 0.1524)
				(type default)
			)
			(layer "F.SilkS")
		)
		(fp_line
			(start -0.7874 -0.4064)
			(end 0.7874 -0.4064)
			(stroke
				(width 0.1524)
				(type default)
			)
			(layer "F.SilkS")
		)
		(fp_line
			(start -0.7874 -0.121666)
			(end -0.7874 -0.4064)
			(stroke
				(width 0.1524)
				(type default)
			)
			(layer "F.SilkS")
		)
		(fp_line
			(start 0.7874 0.4064)
			(end -0.28067 0.4064)
			(stroke
				(width 0.1524)
				(type default)
			)
			(layer "F.SilkS")
		)
		(fp_line
			(start -0.12065 -0.305054)
			(end -0.12065 -0.2794)
			(stroke
				(width 0.1)
				(type default)
			)
			(layer "F.Fab")
		)
		(fp_line
			(start -0.67945 -0.305054)
			(end -0.12065 -0.305054)
			(stroke
				(width 0.1)
				(type default)
			)
			(layer "F.Fab")
		)
		(fp_line
			(start 0.67945 -0.3048)
			(end 0.67945 0.3048)
			(stroke
				(width 0.1)
				(type default)
			)
			(layer "F.Fab")
		)
		(fp_line
			(start 0.12065 -0.3048)
			(end 0.67945 -0.3048)
			(stroke
				(width 0.1)
				(type default)
			)
			(layer "F.Fab")
		)
		(fp_line
			(start 0.12065 -0.2794)
			(end 0.12065 -0.3048)
			(stroke
				(width 0.1)
				(type default)
			)
			(layer "F.Fab")
		)
		(fp_line
			(start -0.12065 -0.2794)
			(end 0.12065 -0.2794)
			(stroke
				(width 0.1)
				(type default)
			)
			(layer "F.Fab")
		)
		(fp_line
			(start 0.120396 0.2794)
			(end -0.12065 0.2794)
			(stroke
				(width 0.1)
				(type default)
			)
			(layer "F.Fab")
		)
		(fp_line
			(start -0.12065 0.2794)
			(end -0.12065 0.3048)
			(stroke
				(width 0.1)
				(type default)
			)
			(layer "F.Fab")
		)
		(fp_line
			(start 0.67945 0.3048)
			(end 0.120396 0.3048)
			(stroke
				(width 0.1)
				(type default)
			)
			(layer "F.Fab")
		)
		(fp_line
			(start 0.120396 0.3048)
			(end 0.120396 0.2794)
			(stroke
				(width 0.1)
				(type default)
			)
			(layer "F.Fab")
		)
		(fp_line
			(start -0.12065 0.3048)
			(end -0.67945 0.3048)
			(stroke
				(width 0.1)
				(type default)
			)
			(layer "F.Fab")
		)
		(fp_line
			(start -0.67945 0.3048)
			(end -0.67945 -0.305054)
			(stroke
				(width 0.1)
				(type default)
			)
			(layer "F.Fab")
		)
		(pad "1" smd circle
			(at -0.40005 0 90)
			(size 0 0)
			(layers "F.Cu" "F.Mask" "F.Paste")
			(net "P0V9_RETIMER_CPU0_VOS1")
		)
		(pad "2" smd circle
			(at 0.40005 0 90)
			(size 0 0)
			(layers "F.Cu" "F.Mask" "F.Paste")
			(net "P0V9_CPU0_RT_2D")
		)
	)
	(footprint ""
		(layer "F.Cu")
		(at 100.342192 -31.795212 90)
		(property "Reference" "R6329"
			(at 0 0 90)
			(layer "F.SilkS")
			(hide yes)
			(effects
				(font
					(size 1.27 1.27)
				)
			)
		)
		(property "Value" ""
			(at 0 0 90)
			(layer "F.Fab")
			(effects
				(font
					(size 1.27 1.27)
				)
			)
		)
		(duplicate_pad_numbers_are_jumpers no)
		(fp_line
			(start 0.7874 -0.4064)
			(end 0.7874 0.4064)
			(stroke
				(width 0.1524)
				(type default)
			)
			(layer "F.SilkS")
		)
		(fp_line
			(start -0.7874 -0.4064)
			(end 0.7874 -0.4064)
			(stroke
				(width 0.1524)
				(type default)
			)
			(layer "F.SilkS")
		)
		(fp_line
			(start 0.7874 0.4064)
			(end -0.7874 0.4064)
			(stroke
				(width 0.1524)
				(type default)
			)
			(layer "F.SilkS")
		)
		(fp_line
			(start -0.7874 0.4064)
			(end -0.7874 -0.4064)
			(stroke
				(width 0.1524)
				(type default)
			)
			(layer "F.SilkS")
		)
		(fp_line
			(start -0.12065 -0.305054)
			(end -0.12065 -0.2794)
			(stroke
				(width 0.1)
				(type default)
			)
			(layer "F.Fab")
		)
		(fp_line
			(start -0.67945 -0.305054)
			(end -0.12065 -0.305054)
			(stroke
				(width 0.1)
				(type default)
			)
			(layer "F.Fab")
		)
		(fp_line
			(start 0.67945 -0.3048)
			(end 0.67945 0.3048)
			(stroke
				(width 0.1)
				(type default)
			)
			(layer "F.Fab")
		)
		(fp_line
			(start 0.12065 -0.3048)
			(end 0.67945 -0.3048)
			(stroke
				(width 0.1)
				(type default)
			)
			(layer "F.Fab")
		)
		(fp_line
			(start 0.12065 -0.2794)
			(end 0.12065 -0.3048)
			(stroke
				(width 0.1)
				(type default)
			)
			(layer "F.Fab")
		)
		(fp_line
			(start -0.12065 -0.2794)
			(end 0.12065 -0.2794)
			(stroke
				(width 0.1)
				(type default)
			)
			(layer "F.Fab")
		)
		(fp_line
			(start 0.120396 0.2794)
			(end -0.12065 0.2794)
			(stroke
				(width 0.1)
				(type default)
			)
			(layer "F.Fab")
		)
		(fp_line
			(start -0.12065 0.2794)
			(end -0.12065 0.3048)
			(stroke
				(width 0.1)
				(type default)
			)
			(layer "F.Fab")
		)
		(fp_line
			(start 0.67945 0.3048)
			(end 0.120396 0.3048)
			(stroke
				(width 0.1)
				(type default)
			)
			(layer "F.Fab")
		)
		(fp_line
			(start 0.120396 0.3048)
			(end 0.120396 0.2794)
			(stroke
				(width 0.1)
				(type default)
			)
			(layer "F.Fab")
		)
		(fp_line
			(start -0.12065 0.3048)
			(end -0.67945 0.3048)
			(stroke
				(width 0.1)
				(type default)
			)
			(layer "F.Fab")
		)
		(fp_line
			(start -0.67945 0.3048)
			(end -0.67945 -0.305054)
			(stroke
				(width 0.1)
				(type default)
			)
			(layer "F.Fab")
		)
		(pad "1" smd circle
			(at -0.40005 0 90)
			(size 0 0)
			(layers "F.Cu" "F.Mask" "F.Paste")
			(net "P3V3_AUX")
		)
		(pad "2" smd circle
			(at 0.40005 0 90)
			(size 0 0)
			(layers "F.Cu" "F.Mask" "F.Paste")
			(net "USB_HUB2_TI_GRSTZ_MRP_PROG_FUNC1")
		)
	)
	(footprint ""
		(layer "F.Cu")
		(at 152.982676 -50.739294 90)
		(property "Reference" "R3595"
			(at 0 0 90)
			(layer "F.SilkS")
			(hide yes)
			(effects
				(font
					(size 1.27 1.27)
				)
			)
		)
		(property "Value" ""
			(at 0 0 90)
			(layer "F.Fab")
			(effects
				(font
					(size 1.27 1.27)
				)
			)
		)
		(duplicate_pad_numbers_are_jumpers no)
		(fp_line
			(start 0.7874 -0.4064)
			(end 0.7874 0.4064)
			(stroke
				(width 0.1524)
				(type default)
			)
			(layer "F.SilkS")
		)
		(fp_line
			(start -0.7874 -0.4064)
			(end 0.7874 -0.4064)
			(stroke
				(width 0.1524)
				(type default)
			)
			(layer "F.SilkS")
		)
		(fp_line
			(start 0.7874 0.4064)
			(end -0.7874 0.4064)
			(stroke
				(width 0.1524)
				(type default)
			)
			(layer "F.SilkS")
		)
		(fp_line
			(start -0.7874 0.4064)
			(end -0.7874 -0.4064)
			(stroke
				(width 0.1524)
				(type default)
			)
			(layer "F.SilkS")
		)
		(fp_line
			(start -0.12065 -0.305054)
			(end -0.12065 -0.2794)
			(stroke
				(width 0.1)
				(type default)
			)
			(layer "F.Fab")
		)
		(fp_line
			(start -0.67945 -0.305054)
			(end -0.12065 -0.305054)
			(stroke
				(width 0.1)
				(type default)
			)
			(layer "F.Fab")
		)
		(fp_line
			(start 0.67945 -0.3048)
			(end 0.67945 0.3048)
			(stroke
				(width 0.1)
				(type default)
			)
			(layer "F.Fab")
		)
		(fp_line
			(start 0.12065 -0.3048)
			(end 0.67945 -0.3048)
			(stroke
				(width 0.1)
				(type default)
			)
			(layer "F.Fab")
		)
		(fp_line
			(start 0.12065 -0.2794)
			(end 0.12065 -0.3048)
			(stroke
				(width 0.1)
				(type default)
			)
			(layer "F.Fab")
		)
		(fp_line
			(start -0.12065 -0.2794)
			(end 0.12065 -0.2794)
			(stroke
				(width 0.1)
				(type default)
			)
			(layer "F.Fab")
		)
		(fp_line
			(start 0.120396 0.2794)
			(end -0.12065 0.2794)
			(stroke
				(width 0.1)
				(type default)
			)
			(layer "F.Fab")
		)
		(fp_line
			(start -0.12065 0.2794)
			(end -0.12065 0.3048)
			(stroke
				(width 0.1)
				(type default)
			)
			(layer "F.Fab")
		)
		(fp_line
			(start 0.67945 0.3048)
			(end 0.120396 0.3048)
			(stroke
				(width 0.1)
				(type default)
			)
			(layer "F.Fab")
		)
		(fp_line
			(start 0.120396 0.3048)
			(end 0.120396 0.2794)
			(stroke
				(width 0.1)
				(type default)
			)
			(layer "F.Fab")
		)
		(fp_line
			(start -0.12065 0.3048)
			(end -0.67945 0.3048)
			(stroke
				(width 0.1)
				(type default)
			)
			(layer "F.Fab")
		)
		(fp_line
			(start -0.67945 0.3048)
			(end -0.67945 -0.305054)
			(stroke
				(width 0.1)
				(type default)
			)
			(layer "F.Fab")
		)
		(pad "1" smd circle
			(at -0.40005 0 90)
			(size 0 0)
			(layers "F.Cu" "F.Mask" "F.Paste")
			(net "SMB_INA230_3V3AUX_SDA")
		)
		(pad "2" smd circle
			(at 0.40005 0 90)
			(size 0 0)
			(layers "F.Cu" "F.Mask" "F.Paste")
			(net "SMB_INA230_4_3V3AUX_SDA_R")
		)
	)
	(footprint ""
		(layer "F.Cu")
		(at 335.411064 -349.43161 180)
		(property "Reference" "PC104"
			(at 0.115316 -2.938272 0)
			(unlocked yes)
			(layer "F.SilkS")
			(effects
				(font
					(size 0.7874 0.5842)
					(thickness 0.1524)
				)
				(justify left)
			)
		)
		(property "Value" ""
			(at 0 0 180)
			(layer "F.Fab")
			(effects
				(font
					(size 1.27 1.27)
				)
			)
		)
		(duplicate_pad_numbers_are_jumpers no)
		(fp_line
			(start -3.400044 1.249934)
			(end 3.400044 1.249934)
			(stroke
				(width 0.1524)
				(type default)
			)
			(layer "F.SilkS")
		)
		(fp_circle
			(center 0 1.249934)
			(end -3.400044 1.249934)
			(stroke
				(width 0.1524)
				(type default)
			)
			(fill no)
			(layer "F.SilkS")
		)
		(fp_poly
			(pts
				(arc
					(start 3.400044 1.249934)
					(mid 0 4.649978)
					(end -3.400044 1.249934)
				)
			)
			(stroke
				(width 0)
				(type default)
			)
			(fill yes)
			(layer "F.SilkS")
		)
		(fp_circle
			(center 0 1.249934)
			(end -3.400044 1.249934)
			(stroke
				(width 0.1)
				(type default)
			)
			(fill no)
			(layer "F.Fab")
		)
		(pad "1" thru_hole rect
			(at 0 0 180)
			(size 1.524 1.524)
			(drill 1.016)
			(layers "*.Cu" "*.Mask")
			(remove_unused_layers no)
			(net "SW_P12V_AUX_PVDDCR_CPU1_P0_FLT")
			(clearance 0)
			(padstack
				(mode front_inner_back)
				(layer "Inner"
					(shape circle)
					(size 1.524 1.524)
					(clearance 0)
				)
				(layer "B.Cu"
					(shape rect)
					(size 1.524 1.524)
					(clearance 0)
				)
			)
		)
		(pad "2" thru_hole circle
			(at 0 2.500122 180)
			(size 1.524 1.524)
			(drill 1.016)
			(layers "*.Cu" "*.Mask")
			(remove_unused_layers no)
			(net "GND")
			(clearance 0)
		)
	)
	(footprint ""
		(layer "F.Cu")
		(at 167.871902 -436.78221)
		(property "Reference" "Q102"
			(at 2.473706 1.534414 0)
			(unlocked yes)
			(layer "F.SilkS")
			(effects
				(font
					(size 0.7874 0.5842)
					(thickness 0.1524)
				)
				(justify left)
			)
		)
		(property "Value" ""
			(at 0 0 0)
			(layer "F.Fab")
			(effects
				(font
					(size 1.27 1.27)
				)
			)
		)
		(duplicate_pad_numbers_are_jumpers no)
		(fp_line
			(start -1.332738 -1.100074)
			(end -0.4826 -1.100074)
			(stroke
				(width 0.1524)
				(type default)
			)
			(layer "F.SilkS")
		)
		(fp_line
			(start -1.332738 1.100074)
			(end -1.332738 -1.100074)
			(stroke
				(width 0.1524)
				(type default)
			)
			(layer "F.SilkS")
		)
		(fp_line
			(start -0.4826 -1.100074)
			(end 0 -0.541274)
			(stroke
				(width 0.1524)
				(type default)
			)
			(layer "F.SilkS")
		)
		(fp_line
			(start 0 -0.541274)
			(end 0.4826 -1.100074)
			(stroke
				(width 0.1524)
				(type default)
			)
			(layer "F.SilkS")
		)
		(fp_line
			(start 0.4826 -1.100074)
			(end 1.332738 -1.100074)
			(stroke
				(width 0.1524)
				(type default)
			)
			(layer "F.SilkS")
		)
		(fp_line
			(start 1.332738 -1.100074)
			(end 1.332738 1.100074)
			(stroke
				(width 0.1524)
				(type default)
			)
			(layer "F.SilkS")
		)
		(fp_line
			(start 1.332738 1.100074)
			(end -1.332738 1.100074)
			(stroke
				(width 0.1524)
				(type default)
			)
			(layer "F.SilkS")
		)
		(fp_poly
			(pts
				(xy -1.429766 -1.020064) (xy -2.15773 -1.313688) (xy -1.631696 -1.778508)
			)
			(stroke
				(width 0)
				(type default)
			)
			(fill yes)
			(layer "F.SilkS")
		)
		(fp_line
			(start -0.674878 -1.100074)
			(end 0.674878 -1.100074)
			(stroke
				(width 0.1)
				(type default)
			)
			(layer "F.Fab")
		)
		(fp_line
			(start -0.674878 1.100074)
			(end -0.674878 -1.100074)
			(stroke
				(width 0.1)
				(type default)
			)
			(layer "F.Fab")
		)
		(fp_line
			(start 0.674878 -1.100074)
			(end 0.674878 1.100074)
			(stroke
				(width 0.1)
				(type default)
			)
			(layer "F.Fab")
		)
		(fp_line
			(start 0.674878 1.100074)
			(end -0.674878 1.100074)
			(stroke
				(width 0.1)
				(type default)
			)
			(layer "F.Fab")
		)
		(fp_poly
			(pts
				(xy -2.2352 -0.298958) (xy -2.2352 -1.001014) (xy -1.533144 -0.649986)
			)
			(stroke
				(width 0)
				(type default)
			)
			(fill yes)
			(layer "F.Fab")
		)
		(pad "1" smd rect
			(at -0.94996 -0.649986 90)
			(size 0.4318 0.508)
			(layers "F.Cu" "F.Mask" "F.Paste")
			(net "GND")
		)
		(pad "2" smd rect
			(at -0.94996 0 90)
			(size 0.4318 0.508)
			(layers "F.Cu" "F.Mask" "F.Paste")
			(net "GPU_BASE_HMC_READY")
		)
		(pad "3" smd rect
			(at -0.94996 0.649986 90)
			(size 0.4318 0.508)
			(layers "F.Cu" "F.Mask" "F.Paste")
			(net "GPU_BASE_HMC_READY_ISO")
		)
		(pad "4" smd rect
			(at 0.94996 0.649986 90)
			(size 0.4318 0.508)
			(layers "F.Cu" "F.Mask" "F.Paste")
			(net "GND")
		)
		(pad "5" smd rect
			(at 0.94996 0 90)
			(size 0.4318 0.508)
			(layers "F.Cu" "F.Mask" "F.Paste")
			(net "GPU_BASE_HMC_READY_N")
		)
		(pad "6" smd rect
			(at 0.94996 -0.649986 90)
			(size 0.4318 0.508)
			(layers "F.Cu" "F.Mask" "F.Paste")
			(net "GPU_BASE_HMC_READY_N")
		)
	)
	(footprint ""
		(layer "F.Cu")
		(at 326.662288 -393.47648 180)
		(property "Reference" "L26"
			(at 0 0 180)
			(layer "F.SilkS")
			(hide yes)
			(effects
				(font
					(size 1.27 1.27)
				)
			)
		)
		(property "Value" ""
			(at 0 0 180)
			(layer "F.Fab")
			(effects
				(font
					(size 1.27 1.27)
				)
			)
		)
		(duplicate_pad_numbers_are_jumpers no)
		(fp_line
			(start 0.762 0.381)
			(end -0.762 0.381)
			(stroke
				(width 0.1524)
				(type default)
			)
			(layer "F.SilkS")
		)
		(fp_line
			(start 0.762 -0.381)
			(end 0.762 0.381)
			(stroke
				(width 0.1524)
				(type default)
			)
			(layer "F.SilkS")
		)
		(fp_line
			(start -0.762 0.381)
			(end -0.762 -0.381)
			(stroke
				(width 0.1524)
				(type default)
			)
			(layer "F.SilkS")
		)
		(fp_line
			(start -0.762 -0.381)
			(end 0.762 -0.381)
			(stroke
				(width 0.1524)
				(type default)
			)
			(layer "F.SilkS")
		)
		(fp_line
			(start 0.680466 0.306324)
			(end 0.118364 0.306324)
			(stroke
				(width 0.1)
				(type default)
			)
			(layer "F.Fab")
		)
		(fp_line
			(start 0.680466 -0.306324)
			(end 0.680466 0.306324)
			(stroke
				(width 0.1)
				(type default)
			)
			(layer "F.Fab")
		)
		(fp_line
			(start 0.118872 -0.2794)
			(end 0.118872 -0.306324)
			(stroke
				(width 0.1)
				(type default)
			)
			(layer "F.Fab")
		)
		(fp_line
			(start 0.118872 -0.306324)
			(end 0.680466 -0.306324)
			(stroke
				(width 0.1)
				(type default)
			)
			(layer "F.Fab")
		)
		(fp_line
			(start 0.118364 0.306324)
			(end 0.118364 0.2794)
			(stroke
				(width 0.1)
				(type default)
			)
			(layer "F.Fab")
		)
		(fp_line
			(start 0.118364 0.2794)
			(end -0.119634 0.2794)
			(stroke
				(width 0.1)
				(type default)
			)
			(layer "F.Fab")
		)
		(fp_line
			(start -0.118364 -0.2794)
			(end 0.118872 -0.2794)
			(stroke
				(width 0.1)
				(type default)
			)
			(layer "F.Fab")
		)
		(fp_line
			(start -0.118364 -0.307086)
			(end -0.118364 -0.2794)
			(stroke
				(width 0.1)
				(type default)
			)
			(layer "F.Fab")
		)
		(fp_line
			(start -0.119634 0.30607)
			(end -0.681736 0.30607)
			(stroke
				(width 0.1)
				(type default)
			)
			(layer "F.Fab")
		)
		(fp_line
			(start -0.119634 0.2794)
			(end -0.119634 0.30607)
			(stroke
				(width 0.1)
				(type default)
			)
			(layer "F.Fab")
		)
		(fp_line
			(start -0.681736 0.30607)
			(end -0.681736 -0.307086)
			(stroke
				(width 0.1)
				(type default)
			)
			(layer "F.Fab")
		)
		(fp_line
			(start -0.681736 -0.307086)
			(end -0.118364 -0.307086)
			(stroke
				(width 0.1)
				(type default)
			)
			(layer "F.Fab")
		)
		(pad "1" smd rect
			(at -0.40005 0)
			(size 0.4572 0.508)
			(layers "F.Cu" "F.Mask" "F.Paste")
			(net "P1V8_CPU0_RT_1D")
		)
		(pad "2" smd rect
			(at 0.40005 0)
			(size 0.4572 0.508)
			(layers "F.Cu" "F.Mask" "F.Paste")
			(net "P1V8_CPU0_RT0_1A_1D")
		)
	)
	(footprint ""
		(layer "F.Cu")
		(at 304.419 -365.125)
		(property "Reference" "R8073"
			(at 0 0 0)
			(layer "F.SilkS")
			(hide yes)
			(effects
				(font
					(size 1.27 1.27)
				)
			)
		)
		(property "Value" ""
			(at 0 0 0)
			(layer "F.Fab")
			(effects
				(font
					(size 1.27 1.27)
				)
			)
		)
		(duplicate_pad_numbers_are_jumpers no)
		(fp_line
			(start -0.7874 -0.4064)
			(end 0.7874 -0.4064)
			(stroke
				(width 0.1524)
				(type default)
			)
			(layer "F.SilkS")
		)
		(fp_line
			(start -0.7874 0.4064)
			(end -0.7874 -0.4064)
			(stroke
				(width 0.1524)
				(type default)
			)
			(layer "F.SilkS")
		)
		(fp_line
			(start 0.7874 -0.4064)
			(end 0.7874 0.4064)
			(stroke
				(width 0.1524)
				(type default)
			)
			(layer "F.SilkS")
		)
		(fp_line
			(start 0.7874 0.4064)
			(end -0.7874 0.4064)
			(stroke
				(width 0.1524)
				(type default)
			)
			(layer "F.SilkS")
		)
		(fp_line
			(start -0.67945 -0.305054)
			(end -0.12065 -0.305054)
			(stroke
				(width 0.1)
				(type default)
			)
			(layer "F.Fab")
		)
		(fp_line
			(start -0.67945 0.3048)
			(end -0.67945 -0.305054)
			(stroke
				(width 0.1)
				(type default)
			)
			(layer "F.Fab")
		)
		(fp_line
			(start -0.12065 -0.305054)
			(end -0.12065 -0.2794)
			(stroke
				(width 0.1)
				(type default)
			)
			(layer "F.Fab")
		)
		(fp_line
			(start -0.12065 -0.2794)
			(end 0.12065 -0.2794)
			(stroke
				(width 0.1)
				(type default)
			)
			(layer "F.Fab")
		)
		(fp_line
			(start -0.12065 0.2794)
			(end -0.12065 0.3048)
			(stroke
				(width 0.1)
				(type default)
			)
			(layer "F.Fab")
		)
		(fp_line
			(start -0.12065 0.3048)
			(end -0.67945 0.3048)
			(stroke
				(width 0.1)
				(type default)
			)
			(layer "F.Fab")
		)
		(fp_line
			(start 0.120396 0.2794)
			(end -0.12065 0.2794)
			(stroke
				(width 0.1)
				(type default)
			)
			(layer "F.Fab")
		)
		(fp_line
			(start 0.120396 0.3048)
			(end 0.120396 0.2794)
			(stroke
				(width 0.1)
				(type default)
			)
			(layer "F.Fab")
		)
		(fp_line
			(start 0.12065 -0.3048)
			(end 0.67945 -0.3048)
			(stroke
				(width 0.1)
				(type default)
			)
			(layer "F.Fab")
		)
		(fp_line
			(start 0.12065 -0.2794)
			(end 0.12065 -0.3048)
			(stroke
				(width 0.1)
				(type default)
			)
			(layer "F.Fab")
		)
		(fp_line
			(start 0.67945 -0.3048)
			(end 0.67945 0.3048)
			(stroke
				(width 0.1)
				(type default)
			)
			(layer "F.Fab")
		)
		(fp_line
			(start 0.67945 0.3048)
			(end 0.120396 0.3048)
			(stroke
				(width 0.1)
				(type default)
			)
			(layer "F.Fab")
		)
		(pad "1" smd circle
			(at -0.40005 0)
			(size 0 0)
			(layers "F.Cu" "F.Mask" "F.Paste")
			(net "PVDDCR_CPU1_P0_SMB_ALERT")
		)
		(pad "2" smd circle
			(at 0.40005 0)
			(size 0 0)
			(layers "F.Cu" "F.Mask" "F.Paste")
			(net "PVDDCR_CPU1_P0_SMB_ALERT_R")
		)
	)
	(footprint ""
		(layer "F.Cu")
		(at 22.892258 -427.580298 -90)
		(property "Reference" "R6165"
			(at 0 0 270)
			(layer "F.SilkS")
			(hide yes)
			(effects
				(font
					(size 1.27 1.27)
				)
			)
		)
		(property "Value" ""
			(at 0 0 270)
			(layer "F.Fab")
			(effects
				(font
					(size 1.27 1.27)
				)
			)
		)
		(duplicate_pad_numbers_are_jumpers no)
		(fp_line
			(start -0.7874 0.4064)
			(end -0.7874 -0.4064)
			(stroke
				(width 0.1524)
				(type default)
			)
			(layer "F.SilkS")
		)
		(fp_line
			(start 0.7874 0.4064)
			(end -0.7874 0.4064)
			(stroke
				(width 0.1524)
				(type default)
			)
			(layer "F.SilkS")
		)
		(fp_line
			(start -0.7874 -0.4064)
			(end 0.7874 -0.4064)
			(stroke
				(width 0.1524)
				(type default)
			)
			(layer "F.SilkS")
		)
		(fp_line
			(start 0.7874 -0.4064)
			(end 0.7874 0.4064)
			(stroke
				(width 0.1524)
				(type default)
			)
			(layer "F.SilkS")
		)
		(fp_line
			(start -0.67945 0.3048)
			(end -0.67945 -0.305054)
			(stroke
				(width 0.1)
				(type default)
			)
			(layer "F.Fab")
		)
		(fp_line
			(start -0.12065 0.3048)
			(end -0.67945 0.3048)
			(stroke
				(width 0.1)
				(type default)
			)
			(layer "F.Fab")
		)
		(fp_line
			(start 0.120396 0.3048)
			(end 0.120396 0.2794)
			(stroke
				(width 0.1)
				(type default)
			)
			(layer "F.Fab")
		)
		(fp_line
			(start 0.67945 0.3048)
			(end 0.120396 0.3048)
			(stroke
				(width 0.1)
				(type default)
			)
			(layer "F.Fab")
		)
		(fp_line
			(start -0.12065 0.2794)
			(end -0.12065 0.3048)
			(stroke
				(width 0.1)
				(type default)
			)
			(layer "F.Fab")
		)
		(fp_line
			(start 0.120396 0.2794)
			(end -0.12065 0.2794)
			(stroke
				(width 0.1)
				(type default)
			)
			(layer "F.Fab")
		)
		(fp_line
			(start -0.12065 -0.2794)
			(end 0.12065 -0.2794)
			(stroke
				(width 0.1)
				(type default)
			)
			(layer "F.Fab")
		)
		(fp_line
			(start 0.12065 -0.2794)
			(end 0.12065 -0.3048)
			(stroke
				(width 0.1)
				(type default)
			)
			(layer "F.Fab")
		)
		(fp_line
			(start 0.12065 -0.3048)
			(end 0.67945 -0.3048)
			(stroke
				(width 0.1)
				(type default)
			)
			(layer "F.Fab")
		)
		(fp_line
			(start 0.67945 -0.3048)
			(end 0.67945 0.3048)
			(stroke
				(width 0.1)
				(type default)
			)
			(layer "F.Fab")
		)
		(fp_line
			(start -0.67945 -0.305054)
			(end -0.12065 -0.305054)
			(stroke
				(width 0.1)
				(type default)
			)
			(layer "F.Fab")
		)
		(fp_line
			(start -0.12065 -0.305054)
			(end -0.12065 -0.2794)
			(stroke
				(width 0.1)
				(type default)
			)
			(layer "F.Fab")
		)
		(pad "1" smd circle
			(at -0.40005 0 270)
			(size 0 0)
			(layers "F.Cu" "F.Mask" "F.Paste")
			(net "P3V3_AUX")
		)
		(pad "2" smd circle
			(at 0.40005 0 270)
			(size 0 0)
			(layers "F.Cu" "F.Mask" "F.Paste")
			(net "FM_P2E_BUF2_EQB0")
		)
	)
	(footprint ""
		(layer "F.Cu")
		(at 263.906 -141.986 90)
		(property "Reference" "R1532"
			(at 0 0 90)
			(layer "F.SilkS")
			(hide yes)
			(effects
				(font
					(size 1.27 1.27)
				)
			)
		)
		(property "Value" ""
			(at 0 0 90)
			(layer "F.Fab")
			(effects
				(font
					(size 1.27 1.27)
				)
			)
		)
		(duplicate_pad_numbers_are_jumpers no)
		(fp_line
			(start 0.7874 -0.4064)
			(end 0.7874 0.4064)
			(stroke
				(width 0.1524)
				(type default)
			)
			(layer "F.SilkS")
		)
		(fp_line
			(start -0.7874 -0.4064)
			(end 0.7874 -0.4064)
			(stroke
				(width 0.1524)
				(type default)
			)
			(layer "F.SilkS")
		)
		(fp_line
			(start 0.7874 0.4064)
			(end -0.7874 0.4064)
			(stroke
				(width 0.1524)
				(type default)
			)
			(layer "F.SilkS")
		)
		(fp_line
			(start -0.7874 0.4064)
			(end -0.7874 -0.4064)
			(stroke
				(width 0.1524)
				(type default)
			)
			(layer "F.SilkS")
		)
		(fp_line
			(start -0.12065 -0.305054)
			(end -0.12065 -0.2794)
			(stroke
				(width 0.1)
				(type default)
			)
			(layer "F.Fab")
		)
		(fp_line
			(start -0.67945 -0.305054)
			(end -0.12065 -0.305054)
			(stroke
				(width 0.1)
				(type default)
			)
			(layer "F.Fab")
		)
		(fp_line
			(start 0.67945 -0.3048)
			(end 0.67945 0.3048)
			(stroke
				(width 0.1)
				(type default)
			)
			(layer "F.Fab")
		)
		(fp_line
			(start 0.12065 -0.3048)
			(end 0.67945 -0.3048)
			(stroke
				(width 0.1)
				(type default)
			)
			(layer "F.Fab")
		)
		(fp_line
			(start 0.12065 -0.2794)
			(end 0.12065 -0.3048)
			(stroke
				(width 0.1)
				(type default)
			)
			(layer "F.Fab")
		)
		(fp_line
			(start -0.12065 -0.2794)
			(end 0.12065 -0.2794)
			(stroke
				(width 0.1)
				(type default)
			)
			(layer "F.Fab")
		)
		(fp_line
			(start 0.120396 0.2794)
			(end -0.12065 0.2794)
			(stroke
				(width 0.1)
				(type default)
			)
			(layer "F.Fab")
		)
		(fp_line
			(start -0.12065 0.2794)
			(end -0.12065 0.3048)
			(stroke
				(width 0.1)
				(type default)
			)
			(layer "F.Fab")
		)
		(fp_line
			(start 0.67945 0.3048)
			(end 0.120396 0.3048)
			(stroke
				(width 0.1)
				(type default)
			)
			(layer "F.Fab")
		)
		(fp_line
			(start 0.120396 0.3048)
			(end 0.120396 0.2794)
			(stroke
				(width 0.1)
				(type default)
			)
			(layer "F.Fab")
		)
		(fp_line
			(start -0.12065 0.3048)
			(end -0.67945 0.3048)
			(stroke
				(width 0.1)
				(type default)
			)
			(layer "F.Fab")
		)
		(fp_line
			(start -0.67945 0.3048)
			(end -0.67945 -0.305054)
			(stroke
				(width 0.1)
				(type default)
			)
			(layer "F.Fab")
		)
		(pad "1" smd circle
			(at -0.40005 0 90)
			(size 0 0)
			(layers "F.Cu" "F.Mask" "F.Paste")
			(net "PVDD18_S5_P0")
		)
		(pad "2" smd circle
			(at 0.40005 0 90)
			(size 0 0)
			(layers "F.Cu" "F.Mask" "F.Paste")
			(net "SPI_CPU0_D0")
		)
	)
	(footprint ""
		(layer "F.Cu")
		(at 104.267 -416.814 180)
		(property "Reference" "R579"
			(at 0 0 180)
			(layer "F.SilkS")
			(hide yes)
			(effects
				(font
					(size 1.27 1.27)
				)
			)
		)
		(property "Value" ""
			(at 0 0 180)
			(layer "F.Fab")
			(effects
				(font
					(size 1.27 1.27)
				)
			)
		)
		(duplicate_pad_numbers_are_jumpers no)
		(fp_line
			(start 0.7874 0.4064)
			(end -0.7874 0.4064)
			(stroke
				(width 0.1524)
				(type default)
			)
			(layer "F.SilkS")
		)
		(fp_line
			(start 0.7874 -0.4064)
			(end 0.7874 0.4064)
			(stroke
				(width 0.1524)
				(type default)
			)
			(layer "F.SilkS")
		)
		(fp_line
			(start -0.7874 0.4064)
			(end -0.7874 -0.4064)
			(stroke
				(width 0.1524)
				(type default)
			)
			(layer "F.SilkS")
		)
		(fp_line
			(start -0.7874 -0.4064)
			(end 0.7874 -0.4064)
			(stroke
				(width 0.1524)
				(type default)
			)
			(layer "F.SilkS")
		)
		(fp_line
			(start 0.67945 0.3048)
			(end 0.120396 0.3048)
			(stroke
				(width 0.1)
				(type default)
			)
			(layer "F.Fab")
		)
		(fp_line
			(start 0.67945 -0.3048)
			(end 0.67945 0.3048)
			(stroke
				(width 0.1)
				(type default)
			)
			(layer "F.Fab")
		)
		(fp_line
			(start 0.12065 -0.2794)
			(end 0.12065 -0.3048)
			(stroke
				(width 0.1)
				(type default)
			)
			(layer "F.Fab")
		)
		(fp_line
			(start 0.12065 -0.3048)
			(end 0.67945 -0.3048)
			(stroke
				(width 0.1)
				(type default)
			)
			(layer "F.Fab")
		)
		(fp_line
			(start 0.120396 0.3048)
			(end 0.120396 0.2794)
			(stroke
				(width 0.1)
				(type default)
			)
			(layer "F.Fab")
		)
		(fp_line
			(start 0.120396 0.2794)
			(end -0.12065 0.2794)
			(stroke
				(width 0.1)
				(type default)
			)
			(layer "F.Fab")
		)
		(fp_line
			(start -0.12065 0.3048)
			(end -0.67945 0.3048)
			(stroke
				(width 0.1)
				(type default)
			)
			(layer "F.Fab")
		)
		(fp_line
			(start -0.12065 0.2794)
			(end -0.12065 0.3048)
			(stroke
				(width 0.1)
				(type default)
			)
			(layer "F.Fab")
		)
		(fp_line
			(start -0.12065 -0.2794)
			(end 0.12065 -0.2794)
			(stroke
				(width 0.1)
				(type default)
			)
			(layer "F.Fab")
		)
		(fp_line
			(start -0.12065 -0.305054)
			(end -0.12065 -0.2794)
			(stroke
				(width 0.1)
				(type default)
			)
			(layer "F.Fab")
		)
		(fp_line
			(start -0.67945 0.3048)
			(end -0.67945 -0.305054)
			(stroke
				(width 0.1)
				(type default)
			)
			(layer "F.Fab")
		)
		(fp_line
			(start -0.67945 -0.305054)
			(end -0.12065 -0.305054)
			(stroke
				(width 0.1)
				(type default)
			)
			(layer "F.Fab")
		)
		(pad "1" smd circle
			(at -0.40005 0 180)
			(size 0 0)
			(layers "F.Cu" "F.Mask" "F.Paste")
			(net "CLK_9ZXL045_P1_SADR0")
		)
		(pad "2" smd circle
			(at 0.40005 0 180)
			(size 0 0)
			(layers "F.Cu" "F.Mask" "F.Paste")
			(net "GND")
		)
	)
	(footprint ""
		(layer "F.Cu")
		(at 26.793444 -423.509694 180)
		(property "Reference" "R3278"
			(at 0 0 180)
			(layer "F.SilkS")
			(hide yes)
			(effects
				(font
					(size 1.27 1.27)
				)
			)
		)
		(property "Value" ""
			(at 0 0 180)
			(layer "F.Fab")
			(effects
				(font
					(size 1.27 1.27)
				)
			)
		)
		(duplicate_pad_numbers_are_jumpers no)
		(fp_line
			(start 0.7874 0.4064)
			(end -0.7874 0.4064)
			(stroke
				(width 0.1524)
				(type default)
			)
			(layer "F.SilkS")
		)
		(fp_line
			(start 0.7874 -0.4064)
			(end 0.7874 0.4064)
			(stroke
				(width 0.1524)
				(type default)
			)
			(layer "F.SilkS")
		)
		(fp_line
			(start -0.7874 0.4064)
			(end -0.7874 -0.4064)
			(stroke
				(width 0.1524)
				(type default)
			)
			(layer "F.SilkS")
		)
		(fp_line
			(start -0.7874 -0.4064)
			(end 0.7874 -0.4064)
			(stroke
				(width 0.1524)
				(type default)
			)
			(layer "F.SilkS")
		)
		(fp_line
			(start 0.67945 0.3048)
			(end 0.120396 0.3048)
			(stroke
				(width 0.1)
				(type default)
			)
			(layer "F.Fab")
		)
		(fp_line
			(start 0.67945 -0.3048)
			(end 0.67945 0.3048)
			(stroke
				(width 0.1)
				(type default)
			)
			(layer "F.Fab")
		)
		(fp_line
			(start 0.12065 -0.2794)
			(end 0.12065 -0.3048)
			(stroke
				(width 0.1)
				(type default)
			)
			(layer "F.Fab")
		)
		(fp_line
			(start 0.12065 -0.3048)
			(end 0.67945 -0.3048)
			(stroke
				(width 0.1)
				(type default)
			)
			(layer "F.Fab")
		)
		(fp_line
			(start 0.120396 0.3048)
			(end 0.120396 0.2794)
			(stroke
				(width 0.1)
				(type default)
			)
			(layer "F.Fab")
		)
		(fp_line
			(start 0.120396 0.2794)
			(end -0.12065 0.2794)
			(stroke
				(width 0.1)
				(type default)
			)
			(layer "F.Fab")
		)
		(fp_line
			(start -0.12065 0.3048)
			(end -0.67945 0.3048)
			(stroke
				(width 0.1)
				(type default)
			)
			(layer "F.Fab")
		)
		(fp_line
			(start -0.12065 0.2794)
			(end -0.12065 0.3048)
			(stroke
				(width 0.1)
				(type default)
			)
			(layer "F.Fab")
		)
		(fp_line
			(start -0.12065 -0.2794)
			(end 0.12065 -0.2794)
			(stroke
				(width 0.1)
				(type default)
			)
			(layer "F.Fab")
		)
		(fp_line
			(start -0.12065 -0.305054)
			(end -0.12065 -0.2794)
			(stroke
				(width 0.1)
				(type default)
			)
			(layer "F.Fab")
		)
		(fp_line
			(start -0.67945 0.3048)
			(end -0.67945 -0.305054)
			(stroke
				(width 0.1)
				(type default)
			)
			(layer "F.Fab")
		)
		(fp_line
			(start -0.67945 -0.305054)
			(end -0.12065 -0.305054)
			(stroke
				(width 0.1)
				(type default)
			)
			(layer "F.Fab")
		)
		(pad "1" smd circle
			(at -0.40005 0 180)
			(size 0 0)
			(layers "F.Cu" "F.Mask" "F.Paste")
			(net "FM_P2E_EQA0")
		)
		(pad "2" smd circle
			(at 0.40005 0 180)
			(size 0 0)
			(layers "F.Cu" "F.Mask" "F.Paste")
			(net "GND")
		)
	)
	(footprint ""
		(layer "F.Cu")
		(at 75.49515 -375.94286 180)
		(property "Reference" "C739"
			(at 0 0 180)
			(layer "F.SilkS")
			(hide yes)
			(effects
				(font
					(size 1.27 1.27)
				)
			)
		)
		(property "Value" ""
			(at 0 0 180)
			(layer "F.Fab")
			(effects
				(font
					(size 1.27 1.27)
				)
			)
		)
		(duplicate_pad_numbers_are_jumpers no)
		(fp_line
			(start 0.299974 0.150114)
			(end -0.299974 0.150114)
			(stroke
				(width 0.1)
				(type default)
			)
			(layer "F.Fab")
		)
		(fp_line
			(start 0.299974 -0.150114)
			(end 0.299974 0.150114)
			(stroke
				(width 0.1)
				(type default)
			)
			(layer "F.Fab")
		)
		(fp_line
			(start -0.299974 0.150114)
			(end -0.299974 -0.150114)
			(stroke
				(width 0.1)
				(type default)
			)
			(layer "F.Fab")
		)
		(fp_line
			(start -0.299974 -0.150114)
			(end 0.299974 -0.150114)
			(stroke
				(width 0.1)
				(type default)
			)
			(layer "F.Fab")
		)
		(pad "1" smd rect
			(at -0.2667 0 180)
			(size 0.3048 0.381)
			(layers "F.Cu" "F.Mask" "F.Paste")
			(net "P5E_CPU1_P1_TX_C_DP<1>")
		)
		(pad "2" smd rect
			(at 0.2667 0 180)
			(size 0.3048 0.381)
			(layers "F.Cu" "F.Mask" "F.Paste")
			(net "P5E_CPU1_P1_TX_DP<1>")
		)
	)
	(footprint ""
		(layer "F.Cu")
		(at 357.338122 -164.284406)
		(property "Reference" "PR353"
			(at 0 0 0)
			(layer "F.SilkS")
			(hide yes)
			(effects
				(font
					(size 1.27 1.27)
				)
			)
		)
		(property "Value" ""
			(at 0 0 0)
			(layer "F.Fab")
			(effects
				(font
					(size 1.27 1.27)
				)
			)
		)
		(duplicate_pad_numbers_are_jumpers no)
		(fp_line
			(start -0.7874 -0.4064)
			(end 0.7874 -0.4064)
			(stroke
				(width 0.1524)
				(type default)
			)
			(layer "F.SilkS")
		)
		(fp_line
			(start -0.7874 0.4064)
			(end -0.7874 -0.4064)
			(stroke
				(width 0.1524)
				(type default)
			)
			(layer "F.SilkS")
		)
		(fp_line
			(start 0.7874 -0.4064)
			(end 0.7874 0.4064)
			(stroke
				(width 0.1524)
				(type default)
			)
			(layer "F.SilkS")
		)
		(fp_line
			(start 0.7874 0.4064)
			(end -0.7874 0.4064)
			(stroke
				(width 0.1524)
				(type default)
			)
			(layer "F.SilkS")
		)
		(fp_line
			(start -0.67945 -0.305054)
			(end -0.12065 -0.305054)
			(stroke
				(width 0.1)
				(type default)
			)
			(layer "F.Fab")
		)
		(fp_line
			(start -0.67945 0.3048)
			(end -0.67945 -0.305054)
			(stroke
				(width 0.1)
				(type default)
			)
			(layer "F.Fab")
		)
		(fp_line
			(start -0.12065 -0.305054)
			(end -0.12065 -0.2794)
			(stroke
				(width 0.1)
				(type default)
			)
			(layer "F.Fab")
		)
		(fp_line
			(start -0.12065 -0.2794)
			(end 0.12065 -0.2794)
			(stroke
				(width 0.1)
				(type default)
			)
			(layer "F.Fab")
		)
		(fp_line
			(start -0.12065 0.2794)
			(end -0.12065 0.3048)
			(stroke
				(width 0.1)
				(type default)
			)
			(layer "F.Fab")
		)
		(fp_line
			(start -0.12065 0.3048)
			(end -0.67945 0.3048)
			(stroke
				(width 0.1)
				(type default)
			)
			(layer "F.Fab")
		)
		(fp_line
			(start 0.120396 0.2794)
			(end -0.12065 0.2794)
			(stroke
				(width 0.1)
				(type default)
			)
			(layer "F.Fab")
		)
		(fp_line
			(start 0.120396 0.3048)
			(end 0.120396 0.2794)
			(stroke
				(width 0.1)
				(type default)
			)
			(layer "F.Fab")
		)
		(fp_line
			(start 0.12065 -0.3048)
			(end 0.67945 -0.3048)
			(stroke
				(width 0.1)
				(type default)
			)
			(layer "F.Fab")
		)
		(fp_line
			(start 0.12065 -0.2794)
			(end 0.12065 -0.3048)
			(stroke
				(width 0.1)
				(type default)
			)
			(layer "F.Fab")
		)
		(fp_line
			(start 0.67945 -0.3048)
			(end 0.67945 0.3048)
			(stroke
				(width 0.1)
				(type default)
			)
			(layer "F.Fab")
		)
		(fp_line
			(start 0.67945 0.3048)
			(end 0.120396 0.3048)
			(stroke
				(width 0.1)
				(type default)
			)
			(layer "F.Fab")
		)
		(pad "1" smd circle
			(at -0.40005 0)
			(size 0 0)
			(layers "F.Cu" "F.Mask" "F.Paste")
			(net "GND")
		)
		(pad "2" smd circle
			(at 0.40005 0)
			(size 0 0)
			(layers "F.Cu" "F.Mask" "F.Paste")
			(net "PVDDCR_CPU0_P0_LSET5")
		)
	)
	(footprint ""
		(layer "F.Cu")
		(at 163.703 -110.200948 180)
		(property "Reference" "R1195"
			(at 0 0 180)
			(layer "F.SilkS")
			(hide yes)
			(effects
				(font
					(size 1.27 1.27)
				)
			)
		)
		(property "Value" ""
			(at 0 0 180)
			(layer "F.Fab")
			(effects
				(font
					(size 1.27 1.27)
				)
			)
		)
		(duplicate_pad_numbers_are_jumpers no)
		(fp_line
			(start 0.7874 0.4064)
			(end -0.7874 0.4064)
			(stroke
				(width 0.1524)
				(type default)
			)
			(layer "F.SilkS")
		)
		(fp_line
			(start 0.7874 -0.4064)
			(end 0.7874 0.4064)
			(stroke
				(width 0.1524)
				(type default)
			)
			(layer "F.SilkS")
		)
		(fp_line
			(start -0.7874 0.4064)
			(end -0.7874 -0.4064)
			(stroke
				(width 0.1524)
				(type default)
			)
			(layer "F.SilkS")
		)
		(fp_line
			(start -0.7874 -0.4064)
			(end 0.7874 -0.4064)
			(stroke
				(width 0.1524)
				(type default)
			)
			(layer "F.SilkS")
		)
		(fp_line
			(start 0.67945 0.3048)
			(end 0.120396 0.3048)
			(stroke
				(width 0.1)
				(type default)
			)
			(layer "F.Fab")
		)
		(fp_line
			(start 0.67945 -0.3048)
			(end 0.67945 0.3048)
			(stroke
				(width 0.1)
				(type default)
			)
			(layer "F.Fab")
		)
		(fp_line
			(start 0.12065 -0.2794)
			(end 0.12065 -0.3048)
			(stroke
				(width 0.1)
				(type default)
			)
			(layer "F.Fab")
		)
		(fp_line
			(start 0.12065 -0.3048)
			(end 0.67945 -0.3048)
			(stroke
				(width 0.1)
				(type default)
			)
			(layer "F.Fab")
		)
		(fp_line
			(start 0.120396 0.3048)
			(end 0.120396 0.2794)
			(stroke
				(width 0.1)
				(type default)
			)
			(layer "F.Fab")
		)
		(fp_line
			(start 0.120396 0.2794)
			(end -0.12065 0.2794)
			(stroke
				(width 0.1)
				(type default)
			)
			(layer "F.Fab")
		)
		(fp_line
			(start -0.12065 0.3048)
			(end -0.67945 0.3048)
			(stroke
				(width 0.1)
				(type default)
			)
			(layer "F.Fab")
		)
		(fp_line
			(start -0.12065 0.2794)
			(end -0.12065 0.3048)
			(stroke
				(width 0.1)
				(type default)
			)
			(layer "F.Fab")
		)
		(fp_line
			(start -0.12065 -0.2794)
			(end 0.12065 -0.2794)
			(stroke
				(width 0.1)
				(type default)
			)
			(layer "F.Fab")
		)
		(fp_line
			(start -0.12065 -0.305054)
			(end -0.12065 -0.2794)
			(stroke
				(width 0.1)
				(type default)
			)
			(layer "F.Fab")
		)
		(fp_line
			(start -0.67945 0.3048)
			(end -0.67945 -0.305054)
			(stroke
				(width 0.1)
				(type default)
			)
			(layer "F.Fab")
		)
		(fp_line
			(start -0.67945 -0.305054)
			(end -0.12065 -0.305054)
			(stroke
				(width 0.1)
				(type default)
			)
			(layer "F.Fab")
		)
		(pad "1" smd circle
			(at -0.40005 0 180)
			(size 0 0)
			(layers "F.Cu" "F.Mask" "F.Paste")
			(net "P12V_OCP_SFF_EN_R")
		)
		(pad "2" smd circle
			(at 0.40005 0 180)
			(size 0 0)
			(layers "F.Cu" "F.Mask" "F.Paste")
			(net "P3V3_AUX")
		)
	)
	(footprint ""
		(layer "F.Cu")
		(at 307.746146 -416.899344 -90)
		(property "Reference" "C6503"
			(at 0 0 270)
			(layer "F.SilkS")
			(hide yes)
			(effects
				(font
					(size 1.27 1.27)
				)
			)
		)
		(property "Value" ""
			(at 0 0 270)
			(layer "F.Fab")
			(effects
				(font
					(size 1.27 1.27)
				)
			)
		)
		(duplicate_pad_numbers_are_jumpers no)
		(fp_line
			(start -0.299974 0.150114)
			(end -0.299974 -0.150114)
			(stroke
				(width 0.1)
				(type default)
			)
			(layer "F.Fab")
		)
		(fp_line
			(start 0.299974 0.150114)
			(end -0.299974 0.150114)
			(stroke
				(width 0.1)
				(type default)
			)
			(layer "F.Fab")
		)
		(fp_line
			(start -0.299974 -0.150114)
			(end 0.299974 -0.150114)
			(stroke
				(width 0.1)
				(type default)
			)
			(layer "F.Fab")
		)
		(fp_line
			(start 0.299974 -0.150114)
			(end 0.299974 0.150114)
			(stroke
				(width 0.1)
				(type default)
			)
			(layer "F.Fab")
		)
		(pad "1" smd rect
			(at -0.2667 0 270)
			(size 0.3048 0.381)
			(layers "F.Cu" "F.Mask" "F.Paste")
			(net "P5E_CPU0_P0_TX_BUF_C_DP<1>")
		)
		(pad "2" smd rect
			(at 0.2667 0 270)
			(size 0.3048 0.381)
			(layers "F.Cu" "F.Mask" "F.Paste")
			(net "P5E_CPU0_P0_TX_BUF_DP<1>")
		)
	)
	(footprint ""
		(layer "F.Cu")
		(at 455.01306 -38.565836)
		(property "Reference" "R45"
			(at 0 0 0)
			(layer "F.SilkS")
			(hide yes)
			(effects
				(font
					(size 1.27 1.27)
				)
			)
		)
		(property "Value" ""
			(at 0 0 0)
			(layer "F.Fab")
			(effects
				(font
					(size 1.27 1.27)
				)
			)
		)
		(duplicate_pad_numbers_are_jumpers no)
		(fp_line
			(start -0.7874 -0.4064)
			(end 0.7874 -0.4064)
			(stroke
				(width 0.1524)
				(type default)
			)
			(layer "F.SilkS")
		)
		(fp_line
			(start -0.7874 0.4064)
			(end -0.7874 -0.4064)
			(stroke
				(width 0.1524)
				(type default)
			)
			(layer "F.SilkS")
		)
		(fp_line
			(start 0.7874 -0.4064)
			(end 0.7874 0.4064)
			(stroke
				(width 0.1524)
				(type default)
			)
			(layer "F.SilkS")
		)
		(fp_line
			(start 0.7874 0.4064)
			(end -0.7874 0.4064)
			(stroke
				(width 0.1524)
				(type default)
			)
			(layer "F.SilkS")
		)
		(fp_line
			(start -0.67945 -0.305054)
			(end -0.12065 -0.305054)
			(stroke
				(width 0.1)
				(type default)
			)
			(layer "F.Fab")
		)
		(fp_line
			(start -0.67945 0.3048)
			(end -0.67945 -0.305054)
			(stroke
				(width 0.1)
				(type default)
			)
			(layer "F.Fab")
		)
		(fp_line
			(start -0.12065 -0.305054)
			(end -0.12065 -0.2794)
			(stroke
				(width 0.1)
				(type default)
			)
			(layer "F.Fab")
		)
		(fp_line
			(start -0.12065 -0.2794)
			(end 0.12065 -0.2794)
			(stroke
				(width 0.1)
				(type default)
			)
			(layer "F.Fab")
		)
		(fp_line
			(start -0.12065 0.2794)
			(end -0.12065 0.3048)
			(stroke
				(width 0.1)
				(type default)
			)
			(layer "F.Fab")
		)
		(fp_line
			(start -0.12065 0.3048)
			(end -0.67945 0.3048)
			(stroke
				(width 0.1)
				(type default)
			)
			(layer "F.Fab")
		)
		(fp_line
			(start 0.120396 0.2794)
			(end -0.12065 0.2794)
			(stroke
				(width 0.1)
				(type default)
			)
			(layer "F.Fab")
		)
		(fp_line
			(start 0.120396 0.3048)
			(end 0.120396 0.2794)
			(stroke
				(width 0.1)
				(type default)
			)
			(layer "F.Fab")
		)
		(fp_line
			(start 0.12065 -0.3048)
			(end 0.67945 -0.3048)
			(stroke
				(width 0.1)
				(type default)
			)
			(layer "F.Fab")
		)
		(fp_line
			(start 0.12065 -0.2794)
			(end 0.12065 -0.3048)
			(stroke
				(width 0.1)
				(type default)
			)
			(layer "F.Fab")
		)
		(fp_line
			(start 0.67945 -0.3048)
			(end 0.67945 0.3048)
			(stroke
				(width 0.1)
				(type default)
			)
			(layer "F.Fab")
		)
		(fp_line
			(start 0.67945 0.3048)
			(end 0.120396 0.3048)
			(stroke
				(width 0.1)
				(type default)
			)
			(layer "F.Fab")
		)
		(pad "1" smd circle
			(at -0.40005 0)
			(size 0 0)
			(layers "F.Cu" "F.Mask" "F.Paste")
			(net "P3V3_OCP_SFF")
		)
		(pad "2" smd circle
			(at 0.40005 0)
			(size 0 0)
			(layers "F.Cu" "F.Mask" "F.Paste")
			(net "PU_OCP_SFF_WAKE_OE")
		)
	)
	(footprint ""
		(layer "F.Cu")
		(at 148.641562 -41.746424)
		(property "Reference" "R1702"
			(at 0 0 0)
			(layer "F.SilkS")
			(hide yes)
			(effects
				(font
					(size 1.27 1.27)
				)
			)
		)
		(property "Value" ""
			(at 0 0 0)
			(layer "F.Fab")
			(effects
				(font
					(size 1.27 1.27)
				)
			)
		)
		(duplicate_pad_numbers_are_jumpers no)
		(fp_line
			(start -0.7874 -0.4064)
			(end 0.7874 -0.4064)
			(stroke
				(width 0.1524)
				(type default)
			)
			(layer "F.SilkS")
		)
		(fp_line
			(start -0.7874 0.4064)
			(end -0.7874 -0.4064)
			(stroke
				(width 0.1524)
				(type default)
			)
			(layer "F.SilkS")
		)
		(fp_line
			(start 0.7874 -0.4064)
			(end 0.7874 0.4064)
			(stroke
				(width 0.1524)
				(type default)
			)
			(layer "F.SilkS")
		)
		(fp_line
			(start 0.7874 0.4064)
			(end -0.7874 0.4064)
			(stroke
				(width 0.1524)
				(type default)
			)
			(layer "F.SilkS")
		)
		(fp_line
			(start -0.67945 -0.305054)
			(end -0.12065 -0.305054)
			(stroke
				(width 0.1)
				(type default)
			)
			(layer "F.Fab")
		)
		(fp_line
			(start -0.67945 0.3048)
			(end -0.67945 -0.305054)
			(stroke
				(width 0.1)
				(type default)
			)
			(layer "F.Fab")
		)
		(fp_line
			(start -0.12065 -0.305054)
			(end -0.12065 -0.2794)
			(stroke
				(width 0.1)
				(type default)
			)
			(layer "F.Fab")
		)
		(fp_line
			(start -0.12065 -0.2794)
			(end 0.12065 -0.2794)
			(stroke
				(width 0.1)
				(type default)
			)
			(layer "F.Fab")
		)
		(fp_line
			(start -0.12065 0.2794)
			(end -0.12065 0.3048)
			(stroke
				(width 0.1)
				(type default)
			)
			(layer "F.Fab")
		)
		(fp_line
			(start -0.12065 0.3048)
			(end -0.67945 0.3048)
			(stroke
				(width 0.1)
				(type default)
			)
			(layer "F.Fab")
		)
		(fp_line
			(start 0.120396 0.2794)
			(end -0.12065 0.2794)
			(stroke
				(width 0.1)
				(type default)
			)
			(layer "F.Fab")
		)
		(fp_line
			(start 0.120396 0.3048)
			(end 0.120396 0.2794)
			(stroke
				(width 0.1)
				(type default)
			)
			(layer "F.Fab")
		)
		(fp_line
			(start 0.12065 -0.3048)
			(end 0.67945 -0.3048)
			(stroke
				(width 0.1)
				(type default)
			)
			(layer "F.Fab")
		)
		(fp_line
			(start 0.12065 -0.2794)
			(end 0.12065 -0.3048)
			(stroke
				(width 0.1)
				(type default)
			)
			(layer "F.Fab")
		)
		(fp_line
			(start 0.67945 -0.3048)
			(end 0.67945 0.3048)
			(stroke
				(width 0.1)
				(type default)
			)
			(layer "F.Fab")
		)
		(fp_line
			(start 0.67945 0.3048)
			(end 0.120396 0.3048)
			(stroke
				(width 0.1)
				(type default)
			)
			(layer "F.Fab")
		)
		(pad "1" smd circle
			(at -0.40005 0)
			(size 0 0)
			(layers "F.Cu" "F.Mask" "F.Paste")
			(net "P1V8_AUX")
		)
		(pad "2" smd circle
			(at 0.40005 0)
			(size 0 0)
			(layers "F.Cu" "F.Mask" "F.Paste")
			(net "SMB_M2_P1_1V8AUX_SDA_R")
		)
	)
	(footprint ""
		(layer "F.Cu")
		(at 200.476358 -387.560566 90)
		(property "Reference" "PC1789"
			(at 0 0 90)
			(layer "F.SilkS")
			(hide yes)
			(effects
				(font
					(size 1.27 1.27)
				)
			)
		)
		(property "Value" ""
			(at 0 0 90)
			(layer "F.Fab")
			(effects
				(font
					(size 1.27 1.27)
				)
			)
		)
		(duplicate_pad_numbers_are_jumpers no)
		(fp_line
			(start 0.7874 -0.4064)
			(end 0.7874 0.4064)
			(stroke
				(width 0.1524)
				(type default)
			)
			(layer "F.SilkS")
		)
		(fp_line
			(start -0.7874 -0.4064)
			(end 0.7874 -0.4064)
			(stroke
				(width 0.1524)
				(type default)
			)
			(layer "F.SilkS")
		)
		(fp_line
			(start 0.7874 0.4064)
			(end -0.7874 0.4064)
			(stroke
				(width 0.1524)
				(type default)
			)
			(layer "F.SilkS")
		)
		(fp_line
			(start -0.7874 0.4064)
			(end -0.7874 -0.4064)
			(stroke
				(width 0.1524)
				(type default)
			)
			(layer "F.SilkS")
		)
		(fp_line
			(start -0.12065 -0.305054)
			(end -0.12065 -0.2794)
			(stroke
				(width 0.1)
				(type default)
			)
			(layer "F.Fab")
		)
		(fp_line
			(start -0.67945 -0.305054)
			(end -0.12065 -0.305054)
			(stroke
				(width 0.1)
				(type default)
			)
			(layer "F.Fab")
		)
		(fp_line
			(start 0.67945 -0.3048)
			(end 0.67945 0.3048)
			(stroke
				(width 0.1)
				(type default)
			)
			(layer "F.Fab")
		)
		(fp_line
			(start 0.12065 -0.3048)
			(end 0.67945 -0.3048)
			(stroke
				(width 0.1)
				(type default)
			)
			(layer "F.Fab")
		)
		(fp_line
			(start 0.12065 -0.2794)
			(end 0.12065 -0.3048)
			(stroke
				(width 0.1)
				(type default)
			)
			(layer "F.Fab")
		)
		(fp_line
			(start -0.12065 -0.2794)
			(end 0.12065 -0.2794)
			(stroke
				(width 0.1)
				(type default)
			)
			(layer "F.Fab")
		)
		(fp_line
			(start 0.120396 0.2794)
			(end -0.12065 0.2794)
			(stroke
				(width 0.1)
				(type default)
			)
			(layer "F.Fab")
		)
		(fp_line
			(start -0.12065 0.2794)
			(end -0.12065 0.3048)
			(stroke
				(width 0.1)
				(type default)
			)
			(layer "F.Fab")
		)
		(fp_line
			(start 0.67945 0.3048)
			(end 0.120396 0.3048)
			(stroke
				(width 0.1)
				(type default)
			)
			(layer "F.Fab")
		)
		(fp_line
			(start 0.120396 0.3048)
			(end 0.120396 0.2794)
			(stroke
				(width 0.1)
				(type default)
			)
			(layer "F.Fab")
		)
		(fp_line
			(start -0.12065 0.3048)
			(end -0.67945 0.3048)
			(stroke
				(width 0.1)
				(type default)
			)
			(layer "F.Fab")
		)
		(fp_line
			(start -0.67945 0.3048)
			(end -0.67945 -0.305054)
			(stroke
				(width 0.1)
				(type default)
			)
			(layer "F.Fab")
		)
		(pad "1" smd circle
			(at -0.40005 0 90)
			(size 0 0)
			(layers "F.Cu" "F.Mask" "F.Paste")
			(net "P12V_AUX")
		)
		(pad "2" smd circle
			(at 0.40005 0 90)
			(size 0 0)
			(layers "F.Cu" "F.Mask" "F.Paste")
			(net "GND")
		)
	)
	(footprint ""
		(layer "F.Cu")
		(at 57.75833 -17.623536 90)
		(property "Reference" "C708"
			(at 0 0 90)
			(layer "F.SilkS")
			(hide yes)
			(effects
				(font
					(size 1.27 1.27)
				)
			)
		)
		(property "Value" ""
			(at 0 0 90)
			(layer "F.Fab")
			(effects
				(font
					(size 1.27 1.27)
				)
			)
		)
		(duplicate_pad_numbers_are_jumpers no)
		(fp_line
			(start 0.299974 -0.150114)
			(end 0.299974 0.150114)
			(stroke
				(width 0.1)
				(type default)
			)
			(layer "F.Fab")
		)
		(fp_line
			(start -0.299974 -0.150114)
			(end 0.299974 -0.150114)
			(stroke
				(width 0.1)
				(type default)
			)
			(layer "F.Fab")
		)
		(fp_line
			(start 0.299974 0.150114)
			(end -0.299974 0.150114)
			(stroke
				(width 0.1)
				(type default)
			)
			(layer "F.Fab")
		)
		(fp_line
			(start -0.299974 0.150114)
			(end -0.299974 -0.150114)
			(stroke
				(width 0.1)
				(type default)
			)
			(layer "F.Fab")
		)
		(pad "1" smd rect
			(at -0.2667 0 90)
			(size 0.3048 0.381)
			(layers "F.Cu" "F.Mask" "F.Paste")
			(net "P5E_CPU1_G1_TX_C_DN<0>")
		)
		(pad "2" smd rect
			(at 0.2667 0 90)
			(size 0.3048 0.381)
			(layers "F.Cu" "F.Mask" "F.Paste")
			(net "P5E_CPU1_G1_TX_DN<0>")
		)
	)
	(footprint ""
		(layer "F.Cu")
		(at 191.055498 -428.496476 90)
		(property "Reference" "R2950"
			(at 0 0 90)
			(layer "F.SilkS")
			(hide yes)
			(effects
				(font
					(size 1.27 1.27)
				)
			)
		)
		(property "Value" ""
			(at 0 0 90)
			(layer "F.Fab")
			(effects
				(font
					(size 1.27 1.27)
				)
			)
		)
		(duplicate_pad_numbers_are_jumpers no)
		(fp_line
			(start 0.7874 -0.4064)
			(end 0.7874 0.4064)
			(stroke
				(width 0.1524)
				(type default)
			)
			(layer "F.SilkS")
		)
		(fp_line
			(start -0.7874 -0.4064)
			(end 0.7874 -0.4064)
			(stroke
				(width 0.1524)
				(type default)
			)
			(layer "F.SilkS")
		)
		(fp_line
			(start 0.7874 0.4064)
			(end -0.7874 0.4064)
			(stroke
				(width 0.1524)
				(type default)
			)
			(layer "F.SilkS")
		)
		(fp_line
			(start -0.7874 0.4064)
			(end -0.7874 -0.4064)
			(stroke
				(width 0.1524)
				(type default)
			)
			(layer "F.SilkS")
		)
		(fp_line
			(start -0.12065 -0.305054)
			(end -0.12065 -0.2794)
			(stroke
				(width 0.1)
				(type default)
			)
			(layer "F.Fab")
		)
		(fp_line
			(start -0.67945 -0.305054)
			(end -0.12065 -0.305054)
			(stroke
				(width 0.1)
				(type default)
			)
			(layer "F.Fab")
		)
		(fp_line
			(start 0.67945 -0.3048)
			(end 0.67945 0.3048)
			(stroke
				(width 0.1)
				(type default)
			)
			(layer "F.Fab")
		)
		(fp_line
			(start 0.12065 -0.3048)
			(end 0.67945 -0.3048)
			(stroke
				(width 0.1)
				(type default)
			)
			(layer "F.Fab")
		)
		(fp_line
			(start 0.12065 -0.2794)
			(end 0.12065 -0.3048)
			(stroke
				(width 0.1)
				(type default)
			)
			(layer "F.Fab")
		)
		(fp_line
			(start -0.12065 -0.2794)
			(end 0.12065 -0.2794)
			(stroke
				(width 0.1)
				(type default)
			)
			(layer "F.Fab")
		)
		(fp_line
			(start 0.120396 0.2794)
			(end -0.12065 0.2794)
			(stroke
				(width 0.1)
				(type default)
			)
			(layer "F.Fab")
		)
		(fp_line
			(start -0.12065 0.2794)
			(end -0.12065 0.3048)
			(stroke
				(width 0.1)
				(type default)
			)
			(layer "F.Fab")
		)
		(fp_line
			(start 0.67945 0.3048)
			(end 0.120396 0.3048)
			(stroke
				(width 0.1)
				(type default)
			)
			(layer "F.Fab")
		)
		(fp_line
			(start 0.120396 0.3048)
			(end 0.120396 0.2794)
			(stroke
				(width 0.1)
				(type default)
			)
			(layer "F.Fab")
		)
		(fp_line
			(start -0.12065 0.3048)
			(end -0.67945 0.3048)
			(stroke
				(width 0.1)
				(type default)
			)
			(layer "F.Fab")
		)
		(fp_line
			(start -0.67945 0.3048)
			(end -0.67945 -0.305054)
			(stroke
				(width 0.1)
				(type default)
			)
			(layer "F.Fab")
		)
		(pad "1" smd circle
			(at -0.40005 0 90)
			(size 0 0)
			(layers "F.Cu" "F.Mask" "F.Paste")
			(net "P3V3_AUX")
		)
		(pad "2" smd circle
			(at 0.40005 0 90)
			(size 0 0)
			(layers "F.Cu" "F.Mask" "F.Paste")
			(net "FM_PDB_BUF_EN_R1_N")
		)
	)
	(footprint ""
		(layer "F.Cu")
		(at 302.133 -355.854 180)
		(property "Reference" "C303"
			(at 0 0 180)
			(layer "F.SilkS")
			(hide yes)
			(effects
				(font
					(size 1.27 1.27)
				)
			)
		)
		(property "Value" ""
			(at 0 0 180)
			(layer "F.Fab")
			(effects
				(font
					(size 1.27 1.27)
				)
			)
		)
		(duplicate_pad_numbers_are_jumpers no)
		(fp_line
			(start 0.7874 0.4064)
			(end -0.7874 0.4064)
			(stroke
				(width 0.1524)
				(type default)
			)
			(layer "F.SilkS")
		)
		(fp_line
			(start 0.7874 -0.4064)
			(end 0.7874 0.4064)
			(stroke
				(width 0.1524)
				(type default)
			)
			(layer "F.SilkS")
		)
		(fp_line
			(start -0.7874 0.4064)
			(end -0.7874 -0.4064)
			(stroke
				(width 0.1524)
				(type default)
			)
			(layer "F.SilkS")
		)
		(fp_line
			(start -0.7874 -0.4064)
			(end 0.7874 -0.4064)
			(stroke
				(width 0.1524)
				(type default)
			)
			(layer "F.SilkS")
		)
		(fp_line
			(start 0.67945 0.3048)
			(end 0.120396 0.3048)
			(stroke
				(width 0.1)
				(type default)
			)
			(layer "F.Fab")
		)
		(fp_line
			(start 0.67945 -0.3048)
			(end 0.67945 0.3048)
			(stroke
				(width 0.1)
				(type default)
			)
			(layer "F.Fab")
		)
		(fp_line
			(start 0.12065 -0.2794)
			(end 0.12065 -0.3048)
			(stroke
				(width 0.1)
				(type default)
			)
			(layer "F.Fab")
		)
		(fp_line
			(start 0.12065 -0.3048)
			(end 0.67945 -0.3048)
			(stroke
				(width 0.1)
				(type default)
			)
			(layer "F.Fab")
		)
		(fp_line
			(start 0.120396 0.3048)
			(end 0.120396 0.2794)
			(stroke
				(width 0.1)
				(type default)
			)
			(layer "F.Fab")
		)
		(fp_line
			(start 0.120396 0.2794)
			(end -0.12065 0.2794)
			(stroke
				(width 0.1)
				(type default)
			)
			(layer "F.Fab")
		)
		(fp_line
			(start -0.12065 0.3048)
			(end -0.67945 0.3048)
			(stroke
				(width 0.1)
				(type default)
			)
			(layer "F.Fab")
		)
		(fp_line
			(start -0.12065 0.2794)
			(end -0.12065 0.3048)
			(stroke
				(width 0.1)
				(type default)
			)
			(layer "F.Fab")
		)
		(fp_line
			(start -0.12065 -0.2794)
			(end 0.12065 -0.2794)
			(stroke
				(width 0.1)
				(type default)
			)
			(layer "F.Fab")
		)
		(fp_line
			(start -0.12065 -0.305054)
			(end -0.12065 -0.2794)
			(stroke
				(width 0.1)
				(type default)
			)
			(layer "F.Fab")
		)
		(fp_line
			(start -0.67945 0.3048)
			(end -0.67945 -0.305054)
			(stroke
				(width 0.1)
				(type default)
			)
			(layer "F.Fab")
		)
		(fp_line
			(start -0.67945 -0.305054)
			(end -0.12065 -0.305054)
			(stroke
				(width 0.1)
				(type default)
			)
			(layer "F.Fab")
		)
		(pad "1" smd circle
			(at -0.40005 0 180)
			(size 0 0)
			(layers "F.Cu" "F.Mask" "F.Paste")
			(net "SVID_PVDDCR_CPU1_P0_SVTO")
		)
		(pad "2" smd circle
			(at 0.40005 0 180)
			(size 0 0)
			(layers "F.Cu" "F.Mask" "F.Paste")
			(net "GND")
		)
	)
	(footprint ""
		(layer "F.Cu")
		(at 103.190294 -385.09448 180)
		(property "Reference" "L31"
			(at 0 0 180)
			(layer "F.SilkS")
			(hide yes)
			(effects
				(font
					(size 1.27 1.27)
				)
			)
		)
		(property "Value" ""
			(at 0 0 180)
			(layer "F.Fab")
			(effects
				(font
					(size 1.27 1.27)
				)
			)
		)
		(duplicate_pad_numbers_are_jumpers no)
		(fp_line
			(start 0.762 0.381)
			(end -0.762 0.381)
			(stroke
				(width 0.1524)
				(type default)
			)
			(layer "F.SilkS")
		)
		(fp_line
			(start 0.762 -0.381)
			(end 0.762 0.381)
			(stroke
				(width 0.1524)
				(type default)
			)
			(layer "F.SilkS")
		)
		(fp_line
			(start -0.762 0.381)
			(end -0.762 -0.381)
			(stroke
				(width 0.1524)
				(type default)
			)
			(layer "F.SilkS")
		)
		(fp_line
			(start -0.762 -0.381)
			(end 0.762 -0.381)
			(stroke
				(width 0.1524)
				(type default)
			)
			(layer "F.SilkS")
		)
		(fp_line
			(start 0.680466 0.306324)
			(end 0.118364 0.306324)
			(stroke
				(width 0.1)
				(type default)
			)
			(layer "F.Fab")
		)
		(fp_line
			(start 0.680466 -0.306324)
			(end 0.680466 0.306324)
			(stroke
				(width 0.1)
				(type default)
			)
			(layer "F.Fab")
		)
		(fp_line
			(start 0.118872 -0.2794)
			(end 0.118872 -0.306324)
			(stroke
				(width 0.1)
				(type default)
			)
			(layer "F.Fab")
		)
		(fp_line
			(start 0.118872 -0.306324)
			(end 0.680466 -0.306324)
			(stroke
				(width 0.1)
				(type default)
			)
			(layer "F.Fab")
		)
		(fp_line
			(start 0.118364 0.306324)
			(end 0.118364 0.2794)
			(stroke
				(width 0.1)
				(type default)
			)
			(layer "F.Fab")
		)
		(fp_line
			(start 0.118364 0.2794)
			(end -0.119634 0.2794)
			(stroke
				(width 0.1)
				(type default)
			)
			(layer "F.Fab")
		)
		(fp_line
			(start -0.118364 -0.2794)
			(end 0.118872 -0.2794)
			(stroke
				(width 0.1)
				(type default)
			)
			(layer "F.Fab")
		)
		(fp_line
			(start -0.118364 -0.307086)
			(end -0.118364 -0.2794)
			(stroke
				(width 0.1)
				(type default)
			)
			(layer "F.Fab")
		)
		(fp_line
			(start -0.119634 0.30607)
			(end -0.681736 0.30607)
			(stroke
				(width 0.1)
				(type default)
			)
			(layer "F.Fab")
		)
		(fp_line
			(start -0.119634 0.2794)
			(end -0.119634 0.30607)
			(stroke
				(width 0.1)
				(type default)
			)
			(layer "F.Fab")
		)
		(fp_line
			(start -0.681736 0.30607)
			(end -0.681736 -0.307086)
			(stroke
				(width 0.1)
				(type default)
			)
			(layer "F.Fab")
		)
		(fp_line
			(start -0.681736 -0.307086)
			(end -0.118364 -0.307086)
			(stroke
				(width 0.1)
				(type default)
			)
			(layer "F.Fab")
		)
		(pad "1" smd rect
			(at -0.40005 0)
			(size 0.4572 0.508)
			(layers "F.Cu" "F.Mask" "F.Paste")
			(net "P1V8_CPU1_RT_1D")
		)
		(pad "2" smd rect
			(at 0.40005 0)
			(size 0.4572 0.508)
			(layers "F.Cu" "F.Mask" "F.Paste")
			(net "P1V8_CPU1_RT1_1A_1D")
		)
	)
	(footprint ""
		(layer "F.Cu")
		(at 257.242056 -121.95937 180)
		(property "Reference" "R3714"
			(at 0 0 180)
			(layer "F.SilkS")
			(hide yes)
			(effects
				(font
					(size 1.27 1.27)
				)
			)
		)
		(property "Value" ""
			(at 0 0 180)
			(layer "F.Fab")
			(effects
				(font
					(size 1.27 1.27)
				)
			)
		)
		(duplicate_pad_numbers_are_jumpers no)
		(fp_line
			(start 0.7874 0.4064)
			(end -0.7874 0.4064)
			(stroke
				(width 0.1524)
				(type default)
			)
			(layer "F.SilkS")
		)
		(fp_line
			(start 0.7874 -0.4064)
			(end 0.7874 0.4064)
			(stroke
				(width 0.1524)
				(type default)
			)
			(layer "F.SilkS")
		)
		(fp_line
			(start -0.7874 0.4064)
			(end -0.7874 -0.4064)
			(stroke
				(width 0.1524)
				(type default)
			)
			(layer "F.SilkS")
		)
		(fp_line
			(start -0.7874 -0.4064)
			(end 0.7874 -0.4064)
			(stroke
				(width 0.1524)
				(type default)
			)
			(layer "F.SilkS")
		)
		(fp_line
			(start 0.67945 0.3048)
			(end 0.120396 0.3048)
			(stroke
				(width 0.1)
				(type default)
			)
			(layer "F.Fab")
		)
		(fp_line
			(start 0.67945 -0.3048)
			(end 0.67945 0.3048)
			(stroke
				(width 0.1)
				(type default)
			)
			(layer "F.Fab")
		)
		(fp_line
			(start 0.12065 -0.2794)
			(end 0.12065 -0.3048)
			(stroke
				(width 0.1)
				(type default)
			)
			(layer "F.Fab")
		)
		(fp_line
			(start 0.12065 -0.3048)
			(end 0.67945 -0.3048)
			(stroke
				(width 0.1)
				(type default)
			)
			(layer "F.Fab")
		)
		(fp_line
			(start 0.120396 0.3048)
			(end 0.120396 0.2794)
			(stroke
				(width 0.1)
				(type default)
			)
			(layer "F.Fab")
		)
		(fp_line
			(start 0.120396 0.2794)
			(end -0.12065 0.2794)
			(stroke
				(width 0.1)
				(type default)
			)
			(layer "F.Fab")
		)
		(fp_line
			(start -0.12065 0.3048)
			(end -0.67945 0.3048)
			(stroke
				(width 0.1)
				(type default)
			)
			(layer "F.Fab")
		)
		(fp_line
			(start -0.12065 0.2794)
			(end -0.12065 0.3048)
			(stroke
				(width 0.1)
				(type default)
			)
			(layer "F.Fab")
		)
		(fp_line
			(start -0.12065 -0.2794)
			(end 0.12065 -0.2794)
			(stroke
				(width 0.1)
				(type default)
			)
			(layer "F.Fab")
		)
		(fp_line
			(start -0.12065 -0.305054)
			(end -0.12065 -0.2794)
			(stroke
				(width 0.1)
				(type default)
			)
			(layer "F.Fab")
		)
		(fp_line
			(start -0.67945 0.3048)
			(end -0.67945 -0.305054)
			(stroke
				(width 0.1)
				(type default)
			)
			(layer "F.Fab")
		)
		(fp_line
			(start -0.67945 -0.305054)
			(end -0.12065 -0.305054)
			(stroke
				(width 0.1)
				(type default)
			)
			(layer "F.Fab")
		)
		(pad "1" smd circle
			(at -0.40005 0 180)
			(size 0 0)
			(layers "F.Cu" "F.Mask" "F.Paste")
			(net "SMB_VR_3V3AUX_SDA_R6")
		)
		(pad "2" smd circle
			(at 0.40005 0 180)
			(size 0 0)
			(layers "F.Cu" "F.Mask" "F.Paste")
			(net "SMB_VR_3V3AUX_SDA")
		)
	)
	(footprint ""
		(layer "F.Cu")
		(at 161.999676 -436.87238 90)
		(property "Reference" "C1707"
			(at 0 0 90)
			(layer "F.SilkS")
			(hide yes)
			(effects
				(font
					(size 1.27 1.27)
				)
			)
		)
		(property "Value" ""
			(at 0 0 90)
			(layer "F.Fab")
			(effects
				(font
					(size 1.27 1.27)
				)
			)
		)
		(duplicate_pad_numbers_are_jumpers no)
		(fp_line
			(start 0.7874 -0.4064)
			(end 0.7874 0.4064)
			(stroke
				(width 0.1524)
				(type default)
			)
			(layer "F.SilkS")
		)
		(fp_line
			(start -0.7874 -0.4064)
			(end 0.7874 -0.4064)
			(stroke
				(width 0.1524)
				(type default)
			)
			(layer "F.SilkS")
		)
		(fp_line
			(start 0.7874 0.4064)
			(end -0.7874 0.4064)
			(stroke
				(width 0.1524)
				(type default)
			)
			(layer "F.SilkS")
		)
		(fp_line
			(start -0.7874 0.4064)
			(end -0.7874 -0.4064)
			(stroke
				(width 0.1524)
				(type default)
			)
			(layer "F.SilkS")
		)
		(fp_line
			(start -0.12065 -0.305054)
			(end -0.12065 -0.2794)
			(stroke
				(width 0.1)
				(type default)
			)
			(layer "F.Fab")
		)
		(fp_line
			(start -0.67945 -0.305054)
			(end -0.12065 -0.305054)
			(stroke
				(width 0.1)
				(type default)
			)
			(layer "F.Fab")
		)
		(fp_line
			(start 0.67945 -0.3048)
			(end 0.67945 0.3048)
			(stroke
				(width 0.1)
				(type default)
			)
			(layer "F.Fab")
		)
		(fp_line
			(start 0.12065 -0.3048)
			(end 0.67945 -0.3048)
			(stroke
				(width 0.1)
				(type default)
			)
			(layer "F.Fab")
		)
		(fp_line
			(start 0.12065 -0.2794)
			(end 0.12065 -0.3048)
			(stroke
				(width 0.1)
				(type default)
			)
			(layer "F.Fab")
		)
		(fp_line
			(start -0.12065 -0.2794)
			(end 0.12065 -0.2794)
			(stroke
				(width 0.1)
				(type default)
			)
			(layer "F.Fab")
		)
		(fp_line
			(start 0.120396 0.2794)
			(end -0.12065 0.2794)
			(stroke
				(width 0.1)
				(type default)
			)
			(layer "F.Fab")
		)
		(fp_line
			(start -0.12065 0.2794)
			(end -0.12065 0.3048)
			(stroke
				(width 0.1)
				(type default)
			)
			(layer "F.Fab")
		)
		(fp_line
			(start 0.67945 0.3048)
			(end 0.120396 0.3048)
			(stroke
				(width 0.1)
				(type default)
			)
			(layer "F.Fab")
		)
		(fp_line
			(start 0.120396 0.3048)
			(end 0.120396 0.2794)
			(stroke
				(width 0.1)
				(type default)
			)
			(layer "F.Fab")
		)
		(fp_line
			(start -0.12065 0.3048)
			(end -0.67945 0.3048)
			(stroke
				(width 0.1)
				(type default)
			)
			(layer "F.Fab")
		)
		(fp_line
			(start -0.67945 0.3048)
			(end -0.67945 -0.305054)
			(stroke
				(width 0.1)
				(type default)
			)
			(layer "F.Fab")
		)
		(pad "1" smd circle
			(at -0.40005 0 90)
			(size 0 0)
			(layers "F.Cu" "F.Mask" "F.Paste")
			(net "P3V3_AUX")
		)
		(pad "2" smd circle
			(at 0.40005 0 90)
			(size 0 0)
			(layers "F.Cu" "F.Mask" "F.Paste")
			(net "GND")
		)
	)
	(footprint ""
		(layer "F.Cu")
		(at 170.213782 -390.33323)
		(property "Reference" "C401"
			(at 0 0 0)
			(layer "F.SilkS")
			(hide yes)
			(effects
				(font
					(size 1.27 1.27)
				)
			)
		)
		(property "Value" ""
			(at 0 0 0)
			(layer "F.Fab")
			(effects
				(font
					(size 1.27 1.27)
				)
			)
		)
		(duplicate_pad_numbers_are_jumpers no)
		(fp_line
			(start -1.524 -0.762)
			(end 1.524 -0.762)
			(stroke
				(width 0.1524)
				(type default)
			)
			(layer "F.SilkS")
		)
		(fp_line
			(start -1.524 0.762)
			(end -1.524 -0.762)
			(stroke
				(width 0.1524)
				(type default)
			)
			(layer "F.SilkS")
		)
		(fp_line
			(start 1.524 -0.762)
			(end 1.524 0.762)
			(stroke
				(width 0.1524)
				(type default)
			)
			(layer "F.SilkS")
		)
		(fp_line
			(start 1.524 0.762)
			(end -1.524 0.762)
			(stroke
				(width 0.1524)
				(type default)
			)
			(layer "F.SilkS")
		)
		(fp_line
			(start -1.1049 -0.724916)
			(end -1.1049 0.724916)
			(stroke
				(width 0.1)
				(type default)
			)
			(layer "F.Fab")
		)
		(fp_line
			(start -1.1049 0.724916)
			(end 1.1049 0.724916)
			(stroke
				(width 0.1)
				(type default)
			)
			(layer "F.Fab")
		)
		(fp_line
			(start 1.1049 -0.724916)
			(end -1.1049 -0.724916)
			(stroke
				(width 0.1)
				(type default)
			)
			(layer "F.Fab")
		)
		(fp_line
			(start 1.1049 0.724916)
			(end 1.1049 -0.724916)
			(stroke
				(width 0.1)
				(type default)
			)
			(layer "F.Fab")
		)
		(pad "1" smd rect
			(at -0.889 0 180)
			(size 1.016 1.27)
			(layers "F.Cu" "F.Mask" "F.Paste")
			(net "P0V9_CPU1_RT2_2A")
		)
		(pad "2" smd rect
			(at 0.889 0 180)
			(size 1.016 1.27)
			(layers "F.Cu" "F.Mask" "F.Paste")
			(net "GND")
		)
	)
	(footprint ""
		(layer "F.Cu")
		(at 164.719 -131.953 180)
		(property "Reference" "R482"
			(at 0 0 180)
			(layer "F.SilkS")
			(hide yes)
			(effects
				(font
					(size 1.27 1.27)
				)
			)
		)
		(property "Value" ""
			(at 0 0 180)
			(layer "F.Fab")
			(effects
				(font
					(size 1.27 1.27)
				)
			)
		)
		(duplicate_pad_numbers_are_jumpers no)
		(fp_line
			(start 0.7874 0.4064)
			(end -0.7874 0.4064)
			(stroke
				(width 0.1524)
				(type default)
			)
			(layer "F.SilkS")
		)
		(fp_line
			(start 0.7874 -0.4064)
			(end 0.7874 0.4064)
			(stroke
				(width 0.1524)
				(type default)
			)
			(layer "F.SilkS")
		)
		(fp_line
			(start -0.7874 0.4064)
			(end -0.7874 -0.4064)
			(stroke
				(width 0.1524)
				(type default)
			)
			(layer "F.SilkS")
		)
		(fp_line
			(start -0.7874 -0.4064)
			(end 0.7874 -0.4064)
			(stroke
				(width 0.1524)
				(type default)
			)
			(layer "F.SilkS")
		)
		(fp_line
			(start 0.67945 0.3048)
			(end 0.120396 0.3048)
			(stroke
				(width 0.1)
				(type default)
			)
			(layer "F.Fab")
		)
		(fp_line
			(start 0.67945 -0.3048)
			(end 0.67945 0.3048)
			(stroke
				(width 0.1)
				(type default)
			)
			(layer "F.Fab")
		)
		(fp_line
			(start 0.12065 -0.2794)
			(end 0.12065 -0.3048)
			(stroke
				(width 0.1)
				(type default)
			)
			(layer "F.Fab")
		)
		(fp_line
			(start 0.12065 -0.3048)
			(end 0.67945 -0.3048)
			(stroke
				(width 0.1)
				(type default)
			)
			(layer "F.Fab")
		)
		(fp_line
			(start 0.120396 0.3048)
			(end 0.120396 0.2794)
			(stroke
				(width 0.1)
				(type default)
			)
			(layer "F.Fab")
		)
		(fp_line
			(start 0.120396 0.2794)
			(end -0.12065 0.2794)
			(stroke
				(width 0.1)
				(type default)
			)
			(layer "F.Fab")
		)
		(fp_line
			(start -0.12065 0.3048)
			(end -0.67945 0.3048)
			(stroke
				(width 0.1)
				(type default)
			)
			(layer "F.Fab")
		)
		(fp_line
			(start -0.12065 0.2794)
			(end -0.12065 0.3048)
			(stroke
				(width 0.1)
				(type default)
			)
			(layer "F.Fab")
		)
		(fp_line
			(start -0.12065 -0.2794)
			(end 0.12065 -0.2794)
			(stroke
				(width 0.1)
				(type default)
			)
			(layer "F.Fab")
		)
		(fp_line
			(start -0.12065 -0.305054)
			(end -0.12065 -0.2794)
			(stroke
				(width 0.1)
				(type default)
			)
			(layer "F.Fab")
		)
		(fp_line
			(start -0.67945 0.3048)
			(end -0.67945 -0.305054)
			(stroke
				(width 0.1)
				(type default)
			)
			(layer "F.Fab")
		)
		(fp_line
			(start -0.67945 -0.305054)
			(end -0.12065 -0.305054)
			(stroke
				(width 0.1)
				(type default)
			)
			(layer "F.Fab")
		)
		(pad "1" smd circle
			(at -0.40005 0 180)
			(size 0 0)
			(layers "F.Cu" "F.Mask" "F.Paste")
			(net "PWRGD_P5V_R")
		)
		(pad "2" smd circle
			(at 0.40005 0 180)
			(size 0 0)
			(layers "F.Cu" "F.Mask" "F.Paste")
			(net "PWRGD_P5V_R1")
		)
	)
	(footprint ""
		(layer "F.Cu")
		(at 322.837048 -44.716954)
		(property "Reference" "R3861"
			(at 0 0 0)
			(layer "F.SilkS")
			(hide yes)
			(effects
				(font
					(size 1.27 1.27)
				)
			)
		)
		(property "Value" ""
			(at 0 0 0)
			(layer "F.Fab")
			(effects
				(font
					(size 1.27 1.27)
				)
			)
		)
		(duplicate_pad_numbers_are_jumpers no)
		(fp_line
			(start -0.7874 -0.4064)
			(end 0.7874 -0.4064)
			(stroke
				(width 0.1524)
				(type default)
			)
			(layer "F.SilkS")
		)
		(fp_line
			(start -0.7874 0.4064)
			(end -0.7874 -0.4064)
			(stroke
				(width 0.1524)
				(type default)
			)
			(layer "F.SilkS")
		)
		(fp_line
			(start 0.7874 -0.4064)
			(end 0.7874 0.4064)
			(stroke
				(width 0.1524)
				(type default)
			)
			(layer "F.SilkS")
		)
		(fp_line
			(start 0.7874 0.4064)
			(end -0.7874 0.4064)
			(stroke
				(width 0.1524)
				(type default)
			)
			(layer "F.SilkS")
		)
		(fp_line
			(start -0.67945 -0.305054)
			(end -0.12065 -0.305054)
			(stroke
				(width 0.1)
				(type default)
			)
			(layer "F.Fab")
		)
		(fp_line
			(start -0.67945 0.3048)
			(end -0.67945 -0.305054)
			(stroke
				(width 0.1)
				(type default)
			)
			(layer "F.Fab")
		)
		(fp_line
			(start -0.12065 -0.305054)
			(end -0.12065 -0.2794)
			(stroke
				(width 0.1)
				(type default)
			)
			(layer "F.Fab")
		)
		(fp_line
			(start -0.12065 -0.2794)
			(end 0.12065 -0.2794)
			(stroke
				(width 0.1)
				(type default)
			)
			(layer "F.Fab")
		)
		(fp_line
			(start -0.12065 0.2794)
			(end -0.12065 0.3048)
			(stroke
				(width 0.1)
				(type default)
			)
			(layer "F.Fab")
		)
		(fp_line
			(start -0.12065 0.3048)
			(end -0.67945 0.3048)
			(stroke
				(width 0.1)
				(type default)
			)
			(layer "F.Fab")
		)
		(fp_line
			(start 0.120396 0.2794)
			(end -0.12065 0.2794)
			(stroke
				(width 0.1)
				(type default)
			)
			(layer "F.Fab")
		)
		(fp_line
			(start 0.120396 0.3048)
			(end 0.120396 0.2794)
			(stroke
				(width 0.1)
				(type default)
			)
			(layer "F.Fab")
		)
		(fp_line
			(start 0.12065 -0.3048)
			(end 0.67945 -0.3048)
			(stroke
				(width 0.1)
				(type default)
			)
			(layer "F.Fab")
		)
		(fp_line
			(start 0.12065 -0.2794)
			(end 0.12065 -0.3048)
			(stroke
				(width 0.1)
				(type default)
			)
			(layer "F.Fab")
		)
		(fp_line
			(start 0.67945 -0.3048)
			(end 0.67945 0.3048)
			(stroke
				(width 0.1)
				(type default)
			)
			(layer "F.Fab")
		)
		(fp_line
			(start 0.67945 0.3048)
			(end 0.120396 0.3048)
			(stroke
				(width 0.1)
				(type default)
			)
			(layer "F.Fab")
		)
		(pad "1" smd rect
			(at -0.40005 0 180)
			(size 0.4572 0.508)
			(layers "F.Cu" "F.Mask" "F.Paste")
			(net "P12V_OCP_V3_2_ISENSE_MAM_TIC")
		)
		(pad "2" smd rect
			(at 0.40005 0 180)
			(size 0.4572 0.508)
			(layers "F.Cu" "F.Mask" "F.Paste")
			(net "P12V_OCP_V3_2_ISENSE_TIC")
		)
	)
	(footprint ""
		(layer "F.Cu")
		(at 140.3096 -401.866608 90)
		(property "Reference" "C7006"
			(at 0 0 90)
			(layer "F.SilkS")
			(hide yes)
			(effects
				(font
					(size 1.27 1.27)
				)
			)
		)
		(property "Value" ""
			(at 0 0 90)
			(layer "F.Fab")
			(effects
				(font
					(size 1.27 1.27)
				)
			)
		)
		(duplicate_pad_numbers_are_jumpers no)
		(fp_line
			(start 1.524 -0.762)
			(end 1.524 0.762)
			(stroke
				(width 0.1524)
				(type default)
			)
			(layer "F.SilkS")
		)
		(fp_line
			(start -1.524 -0.762)
			(end 1.524 -0.762)
			(stroke
				(width 0.1524)
				(type default)
			)
			(layer "F.SilkS")
		)
		(fp_line
			(start 1.524 0.762)
			(end -1.524 0.762)
			(stroke
				(width 0.1524)
				(type default)
			)
			(layer "F.SilkS")
		)
		(fp_line
			(start -1.524 0.762)
			(end -1.524 -0.762)
			(stroke
				(width 0.1524)
				(type default)
			)
			(layer "F.SilkS")
		)
		(fp_line
			(start 1.1049 -0.724916)
			(end -1.1049 -0.724916)
			(stroke
				(width 0.1)
				(type default)
			)
			(layer "F.Fab")
		)
		(fp_line
			(start -1.1049 -0.724916)
			(end -1.1049 0.724916)
			(stroke
				(width 0.1)
				(type default)
			)
			(layer "F.Fab")
		)
		(fp_line
			(start 1.1049 0.724916)
			(end 1.1049 -0.724916)
			(stroke
				(width 0.1)
				(type default)
			)
			(layer "F.Fab")
		)
		(fp_line
			(start -1.1049 0.724916)
			(end 1.1049 0.724916)
			(stroke
				(width 0.1)
				(type default)
			)
			(layer "F.Fab")
		)
		(pad "1" smd rect
			(at -0.889 0 270)
			(size 1.016 1.27)
			(layers "F.Cu" "F.Mask" "F.Paste")
			(net "P0V9_CPU1_RT_2D")
		)
		(pad "2" smd rect
			(at 0.889 0 270)
			(size 1.016 1.27)
			(layers "F.Cu" "F.Mask" "F.Paste")
			(net "GND")
		)
	)
	(footprint ""
		(layer "F.Cu")
		(at 9.271 -73.279)
		(property "Reference" "R8015"
			(at 0 0 0)
			(layer "F.SilkS")
			(hide yes)
			(effects
				(font
					(size 1.27 1.27)
				)
			)
		)
		(property "Value" ""
			(at 0 0 0)
			(layer "F.Fab")
			(effects
				(font
					(size 1.27 1.27)
				)
			)
		)
		(duplicate_pad_numbers_are_jumpers no)
		(fp_line
			(start -0.7874 -0.4064)
			(end 0.7874 -0.4064)
			(stroke
				(width 0.1524)
				(type default)
			)
			(layer "F.SilkS")
		)
		(fp_line
			(start -0.7874 0.4064)
			(end -0.7874 -0.4064)
			(stroke
				(width 0.1524)
				(type default)
			)
			(layer "F.SilkS")
		)
		(fp_line
			(start 0.7874 -0.4064)
			(end 0.7874 0.4064)
			(stroke
				(width 0.1524)
				(type default)
			)
			(layer "F.SilkS")
		)
		(fp_line
			(start 0.7874 0.4064)
			(end -0.7874 0.4064)
			(stroke
				(width 0.1524)
				(type default)
			)
			(layer "F.SilkS")
		)
		(fp_line
			(start -0.67945 -0.305054)
			(end -0.12065 -0.305054)
			(stroke
				(width 0.1)
				(type default)
			)
			(layer "F.Fab")
		)
		(fp_line
			(start -0.67945 0.3048)
			(end -0.67945 -0.305054)
			(stroke
				(width 0.1)
				(type default)
			)
			(layer "F.Fab")
		)
		(fp_line
			(start -0.12065 -0.305054)
			(end -0.12065 -0.2794)
			(stroke
				(width 0.1)
				(type default)
			)
			(layer "F.Fab")
		)
		(fp_line
			(start -0.12065 -0.2794)
			(end 0.12065 -0.2794)
			(stroke
				(width 0.1)
				(type default)
			)
			(layer "F.Fab")
		)
		(fp_line
			(start -0.12065 0.2794)
			(end -0.12065 0.3048)
			(stroke
				(width 0.1)
				(type default)
			)
			(layer "F.Fab")
		)
		(fp_line
			(start -0.12065 0.3048)
			(end -0.67945 0.3048)
			(stroke
				(width 0.1)
				(type default)
			)
			(layer "F.Fab")
		)
		(fp_line
			(start 0.120396 0.2794)
			(end -0.12065 0.2794)
			(stroke
				(width 0.1)
				(type default)
			)
			(layer "F.Fab")
		)
		(fp_line
			(start 0.120396 0.3048)
			(end 0.120396 0.2794)
			(stroke
				(width 0.1)
				(type default)
			)
			(layer "F.Fab")
		)
		(fp_line
			(start 0.12065 -0.3048)
			(end 0.67945 -0.3048)
			(stroke
				(width 0.1)
				(type default)
			)
			(layer "F.Fab")
		)
		(fp_line
			(start 0.12065 -0.2794)
			(end 0.12065 -0.3048)
			(stroke
				(width 0.1)
				(type default)
			)
			(layer "F.Fab")
		)
		(fp_line
			(start 0.67945 -0.3048)
			(end 0.67945 0.3048)
			(stroke
				(width 0.1)
				(type default)
			)
			(layer "F.Fab")
		)
		(fp_line
			(start 0.67945 0.3048)
			(end 0.120396 0.3048)
			(stroke
				(width 0.1)
				(type default)
			)
			(layer "F.Fab")
		)
		(pad "1" smd circle
			(at -0.40005 0)
			(size 0 0)
			(layers "F.Cu" "F.Mask" "F.Paste")
			(net "OCP_V3_2_PRSNT01_R_N")
		)
		(pad "2" smd circle
			(at 0.40005 0)
			(size 0 0)
			(layers "F.Cu" "F.Mask" "F.Paste")
			(net "OCP_V3_2_PRSNT01_R1_N")
		)
	)
	(footprint ""
		(layer "F.Cu")
		(at 185.928762 -26.788872 180)
		(property "Reference" "PR4008"
			(at 0 0 180)
			(layer "F.SilkS")
			(hide yes)
			(effects
				(font
					(size 1.27 1.27)
				)
			)
		)
		(property "Value" ""
			(at 0 0 180)
			(layer "F.Fab")
			(effects
				(font
					(size 1.27 1.27)
				)
			)
		)
		(duplicate_pad_numbers_are_jumpers no)
		(fp_line
			(start 0.7874 0.4064)
			(end -0.7874 0.4064)
			(stroke
				(width 0.1524)
				(type default)
			)
			(layer "F.SilkS")
		)
		(fp_line
			(start 0.7874 -0.4064)
			(end 0.7874 0.4064)
			(stroke
				(width 0.1524)
				(type default)
			)
			(layer "F.SilkS")
		)
		(fp_line
			(start -0.7874 0.4064)
			(end -0.7874 -0.4064)
			(stroke
				(width 0.1524)
				(type default)
			)
			(layer "F.SilkS")
		)
		(fp_line
			(start -0.7874 -0.4064)
			(end 0.7874 -0.4064)
			(stroke
				(width 0.1524)
				(type default)
			)
			(layer "F.SilkS")
		)
		(fp_line
			(start 0.67945 0.3048)
			(end 0.120396 0.3048)
			(stroke
				(width 0.1)
				(type default)
			)
			(layer "F.Fab")
		)
		(fp_line
			(start 0.67945 -0.3048)
			(end 0.67945 0.3048)
			(stroke
				(width 0.1)
				(type default)
			)
			(layer "F.Fab")
		)
		(fp_line
			(start 0.12065 -0.2794)
			(end 0.12065 -0.3048)
			(stroke
				(width 0.1)
				(type default)
			)
			(layer "F.Fab")
		)
		(fp_line
			(start 0.12065 -0.3048)
			(end 0.67945 -0.3048)
			(stroke
				(width 0.1)
				(type default)
			)
			(layer "F.Fab")
		)
		(fp_line
			(start 0.120396 0.3048)
			(end 0.120396 0.2794)
			(stroke
				(width 0.1)
				(type default)
			)
			(layer "F.Fab")
		)
		(fp_line
			(start 0.120396 0.2794)
			(end -0.12065 0.2794)
			(stroke
				(width 0.1)
				(type default)
			)
			(layer "F.Fab")
		)
		(fp_line
			(start -0.12065 0.3048)
			(end -0.67945 0.3048)
			(stroke
				(width 0.1)
				(type default)
			)
			(layer "F.Fab")
		)
		(fp_line
			(start -0.12065 0.2794)
			(end -0.12065 0.3048)
			(stroke
				(width 0.1)
				(type default)
			)
			(layer "F.Fab")
		)
		(fp_line
			(start -0.12065 -0.2794)
			(end 0.12065 -0.2794)
			(stroke
				(width 0.1)
				(type default)
			)
			(layer "F.Fab")
		)
		(fp_line
			(start -0.12065 -0.305054)
			(end -0.12065 -0.2794)
			(stroke
				(width 0.1)
				(type default)
			)
			(layer "F.Fab")
		)
		(fp_line
			(start -0.67945 0.3048)
			(end -0.67945 -0.305054)
			(stroke
				(width 0.1)
				(type default)
			)
			(layer "F.Fab")
		)
		(fp_line
			(start -0.67945 -0.305054)
			(end -0.12065 -0.305054)
			(stroke
				(width 0.1)
				(type default)
			)
			(layer "F.Fab")
		)
		(pad "1" smd circle
			(at -0.40005 0 180)
			(size 0 0)
			(layers "F.Cu" "F.Mask" "F.Paste")
			(net "P12V_SCM_SENSE")
		)
		(pad "2" smd circle
			(at 0.40005 0 180)
			(size 0 0)
			(layers "F.Cu" "F.Mask" "F.Paste")
			(net "GND")
		)
	)
	(footprint ""
		(layer "F.Cu")
		(at 70.9676 -382.6764 180)
		(property "Reference" "R6716"
			(at 0 0 180)
			(layer "F.SilkS")
			(hide yes)
			(effects
				(font
					(size 1.27 1.27)
				)
			)
		)
		(property "Value" ""
			(at 0 0 180)
			(layer "F.Fab")
			(effects
				(font
					(size 1.27 1.27)
				)
			)
		)
		(duplicate_pad_numbers_are_jumpers no)
		(fp_line
			(start 0.32512 0.175006)
			(end -0.32512 0.175006)
			(stroke
				(width 0.1)
				(type default)
			)
			(layer "F.Fab")
		)
		(fp_line
			(start 0.32512 -0.175006)
			(end 0.32512 0.175006)
			(stroke
				(width 0.1)
				(type default)
			)
			(layer "F.Fab")
		)
		(fp_line
			(start -0.32512 0.175006)
			(end -0.32512 -0.175006)
			(stroke
				(width 0.1)
				(type default)
			)
			(layer "F.Fab")
		)
		(fp_line
			(start -0.32512 -0.175006)
			(end 0.32512 -0.175006)
			(stroke
				(width 0.1)
				(type default)
			)
			(layer "F.Fab")
		)
		(pad "1" smd rect
			(at -0.2667 0 180)
			(size 0.3048 0.381)
			(layers "F.Cu" "F.Mask" "F.Paste")
			(net "P1V8_CPU1_RT_1D")
		)
		(pad "2" smd rect
			(at 0.2667 0)
			(size 0.3048 0.381)
			(layers "F.Cu" "F.Mask" "F.Paste")
			(net "RT_CPU1_P0_ADDR1")
		)
	)
	(footprint ""
		(layer "F.Cu")
		(at 271.092676 -117.48135)
		(property "Reference" "R6229"
			(at 0 0 0)
			(layer "F.SilkS")
			(hide yes)
			(effects
				(font
					(size 1.27 1.27)
				)
			)
		)
		(property "Value" ""
			(at 0 0 0)
			(layer "F.Fab")
			(effects
				(font
					(size 1.27 1.27)
				)
			)
		)
		(duplicate_pad_numbers_are_jumpers no)
		(fp_line
			(start -0.7874 -0.4064)
			(end 0.7874 -0.4064)
			(stroke
				(width 0.1524)
				(type default)
			)
			(layer "F.SilkS")
		)
		(fp_line
			(start -0.7874 0.4064)
			(end -0.7874 -0.4064)
			(stroke
				(width 0.1524)
				(type default)
			)
			(layer "F.SilkS")
		)
		(fp_line
			(start 0.7874 -0.4064)
			(end 0.7874 0.4064)
			(stroke
				(width 0.1524)
				(type default)
			)
			(layer "F.SilkS")
		)
		(fp_line
			(start 0.7874 0.4064)
			(end -0.7874 0.4064)
			(stroke
				(width 0.1524)
				(type default)
			)
			(layer "F.SilkS")
		)
		(fp_line
			(start -0.67945 -0.305054)
			(end -0.12065 -0.305054)
			(stroke
				(width 0.1)
				(type default)
			)
			(layer "F.Fab")
		)
		(fp_line
			(start -0.67945 0.3048)
			(end -0.67945 -0.305054)
			(stroke
				(width 0.1)
				(type default)
			)
			(layer "F.Fab")
		)
		(fp_line
			(start -0.12065 -0.305054)
			(end -0.12065 -0.2794)
			(stroke
				(width 0.1)
				(type default)
			)
			(layer "F.Fab")
		)
		(fp_line
			(start -0.12065 -0.2794)
			(end 0.12065 -0.2794)
			(stroke
				(width 0.1)
				(type default)
			)
			(layer "F.Fab")
		)
		(fp_line
			(start -0.12065 0.2794)
			(end -0.12065 0.3048)
			(stroke
				(width 0.1)
				(type default)
			)
			(layer "F.Fab")
		)
		(fp_line
			(start -0.12065 0.3048)
			(end -0.67945 0.3048)
			(stroke
				(width 0.1)
				(type default)
			)
			(layer "F.Fab")
		)
		(fp_line
			(start 0.120396 0.2794)
			(end -0.12065 0.2794)
			(stroke
				(width 0.1)
				(type default)
			)
			(layer "F.Fab")
		)
		(fp_line
			(start 0.120396 0.3048)
			(end 0.120396 0.2794)
			(stroke
				(width 0.1)
				(type default)
			)
			(layer "F.Fab")
		)
		(fp_line
			(start 0.12065 -0.3048)
			(end 0.67945 -0.3048)
			(stroke
				(width 0.1)
				(type default)
			)
			(layer "F.Fab")
		)
		(fp_line
			(start 0.12065 -0.2794)
			(end 0.12065 -0.3048)
			(stroke
				(width 0.1)
				(type default)
			)
			(layer "F.Fab")
		)
		(fp_line
			(start 0.67945 -0.3048)
			(end 0.67945 0.3048)
			(stroke
				(width 0.1)
				(type default)
			)
			(layer "F.Fab")
		)
		(fp_line
			(start 0.67945 0.3048)
			(end 0.120396 0.3048)
			(stroke
				(width 0.1)
				(type default)
			)
			(layer "F.Fab")
		)
		(pad "1" smd circle
			(at -0.40005 0)
			(size 0 0)
			(layers "F.Cu" "F.Mask" "F.Paste")
			(net "SMB_P12V_HSC_SCL_R")
		)
		(pad "2" smd circle
			(at 0.40005 0)
			(size 0 0)
			(layers "F.Cu" "F.Mask" "F.Paste")
			(net "SMB_P12V_HSC_SCL")
		)
	)
	(footprint ""
		(layer "F.Cu")
		(at 361.22229 -393.9032 90)
		(property "Reference" "R1015"
			(at 0 0 90)
			(layer "F.SilkS")
			(hide yes)
			(effects
				(font
					(size 1.27 1.27)
				)
			)
		)
		(property "Value" ""
			(at 0 0 90)
			(layer "F.Fab")
			(effects
				(font
					(size 1.27 1.27)
				)
			)
		)
		(duplicate_pad_numbers_are_jumpers no)
		(fp_line
			(start 0.32512 -0.175006)
			(end 0.32512 0.175006)
			(stroke
				(width 0.1)
				(type default)
			)
			(layer "F.Fab")
		)
		(fp_line
			(start -0.32512 -0.175006)
			(end 0.32512 -0.175006)
			(stroke
				(width 0.1)
				(type default)
			)
			(layer "F.Fab")
		)
		(fp_line
			(start 0.32512 0.175006)
			(end -0.32512 0.175006)
			(stroke
				(width 0.1)
				(type default)
			)
			(layer "F.Fab")
		)
		(fp_line
			(start -0.32512 0.175006)
			(end -0.32512 -0.175006)
			(stroke
				(width 0.1)
				(type default)
			)
			(layer "F.Fab")
		)
		(pad "1" smd rect
			(at -0.2667 0 90)
			(size 0.3048 0.381)
			(layers "F.Cu" "F.Mask" "F.Paste")
			(net "P1V8_CPU0_RT_1D")
		)
		(pad "2" smd rect
			(at 0.2667 0 270)
			(size 0.3048 0.381)
			(layers "F.Cu" "F.Mask" "F.Paste")
			(net "RT_CPU0_P1_ADDR2")
		)
	)
	(footprint ""
		(layer "F.Cu")
		(at 141.197838 -168.30167)
		(property "Reference" "TP20"
			(at 1.07442 0.112268 0)
			(unlocked yes)
			(layer "F.SilkS")
			(effects
				(font
					(size 0.7874 0.5842)
					(thickness 0.1524)
				)
				(justify left)
			)
		)
		(property "Value" ""
			(at 0 0 0)
			(layer "F.Fab")
			(effects
				(font
					(size 1.27 1.27)
				)
			)
		)
		(duplicate_pad_numbers_are_jumpers no)
		(pad "1" smd circle
			(at 0 0)
			(size 0.762 0.762)
			(layers "F.Cu" "F.Mask" "F.Paste")
			(net "VSENSE_PVDDCR_SOC_P1_DP")
		)
	)
	(footprint ""
		(layer "F.Cu")
		(at 163.144454 -38.493954 -90)
		(property "Reference" "R2487"
			(at 0 0 270)
			(layer "F.SilkS")
			(hide yes)
			(effects
				(font
					(size 1.27 1.27)
				)
			)
		)
		(property "Value" ""
			(at 0 0 270)
			(layer "F.Fab")
			(effects
				(font
					(size 1.27 1.27)
				)
			)
		)
		(duplicate_pad_numbers_are_jumpers no)
		(fp_line
			(start -0.7874 0.4064)
			(end -0.7874 -0.4064)
			(stroke
				(width 0.1524)
				(type default)
			)
			(layer "F.SilkS")
		)
		(fp_line
			(start 0.7874 0.4064)
			(end -0.7874 0.4064)
			(stroke
				(width 0.1524)
				(type default)
			)
			(layer "F.SilkS")
		)
		(fp_line
			(start -0.7874 -0.4064)
			(end 0.7874 -0.4064)
			(stroke
				(width 0.1524)
				(type default)
			)
			(layer "F.SilkS")
		)
		(fp_line
			(start 0.7874 -0.4064)
			(end 0.7874 0.4064)
			(stroke
				(width 0.1524)
				(type default)
			)
			(layer "F.SilkS")
		)
		(fp_line
			(start -0.67945 0.3048)
			(end -0.67945 -0.305054)
			(stroke
				(width 0.1)
				(type default)
			)
			(layer "F.Fab")
		)
		(fp_line
			(start -0.12065 0.3048)
			(end -0.67945 0.3048)
			(stroke
				(width 0.1)
				(type default)
			)
			(layer "F.Fab")
		)
		(fp_line
			(start 0.120396 0.3048)
			(end 0.120396 0.2794)
			(stroke
				(width 0.1)
				(type default)
			)
			(layer "F.Fab")
		)
		(fp_line
			(start 0.67945 0.3048)
			(end 0.120396 0.3048)
			(stroke
				(width 0.1)
				(type default)
			)
			(layer "F.Fab")
		)
		(fp_line
			(start -0.12065 0.2794)
			(end -0.12065 0.3048)
			(stroke
				(width 0.1)
				(type default)
			)
			(layer "F.Fab")
		)
		(fp_line
			(start 0.120396 0.2794)
			(end -0.12065 0.2794)
			(stroke
				(width 0.1)
				(type default)
			)
			(layer "F.Fab")
		)
		(fp_line
			(start -0.12065 -0.2794)
			(end 0.12065 -0.2794)
			(stroke
				(width 0.1)
				(type default)
			)
			(layer "F.Fab")
		)
		(fp_line
			(start 0.12065 -0.2794)
			(end 0.12065 -0.3048)
			(stroke
				(width 0.1)
				(type default)
			)
			(layer "F.Fab")
		)
		(fp_line
			(start 0.12065 -0.3048)
			(end 0.67945 -0.3048)
			(stroke
				(width 0.1)
				(type default)
			)
			(layer "F.Fab")
		)
		(fp_line
			(start 0.67945 -0.3048)
			(end 0.67945 0.3048)
			(stroke
				(width 0.1)
				(type default)
			)
			(layer "F.Fab")
		)
		(fp_line
			(start -0.67945 -0.305054)
			(end -0.12065 -0.305054)
			(stroke
				(width 0.1)
				(type default)
			)
			(layer "F.Fab")
		)
		(fp_line
			(start -0.12065 -0.305054)
			(end -0.12065 -0.2794)
			(stroke
				(width 0.1)
				(type default)
			)
			(layer "F.Fab")
		)
		(pad "1" smd circle
			(at -0.40005 0 270)
			(size 0 0)
			(layers "F.Cu" "F.Mask" "F.Paste")
			(net "P3V3_AUX")
		)
		(pad "2" smd circle
			(at 0.40005 0 270)
			(size 0 0)
			(layers "F.Cu" "F.Mask" "F.Paste")
			(net "IRQ_LVC3_WAKE_BUF_N")
		)
	)
	(footprint ""
		(layer "F.Cu")
		(at 22.479 -367.919)
		(property "Reference" "R1494"
			(at 0 0 0)
			(layer "F.SilkS")
			(hide yes)
			(effects
				(font
					(size 1.27 1.27)
				)
			)
		)
		(property "Value" ""
			(at 0 0 0)
			(layer "F.Fab")
			(effects
				(font
					(size 1.27 1.27)
				)
			)
		)
		(duplicate_pad_numbers_are_jumpers no)
		(fp_line
			(start -0.7874 -0.4064)
			(end 0.7874 -0.4064)
			(stroke
				(width 0.1524)
				(type default)
			)
			(layer "F.SilkS")
		)
		(fp_line
			(start -0.7874 0.4064)
			(end -0.7874 -0.4064)
			(stroke
				(width 0.1524)
				(type default)
			)
			(layer "F.SilkS")
		)
		(fp_line
			(start 0.7874 -0.4064)
			(end 0.7874 0.4064)
			(stroke
				(width 0.1524)
				(type default)
			)
			(layer "F.SilkS")
		)
		(fp_line
			(start 0.7874 0.4064)
			(end -0.7874 0.4064)
			(stroke
				(width 0.1524)
				(type default)
			)
			(layer "F.SilkS")
		)
		(fp_line
			(start -0.67945 -0.305054)
			(end -0.12065 -0.305054)
			(stroke
				(width 0.1)
				(type default)
			)
			(layer "F.Fab")
		)
		(fp_line
			(start -0.67945 0.3048)
			(end -0.67945 -0.305054)
			(stroke
				(width 0.1)
				(type default)
			)
			(layer "F.Fab")
		)
		(fp_line
			(start -0.12065 -0.305054)
			(end -0.12065 -0.2794)
			(stroke
				(width 0.1)
				(type default)
			)
			(layer "F.Fab")
		)
		(fp_line
			(start -0.12065 -0.2794)
			(end 0.12065 -0.2794)
			(stroke
				(width 0.1)
				(type default)
			)
			(layer "F.Fab")
		)
		(fp_line
			(start -0.12065 0.2794)
			(end -0.12065 0.3048)
			(stroke
				(width 0.1)
				(type default)
			)
			(layer "F.Fab")
		)
		(fp_line
			(start -0.12065 0.3048)
			(end -0.67945 0.3048)
			(stroke
				(width 0.1)
				(type default)
			)
			(layer "F.Fab")
		)
		(fp_line
			(start 0.120396 0.2794)
			(end -0.12065 0.2794)
			(stroke
				(width 0.1)
				(type default)
			)
			(layer "F.Fab")
		)
		(fp_line
			(start 0.120396 0.3048)
			(end 0.120396 0.2794)
			(stroke
				(width 0.1)
				(type default)
			)
			(layer "F.Fab")
		)
		(fp_line
			(start 0.12065 -0.3048)
			(end 0.67945 -0.3048)
			(stroke
				(width 0.1)
				(type default)
			)
			(layer "F.Fab")
		)
		(fp_line
			(start 0.12065 -0.2794)
			(end 0.12065 -0.3048)
			(stroke
				(width 0.1)
				(type default)
			)
			(layer "F.Fab")
		)
		(fp_line
			(start 0.67945 -0.3048)
			(end 0.67945 0.3048)
			(stroke
				(width 0.1)
				(type default)
			)
			(layer "F.Fab")
		)
		(fp_line
			(start 0.67945 0.3048)
			(end 0.120396 0.3048)
			(stroke
				(width 0.1)
				(type default)
			)
			(layer "F.Fab")
		)
		(pad "1" smd circle
			(at -0.40005 0)
			(size 0 0)
			(layers "F.Cu" "F.Mask" "F.Paste")
			(net "SMB_VR_3V3STBY_SDA")
		)
		(pad "2" smd circle
			(at 0.40005 0)
			(size 0 0)
			(layers "F.Cu" "F.Mask" "F.Paste")
			(net "SMB_SCM_2_R1_SDA")
		)
	)
	(footprint ""
		(layer "F.Cu")
		(at 468.950294 -43.252898 180)
		(property "Reference" "R561"
			(at 0 0 180)
			(layer "F.SilkS")
			(hide yes)
			(effects
				(font
					(size 1.27 1.27)
				)
			)
		)
		(property "Value" ""
			(at 0 0 180)
			(layer "F.Fab")
			(effects
				(font
					(size 1.27 1.27)
				)
			)
		)
		(duplicate_pad_numbers_are_jumpers no)
		(fp_line
			(start 0.7874 0.4064)
			(end -0.7874 0.4064)
			(stroke
				(width 0.1524)
				(type default)
			)
			(layer "F.SilkS")
		)
		(fp_line
			(start 0.7874 -0.4064)
			(end 0.7874 0.4064)
			(stroke
				(width 0.1524)
				(type default)
			)
			(layer "F.SilkS")
		)
		(fp_line
			(start -0.7874 0.4064)
			(end -0.7874 -0.4064)
			(stroke
				(width 0.1524)
				(type default)
			)
			(layer "F.SilkS")
		)
		(fp_line
			(start -0.7874 -0.4064)
			(end 0.7874 -0.4064)
			(stroke
				(width 0.1524)
				(type default)
			)
			(layer "F.SilkS")
		)
		(fp_line
			(start 0.67945 0.3048)
			(end 0.120396 0.3048)
			(stroke
				(width 0.1)
				(type default)
			)
			(layer "F.Fab")
		)
		(fp_line
			(start 0.67945 -0.3048)
			(end 0.67945 0.3048)
			(stroke
				(width 0.1)
				(type default)
			)
			(layer "F.Fab")
		)
		(fp_line
			(start 0.12065 -0.2794)
			(end 0.12065 -0.3048)
			(stroke
				(width 0.1)
				(type default)
			)
			(layer "F.Fab")
		)
		(fp_line
			(start 0.12065 -0.3048)
			(end 0.67945 -0.3048)
			(stroke
				(width 0.1)
				(type default)
			)
			(layer "F.Fab")
		)
		(fp_line
			(start 0.120396 0.3048)
			(end 0.120396 0.2794)
			(stroke
				(width 0.1)
				(type default)
			)
			(layer "F.Fab")
		)
		(fp_line
			(start 0.120396 0.2794)
			(end -0.12065 0.2794)
			(stroke
				(width 0.1)
				(type default)
			)
			(layer "F.Fab")
		)
		(fp_line
			(start -0.12065 0.3048)
			(end -0.67945 0.3048)
			(stroke
				(width 0.1)
				(type default)
			)
			(layer "F.Fab")
		)
		(fp_line
			(start -0.12065 0.2794)
			(end -0.12065 0.3048)
			(stroke
				(width 0.1)
				(type default)
			)
			(layer "F.Fab")
		)
		(fp_line
			(start -0.12065 -0.2794)
			(end 0.12065 -0.2794)
			(stroke
				(width 0.1)
				(type default)
			)
			(layer "F.Fab")
		)
		(fp_line
			(start -0.12065 -0.305054)
			(end -0.12065 -0.2794)
			(stroke
				(width 0.1)
				(type default)
			)
			(layer "F.Fab")
		)
		(fp_line
			(start -0.67945 0.3048)
			(end -0.67945 -0.305054)
			(stroke
				(width 0.1)
				(type default)
			)
			(layer "F.Fab")
		)
		(fp_line
			(start -0.67945 -0.305054)
			(end -0.12065 -0.305054)
			(stroke
				(width 0.1)
				(type default)
			)
			(layer "F.Fab")
		)
		(pad "1" smd circle
			(at -0.40005 0 180)
			(size 0 0)
			(layers "F.Cu" "F.Mask" "F.Paste")
			(net "P12V_OCP_SFF_BUF_EN_R")
		)
		(pad "2" smd circle
			(at 0.40005 0 180)
			(size 0 0)
			(layers "F.Cu" "F.Mask" "F.Paste")
			(net "P12V_OCP_EN_1_R")
		)
	)
	(footprint ""
		(layer "F.Cu")
		(at 372.937278 -140.456158)
		(property "Reference" "R8312"
			(at 0 0 0)
			(layer "F.SilkS")
			(hide yes)
			(effects
				(font
					(size 1.27 1.27)
				)
			)
		)
		(property "Value" ""
			(at 0 0 0)
			(layer "F.Fab")
			(effects
				(font
					(size 1.27 1.27)
				)
			)
		)
		(duplicate_pad_numbers_are_jumpers no)
		(fp_line
			(start -0.7874 -0.4064)
			(end 0.7874 -0.4064)
			(stroke
				(width 0.1524)
				(type default)
			)
			(layer "F.SilkS")
		)
		(fp_line
			(start -0.7874 0.4064)
			(end -0.7874 -0.4064)
			(stroke
				(width 0.1524)
				(type default)
			)
			(layer "F.SilkS")
		)
		(fp_line
			(start 0.7874 -0.4064)
			(end 0.7874 0.4064)
			(stroke
				(width 0.1524)
				(type default)
			)
			(layer "F.SilkS")
		)
		(fp_line
			(start 0.7874 0.4064)
			(end -0.7874 0.4064)
			(stroke
				(width 0.1524)
				(type default)
			)
			(layer "F.SilkS")
		)
		(fp_line
			(start -0.67945 -0.305054)
			(end -0.12065 -0.305054)
			(stroke
				(width 0.1)
				(type default)
			)
			(layer "F.Fab")
		)
		(fp_line
			(start -0.67945 0.3048)
			(end -0.67945 -0.305054)
			(stroke
				(width 0.1)
				(type default)
			)
			(layer "F.Fab")
		)
		(fp_line
			(start -0.12065 -0.305054)
			(end -0.12065 -0.2794)
			(stroke
				(width 0.1)
				(type default)
			)
			(layer "F.Fab")
		)
		(fp_line
			(start -0.12065 -0.2794)
			(end 0.12065 -0.2794)
			(stroke
				(width 0.1)
				(type default)
			)
			(layer "F.Fab")
		)
		(fp_line
			(start -0.12065 0.2794)
			(end -0.12065 0.3048)
			(stroke
				(width 0.1)
				(type default)
			)
			(layer "F.Fab")
		)
		(fp_line
			(start -0.12065 0.3048)
			(end -0.67945 0.3048)
			(stroke
				(width 0.1)
				(type default)
			)
			(layer "F.Fab")
		)
		(fp_line
			(start 0.120396 0.2794)
			(end -0.12065 0.2794)
			(stroke
				(width 0.1)
				(type default)
			)
			(layer "F.Fab")
		)
		(fp_line
			(start 0.120396 0.3048)
			(end 0.120396 0.2794)
			(stroke
				(width 0.1)
				(type default)
			)
			(layer "F.Fab")
		)
		(fp_line
			(start 0.12065 -0.3048)
			(end 0.67945 -0.3048)
			(stroke
				(width 0.1)
				(type default)
			)
			(layer "F.Fab")
		)
		(fp_line
			(start 0.12065 -0.2794)
			(end 0.12065 -0.3048)
			(stroke
				(width 0.1)
				(type default)
			)
			(layer "F.Fab")
		)
		(fp_line
			(start 0.67945 -0.3048)
			(end 0.67945 0.3048)
			(stroke
				(width 0.1)
				(type default)
			)
			(layer "F.Fab")
		)
		(fp_line
			(start 0.67945 0.3048)
			(end 0.120396 0.3048)
			(stroke
				(width 0.1)
				(type default)
			)
			(layer "F.Fab")
		)
		(pad "1" smd circle
			(at -0.40005 0)
			(size 0 0)
			(layers "F.Cu" "F.Mask" "F.Paste")
			(net "PVDDCR_CPU0_P0_EN")
		)
		(pad "2" smd circle
			(at 0.40005 0)
			(size 0 0)
			(layers "F.Cu" "F.Mask" "F.Paste")
			(net "PVDDCR_CPU0_P0_EN_R")
		)
	)
	(footprint ""
		(layer "F.Cu")
		(at 22.49805 -333.151226)
		(property "Reference" "PR460"
			(at 0 0 0)
			(layer "F.SilkS")
			(hide yes)
			(effects
				(font
					(size 1.27 1.27)
				)
			)
		)
		(property "Value" ""
			(at 0 0 0)
			(layer "F.Fab")
			(effects
				(font
					(size 1.27 1.27)
				)
			)
		)
		(duplicate_pad_numbers_are_jumpers no)
		(fp_line
			(start -0.7874 -0.4064)
			(end 0.7874 -0.4064)
			(stroke
				(width 0.1524)
				(type default)
			)
			(layer "F.SilkS")
		)
		(fp_line
			(start -0.7874 0.4064)
			(end -0.7874 -0.4064)
			(stroke
				(width 0.1524)
				(type default)
			)
			(layer "F.SilkS")
		)
		(fp_line
			(start 0.7874 -0.4064)
			(end 0.7874 0.4064)
			(stroke
				(width 0.1524)
				(type default)
			)
			(layer "F.SilkS")
		)
		(fp_line
			(start 0.7874 0.4064)
			(end -0.7874 0.4064)
			(stroke
				(width 0.1524)
				(type default)
			)
			(layer "F.SilkS")
		)
		(fp_line
			(start -0.67945 -0.305054)
			(end -0.12065 -0.305054)
			(stroke
				(width 0.1)
				(type default)
			)
			(layer "F.Fab")
		)
		(fp_line
			(start -0.67945 0.3048)
			(end -0.67945 -0.305054)
			(stroke
				(width 0.1)
				(type default)
			)
			(layer "F.Fab")
		)
		(fp_line
			(start -0.12065 -0.305054)
			(end -0.12065 -0.2794)
			(stroke
				(width 0.1)
				(type default)
			)
			(layer "F.Fab")
		)
		(fp_line
			(start -0.12065 -0.2794)
			(end 0.12065 -0.2794)
			(stroke
				(width 0.1)
				(type default)
			)
			(layer "F.Fab")
		)
		(fp_line
			(start -0.12065 0.2794)
			(end -0.12065 0.3048)
			(stroke
				(width 0.1)
				(type default)
			)
			(layer "F.Fab")
		)
		(fp_line
			(start -0.12065 0.3048)
			(end -0.67945 0.3048)
			(stroke
				(width 0.1)
				(type default)
			)
			(layer "F.Fab")
		)
		(fp_line
			(start 0.120396 0.2794)
			(end -0.12065 0.2794)
			(stroke
				(width 0.1)
				(type default)
			)
			(layer "F.Fab")
		)
		(fp_line
			(start 0.120396 0.3048)
			(end 0.120396 0.2794)
			(stroke
				(width 0.1)
				(type default)
			)
			(layer "F.Fab")
		)
		(fp_line
			(start 0.12065 -0.3048)
			(end 0.67945 -0.3048)
			(stroke
				(width 0.1)
				(type default)
			)
			(layer "F.Fab")
		)
		(fp_line
			(start 0.12065 -0.2794)
			(end 0.12065 -0.3048)
			(stroke
				(width 0.1)
				(type default)
			)
			(layer "F.Fab")
		)
		(fp_line
			(start 0.67945 -0.3048)
			(end 0.67945 0.3048)
			(stroke
				(width 0.1)
				(type default)
			)
			(layer "F.Fab")
		)
		(fp_line
			(start 0.67945 0.3048)
			(end 0.120396 0.3048)
			(stroke
				(width 0.1)
				(type default)
			)
			(layer "F.Fab")
		)
		(pad "1" smd circle
			(at -0.40005 0)
			(size 0 0)
			(layers "F.Cu" "F.Mask" "F.Paste")
			(net "VSENSE_VSS_SENSE_B_P1")
		)
		(pad "2" smd circle
			(at 0.40005 0)
			(size 0 0)
			(layers "F.Cu" "F.Mask" "F.Paste")
			(net "GND")
		)
	)
	(footprint ""
		(layer "F.Cu")
		(at 105.960164 -262.205216 180)
		(property "Reference" "C3920"
			(at 0 0 180)
			(layer "F.SilkS")
			(hide yes)
			(effects
				(font
					(size 1.27 1.27)
				)
			)
		)
		(property "Value" ""
			(at 0 0 180)
			(layer "F.Fab")
			(effects
				(font
					(size 1.27 1.27)
				)
			)
		)
		(duplicate_pad_numbers_are_jumpers no)
		(fp_line
			(start 0.7874 0.4064)
			(end -0.7874 0.4064)
			(stroke
				(width 0.1524)
				(type default)
			)
			(layer "F.SilkS")
		)
		(fp_line
			(start 0.7874 -0.4064)
			(end 0.7874 0.4064)
			(stroke
				(width 0.1524)
				(type default)
			)
			(layer "F.SilkS")
		)
		(fp_line
			(start -0.7874 0.4064)
			(end -0.7874 -0.4064)
			(stroke
				(width 0.1524)
				(type default)
			)
			(layer "F.SilkS")
		)
		(fp_line
			(start -0.7874 -0.4064)
			(end 0.7874 -0.4064)
			(stroke
				(width 0.1524)
				(type default)
			)
			(layer "F.SilkS")
		)
		(fp_line
			(start 0.67945 0.3048)
			(end 0.120396 0.3048)
			(stroke
				(width 0.1)
				(type default)
			)
			(layer "F.Fab")
		)
		(fp_line
			(start 0.67945 -0.3048)
			(end 0.67945 0.3048)
			(stroke
				(width 0.1)
				(type default)
			)
			(layer "F.Fab")
		)
		(fp_line
			(start 0.12065 -0.2794)
			(end 0.12065 -0.3048)
			(stroke
				(width 0.1)
				(type default)
			)
			(layer "F.Fab")
		)
		(fp_line
			(start 0.12065 -0.3048)
			(end 0.67945 -0.3048)
			(stroke
				(width 0.1)
				(type default)
			)
			(layer "F.Fab")
		)
		(fp_line
			(start 0.120396 0.3048)
			(end 0.120396 0.2794)
			(stroke
				(width 0.1)
				(type default)
			)
			(layer "F.Fab")
		)
		(fp_line
			(start 0.120396 0.2794)
			(end -0.12065 0.2794)
			(stroke
				(width 0.1)
				(type default)
			)
			(layer "F.Fab")
		)
		(fp_line
			(start -0.12065 0.3048)
			(end -0.67945 0.3048)
			(stroke
				(width 0.1)
				(type default)
			)
			(layer "F.Fab")
		)
		(fp_line
			(start -0.12065 0.2794)
			(end -0.12065 0.3048)
			(stroke
				(width 0.1)
				(type default)
			)
			(layer "F.Fab")
		)
		(fp_line
			(start -0.12065 -0.2794)
			(end 0.12065 -0.2794)
			(stroke
				(width 0.1)
				(type default)
			)
			(layer "F.Fab")
		)
		(fp_line
			(start -0.12065 -0.305054)
			(end -0.12065 -0.2794)
			(stroke
				(width 0.1)
				(type default)
			)
			(layer "F.Fab")
		)
		(fp_line
			(start -0.67945 0.3048)
			(end -0.67945 -0.305054)
			(stroke
				(width 0.1)
				(type default)
			)
			(layer "F.Fab")
		)
		(fp_line
			(start -0.67945 -0.305054)
			(end -0.12065 -0.305054)
			(stroke
				(width 0.1)
				(type default)
			)
			(layer "F.Fab")
		)
		(pad "1" smd circle
			(at -0.40005 0 180)
			(size 0 0)
			(layers "F.Cu" "F.Mask" "F.Paste")
			(net "PVDD11_S3_P1")
		)
		(pad "2" smd circle
			(at 0.40005 0 180)
			(size 0 0)
			(layers "F.Cu" "F.Mask" "F.Paste")
			(net "GND")
		)
	)
	(footprint ""
		(layer "F.Cu")
		(at 423.796206 -402.7424 -90)
		(property "Reference" "R1061"
			(at 0 0 270)
			(layer "F.SilkS")
			(hide yes)
			(effects
				(font
					(size 1.27 1.27)
				)
			)
		)
		(property "Value" ""
			(at 0 0 270)
			(layer "F.Fab")
			(effects
				(font
					(size 1.27 1.27)
				)
			)
		)
		(duplicate_pad_numbers_are_jumpers no)
		(fp_line
			(start -0.32512 0.175006)
			(end -0.32512 -0.175006)
			(stroke
				(width 0.1)
				(type default)
			)
			(layer "F.Fab")
		)
		(fp_line
			(start 0.32512 0.175006)
			(end -0.32512 0.175006)
			(stroke
				(width 0.1)
				(type default)
			)
			(layer "F.Fab")
		)
		(fp_line
			(start -0.32512 -0.175006)
			(end 0.32512 -0.175006)
			(stroke
				(width 0.1)
				(type default)
			)
			(layer "F.Fab")
		)
		(fp_line
			(start 0.32512 -0.175006)
			(end 0.32512 0.175006)
			(stroke
				(width 0.1)
				(type default)
			)
			(layer "F.Fab")
		)
		(pad "1" smd rect
			(at -0.2667 0 270)
			(size 0.3048 0.381)
			(layers "F.Cu" "F.Mask" "F.Paste")
			(net "RST_RT_CPU0_P2_PERST_R_N")
		)
		(pad "2" smd rect
			(at 0.2667 0 90)
			(size 0.3048 0.381)
			(layers "F.Cu" "F.Mask" "F.Paste")
			(net "GND")
		)
	)
	(footprint ""
		(layer "F.Cu")
		(at 353.185222 -424.279314)
		(property "Reference" "C18"
			(at 0 0 0)
			(layer "F.SilkS")
			(hide yes)
			(effects
				(font
					(size 1.27 1.27)
				)
			)
		)
		(property "Value" ""
			(at 0 0 0)
			(layer "F.Fab")
			(effects
				(font
					(size 1.27 1.27)
				)
			)
		)
		(duplicate_pad_numbers_are_jumpers no)
		(fp_line
			(start -0.7874 -0.4064)
			(end 0.7874 -0.4064)
			(stroke
				(width 0.1524)
				(type default)
			)
			(layer "F.SilkS")
		)
		(fp_line
			(start -0.7874 0.4064)
			(end -0.7874 -0.4064)
			(stroke
				(width 0.1524)
				(type default)
			)
			(layer "F.SilkS")
		)
		(fp_line
			(start 0.7874 -0.4064)
			(end 0.7874 0.4064)
			(stroke
				(width 0.1524)
				(type default)
			)
			(layer "F.SilkS")
		)
		(fp_line
			(start 0.7874 0.4064)
			(end -0.7874 0.4064)
			(stroke
				(width 0.1524)
				(type default)
			)
			(layer "F.SilkS")
		)
		(fp_line
			(start -0.67945 -0.305054)
			(end -0.12065 -0.305054)
			(stroke
				(width 0.1)
				(type default)
			)
			(layer "F.Fab")
		)
		(fp_line
			(start -0.67945 0.3048)
			(end -0.67945 -0.305054)
			(stroke
				(width 0.1)
				(type default)
			)
			(layer "F.Fab")
		)
		(fp_line
			(start -0.12065 -0.305054)
			(end -0.12065 -0.2794)
			(stroke
				(width 0.1)
				(type default)
			)
			(layer "F.Fab")
		)
		(fp_line
			(start -0.12065 -0.2794)
			(end 0.12065 -0.2794)
			(stroke
				(width 0.1)
				(type default)
			)
			(layer "F.Fab")
		)
		(fp_line
			(start -0.12065 0.2794)
			(end -0.12065 0.3048)
			(stroke
				(width 0.1)
				(type default)
			)
			(layer "F.Fab")
		)
		(fp_line
			(start -0.12065 0.3048)
			(end -0.67945 0.3048)
			(stroke
				(width 0.1)
				(type default)
			)
			(layer "F.Fab")
		)
		(fp_line
			(start 0.120396 0.2794)
			(end -0.12065 0.2794)
			(stroke
				(width 0.1)
				(type default)
			)
			(layer "F.Fab")
		)
		(fp_line
			(start 0.120396 0.3048)
			(end 0.120396 0.2794)
			(stroke
				(width 0.1)
				(type default)
			)
			(layer "F.Fab")
		)
		(fp_line
			(start 0.12065 -0.3048)
			(end 0.67945 -0.3048)
			(stroke
				(width 0.1)
				(type default)
			)
			(layer "F.Fab")
		)
		(fp_line
			(start 0.12065 -0.2794)
			(end 0.12065 -0.3048)
			(stroke
				(width 0.1)
				(type default)
			)
			(layer "F.Fab")
		)
		(fp_line
			(start 0.67945 -0.3048)
			(end 0.67945 0.3048)
			(stroke
				(width 0.1)
				(type default)
			)
			(layer "F.Fab")
		)
		(fp_line
			(start 0.67945 0.3048)
			(end 0.120396 0.3048)
			(stroke
				(width 0.1)
				(type default)
			)
			(layer "F.Fab")
		)
		(pad "1" smd circle
			(at -0.40005 0)
			(size 0 0)
			(layers "F.Cu" "F.Mask" "F.Paste")
			(net "SWB_HSC_PWRGD_ISO")
		)
		(pad "2" smd circle
			(at 0.40005 0)
			(size 0 0)
			(layers "F.Cu" "F.Mask" "F.Paste")
			(net "GND")
		)
	)
	(footprint ""
		(layer "F.Cu")
		(at 204.994764 -95.695262)
		(property "Reference" "R1132"
			(at 0 0 0)
			(layer "F.SilkS")
			(hide yes)
			(effects
				(font
					(size 1.27 1.27)
				)
			)
		)
		(property "Value" ""
			(at 0 0 0)
			(layer "F.Fab")
			(effects
				(font
					(size 1.27 1.27)
				)
			)
		)
		(duplicate_pad_numbers_are_jumpers no)
		(fp_line
			(start -0.7874 -0.4064)
			(end 0.7874 -0.4064)
			(stroke
				(width 0.1524)
				(type default)
			)
			(layer "F.SilkS")
		)
		(fp_line
			(start -0.7874 0.4064)
			(end -0.7874 -0.4064)
			(stroke
				(width 0.1524)
				(type default)
			)
			(layer "F.SilkS")
		)
		(fp_line
			(start 0.7874 -0.4064)
			(end 0.7874 0.4064)
			(stroke
				(width 0.1524)
				(type default)
			)
			(layer "F.SilkS")
		)
		(fp_line
			(start 0.7874 0.4064)
			(end -0.7874 0.4064)
			(stroke
				(width 0.1524)
				(type default)
			)
			(layer "F.SilkS")
		)
		(fp_line
			(start -0.67945 -0.305054)
			(end -0.12065 -0.305054)
			(stroke
				(width 0.1)
				(type default)
			)
			(layer "F.Fab")
		)
		(fp_line
			(start -0.67945 0.3048)
			(end -0.67945 -0.305054)
			(stroke
				(width 0.1)
				(type default)
			)
			(layer "F.Fab")
		)
		(fp_line
			(start -0.12065 -0.305054)
			(end -0.12065 -0.2794)
			(stroke
				(width 0.1)
				(type default)
			)
			(layer "F.Fab")
		)
		(fp_line
			(start -0.12065 -0.2794)
			(end 0.12065 -0.2794)
			(stroke
				(width 0.1)
				(type default)
			)
			(layer "F.Fab")
		)
		(fp_line
			(start -0.12065 0.2794)
			(end -0.12065 0.3048)
			(stroke
				(width 0.1)
				(type default)
			)
			(layer "F.Fab")
		)
		(fp_line
			(start -0.12065 0.3048)
			(end -0.67945 0.3048)
			(stroke
				(width 0.1)
				(type default)
			)
			(layer "F.Fab")
		)
		(fp_line
			(start 0.120396 0.2794)
			(end -0.12065 0.2794)
			(stroke
				(width 0.1)
				(type default)
			)
			(layer "F.Fab")
		)
		(fp_line
			(start 0.120396 0.3048)
			(end 0.120396 0.2794)
			(stroke
				(width 0.1)
				(type default)
			)
			(layer "F.Fab")
		)
		(fp_line
			(start 0.12065 -0.3048)
			(end 0.67945 -0.3048)
			(stroke
				(width 0.1)
				(type default)
			)
			(layer "F.Fab")
		)
		(fp_line
			(start 0.12065 -0.2794)
			(end 0.12065 -0.3048)
			(stroke
				(width 0.1)
				(type default)
			)
			(layer "F.Fab")
		)
		(fp_line
			(start 0.67945 -0.3048)
			(end 0.67945 0.3048)
			(stroke
				(width 0.1)
				(type default)
			)
			(layer "F.Fab")
		)
		(fp_line
			(start 0.67945 0.3048)
			(end 0.120396 0.3048)
			(stroke
				(width 0.1)
				(type default)
			)
			(layer "F.Fab")
		)
		(pad "1" smd circle
			(at -0.40005 0)
			(size 0 0)
			(layers "F.Cu" "F.Mask" "F.Paste")
			(net "P12V_OCP_V3_1_PLD_R_PWRGD")
		)
		(pad "2" smd circle
			(at 0.40005 0)
			(size 0 0)
			(layers "F.Cu" "F.Mask" "F.Paste")
			(net "P12V_OCP_V3_1_PLD_PWRGD")
		)
	)
	(footprint ""
		(layer "F.Cu")
		(at 257.85953 -58.527442 180)
		(property "Reference" "R3974"
			(at 0 0 180)
			(layer "F.SilkS")
			(hide yes)
			(effects
				(font
					(size 1.27 1.27)
				)
			)
		)
		(property "Value" ""
			(at 0 0 180)
			(layer "F.Fab")
			(effects
				(font
					(size 1.27 1.27)
				)
			)
		)
		(duplicate_pad_numbers_are_jumpers no)
		(fp_line
			(start 0.7874 0.4064)
			(end -0.7874 0.4064)
			(stroke
				(width 0.1524)
				(type default)
			)
			(layer "F.SilkS")
		)
		(fp_line
			(start 0.7874 -0.4064)
			(end 0.7874 0.4064)
			(stroke
				(width 0.1524)
				(type default)
			)
			(layer "F.SilkS")
		)
		(fp_line
			(start -0.7874 0.4064)
			(end -0.7874 -0.4064)
			(stroke
				(width 0.1524)
				(type default)
			)
			(layer "F.SilkS")
		)
		(fp_line
			(start -0.7874 -0.4064)
			(end 0.7874 -0.4064)
			(stroke
				(width 0.1524)
				(type default)
			)
			(layer "F.SilkS")
		)
		(fp_line
			(start 0.67945 0.3048)
			(end 0.120396 0.3048)
			(stroke
				(width 0.1)
				(type default)
			)
			(layer "F.Fab")
		)
		(fp_line
			(start 0.67945 -0.3048)
			(end 0.67945 0.3048)
			(stroke
				(width 0.1)
				(type default)
			)
			(layer "F.Fab")
		)
		(fp_line
			(start 0.12065 -0.2794)
			(end 0.12065 -0.3048)
			(stroke
				(width 0.1)
				(type default)
			)
			(layer "F.Fab")
		)
		(fp_line
			(start 0.12065 -0.3048)
			(end 0.67945 -0.3048)
			(stroke
				(width 0.1)
				(type default)
			)
			(layer "F.Fab")
		)
		(fp_line
			(start 0.120396 0.3048)
			(end 0.120396 0.2794)
			(stroke
				(width 0.1)
				(type default)
			)
			(layer "F.Fab")
		)
		(fp_line
			(start 0.120396 0.2794)
			(end -0.12065 0.2794)
			(stroke
				(width 0.1)
				(type default)
			)
			(layer "F.Fab")
		)
		(fp_line
			(start -0.12065 0.3048)
			(end -0.67945 0.3048)
			(stroke
				(width 0.1)
				(type default)
			)
			(layer "F.Fab")
		)
		(fp_line
			(start -0.12065 0.2794)
			(end -0.12065 0.3048)
			(stroke
				(width 0.1)
				(type default)
			)
			(layer "F.Fab")
		)
		(fp_line
			(start -0.12065 -0.2794)
			(end 0.12065 -0.2794)
			(stroke
				(width 0.1)
				(type default)
			)
			(layer "F.Fab")
		)
		(fp_line
			(start -0.12065 -0.305054)
			(end -0.12065 -0.2794)
			(stroke
				(width 0.1)
				(type default)
			)
			(layer "F.Fab")
		)
		(fp_line
			(start -0.67945 0.3048)
			(end -0.67945 -0.305054)
			(stroke
				(width 0.1)
				(type default)
			)
			(layer "F.Fab")
		)
		(fp_line
			(start -0.67945 -0.305054)
			(end -0.12065 -0.305054)
			(stroke
				(width 0.1)
				(type default)
			)
			(layer "F.Fab")
		)
		(pad "1" smd rect
			(at -0.40005 0)
			(size 0.4572 0.508)
			(layers "F.Cu" "F.Mask" "F.Paste")
			(net "P12V_E1S_SENSE_0")
		)
		(pad "2" smd rect
			(at 0.40005 0)
			(size 0.4572 0.508)
			(layers "F.Cu" "F.Mask" "F.Paste")
			(net "P12V_E1S_0_ISENSE_MAM_MAM")
		)
	)
	(footprint ""
		(layer "F.Cu")
		(at 333.754476 -340.185248)
		(property "Reference" "PR78"
			(at 0 0 0)
			(layer "F.SilkS")
			(hide yes)
			(effects
				(font
					(size 1.27 1.27)
				)
			)
		)
		(property "Value" ""
			(at 0 0 0)
			(layer "F.Fab")
			(effects
				(font
					(size 1.27 1.27)
				)
			)
		)
		(duplicate_pad_numbers_are_jumpers no)
		(fp_line
			(start -0.7874 -0.4064)
			(end 0.7874 -0.4064)
			(stroke
				(width 0.1524)
				(type default)
			)
			(layer "F.SilkS")
		)
		(fp_line
			(start -0.7874 0.4064)
			(end -0.7874 -0.4064)
			(stroke
				(width 0.1524)
				(type default)
			)
			(layer "F.SilkS")
		)
		(fp_line
			(start 0.7874 -0.4064)
			(end 0.7874 0.4064)
			(stroke
				(width 0.1524)
				(type default)
			)
			(layer "F.SilkS")
		)
		(fp_line
			(start 0.7874 0.4064)
			(end -0.7874 0.4064)
			(stroke
				(width 0.1524)
				(type default)
			)
			(layer "F.SilkS")
		)
		(fp_line
			(start -0.67945 -0.305054)
			(end -0.12065 -0.305054)
			(stroke
				(width 0.1)
				(type default)
			)
			(layer "F.Fab")
		)
		(fp_line
			(start -0.67945 0.3048)
			(end -0.67945 -0.305054)
			(stroke
				(width 0.1)
				(type default)
			)
			(layer "F.Fab")
		)
		(fp_line
			(start -0.12065 -0.305054)
			(end -0.12065 -0.2794)
			(stroke
				(width 0.1)
				(type default)
			)
			(layer "F.Fab")
		)
		(fp_line
			(start -0.12065 -0.2794)
			(end 0.12065 -0.2794)
			(stroke
				(width 0.1)
				(type default)
			)
			(layer "F.Fab")
		)
		(fp_line
			(start -0.12065 0.2794)
			(end -0.12065 0.3048)
			(stroke
				(width 0.1)
				(type default)
			)
			(layer "F.Fab")
		)
		(fp_line
			(start -0.12065 0.3048)
			(end -0.67945 0.3048)
			(stroke
				(width 0.1)
				(type default)
			)
			(layer "F.Fab")
		)
		(fp_line
			(start 0.120396 0.2794)
			(end -0.12065 0.2794)
			(stroke
				(width 0.1)
				(type default)
			)
			(layer "F.Fab")
		)
		(fp_line
			(start 0.120396 0.3048)
			(end 0.120396 0.2794)
			(stroke
				(width 0.1)
				(type default)
			)
			(layer "F.Fab")
		)
		(fp_line
			(start 0.12065 -0.3048)
			(end 0.67945 -0.3048)
			(stroke
				(width 0.1)
				(type default)
			)
			(layer "F.Fab")
		)
		(fp_line
			(start 0.12065 -0.2794)
			(end 0.12065 -0.3048)
			(stroke
				(width 0.1)
				(type default)
			)
			(layer "F.Fab")
		)
		(fp_line
			(start 0.67945 -0.3048)
			(end 0.67945 0.3048)
			(stroke
				(width 0.1)
				(type default)
			)
			(layer "F.Fab")
		)
		(fp_line
			(start 0.67945 0.3048)
			(end 0.120396 0.3048)
			(stroke
				(width 0.1)
				(type default)
			)
			(layer "F.Fab")
		)
		(pad "1" smd circle
			(at -0.40005 0)
			(size 0 0)
			(layers "F.Cu" "F.Mask" "F.Paste")
			(net "PVDDCR_CPU1_P0_LSET1")
		)
		(pad "2" smd circle
			(at 0.40005 0)
			(size 0 0)
			(layers "F.Cu" "F.Mask" "F.Paste")
			(net "GND")
		)
	)
	(footprint ""
		(layer "F.Cu")
		(at 301.221902 -20.04695 -90)
		(property "Reference" "Q8"
			(at 1.510792 -2.157222 90)
			(unlocked yes)
			(layer "F.SilkS")
			(effects
				(font
					(size 0.7874 0.5842)
					(thickness 0.1524)
				)
				(justify left)
			)
		)
		(property "Value" ""
			(at 0 0 270)
			(layer "F.Fab")
			(effects
				(font
					(size 1.27 1.27)
				)
			)
		)
		(duplicate_pad_numbers_are_jumpers no)
		(fp_line
			(start -1.332738 1.100074)
			(end -1.332738 -1.100074)
			(stroke
				(width 0.1524)
				(type default)
			)
			(layer "F.SilkS")
		)
		(fp_line
			(start 1.332738 1.100074)
			(end -1.332738 1.100074)
			(stroke
				(width 0.1524)
				(type default)
			)
			(layer "F.SilkS")
		)
		(fp_line
			(start 0 -0.541274)
			(end 0.4826 -1.100074)
			(stroke
				(width 0.1524)
				(type default)
			)
			(layer "F.SilkS")
		)
		(fp_line
			(start -1.332738 -1.100074)
			(end -0.4826 -1.100074)
			(stroke
				(width 0.1524)
				(type default)
			)
			(layer "F.SilkS")
		)
		(fp_line
			(start -0.4826 -1.100074)
			(end 0 -0.541274)
			(stroke
				(width 0.1524)
				(type default)
			)
			(layer "F.SilkS")
		)
		(fp_line
			(start 0.4826 -1.100074)
			(end 1.332738 -1.100074)
			(stroke
				(width 0.1524)
				(type default)
			)
			(layer "F.SilkS")
		)
		(fp_line
			(start 1.332738 -1.100074)
			(end 1.332738 1.100074)
			(stroke
				(width 0.1524)
				(type default)
			)
			(layer "F.SilkS")
		)
		(fp_poly
			(pts
				(xy -0.983742 -1.228852) (xy -1.33477 -1.930908) (xy -0.632714 -1.930908)
			)
			(stroke
				(width 0)
				(type default)
			)
			(fill yes)
			(layer "F.SilkS")
		)
		(fp_line
			(start -0.674878 1.100074)
			(end -0.674878 -1.100074)
			(stroke
				(width 0.1)
				(type default)
			)
			(layer "F.Fab")
		)
		(fp_line
			(start 0.674878 1.100074)
			(end -0.674878 1.100074)
			(stroke
				(width 0.1)
				(type default)
			)
			(layer "F.Fab")
		)
		(fp_line
			(start -0.674878 -1.100074)
			(end 0.674878 -1.100074)
			(stroke
				(width 0.1)
				(type default)
			)
			(layer "F.Fab")
		)
		(fp_line
			(start 0.674878 -1.100074)
			(end 0.674878 1.100074)
			(stroke
				(width 0.1)
				(type default)
			)
			(layer "F.Fab")
		)
		(fp_poly
			(pts
				(xy -2.2352 -0.298958) (xy -2.2352 -1.001014) (xy -1.533144 -0.649986)
			)
			(stroke
				(width 0)
				(type default)
			)
			(fill yes)
			(layer "F.Fab")
		)
		(pad "1" smd rect
			(at -0.94996 -0.649986)
			(size 0.4318 0.508)
			(layers "F.Cu" "F.Mask" "F.Paste")
			(net "GND")
		)
		(pad "2" smd rect
			(at -0.94996 0)
			(size 0.4318 0.508)
			(layers "F.Cu" "F.Mask" "F.Paste")
			(net "CLR_CMOS")
		)
		(pad "3" smd rect
			(at -0.94996 0.649986)
			(size 0.4318 0.508)
			(layers "F.Cu" "F.Mask" "F.Paste")
			(net "BAT_LDO_EN")
		)
		(pad "4" smd rect
			(at 0.94996 0.649986)
			(size 0.4318 0.508)
			(layers "F.Cu" "F.Mask" "F.Paste")
			(net "GND")
		)
		(pad "5" smd rect
			(at 0.94996 0)
			(size 0.4318 0.508)
			(layers "F.Cu" "F.Mask" "F.Paste")
			(net "CLR_CMOS")
		)
		(pad "6" smd rect
			(at 0.94996 -0.649986)
			(size 0.4318 0.508)
			(layers "F.Cu" "F.Mask" "F.Paste")
			(net "CLR_CMOS_N")
		)
	)
	(footprint ""
		(layer "F.Cu")
		(at 21.176996 -97.083626 180)
		(property "Reference" "R3663"
			(at 0 0 180)
			(layer "F.SilkS")
			(hide yes)
			(effects
				(font
					(size 1.27 1.27)
				)
			)
		)
		(property "Value" ""
			(at 0 0 180)
			(layer "F.Fab")
			(effects
				(font
					(size 1.27 1.27)
				)
			)
		)
		(duplicate_pad_numbers_are_jumpers no)
		(fp_line
			(start 0.7874 0.4064)
			(end -0.7874 0.4064)
			(stroke
				(width 0.1524)
				(type default)
			)
			(layer "F.SilkS")
		)
		(fp_line
			(start 0.7874 -0.4064)
			(end 0.7874 0.4064)
			(stroke
				(width 0.1524)
				(type default)
			)
			(layer "F.SilkS")
		)
		(fp_line
			(start -0.7874 0.4064)
			(end -0.7874 -0.4064)
			(stroke
				(width 0.1524)
				(type default)
			)
			(layer "F.SilkS")
		)
		(fp_line
			(start -0.7874 -0.4064)
			(end 0.7874 -0.4064)
			(stroke
				(width 0.1524)
				(type default)
			)
			(layer "F.SilkS")
		)
		(fp_line
			(start 0.67945 0.3048)
			(end 0.120396 0.3048)
			(stroke
				(width 0.1)
				(type default)
			)
			(layer "F.Fab")
		)
		(fp_line
			(start 0.67945 -0.3048)
			(end 0.67945 0.3048)
			(stroke
				(width 0.1)
				(type default)
			)
			(layer "F.Fab")
		)
		(fp_line
			(start 0.12065 -0.2794)
			(end 0.12065 -0.3048)
			(stroke
				(width 0.1)
				(type default)
			)
			(layer "F.Fab")
		)
		(fp_line
			(start 0.12065 -0.3048)
			(end 0.67945 -0.3048)
			(stroke
				(width 0.1)
				(type default)
			)
			(layer "F.Fab")
		)
		(fp_line
			(start 0.120396 0.3048)
			(end 0.120396 0.2794)
			(stroke
				(width 0.1)
				(type default)
			)
			(layer "F.Fab")
		)
		(fp_line
			(start 0.120396 0.2794)
			(end -0.12065 0.2794)
			(stroke
				(width 0.1)
				(type default)
			)
			(layer "F.Fab")
		)
		(fp_line
			(start -0.12065 0.3048)
			(end -0.67945 0.3048)
			(stroke
				(width 0.1)
				(type default)
			)
			(layer "F.Fab")
		)
		(fp_line
			(start -0.12065 0.2794)
			(end -0.12065 0.3048)
			(stroke
				(width 0.1)
				(type default)
			)
			(layer "F.Fab")
		)
		(fp_line
			(start -0.12065 -0.2794)
			(end 0.12065 -0.2794)
			(stroke
				(width 0.1)
				(type default)
			)
			(layer "F.Fab")
		)
		(fp_line
			(start -0.12065 -0.305054)
			(end -0.12065 -0.2794)
			(stroke
				(width 0.1)
				(type default)
			)
			(layer "F.Fab")
		)
		(fp_line
			(start -0.67945 0.3048)
			(end -0.67945 -0.305054)
			(stroke
				(width 0.1)
				(type default)
			)
			(layer "F.Fab")
		)
		(fp_line
			(start -0.67945 -0.305054)
			(end -0.12065 -0.305054)
			(stroke
				(width 0.1)
				(type default)
			)
			(layer "F.Fab")
		)
		(pad "1" smd circle
			(at -0.40005 0 180)
			(size 0 0)
			(layers "F.Cu" "F.Mask" "F.Paste")
			(net "P3V3_AUX")
		)
		(pad "2" smd circle
			(at 0.40005 0 180)
			(size 0 0)
			(layers "F.Cu" "F.Mask" "F.Paste")
			(net "USB_HUB_PSELF")
		)
	)
	(footprint ""
		(layer "F.Cu")
		(at 527.948906 -147.965414 -90)
		(property "Reference" "X7"
			(at -1.890776 3.496818 0)
			(unlocked yes)
			(layer "F.SilkS")
			(effects
				(font
					(size 0.7874 0.5842)
					(thickness 0.1524)
				)
				(justify left)
			)
		)
		(property "Value" ""
			(at 0 0 270)
			(layer "F.Fab")
			(effects
				(font
					(size 1.27 1.27)
				)
			)
		)
		(property "Device Type" "TP_TDR_4P_FTS_TH-TP_TDR_4P_DIP,EMPTY,TP15"
			(at 1.30175 1.27 0)
			(unlocked yes)
			(layer "F.Fab")
			(hide yes)
			(effects
				(font
					(size 0.635 0.4064)
					(thickness 0.1524)
				)
			)
		)
		(property "User Part Number" "N_A"
			(at 1.30175 1.27 0)
			(unlocked yes)
			(layer "Cmts.User")
			(hide yes)
			(effects
				(font
					(size 0.635 0.4064)
					(thickness 0.1524)
				)
			)
		)
		(duplicate_pad_numbers_are_jumpers no)
		(fp_line
			(start 0 3.81)
			(end 2.54 3.81)
			(stroke
				(width 0.1524)
				(type default)
			)
			(layer "F.SilkS")
		)
		(fp_line
			(start 2.54 3.81)
			(end 2.54 3.6703)
			(stroke
				(width 0.1524)
				(type default)
			)
			(layer "F.SilkS")
		)
		(fp_line
			(start 0 3.175)
			(end 0 3.81)
			(stroke
				(width 0.1524)
				(type default)
			)
			(layer "F.SilkS")
		)
		(fp_line
			(start 2.54 1.4097)
			(end 2.54 1.1303)
			(stroke
				(width 0.1524)
				(type default)
			)
			(layer "F.SilkS")
		)
		(fp_line
			(start 0 0.635)
			(end 0 1.905)
			(stroke
				(width 0.1524)
				(type default)
			)
			(layer "F.SilkS")
		)
		(fp_line
			(start 2.54 -1.1303)
			(end 2.54 -1.27)
			(stroke
				(width 0.1524)
				(type default)
			)
			(layer "F.SilkS")
		)
		(fp_line
			(start 0 -1.27)
			(end 0 -0.635)
			(stroke
				(width 0.1524)
				(type default)
			)
			(layer "F.SilkS")
		)
		(fp_line
			(start 2.54 -1.27)
			(end 0 -1.27)
			(stroke
				(width 0.1524)
				(type default)
			)
			(layer "F.SilkS")
		)
		(fp_poly
			(pts
				(xy -0.761746 0) (xy -2.285746 0.762) (xy -2.285746 -0.762)
			)
			(stroke
				(width 0)
				(type default)
			)
			(fill yes)
			(layer "F.SilkS")
		)
		(fp_line
			(start 0 3.81)
			(end 2.54 3.81)
			(stroke
				(width 0.1)
				(type default)
			)
			(layer "F.Fab")
		)
		(fp_line
			(start 2.54 3.81)
			(end 2.54 -1.27)
			(stroke
				(width 0.1)
				(type default)
			)
			(layer "F.Fab")
		)
		(fp_line
			(start 0 -1.27)
			(end 0 3.81)
			(stroke
				(width 0.1)
				(type default)
			)
			(layer "F.Fab")
		)
		(fp_line
			(start 2.54 -1.27)
			(end 0 -1.27)
			(stroke
				(width 0.1)
				(type default)
			)
			(layer "F.Fab")
		)
		(fp_poly
			(pts
				(xy -0.761746 0) (xy -2.285746 -0.762) (xy -2.285746 0.762)
			)
			(stroke
				(width 0)
				(type default)
			)
			(fill yes)
			(layer "F.Fab")
		)
		(pad "1" thru_hole circle
			(at 0 0 270)
			(size 1.0033 1.0033)
			(drill 0.249936)
			(layers "*.Cu" "*.Mask")
			(remove_unused_layers no)
			(net "TDR_DIFF_80_TOP_DN")
			(clearance 0.10795)
			(thermal_gap 0.10795)
			(padstack
				(mode front_inner_back)
				(layer "Inner"
					(shape circle)
					(size 0.8001 0.8001)
					(clearance 0.1524)
				)
				(layer "B.Cu"
					(shape circle)
					(size 1.0033 1.0033)
					(clearance 0.10795)
				)
			)
		)
		(pad "2" thru_hole circle
			(at 2.54 0 270)
			(size 1.9939 1.9939)
			(drill 0.249936)
			(layers "*.Cu" "*.Mask")
			(remove_unused_layers no)
			(net "T1_GND")
			(clearance 0.10795)
			(thermal_gap 0.10795)
			(padstack
				(mode front_inner_back)
				(layer "Inner"
					(shape circle)
					(size 0.8001 0.8001)
					(clearance 0.1524)
				)
				(layer "B.Cu"
					(shape circle)
					(size 1.9939 1.9939)
					(clearance 0.10795)
				)
			)
		)
		(pad "3" thru_hole circle
			(at 2.54 2.54 270)
			(size 1.9939 1.9939)
			(drill 0.249936)
			(layers "*.Cu" "*.Mask")
			(remove_unused_layers no)
			(net "T1_GND")
			(clearance 0.10795)
			(thermal_gap 0.10795)
			(padstack
				(mode front_inner_back)
				(layer "Inner"
					(shape circle)
					(size 0.8001 0.8001)
					(clearance 0.1524)
				)
				(layer "B.Cu"
					(shape circle)
					(size 1.9939 1.9939)
					(clearance 0.10795)
				)
			)
		)
		(pad "4" thru_hole circle
			(at 0 2.54 270)
			(size 1.0033 1.0033)
			(drill 0.249936)
			(layers "*.Cu" "*.Mask")
			(remove_unused_layers no)
			(net "TDR_DIFF_80_TOP_DP")
			(clearance 0.10795)
			(thermal_gap 0.10795)
			(padstack
				(mode front_inner_back)
				(layer "Inner"
					(shape circle)
					(size 0.8001 0.8001)
					(clearance 0.1524)
				)
				(layer "B.Cu"
					(shape circle)
					(size 1.0033 1.0033)
					(clearance 0.10795)
				)
			)
		)
	)
	(footprint ""
		(layer "F.Cu")
		(at 144.74063 -101.894132)
		(property "Reference" "U259"
			(at 2.9464 -1.69037 0)
			(unlocked yes)
			(layer "F.SilkS")
			(effects
				(font
					(size 0.7874 0.5842)
					(thickness 0.1524)
				)
			)
		)
		(property "Value" ""
			(at 0 0 0)
			(layer "F.Fab")
			(effects
				(font
					(size 1.27 1.27)
				)
			)
		)
		(duplicate_pad_numbers_are_jumpers no)
		(fp_line
			(start -1.7272 1.1176)
			(end -1.7272 -1.1176)
			(stroke
				(width 0.1524)
				(type default)
			)
			(layer "F.SilkS")
		)
		(fp_line
			(start -0.254 -1.1176)
			(end -1.7272 -1.1176)
			(stroke
				(width 0.1524)
				(type default)
			)
			(layer "F.SilkS")
		)
		(fp_line
			(start 0 -0.7366)
			(end -0.254 -1.1176)
			(stroke
				(width 0.1524)
				(type default)
			)
			(layer "F.SilkS")
		)
		(fp_line
			(start 0.254 -1.1176)
			(end 0 -0.7366)
			(stroke
				(width 0.1524)
				(type default)
			)
			(layer "F.SilkS")
		)
		(fp_line
			(start 1.7272 -1.1176)
			(end 0.254 -1.1176)
			(stroke
				(width 0.1524)
				(type default)
			)
			(layer "F.SilkS")
		)
		(fp_line
			(start 1.7272 -1.1176)
			(end 1.7272 1.1176)
			(stroke
				(width 0.1524)
				(type default)
			)
			(layer "F.SilkS")
		)
		(fp_line
			(start 1.7272 1.1176)
			(end -1.7272 1.1176)
			(stroke
				(width 0.1524)
				(type default)
			)
			(layer "F.SilkS")
		)
		(fp_poly
			(pts
				(xy -2.7178 -1.030986) (xy -1.9558 -0.649986) (xy -2.7178 -0.268986)
			)
			(stroke
				(width 0)
				(type default)
			)
			(fill yes)
			(layer "F.SilkS")
		)
		(fp_line
			(start -1.5748 -1.1176)
			(end -1.5748 1.1176)
			(stroke
				(width 0.1)
				(type default)
			)
			(layer "F.Fab")
		)
		(fp_line
			(start -1.5748 1.1176)
			(end 1.5748 1.1176)
			(stroke
				(width 0.1)
				(type default)
			)
			(layer "F.Fab")
		)
		(fp_line
			(start 1.5748 -1.1176)
			(end -1.5748 -1.1176)
			(stroke
				(width 0.1)
				(type default)
			)
			(layer "F.Fab")
		)
		(fp_line
			(start 1.5748 1.1176)
			(end 1.5748 -1.1176)
			(stroke
				(width 0.1)
				(type default)
			)
			(layer "F.Fab")
		)
		(fp_poly
			(pts
				(xy -1.9558 -0.649986) (xy -2.7178 -0.268986) (xy -2.7178 -1.030986)
			)
			(stroke
				(width 0)
				(type default)
			)
			(fill yes)
			(layer "F.Fab")
		)
		(pad "1" smd rect
			(at -0.999998 -0.649986 270)
			(size 0.3556 1.1176)
			(layers "F.Cu" "F.Mask" "F.Paste")
			(net "M2_SSD0_CLKREQ_EN_N")
		)
		(pad "2" smd rect
			(at -0.999998 0 270)
			(size 0.3556 1.1176)
			(layers "F.Cu" "F.Mask" "F.Paste")
			(net "GND")
		)
		(pad "3" smd rect
			(at -0.999998 0.649986 270)
			(size 0.3556 1.1176)
			(layers "F.Cu" "F.Mask" "F.Paste")
			(net "RST_PERST_M2_0_N")
		)
		(pad "4" smd rect
			(at 0.999998 0.649986 270)
			(size 0.3556 1.1176)
			(layers "F.Cu" "F.Mask" "F.Paste")
			(net "RST_PERST_BUF_M2_0_N")
		)
		(pad "5" smd rect
			(at 0.999998 0 270)
			(size 0.3556 1.1176)
			(layers "F.Cu" "F.Mask" "F.Paste")
			(net "P3V3_AUX")
		)
		(pad "6" smd rect
			(at 0.999998 -0.649986 270)
			(size 0.3556 1.1176)
			(layers "F.Cu" "F.Mask" "F.Paste")
			(net "HDD_ACTIVITY_BUF")
		)
	)
	(footprint ""
		(layer "F.Cu")
		(at 78.882494 -325.661274)
		(property "Reference" "PL41"
			(at -0.829056 -16.776446 0)
			(unlocked yes)
			(layer "F.SilkS")
			(effects
				(font
					(size 0.7874 0.5842)
					(thickness 0.1524)
				)
				(justify left)
			)
		)
		(property "Value" ""
			(at 0 0 0)
			(layer "F.Fab")
			(effects
				(font
					(size 1.27 1.27)
				)
			)
		)
		(duplicate_pad_numbers_are_jumpers no)
		(fp_line
			(start -3.750056 -5.500116)
			(end -2.393442 -5.500116)
			(stroke
				(width 0.1524)
				(type default)
			)
			(layer "F.SilkS")
		)
		(fp_line
			(start -3.750056 5.500116)
			(end -3.750056 -5.500116)
			(stroke
				(width 0.1524)
				(type default)
			)
			(layer "F.SilkS")
		)
		(fp_line
			(start -2.393442 5.500116)
			(end -3.750056 5.500116)
			(stroke
				(width 0.1524)
				(type default)
			)
			(layer "F.SilkS")
		)
		(fp_line
			(start 2.393442 5.500116)
			(end 3.750056 5.500116)
			(stroke
				(width 0.1524)
				(type default)
			)
			(layer "F.SilkS")
		)
		(fp_line
			(start 3.750056 -5.500116)
			(end 2.393442 -5.500116)
			(stroke
				(width 0.1524)
				(type default)
			)
			(layer "F.SilkS")
		)
		(fp_line
			(start 3.750056 5.500116)
			(end 3.750056 -5.500116)
			(stroke
				(width 0.1524)
				(type default)
			)
			(layer "F.SilkS")
		)
		(fp_poly
			(pts
				(xy -3.9116 -4.249928) (xy -4.3434 -4.034028) (xy -4.3434 -4.465828)
			)
			(stroke
				(width 0)
				(type default)
			)
			(fill yes)
			(layer "F.SilkS")
		)
		(fp_line
			(start -3.750056 -5.500116)
			(end -3.750056 5.500116)
			(stroke
				(width 0.1)
				(type default)
			)
			(layer "F.Fab")
		)
		(fp_line
			(start -3.750056 5.500116)
			(end 3.750056 5.500116)
			(stroke
				(width 0.1)
				(type default)
			)
			(layer "F.Fab")
		)
		(fp_line
			(start 3.750056 -5.500116)
			(end -3.750056 -5.500116)
			(stroke
				(width 0.1)
				(type default)
			)
			(layer "F.Fab")
		)
		(fp_line
			(start 3.750056 5.500116)
			(end 3.750056 -5.500116)
			(stroke
				(width 0.1)
				(type default)
			)
			(layer "F.Fab")
		)
		(fp_poly
			(pts
				(xy -4.9276 -4.757928) (xy -4.9276 -3.741928) (xy -3.9116 -4.249928)
			)
			(stroke
				(width 0)
				(type default)
			)
			(fill yes)
			(layer "F.Fab")
		)
		(pad "1" smd rect
			(at 0 -4.249928 270)
			(size 2.413 4.5212)
			(layers "F.Cu" "F.Mask" "F.Paste")
			(net "SW_PVDDCR_CPU1_P1_SW2")
		)
		(pad "2" smd rect
			(at 0 -1.175004 270)
			(size 1.3716 4.5212)
			(layers "F.Cu" "F.Mask" "F.Paste")
			(net "IND_CPU1_P1_CPL1")
		)
		(pad "3" smd rect
			(at 0 1.175004 270)
			(size 1.3716 4.5212)
			(layers "F.Cu" "F.Mask" "F.Paste")
			(net "IND_CPU1_P1_CPL2")
		)
		(pad "4" smd rect
			(at 0 4.249928 270)
			(size 2.413 4.5212)
			(layers "F.Cu" "F.Mask" "F.Paste")
			(net "PVDDCR_CPU1_P1")
		)
	)
	(footprint ""
		(layer "F.Cu")
		(at 358.465882 -256.012188 90)
		(property "Reference" "C3928"
			(at 0 0 90)
			(layer "F.SilkS")
			(hide yes)
			(effects
				(font
					(size 1.27 1.27)
				)
			)
		)
		(property "Value" ""
			(at 0 0 90)
			(layer "F.Fab")
			(effects
				(font
					(size 1.27 1.27)
				)
			)
		)
		(duplicate_pad_numbers_are_jumpers no)
		(fp_line
			(start 0.7874 -0.4064)
			(end 0.7874 0.4064)
			(stroke
				(width 0.1524)
				(type default)
			)
			(layer "F.SilkS")
		)
		(fp_line
			(start -0.7874 -0.4064)
			(end 0.7874 -0.4064)
			(stroke
				(width 0.1524)
				(type default)
			)
			(layer "F.SilkS")
		)
		(fp_line
			(start 0.7874 0.4064)
			(end -0.7874 0.4064)
			(stroke
				(width 0.1524)
				(type default)
			)
			(layer "F.SilkS")
		)
		(fp_line
			(start -0.7874 0.4064)
			(end -0.7874 -0.4064)
			(stroke
				(width 0.1524)
				(type default)
			)
			(layer "F.SilkS")
		)
		(fp_line
			(start -0.12065 -0.305054)
			(end -0.12065 -0.2794)
			(stroke
				(width 0.1)
				(type default)
			)
			(layer "F.Fab")
		)
		(fp_line
			(start -0.67945 -0.305054)
			(end -0.12065 -0.305054)
			(stroke
				(width 0.1)
				(type default)
			)
			(layer "F.Fab")
		)
		(fp_line
			(start 0.67945 -0.3048)
			(end 0.67945 0.3048)
			(stroke
				(width 0.1)
				(type default)
			)
			(layer "F.Fab")
		)
		(fp_line
			(start 0.12065 -0.3048)
			(end 0.67945 -0.3048)
			(stroke
				(width 0.1)
				(type default)
			)
			(layer "F.Fab")
		)
		(fp_line
			(start 0.12065 -0.2794)
			(end 0.12065 -0.3048)
			(stroke
				(width 0.1)
				(type default)
			)
			(layer "F.Fab")
		)
		(fp_line
			(start -0.12065 -0.2794)
			(end 0.12065 -0.2794)
			(stroke
				(width 0.1)
				(type default)
			)
			(layer "F.Fab")
		)
		(fp_line
			(start 0.120396 0.2794)
			(end -0.12065 0.2794)
			(stroke
				(width 0.1)
				(type default)
			)
			(layer "F.Fab")
		)
		(fp_line
			(start -0.12065 0.2794)
			(end -0.12065 0.3048)
			(stroke
				(width 0.1)
				(type default)
			)
			(layer "F.Fab")
		)
		(fp_line
			(start 0.67945 0.3048)
			(end 0.120396 0.3048)
			(stroke
				(width 0.1)
				(type default)
			)
			(layer "F.Fab")
		)
		(fp_line
			(start 0.120396 0.3048)
			(end 0.120396 0.2794)
			(stroke
				(width 0.1)
				(type default)
			)
			(layer "F.Fab")
		)
		(fp_line
			(start -0.12065 0.3048)
			(end -0.67945 0.3048)
			(stroke
				(width 0.1)
				(type default)
			)
			(layer "F.Fab")
		)
		(fp_line
			(start -0.67945 0.3048)
			(end -0.67945 -0.305054)
			(stroke
				(width 0.1)
				(type default)
			)
			(layer "F.Fab")
		)
		(pad "1" smd circle
			(at -0.40005 0 90)
			(size 0 0)
			(layers "F.Cu" "F.Mask" "F.Paste")
			(net "PVDDCR_SOC_P0")
		)
		(pad "2" smd circle
			(at 0.40005 0 90)
			(size 0 0)
			(layers "F.Cu" "F.Mask" "F.Paste")
			(net "GND")
		)
	)
	(footprint ""
		(layer "F.Cu")
		(at 452.756016 -46.345602 180)
		(property "Reference" "PR836"
			(at 0 0 180)
			(layer "F.SilkS")
			(hide yes)
			(effects
				(font
					(size 1.27 1.27)
				)
			)
		)
		(property "Value" ""
			(at 0 0 180)
			(layer "F.Fab")
			(effects
				(font
					(size 1.27 1.27)
				)
			)
		)
		(duplicate_pad_numbers_are_jumpers no)
		(fp_line
			(start 0.7874 0.4064)
			(end -0.7874 0.4064)
			(stroke
				(width 0.1524)
				(type default)
			)
			(layer "F.SilkS")
		)
		(fp_line
			(start 0.7874 -0.4064)
			(end 0.7874 0.4064)
			(stroke
				(width 0.1524)
				(type default)
			)
			(layer "F.SilkS")
		)
		(fp_line
			(start -0.7874 0.4064)
			(end -0.7874 -0.4064)
			(stroke
				(width 0.1524)
				(type default)
			)
			(layer "F.SilkS")
		)
		(fp_line
			(start -0.7874 -0.4064)
			(end 0.7874 -0.4064)
			(stroke
				(width 0.1524)
				(type default)
			)
			(layer "F.SilkS")
		)
		(fp_line
			(start 0.67945 0.3048)
			(end 0.120396 0.3048)
			(stroke
				(width 0.1)
				(type default)
			)
			(layer "F.Fab")
		)
		(fp_line
			(start 0.67945 -0.3048)
			(end 0.67945 0.3048)
			(stroke
				(width 0.1)
				(type default)
			)
			(layer "F.Fab")
		)
		(fp_line
			(start 0.12065 -0.2794)
			(end 0.12065 -0.3048)
			(stroke
				(width 0.1)
				(type default)
			)
			(layer "F.Fab")
		)
		(fp_line
			(start 0.12065 -0.3048)
			(end 0.67945 -0.3048)
			(stroke
				(width 0.1)
				(type default)
			)
			(layer "F.Fab")
		)
		(fp_line
			(start 0.120396 0.3048)
			(end 0.120396 0.2794)
			(stroke
				(width 0.1)
				(type default)
			)
			(layer "F.Fab")
		)
		(fp_line
			(start 0.120396 0.2794)
			(end -0.12065 0.2794)
			(stroke
				(width 0.1)
				(type default)
			)
			(layer "F.Fab")
		)
		(fp_line
			(start -0.12065 0.3048)
			(end -0.67945 0.3048)
			(stroke
				(width 0.1)
				(type default)
			)
			(layer "F.Fab")
		)
		(fp_line
			(start -0.12065 0.2794)
			(end -0.12065 0.3048)
			(stroke
				(width 0.1)
				(type default)
			)
			(layer "F.Fab")
		)
		(fp_line
			(start -0.12065 -0.2794)
			(end 0.12065 -0.2794)
			(stroke
				(width 0.1)
				(type default)
			)
			(layer "F.Fab")
		)
		(fp_line
			(start -0.12065 -0.305054)
			(end -0.12065 -0.2794)
			(stroke
				(width 0.1)
				(type default)
			)
			(layer "F.Fab")
		)
		(fp_line
			(start -0.67945 0.3048)
			(end -0.67945 -0.305054)
			(stroke
				(width 0.1)
				(type default)
			)
			(layer "F.Fab")
		)
		(fp_line
			(start -0.67945 -0.305054)
			(end -0.12065 -0.305054)
			(stroke
				(width 0.1)
				(type default)
			)
			(layer "F.Fab")
		)
		(pad "1" smd circle
			(at -0.40005 0 180)
			(size 0 0)
			(layers "F.Cu" "F.Mask" "F.Paste")
			(net "P3V3_AUX_VOS")
		)
		(pad "2" smd circle
			(at 0.40005 0 180)
			(size 0 0)
			(layers "F.Cu" "F.Mask" "F.Paste")
			(net "P3V3_AUX")
		)
	)
	(footprint ""
		(layer "F.Cu")
		(at 302.523398 -430.2379 180)
		(property "Reference" "C16"
			(at 0 0 180)
			(layer "F.SilkS")
			(hide yes)
			(effects
				(font
					(size 1.27 1.27)
				)
			)
		)
		(property "Value" ""
			(at 0 0 180)
			(layer "F.Fab")
			(effects
				(font
					(size 1.27 1.27)
				)
			)
		)
		(duplicate_pad_numbers_are_jumpers no)
		(fp_line
			(start 0.7874 0.4064)
			(end -0.7874 0.4064)
			(stroke
				(width 0.1524)
				(type default)
			)
			(layer "F.SilkS")
		)
		(fp_line
			(start 0.7874 -0.4064)
			(end 0.7874 0.4064)
			(stroke
				(width 0.1524)
				(type default)
			)
			(layer "F.SilkS")
		)
		(fp_line
			(start -0.7874 0.4064)
			(end -0.7874 -0.4064)
			(stroke
				(width 0.1524)
				(type default)
			)
			(layer "F.SilkS")
		)
		(fp_line
			(start -0.7874 -0.4064)
			(end 0.7874 -0.4064)
			(stroke
				(width 0.1524)
				(type default)
			)
			(layer "F.SilkS")
		)
		(fp_line
			(start 0.67945 0.3048)
			(end 0.120396 0.3048)
			(stroke
				(width 0.1)
				(type default)
			)
			(layer "F.Fab")
		)
		(fp_line
			(start 0.67945 -0.3048)
			(end 0.67945 0.3048)
			(stroke
				(width 0.1)
				(type default)
			)
			(layer "F.Fab")
		)
		(fp_line
			(start 0.12065 -0.2794)
			(end 0.12065 -0.3048)
			(stroke
				(width 0.1)
				(type default)
			)
			(layer "F.Fab")
		)
		(fp_line
			(start 0.12065 -0.3048)
			(end 0.67945 -0.3048)
			(stroke
				(width 0.1)
				(type default)
			)
			(layer "F.Fab")
		)
		(fp_line
			(start 0.120396 0.3048)
			(end 0.120396 0.2794)
			(stroke
				(width 0.1)
				(type default)
			)
			(layer "F.Fab")
		)
		(fp_line
			(start 0.120396 0.2794)
			(end -0.12065 0.2794)
			(stroke
				(width 0.1)
				(type default)
			)
			(layer "F.Fab")
		)
		(fp_line
			(start -0.12065 0.3048)
			(end -0.67945 0.3048)
			(stroke
				(width 0.1)
				(type default)
			)
			(layer "F.Fab")
		)
		(fp_line
			(start -0.12065 0.2794)
			(end -0.12065 0.3048)
			(stroke
				(width 0.1)
				(type default)
			)
			(layer "F.Fab")
		)
		(fp_line
			(start -0.12065 -0.2794)
			(end 0.12065 -0.2794)
			(stroke
				(width 0.1)
				(type default)
			)
			(layer "F.Fab")
		)
		(fp_line
			(start -0.12065 -0.305054)
			(end -0.12065 -0.2794)
			(stroke
				(width 0.1)
				(type default)
			)
			(layer "F.Fab")
		)
		(fp_line
			(start -0.67945 0.3048)
			(end -0.67945 -0.305054)
			(stroke
				(width 0.1)
				(type default)
			)
			(layer "F.Fab")
		)
		(fp_line
			(start -0.67945 -0.305054)
			(end -0.12065 -0.305054)
			(stroke
				(width 0.1)
				(type default)
			)
			(layer "F.Fab")
		)
		(pad "1" smd circle
			(at -0.40005 0 180)
			(size 0 0)
			(layers "F.Cu" "F.Mask" "F.Paste")
			(net "GPU_3V3IO_RSVD3_FFU_ISO")
		)
		(pad "2" smd circle
			(at 0.40005 0 180)
			(size 0 0)
			(layers "F.Cu" "F.Mask" "F.Paste")
			(net "GND")
		)
	)
	(footprint ""
		(layer "F.Cu")
		(at 238.45012 -435.58206 -90)
		(property "Reference" "J45"
			(at 11.30173 -38.15588 0)
			(unlocked yes)
			(layer "F.SilkS")
			(effects
				(font
					(size 0.7874 0.5842)
					(thickness 0.1524)
				)
				(justify left)
			)
		)
		(property "Value" ""
			(at 0 0 270)
			(layer "F.Fab")
			(effects
				(font
					(size 1.27 1.27)
				)
			)
		)
		(duplicate_pad_numbers_are_jumpers no)
		(fp_line
			(start -18.370042 42.494962)
			(end -18.370042 -37.414962)
			(stroke
				(width 0.1524)
				(type default)
			)
			(layer "F.SilkS")
		)
		(fp_line
			(start 11.679936 42.494962)
			(end -18.370042 42.494962)
			(stroke
				(width 0.1524)
				(type default)
			)
			(layer "F.SilkS")
		)
		(fp_line
			(start -15.370048 39.494968)
			(end -15.370048 -34.414968)
			(stroke
				(width 0.1524)
				(type default)
			)
			(layer "F.SilkS")
		)
		(fp_line
			(start -0.712978 39.494968)
			(end -15.370048 39.494968)
			(stroke
				(width 0.1524)
				(type default)
			)
			(layer "F.SilkS")
		)
		(fp_line
			(start 8.24992 39.494968)
			(end 5.792978 39.494968)
			(stroke
				(width 0.1524)
				(type default)
			)
			(layer "F.SilkS")
		)
		(fp_line
			(start 8.24992 31.218632)
			(end 8.24992 39.494968)
			(stroke
				(width 0.1524)
				(type default)
			)
			(layer "F.SilkS")
		)
		(fp_line
			(start 8.24992 22.328632)
			(end 8.24992 27.201368)
			(stroke
				(width 0.1524)
				(type default)
			)
			(layer "F.SilkS")
		)
		(fp_line
			(start 8.24992 13.438632)
			(end 8.24992 18.311368)
			(stroke
				(width 0.1524)
				(type default)
			)
			(layer "F.SilkS")
		)
		(fp_line
			(start 8.24992 5.818632)
			(end 8.24992 9.421368)
			(stroke
				(width 0.1524)
				(type default)
			)
			(layer "F.SilkS")
		)
		(fp_line
			(start 8.24992 -4.341368)
			(end 8.24992 -0.738632)
			(stroke
				(width 0.1524)
				(type default)
			)
			(layer "F.SilkS")
		)
		(fp_line
			(start 8.24992 -13.231368)
			(end 8.24992 -8.358632)
			(stroke
				(width 0.1524)
				(type default)
			)
			(layer "F.SilkS")
		)
		(fp_line
			(start 8.24992 -22.121368)
			(end 8.24992 -17.248632)
			(stroke
				(width 0.1524)
				(type default)
			)
			(layer "F.SilkS")
		)
		(fp_line
			(start -15.370048 -34.414968)
			(end -0.712978 -34.414968)
			(stroke
				(width 0.1524)
				(type default)
			)
			(layer "F.SilkS")
		)
		(fp_line
			(start -5.08 -34.414968)
			(end -5.08 39.494968)
			(stroke
				(width 0.1524)
				(type default)
			)
			(layer "F.SilkS")
		)
		(fp_line
			(start 5.792978 -34.414968)
			(end 8.24992 -34.414968)
			(stroke
				(width 0.1524)
				(type default)
			)
			(layer "F.SilkS")
		)
		(fp_line
			(start 8.24992 -34.414968)
			(end 8.24992 -26.138632)
			(stroke
				(width 0.1524)
				(type default)
			)
			(layer "F.SilkS")
		)
		(fp_line
			(start -18.370042 -37.414962)
			(end 11.679936 -37.414962)
			(stroke
				(width 0.1524)
				(type default)
			)
			(layer "F.SilkS")
		)
		(fp_line
			(start 11.679936 -37.414962)
			(end 11.679936 42.494962)
			(stroke
				(width 0.1524)
				(type default)
			)
			(layer "F.SilkS")
		)
		(fp_poly
			(pts
				(xy -4.9022 -0.508) (xy -4.9022 0.508) (xy -3.8862 0)
			)
			(stroke
				(width 0)
				(type default)
			)
			(fill yes)
			(layer "F.SilkS")
		)
		(fp_line
			(start -18.370042 42.494962)
			(end -18.370042 -37.414962)
			(stroke
				(width 0.1524)
				(type default)
			)
			(layer "B.SilkS")
		)
		(fp_line
			(start 11.679936 42.494962)
			(end -18.370042 42.494962)
			(stroke
				(width 0.1524)
				(type default)
			)
			(layer "B.SilkS")
		)
		(fp_line
			(start -18.370042 -37.414962)
			(end 11.679936 -37.414962)
			(stroke
				(width 0.1524)
				(type default)
			)
			(layer "B.SilkS")
		)
		(fp_line
			(start 11.679936 -37.414962)
			(end 11.679936 42.494962)
			(stroke
				(width 0.1524)
				(type default)
			)
			(layer "B.SilkS")
		)
		(fp_line
			(start -18.370042 42.494962)
			(end -18.370042 -37.414962)
			(stroke
				(width 0.1)
				(type default)
			)
			(layer "B.Fab")
		)
		(fp_line
			(start 11.679936 42.494962)
			(end -18.370042 42.494962)
			(stroke
				(width 0.1)
				(type default)
			)
			(layer "B.Fab")
		)
		(fp_line
			(start -18.370042 -37.414962)
			(end 11.679936 -37.414962)
			(stroke
				(width 0.1)
				(type default)
			)
			(layer "B.Fab")
		)
		(fp_line
			(start 11.679936 -37.414962)
			(end 11.679936 42.494962)
			(stroke
				(width 0.1)
				(type default)
			)
			(layer "B.Fab")
		)
		(fp_line
			(start -15.370048 39.494968)
			(end -15.370048 -34.414968)
			(stroke
				(width 0.1)
				(type default)
			)
			(layer "F.Fab")
		)
		(fp_line
			(start 8.24992 39.494968)
			(end -15.370048 39.494968)
			(stroke
				(width 0.1)
				(type default)
			)
			(layer "F.Fab")
		)
		(fp_line
			(start -15.370048 -34.414968)
			(end 8.24992 -34.414968)
			(stroke
				(width 0.1)
				(type default)
			)
			(layer "F.Fab")
		)
		(fp_line
			(start 8.24992 -34.414968)
			(end 8.24992 39.494968)
			(stroke
				(width 0.1)
				(type default)
			)
			(layer "F.Fab")
		)
		(fp_poly
			(pts
				(xy -4.9022 -0.508) (xy -4.9022 0.508) (xy -3.8862 0)
			)
			(stroke
				(width 0)
				(type default)
			)
			(fill yes)
			(layer "F.Fab")
		)
		(fp_text user "PRESS-FIT"
			(at 10.275316 10.8712 0)
			(unlocked yes)
			(layer "F.SilkS")
			(effects
				(font
					(size 1.905 1.4224)
					(thickness 0.1524)
				)
				(justify left)
			)
		)
		(fp_text user "PRESS-FIT"
			(at 9.78281 -6.60908 0)
			(unlocked yes)
			(layer "B.SilkS")
			(effects
				(font
					(size 1.905 1.4224)
					(thickness 0.1524)
				)
				(justify left mirror)
			)
		)
		(fp_text user "PRESS-FIT"
			(at 10.275316 -5.7912 0)
			(unlocked yes)
			(layer "B.Fab")
			(effects
				(font
					(size 1.905 1.4224)
					(thickness 0.1524)
				)
				(justify left mirror)
			)
		)
		(fp_text user "PRESS-FIT"
			(at 10.275316 10.8712 0)
			(unlocked yes)
			(layer "F.Fab")
			(effects
				(font
					(size 1.905 1.4224)
					(thickness 0.1524)
				)
				(justify left)
			)
		)
		(pad "" np_thru_hole circle
			(at 2.54 -32.385 270)
			(size 0 0)
			(drill 3.048)
			(layers "*.Cu" "*.Mask")
			(clearance 0)
		)
		(pad "" np_thru_hole circle
			(at 2.54 37.465 270)
			(size 0 0)
			(drill 3.048)
			(layers "*.Cu" "*.Mask")
			(clearance 0)
		)
		(pad "A1" thru_hole rect
			(at 0 0 270)
			(size 1.669796 1.669796)
			(drill 1.01981)
			(layers "*.Cu" "*.Mask")
			(remove_unused_layers no)
			(net "TP_J45_A1")
			(clearance -0.070866)
			(padstack
				(mode front_inner_back)
				(layer "Inner"
					(shape circle)
					(size 1.669796 1.669796)
					(clearance -0.070866)
				)
				(layer "B.Cu"
					(shape rect)
					(size 1.669796 1.669796)
					(clearance -0.070866)
				)
			)
		)
		(pad "A2" thru_hole circle
			(at 0 2.54 270)
			(size 1.669796 1.669796)
			(drill 1.01981)
			(layers "*.Cu" "*.Mask")
			(remove_unused_layers no)
			(net "FM_AC_PWR_BTN_PDB_N")
			(clearance -0.070866)
		)
		(pad "A3" thru_hole circle
			(at 0 5.08 270)
			(size 1.669796 1.669796)
			(drill 1.01981)
			(layers "*.Cu" "*.Mask")
			(remove_unused_layers no)
			(net "P3V3_PDB_AUX_ADC")
			(clearance -0.070866)
		)
		(pad "B1" thru_hole circle
			(at 2.54 0 270)
			(size 1.669796 1.669796)
			(drill 1.01981)
			(layers "*.Cu" "*.Mask")
			(remove_unused_layers no)
			(net "RST_SMB_SWITCH_R_N")
			(clearance -0.070866)
		)
		(pad "B2" thru_hole circle
			(at 2.54 2.54 270)
			(size 1.669796 1.669796)
			(drill 1.01981)
			(layers "*.Cu" "*.Mask")
			(remove_unused_layers no)
			(net "PWRGD_P3V3_AUX_PDB_BUF")
			(clearance -0.070866)
		)
		(pad "B3" thru_hole circle
			(at 2.54 5.08 270)
			(size 1.669796 1.669796)
			(drill 1.01981)
			(layers "*.Cu" "*.Mask")
			(remove_unused_layers no)
			(net "GND")
			(clearance -0.070866)
		)
		(pad "C1" thru_hole circle
			(at 5.08 0 270)
			(size 1.669796 1.669796)
			(drill 1.01981)
			(layers "*.Cu" "*.Mask")
			(remove_unused_layers no)
			(net "SMB_FAN_3V3AUX_BUF_R_SCL")
			(clearance -0.070866)
		)
		(pad "C2" thru_hole circle
			(at 5.08 2.54 270)
			(size 1.669796 1.669796)
			(drill 1.01981)
			(layers "*.Cu" "*.Mask")
			(remove_unused_layers no)
			(net "SMB_FAN_3V3AUX_BUF_R_SDA")
			(clearance -0.070866)
		)
		(pad "C3" thru_hole circle
			(at 5.08 5.08 270)
			(size 1.669796 1.669796)
			(drill 1.01981)
			(layers "*.Cu" "*.Mask")
			(remove_unused_layers no)
			(net "HPDB_HSC_PWRGD_R")
			(clearance -0.070866)
		)
		(pad "D1" thru_hole circle
			(at 7.62 0 270)
			(size 1.669796 1.669796)
			(drill 1.01981)
			(layers "*.Cu" "*.Mask")
			(remove_unused_layers no)
			(net "FM_FAN_PWR_EN_R")
			(clearance -0.070866)
		)
		(pad "D2" thru_hole circle
			(at 7.62 2.54 270)
			(size 1.669796 1.669796)
			(drill 1.01981)
			(layers "*.Cu" "*.Mask")
			(remove_unused_layers no)
			(net "FM_GPU_HSC_EN_BUF_R1")
			(clearance -0.070866)
		)
		(pad "D3" thru_hole circle
			(at 7.62 5.08 270)
			(size 1.669796 1.669796)
			(drill 1.01981)
			(layers "*.Cu" "*.Mask")
			(remove_unused_layers no)
			(net "PDB_PRSNT_N")
			(clearance -0.070866)
		)
		(pad "P1_1" thru_hole circle
			(at 0 -25.4 270)
			(size 1.669796 1.669796)
			(drill 1.01981)
			(layers "*.Cu" "*.Mask")
			(remove_unused_layers no)
			(net "GND")
			(clearance -0.070866)
		)
		(pad "P1_2" thru_hole circle
			(at 2.54 -25.4 270)
			(size 1.669796 1.669796)
			(drill 1.01981)
			(layers "*.Cu" "*.Mask")
			(remove_unused_layers no)
			(net "GND")
			(clearance -0.070866)
		)
		(pad "P1_3" thru_hole circle
			(at 5.08 -25.4 270)
			(size 1.669796 1.669796)
			(drill 1.01981)
			(layers "*.Cu" "*.Mask")
			(remove_unused_layers no)
			(net "GND")
			(clearance -0.070866)
		)
		(pad "P1_4" thru_hole circle
			(at 7.62 -25.4 270)
			(size 1.669796 1.669796)
			(drill 1.01981)
			(layers "*.Cu" "*.Mask")
			(remove_unused_layers no)
			(net "GND")
			(clearance -0.070866)
		)
		(pad "P1_5" thru_hole circle
			(at 0 -22.86 270)
			(size 1.669796 1.669796)
			(drill 1.01981)
			(layers "*.Cu" "*.Mask")
			(remove_unused_layers no)
			(net "GND")
			(clearance -0.070866)
		)
		(pad "P1_6" thru_hole circle
			(at 2.54 -22.86 270)
			(size 1.669796 1.669796)
			(drill 1.01981)
			(layers "*.Cu" "*.Mask")
			(remove_unused_layers no)
			(net "GND")
			(clearance -0.070866)
		)
		(pad "P1_7" thru_hole circle
			(at 5.08 -22.86 270)
			(size 1.669796 1.669796)
			(drill 1.01981)
			(layers "*.Cu" "*.Mask")
			(remove_unused_layers no)
			(net "GND")
			(clearance -0.070866)
		)
		(pad "P1_8" thru_hole circle
			(at 7.62 -22.86 270)
			(size 1.669796 1.669796)
			(drill 1.01981)
			(layers "*.Cu" "*.Mask")
			(remove_unused_layers no)
			(net "GND")
			(clearance -0.070866)
		)
		(pad "P2_1" thru_hole circle
			(at 0 -16.51 270)
			(size 1.669796 1.669796)
			(drill 1.01981)
			(layers "*.Cu" "*.Mask")
			(remove_unused_layers no)
			(net "GND")
			(clearance -0.070866)
		)
		(pad "P2_2" thru_hole circle
			(at 2.54 -16.51 270)
			(size 1.669796 1.669796)
			(drill 1.01981)
			(layers "*.Cu" "*.Mask")
			(remove_unused_layers no)
			(net "GND")
			(clearance -0.070866)
		)
		(pad "P2_3" thru_hole circle
			(at 5.08 -16.51 270)
			(size 1.669796 1.669796)
			(drill 1.01981)
			(layers "*.Cu" "*.Mask")
			(remove_unused_layers no)
			(net "GND")
			(clearance -0.070866)
		)
		(pad "P2_4" thru_hole circle
			(at 7.62 -16.51 270)
			(size 1.669796 1.669796)
			(drill 1.01981)
			(layers "*.Cu" "*.Mask")
			(remove_unused_layers no)
			(net "GND")
			(clearance -0.070866)
		)
		(pad "P2_5" thru_hole circle
			(at 0 -13.97 270)
			(size 1.669796 1.669796)
			(drill 1.01981)
			(layers "*.Cu" "*.Mask")
			(remove_unused_layers no)
			(net "GND")
			(clearance -0.070866)
		)
		(pad "P2_6" thru_hole circle
			(at 2.54 -13.97 270)
			(size 1.669796 1.669796)
			(drill 1.01981)
			(layers "*.Cu" "*.Mask")
			(remove_unused_layers no)
			(net "GND")
			(clearance -0.070866)
		)
		(pad "P2_7" thru_hole circle
			(at 5.08 -13.97 270)
			(size 1.669796 1.669796)
			(drill 1.01981)
			(layers "*.Cu" "*.Mask")
			(remove_unused_layers no)
			(net "GND")
			(clearance -0.070866)
		)
		(pad "P2_8" thru_hole circle
			(at 7.62 -13.97 270)
			(size 1.669796 1.669796)
			(drill 1.01981)
			(layers "*.Cu" "*.Mask")
			(remove_unused_layers no)
			(net "GND")
			(clearance -0.070866)
		)
		(pad "P3_1" thru_hole circle
			(at 0 -7.62 270)
			(size 1.669796 1.669796)
			(drill 1.01981)
			(layers "*.Cu" "*.Mask")
			(remove_unused_layers no)
			(net "GND")
			(clearance -0.070866)
		)
		(pad "P3_2" thru_hole circle
			(at 2.54 -7.62 270)
			(size 1.669796 1.669796)
			(drill 1.01981)
			(layers "*.Cu" "*.Mask")
			(remove_unused_layers no)
			(net "GND")
			(clearance -0.070866)
		)
		(pad "P3_3" thru_hole circle
			(at 5.08 -7.62 270)
			(size 1.669796 1.669796)
			(drill 1.01981)
			(layers "*.Cu" "*.Mask")
			(remove_unused_layers no)
			(net "GND")
			(clearance -0.070866)
		)
		(pad "P3_4" thru_hole circle
			(at 7.62 -7.62 270)
			(size 1.669796 1.669796)
			(drill 1.01981)
			(layers "*.Cu" "*.Mask")
			(remove_unused_layers no)
			(net "GND")
			(clearance -0.070866)
		)
		(pad "P3_5" thru_hole circle
			(at 0 -5.08 270)
			(size 1.669796 1.669796)
			(drill 1.01981)
			(layers "*.Cu" "*.Mask")
			(remove_unused_layers no)
			(net "GND")
			(clearance -0.070866)
		)
		(pad "P3_6" thru_hole circle
			(at 2.54 -5.08 270)
			(size 1.669796 1.669796)
			(drill 1.01981)
			(layers "*.Cu" "*.Mask")
			(remove_unused_layers no)
			(net "GND")
			(clearance -0.070866)
		)
		(pad "P3_7" thru_hole circle
			(at 5.08 -5.08 270)
			(size 1.669796 1.669796)
			(drill 1.01981)
			(layers "*.Cu" "*.Mask")
			(remove_unused_layers no)
			(net "GND")
			(clearance -0.070866)
		)
		(pad "P3_8" thru_hole circle
			(at 7.62 -5.08 270)
			(size 1.669796 1.669796)
			(drill 1.01981)
			(layers "*.Cu" "*.Mask")
			(remove_unused_layers no)
			(net "GND")
			(clearance -0.070866)
		)
		(pad "P4_1" thru_hole circle
			(at 0 10.16 270)
			(size 1.669796 1.669796)
			(drill 1.01981)
			(layers "*.Cu" "*.Mask")
			(remove_unused_layers no)
			(net "P12V_PSU")
			(clearance -0.070866)
		)
		(pad "P4_2" thru_hole circle
			(at 2.54 10.16 270)
			(size 1.669796 1.669796)
			(drill 1.01981)
			(layers "*.Cu" "*.Mask")
			(remove_unused_layers no)
			(net "P12V_PSU")
			(clearance -0.070866)
		)
		(pad "P4_3" thru_hole circle
			(at 5.08 10.16 270)
			(size 1.669796 1.669796)
			(drill 1.01981)
			(layers "*.Cu" "*.Mask")
			(remove_unused_layers no)
			(net "P12V_PSU")
			(clearance -0.070866)
		)
		(pad "P4_4" thru_hole circle
			(at 7.62 10.16 270)
			(size 1.669796 1.669796)
			(drill 1.01981)
			(layers "*.Cu" "*.Mask")
			(remove_unused_layers no)
			(net "P12V_PSU")
			(clearance -0.070866)
		)
		(pad "P4_5" thru_hole circle
			(at 0 12.7 270)
			(size 1.669796 1.669796)
			(drill 1.01981)
			(layers "*.Cu" "*.Mask")
			(remove_unused_layers no)
			(net "P12V_PSU")
			(clearance -0.070866)
		)
		(pad "P4_6" thru_hole circle
			(at 2.54 12.7 270)
			(size 1.669796 1.669796)
			(drill 1.01981)
			(layers "*.Cu" "*.Mask")
			(remove_unused_layers no)
			(net "P12V_PSU")
			(clearance -0.070866)
		)
		(pad "P4_7" thru_hole circle
			(at 5.08 12.7 270)
			(size 1.669796 1.669796)
			(drill 1.01981)
			(layers "*.Cu" "*.Mask")
			(remove_unused_layers no)
			(net "P12V_PSU")
			(clearance -0.070866)
		)
		(pad "P4_8" thru_hole circle
			(at 7.62 12.7 270)
			(size 1.669796 1.669796)
			(drill 1.01981)
			(layers "*.Cu" "*.Mask")
			(remove_unused_layers no)
			(net "P12V_PSU")
			(clearance -0.070866)
		)
		(pad "P5_1" thru_hole circle
			(at 0 19.05 270)
			(size 1.669796 1.669796)
			(drill 1.01981)
			(layers "*.Cu" "*.Mask")
			(remove_unused_layers no)
			(net "P12V_PSU")
			(clearance -0.070866)
		)
		(pad "P5_2" thru_hole circle
			(at 2.54 19.05 270)
			(size 1.669796 1.669796)
			(drill 1.01981)
			(layers "*.Cu" "*.Mask")
			(remove_unused_layers no)
			(net "P12V_PSU")
			(clearance -0.070866)
		)
		(pad "P5_3" thru_hole circle
			(at 5.08 19.05 270)
			(size 1.669796 1.669796)
			(drill 1.01981)
			(layers "*.Cu" "*.Mask")
			(remove_unused_layers no)
			(net "P12V_PSU")
			(clearance -0.070866)
		)
		(pad "P5_4" thru_hole circle
			(at 7.62 19.05 270)
			(size 1.669796 1.669796)
			(drill 1.01981)
			(layers "*.Cu" "*.Mask")
			(remove_unused_layers no)
			(net "P12V_PSU")
			(clearance -0.070866)
		)
		(pad "P5_5" thru_hole circle
			(at 0 21.59 270)
			(size 1.669796 1.669796)
			(drill 1.01981)
			(layers "*.Cu" "*.Mask")
			(remove_unused_layers no)
			(net "P12V_PSU")
			(clearance -0.070866)
		)
		(pad "P5_6" thru_hole circle
			(at 2.54 21.59 270)
			(size 1.669796 1.669796)
			(drill 1.01981)
			(layers "*.Cu" "*.Mask")
			(remove_unused_layers no)
			(net "P12V_PSU")
			(clearance -0.070866)
		)
		(pad "P5_7" thru_hole circle
			(at 5.08 21.59 270)
			(size 1.669796 1.669796)
			(drill 1.01981)
			(layers "*.Cu" "*.Mask")
			(remove_unused_layers no)
			(net "P12V_PSU")
			(clearance -0.070866)
		)
		(pad "P5_8" thru_hole circle
			(at 7.62 21.59 270)
			(size 1.669796 1.669796)
			(drill 1.01981)
			(layers "*.Cu" "*.Mask")
			(remove_unused_layers no)
			(net "P12V_PSU")
			(clearance -0.070866)
		)
		(pad "P6_1" thru_hole circle
			(at 0 27.94 270)
			(size 1.669796 1.669796)
			(drill 1.01981)
			(layers "*.Cu" "*.Mask")
			(remove_unused_layers no)
			(net "P12V_PSU")
			(clearance -0.070866)
		)
		(pad "P6_2" thru_hole circle
			(at 2.54 27.94 270)
			(size 1.669796 1.669796)
			(drill 1.01981)
			(layers "*.Cu" "*.Mask")
			(remove_unused_layers no)
			(net "P12V_PSU")
			(clearance -0.070866)
		)
		(pad "P6_3" thru_hole circle
			(at 5.08 27.94 270)
			(size 1.669796 1.669796)
			(drill 1.01981)
			(layers "*.Cu" "*.Mask")
			(remove_unused_layers no)
			(net "P12V_PSU")
			(clearance -0.070866)
		)
		(pad "P6_4" thru_hole circle
			(at 7.62 27.94 270)
			(size 1.669796 1.669796)
			(drill 1.01981)
			(layers "*.Cu" "*.Mask")
			(remove_unused_layers no)
			(net "P12V_PSU")
			(clearance -0.070866)
		)
		(pad "P6_5" thru_hole circle
			(at 0 30.48 270)
			(size 1.669796 1.669796)
			(drill 1.01981)
			(layers "*.Cu" "*.Mask")
			(remove_unused_layers no)
			(net "P12V_PSU")
			(clearance -0.070866)
		)
		(pad "P6_6" thru_hole circle
			(at 2.54 30.48 270)
			(size 1.669796 1.669796)
			(drill 1.01981)
			(layers "*.Cu" "*.Mask")
			(remove_unused_layers no)
			(net "P12V_PSU")
			(clearance -0.070866)
		)
		(pad "P6_7" thru_hole circle
			(at 5.08 30.48 270)
			(size 1.669796 1.669796)
			(drill 1.01981)
			(layers "*.Cu" "*.Mask")
			(remove_unused_layers no)
			(net "P12V_PSU")
			(clearance -0.070866)
		)
		(pad "P6_8" thru_hole circle
			(at 7.62 30.48 270)
			(size 1.669796 1.669796)
			(drill 1.01981)
			(layers "*.Cu" "*.Mask")
			(remove_unused_layers no)
			(net "P12V_PSU")
			(clearance -0.070866)
		)
		(zone
			(layer "F.Cu")
			(hatch none 0.5)
			(connect_pads
				(clearance 0)
			)
			(min_thickness 0.25)
			(keepout
				(tracks not_allowed)
				(vias allowed)
				(pads allowed)
				(copperpour not_allowed)
				(footprints allowed)
			)
			(placement
				(enabled no)
				(sheetname "")
			)
			(fill
				(thermal_gap 0.5)
				(thermal_bridge_width 0.5)
				(island_removal_mode 0)
			)
			(polygon
				(pts
					(xy 198.825104 -440.66206) (xy 198.825104 -423.902124) (xy 272.995136 -423.902124) (xy 272.995136 -440.66206)
				)
			)
		)
		(zone
			(layers "F.Cu" "B.Cu" "In1.Cu" "In2.Cu" "In3.Cu" "In4.Cu" "In5.Cu" "In6.Cu"
				"In7.Cu" "In8.Cu" "In9.Cu" "In10.Cu" "In11.Cu" "In12.Cu" "In13.Cu" "In14.Cu"
				"In15.Cu" "In16.Cu"
			)
			(hatch none 0.5)
			(connect_pads
				(clearance 0)
			)
			(min_thickness 0.25)
			(keepout
				(tracks not_allowed)
				(vias allowed)
				(pads allowed)
				(copperpour not_allowed)
				(footprints allowed)
			)
			(placement
				(enabled no)
				(sheetname "")
			)
			(fill
				(thermal_gap 0.5)
				(thermal_bridge_width 0.5)
				(island_removal_mode 0)
			)
			(polygon
				(pts
					(arc
						(start 204.68082 -433.04206)
						(mid 197.28942 -433.04206)
						(end 204.68082 -433.04206)
					)
				)
			)
		)
		(zone
			(layers "F.Cu" "B.Cu" "In1.Cu" "In2.Cu" "In3.Cu" "In4.Cu" "In5.Cu" "In6.Cu"
				"In7.Cu" "In8.Cu" "In9.Cu" "In10.Cu" "In11.Cu" "In12.Cu" "In13.Cu" "In14.Cu"
				"In15.Cu" "In16.Cu"
			)
			(hatch none 0.5)
			(connect_pads
				(clearance 0)
			)
			(min_thickness 0.25)
			(keepout
				(tracks not_allowed)
				(vias allowed)
				(pads allowed)
				(copperpour not_allowed)
				(footprints allowed)
			)
			(placement
				(enabled no)
				(sheetname "")
			)
			(fill
				(thermal_gap 0.5)
				(thermal_bridge_width 0.5)
				(island_removal_mode 0)
			)
			(polygon
				(pts
					(arc
						(start 274.53082 -433.04206)
						(mid 267.13942 -433.04206)
						(end 274.53082 -433.04206)
					)
				)
			)
		)
		(zone
			(layer "B.Cu")
			(hatch none 0.5)
			(connect_pads
				(clearance 0)
			)
			(min_thickness 0.25)
			(keepout
				(tracks allowed)
				(vias not_allowed)
				(pads allowed)
				(copperpour not_allowed)
				(footprints allowed)
			)
			(placement
				(enabled no)
				(sheetname "")
			)
			(fill
				(thermal_gap 0.5)
				(thermal_bridge_width 0.5)
				(island_removal_mode 0)
			)
			(polygon
				(pts
					(xy 207.071722 -436.480458) (xy 264.748518 -436.480458) (xy 264.748518 -427.063662) (xy 207.071722 -427.063662)
				)
			)
		)
	)
	(footprint ""
		(layer "F.Cu")
		(at 157.995366 -57.474358)
		(property "Reference" "C2018"
			(at 0 0 0)
			(layer "F.SilkS")
			(hide yes)
			(effects
				(font
					(size 1.27 1.27)
				)
			)
		)
		(property "Value" ""
			(at 0 0 0)
			(layer "F.Fab")
			(effects
				(font
					(size 1.27 1.27)
				)
			)
		)
		(duplicate_pad_numbers_are_jumpers no)
		(fp_line
			(start -0.7874 -0.4064)
			(end 0.7874 -0.4064)
			(stroke
				(width 0.1524)
				(type default)
			)
			(layer "F.SilkS")
		)
		(fp_line
			(start -0.7874 0.4064)
			(end -0.7874 -0.4064)
			(stroke
				(width 0.1524)
				(type default)
			)
			(layer "F.SilkS")
		)
		(fp_line
			(start 0.7874 -0.4064)
			(end 0.7874 0.4064)
			(stroke
				(width 0.1524)
				(type default)
			)
			(layer "F.SilkS")
		)
		(fp_line
			(start 0.7874 0.4064)
			(end -0.7874 0.4064)
			(stroke
				(width 0.1524)
				(type default)
			)
			(layer "F.SilkS")
		)
		(fp_line
			(start -0.67945 -0.305054)
			(end -0.12065 -0.305054)
			(stroke
				(width 0.1)
				(type default)
			)
			(layer "F.Fab")
		)
		(fp_line
			(start -0.67945 0.3048)
			(end -0.67945 -0.305054)
			(stroke
				(width 0.1)
				(type default)
			)
			(layer "F.Fab")
		)
		(fp_line
			(start -0.12065 -0.305054)
			(end -0.12065 -0.2794)
			(stroke
				(width 0.1)
				(type default)
			)
			(layer "F.Fab")
		)
		(fp_line
			(start -0.12065 -0.2794)
			(end 0.12065 -0.2794)
			(stroke
				(width 0.1)
				(type default)
			)
			(layer "F.Fab")
		)
		(fp_line
			(start -0.12065 0.2794)
			(end -0.12065 0.3048)
			(stroke
				(width 0.1)
				(type default)
			)
			(layer "F.Fab")
		)
		(fp_line
			(start -0.12065 0.3048)
			(end -0.67945 0.3048)
			(stroke
				(width 0.1)
				(type default)
			)
			(layer "F.Fab")
		)
		(fp_line
			(start 0.120396 0.2794)
			(end -0.12065 0.2794)
			(stroke
				(width 0.1)
				(type default)
			)
			(layer "F.Fab")
		)
		(fp_line
			(start 0.120396 0.3048)
			(end 0.120396 0.2794)
			(stroke
				(width 0.1)
				(type default)
			)
			(layer "F.Fab")
		)
		(fp_line
			(start 0.12065 -0.3048)
			(end 0.67945 -0.3048)
			(stroke
				(width 0.1)
				(type default)
			)
			(layer "F.Fab")
		)
		(fp_line
			(start 0.12065 -0.2794)
			(end 0.12065 -0.3048)
			(stroke
				(width 0.1)
				(type default)
			)
			(layer "F.Fab")
		)
		(fp_line
			(start 0.67945 -0.3048)
			(end 0.67945 0.3048)
			(stroke
				(width 0.1)
				(type default)
			)
			(layer "F.Fab")
		)
		(fp_line
			(start 0.67945 0.3048)
			(end 0.120396 0.3048)
			(stroke
				(width 0.1)
				(type default)
			)
			(layer "F.Fab")
		)
		(pad "1" smd circle
			(at -0.40005 0)
			(size 0 0)
			(layers "F.Cu" "F.Mask" "F.Paste")
			(net "P3V3")
		)
		(pad "2" smd circle
			(at 0.40005 0)
			(size 0 0)
			(layers "F.Cu" "F.Mask" "F.Paste")
			(net "GND")
		)
	)
	(footprint ""
		(layer "F.Cu")
		(at 200.914 -101.346 180)
		(property "Reference" "R8000"
			(at 0 0 180)
			(layer "F.SilkS")
			(hide yes)
			(effects
				(font
					(size 1.27 1.27)
				)
			)
		)
		(property "Value" ""
			(at 0 0 180)
			(layer "F.Fab")
			(effects
				(font
					(size 1.27 1.27)
				)
			)
		)
		(duplicate_pad_numbers_are_jumpers no)
		(fp_line
			(start 0.7874 0.4064)
			(end -0.7874 0.4064)
			(stroke
				(width 0.1524)
				(type default)
			)
			(layer "F.SilkS")
		)
		(fp_line
			(start 0.7874 -0.4064)
			(end 0.7874 0.4064)
			(stroke
				(width 0.1524)
				(type default)
			)
			(layer "F.SilkS")
		)
		(fp_line
			(start -0.7874 0.4064)
			(end -0.7874 -0.4064)
			(stroke
				(width 0.1524)
				(type default)
			)
			(layer "F.SilkS")
		)
		(fp_line
			(start -0.7874 -0.4064)
			(end 0.7874 -0.4064)
			(stroke
				(width 0.1524)
				(type default)
			)
			(layer "F.SilkS")
		)
		(fp_line
			(start 0.67945 0.3048)
			(end 0.120396 0.3048)
			(stroke
				(width 0.1)
				(type default)
			)
			(layer "F.Fab")
		)
		(fp_line
			(start 0.67945 -0.3048)
			(end 0.67945 0.3048)
			(stroke
				(width 0.1)
				(type default)
			)
			(layer "F.Fab")
		)
		(fp_line
			(start 0.12065 -0.2794)
			(end 0.12065 -0.3048)
			(stroke
				(width 0.1)
				(type default)
			)
			(layer "F.Fab")
		)
		(fp_line
			(start 0.12065 -0.3048)
			(end 0.67945 -0.3048)
			(stroke
				(width 0.1)
				(type default)
			)
			(layer "F.Fab")
		)
		(fp_line
			(start 0.120396 0.3048)
			(end 0.120396 0.2794)
			(stroke
				(width 0.1)
				(type default)
			)
			(layer "F.Fab")
		)
		(fp_line
			(start 0.120396 0.2794)
			(end -0.12065 0.2794)
			(stroke
				(width 0.1)
				(type default)
			)
			(layer "F.Fab")
		)
		(fp_line
			(start -0.12065 0.3048)
			(end -0.67945 0.3048)
			(stroke
				(width 0.1)
				(type default)
			)
			(layer "F.Fab")
		)
		(fp_line
			(start -0.12065 0.2794)
			(end -0.12065 0.3048)
			(stroke
				(width 0.1)
				(type default)
			)
			(layer "F.Fab")
		)
		(fp_line
			(start -0.12065 -0.2794)
			(end 0.12065 -0.2794)
			(stroke
				(width 0.1)
				(type default)
			)
			(layer "F.Fab")
		)
		(fp_line
			(start -0.12065 -0.305054)
			(end -0.12065 -0.2794)
			(stroke
				(width 0.1)
				(type default)
			)
			(layer "F.Fab")
		)
		(fp_line
			(start -0.67945 0.3048)
			(end -0.67945 -0.305054)
			(stroke
				(width 0.1)
				(type default)
			)
			(layer "F.Fab")
		)
		(fp_line
			(start -0.67945 -0.305054)
			(end -0.12065 -0.305054)
			(stroke
				(width 0.1)
				(type default)
			)
			(layer "F.Fab")
		)
		(pad "1" smd circle
			(at -0.40005 0 180)
			(size 0 0)
			(layers "F.Cu" "F.Mask" "F.Paste")
			(net "PRSNT_SWB_ISO_N")
		)
		(pad "2" smd circle
			(at 0.40005 0 180)
			(size 0 0)
			(layers "F.Cu" "F.Mask" "F.Paste")
			(net "PRSNT_SWB_ISO_R_N")
		)
	)
	(footprint ""
		(layer "F.Cu")
		(at 200.914 -104.521 180)
		(property "Reference" "R8081"
			(at 0 0 180)
			(layer "F.SilkS")
			(hide yes)
			(effects
				(font
					(size 1.27 1.27)
				)
			)
		)
		(property "Value" ""
			(at 0 0 180)
			(layer "F.Fab")
			(effects
				(font
					(size 1.27 1.27)
				)
			)
		)
		(duplicate_pad_numbers_are_jumpers no)
		(fp_line
			(start 0.7874 0.4064)
			(end -0.7874 0.4064)
			(stroke
				(width 0.1524)
				(type default)
			)
			(layer "F.SilkS")
		)
		(fp_line
			(start 0.7874 -0.4064)
			(end 0.7874 0.4064)
			(stroke
				(width 0.1524)
				(type default)
			)
			(layer "F.SilkS")
		)
		(fp_line
			(start -0.7874 0.4064)
			(end -0.7874 -0.4064)
			(stroke
				(width 0.1524)
				(type default)
			)
			(layer "F.SilkS")
		)
		(fp_line
			(start -0.7874 -0.4064)
			(end 0.7874 -0.4064)
			(stroke
				(width 0.1524)
				(type default)
			)
			(layer "F.SilkS")
		)
		(fp_line
			(start 0.67945 0.3048)
			(end 0.120396 0.3048)
			(stroke
				(width 0.1)
				(type default)
			)
			(layer "F.Fab")
		)
		(fp_line
			(start 0.67945 -0.3048)
			(end 0.67945 0.3048)
			(stroke
				(width 0.1)
				(type default)
			)
			(layer "F.Fab")
		)
		(fp_line
			(start 0.12065 -0.2794)
			(end 0.12065 -0.3048)
			(stroke
				(width 0.1)
				(type default)
			)
			(layer "F.Fab")
		)
		(fp_line
			(start 0.12065 -0.3048)
			(end 0.67945 -0.3048)
			(stroke
				(width 0.1)
				(type default)
			)
			(layer "F.Fab")
		)
		(fp_line
			(start 0.120396 0.3048)
			(end 0.120396 0.2794)
			(stroke
				(width 0.1)
				(type default)
			)
			(layer "F.Fab")
		)
		(fp_line
			(start 0.120396 0.2794)
			(end -0.12065 0.2794)
			(stroke
				(width 0.1)
				(type default)
			)
			(layer "F.Fab")
		)
		(fp_line
			(start -0.12065 0.3048)
			(end -0.67945 0.3048)
			(stroke
				(width 0.1)
				(type default)
			)
			(layer "F.Fab")
		)
		(fp_line
			(start -0.12065 0.2794)
			(end -0.12065 0.3048)
			(stroke
				(width 0.1)
				(type default)
			)
			(layer "F.Fab")
		)
		(fp_line
			(start -0.12065 -0.2794)
			(end 0.12065 -0.2794)
			(stroke
				(width 0.1)
				(type default)
			)
			(layer "F.Fab")
		)
		(fp_line
			(start -0.12065 -0.305054)
			(end -0.12065 -0.2794)
			(stroke
				(width 0.1)
				(type default)
			)
			(layer "F.Fab")
		)
		(fp_line
			(start -0.67945 0.3048)
			(end -0.67945 -0.305054)
			(stroke
				(width 0.1)
				(type default)
			)
			(layer "F.Fab")
		)
		(fp_line
			(start -0.67945 -0.305054)
			(end -0.12065 -0.305054)
			(stroke
				(width 0.1)
				(type default)
			)
			(layer "F.Fab")
		)
		(pad "1" smd circle
			(at -0.40005 0 180)
			(size 0 0)
			(layers "F.Cu" "F.Mask" "F.Paste")
			(net "PWRGD_CHAF_CPU0_R1")
		)
		(pad "2" smd circle
			(at 0.40005 0 180)
			(size 0 0)
			(layers "F.Cu" "F.Mask" "F.Paste")
			(net "PWRGD_CHAF_CPU0_R2")
		)
	)
	(footprint ""
		(layer "F.Cu")
		(at 144.315688 -395.436852 -90)
		(property "Reference" "R870"
			(at 0 0 270)
			(layer "F.SilkS")
			(hide yes)
			(effects
				(font
					(size 1.27 1.27)
				)
			)
		)
		(property "Value" ""
			(at 0 0 270)
			(layer "F.Fab")
			(effects
				(font
					(size 1.27 1.27)
				)
			)
		)
		(duplicate_pad_numbers_are_jumpers no)
		(fp_line
			(start -0.32512 0.175006)
			(end -0.32512 -0.175006)
			(stroke
				(width 0.1)
				(type default)
			)
			(layer "F.Fab")
		)
		(fp_line
			(start 0.32512 0.175006)
			(end -0.32512 0.175006)
			(stroke
				(width 0.1)
				(type default)
			)
			(layer "F.Fab")
		)
		(fp_line
			(start -0.32512 -0.175006)
			(end 0.32512 -0.175006)
			(stroke
				(width 0.1)
				(type default)
			)
			(layer "F.Fab")
		)
		(fp_line
			(start 0.32512 -0.175006)
			(end 0.32512 0.175006)
			(stroke
				(width 0.1)
				(type default)
			)
			(layer "F.Fab")
		)
		(pad "1" smd rect
			(at -0.2667 0 270)
			(size 0.3048 0.381)
			(layers "F.Cu" "F.Mask" "F.Paste")
			(net "P1V8_CPU1_RT_1D")
		)
		(pad "2" smd rect
			(at 0.2667 0 90)
			(size 0.3048 0.381)
			(layers "F.Cu" "F.Mask" "F.Paste")
			(net "RST_RT_CPU1_P2_RESET_R_N")
		)
	)
	(footprint ""
		(layer "F.Cu")
		(at 154.633422 -52.771294 90)
		(property "Reference" "R3572"
			(at 0 0 90)
			(layer "F.SilkS")
			(hide yes)
			(effects
				(font
					(size 1.27 1.27)
				)
			)
		)
		(property "Value" ""
			(at 0 0 90)
			(layer "F.Fab")
			(effects
				(font
					(size 1.27 1.27)
				)
			)
		)
		(duplicate_pad_numbers_are_jumpers no)
		(fp_line
			(start 0.7874 -0.4064)
			(end 0.7874 0.4064)
			(stroke
				(width 0.1524)
				(type default)
			)
			(layer "F.SilkS")
		)
		(fp_line
			(start -0.7874 -0.4064)
			(end 0.7874 -0.4064)
			(stroke
				(width 0.1524)
				(type default)
			)
			(layer "F.SilkS")
		)
		(fp_line
			(start 0.7874 0.4064)
			(end -0.7874 0.4064)
			(stroke
				(width 0.1524)
				(type default)
			)
			(layer "F.SilkS")
		)
		(fp_line
			(start -0.7874 0.4064)
			(end -0.7874 -0.4064)
			(stroke
				(width 0.1524)
				(type default)
			)
			(layer "F.SilkS")
		)
		(fp_line
			(start -0.12065 -0.305054)
			(end -0.12065 -0.2794)
			(stroke
				(width 0.1)
				(type default)
			)
			(layer "F.Fab")
		)
		(fp_line
			(start -0.67945 -0.305054)
			(end -0.12065 -0.305054)
			(stroke
				(width 0.1)
				(type default)
			)
			(layer "F.Fab")
		)
		(fp_line
			(start 0.67945 -0.3048)
			(end 0.67945 0.3048)
			(stroke
				(width 0.1)
				(type default)
			)
			(layer "F.Fab")
		)
		(fp_line
			(start 0.12065 -0.3048)
			(end 0.67945 -0.3048)
			(stroke
				(width 0.1)
				(type default)
			)
			(layer "F.Fab")
		)
		(fp_line
			(start 0.12065 -0.2794)
			(end 0.12065 -0.3048)
			(stroke
				(width 0.1)
				(type default)
			)
			(layer "F.Fab")
		)
		(fp_line
			(start -0.12065 -0.2794)
			(end 0.12065 -0.2794)
			(stroke
				(width 0.1)
				(type default)
			)
			(layer "F.Fab")
		)
		(fp_line
			(start 0.120396 0.2794)
			(end -0.12065 0.2794)
			(stroke
				(width 0.1)
				(type default)
			)
			(layer "F.Fab")
		)
		(fp_line
			(start -0.12065 0.2794)
			(end -0.12065 0.3048)
			(stroke
				(width 0.1)
				(type default)
			)
			(layer "F.Fab")
		)
		(fp_line
			(start 0.67945 0.3048)
			(end 0.120396 0.3048)
			(stroke
				(width 0.1)
				(type default)
			)
			(layer "F.Fab")
		)
		(fp_line
			(start 0.120396 0.3048)
			(end 0.120396 0.2794)
			(stroke
				(width 0.1)
				(type default)
			)
			(layer "F.Fab")
		)
		(fp_line
			(start -0.12065 0.3048)
			(end -0.67945 0.3048)
			(stroke
				(width 0.1)
				(type default)
			)
			(layer "F.Fab")
		)
		(fp_line
			(start -0.67945 0.3048)
			(end -0.67945 -0.305054)
			(stroke
				(width 0.1)
				(type default)
			)
			(layer "F.Fab")
		)
		(pad "1" smd circle
			(at -0.40005 0 90)
			(size 0 0)
			(layers "F.Cu" "F.Mask" "F.Paste")
			(net "SMB_INA230_4_3V3AUX_SCL_R")
		)
		(pad "2" smd circle
			(at 0.40005 0 90)
			(size 0 0)
			(layers "F.Cu" "F.Mask" "F.Paste")
			(net "SMB_INA230_4_3V3AUX_SCL_R1")
		)
	)
	(footprint ""
		(layer "F.Cu")
		(at 296.385742 -400.1516 -90)
		(property "Reference" "R975"
			(at 0 0 270)
			(layer "F.SilkS")
			(hide yes)
			(effects
				(font
					(size 1.27 1.27)
				)
			)
		)
		(property "Value" ""
			(at 0 0 270)
			(layer "F.Fab")
			(effects
				(font
					(size 1.27 1.27)
				)
			)
		)
		(duplicate_pad_numbers_are_jumpers no)
		(fp_line
			(start -0.32512 0.175006)
			(end -0.32512 -0.175006)
			(stroke
				(width 0.1)
				(type default)
			)
			(layer "F.Fab")
		)
		(fp_line
			(start 0.32512 0.175006)
			(end -0.32512 0.175006)
			(stroke
				(width 0.1)
				(type default)
			)
			(layer "F.Fab")
		)
		(fp_line
			(start -0.32512 -0.175006)
			(end 0.32512 -0.175006)
			(stroke
				(width 0.1)
				(type default)
			)
			(layer "F.Fab")
		)
		(fp_line
			(start 0.32512 -0.175006)
			(end 0.32512 0.175006)
			(stroke
				(width 0.1)
				(type default)
			)
			(layer "F.Fab")
		)
		(pad "1" smd rect
			(at -0.2667 0 270)
			(size 0.3048 0.381)
			(layers "F.Cu" "F.Mask" "F.Paste")
			(net "P1V8_CPU0_RT_1D")
		)
		(pad "2" smd rect
			(at 0.2667 0 90)
			(size 0.3048 0.381)
			(layers "F.Cu" "F.Mask" "F.Paste")
			(net "JTAG_TEST_MODE_RT_CPU0_P0")
		)
	)
	(footprint ""
		(layer "F.Cu")
		(at 128.809496 -375.49963 -90)
		(property "Reference" "C1527"
			(at 0 0 270)
			(layer "F.SilkS")
			(hide yes)
			(effects
				(font
					(size 1.27 1.27)
				)
			)
		)
		(property "Value" ""
			(at 0 0 270)
			(layer "F.Fab")
			(effects
				(font
					(size 1.27 1.27)
				)
			)
		)
		(duplicate_pad_numbers_are_jumpers no)
		(fp_line
			(start -0.299974 0.150114)
			(end -0.299974 -0.150114)
			(stroke
				(width 0.1)
				(type default)
			)
			(layer "F.Fab")
		)
		(fp_line
			(start 0.299974 0.150114)
			(end -0.299974 0.150114)
			(stroke
				(width 0.1)
				(type default)
			)
			(layer "F.Fab")
		)
		(fp_line
			(start -0.299974 -0.150114)
			(end 0.299974 -0.150114)
			(stroke
				(width 0.1)
				(type default)
			)
			(layer "F.Fab")
		)
		(fp_line
			(start 0.299974 -0.150114)
			(end 0.299974 0.150114)
			(stroke
				(width 0.1)
				(type default)
			)
			(layer "F.Fab")
		)
		(pad "1" smd rect
			(at -0.2667 0 270)
			(size 0.3048 0.381)
			(layers "F.Cu" "F.Mask" "F.Paste")
			(net "P5E_CPU1_P3_TX_C_DP<10>")
		)
		(pad "2" smd rect
			(at 0.2667 0 270)
			(size 0.3048 0.381)
			(layers "F.Cu" "F.Mask" "F.Paste")
			(net "P5E_CPU1_P3_TX_DP<10>")
		)
	)
	(footprint ""
		(layer "F.Cu")
		(at 411.734 -364.236 -90)
		(property "Reference" "R123"
			(at 0 0 270)
			(layer "F.SilkS")
			(hide yes)
			(effects
				(font
					(size 1.27 1.27)
				)
			)
		)
		(property "Value" ""
			(at 0 0 270)
			(layer "F.Fab")
			(effects
				(font
					(size 1.27 1.27)
				)
			)
		)
		(duplicate_pad_numbers_are_jumpers no)
		(fp_line
			(start -0.7874 0.4064)
			(end -0.7874 -0.4064)
			(stroke
				(width 0.1524)
				(type default)
			)
			(layer "F.SilkS")
		)
		(fp_line
			(start 0.7874 0.4064)
			(end -0.7874 0.4064)
			(stroke
				(width 0.1524)
				(type default)
			)
			(layer "F.SilkS")
		)
		(fp_line
			(start -0.7874 -0.4064)
			(end 0.7874 -0.4064)
			(stroke
				(width 0.1524)
				(type default)
			)
			(layer "F.SilkS")
		)
		(fp_line
			(start 0.7874 -0.4064)
			(end 0.7874 0.4064)
			(stroke
				(width 0.1524)
				(type default)
			)
			(layer "F.SilkS")
		)
		(fp_line
			(start -0.67945 0.3048)
			(end -0.67945 -0.305054)
			(stroke
				(width 0.1)
				(type default)
			)
			(layer "F.Fab")
		)
		(fp_line
			(start -0.12065 0.3048)
			(end -0.67945 0.3048)
			(stroke
				(width 0.1)
				(type default)
			)
			(layer "F.Fab")
		)
		(fp_line
			(start 0.120396 0.3048)
			(end 0.120396 0.2794)
			(stroke
				(width 0.1)
				(type default)
			)
			(layer "F.Fab")
		)
		(fp_line
			(start 0.67945 0.3048)
			(end 0.120396 0.3048)
			(stroke
				(width 0.1)
				(type default)
			)
			(layer "F.Fab")
		)
		(fp_line
			(start -0.12065 0.2794)
			(end -0.12065 0.3048)
			(stroke
				(width 0.1)
				(type default)
			)
			(layer "F.Fab")
		)
		(fp_line
			(start 0.120396 0.2794)
			(end -0.12065 0.2794)
			(stroke
				(width 0.1)
				(type default)
			)
			(layer "F.Fab")
		)
		(fp_line
			(start -0.12065 -0.2794)
			(end 0.12065 -0.2794)
			(stroke
				(width 0.1)
				(type default)
			)
			(layer "F.Fab")
		)
		(fp_line
			(start 0.12065 -0.2794)
			(end 0.12065 -0.3048)
			(stroke
				(width 0.1)
				(type default)
			)
			(layer "F.Fab")
		)
		(fp_line
			(start 0.12065 -0.3048)
			(end 0.67945 -0.3048)
			(stroke
				(width 0.1)
				(type default)
			)
			(layer "F.Fab")
		)
		(fp_line
			(start 0.67945 -0.3048)
			(end 0.67945 0.3048)
			(stroke
				(width 0.1)
				(type default)
			)
			(layer "F.Fab")
		)
		(fp_line
			(start -0.67945 -0.305054)
			(end -0.12065 -0.305054)
			(stroke
				(width 0.1)
				(type default)
			)
			(layer "F.Fab")
		)
		(fp_line
			(start -0.12065 -0.305054)
			(end -0.12065 -0.2794)
			(stroke
				(width 0.1)
				(type default)
			)
			(layer "F.Fab")
		)
		(pad "1" smd circle
			(at -0.40005 0 270)
			(size 0 0)
			(layers "F.Cu" "F.Mask" "F.Paste")
			(net "PVDD11_S3_P0_EN")
		)
		(pad "2" smd circle
			(at 0.40005 0 270)
			(size 0 0)
			(layers "F.Cu" "F.Mask" "F.Paste")
			(net "PVDD11_S3_P0_EN_R")
		)
	)
	(footprint ""
		(layer "F.Cu")
		(at 136.10717 -153.865834 -90)
		(property "Reference" "PC346"
			(at 0 0 270)
			(layer "F.SilkS")
			(hide yes)
			(effects
				(font
					(size 1.27 1.27)
				)
			)
		)
		(property "Value" ""
			(at 0 0 270)
			(layer "F.Fab")
			(effects
				(font
					(size 1.27 1.27)
				)
			)
		)
		(duplicate_pad_numbers_are_jumpers no)
		(fp_line
			(start -0.7874 0.4064)
			(end -0.7874 -0.4064)
			(stroke
				(width 0.1524)
				(type default)
			)
			(layer "F.SilkS")
		)
		(fp_line
			(start -0.286766 0.4064)
			(end -0.7874 0.4064)
			(stroke
				(width 0.1524)
				(type default)
			)
			(layer "F.SilkS")
		)
		(fp_line
			(start 0.7874 0.4064)
			(end 0.297434 0.4064)
			(stroke
				(width 0.1524)
				(type default)
			)
			(layer "F.SilkS")
		)
		(fp_line
			(start -0.7874 -0.4064)
			(end 0.7874 -0.4064)
			(stroke
				(width 0.1524)
				(type default)
			)
			(layer "F.SilkS")
		)
		(fp_line
			(start 0.7874 -0.4064)
			(end 0.7874 0.4064)
			(stroke
				(width 0.1524)
				(type default)
			)
			(layer "F.SilkS")
		)
		(fp_line
			(start -0.67945 0.3048)
			(end -0.67945 -0.305054)
			(stroke
				(width 0.1)
				(type default)
			)
			(layer "F.Fab")
		)
		(fp_line
			(start -0.12065 0.3048)
			(end -0.67945 0.3048)
			(stroke
				(width 0.1)
				(type default)
			)
			(layer "F.Fab")
		)
		(fp_line
			(start 0.120396 0.3048)
			(end 0.120396 0.2794)
			(stroke
				(width 0.1)
				(type default)
			)
			(layer "F.Fab")
		)
		(fp_line
			(start 0.67945 0.3048)
			(end 0.120396 0.3048)
			(stroke
				(width 0.1)
				(type default)
			)
			(layer "F.Fab")
		)
		(fp_line
			(start -0.12065 0.2794)
			(end -0.12065 0.3048)
			(stroke
				(width 0.1)
				(type default)
			)
			(layer "F.Fab")
		)
		(fp_line
			(start 0.120396 0.2794)
			(end -0.12065 0.2794)
			(stroke
				(width 0.1)
				(type default)
			)
			(layer "F.Fab")
		)
		(fp_line
			(start -0.12065 -0.2794)
			(end 0.12065 -0.2794)
			(stroke
				(width 0.1)
				(type default)
			)
			(layer "F.Fab")
		)
		(fp_line
			(start 0.12065 -0.2794)
			(end 0.12065 -0.3048)
			(stroke
				(width 0.1)
				(type default)
			)
			(layer "F.Fab")
		)
		(fp_line
			(start 0.12065 -0.3048)
			(end 0.67945 -0.3048)
			(stroke
				(width 0.1)
				(type default)
			)
			(layer "F.Fab")
		)
		(fp_line
			(start 0.67945 -0.3048)
			(end 0.67945 0.3048)
			(stroke
				(width 0.1)
				(type default)
			)
			(layer "F.Fab")
		)
		(fp_line
			(start -0.67945 -0.305054)
			(end -0.12065 -0.305054)
			(stroke
				(width 0.1)
				(type default)
			)
			(layer "F.Fab")
		)
		(fp_line
			(start -0.12065 -0.305054)
			(end -0.12065 -0.2794)
			(stroke
				(width 0.1)
				(type default)
			)
			(layer "F.Fab")
		)
		(pad "1" smd circle
			(at -0.40005 0 270)
			(size 0 0)
			(layers "F.Cu" "F.Mask" "F.Paste")
			(net "PVDDCR_SOC_P1_VCC3")
		)
		(pad "2" smd circle
			(at 0.40005 0 270)
			(size 0 0)
			(layers "F.Cu" "F.Mask" "F.Paste")
			(net "GND")
		)
	)
	(footprint ""
		(layer "F.Cu")
		(at 479.38436 -107.699302 180)
		(property "Reference" "DB10"
			(at -1.716024 2.8194 0)
			(unlocked yes)
			(layer "F.SilkS")
			(effects
				(font
					(size 0.7874 0.5842)
					(thickness 0.1524)
				)
				(justify left)
			)
		)
		(property "Value" ""
			(at 0 0 180)
			(layer "F.Fab")
			(effects
				(font
					(size 1.27 1.27)
				)
			)
		)
		(duplicate_pad_numbers_are_jumpers no)
		(fp_line
			(start 3.330702 -4.771136)
			(end 0 4.011168)
			(stroke
				(width 0.1524)
				(type default)
			)
			(layer "F.SilkS")
		)
		(fp_line
			(start 0 4.011168)
			(end -3.330702 -4.771136)
			(stroke
				(width 0.1524)
				(type default)
			)
			(layer "F.SilkS")
		)
		(fp_line
			(start -3.330702 -4.771136)
			(end 3.330702 -4.771136)
			(stroke
				(width 0.1524)
				(type default)
			)
			(layer "F.SilkS")
		)
		(fp_line
			(start 3.330702 -4.771136)
			(end 0 4.011168)
			(stroke
				(width 0.1)
				(type default)
			)
			(layer "F.Fab")
		)
		(fp_line
			(start 0 4.011168)
			(end -3.330702 -4.771136)
			(stroke
				(width 0.1)
				(type default)
			)
			(layer "F.Fab")
		)
		(fp_line
			(start -3.330702 -4.771136)
			(end 3.330702 -4.771136)
			(stroke
				(width 0.1)
				(type default)
			)
			(layer "F.Fab")
		)
		(pad "1" thru_hole circle
			(at 0 0 180)
			(size 2.159 2.159)
			(drill 1.7018)
			(layers "*.Cu" "*.Mask")
			(remove_unused_layers no)
			(net "T1_GND")
			(clearance 0.0254)
			(thermal_gap 0.0254)
		)
		(pad "2" thru_hole circle
			(at -1.27 -3.348736 180)
			(size 2.159 2.159)
			(drill 1.7018)
			(layers "*.Cu" "*.Mask")
			(remove_unused_layers no)
			(net "TDR_SE_50_OHM_IN3")
			(clearance 0.0254)
			(thermal_gap 0.0254)
		)
		(pad "3" thru_hole circle
			(at 1.27 -3.348736 180)
			(size 2.159 2.159)
			(drill 1.7018)
			(layers "*.Cu" "*.Mask")
			(remove_unused_layers no)
			(net "TDR_SE_50_OHM_IN3")
			(clearance 0.0254)
			(thermal_gap 0.0254)
		)
	)
	(footprint ""
		(layer "F.Cu")
		(at 160.380934 -120.40108)
		(property "Reference" "R2227"
			(at 0 0 0)
			(layer "F.SilkS")
			(hide yes)
			(effects
				(font
					(size 1.27 1.27)
				)
			)
		)
		(property "Value" ""
			(at 0 0 0)
			(layer "F.Fab")
			(effects
				(font
					(size 1.27 1.27)
				)
			)
		)
		(duplicate_pad_numbers_are_jumpers no)
		(fp_line
			(start -0.7874 -0.4064)
			(end 0.7874 -0.4064)
			(stroke
				(width 0.1524)
				(type default)
			)
			(layer "F.SilkS")
		)
		(fp_line
			(start -0.7874 0.4064)
			(end -0.7874 -0.4064)
			(stroke
				(width 0.1524)
				(type default)
			)
			(layer "F.SilkS")
		)
		(fp_line
			(start 0.7874 -0.4064)
			(end 0.7874 0.4064)
			(stroke
				(width 0.1524)
				(type default)
			)
			(layer "F.SilkS")
		)
		(fp_line
			(start 0.7874 0.4064)
			(end -0.7874 0.4064)
			(stroke
				(width 0.1524)
				(type default)
			)
			(layer "F.SilkS")
		)
		(fp_line
			(start -0.67945 -0.305054)
			(end -0.12065 -0.305054)
			(stroke
				(width 0.1)
				(type default)
			)
			(layer "F.Fab")
		)
		(fp_line
			(start -0.67945 0.3048)
			(end -0.67945 -0.305054)
			(stroke
				(width 0.1)
				(type default)
			)
			(layer "F.Fab")
		)
		(fp_line
			(start -0.12065 -0.305054)
			(end -0.12065 -0.2794)
			(stroke
				(width 0.1)
				(type default)
			)
			(layer "F.Fab")
		)
		(fp_line
			(start -0.12065 -0.2794)
			(end 0.12065 -0.2794)
			(stroke
				(width 0.1)
				(type default)
			)
			(layer "F.Fab")
		)
		(fp_line
			(start -0.12065 0.2794)
			(end -0.12065 0.3048)
			(stroke
				(width 0.1)
				(type default)
			)
			(layer "F.Fab")
		)
		(fp_line
			(start -0.12065 0.3048)
			(end -0.67945 0.3048)
			(stroke
				(width 0.1)
				(type default)
			)
			(layer "F.Fab")
		)
		(fp_line
			(start 0.120396 0.2794)
			(end -0.12065 0.2794)
			(stroke
				(width 0.1)
				(type default)
			)
			(layer "F.Fab")
		)
		(fp_line
			(start 0.120396 0.3048)
			(end 0.120396 0.2794)
			(stroke
				(width 0.1)
				(type default)
			)
			(layer "F.Fab")
		)
		(fp_line
			(start 0.12065 -0.3048)
			(end 0.67945 -0.3048)
			(stroke
				(width 0.1)
				(type default)
			)
			(layer "F.Fab")
		)
		(fp_line
			(start 0.12065 -0.2794)
			(end 0.12065 -0.3048)
			(stroke
				(width 0.1)
				(type default)
			)
			(layer "F.Fab")
		)
		(fp_line
			(start 0.67945 -0.3048)
			(end 0.67945 0.3048)
			(stroke
				(width 0.1)
				(type default)
			)
			(layer "F.Fab")
		)
		(fp_line
			(start 0.67945 0.3048)
			(end 0.120396 0.3048)
			(stroke
				(width 0.1)
				(type default)
			)
			(layer "F.Fab")
		)
		(pad "1" smd circle
			(at -0.40005 0)
			(size 0 0)
			(layers "F.Cu" "F.Mask" "F.Paste")
			(net "A_P12V_STBY_ADR_TRIGGER")
		)
		(pad "2" smd circle
			(at 0.40005 0)
			(size 0 0)
			(layers "F.Cu" "F.Mask" "F.Paste")
			(net "GND")
		)
	)
	(footprint ""
		(layer "F.Cu")
		(at 121.909586 -408.517344 -90)
		(property "Reference" "C6697"
			(at 0 0 270)
			(layer "F.SilkS")
			(hide yes)
			(effects
				(font
					(size 1.27 1.27)
				)
			)
		)
		(property "Value" ""
			(at 0 0 270)
			(layer "F.Fab")
			(effects
				(font
					(size 1.27 1.27)
				)
			)
		)
		(duplicate_pad_numbers_are_jumpers no)
		(fp_line
			(start -0.299974 0.150114)
			(end -0.299974 -0.150114)
			(stroke
				(width 0.1)
				(type default)
			)
			(layer "F.Fab")
		)
		(fp_line
			(start 0.299974 0.150114)
			(end -0.299974 0.150114)
			(stroke
				(width 0.1)
				(type default)
			)
			(layer "F.Fab")
		)
		(fp_line
			(start -0.299974 -0.150114)
			(end 0.299974 -0.150114)
			(stroke
				(width 0.1)
				(type default)
			)
			(layer "F.Fab")
		)
		(fp_line
			(start 0.299974 -0.150114)
			(end 0.299974 0.150114)
			(stroke
				(width 0.1)
				(type default)
			)
			(layer "F.Fab")
		)
		(pad "1" smd rect
			(at -0.2667 0 270)
			(size 0.3048 0.381)
			(layers "F.Cu" "F.Mask" "F.Paste")
			(net "P5E_CPU1_P2_TX_BUF_C_DP<2>")
		)
		(pad "2" smd rect
			(at 0.2667 0 270)
			(size 0.3048 0.381)
			(layers "F.Cu" "F.Mask" "F.Paste")
			(net "P5E_CPU1_P2_TX_BUF_DP<2>")
		)
	)
	(footprint ""
		(layer "F.Cu")
		(at 59.220354 -370.57203 -90)
		(property "Reference" "C818"
			(at 0 0 270)
			(layer "F.SilkS")
			(hide yes)
			(effects
				(font
					(size 1.27 1.27)
				)
			)
		)
		(property "Value" ""
			(at 0 0 270)
			(layer "F.Fab")
			(effects
				(font
					(size 1.27 1.27)
				)
			)
		)
		(duplicate_pad_numbers_are_jumpers no)
		(fp_line
			(start -0.299974 0.150114)
			(end -0.299974 -0.150114)
			(stroke
				(width 0.1)
				(type default)
			)
			(layer "F.Fab")
		)
		(fp_line
			(start 0.299974 0.150114)
			(end -0.299974 0.150114)
			(stroke
				(width 0.1)
				(type default)
			)
			(layer "F.Fab")
		)
		(fp_line
			(start -0.299974 -0.150114)
			(end 0.299974 -0.150114)
			(stroke
				(width 0.1)
				(type default)
			)
			(layer "F.Fab")
		)
		(fp_line
			(start 0.299974 -0.150114)
			(end 0.299974 0.150114)
			(stroke
				(width 0.1)
				(type default)
			)
			(layer "F.Fab")
		)
		(pad "1" smd rect
			(at -0.2667 0 270)
			(size 0.3048 0.381)
			(layers "F.Cu" "F.Mask" "F.Paste")
			(net "P5E_CPU1_P0_TX_C_DN<9>")
		)
		(pad "2" smd rect
			(at 0.2667 0 270)
			(size 0.3048 0.381)
			(layers "F.Cu" "F.Mask" "F.Paste")
			(net "P5E_CPU1_P0_TX_DN<9>")
		)
	)
	(footprint ""
		(layer "F.Cu")
		(at 90.209878 -146.91741 180)
		(property "Reference" "R8156"
			(at 0 0 180)
			(layer "F.SilkS")
			(hide yes)
			(effects
				(font
					(size 1.27 1.27)
				)
			)
		)
		(property "Value" ""
			(at 0 0 180)
			(layer "F.Fab")
			(effects
				(font
					(size 1.27 1.27)
				)
			)
		)
		(duplicate_pad_numbers_are_jumpers no)
		(fp_line
			(start 0.7874 0.4064)
			(end -0.7874 0.4064)
			(stroke
				(width 0.1524)
				(type default)
			)
			(layer "F.SilkS")
		)
		(fp_line
			(start 0.7874 -0.4064)
			(end 0.7874 0.4064)
			(stroke
				(width 0.1524)
				(type default)
			)
			(layer "F.SilkS")
		)
		(fp_line
			(start -0.7874 0.4064)
			(end -0.7874 -0.4064)
			(stroke
				(width 0.1524)
				(type default)
			)
			(layer "F.SilkS")
		)
		(fp_line
			(start -0.7874 -0.4064)
			(end 0.7874 -0.4064)
			(stroke
				(width 0.1524)
				(type default)
			)
			(layer "F.SilkS")
		)
		(fp_line
			(start 0.67945 0.3048)
			(end 0.120396 0.3048)
			(stroke
				(width 0.1)
				(type default)
			)
			(layer "F.Fab")
		)
		(fp_line
			(start 0.67945 -0.3048)
			(end 0.67945 0.3048)
			(stroke
				(width 0.1)
				(type default)
			)
			(layer "F.Fab")
		)
		(fp_line
			(start 0.12065 -0.2794)
			(end 0.12065 -0.3048)
			(stroke
				(width 0.1)
				(type default)
			)
			(layer "F.Fab")
		)
		(fp_line
			(start 0.12065 -0.3048)
			(end 0.67945 -0.3048)
			(stroke
				(width 0.1)
				(type default)
			)
			(layer "F.Fab")
		)
		(fp_line
			(start 0.120396 0.3048)
			(end 0.120396 0.2794)
			(stroke
				(width 0.1)
				(type default)
			)
			(layer "F.Fab")
		)
		(fp_line
			(start 0.120396 0.2794)
			(end -0.12065 0.2794)
			(stroke
				(width 0.1)
				(type default)
			)
			(layer "F.Fab")
		)
		(fp_line
			(start -0.12065 0.3048)
			(end -0.67945 0.3048)
			(stroke
				(width 0.1)
				(type default)
			)
			(layer "F.Fab")
		)
		(fp_line
			(start -0.12065 0.2794)
			(end -0.12065 0.3048)
			(stroke
				(width 0.1)
				(type default)
			)
			(layer "F.Fab")
		)
		(fp_line
			(start -0.12065 -0.2794)
			(end 0.12065 -0.2794)
			(stroke
				(width 0.1)
				(type default)
			)
			(layer "F.Fab")
		)
		(fp_line
			(start -0.12065 -0.305054)
			(end -0.12065 -0.2794)
			(stroke
				(width 0.1)
				(type default)
			)
			(layer "F.Fab")
		)
		(fp_line
			(start -0.67945 0.3048)
			(end -0.67945 -0.305054)
			(stroke
				(width 0.1)
				(type default)
			)
			(layer "F.Fab")
		)
		(fp_line
			(start -0.67945 -0.305054)
			(end -0.12065 -0.305054)
			(stroke
				(width 0.1)
				(type default)
			)
			(layer "F.Fab")
		)
		(pad "1" smd circle
			(at -0.40005 0 180)
			(size 0 0)
			(layers "F.Cu" "F.Mask" "F.Paste")
			(net "PVDD18_S5_P1")
		)
		(pad "2" smd circle
			(at 0.40005 0 180)
			(size 0 0)
			(layers "F.Cu" "F.Mask" "F.Paste")
			(net "SVID_PVDDCR_CPU0_P1_SVD_R")
		)
	)
	(footprint ""
		(layer "F.Cu")
		(at 347.024706 -335.17459 -90)
		(property "Reference" "PC135_5"
			(at 0 0 270)
			(layer "F.SilkS")
			(hide yes)
			(effects
				(font
					(size 1.27 1.27)
				)
			)
		)
		(property "Value" ""
			(at 0 0 270)
			(layer "F.Fab")
			(effects
				(font
					(size 1.27 1.27)
				)
			)
		)
		(duplicate_pad_numbers_are_jumpers no)
		(fp_line
			(start -0.7874 0.4064)
			(end -0.7874 -0.4064)
			(stroke
				(width 0.1524)
				(type default)
			)
			(layer "F.SilkS")
		)
		(fp_line
			(start 0.7874 0.4064)
			(end -0.7874 0.4064)
			(stroke
				(width 0.1524)
				(type default)
			)
			(layer "F.SilkS")
		)
		(fp_line
			(start -0.7874 -0.4064)
			(end 0.7874 -0.4064)
			(stroke
				(width 0.1524)
				(type default)
			)
			(layer "F.SilkS")
		)
		(fp_line
			(start 0.7874 -0.4064)
			(end 0.7874 0.4064)
			(stroke
				(width 0.1524)
				(type default)
			)
			(layer "F.SilkS")
		)
		(fp_line
			(start -0.67945 0.3048)
			(end -0.67945 -0.305054)
			(stroke
				(width 0.1)
				(type default)
			)
			(layer "F.Fab")
		)
		(fp_line
			(start -0.12065 0.3048)
			(end -0.67945 0.3048)
			(stroke
				(width 0.1)
				(type default)
			)
			(layer "F.Fab")
		)
		(fp_line
			(start 0.120396 0.3048)
			(end 0.120396 0.2794)
			(stroke
				(width 0.1)
				(type default)
			)
			(layer "F.Fab")
		)
		(fp_line
			(start 0.67945 0.3048)
			(end 0.120396 0.3048)
			(stroke
				(width 0.1)
				(type default)
			)
			(layer "F.Fab")
		)
		(fp_line
			(start -0.12065 0.2794)
			(end -0.12065 0.3048)
			(stroke
				(width 0.1)
				(type default)
			)
			(layer "F.Fab")
		)
		(fp_line
			(start 0.120396 0.2794)
			(end -0.12065 0.2794)
			(stroke
				(width 0.1)
				(type default)
			)
			(layer "F.Fab")
		)
		(fp_line
			(start -0.12065 -0.2794)
			(end 0.12065 -0.2794)
			(stroke
				(width 0.1)
				(type default)
			)
			(layer "F.Fab")
		)
		(fp_line
			(start 0.12065 -0.2794)
			(end 0.12065 -0.3048)
			(stroke
				(width 0.1)
				(type default)
			)
			(layer "F.Fab")
		)
		(fp_line
			(start 0.12065 -0.3048)
			(end 0.67945 -0.3048)
			(stroke
				(width 0.1)
				(type default)
			)
			(layer "F.Fab")
		)
		(fp_line
			(start 0.67945 -0.3048)
			(end 0.67945 0.3048)
			(stroke
				(width 0.1)
				(type default)
			)
			(layer "F.Fab")
		)
		(fp_line
			(start -0.67945 -0.305054)
			(end -0.12065 -0.305054)
			(stroke
				(width 0.1)
				(type default)
			)
			(layer "F.Fab")
		)
		(fp_line
			(start -0.12065 -0.305054)
			(end -0.12065 -0.2794)
			(stroke
				(width 0.1)
				(type default)
			)
			(layer "F.Fab")
		)
		(pad "1" smd circle
			(at -0.40005 0 270)
			(size 0 0)
			(layers "F.Cu" "F.Mask" "F.Paste")
			(net "SW_P12V_AUX_PVDDCR_CPU1_P0_FLT")
		)
		(pad "2" smd circle
			(at 0.40005 0 270)
			(size 0 0)
			(layers "F.Cu" "F.Mask" "F.Paste")
			(net "GND")
		)
	)
	(footprint ""
		(layer "F.Cu")
		(at 281.621738 -388.71652 90)
		(property "Reference" "R6230"
			(at 0 0 90)
			(layer "F.SilkS")
			(hide yes)
			(effects
				(font
					(size 1.27 1.27)
				)
			)
		)
		(property "Value" ""
			(at 0 0 90)
			(layer "F.Fab")
			(effects
				(font
					(size 1.27 1.27)
				)
			)
		)
		(duplicate_pad_numbers_are_jumpers no)
		(fp_line
			(start 0.7874 -0.4064)
			(end 0.7874 0.4064)
			(stroke
				(width 0.1524)
				(type default)
			)
			(layer "F.SilkS")
		)
		(fp_line
			(start -0.7874 -0.4064)
			(end 0.7874 -0.4064)
			(stroke
				(width 0.1524)
				(type default)
			)
			(layer "F.SilkS")
		)
		(fp_line
			(start 0.7874 0.4064)
			(end -0.7874 0.4064)
			(stroke
				(width 0.1524)
				(type default)
			)
			(layer "F.SilkS")
		)
		(fp_line
			(start -0.7874 0.4064)
			(end -0.7874 -0.4064)
			(stroke
				(width 0.1524)
				(type default)
			)
			(layer "F.SilkS")
		)
		(fp_line
			(start -0.12065 -0.305054)
			(end -0.12065 -0.2794)
			(stroke
				(width 0.1)
				(type default)
			)
			(layer "F.Fab")
		)
		(fp_line
			(start -0.67945 -0.305054)
			(end -0.12065 -0.305054)
			(stroke
				(width 0.1)
				(type default)
			)
			(layer "F.Fab")
		)
		(fp_line
			(start 0.67945 -0.3048)
			(end 0.67945 0.3048)
			(stroke
				(width 0.1)
				(type default)
			)
			(layer "F.Fab")
		)
		(fp_line
			(start 0.12065 -0.3048)
			(end 0.67945 -0.3048)
			(stroke
				(width 0.1)
				(type default)
			)
			(layer "F.Fab")
		)
		(fp_line
			(start 0.12065 -0.2794)
			(end 0.12065 -0.3048)
			(stroke
				(width 0.1)
				(type default)
			)
			(layer "F.Fab")
		)
		(fp_line
			(start -0.12065 -0.2794)
			(end 0.12065 -0.2794)
			(stroke
				(width 0.1)
				(type default)
			)
			(layer "F.Fab")
		)
		(fp_line
			(start 0.120396 0.2794)
			(end -0.12065 0.2794)
			(stroke
				(width 0.1)
				(type default)
			)
			(layer "F.Fab")
		)
		(fp_line
			(start -0.12065 0.2794)
			(end -0.12065 0.3048)
			(stroke
				(width 0.1)
				(type default)
			)
			(layer "F.Fab")
		)
		(fp_line
			(start 0.67945 0.3048)
			(end 0.120396 0.3048)
			(stroke
				(width 0.1)
				(type default)
			)
			(layer "F.Fab")
		)
		(fp_line
			(start 0.120396 0.3048)
			(end 0.120396 0.2794)
			(stroke
				(width 0.1)
				(type default)
			)
			(layer "F.Fab")
		)
		(fp_line
			(start -0.12065 0.3048)
			(end -0.67945 0.3048)
			(stroke
				(width 0.1)
				(type default)
			)
			(layer "F.Fab")
		)
		(fp_line
			(start -0.67945 0.3048)
			(end -0.67945 -0.305054)
			(stroke
				(width 0.1)
				(type default)
			)
			(layer "F.Fab")
		)
		(pad "1" smd circle
			(at -0.40005 0 90)
			(size 0 0)
			(layers "F.Cu" "F.Mask" "F.Paste")
			(net "P3V3_AUX")
		)
		(pad "2" smd circle
			(at 0.40005 0 90)
			(size 0 0)
			(layers "F.Cu" "F.Mask" "F.Paste")
			(net "SMB_P12V_HSC_SDA")
		)
	)
	(footprint ""
		(layer "F.Cu")
		(at 347.972126 -336.930238 180)
		(property "Reference" "PC154"
			(at 0 0 180)
			(layer "F.SilkS")
			(hide yes)
			(effects
				(font
					(size 1.27 1.27)
				)
			)
		)
		(property "Value" ""
			(at 0 0 180)
			(layer "F.Fab")
			(effects
				(font
					(size 1.27 1.27)
				)
			)
		)
		(duplicate_pad_numbers_are_jumpers no)
		(fp_line
			(start 0.7874 0.4064)
			(end -0.7874 0.4064)
			(stroke
				(width 0.1524)
				(type default)
			)
			(layer "F.SilkS")
		)
		(fp_line
			(start 0.7874 -0.4064)
			(end 0.7874 0.4064)
			(stroke
				(width 0.1524)
				(type default)
			)
			(layer "F.SilkS")
		)
		(fp_line
			(start -0.7874 0.4064)
			(end -0.7874 -0.4064)
			(stroke
				(width 0.1524)
				(type default)
			)
			(layer "F.SilkS")
		)
		(fp_line
			(start -0.7874 -0.4064)
			(end 0.7874 -0.4064)
			(stroke
				(width 0.1524)
				(type default)
			)
			(layer "F.SilkS")
		)
		(fp_line
			(start 0.67945 0.3048)
			(end 0.120396 0.3048)
			(stroke
				(width 0.1)
				(type default)
			)
			(layer "F.Fab")
		)
		(fp_line
			(start 0.67945 -0.3048)
			(end 0.67945 0.3048)
			(stroke
				(width 0.1)
				(type default)
			)
			(layer "F.Fab")
		)
		(fp_line
			(start 0.12065 -0.2794)
			(end 0.12065 -0.3048)
			(stroke
				(width 0.1)
				(type default)
			)
			(layer "F.Fab")
		)
		(fp_line
			(start 0.12065 -0.3048)
			(end 0.67945 -0.3048)
			(stroke
				(width 0.1)
				(type default)
			)
			(layer "F.Fab")
		)
		(fp_line
			(start 0.120396 0.3048)
			(end 0.120396 0.2794)
			(stroke
				(width 0.1)
				(type default)
			)
			(layer "F.Fab")
		)
		(fp_line
			(start 0.120396 0.2794)
			(end -0.12065 0.2794)
			(stroke
				(width 0.1)
				(type default)
			)
			(layer "F.Fab")
		)
		(fp_line
			(start -0.12065 0.3048)
			(end -0.67945 0.3048)
			(stroke
				(width 0.1)
				(type default)
			)
			(layer "F.Fab")
		)
		(fp_line
			(start -0.12065 0.2794)
			(end -0.12065 0.3048)
			(stroke
				(width 0.1)
				(type default)
			)
			(layer "F.Fab")
		)
		(fp_line
			(start -0.12065 -0.2794)
			(end 0.12065 -0.2794)
			(stroke
				(width 0.1)
				(type default)
			)
			(layer "F.Fab")
		)
		(fp_line
			(start -0.12065 -0.305054)
			(end -0.12065 -0.2794)
			(stroke
				(width 0.1)
				(type default)
			)
			(layer "F.Fab")
		)
		(fp_line
			(start -0.67945 0.3048)
			(end -0.67945 -0.305054)
			(stroke
				(width 0.1)
				(type default)
			)
			(layer "F.Fab")
		)
		(fp_line
			(start -0.67945 -0.305054)
			(end -0.12065 -0.305054)
			(stroke
				(width 0.1)
				(type default)
			)
			(layer "F.Fab")
		)
		(pad "1" smd circle
			(at -0.40005 0 180)
			(size 0 0)
			(layers "F.Cu" "F.Mask" "F.Paste")
			(net "SW_PVDDCR_CPU1_P0_SW6")
		)
		(pad "2" smd circle
			(at 0.40005 0 180)
			(size 0 0)
			(layers "F.Cu" "F.Mask" "F.Paste")
			(net "SW_PVDDCR_CPU1_P0_SW6_RC")
		)
	)
	(footprint ""
		(layer "F.Cu")
		(at 98.845878 -143.74241 180)
		(property "Reference" "PR4"
			(at 0 0 180)
			(layer "F.SilkS")
			(hide yes)
			(effects
				(font
					(size 1.27 1.27)
				)
			)
		)
		(property "Value" ""
			(at 0 0 180)
			(layer "F.Fab")
			(effects
				(font
					(size 1.27 1.27)
				)
			)
		)
		(duplicate_pad_numbers_are_jumpers no)
		(fp_line
			(start 0.7874 0.4064)
			(end -0.7874 0.4064)
			(stroke
				(width 0.1524)
				(type default)
			)
			(layer "F.SilkS")
		)
		(fp_line
			(start 0.7874 -0.4064)
			(end 0.7874 0.4064)
			(stroke
				(width 0.1524)
				(type default)
			)
			(layer "F.SilkS")
		)
		(fp_line
			(start -0.7874 0.4064)
			(end -0.7874 -0.4064)
			(stroke
				(width 0.1524)
				(type default)
			)
			(layer "F.SilkS")
		)
		(fp_line
			(start -0.7874 -0.4064)
			(end 0.7874 -0.4064)
			(stroke
				(width 0.1524)
				(type default)
			)
			(layer "F.SilkS")
		)
		(fp_line
			(start 0.67945 0.3048)
			(end 0.120396 0.3048)
			(stroke
				(width 0.1)
				(type default)
			)
			(layer "F.Fab")
		)
		(fp_line
			(start 0.67945 -0.3048)
			(end 0.67945 0.3048)
			(stroke
				(width 0.1)
				(type default)
			)
			(layer "F.Fab")
		)
		(fp_line
			(start 0.12065 -0.2794)
			(end 0.12065 -0.3048)
			(stroke
				(width 0.1)
				(type default)
			)
			(layer "F.Fab")
		)
		(fp_line
			(start 0.12065 -0.3048)
			(end 0.67945 -0.3048)
			(stroke
				(width 0.1)
				(type default)
			)
			(layer "F.Fab")
		)
		(fp_line
			(start 0.120396 0.3048)
			(end 0.120396 0.2794)
			(stroke
				(width 0.1)
				(type default)
			)
			(layer "F.Fab")
		)
		(fp_line
			(start 0.120396 0.2794)
			(end -0.12065 0.2794)
			(stroke
				(width 0.1)
				(type default)
			)
			(layer "F.Fab")
		)
		(fp_line
			(start -0.12065 0.3048)
			(end -0.67945 0.3048)
			(stroke
				(width 0.1)
				(type default)
			)
			(layer "F.Fab")
		)
		(fp_line
			(start -0.12065 0.2794)
			(end -0.12065 0.3048)
			(stroke
				(width 0.1)
				(type default)
			)
			(layer "F.Fab")
		)
		(fp_line
			(start -0.12065 -0.2794)
			(end 0.12065 -0.2794)
			(stroke
				(width 0.1)
				(type default)
			)
			(layer "F.Fab")
		)
		(fp_line
			(start -0.12065 -0.305054)
			(end -0.12065 -0.2794)
			(stroke
				(width 0.1)
				(type default)
			)
			(layer "F.Fab")
		)
		(fp_line
			(start -0.67945 0.3048)
			(end -0.67945 -0.305054)
			(stroke
				(width 0.1)
				(type default)
			)
			(layer "F.Fab")
		)
		(fp_line
			(start -0.67945 -0.305054)
			(end -0.12065 -0.305054)
			(stroke
				(width 0.1)
				(type default)
			)
			(layer "F.Fab")
		)
		(pad "1" smd circle
			(at -0.40005 0 180)
			(size 0 0)
			(layers "F.Cu" "F.Mask" "F.Paste")
			(net "PVDDCR_CPU0_P1_VMON")
		)
		(pad "2" smd circle
			(at 0.40005 0 180)
			(size 0 0)
			(layers "F.Cu" "F.Mask" "F.Paste")
			(net "GND")
		)
	)
	(footprint ""
		(layer "F.Cu")
		(at 373.931942 -416.899344 -90)
		(property "Reference" "C6568"
			(at 0 0 270)
			(layer "F.SilkS")
			(hide yes)
			(effects
				(font
					(size 1.27 1.27)
				)
			)
		)
		(property "Value" ""
			(at 0 0 270)
			(layer "F.Fab")
			(effects
				(font
					(size 1.27 1.27)
				)
			)
		)
		(duplicate_pad_numbers_are_jumpers no)
		(fp_line
			(start -0.299974 0.150114)
			(end -0.299974 -0.150114)
			(stroke
				(width 0.1)
				(type default)
			)
			(layer "F.Fab")
		)
		(fp_line
			(start 0.299974 0.150114)
			(end -0.299974 0.150114)
			(stroke
				(width 0.1)
				(type default)
			)
			(layer "F.Fab")
		)
		(fp_line
			(start -0.299974 -0.150114)
			(end 0.299974 -0.150114)
			(stroke
				(width 0.1)
				(type default)
			)
			(layer "F.Fab")
		)
		(fp_line
			(start 0.299974 -0.150114)
			(end 0.299974 0.150114)
			(stroke
				(width 0.1)
				(type default)
			)
			(layer "F.Fab")
		)
		(pad "1" smd rect
			(at -0.2667 0 270)
			(size 0.3048 0.381)
			(layers "F.Cu" "F.Mask" "F.Paste")
			(net "P5E_CPU0_P2_TX_BUF_C_DN<1>")
		)
		(pad "2" smd rect
			(at 0.2667 0 270)
			(size 0.3048 0.381)
			(layers "F.Cu" "F.Mask" "F.Paste")
			(net "P5E_CPU0_P2_TX_BUF_DN<1>")
		)
	)
	(footprint ""
		(layer "F.Cu")
		(at 323.018404 -337.653376 90)
		(property "Reference" "PC80"
			(at 0 0 90)
			(layer "F.SilkS")
			(hide yes)
			(effects
				(font
					(size 1.27 1.27)
				)
			)
		)
		(property "Value" ""
			(at 0 0 90)
			(layer "F.Fab")
			(effects
				(font
					(size 1.27 1.27)
				)
			)
		)
		(duplicate_pad_numbers_are_jumpers no)
		(fp_line
			(start 0.7874 -0.4064)
			(end 0.7874 0.4064)
			(stroke
				(width 0.1524)
				(type default)
			)
			(layer "F.SilkS")
		)
		(fp_line
			(start -0.7874 -0.4064)
			(end 0.7874 -0.4064)
			(stroke
				(width 0.1524)
				(type default)
			)
			(layer "F.SilkS")
		)
		(fp_line
			(start 0.7874 0.4064)
			(end 0.039624 0.4064)
			(stroke
				(width 0.1524)
				(type default)
			)
			(layer "F.SilkS")
		)
		(fp_line
			(start -0.7874 0.4064)
			(end -0.7874 -0.4064)
			(stroke
				(width 0.1524)
				(type default)
			)
			(layer "F.SilkS")
		)
		(fp_line
			(start -0.12065 -0.305054)
			(end -0.12065 -0.2794)
			(stroke
				(width 0.1)
				(type default)
			)
			(layer "F.Fab")
		)
		(fp_line
			(start -0.67945 -0.305054)
			(end -0.12065 -0.305054)
			(stroke
				(width 0.1)
				(type default)
			)
			(layer "F.Fab")
		)
		(fp_line
			(start 0.67945 -0.3048)
			(end 0.67945 0.3048)
			(stroke
				(width 0.1)
				(type default)
			)
			(layer "F.Fab")
		)
		(fp_line
			(start 0.12065 -0.3048)
			(end 0.67945 -0.3048)
			(stroke
				(width 0.1)
				(type default)
			)
			(layer "F.Fab")
		)
		(fp_line
			(start 0.12065 -0.2794)
			(end 0.12065 -0.3048)
			(stroke
				(width 0.1)
				(type default)
			)
			(layer "F.Fab")
		)
		(fp_line
			(start -0.12065 -0.2794)
			(end 0.12065 -0.2794)
			(stroke
				(width 0.1)
				(type default)
			)
			(layer "F.Fab")
		)
		(fp_line
			(start 0.120396 0.2794)
			(end -0.12065 0.2794)
			(stroke
				(width 0.1)
				(type default)
			)
			(layer "F.Fab")
		)
		(fp_line
			(start -0.12065 0.2794)
			(end -0.12065 0.3048)
			(stroke
				(width 0.1)
				(type default)
			)
			(layer "F.Fab")
		)
		(fp_line
			(start 0.67945 0.3048)
			(end 0.120396 0.3048)
			(stroke
				(width 0.1)
				(type default)
			)
			(layer "F.Fab")
		)
		(fp_line
			(start 0.120396 0.3048)
			(end 0.120396 0.2794)
			(stroke
				(width 0.1)
				(type default)
			)
			(layer "F.Fab")
		)
		(fp_line
			(start -0.12065 0.3048)
			(end -0.67945 0.3048)
			(stroke
				(width 0.1)
				(type default)
			)
			(layer "F.Fab")
		)
		(fp_line
			(start -0.67945 0.3048)
			(end -0.67945 -0.305054)
			(stroke
				(width 0.1)
				(type default)
			)
			(layer "F.Fab")
		)
		(pad "1" smd circle
			(at -0.40005 0 90)
			(size 0 0)
			(layers "F.Cu" "F.Mask" "F.Paste")
			(net "PVDDCR_CPU1_P0_VCC2")
		)
		(pad "2" smd circle
			(at 0.40005 0 90)
			(size 0 0)
			(layers "F.Cu" "F.Mask" "F.Paste")
			(net "GND")
		)
	)
	(footprint ""
		(layer "F.Cu")
		(at 107.677204 -261.748016 -90)
		(property "Reference" "C2262"
			(at 0 0 270)
			(layer "F.SilkS")
			(hide yes)
			(effects
				(font
					(size 1.27 1.27)
				)
			)
		)
		(property "Value" ""
			(at 0 0 270)
			(layer "F.Fab")
			(effects
				(font
					(size 1.27 1.27)
				)
			)
		)
		(duplicate_pad_numbers_are_jumpers no)
		(fp_line
			(start -0.7874 0.4064)
			(end -0.7874 -0.4064)
			(stroke
				(width 0.1524)
				(type default)
			)
			(layer "F.SilkS")
		)
		(fp_line
			(start 0.7874 0.4064)
			(end -0.7874 0.4064)
			(stroke
				(width 0.1524)
				(type default)
			)
			(layer "F.SilkS")
		)
		(fp_line
			(start -0.7874 -0.4064)
			(end 0.7874 -0.4064)
			(stroke
				(width 0.1524)
				(type default)
			)
			(layer "F.SilkS")
		)
		(fp_line
			(start 0.7874 -0.4064)
			(end 0.7874 0.4064)
			(stroke
				(width 0.1524)
				(type default)
			)
			(layer "F.SilkS")
		)
		(fp_line
			(start -0.67945 0.3048)
			(end -0.67945 -0.305054)
			(stroke
				(width 0.1)
				(type default)
			)
			(layer "F.Fab")
		)
		(fp_line
			(start -0.12065 0.3048)
			(end -0.67945 0.3048)
			(stroke
				(width 0.1)
				(type default)
			)
			(layer "F.Fab")
		)
		(fp_line
			(start 0.120396 0.3048)
			(end 0.120396 0.2794)
			(stroke
				(width 0.1)
				(type default)
			)
			(layer "F.Fab")
		)
		(fp_line
			(start 0.67945 0.3048)
			(end 0.120396 0.3048)
			(stroke
				(width 0.1)
				(type default)
			)
			(layer "F.Fab")
		)
		(fp_line
			(start -0.12065 0.2794)
			(end -0.12065 0.3048)
			(stroke
				(width 0.1)
				(type default)
			)
			(layer "F.Fab")
		)
		(fp_line
			(start 0.120396 0.2794)
			(end -0.12065 0.2794)
			(stroke
				(width 0.1)
				(type default)
			)
			(layer "F.Fab")
		)
		(fp_line
			(start -0.12065 -0.2794)
			(end 0.12065 -0.2794)
			(stroke
				(width 0.1)
				(type default)
			)
			(layer "F.Fab")
		)
		(fp_line
			(start 0.12065 -0.2794)
			(end 0.12065 -0.3048)
			(stroke
				(width 0.1)
				(type default)
			)
			(layer "F.Fab")
		)
		(fp_line
			(start 0.12065 -0.3048)
			(end 0.67945 -0.3048)
			(stroke
				(width 0.1)
				(type default)
			)
			(layer "F.Fab")
		)
		(fp_line
			(start 0.67945 -0.3048)
			(end 0.67945 0.3048)
			(stroke
				(width 0.1)
				(type default)
			)
			(layer "F.Fab")
		)
		(fp_line
			(start -0.67945 -0.305054)
			(end -0.12065 -0.305054)
			(stroke
				(width 0.1)
				(type default)
			)
			(layer "F.Fab")
		)
		(fp_line
			(start -0.12065 -0.305054)
			(end -0.12065 -0.2794)
			(stroke
				(width 0.1)
				(type default)
			)
			(layer "F.Fab")
		)
		(pad "1" smd circle
			(at -0.40005 0 270)
			(size 0 0)
			(layers "F.Cu" "F.Mask" "F.Paste")
			(net "PVDD11_S3_P1")
		)
		(pad "2" smd circle
			(at 0.40005 0 270)
			(size 0 0)
			(layers "F.Cu" "F.Mask" "F.Paste")
			(net "GND")
		)
	)
	(footprint ""
		(layer "F.Cu")
		(at 208.28 -133.223 90)
		(property "Reference" "Q3"
			(at -0.741934 -3.189224 90)
			(unlocked yes)
			(layer "F.SilkS")
			(effects
				(font
					(size 0.7874 0.5842)
					(thickness 0.1524)
				)
				(justify left)
			)
		)
		(property "Value" ""
			(at 0 0 90)
			(layer "F.Fab")
			(effects
				(font
					(size 1.27 1.27)
				)
			)
		)
		(duplicate_pad_numbers_are_jumpers no)
		(fp_line
			(start 1.332738 -1.100074)
			(end 1.332738 1.100074)
			(stroke
				(width 0.1524)
				(type default)
			)
			(layer "F.SilkS")
		)
		(fp_line
			(start 0.4826 -1.100074)
			(end 1.332738 -1.100074)
			(stroke
				(width 0.1524)
				(type default)
			)
			(layer "F.SilkS")
		)
		(fp_line
			(start -0.4826 -1.100074)
			(end 0 -0.541274)
			(stroke
				(width 0.1524)
				(type default)
			)
			(layer "F.SilkS")
		)
		(fp_line
			(start -1.332738 -1.100074)
			(end -0.4826 -1.100074)
			(stroke
				(width 0.1524)
				(type default)
			)
			(layer "F.SilkS")
		)
		(fp_line
			(start 0 -0.541274)
			(end 0.4826 -1.100074)
			(stroke
				(width 0.1524)
				(type default)
			)
			(layer "F.SilkS")
		)
		(fp_line
			(start 1.332738 1.100074)
			(end -1.332738 1.100074)
			(stroke
				(width 0.1524)
				(type default)
			)
			(layer "F.SilkS")
		)
		(fp_line
			(start -1.332738 1.100074)
			(end -1.332738 -1.100074)
			(stroke
				(width 0.1524)
				(type default)
			)
			(layer "F.SilkS")
		)
		(fp_poly
			(pts
				(xy -2.699512 -0.335534) (xy -2.699512 -1.03759) (xy -1.997456 -0.686562)
			)
			(stroke
				(width 0)
				(type default)
			)
			(fill yes)
			(layer "F.SilkS")
		)
		(fp_line
			(start 0.674878 -1.100074)
			(end 0.674878 1.100074)
			(stroke
				(width 0.1)
				(type default)
			)
			(layer "F.Fab")
		)
		(fp_line
			(start -0.674878 -1.100074)
			(end 0.674878 -1.100074)
			(stroke
				(width 0.1)
				(type default)
			)
			(layer "F.Fab")
		)
		(fp_line
			(start 0.674878 1.100074)
			(end -0.674878 1.100074)
			(stroke
				(width 0.1)
				(type default)
			)
			(layer "F.Fab")
		)
		(fp_line
			(start -0.674878 1.100074)
			(end -0.674878 -1.100074)
			(stroke
				(width 0.1)
				(type default)
			)
			(layer "F.Fab")
		)
		(fp_poly
			(pts
				(xy -2.2352 -0.298958) (xy -2.2352 -1.001014) (xy -1.533144 -0.649986)
			)
			(stroke
				(width 0)
				(type default)
			)
			(fill yes)
			(layer "F.Fab")
		)
		(pad "1" smd rect
			(at -0.94996 -0.649986 180)
			(size 0.4318 0.508)
			(layers "F.Cu" "F.Mask" "F.Paste")
			(net "GND")
		)
		(pad "2" smd rect
			(at -0.94996 0 180)
			(size 0.4318 0.508)
			(layers "F.Cu" "F.Mask" "F.Paste")
			(net "SW_P3V3_EN_R")
		)
		(pad "3" smd rect
			(at -0.94996 0.649986 180)
			(size 0.4318 0.508)
			(layers "F.Cu" "F.Mask" "F.Paste")
			(net "SW_P3V3_EN_ISO")
		)
		(pad "4" smd rect
			(at 0.94996 0.649986 180)
			(size 0.4318 0.508)
			(layers "F.Cu" "F.Mask" "F.Paste")
			(net "GND")
		)
		(pad "5" smd rect
			(at 0.94996 0 180)
			(size 0.4318 0.508)
			(layers "F.Cu" "F.Mask" "F.Paste")
			(net "SW_P3V3_EN_N")
		)
		(pad "6" smd rect
			(at 0.94996 -0.649986 180)
			(size 0.4318 0.508)
			(layers "F.Cu" "F.Mask" "F.Paste")
			(net "SW_P3V3_EN_N")
		)
	)
	(footprint ""
		(layer "F.Cu")
		(at 70.307454 -147.339812 -90)
		(property "Reference" "PC153"
			(at 0 0 270)
			(layer "F.SilkS")
			(hide yes)
			(effects
				(font
					(size 1.27 1.27)
				)
			)
		)
		(property "Value" ""
			(at 0 0 270)
			(layer "F.Fab")
			(effects
				(font
					(size 1.27 1.27)
				)
			)
		)
		(duplicate_pad_numbers_are_jumpers no)
		(fp_line
			(start -0.7874 0.4064)
			(end -0.7874 -0.4064)
			(stroke
				(width 0.1524)
				(type default)
			)
			(layer "F.SilkS")
		)
		(fp_line
			(start 0.7874 0.4064)
			(end -0.7874 0.4064)
			(stroke
				(width 0.1524)
				(type default)
			)
			(layer "F.SilkS")
		)
		(fp_line
			(start -0.7874 -0.4064)
			(end 0.7874 -0.4064)
			(stroke
				(width 0.1524)
				(type default)
			)
			(layer "F.SilkS")
		)
		(fp_line
			(start 0.7874 -0.4064)
			(end 0.7874 0.4064)
			(stroke
				(width 0.1524)
				(type default)
			)
			(layer "F.SilkS")
		)
		(fp_line
			(start -0.67945 0.3048)
			(end -0.67945 -0.305054)
			(stroke
				(width 0.1)
				(type default)
			)
			(layer "F.Fab")
		)
		(fp_line
			(start -0.12065 0.3048)
			(end -0.67945 0.3048)
			(stroke
				(width 0.1)
				(type default)
			)
			(layer "F.Fab")
		)
		(fp_line
			(start 0.120396 0.3048)
			(end 0.120396 0.2794)
			(stroke
				(width 0.1)
				(type default)
			)
			(layer "F.Fab")
		)
		(fp_line
			(start 0.67945 0.3048)
			(end 0.120396 0.3048)
			(stroke
				(width 0.1)
				(type default)
			)
			(layer "F.Fab")
		)
		(fp_line
			(start -0.12065 0.2794)
			(end -0.12065 0.3048)
			(stroke
				(width 0.1)
				(type default)
			)
			(layer "F.Fab")
		)
		(fp_line
			(start 0.120396 0.2794)
			(end -0.12065 0.2794)
			(stroke
				(width 0.1)
				(type default)
			)
			(layer "F.Fab")
		)
		(fp_line
			(start -0.12065 -0.2794)
			(end 0.12065 -0.2794)
			(stroke
				(width 0.1)
				(type default)
			)
			(layer "F.Fab")
		)
		(fp_line
			(start 0.12065 -0.2794)
			(end 0.12065 -0.3048)
			(stroke
				(width 0.1)
				(type default)
			)
			(layer "F.Fab")
		)
		(fp_line
			(start 0.12065 -0.3048)
			(end 0.67945 -0.3048)
			(stroke
				(width 0.1)
				(type default)
			)
			(layer "F.Fab")
		)
		(fp_line
			(start 0.67945 -0.3048)
			(end 0.67945 0.3048)
			(stroke
				(width 0.1)
				(type default)
			)
			(layer "F.Fab")
		)
		(fp_line
			(start -0.67945 -0.305054)
			(end -0.12065 -0.305054)
			(stroke
				(width 0.1)
				(type default)
			)
			(layer "F.Fab")
		)
		(fp_line
			(start -0.12065 -0.305054)
			(end -0.12065 -0.2794)
			(stroke
				(width 0.1)
				(type default)
			)
			(layer "F.Fab")
		)
		(pad "1" smd circle
			(at -0.40005 0 270)
			(size 0 0)
			(layers "F.Cu" "F.Mask" "F.Paste")
			(net "PVDD18_S5_P1_REF")
		)
		(pad "2" smd circle
			(at 0.40005 0 270)
			(size 0 0)
			(layers "F.Cu" "F.Mask" "F.Paste")
			(net "GND")
		)
	)
	(footprint ""
		(layer "F.Cu")
		(at 25.90673 -351.578672 90)
		(property "Reference" "PC621_10"
			(at 0 0 90)
			(layer "F.SilkS")
			(hide yes)
			(effects
				(font
					(size 1.27 1.27)
				)
			)
		)
		(property "Value" ""
			(at 0 0 90)
			(layer "F.Fab")
			(effects
				(font
					(size 1.27 1.27)
				)
			)
		)
		(duplicate_pad_numbers_are_jumpers no)
		(fp_line
			(start 0.7874 -0.4064)
			(end 0.7874 0.4064)
			(stroke
				(width 0.1524)
				(type default)
			)
			(layer "F.SilkS")
		)
		(fp_line
			(start -0.7874 -0.4064)
			(end 0.7874 -0.4064)
			(stroke
				(width 0.1524)
				(type default)
			)
			(layer "F.SilkS")
		)
		(fp_line
			(start 0.7874 0.4064)
			(end -0.7874 0.4064)
			(stroke
				(width 0.1524)
				(type default)
			)
			(layer "F.SilkS")
		)
		(fp_line
			(start -0.7874 0.4064)
			(end -0.7874 -0.4064)
			(stroke
				(width 0.1524)
				(type default)
			)
			(layer "F.SilkS")
		)
		(fp_line
			(start -0.12065 -0.305054)
			(end -0.12065 -0.2794)
			(stroke
				(width 0.1)
				(type default)
			)
			(layer "F.Fab")
		)
		(fp_line
			(start -0.67945 -0.305054)
			(end -0.12065 -0.305054)
			(stroke
				(width 0.1)
				(type default)
			)
			(layer "F.Fab")
		)
		(fp_line
			(start 0.67945 -0.3048)
			(end 0.67945 0.3048)
			(stroke
				(width 0.1)
				(type default)
			)
			(layer "F.Fab")
		)
		(fp_line
			(start 0.12065 -0.3048)
			(end 0.67945 -0.3048)
			(stroke
				(width 0.1)
				(type default)
			)
			(layer "F.Fab")
		)
		(fp_line
			(start 0.12065 -0.2794)
			(end 0.12065 -0.3048)
			(stroke
				(width 0.1)
				(type default)
			)
			(layer "F.Fab")
		)
		(fp_line
			(start -0.12065 -0.2794)
			(end 0.12065 -0.2794)
			(stroke
				(width 0.1)
				(type default)
			)
			(layer "F.Fab")
		)
		(fp_line
			(start 0.120396 0.2794)
			(end -0.12065 0.2794)
			(stroke
				(width 0.1)
				(type default)
			)
			(layer "F.Fab")
		)
		(fp_line
			(start -0.12065 0.2794)
			(end -0.12065 0.3048)
			(stroke
				(width 0.1)
				(type default)
			)
			(layer "F.Fab")
		)
		(fp_line
			(start 0.67945 0.3048)
			(end 0.120396 0.3048)
			(stroke
				(width 0.1)
				(type default)
			)
			(layer "F.Fab")
		)
		(fp_line
			(start 0.120396 0.3048)
			(end 0.120396 0.2794)
			(stroke
				(width 0.1)
				(type default)
			)
			(layer "F.Fab")
		)
		(fp_line
			(start -0.12065 0.3048)
			(end -0.67945 0.3048)
			(stroke
				(width 0.1)
				(type default)
			)
			(layer "F.Fab")
		)
		(fp_line
			(start -0.67945 0.3048)
			(end -0.67945 -0.305054)
			(stroke
				(width 0.1)
				(type default)
			)
			(layer "F.Fab")
		)
		(pad "1" smd circle
			(at -0.40005 0 90)
			(size 0 0)
			(layers "F.Cu" "F.Mask" "F.Paste")
			(net "PVDDCR_CPU1_P1_VCCS")
		)
		(pad "2" smd circle
			(at 0.40005 0 90)
			(size 0 0)
			(layers "F.Cu" "F.Mask" "F.Paste")
			(net "GND")
		)
	)
	(footprint ""
		(layer "F.Cu")
		(at 68.961 -53.594 180)
		(property "Reference" "R1147"
			(at 0 0 180)
			(layer "F.SilkS")
			(hide yes)
			(effects
				(font
					(size 1.27 1.27)
				)
			)
		)
		(property "Value" ""
			(at 0 0 180)
			(layer "F.Fab")
			(effects
				(font
					(size 1.27 1.27)
				)
			)
		)
		(duplicate_pad_numbers_are_jumpers no)
		(fp_line
			(start 0.7874 0.4064)
			(end -0.7874 0.4064)
			(stroke
				(width 0.1524)
				(type default)
			)
			(layer "F.SilkS")
		)
		(fp_line
			(start 0.7874 -0.4064)
			(end 0.7874 0.4064)
			(stroke
				(width 0.1524)
				(type default)
			)
			(layer "F.SilkS")
		)
		(fp_line
			(start -0.7874 0.4064)
			(end -0.7874 -0.4064)
			(stroke
				(width 0.1524)
				(type default)
			)
			(layer "F.SilkS")
		)
		(fp_line
			(start -0.7874 -0.4064)
			(end 0.7874 -0.4064)
			(stroke
				(width 0.1524)
				(type default)
			)
			(layer "F.SilkS")
		)
		(fp_line
			(start 0.67945 0.3048)
			(end 0.120396 0.3048)
			(stroke
				(width 0.1)
				(type default)
			)
			(layer "F.Fab")
		)
		(fp_line
			(start 0.67945 -0.3048)
			(end 0.67945 0.3048)
			(stroke
				(width 0.1)
				(type default)
			)
			(layer "F.Fab")
		)
		(fp_line
			(start 0.12065 -0.2794)
			(end 0.12065 -0.3048)
			(stroke
				(width 0.1)
				(type default)
			)
			(layer "F.Fab")
		)
		(fp_line
			(start 0.12065 -0.3048)
			(end 0.67945 -0.3048)
			(stroke
				(width 0.1)
				(type default)
			)
			(layer "F.Fab")
		)
		(fp_line
			(start 0.120396 0.3048)
			(end 0.120396 0.2794)
			(stroke
				(width 0.1)
				(type default)
			)
			(layer "F.Fab")
		)
		(fp_line
			(start 0.120396 0.2794)
			(end -0.12065 0.2794)
			(stroke
				(width 0.1)
				(type default)
			)
			(layer "F.Fab")
		)
		(fp_line
			(start -0.12065 0.3048)
			(end -0.67945 0.3048)
			(stroke
				(width 0.1)
				(type default)
			)
			(layer "F.Fab")
		)
		(fp_line
			(start -0.12065 0.2794)
			(end -0.12065 0.3048)
			(stroke
				(width 0.1)
				(type default)
			)
			(layer "F.Fab")
		)
		(fp_line
			(start -0.12065 -0.2794)
			(end 0.12065 -0.2794)
			(stroke
				(width 0.1)
				(type default)
			)
			(layer "F.Fab")
		)
		(fp_line
			(start -0.12065 -0.305054)
			(end -0.12065 -0.2794)
			(stroke
				(width 0.1)
				(type default)
			)
			(layer "F.Fab")
		)
		(fp_line
			(start -0.67945 0.3048)
			(end -0.67945 -0.305054)
			(stroke
				(width 0.1)
				(type default)
			)
			(layer "F.Fab")
		)
		(fp_line
			(start -0.67945 -0.305054)
			(end -0.12065 -0.305054)
			(stroke
				(width 0.1)
				(type default)
			)
			(layer "F.Fab")
		)
		(pad "1" smd circle
			(at -0.40005 0 180)
			(size 0 0)
			(layers "F.Cu" "F.Mask" "F.Paste")
			(net "OCP_V3_2_AUX_PWR_EN_R2")
		)
		(pad "2" smd circle
			(at 0.40005 0 180)
			(size 0 0)
			(layers "F.Cu" "F.Mask" "F.Paste")
			(net "FM_OCP_V3_2_AUX_PWR_R_EN")
		)
	)
	(footprint ""
		(layer "F.Cu")
		(at 304.931572 -25.62225)
		(property "Reference" "U9"
			(at -1.8034 -1.819148 0)
			(unlocked yes)
			(layer "F.SilkS")
			(effects
				(font
					(size 0.7874 0.5842)
					(thickness 0.1524)
				)
				(justify left)
			)
		)
		(property "Value" ""
			(at 0 0 0)
			(layer "F.Fab")
			(effects
				(font
					(size 1.27 1.27)
				)
			)
		)
		(duplicate_pad_numbers_are_jumpers no)
		(fp_line
			(start -1.684274 -1.074928)
			(end -0.381 -1.074928)
			(stroke
				(width 0.1524)
				(type default)
			)
			(layer "F.SilkS")
		)
		(fp_line
			(start -1.684274 1.074928)
			(end -1.684274 -1.074928)
			(stroke
				(width 0.1524)
				(type default)
			)
			(layer "F.SilkS")
		)
		(fp_line
			(start -0.381 -1.074928)
			(end 0 -0.625094)
			(stroke
				(width 0.1524)
				(type default)
			)
			(layer "F.SilkS")
		)
		(fp_line
			(start 0 -0.625094)
			(end 0.381 -1.074928)
			(stroke
				(width 0.1524)
				(type default)
			)
			(layer "F.SilkS")
		)
		(fp_line
			(start 0.381 -1.074928)
			(end 1.684274 -1.074928)
			(stroke
				(width 0.1524)
				(type default)
			)
			(layer "F.SilkS")
		)
		(fp_line
			(start 1.684274 -1.074928)
			(end 1.684274 1.074928)
			(stroke
				(width 0.1524)
				(type default)
			)
			(layer "F.SilkS")
		)
		(fp_line
			(start 1.684274 1.074928)
			(end -1.684274 1.074928)
			(stroke
				(width 0.1524)
				(type default)
			)
			(layer "F.SilkS")
		)
		(fp_poly
			(pts
				(xy -2.637282 -0.903986) (xy -2.637282 -0.395986) (xy -1.875282 -0.649986)
			)
			(stroke
				(width 0)
				(type default)
			)
			(fill yes)
			(layer "F.SilkS")
		)
		(fp_line
			(start -0.700024 -1.074928)
			(end -0.700024 1.074928)
			(stroke
				(width 0.1)
				(type default)
			)
			(layer "F.Fab")
		)
		(fp_line
			(start -0.700024 1.074928)
			(end 0.700024 1.074928)
			(stroke
				(width 0.1)
				(type default)
			)
			(layer "F.Fab")
		)
		(fp_line
			(start 0.700024 -1.074928)
			(end -0.700024 -1.074928)
			(stroke
				(width 0.1)
				(type default)
			)
			(layer "F.Fab")
		)
		(fp_line
			(start 0.700024 1.074928)
			(end 0.700024 -1.074928)
			(stroke
				(width 0.1)
				(type default)
			)
			(layer "F.Fab")
		)
		(fp_poly
			(pts
				(xy -2.637282 -0.903986) (xy -2.637282 -0.395986) (xy -1.875282 -0.649986)
			)
			(stroke
				(width 0)
				(type default)
			)
			(fill yes)
			(layer "F.Fab")
		)
		(pad "1" smd rect
			(at -1.100074 -0.649986 270)
			(size 0.4064 0.9144)
			(layers "F.Cu" "F.Mask" "F.Paste")
			(net "P1V5_BAT_IN")
		)
		(pad "2" smd rect
			(at -1.100074 0 270)
			(size 0.4064 0.9144)
			(layers "F.Cu" "F.Mask" "F.Paste")
			(net "GND")
		)
		(pad "3" smd rect
			(at -1.100074 0.649986 270)
			(size 0.4064 0.9144)
			(layers "F.Cu" "F.Mask" "F.Paste")
			(net "BAT_LDO_EN")
		)
		(pad "4" smd rect
			(at 1.100074 0.649986 270)
			(size 0.4064 0.9144)
			(layers "F.Cu" "F.Mask" "F.Paste")
			(net "U9_NR")
		)
		(pad "5" smd rect
			(at 1.100074 -0.649986 270)
			(size 0.4064 0.9144)
			(layers "F.Cu" "F.Mask" "F.Paste")
			(net "P1V5_BAT_OUT")
		)
	)
	(footprint ""
		(layer "F.Cu")
		(at 402.214842 -403.603206 -90)
		(property "Reference" "R1079"
			(at 0 0 270)
			(layer "F.SilkS")
			(hide yes)
			(effects
				(font
					(size 1.27 1.27)
				)
			)
		)
		(property "Value" ""
			(at 0 0 270)
			(layer "F.Fab")
			(effects
				(font
					(size 1.27 1.27)
				)
			)
		)
		(duplicate_pad_numbers_are_jumpers no)
		(fp_line
			(start -0.32512 0.175006)
			(end -0.32512 -0.175006)
			(stroke
				(width 0.1)
				(type default)
			)
			(layer "F.Fab")
		)
		(fp_line
			(start 0.32512 0.175006)
			(end -0.32512 0.175006)
			(stroke
				(width 0.1)
				(type default)
			)
			(layer "F.Fab")
		)
		(fp_line
			(start -0.32512 -0.175006)
			(end 0.32512 -0.175006)
			(stroke
				(width 0.1)
				(type default)
			)
			(layer "F.Fab")
		)
		(fp_line
			(start 0.32512 -0.175006)
			(end 0.32512 0.175006)
			(stroke
				(width 0.1)
				(type default)
			)
			(layer "F.Fab")
		)
		(pad "1" smd rect
			(at -0.2667 0 270)
			(size 0.3048 0.381)
			(layers "F.Cu" "F.Mask" "F.Paste")
			(net "JTAG_TEST_MODE_RT_CPU0_P2")
		)
		(pad "2" smd rect
			(at 0.2667 0 90)
			(size 0.3048 0.381)
			(layers "F.Cu" "F.Mask" "F.Paste")
			(net "GND")
		)
	)
	(footprint ""
		(layer "F.Cu")
		(at 95.151702 -375.49963 -90)
		(property "Reference" "C720"
			(at 0 0 270)
			(layer "F.SilkS")
			(hide yes)
			(effects
				(font
					(size 1.27 1.27)
				)
			)
		)
		(property "Value" ""
			(at 0 0 270)
			(layer "F.Fab")
			(effects
				(font
					(size 1.27 1.27)
				)
			)
		)
		(duplicate_pad_numbers_are_jumpers no)
		(fp_line
			(start -0.299974 0.150114)
			(end -0.299974 -0.150114)
			(stroke
				(width 0.1)
				(type default)
			)
			(layer "F.Fab")
		)
		(fp_line
			(start 0.299974 0.150114)
			(end -0.299974 0.150114)
			(stroke
				(width 0.1)
				(type default)
			)
			(layer "F.Fab")
		)
		(fp_line
			(start -0.299974 -0.150114)
			(end 0.299974 -0.150114)
			(stroke
				(width 0.1)
				(type default)
			)
			(layer "F.Fab")
		)
		(fp_line
			(start 0.299974 -0.150114)
			(end 0.299974 0.150114)
			(stroke
				(width 0.1)
				(type default)
			)
			(layer "F.Fab")
		)
		(pad "1" smd rect
			(at -0.2667 0 270)
			(size 0.3048 0.381)
			(layers "F.Cu" "F.Mask" "F.Paste")
			(net "P5E_CPU1_P1_TX_C_DN<10>")
		)
		(pad "2" smd rect
			(at 0.2667 0 270)
			(size 0.3048 0.381)
			(layers "F.Cu" "F.Mask" "F.Paste")
			(net "P5E_CPU1_P1_TX_DN<10>")
		)
	)
	(footprint ""
		(layer "F.Cu")
		(at 108.4199 -395.769084 90)
		(property "Reference" "R6735"
			(at 0 0 90)
			(layer "F.SilkS")
			(hide yes)
			(effects
				(font
					(size 1.27 1.27)
				)
			)
		)
		(property "Value" ""
			(at 0 0 90)
			(layer "F.Fab")
			(effects
				(font
					(size 1.27 1.27)
				)
			)
		)
		(duplicate_pad_numbers_are_jumpers no)
		(fp_line
			(start 0.32512 -0.175006)
			(end 0.32512 0.175006)
			(stroke
				(width 0.1)
				(type default)
			)
			(layer "F.Fab")
		)
		(fp_line
			(start -0.32512 -0.175006)
			(end 0.32512 -0.175006)
			(stroke
				(width 0.1)
				(type default)
			)
			(layer "F.Fab")
		)
		(fp_line
			(start 0.32512 0.175006)
			(end -0.32512 0.175006)
			(stroke
				(width 0.1)
				(type default)
			)
			(layer "F.Fab")
		)
		(fp_line
			(start -0.32512 0.175006)
			(end -0.32512 -0.175006)
			(stroke
				(width 0.1)
				(type default)
			)
			(layer "F.Fab")
		)
		(pad "1" smd rect
			(at -0.2667 0 90)
			(size 0.3048 0.381)
			(layers "F.Cu" "F.Mask" "F.Paste")
			(net "P1V8_CPU1_RT_1D")
		)
		(pad "2" smd rect
			(at 0.2667 0 270)
			(size 0.3048 0.381)
			(layers "F.Cu" "F.Mask" "F.Paste")
			(net "SMB_RT_CPU1_P1_ROM_R_SDA")
		)
	)
	(footprint ""
		(layer "F.Cu")
		(at 416.856418 -366.325912)
		(property "Reference" "R118"
			(at 0 0 0)
			(layer "F.SilkS")
			(hide yes)
			(effects
				(font
					(size 1.27 1.27)
				)
			)
		)
		(property "Value" ""
			(at 0 0 0)
			(layer "F.Fab")
			(effects
				(font
					(size 1.27 1.27)
				)
			)
		)
		(duplicate_pad_numbers_are_jumpers no)
		(fp_line
			(start -0.7874 -0.4064)
			(end 0.7874 -0.4064)
			(stroke
				(width 0.1524)
				(type default)
			)
			(layer "F.SilkS")
		)
		(fp_line
			(start -0.7874 0.4064)
			(end -0.7874 -0.4064)
			(stroke
				(width 0.1524)
				(type default)
			)
			(layer "F.SilkS")
		)
		(fp_line
			(start 0.7874 -0.4064)
			(end 0.7874 0.4064)
			(stroke
				(width 0.1524)
				(type default)
			)
			(layer "F.SilkS")
		)
		(fp_line
			(start 0.7874 0.4064)
			(end -0.7874 0.4064)
			(stroke
				(width 0.1524)
				(type default)
			)
			(layer "F.SilkS")
		)
		(fp_line
			(start -0.67945 -0.305054)
			(end -0.12065 -0.305054)
			(stroke
				(width 0.1)
				(type default)
			)
			(layer "F.Fab")
		)
		(fp_line
			(start -0.67945 0.3048)
			(end -0.67945 -0.305054)
			(stroke
				(width 0.1)
				(type default)
			)
			(layer "F.Fab")
		)
		(fp_line
			(start -0.12065 -0.305054)
			(end -0.12065 -0.2794)
			(stroke
				(width 0.1)
				(type default)
			)
			(layer "F.Fab")
		)
		(fp_line
			(start -0.12065 -0.2794)
			(end 0.12065 -0.2794)
			(stroke
				(width 0.1)
				(type default)
			)
			(layer "F.Fab")
		)
		(fp_line
			(start -0.12065 0.2794)
			(end -0.12065 0.3048)
			(stroke
				(width 0.1)
				(type default)
			)
			(layer "F.Fab")
		)
		(fp_line
			(start -0.12065 0.3048)
			(end -0.67945 0.3048)
			(stroke
				(width 0.1)
				(type default)
			)
			(layer "F.Fab")
		)
		(fp_line
			(start 0.120396 0.2794)
			(end -0.12065 0.2794)
			(stroke
				(width 0.1)
				(type default)
			)
			(layer "F.Fab")
		)
		(fp_line
			(start 0.120396 0.3048)
			(end 0.120396 0.2794)
			(stroke
				(width 0.1)
				(type default)
			)
			(layer "F.Fab")
		)
		(fp_line
			(start 0.12065 -0.3048)
			(end 0.67945 -0.3048)
			(stroke
				(width 0.1)
				(type default)
			)
			(layer "F.Fab")
		)
		(fp_line
			(start 0.12065 -0.2794)
			(end 0.12065 -0.3048)
			(stroke
				(width 0.1)
				(type default)
			)
			(layer "F.Fab")
		)
		(fp_line
			(start 0.67945 -0.3048)
			(end 0.67945 0.3048)
			(stroke
				(width 0.1)
				(type default)
			)
			(layer "F.Fab")
		)
		(fp_line
			(start 0.67945 0.3048)
			(end 0.120396 0.3048)
			(stroke
				(width 0.1)
				(type default)
			)
			(layer "F.Fab")
		)
		(pad "1" smd circle
			(at -0.40005 0)
			(size 0 0)
			(layers "F.Cu" "F.Mask" "F.Paste")
			(net "SMB_SCM_2_R6_SCL")
		)
		(pad "2" smd circle
			(at 0.40005 0)
			(size 0 0)
			(layers "F.Cu" "F.Mask" "F.Paste")
			(net "PVDD11_S3_P0_PMSCL_R")
		)
	)
	(footprint ""
		(layer "F.Cu")
		(at 166.3192 -432.4096 180)
		(property "Reference" "R2707"
			(at 0 0 180)
			(layer "F.SilkS")
			(hide yes)
			(effects
				(font
					(size 1.27 1.27)
				)
			)
		)
		(property "Value" ""
			(at 0 0 180)
			(layer "F.Fab")
			(effects
				(font
					(size 1.27 1.27)
				)
			)
		)
		(duplicate_pad_numbers_are_jumpers no)
		(fp_line
			(start 0.7874 0.4064)
			(end -0.7874 0.4064)
			(stroke
				(width 0.1524)
				(type default)
			)
			(layer "F.SilkS")
		)
		(fp_line
			(start 0.7874 -0.4064)
			(end 0.7874 0.4064)
			(stroke
				(width 0.1524)
				(type default)
			)
			(layer "F.SilkS")
		)
		(fp_line
			(start -0.7874 0.4064)
			(end -0.7874 -0.4064)
			(stroke
				(width 0.1524)
				(type default)
			)
			(layer "F.SilkS")
		)
		(fp_line
			(start -0.7874 -0.4064)
			(end 0.7874 -0.4064)
			(stroke
				(width 0.1524)
				(type default)
			)
			(layer "F.SilkS")
		)
		(fp_line
			(start 0.67945 0.3048)
			(end 0.120396 0.3048)
			(stroke
				(width 0.1)
				(type default)
			)
			(layer "F.Fab")
		)
		(fp_line
			(start 0.67945 -0.3048)
			(end 0.67945 0.3048)
			(stroke
				(width 0.1)
				(type default)
			)
			(layer "F.Fab")
		)
		(fp_line
			(start 0.12065 -0.2794)
			(end 0.12065 -0.3048)
			(stroke
				(width 0.1)
				(type default)
			)
			(layer "F.Fab")
		)
		(fp_line
			(start 0.12065 -0.3048)
			(end 0.67945 -0.3048)
			(stroke
				(width 0.1)
				(type default)
			)
			(layer "F.Fab")
		)
		(fp_line
			(start 0.120396 0.3048)
			(end 0.120396 0.2794)
			(stroke
				(width 0.1)
				(type default)
			)
			(layer "F.Fab")
		)
		(fp_line
			(start 0.120396 0.2794)
			(end -0.12065 0.2794)
			(stroke
				(width 0.1)
				(type default)
			)
			(layer "F.Fab")
		)
		(fp_line
			(start -0.12065 0.3048)
			(end -0.67945 0.3048)
			(stroke
				(width 0.1)
				(type default)
			)
			(layer "F.Fab")
		)
		(fp_line
			(start -0.12065 0.2794)
			(end -0.12065 0.3048)
			(stroke
				(width 0.1)
				(type default)
			)
			(layer "F.Fab")
		)
		(fp_line
			(start -0.12065 -0.2794)
			(end 0.12065 -0.2794)
			(stroke
				(width 0.1)
				(type default)
			)
			(layer "F.Fab")
		)
		(fp_line
			(start -0.12065 -0.305054)
			(end -0.12065 -0.2794)
			(stroke
				(width 0.1)
				(type default)
			)
			(layer "F.Fab")
		)
		(fp_line
			(start -0.67945 0.3048)
			(end -0.67945 -0.305054)
			(stroke
				(width 0.1)
				(type default)
			)
			(layer "F.Fab")
		)
		(fp_line
			(start -0.67945 -0.305054)
			(end -0.12065 -0.305054)
			(stroke
				(width 0.1)
				(type default)
			)
			(layer "F.Fab")
		)
		(pad "1" smd circle
			(at -0.40005 0 180)
			(size 0 0)
			(layers "F.Cu" "F.Mask" "F.Paste")
			(net "SMB_BMC_SWB_EN")
		)
		(pad "2" smd circle
			(at 0.40005 0 180)
			(size 0 0)
			(layers "F.Cu" "F.Mask" "F.Paste")
			(net "SMB_BMC_SWB_EN_R")
		)
	)
	(footprint ""
		(layer "F.Cu")
		(at 378.002292 -383.88163 -90)
		(property "Reference" "C887"
			(at 0 0 270)
			(layer "F.SilkS")
			(hide yes)
			(effects
				(font
					(size 1.27 1.27)
				)
			)
		)
		(property "Value" ""
			(at 0 0 270)
			(layer "F.Fab")
			(effects
				(font
					(size 1.27 1.27)
				)
			)
		)
		(duplicate_pad_numbers_are_jumpers no)
		(fp_line
			(start -0.299974 0.150114)
			(end -0.299974 -0.150114)
			(stroke
				(width 0.1)
				(type default)
			)
			(layer "F.Fab")
		)
		(fp_line
			(start 0.299974 0.150114)
			(end -0.299974 0.150114)
			(stroke
				(width 0.1)
				(type default)
			)
			(layer "F.Fab")
		)
		(fp_line
			(start -0.299974 -0.150114)
			(end 0.299974 -0.150114)
			(stroke
				(width 0.1)
				(type default)
			)
			(layer "F.Fab")
		)
		(fp_line
			(start 0.299974 -0.150114)
			(end 0.299974 0.150114)
			(stroke
				(width 0.1)
				(type default)
			)
			(layer "F.Fab")
		)
		(pad "1" smd rect
			(at -0.2667 0 270)
			(size 0.3048 0.381)
			(layers "F.Cu" "F.Mask" "F.Paste")
			(net "P5E_CPU0_P3_TX_C_DP<7>")
		)
		(pad "2" smd rect
			(at 0.2667 0 270)
			(size 0.3048 0.381)
			(layers "F.Cu" "F.Mask" "F.Paste")
			(net "P5E_CPU0_P3_TX_DP<7>")
		)
	)
	(footprint ""
		(layer "F.Cu")
		(at 172.54347 -418.551868 180)
		(property "Reference" "R9007"
			(at 0 0 180)
			(layer "F.SilkS")
			(hide yes)
			(effects
				(font
					(size 1.27 1.27)
				)
			)
		)
		(property "Value" ""
			(at 0 0 180)
			(layer "F.Fab")
			(effects
				(font
					(size 1.27 1.27)
				)
			)
		)
		(duplicate_pad_numbers_are_jumpers no)
		(fp_line
			(start 0.7874 0.4064)
			(end -0.7874 0.4064)
			(stroke
				(width 0.1524)
				(type default)
			)
			(layer "F.SilkS")
		)
		(fp_line
			(start 0.7874 -0.4064)
			(end 0.7874 0.4064)
			(stroke
				(width 0.1524)
				(type default)
			)
			(layer "F.SilkS")
		)
		(fp_line
			(start -0.7874 0.4064)
			(end -0.7874 -0.4064)
			(stroke
				(width 0.1524)
				(type default)
			)
			(layer "F.SilkS")
		)
		(fp_line
			(start -0.7874 -0.4064)
			(end 0.7874 -0.4064)
			(stroke
				(width 0.1524)
				(type default)
			)
			(layer "F.SilkS")
		)
		(fp_line
			(start 0.67945 0.3048)
			(end 0.120396 0.3048)
			(stroke
				(width 0.1)
				(type default)
			)
			(layer "F.Fab")
		)
		(fp_line
			(start 0.67945 -0.3048)
			(end 0.67945 0.3048)
			(stroke
				(width 0.1)
				(type default)
			)
			(layer "F.Fab")
		)
		(fp_line
			(start 0.12065 -0.2794)
			(end 0.12065 -0.3048)
			(stroke
				(width 0.1)
				(type default)
			)
			(layer "F.Fab")
		)
		(fp_line
			(start 0.12065 -0.3048)
			(end 0.67945 -0.3048)
			(stroke
				(width 0.1)
				(type default)
			)
			(layer "F.Fab")
		)
		(fp_line
			(start 0.120396 0.3048)
			(end 0.120396 0.2794)
			(stroke
				(width 0.1)
				(type default)
			)
			(layer "F.Fab")
		)
		(fp_line
			(start 0.120396 0.2794)
			(end -0.12065 0.2794)
			(stroke
				(width 0.1)
				(type default)
			)
			(layer "F.Fab")
		)
		(fp_line
			(start -0.12065 0.3048)
			(end -0.67945 0.3048)
			(stroke
				(width 0.1)
				(type default)
			)
			(layer "F.Fab")
		)
		(fp_line
			(start -0.12065 0.2794)
			(end -0.12065 0.3048)
			(stroke
				(width 0.1)
				(type default)
			)
			(layer "F.Fab")
		)
		(fp_line
			(start -0.12065 -0.2794)
			(end 0.12065 -0.2794)
			(stroke
				(width 0.1)
				(type default)
			)
			(layer "F.Fab")
		)
		(fp_line
			(start -0.12065 -0.305054)
			(end -0.12065 -0.2794)
			(stroke
				(width 0.1)
				(type default)
			)
			(layer "F.Fab")
		)
		(fp_line
			(start -0.67945 0.3048)
			(end -0.67945 -0.305054)
			(stroke
				(width 0.1)
				(type default)
			)
			(layer "F.Fab")
		)
		(fp_line
			(start -0.67945 -0.305054)
			(end -0.12065 -0.305054)
			(stroke
				(width 0.1)
				(type default)
			)
			(layer "F.Fab")
		)
		(pad "1" smd circle
			(at -0.40005 0 180)
			(size 0 0)
			(layers "F.Cu" "F.Mask" "F.Paste")
			(net "PRSNT_CABLE_SWB_B2_N")
		)
		(pad "2" smd circle
			(at 0.40005 0 180)
			(size 0 0)
			(layers "F.Cu" "F.Mask" "F.Paste")
			(net "GND")
		)
	)
	(footprint ""
		(layer "F.Cu")
		(at 412.472886 -72.832468)
		(property "Reference" "R3263"
			(at 0 0 0)
			(layer "F.SilkS")
			(hide yes)
			(effects
				(font
					(size 1.27 1.27)
				)
			)
		)
		(property "Value" ""
			(at 0 0 0)
			(layer "F.Fab")
			(effects
				(font
					(size 1.27 1.27)
				)
			)
		)
		(duplicate_pad_numbers_are_jumpers no)
		(fp_line
			(start -0.7874 -0.4064)
			(end 0.7874 -0.4064)
			(stroke
				(width 0.1524)
				(type default)
			)
			(layer "F.SilkS")
		)
		(fp_line
			(start -0.7874 0.4064)
			(end -0.7874 -0.4064)
			(stroke
				(width 0.1524)
				(type default)
			)
			(layer "F.SilkS")
		)
		(fp_line
			(start 0.7874 -0.4064)
			(end 0.7874 0.4064)
			(stroke
				(width 0.1524)
				(type default)
			)
			(layer "F.SilkS")
		)
		(fp_line
			(start 0.7874 0.4064)
			(end -0.7874 0.4064)
			(stroke
				(width 0.1524)
				(type default)
			)
			(layer "F.SilkS")
		)
		(fp_line
			(start -0.67945 -0.305054)
			(end -0.12065 -0.305054)
			(stroke
				(width 0.1)
				(type default)
			)
			(layer "F.Fab")
		)
		(fp_line
			(start -0.67945 0.3048)
			(end -0.67945 -0.305054)
			(stroke
				(width 0.1)
				(type default)
			)
			(layer "F.Fab")
		)
		(fp_line
			(start -0.12065 -0.305054)
			(end -0.12065 -0.2794)
			(stroke
				(width 0.1)
				(type default)
			)
			(layer "F.Fab")
		)
		(fp_line
			(start -0.12065 -0.2794)
			(end 0.12065 -0.2794)
			(stroke
				(width 0.1)
				(type default)
			)
			(layer "F.Fab")
		)
		(fp_line
			(start -0.12065 0.2794)
			(end -0.12065 0.3048)
			(stroke
				(width 0.1)
				(type default)
			)
			(layer "F.Fab")
		)
		(fp_line
			(start -0.12065 0.3048)
			(end -0.67945 0.3048)
			(stroke
				(width 0.1)
				(type default)
			)
			(layer "F.Fab")
		)
		(fp_line
			(start 0.120396 0.2794)
			(end -0.12065 0.2794)
			(stroke
				(width 0.1)
				(type default)
			)
			(layer "F.Fab")
		)
		(fp_line
			(start 0.120396 0.3048)
			(end 0.120396 0.2794)
			(stroke
				(width 0.1)
				(type default)
			)
			(layer "F.Fab")
		)
		(fp_line
			(start 0.12065 -0.3048)
			(end 0.67945 -0.3048)
			(stroke
				(width 0.1)
				(type default)
			)
			(layer "F.Fab")
		)
		(fp_line
			(start 0.12065 -0.2794)
			(end 0.12065 -0.3048)
			(stroke
				(width 0.1)
				(type default)
			)
			(layer "F.Fab")
		)
		(fp_line
			(start 0.67945 -0.3048)
			(end 0.67945 0.3048)
			(stroke
				(width 0.1)
				(type default)
			)
			(layer "F.Fab")
		)
		(fp_line
			(start 0.67945 0.3048)
			(end 0.120396 0.3048)
			(stroke
				(width 0.1)
				(type default)
			)
			(layer "F.Fab")
		)
		(pad "1" smd circle
			(at -0.40005 0)
			(size 0 0)
			(layers "F.Cu" "F.Mask" "F.Paste")
			(net "HP_LVC3_OCP_V3_1_R_EN")
		)
		(pad "2" smd circle
			(at 0.40005 0)
			(size 0 0)
			(layers "F.Cu" "F.Mask" "F.Paste")
			(net "P3V3_OCP_SFF_EN_R")
		)
	)
	(footprint ""
		(layer "F.Cu")
		(at 14.886178 -107.631484 180)
		(property "Reference" "R4482"
			(at 0 0 180)
			(layer "F.SilkS")
			(hide yes)
			(effects
				(font
					(size 1.27 1.27)
				)
			)
		)
		(property "Value" ""
			(at 0 0 180)
			(layer "F.Fab")
			(effects
				(font
					(size 1.27 1.27)
				)
			)
		)
		(duplicate_pad_numbers_are_jumpers no)
		(fp_line
			(start 0.7874 0.4064)
			(end -0.7874 0.4064)
			(stroke
				(width 0.1524)
				(type default)
			)
			(layer "F.SilkS")
		)
		(fp_line
			(start 0.7874 -0.4064)
			(end 0.7874 0.4064)
			(stroke
				(width 0.1524)
				(type default)
			)
			(layer "F.SilkS")
		)
		(fp_line
			(start -0.7874 0.4064)
			(end -0.7874 -0.4064)
			(stroke
				(width 0.1524)
				(type default)
			)
			(layer "F.SilkS")
		)
		(fp_line
			(start -0.7874 -0.4064)
			(end 0.7874 -0.4064)
			(stroke
				(width 0.1524)
				(type default)
			)
			(layer "F.SilkS")
		)
		(fp_line
			(start 0.67945 0.3048)
			(end 0.120396 0.3048)
			(stroke
				(width 0.1)
				(type default)
			)
			(layer "F.Fab")
		)
		(fp_line
			(start 0.67945 -0.3048)
			(end 0.67945 0.3048)
			(stroke
				(width 0.1)
				(type default)
			)
			(layer "F.Fab")
		)
		(fp_line
			(start 0.12065 -0.2794)
			(end 0.12065 -0.3048)
			(stroke
				(width 0.1)
				(type default)
			)
			(layer "F.Fab")
		)
		(fp_line
			(start 0.12065 -0.3048)
			(end 0.67945 -0.3048)
			(stroke
				(width 0.1)
				(type default)
			)
			(layer "F.Fab")
		)
		(fp_line
			(start 0.120396 0.3048)
			(end 0.120396 0.2794)
			(stroke
				(width 0.1)
				(type default)
			)
			(layer "F.Fab")
		)
		(fp_line
			(start 0.120396 0.2794)
			(end -0.12065 0.2794)
			(stroke
				(width 0.1)
				(type default)
			)
			(layer "F.Fab")
		)
		(fp_line
			(start -0.12065 0.3048)
			(end -0.67945 0.3048)
			(stroke
				(width 0.1)
				(type default)
			)
			(layer "F.Fab")
		)
		(fp_line
			(start -0.12065 0.2794)
			(end -0.12065 0.3048)
			(stroke
				(width 0.1)
				(type default)
			)
			(layer "F.Fab")
		)
		(fp_line
			(start -0.12065 -0.2794)
			(end 0.12065 -0.2794)
			(stroke
				(width 0.1)
				(type default)
			)
			(layer "F.Fab")
		)
		(fp_line
			(start -0.12065 -0.305054)
			(end -0.12065 -0.2794)
			(stroke
				(width 0.1)
				(type default)
			)
			(layer "F.Fab")
		)
		(fp_line
			(start -0.67945 0.3048)
			(end -0.67945 -0.305054)
			(stroke
				(width 0.1)
				(type default)
			)
			(layer "F.Fab")
		)
		(fp_line
			(start -0.67945 -0.305054)
			(end -0.12065 -0.305054)
			(stroke
				(width 0.1)
				(type default)
			)
			(layer "F.Fab")
		)
		(pad "1" smd circle
			(at -0.40005 0 180)
			(size 0 0)
			(layers "F.Cu" "F.Mask" "F.Paste")
			(net "USB2_HOST_BMC_B_BUF_DP")
		)
		(pad "2" smd circle
			(at 0.40005 0 180)
			(size 0 0)
			(layers "F.Cu" "F.Mask" "F.Paste")
			(net "GND")
		)
	)
	(footprint ""
		(layer "F.Cu")
		(at 280.025348 -344.982038 90)
		(property "Reference" "PR379"
			(at 0 0 90)
			(layer "F.SilkS")
			(hide yes)
			(effects
				(font
					(size 1.27 1.27)
				)
			)
		)
		(property "Value" ""
			(at 0 0 90)
			(layer "F.Fab")
			(effects
				(font
					(size 1.27 1.27)
				)
			)
		)
		(duplicate_pad_numbers_are_jumpers no)
		(fp_line
			(start 0.7874 -0.4064)
			(end 0.7874 0.4064)
			(stroke
				(width 0.1524)
				(type default)
			)
			(layer "F.SilkS")
		)
		(fp_line
			(start -0.7874 -0.4064)
			(end 0.7874 -0.4064)
			(stroke
				(width 0.1524)
				(type default)
			)
			(layer "F.SilkS")
		)
		(fp_line
			(start 0.7874 0.4064)
			(end -0.7874 0.4064)
			(stroke
				(width 0.1524)
				(type default)
			)
			(layer "F.SilkS")
		)
		(fp_line
			(start -0.7874 0.4064)
			(end -0.7874 -0.4064)
			(stroke
				(width 0.1524)
				(type default)
			)
			(layer "F.SilkS")
		)
		(fp_line
			(start -0.12065 -0.305054)
			(end -0.12065 -0.2794)
			(stroke
				(width 0.1)
				(type default)
			)
			(layer "F.Fab")
		)
		(fp_line
			(start -0.67945 -0.305054)
			(end -0.12065 -0.305054)
			(stroke
				(width 0.1)
				(type default)
			)
			(layer "F.Fab")
		)
		(fp_line
			(start 0.67945 -0.3048)
			(end 0.67945 0.3048)
			(stroke
				(width 0.1)
				(type default)
			)
			(layer "F.Fab")
		)
		(fp_line
			(start 0.12065 -0.3048)
			(end 0.67945 -0.3048)
			(stroke
				(width 0.1)
				(type default)
			)
			(layer "F.Fab")
		)
		(fp_line
			(start 0.12065 -0.2794)
			(end 0.12065 -0.3048)
			(stroke
				(width 0.1)
				(type default)
			)
			(layer "F.Fab")
		)
		(fp_line
			(start -0.12065 -0.2794)
			(end 0.12065 -0.2794)
			(stroke
				(width 0.1)
				(type default)
			)
			(layer "F.Fab")
		)
		(fp_line
			(start 0.120396 0.2794)
			(end -0.12065 0.2794)
			(stroke
				(width 0.1)
				(type default)
			)
			(layer "F.Fab")
		)
		(fp_line
			(start -0.12065 0.2794)
			(end -0.12065 0.3048)
			(stroke
				(width 0.1)
				(type default)
			)
			(layer "F.Fab")
		)
		(fp_line
			(start 0.67945 0.3048)
			(end 0.120396 0.3048)
			(stroke
				(width 0.1)
				(type default)
			)
			(layer "F.Fab")
		)
		(fp_line
			(start 0.120396 0.3048)
			(end 0.120396 0.2794)
			(stroke
				(width 0.1)
				(type default)
			)
			(layer "F.Fab")
		)
		(fp_line
			(start -0.12065 0.3048)
			(end -0.67945 0.3048)
			(stroke
				(width 0.1)
				(type default)
			)
			(layer "F.Fab")
		)
		(fp_line
			(start -0.67945 0.3048)
			(end -0.67945 -0.305054)
			(stroke
				(width 0.1)
				(type default)
			)
			(layer "F.Fab")
		)
		(pad "1" smd circle
			(at -0.40005 0 90)
			(size 0 0)
			(layers "F.Cu" "F.Mask" "F.Paste")
			(net "SW_PVDDIO_P0_SW3_RC")
		)
		(pad "2" smd circle
			(at 0.40005 0 90)
			(size 0 0)
			(layers "F.Cu" "F.Mask" "F.Paste")
			(net "GND")
		)
	)
	(footprint ""
		(layer "F.Cu")
		(at 271.295876 -418.97173 90)
		(property "Reference" "R2585"
			(at 0 0 90)
			(layer "F.SilkS")
			(hide yes)
			(effects
				(font
					(size 1.27 1.27)
				)
			)
		)
		(property "Value" ""
			(at 0 0 90)
			(layer "F.Fab")
			(effects
				(font
					(size 1.27 1.27)
				)
			)
		)
		(duplicate_pad_numbers_are_jumpers no)
		(fp_line
			(start 0.7874 -0.4064)
			(end 0.7874 0.4064)
			(stroke
				(width 0.1524)
				(type default)
			)
			(layer "F.SilkS")
		)
		(fp_line
			(start -0.7874 -0.4064)
			(end 0.7874 -0.4064)
			(stroke
				(width 0.1524)
				(type default)
			)
			(layer "F.SilkS")
		)
		(fp_line
			(start 0.7874 0.4064)
			(end -0.7874 0.4064)
			(stroke
				(width 0.1524)
				(type default)
			)
			(layer "F.SilkS")
		)
		(fp_line
			(start -0.7874 0.4064)
			(end -0.7874 -0.4064)
			(stroke
				(width 0.1524)
				(type default)
			)
			(layer "F.SilkS")
		)
		(fp_line
			(start -0.12065 -0.305054)
			(end -0.12065 -0.2794)
			(stroke
				(width 0.1)
				(type default)
			)
			(layer "F.Fab")
		)
		(fp_line
			(start -0.67945 -0.305054)
			(end -0.12065 -0.305054)
			(stroke
				(width 0.1)
				(type default)
			)
			(layer "F.Fab")
		)
		(fp_line
			(start 0.67945 -0.3048)
			(end 0.67945 0.3048)
			(stroke
				(width 0.1)
				(type default)
			)
			(layer "F.Fab")
		)
		(fp_line
			(start 0.12065 -0.3048)
			(end 0.67945 -0.3048)
			(stroke
				(width 0.1)
				(type default)
			)
			(layer "F.Fab")
		)
		(fp_line
			(start 0.12065 -0.2794)
			(end 0.12065 -0.3048)
			(stroke
				(width 0.1)
				(type default)
			)
			(layer "F.Fab")
		)
		(fp_line
			(start -0.12065 -0.2794)
			(end 0.12065 -0.2794)
			(stroke
				(width 0.1)
				(type default)
			)
			(layer "F.Fab")
		)
		(fp_line
			(start 0.120396 0.2794)
			(end -0.12065 0.2794)
			(stroke
				(width 0.1)
				(type default)
			)
			(layer "F.Fab")
		)
		(fp_line
			(start -0.12065 0.2794)
			(end -0.12065 0.3048)
			(stroke
				(width 0.1)
				(type default)
			)
			(layer "F.Fab")
		)
		(fp_line
			(start 0.67945 0.3048)
			(end 0.120396 0.3048)
			(stroke
				(width 0.1)
				(type default)
			)
			(layer "F.Fab")
		)
		(fp_line
			(start 0.120396 0.3048)
			(end 0.120396 0.2794)
			(stroke
				(width 0.1)
				(type default)
			)
			(layer "F.Fab")
		)
		(fp_line
			(start -0.12065 0.3048)
			(end -0.67945 0.3048)
			(stroke
				(width 0.1)
				(type default)
			)
			(layer "F.Fab")
		)
		(fp_line
			(start -0.67945 0.3048)
			(end -0.67945 -0.305054)
			(stroke
				(width 0.1)
				(type default)
			)
			(layer "F.Fab")
		)
		(pad "1" smd circle
			(at -0.40005 0 90)
			(size 0 0)
			(layers "F.Cu" "F.Mask" "F.Paste")
			(net "HSC_EN")
		)
		(pad "2" smd circle
			(at 0.40005 0 90)
			(size 0 0)
			(layers "F.Cu" "F.Mask" "F.Paste")
			(net "GND")
		)
	)
	(footprint ""
		(layer "F.Cu")
		(at 171.196 -115.280948)
		(property "Reference" "R56"
			(at 0 0 0)
			(layer "F.SilkS")
			(hide yes)
			(effects
				(font
					(size 1.27 1.27)
				)
			)
		)
		(property "Value" ""
			(at 0 0 0)
			(layer "F.Fab")
			(effects
				(font
					(size 1.27 1.27)
				)
			)
		)
		(duplicate_pad_numbers_are_jumpers no)
		(fp_line
			(start -0.7874 -0.4064)
			(end 0.7874 -0.4064)
			(stroke
				(width 0.1524)
				(type default)
			)
			(layer "F.SilkS")
		)
		(fp_line
			(start -0.7874 0.4064)
			(end -0.7874 -0.4064)
			(stroke
				(width 0.1524)
				(type default)
			)
			(layer "F.SilkS")
		)
		(fp_line
			(start 0.7874 -0.4064)
			(end 0.7874 0.4064)
			(stroke
				(width 0.1524)
				(type default)
			)
			(layer "F.SilkS")
		)
		(fp_line
			(start 0.7874 0.4064)
			(end -0.7874 0.4064)
			(stroke
				(width 0.1524)
				(type default)
			)
			(layer "F.SilkS")
		)
		(fp_line
			(start -0.67945 -0.305054)
			(end -0.12065 -0.305054)
			(stroke
				(width 0.1)
				(type default)
			)
			(layer "F.Fab")
		)
		(fp_line
			(start -0.67945 0.3048)
			(end -0.67945 -0.305054)
			(stroke
				(width 0.1)
				(type default)
			)
			(layer "F.Fab")
		)
		(fp_line
			(start -0.12065 -0.305054)
			(end -0.12065 -0.2794)
			(stroke
				(width 0.1)
				(type default)
			)
			(layer "F.Fab")
		)
		(fp_line
			(start -0.12065 -0.2794)
			(end 0.12065 -0.2794)
			(stroke
				(width 0.1)
				(type default)
			)
			(layer "F.Fab")
		)
		(fp_line
			(start -0.12065 0.2794)
			(end -0.12065 0.3048)
			(stroke
				(width 0.1)
				(type default)
			)
			(layer "F.Fab")
		)
		(fp_line
			(start -0.12065 0.3048)
			(end -0.67945 0.3048)
			(stroke
				(width 0.1)
				(type default)
			)
			(layer "F.Fab")
		)
		(fp_line
			(start 0.120396 0.2794)
			(end -0.12065 0.2794)
			(stroke
				(width 0.1)
				(type default)
			)
			(layer "F.Fab")
		)
		(fp_line
			(start 0.120396 0.3048)
			(end 0.120396 0.2794)
			(stroke
				(width 0.1)
				(type default)
			)
			(layer "F.Fab")
		)
		(fp_line
			(start 0.12065 -0.3048)
			(end 0.67945 -0.3048)
			(stroke
				(width 0.1)
				(type default)
			)
			(layer "F.Fab")
		)
		(fp_line
			(start 0.12065 -0.2794)
			(end 0.12065 -0.3048)
			(stroke
				(width 0.1)
				(type default)
			)
			(layer "F.Fab")
		)
		(fp_line
			(start 0.67945 -0.3048)
			(end 0.67945 0.3048)
			(stroke
				(width 0.1)
				(type default)
			)
			(layer "F.Fab")
		)
		(fp_line
			(start 0.67945 0.3048)
			(end 0.120396 0.3048)
			(stroke
				(width 0.1)
				(type default)
			)
			(layer "F.Fab")
		)
		(pad "1" smd circle
			(at -0.40005 0)
			(size 0 0)
			(layers "F.Cu" "F.Mask" "F.Paste")
			(net "SMB_1_PLD_3V3AUX_SDA_R1")
		)
		(pad "2" smd circle
			(at 0.40005 0)
			(size 0 0)
			(layers "F.Cu" "F.Mask" "F.Paste")
			(net "SMB_1_PLD_3V3AUX_SDA_R2")
		)
	)
	(footprint ""
		(layer "F.Cu")
		(at 33.617662 -419.249098 90)
		(property "Reference" "R3275"
			(at 0 0 90)
			(layer "F.SilkS")
			(hide yes)
			(effects
				(font
					(size 1.27 1.27)
				)
			)
		)
		(property "Value" ""
			(at 0 0 90)
			(layer "F.Fab")
			(effects
				(font
					(size 1.27 1.27)
				)
			)
		)
		(duplicate_pad_numbers_are_jumpers no)
		(fp_line
			(start 0.7874 -0.4064)
			(end 0.7874 0.4064)
			(stroke
				(width 0.1524)
				(type default)
			)
			(layer "F.SilkS")
		)
		(fp_line
			(start -0.7874 -0.4064)
			(end 0.7874 -0.4064)
			(stroke
				(width 0.1524)
				(type default)
			)
			(layer "F.SilkS")
		)
		(fp_line
			(start 0.7874 0.4064)
			(end -0.7874 0.4064)
			(stroke
				(width 0.1524)
				(type default)
			)
			(layer "F.SilkS")
		)
		(fp_line
			(start -0.7874 0.4064)
			(end -0.7874 -0.4064)
			(stroke
				(width 0.1524)
				(type default)
			)
			(layer "F.SilkS")
		)
		(fp_line
			(start -0.12065 -0.305054)
			(end -0.12065 -0.2794)
			(stroke
				(width 0.1)
				(type default)
			)
			(layer "F.Fab")
		)
		(fp_line
			(start -0.67945 -0.305054)
			(end -0.12065 -0.305054)
			(stroke
				(width 0.1)
				(type default)
			)
			(layer "F.Fab")
		)
		(fp_line
			(start 0.67945 -0.3048)
			(end 0.67945 0.3048)
			(stroke
				(width 0.1)
				(type default)
			)
			(layer "F.Fab")
		)
		(fp_line
			(start 0.12065 -0.3048)
			(end 0.67945 -0.3048)
			(stroke
				(width 0.1)
				(type default)
			)
			(layer "F.Fab")
		)
		(fp_line
			(start 0.12065 -0.2794)
			(end 0.12065 -0.3048)
			(stroke
				(width 0.1)
				(type default)
			)
			(layer "F.Fab")
		)
		(fp_line
			(start -0.12065 -0.2794)
			(end 0.12065 -0.2794)
			(stroke
				(width 0.1)
				(type default)
			)
			(layer "F.Fab")
		)
		(fp_line
			(start 0.120396 0.2794)
			(end -0.12065 0.2794)
			(stroke
				(width 0.1)
				(type default)
			)
			(layer "F.Fab")
		)
		(fp_line
			(start -0.12065 0.2794)
			(end -0.12065 0.3048)
			(stroke
				(width 0.1)
				(type default)
			)
			(layer "F.Fab")
		)
		(fp_line
			(start 0.67945 0.3048)
			(end 0.120396 0.3048)
			(stroke
				(width 0.1)
				(type default)
			)
			(layer "F.Fab")
		)
		(fp_line
			(start 0.120396 0.3048)
			(end 0.120396 0.2794)
			(stroke
				(width 0.1)
				(type default)
			)
			(layer "F.Fab")
		)
		(fp_line
			(start -0.12065 0.3048)
			(end -0.67945 0.3048)
			(stroke
				(width 0.1)
				(type default)
			)
			(layer "F.Fab")
		)
		(fp_line
			(start -0.67945 0.3048)
			(end -0.67945 -0.305054)
			(stroke
				(width 0.1)
				(type default)
			)
			(layer "F.Fab")
		)
		(pad "1" smd circle
			(at -0.40005 0 90)
			(size 0 0)
			(layers "F.Cu" "F.Mask" "F.Paste")
			(net "P3V3_AUX")
		)
		(pad "2" smd circle
			(at 0.40005 0 90)
			(size 0 0)
			(layers "F.Cu" "F.Mask" "F.Paste")
			(net "FM_P2E_FGA")
		)
	)
	(footprint ""
		(layer "F.Cu")
		(at 243.37137 -291.761926)
		(property "Reference" "PU6500"
			(at 0.786384 -3.70332 0)
			(unlocked yes)
			(layer "F.SilkS")
			(effects
				(font
					(size 0.7874 0.5842)
					(thickness 0.1524)
				)
				(justify left)
			)
		)
		(property "Value" ""
			(at 0 0 0)
			(layer "F.Fab")
			(effects
				(font
					(size 1.27 1.27)
				)
			)
		)
		(duplicate_pad_numbers_are_jumpers no)
		(fp_line
			(start -1.549908 -2.050034)
			(end -1.549908 -1.9812)
			(stroke
				(width 0.1524)
				(type default)
			)
			(layer "F.SilkS")
		)
		(fp_line
			(start -1.549908 1.9812)
			(end -1.549908 2.050034)
			(stroke
				(width 0.1524)
				(type default)
			)
			(layer "F.SilkS")
		)
		(fp_line
			(start -1.549908 2.050034)
			(end -0.5842 2.050034)
			(stroke
				(width 0.1524)
				(type default)
			)
			(layer "F.SilkS")
		)
		(fp_line
			(start -0.5842 -2.050034)
			(end -1.549908 -2.050034)
			(stroke
				(width 0.1524)
				(type default)
			)
			(layer "F.SilkS")
		)
		(fp_line
			(start 0 2.050034)
			(end 1.549908 2.050034)
			(stroke
				(width 0.1524)
				(type default)
			)
			(layer "F.SilkS")
		)
		(fp_line
			(start 1.549908 -2.050034)
			(end 0.5842 -2.050034)
			(stroke
				(width 0.1524)
				(type default)
			)
			(layer "F.SilkS")
		)
		(fp_line
			(start 1.549908 -1.9812)
			(end 1.549908 -2.050034)
			(stroke
				(width 0.1524)
				(type default)
			)
			(layer "F.SilkS")
		)
		(fp_line
			(start 1.549908 2.050034)
			(end 1.549908 1.9304)
			(stroke
				(width 0.1524)
				(type default)
			)
			(layer "F.SilkS")
		)
		(fp_poly
			(pts
				(xy -2.9464 -2.208022) (xy -2.9464 -1.192022) (xy -1.9304 -1.700022)
			)
			(stroke
				(width 0)
				(type default)
			)
			(fill yes)
			(layer "F.SilkS")
		)
		(fp_line
			(start -1.549908 -2.050034)
			(end -1.549908 2.050034)
			(stroke
				(width 0.1)
				(type default)
			)
			(layer "F.Fab")
		)
		(fp_line
			(start -1.549908 2.050034)
			(end 1.549908 2.050034)
			(stroke
				(width 0.1)
				(type default)
			)
			(layer "F.Fab")
		)
		(fp_line
			(start 1.549908 -2.050034)
			(end -1.549908 -2.050034)
			(stroke
				(width 0.1)
				(type default)
			)
			(layer "F.Fab")
		)
		(fp_line
			(start 1.549908 2.050034)
			(end 1.549908 -2.050034)
			(stroke
				(width 0.1)
				(type default)
			)
			(layer "F.Fab")
		)
		(fp_poly
			(pts
				(xy -2.9464 -2.208022) (xy -2.9464 -1.192022) (xy -1.9304 -1.700022)
			)
			(stroke
				(width 0)
				(type default)
			)
			(fill yes)
			(layer "F.Fab")
		)
		(pad "1" smd circle
			(at -1.35001 -1.700022)
			(size 0 0)
			(layers "F.Cu" "F.Mask" "F.Paste")
			(net "SW_P1V8_RETIMER_CPU0_BST")
		)
		(pad "2" smd rect
			(at -1.400048 -1.199896 90)
			(size 0.1778 0.8128)
			(layers "F.Cu" "F.Mask" "F.Paste")
			(net "GND")
		)
		(pad "3" smd rect
			(at -1.400048 -0.8001 90)
			(size 0.1778 0.8128)
			(layers "F.Cu" "F.Mask" "F.Paste")
			(net "P1V8_RETIMER_CPU0_CS")
		)
		(pad "4" smd rect
			(at -1.400048 -0.40005 90)
			(size 0.1778 0.8128)
			(layers "F.Cu" "F.Mask" "F.Paste")
			(net "P1V8_RETIMER_CPU0_MODE")
		)
		(pad "5" smd rect
			(at -1.400048 0 90)
			(size 0.1778 0.8128)
			(layers "F.Cu" "F.Mask" "F.Paste")
			(net "P1V8_RETIMER_CPU0_REF")
		)
		(pad "6" smd rect
			(at -1.400048 0.40005 90)
			(size 0.1778 0.8128)
			(layers "F.Cu" "F.Mask" "F.Paste")
			(net "GND")
		)
		(pad "7" smd rect
			(at -1.400048 0.8001 90)
			(size 0.1778 0.8128)
			(layers "F.Cu" "F.Mask" "F.Paste")
			(net "P1V8_RETIMER_CPU0_FB")
		)
		(pad "8" smd rect
			(at -1.400048 1.199896 90)
			(size 0.1778 0.8128)
			(layers "F.Cu" "F.Mask" "F.Paste")
			(net "P1V8_RETIMER_CPU0_EN")
		)
		(pad "9" smd rect
			(at -1.400048 1.700022 90)
			(size 0.3048 0.8128)
			(layers "F.Cu" "F.Mask" "F.Paste")
			(net "PWRGD_P1V8_RETIMER_CPU0")
		)
		(pad "10" smd rect
			(at -0.299974 1.299972)
			(size 0.3048 2.0066)
			(layers "F.Cu" "F.Mask" "F.Paste")
			(net "SW_P12V_AUX_P1V8_RETIMER_CPU0_FLT")
		)
		(pad "11_18" smd circle
			(at 1.175004 0.275082)
			(size 0 0)
			(layers "F.Cu" "F.Mask" "F.Paste")
			(net "GND")
		)
		(pad "19" smd rect
			(at 1.400048 -1.700022 270)
			(size 0.3048 0.8128)
			(layers "F.Cu" "F.Mask" "F.Paste")
			(net "P1V8_RETIMER_CPU0_VCC")
		)
		(pad "20" smd rect
			(at 0.299974 -1.299972)
			(size 0.3048 2.0066)
			(layers "F.Cu" "F.Mask" "F.Paste")
			(net "SW_P1V8_RETIMER_CPU0_SW")
		)
		(pad "21" smd rect
			(at -0.299974 -1.299972)
			(size 0.3048 2.0066)
			(layers "F.Cu" "F.Mask" "F.Paste")
			(net "SW_P12V_AUX_P1V8_RETIMER_CPU0_FLT")
		)
	)
	(footprint ""
		(layer "F.Cu")
		(at 177.81016 -390.2075)
		(property "Reference" "R1426"
			(at 0 0 0)
			(layer "F.SilkS")
			(hide yes)
			(effects
				(font
					(size 1.27 1.27)
				)
			)
		)
		(property "Value" ""
			(at 0 0 0)
			(layer "F.Fab")
			(effects
				(font
					(size 1.27 1.27)
				)
			)
		)
		(duplicate_pad_numbers_are_jumpers no)
		(fp_line
			(start -0.32512 -0.175006)
			(end 0.32512 -0.175006)
			(stroke
				(width 0.1)
				(type default)
			)
			(layer "F.Fab")
		)
		(fp_line
			(start -0.32512 0.175006)
			(end -0.32512 -0.175006)
			(stroke
				(width 0.1)
				(type default)
			)
			(layer "F.Fab")
		)
		(fp_line
			(start 0.32512 -0.175006)
			(end 0.32512 0.175006)
			(stroke
				(width 0.1)
				(type default)
			)
			(layer "F.Fab")
		)
		(fp_line
			(start 0.32512 0.175006)
			(end -0.32512 0.175006)
			(stroke
				(width 0.1)
				(type default)
			)
			(layer "F.Fab")
		)
		(pad "1" smd rect
			(at -0.2667 0)
			(size 0.3048 0.381)
			(layers "F.Cu" "F.Mask" "F.Paste")
			(net "P1V8_CPU1_RT_1D")
		)
		(pad "2" smd rect
			(at 0.2667 0 180)
			(size 0.3048 0.381)
			(layers "F.Cu" "F.Mask" "F.Paste")
			(net "RXDET_BYP_RT_CPU1_P2")
		)
	)
	(footprint ""
		(layer "F.Cu")
		(at 356.29596 -258.795012)
		(property "Reference" "C3899"
			(at 0 0 0)
			(layer "F.SilkS")
			(hide yes)
			(effects
				(font
					(size 1.27 1.27)
				)
			)
		)
		(property "Value" ""
			(at 0 0 0)
			(layer "F.Fab")
			(effects
				(font
					(size 1.27 1.27)
				)
			)
		)
		(duplicate_pad_numbers_are_jumpers no)
		(fp_line
			(start -0.7874 -0.4064)
			(end 0.7874 -0.4064)
			(stroke
				(width 0.1524)
				(type default)
			)
			(layer "F.SilkS")
		)
		(fp_line
			(start -0.7874 0.4064)
			(end -0.7874 -0.4064)
			(stroke
				(width 0.1524)
				(type default)
			)
			(layer "F.SilkS")
		)
		(fp_line
			(start 0.7874 -0.4064)
			(end 0.7874 0.4064)
			(stroke
				(width 0.1524)
				(type default)
			)
			(layer "F.SilkS")
		)
		(fp_line
			(start 0.7874 0.4064)
			(end -0.7874 0.4064)
			(stroke
				(width 0.1524)
				(type default)
			)
			(layer "F.SilkS")
		)
		(fp_line
			(start -0.67945 -0.305054)
			(end -0.12065 -0.305054)
			(stroke
				(width 0.1)
				(type default)
			)
			(layer "F.Fab")
		)
		(fp_line
			(start -0.67945 0.3048)
			(end -0.67945 -0.305054)
			(stroke
				(width 0.1)
				(type default)
			)
			(layer "F.Fab")
		)
		(fp_line
			(start -0.12065 -0.305054)
			(end -0.12065 -0.2794)
			(stroke
				(width 0.1)
				(type default)
			)
			(layer "F.Fab")
		)
		(fp_line
			(start -0.12065 -0.2794)
			(end 0.12065 -0.2794)
			(stroke
				(width 0.1)
				(type default)
			)
			(layer "F.Fab")
		)
		(fp_line
			(start -0.12065 0.2794)
			(end -0.12065 0.3048)
			(stroke
				(width 0.1)
				(type default)
			)
			(layer "F.Fab")
		)
		(fp_line
			(start -0.12065 0.3048)
			(end -0.67945 0.3048)
			(stroke
				(width 0.1)
				(type default)
			)
			(layer "F.Fab")
		)
		(fp_line
			(start 0.120396 0.2794)
			(end -0.12065 0.2794)
			(stroke
				(width 0.1)
				(type default)
			)
			(layer "F.Fab")
		)
		(fp_line
			(start 0.120396 0.3048)
			(end 0.120396 0.2794)
			(stroke
				(width 0.1)
				(type default)
			)
			(layer "F.Fab")
		)
		(fp_line
			(start 0.12065 -0.3048)
			(end 0.67945 -0.3048)
			(stroke
				(width 0.1)
				(type default)
			)
			(layer "F.Fab")
		)
		(fp_line
			(start 0.12065 -0.2794)
			(end 0.12065 -0.3048)
			(stroke
				(width 0.1)
				(type default)
			)
			(layer "F.Fab")
		)
		(fp_line
			(start 0.67945 -0.3048)
			(end 0.67945 0.3048)
			(stroke
				(width 0.1)
				(type default)
			)
			(layer "F.Fab")
		)
		(fp_line
			(start 0.67945 0.3048)
			(end 0.120396 0.3048)
			(stroke
				(width 0.1)
				(type default)
			)
			(layer "F.Fab")
		)
		(pad "1" smd circle
			(at -0.40005 0)
			(size 0 0)
			(layers "F.Cu" "F.Mask" "F.Paste")
			(net "PVDDIO_P0")
		)
		(pad "2" smd circle
			(at 0.40005 0)
			(size 0 0)
			(layers "F.Cu" "F.Mask" "F.Paste")
			(net "GND")
		)
	)
	(footprint ""
		(layer "F.Cu")
		(at 138.426952 -57.516014 180)
		(property "Reference" "R6102"
			(at 0 0 180)
			(layer "F.SilkS")
			(hide yes)
			(effects
				(font
					(size 1.27 1.27)
				)
			)
		)
		(property "Value" ""
			(at 0 0 180)
			(layer "F.Fab")
			(effects
				(font
					(size 1.27 1.27)
				)
			)
		)
		(duplicate_pad_numbers_are_jumpers no)
		(fp_line
			(start 0.7874 0.4064)
			(end -0.7874 0.4064)
			(stroke
				(width 0.1524)
				(type default)
			)
			(layer "F.SilkS")
		)
		(fp_line
			(start 0.7874 -0.4064)
			(end 0.7874 0.4064)
			(stroke
				(width 0.1524)
				(type default)
			)
			(layer "F.SilkS")
		)
		(fp_line
			(start -0.7874 0.4064)
			(end -0.7874 -0.4064)
			(stroke
				(width 0.1524)
				(type default)
			)
			(layer "F.SilkS")
		)
		(fp_line
			(start -0.7874 -0.4064)
			(end 0.7874 -0.4064)
			(stroke
				(width 0.1524)
				(type default)
			)
			(layer "F.SilkS")
		)
		(fp_line
			(start 0.67945 0.3048)
			(end 0.120396 0.3048)
			(stroke
				(width 0.1)
				(type default)
			)
			(layer "F.Fab")
		)
		(fp_line
			(start 0.67945 -0.3048)
			(end 0.67945 0.3048)
			(stroke
				(width 0.1)
				(type default)
			)
			(layer "F.Fab")
		)
		(fp_line
			(start 0.12065 -0.2794)
			(end 0.12065 -0.3048)
			(stroke
				(width 0.1)
				(type default)
			)
			(layer "F.Fab")
		)
		(fp_line
			(start 0.12065 -0.3048)
			(end 0.67945 -0.3048)
			(stroke
				(width 0.1)
				(type default)
			)
			(layer "F.Fab")
		)
		(fp_line
			(start 0.120396 0.3048)
			(end 0.120396 0.2794)
			(stroke
				(width 0.1)
				(type default)
			)
			(layer "F.Fab")
		)
		(fp_line
			(start 0.120396 0.2794)
			(end -0.12065 0.2794)
			(stroke
				(width 0.1)
				(type default)
			)
			(layer "F.Fab")
		)
		(fp_line
			(start -0.12065 0.3048)
			(end -0.67945 0.3048)
			(stroke
				(width 0.1)
				(type default)
			)
			(layer "F.Fab")
		)
		(fp_line
			(start -0.12065 0.2794)
			(end -0.12065 0.3048)
			(stroke
				(width 0.1)
				(type default)
			)
			(layer "F.Fab")
		)
		(fp_line
			(start -0.12065 -0.2794)
			(end 0.12065 -0.2794)
			(stroke
				(width 0.1)
				(type default)
			)
			(layer "F.Fab")
		)
		(fp_line
			(start -0.12065 -0.305054)
			(end -0.12065 -0.2794)
			(stroke
				(width 0.1)
				(type default)
			)
			(layer "F.Fab")
		)
		(fp_line
			(start -0.67945 0.3048)
			(end -0.67945 -0.305054)
			(stroke
				(width 0.1)
				(type default)
			)
			(layer "F.Fab")
		)
		(fp_line
			(start -0.67945 -0.305054)
			(end -0.12065 -0.305054)
			(stroke
				(width 0.1)
				(type default)
			)
			(layer "F.Fab")
		)
		(pad "1" smd circle
			(at -0.40005 0 180)
			(size 0 0)
			(layers "F.Cu" "F.Mask" "F.Paste")
			(net "SCM_JTAG_MUX_S0")
		)
		(pad "2" smd circle
			(at 0.40005 0 180)
			(size 0 0)
			(layers "F.Cu" "F.Mask" "F.Paste")
			(net "SCM_JTAG_MUX_S0_R2")
		)
	)
	(footprint ""
		(layer "F.Cu")
		(at 215.74379 -390.377934 90)
		(property "Reference" "PD111"
			(at 1.8034 -3.343148 90)
			(unlocked yes)
			(layer "F.SilkS")
			(effects
				(font
					(size 0.7874 0.5842)
					(thickness 0.1524)
				)
			)
		)
		(property "Value" ""
			(at 0 0 90)
			(layer "F.Fab")
			(effects
				(font
					(size 1.27 1.27)
				)
			)
		)
		(duplicate_pad_numbers_are_jumpers no)
		(fp_line
			(start 3.541776 -2.54)
			(end 3.541776 2.54)
			(stroke
				(width 0.1524)
				(type default)
			)
			(layer "F.SilkS")
		)
		(fp_line
			(start -3.539744 -2.54)
			(end 3.541776 -2.54)
			(stroke
				(width 0.1524)
				(type default)
			)
			(layer "F.SilkS")
		)
		(fp_line
			(start 3.541776 2.54)
			(end -3.539744 2.54)
			(stroke
				(width 0.1524)
				(type default)
			)
			(layer "F.SilkS")
		)
		(fp_line
			(start -3.539744 2.54)
			(end -3.539744 -2.54)
			(stroke
				(width 0.1524)
				(type default)
			)
			(layer "F.SilkS")
		)
		(fp_poly
			(pts
				(xy -5.651246 1.802892) (xy -5.651246 0.786892) (xy -4.635246 1.294892)
			)
			(stroke
				(width 0)
				(type default)
			)
			(fill yes)
			(layer "F.SilkS")
		)
		(fp_line
			(start 3.074924 -2.175002)
			(end 3.074924 2.175002)
			(stroke
				(width 0.1)
				(type default)
			)
			(layer "F.Fab")
		)
		(fp_line
			(start -3.074924 -2.175002)
			(end 3.074924 -2.175002)
			(stroke
				(width 0.1)
				(type default)
			)
			(layer "F.Fab")
		)
		(fp_line
			(start 3.074924 2.175002)
			(end -3.074924 2.175002)
			(stroke
				(width 0.1)
				(type default)
			)
			(layer "F.Fab")
		)
		(fp_line
			(start -3.074924 2.175002)
			(end -3.074924 -2.175002)
			(stroke
				(width 0.1)
				(type default)
			)
			(layer "F.Fab")
		)
		(fp_poly
			(pts
				(xy -4.699 0.531876) (xy -4.699 1.547876) (xy -3.683 1.039876)
			)
			(stroke
				(width 0)
				(type default)
			)
			(fill yes)
			(layer "F.Fab")
		)
		(pad "1" smd rect
			(at -2.765044 1.039876 270)
			(size 1.27 1.4224)
			(layers "F.Cu" "F.Mask" "F.Paste")
			(net "GND")
		)
		(pad "2" smd rect
			(at -2.765044 -1.039876 270)
			(size 1.27 1.4224)
			(layers "F.Cu" "F.Mask" "F.Paste")
			(net "GND")
		)
		(pad "K" smd rect
			(at 1.039876 0 270)
			(size 4.7244 4.8006)
			(layers "F.Cu" "F.Mask" "F.Paste")
			(net "P12V_AUX")
		)
	)
	(footprint ""
		(layer "F.Cu")
		(at 393.086336 -184.478168 -90)
		(property "Reference" "PR499"
			(at 0 0 270)
			(layer "F.SilkS")
			(hide yes)
			(effects
				(font
					(size 1.27 1.27)
				)
			)
		)
		(property "Value" ""
			(at 0 0 270)
			(layer "F.Fab")
			(effects
				(font
					(size 1.27 1.27)
				)
			)
		)
		(duplicate_pad_numbers_are_jumpers no)
		(fp_line
			(start -0.7874 0.4064)
			(end -0.7874 -0.4064)
			(stroke
				(width 0.1524)
				(type default)
			)
			(layer "F.SilkS")
		)
		(fp_line
			(start 0.7874 0.4064)
			(end -0.7874 0.4064)
			(stroke
				(width 0.1524)
				(type default)
			)
			(layer "F.SilkS")
		)
		(fp_line
			(start -0.7874 -0.4064)
			(end 0.7874 -0.4064)
			(stroke
				(width 0.1524)
				(type default)
			)
			(layer "F.SilkS")
		)
		(fp_line
			(start 0.7874 -0.4064)
			(end 0.7874 0.4064)
			(stroke
				(width 0.1524)
				(type default)
			)
			(layer "F.SilkS")
		)
		(fp_line
			(start -0.67945 0.3048)
			(end -0.67945 -0.305054)
			(stroke
				(width 0.1)
				(type default)
			)
			(layer "F.Fab")
		)
		(fp_line
			(start -0.12065 0.3048)
			(end -0.67945 0.3048)
			(stroke
				(width 0.1)
				(type default)
			)
			(layer "F.Fab")
		)
		(fp_line
			(start 0.120396 0.3048)
			(end 0.120396 0.2794)
			(stroke
				(width 0.1)
				(type default)
			)
			(layer "F.Fab")
		)
		(fp_line
			(start 0.67945 0.3048)
			(end 0.120396 0.3048)
			(stroke
				(width 0.1)
				(type default)
			)
			(layer "F.Fab")
		)
		(fp_line
			(start -0.12065 0.2794)
			(end -0.12065 0.3048)
			(stroke
				(width 0.1)
				(type default)
			)
			(layer "F.Fab")
		)
		(fp_line
			(start 0.120396 0.2794)
			(end -0.12065 0.2794)
			(stroke
				(width 0.1)
				(type default)
			)
			(layer "F.Fab")
		)
		(fp_line
			(start -0.12065 -0.2794)
			(end 0.12065 -0.2794)
			(stroke
				(width 0.1)
				(type default)
			)
			(layer "F.Fab")
		)
		(fp_line
			(start 0.12065 -0.2794)
			(end 0.12065 -0.3048)
			(stroke
				(width 0.1)
				(type default)
			)
			(layer "F.Fab")
		)
		(fp_line
			(start 0.12065 -0.3048)
			(end 0.67945 -0.3048)
			(stroke
				(width 0.1)
				(type default)
			)
			(layer "F.Fab")
		)
		(fp_line
			(start 0.67945 -0.3048)
			(end 0.67945 0.3048)
			(stroke
				(width 0.1)
				(type default)
			)
			(layer "F.Fab")
		)
		(fp_line
			(start -0.67945 -0.305054)
			(end -0.12065 -0.305054)
			(stroke
				(width 0.1)
				(type default)
			)
			(layer "F.Fab")
		)
		(fp_line
			(start -0.12065 -0.305054)
			(end -0.12065 -0.2794)
			(stroke
				(width 0.1)
				(type default)
			)
			(layer "F.Fab")
		)
		(pad "1" smd circle
			(at -0.40005 0 270)
			(size 0 0)
			(layers "F.Cu" "F.Mask" "F.Paste")
			(net "SW_PVDDCR_CPU0_P0_SW4_RC")
		)
		(pad "2" smd circle
			(at 0.40005 0 270)
			(size 0 0)
			(layers "F.Cu" "F.Mask" "F.Paste")
			(net "GND")
		)
	)
	(footprint ""
		(layer "F.Cu")
		(at 401.501102 -416.899344 -90)
		(property "Reference" "C6586"
			(at 0 0 270)
			(layer "F.SilkS")
			(hide yes)
			(effects
				(font
					(size 1.27 1.27)
				)
			)
		)
		(property "Value" ""
			(at 0 0 270)
			(layer "F.Fab")
			(effects
				(font
					(size 1.27 1.27)
				)
			)
		)
		(duplicate_pad_numbers_are_jumpers no)
		(fp_line
			(start -0.299974 0.150114)
			(end -0.299974 -0.150114)
			(stroke
				(width 0.1)
				(type default)
			)
			(layer "F.Fab")
		)
		(fp_line
			(start 0.299974 0.150114)
			(end -0.299974 0.150114)
			(stroke
				(width 0.1)
				(type default)
			)
			(layer "F.Fab")
		)
		(fp_line
			(start -0.299974 -0.150114)
			(end 0.299974 -0.150114)
			(stroke
				(width 0.1)
				(type default)
			)
			(layer "F.Fab")
		)
		(fp_line
			(start 0.299974 -0.150114)
			(end 0.299974 0.150114)
			(stroke
				(width 0.1)
				(type default)
			)
			(layer "F.Fab")
		)
		(pad "1" smd rect
			(at -0.2667 0 270)
			(size 0.3048 0.381)
			(layers "F.Cu" "F.Mask" "F.Paste")
			(net "P5E_CPU0_P2_TX_BUF_C_DN<10>")
		)
		(pad "2" smd rect
			(at 0.2667 0 270)
			(size 0.3048 0.381)
			(layers "F.Cu" "F.Mask" "F.Paste")
			(net "P5E_CPU0_P2_TX_BUF_DN<10>")
		)
	)
	(footprint ""
		(layer "F.Cu")
		(at 110.067344 -382.39446 180)
		(property "Reference" "C1547"
			(at 0 0 180)
			(layer "F.SilkS")
			(hide yes)
			(effects
				(font
					(size 1.27 1.27)
				)
			)
		)
		(property "Value" ""
			(at 0 0 180)
			(layer "F.Fab")
			(effects
				(font
					(size 1.27 1.27)
				)
			)
		)
		(duplicate_pad_numbers_are_jumpers no)
		(fp_line
			(start 0.299974 0.150114)
			(end -0.299974 0.150114)
			(stroke
				(width 0.1)
				(type default)
			)
			(layer "F.Fab")
		)
		(fp_line
			(start 0.299974 -0.150114)
			(end 0.299974 0.150114)
			(stroke
				(width 0.1)
				(type default)
			)
			(layer "F.Fab")
		)
		(fp_line
			(start -0.299974 0.150114)
			(end -0.299974 -0.150114)
			(stroke
				(width 0.1)
				(type default)
			)
			(layer "F.Fab")
		)
		(fp_line
			(start -0.299974 -0.150114)
			(end 0.299974 -0.150114)
			(stroke
				(width 0.1)
				(type default)
			)
			(layer "F.Fab")
		)
		(pad "1" smd rect
			(at -0.2667 0 180)
			(size 0.3048 0.381)
			(layers "F.Cu" "F.Mask" "F.Paste")
			(net "P5E_CPU1_P3_TX_C_DP<0>")
		)
		(pad "2" smd rect
			(at 0.2667 0 180)
			(size 0.3048 0.381)
			(layers "F.Cu" "F.Mask" "F.Paste")
			(net "P5E_CPU1_P3_TX_DP<0>")
		)
	)
	(footprint ""
		(layer "F.Cu")
		(at 97.074736 -119.469154 90)
		(property "Reference" "C5014"
			(at 0 0 90)
			(layer "F.SilkS")
			(hide yes)
			(effects
				(font
					(size 1.27 1.27)
				)
			)
		)
		(property "Value" ""
			(at 0 0 90)
			(layer "F.Fab")
			(effects
				(font
					(size 1.27 1.27)
				)
			)
		)
		(duplicate_pad_numbers_are_jumpers no)
		(fp_line
			(start 0.7874 -0.4064)
			(end 0.7874 0.4064)
			(stroke
				(width 0.1524)
				(type default)
			)
			(layer "F.SilkS")
		)
		(fp_line
			(start -0.7874 -0.4064)
			(end 0.7874 -0.4064)
			(stroke
				(width 0.1524)
				(type default)
			)
			(layer "F.SilkS")
		)
		(fp_line
			(start 0.7874 0.4064)
			(end -0.7874 0.4064)
			(stroke
				(width 0.1524)
				(type default)
			)
			(layer "F.SilkS")
		)
		(fp_line
			(start -0.7874 0.4064)
			(end -0.7874 -0.4064)
			(stroke
				(width 0.1524)
				(type default)
			)
			(layer "F.SilkS")
		)
		(fp_line
			(start -0.12065 -0.305054)
			(end -0.12065 -0.2794)
			(stroke
				(width 0.1)
				(type default)
			)
			(layer "F.Fab")
		)
		(fp_line
			(start -0.67945 -0.305054)
			(end -0.12065 -0.305054)
			(stroke
				(width 0.1)
				(type default)
			)
			(layer "F.Fab")
		)
		(fp_line
			(start 0.67945 -0.3048)
			(end 0.67945 0.3048)
			(stroke
				(width 0.1)
				(type default)
			)
			(layer "F.Fab")
		)
		(fp_line
			(start 0.12065 -0.3048)
			(end 0.67945 -0.3048)
			(stroke
				(width 0.1)
				(type default)
			)
			(layer "F.Fab")
		)
		(fp_line
			(start 0.12065 -0.2794)
			(end 0.12065 -0.3048)
			(stroke
				(width 0.1)
				(type default)
			)
			(layer "F.Fab")
		)
		(fp_line
			(start -0.12065 -0.2794)
			(end 0.12065 -0.2794)
			(stroke
				(width 0.1)
				(type default)
			)
			(layer "F.Fab")
		)
		(fp_line
			(start 0.120396 0.2794)
			(end -0.12065 0.2794)
			(stroke
				(width 0.1)
				(type default)
			)
			(layer "F.Fab")
		)
		(fp_line
			(start -0.12065 0.2794)
			(end -0.12065 0.3048)
			(stroke
				(width 0.1)
				(type default)
			)
			(layer "F.Fab")
		)
		(fp_line
			(start 0.67945 0.3048)
			(end 0.120396 0.3048)
			(stroke
				(width 0.1)
				(type default)
			)
			(layer "F.Fab")
		)
		(fp_line
			(start 0.120396 0.3048)
			(end 0.120396 0.2794)
			(stroke
				(width 0.1)
				(type default)
			)
			(layer "F.Fab")
		)
		(fp_line
			(start -0.12065 0.3048)
			(end -0.67945 0.3048)
			(stroke
				(width 0.1)
				(type default)
			)
			(layer "F.Fab")
		)
		(fp_line
			(start -0.67945 0.3048)
			(end -0.67945 -0.305054)
			(stroke
				(width 0.1)
				(type default)
			)
			(layer "F.Fab")
		)
		(pad "1" smd circle
			(at -0.40005 0 90)
			(size 0 0)
			(layers "F.Cu" "F.Mask" "F.Paste")
			(net "PWRGD_P12V_MEM_R")
		)
		(pad "2" smd circle
			(at 0.40005 0 90)
			(size 0 0)
			(layers "F.Cu" "F.Mask" "F.Paste")
			(net "GND")
		)
	)
	(footprint ""
		(layer "F.Cu")
		(at 234.771946 -141.805152)
		(property "Reference" "Q63"
			(at -3.24866 -1.300988 0)
			(unlocked yes)
			(layer "F.SilkS")
			(effects
				(font
					(size 0.7874 0.5842)
					(thickness 0.1524)
				)
			)
		)
		(property "Value" ""
			(at 0 0 0)
			(layer "F.Fab")
			(effects
				(font
					(size 1.27 1.27)
				)
			)
		)
		(duplicate_pad_numbers_are_jumpers no)
		(fp_line
			(start -1.949958 -1.610106)
			(end 1.949958 -1.610106)
			(stroke
				(width 0.1524)
				(type default)
			)
			(layer "F.SilkS")
		)
		(fp_line
			(start -1.949958 1.610106)
			(end -1.949958 -1.610106)
			(stroke
				(width 0.1524)
				(type default)
			)
			(layer "F.SilkS")
		)
		(fp_line
			(start 1.949958 -1.560068)
			(end 1.949958 1.610106)
			(stroke
				(width 0.1524)
				(type default)
			)
			(layer "F.SilkS")
		)
		(fp_line
			(start 1.949958 1.610106)
			(end -1.949958 1.610106)
			(stroke
				(width 0.1524)
				(type default)
			)
			(layer "F.SilkS")
		)
		(fp_line
			(start -0.750062 -1.560068)
			(end 0.750062 -1.560068)
			(stroke
				(width 0.1)
				(type default)
			)
			(layer "F.Fab")
		)
		(fp_line
			(start -0.750062 1.560068)
			(end -0.750062 -1.560068)
			(stroke
				(width 0.1)
				(type default)
			)
			(layer "F.Fab")
		)
		(fp_line
			(start 0.750062 -1.560068)
			(end 0.750062 1.560068)
			(stroke
				(width 0.1)
				(type default)
			)
			(layer "F.Fab")
		)
		(fp_line
			(start 0.750062 1.560068)
			(end -0.750062 1.560068)
			(stroke
				(width 0.1)
				(type default)
			)
			(layer "F.Fab")
		)
		(pad "D" smd rect
			(at 1.100074 0 270)
			(size 1.016 1.4224)
			(layers "F.Cu" "F.Mask" "F.Paste")
			(net "FM_PLD_CPU0_PRSNT_HDT_N")
		)
		(pad "G" smd rect
			(at -1.100074 -0.94996 270)
			(size 1.016 1.4224)
			(layers "F.Cu" "F.Mask" "F.Paste")
			(net "CPU0_HDT_BYPASS_SEL")
		)
		(pad "S" smd rect
			(at -1.100074 0.94996 270)
			(size 1.016 1.4224)
			(layers "F.Cu" "F.Mask" "F.Paste")
			(net "GND")
		)
	)
	(footprint ""
		(layer "F.Cu")
		(at 441.31103 -394.302234 180)
		(property "Reference" "PC6564"
			(at 0 0 180)
			(layer "F.SilkS")
			(hide yes)
			(effects
				(font
					(size 1.27 1.27)
				)
			)
		)
		(property "Value" ""
			(at 0 0 180)
			(layer "F.Fab")
			(effects
				(font
					(size 1.27 1.27)
				)
			)
		)
		(duplicate_pad_numbers_are_jumpers no)
		(fp_line
			(start 0.7874 0.4064)
			(end -0.7874 0.4064)
			(stroke
				(width 0.1524)
				(type default)
			)
			(layer "F.SilkS")
		)
		(fp_line
			(start 0.7874 -0.4064)
			(end 0.7874 0.4064)
			(stroke
				(width 0.1524)
				(type default)
			)
			(layer "F.SilkS")
		)
		(fp_line
			(start -0.7874 0.4064)
			(end -0.7874 -0.4064)
			(stroke
				(width 0.1524)
				(type default)
			)
			(layer "F.SilkS")
		)
		(fp_line
			(start -0.7874 -0.4064)
			(end 0.7874 -0.4064)
			(stroke
				(width 0.1524)
				(type default)
			)
			(layer "F.SilkS")
		)
		(fp_line
			(start 0.67945 0.3048)
			(end 0.120396 0.3048)
			(stroke
				(width 0.1)
				(type default)
			)
			(layer "F.Fab")
		)
		(fp_line
			(start 0.67945 -0.3048)
			(end 0.67945 0.3048)
			(stroke
				(width 0.1)
				(type default)
			)
			(layer "F.Fab")
		)
		(fp_line
			(start 0.12065 -0.2794)
			(end 0.12065 -0.3048)
			(stroke
				(width 0.1)
				(type default)
			)
			(layer "F.Fab")
		)
		(fp_line
			(start 0.12065 -0.3048)
			(end 0.67945 -0.3048)
			(stroke
				(width 0.1)
				(type default)
			)
			(layer "F.Fab")
		)
		(fp_line
			(start 0.120396 0.3048)
			(end 0.120396 0.2794)
			(stroke
				(width 0.1)
				(type default)
			)
			(layer "F.Fab")
		)
		(fp_line
			(start 0.120396 0.2794)
			(end -0.12065 0.2794)
			(stroke
				(width 0.1)
				(type default)
			)
			(layer "F.Fab")
		)
		(fp_line
			(start -0.12065 0.3048)
			(end -0.67945 0.3048)
			(stroke
				(width 0.1)
				(type default)
			)
			(layer "F.Fab")
		)
		(fp_line
			(start -0.12065 0.2794)
			(end -0.12065 0.3048)
			(stroke
				(width 0.1)
				(type default)
			)
			(layer "F.Fab")
		)
		(fp_line
			(start -0.12065 -0.2794)
			(end 0.12065 -0.2794)
			(stroke
				(width 0.1)
				(type default)
			)
			(layer "F.Fab")
		)
		(fp_line
			(start -0.12065 -0.305054)
			(end -0.12065 -0.2794)
			(stroke
				(width 0.1)
				(type default)
			)
			(layer "F.Fab")
		)
		(fp_line
			(start -0.67945 0.3048)
			(end -0.67945 -0.305054)
			(stroke
				(width 0.1)
				(type default)
			)
			(layer "F.Fab")
		)
		(fp_line
			(start -0.67945 -0.305054)
			(end -0.12065 -0.305054)
			(stroke
				(width 0.1)
				(type default)
			)
			(layer "F.Fab")
		)
		(pad "1" smd circle
			(at -0.40005 0 180)
			(size 0 0)
			(layers "F.Cu" "F.Mask" "F.Paste")
			(net "SW_P0V9_RETIMER_CPU0_SW1")
		)
		(pad "2" smd circle
			(at 0.40005 0 180)
			(size 0 0)
			(layers "F.Cu" "F.Mask" "F.Paste")
			(net "SW_P0V9_RETIMER_CPU0_SW1_RC")
		)
	)
	(footprint ""
		(layer "F.Cu")
		(at 94.358968 -184.410096 -90)
		(property "Reference" "PR486"
			(at 0 0 270)
			(layer "F.SilkS")
			(hide yes)
			(effects
				(font
					(size 1.27 1.27)
				)
			)
		)
		(property "Value" ""
			(at 0 0 270)
			(layer "F.Fab")
			(effects
				(font
					(size 1.27 1.27)
				)
			)
		)
		(duplicate_pad_numbers_are_jumpers no)
		(fp_line
			(start -0.7874 0.4064)
			(end -0.7874 -0.4064)
			(stroke
				(width 0.1524)
				(type default)
			)
			(layer "F.SilkS")
		)
		(fp_line
			(start 0.7874 0.4064)
			(end -0.7874 0.4064)
			(stroke
				(width 0.1524)
				(type default)
			)
			(layer "F.SilkS")
		)
		(fp_line
			(start -0.7874 -0.4064)
			(end 0.7874 -0.4064)
			(stroke
				(width 0.1524)
				(type default)
			)
			(layer "F.SilkS")
		)
		(fp_line
			(start 0.7874 -0.4064)
			(end 0.7874 0.4064)
			(stroke
				(width 0.1524)
				(type default)
			)
			(layer "F.SilkS")
		)
		(fp_line
			(start -0.67945 0.3048)
			(end -0.67945 -0.305054)
			(stroke
				(width 0.1)
				(type default)
			)
			(layer "F.Fab")
		)
		(fp_line
			(start -0.12065 0.3048)
			(end -0.67945 0.3048)
			(stroke
				(width 0.1)
				(type default)
			)
			(layer "F.Fab")
		)
		(fp_line
			(start 0.120396 0.3048)
			(end 0.120396 0.2794)
			(stroke
				(width 0.1)
				(type default)
			)
			(layer "F.Fab")
		)
		(fp_line
			(start 0.67945 0.3048)
			(end 0.120396 0.3048)
			(stroke
				(width 0.1)
				(type default)
			)
			(layer "F.Fab")
		)
		(fp_line
			(start -0.12065 0.2794)
			(end -0.12065 0.3048)
			(stroke
				(width 0.1)
				(type default)
			)
			(layer "F.Fab")
		)
		(fp_line
			(start 0.120396 0.2794)
			(end -0.12065 0.2794)
			(stroke
				(width 0.1)
				(type default)
			)
			(layer "F.Fab")
		)
		(fp_line
			(start -0.12065 -0.2794)
			(end 0.12065 -0.2794)
			(stroke
				(width 0.1)
				(type default)
			)
			(layer "F.Fab")
		)
		(fp_line
			(start 0.12065 -0.2794)
			(end 0.12065 -0.3048)
			(stroke
				(width 0.1)
				(type default)
			)
			(layer "F.Fab")
		)
		(fp_line
			(start 0.12065 -0.3048)
			(end 0.67945 -0.3048)
			(stroke
				(width 0.1)
				(type default)
			)
			(layer "F.Fab")
		)
		(fp_line
			(start 0.67945 -0.3048)
			(end 0.67945 0.3048)
			(stroke
				(width 0.1)
				(type default)
			)
			(layer "F.Fab")
		)
		(fp_line
			(start -0.67945 -0.305054)
			(end -0.12065 -0.305054)
			(stroke
				(width 0.1)
				(type default)
			)
			(layer "F.Fab")
		)
		(fp_line
			(start -0.12065 -0.305054)
			(end -0.12065 -0.2794)
			(stroke
				(width 0.1)
				(type default)
			)
			(layer "F.Fab")
		)
		(pad "1" smd circle
			(at -0.40005 0 270)
			(size 0 0)
			(layers "F.Cu" "F.Mask" "F.Paste")
			(net "SW_PVDDCR_CPU0_P1_SW2_RC")
		)
		(pad "2" smd circle
			(at 0.40005 0 270)
			(size 0 0)
			(layers "F.Cu" "F.Mask" "F.Paste")
			(net "GND")
		)
	)
	(footprint ""
		(layer "F.Cu")
		(at 360.681778 -177.604674 90)
		(property "Reference" "PC481_1"
			(at 0 0 90)
			(layer "F.SilkS")
			(hide yes)
			(effects
				(font
					(size 1.27 1.27)
				)
			)
		)
		(property "Value" ""
			(at 0 0 90)
			(layer "F.Fab")
			(effects
				(font
					(size 1.27 1.27)
				)
			)
		)
		(duplicate_pad_numbers_are_jumpers no)
		(fp_line
			(start 0.7874 -0.4064)
			(end 0.7874 0.4064)
			(stroke
				(width 0.1524)
				(type default)
			)
			(layer "F.SilkS")
		)
		(fp_line
			(start -0.7874 -0.4064)
			(end 0.7874 -0.4064)
			(stroke
				(width 0.1524)
				(type default)
			)
			(layer "F.SilkS")
		)
		(fp_line
			(start 0.7874 0.4064)
			(end -0.7874 0.4064)
			(stroke
				(width 0.1524)
				(type default)
			)
			(layer "F.SilkS")
		)
		(fp_line
			(start -0.7874 0.4064)
			(end -0.7874 -0.4064)
			(stroke
				(width 0.1524)
				(type default)
			)
			(layer "F.SilkS")
		)
		(fp_line
			(start -0.12065 -0.305054)
			(end -0.12065 -0.2794)
			(stroke
				(width 0.1)
				(type default)
			)
			(layer "F.Fab")
		)
		(fp_line
			(start -0.67945 -0.305054)
			(end -0.12065 -0.305054)
			(stroke
				(width 0.1)
				(type default)
			)
			(layer "F.Fab")
		)
		(fp_line
			(start 0.67945 -0.3048)
			(end 0.67945 0.3048)
			(stroke
				(width 0.1)
				(type default)
			)
			(layer "F.Fab")
		)
		(fp_line
			(start 0.12065 -0.3048)
			(end 0.67945 -0.3048)
			(stroke
				(width 0.1)
				(type default)
			)
			(layer "F.Fab")
		)
		(fp_line
			(start 0.12065 -0.2794)
			(end 0.12065 -0.3048)
			(stroke
				(width 0.1)
				(type default)
			)
			(layer "F.Fab")
		)
		(fp_line
			(start -0.12065 -0.2794)
			(end 0.12065 -0.2794)
			(stroke
				(width 0.1)
				(type default)
			)
			(layer "F.Fab")
		)
		(fp_line
			(start 0.120396 0.2794)
			(end -0.12065 0.2794)
			(stroke
				(width 0.1)
				(type default)
			)
			(layer "F.Fab")
		)
		(fp_line
			(start -0.12065 0.2794)
			(end -0.12065 0.3048)
			(stroke
				(width 0.1)
				(type default)
			)
			(layer "F.Fab")
		)
		(fp_line
			(start 0.67945 0.3048)
			(end 0.120396 0.3048)
			(stroke
				(width 0.1)
				(type default)
			)
			(layer "F.Fab")
		)
		(fp_line
			(start 0.120396 0.3048)
			(end 0.120396 0.2794)
			(stroke
				(width 0.1)
				(type default)
			)
			(layer "F.Fab")
		)
		(fp_line
			(start -0.12065 0.3048)
			(end -0.67945 0.3048)
			(stroke
				(width 0.1)
				(type default)
			)
			(layer "F.Fab")
		)
		(fp_line
			(start -0.67945 0.3048)
			(end -0.67945 -0.305054)
			(stroke
				(width 0.1)
				(type default)
			)
			(layer "F.Fab")
		)
		(pad "1" smd circle
			(at -0.40005 0 90)
			(size 0 0)
			(layers "F.Cu" "F.Mask" "F.Paste")
			(net "SW_P12V_AUX_PVDDCR_CPU0_P0_FLT")
		)
		(pad "2" smd circle
			(at 0.40005 0 90)
			(size 0 0)
			(layers "F.Cu" "F.Mask" "F.Paste")
			(net "GND")
		)
	)
	(footprint ""
		(layer "F.Cu")
		(at 12.860274 -389.044434 -90)
		(property "Reference" "PC6609_09P1_1"
			(at 0 0 270)
			(layer "F.SilkS")
			(hide yes)
			(effects
				(font
					(size 1.27 1.27)
				)
			)
		)
		(property "Value" ""
			(at 0 0 270)
			(layer "F.Fab")
			(effects
				(font
					(size 1.27 1.27)
				)
			)
		)
		(duplicate_pad_numbers_are_jumpers no)
		(fp_line
			(start -0.7874 0.4064)
			(end -0.7874 -0.4064)
			(stroke
				(width 0.1524)
				(type default)
			)
			(layer "F.SilkS")
		)
		(fp_line
			(start 0.7874 0.4064)
			(end -0.7874 0.4064)
			(stroke
				(width 0.1524)
				(type default)
			)
			(layer "F.SilkS")
		)
		(fp_line
			(start -0.7874 -0.4064)
			(end 0.7874 -0.4064)
			(stroke
				(width 0.1524)
				(type default)
			)
			(layer "F.SilkS")
		)
		(fp_line
			(start 0.7874 -0.4064)
			(end 0.7874 0.4064)
			(stroke
				(width 0.1524)
				(type default)
			)
			(layer "F.SilkS")
		)
		(fp_line
			(start -0.67945 0.3048)
			(end -0.67945 -0.305054)
			(stroke
				(width 0.1)
				(type default)
			)
			(layer "F.Fab")
		)
		(fp_line
			(start -0.12065 0.3048)
			(end -0.67945 0.3048)
			(stroke
				(width 0.1)
				(type default)
			)
			(layer "F.Fab")
		)
		(fp_line
			(start 0.120396 0.3048)
			(end 0.120396 0.2794)
			(stroke
				(width 0.1)
				(type default)
			)
			(layer "F.Fab")
		)
		(fp_line
			(start 0.67945 0.3048)
			(end 0.120396 0.3048)
			(stroke
				(width 0.1)
				(type default)
			)
			(layer "F.Fab")
		)
		(fp_line
			(start -0.12065 0.2794)
			(end -0.12065 0.3048)
			(stroke
				(width 0.1)
				(type default)
			)
			(layer "F.Fab")
		)
		(fp_line
			(start 0.120396 0.2794)
			(end -0.12065 0.2794)
			(stroke
				(width 0.1)
				(type default)
			)
			(layer "F.Fab")
		)
		(fp_line
			(start -0.12065 -0.2794)
			(end 0.12065 -0.2794)
			(stroke
				(width 0.1)
				(type default)
			)
			(layer "F.Fab")
		)
		(fp_line
			(start 0.12065 -0.2794)
			(end 0.12065 -0.3048)
			(stroke
				(width 0.1)
				(type default)
			)
			(layer "F.Fab")
		)
		(fp_line
			(start 0.12065 -0.3048)
			(end 0.67945 -0.3048)
			(stroke
				(width 0.1)
				(type default)
			)
			(layer "F.Fab")
		)
		(fp_line
			(start 0.67945 -0.3048)
			(end 0.67945 0.3048)
			(stroke
				(width 0.1)
				(type default)
			)
			(layer "F.Fab")
		)
		(fp_line
			(start -0.67945 -0.305054)
			(end -0.12065 -0.305054)
			(stroke
				(width 0.1)
				(type default)
			)
			(layer "F.Fab")
		)
		(fp_line
			(start -0.12065 -0.305054)
			(end -0.12065 -0.2794)
			(stroke
				(width 0.1)
				(type default)
			)
			(layer "F.Fab")
		)
		(pad "1" smd circle
			(at -0.40005 0 270)
			(size 0 0)
			(layers "F.Cu" "F.Mask" "F.Paste")
			(net "P0V9_RETIMER_CPU1_PVCC")
		)
		(pad "2" smd circle
			(at 0.40005 0 270)
			(size 0 0)
			(layers "F.Cu" "F.Mask" "F.Paste")
			(net "GND")
		)
	)
	(footprint ""
		(layer "F.Cu")
		(at 169.368724 -376.067828)
		(property "Reference" "C745"
			(at 0 0 0)
			(layer "F.SilkS")
			(hide yes)
			(effects
				(font
					(size 1.27 1.27)
				)
			)
		)
		(property "Value" ""
			(at 0 0 0)
			(layer "F.Fab")
			(effects
				(font
					(size 1.27 1.27)
				)
			)
		)
		(duplicate_pad_numbers_are_jumpers no)
		(fp_line
			(start -0.299974 -0.150114)
			(end 0.299974 -0.150114)
			(stroke
				(width 0.1)
				(type default)
			)
			(layer "F.Fab")
		)
		(fp_line
			(start -0.299974 0.150114)
			(end -0.299974 -0.150114)
			(stroke
				(width 0.1)
				(type default)
			)
			(layer "F.Fab")
		)
		(fp_line
			(start 0.299974 -0.150114)
			(end 0.299974 0.150114)
			(stroke
				(width 0.1)
				(type default)
			)
			(layer "F.Fab")
		)
		(fp_line
			(start 0.299974 0.150114)
			(end -0.299974 0.150114)
			(stroke
				(width 0.1)
				(type default)
			)
			(layer "F.Fab")
		)
		(pad "1" smd rect
			(at -0.2667 0)
			(size 0.3048 0.381)
			(layers "F.Cu" "F.Mask" "F.Paste")
			(net "P5E_CPU1_P2_TX_C_DP<14>")
		)
		(pad "2" smd rect
			(at 0.2667 0)
			(size 0.3048 0.381)
			(layers "F.Cu" "F.Mask" "F.Paste")
			(net "P5E_CPU1_P2_TX_DP<14>")
		)
	)
	(footprint ""
		(layer "F.Cu")
		(at 8.42772 -76.144628 90)
		(property "Reference" "C1875"
			(at 0 0 90)
			(layer "F.SilkS")
			(hide yes)
			(effects
				(font
					(size 1.27 1.27)
				)
			)
		)
		(property "Value" ""
			(at 0 0 90)
			(layer "F.Fab")
			(effects
				(font
					(size 1.27 1.27)
				)
			)
		)
		(duplicate_pad_numbers_are_jumpers no)
		(fp_line
			(start 0.7874 -0.4064)
			(end 0.7874 0.4064)
			(stroke
				(width 0.1524)
				(type default)
			)
			(layer "F.SilkS")
		)
		(fp_line
			(start -0.7874 -0.4064)
			(end 0.7874 -0.4064)
			(stroke
				(width 0.1524)
				(type default)
			)
			(layer "F.SilkS")
		)
		(fp_line
			(start 0.7874 0.4064)
			(end -0.7874 0.4064)
			(stroke
				(width 0.1524)
				(type default)
			)
			(layer "F.SilkS")
		)
		(fp_line
			(start -0.7874 0.4064)
			(end -0.7874 -0.4064)
			(stroke
				(width 0.1524)
				(type default)
			)
			(layer "F.SilkS")
		)
		(fp_line
			(start -0.12065 -0.305054)
			(end -0.12065 -0.2794)
			(stroke
				(width 0.1)
				(type default)
			)
			(layer "F.Fab")
		)
		(fp_line
			(start -0.67945 -0.305054)
			(end -0.12065 -0.305054)
			(stroke
				(width 0.1)
				(type default)
			)
			(layer "F.Fab")
		)
		(fp_line
			(start 0.67945 -0.3048)
			(end 0.67945 0.3048)
			(stroke
				(width 0.1)
				(type default)
			)
			(layer "F.Fab")
		)
		(fp_line
			(start 0.12065 -0.3048)
			(end 0.67945 -0.3048)
			(stroke
				(width 0.1)
				(type default)
			)
			(layer "F.Fab")
		)
		(fp_line
			(start 0.12065 -0.2794)
			(end 0.12065 -0.3048)
			(stroke
				(width 0.1)
				(type default)
			)
			(layer "F.Fab")
		)
		(fp_line
			(start -0.12065 -0.2794)
			(end 0.12065 -0.2794)
			(stroke
				(width 0.1)
				(type default)
			)
			(layer "F.Fab")
		)
		(fp_line
			(start 0.120396 0.2794)
			(end -0.12065 0.2794)
			(stroke
				(width 0.1)
				(type default)
			)
			(layer "F.Fab")
		)
		(fp_line
			(start -0.12065 0.2794)
			(end -0.12065 0.3048)
			(stroke
				(width 0.1)
				(type default)
			)
			(layer "F.Fab")
		)
		(fp_line
			(start 0.67945 0.3048)
			(end 0.120396 0.3048)
			(stroke
				(width 0.1)
				(type default)
			)
			(layer "F.Fab")
		)
		(fp_line
			(start 0.120396 0.3048)
			(end 0.120396 0.2794)
			(stroke
				(width 0.1)
				(type default)
			)
			(layer "F.Fab")
		)
		(fp_line
			(start -0.12065 0.3048)
			(end -0.67945 0.3048)
			(stroke
				(width 0.1)
				(type default)
			)
			(layer "F.Fab")
		)
		(fp_line
			(start -0.67945 0.3048)
			(end -0.67945 -0.305054)
			(stroke
				(width 0.1)
				(type default)
			)
			(layer "F.Fab")
		)
		(pad "1" smd circle
			(at -0.40005 0 90)
			(size 0 0)
			(layers "F.Cu" "F.Mask" "F.Paste")
			(net "P3V3_AUX")
		)
		(pad "2" smd circle
			(at 0.40005 0 90)
			(size 0 0)
			(layers "F.Cu" "F.Mask" "F.Paste")
			(net "GND")
		)
	)
	(footprint ""
		(layer "F.Cu")
		(at 213.54288 -34.508948 180)
		(property "Reference" "R3576"
			(at 0 0 180)
			(layer "F.SilkS")
			(hide yes)
			(effects
				(font
					(size 1.27 1.27)
				)
			)
		)
		(property "Value" ""
			(at 0 0 180)
			(layer "F.Fab")
			(effects
				(font
					(size 1.27 1.27)
				)
			)
		)
		(duplicate_pad_numbers_are_jumpers no)
		(fp_line
			(start 0.7874 0.4064)
			(end -0.7874 0.4064)
			(stroke
				(width 0.1524)
				(type default)
			)
			(layer "F.SilkS")
		)
		(fp_line
			(start 0.7874 -0.4064)
			(end 0.7874 0.4064)
			(stroke
				(width 0.1524)
				(type default)
			)
			(layer "F.SilkS")
		)
		(fp_line
			(start -0.7874 0.4064)
			(end -0.7874 -0.4064)
			(stroke
				(width 0.1524)
				(type default)
			)
			(layer "F.SilkS")
		)
		(fp_line
			(start -0.7874 -0.4064)
			(end 0.7874 -0.4064)
			(stroke
				(width 0.1524)
				(type default)
			)
			(layer "F.SilkS")
		)
		(fp_line
			(start 0.67945 0.3048)
			(end 0.120396 0.3048)
			(stroke
				(width 0.1)
				(type default)
			)
			(layer "F.Fab")
		)
		(fp_line
			(start 0.67945 -0.3048)
			(end 0.67945 0.3048)
			(stroke
				(width 0.1)
				(type default)
			)
			(layer "F.Fab")
		)
		(fp_line
			(start 0.12065 -0.2794)
			(end 0.12065 -0.3048)
			(stroke
				(width 0.1)
				(type default)
			)
			(layer "F.Fab")
		)
		(fp_line
			(start 0.12065 -0.3048)
			(end 0.67945 -0.3048)
			(stroke
				(width 0.1)
				(type default)
			)
			(layer "F.Fab")
		)
		(fp_line
			(start 0.120396 0.3048)
			(end 0.120396 0.2794)
			(stroke
				(width 0.1)
				(type default)
			)
			(layer "F.Fab")
		)
		(fp_line
			(start 0.120396 0.2794)
			(end -0.12065 0.2794)
			(stroke
				(width 0.1)
				(type default)
			)
			(layer "F.Fab")
		)
		(fp_line
			(start -0.12065 0.3048)
			(end -0.67945 0.3048)
			(stroke
				(width 0.1)
				(type default)
			)
			(layer "F.Fab")
		)
		(fp_line
			(start -0.12065 0.2794)
			(end -0.12065 0.3048)
			(stroke
				(width 0.1)
				(type default)
			)
			(layer "F.Fab")
		)
		(fp_line
			(start -0.12065 -0.2794)
			(end 0.12065 -0.2794)
			(stroke
				(width 0.1)
				(type default)
			)
			(layer "F.Fab")
		)
		(fp_line
			(start -0.12065 -0.305054)
			(end -0.12065 -0.2794)
			(stroke
				(width 0.1)
				(type default)
			)
			(layer "F.Fab")
		)
		(fp_line
			(start -0.67945 0.3048)
			(end -0.67945 -0.305054)
			(stroke
				(width 0.1)
				(type default)
			)
			(layer "F.Fab")
		)
		(fp_line
			(start -0.67945 -0.305054)
			(end -0.12065 -0.305054)
			(stroke
				(width 0.1)
				(type default)
			)
			(layer "F.Fab")
		)
		(pad "1" smd circle
			(at -0.40005 0 180)
			(size 0 0)
			(layers "F.Cu" "F.Mask" "F.Paste")
			(net "SMB_INA230_5_3V3AUX_SCL_R")
		)
		(pad "2" smd circle
			(at 0.40005 0 180)
			(size 0 0)
			(layers "F.Cu" "F.Mask" "F.Paste")
			(net "SMB_INA230_5_3V3AUX_SCL_R1")
		)
	)
	(footprint ""
		(layer "F.Cu")
		(at 18.702782 -136.985502)
		(property "Reference" "R3337"
			(at 0 0 0)
			(layer "F.SilkS")
			(hide yes)
			(effects
				(font
					(size 1.27 1.27)
				)
			)
		)
		(property "Value" ""
			(at 0 0 0)
			(layer "F.Fab")
			(effects
				(font
					(size 1.27 1.27)
				)
			)
		)
		(duplicate_pad_numbers_are_jumpers no)
		(fp_line
			(start -0.7874 -0.4064)
			(end 0.7874 -0.4064)
			(stroke
				(width 0.1524)
				(type default)
			)
			(layer "F.SilkS")
		)
		(fp_line
			(start -0.7874 0.4064)
			(end -0.7874 -0.4064)
			(stroke
				(width 0.1524)
				(type default)
			)
			(layer "F.SilkS")
		)
		(fp_line
			(start 0.7874 -0.4064)
			(end 0.7874 0.4064)
			(stroke
				(width 0.1524)
				(type default)
			)
			(layer "F.SilkS")
		)
		(fp_line
			(start 0.7874 0.4064)
			(end -0.7874 0.4064)
			(stroke
				(width 0.1524)
				(type default)
			)
			(layer "F.SilkS")
		)
		(fp_line
			(start -0.67945 -0.305054)
			(end -0.12065 -0.305054)
			(stroke
				(width 0.1)
				(type default)
			)
			(layer "F.Fab")
		)
		(fp_line
			(start -0.67945 0.3048)
			(end -0.67945 -0.305054)
			(stroke
				(width 0.1)
				(type default)
			)
			(layer "F.Fab")
		)
		(fp_line
			(start -0.12065 -0.305054)
			(end -0.12065 -0.2794)
			(stroke
				(width 0.1)
				(type default)
			)
			(layer "F.Fab")
		)
		(fp_line
			(start -0.12065 -0.2794)
			(end 0.12065 -0.2794)
			(stroke
				(width 0.1)
				(type default)
			)
			(layer "F.Fab")
		)
		(fp_line
			(start -0.12065 0.2794)
			(end -0.12065 0.3048)
			(stroke
				(width 0.1)
				(type default)
			)
			(layer "F.Fab")
		)
		(fp_line
			(start -0.12065 0.3048)
			(end -0.67945 0.3048)
			(stroke
				(width 0.1)
				(type default)
			)
			(layer "F.Fab")
		)
		(fp_line
			(start 0.120396 0.2794)
			(end -0.12065 0.2794)
			(stroke
				(width 0.1)
				(type default)
			)
			(layer "F.Fab")
		)
		(fp_line
			(start 0.120396 0.3048)
			(end 0.120396 0.2794)
			(stroke
				(width 0.1)
				(type default)
			)
			(layer "F.Fab")
		)
		(fp_line
			(start 0.12065 -0.3048)
			(end 0.67945 -0.3048)
			(stroke
				(width 0.1)
				(type default)
			)
			(layer "F.Fab")
		)
		(fp_line
			(start 0.12065 -0.2794)
			(end 0.12065 -0.3048)
			(stroke
				(width 0.1)
				(type default)
			)
			(layer "F.Fab")
		)
		(fp_line
			(start 0.67945 -0.3048)
			(end 0.67945 0.3048)
			(stroke
				(width 0.1)
				(type default)
			)
			(layer "F.Fab")
		)
		(fp_line
			(start 0.67945 0.3048)
			(end 0.120396 0.3048)
			(stroke
				(width 0.1)
				(type default)
			)
			(layer "F.Fab")
		)
		(pad "1" smd circle
			(at -0.40005 0)
			(size 0 0)
			(layers "F.Cu" "F.Mask" "F.Paste")
			(net "CLK_100M_GPU_FPGA_DP_R")
		)
		(pad "2" smd circle
			(at 0.40005 0)
			(size 0 0)
			(layers "F.Cu" "F.Mask" "F.Paste")
			(net "CLK_100M_GPU_FPGA_DP")
		)
	)
	(footprint ""
		(layer "F.Cu")
		(at 423.56278 -106.129328 90)
		(property "Reference" "PC2163"
			(at 0 0 90)
			(layer "F.SilkS")
			(hide yes)
			(effects
				(font
					(size 1.27 1.27)
				)
			)
		)
		(property "Value" ""
			(at 0 0 90)
			(layer "F.Fab")
			(effects
				(font
					(size 1.27 1.27)
				)
			)
		)
		(duplicate_pad_numbers_are_jumpers no)
		(fp_line
			(start 1.524 -0.762)
			(end 1.524 0.762)
			(stroke
				(width 0.1524)
				(type default)
			)
			(layer "F.SilkS")
		)
		(fp_line
			(start -1.524 -0.762)
			(end 1.524 -0.762)
			(stroke
				(width 0.1524)
				(type default)
			)
			(layer "F.SilkS")
		)
		(fp_line
			(start 1.524 0.762)
			(end -1.524 0.762)
			(stroke
				(width 0.1524)
				(type default)
			)
			(layer "F.SilkS")
		)
		(fp_line
			(start -1.524 0.762)
			(end -1.524 -0.762)
			(stroke
				(width 0.1524)
				(type default)
			)
			(layer "F.SilkS")
		)
		(fp_line
			(start 1.1049 -0.724916)
			(end -1.1049 -0.724916)
			(stroke
				(width 0.1)
				(type default)
			)
			(layer "F.Fab")
		)
		(fp_line
			(start -1.1049 -0.724916)
			(end -1.1049 0.724916)
			(stroke
				(width 0.1)
				(type default)
			)
			(layer "F.Fab")
		)
		(fp_line
			(start 1.1049 0.724916)
			(end 1.1049 -0.724916)
			(stroke
				(width 0.1)
				(type default)
			)
			(layer "F.Fab")
		)
		(fp_line
			(start -1.1049 0.724916)
			(end 1.1049 0.724916)
			(stroke
				(width 0.1)
				(type default)
			)
			(layer "F.Fab")
		)
		(pad "1" smd rect
			(at -0.889 0 270)
			(size 1.016 1.27)
			(layers "F.Cu" "F.Mask" "F.Paste")
			(net "P3V3_OCP_SFF_R")
		)
		(pad "2" smd rect
			(at 0.889 0 270)
			(size 1.016 1.27)
			(layers "F.Cu" "F.Mask" "F.Paste")
			(net "GND")
		)
	)
	(footprint ""
		(layer "F.Cu")
		(at 184.5945 -408.110182 180)
		(property "Reference" "PR3926"
			(at 0 0 180)
			(layer "F.SilkS")
			(hide yes)
			(effects
				(font
					(size 1.27 1.27)
				)
			)
		)
		(property "Value" ""
			(at 0 0 180)
			(layer "F.Fab")
			(effects
				(font
					(size 1.27 1.27)
				)
			)
		)
		(duplicate_pad_numbers_are_jumpers no)
		(fp_line
			(start 0.7874 0.4064)
			(end -0.7874 0.4064)
			(stroke
				(width 0.1524)
				(type default)
			)
			(layer "F.SilkS")
		)
		(fp_line
			(start 0.7874 -0.4064)
			(end 0.7874 0.4064)
			(stroke
				(width 0.1524)
				(type default)
			)
			(layer "F.SilkS")
		)
		(fp_line
			(start -0.7874 0.4064)
			(end -0.7874 -0.4064)
			(stroke
				(width 0.1524)
				(type default)
			)
			(layer "F.SilkS")
		)
		(fp_line
			(start -0.7874 -0.4064)
			(end 0.7874 -0.4064)
			(stroke
				(width 0.1524)
				(type default)
			)
			(layer "F.SilkS")
		)
		(fp_line
			(start 0.67945 0.3048)
			(end 0.120396 0.3048)
			(stroke
				(width 0.1)
				(type default)
			)
			(layer "F.Fab")
		)
		(fp_line
			(start 0.67945 -0.3048)
			(end 0.67945 0.3048)
			(stroke
				(width 0.1)
				(type default)
			)
			(layer "F.Fab")
		)
		(fp_line
			(start 0.12065 -0.2794)
			(end 0.12065 -0.3048)
			(stroke
				(width 0.1)
				(type default)
			)
			(layer "F.Fab")
		)
		(fp_line
			(start 0.12065 -0.3048)
			(end 0.67945 -0.3048)
			(stroke
				(width 0.1)
				(type default)
			)
			(layer "F.Fab")
		)
		(fp_line
			(start 0.120396 0.3048)
			(end 0.120396 0.2794)
			(stroke
				(width 0.1)
				(type default)
			)
			(layer "F.Fab")
		)
		(fp_line
			(start 0.120396 0.2794)
			(end -0.12065 0.2794)
			(stroke
				(width 0.1)
				(type default)
			)
			(layer "F.Fab")
		)
		(fp_line
			(start -0.12065 0.3048)
			(end -0.67945 0.3048)
			(stroke
				(width 0.1)
				(type default)
			)
			(layer "F.Fab")
		)
		(fp_line
			(start -0.12065 0.2794)
			(end -0.12065 0.3048)
			(stroke
				(width 0.1)
				(type default)
			)
			(layer "F.Fab")
		)
		(fp_line
			(start -0.12065 -0.2794)
			(end 0.12065 -0.2794)
			(stroke
				(width 0.1)
				(type default)
			)
			(layer "F.Fab")
		)
		(fp_line
			(start -0.12065 -0.305054)
			(end -0.12065 -0.2794)
			(stroke
				(width 0.1)
				(type default)
			)
			(layer "F.Fab")
		)
		(fp_line
			(start -0.67945 0.3048)
			(end -0.67945 -0.305054)
			(stroke
				(width 0.1)
				(type default)
			)
			(layer "F.Fab")
		)
		(fp_line
			(start -0.67945 -0.305054)
			(end -0.12065 -0.305054)
			(stroke
				(width 0.1)
				(type default)
			)
			(layer "F.Fab")
		)
		(pad "1" smd circle
			(at -0.40005 0 180)
			(size 0 0)
			(layers "F.Cu" "F.Mask" "F.Paste")
			(net "P12V_PSU")
		)
		(pad "2" smd circle
			(at 0.40005 0 180)
			(size 0 0)
			(layers "F.Cu" "F.Mask" "F.Paste")
			(net "HSC_VSENSE")
		)
	)
	(footprint ""
		(layer "F.Cu")
		(at 219.99956 -103.17226 180)
		(property "Reference" "U9050"
			(at -3.35915 -1.37668 90)
			(unlocked yes)
			(layer "F.SilkS")
			(effects
				(font
					(size 0.7874 0.5842)
					(thickness 0.1524)
				)
				(justify left)
			)
		)
		(property "Value" ""
			(at 0 0 180)
			(layer "F.Fab")
			(effects
				(font
					(size 1.27 1.27)
				)
			)
		)
		(duplicate_pad_numbers_are_jumpers no)
		(fp_line
			(start 1.733296 1.549908)
			(end 1.733296 -1.549908)
			(stroke
				(width 0.1524)
				(type default)
			)
			(layer "F.SilkS")
		)
		(fp_line
			(start 1.733296 -1.549908)
			(end 0.660908 -1.549908)
			(stroke
				(width 0.1524)
				(type default)
			)
			(layer "F.SilkS")
		)
		(fp_line
			(start 0.660908 -1.549908)
			(end 0 -0.889)
			(stroke
				(width 0.1524)
				(type default)
			)
			(layer "F.SilkS")
		)
		(fp_line
			(start 0 -0.889)
			(end -0.660908 -1.549908)
			(stroke
				(width 0.1524)
				(type default)
			)
			(layer "F.SilkS")
		)
		(fp_line
			(start -0.660908 -1.549908)
			(end -1.733296 -1.549908)
			(stroke
				(width 0.1524)
				(type default)
			)
			(layer "F.SilkS")
		)
		(fp_line
			(start -1.733296 1.549908)
			(end 1.733296 1.549908)
			(stroke
				(width 0.1524)
				(type default)
			)
			(layer "F.SilkS")
		)
		(fp_line
			(start -1.733296 -1.549908)
			(end -1.733296 1.549908)
			(stroke
				(width 0.1524)
				(type default)
			)
			(layer "F.SilkS")
		)
		(fp_poly
			(pts
				(xy -2.4384 -1.20396) (xy -2.4384 -0.69596) (xy -1.9304 -0.94996)
			)
			(stroke
				(width 0)
				(type default)
			)
			(fill yes)
			(layer "F.SilkS")
		)
		(fp_line
			(start 0.849884 1.549908)
			(end 0.849884 -1.549908)
			(stroke
				(width 0.1)
				(type default)
			)
			(layer "F.Fab")
		)
		(fp_line
			(start 0.849884 -1.549908)
			(end -0.849884 -1.549908)
			(stroke
				(width 0.1)
				(type default)
			)
			(layer "F.Fab")
		)
		(fp_line
			(start -0.849884 1.549908)
			(end 0.849884 1.549908)
			(stroke
				(width 0.1)
				(type default)
			)
			(layer "F.Fab")
		)
		(fp_line
			(start -0.849884 -1.549908)
			(end -0.849884 1.549908)
			(stroke
				(width 0.1)
				(type default)
			)
			(layer "F.Fab")
		)
		(fp_poly
			(pts
				(xy -2.4384 -1.20396) (xy -2.4384 -0.69596) (xy -1.9304 -0.94996)
			)
			(stroke
				(width 0)
				(type default)
			)
			(fill yes)
			(layer "F.Fab")
		)
		(pad "1" smd rect
			(at -1.199896 -0.94996 90)
			(size 0.5588 0.8128)
			(layers "F.Cu" "F.Mask" "F.Paste")
			(net "OCP_V3_1_P3V3_PWRGD")
		)
		(pad "2" smd rect
			(at -1.199896 0 90)
			(size 0.5588 0.8128)
			(layers "F.Cu" "F.Mask" "F.Paste")
			(net "HP_LVC3_OCP_V3_1_P12V_R2_PWRGD")
		)
		(pad "3" smd rect
			(at -1.199896 0.94996 90)
			(size 0.5588 0.8128)
			(layers "F.Cu" "F.Mask" "F.Paste")
			(net "GND")
		)
		(pad "4" smd rect
			(at 1.199896 0.94996 90)
			(size 0.5588 0.8128)
			(layers "F.Cu" "F.Mask" "F.Paste")
			(net "HP_LVC3_OCP_V3_1_PWRGD_R2")
		)
		(pad "5" smd rect
			(at 1.199896 -0.94996 90)
			(size 0.5588 0.8128)
			(layers "F.Cu" "F.Mask" "F.Paste")
			(net "P3V3_AUX")
		)
	)
	(footprint ""
		(layer "F.Cu")
		(at 450.389752 -394.302234 180)
		(property "Reference" "PC6585"
			(at 0 0 180)
			(layer "F.SilkS")
			(hide yes)
			(effects
				(font
					(size 1.27 1.27)
				)
			)
		)
		(property "Value" ""
			(at 0 0 180)
			(layer "F.Fab")
			(effects
				(font
					(size 1.27 1.27)
				)
			)
		)
		(duplicate_pad_numbers_are_jumpers no)
		(fp_line
			(start 0.7874 0.4064)
			(end -0.7874 0.4064)
			(stroke
				(width 0.1524)
				(type default)
			)
			(layer "F.SilkS")
		)
		(fp_line
			(start 0.7874 -0.4064)
			(end 0.7874 0.4064)
			(stroke
				(width 0.1524)
				(type default)
			)
			(layer "F.SilkS")
		)
		(fp_line
			(start -0.7874 0.4064)
			(end -0.7874 -0.4064)
			(stroke
				(width 0.1524)
				(type default)
			)
			(layer "F.SilkS")
		)
		(fp_line
			(start -0.7874 -0.4064)
			(end 0.7874 -0.4064)
			(stroke
				(width 0.1524)
				(type default)
			)
			(layer "F.SilkS")
		)
		(fp_line
			(start 0.67945 0.3048)
			(end 0.120396 0.3048)
			(stroke
				(width 0.1)
				(type default)
			)
			(layer "F.Fab")
		)
		(fp_line
			(start 0.67945 -0.3048)
			(end 0.67945 0.3048)
			(stroke
				(width 0.1)
				(type default)
			)
			(layer "F.Fab")
		)
		(fp_line
			(start 0.12065 -0.2794)
			(end 0.12065 -0.3048)
			(stroke
				(width 0.1)
				(type default)
			)
			(layer "F.Fab")
		)
		(fp_line
			(start 0.12065 -0.3048)
			(end 0.67945 -0.3048)
			(stroke
				(width 0.1)
				(type default)
			)
			(layer "F.Fab")
		)
		(fp_line
			(start 0.120396 0.3048)
			(end 0.120396 0.2794)
			(stroke
				(width 0.1)
				(type default)
			)
			(layer "F.Fab")
		)
		(fp_line
			(start 0.120396 0.2794)
			(end -0.12065 0.2794)
			(stroke
				(width 0.1)
				(type default)
			)
			(layer "F.Fab")
		)
		(fp_line
			(start -0.12065 0.3048)
			(end -0.67945 0.3048)
			(stroke
				(width 0.1)
				(type default)
			)
			(layer "F.Fab")
		)
		(fp_line
			(start -0.12065 0.2794)
			(end -0.12065 0.3048)
			(stroke
				(width 0.1)
				(type default)
			)
			(layer "F.Fab")
		)
		(fp_line
			(start -0.12065 -0.2794)
			(end 0.12065 -0.2794)
			(stroke
				(width 0.1)
				(type default)
			)
			(layer "F.Fab")
		)
		(fp_line
			(start -0.12065 -0.305054)
			(end -0.12065 -0.2794)
			(stroke
				(width 0.1)
				(type default)
			)
			(layer "F.Fab")
		)
		(fp_line
			(start -0.67945 0.3048)
			(end -0.67945 -0.305054)
			(stroke
				(width 0.1)
				(type default)
			)
			(layer "F.Fab")
		)
		(fp_line
			(start -0.67945 -0.305054)
			(end -0.12065 -0.305054)
			(stroke
				(width 0.1)
				(type default)
			)
			(layer "F.Fab")
		)
		(pad "1" smd circle
			(at -0.40005 0 180)
			(size 0 0)
			(layers "F.Cu" "F.Mask" "F.Paste")
			(net "SW_P0V9_RETIMER_CPU0_SW2")
		)
		(pad "2" smd circle
			(at 0.40005 0 180)
			(size 0 0)
			(layers "F.Cu" "F.Mask" "F.Paste")
			(net "SW_P0V9_RETIMER_CPU0_SW2_RC")
		)
	)
	(footprint ""
		(layer "F.Cu")
		(at 91.986354 -177.464212)
		(property "Reference" "PR188"
			(at 0 0 0)
			(layer "F.SilkS")
			(hide yes)
			(effects
				(font
					(size 1.27 1.27)
				)
			)
		)
		(property "Value" ""
			(at 0 0 0)
			(layer "F.Fab")
			(effects
				(font
					(size 1.27 1.27)
				)
			)
		)
		(duplicate_pad_numbers_are_jumpers no)
		(fp_line
			(start -0.7874 -0.4064)
			(end 0.7874 -0.4064)
			(stroke
				(width 0.1524)
				(type default)
			)
			(layer "F.SilkS")
		)
		(fp_line
			(start -0.7874 0.4064)
			(end -0.7874 -0.4064)
			(stroke
				(width 0.1524)
				(type default)
			)
			(layer "F.SilkS")
		)
		(fp_line
			(start 0.7874 -0.4064)
			(end 0.7874 0.4064)
			(stroke
				(width 0.1524)
				(type default)
			)
			(layer "F.SilkS")
		)
		(fp_line
			(start 0.7874 0.4064)
			(end -0.7874 0.4064)
			(stroke
				(width 0.1524)
				(type default)
			)
			(layer "F.SilkS")
		)
		(fp_line
			(start -0.67945 -0.305054)
			(end -0.12065 -0.305054)
			(stroke
				(width 0.1)
				(type default)
			)
			(layer "F.Fab")
		)
		(fp_line
			(start -0.67945 0.3048)
			(end -0.67945 -0.305054)
			(stroke
				(width 0.1)
				(type default)
			)
			(layer "F.Fab")
		)
		(fp_line
			(start -0.12065 -0.305054)
			(end -0.12065 -0.2794)
			(stroke
				(width 0.1)
				(type default)
			)
			(layer "F.Fab")
		)
		(fp_line
			(start -0.12065 -0.2794)
			(end 0.12065 -0.2794)
			(stroke
				(width 0.1)
				(type default)
			)
			(layer "F.Fab")
		)
		(fp_line
			(start -0.12065 0.2794)
			(end -0.12065 0.3048)
			(stroke
				(width 0.1)
				(type default)
			)
			(layer "F.Fab")
		)
		(fp_line
			(start -0.12065 0.3048)
			(end -0.67945 0.3048)
			(stroke
				(width 0.1)
				(type default)
			)
			(layer "F.Fab")
		)
		(fp_line
			(start 0.120396 0.2794)
			(end -0.12065 0.2794)
			(stroke
				(width 0.1)
				(type default)
			)
			(layer "F.Fab")
		)
		(fp_line
			(start 0.120396 0.3048)
			(end 0.120396 0.2794)
			(stroke
				(width 0.1)
				(type default)
			)
			(layer "F.Fab")
		)
		(fp_line
			(start 0.12065 -0.3048)
			(end 0.67945 -0.3048)
			(stroke
				(width 0.1)
				(type default)
			)
			(layer "F.Fab")
		)
		(fp_line
			(start 0.12065 -0.2794)
			(end 0.12065 -0.3048)
			(stroke
				(width 0.1)
				(type default)
			)
			(layer "F.Fab")
		)
		(fp_line
			(start 0.67945 -0.3048)
			(end 0.67945 0.3048)
			(stroke
				(width 0.1)
				(type default)
			)
			(layer "F.Fab")
		)
		(fp_line
			(start 0.67945 0.3048)
			(end 0.120396 0.3048)
			(stroke
				(width 0.1)
				(type default)
			)
			(layer "F.Fab")
		)
		(pad "1" smd circle
			(at -0.40005 0)
			(size 0 0)
			(layers "F.Cu" "F.Mask" "F.Paste")
			(net "GND")
		)
		(pad "2" smd circle
			(at 0.40005 0)
			(size 0 0)
			(layers "F.Cu" "F.Mask" "F.Paste")
			(net "PVDDCR_CPU0_P1_LSET2")
		)
	)
	(footprint ""
		(layer "F.Cu")
		(at 300.736 -108.56595 -90)
		(property "Reference" "R1349"
			(at 0 0 270)
			(layer "F.SilkS")
			(hide yes)
			(effects
				(font
					(size 1.27 1.27)
				)
			)
		)
		(property "Value" ""
			(at 0 0 270)
			(layer "F.Fab")
			(effects
				(font
					(size 1.27 1.27)
				)
			)
		)
		(duplicate_pad_numbers_are_jumpers no)
		(fp_line
			(start -0.7874 0.4064)
			(end -0.7874 -0.4064)
			(stroke
				(width 0.1524)
				(type default)
			)
			(layer "F.SilkS")
		)
		(fp_line
			(start 0.7874 0.4064)
			(end -0.7874 0.4064)
			(stroke
				(width 0.1524)
				(type default)
			)
			(layer "F.SilkS")
		)
		(fp_line
			(start -0.7874 -0.4064)
			(end 0.7874 -0.4064)
			(stroke
				(width 0.1524)
				(type default)
			)
			(layer "F.SilkS")
		)
		(fp_line
			(start 0.7874 -0.4064)
			(end 0.7874 0.4064)
			(stroke
				(width 0.1524)
				(type default)
			)
			(layer "F.SilkS")
		)
		(fp_line
			(start -0.67945 0.3048)
			(end -0.67945 -0.305054)
			(stroke
				(width 0.1)
				(type default)
			)
			(layer "F.Fab")
		)
		(fp_line
			(start -0.12065 0.3048)
			(end -0.67945 0.3048)
			(stroke
				(width 0.1)
				(type default)
			)
			(layer "F.Fab")
		)
		(fp_line
			(start 0.120396 0.3048)
			(end 0.120396 0.2794)
			(stroke
				(width 0.1)
				(type default)
			)
			(layer "F.Fab")
		)
		(fp_line
			(start 0.67945 0.3048)
			(end 0.120396 0.3048)
			(stroke
				(width 0.1)
				(type default)
			)
			(layer "F.Fab")
		)
		(fp_line
			(start -0.12065 0.2794)
			(end -0.12065 0.3048)
			(stroke
				(width 0.1)
				(type default)
			)
			(layer "F.Fab")
		)
		(fp_line
			(start 0.120396 0.2794)
			(end -0.12065 0.2794)
			(stroke
				(width 0.1)
				(type default)
			)
			(layer "F.Fab")
		)
		(fp_line
			(start -0.12065 -0.2794)
			(end 0.12065 -0.2794)
			(stroke
				(width 0.1)
				(type default)
			)
			(layer "F.Fab")
		)
		(fp_line
			(start 0.12065 -0.2794)
			(end 0.12065 -0.3048)
			(stroke
				(width 0.1)
				(type default)
			)
			(layer "F.Fab")
		)
		(fp_line
			(start 0.12065 -0.3048)
			(end 0.67945 -0.3048)
			(stroke
				(width 0.1)
				(type default)
			)
			(layer "F.Fab")
		)
		(fp_line
			(start 0.67945 -0.3048)
			(end 0.67945 0.3048)
			(stroke
				(width 0.1)
				(type default)
			)
			(layer "F.Fab")
		)
		(fp_line
			(start -0.67945 -0.305054)
			(end -0.12065 -0.305054)
			(stroke
				(width 0.1)
				(type default)
			)
			(layer "F.Fab")
		)
		(fp_line
			(start -0.12065 -0.305054)
			(end -0.12065 -0.2794)
			(stroke
				(width 0.1)
				(type default)
			)
			(layer "F.Fab")
		)
		(pad "1" smd circle
			(at -0.40005 0 270)
			(size 0 0)
			(layers "F.Cu" "F.Mask" "F.Paste")
			(net "SMB_INA230_3V3AUX_SDA")
		)
		(pad "2" smd circle
			(at 0.40005 0 270)
			(size 0 0)
			(layers "F.Cu" "F.Mask" "F.Paste")
			(net "SMB_INA230_8_3V3AUX_SDA_R")
		)
	)
	(footprint ""
		(layer "F.Cu")
		(at 115.68557 -171.923456 180)
		(property "Reference" "PU30"
			(at 2.49682 -7.206742 0)
			(unlocked yes)
			(layer "F.SilkS")
			(effects
				(font
					(size 0.7874 0.5842)
					(thickness 0.1524)
				)
				(justify left)
			)
		)
		(property "Value" ""
			(at 0 0 180)
			(layer "F.Fab")
			(effects
				(font
					(size 1.27 1.27)
				)
			)
		)
		(duplicate_pad_numbers_are_jumpers no)
		(fp_line
			(start 2.500122 2.999994)
			(end 2.2987 2.999994)
			(stroke
				(width 0.1524)
				(type default)
			)
			(layer "F.SilkS")
		)
		(fp_line
			(start 2.500122 2.339594)
			(end 2.500122 2.999994)
			(stroke
				(width 0.1524)
				(type default)
			)
			(layer "F.SilkS")
		)
		(fp_line
			(start 2.500122 -2.999994)
			(end 2.500122 -2.44348)
			(stroke
				(width 0.1524)
				(type default)
			)
			(layer "F.SilkS")
		)
		(fp_line
			(start 2.31394 -2.999994)
			(end 2.500122 -2.999994)
			(stroke
				(width 0.1524)
				(type default)
			)
			(layer "F.SilkS")
		)
		(fp_line
			(start -2.2987 2.999994)
			(end -2.500122 2.999994)
			(stroke
				(width 0.1524)
				(type default)
			)
			(layer "F.SilkS")
		)
		(fp_line
			(start -2.500122 2.999994)
			(end -2.500122 2.339594)
			(stroke
				(width 0.1524)
				(type default)
			)
			(layer "F.SilkS")
		)
		(fp_line
			(start -2.500122 0.6604)
			(end -2.500122 0.229108)
			(stroke
				(width 0.1524)
				(type default)
			)
			(layer "F.SilkS")
		)
		(fp_line
			(start -2.500122 -2.529078)
			(end -2.500122 -2.999994)
			(stroke
				(width 0.1524)
				(type default)
			)
			(layer "F.SilkS")
		)
		(fp_line
			(start -2.500122 -2.999994)
			(end -2.24409 -2.999994)
			(stroke
				(width 0.1524)
				(type default)
			)
			(layer "F.SilkS")
		)
		(fp_poly
			(pts
				(xy -2.781554 -2.38633) (xy -3.455162 -2.610866) (xy -3.00609 -3.059938)
			)
			(stroke
				(width 0)
				(type default)
			)
			(fill yes)
			(layer "F.SilkS")
		)
		(fp_line
			(start 2.500122 2.999994)
			(end -2.500122 2.999994)
			(stroke
				(width 0.1)
				(type default)
			)
			(layer "F.Fab")
		)
		(fp_line
			(start 2.500122 -2.999994)
			(end 2.500122 2.999994)
			(stroke
				(width 0.1)
				(type default)
			)
			(layer "F.Fab")
		)
		(fp_line
			(start -2.500122 2.999994)
			(end -2.500122 -2.999994)
			(stroke
				(width 0.1)
				(type default)
			)
			(layer "F.Fab")
		)
		(fp_line
			(start -2.500122 -2.999994)
			(end 2.500122 -2.999994)
			(stroke
				(width 0.1)
				(type default)
			)
			(layer "F.Fab")
		)
		(fp_poly
			(pts
				(xy -4.218432 -2.783078) (xy -4.218432 -1.767078) (xy -3.202432 -2.275078)
			)
			(stroke
				(width 0)
				(type default)
			)
			(fill yes)
			(layer "F.Fab")
		)
		(pad "1" smd rect
			(at -2.400046 -2.275078 270)
			(size 0.2286 0.6096)
			(layers "F.Cu" "F.Mask" "F.Paste")
			(net "PVDDCR_SOC_P1_VOS1")
		)
		(pad "2" smd rect
			(at -2.400046 -1.82499 270)
			(size 0.2286 0.6096)
			(layers "F.Cu" "F.Mask" "F.Paste")
			(net "GND")
		)
		(pad "3" smd rect
			(at -2.400046 -1.374902 270)
			(size 0.2286 0.6096)
			(layers "F.Cu" "F.Mask" "F.Paste")
			(net "PVDDCR_SOC_P1_VCC1")
		)
		(pad "4" smd rect
			(at -2.400046 -0.925068 270)
			(size 0.2286 0.6096)
			(layers "F.Cu" "F.Mask" "F.Paste")
			(net "PVDDCR_CPU0_P1_PVCC")
		)
		(pad "5" smd rect
			(at -2.400046 -0.47498 270)
			(size 0.2286 0.6096)
			(layers "F.Cu" "F.Mask" "F.Paste")
			(net "GND")
		)
		(pad "6" smd rect
			(at -2.400046 -0.024892 270)
			(size 0.2286 0.6096)
			(layers "F.Cu" "F.Mask" "F.Paste")
			(net "NC_PVDDCR_SOC_P1_GL1_1")
		)
		(pad "7_9-20_24" smd circle
			(at 0 1.150112 270)
			(size 0 0)
			(layers "F.Cu" "F.Mask" "F.Paste")
			(net "GND")
		)
		(pad "10_19" smd rect
			(at 0 2.899918 270)
			(size 0.6096 4.318)
			(layers "F.Cu" "F.Mask" "F.Paste")
			(net "SW_PVDDCR_SOC_P1_SW1")
		)
		(pad "25_29" smd rect
			(at 1.549908 -1.279906 90)
			(size 2.0574 2.3114)
			(layers "F.Cu" "F.Mask" "F.Paste")
			(net "SW_P12V_AUX_PVDDCR_SOC_P1_FLT")
		)
		(pad "30" smd rect
			(at 2.05994 -2.899918 180)
			(size 0.2286 0.6096)
			(layers "F.Cu" "F.Mask" "F.Paste")
			(net "SW_P12V_AUX_PVDDCR_SOC_P1_FLT")
		)
		(pad "31" smd rect
			(at 1.610106 -2.899918 180)
			(size 0.2286 0.6096)
			(layers "F.Cu" "F.Mask" "F.Paste")
			(net "NC_PVDDCR_SOC_P1_DNC1")
		)
		(pad "32" smd rect
			(at 1.160018 -2.899918 180)
			(size 0.2286 0.6096)
			(layers "F.Cu" "F.Mask" "F.Paste")
			(net "SW_PVDDCR_SOC_P1_PH1")
		)
		(pad "33" smd rect
			(at 0.70993 -2.899918 180)
			(size 0.2286 0.6096)
			(layers "F.Cu" "F.Mask" "F.Paste")
			(net "SW_PVDDCR_SOC_P1_BOOT1")
		)
		(pad "34" smd rect
			(at 0.260096 -2.899918 180)
			(size 0.2286 0.6096)
			(layers "F.Cu" "F.Mask" "F.Paste")
			(net "PVDDCR_SOC_P1_PWM1")
		)
		(pad "35" smd rect
			(at -0.189992 -2.899918 180)
			(size 0.2286 0.6096)
			(layers "F.Cu" "F.Mask" "F.Paste")
			(net "PVDDCR_SOC_P1_VCC1")
		)
		(pad "36" smd rect
			(at -0.64008 -2.899918 180)
			(size 0.2286 0.6096)
			(layers "F.Cu" "F.Mask" "F.Paste")
			(net "PVDDCR_SOC_P1_TEMP1")
		)
		(pad "37" smd rect
			(at -1.089914 -2.899918 180)
			(size 0.2286 0.6096)
			(layers "F.Cu" "F.Mask" "F.Paste")
			(net "PVDDCR_SOC_P1_LSET1")
		)
		(pad "38" smd rect
			(at -1.540002 -2.899918 180)
			(size 0.2286 0.6096)
			(layers "F.Cu" "F.Mask" "F.Paste")
			(net "PVDDCR_SOC_P1_IMON1")
		)
		(pad "39" smd rect
			(at -1.99009 -2.899918 180)
			(size 0.2286 0.6096)
			(layers "F.Cu" "F.Mask" "F.Paste")
			(net "PVDDCR_CPU0_P1_VCCS")
		)
		(pad "40" smd rect
			(at -0.87503 -1.27508 180)
			(size 1.7526 1.9558)
			(layers "F.Cu" "F.Mask" "F.Paste")
			(net "GND")
		)
		(pad "41" smd rect
			(at -1.525016 0.249936 90)
			(size 0.3048 0.4572)
			(layers "F.Cu" "F.Mask" "F.Paste")
			(net "NC_PVDDCR_SOC_P1_GL2_1")
		)
		(zone
			(layer "F.Cu")
			(hatch none 0.5)
			(connect_pads
				(clearance 0)
			)
			(min_thickness 0.25)
			(keepout
				(tracks not_allowed)
				(vias allowed)
				(pads allowed)
				(copperpour not_allowed)
				(footprints allowed)
			)
			(placement
				(enabled no)
				(sheetname "")
			)
			(fill
				(thermal_gap 0.5)
				(thermal_bridge_width 0.5)
				(island_removal_mode 0)
			)
			(polygon
				(pts
					(xy 118.185692 -174.467774) (xy 118.185692 -174.17415) (xy 113.185448 -174.17415) (xy 113.185448 -174.467774)
					(xy 113.47577 -174.467774) (xy 117.89537 -174.467774)
				)
			)
		)
		(zone
			(layer "F.Cu")
			(hatch none 0.5)
			(connect_pads
				(clearance 0)
			)
			(min_thickness 0.25)
			(keepout
				(tracks not_allowed)
				(vias allowed)
				(pads allowed)
				(copperpour not_allowed)
				(footprints allowed)
			)
			(placement
				(enabled no)
				(sheetname "")
			)
			(fill
				(thermal_gap 0.5)
				(thermal_bridge_width 0.5)
				(island_removal_mode 0)
			)
			(polygon
				(pts
					(xy 115.6335 -171.677076) (xy 115.6335 -169.619676) (xy 117.4877 -169.619676) (xy 117.4877 -169.860722)
					(xy 117.730016 -169.860722) (xy 117.730016 -169.379138) (xy 113.800636 -169.379138) (xy 113.800636 -169.56405)
					(xy 115.342162 -169.56405) (xy 115.342162 -171.72305) (xy 113.185448 -171.72305) (xy 113.185448 -171.972732)
					(xy 115.369848 -171.972732) (xy 115.6335 -171.70908)
				)
			)
		)
	)
	(footprint ""
		(layer "F.Cu")
		(at 19.05 -364.236 180)
		(property "Reference" "PR232"
			(at 0 0 180)
			(layer "F.SilkS")
			(hide yes)
			(effects
				(font
					(size 1.27 1.27)
				)
			)
		)
		(property "Value" ""
			(at 0 0 180)
			(layer "F.Fab")
			(effects
				(font
					(size 1.27 1.27)
				)
			)
		)
		(duplicate_pad_numbers_are_jumpers no)
		(fp_line
			(start 0.7874 0.4064)
			(end -0.7874 0.4064)
			(stroke
				(width 0.1524)
				(type default)
			)
			(layer "F.SilkS")
		)
		(fp_line
			(start 0.7874 -0.4064)
			(end 0.7874 0.4064)
			(stroke
				(width 0.1524)
				(type default)
			)
			(layer "F.SilkS")
		)
		(fp_line
			(start -0.7874 0.4064)
			(end -0.7874 -0.4064)
			(stroke
				(width 0.1524)
				(type default)
			)
			(layer "F.SilkS")
		)
		(fp_line
			(start -0.7874 -0.4064)
			(end 0.7874 -0.4064)
			(stroke
				(width 0.1524)
				(type default)
			)
			(layer "F.SilkS")
		)
		(fp_line
			(start 0.67945 0.3048)
			(end 0.120396 0.3048)
			(stroke
				(width 0.1)
				(type default)
			)
			(layer "F.Fab")
		)
		(fp_line
			(start 0.67945 -0.3048)
			(end 0.67945 0.3048)
			(stroke
				(width 0.1)
				(type default)
			)
			(layer "F.Fab")
		)
		(fp_line
			(start 0.12065 -0.2794)
			(end 0.12065 -0.3048)
			(stroke
				(width 0.1)
				(type default)
			)
			(layer "F.Fab")
		)
		(fp_line
			(start 0.12065 -0.3048)
			(end 0.67945 -0.3048)
			(stroke
				(width 0.1)
				(type default)
			)
			(layer "F.Fab")
		)
		(fp_line
			(start 0.120396 0.3048)
			(end 0.120396 0.2794)
			(stroke
				(width 0.1)
				(type default)
			)
			(layer "F.Fab")
		)
		(fp_line
			(start 0.120396 0.2794)
			(end -0.12065 0.2794)
			(stroke
				(width 0.1)
				(type default)
			)
			(layer "F.Fab")
		)
		(fp_line
			(start -0.12065 0.3048)
			(end -0.67945 0.3048)
			(stroke
				(width 0.1)
				(type default)
			)
			(layer "F.Fab")
		)
		(fp_line
			(start -0.12065 0.2794)
			(end -0.12065 0.3048)
			(stroke
				(width 0.1)
				(type default)
			)
			(layer "F.Fab")
		)
		(fp_line
			(start -0.12065 -0.2794)
			(end 0.12065 -0.2794)
			(stroke
				(width 0.1)
				(type default)
			)
			(layer "F.Fab")
		)
		(fp_line
			(start -0.12065 -0.305054)
			(end -0.12065 -0.2794)
			(stroke
				(width 0.1)
				(type default)
			)
			(layer "F.Fab")
		)
		(fp_line
			(start -0.67945 0.3048)
			(end -0.67945 -0.305054)
			(stroke
				(width 0.1)
				(type default)
			)
			(layer "F.Fab")
		)
		(fp_line
			(start -0.67945 -0.305054)
			(end -0.12065 -0.305054)
			(stroke
				(width 0.1)
				(type default)
			)
			(layer "F.Fab")
		)
		(pad "1" smd circle
			(at -0.40005 0 180)
			(size 0 0)
			(layers "F.Cu" "F.Mask" "F.Paste")
			(net "P3V3_AUX")
		)
		(pad "2" smd circle
			(at 0.40005 0 180)
			(size 0 0)
			(layers "F.Cu" "F.Mask" "F.Paste")
			(net "PVDDIO_P1_EN_G")
		)
	)
	(footprint ""
		(layer "F.Cu")
		(at 181.71033 -92.672408 90)
		(property "Reference" "R6148"
			(at 0 0 90)
			(layer "F.SilkS")
			(hide yes)
			(effects
				(font
					(size 1.27 1.27)
				)
			)
		)
		(property "Value" ""
			(at 0 0 90)
			(layer "F.Fab")
			(effects
				(font
					(size 1.27 1.27)
				)
			)
		)
		(duplicate_pad_numbers_are_jumpers no)
		(fp_line
			(start 0.7874 -0.4064)
			(end 0.7874 0.4064)
			(stroke
				(width 0.1524)
				(type default)
			)
			(layer "F.SilkS")
		)
		(fp_line
			(start -0.7874 -0.4064)
			(end 0.7874 -0.4064)
			(stroke
				(width 0.1524)
				(type default)
			)
			(layer "F.SilkS")
		)
		(fp_line
			(start 0.7874 0.4064)
			(end -0.7874 0.4064)
			(stroke
				(width 0.1524)
				(type default)
			)
			(layer "F.SilkS")
		)
		(fp_line
			(start -0.7874 0.4064)
			(end -0.7874 -0.4064)
			(stroke
				(width 0.1524)
				(type default)
			)
			(layer "F.SilkS")
		)
		(fp_line
			(start -0.12065 -0.305054)
			(end -0.12065 -0.2794)
			(stroke
				(width 0.1)
				(type default)
			)
			(layer "F.Fab")
		)
		(fp_line
			(start -0.67945 -0.305054)
			(end -0.12065 -0.305054)
			(stroke
				(width 0.1)
				(type default)
			)
			(layer "F.Fab")
		)
		(fp_line
			(start 0.67945 -0.3048)
			(end 0.67945 0.3048)
			(stroke
				(width 0.1)
				(type default)
			)
			(layer "F.Fab")
		)
		(fp_line
			(start 0.12065 -0.3048)
			(end 0.67945 -0.3048)
			(stroke
				(width 0.1)
				(type default)
			)
			(layer "F.Fab")
		)
		(fp_line
			(start 0.12065 -0.2794)
			(end 0.12065 -0.3048)
			(stroke
				(width 0.1)
				(type default)
			)
			(layer "F.Fab")
		)
		(fp_line
			(start -0.12065 -0.2794)
			(end 0.12065 -0.2794)
			(stroke
				(width 0.1)
				(type default)
			)
			(layer "F.Fab")
		)
		(fp_line
			(start 0.120396 0.2794)
			(end -0.12065 0.2794)
			(stroke
				(width 0.1)
				(type default)
			)
			(layer "F.Fab")
		)
		(fp_line
			(start -0.12065 0.2794)
			(end -0.12065 0.3048)
			(stroke
				(width 0.1)
				(type default)
			)
			(layer "F.Fab")
		)
		(fp_line
			(start 0.67945 0.3048)
			(end 0.120396 0.3048)
			(stroke
				(width 0.1)
				(type default)
			)
			(layer "F.Fab")
		)
		(fp_line
			(start 0.120396 0.3048)
			(end 0.120396 0.2794)
			(stroke
				(width 0.1)
				(type default)
			)
			(layer "F.Fab")
		)
		(fp_line
			(start -0.12065 0.3048)
			(end -0.67945 0.3048)
			(stroke
				(width 0.1)
				(type default)
			)
			(layer "F.Fab")
		)
		(fp_line
			(start -0.67945 0.3048)
			(end -0.67945 -0.305054)
			(stroke
				(width 0.1)
				(type default)
			)
			(layer "F.Fab")
		)
		(pad "1" smd circle
			(at -0.40005 0 90)
			(size 0 0)
			(layers "F.Cu" "F.Mask" "F.Paste")
			(net "P1V8_AUX")
		)
		(pad "2" smd circle
			(at 0.40005 0 90)
			(size 0 0)
			(layers "F.Cu" "F.Mask" "F.Paste")
			(net "FAB_BMC_REV_ID0")
		)
	)
	(footprint ""
		(layer "F.Cu")
		(at 194.371722 -76.016866)
		(property "Reference" "R59"
			(at 0 0 0)
			(layer "F.SilkS")
			(hide yes)
			(effects
				(font
					(size 1.27 1.27)
				)
			)
		)
		(property "Value" ""
			(at 0 0 0)
			(layer "F.Fab")
			(effects
				(font
					(size 1.27 1.27)
				)
			)
		)
		(duplicate_pad_numbers_are_jumpers no)
		(fp_line
			(start -0.7874 -0.4064)
			(end 0.7874 -0.4064)
			(stroke
				(width 0.1524)
				(type default)
			)
			(layer "F.SilkS")
		)
		(fp_line
			(start -0.7874 0.4064)
			(end -0.7874 -0.4064)
			(stroke
				(width 0.1524)
				(type default)
			)
			(layer "F.SilkS")
		)
		(fp_line
			(start 0.7874 -0.4064)
			(end 0.7874 0.4064)
			(stroke
				(width 0.1524)
				(type default)
			)
			(layer "F.SilkS")
		)
		(fp_line
			(start 0.7874 0.4064)
			(end -0.7874 0.4064)
			(stroke
				(width 0.1524)
				(type default)
			)
			(layer "F.SilkS")
		)
		(fp_line
			(start -0.67945 -0.305054)
			(end -0.12065 -0.305054)
			(stroke
				(width 0.1)
				(type default)
			)
			(layer "F.Fab")
		)
		(fp_line
			(start -0.67945 0.3048)
			(end -0.67945 -0.305054)
			(stroke
				(width 0.1)
				(type default)
			)
			(layer "F.Fab")
		)
		(fp_line
			(start -0.12065 -0.305054)
			(end -0.12065 -0.2794)
			(stroke
				(width 0.1)
				(type default)
			)
			(layer "F.Fab")
		)
		(fp_line
			(start -0.12065 -0.2794)
			(end 0.12065 -0.2794)
			(stroke
				(width 0.1)
				(type default)
			)
			(layer "F.Fab")
		)
		(fp_line
			(start -0.12065 0.2794)
			(end -0.12065 0.3048)
			(stroke
				(width 0.1)
				(type default)
			)
			(layer "F.Fab")
		)
		(fp_line
			(start -0.12065 0.3048)
			(end -0.67945 0.3048)
			(stroke
				(width 0.1)
				(type default)
			)
			(layer "F.Fab")
		)
		(fp_line
			(start 0.120396 0.2794)
			(end -0.12065 0.2794)
			(stroke
				(width 0.1)
				(type default)
			)
			(layer "F.Fab")
		)
		(fp_line
			(start 0.120396 0.3048)
			(end 0.120396 0.2794)
			(stroke
				(width 0.1)
				(type default)
			)
			(layer "F.Fab")
		)
		(fp_line
			(start 0.12065 -0.3048)
			(end 0.67945 -0.3048)
			(stroke
				(width 0.1)
				(type default)
			)
			(layer "F.Fab")
		)
		(fp_line
			(start 0.12065 -0.2794)
			(end 0.12065 -0.3048)
			(stroke
				(width 0.1)
				(type default)
			)
			(layer "F.Fab")
		)
		(fp_line
			(start 0.67945 -0.3048)
			(end 0.67945 0.3048)
			(stroke
				(width 0.1)
				(type default)
			)
			(layer "F.Fab")
		)
		(fp_line
			(start 0.67945 0.3048)
			(end 0.120396 0.3048)
			(stroke
				(width 0.1)
				(type default)
			)
			(layer "F.Fab")
		)
		(pad "1" smd circle
			(at -0.40005 0)
			(size 0 0)
			(layers "F.Cu" "F.Mask" "F.Paste")
			(net "NCSI_BMC_CRS_DV_R")
		)
		(pad "2" smd circle
			(at 0.40005 0)
			(size 0 0)
			(layers "F.Cu" "F.Mask" "F.Paste")
			(net "RMII_OCP_BMC_CRSDV")
		)
	)
	(footprint ""
		(layer "F.Cu")
		(at 73.496678 -29.845762 90)
		(property "Reference" "PC2165"
			(at 0 0 90)
			(layer "F.SilkS")
			(hide yes)
			(effects
				(font
					(size 1.27 1.27)
				)
			)
		)
		(property "Value" ""
			(at 0 0 90)
			(layer "F.Fab")
			(effects
				(font
					(size 1.27 1.27)
				)
			)
		)
		(duplicate_pad_numbers_are_jumpers no)
		(fp_line
			(start 0.7874 -0.4064)
			(end 0.7874 0.4064)
			(stroke
				(width 0.1524)
				(type default)
			)
			(layer "F.SilkS")
		)
		(fp_line
			(start -0.7874 -0.4064)
			(end 0.7874 -0.4064)
			(stroke
				(width 0.1524)
				(type default)
			)
			(layer "F.SilkS")
		)
		(fp_line
			(start 0.7874 0.4064)
			(end -0.7874 0.4064)
			(stroke
				(width 0.1524)
				(type default)
			)
			(layer "F.SilkS")
		)
		(fp_line
			(start -0.7874 0.4064)
			(end -0.7874 -0.4064)
			(stroke
				(width 0.1524)
				(type default)
			)
			(layer "F.SilkS")
		)
		(fp_line
			(start -0.12065 -0.305054)
			(end -0.12065 -0.2794)
			(stroke
				(width 0.1)
				(type default)
			)
			(layer "F.Fab")
		)
		(fp_line
			(start -0.67945 -0.305054)
			(end -0.12065 -0.305054)
			(stroke
				(width 0.1)
				(type default)
			)
			(layer "F.Fab")
		)
		(fp_line
			(start 0.67945 -0.3048)
			(end 0.67945 0.3048)
			(stroke
				(width 0.1)
				(type default)
			)
			(layer "F.Fab")
		)
		(fp_line
			(start 0.12065 -0.3048)
			(end 0.67945 -0.3048)
			(stroke
				(width 0.1)
				(type default)
			)
			(layer "F.Fab")
		)
		(fp_line
			(start 0.12065 -0.2794)
			(end 0.12065 -0.3048)
			(stroke
				(width 0.1)
				(type default)
			)
			(layer "F.Fab")
		)
		(fp_line
			(start -0.12065 -0.2794)
			(end 0.12065 -0.2794)
			(stroke
				(width 0.1)
				(type default)
			)
			(layer "F.Fab")
		)
		(fp_line
			(start 0.120396 0.2794)
			(end -0.12065 0.2794)
			(stroke
				(width 0.1)
				(type default)
			)
			(layer "F.Fab")
		)
		(fp_line
			(start -0.12065 0.2794)
			(end -0.12065 0.3048)
			(stroke
				(width 0.1)
				(type default)
			)
			(layer "F.Fab")
		)
		(fp_line
			(start 0.67945 0.3048)
			(end 0.120396 0.3048)
			(stroke
				(width 0.1)
				(type default)
			)
			(layer "F.Fab")
		)
		(fp_line
			(start 0.120396 0.3048)
			(end 0.120396 0.2794)
			(stroke
				(width 0.1)
				(type default)
			)
			(layer "F.Fab")
		)
		(fp_line
			(start -0.12065 0.3048)
			(end -0.67945 0.3048)
			(stroke
				(width 0.1)
				(type default)
			)
			(layer "F.Fab")
		)
		(fp_line
			(start -0.67945 0.3048)
			(end -0.67945 -0.305054)
			(stroke
				(width 0.1)
				(type default)
			)
			(layer "F.Fab")
		)
		(pad "1" smd circle
			(at -0.40005 0 90)
			(size 0 0)
			(layers "F.Cu" "F.Mask" "F.Paste")
			(net "P12V_AUX")
		)
		(pad "2" smd circle
			(at 0.40005 0 90)
			(size 0 0)
			(layers "F.Cu" "F.Mask" "F.Paste")
			(net "GND")
		)
	)
	(footprint ""
		(layer "F.Cu")
		(at 366.36579 -393.96416)
		(property "Reference" "R1112"
			(at 0 0 0)
			(layer "F.SilkS")
			(hide yes)
			(effects
				(font
					(size 1.27 1.27)
				)
			)
		)
		(property "Value" ""
			(at 0 0 0)
			(layer "F.Fab")
			(effects
				(font
					(size 1.27 1.27)
				)
			)
		)
		(duplicate_pad_numbers_are_jumpers no)
		(fp_line
			(start -0.32512 -0.175006)
			(end 0.32512 -0.175006)
			(stroke
				(width 0.1)
				(type default)
			)
			(layer "F.Fab")
		)
		(fp_line
			(start -0.32512 0.175006)
			(end -0.32512 -0.175006)
			(stroke
				(width 0.1)
				(type default)
			)
			(layer "F.Fab")
		)
		(fp_line
			(start 0.32512 -0.175006)
			(end 0.32512 0.175006)
			(stroke
				(width 0.1)
				(type default)
			)
			(layer "F.Fab")
		)
		(fp_line
			(start 0.32512 0.175006)
			(end -0.32512 0.175006)
			(stroke
				(width 0.1)
				(type default)
			)
			(layer "F.Fab")
		)
		(pad "1" smd rect
			(at -0.2667 0)
			(size 0.3048 0.381)
			(layers "F.Cu" "F.Mask" "F.Paste")
			(net "GPIO2_RT_CPU0_P3")
		)
		(pad "2" smd rect
			(at 0.2667 0 180)
			(size 0.3048 0.381)
			(layers "F.Cu" "F.Mask" "F.Paste")
			(net "GND")
		)
	)
	(footprint ""
		(layer "F.Cu")
		(at 440.687968 -94.077536 180)
		(property "Reference" "U266"
			(at 0.221996 2.912872 0)
			(unlocked yes)
			(layer "F.SilkS")
			(effects
				(font
					(size 0.7874 0.5842)
					(thickness 0.1524)
				)
			)
		)
		(property "Value" ""
			(at 0 0 180)
			(layer "F.Fab")
			(effects
				(font
					(size 1.27 1.27)
				)
			)
		)
		(duplicate_pad_numbers_are_jumpers no)
		(fp_line
			(start 1.500124 1.500124)
			(end 1.004062 1.500124)
			(stroke
				(width 0.1524)
				(type default)
			)
			(layer "F.SilkS")
		)
		(fp_line
			(start 1.500124 1.004062)
			(end 1.500124 1.500124)
			(stroke
				(width 0.1524)
				(type default)
			)
			(layer "F.SilkS")
		)
		(fp_line
			(start 1.500124 -1.500124)
			(end 1.500124 -1.004062)
			(stroke
				(width 0.1524)
				(type default)
			)
			(layer "F.SilkS")
		)
		(fp_line
			(start 1.004062 -1.500124)
			(end 1.500124 -1.500124)
			(stroke
				(width 0.1524)
				(type default)
			)
			(layer "F.SilkS")
		)
		(fp_line
			(start -1.004062 1.500124)
			(end -1.500124 1.500124)
			(stroke
				(width 0.1524)
				(type default)
			)
			(layer "F.SilkS")
		)
		(fp_line
			(start -1.500124 1.500124)
			(end -1.500124 1.004062)
			(stroke
				(width 0.1524)
				(type default)
			)
			(layer "F.SilkS")
		)
		(fp_line
			(start -1.500124 -1.004062)
			(end -1.500124 -1.500124)
			(stroke
				(width 0.1524)
				(type default)
			)
			(layer "F.SilkS")
		)
		(fp_line
			(start -1.500124 -1.500124)
			(end -1.004062 -1.500124)
			(stroke
				(width 0.1524)
				(type default)
			)
			(layer "F.SilkS")
		)
		(fp_poly
			(pts
				(xy -2.242312 -0.54102) (xy -2.242312 -0.999744) (xy -1.783588 -0.770382)
			)
			(stroke
				(width 0)
				(type default)
			)
			(fill yes)
			(layer "F.SilkS")
		)
		(fp_line
			(start 1.500124 1.500124)
			(end -1.500124 1.500124)
			(stroke
				(width 0.1)
				(type default)
			)
			(layer "F.Fab")
		)
		(fp_line
			(start 1.500124 -1.500124)
			(end 1.500124 1.500124)
			(stroke
				(width 0.1)
				(type default)
			)
			(layer "F.Fab")
		)
		(fp_line
			(start -1.500124 1.500124)
			(end -1.500124 -1.500124)
			(stroke
				(width 0.1)
				(type default)
			)
			(layer "F.Fab")
		)
		(fp_line
			(start -1.500124 -1.500124)
			(end 1.500124 -1.500124)
			(stroke
				(width 0.1)
				(type default)
			)
			(layer "F.Fab")
		)
		(fp_poly
			(pts
				(xy -2.847848 -1.258062) (xy -2.847848 -0.242062) (xy -1.831848 -0.750062)
			)
			(stroke
				(width 0)
				(type default)
			)
			(fill yes)
			(layer "F.Fab")
		)
		(pad "1" smd rect
			(at -1.400048 -0.750062 90)
			(size 0.2286 0.6096)
			(layers "F.Cu" "F.Mask" "F.Paste")
			(net "INA230_1_A1")
		)
		(pad "2" smd rect
			(at -1.400048 -0.249936 90)
			(size 0.2286 0.6096)
			(layers "F.Cu" "F.Mask" "F.Paste")
			(net "INA230_1_A0")
		)
		(pad "3" smd rect
			(at -1.400048 0.249936 90)
			(size 0.2286 0.6096)
			(layers "F.Cu" "F.Mask" "F.Paste")
			(net "OCP_SFF_P3V3_ADC_ALERT_R")
		)
		(pad "4" smd rect
			(at -1.400048 0.750062 90)
			(size 0.2286 0.6096)
			(layers "F.Cu" "F.Mask" "F.Paste")
			(net "SMB_INA230_1_3V3AUX_SDA_R1")
		)
		(pad "5" smd rect
			(at -0.750062 1.400048 180)
			(size 0.2286 0.6096)
			(layers "F.Cu" "F.Mask" "F.Paste")
			(net "SMB_INA230_1_3V3AUX_SCL_R1")
		)
		(pad "6" smd rect
			(at -0.249936 1.400048 180)
			(size 0.2286 0.6096)
			(layers "F.Cu" "F.Mask" "F.Paste")
			(net "NC_INA230_1_NC0")
		)
		(pad "7" smd rect
			(at 0.249936 1.400048 180)
			(size 0.2286 0.6096)
			(layers "F.Cu" "F.Mask" "F.Paste")
			(net "NC_INA230_1_NC1")
		)
		(pad "8" smd rect
			(at 0.750062 1.400048 180)
			(size 0.2286 0.6096)
			(layers "F.Cu" "F.Mask" "F.Paste")
			(net "NC_INA230_1_NC2")
		)
		(pad "9" smd rect
			(at 1.400048 0.750062 90)
			(size 0.2286 0.6096)
			(layers "F.Cu" "F.Mask" "F.Paste")
			(net "P3V3_AUX")
		)
		(pad "10" smd rect
			(at 1.400048 0.249936 90)
			(size 0.2286 0.6096)
			(layers "F.Cu" "F.Mask" "F.Paste")
			(net "GND")
		)
		(pad "11" smd rect
			(at 1.400048 -0.249936 90)
			(size 0.2286 0.6096)
			(layers "F.Cu" "F.Mask" "F.Paste")
			(net "P3V3_OCP_SFF_R")
		)
		(pad "12" smd rect
			(at 1.400048 -0.750062 90)
			(size 0.2286 0.6096)
			(layers "F.Cu" "F.Mask" "F.Paste")
			(net "VSENSE_P3V3_INA230_1_INN")
		)
		(pad "13" smd rect
			(at 0.750062 -1.400048 180)
			(size 0.2286 0.6096)
			(layers "F.Cu" "F.Mask" "F.Paste")
			(net "VSENSE_P3V3_INA230_1_INP")
		)
		(pad "14" smd rect
			(at 0.249936 -1.400048 180)
			(size 0.2286 0.6096)
			(layers "F.Cu" "F.Mask" "F.Paste")
			(net "NC_INA230_1_NC3")
		)
		(pad "15" smd rect
			(at -0.249936 -1.400048 180)
			(size 0.2286 0.6096)
			(layers "F.Cu" "F.Mask" "F.Paste")
			(net "NC_INA230_1_NC4")
		)
		(pad "16" smd rect
			(at -0.750062 -1.400048 180)
			(size 0.2286 0.6096)
			(layers "F.Cu" "F.Mask" "F.Paste")
			(net "NC_INA230_1_NC5")
		)
		(pad "TH" smd rect
			(at 0 0 180)
			(size 1.7018 1.7018)
			(layers "F.Cu" "F.Mask" "F.Paste")
			(net "GND")
		)
		(zone
			(layer "F.Cu")
			(hatch none 0.5)
			(connect_pads
				(clearance 0)
			)
			(min_thickness 0.25)
			(keepout
				(tracks not_allowed)
				(vias allowed)
				(pads allowed)
				(copperpour not_allowed)
				(footprints allowed)
			)
			(placement
				(enabled no)
				(sheetname "")
			)
			(fill
				(thermal_gap 0.5)
				(thermal_bridge_width 0.5)
				(island_removal_mode 0)
			)
			(polygon
				(pts
					(xy 441.732416 -94.052136) (xy 441.732416 -93.033088) (xy 439.64352 -93.033088) (xy 439.64352 -95.121984)
					(xy 441.732416 -95.121984) (xy 441.732416 -94.077536) (xy 441.589668 -94.077536) (xy 441.589668 -94.979236)
					(xy 439.786268 -94.979236) (xy 439.786268 -93.175836) (xy 441.589668 -93.175836) (xy 441.589668 -94.052136)
				)
			)
		)
	)
	(footprint ""
		(layer "F.Cu")
		(at 259.842 -143.764)
		(property "Reference" "R127"
			(at 0 0 0)
			(layer "F.SilkS")
			(hide yes)
			(effects
				(font
					(size 1.27 1.27)
				)
			)
		)
		(property "Value" ""
			(at 0 0 0)
			(layer "F.Fab")
			(effects
				(font
					(size 1.27 1.27)
				)
			)
		)
		(duplicate_pad_numbers_are_jumpers no)
		(fp_line
			(start -0.7874 -0.4064)
			(end 0.7874 -0.4064)
			(stroke
				(width 0.1524)
				(type default)
			)
			(layer "F.SilkS")
		)
		(fp_line
			(start -0.7874 0.4064)
			(end -0.7874 -0.4064)
			(stroke
				(width 0.1524)
				(type default)
			)
			(layer "F.SilkS")
		)
		(fp_line
			(start 0.7874 -0.4064)
			(end 0.7874 0.4064)
			(stroke
				(width 0.1524)
				(type default)
			)
			(layer "F.SilkS")
		)
		(fp_line
			(start 0.7874 0.4064)
			(end -0.7874 0.4064)
			(stroke
				(width 0.1524)
				(type default)
			)
			(layer "F.SilkS")
		)
		(fp_line
			(start -0.67945 -0.305054)
			(end -0.12065 -0.305054)
			(stroke
				(width 0.1)
				(type default)
			)
			(layer "F.Fab")
		)
		(fp_line
			(start -0.67945 0.3048)
			(end -0.67945 -0.305054)
			(stroke
				(width 0.1)
				(type default)
			)
			(layer "F.Fab")
		)
		(fp_line
			(start -0.12065 -0.305054)
			(end -0.12065 -0.2794)
			(stroke
				(width 0.1)
				(type default)
			)
			(layer "F.Fab")
		)
		(fp_line
			(start -0.12065 -0.2794)
			(end 0.12065 -0.2794)
			(stroke
				(width 0.1)
				(type default)
			)
			(layer "F.Fab")
		)
		(fp_line
			(start -0.12065 0.2794)
			(end -0.12065 0.3048)
			(stroke
				(width 0.1)
				(type default)
			)
			(layer "F.Fab")
		)
		(fp_line
			(start -0.12065 0.3048)
			(end -0.67945 0.3048)
			(stroke
				(width 0.1)
				(type default)
			)
			(layer "F.Fab")
		)
		(fp_line
			(start 0.120396 0.2794)
			(end -0.12065 0.2794)
			(stroke
				(width 0.1)
				(type default)
			)
			(layer "F.Fab")
		)
		(fp_line
			(start 0.120396 0.3048)
			(end 0.120396 0.2794)
			(stroke
				(width 0.1)
				(type default)
			)
			(layer "F.Fab")
		)
		(fp_line
			(start 0.12065 -0.3048)
			(end 0.67945 -0.3048)
			(stroke
				(width 0.1)
				(type default)
			)
			(layer "F.Fab")
		)
		(fp_line
			(start 0.12065 -0.2794)
			(end 0.12065 -0.3048)
			(stroke
				(width 0.1)
				(type default)
			)
			(layer "F.Fab")
		)
		(fp_line
			(start 0.67945 -0.3048)
			(end 0.67945 0.3048)
			(stroke
				(width 0.1)
				(type default)
			)
			(layer "F.Fab")
		)
		(fp_line
			(start 0.67945 0.3048)
			(end 0.120396 0.3048)
			(stroke
				(width 0.1)
				(type default)
			)
			(layer "F.Fab")
		)
		(pad "1" smd circle
			(at -0.40005 0)
			(size 0 0)
			(layers "F.Cu" "F.Mask" "F.Paste")
			(net "P3V3_AUX")
		)
		(pad "2" smd circle
			(at 0.40005 0)
			(size 0 0)
			(layers "F.Cu" "F.Mask" "F.Paste")
			(net "SPI_CPU0_LVC3_SCM_D1")
		)
	)
	(footprint ""
		(layer "F.Cu")
		(at 430.666144 -356.35184 180)
		(property "Reference" "PR134"
			(at 0 0 180)
			(layer "F.SilkS")
			(hide yes)
			(effects
				(font
					(size 1.27 1.27)
				)
			)
		)
		(property "Value" ""
			(at 0 0 180)
			(layer "F.Fab")
			(effects
				(font
					(size 1.27 1.27)
				)
			)
		)
		(duplicate_pad_numbers_are_jumpers no)
		(fp_line
			(start 0.7874 0.4064)
			(end -0.7874 0.4064)
			(stroke
				(width 0.1524)
				(type default)
			)
			(layer "F.SilkS")
		)
		(fp_line
			(start 0.7874 -0.4064)
			(end 0.7874 0.4064)
			(stroke
				(width 0.1524)
				(type default)
			)
			(layer "F.SilkS")
		)
		(fp_line
			(start -0.7874 0.4064)
			(end -0.7874 -0.4064)
			(stroke
				(width 0.1524)
				(type default)
			)
			(layer "F.SilkS")
		)
		(fp_line
			(start -0.7874 -0.4064)
			(end 0.7874 -0.4064)
			(stroke
				(width 0.1524)
				(type default)
			)
			(layer "F.SilkS")
		)
		(fp_line
			(start 0.67945 0.3048)
			(end 0.120396 0.3048)
			(stroke
				(width 0.1)
				(type default)
			)
			(layer "F.Fab")
		)
		(fp_line
			(start 0.67945 -0.3048)
			(end 0.67945 0.3048)
			(stroke
				(width 0.1)
				(type default)
			)
			(layer "F.Fab")
		)
		(fp_line
			(start 0.12065 -0.2794)
			(end 0.12065 -0.3048)
			(stroke
				(width 0.1)
				(type default)
			)
			(layer "F.Fab")
		)
		(fp_line
			(start 0.12065 -0.3048)
			(end 0.67945 -0.3048)
			(stroke
				(width 0.1)
				(type default)
			)
			(layer "F.Fab")
		)
		(fp_line
			(start 0.120396 0.3048)
			(end 0.120396 0.2794)
			(stroke
				(width 0.1)
				(type default)
			)
			(layer "F.Fab")
		)
		(fp_line
			(start 0.120396 0.2794)
			(end -0.12065 0.2794)
			(stroke
				(width 0.1)
				(type default)
			)
			(layer "F.Fab")
		)
		(fp_line
			(start -0.12065 0.3048)
			(end -0.67945 0.3048)
			(stroke
				(width 0.1)
				(type default)
			)
			(layer "F.Fab")
		)
		(fp_line
			(start -0.12065 0.2794)
			(end -0.12065 0.3048)
			(stroke
				(width 0.1)
				(type default)
			)
			(layer "F.Fab")
		)
		(fp_line
			(start -0.12065 -0.2794)
			(end 0.12065 -0.2794)
			(stroke
				(width 0.1)
				(type default)
			)
			(layer "F.Fab")
		)
		(fp_line
			(start -0.12065 -0.305054)
			(end -0.12065 -0.2794)
			(stroke
				(width 0.1)
				(type default)
			)
			(layer "F.Fab")
		)
		(fp_line
			(start -0.67945 0.3048)
			(end -0.67945 -0.305054)
			(stroke
				(width 0.1)
				(type default)
			)
			(layer "F.Fab")
		)
		(fp_line
			(start -0.67945 -0.305054)
			(end -0.12065 -0.305054)
			(stroke
				(width 0.1)
				(type default)
			)
			(layer "F.Fab")
		)
		(pad "1" smd circle
			(at -0.40005 0 180)
			(size 0 0)
			(layers "F.Cu" "F.Mask" "F.Paste")
			(net "GND")
		)
		(pad "2" smd circle
			(at 0.40005 0 180)
			(size 0 0)
			(layers "F.Cu" "F.Mask" "F.Paste")
			(net "PVDD11_S3_P0_LSET2")
		)
	)
	(footprint ""
		(layer "F.Cu")
		(at 308.528974 -33.351978)
		(property "Reference" "U166"
			(at -1.4224 -1.844548 0)
			(unlocked yes)
			(layer "F.SilkS")
			(effects
				(font
					(size 0.7874 0.5842)
					(thickness 0.1524)
				)
				(justify left)
			)
		)
		(property "Value" ""
			(at 0 0 0)
			(layer "F.Fab")
			(effects
				(font
					(size 1.27 1.27)
				)
			)
		)
		(duplicate_pad_numbers_are_jumpers no)
		(fp_line
			(start -1.335278 -1.100074)
			(end -1.335278 1.100074)
			(stroke
				(width 0.1524)
				(type default)
			)
			(layer "F.SilkS")
		)
		(fp_line
			(start -1.335278 1.100074)
			(end 1.335278 1.100074)
			(stroke
				(width 0.1524)
				(type default)
			)
			(layer "F.SilkS")
		)
		(fp_line
			(start 1.335278 -1.100074)
			(end -1.335278 -1.100074)
			(stroke
				(width 0.1524)
				(type default)
			)
			(layer "F.SilkS")
		)
		(fp_line
			(start 1.335278 1.100074)
			(end 1.335278 -1.100074)
			(stroke
				(width 0.1524)
				(type default)
			)
			(layer "F.SilkS")
		)
		(fp_line
			(start -0.674878 -1.100074)
			(end -0.674878 1.100074)
			(stroke
				(width 0.1)
				(type default)
			)
			(layer "F.Fab")
		)
		(fp_line
			(start -0.674878 1.100074)
			(end 0.674878 1.100074)
			(stroke
				(width 0.1)
				(type default)
			)
			(layer "F.Fab")
		)
		(fp_line
			(start 0.674878 -1.100074)
			(end -0.674878 -1.100074)
			(stroke
				(width 0.1)
				(type default)
			)
			(layer "F.Fab")
		)
		(fp_line
			(start 0.674878 1.100074)
			(end 0.674878 -1.100074)
			(stroke
				(width 0.1)
				(type default)
			)
			(layer "F.Fab")
		)
		(pad "1" smd rect
			(at -0.8001 0.649986 270)
			(size 0.6096 0.8128)
			(layers "F.Cu" "F.Mask" "F.Paste")
			(net "P3V3_STBY_R")
		)
		(pad "2" smd rect
			(at -0.8001 -0.649986 270)
			(size 0.6096 0.8128)
			(layers "F.Cu" "F.Mask" "F.Paste")
			(net "P3V_BAT_R")
		)
		(pad "3" smd rect
			(at 0.8001 0 270)
			(size 0.6096 0.8128)
			(layers "F.Cu" "F.Mask" "F.Paste")
			(net "P3V3_RTC_AUX")
		)
	)
	(footprint ""
		(layer "F.Cu")
		(at 463.735928 -94.317566)
		(property "Reference" "R3233"
			(at 0 0 0)
			(layer "F.SilkS")
			(hide yes)
			(effects
				(font
					(size 1.27 1.27)
				)
			)
		)
		(property "Value" ""
			(at 0 0 0)
			(layer "F.Fab")
			(effects
				(font
					(size 1.27 1.27)
				)
			)
		)
		(duplicate_pad_numbers_are_jumpers no)
		(fp_line
			(start -0.7874 -0.4064)
			(end 0.7874 -0.4064)
			(stroke
				(width 0.1524)
				(type default)
			)
			(layer "F.SilkS")
		)
		(fp_line
			(start -0.7874 0.4064)
			(end -0.7874 -0.4064)
			(stroke
				(width 0.1524)
				(type default)
			)
			(layer "F.SilkS")
		)
		(fp_line
			(start 0.7874 -0.4064)
			(end 0.7874 0.4064)
			(stroke
				(width 0.1524)
				(type default)
			)
			(layer "F.SilkS")
		)
		(fp_line
			(start 0.7874 0.4064)
			(end -0.7874 0.4064)
			(stroke
				(width 0.1524)
				(type default)
			)
			(layer "F.SilkS")
		)
		(fp_line
			(start -0.67945 -0.305054)
			(end -0.12065 -0.305054)
			(stroke
				(width 0.1)
				(type default)
			)
			(layer "F.Fab")
		)
		(fp_line
			(start -0.67945 0.3048)
			(end -0.67945 -0.305054)
			(stroke
				(width 0.1)
				(type default)
			)
			(layer "F.Fab")
		)
		(fp_line
			(start -0.12065 -0.305054)
			(end -0.12065 -0.2794)
			(stroke
				(width 0.1)
				(type default)
			)
			(layer "F.Fab")
		)
		(fp_line
			(start -0.12065 -0.2794)
			(end 0.12065 -0.2794)
			(stroke
				(width 0.1)
				(type default)
			)
			(layer "F.Fab")
		)
		(fp_line
			(start -0.12065 0.2794)
			(end -0.12065 0.3048)
			(stroke
				(width 0.1)
				(type default)
			)
			(layer "F.Fab")
		)
		(fp_line
			(start -0.12065 0.3048)
			(end -0.67945 0.3048)
			(stroke
				(width 0.1)
				(type default)
			)
			(layer "F.Fab")
		)
		(fp_line
			(start 0.120396 0.2794)
			(end -0.12065 0.2794)
			(stroke
				(width 0.1)
				(type default)
			)
			(layer "F.Fab")
		)
		(fp_line
			(start 0.120396 0.3048)
			(end 0.120396 0.2794)
			(stroke
				(width 0.1)
				(type default)
			)
			(layer "F.Fab")
		)
		(fp_line
			(start 0.12065 -0.3048)
			(end 0.67945 -0.3048)
			(stroke
				(width 0.1)
				(type default)
			)
			(layer "F.Fab")
		)
		(fp_line
			(start 0.12065 -0.2794)
			(end 0.12065 -0.3048)
			(stroke
				(width 0.1)
				(type default)
			)
			(layer "F.Fab")
		)
		(fp_line
			(start 0.67945 -0.3048)
			(end 0.67945 0.3048)
			(stroke
				(width 0.1)
				(type default)
			)
			(layer "F.Fab")
		)
		(fp_line
			(start 0.67945 0.3048)
			(end 0.120396 0.3048)
			(stroke
				(width 0.1)
				(type default)
			)
			(layer "F.Fab")
		)
		(pad "1" smd circle
			(at -0.40005 0)
			(size 0 0)
			(layers "F.Cu" "F.Mask" "F.Paste")
			(net "RST_HP_OCP_SFF_R_N")
		)
		(pad "2" smd circle
			(at 0.40005 0)
			(size 0 0)
			(layers "F.Cu" "F.Mask" "F.Paste")
			(net "RST_SMB_OCP_SFF_N")
		)
	)
	(footprint ""
		(layer "F.Cu")
		(at 294.421052 -118.285514)
		(property "Reference" "R3581"
			(at 0 0 0)
			(layer "F.SilkS")
			(hide yes)
			(effects
				(font
					(size 1.27 1.27)
				)
			)
		)
		(property "Value" ""
			(at 0 0 0)
			(layer "F.Fab")
			(effects
				(font
					(size 1.27 1.27)
				)
			)
		)
		(duplicate_pad_numbers_are_jumpers no)
		(fp_line
			(start -0.7874 -0.4064)
			(end 0.7874 -0.4064)
			(stroke
				(width 0.1524)
				(type default)
			)
			(layer "F.SilkS")
		)
		(fp_line
			(start -0.7874 0.4064)
			(end -0.7874 -0.4064)
			(stroke
				(width 0.1524)
				(type default)
			)
			(layer "F.SilkS")
		)
		(fp_line
			(start 0.7874 -0.4064)
			(end 0.7874 0.4064)
			(stroke
				(width 0.1524)
				(type default)
			)
			(layer "F.SilkS")
		)
		(fp_line
			(start 0.7874 0.4064)
			(end -0.7874 0.4064)
			(stroke
				(width 0.1524)
				(type default)
			)
			(layer "F.SilkS")
		)
		(fp_line
			(start -0.67945 -0.305054)
			(end -0.12065 -0.305054)
			(stroke
				(width 0.1)
				(type default)
			)
			(layer "F.Fab")
		)
		(fp_line
			(start -0.67945 0.3048)
			(end -0.67945 -0.305054)
			(stroke
				(width 0.1)
				(type default)
			)
			(layer "F.Fab")
		)
		(fp_line
			(start -0.12065 -0.305054)
			(end -0.12065 -0.2794)
			(stroke
				(width 0.1)
				(type default)
			)
			(layer "F.Fab")
		)
		(fp_line
			(start -0.12065 -0.2794)
			(end 0.12065 -0.2794)
			(stroke
				(width 0.1)
				(type default)
			)
			(layer "F.Fab")
		)
		(fp_line
			(start -0.12065 0.2794)
			(end -0.12065 0.3048)
			(stroke
				(width 0.1)
				(type default)
			)
			(layer "F.Fab")
		)
		(fp_line
			(start -0.12065 0.3048)
			(end -0.67945 0.3048)
			(stroke
				(width 0.1)
				(type default)
			)
			(layer "F.Fab")
		)
		(fp_line
			(start 0.120396 0.2794)
			(end -0.12065 0.2794)
			(stroke
				(width 0.1)
				(type default)
			)
			(layer "F.Fab")
		)
		(fp_line
			(start 0.120396 0.3048)
			(end 0.120396 0.2794)
			(stroke
				(width 0.1)
				(type default)
			)
			(layer "F.Fab")
		)
		(fp_line
			(start 0.12065 -0.3048)
			(end 0.67945 -0.3048)
			(stroke
				(width 0.1)
				(type default)
			)
			(layer "F.Fab")
		)
		(fp_line
			(start 0.12065 -0.2794)
			(end 0.12065 -0.3048)
			(stroke
				(width 0.1)
				(type default)
			)
			(layer "F.Fab")
		)
		(fp_line
			(start 0.67945 -0.3048)
			(end 0.67945 0.3048)
			(stroke
				(width 0.1)
				(type default)
			)
			(layer "F.Fab")
		)
		(fp_line
			(start 0.67945 0.3048)
			(end 0.120396 0.3048)
			(stroke
				(width 0.1)
				(type default)
			)
			(layer "F.Fab")
		)
		(pad "1" smd circle
			(at -0.40005 0)
			(size 0 0)
			(layers "F.Cu" "F.Mask" "F.Paste")
			(net "SMB_INA230_3V3AUX_SDA_R")
		)
		(pad "2" smd circle
			(at 0.40005 0)
			(size 0 0)
			(layers "F.Cu" "F.Mask" "F.Paste")
			(net "SMB_INA230_3V3AUX_SDA")
		)
	)
	(footprint ""
		(layer "F.Cu")
		(at 180.710332 -92.67444 -90)
		(property "Reference" "R6149"
			(at 0 0 270)
			(layer "F.SilkS")
			(hide yes)
			(effects
				(font
					(size 1.27 1.27)
				)
			)
		)
		(property "Value" ""
			(at 0 0 270)
			(layer "F.Fab")
			(effects
				(font
					(size 1.27 1.27)
				)
			)
		)
		(duplicate_pad_numbers_are_jumpers no)
		(fp_line
			(start -0.7874 0.4064)
			(end -0.7874 -0.4064)
			(stroke
				(width 0.1524)
				(type default)
			)
			(layer "F.SilkS")
		)
		(fp_line
			(start 0.7874 0.4064)
			(end -0.7874 0.4064)
			(stroke
				(width 0.1524)
				(type default)
			)
			(layer "F.SilkS")
		)
		(fp_line
			(start -0.7874 -0.4064)
			(end 0.7874 -0.4064)
			(stroke
				(width 0.1524)
				(type default)
			)
			(layer "F.SilkS")
		)
		(fp_line
			(start 0.7874 -0.4064)
			(end 0.7874 0.4064)
			(stroke
				(width 0.1524)
				(type default)
			)
			(layer "F.SilkS")
		)
		(fp_line
			(start -0.67945 0.3048)
			(end -0.67945 -0.305054)
			(stroke
				(width 0.1)
				(type default)
			)
			(layer "F.Fab")
		)
		(fp_line
			(start -0.12065 0.3048)
			(end -0.67945 0.3048)
			(stroke
				(width 0.1)
				(type default)
			)
			(layer "F.Fab")
		)
		(fp_line
			(start 0.120396 0.3048)
			(end 0.120396 0.2794)
			(stroke
				(width 0.1)
				(type default)
			)
			(layer "F.Fab")
		)
		(fp_line
			(start 0.67945 0.3048)
			(end 0.120396 0.3048)
			(stroke
				(width 0.1)
				(type default)
			)
			(layer "F.Fab")
		)
		(fp_line
			(start -0.12065 0.2794)
			(end -0.12065 0.3048)
			(stroke
				(width 0.1)
				(type default)
			)
			(layer "F.Fab")
		)
		(fp_line
			(start 0.120396 0.2794)
			(end -0.12065 0.2794)
			(stroke
				(width 0.1)
				(type default)
			)
			(layer "F.Fab")
		)
		(fp_line
			(start -0.12065 -0.2794)
			(end 0.12065 -0.2794)
			(stroke
				(width 0.1)
				(type default)
			)
			(layer "F.Fab")
		)
		(fp_line
			(start 0.12065 -0.2794)
			(end 0.12065 -0.3048)
			(stroke
				(width 0.1)
				(type default)
			)
			(layer "F.Fab")
		)
		(fp_line
			(start 0.12065 -0.3048)
			(end 0.67945 -0.3048)
			(stroke
				(width 0.1)
				(type default)
			)
			(layer "F.Fab")
		)
		(fp_line
			(start 0.67945 -0.3048)
			(end 0.67945 0.3048)
			(stroke
				(width 0.1)
				(type default)
			)
			(layer "F.Fab")
		)
		(fp_line
			(start -0.67945 -0.305054)
			(end -0.12065 -0.305054)
			(stroke
				(width 0.1)
				(type default)
			)
			(layer "F.Fab")
		)
		(fp_line
			(start -0.12065 -0.305054)
			(end -0.12065 -0.2794)
			(stroke
				(width 0.1)
				(type default)
			)
			(layer "F.Fab")
		)
		(pad "1" smd circle
			(at -0.40005 0 270)
			(size 0 0)
			(layers "F.Cu" "F.Mask" "F.Paste")
			(net "FAB_BMC_REV_ID2")
		)
		(pad "2" smd circle
			(at 0.40005 0 270)
			(size 0 0)
			(layers "F.Cu" "F.Mask" "F.Paste")
			(net "GND")
		)
	)
	(footprint ""
		(layer "F.Cu")
		(at 398.046956 -186.488324 180)
		(property "Reference" "PL63"
			(at -4.603242 2.798064 90)
			(unlocked yes)
			(layer "F.SilkS")
			(effects
				(font
					(size 0.7874 0.5842)
					(thickness 0.1524)
				)
				(justify left)
			)
		)
		(property "Value" ""
			(at 0 0 180)
			(layer "F.Fab")
			(effects
				(font
					(size 1.27 1.27)
				)
			)
		)
		(duplicate_pad_numbers_are_jumpers no)
		(fp_line
			(start 3.750056 5.500116)
			(end 3.750056 -5.500116)
			(stroke
				(width 0.1524)
				(type default)
			)
			(layer "F.SilkS")
		)
		(fp_line
			(start 3.750056 -5.500116)
			(end 2.393442 -5.500116)
			(stroke
				(width 0.1524)
				(type default)
			)
			(layer "F.SilkS")
		)
		(fp_line
			(start 2.393442 5.500116)
			(end 3.750056 5.500116)
			(stroke
				(width 0.1524)
				(type default)
			)
			(layer "F.SilkS")
		)
		(fp_line
			(start -2.393442 5.500116)
			(end -3.750056 5.500116)
			(stroke
				(width 0.1524)
				(type default)
			)
			(layer "F.SilkS")
		)
		(fp_line
			(start -3.750056 5.500116)
			(end -3.750056 -5.500116)
			(stroke
				(width 0.1524)
				(type default)
			)
			(layer "F.SilkS")
		)
		(fp_line
			(start -3.750056 -5.500116)
			(end -2.393442 -5.500116)
			(stroke
				(width 0.1524)
				(type default)
			)
			(layer "F.SilkS")
		)
		(fp_poly
			(pts
				(xy -3.9116 -4.249928) (xy -4.543044 -3.934206) (xy -4.543044 -4.56565)
			)
			(stroke
				(width 0)
				(type default)
			)
			(fill yes)
			(layer "F.SilkS")
		)
		(fp_line
			(start 3.750056 5.500116)
			(end 3.750056 -5.500116)
			(stroke
				(width 0.1)
				(type default)
			)
			(layer "F.Fab")
		)
		(fp_line
			(start 3.750056 -5.500116)
			(end -3.750056 -5.500116)
			(stroke
				(width 0.1)
				(type default)
			)
			(layer "F.Fab")
		)
		(fp_line
			(start -3.750056 5.500116)
			(end 3.750056 5.500116)
			(stroke
				(width 0.1)
				(type default)
			)
			(layer "F.Fab")
		)
		(fp_line
			(start -3.750056 -5.500116)
			(end -3.750056 5.500116)
			(stroke
				(width 0.1)
				(type default)
			)
			(layer "F.Fab")
		)
		(fp_poly
			(pts
				(xy -4.9276 -4.757928) (xy -4.9276 -3.741928) (xy -3.9116 -4.249928)
			)
			(stroke
				(width 0)
				(type default)
			)
			(fill yes)
			(layer "F.Fab")
		)
		(pad "1" smd rect
			(at 0 -4.249928 90)
			(size 2.413 4.5212)
			(layers "F.Cu" "F.Mask" "F.Paste")
			(net "SW_PVDDCR_SOC_P0_SW1")
		)
		(pad "2" smd rect
			(at 0 -1.175004 90)
			(size 1.3716 4.5212)
			(layers "F.Cu" "F.Mask" "F.Paste")
			(net "IND_SOC_P0_CPL2")
		)
		(pad "3" smd rect
			(at 0 1.175004 90)
			(size 1.3716 4.5212)
			(layers "F.Cu" "F.Mask" "F.Paste")
			(net "GND")
		)
		(pad "4" smd rect
			(at 0 4.249928 90)
			(size 2.413 4.5212)
			(layers "F.Cu" "F.Mask" "F.Paste")
			(net "PVDDCR_SOC_P0")
		)
	)
	(footprint ""
		(layer "F.Cu")
		(at 91.568524 -408.517344 -90)
		(property "Reference" "C6657"
			(at 0 0 270)
			(layer "F.SilkS")
			(hide yes)
			(effects
				(font
					(size 1.27 1.27)
				)
			)
		)
		(property "Value" ""
			(at 0 0 270)
			(layer "F.Fab")
			(effects
				(font
					(size 1.27 1.27)
				)
			)
		)
		(duplicate_pad_numbers_are_jumpers no)
		(fp_line
			(start -0.299974 0.150114)
			(end -0.299974 -0.150114)
			(stroke
				(width 0.1)
				(type default)
			)
			(layer "F.Fab")
		)
		(fp_line
			(start 0.299974 0.150114)
			(end -0.299974 0.150114)
			(stroke
				(width 0.1)
				(type default)
			)
			(layer "F.Fab")
		)
		(fp_line
			(start -0.299974 -0.150114)
			(end 0.299974 -0.150114)
			(stroke
				(width 0.1)
				(type default)
			)
			(layer "F.Fab")
		)
		(fp_line
			(start 0.299974 -0.150114)
			(end 0.299974 0.150114)
			(stroke
				(width 0.1)
				(type default)
			)
			(layer "F.Fab")
		)
		(pad "1" smd rect
			(at -0.2667 0 270)
			(size 0.3048 0.381)
			(layers "F.Cu" "F.Mask" "F.Paste")
			(net "P5E_CPU1_P0_TX_BUF_C_DP<14>")
		)
		(pad "2" smd rect
			(at 0.2667 0 270)
			(size 0.3048 0.381)
			(layers "F.Cu" "F.Mask" "F.Paste")
			(net "P5E_CPU1_P0_TX_BUF_DP<14>")
		)
	)
	(footprint ""
		(layer "F.Cu")
		(at 241.114834 -374.81129 90)
		(property "Reference" "PD17"
			(at 2.0574 -3.343148 90)
			(unlocked yes)
			(layer "F.SilkS")
			(effects
				(font
					(size 0.7874 0.5842)
					(thickness 0.1524)
				)
			)
		)
		(property "Value" ""
			(at 0 0 90)
			(layer "F.Fab")
			(effects
				(font
					(size 1.27 1.27)
				)
			)
		)
		(duplicate_pad_numbers_are_jumpers no)
		(fp_line
			(start 3.541776 -2.54)
			(end 3.541776 2.54)
			(stroke
				(width 0.1524)
				(type default)
			)
			(layer "F.SilkS")
		)
		(fp_line
			(start -3.539744 -2.54)
			(end 3.541776 -2.54)
			(stroke
				(width 0.1524)
				(type default)
			)
			(layer "F.SilkS")
		)
		(fp_line
			(start 3.541776 2.54)
			(end -3.539744 2.54)
			(stroke
				(width 0.1524)
				(type default)
			)
			(layer "F.SilkS")
		)
		(fp_line
			(start -3.539744 2.54)
			(end -3.539744 -2.54)
			(stroke
				(width 0.1524)
				(type default)
			)
			(layer "F.SilkS")
		)
		(fp_poly
			(pts
				(xy -2.86258 2.690876) (xy -2.35458 3.706876) (xy -3.37058 3.706876)
			)
			(stroke
				(width 0)
				(type default)
			)
			(fill yes)
			(layer "F.SilkS")
		)
		(fp_line
			(start 3.074924 -2.175002)
			(end 3.074924 2.175002)
			(stroke
				(width 0.1)
				(type default)
			)
			(layer "F.Fab")
		)
		(fp_line
			(start -3.074924 -2.175002)
			(end 3.074924 -2.175002)
			(stroke
				(width 0.1)
				(type default)
			)
			(layer "F.Fab")
		)
		(fp_line
			(start 3.074924 2.175002)
			(end -3.074924 2.175002)
			(stroke
				(width 0.1)
				(type default)
			)
			(layer "F.Fab")
		)
		(fp_line
			(start -3.074924 2.175002)
			(end -3.074924 -2.175002)
			(stroke
				(width 0.1)
				(type default)
			)
			(layer "F.Fab")
		)
		(fp_poly
			(pts
				(xy -4.699 0.531876) (xy -4.699 1.547876) (xy -3.683 1.039876)
			)
			(stroke
				(width 0)
				(type default)
			)
			(fill yes)
			(layer "F.Fab")
		)
		(pad "1" smd rect
			(at -2.765044 1.039876 270)
			(size 1.27 1.4224)
			(layers "F.Cu" "F.Mask" "F.Paste")
			(net "GND")
		)
		(pad "2" smd rect
			(at -2.765044 -1.039876 270)
			(size 1.27 1.4224)
			(layers "F.Cu" "F.Mask" "F.Paste")
			(net "GND")
		)
		(pad "K" smd rect
			(at 1.039876 0 270)
			(size 4.7244 4.8006)
			(layers "F.Cu" "F.Mask" "F.Paste")
			(net "P12V_AUX")
		)
	)
	(footprint ""
		(layer "F.Cu")
		(at 303.200308 -41.906698)
		(property "Reference" "R3669"
			(at 0 0 0)
			(layer "F.SilkS")
			(hide yes)
			(effects
				(font
					(size 1.27 1.27)
				)
			)
		)
		(property "Value" ""
			(at 0 0 0)
			(layer "F.Fab")
			(effects
				(font
					(size 1.27 1.27)
				)
			)
		)
		(duplicate_pad_numbers_are_jumpers no)
		(fp_line
			(start -0.7874 -0.4064)
			(end 0.7874 -0.4064)
			(stroke
				(width 0.1524)
				(type default)
			)
			(layer "F.SilkS")
		)
		(fp_line
			(start -0.7874 0.4064)
			(end -0.7874 -0.4064)
			(stroke
				(width 0.1524)
				(type default)
			)
			(layer "F.SilkS")
		)
		(fp_line
			(start 0.7874 -0.4064)
			(end 0.7874 0.4064)
			(stroke
				(width 0.1524)
				(type default)
			)
			(layer "F.SilkS")
		)
		(fp_line
			(start 0.7874 0.4064)
			(end -0.7874 0.4064)
			(stroke
				(width 0.1524)
				(type default)
			)
			(layer "F.SilkS")
		)
		(fp_line
			(start -0.67945 -0.305054)
			(end -0.12065 -0.305054)
			(stroke
				(width 0.1)
				(type default)
			)
			(layer "F.Fab")
		)
		(fp_line
			(start -0.67945 0.3048)
			(end -0.67945 -0.305054)
			(stroke
				(width 0.1)
				(type default)
			)
			(layer "F.Fab")
		)
		(fp_line
			(start -0.12065 -0.305054)
			(end -0.12065 -0.2794)
			(stroke
				(width 0.1)
				(type default)
			)
			(layer "F.Fab")
		)
		(fp_line
			(start -0.12065 -0.2794)
			(end 0.12065 -0.2794)
			(stroke
				(width 0.1)
				(type default)
			)
			(layer "F.Fab")
		)
		(fp_line
			(start -0.12065 0.2794)
			(end -0.12065 0.3048)
			(stroke
				(width 0.1)
				(type default)
			)
			(layer "F.Fab")
		)
		(fp_line
			(start -0.12065 0.3048)
			(end -0.67945 0.3048)
			(stroke
				(width 0.1)
				(type default)
			)
			(layer "F.Fab")
		)
		(fp_line
			(start 0.120396 0.2794)
			(end -0.12065 0.2794)
			(stroke
				(width 0.1)
				(type default)
			)
			(layer "F.Fab")
		)
		(fp_line
			(start 0.120396 0.3048)
			(end 0.120396 0.2794)
			(stroke
				(width 0.1)
				(type default)
			)
			(layer "F.Fab")
		)
		(fp_line
			(start 0.12065 -0.3048)
			(end 0.67945 -0.3048)
			(stroke
				(width 0.1)
				(type default)
			)
			(layer "F.Fab")
		)
		(fp_line
			(start 0.12065 -0.2794)
			(end 0.12065 -0.3048)
			(stroke
				(width 0.1)
				(type default)
			)
			(layer "F.Fab")
		)
		(fp_line
			(start 0.67945 -0.3048)
			(end 0.67945 0.3048)
			(stroke
				(width 0.1)
				(type default)
			)
			(layer "F.Fab")
		)
		(fp_line
			(start 0.67945 0.3048)
			(end 0.120396 0.3048)
			(stroke
				(width 0.1)
				(type default)
			)
			(layer "F.Fab")
		)
		(pad "1" smd circle
			(at -0.40005 0)
			(size 0 0)
			(layers "F.Cu" "F.Mask" "F.Paste")
			(net "P3V3_AUX")
		)
		(pad "2" smd circle
			(at 0.40005 0)
			(size 0 0)
			(layers "F.Cu" "F.Mask" "F.Paste")
			(net "ADC128_A0")
		)
	)
	(footprint ""
		(layer "F.Cu")
		(at 426.673264 -423.621962 90)
		(property "Reference" "R6250"
			(at 0 0 90)
			(layer "F.SilkS")
			(hide yes)
			(effects
				(font
					(size 1.27 1.27)
				)
			)
		)
		(property "Value" ""
			(at 0 0 90)
			(layer "F.Fab")
			(effects
				(font
					(size 1.27 1.27)
				)
			)
		)
		(duplicate_pad_numbers_are_jumpers no)
		(fp_line
			(start 0.7874 -0.4064)
			(end 0.7874 0.4064)
			(stroke
				(width 0.1524)
				(type default)
			)
			(layer "F.SilkS")
		)
		(fp_line
			(start -0.7874 -0.4064)
			(end 0.7874 -0.4064)
			(stroke
				(width 0.1524)
				(type default)
			)
			(layer "F.SilkS")
		)
		(fp_line
			(start 0.7874 0.4064)
			(end -0.7874 0.4064)
			(stroke
				(width 0.1524)
				(type default)
			)
			(layer "F.SilkS")
		)
		(fp_line
			(start -0.7874 0.4064)
			(end -0.7874 -0.4064)
			(stroke
				(width 0.1524)
				(type default)
			)
			(layer "F.SilkS")
		)
		(fp_line
			(start -0.12065 -0.305054)
			(end -0.12065 -0.2794)
			(stroke
				(width 0.1)
				(type default)
			)
			(layer "F.Fab")
		)
		(fp_line
			(start -0.67945 -0.305054)
			(end -0.12065 -0.305054)
			(stroke
				(width 0.1)
				(type default)
			)
			(layer "F.Fab")
		)
		(fp_line
			(start 0.67945 -0.3048)
			(end 0.67945 0.3048)
			(stroke
				(width 0.1)
				(type default)
			)
			(layer "F.Fab")
		)
		(fp_line
			(start 0.12065 -0.3048)
			(end 0.67945 -0.3048)
			(stroke
				(width 0.1)
				(type default)
			)
			(layer "F.Fab")
		)
		(fp_line
			(start 0.12065 -0.2794)
			(end 0.12065 -0.3048)
			(stroke
				(width 0.1)
				(type default)
			)
			(layer "F.Fab")
		)
		(fp_line
			(start -0.12065 -0.2794)
			(end 0.12065 -0.2794)
			(stroke
				(width 0.1)
				(type default)
			)
			(layer "F.Fab")
		)
		(fp_line
			(start 0.120396 0.2794)
			(end -0.12065 0.2794)
			(stroke
				(width 0.1)
				(type default)
			)
			(layer "F.Fab")
		)
		(fp_line
			(start -0.12065 0.2794)
			(end -0.12065 0.3048)
			(stroke
				(width 0.1)
				(type default)
			)
			(layer "F.Fab")
		)
		(fp_line
			(start 0.67945 0.3048)
			(end 0.120396 0.3048)
			(stroke
				(width 0.1)
				(type default)
			)
			(layer "F.Fab")
		)
		(fp_line
			(start 0.120396 0.3048)
			(end 0.120396 0.2794)
			(stroke
				(width 0.1)
				(type default)
			)
			(layer "F.Fab")
		)
		(fp_line
			(start -0.12065 0.3048)
			(end -0.67945 0.3048)
			(stroke
				(width 0.1)
				(type default)
			)
			(layer "F.Fab")
		)
		(fp_line
			(start -0.67945 0.3048)
			(end -0.67945 -0.305054)
			(stroke
				(width 0.1)
				(type default)
			)
			(layer "F.Fab")
		)
		(pad "1" smd circle
			(at -0.40005 0 90)
			(size 0 0)
			(layers "F.Cu" "F.Mask" "F.Paste")
			(net "GND")
		)
		(pad "2" smd circle
			(at 0.40005 0 90)
			(size 0 0)
			(layers "F.Cu" "F.Mask" "F.Paste")
			(net "HSC_TYPE_ADC_A1")
		)
	)
	(footprint ""
		(layer "F.Cu")
		(at 141.29512 -30.82671 90)
		(property "Reference" "C6017"
			(at 0 0 90)
			(layer "F.SilkS")
			(hide yes)
			(effects
				(font
					(size 1.27 1.27)
				)
			)
		)
		(property "Value" ""
			(at 0 0 90)
			(layer "F.Fab")
			(effects
				(font
					(size 1.27 1.27)
				)
			)
		)
		(duplicate_pad_numbers_are_jumpers no)
		(fp_line
			(start 0.7874 -0.4064)
			(end 0.7874 0.4064)
			(stroke
				(width 0.1524)
				(type default)
			)
			(layer "F.SilkS")
		)
		(fp_line
			(start -0.7874 -0.4064)
			(end 0.7874 -0.4064)
			(stroke
				(width 0.1524)
				(type default)
			)
			(layer "F.SilkS")
		)
		(fp_line
			(start 0.7874 0.4064)
			(end -0.7874 0.4064)
			(stroke
				(width 0.1524)
				(type default)
			)
			(layer "F.SilkS")
		)
		(fp_line
			(start -0.7874 0.4064)
			(end -0.7874 -0.4064)
			(stroke
				(width 0.1524)
				(type default)
			)
			(layer "F.SilkS")
		)
		(fp_line
			(start 0.6858 -0.3048)
			(end 0.6858 0.3048)
			(stroke
				(width 0.1)
				(type default)
			)
			(layer "F.Fab")
		)
		(fp_line
			(start 0.1016 -0.3048)
			(end 0.6858 -0.3048)
			(stroke
				(width 0.1)
				(type default)
			)
			(layer "F.Fab")
		)
		(fp_line
			(start -0.1016 -0.3048)
			(end -0.1016 -0.2794)
			(stroke
				(width 0.1)
				(type default)
			)
			(layer "F.Fab")
		)
		(fp_line
			(start -0.6858 -0.3048)
			(end -0.1016 -0.3048)
			(stroke
				(width 0.1)
				(type default)
			)
			(layer "F.Fab")
		)
		(fp_line
			(start 0.1016 -0.2794)
			(end 0.1016 -0.3048)
			(stroke
				(width 0.1)
				(type default)
			)
			(layer "F.Fab")
		)
		(fp_line
			(start -0.1016 -0.2794)
			(end 0.1016 -0.2794)
			(stroke
				(width 0.1)
				(type default)
			)
			(layer "F.Fab")
		)
		(fp_line
			(start 0.1016 0.2794)
			(end -0.1016 0.2794)
			(stroke
				(width 0.1)
				(type default)
			)
			(layer "F.Fab")
		)
		(fp_line
			(start -0.1016 0.2794)
			(end -0.1016 0.3048)
			(stroke
				(width 0.1)
				(type default)
			)
			(layer "F.Fab")
		)
		(fp_line
			(start 0.6858 0.3048)
			(end 0.1016 0.3048)
			(stroke
				(width 0.1)
				(type default)
			)
			(layer "F.Fab")
		)
		(fp_line
			(start 0.1016 0.3048)
			(end 0.1016 0.2794)
			(stroke
				(width 0.1)
				(type default)
			)
			(layer "F.Fab")
		)
		(fp_line
			(start -0.1016 0.3048)
			(end -0.6858 0.3048)
			(stroke
				(width 0.1)
				(type default)
			)
			(layer "F.Fab")
		)
		(fp_line
			(start -0.6858 0.3048)
			(end -0.6858 -0.3048)
			(stroke
				(width 0.1)
				(type default)
			)
			(layer "F.Fab")
		)
		(pad "1" smd rect
			(at -0.40005 0 270)
			(size 0.4572 0.508)
			(layers "F.Cu" "F.Mask" "F.Paste")
			(net "USB3_CPU0_BMC_RX_HUB2_DP")
		)
		(pad "2" smd rect
			(at 0.40005 0 270)
			(size 0.4572 0.508)
			(layers "F.Cu" "F.Mask" "F.Paste")
			(net "USB3_CPU0_BMC_RX_HUB_C_DP")
		)
	)
	(footprint ""
		(layer "F.Cu")
		(at 308.813962 -337.399122)
		(property "Reference" "PL13"
			(at -6.299962 -15.126208 0)
			(unlocked yes)
			(layer "F.SilkS")
			(effects
				(font
					(size 0.7874 0.5842)
					(thickness 0.1524)
				)
				(justify left)
			)
		)
		(property "Value" ""
			(at 0 0 0)
			(layer "F.Fab")
			(effects
				(font
					(size 1.27 1.27)
				)
			)
		)
		(duplicate_pad_numbers_are_jumpers no)
		(fp_line
			(start -3.750056 -5.500116)
			(end -2.393442 -5.500116)
			(stroke
				(width 0.1524)
				(type default)
			)
			(layer "F.SilkS")
		)
		(fp_line
			(start -3.750056 5.500116)
			(end -3.750056 -5.500116)
			(stroke
				(width 0.1524)
				(type default)
			)
			(layer "F.SilkS")
		)
		(fp_line
			(start -2.393442 5.500116)
			(end -3.750056 5.500116)
			(stroke
				(width 0.1524)
				(type default)
			)
			(layer "F.SilkS")
		)
		(fp_line
			(start 2.393442 5.500116)
			(end 3.750056 5.500116)
			(stroke
				(width 0.1524)
				(type default)
			)
			(layer "F.SilkS")
		)
		(fp_line
			(start 3.750056 -5.500116)
			(end 2.393442 -5.500116)
			(stroke
				(width 0.1524)
				(type default)
			)
			(layer "F.SilkS")
		)
		(fp_line
			(start 3.750056 5.500116)
			(end 3.750056 -5.500116)
			(stroke
				(width 0.1524)
				(type default)
			)
			(layer "F.SilkS")
		)
		(fp_poly
			(pts
				(xy -3.9116 -4.249928) (xy -4.3434 -4.034028) (xy -4.3434 -4.465828)
			)
			(stroke
				(width 0)
				(type default)
			)
			(fill yes)
			(layer "F.SilkS")
		)
		(fp_line
			(start -3.750056 -5.500116)
			(end -3.750056 5.500116)
			(stroke
				(width 0.1)
				(type default)
			)
			(layer "F.Fab")
		)
		(fp_line
			(start -3.750056 5.500116)
			(end 3.750056 5.500116)
			(stroke
				(width 0.1)
				(type default)
			)
			(layer "F.Fab")
		)
		(fp_line
			(start 3.750056 -5.500116)
			(end -3.750056 -5.500116)
			(stroke
				(width 0.1)
				(type default)
			)
			(layer "F.Fab")
		)
		(fp_line
			(start 3.750056 5.500116)
			(end 3.750056 -5.500116)
			(stroke
				(width 0.1)
				(type default)
			)
			(layer "F.Fab")
		)
		(fp_poly
			(pts
				(xy -4.9276 -4.757928) (xy -4.9276 -3.741928) (xy -3.9116 -4.249928)
			)
			(stroke
				(width 0)
				(type default)
			)
			(fill yes)
			(layer "F.Fab")
		)
		(pad "1" smd rect
			(at 0 -4.249928 270)
			(size 2.413 4.5212)
			(layers "F.Cu" "F.Mask" "F.Paste")
			(net "SW_PVDDCR_CPU1_P0_SW4")
		)
		(pad "2" smd rect
			(at 0 -1.175004 270)
			(size 1.3716 4.5212)
			(layers "F.Cu" "F.Mask" "F.Paste")
			(net "IND_CPU1_P0_CPL3")
		)
		(pad "3" smd rect
			(at 0 1.175004 270)
			(size 1.3716 4.5212)
			(layers "F.Cu" "F.Mask" "F.Paste")
			(net "GND")
		)
		(pad "4" smd rect
			(at 0 4.249928 270)
			(size 2.413 4.5212)
			(layers "F.Cu" "F.Mask" "F.Paste")
			(net "PVDDCR_CPU1_P0")
		)
	)
	(footprint ""
		(layer "F.Cu")
		(at 21.176996 -98.171508)
		(property "Reference" "R3665"
			(at 0 0 0)
			(layer "F.SilkS")
			(hide yes)
			(effects
				(font
					(size 1.27 1.27)
				)
			)
		)
		(property "Value" ""
			(at 0 0 0)
			(layer "F.Fab")
			(effects
				(font
					(size 1.27 1.27)
				)
			)
		)
		(duplicate_pad_numbers_are_jumpers no)
		(fp_line
			(start -0.7874 -0.4064)
			(end 0.7874 -0.4064)
			(stroke
				(width 0.1524)
				(type default)
			)
			(layer "F.SilkS")
		)
		(fp_line
			(start -0.7874 0.4064)
			(end -0.7874 -0.4064)
			(stroke
				(width 0.1524)
				(type default)
			)
			(layer "F.SilkS")
		)
		(fp_line
			(start 0.7874 -0.4064)
			(end 0.7874 0.4064)
			(stroke
				(width 0.1524)
				(type default)
			)
			(layer "F.SilkS")
		)
		(fp_line
			(start 0.7874 0.4064)
			(end -0.7874 0.4064)
			(stroke
				(width 0.1524)
				(type default)
			)
			(layer "F.SilkS")
		)
		(fp_line
			(start -0.67945 -0.305054)
			(end -0.12065 -0.305054)
			(stroke
				(width 0.1)
				(type default)
			)
			(layer "F.Fab")
		)
		(fp_line
			(start -0.67945 0.3048)
			(end -0.67945 -0.305054)
			(stroke
				(width 0.1)
				(type default)
			)
			(layer "F.Fab")
		)
		(fp_line
			(start -0.12065 -0.305054)
			(end -0.12065 -0.2794)
			(stroke
				(width 0.1)
				(type default)
			)
			(layer "F.Fab")
		)
		(fp_line
			(start -0.12065 -0.2794)
			(end 0.12065 -0.2794)
			(stroke
				(width 0.1)
				(type default)
			)
			(layer "F.Fab")
		)
		(fp_line
			(start -0.12065 0.2794)
			(end -0.12065 0.3048)
			(stroke
				(width 0.1)
				(type default)
			)
			(layer "F.Fab")
		)
		(fp_line
			(start -0.12065 0.3048)
			(end -0.67945 0.3048)
			(stroke
				(width 0.1)
				(type default)
			)
			(layer "F.Fab")
		)
		(fp_line
			(start 0.120396 0.2794)
			(end -0.12065 0.2794)
			(stroke
				(width 0.1)
				(type default)
			)
			(layer "F.Fab")
		)
		(fp_line
			(start 0.120396 0.3048)
			(end 0.120396 0.2794)
			(stroke
				(width 0.1)
				(type default)
			)
			(layer "F.Fab")
		)
		(fp_line
			(start 0.12065 -0.3048)
			(end 0.67945 -0.3048)
			(stroke
				(width 0.1)
				(type default)
			)
			(layer "F.Fab")
		)
		(fp_line
			(start 0.12065 -0.2794)
			(end 0.12065 -0.3048)
			(stroke
				(width 0.1)
				(type default)
			)
			(layer "F.Fab")
		)
		(fp_line
			(start 0.67945 -0.3048)
			(end 0.67945 0.3048)
			(stroke
				(width 0.1)
				(type default)
			)
			(layer "F.Fab")
		)
		(fp_line
			(start 0.67945 0.3048)
			(end 0.120396 0.3048)
			(stroke
				(width 0.1)
				(type default)
			)
			(layer "F.Fab")
		)
		(pad "1" smd circle
			(at -0.40005 0)
			(size 0 0)
			(layers "F.Cu" "F.Mask" "F.Paste")
			(net "USB_HUB_PGANG")
		)
		(pad "2" smd circle
			(at 0.40005 0)
			(size 0 0)
			(layers "F.Cu" "F.Mask" "F.Paste")
			(net "GND")
		)
	)
	(footprint ""
		(layer "F.Cu")
		(at 395.595348 -16.100298 90)
		(property "Reference" "C1552"
			(at 0 0 90)
			(layer "F.SilkS")
			(hide yes)
			(effects
				(font
					(size 1.27 1.27)
				)
			)
		)
		(property "Value" ""
			(at 0 0 90)
			(layer "F.Fab")
			(effects
				(font
					(size 1.27 1.27)
				)
			)
		)
		(duplicate_pad_numbers_are_jumpers no)
		(fp_line
			(start 0.299974 -0.150114)
			(end 0.299974 0.150114)
			(stroke
				(width 0.1)
				(type default)
			)
			(layer "F.Fab")
		)
		(fp_line
			(start -0.299974 -0.150114)
			(end 0.299974 -0.150114)
			(stroke
				(width 0.1)
				(type default)
			)
			(layer "F.Fab")
		)
		(fp_line
			(start 0.299974 0.150114)
			(end -0.299974 0.150114)
			(stroke
				(width 0.1)
				(type default)
			)
			(layer "F.Fab")
		)
		(fp_line
			(start -0.299974 0.150114)
			(end -0.299974 -0.150114)
			(stroke
				(width 0.1)
				(type default)
			)
			(layer "F.Fab")
		)
		(pad "1" smd rect
			(at -0.2667 0 90)
			(size 0.3048 0.381)
			(layers "F.Cu" "F.Mask" "F.Paste")
			(net "P5E_CPU0_G3_TX_C_DN<13>")
		)
		(pad "2" smd rect
			(at 0.2667 0 90)
			(size 0.3048 0.381)
			(layers "F.Cu" "F.Mask" "F.Paste")
			(net "P5E_CPU0_G3_TX_DN<13>")
		)
	)
	(footprint ""
		(layer "F.Cu")
		(at 42.527982 -386.951474)
		(property "Reference" "R609"
			(at 0 0 0)
			(layer "F.SilkS")
			(hide yes)
			(effects
				(font
					(size 1.27 1.27)
				)
			)
		)
		(property "Value" ""
			(at 0 0 0)
			(layer "F.Fab")
			(effects
				(font
					(size 1.27 1.27)
				)
			)
		)
		(duplicate_pad_numbers_are_jumpers no)
		(fp_line
			(start -0.32512 -0.175006)
			(end 0.32512 -0.175006)
			(stroke
				(width 0.1)
				(type default)
			)
			(layer "F.Fab")
		)
		(fp_line
			(start -0.32512 0.175006)
			(end -0.32512 -0.175006)
			(stroke
				(width 0.1)
				(type default)
			)
			(layer "F.Fab")
		)
		(fp_line
			(start 0.32512 -0.175006)
			(end 0.32512 0.175006)
			(stroke
				(width 0.1)
				(type default)
			)
			(layer "F.Fab")
		)
		(fp_line
			(start 0.32512 0.175006)
			(end -0.32512 0.175006)
			(stroke
				(width 0.1)
				(type default)
			)
			(layer "F.Fab")
		)
		(pad "1" smd rect
			(at -0.2667 0)
			(size 0.3048 0.381)
			(layers "F.Cu" "F.Mask" "F.Paste")
			(net "CLK_100M_RETIMER_CPU1_P0_R_DN")
		)
		(pad "2" smd rect
			(at 0.2667 0 180)
			(size 0.3048 0.381)
			(layers "F.Cu" "F.Mask" "F.Paste")
			(net "CLK_100M_RETIMER_CPU1_P0_DN")
		)
	)
	(footprint ""
		(layer "F.Cu")
		(at 171.269406 -125.751336 180)
		(property "Reference" "R6144"
			(at 0 0 180)
			(layer "F.SilkS")
			(hide yes)
			(effects
				(font
					(size 1.27 1.27)
				)
			)
		)
		(property "Value" ""
			(at 0 0 180)
			(layer "F.Fab")
			(effects
				(font
					(size 1.27 1.27)
				)
			)
		)
		(duplicate_pad_numbers_are_jumpers no)
		(fp_line
			(start 0.7874 0.4064)
			(end -0.7874 0.4064)
			(stroke
				(width 0.1524)
				(type default)
			)
			(layer "F.SilkS")
		)
		(fp_line
			(start 0.7874 -0.4064)
			(end 0.7874 0.4064)
			(stroke
				(width 0.1524)
				(type default)
			)
			(layer "F.SilkS")
		)
		(fp_line
			(start -0.7874 0.4064)
			(end -0.7874 -0.4064)
			(stroke
				(width 0.1524)
				(type default)
			)
			(layer "F.SilkS")
		)
		(fp_line
			(start -0.7874 -0.4064)
			(end 0.7874 -0.4064)
			(stroke
				(width 0.1524)
				(type default)
			)
			(layer "F.SilkS")
		)
		(fp_line
			(start 0.67945 0.3048)
			(end 0.120396 0.3048)
			(stroke
				(width 0.1)
				(type default)
			)
			(layer "F.Fab")
		)
		(fp_line
			(start 0.67945 -0.3048)
			(end 0.67945 0.3048)
			(stroke
				(width 0.1)
				(type default)
			)
			(layer "F.Fab")
		)
		(fp_line
			(start 0.12065 -0.2794)
			(end 0.12065 -0.3048)
			(stroke
				(width 0.1)
				(type default)
			)
			(layer "F.Fab")
		)
		(fp_line
			(start 0.12065 -0.3048)
			(end 0.67945 -0.3048)
			(stroke
				(width 0.1)
				(type default)
			)
			(layer "F.Fab")
		)
		(fp_line
			(start 0.120396 0.3048)
			(end 0.120396 0.2794)
			(stroke
				(width 0.1)
				(type default)
			)
			(layer "F.Fab")
		)
		(fp_line
			(start 0.120396 0.2794)
			(end -0.12065 0.2794)
			(stroke
				(width 0.1)
				(type default)
			)
			(layer "F.Fab")
		)
		(fp_line
			(start -0.12065 0.3048)
			(end -0.67945 0.3048)
			(stroke
				(width 0.1)
				(type default)
			)
			(layer "F.Fab")
		)
		(fp_line
			(start -0.12065 0.2794)
			(end -0.12065 0.3048)
			(stroke
				(width 0.1)
				(type default)
			)
			(layer "F.Fab")
		)
		(fp_line
			(start -0.12065 -0.2794)
			(end 0.12065 -0.2794)
			(stroke
				(width 0.1)
				(type default)
			)
			(layer "F.Fab")
		)
		(fp_line
			(start -0.12065 -0.305054)
			(end -0.12065 -0.2794)
			(stroke
				(width 0.1)
				(type default)
			)
			(layer "F.Fab")
		)
		(fp_line
			(start -0.67945 0.3048)
			(end -0.67945 -0.305054)
			(stroke
				(width 0.1)
				(type default)
			)
			(layer "F.Fab")
		)
		(fp_line
			(start -0.67945 -0.305054)
			(end -0.12065 -0.305054)
			(stroke
				(width 0.1)
				(type default)
			)
			(layer "F.Fab")
		)
		(pad "1" smd circle
			(at -0.40005 0 180)
			(size 0 0)
			(layers "F.Cu" "F.Mask" "F.Paste")
			(net "FM_BOARD_BMC_SKU_ID1")
		)
		(pad "2" smd circle
			(at 0.40005 0 180)
			(size 0 0)
			(layers "F.Cu" "F.Mask" "F.Paste")
			(net "GND")
		)
	)
	(footprint ""
		(layer "F.Cu")
		(at 100.285296 -422.43248 90)
		(property "Reference" "R4195"
			(at 0 0 90)
			(layer "F.SilkS")
			(hide yes)
			(effects
				(font
					(size 1.27 1.27)
				)
			)
		)
		(property "Value" ""
			(at 0 0 90)
			(layer "F.Fab")
			(effects
				(font
					(size 1.27 1.27)
				)
			)
		)
		(duplicate_pad_numbers_are_jumpers no)
		(fp_line
			(start 0.7874 -0.4064)
			(end 0.7874 0.4064)
			(stroke
				(width 0.1524)
				(type default)
			)
			(layer "F.SilkS")
		)
		(fp_line
			(start -0.7874 -0.4064)
			(end 0.7874 -0.4064)
			(stroke
				(width 0.1524)
				(type default)
			)
			(layer "F.SilkS")
		)
		(fp_line
			(start 0.7874 0.4064)
			(end -0.7874 0.4064)
			(stroke
				(width 0.1524)
				(type default)
			)
			(layer "F.SilkS")
		)
		(fp_line
			(start -0.7874 0.4064)
			(end -0.7874 -0.4064)
			(stroke
				(width 0.1524)
				(type default)
			)
			(layer "F.SilkS")
		)
		(fp_line
			(start -0.12065 -0.305054)
			(end -0.12065 -0.2794)
			(stroke
				(width 0.1)
				(type default)
			)
			(layer "F.Fab")
		)
		(fp_line
			(start -0.67945 -0.305054)
			(end -0.12065 -0.305054)
			(stroke
				(width 0.1)
				(type default)
			)
			(layer "F.Fab")
		)
		(fp_line
			(start 0.67945 -0.3048)
			(end 0.67945 0.3048)
			(stroke
				(width 0.1)
				(type default)
			)
			(layer "F.Fab")
		)
		(fp_line
			(start 0.12065 -0.3048)
			(end 0.67945 -0.3048)
			(stroke
				(width 0.1)
				(type default)
			)
			(layer "F.Fab")
		)
		(fp_line
			(start 0.12065 -0.2794)
			(end 0.12065 -0.3048)
			(stroke
				(width 0.1)
				(type default)
			)
			(layer "F.Fab")
		)
		(fp_line
			(start -0.12065 -0.2794)
			(end 0.12065 -0.2794)
			(stroke
				(width 0.1)
				(type default)
			)
			(layer "F.Fab")
		)
		(fp_line
			(start 0.120396 0.2794)
			(end -0.12065 0.2794)
			(stroke
				(width 0.1)
				(type default)
			)
			(layer "F.Fab")
		)
		(fp_line
			(start -0.12065 0.2794)
			(end -0.12065 0.3048)
			(stroke
				(width 0.1)
				(type default)
			)
			(layer "F.Fab")
		)
		(fp_line
			(start 0.67945 0.3048)
			(end 0.120396 0.3048)
			(stroke
				(width 0.1)
				(type default)
			)
			(layer "F.Fab")
		)
		(fp_line
			(start 0.120396 0.3048)
			(end 0.120396 0.2794)
			(stroke
				(width 0.1)
				(type default)
			)
			(layer "F.Fab")
		)
		(fp_line
			(start -0.12065 0.3048)
			(end -0.67945 0.3048)
			(stroke
				(width 0.1)
				(type default)
			)
			(layer "F.Fab")
		)
		(fp_line
			(start -0.67945 0.3048)
			(end -0.67945 -0.305054)
			(stroke
				(width 0.1)
				(type default)
			)
			(layer "F.Fab")
		)
		(pad "1" smd circle
			(at -0.40005 0 90)
			(size 0 0)
			(layers "F.Cu" "F.Mask" "F.Paste")
			(net "U272_2_ADD1")
		)
		(pad "2" smd circle
			(at 0.40005 0 90)
			(size 0 0)
			(layers "F.Cu" "F.Mask" "F.Paste")
			(net "GND")
		)
	)
	(footprint ""
		(layer "F.Cu")
		(at 187.11037 -355.705156)
		(property "Reference" "PC509_1"
			(at 0 0 0)
			(layer "F.SilkS")
			(hide yes)
			(effects
				(font
					(size 1.27 1.27)
				)
			)
		)
		(property "Value" ""
			(at 0 0 0)
			(layer "F.Fab")
			(effects
				(font
					(size 1.27 1.27)
				)
			)
		)
		(duplicate_pad_numbers_are_jumpers no)
		(fp_line
			(start -0.7874 -0.4064)
			(end 0.7874 -0.4064)
			(stroke
				(width 0.1524)
				(type default)
			)
			(layer "F.SilkS")
		)
		(fp_line
			(start -0.7874 0.4064)
			(end -0.7874 -0.4064)
			(stroke
				(width 0.1524)
				(type default)
			)
			(layer "F.SilkS")
		)
		(fp_line
			(start 0.7874 -0.4064)
			(end 0.7874 0.4064)
			(stroke
				(width 0.1524)
				(type default)
			)
			(layer "F.SilkS")
		)
		(fp_line
			(start 0.7874 0.4064)
			(end -0.7874 0.4064)
			(stroke
				(width 0.1524)
				(type default)
			)
			(layer "F.SilkS")
		)
		(fp_line
			(start -0.67945 -0.305054)
			(end -0.12065 -0.305054)
			(stroke
				(width 0.1)
				(type default)
			)
			(layer "F.Fab")
		)
		(fp_line
			(start -0.67945 0.3048)
			(end -0.67945 -0.305054)
			(stroke
				(width 0.1)
				(type default)
			)
			(layer "F.Fab")
		)
		(fp_line
			(start -0.12065 -0.305054)
			(end -0.12065 -0.2794)
			(stroke
				(width 0.1)
				(type default)
			)
			(layer "F.Fab")
		)
		(fp_line
			(start -0.12065 -0.2794)
			(end 0.12065 -0.2794)
			(stroke
				(width 0.1)
				(type default)
			)
			(layer "F.Fab")
		)
		(fp_line
			(start -0.12065 0.2794)
			(end -0.12065 0.3048)
			(stroke
				(width 0.1)
				(type default)
			)
			(layer "F.Fab")
		)
		(fp_line
			(start -0.12065 0.3048)
			(end -0.67945 0.3048)
			(stroke
				(width 0.1)
				(type default)
			)
			(layer "F.Fab")
		)
		(fp_line
			(start 0.120396 0.2794)
			(end -0.12065 0.2794)
			(stroke
				(width 0.1)
				(type default)
			)
			(layer "F.Fab")
		)
		(fp_line
			(start 0.120396 0.3048)
			(end 0.120396 0.2794)
			(stroke
				(width 0.1)
				(type default)
			)
			(layer "F.Fab")
		)
		(fp_line
			(start 0.12065 -0.3048)
			(end 0.67945 -0.3048)
			(stroke
				(width 0.1)
				(type default)
			)
			(layer "F.Fab")
		)
		(fp_line
			(start 0.12065 -0.2794)
			(end 0.12065 -0.3048)
			(stroke
				(width 0.1)
				(type default)
			)
			(layer "F.Fab")
		)
		(fp_line
			(start 0.67945 -0.3048)
			(end 0.67945 0.3048)
			(stroke
				(width 0.1)
				(type default)
			)
			(layer "F.Fab")
		)
		(fp_line
			(start 0.67945 0.3048)
			(end 0.120396 0.3048)
			(stroke
				(width 0.1)
				(type default)
			)
			(layer "F.Fab")
		)
		(pad "1" smd circle
			(at -0.40005 0)
			(size 0 0)
			(layers "F.Cu" "F.Mask" "F.Paste")
			(net "SW_P12V_AUX_PVDD11_S3_P1_FLT")
		)
		(pad "2" smd circle
			(at 0.40005 0)
			(size 0 0)
			(layers "F.Cu" "F.Mask" "F.Paste")
			(net "GND")
		)
	)
	(footprint ""
		(layer "F.Cu")
		(at 28.288488 -437.458358 180)
		(property "Reference" "U200"
			(at 3.169412 2.695194 0)
			(unlocked yes)
			(layer "F.SilkS")
			(effects
				(font
					(size 0.7874 0.5842)
					(thickness 0.1524)
				)
				(justify left)
			)
		)
		(property "Value" ""
			(at 0 0 180)
			(layer "F.Fab")
			(effects
				(font
					(size 1.27 1.27)
				)
			)
		)
		(duplicate_pad_numbers_are_jumpers no)
		(fp_line
			(start 1.3716 1.524)
			(end -1.3716 1.524)
			(stroke
				(width 0.1524)
				(type default)
			)
			(layer "F.SilkS")
		)
		(fp_line
			(start 1.3716 -1.524)
			(end 1.3716 1.524)
			(stroke
				(width 0.1524)
				(type default)
			)
			(layer "F.SilkS")
		)
		(fp_line
			(start 0.508 -1.524)
			(end 1.3716 -1.524)
			(stroke
				(width 0.1524)
				(type default)
			)
			(layer "F.SilkS")
		)
		(fp_line
			(start 0 -1.016)
			(end 0.508 -1.524)
			(stroke
				(width 0.1524)
				(type default)
			)
			(layer "F.SilkS")
		)
		(fp_line
			(start -0.508 -1.524)
			(end 0 -1.016)
			(stroke
				(width 0.1524)
				(type default)
			)
			(layer "F.SilkS")
		)
		(fp_line
			(start -1.3716 1.524)
			(end -1.3716 -1.524)
			(stroke
				(width 0.1524)
				(type default)
			)
			(layer "F.SilkS")
		)
		(fp_line
			(start -1.3716 -1.524)
			(end -0.508 -1.524)
			(stroke
				(width 0.1524)
				(type default)
			)
			(layer "F.SilkS")
		)
		(fp_poly
			(pts
				(xy -4.108704 -0.70358) (xy -4.108704 -1.32842) (xy -3.554984 -1.000252)
			)
			(stroke
				(width 0)
				(type default)
			)
			(fill yes)
			(layer "F.SilkS")
		)
		(fp_line
			(start 2.54 1.0668)
			(end 1.5494 1.0668)
			(stroke
				(width 0.1)
				(type default)
			)
			(layer "F.Fab")
		)
		(fp_line
			(start 2.54 -1.0668)
			(end 2.54 1.0668)
			(stroke
				(width 0.1)
				(type default)
			)
			(layer "F.Fab")
		)
		(fp_line
			(start 1.5494 1.524)
			(end -1.5494 1.524)
			(stroke
				(width 0.1)
				(type default)
			)
			(layer "F.Fab")
		)
		(fp_line
			(start 1.5494 1.0668)
			(end 1.5494 1.524)
			(stroke
				(width 0.1)
				(type default)
			)
			(layer "F.Fab")
		)
		(fp_line
			(start 1.5494 -1.0668)
			(end 2.54 -1.0668)
			(stroke
				(width 0.1)
				(type default)
			)
			(layer "F.Fab")
		)
		(fp_line
			(start 1.5494 -1.0668)
			(end 1.5494 1.0668)
			(stroke
				(width 0.1)
				(type default)
			)
			(layer "F.Fab")
		)
		(fp_line
			(start 1.5494 -1.524)
			(end 1.5494 -1.0668)
			(stroke
				(width 0.1)
				(type default)
			)
			(layer "F.Fab")
		)
		(fp_line
			(start -1.5494 1.524)
			(end -1.5494 1.0668)
			(stroke
				(width 0.1)
				(type default)
			)
			(layer "F.Fab")
		)
		(fp_line
			(start -1.5494 1.0668)
			(end -1.5494 -1.0668)
			(stroke
				(width 0.1)
				(type default)
			)
			(layer "F.Fab")
		)
		(fp_line
			(start -1.5494 1.0668)
			(end -2.54 1.0668)
			(stroke
				(width 0.1)
				(type default)
			)
			(layer "F.Fab")
		)
		(fp_line
			(start -1.5494 -1.0668)
			(end -1.5494 -1.524)
			(stroke
				(width 0.1)
				(type default)
			)
			(layer "F.Fab")
		)
		(fp_line
			(start -1.5494 -1.524)
			(end 1.5494 -1.524)
			(stroke
				(width 0.1)
				(type default)
			)
			(layer "F.Fab")
		)
		(fp_line
			(start -2.54 1.0668)
			(end -2.54 -1.0668)
			(stroke
				(width 0.1)
				(type default)
			)
			(layer "F.Fab")
		)
		(fp_line
			(start -2.54 -1.0668)
			(end -1.5494 -1.0668)
			(stroke
				(width 0.1)
				(type default)
			)
			(layer "F.Fab")
		)
		(fp_poly
			(pts
				(xy -3.60172 -0.719328) (xy -3.60172 -1.344168) (xy -3.048 -1.016)
			)
			(stroke
				(width 0)
				(type default)
			)
			(fill yes)
			(layer "F.Fab")
		)
		(pad "1" smd rect
			(at -2.232406 -0.975106 90)
			(size 0.3556 1.4224)
			(layers "F.Cu" "F.Mask" "F.Paste")
			(net "SMB_BMC_GPU_EN_R3")
		)
		(pad "2" smd rect
			(at -2.232406 -0.32512 90)
			(size 0.3556 1.4224)
			(layers "F.Cu" "F.Mask" "F.Paste")
			(net "SMB_2_BMC_GPU_BUF_R_SCL")
		)
		(pad "3" smd rect
			(at -2.232406 0.32512 90)
			(size 0.3556 1.4224)
			(layers "F.Cu" "F.Mask" "F.Paste")
			(net "SMB_2_BMC_GPU_R_SCL")
		)
		(pad "4" smd rect
			(at -2.232406 0.975106 90)
			(size 0.3556 1.4224)
			(layers "F.Cu" "F.Mask" "F.Paste")
			(net "GND")
		)
		(pad "5" smd rect
			(at 2.232406 0.975106 90)
			(size 0.3556 1.4224)
			(layers "F.Cu" "F.Mask" "F.Paste")
			(net "Net_10759")
		)
		(pad "6" smd rect
			(at 2.232406 0.32512 90)
			(size 0.3556 1.4224)
			(layers "F.Cu" "F.Mask" "F.Paste")
			(net "SMB_2_BMC_GPU_R_SDA")
		)
		(pad "7" smd rect
			(at 2.232406 -0.32512 90)
			(size 0.3556 1.4224)
			(layers "F.Cu" "F.Mask" "F.Paste")
			(net "SMB_2_BMC_GPU_BUF_R_SDA")
		)
		(pad "8" smd rect
			(at 2.232406 -0.975106 90)
			(size 0.3556 1.4224)
			(layers "F.Cu" "F.Mask" "F.Paste")
			(net "P3V3_AUX")
		)
	)
	(footprint ""
		(layer "F.Cu")
		(at 190.119 -133.568948 90)
		(property "Reference" "R708"
			(at 0 0 90)
			(layer "F.SilkS")
			(hide yes)
			(effects
				(font
					(size 1.27 1.27)
				)
			)
		)
		(property "Value" ""
			(at 0 0 90)
			(layer "F.Fab")
			(effects
				(font
					(size 1.27 1.27)
				)
			)
		)
		(duplicate_pad_numbers_are_jumpers no)
		(fp_line
			(start 0.7874 -0.4064)
			(end 0.7874 0.4064)
			(stroke
				(width 0.1524)
				(type default)
			)
			(layer "F.SilkS")
		)
		(fp_line
			(start -0.7874 -0.4064)
			(end 0.7874 -0.4064)
			(stroke
				(width 0.1524)
				(type default)
			)
			(layer "F.SilkS")
		)
		(fp_line
			(start 0.7874 0.4064)
			(end -0.7874 0.4064)
			(stroke
				(width 0.1524)
				(type default)
			)
			(layer "F.SilkS")
		)
		(fp_line
			(start -0.7874 0.4064)
			(end -0.7874 -0.4064)
			(stroke
				(width 0.1524)
				(type default)
			)
			(layer "F.SilkS")
		)
		(fp_line
			(start -0.12065 -0.305054)
			(end -0.12065 -0.2794)
			(stroke
				(width 0.1)
				(type default)
			)
			(layer "F.Fab")
		)
		(fp_line
			(start -0.67945 -0.305054)
			(end -0.12065 -0.305054)
			(stroke
				(width 0.1)
				(type default)
			)
			(layer "F.Fab")
		)
		(fp_line
			(start 0.67945 -0.3048)
			(end 0.67945 0.3048)
			(stroke
				(width 0.1)
				(type default)
			)
			(layer "F.Fab")
		)
		(fp_line
			(start 0.12065 -0.3048)
			(end 0.67945 -0.3048)
			(stroke
				(width 0.1)
				(type default)
			)
			(layer "F.Fab")
		)
		(fp_line
			(start 0.12065 -0.2794)
			(end 0.12065 -0.3048)
			(stroke
				(width 0.1)
				(type default)
			)
			(layer "F.Fab")
		)
		(fp_line
			(start -0.12065 -0.2794)
			(end 0.12065 -0.2794)
			(stroke
				(width 0.1)
				(type default)
			)
			(layer "F.Fab")
		)
		(fp_line
			(start 0.120396 0.2794)
			(end -0.12065 0.2794)
			(stroke
				(width 0.1)
				(type default)
			)
			(layer "F.Fab")
		)
		(fp_line
			(start -0.12065 0.2794)
			(end -0.12065 0.3048)
			(stroke
				(width 0.1)
				(type default)
			)
			(layer "F.Fab")
		)
		(fp_line
			(start 0.67945 0.3048)
			(end 0.120396 0.3048)
			(stroke
				(width 0.1)
				(type default)
			)
			(layer "F.Fab")
		)
		(fp_line
			(start 0.120396 0.3048)
			(end 0.120396 0.2794)
			(stroke
				(width 0.1)
				(type default)
			)
			(layer "F.Fab")
		)
		(fp_line
			(start -0.12065 0.3048)
			(end -0.67945 0.3048)
			(stroke
				(width 0.1)
				(type default)
			)
			(layer "F.Fab")
		)
		(fp_line
			(start -0.67945 0.3048)
			(end -0.67945 -0.305054)
			(stroke
				(width 0.1)
				(type default)
			)
			(layer "F.Fab")
		)
		(pad "1" smd circle
			(at -0.40005 0 90)
			(size 0 0)
			(layers "F.Cu" "F.Mask" "F.Paste")
			(net "FM_HDT_HDR_PWROK")
		)
		(pad "2" smd circle
			(at 0.40005 0 90)
			(size 0 0)
			(layers "F.Cu" "F.Mask" "F.Paste")
			(net "HDT_HDR_PWROK")
		)
	)
	(footprint ""
		(layer "F.Cu")
		(at 402.356066 -143.029432 -90)
		(property "Reference" "C1042"
			(at 0 0 270)
			(layer "F.SilkS")
			(hide yes)
			(effects
				(font
					(size 1.27 1.27)
				)
			)
		)
		(property "Value" ""
			(at 0 0 270)
			(layer "F.Fab")
			(effects
				(font
					(size 1.27 1.27)
				)
			)
		)
		(duplicate_pad_numbers_are_jumpers no)
		(fp_line
			(start -0.7874 0.4064)
			(end -0.7874 -0.4064)
			(stroke
				(width 0.1524)
				(type default)
			)
			(layer "F.SilkS")
		)
		(fp_line
			(start 0.7874 0.4064)
			(end -0.7874 0.4064)
			(stroke
				(width 0.1524)
				(type default)
			)
			(layer "F.SilkS")
		)
		(fp_line
			(start -0.7874 -0.4064)
			(end 0.7874 -0.4064)
			(stroke
				(width 0.1524)
				(type default)
			)
			(layer "F.SilkS")
		)
		(fp_line
			(start 0.7874 -0.4064)
			(end 0.7874 0.4064)
			(stroke
				(width 0.1524)
				(type default)
			)
			(layer "F.SilkS")
		)
		(fp_line
			(start -0.67945 0.3048)
			(end -0.67945 -0.305054)
			(stroke
				(width 0.1)
				(type default)
			)
			(layer "F.Fab")
		)
		(fp_line
			(start -0.12065 0.3048)
			(end -0.67945 0.3048)
			(stroke
				(width 0.1)
				(type default)
			)
			(layer "F.Fab")
		)
		(fp_line
			(start 0.120396 0.3048)
			(end 0.120396 0.2794)
			(stroke
				(width 0.1)
				(type default)
			)
			(layer "F.Fab")
		)
		(fp_line
			(start 0.67945 0.3048)
			(end 0.120396 0.3048)
			(stroke
				(width 0.1)
				(type default)
			)
			(layer "F.Fab")
		)
		(fp_line
			(start -0.12065 0.2794)
			(end -0.12065 0.3048)
			(stroke
				(width 0.1)
				(type default)
			)
			(layer "F.Fab")
		)
		(fp_line
			(start 0.120396 0.2794)
			(end -0.12065 0.2794)
			(stroke
				(width 0.1)
				(type default)
			)
			(layer "F.Fab")
		)
		(fp_line
			(start -0.12065 -0.2794)
			(end 0.12065 -0.2794)
			(stroke
				(width 0.1)
				(type default)
			)
			(layer "F.Fab")
		)
		(fp_line
			(start 0.12065 -0.2794)
			(end 0.12065 -0.3048)
			(stroke
				(width 0.1)
				(type default)
			)
			(layer "F.Fab")
		)
		(fp_line
			(start 0.12065 -0.3048)
			(end 0.67945 -0.3048)
			(stroke
				(width 0.1)
				(type default)
			)
			(layer "F.Fab")
		)
		(fp_line
			(start 0.67945 -0.3048)
			(end 0.67945 0.3048)
			(stroke
				(width 0.1)
				(type default)
			)
			(layer "F.Fab")
		)
		(fp_line
			(start -0.67945 -0.305054)
			(end -0.12065 -0.305054)
			(stroke
				(width 0.1)
				(type default)
			)
			(layer "F.Fab")
		)
		(fp_line
			(start -0.12065 -0.305054)
			(end -0.12065 -0.2794)
			(stroke
				(width 0.1)
				(type default)
			)
			(layer "F.Fab")
		)
		(pad "1" smd circle
			(at -0.40005 0 270)
			(size 0 0)
			(layers "F.Cu" "F.Mask" "F.Paste")
			(net "P5V_AUX")
		)
		(pad "2" smd circle
			(at 0.40005 0 270)
			(size 0 0)
			(layers "F.Cu" "F.Mask" "F.Paste")
			(net "GND")
		)
	)
	(footprint ""
		(layer "F.Cu")
		(at 120.358662 -15.247366)
		(property "Reference" "R4193"
			(at 0 0 0)
			(layer "F.SilkS")
			(hide yes)
			(effects
				(font
					(size 1.27 1.27)
				)
			)
		)
		(property "Value" ""
			(at 0 0 0)
			(layer "F.Fab")
			(effects
				(font
					(size 1.27 1.27)
				)
			)
		)
		(duplicate_pad_numbers_are_jumpers no)
		(fp_line
			(start -0.7874 -0.4064)
			(end 0.7874 -0.4064)
			(stroke
				(width 0.1524)
				(type default)
			)
			(layer "F.SilkS")
		)
		(fp_line
			(start -0.7874 0.4064)
			(end -0.7874 -0.4064)
			(stroke
				(width 0.1524)
				(type default)
			)
			(layer "F.SilkS")
		)
		(fp_line
			(start 0.7874 -0.4064)
			(end 0.7874 0.4064)
			(stroke
				(width 0.1524)
				(type default)
			)
			(layer "F.SilkS")
		)
		(fp_line
			(start 0.7874 0.4064)
			(end -0.7874 0.4064)
			(stroke
				(width 0.1524)
				(type default)
			)
			(layer "F.SilkS")
		)
		(fp_line
			(start -0.67945 -0.305054)
			(end -0.12065 -0.305054)
			(stroke
				(width 0.1)
				(type default)
			)
			(layer "F.Fab")
		)
		(fp_line
			(start -0.67945 0.3048)
			(end -0.67945 -0.305054)
			(stroke
				(width 0.1)
				(type default)
			)
			(layer "F.Fab")
		)
		(fp_line
			(start -0.12065 -0.305054)
			(end -0.12065 -0.2794)
			(stroke
				(width 0.1)
				(type default)
			)
			(layer "F.Fab")
		)
		(fp_line
			(start -0.12065 -0.2794)
			(end 0.12065 -0.2794)
			(stroke
				(width 0.1)
				(type default)
			)
			(layer "F.Fab")
		)
		(fp_line
			(start -0.12065 0.2794)
			(end -0.12065 0.3048)
			(stroke
				(width 0.1)
				(type default)
			)
			(layer "F.Fab")
		)
		(fp_line
			(start -0.12065 0.3048)
			(end -0.67945 0.3048)
			(stroke
				(width 0.1)
				(type default)
			)
			(layer "F.Fab")
		)
		(fp_line
			(start 0.120396 0.2794)
			(end -0.12065 0.2794)
			(stroke
				(width 0.1)
				(type default)
			)
			(layer "F.Fab")
		)
		(fp_line
			(start 0.120396 0.3048)
			(end 0.120396 0.2794)
			(stroke
				(width 0.1)
				(type default)
			)
			(layer "F.Fab")
		)
		(fp_line
			(start 0.12065 -0.3048)
			(end 0.67945 -0.3048)
			(stroke
				(width 0.1)
				(type default)
			)
			(layer "F.Fab")
		)
		(fp_line
			(start 0.12065 -0.2794)
			(end 0.12065 -0.3048)
			(stroke
				(width 0.1)
				(type default)
			)
			(layer "F.Fab")
		)
		(fp_line
			(start 0.67945 -0.3048)
			(end 0.67945 0.3048)
			(stroke
				(width 0.1)
				(type default)
			)
			(layer "F.Fab")
		)
		(fp_line
			(start 0.67945 0.3048)
			(end 0.120396 0.3048)
			(stroke
				(width 0.1)
				(type default)
			)
			(layer "F.Fab")
		)
		(pad "1" smd circle
			(at -0.40005 0)
			(size 0 0)
			(layers "F.Cu" "F.Mask" "F.Paste")
			(net "U273_3_ADD1")
		)
		(pad "2" smd circle
			(at 0.40005 0)
			(size 0 0)
			(layers "F.Cu" "F.Mask" "F.Paste")
			(net "GND")
		)
	)
	(footprint ""
		(layer "F.Cu")
		(at 19.915124 -407.976578 -90)
		(property "Reference" "R6787"
			(at 0 0 270)
			(layer "F.SilkS")
			(hide yes)
			(effects
				(font
					(size 1.27 1.27)
				)
			)
		)
		(property "Value" ""
			(at 0 0 270)
			(layer "F.Fab")
			(effects
				(font
					(size 1.27 1.27)
				)
			)
		)
		(duplicate_pad_numbers_are_jumpers no)
		(fp_line
			(start -0.7874 0.4064)
			(end -0.7874 -0.4064)
			(stroke
				(width 0.1524)
				(type default)
			)
			(layer "F.SilkS")
		)
		(fp_line
			(start 0.7874 0.4064)
			(end -0.7874 0.4064)
			(stroke
				(width 0.1524)
				(type default)
			)
			(layer "F.SilkS")
		)
		(fp_line
			(start -0.7874 -0.4064)
			(end 0.7874 -0.4064)
			(stroke
				(width 0.1524)
				(type default)
			)
			(layer "F.SilkS")
		)
		(fp_line
			(start 0.7874 -0.4064)
			(end 0.7874 0.4064)
			(stroke
				(width 0.1524)
				(type default)
			)
			(layer "F.SilkS")
		)
		(fp_line
			(start -0.67945 0.3048)
			(end -0.67945 -0.305054)
			(stroke
				(width 0.1)
				(type default)
			)
			(layer "F.Fab")
		)
		(fp_line
			(start -0.12065 0.3048)
			(end -0.67945 0.3048)
			(stroke
				(width 0.1)
				(type default)
			)
			(layer "F.Fab")
		)
		(fp_line
			(start 0.120396 0.3048)
			(end 0.120396 0.2794)
			(stroke
				(width 0.1)
				(type default)
			)
			(layer "F.Fab")
		)
		(fp_line
			(start 0.67945 0.3048)
			(end 0.120396 0.3048)
			(stroke
				(width 0.1)
				(type default)
			)
			(layer "F.Fab")
		)
		(fp_line
			(start -0.12065 0.2794)
			(end -0.12065 0.3048)
			(stroke
				(width 0.1)
				(type default)
			)
			(layer "F.Fab")
		)
		(fp_line
			(start 0.120396 0.2794)
			(end -0.12065 0.2794)
			(stroke
				(width 0.1)
				(type default)
			)
			(layer "F.Fab")
		)
		(fp_line
			(start -0.12065 -0.2794)
			(end 0.12065 -0.2794)
			(stroke
				(width 0.1)
				(type default)
			)
			(layer "F.Fab")
		)
		(fp_line
			(start 0.12065 -0.2794)
			(end 0.12065 -0.3048)
			(stroke
				(width 0.1)
				(type default)
			)
			(layer "F.Fab")
		)
		(fp_line
			(start 0.12065 -0.3048)
			(end 0.67945 -0.3048)
			(stroke
				(width 0.1)
				(type default)
			)
			(layer "F.Fab")
		)
		(fp_line
			(start 0.67945 -0.3048)
			(end 0.67945 0.3048)
			(stroke
				(width 0.1)
				(type default)
			)
			(layer "F.Fab")
		)
		(fp_line
			(start -0.67945 -0.305054)
			(end -0.12065 -0.305054)
			(stroke
				(width 0.1)
				(type default)
			)
			(layer "F.Fab")
		)
		(fp_line
			(start -0.12065 -0.305054)
			(end -0.12065 -0.2794)
			(stroke
				(width 0.1)
				(type default)
			)
			(layer "F.Fab")
		)
		(pad "1" smd circle
			(at -0.40005 0 270)
			(size 0 0)
			(layers "F.Cu" "F.Mask" "F.Paste")
			(net "P0V9_RETIMER_CPU1_EN0_R")
		)
		(pad "2" smd circle
			(at 0.40005 0 270)
			(size 0 0)
			(layers "F.Cu" "F.Mask" "F.Paste")
			(net "GND")
		)
	)
	(footprint ""
		(layer "F.Cu")
		(at 398.276318 -75.518264)
		(property "Reference" "C1097"
			(at 0 0 0)
			(layer "F.SilkS")
			(hide yes)
			(effects
				(font
					(size 1.27 1.27)
				)
			)
		)
		(property "Value" ""
			(at 0 0 0)
			(layer "F.Fab")
			(effects
				(font
					(size 1.27 1.27)
				)
			)
		)
		(duplicate_pad_numbers_are_jumpers no)
		(fp_line
			(start -0.7874 -0.4064)
			(end 0.7874 -0.4064)
			(stroke
				(width 0.1524)
				(type default)
			)
			(layer "F.SilkS")
		)
		(fp_line
			(start -0.7874 0.4064)
			(end -0.7874 -0.4064)
			(stroke
				(width 0.1524)
				(type default)
			)
			(layer "F.SilkS")
		)
		(fp_line
			(start 0.7874 -0.4064)
			(end 0.7874 0.4064)
			(stroke
				(width 0.1524)
				(type default)
			)
			(layer "F.SilkS")
		)
		(fp_line
			(start 0.7874 0.4064)
			(end -0.7874 0.4064)
			(stroke
				(width 0.1524)
				(type default)
			)
			(layer "F.SilkS")
		)
		(fp_line
			(start -0.67945 -0.305054)
			(end -0.12065 -0.305054)
			(stroke
				(width 0.1)
				(type default)
			)
			(layer "F.Fab")
		)
		(fp_line
			(start -0.67945 0.3048)
			(end -0.67945 -0.305054)
			(stroke
				(width 0.1)
				(type default)
			)
			(layer "F.Fab")
		)
		(fp_line
			(start -0.12065 -0.305054)
			(end -0.12065 -0.2794)
			(stroke
				(width 0.1)
				(type default)
			)
			(layer "F.Fab")
		)
		(fp_line
			(start -0.12065 -0.2794)
			(end 0.12065 -0.2794)
			(stroke
				(width 0.1)
				(type default)
			)
			(layer "F.Fab")
		)
		(fp_line
			(start -0.12065 0.2794)
			(end -0.12065 0.3048)
			(stroke
				(width 0.1)
				(type default)
			)
			(layer "F.Fab")
		)
		(fp_line
			(start -0.12065 0.3048)
			(end -0.67945 0.3048)
			(stroke
				(width 0.1)
				(type default)
			)
			(layer "F.Fab")
		)
		(fp_line
			(start 0.120396 0.2794)
			(end -0.12065 0.2794)
			(stroke
				(width 0.1)
				(type default)
			)
			(layer "F.Fab")
		)
		(fp_line
			(start 0.120396 0.3048)
			(end 0.120396 0.2794)
			(stroke
				(width 0.1)
				(type default)
			)
			(layer "F.Fab")
		)
		(fp_line
			(start 0.12065 -0.3048)
			(end 0.67945 -0.3048)
			(stroke
				(width 0.1)
				(type default)
			)
			(layer "F.Fab")
		)
		(fp_line
			(start 0.12065 -0.2794)
			(end 0.12065 -0.3048)
			(stroke
				(width 0.1)
				(type default)
			)
			(layer "F.Fab")
		)
		(fp_line
			(start 0.67945 -0.3048)
			(end 0.67945 0.3048)
			(stroke
				(width 0.1)
				(type default)
			)
			(layer "F.Fab")
		)
		(fp_line
			(start 0.67945 0.3048)
			(end 0.120396 0.3048)
			(stroke
				(width 0.1)
				(type default)
			)
			(layer "F.Fab")
		)
		(pad "1" smd circle
			(at -0.40005 0)
			(size 0 0)
			(layers "F.Cu" "F.Mask" "F.Paste")
			(net "P3V3_AUX")
		)
		(pad "2" smd circle
			(at 0.40005 0)
			(size 0 0)
			(layers "F.Cu" "F.Mask" "F.Paste")
			(net "GND")
		)
	)
	(footprint ""
		(layer "F.Cu")
		(at 402.126958 -321.002152 90)
		(property "Reference" "R276"
			(at 0 0 90)
			(layer "F.SilkS")
			(hide yes)
			(effects
				(font
					(size 1.27 1.27)
				)
			)
		)
		(property "Value" ""
			(at 0 0 90)
			(layer "F.Fab")
			(effects
				(font
					(size 1.27 1.27)
				)
			)
		)
		(duplicate_pad_numbers_are_jumpers no)
		(fp_line
			(start 0.7874 -0.4064)
			(end 0.7874 0.4064)
			(stroke
				(width 0.1524)
				(type default)
			)
			(layer "F.SilkS")
		)
		(fp_line
			(start -0.7874 -0.4064)
			(end 0.7874 -0.4064)
			(stroke
				(width 0.1524)
				(type default)
			)
			(layer "F.SilkS")
		)
		(fp_line
			(start 0.7874 0.4064)
			(end -0.7874 0.4064)
			(stroke
				(width 0.1524)
				(type default)
			)
			(layer "F.SilkS")
		)
		(fp_line
			(start -0.7874 0.4064)
			(end -0.7874 -0.4064)
			(stroke
				(width 0.1524)
				(type default)
			)
			(layer "F.SilkS")
		)
		(fp_line
			(start -0.12065 -0.305054)
			(end -0.12065 -0.2794)
			(stroke
				(width 0.1)
				(type default)
			)
			(layer "F.Fab")
		)
		(fp_line
			(start -0.67945 -0.305054)
			(end -0.12065 -0.305054)
			(stroke
				(width 0.1)
				(type default)
			)
			(layer "F.Fab")
		)
		(fp_line
			(start 0.67945 -0.3048)
			(end 0.67945 0.3048)
			(stroke
				(width 0.1)
				(type default)
			)
			(layer "F.Fab")
		)
		(fp_line
			(start 0.12065 -0.3048)
			(end 0.67945 -0.3048)
			(stroke
				(width 0.1)
				(type default)
			)
			(layer "F.Fab")
		)
		(fp_line
			(start 0.12065 -0.2794)
			(end 0.12065 -0.3048)
			(stroke
				(width 0.1)
				(type default)
			)
			(layer "F.Fab")
		)
		(fp_line
			(start -0.12065 -0.2794)
			(end 0.12065 -0.2794)
			(stroke
				(width 0.1)
				(type default)
			)
			(layer "F.Fab")
		)
		(fp_line
			(start 0.120396 0.2794)
			(end -0.12065 0.2794)
			(stroke
				(width 0.1)
				(type default)
			)
			(layer "F.Fab")
		)
		(fp_line
			(start -0.12065 0.2794)
			(end -0.12065 0.3048)
			(stroke
				(width 0.1)
				(type default)
			)
			(layer "F.Fab")
		)
		(fp_line
			(start 0.67945 0.3048)
			(end 0.120396 0.3048)
			(stroke
				(width 0.1)
				(type default)
			)
			(layer "F.Fab")
		)
		(fp_line
			(start 0.120396 0.3048)
			(end 0.120396 0.2794)
			(stroke
				(width 0.1)
				(type default)
			)
			(layer "F.Fab")
		)
		(fp_line
			(start -0.12065 0.3048)
			(end -0.67945 0.3048)
			(stroke
				(width 0.1)
				(type default)
			)
			(layer "F.Fab")
		)
		(fp_line
			(start -0.67945 0.3048)
			(end -0.67945 -0.305054)
			(stroke
				(width 0.1)
				(type default)
			)
			(layer "F.Fab")
		)
		(pad "1" smd circle
			(at -0.40005 0 90)
			(size 0 0)
			(layers "F.Cu" "F.Mask" "F.Paste")
			(net "CPU0_PWR_GOOD")
		)
		(pad "2" smd circle
			(at 0.40005 0 90)
			(size 0 0)
			(layers "F.Cu" "F.Mask" "F.Paste")
			(net "PVDD18_S5_P0")
		)
	)
	(footprint ""
		(layer "F.Cu")
		(at 113.375948 -256.012442 90)
		(property "Reference" "C2439"
			(at 0 0 90)
			(layer "F.SilkS")
			(hide yes)
			(effects
				(font
					(size 1.27 1.27)
				)
			)
		)
		(property "Value" ""
			(at 0 0 90)
			(layer "F.Fab")
			(effects
				(font
					(size 1.27 1.27)
				)
			)
		)
		(duplicate_pad_numbers_are_jumpers no)
		(fp_line
			(start 0.7874 -0.4064)
			(end 0.7874 0.4064)
			(stroke
				(width 0.1524)
				(type default)
			)
			(layer "F.SilkS")
		)
		(fp_line
			(start -0.7874 -0.4064)
			(end 0.7874 -0.4064)
			(stroke
				(width 0.1524)
				(type default)
			)
			(layer "F.SilkS")
		)
		(fp_line
			(start 0.7874 0.4064)
			(end -0.7874 0.4064)
			(stroke
				(width 0.1524)
				(type default)
			)
			(layer "F.SilkS")
		)
		(fp_line
			(start -0.7874 0.4064)
			(end -0.7874 -0.4064)
			(stroke
				(width 0.1524)
				(type default)
			)
			(layer "F.SilkS")
		)
		(fp_line
			(start -0.12065 -0.305054)
			(end -0.12065 -0.2794)
			(stroke
				(width 0.1)
				(type default)
			)
			(layer "F.Fab")
		)
		(fp_line
			(start -0.67945 -0.305054)
			(end -0.12065 -0.305054)
			(stroke
				(width 0.1)
				(type default)
			)
			(layer "F.Fab")
		)
		(fp_line
			(start 0.67945 -0.3048)
			(end 0.67945 0.3048)
			(stroke
				(width 0.1)
				(type default)
			)
			(layer "F.Fab")
		)
		(fp_line
			(start 0.12065 -0.3048)
			(end 0.67945 -0.3048)
			(stroke
				(width 0.1)
				(type default)
			)
			(layer "F.Fab")
		)
		(fp_line
			(start 0.12065 -0.2794)
			(end 0.12065 -0.3048)
			(stroke
				(width 0.1)
				(type default)
			)
			(layer "F.Fab")
		)
		(fp_line
			(start -0.12065 -0.2794)
			(end 0.12065 -0.2794)
			(stroke
				(width 0.1)
				(type default)
			)
			(layer "F.Fab")
		)
		(fp_line
			(start 0.120396 0.2794)
			(end -0.12065 0.2794)
			(stroke
				(width 0.1)
				(type default)
			)
			(layer "F.Fab")
		)
		(fp_line
			(start -0.12065 0.2794)
			(end -0.12065 0.3048)
			(stroke
				(width 0.1)
				(type default)
			)
			(layer "F.Fab")
		)
		(fp_line
			(start 0.67945 0.3048)
			(end 0.120396 0.3048)
			(stroke
				(width 0.1)
				(type default)
			)
			(layer "F.Fab")
		)
		(fp_line
			(start 0.120396 0.3048)
			(end 0.120396 0.2794)
			(stroke
				(width 0.1)
				(type default)
			)
			(layer "F.Fab")
		)
		(fp_line
			(start -0.12065 0.3048)
			(end -0.67945 0.3048)
			(stroke
				(width 0.1)
				(type default)
			)
			(layer "F.Fab")
		)
		(fp_line
			(start -0.67945 0.3048)
			(end -0.67945 -0.305054)
			(stroke
				(width 0.1)
				(type default)
			)
			(layer "F.Fab")
		)
		(pad "1" smd circle
			(at -0.40005 0 90)
			(size 0 0)
			(layers "F.Cu" "F.Mask" "F.Paste")
			(net "PVDDCR_SOC_P1")
		)
		(pad "2" smd circle
			(at 0.40005 0 90)
			(size 0 0)
			(layers "F.Cu" "F.Mask" "F.Paste")
			(net "GND")
		)
	)
	(footprint ""
		(layer "F.Cu")
		(at 171.196 -110.200948 180)
		(property "Reference" "R6095"
			(at 0 0 180)
			(layer "F.SilkS")
			(hide yes)
			(effects
				(font
					(size 1.27 1.27)
				)
			)
		)
		(property "Value" ""
			(at 0 0 180)
			(layer "F.Fab")
			(effects
				(font
					(size 1.27 1.27)
				)
			)
		)
		(duplicate_pad_numbers_are_jumpers no)
		(fp_line
			(start 0.7874 0.4064)
			(end -0.7874 0.4064)
			(stroke
				(width 0.1524)
				(type default)
			)
			(layer "F.SilkS")
		)
		(fp_line
			(start 0.7874 -0.4064)
			(end 0.7874 0.4064)
			(stroke
				(width 0.1524)
				(type default)
			)
			(layer "F.SilkS")
		)
		(fp_line
			(start -0.7874 0.4064)
			(end -0.7874 -0.4064)
			(stroke
				(width 0.1524)
				(type default)
			)
			(layer "F.SilkS")
		)
		(fp_line
			(start -0.7874 -0.4064)
			(end 0.7874 -0.4064)
			(stroke
				(width 0.1524)
				(type default)
			)
			(layer "F.SilkS")
		)
		(fp_line
			(start 0.67945 0.3048)
			(end 0.120396 0.3048)
			(stroke
				(width 0.1)
				(type default)
			)
			(layer "F.Fab")
		)
		(fp_line
			(start 0.67945 -0.3048)
			(end 0.67945 0.3048)
			(stroke
				(width 0.1)
				(type default)
			)
			(layer "F.Fab")
		)
		(fp_line
			(start 0.12065 -0.2794)
			(end 0.12065 -0.3048)
			(stroke
				(width 0.1)
				(type default)
			)
			(layer "F.Fab")
		)
		(fp_line
			(start 0.12065 -0.3048)
			(end 0.67945 -0.3048)
			(stroke
				(width 0.1)
				(type default)
			)
			(layer "F.Fab")
		)
		(fp_line
			(start 0.120396 0.3048)
			(end 0.120396 0.2794)
			(stroke
				(width 0.1)
				(type default)
			)
			(layer "F.Fab")
		)
		(fp_line
			(start 0.120396 0.2794)
			(end -0.12065 0.2794)
			(stroke
				(width 0.1)
				(type default)
			)
			(layer "F.Fab")
		)
		(fp_line
			(start -0.12065 0.3048)
			(end -0.67945 0.3048)
			(stroke
				(width 0.1)
				(type default)
			)
			(layer "F.Fab")
		)
		(fp_line
			(start -0.12065 0.2794)
			(end -0.12065 0.3048)
			(stroke
				(width 0.1)
				(type default)
			)
			(layer "F.Fab")
		)
		(fp_line
			(start -0.12065 -0.2794)
			(end 0.12065 -0.2794)
			(stroke
				(width 0.1)
				(type default)
			)
			(layer "F.Fab")
		)
		(fp_line
			(start -0.12065 -0.305054)
			(end -0.12065 -0.2794)
			(stroke
				(width 0.1)
				(type default)
			)
			(layer "F.Fab")
		)
		(fp_line
			(start -0.67945 0.3048)
			(end -0.67945 -0.305054)
			(stroke
				(width 0.1)
				(type default)
			)
			(layer "F.Fab")
		)
		(fp_line
			(start -0.67945 -0.305054)
			(end -0.12065 -0.305054)
			(stroke
				(width 0.1)
				(type default)
			)
			(layer "F.Fab")
		)
		(pad "1" smd circle
			(at -0.40005 0 180)
			(size 0 0)
			(layers "F.Cu" "F.Mask" "F.Paste")
			(net "IRQ_HSC_FAULT_BUF_R_N")
		)
		(pad "2" smd circle
			(at 0.40005 0 180)
			(size 0 0)
			(layers "F.Cu" "F.Mask" "F.Paste")
			(net "IRQ_HSC_FAULT_BUF_N")
		)
	)
	(footprint ""
		(layer "F.Cu")
		(at 40.31996 -434.086 90)
		(property "Reference" "R2914"
			(at 0 0 90)
			(layer "F.SilkS")
			(hide yes)
			(effects
				(font
					(size 1.27 1.27)
				)
			)
		)
		(property "Value" ""
			(at 0 0 90)
			(layer "F.Fab")
			(effects
				(font
					(size 1.27 1.27)
				)
			)
		)
		(duplicate_pad_numbers_are_jumpers no)
		(fp_line
			(start 0.7874 -0.4064)
			(end 0.7874 0.4064)
			(stroke
				(width 0.1524)
				(type default)
			)
			(layer "F.SilkS")
		)
		(fp_line
			(start -0.7874 -0.4064)
			(end 0.7874 -0.4064)
			(stroke
				(width 0.1524)
				(type default)
			)
			(layer "F.SilkS")
		)
		(fp_line
			(start 0.7874 0.4064)
			(end -0.7874 0.4064)
			(stroke
				(width 0.1524)
				(type default)
			)
			(layer "F.SilkS")
		)
		(fp_line
			(start -0.7874 0.4064)
			(end -0.7874 -0.4064)
			(stroke
				(width 0.1524)
				(type default)
			)
			(layer "F.SilkS")
		)
		(fp_line
			(start -0.12065 -0.305054)
			(end -0.12065 -0.2794)
			(stroke
				(width 0.1)
				(type default)
			)
			(layer "F.Fab")
		)
		(fp_line
			(start -0.67945 -0.305054)
			(end -0.12065 -0.305054)
			(stroke
				(width 0.1)
				(type default)
			)
			(layer "F.Fab")
		)
		(fp_line
			(start 0.67945 -0.3048)
			(end 0.67945 0.3048)
			(stroke
				(width 0.1)
				(type default)
			)
			(layer "F.Fab")
		)
		(fp_line
			(start 0.12065 -0.3048)
			(end 0.67945 -0.3048)
			(stroke
				(width 0.1)
				(type default)
			)
			(layer "F.Fab")
		)
		(fp_line
			(start 0.12065 -0.2794)
			(end 0.12065 -0.3048)
			(stroke
				(width 0.1)
				(type default)
			)
			(layer "F.Fab")
		)
		(fp_line
			(start -0.12065 -0.2794)
			(end 0.12065 -0.2794)
			(stroke
				(width 0.1)
				(type default)
			)
			(layer "F.Fab")
		)
		(fp_line
			(start 0.120396 0.2794)
			(end -0.12065 0.2794)
			(stroke
				(width 0.1)
				(type default)
			)
			(layer "F.Fab")
		)
		(fp_line
			(start -0.12065 0.2794)
			(end -0.12065 0.3048)
			(stroke
				(width 0.1)
				(type default)
			)
			(layer "F.Fab")
		)
		(fp_line
			(start 0.67945 0.3048)
			(end 0.120396 0.3048)
			(stroke
				(width 0.1)
				(type default)
			)
			(layer "F.Fab")
		)
		(fp_line
			(start 0.120396 0.3048)
			(end 0.120396 0.2794)
			(stroke
				(width 0.1)
				(type default)
			)
			(layer "F.Fab")
		)
		(fp_line
			(start -0.12065 0.3048)
			(end -0.67945 0.3048)
			(stroke
				(width 0.1)
				(type default)
			)
			(layer "F.Fab")
		)
		(fp_line
			(start -0.67945 0.3048)
			(end -0.67945 -0.305054)
			(stroke
				(width 0.1)
				(type default)
			)
			(layer "F.Fab")
		)
		(pad "1" smd circle
			(at -0.40005 0 90)
			(size 0 0)
			(layers "F.Cu" "F.Mask" "F.Paste")
			(net "P3V3_AUX")
		)
		(pad "2" smd circle
			(at 0.40005 0 90)
			(size 0 0)
			(layers "F.Cu" "F.Mask" "F.Paste")
			(net "FM_SWB_PWR_EN_R1_BUF")
		)
	)
	(footprint ""
		(layer "F.Cu")
		(at 174.879 -137.632948 90)
		(property "Reference" "R248"
			(at 0 0 90)
			(layer "F.SilkS")
			(hide yes)
			(effects
				(font
					(size 1.27 1.27)
				)
			)
		)
		(property "Value" ""
			(at 0 0 90)
			(layer "F.Fab")
			(effects
				(font
					(size 1.27 1.27)
				)
			)
		)
		(duplicate_pad_numbers_are_jumpers no)
		(fp_line
			(start 0.7874 -0.4064)
			(end 0.7874 0.4064)
			(stroke
				(width 0.1524)
				(type default)
			)
			(layer "F.SilkS")
		)
		(fp_line
			(start -0.7874 -0.4064)
			(end 0.7874 -0.4064)
			(stroke
				(width 0.1524)
				(type default)
			)
			(layer "F.SilkS")
		)
		(fp_line
			(start 0.7874 0.4064)
			(end -0.7874 0.4064)
			(stroke
				(width 0.1524)
				(type default)
			)
			(layer "F.SilkS")
		)
		(fp_line
			(start -0.7874 0.4064)
			(end -0.7874 -0.4064)
			(stroke
				(width 0.1524)
				(type default)
			)
			(layer "F.SilkS")
		)
		(fp_line
			(start -0.12065 -0.305054)
			(end -0.12065 -0.2794)
			(stroke
				(width 0.1)
				(type default)
			)
			(layer "F.Fab")
		)
		(fp_line
			(start -0.67945 -0.305054)
			(end -0.12065 -0.305054)
			(stroke
				(width 0.1)
				(type default)
			)
			(layer "F.Fab")
		)
		(fp_line
			(start 0.67945 -0.3048)
			(end 0.67945 0.3048)
			(stroke
				(width 0.1)
				(type default)
			)
			(layer "F.Fab")
		)
		(fp_line
			(start 0.12065 -0.3048)
			(end 0.67945 -0.3048)
			(stroke
				(width 0.1)
				(type default)
			)
			(layer "F.Fab")
		)
		(fp_line
			(start 0.12065 -0.2794)
			(end 0.12065 -0.3048)
			(stroke
				(width 0.1)
				(type default)
			)
			(layer "F.Fab")
		)
		(fp_line
			(start -0.12065 -0.2794)
			(end 0.12065 -0.2794)
			(stroke
				(width 0.1)
				(type default)
			)
			(layer "F.Fab")
		)
		(fp_line
			(start 0.120396 0.2794)
			(end -0.12065 0.2794)
			(stroke
				(width 0.1)
				(type default)
			)
			(layer "F.Fab")
		)
		(fp_line
			(start -0.12065 0.2794)
			(end -0.12065 0.3048)
			(stroke
				(width 0.1)
				(type default)
			)
			(layer "F.Fab")
		)
		(fp_line
			(start 0.67945 0.3048)
			(end 0.120396 0.3048)
			(stroke
				(width 0.1)
				(type default)
			)
			(layer "F.Fab")
		)
		(fp_line
			(start 0.120396 0.3048)
			(end 0.120396 0.2794)
			(stroke
				(width 0.1)
				(type default)
			)
			(layer "F.Fab")
		)
		(fp_line
			(start -0.12065 0.3048)
			(end -0.67945 0.3048)
			(stroke
				(width 0.1)
				(type default)
			)
			(layer "F.Fab")
		)
		(fp_line
			(start -0.67945 0.3048)
			(end -0.67945 -0.305054)
			(stroke
				(width 0.1)
				(type default)
			)
			(layer "F.Fab")
		)
		(pad "1" smd circle
			(at -0.40005 0 90)
			(size 0 0)
			(layers "F.Cu" "F.Mask" "F.Paste")
			(net "FM_CPU0_SLP_S5_N")
		)
		(pad "2" smd circle
			(at 0.40005 0 90)
			(size 0 0)
			(layers "F.Cu" "F.Mask" "F.Paste")
			(net "CPU0_SLP_S5_N")
		)
	)
	(footprint ""
		(layer "F.Cu")
		(at 324.635876 -70.098412 90)
		(property "Reference" "D74"
			(at -3.934714 -0.691642 90)
			(unlocked yes)
			(layer "F.SilkS")
			(effects
				(font
					(size 0.7874 0.5842)
					(thickness 0.1524)
				)
				(justify left)
			)
		)
		(property "Value" ""
			(at 0 0 90)
			(layer "F.Fab")
			(effects
				(font
					(size 1.27 1.27)
				)
			)
		)
		(duplicate_pad_numbers_are_jumpers no)
		(fp_line
			(start 1.16078 -0.4826)
			(end 1.16078 0.4826)
			(stroke
				(width 0.1524)
				(type default)
			)
			(layer "F.SilkS")
		)
		(fp_line
			(start 1.03378 -0.4826)
			(end 1.03378 0.4826)
			(stroke
				(width 0.1524)
				(type default)
			)
			(layer "F.SilkS")
		)
		(fp_line
			(start 0.90678 -0.4826)
			(end 0.90678 0.4826)
			(stroke
				(width 0.1524)
				(type default)
			)
			(layer "F.SilkS")
		)
		(fp_line
			(start -0.64008 -0.4826)
			(end 1.16078 -0.4826)
			(stroke
				(width 0.1524)
				(type default)
			)
			(layer "F.SilkS")
		)
		(fp_line
			(start -0.79248 -0.4826)
			(end 1.03378 -0.4826)
			(stroke
				(width 0.1524)
				(type default)
			)
			(layer "F.SilkS")
		)
		(fp_line
			(start -0.89408 -0.4826)
			(end 0.90678 -0.4826)
			(stroke
				(width 0.1524)
				(type default)
			)
			(layer "F.SilkS")
		)
		(fp_line
			(start 1.16078 0.4826)
			(end -0.64008 0.4826)
			(stroke
				(width 0.1524)
				(type default)
			)
			(layer "F.SilkS")
		)
		(fp_line
			(start 1.03378 0.4826)
			(end -0.79248 0.4826)
			(stroke
				(width 0.1524)
				(type default)
			)
			(layer "F.SilkS")
		)
		(fp_line
			(start 0.90678 0.4826)
			(end -0.90678 0.4826)
			(stroke
				(width 0.1524)
				(type default)
			)
			(layer "F.SilkS")
		)
		(fp_line
			(start -0.90678 0.4826)
			(end -0.90678 -0.4699)
			(stroke
				(width 0.1524)
				(type default)
			)
			(layer "F.SilkS")
		)
		(fp_line
			(start 0.499872 -0.249936)
			(end 0.499872 0.249936)
			(stroke
				(width 0.1)
				(type default)
			)
			(layer "F.Fab")
		)
		(fp_line
			(start -0.499872 -0.249936)
			(end 0.499872 -0.249936)
			(stroke
				(width 0.1)
				(type default)
			)
			(layer "F.Fab")
		)
		(fp_line
			(start 0.499872 0.249936)
			(end -0.499872 0.249936)
			(stroke
				(width 0.1)
				(type default)
			)
			(layer "F.Fab")
		)
		(fp_line
			(start -0.499872 0.249936)
			(end -0.499872 -0.249936)
			(stroke
				(width 0.1)
				(type default)
			)
			(layer "F.Fab")
		)
		(pad "A" smd rect
			(at -0.47498 0 90)
			(size 0.6096 0.7112)
			(layers "F.Cu" "F.Mask" "F.Paste")
			(net "LED_PWRGD_PVDDCR_CPU0_P0_R")
		)
		(pad "C" smd rect
			(at 0.47498 0 90)
			(size 0.6096 0.7112)
			(layers "F.Cu" "F.Mask" "F.Paste")
			(net "LED_PWRGD_PVDDCR_CPU0_P0_D")
		)
	)
	(footprint ""
		(layer "F.Cu")
		(at 265.649964 -22.29993)
		(property "Reference" "H86"
			(at -4.919472 -5.971794 0)
			(unlocked yes)
			(layer "F.SilkS")
			(effects
				(font
					(size 0.7874 0.5842)
					(thickness 0.1524)
				)
				(justify left)
			)
		)
		(property "Value" ""
			(at 0 0 0)
			(layer "F.Fab")
			(effects
				(font
					(size 1.27 1.27)
				)
			)
		)
		(duplicate_pad_numbers_are_jumpers no)
		(pad "1" thru_hole circle
			(at 0 0)
			(size 10.0076 10.0076)
			(drill 5.6134)
			(layers "*.Cu" "*.Mask")
			(remove_unused_layers no)
			(net "GND")
			(clearance -1.9431)
		)
	)
	(footprint ""
		(layer "F.Cu")
		(at 105.64876 -57.486042 180)
		(property "Reference" "R1746"
			(at 0 0 180)
			(layer "F.SilkS")
			(hide yes)
			(effects
				(font
					(size 1.27 1.27)
				)
			)
		)
		(property "Value" ""
			(at 0 0 180)
			(layer "F.Fab")
			(effects
				(font
					(size 1.27 1.27)
				)
			)
		)
		(duplicate_pad_numbers_are_jumpers no)
		(fp_line
			(start 0.7874 0.4064)
			(end -0.7874 0.4064)
			(stroke
				(width 0.1524)
				(type default)
			)
			(layer "F.SilkS")
		)
		(fp_line
			(start 0.7874 -0.4064)
			(end 0.7874 0.4064)
			(stroke
				(width 0.1524)
				(type default)
			)
			(layer "F.SilkS")
		)
		(fp_line
			(start -0.7874 0.4064)
			(end -0.7874 -0.4064)
			(stroke
				(width 0.1524)
				(type default)
			)
			(layer "F.SilkS")
		)
		(fp_line
			(start -0.7874 -0.4064)
			(end 0.7874 -0.4064)
			(stroke
				(width 0.1524)
				(type default)
			)
			(layer "F.SilkS")
		)
		(fp_line
			(start 0.67945 0.3048)
			(end 0.120396 0.3048)
			(stroke
				(width 0.1)
				(type default)
			)
			(layer "F.Fab")
		)
		(fp_line
			(start 0.67945 -0.3048)
			(end 0.67945 0.3048)
			(stroke
				(width 0.1)
				(type default)
			)
			(layer "F.Fab")
		)
		(fp_line
			(start 0.12065 -0.2794)
			(end 0.12065 -0.3048)
			(stroke
				(width 0.1)
				(type default)
			)
			(layer "F.Fab")
		)
		(fp_line
			(start 0.12065 -0.3048)
			(end 0.67945 -0.3048)
			(stroke
				(width 0.1)
				(type default)
			)
			(layer "F.Fab")
		)
		(fp_line
			(start 0.120396 0.3048)
			(end 0.120396 0.2794)
			(stroke
				(width 0.1)
				(type default)
			)
			(layer "F.Fab")
		)
		(fp_line
			(start 0.120396 0.2794)
			(end -0.12065 0.2794)
			(stroke
				(width 0.1)
				(type default)
			)
			(layer "F.Fab")
		)
		(fp_line
			(start -0.12065 0.3048)
			(end -0.67945 0.3048)
			(stroke
				(width 0.1)
				(type default)
			)
			(layer "F.Fab")
		)
		(fp_line
			(start -0.12065 0.2794)
			(end -0.12065 0.3048)
			(stroke
				(width 0.1)
				(type default)
			)
			(layer "F.Fab")
		)
		(fp_line
			(start -0.12065 -0.2794)
			(end 0.12065 -0.2794)
			(stroke
				(width 0.1)
				(type default)
			)
			(layer "F.Fab")
		)
		(fp_line
			(start -0.12065 -0.305054)
			(end -0.12065 -0.2794)
			(stroke
				(width 0.1)
				(type default)
			)
			(layer "F.Fab")
		)
		(fp_line
			(start -0.67945 0.3048)
			(end -0.67945 -0.305054)
			(stroke
				(width 0.1)
				(type default)
			)
			(layer "F.Fab")
		)
		(fp_line
			(start -0.67945 -0.305054)
			(end -0.12065 -0.305054)
			(stroke
				(width 0.1)
				(type default)
			)
			(layer "F.Fab")
		)
		(pad "1" smd circle
			(at -0.40005 0 180)
			(size 0 0)
			(layers "F.Cu" "F.Mask" "F.Paste")
			(net "P3V3_AUX")
		)
		(pad "2" smd circle
			(at 0.40005 0 180)
			(size 0 0)
			(layers "F.Cu" "F.Mask" "F.Paste")
			(net "JTAG_SCM_MUX_TMS")
		)
	)
	(footprint ""
		(layer "F.Cu")
		(at 197.21068 -41.466516 180)
		(property "Reference" "R4062"
			(at 0 0 180)
			(layer "F.SilkS")
			(hide yes)
			(effects
				(font
					(size 1.27 1.27)
				)
			)
		)
		(property "Value" ""
			(at 0 0 180)
			(layer "F.Fab")
			(effects
				(font
					(size 1.27 1.27)
				)
			)
		)
		(duplicate_pad_numbers_are_jumpers no)
		(fp_line
			(start 0.7874 0.4064)
			(end -0.7874 0.4064)
			(stroke
				(width 0.1524)
				(type default)
			)
			(layer "F.SilkS")
		)
		(fp_line
			(start 0.7874 -0.4064)
			(end 0.7874 0.4064)
			(stroke
				(width 0.1524)
				(type default)
			)
			(layer "F.SilkS")
		)
		(fp_line
			(start -0.7874 0.4064)
			(end -0.7874 -0.4064)
			(stroke
				(width 0.1524)
				(type default)
			)
			(layer "F.SilkS")
		)
		(fp_line
			(start -0.7874 -0.4064)
			(end 0.7874 -0.4064)
			(stroke
				(width 0.1524)
				(type default)
			)
			(layer "F.SilkS")
		)
		(fp_line
			(start 0.67945 0.3048)
			(end 0.120396 0.3048)
			(stroke
				(width 0.1)
				(type default)
			)
			(layer "F.Fab")
		)
		(fp_line
			(start 0.67945 -0.3048)
			(end 0.67945 0.3048)
			(stroke
				(width 0.1)
				(type default)
			)
			(layer "F.Fab")
		)
		(fp_line
			(start 0.12065 -0.2794)
			(end 0.12065 -0.3048)
			(stroke
				(width 0.1)
				(type default)
			)
			(layer "F.Fab")
		)
		(fp_line
			(start 0.12065 -0.3048)
			(end 0.67945 -0.3048)
			(stroke
				(width 0.1)
				(type default)
			)
			(layer "F.Fab")
		)
		(fp_line
			(start 0.120396 0.3048)
			(end 0.120396 0.2794)
			(stroke
				(width 0.1)
				(type default)
			)
			(layer "F.Fab")
		)
		(fp_line
			(start 0.120396 0.2794)
			(end -0.12065 0.2794)
			(stroke
				(width 0.1)
				(type default)
			)
			(layer "F.Fab")
		)
		(fp_line
			(start -0.12065 0.3048)
			(end -0.67945 0.3048)
			(stroke
				(width 0.1)
				(type default)
			)
			(layer "F.Fab")
		)
		(fp_line
			(start -0.12065 0.2794)
			(end -0.12065 0.3048)
			(stroke
				(width 0.1)
				(type default)
			)
			(layer "F.Fab")
		)
		(fp_line
			(start -0.12065 -0.2794)
			(end 0.12065 -0.2794)
			(stroke
				(width 0.1)
				(type default)
			)
			(layer "F.Fab")
		)
		(fp_line
			(start -0.12065 -0.305054)
			(end -0.12065 -0.2794)
			(stroke
				(width 0.1)
				(type default)
			)
			(layer "F.Fab")
		)
		(fp_line
			(start -0.67945 0.3048)
			(end -0.67945 -0.305054)
			(stroke
				(width 0.1)
				(type default)
			)
			(layer "F.Fab")
		)
		(fp_line
			(start -0.67945 -0.305054)
			(end -0.12065 -0.305054)
			(stroke
				(width 0.1)
				(type default)
			)
			(layer "F.Fab")
		)
		(pad "1" smd circle
			(at -0.40005 0 180)
			(size 0 0)
			(layers "F.Cu" "F.Mask" "F.Paste")
			(net "P12V_SCM_EN")
		)
		(pad "2" smd circle
			(at 0.40005 0 180)
			(size 0 0)
			(layers "F.Cu" "F.Mask" "F.Paste")
			(net "P12V_SCM_EN_R")
		)
	)
	(footprint ""
		(layer "F.Cu")
		(at 103.190294 -384.10388 180)
		(property "Reference" "R704"
			(at 0 0 180)
			(layer "F.SilkS")
			(hide yes)
			(effects
				(font
					(size 1.27 1.27)
				)
			)
		)
		(property "Value" ""
			(at 0 0 180)
			(layer "F.Fab")
			(effects
				(font
					(size 1.27 1.27)
				)
			)
		)
		(duplicate_pad_numbers_are_jumpers no)
		(fp_line
			(start 0.7874 0.4064)
			(end -0.7874 0.4064)
			(stroke
				(width 0.1524)
				(type default)
			)
			(layer "F.SilkS")
		)
		(fp_line
			(start 0.7874 -0.4064)
			(end 0.7874 0.4064)
			(stroke
				(width 0.1524)
				(type default)
			)
			(layer "F.SilkS")
		)
		(fp_line
			(start -0.7874 0.4064)
			(end -0.7874 -0.4064)
			(stroke
				(width 0.1524)
				(type default)
			)
			(layer "F.SilkS")
		)
		(fp_line
			(start -0.7874 -0.4064)
			(end 0.7874 -0.4064)
			(stroke
				(width 0.1524)
				(type default)
			)
			(layer "F.SilkS")
		)
		(fp_line
			(start 0.67945 0.3048)
			(end 0.120396 0.3048)
			(stroke
				(width 0.1)
				(type default)
			)
			(layer "F.Fab")
		)
		(fp_line
			(start 0.67945 -0.3048)
			(end 0.67945 0.3048)
			(stroke
				(width 0.1)
				(type default)
			)
			(layer "F.Fab")
		)
		(fp_line
			(start 0.12065 -0.2794)
			(end 0.12065 -0.3048)
			(stroke
				(width 0.1)
				(type default)
			)
			(layer "F.Fab")
		)
		(fp_line
			(start 0.12065 -0.3048)
			(end 0.67945 -0.3048)
			(stroke
				(width 0.1)
				(type default)
			)
			(layer "F.Fab")
		)
		(fp_line
			(start 0.120396 0.3048)
			(end 0.120396 0.2794)
			(stroke
				(width 0.1)
				(type default)
			)
			(layer "F.Fab")
		)
		(fp_line
			(start 0.120396 0.2794)
			(end -0.12065 0.2794)
			(stroke
				(width 0.1)
				(type default)
			)
			(layer "F.Fab")
		)
		(fp_line
			(start -0.12065 0.3048)
			(end -0.67945 0.3048)
			(stroke
				(width 0.1)
				(type default)
			)
			(layer "F.Fab")
		)
		(fp_line
			(start -0.12065 0.2794)
			(end -0.12065 0.3048)
			(stroke
				(width 0.1)
				(type default)
			)
			(layer "F.Fab")
		)
		(fp_line
			(start -0.12065 -0.2794)
			(end 0.12065 -0.2794)
			(stroke
				(width 0.1)
				(type default)
			)
			(layer "F.Fab")
		)
		(fp_line
			(start -0.12065 -0.305054)
			(end -0.12065 -0.2794)
			(stroke
				(width 0.1)
				(type default)
			)
			(layer "F.Fab")
		)
		(fp_line
			(start -0.67945 0.3048)
			(end -0.67945 -0.305054)
			(stroke
				(width 0.1)
				(type default)
			)
			(layer "F.Fab")
		)
		(fp_line
			(start -0.67945 -0.305054)
			(end -0.12065 -0.305054)
			(stroke
				(width 0.1)
				(type default)
			)
			(layer "F.Fab")
		)
		(pad "1" smd rect
			(at -0.40005 0)
			(size 0.4572 0.508)
			(layers "F.Cu" "F.Mask" "F.Paste")
			(net "P1V8_CPU1_RT_1D")
		)
		(pad "2" smd rect
			(at 0.40005 0)
			(size 0.4572 0.508)
			(layers "F.Cu" "F.Mask" "F.Paste")
			(net "P1V8_CPU1_RT1_1A_1D")
		)
	)
	(footprint ""
		(layer "F.Cu")
		(at 447.687192 -21.236178 180)
		(property "Reference" "PR5484"
			(at 0 0 180)
			(layer "F.SilkS")
			(hide yes)
			(effects
				(font
					(size 1.27 1.27)
				)
			)
		)
		(property "Value" ""
			(at 0 0 180)
			(layer "F.Fab")
			(effects
				(font
					(size 1.27 1.27)
				)
			)
		)
		(duplicate_pad_numbers_are_jumpers no)
		(fp_line
			(start 0.7874 0.4064)
			(end -0.7874 0.4064)
			(stroke
				(width 0.1524)
				(type default)
			)
			(layer "F.SilkS")
		)
		(fp_line
			(start 0.7874 -0.4064)
			(end 0.7874 0.4064)
			(stroke
				(width 0.1524)
				(type default)
			)
			(layer "F.SilkS")
		)
		(fp_line
			(start -0.7874 0.4064)
			(end -0.7874 -0.4064)
			(stroke
				(width 0.1524)
				(type default)
			)
			(layer "F.SilkS")
		)
		(fp_line
			(start -0.7874 -0.4064)
			(end 0.7874 -0.4064)
			(stroke
				(width 0.1524)
				(type default)
			)
			(layer "F.SilkS")
		)
		(fp_line
			(start 0.67945 0.3048)
			(end 0.120396 0.3048)
			(stroke
				(width 0.1)
				(type default)
			)
			(layer "F.Fab")
		)
		(fp_line
			(start 0.67945 -0.3048)
			(end 0.67945 0.3048)
			(stroke
				(width 0.1)
				(type default)
			)
			(layer "F.Fab")
		)
		(fp_line
			(start 0.12065 -0.2794)
			(end 0.12065 -0.3048)
			(stroke
				(width 0.1)
				(type default)
			)
			(layer "F.Fab")
		)
		(fp_line
			(start 0.12065 -0.3048)
			(end 0.67945 -0.3048)
			(stroke
				(width 0.1)
				(type default)
			)
			(layer "F.Fab")
		)
		(fp_line
			(start 0.120396 0.3048)
			(end 0.120396 0.2794)
			(stroke
				(width 0.1)
				(type default)
			)
			(layer "F.Fab")
		)
		(fp_line
			(start 0.120396 0.2794)
			(end -0.12065 0.2794)
			(stroke
				(width 0.1)
				(type default)
			)
			(layer "F.Fab")
		)
		(fp_line
			(start -0.12065 0.3048)
			(end -0.67945 0.3048)
			(stroke
				(width 0.1)
				(type default)
			)
			(layer "F.Fab")
		)
		(fp_line
			(start -0.12065 0.2794)
			(end -0.12065 0.3048)
			(stroke
				(width 0.1)
				(type default)
			)
			(layer "F.Fab")
		)
		(fp_line
			(start -0.12065 -0.2794)
			(end 0.12065 -0.2794)
			(stroke
				(width 0.1)
				(type default)
			)
			(layer "F.Fab")
		)
		(fp_line
			(start -0.12065 -0.305054)
			(end -0.12065 -0.2794)
			(stroke
				(width 0.1)
				(type default)
			)
			(layer "F.Fab")
		)
		(fp_line
			(start -0.67945 0.3048)
			(end -0.67945 -0.305054)
			(stroke
				(width 0.1)
				(type default)
			)
			(layer "F.Fab")
		)
		(fp_line
			(start -0.67945 -0.305054)
			(end -0.12065 -0.305054)
			(stroke
				(width 0.1)
				(type default)
			)
			(layer "F.Fab")
		)
		(pad "1" smd circle
			(at -0.40005 0 180)
			(size 0 0)
			(layers "F.Cu" "F.Mask" "F.Paste")
			(net "P12V_OCP_CB_1")
		)
		(pad "2" smd circle
			(at 0.40005 0 180)
			(size 0 0)
			(layers "F.Cu" "F.Mask" "F.Paste")
			(net "GND")
		)
	)
	(footprint ""
		(layer "F.Cu")
		(at 139.065 -116.586 180)
		(property "Reference" "C8022"
			(at 0 0 180)
			(layer "F.SilkS")
			(hide yes)
			(effects
				(font
					(size 1.27 1.27)
				)
			)
		)
		(property "Value" ""
			(at 0 0 180)
			(layer "F.Fab")
			(effects
				(font
					(size 1.27 1.27)
				)
			)
		)
		(duplicate_pad_numbers_are_jumpers no)
		(fp_line
			(start 0.7874 0.4064)
			(end -0.7874 0.4064)
			(stroke
				(width 0.1524)
				(type default)
			)
			(layer "F.SilkS")
		)
		(fp_line
			(start 0.7874 -0.4064)
			(end 0.7874 0.4064)
			(stroke
				(width 0.1524)
				(type default)
			)
			(layer "F.SilkS")
		)
		(fp_line
			(start -0.7874 0.4064)
			(end -0.7874 -0.4064)
			(stroke
				(width 0.1524)
				(type default)
			)
			(layer "F.SilkS")
		)
		(fp_line
			(start -0.7874 -0.4064)
			(end 0.7874 -0.4064)
			(stroke
				(width 0.1524)
				(type default)
			)
			(layer "F.SilkS")
		)
		(fp_line
			(start 0.67945 0.3048)
			(end 0.120396 0.3048)
			(stroke
				(width 0.1)
				(type default)
			)
			(layer "F.Fab")
		)
		(fp_line
			(start 0.67945 -0.3048)
			(end 0.67945 0.3048)
			(stroke
				(width 0.1)
				(type default)
			)
			(layer "F.Fab")
		)
		(fp_line
			(start 0.12065 -0.2794)
			(end 0.12065 -0.3048)
			(stroke
				(width 0.1)
				(type default)
			)
			(layer "F.Fab")
		)
		(fp_line
			(start 0.12065 -0.3048)
			(end 0.67945 -0.3048)
			(stroke
				(width 0.1)
				(type default)
			)
			(layer "F.Fab")
		)
		(fp_line
			(start 0.120396 0.3048)
			(end 0.120396 0.2794)
			(stroke
				(width 0.1)
				(type default)
			)
			(layer "F.Fab")
		)
		(fp_line
			(start 0.120396 0.2794)
			(end -0.12065 0.2794)
			(stroke
				(width 0.1)
				(type default)
			)
			(layer "F.Fab")
		)
		(fp_line
			(start -0.12065 0.3048)
			(end -0.67945 0.3048)
			(stroke
				(width 0.1)
				(type default)
			)
			(layer "F.Fab")
		)
		(fp_line
			(start -0.12065 0.2794)
			(end -0.12065 0.3048)
			(stroke
				(width 0.1)
				(type default)
			)
			(layer "F.Fab")
		)
		(fp_line
			(start -0.12065 -0.2794)
			(end 0.12065 -0.2794)
			(stroke
				(width 0.1)
				(type default)
			)
			(layer "F.Fab")
		)
		(fp_line
			(start -0.12065 -0.305054)
			(end -0.12065 -0.2794)
			(stroke
				(width 0.1)
				(type default)
			)
			(layer "F.Fab")
		)
		(fp_line
			(start -0.67945 0.3048)
			(end -0.67945 -0.305054)
			(stroke
				(width 0.1)
				(type default)
			)
			(layer "F.Fab")
		)
		(fp_line
			(start -0.67945 -0.305054)
			(end -0.12065 -0.305054)
			(stroke
				(width 0.1)
				(type default)
			)
			(layer "F.Fab")
		)
		(pad "1" smd circle
			(at -0.40005 0 180)
			(size 0 0)
			(layers "F.Cu" "F.Mask" "F.Paste")
			(net "P12V_AUX")
		)
		(pad "2" smd circle
			(at 0.40005 0 180)
			(size 0 0)
			(layers "F.Cu" "F.Mask" "F.Paste")
			(net "GND")
		)
	)
	(footprint ""
		(layer "F.Cu")
		(at 44.069 -435.61)
		(property "Reference" "R3506"
			(at 0 0 0)
			(layer "F.SilkS")
			(hide yes)
			(effects
				(font
					(size 1.27 1.27)
				)
			)
		)
		(property "Value" ""
			(at 0 0 0)
			(layer "F.Fab")
			(effects
				(font
					(size 1.27 1.27)
				)
			)
		)
		(duplicate_pad_numbers_are_jumpers no)
		(fp_line
			(start -0.7874 -0.4064)
			(end 0.7874 -0.4064)
			(stroke
				(width 0.1524)
				(type default)
			)
			(layer "F.SilkS")
		)
		(fp_line
			(start -0.7874 0.4064)
			(end -0.7874 -0.4064)
			(stroke
				(width 0.1524)
				(type default)
			)
			(layer "F.SilkS")
		)
		(fp_line
			(start 0.7874 -0.4064)
			(end 0.7874 0.4064)
			(stroke
				(width 0.1524)
				(type default)
			)
			(layer "F.SilkS")
		)
		(fp_line
			(start 0.7874 0.4064)
			(end -0.7874 0.4064)
			(stroke
				(width 0.1524)
				(type default)
			)
			(layer "F.SilkS")
		)
		(fp_line
			(start -0.67945 -0.305054)
			(end -0.12065 -0.305054)
			(stroke
				(width 0.1)
				(type default)
			)
			(layer "F.Fab")
		)
		(fp_line
			(start -0.67945 0.3048)
			(end -0.67945 -0.305054)
			(stroke
				(width 0.1)
				(type default)
			)
			(layer "F.Fab")
		)
		(fp_line
			(start -0.12065 -0.305054)
			(end -0.12065 -0.2794)
			(stroke
				(width 0.1)
				(type default)
			)
			(layer "F.Fab")
		)
		(fp_line
			(start -0.12065 -0.2794)
			(end 0.12065 -0.2794)
			(stroke
				(width 0.1)
				(type default)
			)
			(layer "F.Fab")
		)
		(fp_line
			(start -0.12065 0.2794)
			(end -0.12065 0.3048)
			(stroke
				(width 0.1)
				(type default)
			)
			(layer "F.Fab")
		)
		(fp_line
			(start -0.12065 0.3048)
			(end -0.67945 0.3048)
			(stroke
				(width 0.1)
				(type default)
			)
			(layer "F.Fab")
		)
		(fp_line
			(start 0.120396 0.2794)
			(end -0.12065 0.2794)
			(stroke
				(width 0.1)
				(type default)
			)
			(layer "F.Fab")
		)
		(fp_line
			(start 0.120396 0.3048)
			(end 0.120396 0.2794)
			(stroke
				(width 0.1)
				(type default)
			)
			(layer "F.Fab")
		)
		(fp_line
			(start 0.12065 -0.3048)
			(end 0.67945 -0.3048)
			(stroke
				(width 0.1)
				(type default)
			)
			(layer "F.Fab")
		)
		(fp_line
			(start 0.12065 -0.2794)
			(end 0.12065 -0.3048)
			(stroke
				(width 0.1)
				(type default)
			)
			(layer "F.Fab")
		)
		(fp_line
			(start 0.67945 -0.3048)
			(end 0.67945 0.3048)
			(stroke
				(width 0.1)
				(type default)
			)
			(layer "F.Fab")
		)
		(fp_line
			(start 0.67945 0.3048)
			(end 0.120396 0.3048)
			(stroke
				(width 0.1)
				(type default)
			)
			(layer "F.Fab")
		)
		(pad "1" smd circle
			(at -0.40005 0)
			(size 0 0)
			(layers "F.Cu" "F.Mask" "F.Paste")
			(net "P3V3_AUX")
		)
		(pad "2" smd circle
			(at 0.40005 0)
			(size 0 0)
			(layers "F.Cu" "F.Mask" "F.Paste")
			(net "GPU_FPGA_RST_R_N")
		)
	)
	(footprint ""
		(layer "F.Cu")
		(at 172.540422 -416.484816)
		(property "Reference" "R9009"
			(at 0 0 0)
			(layer "F.SilkS")
			(hide yes)
			(effects
				(font
					(size 1.27 1.27)
				)
			)
		)
		(property "Value" ""
			(at 0 0 0)
			(layer "F.Fab")
			(effects
				(font
					(size 1.27 1.27)
				)
			)
		)
		(duplicate_pad_numbers_are_jumpers no)
		(fp_line
			(start -0.7874 -0.4064)
			(end 0.7874 -0.4064)
			(stroke
				(width 0.1524)
				(type default)
			)
			(layer "F.SilkS")
		)
		(fp_line
			(start -0.7874 0.4064)
			(end -0.7874 -0.4064)
			(stroke
				(width 0.1524)
				(type default)
			)
			(layer "F.SilkS")
		)
		(fp_line
			(start 0.7874 -0.4064)
			(end 0.7874 0.4064)
			(stroke
				(width 0.1524)
				(type default)
			)
			(layer "F.SilkS")
		)
		(fp_line
			(start 0.7874 0.4064)
			(end -0.7874 0.4064)
			(stroke
				(width 0.1524)
				(type default)
			)
			(layer "F.SilkS")
		)
		(fp_line
			(start -0.67945 -0.305054)
			(end -0.12065 -0.305054)
			(stroke
				(width 0.1)
				(type default)
			)
			(layer "F.Fab")
		)
		(fp_line
			(start -0.67945 0.3048)
			(end -0.67945 -0.305054)
			(stroke
				(width 0.1)
				(type default)
			)
			(layer "F.Fab")
		)
		(fp_line
			(start -0.12065 -0.305054)
			(end -0.12065 -0.2794)
			(stroke
				(width 0.1)
				(type default)
			)
			(layer "F.Fab")
		)
		(fp_line
			(start -0.12065 -0.2794)
			(end 0.12065 -0.2794)
			(stroke
				(width 0.1)
				(type default)
			)
			(layer "F.Fab")
		)
		(fp_line
			(start -0.12065 0.2794)
			(end -0.12065 0.3048)
			(stroke
				(width 0.1)
				(type default)
			)
			(layer "F.Fab")
		)
		(fp_line
			(start -0.12065 0.3048)
			(end -0.67945 0.3048)
			(stroke
				(width 0.1)
				(type default)
			)
			(layer "F.Fab")
		)
		(fp_line
			(start 0.120396 0.2794)
			(end -0.12065 0.2794)
			(stroke
				(width 0.1)
				(type default)
			)
			(layer "F.Fab")
		)
		(fp_line
			(start 0.120396 0.3048)
			(end 0.120396 0.2794)
			(stroke
				(width 0.1)
				(type default)
			)
			(layer "F.Fab")
		)
		(fp_line
			(start 0.12065 -0.3048)
			(end 0.67945 -0.3048)
			(stroke
				(width 0.1)
				(type default)
			)
			(layer "F.Fab")
		)
		(fp_line
			(start 0.12065 -0.2794)
			(end 0.12065 -0.3048)
			(stroke
				(width 0.1)
				(type default)
			)
			(layer "F.Fab")
		)
		(fp_line
			(start 0.67945 -0.3048)
			(end 0.67945 0.3048)
			(stroke
				(width 0.1)
				(type default)
			)
			(layer "F.Fab")
		)
		(fp_line
			(start 0.67945 0.3048)
			(end 0.120396 0.3048)
			(stroke
				(width 0.1)
				(type default)
			)
			(layer "F.Fab")
		)
		(pad "1" smd circle
			(at -0.40005 0)
			(size 0 0)
			(layers "F.Cu" "F.Mask" "F.Paste")
			(net "P3V3_AUX")
		)
		(pad "2" smd circle
			(at 0.40005 0)
			(size 0 0)
			(layers "F.Cu" "F.Mask" "F.Paste")
			(net "PRSNT_CABLE_SWB_B2_ISO_N")
		)
	)
	(footprint ""
		(layer "F.Cu")
		(at 28.021026 -428.755302)
		(property "Reference" "R6156"
			(at 0 0 0)
			(layer "F.SilkS")
			(hide yes)
			(effects
				(font
					(size 1.27 1.27)
				)
			)
		)
		(property "Value" ""
			(at 0 0 0)
			(layer "F.Fab")
			(effects
				(font
					(size 1.27 1.27)
				)
			)
		)
		(duplicate_pad_numbers_are_jumpers no)
		(fp_line
			(start -0.32512 -0.175006)
			(end 0.32512 -0.175006)
			(stroke
				(width 0.1)
				(type default)
			)
			(layer "F.Fab")
		)
		(fp_line
			(start -0.32512 0.175006)
			(end -0.32512 -0.175006)
			(stroke
				(width 0.1)
				(type default)
			)
			(layer "F.Fab")
		)
		(fp_line
			(start 0.32512 -0.175006)
			(end 0.32512 0.175006)
			(stroke
				(width 0.1)
				(type default)
			)
			(layer "F.Fab")
		)
		(fp_line
			(start 0.32512 0.175006)
			(end -0.32512 0.175006)
			(stroke
				(width 0.1)
				(type default)
			)
			(layer "F.Fab")
		)
		(pad "1" smd rect
			(at -0.2667 0)
			(size 0.3048 0.381)
			(layers "F.Cu" "F.Mask" "F.Paste")
			(net "P2E_MB_BMC_RX_DP<0>")
		)
		(pad "2" smd rect
			(at 0.2667 0 180)
			(size 0.3048 0.381)
			(layers "F.Cu" "F.Mask" "F.Paste")
			(net "P2E_MB_BMC_RX_R1_DP<0>")
		)
	)
	(footprint ""
		(layer "F.Cu")
		(at 335.114646 -403.603206 -90)
		(property "Reference" "R1037"
			(at 0 0 270)
			(layer "F.SilkS")
			(hide yes)
			(effects
				(font
					(size 1.27 1.27)
				)
			)
		)
		(property "Value" ""
			(at 0 0 270)
			(layer "F.Fab")
			(effects
				(font
					(size 1.27 1.27)
				)
			)
		)
		(duplicate_pad_numbers_are_jumpers no)
		(fp_line
			(start -0.32512 0.175006)
			(end -0.32512 -0.175006)
			(stroke
				(width 0.1)
				(type default)
			)
			(layer "F.Fab")
		)
		(fp_line
			(start 0.32512 0.175006)
			(end -0.32512 0.175006)
			(stroke
				(width 0.1)
				(type default)
			)
			(layer "F.Fab")
		)
		(fp_line
			(start -0.32512 -0.175006)
			(end 0.32512 -0.175006)
			(stroke
				(width 0.1)
				(type default)
			)
			(layer "F.Fab")
		)
		(fp_line
			(start 0.32512 -0.175006)
			(end 0.32512 0.175006)
			(stroke
				(width 0.1)
				(type default)
			)
			(layer "F.Fab")
		)
		(pad "1" smd rect
			(at -0.2667 0 270)
			(size 0.3048 0.381)
			(layers "F.Cu" "F.Mask" "F.Paste")
			(net "JTAG_TEST_MODE_RT_CPU0_P1")
		)
		(pad "2" smd rect
			(at 0.2667 0 90)
			(size 0.3048 0.381)
			(layers "F.Cu" "F.Mask" "F.Paste")
			(net "GND")
		)
	)
	(footprint ""
		(layer "F.Cu")
		(at 191.065404 -32.110426 180)
		(property "Reference" "PD115"
			(at 2.149348 1.672336 0)
			(unlocked yes)
			(layer "F.SilkS")
			(effects
				(font
					(size 0.7874 0.5842)
					(thickness 0.1524)
				)
				(justify left)
			)
		)
		(property "Value" ""
			(at 0 0 180)
			(layer "F.Fab")
			(effects
				(font
					(size 1.27 1.27)
				)
			)
		)
		(duplicate_pad_numbers_are_jumpers no)
		(fp_line
			(start 2.631186 0.999998)
			(end 2.631186 -0.999998)
			(stroke
				(width 0.1524)
				(type default)
			)
			(layer "F.SilkS")
		)
		(fp_line
			(start 2.631186 -0.999998)
			(end -2.250186 -0.999998)
			(stroke
				(width 0.1524)
				(type default)
			)
			(layer "F.SilkS")
		)
		(fp_line
			(start 0.381 -0.0508)
			(end 0.635 -0.0508)
			(stroke
				(width 0.1524)
				(type default)
			)
			(layer "F.SilkS")
		)
		(fp_line
			(start 0.381 -0.0508)
			(end -0.381 0.3302)
			(stroke
				(width 0.1524)
				(type default)
			)
			(layer "F.SilkS")
		)
		(fp_line
			(start 0.381 -0.4318)
			(end 0.381 0.3302)
			(stroke
				(width 0.1524)
				(type default)
			)
			(layer "F.SilkS")
		)
		(fp_line
			(start -0.381 0.3302)
			(end -0.381 -0.4318)
			(stroke
				(width 0.1524)
				(type default)
			)
			(layer "F.SilkS")
		)
		(fp_line
			(start -0.381 -0.0508)
			(end -0.6604 -0.0508)
			(stroke
				(width 0.1524)
				(type default)
			)
			(layer "F.SilkS")
		)
		(fp_line
			(start -0.381 -0.4318)
			(end 0.381 -0.0508)
			(stroke
				(width 0.1524)
				(type default)
			)
			(layer "F.SilkS")
		)
		(fp_line
			(start -2.250186 0.999998)
			(end 2.631186 0.999998)
			(stroke
				(width 0.1524)
				(type default)
			)
			(layer "F.SilkS")
		)
		(fp_line
			(start -2.250186 -0.999998)
			(end -2.250186 0.999998)
			(stroke
				(width 0.1524)
				(type default)
			)
			(layer "F.SilkS")
		)
		(fp_rect
			(start 2.6162 -0.9652)
			(end 2.1844 1.016)
			(stroke
				(width 0)
				(type default)
			)
			(fill yes)
			(layer "F.SilkS")
		)
		(fp_line
			(start 1.450086 0.999998)
			(end 1.450086 -0.999998)
			(stroke
				(width 0.1)
				(type default)
			)
			(layer "F.Fab")
		)
		(fp_line
			(start 1.450086 -0.999998)
			(end -1.450086 -0.999998)
			(stroke
				(width 0.1)
				(type default)
			)
			(layer "F.Fab")
		)
		(fp_line
			(start -1.450086 0.999998)
			(end 1.450086 0.999998)
			(stroke
				(width 0.1)
				(type default)
			)
			(layer "F.Fab")
		)
		(fp_line
			(start -1.450086 -0.999998)
			(end -1.450086 0.999998)
			(stroke
				(width 0.1)
				(type default)
			)
			(layer "F.Fab")
		)
		(fp_text user "-"
			(at 2.4384 -0.22225 180)
			(unlocked yes)
			(layer "F.SilkS")
			(effects
				(font
					(size 1.905 1.4224)
					(thickness 0.1524)
				)
				(justify left)
			)
		)
		(fp_text user "+"
			(at -3.4798 -0.22225 180)
			(unlocked yes)
			(layer "F.SilkS")
			(effects
				(font
					(size 1.905 1.4224)
					(thickness 0.1524)
				)
				(justify left)
			)
		)
		(fp_text user "-"
			(at 2.4384 -0.22225 180)
			(unlocked yes)
			(layer "F.Fab")
			(effects
				(font
					(size 1.905 1.4224)
					(thickness 0.1524)
				)
				(justify left)
			)
		)
		(fp_text user "+"
			(at -3.4798 -0.22225 180)
			(unlocked yes)
			(layer "F.Fab")
			(effects
				(font
					(size 1.905 1.4224)
					(thickness 0.1524)
				)
				(justify left)
			)
		)
		(pad "A" smd rect
			(at -1.450086 0 180)
			(size 1.3208 1.4224)
			(layers "F.Cu" "F.Mask" "F.Paste")
			(net "GND")
		)
		(pad "C" smd rect
			(at 1.450086 0 180)
			(size 1.3208 1.4224)
			(layers "F.Cu" "F.Mask" "F.Paste")
			(net "P12V_AUX")
		)
	)
	(footprint ""
		(layer "F.Cu")
		(at 461.460088 -347.699838)
		(property "Reference" "H95"
			(at -5.244084 -5.691886 0)
			(unlocked yes)
			(layer "F.SilkS")
			(effects
				(font
					(size 0.7874 0.5842)
					(thickness 0.1524)
				)
				(justify left)
			)
		)
		(property "Value" ""
			(at 0 0 0)
			(layer "F.Fab")
			(effects
				(font
					(size 1.27 1.27)
				)
			)
		)
		(duplicate_pad_numbers_are_jumpers no)
		(pad "1" thru_hole circle
			(at 0 0)
			(size 10.0076 10.0076)
			(drill 5.6134)
			(layers "*.Cu" "*.Mask")
			(remove_unused_layers no)
			(net "GND")
			(clearance -1.9431)
		)
	)
	(footprint ""
		(layer "F.Cu")
		(at 303.353978 -13.41501)
		(property "Reference" "R4189"
			(at 0 0 0)
			(layer "F.SilkS")
			(hide yes)
			(effects
				(font
					(size 1.27 1.27)
				)
			)
		)
		(property "Value" ""
			(at 0 0 0)
			(layer "F.Fab")
			(effects
				(font
					(size 1.27 1.27)
				)
			)
		)
		(duplicate_pad_numbers_are_jumpers no)
		(fp_line
			(start -0.7874 -0.4064)
			(end 0.7874 -0.4064)
			(stroke
				(width 0.1524)
				(type default)
			)
			(layer "F.SilkS")
		)
		(fp_line
			(start -0.7874 0.4064)
			(end -0.7874 -0.4064)
			(stroke
				(width 0.1524)
				(type default)
			)
			(layer "F.SilkS")
		)
		(fp_line
			(start 0.7874 -0.4064)
			(end 0.7874 0.4064)
			(stroke
				(width 0.1524)
				(type default)
			)
			(layer "F.SilkS")
		)
		(fp_line
			(start 0.7874 0.4064)
			(end -0.7874 0.4064)
			(stroke
				(width 0.1524)
				(type default)
			)
			(layer "F.SilkS")
		)
		(fp_line
			(start -0.67945 -0.305054)
			(end -0.12065 -0.305054)
			(stroke
				(width 0.1)
				(type default)
			)
			(layer "F.Fab")
		)
		(fp_line
			(start -0.67945 0.3048)
			(end -0.67945 -0.305054)
			(stroke
				(width 0.1)
				(type default)
			)
			(layer "F.Fab")
		)
		(fp_line
			(start -0.12065 -0.305054)
			(end -0.12065 -0.2794)
			(stroke
				(width 0.1)
				(type default)
			)
			(layer "F.Fab")
		)
		(fp_line
			(start -0.12065 -0.2794)
			(end 0.12065 -0.2794)
			(stroke
				(width 0.1)
				(type default)
			)
			(layer "F.Fab")
		)
		(fp_line
			(start -0.12065 0.2794)
			(end -0.12065 0.3048)
			(stroke
				(width 0.1)
				(type default)
			)
			(layer "F.Fab")
		)
		(fp_line
			(start -0.12065 0.3048)
			(end -0.67945 0.3048)
			(stroke
				(width 0.1)
				(type default)
			)
			(layer "F.Fab")
		)
		(fp_line
			(start 0.120396 0.2794)
			(end -0.12065 0.2794)
			(stroke
				(width 0.1)
				(type default)
			)
			(layer "F.Fab")
		)
		(fp_line
			(start 0.120396 0.3048)
			(end 0.120396 0.2794)
			(stroke
				(width 0.1)
				(type default)
			)
			(layer "F.Fab")
		)
		(fp_line
			(start 0.12065 -0.3048)
			(end 0.67945 -0.3048)
			(stroke
				(width 0.1)
				(type default)
			)
			(layer "F.Fab")
		)
		(fp_line
			(start 0.12065 -0.2794)
			(end 0.12065 -0.3048)
			(stroke
				(width 0.1)
				(type default)
			)
			(layer "F.Fab")
		)
		(fp_line
			(start 0.67945 -0.3048)
			(end 0.67945 0.3048)
			(stroke
				(width 0.1)
				(type default)
			)
			(layer "F.Fab")
		)
		(fp_line
			(start 0.67945 0.3048)
			(end 0.120396 0.3048)
			(stroke
				(width 0.1)
				(type default)
			)
			(layer "F.Fab")
		)
		(pad "1" smd circle
			(at -0.40005 0)
			(size 0 0)
			(layers "F.Cu" "F.Mask" "F.Paste")
			(net "U271_1_ADD2")
		)
		(pad "2" smd circle
			(at 0.40005 0)
			(size 0 0)
			(layers "F.Cu" "F.Mask" "F.Paste")
			(net "GND")
		)
	)
	(footprint ""
		(layer "F.Cu")
		(at 66.0654 -39.487348 90)
		(property "Reference" "R3827"
			(at 0 0 90)
			(layer "F.SilkS")
			(hide yes)
			(effects
				(font
					(size 1.27 1.27)
				)
			)
		)
		(property "Value" ""
			(at 0 0 90)
			(layer "F.Fab")
			(effects
				(font
					(size 1.27 1.27)
				)
			)
		)
		(duplicate_pad_numbers_are_jumpers no)
		(fp_line
			(start 0.7874 -0.4064)
			(end 0.7874 0.4064)
			(stroke
				(width 0.1524)
				(type default)
			)
			(layer "F.SilkS")
		)
		(fp_line
			(start -0.7874 -0.4064)
			(end 0.7874 -0.4064)
			(stroke
				(width 0.1524)
				(type default)
			)
			(layer "F.SilkS")
		)
		(fp_line
			(start 0.7874 0.4064)
			(end -0.7874 0.4064)
			(stroke
				(width 0.1524)
				(type default)
			)
			(layer "F.SilkS")
		)
		(fp_line
			(start -0.7874 0.4064)
			(end -0.7874 -0.4064)
			(stroke
				(width 0.1524)
				(type default)
			)
			(layer "F.SilkS")
		)
		(fp_line
			(start -0.12065 -0.305054)
			(end -0.12065 -0.2794)
			(stroke
				(width 0.1)
				(type default)
			)
			(layer "F.Fab")
		)
		(fp_line
			(start -0.67945 -0.305054)
			(end -0.12065 -0.305054)
			(stroke
				(width 0.1)
				(type default)
			)
			(layer "F.Fab")
		)
		(fp_line
			(start 0.67945 -0.3048)
			(end 0.67945 0.3048)
			(stroke
				(width 0.1)
				(type default)
			)
			(layer "F.Fab")
		)
		(fp_line
			(start 0.12065 -0.3048)
			(end 0.67945 -0.3048)
			(stroke
				(width 0.1)
				(type default)
			)
			(layer "F.Fab")
		)
		(fp_line
			(start 0.12065 -0.2794)
			(end 0.12065 -0.3048)
			(stroke
				(width 0.1)
				(type default)
			)
			(layer "F.Fab")
		)
		(fp_line
			(start -0.12065 -0.2794)
			(end 0.12065 -0.2794)
			(stroke
				(width 0.1)
				(type default)
			)
			(layer "F.Fab")
		)
		(fp_line
			(start 0.120396 0.2794)
			(end -0.12065 0.2794)
			(stroke
				(width 0.1)
				(type default)
			)
			(layer "F.Fab")
		)
		(fp_line
			(start -0.12065 0.2794)
			(end -0.12065 0.3048)
			(stroke
				(width 0.1)
				(type default)
			)
			(layer "F.Fab")
		)
		(fp_line
			(start 0.67945 0.3048)
			(end 0.120396 0.3048)
			(stroke
				(width 0.1)
				(type default)
			)
			(layer "F.Fab")
		)
		(fp_line
			(start 0.120396 0.3048)
			(end 0.120396 0.2794)
			(stroke
				(width 0.1)
				(type default)
			)
			(layer "F.Fab")
		)
		(fp_line
			(start -0.12065 0.3048)
			(end -0.67945 0.3048)
			(stroke
				(width 0.1)
				(type default)
			)
			(layer "F.Fab")
		)
		(fp_line
			(start -0.67945 0.3048)
			(end -0.67945 -0.305054)
			(stroke
				(width 0.1)
				(type default)
			)
			(layer "F.Fab")
		)
		(pad "1" smd circle
			(at -0.40005 0 90)
			(size 0 0)
			(layers "F.Cu" "F.Mask" "F.Paste")
			(net "P12V_OCP_UV_2_R")
		)
		(pad "2" smd circle
			(at 0.40005 0 90)
			(size 0 0)
			(layers "F.Cu" "F.Mask" "F.Paste")
			(net "P12V_OCP_UV_2")
		)
	)
	(footprint ""
		(layer "F.Cu")
		(at 197.523608 -105.497376 180)
		(property "Reference" "R1185"
			(at 0 0 180)
			(layer "F.SilkS")
			(hide yes)
			(effects
				(font
					(size 1.27 1.27)
				)
			)
		)
		(property "Value" ""
			(at 0 0 180)
			(layer "F.Fab")
			(effects
				(font
					(size 1.27 1.27)
				)
			)
		)
		(duplicate_pad_numbers_are_jumpers no)
		(fp_line
			(start 0.7874 0.4064)
			(end -0.7874 0.4064)
			(stroke
				(width 0.1524)
				(type default)
			)
			(layer "F.SilkS")
		)
		(fp_line
			(start 0.7874 -0.4064)
			(end 0.7874 0.4064)
			(stroke
				(width 0.1524)
				(type default)
			)
			(layer "F.SilkS")
		)
		(fp_line
			(start -0.7874 0.4064)
			(end -0.7874 -0.4064)
			(stroke
				(width 0.1524)
				(type default)
			)
			(layer "F.SilkS")
		)
		(fp_line
			(start -0.7874 -0.4064)
			(end 0.7874 -0.4064)
			(stroke
				(width 0.1524)
				(type default)
			)
			(layer "F.SilkS")
		)
		(fp_line
			(start 0.67945 0.3048)
			(end 0.120396 0.3048)
			(stroke
				(width 0.1)
				(type default)
			)
			(layer "F.Fab")
		)
		(fp_line
			(start 0.67945 -0.3048)
			(end 0.67945 0.3048)
			(stroke
				(width 0.1)
				(type default)
			)
			(layer "F.Fab")
		)
		(fp_line
			(start 0.12065 -0.2794)
			(end 0.12065 -0.3048)
			(stroke
				(width 0.1)
				(type default)
			)
			(layer "F.Fab")
		)
		(fp_line
			(start 0.12065 -0.3048)
			(end 0.67945 -0.3048)
			(stroke
				(width 0.1)
				(type default)
			)
			(layer "F.Fab")
		)
		(fp_line
			(start 0.120396 0.3048)
			(end 0.120396 0.2794)
			(stroke
				(width 0.1)
				(type default)
			)
			(layer "F.Fab")
		)
		(fp_line
			(start 0.120396 0.2794)
			(end -0.12065 0.2794)
			(stroke
				(width 0.1)
				(type default)
			)
			(layer "F.Fab")
		)
		(fp_line
			(start -0.12065 0.3048)
			(end -0.67945 0.3048)
			(stroke
				(width 0.1)
				(type default)
			)
			(layer "F.Fab")
		)
		(fp_line
			(start -0.12065 0.2794)
			(end -0.12065 0.3048)
			(stroke
				(width 0.1)
				(type default)
			)
			(layer "F.Fab")
		)
		(fp_line
			(start -0.12065 -0.2794)
			(end 0.12065 -0.2794)
			(stroke
				(width 0.1)
				(type default)
			)
			(layer "F.Fab")
		)
		(fp_line
			(start -0.12065 -0.305054)
			(end -0.12065 -0.2794)
			(stroke
				(width 0.1)
				(type default)
			)
			(layer "F.Fab")
		)
		(fp_line
			(start -0.67945 0.3048)
			(end -0.67945 -0.305054)
			(stroke
				(width 0.1)
				(type default)
			)
			(layer "F.Fab")
		)
		(fp_line
			(start -0.67945 -0.305054)
			(end -0.12065 -0.305054)
			(stroke
				(width 0.1)
				(type default)
			)
			(layer "F.Fab")
		)
		(pad "1" smd circle
			(at -0.40005 0 180)
			(size 0 0)
			(layers "F.Cu" "F.Mask" "F.Paste")
			(net "PVDDCR_CPU0_P0_PMALERT")
		)
		(pad "2" smd circle
			(at 0.40005 0 180)
			(size 0 0)
			(layers "F.Cu" "F.Mask" "F.Paste")
			(net "P3V3_AUX")
		)
	)
	(footprint ""
		(layer "F.Cu")
		(at 187.280296 -133.477762 -90)
		(property "Reference" "R6792"
			(at 0 0 270)
			(layer "F.SilkS")
			(hide yes)
			(effects
				(font
					(size 1.27 1.27)
				)
			)
		)
		(property "Value" ""
			(at 0 0 270)
			(layer "F.Fab")
			(effects
				(font
					(size 1.27 1.27)
				)
			)
		)
		(duplicate_pad_numbers_are_jumpers no)
		(fp_line
			(start -0.7874 0.4064)
			(end -0.7874 -0.4064)
			(stroke
				(width 0.1524)
				(type default)
			)
			(layer "F.SilkS")
		)
		(fp_line
			(start 0.7874 0.4064)
			(end -0.7874 0.4064)
			(stroke
				(width 0.1524)
				(type default)
			)
			(layer "F.SilkS")
		)
		(fp_line
			(start -0.7874 -0.4064)
			(end 0.7874 -0.4064)
			(stroke
				(width 0.1524)
				(type default)
			)
			(layer "F.SilkS")
		)
		(fp_line
			(start 0.7874 -0.4064)
			(end 0.7874 0.4064)
			(stroke
				(width 0.1524)
				(type default)
			)
			(layer "F.SilkS")
		)
		(fp_line
			(start -0.67945 0.3048)
			(end -0.67945 -0.305054)
			(stroke
				(width 0.1)
				(type default)
			)
			(layer "F.Fab")
		)
		(fp_line
			(start -0.12065 0.3048)
			(end -0.67945 0.3048)
			(stroke
				(width 0.1)
				(type default)
			)
			(layer "F.Fab")
		)
		(fp_line
			(start 0.120396 0.3048)
			(end 0.120396 0.2794)
			(stroke
				(width 0.1)
				(type default)
			)
			(layer "F.Fab")
		)
		(fp_line
			(start 0.67945 0.3048)
			(end 0.120396 0.3048)
			(stroke
				(width 0.1)
				(type default)
			)
			(layer "F.Fab")
		)
		(fp_line
			(start -0.12065 0.2794)
			(end -0.12065 0.3048)
			(stroke
				(width 0.1)
				(type default)
			)
			(layer "F.Fab")
		)
		(fp_line
			(start 0.120396 0.2794)
			(end -0.12065 0.2794)
			(stroke
				(width 0.1)
				(type default)
			)
			(layer "F.Fab")
		)
		(fp_line
			(start -0.12065 -0.2794)
			(end 0.12065 -0.2794)
			(stroke
				(width 0.1)
				(type default)
			)
			(layer "F.Fab")
		)
		(fp_line
			(start 0.12065 -0.2794)
			(end 0.12065 -0.3048)
			(stroke
				(width 0.1)
				(type default)
			)
			(layer "F.Fab")
		)
		(fp_line
			(start 0.12065 -0.3048)
			(end 0.67945 -0.3048)
			(stroke
				(width 0.1)
				(type default)
			)
			(layer "F.Fab")
		)
		(fp_line
			(start 0.67945 -0.3048)
			(end 0.67945 0.3048)
			(stroke
				(width 0.1)
				(type default)
			)
			(layer "F.Fab")
		)
		(fp_line
			(start -0.67945 -0.305054)
			(end -0.12065 -0.305054)
			(stroke
				(width 0.1)
				(type default)
			)
			(layer "F.Fab")
		)
		(fp_line
			(start -0.12065 -0.305054)
			(end -0.12065 -0.2794)
			(stroke
				(width 0.1)
				(type default)
			)
			(layer "F.Fab")
		)
		(pad "1" smd circle
			(at -0.40005 0 270)
			(size 0 0)
			(layers "F.Cu" "F.Mask" "F.Paste")
			(net "RST_RT_CPU1_P2_PERST_R_N")
		)
		(pad "2" smd circle
			(at 0.40005 0 270)
			(size 0 0)
			(layers "F.Cu" "F.Mask" "F.Paste")
			(net "RST_RT_CPU1_P2_PERST_R2_N")
		)
	)
	(footprint ""
		(layer "F.Cu")
		(at 346.987876 -70.098412 90)
		(property "Reference" "D85"
			(at -3.934714 -0.691642 90)
			(unlocked yes)
			(layer "F.SilkS")
			(effects
				(font
					(size 0.7874 0.5842)
					(thickness 0.1524)
				)
				(justify left)
			)
		)
		(property "Value" ""
			(at 0 0 90)
			(layer "F.Fab")
			(effects
				(font
					(size 1.27 1.27)
				)
			)
		)
		(duplicate_pad_numbers_are_jumpers no)
		(fp_line
			(start 1.16078 -0.4826)
			(end 1.16078 0.4826)
			(stroke
				(width 0.1524)
				(type default)
			)
			(layer "F.SilkS")
		)
		(fp_line
			(start 1.03378 -0.4826)
			(end 1.03378 0.4826)
			(stroke
				(width 0.1524)
				(type default)
			)
			(layer "F.SilkS")
		)
		(fp_line
			(start 0.90678 -0.4826)
			(end 0.90678 0.4826)
			(stroke
				(width 0.1524)
				(type default)
			)
			(layer "F.SilkS")
		)
		(fp_line
			(start -0.64008 -0.4826)
			(end 1.16078 -0.4826)
			(stroke
				(width 0.1524)
				(type default)
			)
			(layer "F.SilkS")
		)
		(fp_line
			(start -0.79248 -0.4826)
			(end 1.03378 -0.4826)
			(stroke
				(width 0.1524)
				(type default)
			)
			(layer "F.SilkS")
		)
		(fp_line
			(start -0.89408 -0.4826)
			(end 0.90678 -0.4826)
			(stroke
				(width 0.1524)
				(type default)
			)
			(layer "F.SilkS")
		)
		(fp_line
			(start 1.16078 0.4826)
			(end -0.64008 0.4826)
			(stroke
				(width 0.1524)
				(type default)
			)
			(layer "F.SilkS")
		)
		(fp_line
			(start 1.03378 0.4826)
			(end -0.79248 0.4826)
			(stroke
				(width 0.1524)
				(type default)
			)
			(layer "F.SilkS")
		)
		(fp_line
			(start 0.90678 0.4826)
			(end -0.90678 0.4826)
			(stroke
				(width 0.1524)
				(type default)
			)
			(layer "F.SilkS")
		)
		(fp_line
			(start -0.90678 0.4826)
			(end -0.90678 -0.4699)
			(stroke
				(width 0.1524)
				(type default)
			)
			(layer "F.SilkS")
		)
		(fp_line
			(start 0.499872 -0.249936)
			(end 0.499872 0.249936)
			(stroke
				(width 0.1)
				(type default)
			)
			(layer "F.Fab")
		)
		(fp_line
			(start -0.499872 -0.249936)
			(end 0.499872 -0.249936)
			(stroke
				(width 0.1)
				(type default)
			)
			(layer "F.Fab")
		)
		(fp_line
			(start 0.499872 0.249936)
			(end -0.499872 0.249936)
			(stroke
				(width 0.1)
				(type default)
			)
			(layer "F.Fab")
		)
		(fp_line
			(start -0.499872 0.249936)
			(end -0.499872 -0.249936)
			(stroke
				(width 0.1)
				(type default)
			)
			(layer "F.Fab")
		)
		(pad "A" smd rect
			(at -0.47498 0 90)
			(size 0.6096 0.7112)
			(layers "F.Cu" "F.Mask" "F.Paste")
			(net "LED_PWRGD_PVDD18_S5_P1_R")
		)
		(pad "C" smd rect
			(at 0.47498 0 90)
			(size 0.6096 0.7112)
			(layers "F.Cu" "F.Mask" "F.Paste")
			(net "LED_PWRGD_PVDD18_S5_P1_D")
		)
	)
	(footprint ""
		(layer "F.Cu")
		(at 108.355892 -259.845302)
		(property "Reference" "C2127"
			(at 0 0 0)
			(layer "F.SilkS")
			(hide yes)
			(effects
				(font
					(size 1.27 1.27)
				)
			)
		)
		(property "Value" ""
			(at 0 0 0)
			(layer "F.Fab")
			(effects
				(font
					(size 1.27 1.27)
				)
			)
		)
		(duplicate_pad_numbers_are_jumpers no)
		(fp_line
			(start -0.7874 -0.4064)
			(end 0.7874 -0.4064)
			(stroke
				(width 0.1524)
				(type default)
			)
			(layer "F.SilkS")
		)
		(fp_line
			(start -0.7874 0.4064)
			(end -0.7874 -0.4064)
			(stroke
				(width 0.1524)
				(type default)
			)
			(layer "F.SilkS")
		)
		(fp_line
			(start 0.7874 -0.4064)
			(end 0.7874 0.4064)
			(stroke
				(width 0.1524)
				(type default)
			)
			(layer "F.SilkS")
		)
		(fp_line
			(start 0.7874 0.4064)
			(end -0.7874 0.4064)
			(stroke
				(width 0.1524)
				(type default)
			)
			(layer "F.SilkS")
		)
		(fp_line
			(start -0.67945 -0.305054)
			(end -0.12065 -0.305054)
			(stroke
				(width 0.1)
				(type default)
			)
			(layer "F.Fab")
		)
		(fp_line
			(start -0.67945 0.3048)
			(end -0.67945 -0.305054)
			(stroke
				(width 0.1)
				(type default)
			)
			(layer "F.Fab")
		)
		(fp_line
			(start -0.12065 -0.305054)
			(end -0.12065 -0.2794)
			(stroke
				(width 0.1)
				(type default)
			)
			(layer "F.Fab")
		)
		(fp_line
			(start -0.12065 -0.2794)
			(end 0.12065 -0.2794)
			(stroke
				(width 0.1)
				(type default)
			)
			(layer "F.Fab")
		)
		(fp_line
			(start -0.12065 0.2794)
			(end -0.12065 0.3048)
			(stroke
				(width 0.1)
				(type default)
			)
			(layer "F.Fab")
		)
		(fp_line
			(start -0.12065 0.3048)
			(end -0.67945 0.3048)
			(stroke
				(width 0.1)
				(type default)
			)
			(layer "F.Fab")
		)
		(fp_line
			(start 0.120396 0.2794)
			(end -0.12065 0.2794)
			(stroke
				(width 0.1)
				(type default)
			)
			(layer "F.Fab")
		)
		(fp_line
			(start 0.120396 0.3048)
			(end 0.120396 0.2794)
			(stroke
				(width 0.1)
				(type default)
			)
			(layer "F.Fab")
		)
		(fp_line
			(start 0.12065 -0.3048)
			(end 0.67945 -0.3048)
			(stroke
				(width 0.1)
				(type default)
			)
			(layer "F.Fab")
		)
		(fp_line
			(start 0.12065 -0.2794)
			(end 0.12065 -0.3048)
			(stroke
				(width 0.1)
				(type default)
			)
			(layer "F.Fab")
		)
		(fp_line
			(start 0.67945 -0.3048)
			(end 0.67945 0.3048)
			(stroke
				(width 0.1)
				(type default)
			)
			(layer "F.Fab")
		)
		(fp_line
			(start 0.67945 0.3048)
			(end 0.120396 0.3048)
			(stroke
				(width 0.1)
				(type default)
			)
			(layer "F.Fab")
		)
		(pad "1" smd circle
			(at -0.40005 0)
			(size 0 0)
			(layers "F.Cu" "F.Mask" "F.Paste")
			(net "PVDDIO_P1")
		)
		(pad "2" smd circle
			(at 0.40005 0)
			(size 0 0)
			(layers "F.Cu" "F.Mask" "F.Paste")
			(net "GND")
		)
	)
	(footprint ""
		(layer "F.Cu")
		(at 223.378522 -74.510138 180)
		(property "Reference" "PC2213"
			(at 0 0 180)
			(layer "F.SilkS")
			(hide yes)
			(effects
				(font
					(size 1.27 1.27)
				)
			)
		)
		(property "Value" ""
			(at 0 0 180)
			(layer "F.Fab")
			(effects
				(font
					(size 1.27 1.27)
				)
			)
		)
		(duplicate_pad_numbers_are_jumpers no)
		(fp_line
			(start 0.7874 0.4064)
			(end -0.7874 0.4064)
			(stroke
				(width 0.1524)
				(type default)
			)
			(layer "F.SilkS")
		)
		(fp_line
			(start 0.7874 -0.4064)
			(end 0.7874 0.4064)
			(stroke
				(width 0.1524)
				(type default)
			)
			(layer "F.SilkS")
		)
		(fp_line
			(start -0.7874 0.4064)
			(end -0.7874 -0.4064)
			(stroke
				(width 0.1524)
				(type default)
			)
			(layer "F.SilkS")
		)
		(fp_line
			(start -0.7874 -0.4064)
			(end 0.7874 -0.4064)
			(stroke
				(width 0.1524)
				(type default)
			)
			(layer "F.SilkS")
		)
		(fp_line
			(start 0.67945 0.3048)
			(end 0.120396 0.3048)
			(stroke
				(width 0.1)
				(type default)
			)
			(layer "F.Fab")
		)
		(fp_line
			(start 0.67945 -0.3048)
			(end 0.67945 0.3048)
			(stroke
				(width 0.1)
				(type default)
			)
			(layer "F.Fab")
		)
		(fp_line
			(start 0.12065 -0.2794)
			(end 0.12065 -0.3048)
			(stroke
				(width 0.1)
				(type default)
			)
			(layer "F.Fab")
		)
		(fp_line
			(start 0.12065 -0.3048)
			(end 0.67945 -0.3048)
			(stroke
				(width 0.1)
				(type default)
			)
			(layer "F.Fab")
		)
		(fp_line
			(start 0.120396 0.3048)
			(end 0.120396 0.2794)
			(stroke
				(width 0.1)
				(type default)
			)
			(layer "F.Fab")
		)
		(fp_line
			(start 0.120396 0.2794)
			(end -0.12065 0.2794)
			(stroke
				(width 0.1)
				(type default)
			)
			(layer "F.Fab")
		)
		(fp_line
			(start -0.12065 0.3048)
			(end -0.67945 0.3048)
			(stroke
				(width 0.1)
				(type default)
			)
			(layer "F.Fab")
		)
		(fp_line
			(start -0.12065 0.2794)
			(end -0.12065 0.3048)
			(stroke
				(width 0.1)
				(type default)
			)
			(layer "F.Fab")
		)
		(fp_line
			(start -0.12065 -0.2794)
			(end 0.12065 -0.2794)
			(stroke
				(width 0.1)
				(type default)
			)
			(layer "F.Fab")
		)
		(fp_line
			(start -0.12065 -0.305054)
			(end -0.12065 -0.2794)
			(stroke
				(width 0.1)
				(type default)
			)
			(layer "F.Fab")
		)
		(fp_line
			(start -0.67945 0.3048)
			(end -0.67945 -0.305054)
			(stroke
				(width 0.1)
				(type default)
			)
			(layer "F.Fab")
		)
		(fp_line
			(start -0.67945 -0.305054)
			(end -0.12065 -0.305054)
			(stroke
				(width 0.1)
				(type default)
			)
			(layer "F.Fab")
		)
		(pad "1" smd circle
			(at -0.40005 0 180)
			(size 0 0)
			(layers "F.Cu" "F.Mask" "F.Paste")
			(net "P3V3_E1S_0_R")
		)
		(pad "2" smd circle
			(at 0.40005 0 180)
			(size 0 0)
			(layers "F.Cu" "F.Mask" "F.Paste")
			(net "P3V3_E1S_GATE_0")
		)
	)
	(footprint ""
		(layer "F.Cu")
		(at 22.479 -357.632 180)
		(property "Reference" "PR217"
			(at 0 0 180)
			(layer "F.SilkS")
			(hide yes)
			(effects
				(font
					(size 1.27 1.27)
				)
			)
		)
		(property "Value" ""
			(at 0 0 180)
			(layer "F.Fab")
			(effects
				(font
					(size 1.27 1.27)
				)
			)
		)
		(duplicate_pad_numbers_are_jumpers no)
		(fp_line
			(start 0.7874 0.4064)
			(end -0.7874 0.4064)
			(stroke
				(width 0.1524)
				(type default)
			)
			(layer "F.SilkS")
		)
		(fp_line
			(start 0.7874 -0.4064)
			(end 0.7874 0.4064)
			(stroke
				(width 0.1524)
				(type default)
			)
			(layer "F.SilkS")
		)
		(fp_line
			(start -0.7874 0.4064)
			(end -0.7874 -0.4064)
			(stroke
				(width 0.1524)
				(type default)
			)
			(layer "F.SilkS")
		)
		(fp_line
			(start -0.7874 -0.4064)
			(end 0.7874 -0.4064)
			(stroke
				(width 0.1524)
				(type default)
			)
			(layer "F.SilkS")
		)
		(fp_line
			(start 0.67945 0.3048)
			(end 0.120396 0.3048)
			(stroke
				(width 0.1)
				(type default)
			)
			(layer "F.Fab")
		)
		(fp_line
			(start 0.67945 -0.3048)
			(end 0.67945 0.3048)
			(stroke
				(width 0.1)
				(type default)
			)
			(layer "F.Fab")
		)
		(fp_line
			(start 0.12065 -0.2794)
			(end 0.12065 -0.3048)
			(stroke
				(width 0.1)
				(type default)
			)
			(layer "F.Fab")
		)
		(fp_line
			(start 0.12065 -0.3048)
			(end 0.67945 -0.3048)
			(stroke
				(width 0.1)
				(type default)
			)
			(layer "F.Fab")
		)
		(fp_line
			(start 0.120396 0.3048)
			(end 0.120396 0.2794)
			(stroke
				(width 0.1)
				(type default)
			)
			(layer "F.Fab")
		)
		(fp_line
			(start 0.120396 0.2794)
			(end -0.12065 0.2794)
			(stroke
				(width 0.1)
				(type default)
			)
			(layer "F.Fab")
		)
		(fp_line
			(start -0.12065 0.3048)
			(end -0.67945 0.3048)
			(stroke
				(width 0.1)
				(type default)
			)
			(layer "F.Fab")
		)
		(fp_line
			(start -0.12065 0.2794)
			(end -0.12065 0.3048)
			(stroke
				(width 0.1)
				(type default)
			)
			(layer "F.Fab")
		)
		(fp_line
			(start -0.12065 -0.2794)
			(end 0.12065 -0.2794)
			(stroke
				(width 0.1)
				(type default)
			)
			(layer "F.Fab")
		)
		(fp_line
			(start -0.12065 -0.305054)
			(end -0.12065 -0.2794)
			(stroke
				(width 0.1)
				(type default)
			)
			(layer "F.Fab")
		)
		(fp_line
			(start -0.67945 0.3048)
			(end -0.67945 -0.305054)
			(stroke
				(width 0.1)
				(type default)
			)
			(layer "F.Fab")
		)
		(fp_line
			(start -0.67945 -0.305054)
			(end -0.12065 -0.305054)
			(stroke
				(width 0.1)
				(type default)
			)
			(layer "F.Fab")
		)
		(pad "1" smd circle
			(at -0.40005 0 180)
			(size 0 0)
			(layers "F.Cu" "F.Mask" "F.Paste")
			(net "SVID_PVDDCR_CPU1_P1_SVTI")
		)
		(pad "2" smd circle
			(at 0.40005 0 180)
			(size 0 0)
			(layers "F.Cu" "F.Mask" "F.Paste")
			(net "GND")
		)
	)
	(footprint ""
		(layer "F.Cu")
		(at 273.35734 -123.896628 180)
		(property "Reference" "R4270"
			(at 0 0 180)
			(layer "F.SilkS")
			(hide yes)
			(effects
				(font
					(size 1.27 1.27)
				)
			)
		)
		(property "Value" ""
			(at 0 0 180)
			(layer "F.Fab")
			(effects
				(font
					(size 1.27 1.27)
				)
			)
		)
		(duplicate_pad_numbers_are_jumpers no)
		(fp_line
			(start 0.7874 0.4064)
			(end -0.7874 0.4064)
			(stroke
				(width 0.1524)
				(type default)
			)
			(layer "F.SilkS")
		)
		(fp_line
			(start 0.7874 -0.4064)
			(end 0.7874 0.4064)
			(stroke
				(width 0.1524)
				(type default)
			)
			(layer "F.SilkS")
		)
		(fp_line
			(start -0.7874 0.4064)
			(end -0.7874 -0.4064)
			(stroke
				(width 0.1524)
				(type default)
			)
			(layer "F.SilkS")
		)
		(fp_line
			(start -0.7874 -0.4064)
			(end 0.7874 -0.4064)
			(stroke
				(width 0.1524)
				(type default)
			)
			(layer "F.SilkS")
		)
		(fp_line
			(start 0.67945 0.3048)
			(end 0.120396 0.3048)
			(stroke
				(width 0.1)
				(type default)
			)
			(layer "F.Fab")
		)
		(fp_line
			(start 0.67945 -0.3048)
			(end 0.67945 0.3048)
			(stroke
				(width 0.1)
				(type default)
			)
			(layer "F.Fab")
		)
		(fp_line
			(start 0.12065 -0.2794)
			(end 0.12065 -0.3048)
			(stroke
				(width 0.1)
				(type default)
			)
			(layer "F.Fab")
		)
		(fp_line
			(start 0.12065 -0.3048)
			(end 0.67945 -0.3048)
			(stroke
				(width 0.1)
				(type default)
			)
			(layer "F.Fab")
		)
		(fp_line
			(start 0.120396 0.3048)
			(end 0.120396 0.2794)
			(stroke
				(width 0.1)
				(type default)
			)
			(layer "F.Fab")
		)
		(fp_line
			(start 0.120396 0.2794)
			(end -0.12065 0.2794)
			(stroke
				(width 0.1)
				(type default)
			)
			(layer "F.Fab")
		)
		(fp_line
			(start -0.12065 0.3048)
			(end -0.67945 0.3048)
			(stroke
				(width 0.1)
				(type default)
			)
			(layer "F.Fab")
		)
		(fp_line
			(start -0.12065 0.2794)
			(end -0.12065 0.3048)
			(stroke
				(width 0.1)
				(type default)
			)
			(layer "F.Fab")
		)
		(fp_line
			(start -0.12065 -0.2794)
			(end 0.12065 -0.2794)
			(stroke
				(width 0.1)
				(type default)
			)
			(layer "F.Fab")
		)
		(fp_line
			(start -0.12065 -0.305054)
			(end -0.12065 -0.2794)
			(stroke
				(width 0.1)
				(type default)
			)
			(layer "F.Fab")
		)
		(fp_line
			(start -0.67945 0.3048)
			(end -0.67945 -0.305054)
			(stroke
				(width 0.1)
				(type default)
			)
			(layer "F.Fab")
		)
		(fp_line
			(start -0.67945 -0.305054)
			(end -0.12065 -0.305054)
			(stroke
				(width 0.1)
				(type default)
			)
			(layer "F.Fab")
		)
		(pad "1" smd circle
			(at -0.40005 0 180)
			(size 0 0)
			(layers "F.Cu" "F.Mask" "F.Paste")
			(net "P3V3_AUX")
		)
		(pad "2" smd circle
			(at 0.40005 0 180)
			(size 0 0)
			(layers "F.Cu" "F.Mask" "F.Paste")
			(net "SMB_VR_SENSOR_3V3AUX_SDA")
		)
	)
	(footprint ""
		(layer "F.Cu")
		(at 445.19088 -97.269808 180)
		(property "Reference" "R3600"
			(at 0 0 180)
			(layer "F.SilkS")
			(hide yes)
			(effects
				(font
					(size 1.27 1.27)
				)
			)
		)
		(property "Value" ""
			(at 0 0 180)
			(layer "F.Fab")
			(effects
				(font
					(size 1.27 1.27)
				)
			)
		)
		(duplicate_pad_numbers_are_jumpers no)
		(fp_line
			(start 0.7874 0.4064)
			(end -0.7874 0.4064)
			(stroke
				(width 0.1524)
				(type default)
			)
			(layer "F.SilkS")
		)
		(fp_line
			(start 0.7874 -0.4064)
			(end 0.7874 0.4064)
			(stroke
				(width 0.1524)
				(type default)
			)
			(layer "F.SilkS")
		)
		(fp_line
			(start -0.7874 0.4064)
			(end -0.7874 -0.4064)
			(stroke
				(width 0.1524)
				(type default)
			)
			(layer "F.SilkS")
		)
		(fp_line
			(start -0.7874 -0.4064)
			(end 0.7874 -0.4064)
			(stroke
				(width 0.1524)
				(type default)
			)
			(layer "F.SilkS")
		)
		(fp_line
			(start 0.67945 0.3048)
			(end 0.120396 0.3048)
			(stroke
				(width 0.1)
				(type default)
			)
			(layer "F.Fab")
		)
		(fp_line
			(start 0.67945 -0.3048)
			(end 0.67945 0.3048)
			(stroke
				(width 0.1)
				(type default)
			)
			(layer "F.Fab")
		)
		(fp_line
			(start 0.12065 -0.2794)
			(end 0.12065 -0.3048)
			(stroke
				(width 0.1)
				(type default)
			)
			(layer "F.Fab")
		)
		(fp_line
			(start 0.12065 -0.3048)
			(end 0.67945 -0.3048)
			(stroke
				(width 0.1)
				(type default)
			)
			(layer "F.Fab")
		)
		(fp_line
			(start 0.120396 0.3048)
			(end 0.120396 0.2794)
			(stroke
				(width 0.1)
				(type default)
			)
			(layer "F.Fab")
		)
		(fp_line
			(start 0.120396 0.2794)
			(end -0.12065 0.2794)
			(stroke
				(width 0.1)
				(type default)
			)
			(layer "F.Fab")
		)
		(fp_line
			(start -0.12065 0.3048)
			(end -0.67945 0.3048)
			(stroke
				(width 0.1)
				(type default)
			)
			(layer "F.Fab")
		)
		(fp_line
			(start -0.12065 0.2794)
			(end -0.12065 0.3048)
			(stroke
				(width 0.1)
				(type default)
			)
			(layer "F.Fab")
		)
		(fp_line
			(start -0.12065 -0.2794)
			(end 0.12065 -0.2794)
			(stroke
				(width 0.1)
				(type default)
			)
			(layer "F.Fab")
		)
		(fp_line
			(start -0.12065 -0.305054)
			(end -0.12065 -0.2794)
			(stroke
				(width 0.1)
				(type default)
			)
			(layer "F.Fab")
		)
		(fp_line
			(start -0.67945 0.3048)
			(end -0.67945 -0.305054)
			(stroke
				(width 0.1)
				(type default)
			)
			(layer "F.Fab")
		)
		(fp_line
			(start -0.67945 -0.305054)
			(end -0.12065 -0.305054)
			(stroke
				(width 0.1)
				(type default)
			)
			(layer "F.Fab")
		)
		(pad "1" smd circle
			(at -0.40005 0 180)
			(size 0 0)
			(layers "F.Cu" "F.Mask" "F.Paste")
			(net "SMB_INA230_1_3V3AUX_SCL_R")
		)
		(pad "2" smd circle
			(at 0.40005 0 180)
			(size 0 0)
			(layers "F.Cu" "F.Mask" "F.Paste")
			(net "SMB_INA230_1_3V3AUX_SCL_R1")
		)
	)
	(footprint ""
		(layer "F.Cu")
		(at 358.268524 -385.364228)
		(property "Reference" "C937"
			(at 0 0 0)
			(layer "F.SilkS")
			(hide yes)
			(effects
				(font
					(size 1.27 1.27)
				)
			)
		)
		(property "Value" ""
			(at 0 0 0)
			(layer "F.Fab")
			(effects
				(font
					(size 1.27 1.27)
				)
			)
		)
		(duplicate_pad_numbers_are_jumpers no)
		(fp_line
			(start -0.299974 -0.150114)
			(end 0.299974 -0.150114)
			(stroke
				(width 0.1)
				(type default)
			)
			(layer "F.Fab")
		)
		(fp_line
			(start -0.299974 0.150114)
			(end -0.299974 -0.150114)
			(stroke
				(width 0.1)
				(type default)
			)
			(layer "F.Fab")
		)
		(fp_line
			(start 0.299974 -0.150114)
			(end 0.299974 0.150114)
			(stroke
				(width 0.1)
				(type default)
			)
			(layer "F.Fab")
		)
		(fp_line
			(start 0.299974 0.150114)
			(end -0.299974 0.150114)
			(stroke
				(width 0.1)
				(type default)
			)
			(layer "F.Fab")
		)
		(pad "1" smd rect
			(at -0.2667 0)
			(size 0.3048 0.381)
			(layers "F.Cu" "F.Mask" "F.Paste")
			(net "P5E_CPU0_P1_TX_C_DP<14>")
		)
		(pad "2" smd rect
			(at 0.2667 0)
			(size 0.3048 0.381)
			(layers "F.Cu" "F.Mask" "F.Paste")
			(net "P5E_CPU0_P1_TX_DP<14>")
		)
	)
	(footprint ""
		(layer "F.Cu")
		(at 172.54347 -415.503868 180)
		(property "Reference" "C9001"
			(at 0 0 180)
			(layer "F.SilkS")
			(hide yes)
			(effects
				(font
					(size 1.27 1.27)
				)
			)
		)
		(property "Value" ""
			(at 0 0 180)
			(layer "F.Fab")
			(effects
				(font
					(size 1.27 1.27)
				)
			)
		)
		(duplicate_pad_numbers_are_jumpers no)
		(fp_line
			(start 0.7874 0.4064)
			(end -0.7874 0.4064)
			(stroke
				(width 0.1524)
				(type default)
			)
			(layer "F.SilkS")
		)
		(fp_line
			(start 0.7874 -0.4064)
			(end 0.7874 0.4064)
			(stroke
				(width 0.1524)
				(type default)
			)
			(layer "F.SilkS")
		)
		(fp_line
			(start -0.7874 0.4064)
			(end -0.7874 -0.4064)
			(stroke
				(width 0.1524)
				(type default)
			)
			(layer "F.SilkS")
		)
		(fp_line
			(start -0.7874 -0.4064)
			(end 0.7874 -0.4064)
			(stroke
				(width 0.1524)
				(type default)
			)
			(layer "F.SilkS")
		)
		(fp_line
			(start 0.67945 0.3048)
			(end 0.120396 0.3048)
			(stroke
				(width 0.1)
				(type default)
			)
			(layer "F.Fab")
		)
		(fp_line
			(start 0.67945 -0.3048)
			(end 0.67945 0.3048)
			(stroke
				(width 0.1)
				(type default)
			)
			(layer "F.Fab")
		)
		(fp_line
			(start 0.12065 -0.2794)
			(end 0.12065 -0.3048)
			(stroke
				(width 0.1)
				(type default)
			)
			(layer "F.Fab")
		)
		(fp_line
			(start 0.12065 -0.3048)
			(end 0.67945 -0.3048)
			(stroke
				(width 0.1)
				(type default)
			)
			(layer "F.Fab")
		)
		(fp_line
			(start 0.120396 0.3048)
			(end 0.120396 0.2794)
			(stroke
				(width 0.1)
				(type default)
			)
			(layer "F.Fab")
		)
		(fp_line
			(start 0.120396 0.2794)
			(end -0.12065 0.2794)
			(stroke
				(width 0.1)
				(type default)
			)
			(layer "F.Fab")
		)
		(fp_line
			(start -0.12065 0.3048)
			(end -0.67945 0.3048)
			(stroke
				(width 0.1)
				(type default)
			)
			(layer "F.Fab")
		)
		(fp_line
			(start -0.12065 0.2794)
			(end -0.12065 0.3048)
			(stroke
				(width 0.1)
				(type default)
			)
			(layer "F.Fab")
		)
		(fp_line
			(start -0.12065 -0.2794)
			(end 0.12065 -0.2794)
			(stroke
				(width 0.1)
				(type default)
			)
			(layer "F.Fab")
		)
		(fp_line
			(start -0.12065 -0.305054)
			(end -0.12065 -0.2794)
			(stroke
				(width 0.1)
				(type default)
			)
			(layer "F.Fab")
		)
		(fp_line
			(start -0.67945 0.3048)
			(end -0.67945 -0.305054)
			(stroke
				(width 0.1)
				(type default)
			)
			(layer "F.Fab")
		)
		(fp_line
			(start -0.67945 -0.305054)
			(end -0.12065 -0.305054)
			(stroke
				(width 0.1)
				(type default)
			)
			(layer "F.Fab")
		)
		(pad "1" smd circle
			(at -0.40005 0 180)
			(size 0 0)
			(layers "F.Cu" "F.Mask" "F.Paste")
			(net "PRSNT_CABLE_SWB_B2_ISO_N")
		)
		(pad "2" smd circle
			(at 0.40005 0 180)
			(size 0 0)
			(layers "F.Cu" "F.Mask" "F.Paste")
			(net "GND")
		)
	)
	(footprint ""
		(layer "F.Cu")
		(at 334.028288 -403.818852 -90)
		(property "Reference" "R1039"
			(at 0 0 270)
			(layer "F.SilkS")
			(hide yes)
			(effects
				(font
					(size 1.27 1.27)
				)
			)
		)
		(property "Value" ""
			(at 0 0 270)
			(layer "F.Fab")
			(effects
				(font
					(size 1.27 1.27)
				)
			)
		)
		(duplicate_pad_numbers_are_jumpers no)
		(fp_line
			(start -0.32512 0.175006)
			(end -0.32512 -0.175006)
			(stroke
				(width 0.1)
				(type default)
			)
			(layer "F.Fab")
		)
		(fp_line
			(start 0.32512 0.175006)
			(end -0.32512 0.175006)
			(stroke
				(width 0.1)
				(type default)
			)
			(layer "F.Fab")
		)
		(fp_line
			(start -0.32512 -0.175006)
			(end 0.32512 -0.175006)
			(stroke
				(width 0.1)
				(type default)
			)
			(layer "F.Fab")
		)
		(fp_line
			(start 0.32512 -0.175006)
			(end 0.32512 0.175006)
			(stroke
				(width 0.1)
				(type default)
			)
			(layer "F.Fab")
		)
		(pad "1" smd rect
			(at -0.2667 0 270)
			(size 0.3048 0.381)
			(layers "F.Cu" "F.Mask" "F.Paste")
			(net "P1V8_CPU0_RT_1D")
		)
		(pad "2" smd rect
			(at 0.2667 0 90)
			(size 0.3048 0.381)
			(layers "F.Cu" "F.Mask" "F.Paste")
			(net "MODE_RT_CPU0_P1")
		)
	)
	(footprint ""
		(layer "F.Cu")
		(at 24.765 -363.347 180)
		(property "Reference" "PC363"
			(at 0 0 180)
			(layer "F.SilkS")
			(hide yes)
			(effects
				(font
					(size 1.27 1.27)
				)
			)
		)
		(property "Value" ""
			(at 0 0 180)
			(layer "F.Fab")
			(effects
				(font
					(size 1.27 1.27)
				)
			)
		)
		(duplicate_pad_numbers_are_jumpers no)
		(fp_line
			(start 0.7874 0.4064)
			(end -0.7874 0.4064)
			(stroke
				(width 0.1524)
				(type default)
			)
			(layer "F.SilkS")
		)
		(fp_line
			(start 0.7874 -0.4064)
			(end 0.7874 0.4064)
			(stroke
				(width 0.1524)
				(type default)
			)
			(layer "F.SilkS")
		)
		(fp_line
			(start -0.7874 0.4064)
			(end -0.7874 -0.4064)
			(stroke
				(width 0.1524)
				(type default)
			)
			(layer "F.SilkS")
		)
		(fp_line
			(start -0.7874 -0.4064)
			(end 0.7874 -0.4064)
			(stroke
				(width 0.1524)
				(type default)
			)
			(layer "F.SilkS")
		)
		(fp_line
			(start 0.67945 0.3048)
			(end 0.120396 0.3048)
			(stroke
				(width 0.1)
				(type default)
			)
			(layer "F.Fab")
		)
		(fp_line
			(start 0.67945 -0.3048)
			(end 0.67945 0.3048)
			(stroke
				(width 0.1)
				(type default)
			)
			(layer "F.Fab")
		)
		(fp_line
			(start 0.12065 -0.2794)
			(end 0.12065 -0.3048)
			(stroke
				(width 0.1)
				(type default)
			)
			(layer "F.Fab")
		)
		(fp_line
			(start 0.12065 -0.3048)
			(end 0.67945 -0.3048)
			(stroke
				(width 0.1)
				(type default)
			)
			(layer "F.Fab")
		)
		(fp_line
			(start 0.120396 0.3048)
			(end 0.120396 0.2794)
			(stroke
				(width 0.1)
				(type default)
			)
			(layer "F.Fab")
		)
		(fp_line
			(start 0.120396 0.2794)
			(end -0.12065 0.2794)
			(stroke
				(width 0.1)
				(type default)
			)
			(layer "F.Fab")
		)
		(fp_line
			(start -0.12065 0.3048)
			(end -0.67945 0.3048)
			(stroke
				(width 0.1)
				(type default)
			)
			(layer "F.Fab")
		)
		(fp_line
			(start -0.12065 0.2794)
			(end -0.12065 0.3048)
			(stroke
				(width 0.1)
				(type default)
			)
			(layer "F.Fab")
		)
		(fp_line
			(start -0.12065 -0.2794)
			(end 0.12065 -0.2794)
			(stroke
				(width 0.1)
				(type default)
			)
			(layer "F.Fab")
		)
		(fp_line
			(start -0.12065 -0.305054)
			(end -0.12065 -0.2794)
			(stroke
				(width 0.1)
				(type default)
			)
			(layer "F.Fab")
		)
		(fp_line
			(start -0.67945 0.3048)
			(end -0.67945 -0.305054)
			(stroke
				(width 0.1)
				(type default)
			)
			(layer "F.Fab")
		)
		(fp_line
			(start -0.67945 -0.305054)
			(end -0.12065 -0.305054)
			(stroke
				(width 0.1)
				(type default)
			)
			(layer "F.Fab")
		)
		(pad "1" smd circle
			(at -0.40005 0 180)
			(size 0 0)
			(layers "F.Cu" "F.Mask" "F.Paste")
			(net "PVDD18_S5_P1")
		)
		(pad "2" smd circle
			(at 0.40005 0 180)
			(size 0 0)
			(layers "F.Cu" "F.Mask" "F.Paste")
			(net "GND")
		)
	)
	(footprint ""
		(layer "F.Cu")
		(at 49.276 -435.991 -90)
		(property "Reference" "C1770"
			(at 0 0 270)
			(layer "F.SilkS")
			(hide yes)
			(effects
				(font
					(size 1.27 1.27)
				)
			)
		)
		(property "Value" ""
			(at 0 0 270)
			(layer "F.Fab")
			(effects
				(font
					(size 1.27 1.27)
				)
			)
		)
		(duplicate_pad_numbers_are_jumpers no)
		(fp_line
			(start -0.7874 0.4064)
			(end -0.7874 -0.4064)
			(stroke
				(width 0.1524)
				(type default)
			)
			(layer "F.SilkS")
		)
		(fp_line
			(start 0.7874 0.4064)
			(end -0.7874 0.4064)
			(stroke
				(width 0.1524)
				(type default)
			)
			(layer "F.SilkS")
		)
		(fp_line
			(start -0.7874 -0.4064)
			(end 0.7874 -0.4064)
			(stroke
				(width 0.1524)
				(type default)
			)
			(layer "F.SilkS")
		)
		(fp_line
			(start 0.7874 -0.4064)
			(end 0.7874 0.4064)
			(stroke
				(width 0.1524)
				(type default)
			)
			(layer "F.SilkS")
		)
		(fp_line
			(start -0.67945 0.3048)
			(end -0.67945 -0.305054)
			(stroke
				(width 0.1)
				(type default)
			)
			(layer "F.Fab")
		)
		(fp_line
			(start -0.12065 0.3048)
			(end -0.67945 0.3048)
			(stroke
				(width 0.1)
				(type default)
			)
			(layer "F.Fab")
		)
		(fp_line
			(start 0.120396 0.3048)
			(end 0.120396 0.2794)
			(stroke
				(width 0.1)
				(type default)
			)
			(layer "F.Fab")
		)
		(fp_line
			(start 0.67945 0.3048)
			(end 0.120396 0.3048)
			(stroke
				(width 0.1)
				(type default)
			)
			(layer "F.Fab")
		)
		(fp_line
			(start -0.12065 0.2794)
			(end -0.12065 0.3048)
			(stroke
				(width 0.1)
				(type default)
			)
			(layer "F.Fab")
		)
		(fp_line
			(start 0.120396 0.2794)
			(end -0.12065 0.2794)
			(stroke
				(width 0.1)
				(type default)
			)
			(layer "F.Fab")
		)
		(fp_line
			(start -0.12065 -0.2794)
			(end 0.12065 -0.2794)
			(stroke
				(width 0.1)
				(type default)
			)
			(layer "F.Fab")
		)
		(fp_line
			(start 0.12065 -0.2794)
			(end 0.12065 -0.3048)
			(stroke
				(width 0.1)
				(type default)
			)
			(layer "F.Fab")
		)
		(fp_line
			(start 0.12065 -0.3048)
			(end 0.67945 -0.3048)
			(stroke
				(width 0.1)
				(type default)
			)
			(layer "F.Fab")
		)
		(fp_line
			(start 0.67945 -0.3048)
			(end 0.67945 0.3048)
			(stroke
				(width 0.1)
				(type default)
			)
			(layer "F.Fab")
		)
		(fp_line
			(start -0.67945 -0.305054)
			(end -0.12065 -0.305054)
			(stroke
				(width 0.1)
				(type default)
			)
			(layer "F.Fab")
		)
		(fp_line
			(start -0.12065 -0.305054)
			(end -0.12065 -0.2794)
			(stroke
				(width 0.1)
				(type default)
			)
			(layer "F.Fab")
		)
		(pad "1" smd circle
			(at -0.40005 0 270)
			(size 0 0)
			(layers "F.Cu" "F.Mask" "F.Paste")
			(net "P3V3_AUX")
		)
		(pad "2" smd circle
			(at 0.40005 0 270)
			(size 0 0)
			(layers "F.Cu" "F.Mask" "F.Paste")
			(net "GND")
		)
	)
	(footprint ""
		(layer "F.Cu")
		(at 111.251238 -39.40175 90)
		(property "Reference" "R6291"
			(at 0 0 90)
			(layer "F.SilkS")
			(hide yes)
			(effects
				(font
					(size 1.27 1.27)
				)
			)
		)
		(property "Value" ""
			(at 0 0 90)
			(layer "F.Fab")
			(effects
				(font
					(size 1.27 1.27)
				)
			)
		)
		(duplicate_pad_numbers_are_jumpers no)
		(fp_line
			(start 0.7874 -0.4064)
			(end 0.7874 0.4064)
			(stroke
				(width 0.1524)
				(type default)
			)
			(layer "F.SilkS")
		)
		(fp_line
			(start -0.7874 -0.4064)
			(end 0.7874 -0.4064)
			(stroke
				(width 0.1524)
				(type default)
			)
			(layer "F.SilkS")
		)
		(fp_line
			(start 0.7874 0.4064)
			(end -0.7874 0.4064)
			(stroke
				(width 0.1524)
				(type default)
			)
			(layer "F.SilkS")
		)
		(fp_line
			(start -0.7874 0.4064)
			(end -0.7874 -0.4064)
			(stroke
				(width 0.1524)
				(type default)
			)
			(layer "F.SilkS")
		)
		(fp_line
			(start -0.12065 -0.305054)
			(end -0.12065 -0.2794)
			(stroke
				(width 0.1)
				(type default)
			)
			(layer "F.Fab")
		)
		(fp_line
			(start -0.67945 -0.305054)
			(end -0.12065 -0.305054)
			(stroke
				(width 0.1)
				(type default)
			)
			(layer "F.Fab")
		)
		(fp_line
			(start 0.67945 -0.3048)
			(end 0.67945 0.3048)
			(stroke
				(width 0.1)
				(type default)
			)
			(layer "F.Fab")
		)
		(fp_line
			(start 0.12065 -0.3048)
			(end 0.67945 -0.3048)
			(stroke
				(width 0.1)
				(type default)
			)
			(layer "F.Fab")
		)
		(fp_line
			(start 0.12065 -0.2794)
			(end 0.12065 -0.3048)
			(stroke
				(width 0.1)
				(type default)
			)
			(layer "F.Fab")
		)
		(fp_line
			(start -0.12065 -0.2794)
			(end 0.12065 -0.2794)
			(stroke
				(width 0.1)
				(type default)
			)
			(layer "F.Fab")
		)
		(fp_line
			(start 0.120396 0.2794)
			(end -0.12065 0.2794)
			(stroke
				(width 0.1)
				(type default)
			)
			(layer "F.Fab")
		)
		(fp_line
			(start -0.12065 0.2794)
			(end -0.12065 0.3048)
			(stroke
				(width 0.1)
				(type default)
			)
			(layer "F.Fab")
		)
		(fp_line
			(start 0.67945 0.3048)
			(end 0.120396 0.3048)
			(stroke
				(width 0.1)
				(type default)
			)
			(layer "F.Fab")
		)
		(fp_line
			(start 0.120396 0.3048)
			(end 0.120396 0.2794)
			(stroke
				(width 0.1)
				(type default)
			)
			(layer "F.Fab")
		)
		(fp_line
			(start -0.12065 0.3048)
			(end -0.67945 0.3048)
			(stroke
				(width 0.1)
				(type default)
			)
			(layer "F.Fab")
		)
		(fp_line
			(start -0.67945 0.3048)
			(end -0.67945 -0.305054)
			(stroke
				(width 0.1)
				(type default)
			)
			(layer "F.Fab")
		)
		(pad "1" smd circle
			(at -0.40005 0 90)
			(size 0 0)
			(layers "F.Cu" "F.Mask" "F.Paste")
			(net "USB_HUB2_TI_GANGED_MRP_I2C_SLV_CFG0")
		)
		(pad "2" smd circle
			(at 0.40005 0 90)
			(size 0 0)
			(layers "F.Cu" "F.Mask" "F.Paste")
			(net "USB_HUB2_MRP_I2C_SLV_CFG0")
		)
	)
	(footprint ""
		(layer "F.Cu")
		(at 105.515156 -344.591132 -90)
		(property "Reference" "PC146"
			(at 0 0 270)
			(layer "F.SilkS")
			(hide yes)
			(effects
				(font
					(size 1.27 1.27)
				)
			)
		)
		(property "Value" ""
			(at 0 0 270)
			(layer "F.Fab")
			(effects
				(font
					(size 1.27 1.27)
				)
			)
		)
		(duplicate_pad_numbers_are_jumpers no)
		(fp_line
			(start -0.7874 0.4064)
			(end -0.7874 -0.4064)
			(stroke
				(width 0.1524)
				(type default)
			)
			(layer "F.SilkS")
		)
		(fp_line
			(start 0.7874 0.4064)
			(end -0.7874 0.4064)
			(stroke
				(width 0.1524)
				(type default)
			)
			(layer "F.SilkS")
		)
		(fp_line
			(start -0.7874 -0.4064)
			(end 0.7874 -0.4064)
			(stroke
				(width 0.1524)
				(type default)
			)
			(layer "F.SilkS")
		)
		(fp_line
			(start 0.7874 -0.4064)
			(end 0.7874 0.4064)
			(stroke
				(width 0.1524)
				(type default)
			)
			(layer "F.SilkS")
		)
		(fp_line
			(start -0.67945 0.3048)
			(end -0.67945 -0.305054)
			(stroke
				(width 0.1)
				(type default)
			)
			(layer "F.Fab")
		)
		(fp_line
			(start -0.12065 0.3048)
			(end -0.67945 0.3048)
			(stroke
				(width 0.1)
				(type default)
			)
			(layer "F.Fab")
		)
		(fp_line
			(start 0.120396 0.3048)
			(end 0.120396 0.2794)
			(stroke
				(width 0.1)
				(type default)
			)
			(layer "F.Fab")
		)
		(fp_line
			(start 0.67945 0.3048)
			(end 0.120396 0.3048)
			(stroke
				(width 0.1)
				(type default)
			)
			(layer "F.Fab")
		)
		(fp_line
			(start -0.12065 0.2794)
			(end -0.12065 0.3048)
			(stroke
				(width 0.1)
				(type default)
			)
			(layer "F.Fab")
		)
		(fp_line
			(start 0.120396 0.2794)
			(end -0.12065 0.2794)
			(stroke
				(width 0.1)
				(type default)
			)
			(layer "F.Fab")
		)
		(fp_line
			(start -0.12065 -0.2794)
			(end 0.12065 -0.2794)
			(stroke
				(width 0.1)
				(type default)
			)
			(layer "F.Fab")
		)
		(fp_line
			(start 0.12065 -0.2794)
			(end 0.12065 -0.3048)
			(stroke
				(width 0.1)
				(type default)
			)
			(layer "F.Fab")
		)
		(fp_line
			(start 0.12065 -0.3048)
			(end 0.67945 -0.3048)
			(stroke
				(width 0.1)
				(type default)
			)
			(layer "F.Fab")
		)
		(fp_line
			(start 0.67945 -0.3048)
			(end 0.67945 0.3048)
			(stroke
				(width 0.1)
				(type default)
			)
			(layer "F.Fab")
		)
		(fp_line
			(start -0.67945 -0.305054)
			(end -0.12065 -0.305054)
			(stroke
				(width 0.1)
				(type default)
			)
			(layer "F.Fab")
		)
		(fp_line
			(start -0.12065 -0.305054)
			(end -0.12065 -0.2794)
			(stroke
				(width 0.1)
				(type default)
			)
			(layer "F.Fab")
		)
		(pad "1" smd circle
			(at -0.40005 0 270)
			(size 0 0)
			(layers "F.Cu" "F.Mask" "F.Paste")
			(net "SW_PVDDCR_CPU1_P1_BOOT6_R")
		)
		(pad "2" smd circle
			(at 0.40005 0 270)
			(size 0 0)
			(layers "F.Cu" "F.Mask" "F.Paste")
			(net "SW_PVDDCR_CPU1_P1_BOOTR6")
		)
	)
	(footprint ""
		(layer "F.Cu")
		(at 75.7936 -384.66268)
		(property "Reference" "R783"
			(at 0 0 0)
			(layer "F.SilkS")
			(hide yes)
			(effects
				(font
					(size 1.27 1.27)
				)
			)
		)
		(property "Value" ""
			(at 0 0 0)
			(layer "F.Fab")
			(effects
				(font
					(size 1.27 1.27)
				)
			)
		)
		(duplicate_pad_numbers_are_jumpers no)
		(fp_line
			(start -0.32512 -0.175006)
			(end 0.32512 -0.175006)
			(stroke
				(width 0.1)
				(type default)
			)
			(layer "F.Fab")
		)
		(fp_line
			(start -0.32512 0.175006)
			(end -0.32512 -0.175006)
			(stroke
				(width 0.1)
				(type default)
			)
			(layer "F.Fab")
		)
		(fp_line
			(start 0.32512 -0.175006)
			(end 0.32512 0.175006)
			(stroke
				(width 0.1)
				(type default)
			)
			(layer "F.Fab")
		)
		(fp_line
			(start 0.32512 0.175006)
			(end -0.32512 0.175006)
			(stroke
				(width 0.1)
				(type default)
			)
			(layer "F.Fab")
		)
		(pad "1" smd rect
			(at -0.2667 0)
			(size 0.3048 0.381)
			(layers "F.Cu" "F.Mask" "F.Paste")
			(net "GPIO3_RT_CPU1_P1")
		)
		(pad "2" smd rect
			(at 0.2667 0 180)
			(size 0.3048 0.381)
			(layers "F.Cu" "F.Mask" "F.Paste")
			(net "GND")
		)
	)
	(footprint ""
		(layer "F.Cu")
		(at 100.046282 -339.937598 -90)
		(property "Reference" "PC139_C1P1_6"
			(at 0 0 270)
			(layer "F.SilkS")
			(hide yes)
			(effects
				(font
					(size 1.27 1.27)
				)
			)
		)
		(property "Value" ""
			(at 0 0 270)
			(layer "F.Fab")
			(effects
				(font
					(size 1.27 1.27)
				)
			)
		)
		(duplicate_pad_numbers_are_jumpers no)
		(fp_line
			(start -0.7874 0.4064)
			(end -0.7874 -0.4064)
			(stroke
				(width 0.1524)
				(type default)
			)
			(layer "F.SilkS")
		)
		(fp_line
			(start 0.7874 0.4064)
			(end -0.7874 0.4064)
			(stroke
				(width 0.1524)
				(type default)
			)
			(layer "F.SilkS")
		)
		(fp_line
			(start -0.7874 -0.4064)
			(end 0.7874 -0.4064)
			(stroke
				(width 0.1524)
				(type default)
			)
			(layer "F.SilkS")
		)
		(fp_line
			(start 0.7874 -0.4064)
			(end 0.7874 0.4064)
			(stroke
				(width 0.1524)
				(type default)
			)
			(layer "F.SilkS")
		)
		(fp_line
			(start -0.67945 0.3048)
			(end -0.67945 -0.305054)
			(stroke
				(width 0.1)
				(type default)
			)
			(layer "F.Fab")
		)
		(fp_line
			(start -0.12065 0.3048)
			(end -0.67945 0.3048)
			(stroke
				(width 0.1)
				(type default)
			)
			(layer "F.Fab")
		)
		(fp_line
			(start 0.120396 0.3048)
			(end 0.120396 0.2794)
			(stroke
				(width 0.1)
				(type default)
			)
			(layer "F.Fab")
		)
		(fp_line
			(start 0.67945 0.3048)
			(end 0.120396 0.3048)
			(stroke
				(width 0.1)
				(type default)
			)
			(layer "F.Fab")
		)
		(fp_line
			(start -0.12065 0.2794)
			(end -0.12065 0.3048)
			(stroke
				(width 0.1)
				(type default)
			)
			(layer "F.Fab")
		)
		(fp_line
			(start 0.120396 0.2794)
			(end -0.12065 0.2794)
			(stroke
				(width 0.1)
				(type default)
			)
			(layer "F.Fab")
		)
		(fp_line
			(start -0.12065 -0.2794)
			(end 0.12065 -0.2794)
			(stroke
				(width 0.1)
				(type default)
			)
			(layer "F.Fab")
		)
		(fp_line
			(start 0.12065 -0.2794)
			(end 0.12065 -0.3048)
			(stroke
				(width 0.1)
				(type default)
			)
			(layer "F.Fab")
		)
		(fp_line
			(start 0.12065 -0.3048)
			(end 0.67945 -0.3048)
			(stroke
				(width 0.1)
				(type default)
			)
			(layer "F.Fab")
		)
		(fp_line
			(start 0.67945 -0.3048)
			(end 0.67945 0.3048)
			(stroke
				(width 0.1)
				(type default)
			)
			(layer "F.Fab")
		)
		(fp_line
			(start -0.67945 -0.305054)
			(end -0.12065 -0.305054)
			(stroke
				(width 0.1)
				(type default)
			)
			(layer "F.Fab")
		)
		(fp_line
			(start -0.12065 -0.305054)
			(end -0.12065 -0.2794)
			(stroke
				(width 0.1)
				(type default)
			)
			(layer "F.Fab")
		)
		(pad "1" smd circle
			(at -0.40005 0 270)
			(size 0 0)
			(layers "F.Cu" "F.Mask" "F.Paste")
			(net "PVDDCR_CPU1_P1_PVCC")
		)
		(pad "2" smd circle
			(at 0.40005 0 270)
			(size 0 0)
			(layers "F.Cu" "F.Mask" "F.Paste")
			(net "GND")
		)
	)
	(footprint ""
		(layer "F.Cu")
		(at 376.33402 -423.904918 180)
		(property "Reference" "R1127"
			(at 0 0 180)
			(layer "F.SilkS")
			(hide yes)
			(effects
				(font
					(size 1.27 1.27)
				)
			)
		)
		(property "Value" ""
			(at 0 0 180)
			(layer "F.Fab")
			(effects
				(font
					(size 1.27 1.27)
				)
			)
		)
		(duplicate_pad_numbers_are_jumpers no)
		(fp_line
			(start 0.32512 0.175006)
			(end -0.32512 0.175006)
			(stroke
				(width 0.1)
				(type default)
			)
			(layer "F.Fab")
		)
		(fp_line
			(start 0.32512 -0.175006)
			(end 0.32512 0.175006)
			(stroke
				(width 0.1)
				(type default)
			)
			(layer "F.Fab")
		)
		(fp_line
			(start -0.32512 0.175006)
			(end -0.32512 -0.175006)
			(stroke
				(width 0.1)
				(type default)
			)
			(layer "F.Fab")
		)
		(fp_line
			(start -0.32512 -0.175006)
			(end 0.32512 -0.175006)
			(stroke
				(width 0.1)
				(type default)
			)
			(layer "F.Fab")
		)
		(pad "1" smd rect
			(at -0.2667 0 180)
			(size 0.3048 0.381)
			(layers "F.Cu" "F.Mask" "F.Paste")
			(net "U17_E2")
		)
		(pad "2" smd rect
			(at 0.2667 0)
			(size 0.3048 0.381)
			(layers "F.Cu" "F.Mask" "F.Paste")
			(net "GND")
		)
	)
	(footprint ""
		(layer "F.Cu")
		(at 226.0981 -398.940782 180)
		(property "Reference" "PC2349"
			(at 0 0 180)
			(layer "F.SilkS")
			(hide yes)
			(effects
				(font
					(size 1.27 1.27)
				)
			)
		)
		(property "Value" ""
			(at 0 0 180)
			(layer "F.Fab")
			(effects
				(font
					(size 1.27 1.27)
				)
			)
		)
		(duplicate_pad_numbers_are_jumpers no)
		(fp_line
			(start 0.7874 0.4064)
			(end -0.7874 0.4064)
			(stroke
				(width 0.1524)
				(type default)
			)
			(layer "F.SilkS")
		)
		(fp_line
			(start 0.7874 -0.4064)
			(end 0.7874 0.4064)
			(stroke
				(width 0.1524)
				(type default)
			)
			(layer "F.SilkS")
		)
		(fp_line
			(start -0.7874 0.4064)
			(end -0.7874 -0.4064)
			(stroke
				(width 0.1524)
				(type default)
			)
			(layer "F.SilkS")
		)
		(fp_line
			(start -0.7874 -0.4064)
			(end 0.7874 -0.4064)
			(stroke
				(width 0.1524)
				(type default)
			)
			(layer "F.SilkS")
		)
		(fp_line
			(start 0.67945 0.3048)
			(end 0.120396 0.3048)
			(stroke
				(width 0.1)
				(type default)
			)
			(layer "F.Fab")
		)
		(fp_line
			(start 0.67945 -0.3048)
			(end 0.67945 0.3048)
			(stroke
				(width 0.1)
				(type default)
			)
			(layer "F.Fab")
		)
		(fp_line
			(start 0.12065 -0.2794)
			(end 0.12065 -0.3048)
			(stroke
				(width 0.1)
				(type default)
			)
			(layer "F.Fab")
		)
		(fp_line
			(start 0.12065 -0.3048)
			(end 0.67945 -0.3048)
			(stroke
				(width 0.1)
				(type default)
			)
			(layer "F.Fab")
		)
		(fp_line
			(start 0.120396 0.3048)
			(end 0.120396 0.2794)
			(stroke
				(width 0.1)
				(type default)
			)
			(layer "F.Fab")
		)
		(fp_line
			(start 0.120396 0.2794)
			(end -0.12065 0.2794)
			(stroke
				(width 0.1)
				(type default)
			)
			(layer "F.Fab")
		)
		(fp_line
			(start -0.12065 0.3048)
			(end -0.67945 0.3048)
			(stroke
				(width 0.1)
				(type default)
			)
			(layer "F.Fab")
		)
		(fp_line
			(start -0.12065 0.2794)
			(end -0.12065 0.3048)
			(stroke
				(width 0.1)
				(type default)
			)
			(layer "F.Fab")
		)
		(fp_line
			(start -0.12065 -0.2794)
			(end 0.12065 -0.2794)
			(stroke
				(width 0.1)
				(type default)
			)
			(layer "F.Fab")
		)
		(fp_line
			(start -0.12065 -0.305054)
			(end -0.12065 -0.2794)
			(stroke
				(width 0.1)
				(type default)
			)
			(layer "F.Fab")
		)
		(fp_line
			(start -0.67945 0.3048)
			(end -0.67945 -0.305054)
			(stroke
				(width 0.1)
				(type default)
			)
			(layer "F.Fab")
		)
		(fp_line
			(start -0.67945 -0.305054)
			(end -0.12065 -0.305054)
			(stroke
				(width 0.1)
				(type default)
			)
			(layer "F.Fab")
		)
		(pad "1" smd circle
			(at -0.40005 0 180)
			(size 0 0)
			(layers "F.Cu" "F.Mask" "F.Paste")
			(net "HSC_OCREF")
		)
		(pad "2" smd circle
			(at 0.40005 0 180)
			(size 0 0)
			(layers "F.Cu" "F.Mask" "F.Paste")
			(net "AGND_HSC")
		)
	)
	(footprint ""
		(layer "F.Cu")
		(at 430.355756 -109.25937 -90)
		(property "Reference" "PC2093"
			(at 0 0 270)
			(layer "F.SilkS")
			(hide yes)
			(effects
				(font
					(size 1.27 1.27)
				)
			)
		)
		(property "Value" ""
			(at 0 0 270)
			(layer "F.Fab")
			(effects
				(font
					(size 1.27 1.27)
				)
			)
		)
		(duplicate_pad_numbers_are_jumpers no)
		(fp_line
			(start -0.7874 0.4064)
			(end -0.7874 -0.4064)
			(stroke
				(width 0.1524)
				(type default)
			)
			(layer "F.SilkS")
		)
		(fp_line
			(start 0.7874 0.4064)
			(end -0.7874 0.4064)
			(stroke
				(width 0.1524)
				(type default)
			)
			(layer "F.SilkS")
		)
		(fp_line
			(start -0.7874 -0.4064)
			(end 0.7874 -0.4064)
			(stroke
				(width 0.1524)
				(type default)
			)
			(layer "F.SilkS")
		)
		(fp_line
			(start 0.7874 -0.4064)
			(end 0.7874 0.4064)
			(stroke
				(width 0.1524)
				(type default)
			)
			(layer "F.SilkS")
		)
		(fp_line
			(start -0.67945 0.3048)
			(end -0.67945 -0.305054)
			(stroke
				(width 0.1)
				(type default)
			)
			(layer "F.Fab")
		)
		(fp_line
			(start -0.12065 0.3048)
			(end -0.67945 0.3048)
			(stroke
				(width 0.1)
				(type default)
			)
			(layer "F.Fab")
		)
		(fp_line
			(start 0.120396 0.3048)
			(end 0.120396 0.2794)
			(stroke
				(width 0.1)
				(type default)
			)
			(layer "F.Fab")
		)
		(fp_line
			(start 0.67945 0.3048)
			(end 0.120396 0.3048)
			(stroke
				(width 0.1)
				(type default)
			)
			(layer "F.Fab")
		)
		(fp_line
			(start -0.12065 0.2794)
			(end -0.12065 0.3048)
			(stroke
				(width 0.1)
				(type default)
			)
			(layer "F.Fab")
		)
		(fp_line
			(start 0.120396 0.2794)
			(end -0.12065 0.2794)
			(stroke
				(width 0.1)
				(type default)
			)
			(layer "F.Fab")
		)
		(fp_line
			(start -0.12065 -0.2794)
			(end 0.12065 -0.2794)
			(stroke
				(width 0.1)
				(type default)
			)
			(layer "F.Fab")
		)
		(fp_line
			(start 0.12065 -0.2794)
			(end 0.12065 -0.3048)
			(stroke
				(width 0.1)
				(type default)
			)
			(layer "F.Fab")
		)
		(fp_line
			(start 0.12065 -0.3048)
			(end 0.67945 -0.3048)
			(stroke
				(width 0.1)
				(type default)
			)
			(layer "F.Fab")
		)
		(fp_line
			(start 0.67945 -0.3048)
			(end 0.67945 0.3048)
			(stroke
				(width 0.1)
				(type default)
			)
			(layer "F.Fab")
		)
		(fp_line
			(start -0.67945 -0.305054)
			(end -0.12065 -0.305054)
			(stroke
				(width 0.1)
				(type default)
			)
			(layer "F.Fab")
		)
		(fp_line
			(start -0.12065 -0.305054)
			(end -0.12065 -0.2794)
			(stroke
				(width 0.1)
				(type default)
			)
			(layer "F.Fab")
		)
		(pad "1" smd circle
			(at -0.40005 0 270)
			(size 0 0)
			(layers "F.Cu" "F.Mask" "F.Paste")
			(net "GND")
		)
		(pad "2" smd circle
			(at 0.40005 0 270)
			(size 0 0)
			(layers "F.Cu" "F.Mask" "F.Paste")
			(net "P3V3_OCP_REG_1")
		)
	)
	(footprint ""
		(layer "F.Cu")
		(at 299.265594 -393.96416)
		(property "Reference" "R979"
			(at 0 0 0)
			(layer "F.SilkS")
			(hide yes)
			(effects
				(font
					(size 1.27 1.27)
				)
			)
		)
		(property "Value" ""
			(at 0 0 0)
			(layer "F.Fab")
			(effects
				(font
					(size 1.27 1.27)
				)
			)
		)
		(duplicate_pad_numbers_are_jumpers no)
		(fp_line
			(start -0.32512 -0.175006)
			(end 0.32512 -0.175006)
			(stroke
				(width 0.1)
				(type default)
			)
			(layer "F.Fab")
		)
		(fp_line
			(start -0.32512 0.175006)
			(end -0.32512 -0.175006)
			(stroke
				(width 0.1)
				(type default)
			)
			(layer "F.Fab")
		)
		(fp_line
			(start 0.32512 -0.175006)
			(end 0.32512 0.175006)
			(stroke
				(width 0.1)
				(type default)
			)
			(layer "F.Fab")
		)
		(fp_line
			(start 0.32512 0.175006)
			(end -0.32512 0.175006)
			(stroke
				(width 0.1)
				(type default)
			)
			(layer "F.Fab")
		)
		(pad "1" smd rect
			(at -0.2667 0)
			(size 0.3048 0.381)
			(layers "F.Cu" "F.Mask" "F.Paste")
			(net "GPIO2_RT_CPU0_P0")
		)
		(pad "2" smd rect
			(at 0.2667 0 180)
			(size 0.3048 0.381)
			(layers "F.Cu" "F.Mask" "F.Paste")
			(net "GND")
		)
	)
	(footprint ""
		(layer "F.Cu")
		(at 41.995852 -385.58216)
		(property "Reference" "R706"
			(at 0 0 0)
			(layer "F.SilkS")
			(hide yes)
			(effects
				(font
					(size 1.27 1.27)
				)
			)
		)
		(property "Value" ""
			(at 0 0 0)
			(layer "F.Fab")
			(effects
				(font
					(size 1.27 1.27)
				)
			)
		)
		(duplicate_pad_numbers_are_jumpers no)
		(fp_line
			(start -0.32512 -0.175006)
			(end 0.32512 -0.175006)
			(stroke
				(width 0.1)
				(type default)
			)
			(layer "F.Fab")
		)
		(fp_line
			(start -0.32512 0.175006)
			(end -0.32512 -0.175006)
			(stroke
				(width 0.1)
				(type default)
			)
			(layer "F.Fab")
		)
		(fp_line
			(start 0.32512 -0.175006)
			(end 0.32512 0.175006)
			(stroke
				(width 0.1)
				(type default)
			)
			(layer "F.Fab")
		)
		(fp_line
			(start 0.32512 0.175006)
			(end -0.32512 0.175006)
			(stroke
				(width 0.1)
				(type default)
			)
			(layer "F.Fab")
		)
		(pad "1" smd rect
			(at -0.2667 0)
			(size 0.3048 0.381)
			(layers "F.Cu" "F.Mask" "F.Paste")
			(net "P1V8_CPU1_RT_1D")
		)
		(pad "2" smd rect
			(at 0.2667 0 180)
			(size 0.3048 0.381)
			(layers "F.Cu" "F.Mask" "F.Paste")
			(net "GPIO2_RT_CPU1_P0")
		)
	)
	(footprint ""
		(layer "F.Cu")
		(at 323.007482 -331.983842 180)
		(property "Reference" "PC190"
			(at 0 0 180)
			(layer "F.SilkS")
			(hide yes)
			(effects
				(font
					(size 1.27 1.27)
				)
			)
		)
		(property "Value" ""
			(at 0 0 180)
			(layer "F.Fab")
			(effects
				(font
					(size 1.27 1.27)
				)
			)
		)
		(duplicate_pad_numbers_are_jumpers no)
		(fp_line
			(start 0.7874 0.4064)
			(end -0.7874 0.4064)
			(stroke
				(width 0.1524)
				(type default)
			)
			(layer "F.SilkS")
		)
		(fp_line
			(start 0.7874 -0.4064)
			(end 0.7874 0.4064)
			(stroke
				(width 0.1524)
				(type default)
			)
			(layer "F.SilkS")
		)
		(fp_line
			(start -0.7874 0.4064)
			(end -0.7874 -0.4064)
			(stroke
				(width 0.1524)
				(type default)
			)
			(layer "F.SilkS")
		)
		(fp_line
			(start -0.7874 -0.4064)
			(end 0.7874 -0.4064)
			(stroke
				(width 0.1524)
				(type default)
			)
			(layer "F.SilkS")
		)
		(fp_line
			(start 0.67945 0.3048)
			(end 0.120396 0.3048)
			(stroke
				(width 0.1)
				(type default)
			)
			(layer "F.Fab")
		)
		(fp_line
			(start 0.67945 -0.3048)
			(end 0.67945 0.3048)
			(stroke
				(width 0.1)
				(type default)
			)
			(layer "F.Fab")
		)
		(fp_line
			(start 0.12065 -0.2794)
			(end 0.12065 -0.3048)
			(stroke
				(width 0.1)
				(type default)
			)
			(layer "F.Fab")
		)
		(fp_line
			(start 0.12065 -0.3048)
			(end 0.67945 -0.3048)
			(stroke
				(width 0.1)
				(type default)
			)
			(layer "F.Fab")
		)
		(fp_line
			(start 0.120396 0.3048)
			(end 0.120396 0.2794)
			(stroke
				(width 0.1)
				(type default)
			)
			(layer "F.Fab")
		)
		(fp_line
			(start 0.120396 0.2794)
			(end -0.12065 0.2794)
			(stroke
				(width 0.1)
				(type default)
			)
			(layer "F.Fab")
		)
		(fp_line
			(start -0.12065 0.3048)
			(end -0.67945 0.3048)
			(stroke
				(width 0.1)
				(type default)
			)
			(layer "F.Fab")
		)
		(fp_line
			(start -0.12065 0.2794)
			(end -0.12065 0.3048)
			(stroke
				(width 0.1)
				(type default)
			)
			(layer "F.Fab")
		)
		(fp_line
			(start -0.12065 -0.2794)
			(end 0.12065 -0.2794)
			(stroke
				(width 0.1)
				(type default)
			)
			(layer "F.Fab")
		)
		(fp_line
			(start -0.12065 -0.305054)
			(end -0.12065 -0.2794)
			(stroke
				(width 0.1)
				(type default)
			)
			(layer "F.Fab")
		)
		(fp_line
			(start -0.67945 0.3048)
			(end -0.67945 -0.305054)
			(stroke
				(width 0.1)
				(type default)
			)
			(layer "F.Fab")
		)
		(fp_line
			(start -0.67945 -0.305054)
			(end -0.12065 -0.305054)
			(stroke
				(width 0.1)
				(type default)
			)
			(layer "F.Fab")
		)
		(pad "1" smd circle
			(at -0.40005 0 180)
			(size 0 0)
			(layers "F.Cu" "F.Mask" "F.Paste")
			(net "SW_PVDDCR_CPU1_P0_SW2")
		)
		(pad "2" smd circle
			(at 0.40005 0 180)
			(size 0 0)
			(layers "F.Cu" "F.Mask" "F.Paste")
			(net "SW_PVDDCR_CPU1_P0_SW2_RC")
		)
	)
	(footprint ""
		(layer "F.Cu")
		(at 206.381604 -342.075262 -90)
		(property "Reference" "PC132"
			(at 0 0 270)
			(layer "F.SilkS")
			(hide yes)
			(effects
				(font
					(size 1.27 1.27)
				)
			)
		)
		(property "Value" ""
			(at 0 0 270)
			(layer "F.Fab")
			(effects
				(font
					(size 1.27 1.27)
				)
			)
		)
		(duplicate_pad_numbers_are_jumpers no)
		(fp_line
			(start -0.7874 0.4064)
			(end -0.7874 -0.4064)
			(stroke
				(width 0.1524)
				(type default)
			)
			(layer "F.SilkS")
		)
		(fp_line
			(start 0.7874 0.4064)
			(end -0.7874 0.4064)
			(stroke
				(width 0.1524)
				(type default)
			)
			(layer "F.SilkS")
		)
		(fp_line
			(start -0.7874 -0.4064)
			(end 0.7874 -0.4064)
			(stroke
				(width 0.1524)
				(type default)
			)
			(layer "F.SilkS")
		)
		(fp_line
			(start 0.7874 -0.4064)
			(end 0.7874 0.4064)
			(stroke
				(width 0.1524)
				(type default)
			)
			(layer "F.SilkS")
		)
		(fp_line
			(start -0.67945 0.3048)
			(end -0.67945 -0.305054)
			(stroke
				(width 0.1)
				(type default)
			)
			(layer "F.Fab")
		)
		(fp_line
			(start -0.12065 0.3048)
			(end -0.67945 0.3048)
			(stroke
				(width 0.1)
				(type default)
			)
			(layer "F.Fab")
		)
		(fp_line
			(start 0.120396 0.3048)
			(end 0.120396 0.2794)
			(stroke
				(width 0.1)
				(type default)
			)
			(layer "F.Fab")
		)
		(fp_line
			(start 0.67945 0.3048)
			(end 0.120396 0.3048)
			(stroke
				(width 0.1)
				(type default)
			)
			(layer "F.Fab")
		)
		(fp_line
			(start -0.12065 0.2794)
			(end -0.12065 0.3048)
			(stroke
				(width 0.1)
				(type default)
			)
			(layer "F.Fab")
		)
		(fp_line
			(start 0.120396 0.2794)
			(end -0.12065 0.2794)
			(stroke
				(width 0.1)
				(type default)
			)
			(layer "F.Fab")
		)
		(fp_line
			(start -0.12065 -0.2794)
			(end 0.12065 -0.2794)
			(stroke
				(width 0.1)
				(type default)
			)
			(layer "F.Fab")
		)
		(fp_line
			(start 0.12065 -0.2794)
			(end 0.12065 -0.3048)
			(stroke
				(width 0.1)
				(type default)
			)
			(layer "F.Fab")
		)
		(fp_line
			(start 0.12065 -0.3048)
			(end 0.67945 -0.3048)
			(stroke
				(width 0.1)
				(type default)
			)
			(layer "F.Fab")
		)
		(fp_line
			(start 0.67945 -0.3048)
			(end 0.67945 0.3048)
			(stroke
				(width 0.1)
				(type default)
			)
			(layer "F.Fab")
		)
		(fp_line
			(start -0.67945 -0.305054)
			(end -0.12065 -0.305054)
			(stroke
				(width 0.1)
				(type default)
			)
			(layer "F.Fab")
		)
		(fp_line
			(start -0.12065 -0.305054)
			(end -0.12065 -0.2794)
			(stroke
				(width 0.1)
				(type default)
			)
			(layer "F.Fab")
		)
		(pad "1" smd circle
			(at -0.40005 0 270)
			(size 0 0)
			(layers "F.Cu" "F.Mask" "F.Paste")
			(net "PVDD_33_S5_FB")
		)
		(pad "2" smd circle
			(at 0.40005 0 270)
			(size 0 0)
			(layers "F.Cu" "F.Mask" "F.Paste")
			(net "PVDD_33_S5")
		)
	)
	(footprint ""
		(layer "F.Cu")
		(at 204.7621 -399.956782)
		(property "Reference" "PR3919"
			(at 0 0 0)
			(layer "F.SilkS")
			(hide yes)
			(effects
				(font
					(size 1.27 1.27)
				)
			)
		)
		(property "Value" ""
			(at 0 0 0)
			(layer "F.Fab")
			(effects
				(font
					(size 1.27 1.27)
				)
			)
		)
		(duplicate_pad_numbers_are_jumpers no)
		(fp_line
			(start -0.7874 -0.4064)
			(end 0.7874 -0.4064)
			(stroke
				(width 0.1524)
				(type default)
			)
			(layer "F.SilkS")
		)
		(fp_line
			(start -0.7874 0.4064)
			(end -0.7874 -0.4064)
			(stroke
				(width 0.1524)
				(type default)
			)
			(layer "F.SilkS")
		)
		(fp_line
			(start 0.7874 -0.4064)
			(end 0.7874 0.4064)
			(stroke
				(width 0.1524)
				(type default)
			)
			(layer "F.SilkS")
		)
		(fp_line
			(start 0.7874 0.4064)
			(end -0.7874 0.4064)
			(stroke
				(width 0.1524)
				(type default)
			)
			(layer "F.SilkS")
		)
		(fp_line
			(start -0.67945 -0.305054)
			(end -0.12065 -0.305054)
			(stroke
				(width 0.1)
				(type default)
			)
			(layer "F.Fab")
		)
		(fp_line
			(start -0.67945 0.3048)
			(end -0.67945 -0.305054)
			(stroke
				(width 0.1)
				(type default)
			)
			(layer "F.Fab")
		)
		(fp_line
			(start -0.12065 -0.305054)
			(end -0.12065 -0.2794)
			(stroke
				(width 0.1)
				(type default)
			)
			(layer "F.Fab")
		)
		(fp_line
			(start -0.12065 -0.2794)
			(end 0.12065 -0.2794)
			(stroke
				(width 0.1)
				(type default)
			)
			(layer "F.Fab")
		)
		(fp_line
			(start -0.12065 0.2794)
			(end -0.12065 0.3048)
			(stroke
				(width 0.1)
				(type default)
			)
			(layer "F.Fab")
		)
		(fp_line
			(start -0.12065 0.3048)
			(end -0.67945 0.3048)
			(stroke
				(width 0.1)
				(type default)
			)
			(layer "F.Fab")
		)
		(fp_line
			(start 0.120396 0.2794)
			(end -0.12065 0.2794)
			(stroke
				(width 0.1)
				(type default)
			)
			(layer "F.Fab")
		)
		(fp_line
			(start 0.120396 0.3048)
			(end 0.120396 0.2794)
			(stroke
				(width 0.1)
				(type default)
			)
			(layer "F.Fab")
		)
		(fp_line
			(start 0.12065 -0.3048)
			(end 0.67945 -0.3048)
			(stroke
				(width 0.1)
				(type default)
			)
			(layer "F.Fab")
		)
		(fp_line
			(start 0.12065 -0.2794)
			(end 0.12065 -0.3048)
			(stroke
				(width 0.1)
				(type default)
			)
			(layer "F.Fab")
		)
		(fp_line
			(start 0.67945 -0.3048)
			(end 0.67945 0.3048)
			(stroke
				(width 0.1)
				(type default)
			)
			(layer "F.Fab")
		)
		(fp_line
			(start 0.67945 0.3048)
			(end 0.120396 0.3048)
			(stroke
				(width 0.1)
				(type default)
			)
			(layer "F.Fab")
		)
		(pad "1" smd circle
			(at -0.40005 0)
			(size 0 0)
			(layers "F.Cu" "F.Mask" "F.Paste")
			(net "HSC_D_OC_1")
		)
		(pad "2" smd circle
			(at 0.40005 0)
			(size 0 0)
			(layers "F.Cu" "F.Mask" "F.Paste")
			(net "HSC_D_OC_R")
		)
	)
	(footprint ""
		(layer "F.Cu")
		(at 295.09085 -369.375436 180)
		(property "Reference" "PR55"
			(at 0 0 180)
			(layer "F.SilkS")
			(hide yes)
			(effects
				(font
					(size 1.27 1.27)
				)
			)
		)
		(property "Value" ""
			(at 0 0 180)
			(layer "F.Fab")
			(effects
				(font
					(size 1.27 1.27)
				)
			)
		)
		(duplicate_pad_numbers_are_jumpers no)
		(fp_line
			(start 0.7874 0.4064)
			(end -0.7874 0.4064)
			(stroke
				(width 0.1524)
				(type default)
			)
			(layer "F.SilkS")
		)
		(fp_line
			(start 0.7874 -0.4064)
			(end 0.7874 0.4064)
			(stroke
				(width 0.1524)
				(type default)
			)
			(layer "F.SilkS")
		)
		(fp_line
			(start -0.7874 0.4064)
			(end -0.7874 -0.4064)
			(stroke
				(width 0.1524)
				(type default)
			)
			(layer "F.SilkS")
		)
		(fp_line
			(start -0.7874 -0.4064)
			(end 0.7874 -0.4064)
			(stroke
				(width 0.1524)
				(type default)
			)
			(layer "F.SilkS")
		)
		(fp_line
			(start 0.67945 0.3048)
			(end 0.120396 0.3048)
			(stroke
				(width 0.1)
				(type default)
			)
			(layer "F.Fab")
		)
		(fp_line
			(start 0.67945 -0.3048)
			(end 0.67945 0.3048)
			(stroke
				(width 0.1)
				(type default)
			)
			(layer "F.Fab")
		)
		(fp_line
			(start 0.12065 -0.2794)
			(end 0.12065 -0.3048)
			(stroke
				(width 0.1)
				(type default)
			)
			(layer "F.Fab")
		)
		(fp_line
			(start 0.12065 -0.3048)
			(end 0.67945 -0.3048)
			(stroke
				(width 0.1)
				(type default)
			)
			(layer "F.Fab")
		)
		(fp_line
			(start 0.120396 0.3048)
			(end 0.120396 0.2794)
			(stroke
				(width 0.1)
				(type default)
			)
			(layer "F.Fab")
		)
		(fp_line
			(start 0.120396 0.2794)
			(end -0.12065 0.2794)
			(stroke
				(width 0.1)
				(type default)
			)
			(layer "F.Fab")
		)
		(fp_line
			(start -0.12065 0.3048)
			(end -0.67945 0.3048)
			(stroke
				(width 0.1)
				(type default)
			)
			(layer "F.Fab")
		)
		(fp_line
			(start -0.12065 0.2794)
			(end -0.12065 0.3048)
			(stroke
				(width 0.1)
				(type default)
			)
			(layer "F.Fab")
		)
		(fp_line
			(start -0.12065 -0.2794)
			(end 0.12065 -0.2794)
			(stroke
				(width 0.1)
				(type default)
			)
			(layer "F.Fab")
		)
		(fp_line
			(start -0.12065 -0.305054)
			(end -0.12065 -0.2794)
			(stroke
				(width 0.1)
				(type default)
			)
			(layer "F.Fab")
		)
		(fp_line
			(start -0.67945 0.3048)
			(end -0.67945 -0.305054)
			(stroke
				(width 0.1)
				(type default)
			)
			(layer "F.Fab")
		)
		(fp_line
			(start -0.67945 -0.305054)
			(end -0.12065 -0.305054)
			(stroke
				(width 0.1)
				(type default)
			)
			(layer "F.Fab")
		)
		(pad "1" smd circle
			(at -0.40005 0 180)
			(size 0 0)
			(layers "F.Cu" "F.Mask" "F.Paste")
			(net "P3V3_AUX")
		)
		(pad "2" smd circle
			(at 0.40005 0 180)
			(size 0 0)
			(layers "F.Cu" "F.Mask" "F.Paste")
			(net "PVDDIO_P0_EN_G")
		)
	)
	(footprint ""
		(layer "F.Cu")
		(at 409.824936 -170.328082 -90)
		(property "Reference" "PR503"
			(at 0 0 270)
			(layer "F.SilkS")
			(hide yes)
			(effects
				(font
					(size 1.27 1.27)
				)
			)
		)
		(property "Value" ""
			(at 0 0 270)
			(layer "F.Fab")
			(effects
				(font
					(size 1.27 1.27)
				)
			)
		)
		(duplicate_pad_numbers_are_jumpers no)
		(fp_line
			(start -0.7874 0.4064)
			(end -0.7874 -0.4064)
			(stroke
				(width 0.1524)
				(type default)
			)
			(layer "F.SilkS")
		)
		(fp_line
			(start 0.7874 0.4064)
			(end -0.7874 0.4064)
			(stroke
				(width 0.1524)
				(type default)
			)
			(layer "F.SilkS")
		)
		(fp_line
			(start -0.7874 -0.4064)
			(end 0.7874 -0.4064)
			(stroke
				(width 0.1524)
				(type default)
			)
			(layer "F.SilkS")
		)
		(fp_line
			(start 0.7874 -0.4064)
			(end 0.7874 0.4064)
			(stroke
				(width 0.1524)
				(type default)
			)
			(layer "F.SilkS")
		)
		(fp_line
			(start -0.67945 0.3048)
			(end -0.67945 -0.305054)
			(stroke
				(width 0.1)
				(type default)
			)
			(layer "F.Fab")
		)
		(fp_line
			(start -0.12065 0.3048)
			(end -0.67945 0.3048)
			(stroke
				(width 0.1)
				(type default)
			)
			(layer "F.Fab")
		)
		(fp_line
			(start 0.120396 0.3048)
			(end 0.120396 0.2794)
			(stroke
				(width 0.1)
				(type default)
			)
			(layer "F.Fab")
		)
		(fp_line
			(start 0.67945 0.3048)
			(end 0.120396 0.3048)
			(stroke
				(width 0.1)
				(type default)
			)
			(layer "F.Fab")
		)
		(fp_line
			(start -0.12065 0.2794)
			(end -0.12065 0.3048)
			(stroke
				(width 0.1)
				(type default)
			)
			(layer "F.Fab")
		)
		(fp_line
			(start 0.120396 0.2794)
			(end -0.12065 0.2794)
			(stroke
				(width 0.1)
				(type default)
			)
			(layer "F.Fab")
		)
		(fp_line
			(start -0.12065 -0.2794)
			(end 0.12065 -0.2794)
			(stroke
				(width 0.1)
				(type default)
			)
			(layer "F.Fab")
		)
		(fp_line
			(start 0.12065 -0.2794)
			(end 0.12065 -0.3048)
			(stroke
				(width 0.1)
				(type default)
			)
			(layer "F.Fab")
		)
		(fp_line
			(start 0.12065 -0.3048)
			(end 0.67945 -0.3048)
			(stroke
				(width 0.1)
				(type default)
			)
			(layer "F.Fab")
		)
		(fp_line
			(start 0.67945 -0.3048)
			(end 0.67945 0.3048)
			(stroke
				(width 0.1)
				(type default)
			)
			(layer "F.Fab")
		)
		(fp_line
			(start -0.67945 -0.305054)
			(end -0.12065 -0.305054)
			(stroke
				(width 0.1)
				(type default)
			)
			(layer "F.Fab")
		)
		(fp_line
			(start -0.12065 -0.305054)
			(end -0.12065 -0.2794)
			(stroke
				(width 0.1)
				(type default)
			)
			(layer "F.Fab")
		)
		(pad "1" smd circle
			(at -0.40005 0 270)
			(size 0 0)
			(layers "F.Cu" "F.Mask" "F.Paste")
			(net "SW_PVDDCR_SOC_P0_SW2_RC")
		)
		(pad "2" smd circle
			(at 0.40005 0 270)
			(size 0 0)
			(layers "F.Cu" "F.Mask" "F.Paste")
			(net "GND")
		)
	)
	(footprint ""
		(layer "F.Cu")
		(at 205.665832 -137.527792)
		(property "Reference" "R2528"
			(at 0 0 0)
			(layer "F.SilkS")
			(hide yes)
			(effects
				(font
					(size 1.27 1.27)
				)
			)
		)
		(property "Value" ""
			(at 0 0 0)
			(layer "F.Fab")
			(effects
				(font
					(size 1.27 1.27)
				)
			)
		)
		(duplicate_pad_numbers_are_jumpers no)
		(fp_line
			(start -0.7874 -0.4064)
			(end 0.7874 -0.4064)
			(stroke
				(width 0.1524)
				(type default)
			)
			(layer "F.SilkS")
		)
		(fp_line
			(start -0.7874 0.4064)
			(end -0.7874 -0.4064)
			(stroke
				(width 0.1524)
				(type default)
			)
			(layer "F.SilkS")
		)
		(fp_line
			(start 0.7874 -0.4064)
			(end 0.7874 0.4064)
			(stroke
				(width 0.1524)
				(type default)
			)
			(layer "F.SilkS")
		)
		(fp_line
			(start 0.7874 0.4064)
			(end -0.7874 0.4064)
			(stroke
				(width 0.1524)
				(type default)
			)
			(layer "F.SilkS")
		)
		(fp_line
			(start -0.67945 -0.305054)
			(end -0.12065 -0.305054)
			(stroke
				(width 0.1)
				(type default)
			)
			(layer "F.Fab")
		)
		(fp_line
			(start -0.67945 0.3048)
			(end -0.67945 -0.305054)
			(stroke
				(width 0.1)
				(type default)
			)
			(layer "F.Fab")
		)
		(fp_line
			(start -0.12065 -0.305054)
			(end -0.12065 -0.2794)
			(stroke
				(width 0.1)
				(type default)
			)
			(layer "F.Fab")
		)
		(fp_line
			(start -0.12065 -0.2794)
			(end 0.12065 -0.2794)
			(stroke
				(width 0.1)
				(type default)
			)
			(layer "F.Fab")
		)
		(fp_line
			(start -0.12065 0.2794)
			(end -0.12065 0.3048)
			(stroke
				(width 0.1)
				(type default)
			)
			(layer "F.Fab")
		)
		(fp_line
			(start -0.12065 0.3048)
			(end -0.67945 0.3048)
			(stroke
				(width 0.1)
				(type default)
			)
			(layer "F.Fab")
		)
		(fp_line
			(start 0.120396 0.2794)
			(end -0.12065 0.2794)
			(stroke
				(width 0.1)
				(type default)
			)
			(layer "F.Fab")
		)
		(fp_line
			(start 0.120396 0.3048)
			(end 0.120396 0.2794)
			(stroke
				(width 0.1)
				(type default)
			)
			(layer "F.Fab")
		)
		(fp_line
			(start 0.12065 -0.3048)
			(end 0.67945 -0.3048)
			(stroke
				(width 0.1)
				(type default)
			)
			(layer "F.Fab")
		)
		(fp_line
			(start 0.12065 -0.2794)
			(end 0.12065 -0.3048)
			(stroke
				(width 0.1)
				(type default)
			)
			(layer "F.Fab")
		)
		(fp_line
			(start 0.67945 -0.3048)
			(end 0.67945 0.3048)
			(stroke
				(width 0.1)
				(type default)
			)
			(layer "F.Fab")
		)
		(fp_line
			(start 0.67945 0.3048)
			(end 0.120396 0.3048)
			(stroke
				(width 0.1)
				(type default)
			)
			(layer "F.Fab")
		)
		(pad "1" smd circle
			(at -0.40005 0)
			(size 0 0)
			(layers "F.Cu" "F.Mask" "F.Paste")
			(net "P12V_AUX")
		)
		(pad "2" smd circle
			(at 0.40005 0)
			(size 0 0)
			(layers "F.Cu" "F.Mask" "F.Paste")
			(net "FM_P12V_HSC_EN_N")
		)
	)
	(footprint ""
		(layer "F.Cu")
		(at 121.539 -321.691 90)
		(property "Reference" "R8350"
			(at 0 0 90)
			(layer "F.SilkS")
			(hide yes)
			(effects
				(font
					(size 1.27 1.27)
				)
			)
		)
		(property "Value" ""
			(at 0 0 90)
			(layer "F.Fab")
			(effects
				(font
					(size 1.27 1.27)
				)
			)
		)
		(duplicate_pad_numbers_are_jumpers no)
		(fp_line
			(start -0.381 -0.4064)
			(end 0.4064 -0.4064)
			(stroke
				(width 0.1524)
				(type default)
			)
			(layer "F.SilkS")
		)
		(fp_line
			(start 0.7874 0)
			(end 0.7874 0.4064)
			(stroke
				(width 0.1524)
				(type default)
			)
			(layer "F.SilkS")
		)
		(fp_line
			(start 0.7874 0.4064)
			(end -0.7874 0.4064)
			(stroke
				(width 0.1524)
				(type default)
			)
			(layer "F.SilkS")
		)
		(fp_line
			(start -0.7874 0.4064)
			(end -0.7874 -0.0254)
			(stroke
				(width 0.1524)
				(type default)
			)
			(layer "F.SilkS")
		)
		(fp_line
			(start -0.12065 -0.305054)
			(end -0.12065 -0.2794)
			(stroke
				(width 0.1)
				(type default)
			)
			(layer "F.Fab")
		)
		(fp_line
			(start -0.67945 -0.305054)
			(end -0.12065 -0.305054)
			(stroke
				(width 0.1)
				(type default)
			)
			(layer "F.Fab")
		)
		(fp_line
			(start 0.67945 -0.3048)
			(end 0.67945 0.3048)
			(stroke
				(width 0.1)
				(type default)
			)
			(layer "F.Fab")
		)
		(fp_line
			(start 0.12065 -0.3048)
			(end 0.67945 -0.3048)
			(stroke
				(width 0.1)
				(type default)
			)
			(layer "F.Fab")
		)
		(fp_line
			(start 0.12065 -0.2794)
			(end 0.12065 -0.3048)
			(stroke
				(width 0.1)
				(type default)
			)
			(layer "F.Fab")
		)
		(fp_line
			(start -0.12065 -0.2794)
			(end 0.12065 -0.2794)
			(stroke
				(width 0.1)
				(type default)
			)
			(layer "F.Fab")
		)
		(fp_line
			(start 0.120396 0.2794)
			(end -0.12065 0.2794)
			(stroke
				(width 0.1)
				(type default)
			)
			(layer "F.Fab")
		)
		(fp_line
			(start -0.12065 0.2794)
			(end -0.12065 0.3048)
			(stroke
				(width 0.1)
				(type default)
			)
			(layer "F.Fab")
		)
		(fp_line
			(start 0.67945 0.3048)
			(end 0.120396 0.3048)
			(stroke
				(width 0.1)
				(type default)
			)
			(layer "F.Fab")
		)
		(fp_line
			(start 0.120396 0.3048)
			(end 0.120396 0.2794)
			(stroke
				(width 0.1)
				(type default)
			)
			(layer "F.Fab")
		)
		(fp_line
			(start -0.12065 0.3048)
			(end -0.67945 0.3048)
			(stroke
				(width 0.1)
				(type default)
			)
			(layer "F.Fab")
		)
		(fp_line
			(start -0.67945 0.3048)
			(end -0.67945 -0.305054)
			(stroke
				(width 0.1)
				(type default)
			)
			(layer "F.Fab")
		)
		(pad "1" smd circle
			(at -0.40005 0 90)
			(size 0 0)
			(layers "F.Cu" "F.Mask" "F.Paste")
			(net "CLK_100M_CPU1_CLK13_R_DP")
		)
		(pad "2" smd circle
			(at 0.40005 0 90)
			(size 0 0)
			(layers "F.Cu" "F.Mask" "F.Paste")
			(net "CLK_100M_CPU1_CLK13_DP")
		)
	)
	(footprint ""
		(layer "F.Cu")
		(at 304.419 -363.982 180)
		(property "Reference" "C8070"
			(at 0 0 180)
			(layer "F.SilkS")
			(hide yes)
			(effects
				(font
					(size 1.27 1.27)
				)
			)
		)
		(property "Value" ""
			(at 0 0 180)
			(layer "F.Fab")
			(effects
				(font
					(size 1.27 1.27)
				)
			)
		)
		(duplicate_pad_numbers_are_jumpers no)
		(fp_line
			(start 0.7874 0.4064)
			(end -0.7874 0.4064)
			(stroke
				(width 0.1524)
				(type default)
			)
			(layer "F.SilkS")
		)
		(fp_line
			(start 0.7874 -0.4064)
			(end 0.7874 0.4064)
			(stroke
				(width 0.1524)
				(type default)
			)
			(layer "F.SilkS")
		)
		(fp_line
			(start -0.7874 0.4064)
			(end -0.7874 -0.4064)
			(stroke
				(width 0.1524)
				(type default)
			)
			(layer "F.SilkS")
		)
		(fp_line
			(start -0.7874 -0.4064)
			(end 0.7874 -0.4064)
			(stroke
				(width 0.1524)
				(type default)
			)
			(layer "F.SilkS")
		)
		(fp_line
			(start 0.67945 0.3048)
			(end 0.120396 0.3048)
			(stroke
				(width 0.1)
				(type default)
			)
			(layer "F.Fab")
		)
		(fp_line
			(start 0.67945 -0.3048)
			(end 0.67945 0.3048)
			(stroke
				(width 0.1)
				(type default)
			)
			(layer "F.Fab")
		)
		(fp_line
			(start 0.12065 -0.2794)
			(end 0.12065 -0.3048)
			(stroke
				(width 0.1)
				(type default)
			)
			(layer "F.Fab")
		)
		(fp_line
			(start 0.12065 -0.3048)
			(end 0.67945 -0.3048)
			(stroke
				(width 0.1)
				(type default)
			)
			(layer "F.Fab")
		)
		(fp_line
			(start 0.120396 0.3048)
			(end 0.120396 0.2794)
			(stroke
				(width 0.1)
				(type default)
			)
			(layer "F.Fab")
		)
		(fp_line
			(start 0.120396 0.2794)
			(end -0.12065 0.2794)
			(stroke
				(width 0.1)
				(type default)
			)
			(layer "F.Fab")
		)
		(fp_line
			(start -0.12065 0.3048)
			(end -0.67945 0.3048)
			(stroke
				(width 0.1)
				(type default)
			)
			(layer "F.Fab")
		)
		(fp_line
			(start -0.12065 0.2794)
			(end -0.12065 0.3048)
			(stroke
				(width 0.1)
				(type default)
			)
			(layer "F.Fab")
		)
		(fp_line
			(start -0.12065 -0.2794)
			(end 0.12065 -0.2794)
			(stroke
				(width 0.1)
				(type default)
			)
			(layer "F.Fab")
		)
		(fp_line
			(start -0.12065 -0.305054)
			(end -0.12065 -0.2794)
			(stroke
				(width 0.1)
				(type default)
			)
			(layer "F.Fab")
		)
		(fp_line
			(start -0.67945 0.3048)
			(end -0.67945 -0.305054)
			(stroke
				(width 0.1)
				(type default)
			)
			(layer "F.Fab")
		)
		(fp_line
			(start -0.67945 -0.305054)
			(end -0.12065 -0.305054)
			(stroke
				(width 0.1)
				(type default)
			)
			(layer "F.Fab")
		)
		(pad "1" smd circle
			(at -0.40005 0 180)
			(size 0 0)
			(layers "F.Cu" "F.Mask" "F.Paste")
			(net "PWRGD_PVDDCR_CPU1_P0_R")
		)
		(pad "2" smd circle
			(at 0.40005 0 180)
			(size 0 0)
			(layers "F.Cu" "F.Mask" "F.Paste")
			(net "GND")
		)
	)
	(footprint ""
		(layer "F.Cu")
		(at 253.063756 -418.11067 -90)
		(property "Reference" "PD13"
			(at -1.69926 -3.99034 90)
			(unlocked yes)
			(layer "F.SilkS")
			(effects
				(font
					(size 0.7874 0.5842)
					(thickness 0.1524)
				)
				(justify left)
			)
		)
		(property "Value" ""
			(at 0 0 270)
			(layer "F.Fab")
			(effects
				(font
					(size 1.27 1.27)
				)
			)
		)
		(duplicate_pad_numbers_are_jumpers no)
		(fp_line
			(start -4.664456 3.109976)
			(end -4.664456 -3.109976)
			(stroke
				(width 0.1524)
				(type default)
			)
			(layer "F.SilkS")
		)
		(fp_line
			(start 4.156202 3.109976)
			(end 4.183126 3.109976)
			(stroke
				(width 0.1524)
				(type default)
			)
			(layer "F.SilkS")
		)
		(fp_line
			(start 4.743704 3.109976)
			(end 4.6101 3.109976)
			(stroke
				(width 0.1524)
				(type default)
			)
			(layer "F.SilkS")
		)
		(fp_line
			(start 4.743704 3.109976)
			(end 5.4102 3.109976)
			(stroke
				(width 0.1524)
				(type default)
			)
			(layer "F.SilkS")
		)
		(fp_line
			(start 4.769104 3.109976)
			(end -4.664456 3.109976)
			(stroke
				(width 0.1524)
				(type default)
			)
			(layer "F.SilkS")
		)
		(fp_line
			(start 4.794504 3.109976)
			(end 3.554984 3.109976)
			(stroke
				(width 0.1524)
				(type default)
			)
			(layer "F.SilkS")
		)
		(fp_line
			(start 5.4102 3.109976)
			(end 5.4102 -3.109976)
			(stroke
				(width 0.1524)
				(type default)
			)
			(layer "F.SilkS")
		)
		(fp_line
			(start 4.715002 3.035554)
			(end 4.7117 2.984754)
			(stroke
				(width 0.1524)
				(type default)
			)
			(layer "F.SilkS")
		)
		(fp_line
			(start 0.762 1.27)
			(end 0.762 -1.27)
			(stroke
				(width 0.1524)
				(type default)
			)
			(layer "F.SilkS")
		)
		(fp_line
			(start -0.508 1.016)
			(end -0.508 -1.016)
			(stroke
				(width 0.1524)
				(type default)
			)
			(layer "F.SilkS")
		)
		(fp_line
			(start -1.0668 0)
			(end -0.6096 0)
			(stroke
				(width 0.1524)
				(type default)
			)
			(layer "F.SilkS")
		)
		(fp_line
			(start 0.762 0)
			(end -0.508 1.016)
			(stroke
				(width 0.1524)
				(type default)
			)
			(layer "F.SilkS")
		)
		(fp_line
			(start 0.762 0)
			(end 1.2192 0)
			(stroke
				(width 0.1524)
				(type default)
			)
			(layer "F.SilkS")
		)
		(fp_line
			(start -0.508 -1.016)
			(end 0.762 0)
			(stroke
				(width 0.1524)
				(type default)
			)
			(layer "F.SilkS")
		)
		(fp_line
			(start -4.664456 -3.109976)
			(end 4.743704 -3.109976)
			(stroke
				(width 0.1524)
				(type default)
			)
			(layer "F.SilkS")
		)
		(fp_line
			(start 4.183126 -3.109976)
			(end 4.794504 -3.109976)
			(stroke
				(width 0.1524)
				(type default)
			)
			(layer "F.SilkS")
		)
		(fp_line
			(start 4.511802 -3.109976)
			(end 4.207002 -3.109976)
			(stroke
				(width 0.1524)
				(type default)
			)
			(layer "F.SilkS")
		)
		(fp_line
			(start 4.6101 -3.109976)
			(end 4.283202 -3.109976)
			(stroke
				(width 0.1524)
				(type default)
			)
			(layer "F.SilkS")
		)
		(fp_line
			(start 4.695444 -3.109976)
			(end 4.695444 3.109976)
			(stroke
				(width 0.1524)
				(type default)
			)
			(layer "F.SilkS")
		)
		(fp_line
			(start 4.70535 -3.109976)
			(end 4.70535 3.109976)
			(stroke
				(width 0.1524)
				(type default)
			)
			(layer "F.SilkS")
		)
		(fp_line
			(start 4.70535 -3.109976)
			(end 4.70535 3.109976)
			(stroke
				(width 0.1524)
				(type default)
			)
			(layer "F.SilkS")
		)
		(fp_line
			(start 4.70535 -3.109976)
			(end 4.70535 3.109976)
			(stroke
				(width 0.1524)
				(type default)
			)
			(layer "F.SilkS")
		)
		(fp_line
			(start 4.805426 -3.109976)
			(end 4.805426 3.109976)
			(stroke
				(width 0.1524)
				(type default)
			)
			(layer "F.SilkS")
		)
		(fp_line
			(start 4.932426 -3.109976)
			(end 4.932426 3.109976)
			(stroke
				(width 0.1524)
				(type default)
			)
			(layer "F.SilkS")
		)
		(fp_line
			(start 5.008626 -3.109976)
			(end 5.008626 3.109976)
			(stroke
				(width 0.1524)
				(type default)
			)
			(layer "F.SilkS")
		)
		(fp_line
			(start 5.110226 -3.109976)
			(end 5.110226 3.109976)
			(stroke
				(width 0.1524)
				(type default)
			)
			(layer "F.SilkS")
		)
		(fp_line
			(start 5.211826 -3.109976)
			(end 5.211826 3.109976)
			(stroke
				(width 0.1524)
				(type default)
			)
			(layer "F.SilkS")
		)
		(fp_line
			(start 5.262626 -3.109976)
			(end 5.262626 3.109976)
			(stroke
				(width 0.1524)
				(type default)
			)
			(layer "F.SilkS")
		)
		(fp_line
			(start 5.313426 -3.109976)
			(end 5.313426 3.109976)
			(stroke
				(width 0.1524)
				(type default)
			)
			(layer "F.SilkS")
		)
		(fp_line
			(start 5.4102 -3.109976)
			(end 4.783074 -3.109976)
			(stroke
				(width 0.1524)
				(type default)
			)
			(layer "F.SilkS")
		)
		(fp_line
			(start -4.065016 3.109976)
			(end -4.065016 -3.109976)
			(stroke
				(width 0.1)
				(type default)
			)
			(layer "F.Fab")
		)
		(fp_line
			(start 4.065016 3.109976)
			(end -4.065016 3.109976)
			(stroke
				(width 0.1)
				(type default)
			)
			(layer "F.Fab")
		)
		(fp_line
			(start -4.065016 -3.109976)
			(end 4.065016 -3.109976)
			(stroke
				(width 0.1)
				(type default)
			)
			(layer "F.Fab")
		)
		(fp_line
			(start 4.065016 -3.109976)
			(end 4.065016 3.109976)
			(stroke
				(width 0.1)
				(type default)
			)
			(layer "F.Fab")
		)
		(fp_text user "-"
			(at 6.643624 0.40005 90)
			(unlocked yes)
			(layer "F.SilkS")
			(effects
				(font
					(size 1.905 1.4224)
					(thickness 0.1524)
				)
				(justify left)
			)
		)
		(fp_text user "+"
			(at -4.5974 0.24765 90)
			(unlocked yes)
			(layer "F.SilkS")
			(effects
				(font
					(size 1.905 1.4224)
					(thickness 0.1524)
				)
				(justify left)
			)
		)
		(fp_text user "-"
			(at 6.643624 0.40005 90)
			(unlocked yes)
			(layer "F.Fab")
			(effects
				(font
					(size 1.905 1.4224)
					(thickness 0.1524)
				)
				(justify left)
			)
		)
		(fp_text user "+"
			(at -4.5974 0.24765 90)
			(unlocked yes)
			(layer "F.Fab")
			(effects
				(font
					(size 1.905 1.4224)
					(thickness 0.1524)
				)
				(justify left)
			)
		)
		(pad "A" smd rect
			(at -3.299968 0 90)
			(size 2.413 3.302)
			(layers "F.Cu" "F.Mask" "F.Paste")
			(net "GND")
		)
		(pad "C" smd rect
			(at 3.299968 0 90)
			(size 2.413 3.302)
			(layers "F.Cu" "F.Mask" "F.Paste")
			(net "P12V_PSU_FUSE")
		)
	)
	(footprint ""
		(layer "F.Cu")
		(at 117.094 -417.957 90)
		(property "Reference" "C1802"
			(at 0 0 90)
			(layer "F.SilkS")
			(hide yes)
			(effects
				(font
					(size 1.27 1.27)
				)
			)
		)
		(property "Value" ""
			(at 0 0 90)
			(layer "F.Fab")
			(effects
				(font
					(size 1.27 1.27)
				)
			)
		)
		(duplicate_pad_numbers_are_jumpers no)
		(fp_line
			(start 0.7874 -0.4064)
			(end 0.7874 0.4064)
			(stroke
				(width 0.1524)
				(type default)
			)
			(layer "F.SilkS")
		)
		(fp_line
			(start -0.7874 -0.4064)
			(end 0.7874 -0.4064)
			(stroke
				(width 0.1524)
				(type default)
			)
			(layer "F.SilkS")
		)
		(fp_line
			(start 0.7874 0.4064)
			(end -0.7874 0.4064)
			(stroke
				(width 0.1524)
				(type default)
			)
			(layer "F.SilkS")
		)
		(fp_line
			(start -0.7874 0.4064)
			(end -0.7874 -0.4064)
			(stroke
				(width 0.1524)
				(type default)
			)
			(layer "F.SilkS")
		)
		(fp_line
			(start -0.12065 -0.305054)
			(end -0.12065 -0.2794)
			(stroke
				(width 0.1)
				(type default)
			)
			(layer "F.Fab")
		)
		(fp_line
			(start -0.67945 -0.305054)
			(end -0.12065 -0.305054)
			(stroke
				(width 0.1)
				(type default)
			)
			(layer "F.Fab")
		)
		(fp_line
			(start 0.67945 -0.3048)
			(end 0.67945 0.3048)
			(stroke
				(width 0.1)
				(type default)
			)
			(layer "F.Fab")
		)
		(fp_line
			(start 0.12065 -0.3048)
			(end 0.67945 -0.3048)
			(stroke
				(width 0.1)
				(type default)
			)
			(layer "F.Fab")
		)
		(fp_line
			(start 0.12065 -0.2794)
			(end 0.12065 -0.3048)
			(stroke
				(width 0.1)
				(type default)
			)
			(layer "F.Fab")
		)
		(fp_line
			(start -0.12065 -0.2794)
			(end 0.12065 -0.2794)
			(stroke
				(width 0.1)
				(type default)
			)
			(layer "F.Fab")
		)
		(fp_line
			(start 0.120396 0.2794)
			(end -0.12065 0.2794)
			(stroke
				(width 0.1)
				(type default)
			)
			(layer "F.Fab")
		)
		(fp_line
			(start -0.12065 0.2794)
			(end -0.12065 0.3048)
			(stroke
				(width 0.1)
				(type default)
			)
			(layer "F.Fab")
		)
		(fp_line
			(start 0.67945 0.3048)
			(end 0.120396 0.3048)
			(stroke
				(width 0.1)
				(type default)
			)
			(layer "F.Fab")
		)
		(fp_line
			(start 0.120396 0.3048)
			(end 0.120396 0.2794)
			(stroke
				(width 0.1)
				(type default)
			)
			(layer "F.Fab")
		)
		(fp_line
			(start -0.12065 0.3048)
			(end -0.67945 0.3048)
			(stroke
				(width 0.1)
				(type default)
			)
			(layer "F.Fab")
		)
		(fp_line
			(start -0.67945 0.3048)
			(end -0.67945 -0.305054)
			(stroke
				(width 0.1)
				(type default)
			)
			(layer "F.Fab")
		)
		(pad "1" smd circle
			(at -0.40005 0 90)
			(size 0 0)
			(layers "F.Cu" "F.Mask" "F.Paste")
			(net "FM_SMB_1_ALERT_GPU_ISO_N")
		)
		(pad "2" smd circle
			(at 0.40005 0 90)
			(size 0 0)
			(layers "F.Cu" "F.Mask" "F.Paste")
			(net "GND")
		)
	)
	(footprint ""
		(layer "F.Cu")
		(at 215.4301 -400.972782 180)
		(property "Reference" "PR3986"
			(at 0 0 180)
			(layer "F.SilkS")
			(hide yes)
			(effects
				(font
					(size 1.27 1.27)
				)
			)
		)
		(property "Value" ""
			(at 0 0 180)
			(layer "F.Fab")
			(effects
				(font
					(size 1.27 1.27)
				)
			)
		)
		(duplicate_pad_numbers_are_jumpers no)
		(fp_line
			(start 0.7874 0.4064)
			(end -0.7874 0.4064)
			(stroke
				(width 0.1524)
				(type default)
			)
			(layer "F.SilkS")
		)
		(fp_line
			(start 0.7874 -0.4064)
			(end 0.7874 0.4064)
			(stroke
				(width 0.1524)
				(type default)
			)
			(layer "F.SilkS")
		)
		(fp_line
			(start -0.7874 0.4064)
			(end -0.7874 -0.4064)
			(stroke
				(width 0.1524)
				(type default)
			)
			(layer "F.SilkS")
		)
		(fp_line
			(start -0.7874 -0.4064)
			(end 0.7874 -0.4064)
			(stroke
				(width 0.1524)
				(type default)
			)
			(layer "F.SilkS")
		)
		(fp_line
			(start 0.67945 0.3048)
			(end 0.120396 0.3048)
			(stroke
				(width 0.1)
				(type default)
			)
			(layer "F.Fab")
		)
		(fp_line
			(start 0.67945 -0.3048)
			(end 0.67945 0.3048)
			(stroke
				(width 0.1)
				(type default)
			)
			(layer "F.Fab")
		)
		(fp_line
			(start 0.12065 -0.2794)
			(end 0.12065 -0.3048)
			(stroke
				(width 0.1)
				(type default)
			)
			(layer "F.Fab")
		)
		(fp_line
			(start 0.12065 -0.3048)
			(end 0.67945 -0.3048)
			(stroke
				(width 0.1)
				(type default)
			)
			(layer "F.Fab")
		)
		(fp_line
			(start 0.120396 0.3048)
			(end 0.120396 0.2794)
			(stroke
				(width 0.1)
				(type default)
			)
			(layer "F.Fab")
		)
		(fp_line
			(start 0.120396 0.2794)
			(end -0.12065 0.2794)
			(stroke
				(width 0.1)
				(type default)
			)
			(layer "F.Fab")
		)
		(fp_line
			(start -0.12065 0.3048)
			(end -0.67945 0.3048)
			(stroke
				(width 0.1)
				(type default)
			)
			(layer "F.Fab")
		)
		(fp_line
			(start -0.12065 0.2794)
			(end -0.12065 0.3048)
			(stroke
				(width 0.1)
				(type default)
			)
			(layer "F.Fab")
		)
		(fp_line
			(start -0.12065 -0.2794)
			(end 0.12065 -0.2794)
			(stroke
				(width 0.1)
				(type default)
			)
			(layer "F.Fab")
		)
		(fp_line
			(start -0.12065 -0.305054)
			(end -0.12065 -0.2794)
			(stroke
				(width 0.1)
				(type default)
			)
			(layer "F.Fab")
		)
		(fp_line
			(start -0.67945 0.3048)
			(end -0.67945 -0.305054)
			(stroke
				(width 0.1)
				(type default)
			)
			(layer "F.Fab")
		)
		(fp_line
			(start -0.67945 -0.305054)
			(end -0.12065 -0.305054)
			(stroke
				(width 0.1)
				(type default)
			)
			(layer "F.Fab")
		)
		(pad "1" smd circle
			(at -0.40005 0 180)
			(size 0 0)
			(layers "F.Cu" "F.Mask" "F.Paste")
			(net "HSC_CS_3")
		)
		(pad "2" smd circle
			(at 0.40005 0 180)
			(size 0 0)
			(layers "F.Cu" "F.Mask" "F.Paste")
			(net "AGND_HSC")
		)
	)
	(footprint ""
		(layer "F.Cu")
		(at 120.523 -321.691 90)
		(property "Reference" "R8351"
			(at 0 0 90)
			(layer "F.SilkS")
			(hide yes)
			(effects
				(font
					(size 1.27 1.27)
				)
			)
		)
		(property "Value" ""
			(at 0 0 90)
			(layer "F.Fab")
			(effects
				(font
					(size 1.27 1.27)
				)
			)
		)
		(duplicate_pad_numbers_are_jumpers no)
		(fp_line
			(start 0.7874 -0.4064)
			(end 0.7874 -0.0762)
			(stroke
				(width 0.1524)
				(type default)
			)
			(layer "F.SilkS")
		)
		(fp_line
			(start -0.7874 -0.4064)
			(end 0.7874 -0.4064)
			(stroke
				(width 0.1524)
				(type default)
			)
			(layer "F.SilkS")
		)
		(fp_line
			(start -0.7874 -0.0254)
			(end -0.7874 -0.4064)
			(stroke
				(width 0.1524)
				(type default)
			)
			(layer "F.SilkS")
		)
		(fp_line
			(start 0.4064 0.4064)
			(end -0.381 0.4064)
			(stroke
				(width 0.1524)
				(type default)
			)
			(layer "F.SilkS")
		)
		(fp_line
			(start -0.12065 -0.305054)
			(end -0.12065 -0.2794)
			(stroke
				(width 0.1)
				(type default)
			)
			(layer "F.Fab")
		)
		(fp_line
			(start -0.67945 -0.305054)
			(end -0.12065 -0.305054)
			(stroke
				(width 0.1)
				(type default)
			)
			(layer "F.Fab")
		)
		(fp_line
			(start 0.67945 -0.3048)
			(end 0.67945 0.3048)
			(stroke
				(width 0.1)
				(type default)
			)
			(layer "F.Fab")
		)
		(fp_line
			(start 0.12065 -0.3048)
			(end 0.67945 -0.3048)
			(stroke
				(width 0.1)
				(type default)
			)
			(layer "F.Fab")
		)
		(fp_line
			(start 0.12065 -0.2794)
			(end 0.12065 -0.3048)
			(stroke
				(width 0.1)
				(type default)
			)
			(layer "F.Fab")
		)
		(fp_line
			(start -0.12065 -0.2794)
			(end 0.12065 -0.2794)
			(stroke
				(width 0.1)
				(type default)
			)
			(layer "F.Fab")
		)
		(fp_line
			(start 0.120396 0.2794)
			(end -0.12065 0.2794)
			(stroke
				(width 0.1)
				(type default)
			)
			(layer "F.Fab")
		)
		(fp_line
			(start -0.12065 0.2794)
			(end -0.12065 0.3048)
			(stroke
				(width 0.1)
				(type default)
			)
			(layer "F.Fab")
		)
		(fp_line
			(start 0.67945 0.3048)
			(end 0.120396 0.3048)
			(stroke
				(width 0.1)
				(type default)
			)
			(layer "F.Fab")
		)
		(fp_line
			(start 0.120396 0.3048)
			(end 0.120396 0.2794)
			(stroke
				(width 0.1)
				(type default)
			)
			(layer "F.Fab")
		)
		(fp_line
			(start -0.12065 0.3048)
			(end -0.67945 0.3048)
			(stroke
				(width 0.1)
				(type default)
			)
			(layer "F.Fab")
		)
		(fp_line
			(start -0.67945 0.3048)
			(end -0.67945 -0.305054)
			(stroke
				(width 0.1)
				(type default)
			)
			(layer "F.Fab")
		)
		(pad "1" smd circle
			(at -0.40005 0 90)
			(size 0 0)
			(layers "F.Cu" "F.Mask" "F.Paste")
			(net "CLK_100M_CPU1_CLK13_R_DN")
		)
		(pad "2" smd circle
			(at 0.40005 0 90)
			(size 0 0)
			(layers "F.Cu" "F.Mask" "F.Paste")
			(net "CLK_100M_CPU1_CLK13_DN")
		)
	)
	(footprint ""
		(layer "F.Cu")
		(at 371.298724 -435.600094)
		(property "Reference" "H128"
			(at -5.98043 -4.94538 0)
			(unlocked yes)
			(layer "F.SilkS")
			(effects
				(font
					(size 0.7874 0.5842)
					(thickness 0.1524)
				)
				(justify left)
			)
		)
		(property "Value" ""
			(at 0 0 0)
			(layer "F.Fab")
			(effects
				(font
					(size 1.27 1.27)
				)
			)
		)
		(duplicate_pad_numbers_are_jumpers no)
		(pad "1" thru_hole circle
			(at 0 0)
			(size 10.0076 10.0076)
			(drill 5.6134)
			(layers "*.Cu" "*.Mask")
			(remove_unused_layers no)
			(net "GND")
			(clearance -1.9431)
		)
	)
	(footprint ""
		(layer "F.Cu")
		(at 63.059564 -16.220948 -90)
		(property "Reference" "R3169"
			(at 0 0 270)
			(layer "F.SilkS")
			(hide yes)
			(effects
				(font
					(size 1.27 1.27)
				)
			)
		)
		(property "Value" ""
			(at 0 0 270)
			(layer "F.Fab")
			(effects
				(font
					(size 1.27 1.27)
				)
			)
		)
		(duplicate_pad_numbers_are_jumpers no)
		(fp_line
			(start -0.7874 0.4064)
			(end -0.7874 -0.4064)
			(stroke
				(width 0.1524)
				(type default)
			)
			(layer "F.SilkS")
		)
		(fp_line
			(start 0.7874 0.4064)
			(end -0.7874 0.4064)
			(stroke
				(width 0.1524)
				(type default)
			)
			(layer "F.SilkS")
		)
		(fp_line
			(start -0.7874 -0.4064)
			(end 0.7874 -0.4064)
			(stroke
				(width 0.1524)
				(type default)
			)
			(layer "F.SilkS")
		)
		(fp_line
			(start 0.7874 -0.4064)
			(end 0.7874 0.4064)
			(stroke
				(width 0.1524)
				(type default)
			)
			(layer "F.SilkS")
		)
		(fp_line
			(start -0.67945 0.3048)
			(end -0.67945 -0.305054)
			(stroke
				(width 0.1)
				(type default)
			)
			(layer "F.Fab")
		)
		(fp_line
			(start -0.12065 0.3048)
			(end -0.67945 0.3048)
			(stroke
				(width 0.1)
				(type default)
			)
			(layer "F.Fab")
		)
		(fp_line
			(start 0.120396 0.3048)
			(end 0.120396 0.2794)
			(stroke
				(width 0.1)
				(type default)
			)
			(layer "F.Fab")
		)
		(fp_line
			(start 0.67945 0.3048)
			(end 0.120396 0.3048)
			(stroke
				(width 0.1)
				(type default)
			)
			(layer "F.Fab")
		)
		(fp_line
			(start -0.12065 0.2794)
			(end -0.12065 0.3048)
			(stroke
				(width 0.1)
				(type default)
			)
			(layer "F.Fab")
		)
		(fp_line
			(start 0.120396 0.2794)
			(end -0.12065 0.2794)
			(stroke
				(width 0.1)
				(type default)
			)
			(layer "F.Fab")
		)
		(fp_line
			(start -0.12065 -0.2794)
			(end 0.12065 -0.2794)
			(stroke
				(width 0.1)
				(type default)
			)
			(layer "F.Fab")
		)
		(fp_line
			(start 0.12065 -0.2794)
			(end 0.12065 -0.3048)
			(stroke
				(width 0.1)
				(type default)
			)
			(layer "F.Fab")
		)
		(fp_line
			(start 0.12065 -0.3048)
			(end 0.67945 -0.3048)
			(stroke
				(width 0.1)
				(type default)
			)
			(layer "F.Fab")
		)
		(fp_line
			(start 0.67945 -0.3048)
			(end 0.67945 0.3048)
			(stroke
				(width 0.1)
				(type default)
			)
			(layer "F.Fab")
		)
		(fp_line
			(start -0.67945 -0.305054)
			(end -0.12065 -0.305054)
			(stroke
				(width 0.1)
				(type default)
			)
			(layer "F.Fab")
		)
		(fp_line
			(start -0.12065 -0.305054)
			(end -0.12065 -0.2794)
			(stroke
				(width 0.1)
				(type default)
			)
			(layer "F.Fab")
		)
		(pad "1" smd circle
			(at -0.40005 0 270)
			(size 0 0)
			(layers "F.Cu" "F.Mask" "F.Paste")
			(net "OCP_V3_2_ISO_BIF0_EN")
		)
		(pad "2" smd circle
			(at 0.40005 0 270)
			(size 0 0)
			(layers "F.Cu" "F.Mask" "F.Paste")
			(net "OCP_V3_2_BIF0_R_N")
		)
	)
	(footprint ""
		(layer "F.Cu")
		(at 66.491612 -346.86875 -90)
		(property "Reference" "PC405_4"
			(at 0 0 270)
			(layer "F.SilkS")
			(hide yes)
			(effects
				(font
					(size 1.27 1.27)
				)
			)
		)
		(property "Value" ""
			(at 0 0 270)
			(layer "F.Fab")
			(effects
				(font
					(size 1.27 1.27)
				)
			)
		)
		(duplicate_pad_numbers_are_jumpers no)
		(fp_line
			(start -0.7874 0.4064)
			(end -0.7874 -0.4064)
			(stroke
				(width 0.1524)
				(type default)
			)
			(layer "F.SilkS")
		)
		(fp_line
			(start 0.7874 0.4064)
			(end -0.7874 0.4064)
			(stroke
				(width 0.1524)
				(type default)
			)
			(layer "F.SilkS")
		)
		(fp_line
			(start -0.7874 -0.4064)
			(end 0.7874 -0.4064)
			(stroke
				(width 0.1524)
				(type default)
			)
			(layer "F.SilkS")
		)
		(fp_line
			(start 0.7874 -0.4064)
			(end 0.7874 0.4064)
			(stroke
				(width 0.1524)
				(type default)
			)
			(layer "F.SilkS")
		)
		(fp_line
			(start -0.67945 0.3048)
			(end -0.67945 -0.305054)
			(stroke
				(width 0.1)
				(type default)
			)
			(layer "F.Fab")
		)
		(fp_line
			(start -0.12065 0.3048)
			(end -0.67945 0.3048)
			(stroke
				(width 0.1)
				(type default)
			)
			(layer "F.Fab")
		)
		(fp_line
			(start 0.120396 0.3048)
			(end 0.120396 0.2794)
			(stroke
				(width 0.1)
				(type default)
			)
			(layer "F.Fab")
		)
		(fp_line
			(start 0.67945 0.3048)
			(end 0.120396 0.3048)
			(stroke
				(width 0.1)
				(type default)
			)
			(layer "F.Fab")
		)
		(fp_line
			(start -0.12065 0.2794)
			(end -0.12065 0.3048)
			(stroke
				(width 0.1)
				(type default)
			)
			(layer "F.Fab")
		)
		(fp_line
			(start 0.120396 0.2794)
			(end -0.12065 0.2794)
			(stroke
				(width 0.1)
				(type default)
			)
			(layer "F.Fab")
		)
		(fp_line
			(start -0.12065 -0.2794)
			(end 0.12065 -0.2794)
			(stroke
				(width 0.1)
				(type default)
			)
			(layer "F.Fab")
		)
		(fp_line
			(start 0.12065 -0.2794)
			(end 0.12065 -0.3048)
			(stroke
				(width 0.1)
				(type default)
			)
			(layer "F.Fab")
		)
		(fp_line
			(start 0.12065 -0.3048)
			(end 0.67945 -0.3048)
			(stroke
				(width 0.1)
				(type default)
			)
			(layer "F.Fab")
		)
		(fp_line
			(start 0.67945 -0.3048)
			(end 0.67945 0.3048)
			(stroke
				(width 0.1)
				(type default)
			)
			(layer "F.Fab")
		)
		(fp_line
			(start -0.67945 -0.305054)
			(end -0.12065 -0.305054)
			(stroke
				(width 0.1)
				(type default)
			)
			(layer "F.Fab")
		)
		(fp_line
			(start -0.12065 -0.305054)
			(end -0.12065 -0.2794)
			(stroke
				(width 0.1)
				(type default)
			)
			(layer "F.Fab")
		)
		(pad "1" smd circle
			(at -0.40005 0 270)
			(size 0 0)
			(layers "F.Cu" "F.Mask" "F.Paste")
			(net "SW_P12V_AUX_PVDDCR_CPU1_P1_FLT")
		)
		(pad "2" smd circle
			(at 0.40005 0 270)
			(size 0 0)
			(layers "F.Cu" "F.Mask" "F.Paste")
			(net "GND")
		)
	)
	(footprint ""
		(layer "F.Cu")
		(at 132.610352 -52.28844 90)
		(property "Reference" "C1513"
			(at 0 0 90)
			(layer "F.SilkS")
			(hide yes)
			(effects
				(font
					(size 1.27 1.27)
				)
			)
		)
		(property "Value" ""
			(at 0 0 90)
			(layer "F.Fab")
			(effects
				(font
					(size 1.27 1.27)
				)
			)
		)
		(duplicate_pad_numbers_are_jumpers no)
		(fp_line
			(start 0.7874 -0.4064)
			(end 0.7874 0.4064)
			(stroke
				(width 0.1524)
				(type default)
			)
			(layer "F.SilkS")
		)
		(fp_line
			(start -0.7874 -0.4064)
			(end 0.7874 -0.4064)
			(stroke
				(width 0.1524)
				(type default)
			)
			(layer "F.SilkS")
		)
		(fp_line
			(start 0.7874 0.4064)
			(end -0.7874 0.4064)
			(stroke
				(width 0.1524)
				(type default)
			)
			(layer "F.SilkS")
		)
		(fp_line
			(start -0.7874 0.4064)
			(end -0.7874 -0.4064)
			(stroke
				(width 0.1524)
				(type default)
			)
			(layer "F.SilkS")
		)
		(fp_line
			(start -0.12065 -0.305054)
			(end -0.12065 -0.2794)
			(stroke
				(width 0.1)
				(type default)
			)
			(layer "F.Fab")
		)
		(fp_line
			(start -0.67945 -0.305054)
			(end -0.12065 -0.305054)
			(stroke
				(width 0.1)
				(type default)
			)
			(layer "F.Fab")
		)
		(fp_line
			(start 0.67945 -0.3048)
			(end 0.67945 0.3048)
			(stroke
				(width 0.1)
				(type default)
			)
			(layer "F.Fab")
		)
		(fp_line
			(start 0.12065 -0.3048)
			(end 0.67945 -0.3048)
			(stroke
				(width 0.1)
				(type default)
			)
			(layer "F.Fab")
		)
		(fp_line
			(start 0.12065 -0.2794)
			(end 0.12065 -0.3048)
			(stroke
				(width 0.1)
				(type default)
			)
			(layer "F.Fab")
		)
		(fp_line
			(start -0.12065 -0.2794)
			(end 0.12065 -0.2794)
			(stroke
				(width 0.1)
				(type default)
			)
			(layer "F.Fab")
		)
		(fp_line
			(start 0.120396 0.2794)
			(end -0.12065 0.2794)
			(stroke
				(width 0.1)
				(type default)
			)
			(layer "F.Fab")
		)
		(fp_line
			(start -0.12065 0.2794)
			(end -0.12065 0.3048)
			(stroke
				(width 0.1)
				(type default)
			)
			(layer "F.Fab")
		)
		(fp_line
			(start 0.67945 0.3048)
			(end 0.120396 0.3048)
			(stroke
				(width 0.1)
				(type default)
			)
			(layer "F.Fab")
		)
		(fp_line
			(start 0.120396 0.3048)
			(end 0.120396 0.2794)
			(stroke
				(width 0.1)
				(type default)
			)
			(layer "F.Fab")
		)
		(fp_line
			(start -0.12065 0.3048)
			(end -0.67945 0.3048)
			(stroke
				(width 0.1)
				(type default)
			)
			(layer "F.Fab")
		)
		(fp_line
			(start -0.67945 0.3048)
			(end -0.67945 -0.305054)
			(stroke
				(width 0.1)
				(type default)
			)
			(layer "F.Fab")
		)
		(pad "1" smd circle
			(at -0.40005 0 90)
			(size 0 0)
			(layers "F.Cu" "F.Mask" "F.Paste")
			(net "PVDD18_S5_P0")
		)
		(pad "2" smd circle
			(at 0.40005 0 90)
			(size 0 0)
			(layers "F.Cu" "F.Mask" "F.Paste")
			(net "GND")
		)
	)
	(footprint ""
		(layer "F.Cu")
		(at 52.705 -433.578)
		(property "Reference" "R3391"
			(at 0 0 0)
			(layer "F.SilkS")
			(hide yes)
			(effects
				(font
					(size 1.27 1.27)
				)
			)
		)
		(property "Value" ""
			(at 0 0 0)
			(layer "F.Fab")
			(effects
				(font
					(size 1.27 1.27)
				)
			)
		)
		(duplicate_pad_numbers_are_jumpers no)
		(fp_line
			(start -0.7874 -0.4064)
			(end 0.7874 -0.4064)
			(stroke
				(width 0.1524)
				(type default)
			)
			(layer "F.SilkS")
		)
		(fp_line
			(start -0.7874 0.4064)
			(end -0.7874 -0.4064)
			(stroke
				(width 0.1524)
				(type default)
			)
			(layer "F.SilkS")
		)
		(fp_line
			(start 0.7874 -0.4064)
			(end 0.7874 0.4064)
			(stroke
				(width 0.1524)
				(type default)
			)
			(layer "F.SilkS")
		)
		(fp_line
			(start 0.7874 0.4064)
			(end -0.7874 0.4064)
			(stroke
				(width 0.1524)
				(type default)
			)
			(layer "F.SilkS")
		)
		(fp_line
			(start -0.67945 -0.305054)
			(end -0.12065 -0.305054)
			(stroke
				(width 0.1)
				(type default)
			)
			(layer "F.Fab")
		)
		(fp_line
			(start -0.67945 0.3048)
			(end -0.67945 -0.305054)
			(stroke
				(width 0.1)
				(type default)
			)
			(layer "F.Fab")
		)
		(fp_line
			(start -0.12065 -0.305054)
			(end -0.12065 -0.2794)
			(stroke
				(width 0.1)
				(type default)
			)
			(layer "F.Fab")
		)
		(fp_line
			(start -0.12065 -0.2794)
			(end 0.12065 -0.2794)
			(stroke
				(width 0.1)
				(type default)
			)
			(layer "F.Fab")
		)
		(fp_line
			(start -0.12065 0.2794)
			(end -0.12065 0.3048)
			(stroke
				(width 0.1)
				(type default)
			)
			(layer "F.Fab")
		)
		(fp_line
			(start -0.12065 0.3048)
			(end -0.67945 0.3048)
			(stroke
				(width 0.1)
				(type default)
			)
			(layer "F.Fab")
		)
		(fp_line
			(start 0.120396 0.2794)
			(end -0.12065 0.2794)
			(stroke
				(width 0.1)
				(type default)
			)
			(layer "F.Fab")
		)
		(fp_line
			(start 0.120396 0.3048)
			(end 0.120396 0.2794)
			(stroke
				(width 0.1)
				(type default)
			)
			(layer "F.Fab")
		)
		(fp_line
			(start 0.12065 -0.3048)
			(end 0.67945 -0.3048)
			(stroke
				(width 0.1)
				(type default)
			)
			(layer "F.Fab")
		)
		(fp_line
			(start 0.12065 -0.2794)
			(end 0.12065 -0.3048)
			(stroke
				(width 0.1)
				(type default)
			)
			(layer "F.Fab")
		)
		(fp_line
			(start 0.67945 -0.3048)
			(end 0.67945 0.3048)
			(stroke
				(width 0.1)
				(type default)
			)
			(layer "F.Fab")
		)
		(fp_line
			(start 0.67945 0.3048)
			(end 0.120396 0.3048)
			(stroke
				(width 0.1)
				(type default)
			)
			(layer "F.Fab")
		)
		(pad "1" smd circle
			(at -0.40005 0)
			(size 0 0)
			(layers "F.Cu" "F.Mask" "F.Paste")
			(net "RST_PERST_2_SWB_BUF_R_N")
		)
		(pad "2" smd circle
			(at 0.40005 0)
			(size 0 0)
			(layers "F.Cu" "F.Mask" "F.Paste")
			(net "RST_PERST_2_SWB_BUF_N")
		)
	)
	(footprint ""
		(layer "F.Cu")
		(at 425.36872 -385.364228)
		(property "Reference" "C840"
			(at 0 0 0)
			(layer "F.SilkS")
			(hide yes)
			(effects
				(font
					(size 1.27 1.27)
				)
			)
		)
		(property "Value" ""
			(at 0 0 0)
			(layer "F.Fab")
			(effects
				(font
					(size 1.27 1.27)
				)
			)
		)
		(duplicate_pad_numbers_are_jumpers no)
		(fp_line
			(start -0.299974 -0.150114)
			(end 0.299974 -0.150114)
			(stroke
				(width 0.1)
				(type default)
			)
			(layer "F.Fab")
		)
		(fp_line
			(start -0.299974 0.150114)
			(end -0.299974 -0.150114)
			(stroke
				(width 0.1)
				(type default)
			)
			(layer "F.Fab")
		)
		(fp_line
			(start 0.299974 -0.150114)
			(end 0.299974 0.150114)
			(stroke
				(width 0.1)
				(type default)
			)
			(layer "F.Fab")
		)
		(fp_line
			(start 0.299974 0.150114)
			(end -0.299974 0.150114)
			(stroke
				(width 0.1)
				(type default)
			)
			(layer "F.Fab")
		)
		(pad "1" smd rect
			(at -0.2667 0)
			(size 0.3048 0.381)
			(layers "F.Cu" "F.Mask" "F.Paste")
			(net "P5E_CPU0_P2_TX_C_DN<14>")
		)
		(pad "2" smd rect
			(at 0.2667 0)
			(size 0.3048 0.381)
			(layers "F.Cu" "F.Mask" "F.Paste")
			(net "P5E_CPU0_P2_TX_DN<14>")
		)
	)
	(footprint ""
		(layer "F.Cu")
		(at 514.718808 -298.391326 90)
		(property "Reference" "X8"
			(at -1.99009 1.316736 0)
			(unlocked yes)
			(layer "F.SilkS")
			(effects
				(font
					(size 0.7874 0.5842)
					(thickness 0.1524)
				)
				(justify left)
			)
		)
		(property "Value" ""
			(at 0 0 90)
			(layer "F.Fab")
			(effects
				(font
					(size 1.27 1.27)
				)
			)
		)
		(property "User Part Number" "N_A"
			(at 1.30175 1.27 180)
			(unlocked yes)
			(layer "Cmts.User")
			(hide yes)
			(effects
				(font
					(size 0.635 0.4064)
					(thickness 0.1524)
				)
			)
		)
		(property "Device Type" "TP_TDR_4P_FTS_TH-TP_TDR_4P_DIP,EMPTY,TP15"
			(at 1.30175 1.27 180)
			(unlocked yes)
			(layer "F.Fab")
			(hide yes)
			(effects
				(font
					(size 0.635 0.4064)
					(thickness 0.1524)
				)
			)
		)
		(duplicate_pad_numbers_are_jumpers no)
		(fp_line
			(start 2.54 -1.27)
			(end 0 -1.27)
			(stroke
				(width 0.1524)
				(type default)
			)
			(layer "F.SilkS")
		)
		(fp_line
			(start 0 -1.27)
			(end 0 -0.635)
			(stroke
				(width 0.1524)
				(type default)
			)
			(layer "F.SilkS")
		)
		(fp_line
			(start 2.54 -1.1303)
			(end 2.54 -1.27)
			(stroke
				(width 0.1524)
				(type default)
			)
			(layer "F.SilkS")
		)
		(fp_line
			(start 0 0.635)
			(end 0 1.905)
			(stroke
				(width 0.1524)
				(type default)
			)
			(layer "F.SilkS")
		)
		(fp_line
			(start 2.54 1.4097)
			(end 2.54 1.1303)
			(stroke
				(width 0.1524)
				(type default)
			)
			(layer "F.SilkS")
		)
		(fp_line
			(start 0 3.175)
			(end 0 3.81)
			(stroke
				(width 0.1524)
				(type default)
			)
			(layer "F.SilkS")
		)
		(fp_line
			(start 2.54 3.81)
			(end 2.54 3.6703)
			(stroke
				(width 0.1524)
				(type default)
			)
			(layer "F.SilkS")
		)
		(fp_line
			(start 0 3.81)
			(end 2.54 3.81)
			(stroke
				(width 0.1524)
				(type default)
			)
			(layer "F.SilkS")
		)
		(fp_poly
			(pts
				(xy -0.761746 0) (xy -2.285746 0.762) (xy -2.285746 -0.762)
			)
			(stroke
				(width 0)
				(type default)
			)
			(fill yes)
			(layer "F.SilkS")
		)
		(fp_line
			(start 2.54 -1.27)
			(end 0 -1.27)
			(stroke
				(width 0.1)
				(type default)
			)
			(layer "F.Fab")
		)
		(fp_line
			(start 0 -1.27)
			(end 0 3.81)
			(stroke
				(width 0.1)
				(type default)
			)
			(layer "F.Fab")
		)
		(fp_line
			(start 2.54 3.81)
			(end 2.54 -1.27)
			(stroke
				(width 0.1)
				(type default)
			)
			(layer "F.Fab")
		)
		(fp_line
			(start 0 3.81)
			(end 2.54 3.81)
			(stroke
				(width 0.1)
				(type default)
			)
			(layer "F.Fab")
		)
		(fp_poly
			(pts
				(xy -0.761746 0) (xy -2.285746 -0.762) (xy -2.285746 0.762)
			)
			(stroke
				(width 0)
				(type default)
			)
			(fill yes)
			(layer "F.Fab")
		)
		(pad "1" thru_hole circle
			(at 0 0 90)
			(size 1.0033 1.0033)
			(drill 0.249936)
			(layers "*.Cu" "*.Mask")
			(remove_unused_layers no)
			(net "TDR_DIFF_80_IN1_DN")
			(clearance 0.10795)
			(thermal_gap 0.10795)
			(padstack
				(mode front_inner_back)
				(layer "Inner"
					(shape circle)
					(size 0.8001 0.8001)
					(clearance 0.1524)
				)
				(layer "B.Cu"
					(shape circle)
					(size 1.0033 1.0033)
					(clearance 0.10795)
				)
			)
		)
		(pad "2" thru_hole circle
			(at 2.54 0 90)
			(size 1.9939 1.9939)
			(drill 0.249936)
			(layers "*.Cu" "*.Mask")
			(remove_unused_layers no)
			(net "T1_GND")
			(clearance 0.10795)
			(thermal_gap 0.10795)
			(padstack
				(mode front_inner_back)
				(layer "Inner"
					(shape circle)
					(size 0.8001 0.8001)
					(clearance 0.1524)
				)
				(layer "B.Cu"
					(shape circle)
					(size 1.9939 1.9939)
					(clearance 0.10795)
				)
			)
		)
		(pad "3" thru_hole circle
			(at 2.54 2.54 90)
			(size 1.9939 1.9939)
			(drill 0.249936)
			(layers "*.Cu" "*.Mask")
			(remove_unused_layers no)
			(net "T1_GND")
			(clearance 0.10795)
			(thermal_gap 0.10795)
			(padstack
				(mode front_inner_back)
				(layer "Inner"
					(shape circle)
					(size 0.8001 0.8001)
					(clearance 0.1524)
				)
				(layer "B.Cu"
					(shape circle)
					(size 1.9939 1.9939)
					(clearance 0.10795)
				)
			)
		)
		(pad "4" thru_hole circle
			(at 0 2.54 90)
			(size 1.0033 1.0033)
			(drill 0.249936)
			(layers "*.Cu" "*.Mask")
			(remove_unused_layers no)
			(net "TDR_DIFF_80_IN1_DP")
			(clearance 0.10795)
			(thermal_gap 0.10795)
			(padstack
				(mode front_inner_back)
				(layer "Inner"
					(shape circle)
					(size 0.8001 0.8001)
					(clearance 0.1524)
				)
				(layer "B.Cu"
					(shape circle)
					(size 1.0033 1.0033)
					(clearance 0.10795)
				)
			)
		)
	)
	(footprint ""
		(layer "F.Cu")
		(at 120.68175 -25.545796)
		(property "Reference" "R6264"
			(at 0 0 0)
			(layer "F.SilkS")
			(hide yes)
			(effects
				(font
					(size 1.27 1.27)
				)
			)
		)
		(property "Value" ""
			(at 0 0 0)
			(layer "F.Fab")
			(effects
				(font
					(size 1.27 1.27)
				)
			)
		)
		(duplicate_pad_numbers_are_jumpers no)
		(fp_line
			(start -0.7874 -0.4064)
			(end 0.7874 -0.4064)
			(stroke
				(width 0.1524)
				(type default)
			)
			(layer "F.SilkS")
		)
		(fp_line
			(start -0.7874 0.4064)
			(end -0.7874 -0.4064)
			(stroke
				(width 0.1524)
				(type default)
			)
			(layer "F.SilkS")
		)
		(fp_line
			(start 0.7874 -0.4064)
			(end 0.7874 0.4064)
			(stroke
				(width 0.1524)
				(type default)
			)
			(layer "F.SilkS")
		)
		(fp_line
			(start 0.7874 0.4064)
			(end -0.7874 0.4064)
			(stroke
				(width 0.1524)
				(type default)
			)
			(layer "F.SilkS")
		)
		(fp_line
			(start -0.67945 -0.305054)
			(end -0.12065 -0.305054)
			(stroke
				(width 0.1)
				(type default)
			)
			(layer "F.Fab")
		)
		(fp_line
			(start -0.67945 0.3048)
			(end -0.67945 -0.305054)
			(stroke
				(width 0.1)
				(type default)
			)
			(layer "F.Fab")
		)
		(fp_line
			(start -0.12065 -0.305054)
			(end -0.12065 -0.2794)
			(stroke
				(width 0.1)
				(type default)
			)
			(layer "F.Fab")
		)
		(fp_line
			(start -0.12065 -0.2794)
			(end 0.12065 -0.2794)
			(stroke
				(width 0.1)
				(type default)
			)
			(layer "F.Fab")
		)
		(fp_line
			(start -0.12065 0.2794)
			(end -0.12065 0.3048)
			(stroke
				(width 0.1)
				(type default)
			)
			(layer "F.Fab")
		)
		(fp_line
			(start -0.12065 0.3048)
			(end -0.67945 0.3048)
			(stroke
				(width 0.1)
				(type default)
			)
			(layer "F.Fab")
		)
		(fp_line
			(start 0.120396 0.2794)
			(end -0.12065 0.2794)
			(stroke
				(width 0.1)
				(type default)
			)
			(layer "F.Fab")
		)
		(fp_line
			(start 0.120396 0.3048)
			(end 0.120396 0.2794)
			(stroke
				(width 0.1)
				(type default)
			)
			(layer "F.Fab")
		)
		(fp_line
			(start 0.12065 -0.3048)
			(end 0.67945 -0.3048)
			(stroke
				(width 0.1)
				(type default)
			)
			(layer "F.Fab")
		)
		(fp_line
			(start 0.12065 -0.2794)
			(end 0.12065 -0.3048)
			(stroke
				(width 0.1)
				(type default)
			)
			(layer "F.Fab")
		)
		(fp_line
			(start 0.67945 -0.3048)
			(end 0.67945 0.3048)
			(stroke
				(width 0.1)
				(type default)
			)
			(layer "F.Fab")
		)
		(fp_line
			(start 0.67945 0.3048)
			(end 0.120396 0.3048)
			(stroke
				(width 0.1)
				(type default)
			)
			(layer "F.Fab")
		)
		(pad "1" smd circle
			(at -0.40005 0)
			(size 0 0)
			(layers "F.Cu" "F.Mask" "F.Paste")
			(net "USB_HUB2_TI_USB_DM_DN3_MRP_VDD33")
		)
		(pad "2" smd circle
			(at 0.40005 0)
			(size 0 0)
			(layers "F.Cu" "F.Mask" "F.Paste")
			(net "P3V3_AUX_CPU0_USB2_AVDD33")
		)
	)
	(footprint ""
		(layer "F.Cu")
		(at 163.178744 -344.153998 -90)
		(property "Reference" "PR407"
			(at 0 0 270)
			(layer "F.SilkS")
			(hide yes)
			(effects
				(font
					(size 1.27 1.27)
				)
			)
		)
		(property "Value" ""
			(at 0 0 270)
			(layer "F.Fab")
			(effects
				(font
					(size 1.27 1.27)
				)
			)
		)
		(duplicate_pad_numbers_are_jumpers no)
		(fp_line
			(start -0.7874 0.4064)
			(end -0.7874 -0.4064)
			(stroke
				(width 0.1524)
				(type default)
			)
			(layer "F.SilkS")
		)
		(fp_line
			(start 0.7874 0.4064)
			(end -0.7874 0.4064)
			(stroke
				(width 0.1524)
				(type default)
			)
			(layer "F.SilkS")
		)
		(fp_line
			(start -0.7874 -0.4064)
			(end 0.7874 -0.4064)
			(stroke
				(width 0.1524)
				(type default)
			)
			(layer "F.SilkS")
		)
		(fp_line
			(start 0.7874 -0.4064)
			(end 0.7874 0.4064)
			(stroke
				(width 0.1524)
				(type default)
			)
			(layer "F.SilkS")
		)
		(fp_line
			(start -0.67945 0.3048)
			(end -0.67945 -0.305054)
			(stroke
				(width 0.1)
				(type default)
			)
			(layer "F.Fab")
		)
		(fp_line
			(start -0.12065 0.3048)
			(end -0.67945 0.3048)
			(stroke
				(width 0.1)
				(type default)
			)
			(layer "F.Fab")
		)
		(fp_line
			(start 0.120396 0.3048)
			(end 0.120396 0.2794)
			(stroke
				(width 0.1)
				(type default)
			)
			(layer "F.Fab")
		)
		(fp_line
			(start 0.67945 0.3048)
			(end 0.120396 0.3048)
			(stroke
				(width 0.1)
				(type default)
			)
			(layer "F.Fab")
		)
		(fp_line
			(start -0.12065 0.2794)
			(end -0.12065 0.3048)
			(stroke
				(width 0.1)
				(type default)
			)
			(layer "F.Fab")
		)
		(fp_line
			(start 0.120396 0.2794)
			(end -0.12065 0.2794)
			(stroke
				(width 0.1)
				(type default)
			)
			(layer "F.Fab")
		)
		(fp_line
			(start -0.12065 -0.2794)
			(end 0.12065 -0.2794)
			(stroke
				(width 0.1)
				(type default)
			)
			(layer "F.Fab")
		)
		(fp_line
			(start 0.12065 -0.2794)
			(end 0.12065 -0.3048)
			(stroke
				(width 0.1)
				(type default)
			)
			(layer "F.Fab")
		)
		(fp_line
			(start 0.12065 -0.3048)
			(end 0.67945 -0.3048)
			(stroke
				(width 0.1)
				(type default)
			)
			(layer "F.Fab")
		)
		(fp_line
			(start 0.67945 -0.3048)
			(end 0.67945 0.3048)
			(stroke
				(width 0.1)
				(type default)
			)
			(layer "F.Fab")
		)
		(fp_line
			(start -0.67945 -0.305054)
			(end -0.12065 -0.305054)
			(stroke
				(width 0.1)
				(type default)
			)
			(layer "F.Fab")
		)
		(fp_line
			(start -0.12065 -0.305054)
			(end -0.12065 -0.2794)
			(stroke
				(width 0.1)
				(type default)
			)
			(layer "F.Fab")
		)
		(pad "1" smd circle
			(at -0.40005 0 270)
			(size 0 0)
			(layers "F.Cu" "F.Mask" "F.Paste")
			(net "NC_PVDD11_S3_P1_IMON4")
		)
		(pad "2" smd circle
			(at 0.40005 0 270)
			(size 0 0)
			(layers "F.Cu" "F.Mask" "F.Paste")
			(net "GND")
		)
	)
	(footprint ""
		(layer "F.Cu")
		(at 423.779696 -357.688134 -90)
		(property "Reference" "PR36"
			(at 0 0 270)
			(layer "F.SilkS")
			(hide yes)
			(effects
				(font
					(size 1.27 1.27)
				)
			)
		)
		(property "Value" ""
			(at 0 0 270)
			(layer "F.Fab")
			(effects
				(font
					(size 1.27 1.27)
				)
			)
		)
		(duplicate_pad_numbers_are_jumpers no)
		(fp_line
			(start -0.7874 0.4064)
			(end -0.7874 -0.4064)
			(stroke
				(width 0.1524)
				(type default)
			)
			(layer "F.SilkS")
		)
		(fp_line
			(start 0.7874 0.4064)
			(end -0.7874 0.4064)
			(stroke
				(width 0.1524)
				(type default)
			)
			(layer "F.SilkS")
		)
		(fp_line
			(start -0.7874 -0.4064)
			(end 0.7874 -0.4064)
			(stroke
				(width 0.1524)
				(type default)
			)
			(layer "F.SilkS")
		)
		(fp_line
			(start 0.7874 -0.4064)
			(end 0.7874 0.4064)
			(stroke
				(width 0.1524)
				(type default)
			)
			(layer "F.SilkS")
		)
		(fp_line
			(start -0.67945 0.3048)
			(end -0.67945 -0.305054)
			(stroke
				(width 0.1)
				(type default)
			)
			(layer "F.Fab")
		)
		(fp_line
			(start -0.12065 0.3048)
			(end -0.67945 0.3048)
			(stroke
				(width 0.1)
				(type default)
			)
			(layer "F.Fab")
		)
		(fp_line
			(start 0.120396 0.3048)
			(end 0.120396 0.2794)
			(stroke
				(width 0.1)
				(type default)
			)
			(layer "F.Fab")
		)
		(fp_line
			(start 0.67945 0.3048)
			(end 0.120396 0.3048)
			(stroke
				(width 0.1)
				(type default)
			)
			(layer "F.Fab")
		)
		(fp_line
			(start -0.12065 0.2794)
			(end -0.12065 0.3048)
			(stroke
				(width 0.1)
				(type default)
			)
			(layer "F.Fab")
		)
		(fp_line
			(start 0.120396 0.2794)
			(end -0.12065 0.2794)
			(stroke
				(width 0.1)
				(type default)
			)
			(layer "F.Fab")
		)
		(fp_line
			(start -0.12065 -0.2794)
			(end 0.12065 -0.2794)
			(stroke
				(width 0.1)
				(type default)
			)
			(layer "F.Fab")
		)
		(fp_line
			(start 0.12065 -0.2794)
			(end 0.12065 -0.3048)
			(stroke
				(width 0.1)
				(type default)
			)
			(layer "F.Fab")
		)
		(fp_line
			(start 0.12065 -0.3048)
			(end 0.67945 -0.3048)
			(stroke
				(width 0.1)
				(type default)
			)
			(layer "F.Fab")
		)
		(fp_line
			(start 0.67945 -0.3048)
			(end 0.67945 0.3048)
			(stroke
				(width 0.1)
				(type default)
			)
			(layer "F.Fab")
		)
		(fp_line
			(start -0.67945 -0.305054)
			(end -0.12065 -0.305054)
			(stroke
				(width 0.1)
				(type default)
			)
			(layer "F.Fab")
		)
		(fp_line
			(start -0.12065 -0.305054)
			(end -0.12065 -0.2794)
			(stroke
				(width 0.1)
				(type default)
			)
			(layer "F.Fab")
		)
		(pad "1" smd circle
			(at -0.40005 0 270)
			(size 0 0)
			(layers "F.Cu" "F.Mask" "F.Paste")
			(net "NC_PVDD11_S3_P0_IMON8")
		)
		(pad "2" smd circle
			(at 0.40005 0 270)
			(size 0 0)
			(layers "F.Cu" "F.Mask" "F.Paste")
			(net "GND")
		)
	)
	(footprint ""
		(layer "F.Cu")
		(at 281.827732 -392.705844 90)
		(property "Reference" "R355"
			(at 0 0 90)
			(layer "F.SilkS")
			(hide yes)
			(effects
				(font
					(size 1.27 1.27)
				)
			)
		)
		(property "Value" ""
			(at 0 0 90)
			(layer "F.Fab")
			(effects
				(font
					(size 1.27 1.27)
				)
			)
		)
		(duplicate_pad_numbers_are_jumpers no)
		(fp_line
			(start 0.7874 -0.4064)
			(end 0.7874 0.4064)
			(stroke
				(width 0.1524)
				(type default)
			)
			(layer "F.SilkS")
		)
		(fp_line
			(start -0.7874 -0.4064)
			(end 0.7874 -0.4064)
			(stroke
				(width 0.1524)
				(type default)
			)
			(layer "F.SilkS")
		)
		(fp_line
			(start 0.7874 0.4064)
			(end -0.7874 0.4064)
			(stroke
				(width 0.1524)
				(type default)
			)
			(layer "F.SilkS")
		)
		(fp_line
			(start -0.7874 0.4064)
			(end -0.7874 -0.4064)
			(stroke
				(width 0.1524)
				(type default)
			)
			(layer "F.SilkS")
		)
		(fp_line
			(start -0.12065 -0.305054)
			(end -0.12065 -0.2794)
			(stroke
				(width 0.1)
				(type default)
			)
			(layer "F.Fab")
		)
		(fp_line
			(start -0.67945 -0.305054)
			(end -0.12065 -0.305054)
			(stroke
				(width 0.1)
				(type default)
			)
			(layer "F.Fab")
		)
		(fp_line
			(start 0.67945 -0.3048)
			(end 0.67945 0.3048)
			(stroke
				(width 0.1)
				(type default)
			)
			(layer "F.Fab")
		)
		(fp_line
			(start 0.12065 -0.3048)
			(end 0.67945 -0.3048)
			(stroke
				(width 0.1)
				(type default)
			)
			(layer "F.Fab")
		)
		(fp_line
			(start 0.12065 -0.2794)
			(end 0.12065 -0.3048)
			(stroke
				(width 0.1)
				(type default)
			)
			(layer "F.Fab")
		)
		(fp_line
			(start -0.12065 -0.2794)
			(end 0.12065 -0.2794)
			(stroke
				(width 0.1)
				(type default)
			)
			(layer "F.Fab")
		)
		(fp_line
			(start 0.120396 0.2794)
			(end -0.12065 0.2794)
			(stroke
				(width 0.1)
				(type default)
			)
			(layer "F.Fab")
		)
		(fp_line
			(start -0.12065 0.2794)
			(end -0.12065 0.3048)
			(stroke
				(width 0.1)
				(type default)
			)
			(layer "F.Fab")
		)
		(fp_line
			(start 0.67945 0.3048)
			(end 0.120396 0.3048)
			(stroke
				(width 0.1)
				(type default)
			)
			(layer "F.Fab")
		)
		(fp_line
			(start 0.120396 0.3048)
			(end 0.120396 0.2794)
			(stroke
				(width 0.1)
				(type default)
			)
			(layer "F.Fab")
		)
		(fp_line
			(start -0.12065 0.3048)
			(end -0.67945 0.3048)
			(stroke
				(width 0.1)
				(type default)
			)
			(layer "F.Fab")
		)
		(fp_line
			(start -0.67945 0.3048)
			(end -0.67945 -0.305054)
			(stroke
				(width 0.1)
				(type default)
			)
			(layer "F.Fab")
		)
		(pad "1" smd circle
			(at -0.40005 0 90)
			(size 0 0)
			(layers "F.Cu" "F.Mask" "F.Paste")
			(net "P3V3_AUX")
		)
		(pad "2" smd circle
			(at 0.40005 0 90)
			(size 0 0)
			(layers "F.Cu" "F.Mask" "F.Paste")
			(net "P12V_HSC_TEMP_ALERT_R_N")
		)
	)
	(footprint ""
		(layer "F.Cu")
		(at 69.431154 -370.57203 -90)
		(property "Reference" "C811"
			(at 0 0 270)
			(layer "F.SilkS")
			(hide yes)
			(effects
				(font
					(size 1.27 1.27)
				)
			)
		)
		(property "Value" ""
			(at 0 0 270)
			(layer "F.Fab")
			(effects
				(font
					(size 1.27 1.27)
				)
			)
		)
		(duplicate_pad_numbers_are_jumpers no)
		(fp_line
			(start -0.299974 0.150114)
			(end -0.299974 -0.150114)
			(stroke
				(width 0.1)
				(type default)
			)
			(layer "F.Fab")
		)
		(fp_line
			(start 0.299974 0.150114)
			(end -0.299974 0.150114)
			(stroke
				(width 0.1)
				(type default)
			)
			(layer "F.Fab")
		)
		(fp_line
			(start -0.299974 -0.150114)
			(end 0.299974 -0.150114)
			(stroke
				(width 0.1)
				(type default)
			)
			(layer "F.Fab")
		)
		(fp_line
			(start 0.299974 -0.150114)
			(end 0.299974 0.150114)
			(stroke
				(width 0.1)
				(type default)
			)
			(layer "F.Fab")
		)
		(pad "1" smd rect
			(at -0.2667 0 270)
			(size 0.3048 0.381)
			(layers "F.Cu" "F.Mask" "F.Paste")
			(net "P5E_CPU1_P0_TX_C_DP<13>")
		)
		(pad "2" smd rect
			(at 0.2667 0 270)
			(size 0.3048 0.381)
			(layers "F.Cu" "F.Mask" "F.Paste")
			(net "P5E_CPU1_P0_TX_DP<13>")
		)
	)
	(footprint ""
		(layer "F.Cu")
		(at 16.56207 -388.854188)
		(property "Reference" "PU6511"
			(at -5.86232 -8.184642 0)
			(unlocked yes)
			(layer "F.SilkS")
			(effects
				(font
					(size 0.7874 0.5842)
					(thickness 0.1524)
				)
				(justify left)
			)
		)
		(property "Value" ""
			(at 0 0 0)
			(layer "F.Fab")
			(effects
				(font
					(size 1.27 1.27)
				)
			)
		)
		(duplicate_pad_numbers_are_jumpers no)
		(fp_line
			(start -2.500122 -2.999994)
			(end -2.24409 -2.999994)
			(stroke
				(width 0.1524)
				(type default)
			)
			(layer "F.SilkS")
		)
		(fp_line
			(start -2.500122 -2.529078)
			(end -2.500122 -2.999994)
			(stroke
				(width 0.1524)
				(type default)
			)
			(layer "F.SilkS")
		)
		(fp_line
			(start -2.500122 0.6604)
			(end -2.500122 0.229108)
			(stroke
				(width 0.1524)
				(type default)
			)
			(layer "F.SilkS")
		)
		(fp_line
			(start -2.500122 2.999994)
			(end -2.500122 2.339594)
			(stroke
				(width 0.1524)
				(type default)
			)
			(layer "F.SilkS")
		)
		(fp_line
			(start -2.2987 2.999994)
			(end -2.500122 2.999994)
			(stroke
				(width 0.1524)
				(type default)
			)
			(layer "F.SilkS")
		)
		(fp_line
			(start 2.31394 -2.999994)
			(end 2.500122 -2.999994)
			(stroke
				(width 0.1524)
				(type default)
			)
			(layer "F.SilkS")
		)
		(fp_line
			(start 2.500122 -2.999994)
			(end 2.500122 -2.44348)
			(stroke
				(width 0.1524)
				(type default)
			)
			(layer "F.SilkS")
		)
		(fp_line
			(start 2.500122 2.339594)
			(end 2.500122 2.999994)
			(stroke
				(width 0.1524)
				(type default)
			)
			(layer "F.SilkS")
		)
		(fp_line
			(start 2.500122 2.999994)
			(end 2.2987 2.999994)
			(stroke
				(width 0.1524)
				(type default)
			)
			(layer "F.SilkS")
		)
		(fp_poly
			(pts
				(xy -3.721862 -2.76352) (xy -2.77876 -2.450338) (xy -3.09372 -3.391662)
			)
			(stroke
				(width 0)
				(type default)
			)
			(fill yes)
			(layer "F.SilkS")
		)
		(fp_line
			(start -2.500122 -2.999994)
			(end 2.500122 -2.999994)
			(stroke
				(width 0.1)
				(type default)
			)
			(layer "F.Fab")
		)
		(fp_line
			(start -2.500122 2.999994)
			(end -2.500122 -2.999994)
			(stroke
				(width 0.1)
				(type default)
			)
			(layer "F.Fab")
		)
		(fp_line
			(start 2.500122 -2.999994)
			(end 2.500122 2.999994)
			(stroke
				(width 0.1)
				(type default)
			)
			(layer "F.Fab")
		)
		(fp_line
			(start 2.500122 2.999994)
			(end -2.500122 2.999994)
			(stroke
				(width 0.1)
				(type default)
			)
			(layer "F.Fab")
		)
		(fp_poly
			(pts
				(xy -4.218432 -2.783078) (xy -4.218432 -1.767078) (xy -3.202432 -2.275078)
			)
			(stroke
				(width 0)
				(type default)
			)
			(fill yes)
			(layer "F.Fab")
		)
		(pad "1" smd rect
			(at -2.400046 -2.275078 90)
			(size 0.2286 0.6096)
			(layers "F.Cu" "F.Mask" "F.Paste")
			(net "P0V9_RETIMER_CPU1_VOS1")
		)
		(pad "2" smd rect
			(at -2.400046 -1.82499 90)
			(size 0.2286 0.6096)
			(layers "F.Cu" "F.Mask" "F.Paste")
			(net "GND")
		)
		(pad "3" smd rect
			(at -2.400046 -1.374902 90)
			(size 0.2286 0.6096)
			(layers "F.Cu" "F.Mask" "F.Paste")
			(net "P0V9_RETIMER_CPU1_VCC1")
		)
		(pad "4" smd rect
			(at -2.400046 -0.925068 90)
			(size 0.2286 0.6096)
			(layers "F.Cu" "F.Mask" "F.Paste")
			(net "P0V9_RETIMER_CPU1_PVCC")
		)
		(pad "5" smd rect
			(at -2.400046 -0.47498 90)
			(size 0.2286 0.6096)
			(layers "F.Cu" "F.Mask" "F.Paste")
			(net "GND")
		)
		(pad "6" smd rect
			(at -2.400046 -0.024892 90)
			(size 0.2286 0.6096)
			(layers "F.Cu" "F.Mask" "F.Paste")
			(net "NC_PV09_RETIMER_CPU1_GL1_1")
		)
		(pad "7_9-20_24" smd circle
			(at 0 1.150112 90)
			(size 0 0)
			(layers "F.Cu" "F.Mask" "F.Paste")
			(net "GND")
		)
		(pad "10_19" smd rect
			(at 0 2.899918 90)
			(size 0.6096 4.318)
			(layers "F.Cu" "F.Mask" "F.Paste")
			(net "SW_P0V9_RETIMER_CPU1_SW1")
		)
		(pad "25_29" smd rect
			(at 1.549908 -1.279906 270)
			(size 2.0574 2.3114)
			(layers "F.Cu" "F.Mask" "F.Paste")
			(net "SW_P12V_AUX_P0V9_RETIMER_CPU1_FLT")
		)
		(pad "30" smd rect
			(at 2.05994 -2.899918)
			(size 0.2286 0.6096)
			(layers "F.Cu" "F.Mask" "F.Paste")
			(net "SW_P12V_AUX_P0V9_RETIMER_CPU1_FLT")
		)
		(pad "31" smd rect
			(at 1.610106 -2.899918)
			(size 0.2286 0.6096)
			(layers "F.Cu" "F.Mask" "F.Paste")
			(net "NC_PV09_RETIMER_CPU1_DNC1")
		)
		(pad "32" smd rect
			(at 1.160018 -2.899918)
			(size 0.2286 0.6096)
			(layers "F.Cu" "F.Mask" "F.Paste")
			(net "SW_P0V9_RETIMER_CPU1_PH1")
		)
		(pad "33" smd rect
			(at 0.70993 -2.899918)
			(size 0.2286 0.6096)
			(layers "F.Cu" "F.Mask" "F.Paste")
			(net "SW_P0V9_RETIMER_CPU1_BOOT1")
		)
		(pad "34" smd rect
			(at 0.260096 -2.899918)
			(size 0.2286 0.6096)
			(layers "F.Cu" "F.Mask" "F.Paste")
			(net "P0V9_RETIMER_CPU1_PWM1")
		)
		(pad "35" smd rect
			(at -0.189992 -2.899918)
			(size 0.2286 0.6096)
			(layers "F.Cu" "F.Mask" "F.Paste")
			(net "P0V9_RETIMER_CPU1_VCC1")
		)
		(pad "36" smd rect
			(at -0.64008 -2.899918)
			(size 0.2286 0.6096)
			(layers "F.Cu" "F.Mask" "F.Paste")
			(net "P0V9_RETIMER_CPU1_TEMP0")
		)
		(pad "37" smd rect
			(at -1.089914 -2.899918)
			(size 0.2286 0.6096)
			(layers "F.Cu" "F.Mask" "F.Paste")
			(net "P0V9_RETIMER_CPU1_LSET1")
		)
		(pad "38" smd rect
			(at -1.540002 -2.899918)
			(size 0.2286 0.6096)
			(layers "F.Cu" "F.Mask" "F.Paste")
			(net "P0V9_RETIMER_CPU1_IMON1")
		)
		(pad "39" smd rect
			(at -1.99009 -2.899918)
			(size 0.2286 0.6096)
			(layers "F.Cu" "F.Mask" "F.Paste")
			(net "PV09_RETIMER_CPU1_VCCS")
		)
		(pad "40" smd rect
			(at -0.87503 -1.27508)
			(size 1.7526 1.9558)
			(layers "F.Cu" "F.Mask" "F.Paste")
			(net "GND")
		)
		(pad "41" smd rect
			(at -1.525016 0.249936 270)
			(size 0.3048 0.4572)
			(layers "F.Cu" "F.Mask" "F.Paste")
			(net "NC_PV09_RETIMER_CPU1_GL2_1")
		)
		(zone
			(layer "F.Cu")
			(hatch none 0.5)
			(connect_pads
				(clearance 0)
			)
			(min_thickness 0.25)
			(keepout
				(tracks not_allowed)
				(vias allowed)
				(pads allowed)
				(copperpour not_allowed)
				(footprints allowed)
			)
			(placement
				(enabled no)
				(sheetname "")
			)
			(fill
				(thermal_gap 0.5)
				(thermal_bridge_width 0.5)
				(island_removal_mode 0)
			)
			(polygon
				(pts
					(xy 14.061948 -385.854194) (xy 14.061948 -386.603494) (xy 19.062192 -386.603494) (xy 19.062192 -385.854194)
					(xy 18.77187 -385.854194) (xy 18.77187 -386.30987) (xy 14.35227 -386.30987) (xy 14.35227 -385.854194)
				)
			)
		)
		(zone
			(layer "F.Cu")
			(hatch none 0.5)
			(connect_pads
				(clearance 0)
			)
			(min_thickness 0.25)
			(keepout
				(tracks not_allowed)
				(vias allowed)
				(pads allowed)
				(copperpour not_allowed)
				(footprints allowed)
			)
			(placement
				(enabled no)
				(sheetname "")
			)
			(fill
				(thermal_gap 0.5)
				(thermal_bridge_width 0.5)
				(island_removal_mode 0)
			)
			(polygon
				(pts
					(xy 14.061948 -388.104888) (xy 14.061948 -388.56158) (xy 14.757654 -388.56158) (xy 14.757654 -388.401052)
					(xy 15.316454 -388.401052) (xy 15.316454 -388.807452) (xy 14.757654 -388.807452) (xy 14.757654 -388.58698)
					(xy 14.061948 -388.58698) (xy 14.061948 -388.71398) (xy 14.517624 -388.71398) (xy 14.517624 -390.891522)
					(xy 14.75994 -390.891522) (xy 14.75994 -389.100568) (xy 16.61414 -389.100568) (xy 16.61414 -391.157968)
					(xy 14.75994 -391.157968) (xy 14.75994 -390.916922) (xy 14.517624 -390.916922) (xy 14.517624 -391.398506)
					(xy 19.062192 -391.398506) (xy 19.062192 -391.213594) (xy 16.905478 -391.213594) (xy 16.905478 -389.054594)
					(xy 19.062192 -389.054594) (xy 19.062192 -388.804912) (xy 15.611348 -388.804912) (xy 15.611348 -388.104888)
				)
			)
		)
	)
	(footprint ""
		(layer "F.Cu")
		(at 17.467072 -393.394184 90)
		(property "Reference" "PR6623"
			(at 0 0 90)
			(layer "F.SilkS")
			(hide yes)
			(effects
				(font
					(size 1.27 1.27)
				)
			)
		)
		(property "Value" ""
			(at 0 0 90)
			(layer "F.Fab")
			(effects
				(font
					(size 1.27 1.27)
				)
			)
		)
		(duplicate_pad_numbers_are_jumpers no)
		(fp_line
			(start 0.7874 -0.4064)
			(end 0.7874 0.4064)
			(stroke
				(width 0.1524)
				(type default)
			)
			(layer "F.SilkS")
		)
		(fp_line
			(start -0.7874 -0.4064)
			(end 0.7874 -0.4064)
			(stroke
				(width 0.1524)
				(type default)
			)
			(layer "F.SilkS")
		)
		(fp_line
			(start 0.7874 0.4064)
			(end -0.7874 0.4064)
			(stroke
				(width 0.1524)
				(type default)
			)
			(layer "F.SilkS")
		)
		(fp_line
			(start -0.7874 0.4064)
			(end -0.7874 -0.4064)
			(stroke
				(width 0.1524)
				(type default)
			)
			(layer "F.SilkS")
		)
		(fp_line
			(start -0.12065 -0.305054)
			(end -0.12065 -0.2794)
			(stroke
				(width 0.1)
				(type default)
			)
			(layer "F.Fab")
		)
		(fp_line
			(start -0.67945 -0.305054)
			(end -0.12065 -0.305054)
			(stroke
				(width 0.1)
				(type default)
			)
			(layer "F.Fab")
		)
		(fp_line
			(start 0.67945 -0.3048)
			(end 0.67945 0.3048)
			(stroke
				(width 0.1)
				(type default)
			)
			(layer "F.Fab")
		)
		(fp_line
			(start 0.12065 -0.3048)
			(end 0.67945 -0.3048)
			(stroke
				(width 0.1)
				(type default)
			)
			(layer "F.Fab")
		)
		(fp_line
			(start 0.12065 -0.2794)
			(end 0.12065 -0.3048)
			(stroke
				(width 0.1)
				(type default)
			)
			(layer "F.Fab")
		)
		(fp_line
			(start -0.12065 -0.2794)
			(end 0.12065 -0.2794)
			(stroke
				(width 0.1)
				(type default)
			)
			(layer "F.Fab")
		)
		(fp_line
			(start 0.120396 0.2794)
			(end -0.12065 0.2794)
			(stroke
				(width 0.1)
				(type default)
			)
			(layer "F.Fab")
		)
		(fp_line
			(start -0.12065 0.2794)
			(end -0.12065 0.3048)
			(stroke
				(width 0.1)
				(type default)
			)
			(layer "F.Fab")
		)
		(fp_line
			(start 0.67945 0.3048)
			(end 0.120396 0.3048)
			(stroke
				(width 0.1)
				(type default)
			)
			(layer "F.Fab")
		)
		(fp_line
			(start 0.120396 0.3048)
			(end 0.120396 0.2794)
			(stroke
				(width 0.1)
				(type default)
			)
			(layer "F.Fab")
		)
		(fp_line
			(start -0.12065 0.3048)
			(end -0.67945 0.3048)
			(stroke
				(width 0.1)
				(type default)
			)
			(layer "F.Fab")
		)
		(fp_line
			(start -0.67945 0.3048)
			(end -0.67945 -0.305054)
			(stroke
				(width 0.1)
				(type default)
			)
			(layer "F.Fab")
		)
		(pad "1" smd circle
			(at -0.40005 0 90)
			(size 0 0)
			(layers "F.Cu" "F.Mask" "F.Paste")
			(net "SW_P0V9_RETIMER_CPU1_BOOT1")
		)
		(pad "2" smd circle
			(at 0.40005 0 90)
			(size 0 0)
			(layers "F.Cu" "F.Mask" "F.Paste")
			(net "SW_P0V9_RETIMER_CPU1_BOOT1_RC")
		)
	)
	(footprint ""
		(layer "F.Cu")
		(at 37.220906 19.444716 -90)
		(property "Reference" "U25_SRM"
			(at 0 0 270)
			(layer "F.SilkS")
			(hide yes)
			(effects
				(font
					(size 1.27 1.27)
				)
			)
		)
		(property "Value" ""
			(at 0 0 270)
			(layer "F.Fab")
			(effects
				(font
					(size 1.27 1.27)
				)
			)
		)
		(duplicate_pad_numbers_are_jumpers no)
		(pad "1" smd circle
			(at 0 0 270)
			(size 0.762 0.762)
			(layers "F.Cu" "F.Mask" "F.Paste")
			(net "Net_10788")
		)
	)
	(footprint ""
		(layer "F.Cu")
		(at 105.960164 -256.505456)
		(property "Reference" "C2667"
			(at 0 0 0)
			(layer "F.SilkS")
			(hide yes)
			(effects
				(font
					(size 1.27 1.27)
				)
			)
		)
		(property "Value" ""
			(at 0 0 0)
			(layer "F.Fab")
			(effects
				(font
					(size 1.27 1.27)
				)
			)
		)
		(duplicate_pad_numbers_are_jumpers no)
		(fp_line
			(start -0.7874 -0.4064)
			(end 0.7874 -0.4064)
			(stroke
				(width 0.1524)
				(type default)
			)
			(layer "F.SilkS")
		)
		(fp_line
			(start -0.7874 0.4064)
			(end -0.7874 -0.4064)
			(stroke
				(width 0.1524)
				(type default)
			)
			(layer "F.SilkS")
		)
		(fp_line
			(start 0.7874 -0.4064)
			(end 0.7874 0.4064)
			(stroke
				(width 0.1524)
				(type default)
			)
			(layer "F.SilkS")
		)
		(fp_line
			(start 0.7874 0.4064)
			(end -0.7874 0.4064)
			(stroke
				(width 0.1524)
				(type default)
			)
			(layer "F.SilkS")
		)
		(fp_line
			(start -0.67945 -0.305054)
			(end -0.12065 -0.305054)
			(stroke
				(width 0.1)
				(type default)
			)
			(layer "F.Fab")
		)
		(fp_line
			(start -0.67945 0.3048)
			(end -0.67945 -0.305054)
			(stroke
				(width 0.1)
				(type default)
			)
			(layer "F.Fab")
		)
		(fp_line
			(start -0.12065 -0.305054)
			(end -0.12065 -0.2794)
			(stroke
				(width 0.1)
				(type default)
			)
			(layer "F.Fab")
		)
		(fp_line
			(start -0.12065 -0.2794)
			(end 0.12065 -0.2794)
			(stroke
				(width 0.1)
				(type default)
			)
			(layer "F.Fab")
		)
		(fp_line
			(start -0.12065 0.2794)
			(end -0.12065 0.3048)
			(stroke
				(width 0.1)
				(type default)
			)
			(layer "F.Fab")
		)
		(fp_line
			(start -0.12065 0.3048)
			(end -0.67945 0.3048)
			(stroke
				(width 0.1)
				(type default)
			)
			(layer "F.Fab")
		)
		(fp_line
			(start 0.120396 0.2794)
			(end -0.12065 0.2794)
			(stroke
				(width 0.1)
				(type default)
			)
			(layer "F.Fab")
		)
		(fp_line
			(start 0.120396 0.3048)
			(end 0.120396 0.2794)
			(stroke
				(width 0.1)
				(type default)
			)
			(layer "F.Fab")
		)
		(fp_line
			(start 0.12065 -0.3048)
			(end 0.67945 -0.3048)
			(stroke
				(width 0.1)
				(type default)
			)
			(layer "F.Fab")
		)
		(fp_line
			(start 0.12065 -0.2794)
			(end 0.12065 -0.3048)
			(stroke
				(width 0.1)
				(type default)
			)
			(layer "F.Fab")
		)
		(fp_line
			(start 0.67945 -0.3048)
			(end 0.67945 0.3048)
			(stroke
				(width 0.1)
				(type default)
			)
			(layer "F.Fab")
		)
		(fp_line
			(start 0.67945 0.3048)
			(end 0.120396 0.3048)
			(stroke
				(width 0.1)
				(type default)
			)
			(layer "F.Fab")
		)
		(pad "1" smd circle
			(at -0.40005 0)
			(size 0 0)
			(layers "F.Cu" "F.Mask" "F.Paste")
			(net "PVDD18_S5_P1")
		)
		(pad "2" smd circle
			(at 0.40005 0)
			(size 0 0)
			(layers "F.Cu" "F.Mask" "F.Paste")
			(net "GND")
		)
	)
	(footprint ""
		(layer "F.Cu")
		(at 56.604154 -373.03583 -90)
		(property "Reference" "C821"
			(at 0 0 270)
			(layer "F.SilkS")
			(hide yes)
			(effects
				(font
					(size 1.27 1.27)
				)
			)
		)
		(property "Value" ""
			(at 0 0 270)
			(layer "F.Fab")
			(effects
				(font
					(size 1.27 1.27)
				)
			)
		)
		(duplicate_pad_numbers_are_jumpers no)
		(fp_line
			(start -0.299974 0.150114)
			(end -0.299974 -0.150114)
			(stroke
				(width 0.1)
				(type default)
			)
			(layer "F.Fab")
		)
		(fp_line
			(start 0.299974 0.150114)
			(end -0.299974 0.150114)
			(stroke
				(width 0.1)
				(type default)
			)
			(layer "F.Fab")
		)
		(fp_line
			(start -0.299974 -0.150114)
			(end 0.299974 -0.150114)
			(stroke
				(width 0.1)
				(type default)
			)
			(layer "F.Fab")
		)
		(fp_line
			(start 0.299974 -0.150114)
			(end 0.299974 0.150114)
			(stroke
				(width 0.1)
				(type default)
			)
			(layer "F.Fab")
		)
		(pad "1" smd rect
			(at -0.2667 0 270)
			(size 0.3048 0.381)
			(layers "F.Cu" "F.Mask" "F.Paste")
			(net "P5E_CPU1_P0_TX_C_DP<8>")
		)
		(pad "2" smd rect
			(at 0.2667 0 270)
			(size 0.3048 0.381)
			(layers "F.Cu" "F.Mask" "F.Paste")
			(net "P5E_CPU1_P0_TX_DP<8>")
		)
	)
	(footprint ""
		(layer "F.Cu")
		(at 204.64526 -51.999896)
		(property "Reference" "H113"
			(at -9.058656 -6.511544 0)
			(unlocked yes)
			(layer "F.SilkS")
			(effects
				(font
					(size 0.7874 0.5842)
					(thickness 0.1524)
				)
				(justify left)
			)
		)
		(property "Value" ""
			(at 0 0 0)
			(layer "F.Fab")
			(effects
				(font
					(size 1.27 1.27)
				)
			)
		)
		(duplicate_pad_numbers_are_jumpers no)
		(fp_circle
			(center 0 0)
			(end 7.999984 0)
			(stroke
				(width 0.1524)
				(type default)
			)
			(fill no)
			(layer "F.SilkS")
		)
		(fp_circle
			(center 0 0)
			(end 7.999984 0)
			(stroke
				(width 0.1524)
				(type default)
			)
			(fill no)
			(layer "B.SilkS")
		)
		(fp_circle
			(center 0 0)
			(end 7.999984 0)
			(stroke
				(width 0.1)
				(type default)
			)
			(fill no)
			(layer "B.Fab")
		)
		(fp_circle
			(center 0 0)
			(end 7.999984 0)
			(stroke
				(width 0.1)
				(type default)
			)
			(fill no)
			(layer "F.Fab")
		)
		(pad "" np_thru_hole circle
			(at 0 0)
			(size 5.5118 5.5118)
			(drill 5.5118)
			(layers "*.Cu" "*.Mask")
			(clearance 0.381)
			(thermal_gap 0.381)
		)
		(pad "2" thru_hole circle
			(at 0 -3.999992)
			(size 0.762 0.762)
			(drill 0.5588)
			(layers "*.Cu" "*.Mask")
			(remove_unused_layers no)
			(net "GND")
			(clearance 0.1524)
			(thermal_gap 0.1524)
		)
		(pad "3" thru_hole circle
			(at -2.999994 -2.500122)
			(size 0.762 0.762)
			(drill 0.5588)
			(layers "*.Cu" "*.Mask")
			(remove_unused_layers no)
			(net "GND")
			(clearance 0.1524)
			(thermal_gap 0.1524)
		)
		(pad "4" thru_hole circle
			(at -3.999992 0)
			(size 0.762 0.762)
			(drill 0.5588)
			(layers "*.Cu" "*.Mask")
			(remove_unused_layers no)
			(net "GND")
			(clearance 0.1524)
			(thermal_gap 0.1524)
		)
		(pad "5" thru_hole circle
			(at -2.999994 2.500122)
			(size 0.762 0.762)
			(drill 0.5588)
			(layers "*.Cu" "*.Mask")
			(remove_unused_layers no)
			(net "GND")
			(clearance 0.1524)
			(thermal_gap 0.1524)
		)
		(pad "6" thru_hole circle
			(at 0 3.999992)
			(size 0.762 0.762)
			(drill 0.5588)
			(layers "*.Cu" "*.Mask")
			(remove_unused_layers no)
			(net "GND")
			(clearance 0.1524)
			(thermal_gap 0.1524)
		)
		(pad "7" thru_hole circle
			(at 2.999994 2.500122)
			(size 0.762 0.762)
			(drill 0.5588)
			(layers "*.Cu" "*.Mask")
			(remove_unused_layers no)
			(net "GND")
			(clearance 0.1524)
			(thermal_gap 0.1524)
		)
		(pad "8" thru_hole circle
			(at 3.999992 0)
			(size 0.762 0.762)
			(drill 0.5588)
			(layers "*.Cu" "*.Mask")
			(remove_unused_layers no)
			(net "GND")
			(clearance 0.1524)
			(thermal_gap 0.1524)
		)
		(pad "9" thru_hole circle
			(at 2.999994 -2.500122)
			(size 0.762 0.762)
			(drill 0.5588)
			(layers "*.Cu" "*.Mask")
			(remove_unused_layers no)
			(net "GND")
			(clearance 0.1524)
			(thermal_gap 0.1524)
		)
		(zone
			(layer "F.Cu")
			(hatch none 0.5)
			(connect_pads
				(clearance 0)
			)
			(min_thickness 0.25)
			(keepout
				(tracks not_allowed)
				(vias allowed)
				(pads allowed)
				(copperpour not_allowed)
				(footprints allowed)
			)
			(placement
				(enabled no)
				(sheetname "")
			)
			(fill
				(thermal_gap 0.5)
				(thermal_bridge_width 0.5)
				(island_removal_mode 0)
			)
			(polygon
				(pts
					(arc
						(start 204.64526 -59.99988)
						(mid 198.988417 -57.656739)
						(end 196.645276 -51.999896)
					)
					(arc
						(start 196.645276 -51.999896)
						(mid 198.988417 -46.343053)
						(end 204.64526 -43.999912)
					)
					(xy 204.64526 -46.74616) (xy 204.594206 -46.74616)
					(arc
						(start 204.593952 -46.74616)
						(mid 199.391273 -51.999896)
						(end 204.593952 -57.253632)
					)
					(xy 204.594206 -57.253632) (xy 204.64526 -57.253632)
				)
			)
		)
		(zone
			(layer "F.Cu")
			(hatch none 0.5)
			(connect_pads
				(clearance 0)
			)
			(min_thickness 0.25)
			(keepout
				(tracks not_allowed)
				(vias allowed)
				(pads allowed)
				(copperpour not_allowed)
				(footprints allowed)
			)
			(placement
				(enabled no)
				(sheetname "")
			)
			(fill
				(thermal_gap 0.5)
				(thermal_bridge_width 0.5)
				(island_removal_mode 0)
			)
			(polygon
				(pts
					(arc
						(start 204.64526 -59.99988)
						(mid 210.302103 -57.656739)
						(end 212.645244 -51.999896)
					)
					(arc
						(start 212.645244 -51.999896)
						(mid 210.302103 -46.343053)
						(end 204.64526 -43.999912)
					)
					(xy 204.64526 -46.74616) (xy 204.696314 -46.74616)
					(arc
						(start 204.696568 -46.74616)
						(mid 209.899247 -51.999896)
						(end 204.696568 -57.253632)
					)
					(xy 204.696314 -57.253632) (xy 204.64526 -57.253632)
				)
			)
		)
		(zone
			(layers "F.Cu" "B.Cu" "In1.Cu" "In2.Cu" "In3.Cu" "In4.Cu" "In5.Cu" "In6.Cu"
				"In7.Cu" "In8.Cu" "In9.Cu" "In10.Cu" "In11.Cu" "In12.Cu" "In13.Cu" "In14.Cu"
				"In15.Cu" "In16.Cu"
			)
			(hatch none 0.5)
			(connect_pads
				(clearance 0)
			)
			(min_thickness 0.25)
			(keepout
				(tracks not_allowed)
				(vias allowed)
				(pads allowed)
				(copperpour not_allowed)
				(footprints allowed)
			)
			(placement
				(enabled no)
				(sheetname "")
			)
			(fill
				(thermal_gap 0.5)
				(thermal_bridge_width 0.5)
				(island_removal_mode 0)
			)
			(polygon
				(pts
					(arc
						(start 207.92186 -51.999896)
						(mid 201.36866 -51.999896)
						(end 207.92186 -51.999896)
					)
				)
			)
		)
		(zone
			(layer "B.Cu")
			(hatch none 0.5)
			(connect_pads
				(clearance 0)
			)
			(min_thickness 0.25)
			(keepout
				(tracks not_allowed)
				(vias allowed)
				(pads allowed)
				(copperpour not_allowed)
				(footprints allowed)
			)
			(placement
				(enabled no)
				(sheetname "")
			)
			(fill
				(thermal_gap 0.5)
				(thermal_bridge_width 0.5)
				(island_removal_mode 0)
			)
			(polygon
				(pts
					(arc
						(start 204.64526 -57.507886)
						(mid 199.13727 -51.999896)
						(end 204.64526 -46.491906)
					)
					(arc
						(start 204.64526 -46.974506)
						(mid 199.61987 -51.999896)
						(end 204.64526 -57.025286)
					)
				)
			)
		)
		(zone
			(layer "B.Cu")
			(hatch none 0.5)
			(connect_pads
				(clearance 0)
			)
			(min_thickness 0.25)
			(keepout
				(tracks not_allowed)
				(vias allowed)
				(pads allowed)
				(copperpour not_allowed)
				(footprints allowed)
			)
			(placement
				(enabled no)
				(sheetname "")
			)
			(fill
				(thermal_gap 0.5)
				(thermal_bridge_width 0.5)
				(island_removal_mode 0)
			)
			(polygon
				(pts
					(arc
						(start 204.64526 -57.507886)
						(mid 210.15325 -51.999896)
						(end 204.64526 -46.491906)
					)
					(arc
						(start 204.64526 -46.974506)
						(mid 209.67065 -51.999896)
						(end 204.64526 -57.025286)
					)
				)
			)
		)
	)
	(footprint ""
		(layer "F.Cu")
		(at 78.133702 -370.57203 -90)
		(property "Reference" "C734"
			(at 0 0 270)
			(layer "F.SilkS")
			(hide yes)
			(effects
				(font
					(size 1.27 1.27)
				)
			)
		)
		(property "Value" ""
			(at 0 0 270)
			(layer "F.Fab")
			(effects
				(font
					(size 1.27 1.27)
				)
			)
		)
		(duplicate_pad_numbers_are_jumpers no)
		(fp_line
			(start -0.299974 0.150114)
			(end -0.299974 -0.150114)
			(stroke
				(width 0.1)
				(type default)
			)
			(layer "F.Fab")
		)
		(fp_line
			(start 0.299974 0.150114)
			(end -0.299974 0.150114)
			(stroke
				(width 0.1)
				(type default)
			)
			(layer "F.Fab")
		)
		(fp_line
			(start -0.299974 -0.150114)
			(end 0.299974 -0.150114)
			(stroke
				(width 0.1)
				(type default)
			)
			(layer "F.Fab")
		)
		(fp_line
			(start 0.299974 -0.150114)
			(end 0.299974 0.150114)
			(stroke
				(width 0.1)
				(type default)
			)
			(layer "F.Fab")
		)
		(pad "1" smd rect
			(at -0.2667 0 270)
			(size 0.3048 0.381)
			(layers "F.Cu" "F.Mask" "F.Paste")
			(net "P5E_CPU1_P1_TX_C_DN<3>")
		)
		(pad "2" smd rect
			(at 0.2667 0 270)
			(size 0.3048 0.381)
			(layers "F.Cu" "F.Mask" "F.Paste")
			(net "P5E_CPU1_P1_TX_DN<3>")
		)
	)
	(footprint ""
		(layer "F.Cu")
		(at 69.862446 -384.10388 180)
		(property "Reference" "R6703"
			(at 0 0 180)
			(layer "F.SilkS")
			(hide yes)
			(effects
				(font
					(size 1.27 1.27)
				)
			)
		)
		(property "Value" ""
			(at 0 0 180)
			(layer "F.Fab")
			(effects
				(font
					(size 1.27 1.27)
				)
			)
		)
		(duplicate_pad_numbers_are_jumpers no)
		(fp_line
			(start 0.7874 0.4064)
			(end -0.7874 0.4064)
			(stroke
				(width 0.1524)
				(type default)
			)
			(layer "F.SilkS")
		)
		(fp_line
			(start 0.7874 -0.4064)
			(end 0.7874 0.4064)
			(stroke
				(width 0.1524)
				(type default)
			)
			(layer "F.SilkS")
		)
		(fp_line
			(start -0.7874 0.4064)
			(end -0.7874 -0.4064)
			(stroke
				(width 0.1524)
				(type default)
			)
			(layer "F.SilkS")
		)
		(fp_line
			(start -0.7874 -0.4064)
			(end 0.7874 -0.4064)
			(stroke
				(width 0.1524)
				(type default)
			)
			(layer "F.SilkS")
		)
		(fp_line
			(start 0.67945 0.3048)
			(end 0.120396 0.3048)
			(stroke
				(width 0.1)
				(type default)
			)
			(layer "F.Fab")
		)
		(fp_line
			(start 0.67945 -0.3048)
			(end 0.67945 0.3048)
			(stroke
				(width 0.1)
				(type default)
			)
			(layer "F.Fab")
		)
		(fp_line
			(start 0.12065 -0.2794)
			(end 0.12065 -0.3048)
			(stroke
				(width 0.1)
				(type default)
			)
			(layer "F.Fab")
		)
		(fp_line
			(start 0.12065 -0.3048)
			(end 0.67945 -0.3048)
			(stroke
				(width 0.1)
				(type default)
			)
			(layer "F.Fab")
		)
		(fp_line
			(start 0.120396 0.3048)
			(end 0.120396 0.2794)
			(stroke
				(width 0.1)
				(type default)
			)
			(layer "F.Fab")
		)
		(fp_line
			(start 0.120396 0.2794)
			(end -0.12065 0.2794)
			(stroke
				(width 0.1)
				(type default)
			)
			(layer "F.Fab")
		)
		(fp_line
			(start -0.12065 0.3048)
			(end -0.67945 0.3048)
			(stroke
				(width 0.1)
				(type default)
			)
			(layer "F.Fab")
		)
		(fp_line
			(start -0.12065 0.2794)
			(end -0.12065 0.3048)
			(stroke
				(width 0.1)
				(type default)
			)
			(layer "F.Fab")
		)
		(fp_line
			(start -0.12065 -0.2794)
			(end 0.12065 -0.2794)
			(stroke
				(width 0.1)
				(type default)
			)
			(layer "F.Fab")
		)
		(fp_line
			(start -0.12065 -0.305054)
			(end -0.12065 -0.2794)
			(stroke
				(width 0.1)
				(type default)
			)
			(layer "F.Fab")
		)
		(fp_line
			(start -0.67945 0.3048)
			(end -0.67945 -0.305054)
			(stroke
				(width 0.1)
				(type default)
			)
			(layer "F.Fab")
		)
		(fp_line
			(start -0.67945 -0.305054)
			(end -0.12065 -0.305054)
			(stroke
				(width 0.1)
				(type default)
			)
			(layer "F.Fab")
		)
		(pad "1" smd rect
			(at -0.40005 0)
			(size 0.4572 0.508)
			(layers "F.Cu" "F.Mask" "F.Paste")
			(net "P1V8_CPU1_RT0_1A_1D")
		)
		(pad "2" smd rect
			(at 0.40005 0)
			(size 0.4572 0.508)
			(layers "F.Cu" "F.Mask" "F.Paste")
			(net "P1V8_CPU1_RT0_1A")
		)
	)
	(footprint ""
		(layer "F.Cu")
		(at 215.646 -99.822)
		(property "Reference" "U9002"
			(at -0.88519 -1.39446 90)
			(unlocked yes)
			(layer "F.SilkS")
			(effects
				(font
					(size 0.7874 0.5842)
					(thickness 0.1524)
				)
				(justify left)
			)
		)
		(property "Value" ""
			(at 0 0 0)
			(layer "F.Fab")
			(effects
				(font
					(size 1.27 1.27)
				)
			)
		)
		(duplicate_pad_numbers_are_jumpers no)
		(fp_line
			(start -1.4986 -1.100074)
			(end 1.4986 -1.100074)
			(stroke
				(width 0.1524)
				(type default)
			)
			(layer "F.SilkS")
		)
		(fp_line
			(start -1.4986 1.100074)
			(end -1.4986 -1.100074)
			(stroke
				(width 0.1524)
				(type default)
			)
			(layer "F.SilkS")
		)
		(fp_line
			(start 1.4986 -1.100074)
			(end 1.4986 1.100074)
			(stroke
				(width 0.1524)
				(type default)
			)
			(layer "F.SilkS")
		)
		(fp_line
			(start 1.4986 1.100074)
			(end -1.4986 1.100074)
			(stroke
				(width 0.1524)
				(type default)
			)
			(layer "F.SilkS")
		)
		(fp_poly
			(pts
				(xy -2.378456 -0.7366) (xy -2.169922 -1.325372) (xy -1.757426 -0.831342)
			)
			(stroke
				(width 0)
				(type default)
			)
			(fill yes)
			(layer "F.SilkS")
		)
		(fp_line
			(start -0.67437 -1.100074)
			(end 0.67437 -1.100074)
			(stroke
				(width 0.1)
				(type default)
			)
			(layer "F.Fab")
		)
		(fp_line
			(start -0.67437 1.100074)
			(end -0.67437 -1.100074)
			(stroke
				(width 0.1)
				(type default)
			)
			(layer "F.Fab")
		)
		(fp_line
			(start 0.67437 -1.100074)
			(end 0.67437 1.100074)
			(stroke
				(width 0.1)
				(type default)
			)
			(layer "F.Fab")
		)
		(fp_line
			(start 0.67437 1.100074)
			(end -0.67437 1.100074)
			(stroke
				(width 0.1)
				(type default)
			)
			(layer "F.Fab")
		)
		(fp_poly
			(pts
				(xy -2.20472 -0.338328) (xy -2.20472 -0.963168) (xy -1.651 -0.635)
			)
			(stroke
				(width 0)
				(type default)
			)
			(fill yes)
			(layer "F.Fab")
		)
		(pad "1" smd rect
			(at -0.889 -0.649986)
			(size 1.016 0.381)
			(layers "F.Cu" "F.Mask" "F.Paste")
			(net "HP_LVC3_OCP_V3_1_PWRGD_R1")
		)
		(pad "2" smd rect
			(at -0.889 0)
			(size 1.016 0.381)
			(layers "F.Cu" "F.Mask" "F.Paste")
			(net "FM_PLD_OCP_SFF_AUX_PWR_EN")
		)
		(pad "3" smd rect
			(at -0.889 0.649986)
			(size 1.016 0.381)
			(layers "F.Cu" "F.Mask" "F.Paste")
			(net "GND")
		)
		(pad "4" smd rect
			(at 0.889 0.649986)
			(size 1.016 0.381)
			(layers "F.Cu" "F.Mask" "F.Paste")
			(net "OCP_SFF_AUX_PWR_EN_R3")
		)
		(pad "5" smd rect
			(at 0.889 -0.649986)
			(size 1.016 0.381)
			(layers "F.Cu" "F.Mask" "F.Paste")
			(net "P3V3_AUX")
		)
	)
	(footprint ""
		(layer "F.Cu")
		(at 415.459164 -17.624298 90)
		(property "Reference" "C1566"
			(at 0 0 90)
			(layer "F.SilkS")
			(hide yes)
			(effects
				(font
					(size 1.27 1.27)
				)
			)
		)
		(property "Value" ""
			(at 0 0 90)
			(layer "F.Fab")
			(effects
				(font
					(size 1.27 1.27)
				)
			)
		)
		(duplicate_pad_numbers_are_jumpers no)
		(fp_line
			(start 0.299974 -0.150114)
			(end 0.299974 0.150114)
			(stroke
				(width 0.1)
				(type default)
			)
			(layer "F.Fab")
		)
		(fp_line
			(start -0.299974 -0.150114)
			(end 0.299974 -0.150114)
			(stroke
				(width 0.1)
				(type default)
			)
			(layer "F.Fab")
		)
		(fp_line
			(start 0.299974 0.150114)
			(end -0.299974 0.150114)
			(stroke
				(width 0.1)
				(type default)
			)
			(layer "F.Fab")
		)
		(fp_line
			(start -0.299974 0.150114)
			(end -0.299974 -0.150114)
			(stroke
				(width 0.1)
				(type default)
			)
			(layer "F.Fab")
		)
		(pad "1" smd rect
			(at -0.2667 0 90)
			(size 0.3048 0.381)
			(layers "F.Cu" "F.Mask" "F.Paste")
			(net "P5E_CPU0_G3_TX_C_DN<6>")
		)
		(pad "2" smd rect
			(at 0.2667 0 90)
			(size 0.3048 0.381)
			(layers "F.Cu" "F.Mask" "F.Paste")
			(net "P5E_CPU0_G3_TX_DN<6>")
		)
	)
	(footprint ""
		(layer "F.Cu")
		(at 142.367 -117.475 180)
		(property "Reference" "U8010"
			(at 4.572 1.37033 0)
			(unlocked yes)
			(layer "F.SilkS")
			(effects
				(font
					(size 0.7874 0.5842)
					(thickness 0.1524)
				)
			)
		)
		(property "Value" ""
			(at 0 0 180)
			(layer "F.Fab")
			(effects
				(font
					(size 1.27 1.27)
				)
			)
		)
		(duplicate_pad_numbers_are_jumpers no)
		(fp_line
			(start 2.032 1.549908)
			(end -2.032 1.549908)
			(stroke
				(width 0.1524)
				(type default)
			)
			(layer "F.SilkS")
		)
		(fp_line
			(start 2.032 -1.549908)
			(end 2.032 1.549908)
			(stroke
				(width 0.1524)
				(type default)
			)
			(layer "F.SilkS")
		)
		(fp_line
			(start 0.508 -1.549908)
			(end 2.032 -1.549908)
			(stroke
				(width 0.1524)
				(type default)
			)
			(layer "F.SilkS")
		)
		(fp_line
			(start 0 -0.762)
			(end 0.508 -1.549908)
			(stroke
				(width 0.1524)
				(type default)
			)
			(layer "F.SilkS")
		)
		(fp_line
			(start -0.508 -1.549908)
			(end 0 -0.762)
			(stroke
				(width 0.1524)
				(type default)
			)
			(layer "F.SilkS")
		)
		(fp_line
			(start -2.032 1.549908)
			(end -2.032 -1.549908)
			(stroke
				(width 0.1524)
				(type default)
			)
			(layer "F.SilkS")
		)
		(fp_line
			(start -2.032 -1.549908)
			(end -0.508 -1.549908)
			(stroke
				(width 0.1524)
				(type default)
			)
			(layer "F.SilkS")
		)
		(fp_poly
			(pts
				(xy -4.349496 -1.589024) (xy -4.349496 -0.573024) (xy -3.333496 -1.081024)
			)
			(stroke
				(width 0)
				(type default)
			)
			(fill yes)
			(layer "F.SilkS")
		)
		(fp_line
			(start 0.849884 1.549908)
			(end -0.849884 1.549908)
			(stroke
				(width 0.1)
				(type default)
			)
			(layer "F.Fab")
		)
		(fp_line
			(start 0.849884 -1.549908)
			(end 0.849884 1.549908)
			(stroke
				(width 0.1)
				(type default)
			)
			(layer "F.Fab")
		)
		(fp_line
			(start -0.849884 1.549908)
			(end -0.849884 -1.549908)
			(stroke
				(width 0.1)
				(type default)
			)
			(layer "F.Fab")
		)
		(fp_line
			(start -0.849884 -1.549908)
			(end 0.849884 -1.549908)
			(stroke
				(width 0.1)
				(type default)
			)
			(layer "F.Fab")
		)
		(fp_poly
			(pts
				(xy -3.2004 -1.45796) (xy -3.2004 -0.44196) (xy -2.1844 -0.94996)
			)
			(stroke
				(width 0)
				(type default)
			)
			(fill yes)
			(layer "F.Fab")
		)
		(pad "1" smd rect
			(at -1.35001 -0.94996 90)
			(size 0.6096 1.0668)
			(layers "F.Cu" "F.Mask" "F.Paste")
			(net "UV_P2V5_COMP")
		)
		(pad "2" smd rect
			(at -1.35001 0 90)
			(size 0.6096 1.0668)
			(layers "F.Cu" "F.Mask" "F.Paste")
			(net "GND")
		)
		(pad "3" smd rect
			(at -1.35001 0.94996 90)
			(size 0.6096 1.0668)
			(layers "F.Cu" "F.Mask" "F.Paste")
			(net "P12V_AUX_UV_TRIGGER")
		)
		(pad "4" smd rect
			(at 1.35001 0.94996 90)
			(size 0.6096 1.0668)
			(layers "F.Cu" "F.Mask" "F.Paste")
			(net "IRQ_UV_DETECT_R2_N")
		)
		(pad "5" smd rect
			(at 1.35001 -0.94996 90)
			(size 0.6096 1.0668)
			(layers "F.Cu" "F.Mask" "F.Paste")
			(net "P12V_AUX")
		)
	)
	(footprint ""
		(layer "F.Cu")
		(at 229.0191 -304.162206 90)
		(property "Reference" "PL6502"
			(at -7.4422 -7.254748 90)
			(unlocked yes)
			(layer "F.SilkS")
			(effects
				(font
					(size 0.7874 0.5842)
					(thickness 0.1524)
				)
				(justify left)
			)
		)
		(property "Value" ""
			(at 0 0 90)
			(layer "F.Fab")
			(effects
				(font
					(size 1.27 1.27)
				)
			)
		)
		(duplicate_pad_numbers_are_jumpers no)
		(fp_line
			(start 7.4422 -6.400038)
			(end 7.4422 6.400038)
			(stroke
				(width 0.1524)
				(type default)
			)
			(layer "F.SilkS")
		)
		(fp_line
			(start -7.4422 -6.400038)
			(end 7.4422 -6.400038)
			(stroke
				(width 0.1524)
				(type default)
			)
			(layer "F.SilkS")
		)
		(fp_line
			(start 7.4422 6.400038)
			(end -7.4422 6.400038)
			(stroke
				(width 0.1524)
				(type default)
			)
			(layer "F.SilkS")
		)
		(fp_line
			(start -7.4422 6.400038)
			(end -7.4422 -6.400038)
			(stroke
				(width 0.1524)
				(type default)
			)
			(layer "F.SilkS")
		)
		(fp_line
			(start 6.938264 -6.400038)
			(end -6.862064 -6.400038)
			(stroke
				(width 0.1)
				(type default)
			)
			(layer "F.Fab")
		)
		(fp_line
			(start -6.862064 -6.400038)
			(end -6.862064 6.400038)
			(stroke
				(width 0.1)
				(type default)
			)
			(layer "F.Fab")
		)
		(fp_line
			(start 6.938264 6.400038)
			(end 6.938264 -6.400038)
			(stroke
				(width 0.1)
				(type default)
			)
			(layer "F.Fab")
		)
		(fp_line
			(start -6.862064 6.400038)
			(end 6.938264 6.400038)
			(stroke
				(width 0.1)
				(type default)
			)
			(layer "F.Fab")
		)
		(pad "1" smd rect
			(at -5.650484 0 90)
			(size 3.302 4.29768)
			(layers "F.Cu" "F.Mask" "F.Paste")
			(net "SW_P1V8_RETIMER_CPU1_SW")
		)
		(pad "2" smd rect
			(at 5.650484 0 90)
			(size 3.302 4.29768)
			(layers "F.Cu" "F.Mask" "F.Paste")
			(net "P1V8_CPU1_RT_1D")
		)
	)
	(footprint ""
		(layer "F.Cu")
		(at 76.654914 -172.76826 -90)
		(property "Reference" "PC306_5"
			(at 0 0 270)
			(layer "F.SilkS")
			(hide yes)
			(effects
				(font
					(size 1.27 1.27)
				)
			)
		)
		(property "Value" ""
			(at 0 0 270)
			(layer "F.Fab")
			(effects
				(font
					(size 1.27 1.27)
				)
			)
		)
		(duplicate_pad_numbers_are_jumpers no)
		(fp_line
			(start -0.7874 0.4064)
			(end -0.7874 -0.4064)
			(stroke
				(width 0.1524)
				(type default)
			)
			(layer "F.SilkS")
		)
		(fp_line
			(start 0.7874 0.4064)
			(end -0.7874 0.4064)
			(stroke
				(width 0.1524)
				(type default)
			)
			(layer "F.SilkS")
		)
		(fp_line
			(start -0.7874 -0.4064)
			(end 0.7874 -0.4064)
			(stroke
				(width 0.1524)
				(type default)
			)
			(layer "F.SilkS")
		)
		(fp_line
			(start 0.7874 -0.4064)
			(end 0.7874 0.4064)
			(stroke
				(width 0.1524)
				(type default)
			)
			(layer "F.SilkS")
		)
		(fp_line
			(start -0.67945 0.3048)
			(end -0.67945 -0.305054)
			(stroke
				(width 0.1)
				(type default)
			)
			(layer "F.Fab")
		)
		(fp_line
			(start -0.12065 0.3048)
			(end -0.67945 0.3048)
			(stroke
				(width 0.1)
				(type default)
			)
			(layer "F.Fab")
		)
		(fp_line
			(start 0.120396 0.3048)
			(end 0.120396 0.2794)
			(stroke
				(width 0.1)
				(type default)
			)
			(layer "F.Fab")
		)
		(fp_line
			(start 0.67945 0.3048)
			(end 0.120396 0.3048)
			(stroke
				(width 0.1)
				(type default)
			)
			(layer "F.Fab")
		)
		(fp_line
			(start -0.12065 0.2794)
			(end -0.12065 0.3048)
			(stroke
				(width 0.1)
				(type default)
			)
			(layer "F.Fab")
		)
		(fp_line
			(start 0.120396 0.2794)
			(end -0.12065 0.2794)
			(stroke
				(width 0.1)
				(type default)
			)
			(layer "F.Fab")
		)
		(fp_line
			(start -0.12065 -0.2794)
			(end 0.12065 -0.2794)
			(stroke
				(width 0.1)
				(type default)
			)
			(layer "F.Fab")
		)
		(fp_line
			(start 0.12065 -0.2794)
			(end 0.12065 -0.3048)
			(stroke
				(width 0.1)
				(type default)
			)
			(layer "F.Fab")
		)
		(fp_line
			(start 0.12065 -0.3048)
			(end 0.67945 -0.3048)
			(stroke
				(width 0.1)
				(type default)
			)
			(layer "F.Fab")
		)
		(fp_line
			(start 0.67945 -0.3048)
			(end 0.67945 0.3048)
			(stroke
				(width 0.1)
				(type default)
			)
			(layer "F.Fab")
		)
		(fp_line
			(start -0.67945 -0.305054)
			(end -0.12065 -0.305054)
			(stroke
				(width 0.1)
				(type default)
			)
			(layer "F.Fab")
		)
		(fp_line
			(start -0.12065 -0.305054)
			(end -0.12065 -0.2794)
			(stroke
				(width 0.1)
				(type default)
			)
			(layer "F.Fab")
		)
		(pad "1" smd circle
			(at -0.40005 0 270)
			(size 0 0)
			(layers "F.Cu" "F.Mask" "F.Paste")
			(net "PVDDCR_CPU0_P1_VCCS")
		)
		(pad "2" smd circle
			(at 0.40005 0 270)
			(size 0 0)
			(layers "F.Cu" "F.Mask" "F.Paste")
			(net "GND")
		)
	)
	(footprint ""
		(layer "F.Cu")
		(at 94.375732 -185.680096)
		(property "Reference" "PC173"
			(at 0 0 0)
			(layer "F.SilkS")
			(hide yes)
			(effects
				(font
					(size 1.27 1.27)
				)
			)
		)
		(property "Value" ""
			(at 0 0 0)
			(layer "F.Fab")
			(effects
				(font
					(size 1.27 1.27)
				)
			)
		)
		(duplicate_pad_numbers_are_jumpers no)
		(fp_line
			(start -0.7874 -0.4064)
			(end 0.7874 -0.4064)
			(stroke
				(width 0.1524)
				(type default)
			)
			(layer "F.SilkS")
		)
		(fp_line
			(start -0.7874 0.4064)
			(end -0.7874 -0.4064)
			(stroke
				(width 0.1524)
				(type default)
			)
			(layer "F.SilkS")
		)
		(fp_line
			(start 0.7874 -0.4064)
			(end 0.7874 0.4064)
			(stroke
				(width 0.1524)
				(type default)
			)
			(layer "F.SilkS")
		)
		(fp_line
			(start 0.7874 0.4064)
			(end -0.7874 0.4064)
			(stroke
				(width 0.1524)
				(type default)
			)
			(layer "F.SilkS")
		)
		(fp_line
			(start -0.67945 -0.305054)
			(end -0.12065 -0.305054)
			(stroke
				(width 0.1)
				(type default)
			)
			(layer "F.Fab")
		)
		(fp_line
			(start -0.67945 0.3048)
			(end -0.67945 -0.305054)
			(stroke
				(width 0.1)
				(type default)
			)
			(layer "F.Fab")
		)
		(fp_line
			(start -0.12065 -0.305054)
			(end -0.12065 -0.2794)
			(stroke
				(width 0.1)
				(type default)
			)
			(layer "F.Fab")
		)
		(fp_line
			(start -0.12065 -0.2794)
			(end 0.12065 -0.2794)
			(stroke
				(width 0.1)
				(type default)
			)
			(layer "F.Fab")
		)
		(fp_line
			(start -0.12065 0.2794)
			(end -0.12065 0.3048)
			(stroke
				(width 0.1)
				(type default)
			)
			(layer "F.Fab")
		)
		(fp_line
			(start -0.12065 0.3048)
			(end -0.67945 0.3048)
			(stroke
				(width 0.1)
				(type default)
			)
			(layer "F.Fab")
		)
		(fp_line
			(start 0.120396 0.2794)
			(end -0.12065 0.2794)
			(stroke
				(width 0.1)
				(type default)
			)
			(layer "F.Fab")
		)
		(fp_line
			(start 0.120396 0.3048)
			(end 0.120396 0.2794)
			(stroke
				(width 0.1)
				(type default)
			)
			(layer "F.Fab")
		)
		(fp_line
			(start 0.12065 -0.3048)
			(end 0.67945 -0.3048)
			(stroke
				(width 0.1)
				(type default)
			)
			(layer "F.Fab")
		)
		(fp_line
			(start 0.12065 -0.2794)
			(end 0.12065 -0.3048)
			(stroke
				(width 0.1)
				(type default)
			)
			(layer "F.Fab")
		)
		(fp_line
			(start 0.67945 -0.3048)
			(end 0.67945 0.3048)
			(stroke
				(width 0.1)
				(type default)
			)
			(layer "F.Fab")
		)
		(fp_line
			(start 0.67945 0.3048)
			(end 0.120396 0.3048)
			(stroke
				(width 0.1)
				(type default)
			)
			(layer "F.Fab")
		)
		(pad "1" smd circle
			(at -0.40005 0)
			(size 0 0)
			(layers "F.Cu" "F.Mask" "F.Paste")
			(net "SW_PVDDCR_CPU0_P1_SW2")
		)
		(pad "2" smd circle
			(at 0.40005 0)
			(size 0 0)
			(layers "F.Cu" "F.Mask" "F.Paste")
			(net "SW_PVDDCR_CPU0_P1_SW2_RC")
		)
	)
	(footprint ""
		(layer "F.Cu")
		(at 288.26587 -97.967292)
		(property "Reference" "C1511"
			(at 0 0 0)
			(layer "F.SilkS")
			(hide yes)
			(effects
				(font
					(size 1.27 1.27)
				)
			)
		)
		(property "Value" ""
			(at 0 0 0)
			(layer "F.Fab")
			(effects
				(font
					(size 1.27 1.27)
				)
			)
		)
		(duplicate_pad_numbers_are_jumpers no)
		(fp_line
			(start -0.7874 -0.4064)
			(end 0.7874 -0.4064)
			(stroke
				(width 0.1524)
				(type default)
			)
			(layer "F.SilkS")
		)
		(fp_line
			(start -0.7874 0.4064)
			(end -0.7874 -0.4064)
			(stroke
				(width 0.1524)
				(type default)
			)
			(layer "F.SilkS")
		)
		(fp_line
			(start 0.7874 -0.4064)
			(end 0.7874 0.4064)
			(stroke
				(width 0.1524)
				(type default)
			)
			(layer "F.SilkS")
		)
		(fp_line
			(start 0.7874 0.4064)
			(end -0.7874 0.4064)
			(stroke
				(width 0.1524)
				(type default)
			)
			(layer "F.SilkS")
		)
		(fp_line
			(start -0.67945 -0.305054)
			(end -0.12065 -0.305054)
			(stroke
				(width 0.1)
				(type default)
			)
			(layer "F.Fab")
		)
		(fp_line
			(start -0.67945 0.3048)
			(end -0.67945 -0.305054)
			(stroke
				(width 0.1)
				(type default)
			)
			(layer "F.Fab")
		)
		(fp_line
			(start -0.12065 -0.305054)
			(end -0.12065 -0.2794)
			(stroke
				(width 0.1)
				(type default)
			)
			(layer "F.Fab")
		)
		(fp_line
			(start -0.12065 -0.2794)
			(end 0.12065 -0.2794)
			(stroke
				(width 0.1)
				(type default)
			)
			(layer "F.Fab")
		)
		(fp_line
			(start -0.12065 0.2794)
			(end -0.12065 0.3048)
			(stroke
				(width 0.1)
				(type default)
			)
			(layer "F.Fab")
		)
		(fp_line
			(start -0.12065 0.3048)
			(end -0.67945 0.3048)
			(stroke
				(width 0.1)
				(type default)
			)
			(layer "F.Fab")
		)
		(fp_line
			(start 0.120396 0.2794)
			(end -0.12065 0.2794)
			(stroke
				(width 0.1)
				(type default)
			)
			(layer "F.Fab")
		)
		(fp_line
			(start 0.120396 0.3048)
			(end 0.120396 0.2794)
			(stroke
				(width 0.1)
				(type default)
			)
			(layer "F.Fab")
		)
		(fp_line
			(start 0.12065 -0.3048)
			(end 0.67945 -0.3048)
			(stroke
				(width 0.1)
				(type default)
			)
			(layer "F.Fab")
		)
		(fp_line
			(start 0.12065 -0.2794)
			(end 0.12065 -0.3048)
			(stroke
				(width 0.1)
				(type default)
			)
			(layer "F.Fab")
		)
		(fp_line
			(start 0.67945 -0.3048)
			(end 0.67945 0.3048)
			(stroke
				(width 0.1)
				(type default)
			)
			(layer "F.Fab")
		)
		(fp_line
			(start 0.67945 0.3048)
			(end 0.120396 0.3048)
			(stroke
				(width 0.1)
				(type default)
			)
			(layer "F.Fab")
		)
		(pad "1" smd circle
			(at -0.40005 0)
			(size 0 0)
			(layers "F.Cu" "F.Mask" "F.Paste")
			(net "JTAG_TRST_N")
		)
		(pad "2" smd circle
			(at 0.40005 0)
			(size 0 0)
			(layers "F.Cu" "F.Mask" "F.Paste")
			(net "GND")
		)
	)
	(footprint ""
		(layer "F.Cu")
		(at 294.769794 -18.780506 180)
		(property "Reference" "C73"
			(at 0 0 180)
			(layer "F.SilkS")
			(hide yes)
			(effects
				(font
					(size 1.27 1.27)
				)
			)
		)
		(property "Value" ""
			(at 0 0 180)
			(layer "F.Fab")
			(effects
				(font
					(size 1.27 1.27)
				)
			)
		)
		(duplicate_pad_numbers_are_jumpers no)
		(fp_line
			(start 0.7874 0.4064)
			(end -0.7874 0.4064)
			(stroke
				(width 0.1524)
				(type default)
			)
			(layer "F.SilkS")
		)
		(fp_line
			(start 0.7874 -0.4064)
			(end 0.7874 0.4064)
			(stroke
				(width 0.1524)
				(type default)
			)
			(layer "F.SilkS")
		)
		(fp_line
			(start -0.7874 0.4064)
			(end -0.7874 -0.4064)
			(stroke
				(width 0.1524)
				(type default)
			)
			(layer "F.SilkS")
		)
		(fp_line
			(start -0.7874 -0.4064)
			(end 0.7874 -0.4064)
			(stroke
				(width 0.1524)
				(type default)
			)
			(layer "F.SilkS")
		)
		(fp_line
			(start 0.67945 0.3048)
			(end 0.120396 0.3048)
			(stroke
				(width 0.1)
				(type default)
			)
			(layer "F.Fab")
		)
		(fp_line
			(start 0.67945 -0.3048)
			(end 0.67945 0.3048)
			(stroke
				(width 0.1)
				(type default)
			)
			(layer "F.Fab")
		)
		(fp_line
			(start 0.12065 -0.2794)
			(end 0.12065 -0.3048)
			(stroke
				(width 0.1)
				(type default)
			)
			(layer "F.Fab")
		)
		(fp_line
			(start 0.12065 -0.3048)
			(end 0.67945 -0.3048)
			(stroke
				(width 0.1)
				(type default)
			)
			(layer "F.Fab")
		)
		(fp_line
			(start 0.120396 0.3048)
			(end 0.120396 0.2794)
			(stroke
				(width 0.1)
				(type default)
			)
			(layer "F.Fab")
		)
		(fp_line
			(start 0.120396 0.2794)
			(end -0.12065 0.2794)
			(stroke
				(width 0.1)
				(type default)
			)
			(layer "F.Fab")
		)
		(fp_line
			(start -0.12065 0.3048)
			(end -0.67945 0.3048)
			(stroke
				(width 0.1)
				(type default)
			)
			(layer "F.Fab")
		)
		(fp_line
			(start -0.12065 0.2794)
			(end -0.12065 0.3048)
			(stroke
				(width 0.1)
				(type default)
			)
			(layer "F.Fab")
		)
		(fp_line
			(start -0.12065 -0.2794)
			(end 0.12065 -0.2794)
			(stroke
				(width 0.1)
				(type default)
			)
			(layer "F.Fab")
		)
		(fp_line
			(start -0.12065 -0.305054)
			(end -0.12065 -0.2794)
			(stroke
				(width 0.1)
				(type default)
			)
			(layer "F.Fab")
		)
		(fp_line
			(start -0.67945 0.3048)
			(end -0.67945 -0.305054)
			(stroke
				(width 0.1)
				(type default)
			)
			(layer "F.Fab")
		)
		(fp_line
			(start -0.67945 -0.305054)
			(end -0.12065 -0.305054)
			(stroke
				(width 0.1)
				(type default)
			)
			(layer "F.Fab")
		)
		(pad "1" smd circle
			(at -0.40005 0 180)
			(size 0 0)
			(layers "F.Cu" "F.Mask" "F.Paste")
			(net "P3V3_AUX")
		)
		(pad "2" smd circle
			(at 0.40005 0 180)
			(size 0 0)
			(layers "F.Cu" "F.Mask" "F.Paste")
			(net "GND")
		)
	)
	(footprint ""
		(layer "F.Cu")
		(at 113.20653 -15.879064)
		(property "Reference" "U273"
			(at 1.29413 -3.490214 0)
			(unlocked yes)
			(layer "F.SilkS")
			(effects
				(font
					(size 0.7874 0.5842)
					(thickness 0.1524)
				)
				(justify left)
			)
		)
		(property "Value" ""
			(at 0 0 0)
			(layer "F.Fab")
			(effects
				(font
					(size 1.27 1.27)
				)
			)
		)
		(duplicate_pad_numbers_are_jumpers no)
		(fp_line
			(start -3.447796 -2.500122)
			(end -3.447796 2.500122)
			(stroke
				(width 0.1524)
				(type default)
			)
			(layer "F.SilkS")
		)
		(fp_line
			(start -3.447796 2.500122)
			(end 3.447796 2.500122)
			(stroke
				(width 0.1524)
				(type default)
			)
			(layer "F.SilkS")
		)
		(fp_line
			(start -1.484122 -2.500122)
			(end -3.447796 -2.500122)
			(stroke
				(width 0.1524)
				(type default)
			)
			(layer "F.SilkS")
		)
		(fp_line
			(start 0 -1.016)
			(end -1.484122 -2.500122)
			(stroke
				(width 0.1524)
				(type default)
			)
			(layer "F.SilkS")
		)
		(fp_line
			(start 1.484122 -2.500122)
			(end 0 -1.016)
			(stroke
				(width 0.1524)
				(type default)
			)
			(layer "F.SilkS")
		)
		(fp_line
			(start 3.447796 -2.500122)
			(end 1.484122 -2.500122)
			(stroke
				(width 0.1524)
				(type default)
			)
			(layer "F.SilkS")
		)
		(fp_line
			(start 3.447796 2.500122)
			(end 3.447796 -2.500122)
			(stroke
				(width 0.1524)
				(type default)
			)
			(layer "F.SilkS")
		)
		(fp_poly
			(pts
				(xy -4.670552 -0.917702) (xy -4.901184 -1.907032) (xy -3.796538 -1.64338)
			)
			(stroke
				(width 0)
				(type default)
			)
			(fill yes)
			(layer "F.SilkS")
		)
		(fp_line
			(start -1.999996 -2.500122)
			(end -1.999996 2.500122)
			(stroke
				(width 0.1)
				(type default)
			)
			(layer "F.Fab")
		)
		(fp_line
			(start -1.999996 2.500122)
			(end 1.999996 2.500122)
			(stroke
				(width 0.1)
				(type default)
			)
			(layer "F.Fab")
		)
		(fp_line
			(start 1.999996 -2.500122)
			(end -1.999996 -2.500122)
			(stroke
				(width 0.1)
				(type default)
			)
			(layer "F.Fab")
		)
		(fp_line
			(start 1.999996 2.500122)
			(end 1.999996 -2.500122)
			(stroke
				(width 0.1)
				(type default)
			)
			(layer "F.Fab")
		)
		(fp_poly
			(pts
				(xy -4.5974 -2.413) (xy -4.5974 -1.397) (xy -3.5814 -1.905)
			)
			(stroke
				(width 0)
				(type default)
			)
			(fill yes)
			(layer "F.Fab")
		)
		(pad "1" smd rect
			(at -2.649982 -1.905 270)
			(size 0.6096 1.3208)
			(layers "F.Cu" "F.Mask" "F.Paste")
			(net "SMB_LM75_3_3V3AUX_SDA_R1")
		)
		(pad "2" smd rect
			(at -2.649982 -0.635 270)
			(size 0.6096 1.3208)
			(layers "F.Cu" "F.Mask" "F.Paste")
			(net "SMB_LM75_3_3V3AUX_SCL_R1")
		)
		(pad "3" smd rect
			(at -2.649982 0.635 270)
			(size 0.6096 1.3208)
			(layers "F.Cu" "F.Mask" "F.Paste")
			(net "FM_LM75_3_ALERT_N")
		)
		(pad "4" smd rect
			(at -2.649982 1.905 270)
			(size 0.6096 1.3208)
			(layers "F.Cu" "F.Mask" "F.Paste")
			(net "GND")
		)
		(pad "5" smd rect
			(at 2.649982 1.905 270)
			(size 0.6096 1.3208)
			(layers "F.Cu" "F.Mask" "F.Paste")
			(net "U273_3_ADD2")
		)
		(pad "6" smd rect
			(at 2.649982 0.635 270)
			(size 0.6096 1.3208)
			(layers "F.Cu" "F.Mask" "F.Paste")
			(net "U273_3_ADD1")
		)
		(pad "7" smd rect
			(at 2.649982 -0.635 270)
			(size 0.6096 1.3208)
			(layers "F.Cu" "F.Mask" "F.Paste")
			(net "U273_3_ADD0")
		)
		(pad "8" smd rect
			(at 2.649982 -1.905 270)
			(size 0.6096 1.3208)
			(layers "F.Cu" "F.Mask" "F.Paste")
			(net "P3V3_AUX")
		)
	)
	(footprint ""
		(layer "F.Cu")
		(at 105.64876 -58.502042 180)
		(property "Reference" "R1737"
			(at 0 0 180)
			(layer "F.SilkS")
			(hide yes)
			(effects
				(font
					(size 1.27 1.27)
				)
			)
		)
		(property "Value" ""
			(at 0 0 180)
			(layer "F.Fab")
			(effects
				(font
					(size 1.27 1.27)
				)
			)
		)
		(duplicate_pad_numbers_are_jumpers no)
		(fp_line
			(start 0.7874 0.4064)
			(end -0.7874 0.4064)
			(stroke
				(width 0.1524)
				(type default)
			)
			(layer "F.SilkS")
		)
		(fp_line
			(start 0.7874 -0.4064)
			(end 0.7874 0.4064)
			(stroke
				(width 0.1524)
				(type default)
			)
			(layer "F.SilkS")
		)
		(fp_line
			(start -0.7874 0.4064)
			(end -0.7874 -0.4064)
			(stroke
				(width 0.1524)
				(type default)
			)
			(layer "F.SilkS")
		)
		(fp_line
			(start -0.7874 -0.4064)
			(end 0.7874 -0.4064)
			(stroke
				(width 0.1524)
				(type default)
			)
			(layer "F.SilkS")
		)
		(fp_line
			(start 0.67945 0.3048)
			(end 0.120396 0.3048)
			(stroke
				(width 0.1)
				(type default)
			)
			(layer "F.Fab")
		)
		(fp_line
			(start 0.67945 -0.3048)
			(end 0.67945 0.3048)
			(stroke
				(width 0.1)
				(type default)
			)
			(layer "F.Fab")
		)
		(fp_line
			(start 0.12065 -0.2794)
			(end 0.12065 -0.3048)
			(stroke
				(width 0.1)
				(type default)
			)
			(layer "F.Fab")
		)
		(fp_line
			(start 0.12065 -0.3048)
			(end 0.67945 -0.3048)
			(stroke
				(width 0.1)
				(type default)
			)
			(layer "F.Fab")
		)
		(fp_line
			(start 0.120396 0.3048)
			(end 0.120396 0.2794)
			(stroke
				(width 0.1)
				(type default)
			)
			(layer "F.Fab")
		)
		(fp_line
			(start 0.120396 0.2794)
			(end -0.12065 0.2794)
			(stroke
				(width 0.1)
				(type default)
			)
			(layer "F.Fab")
		)
		(fp_line
			(start -0.12065 0.3048)
			(end -0.67945 0.3048)
			(stroke
				(width 0.1)
				(type default)
			)
			(layer "F.Fab")
		)
		(fp_line
			(start -0.12065 0.2794)
			(end -0.12065 0.3048)
			(stroke
				(width 0.1)
				(type default)
			)
			(layer "F.Fab")
		)
		(fp_line
			(start -0.12065 -0.2794)
			(end 0.12065 -0.2794)
			(stroke
				(width 0.1)
				(type default)
			)
			(layer "F.Fab")
		)
		(fp_line
			(start -0.12065 -0.305054)
			(end -0.12065 -0.2794)
			(stroke
				(width 0.1)
				(type default)
			)
			(layer "F.Fab")
		)
		(fp_line
			(start -0.67945 0.3048)
			(end -0.67945 -0.305054)
			(stroke
				(width 0.1)
				(type default)
			)
			(layer "F.Fab")
		)
		(fp_line
			(start -0.67945 -0.305054)
			(end -0.12065 -0.305054)
			(stroke
				(width 0.1)
				(type default)
			)
			(layer "F.Fab")
		)
		(pad "1" smd circle
			(at -0.40005 0 180)
			(size 0 0)
			(layers "F.Cu" "F.Mask" "F.Paste")
			(net "JTAG_SCM_MUX_R_TMS")
		)
		(pad "2" smd circle
			(at 0.40005 0 180)
			(size 0 0)
			(layers "F.Cu" "F.Mask" "F.Paste")
			(net "JTAG_SCM_MUX_TMS")
		)
	)
	(footprint ""
		(layer "F.Cu")
		(at 455.01306 -42.121836)
		(property "Reference" "R5487"
			(at 0 0 0)
			(layer "F.SilkS")
			(hide yes)
			(effects
				(font
					(size 1.27 1.27)
				)
			)
		)
		(property "Value" ""
			(at 0 0 0)
			(layer "F.Fab")
			(effects
				(font
					(size 1.27 1.27)
				)
			)
		)
		(duplicate_pad_numbers_are_jumpers no)
		(fp_line
			(start -0.7874 -0.4064)
			(end 0.7874 -0.4064)
			(stroke
				(width 0.1524)
				(type default)
			)
			(layer "F.SilkS")
		)
		(fp_line
			(start -0.7874 0.4064)
			(end -0.7874 -0.4064)
			(stroke
				(width 0.1524)
				(type default)
			)
			(layer "F.SilkS")
		)
		(fp_line
			(start 0.7874 -0.4064)
			(end 0.7874 0.4064)
			(stroke
				(width 0.1524)
				(type default)
			)
			(layer "F.SilkS")
		)
		(fp_line
			(start 0.7874 0.4064)
			(end -0.7874 0.4064)
			(stroke
				(width 0.1524)
				(type default)
			)
			(layer "F.SilkS")
		)
		(fp_line
			(start -0.67945 -0.305054)
			(end -0.12065 -0.305054)
			(stroke
				(width 0.1)
				(type default)
			)
			(layer "F.Fab")
		)
		(fp_line
			(start -0.67945 0.3048)
			(end -0.67945 -0.305054)
			(stroke
				(width 0.1)
				(type default)
			)
			(layer "F.Fab")
		)
		(fp_line
			(start -0.12065 -0.305054)
			(end -0.12065 -0.2794)
			(stroke
				(width 0.1)
				(type default)
			)
			(layer "F.Fab")
		)
		(fp_line
			(start -0.12065 -0.2794)
			(end 0.12065 -0.2794)
			(stroke
				(width 0.1)
				(type default)
			)
			(layer "F.Fab")
		)
		(fp_line
			(start -0.12065 0.2794)
			(end -0.12065 0.3048)
			(stroke
				(width 0.1)
				(type default)
			)
			(layer "F.Fab")
		)
		(fp_line
			(start -0.12065 0.3048)
			(end -0.67945 0.3048)
			(stroke
				(width 0.1)
				(type default)
			)
			(layer "F.Fab")
		)
		(fp_line
			(start 0.120396 0.2794)
			(end -0.12065 0.2794)
			(stroke
				(width 0.1)
				(type default)
			)
			(layer "F.Fab")
		)
		(fp_line
			(start 0.120396 0.3048)
			(end 0.120396 0.2794)
			(stroke
				(width 0.1)
				(type default)
			)
			(layer "F.Fab")
		)
		(fp_line
			(start 0.12065 -0.3048)
			(end 0.67945 -0.3048)
			(stroke
				(width 0.1)
				(type default)
			)
			(layer "F.Fab")
		)
		(fp_line
			(start 0.12065 -0.2794)
			(end 0.12065 -0.3048)
			(stroke
				(width 0.1)
				(type default)
			)
			(layer "F.Fab")
		)
		(fp_line
			(start 0.67945 -0.3048)
			(end 0.67945 0.3048)
			(stroke
				(width 0.1)
				(type default)
			)
			(layer "F.Fab")
		)
		(fp_line
			(start 0.67945 0.3048)
			(end 0.120396 0.3048)
			(stroke
				(width 0.1)
				(type default)
			)
			(layer "F.Fab")
		)
		(pad "1" smd circle
			(at -0.40005 0)
			(size 0 0)
			(layers "F.Cu" "F.Mask" "F.Paste")
			(net "P3V3_OCP_SFF_EN_R")
		)
		(pad "2" smd circle
			(at 0.40005 0)
			(size 0 0)
			(layers "F.Cu" "F.Mask" "F.Paste")
			(net "P3V3_OCP_EN_1_R")
		)
	)
	(footprint ""
		(layer "F.Cu")
		(at 72.463914 -146.735292 180)
		(property "Reference" "PC64"
			(at 0 0 180)
			(layer "F.SilkS")
			(hide yes)
			(effects
				(font
					(size 1.27 1.27)
				)
			)
		)
		(property "Value" ""
			(at 0 0 180)
			(layer "F.Fab")
			(effects
				(font
					(size 1.27 1.27)
				)
			)
		)
		(duplicate_pad_numbers_are_jumpers no)
		(fp_line
			(start 0.7874 0.4064)
			(end -0.7874 0.4064)
			(stroke
				(width 0.1524)
				(type default)
			)
			(layer "F.SilkS")
		)
		(fp_line
			(start 0.7874 -0.4064)
			(end 0.7874 0.4064)
			(stroke
				(width 0.1524)
				(type default)
			)
			(layer "F.SilkS")
		)
		(fp_line
			(start -0.7874 0.4064)
			(end -0.7874 -0.4064)
			(stroke
				(width 0.1524)
				(type default)
			)
			(layer "F.SilkS")
		)
		(fp_line
			(start -0.7874 -0.4064)
			(end 0.7874 -0.4064)
			(stroke
				(width 0.1524)
				(type default)
			)
			(layer "F.SilkS")
		)
		(fp_line
			(start 0.67945 0.3048)
			(end 0.120396 0.3048)
			(stroke
				(width 0.1)
				(type default)
			)
			(layer "F.Fab")
		)
		(fp_line
			(start 0.67945 -0.3048)
			(end 0.67945 0.3048)
			(stroke
				(width 0.1)
				(type default)
			)
			(layer "F.Fab")
		)
		(fp_line
			(start 0.12065 -0.2794)
			(end 0.12065 -0.3048)
			(stroke
				(width 0.1)
				(type default)
			)
			(layer "F.Fab")
		)
		(fp_line
			(start 0.12065 -0.3048)
			(end 0.67945 -0.3048)
			(stroke
				(width 0.1)
				(type default)
			)
			(layer "F.Fab")
		)
		(fp_line
			(start 0.120396 0.3048)
			(end 0.120396 0.2794)
			(stroke
				(width 0.1)
				(type default)
			)
			(layer "F.Fab")
		)
		(fp_line
			(start 0.120396 0.2794)
			(end -0.12065 0.2794)
			(stroke
				(width 0.1)
				(type default)
			)
			(layer "F.Fab")
		)
		(fp_line
			(start -0.12065 0.3048)
			(end -0.67945 0.3048)
			(stroke
				(width 0.1)
				(type default)
			)
			(layer "F.Fab")
		)
		(fp_line
			(start -0.12065 0.2794)
			(end -0.12065 0.3048)
			(stroke
				(width 0.1)
				(type default)
			)
			(layer "F.Fab")
		)
		(fp_line
			(start -0.12065 -0.2794)
			(end 0.12065 -0.2794)
			(stroke
				(width 0.1)
				(type default)
			)
			(layer "F.Fab")
		)
		(fp_line
			(start -0.12065 -0.305054)
			(end -0.12065 -0.2794)
			(stroke
				(width 0.1)
				(type default)
			)
			(layer "F.Fab")
		)
		(fp_line
			(start -0.67945 0.3048)
			(end -0.67945 -0.305054)
			(stroke
				(width 0.1)
				(type default)
			)
			(layer "F.Fab")
		)
		(fp_line
			(start -0.67945 -0.305054)
			(end -0.12065 -0.305054)
			(stroke
				(width 0.1)
				(type default)
			)
			(layer "F.Fab")
		)
		(pad "1" smd circle
			(at -0.40005 0 180)
			(size 0 0)
			(layers "F.Cu" "F.Mask" "F.Paste")
			(net "PVDD18_S5_P1_FB")
		)
		(pad "2" smd circle
			(at 0.40005 0 180)
			(size 0 0)
			(layers "F.Cu" "F.Mask" "F.Paste")
			(net "PVDD18_S5_P1_FB_RC")
		)
	)
	(footprint ""
		(layer "F.Cu")
		(at 331.494892 -389.86206 180)
		(property "Reference" "C964"
			(at 0 0 180)
			(layer "F.SilkS")
			(hide yes)
			(effects
				(font
					(size 1.27 1.27)
				)
			)
		)
		(property "Value" ""
			(at 0 0 180)
			(layer "F.Fab")
			(effects
				(font
					(size 1.27 1.27)
				)
			)
		)
		(duplicate_pad_numbers_are_jumpers no)
		(fp_line
			(start 0.299974 0.150114)
			(end -0.299974 0.150114)
			(stroke
				(width 0.1)
				(type default)
			)
			(layer "F.Fab")
		)
		(fp_line
			(start 0.299974 -0.150114)
			(end 0.299974 0.150114)
			(stroke
				(width 0.1)
				(type default)
			)
			(layer "F.Fab")
		)
		(fp_line
			(start -0.299974 0.150114)
			(end -0.299974 -0.150114)
			(stroke
				(width 0.1)
				(type default)
			)
			(layer "F.Fab")
		)
		(fp_line
			(start -0.299974 -0.150114)
			(end 0.299974 -0.150114)
			(stroke
				(width 0.1)
				(type default)
			)
			(layer "F.Fab")
		)
		(pad "1" smd rect
			(at -0.2667 0 180)
			(size 0.3048 0.381)
			(layers "F.Cu" "F.Mask" "F.Paste")
			(net "P5E_CPU0_P1_TX_C_DN<0>")
		)
		(pad "2" smd rect
			(at 0.2667 0 180)
			(size 0.3048 0.381)
			(layers "F.Cu" "F.Mask" "F.Paste")
			(net "P5E_CPU0_P1_TX_DN<0>")
		)
	)
	(footprint ""
		(layer "F.Cu")
		(at 105.918 -426.466 90)
		(property "Reference" "R3460"
			(at 0 0 90)
			(layer "F.SilkS")
			(hide yes)
			(effects
				(font
					(size 1.27 1.27)
				)
			)
		)
		(property "Value" ""
			(at 0 0 90)
			(layer "F.Fab")
			(effects
				(font
					(size 1.27 1.27)
				)
			)
		)
		(duplicate_pad_numbers_are_jumpers no)
		(fp_line
			(start 0.7874 -0.4064)
			(end 0.7874 0.4064)
			(stroke
				(width 0.1524)
				(type default)
			)
			(layer "F.SilkS")
		)
		(fp_line
			(start -0.7874 -0.4064)
			(end 0.7874 -0.4064)
			(stroke
				(width 0.1524)
				(type default)
			)
			(layer "F.SilkS")
		)
		(fp_line
			(start 0.7874 0.4064)
			(end -0.7874 0.4064)
			(stroke
				(width 0.1524)
				(type default)
			)
			(layer "F.SilkS")
		)
		(fp_line
			(start -0.7874 0.4064)
			(end -0.7874 -0.4064)
			(stroke
				(width 0.1524)
				(type default)
			)
			(layer "F.SilkS")
		)
		(fp_line
			(start -0.12065 -0.305054)
			(end -0.12065 -0.2794)
			(stroke
				(width 0.1)
				(type default)
			)
			(layer "F.Fab")
		)
		(fp_line
			(start -0.67945 -0.305054)
			(end -0.12065 -0.305054)
			(stroke
				(width 0.1)
				(type default)
			)
			(layer "F.Fab")
		)
		(fp_line
			(start 0.67945 -0.3048)
			(end 0.67945 0.3048)
			(stroke
				(width 0.1)
				(type default)
			)
			(layer "F.Fab")
		)
		(fp_line
			(start 0.12065 -0.3048)
			(end 0.67945 -0.3048)
			(stroke
				(width 0.1)
				(type default)
			)
			(layer "F.Fab")
		)
		(fp_line
			(start 0.12065 -0.2794)
			(end 0.12065 -0.3048)
			(stroke
				(width 0.1)
				(type default)
			)
			(layer "F.Fab")
		)
		(fp_line
			(start -0.12065 -0.2794)
			(end 0.12065 -0.2794)
			(stroke
				(width 0.1)
				(type default)
			)
			(layer "F.Fab")
		)
		(fp_line
			(start 0.120396 0.2794)
			(end -0.12065 0.2794)
			(stroke
				(width 0.1)
				(type default)
			)
			(layer "F.Fab")
		)
		(fp_line
			(start -0.12065 0.2794)
			(end -0.12065 0.3048)
			(stroke
				(width 0.1)
				(type default)
			)
			(layer "F.Fab")
		)
		(fp_line
			(start 0.67945 0.3048)
			(end 0.120396 0.3048)
			(stroke
				(width 0.1)
				(type default)
			)
			(layer "F.Fab")
		)
		(fp_line
			(start 0.120396 0.3048)
			(end 0.120396 0.2794)
			(stroke
				(width 0.1)
				(type default)
			)
			(layer "F.Fab")
		)
		(fp_line
			(start -0.12065 0.3048)
			(end -0.67945 0.3048)
			(stroke
				(width 0.1)
				(type default)
			)
			(layer "F.Fab")
		)
		(fp_line
			(start -0.67945 0.3048)
			(end -0.67945 -0.305054)
			(stroke
				(width 0.1)
				(type default)
			)
			(layer "F.Fab")
		)
		(pad "1" smd circle
			(at -0.40005 0 90)
			(size 0 0)
			(layers "F.Cu" "F.Mask" "F.Paste")
			(net "GPU_NVS_PWR_BRAKE_N")
		)
		(pad "2" smd circle
			(at 0.40005 0 90)
			(size 0 0)
			(layers "F.Cu" "F.Mask" "F.Paste")
			(net "GND")
		)
	)
	(footprint ""
		(layer "F.Cu")
		(at 144.319244 -370.57203 -90)
		(property "Reference" "C767"
			(at 0 0 270)
			(layer "F.SilkS")
			(hide yes)
			(effects
				(font
					(size 1.27 1.27)
				)
			)
		)
		(property "Value" ""
			(at 0 0 270)
			(layer "F.Fab")
			(effects
				(font
					(size 1.27 1.27)
				)
			)
		)
		(duplicate_pad_numbers_are_jumpers no)
		(fp_line
			(start -0.299974 0.150114)
			(end -0.299974 -0.150114)
			(stroke
				(width 0.1)
				(type default)
			)
			(layer "F.Fab")
		)
		(fp_line
			(start 0.299974 0.150114)
			(end -0.299974 0.150114)
			(stroke
				(width 0.1)
				(type default)
			)
			(layer "F.Fab")
		)
		(fp_line
			(start -0.299974 -0.150114)
			(end 0.299974 -0.150114)
			(stroke
				(width 0.1)
				(type default)
			)
			(layer "F.Fab")
		)
		(fp_line
			(start 0.299974 -0.150114)
			(end 0.299974 0.150114)
			(stroke
				(width 0.1)
				(type default)
			)
			(layer "F.Fab")
		)
		(pad "1" smd rect
			(at -0.2667 0 270)
			(size 0.3048 0.381)
			(layers "F.Cu" "F.Mask" "F.Paste")
			(net "P5E_CPU1_P2_TX_C_DP<3>")
		)
		(pad "2" smd rect
			(at 0.2667 0 270)
			(size 0.3048 0.381)
			(layers "F.Cu" "F.Mask" "F.Paste")
			(net "P5E_CPU1_P2_TX_DP<3>")
		)
	)
	(footprint ""
		(layer "F.Cu")
		(at 438.455308 -405.788622 -90)
		(property "Reference" "PR6551"
			(at 0 0 270)
			(layer "F.SilkS")
			(hide yes)
			(effects
				(font
					(size 1.27 1.27)
				)
			)
		)
		(property "Value" ""
			(at 0 0 270)
			(layer "F.Fab")
			(effects
				(font
					(size 1.27 1.27)
				)
			)
		)
		(duplicate_pad_numbers_are_jumpers no)
		(fp_line
			(start -0.7874 0.4064)
			(end -0.7874 -0.4064)
			(stroke
				(width 0.1524)
				(type default)
			)
			(layer "F.SilkS")
		)
		(fp_line
			(start 0.7874 0.4064)
			(end -0.7874 0.4064)
			(stroke
				(width 0.1524)
				(type default)
			)
			(layer "F.SilkS")
		)
		(fp_line
			(start -0.7874 -0.4064)
			(end 0.7874 -0.4064)
			(stroke
				(width 0.1524)
				(type default)
			)
			(layer "F.SilkS")
		)
		(fp_line
			(start 0.7874 -0.4064)
			(end 0.7874 0.4064)
			(stroke
				(width 0.1524)
				(type default)
			)
			(layer "F.SilkS")
		)
		(fp_line
			(start -0.67945 0.3048)
			(end -0.67945 -0.305054)
			(stroke
				(width 0.1)
				(type default)
			)
			(layer "F.Fab")
		)
		(fp_line
			(start -0.12065 0.3048)
			(end -0.67945 0.3048)
			(stroke
				(width 0.1)
				(type default)
			)
			(layer "F.Fab")
		)
		(fp_line
			(start 0.120396 0.3048)
			(end 0.120396 0.2794)
			(stroke
				(width 0.1)
				(type default)
			)
			(layer "F.Fab")
		)
		(fp_line
			(start 0.67945 0.3048)
			(end 0.120396 0.3048)
			(stroke
				(width 0.1)
				(type default)
			)
			(layer "F.Fab")
		)
		(fp_line
			(start -0.12065 0.2794)
			(end -0.12065 0.3048)
			(stroke
				(width 0.1)
				(type default)
			)
			(layer "F.Fab")
		)
		(fp_line
			(start 0.120396 0.2794)
			(end -0.12065 0.2794)
			(stroke
				(width 0.1)
				(type default)
			)
			(layer "F.Fab")
		)
		(fp_line
			(start -0.12065 -0.2794)
			(end 0.12065 -0.2794)
			(stroke
				(width 0.1)
				(type default)
			)
			(layer "F.Fab")
		)
		(fp_line
			(start 0.12065 -0.2794)
			(end 0.12065 -0.3048)
			(stroke
				(width 0.1)
				(type default)
			)
			(layer "F.Fab")
		)
		(fp_line
			(start 0.12065 -0.3048)
			(end 0.67945 -0.3048)
			(stroke
				(width 0.1)
				(type default)
			)
			(layer "F.Fab")
		)
		(fp_line
			(start 0.67945 -0.3048)
			(end 0.67945 0.3048)
			(stroke
				(width 0.1)
				(type default)
			)
			(layer "F.Fab")
		)
		(fp_line
			(start -0.67945 -0.305054)
			(end -0.12065 -0.305054)
			(stroke
				(width 0.1)
				(type default)
			)
			(layer "F.Fab")
		)
		(fp_line
			(start -0.12065 -0.305054)
			(end -0.12065 -0.2794)
			(stroke
				(width 0.1)
				(type default)
			)
			(layer "F.Fab")
		)
		(pad "1" smd circle
			(at -0.40005 0 270)
			(size 0 0)
			(layers "F.Cu" "F.Mask" "F.Paste")
			(net "P3V3_AUX")
		)
		(pad "2" smd circle
			(at 0.40005 0 270)
			(size 0 0)
			(layers "F.Cu" "F.Mask" "F.Paste")
			(net "P0V9_RETIMER_CPU0_PVCC")
		)
	)
	(footprint ""
		(layer "F.Cu")
		(at 181.868064 -133.58495 -90)
		(property "Reference" "R159"
			(at 0 0 270)
			(layer "F.SilkS")
			(hide yes)
			(effects
				(font
					(size 1.27 1.27)
				)
			)
		)
		(property "Value" ""
			(at 0 0 270)
			(layer "F.Fab")
			(effects
				(font
					(size 1.27 1.27)
				)
			)
		)
		(duplicate_pad_numbers_are_jumpers no)
		(fp_line
			(start -0.7874 0.4064)
			(end -0.7874 -0.4064)
			(stroke
				(width 0.1524)
				(type default)
			)
			(layer "F.SilkS")
		)
		(fp_line
			(start 0.7874 0.4064)
			(end -0.7874 0.4064)
			(stroke
				(width 0.1524)
				(type default)
			)
			(layer "F.SilkS")
		)
		(fp_line
			(start -0.7874 -0.4064)
			(end 0.7874 -0.4064)
			(stroke
				(width 0.1524)
				(type default)
			)
			(layer "F.SilkS")
		)
		(fp_line
			(start 0.7874 -0.4064)
			(end 0.7874 0.4064)
			(stroke
				(width 0.1524)
				(type default)
			)
			(layer "F.SilkS")
		)
		(fp_line
			(start -0.67945 0.3048)
			(end -0.67945 -0.305054)
			(stroke
				(width 0.1)
				(type default)
			)
			(layer "F.Fab")
		)
		(fp_line
			(start -0.12065 0.3048)
			(end -0.67945 0.3048)
			(stroke
				(width 0.1)
				(type default)
			)
			(layer "F.Fab")
		)
		(fp_line
			(start 0.120396 0.3048)
			(end 0.120396 0.2794)
			(stroke
				(width 0.1)
				(type default)
			)
			(layer "F.Fab")
		)
		(fp_line
			(start 0.67945 0.3048)
			(end 0.120396 0.3048)
			(stroke
				(width 0.1)
				(type default)
			)
			(layer "F.Fab")
		)
		(fp_line
			(start -0.12065 0.2794)
			(end -0.12065 0.3048)
			(stroke
				(width 0.1)
				(type default)
			)
			(layer "F.Fab")
		)
		(fp_line
			(start 0.120396 0.2794)
			(end -0.12065 0.2794)
			(stroke
				(width 0.1)
				(type default)
			)
			(layer "F.Fab")
		)
		(fp_line
			(start -0.12065 -0.2794)
			(end 0.12065 -0.2794)
			(stroke
				(width 0.1)
				(type default)
			)
			(layer "F.Fab")
		)
		(fp_line
			(start 0.12065 -0.2794)
			(end 0.12065 -0.3048)
			(stroke
				(width 0.1)
				(type default)
			)
			(layer "F.Fab")
		)
		(fp_line
			(start 0.12065 -0.3048)
			(end 0.67945 -0.3048)
			(stroke
				(width 0.1)
				(type default)
			)
			(layer "F.Fab")
		)
		(fp_line
			(start 0.67945 -0.3048)
			(end 0.67945 0.3048)
			(stroke
				(width 0.1)
				(type default)
			)
			(layer "F.Fab")
		)
		(fp_line
			(start -0.67945 -0.305054)
			(end -0.12065 -0.305054)
			(stroke
				(width 0.1)
				(type default)
			)
			(layer "F.Fab")
		)
		(fp_line
			(start -0.12065 -0.305054)
			(end -0.12065 -0.2794)
			(stroke
				(width 0.1)
				(type default)
			)
			(layer "F.Fab")
		)
		(pad "1" smd circle
			(at -0.40005 0 270)
			(size 0 0)
			(layers "F.Cu" "F.Mask" "F.Paste")
			(net "CPU0_JTAG_BUF_OE")
		)
		(pad "2" smd circle
			(at 0.40005 0 270)
			(size 0 0)
			(layers "F.Cu" "F.Mask" "F.Paste")
			(net "CPU0_JTAG_BUF_R_OE")
		)
	)
	(footprint ""
		(layer "F.Cu")
		(at 442.077602 -420.10711)
		(property "Reference" "PC6540"
			(at 0 0 0)
			(layer "F.SilkS")
			(hide yes)
			(effects
				(font
					(size 1.27 1.27)
				)
			)
		)
		(property "Value" ""
			(at 0 0 0)
			(layer "F.Fab")
			(effects
				(font
					(size 1.27 1.27)
				)
			)
		)
		(duplicate_pad_numbers_are_jumpers no)
		(fp_line
			(start -0.7874 -0.4064)
			(end 0.7874 -0.4064)
			(stroke
				(width 0.1524)
				(type default)
			)
			(layer "F.SilkS")
		)
		(fp_line
			(start -0.7874 0.4064)
			(end -0.7874 -0.4064)
			(stroke
				(width 0.1524)
				(type default)
			)
			(layer "F.SilkS")
		)
		(fp_line
			(start 0.7874 -0.4064)
			(end 0.7874 0.4064)
			(stroke
				(width 0.1524)
				(type default)
			)
			(layer "F.SilkS")
		)
		(fp_line
			(start 0.7874 0.4064)
			(end -0.7874 0.4064)
			(stroke
				(width 0.1524)
				(type default)
			)
			(layer "F.SilkS")
		)
		(fp_line
			(start -0.67945 -0.305054)
			(end -0.12065 -0.305054)
			(stroke
				(width 0.1)
				(type default)
			)
			(layer "F.Fab")
		)
		(fp_line
			(start -0.67945 0.3048)
			(end -0.67945 -0.305054)
			(stroke
				(width 0.1)
				(type default)
			)
			(layer "F.Fab")
		)
		(fp_line
			(start -0.12065 -0.305054)
			(end -0.12065 -0.2794)
			(stroke
				(width 0.1)
				(type default)
			)
			(layer "F.Fab")
		)
		(fp_line
			(start -0.12065 -0.2794)
			(end 0.12065 -0.2794)
			(stroke
				(width 0.1)
				(type default)
			)
			(layer "F.Fab")
		)
		(fp_line
			(start -0.12065 0.2794)
			(end -0.12065 0.3048)
			(stroke
				(width 0.1)
				(type default)
			)
			(layer "F.Fab")
		)
		(fp_line
			(start -0.12065 0.3048)
			(end -0.67945 0.3048)
			(stroke
				(width 0.1)
				(type default)
			)
			(layer "F.Fab")
		)
		(fp_line
			(start 0.120396 0.2794)
			(end -0.12065 0.2794)
			(stroke
				(width 0.1)
				(type default)
			)
			(layer "F.Fab")
		)
		(fp_line
			(start 0.120396 0.3048)
			(end 0.120396 0.2794)
			(stroke
				(width 0.1)
				(type default)
			)
			(layer "F.Fab")
		)
		(fp_line
			(start 0.12065 -0.3048)
			(end 0.67945 -0.3048)
			(stroke
				(width 0.1)
				(type default)
			)
			(layer "F.Fab")
		)
		(fp_line
			(start 0.12065 -0.2794)
			(end 0.12065 -0.3048)
			(stroke
				(width 0.1)
				(type default)
			)
			(layer "F.Fab")
		)
		(fp_line
			(start 0.67945 -0.3048)
			(end 0.67945 0.3048)
			(stroke
				(width 0.1)
				(type default)
			)
			(layer "F.Fab")
		)
		(fp_line
			(start 0.67945 0.3048)
			(end 0.120396 0.3048)
			(stroke
				(width 0.1)
				(type default)
			)
			(layer "F.Fab")
		)
		(pad "1" smd circle
			(at -0.40005 0)
			(size 0 0)
			(layers "F.Cu" "F.Mask" "F.Paste")
			(net "P0V9_RETIMER_CPU0_SENSE_R_P")
		)
		(pad "2" smd circle
			(at 0.40005 0)
			(size 0 0)
			(layers "F.Cu" "F.Mask" "F.Paste")
			(net "P0V9_RETIMER_CPU0_SENSE_SH_N")
		)
	)
	(footprint ""
		(layer "F.Cu")
		(at 420.75735 -38.547548)
		(property "Reference" "R22"
			(at 0 0 0)
			(layer "F.SilkS")
			(hide yes)
			(effects
				(font
					(size 1.27 1.27)
				)
			)
		)
		(property "Value" ""
			(at 0 0 0)
			(layer "F.Fab")
			(effects
				(font
					(size 1.27 1.27)
				)
			)
		)
		(duplicate_pad_numbers_are_jumpers no)
		(fp_line
			(start -0.7874 -0.4064)
			(end 0.7874 -0.4064)
			(stroke
				(width 0.1524)
				(type default)
			)
			(layer "F.SilkS")
		)
		(fp_line
			(start -0.7874 0.4064)
			(end -0.7874 -0.4064)
			(stroke
				(width 0.1524)
				(type default)
			)
			(layer "F.SilkS")
		)
		(fp_line
			(start 0.7874 -0.4064)
			(end 0.7874 0.4064)
			(stroke
				(width 0.1524)
				(type default)
			)
			(layer "F.SilkS")
		)
		(fp_line
			(start 0.7874 0.4064)
			(end -0.7874 0.4064)
			(stroke
				(width 0.1524)
				(type default)
			)
			(layer "F.SilkS")
		)
		(fp_line
			(start -0.67945 -0.305054)
			(end -0.12065 -0.305054)
			(stroke
				(width 0.1)
				(type default)
			)
			(layer "F.Fab")
		)
		(fp_line
			(start -0.67945 0.3048)
			(end -0.67945 -0.305054)
			(stroke
				(width 0.1)
				(type default)
			)
			(layer "F.Fab")
		)
		(fp_line
			(start -0.12065 -0.305054)
			(end -0.12065 -0.2794)
			(stroke
				(width 0.1)
				(type default)
			)
			(layer "F.Fab")
		)
		(fp_line
			(start -0.12065 -0.2794)
			(end 0.12065 -0.2794)
			(stroke
				(width 0.1)
				(type default)
			)
			(layer "F.Fab")
		)
		(fp_line
			(start -0.12065 0.2794)
			(end -0.12065 0.3048)
			(stroke
				(width 0.1)
				(type default)
			)
			(layer "F.Fab")
		)
		(fp_line
			(start -0.12065 0.3048)
			(end -0.67945 0.3048)
			(stroke
				(width 0.1)
				(type default)
			)
			(layer "F.Fab")
		)
		(fp_line
			(start 0.120396 0.2794)
			(end -0.12065 0.2794)
			(stroke
				(width 0.1)
				(type default)
			)
			(layer "F.Fab")
		)
		(fp_line
			(start 0.120396 0.3048)
			(end 0.120396 0.2794)
			(stroke
				(width 0.1)
				(type default)
			)
			(layer "F.Fab")
		)
		(fp_line
			(start 0.12065 -0.3048)
			(end 0.67945 -0.3048)
			(stroke
				(width 0.1)
				(type default)
			)
			(layer "F.Fab")
		)
		(fp_line
			(start 0.12065 -0.2794)
			(end 0.12065 -0.3048)
			(stroke
				(width 0.1)
				(type default)
			)
			(layer "F.Fab")
		)
		(fp_line
			(start 0.67945 -0.3048)
			(end 0.67945 0.3048)
			(stroke
				(width 0.1)
				(type default)
			)
			(layer "F.Fab")
		)
		(fp_line
			(start 0.67945 0.3048)
			(end 0.120396 0.3048)
			(stroke
				(width 0.1)
				(type default)
			)
			(layer "F.Fab")
		)
		(pad "1" smd circle
			(at -0.40005 0)
			(size 0 0)
			(layers "F.Cu" "F.Mask" "F.Paste")
			(net "P1V8_AUX")
		)
		(pad "2" smd circle
			(at 0.40005 0)
			(size 0 0)
			(layers "F.Cu" "F.Mask" "F.Paste")
			(net "PU_BIOS_USB_RECOVERY")
		)
	)
	(footprint ""
		(layer "F.Cu")
		(at 162.162744 -344.153998 -90)
		(property "Reference" "PR406"
			(at 0 0 270)
			(layer "F.SilkS")
			(hide yes)
			(effects
				(font
					(size 1.27 1.27)
				)
			)
		)
		(property "Value" ""
			(at 0 0 270)
			(layer "F.Fab")
			(effects
				(font
					(size 1.27 1.27)
				)
			)
		)
		(duplicate_pad_numbers_are_jumpers no)
		(fp_line
			(start -0.7874 0.4064)
			(end -0.7874 -0.4064)
			(stroke
				(width 0.1524)
				(type default)
			)
			(layer "F.SilkS")
		)
		(fp_line
			(start 0.7874 0.4064)
			(end -0.7874 0.4064)
			(stroke
				(width 0.1524)
				(type default)
			)
			(layer "F.SilkS")
		)
		(fp_line
			(start -0.7874 -0.4064)
			(end 0.7874 -0.4064)
			(stroke
				(width 0.1524)
				(type default)
			)
			(layer "F.SilkS")
		)
		(fp_line
			(start 0.7874 -0.4064)
			(end 0.7874 0.4064)
			(stroke
				(width 0.1524)
				(type default)
			)
			(layer "F.SilkS")
		)
		(fp_line
			(start -0.67945 0.3048)
			(end -0.67945 -0.305054)
			(stroke
				(width 0.1)
				(type default)
			)
			(layer "F.Fab")
		)
		(fp_line
			(start -0.12065 0.3048)
			(end -0.67945 0.3048)
			(stroke
				(width 0.1)
				(type default)
			)
			(layer "F.Fab")
		)
		(fp_line
			(start 0.120396 0.3048)
			(end 0.120396 0.2794)
			(stroke
				(width 0.1)
				(type default)
			)
			(layer "F.Fab")
		)
		(fp_line
			(start 0.67945 0.3048)
			(end 0.120396 0.3048)
			(stroke
				(width 0.1)
				(type default)
			)
			(layer "F.Fab")
		)
		(fp_line
			(start -0.12065 0.2794)
			(end -0.12065 0.3048)
			(stroke
				(width 0.1)
				(type default)
			)
			(layer "F.Fab")
		)
		(fp_line
			(start 0.120396 0.2794)
			(end -0.12065 0.2794)
			(stroke
				(width 0.1)
				(type default)
			)
			(layer "F.Fab")
		)
		(fp_line
			(start -0.12065 -0.2794)
			(end 0.12065 -0.2794)
			(stroke
				(width 0.1)
				(type default)
			)
			(layer "F.Fab")
		)
		(fp_line
			(start 0.12065 -0.2794)
			(end 0.12065 -0.3048)
			(stroke
				(width 0.1)
				(type default)
			)
			(layer "F.Fab")
		)
		(fp_line
			(start 0.12065 -0.3048)
			(end 0.67945 -0.3048)
			(stroke
				(width 0.1)
				(type default)
			)
			(layer "F.Fab")
		)
		(fp_line
			(start 0.67945 -0.3048)
			(end 0.67945 0.3048)
			(stroke
				(width 0.1)
				(type default)
			)
			(layer "F.Fab")
		)
		(fp_line
			(start -0.67945 -0.305054)
			(end -0.12065 -0.305054)
			(stroke
				(width 0.1)
				(type default)
			)
			(layer "F.Fab")
		)
		(fp_line
			(start -0.12065 -0.305054)
			(end -0.12065 -0.2794)
			(stroke
				(width 0.1)
				(type default)
			)
			(layer "F.Fab")
		)
		(pad "1" smd circle
			(at -0.40005 0 270)
			(size 0 0)
			(layers "F.Cu" "F.Mask" "F.Paste")
			(net "NC_PVDD11_S3_P1_IMON3")
		)
		(pad "2" smd circle
			(at 0.40005 0 270)
			(size 0 0)
			(layers "F.Cu" "F.Mask" "F.Paste")
			(net "GND")
		)
	)
	(footprint ""
		(layer "F.Cu")
		(at 103.185722 -26.435304 90)
		(property "Reference" "R6330"
			(at 0 0 90)
			(layer "F.SilkS")
			(hide yes)
			(effects
				(font
					(size 1.27 1.27)
				)
			)
		)
		(property "Value" ""
			(at 0 0 90)
			(layer "F.Fab")
			(effects
				(font
					(size 1.27 1.27)
				)
			)
		)
		(duplicate_pad_numbers_are_jumpers no)
		(fp_line
			(start 0.7874 -0.4064)
			(end 0.7874 0.4064)
			(stroke
				(width 0.1524)
				(type default)
			)
			(layer "F.SilkS")
		)
		(fp_line
			(start -0.7874 -0.4064)
			(end 0.7874 -0.4064)
			(stroke
				(width 0.1524)
				(type default)
			)
			(layer "F.SilkS")
		)
		(fp_line
			(start 0.7874 0.4064)
			(end -0.7874 0.4064)
			(stroke
				(width 0.1524)
				(type default)
			)
			(layer "F.SilkS")
		)
		(fp_line
			(start -0.7874 0.4064)
			(end -0.7874 -0.4064)
			(stroke
				(width 0.1524)
				(type default)
			)
			(layer "F.SilkS")
		)
		(fp_line
			(start -0.12065 -0.305054)
			(end -0.12065 -0.2794)
			(stroke
				(width 0.1)
				(type default)
			)
			(layer "F.Fab")
		)
		(fp_line
			(start -0.67945 -0.305054)
			(end -0.12065 -0.305054)
			(stroke
				(width 0.1)
				(type default)
			)
			(layer "F.Fab")
		)
		(fp_line
			(start 0.67945 -0.3048)
			(end 0.67945 0.3048)
			(stroke
				(width 0.1)
				(type default)
			)
			(layer "F.Fab")
		)
		(fp_line
			(start 0.12065 -0.3048)
			(end 0.67945 -0.3048)
			(stroke
				(width 0.1)
				(type default)
			)
			(layer "F.Fab")
		)
		(fp_line
			(start 0.12065 -0.2794)
			(end 0.12065 -0.3048)
			(stroke
				(width 0.1)
				(type default)
			)
			(layer "F.Fab")
		)
		(fp_line
			(start -0.12065 -0.2794)
			(end 0.12065 -0.2794)
			(stroke
				(width 0.1)
				(type default)
			)
			(layer "F.Fab")
		)
		(fp_line
			(start 0.120396 0.2794)
			(end -0.12065 0.2794)
			(stroke
				(width 0.1)
				(type default)
			)
			(layer "F.Fab")
		)
		(fp_line
			(start -0.12065 0.2794)
			(end -0.12065 0.3048)
			(stroke
				(width 0.1)
				(type default)
			)
			(layer "F.Fab")
		)
		(fp_line
			(start 0.67945 0.3048)
			(end 0.120396 0.3048)
			(stroke
				(width 0.1)
				(type default)
			)
			(layer "F.Fab")
		)
		(fp_line
			(start 0.120396 0.3048)
			(end 0.120396 0.2794)
			(stroke
				(width 0.1)
				(type default)
			)
			(layer "F.Fab")
		)
		(fp_line
			(start -0.12065 0.3048)
			(end -0.67945 0.3048)
			(stroke
				(width 0.1)
				(type default)
			)
			(layer "F.Fab")
		)
		(fp_line
			(start -0.67945 0.3048)
			(end -0.67945 -0.305054)
			(stroke
				(width 0.1)
				(type default)
			)
			(layer "F.Fab")
		)
		(pad "1" smd circle
			(at -0.40005 0 90)
			(size 0 0)
			(layers "F.Cu" "F.Mask" "F.Paste")
			(net "GND")
		)
		(pad "2" smd circle
			(at 0.40005 0 90)
			(size 0 0)
			(layers "F.Cu" "F.Mask" "F.Paste")
			(net "USB_HUB2_TI_NC_MRP_ATEST")
		)
	)
	(footprint ""
		(layer "F.Cu")
		(at 356.29596 -259.845048)
		(property "Reference" "C3898"
			(at 0 0 0)
			(layer "F.SilkS")
			(hide yes)
			(effects
				(font
					(size 1.27 1.27)
				)
			)
		)
		(property "Value" ""
			(at 0 0 0)
			(layer "F.Fab")
			(effects
				(font
					(size 1.27 1.27)
				)
			)
		)
		(duplicate_pad_numbers_are_jumpers no)
		(fp_line
			(start -0.7874 -0.4064)
			(end 0.7874 -0.4064)
			(stroke
				(width 0.1524)
				(type default)
			)
			(layer "F.SilkS")
		)
		(fp_line
			(start -0.7874 0.4064)
			(end -0.7874 -0.4064)
			(stroke
				(width 0.1524)
				(type default)
			)
			(layer "F.SilkS")
		)
		(fp_line
			(start 0.7874 -0.4064)
			(end 0.7874 0.4064)
			(stroke
				(width 0.1524)
				(type default)
			)
			(layer "F.SilkS")
		)
		(fp_line
			(start 0.7874 0.4064)
			(end -0.7874 0.4064)
			(stroke
				(width 0.1524)
				(type default)
			)
			(layer "F.SilkS")
		)
		(fp_line
			(start -0.67945 -0.305054)
			(end -0.12065 -0.305054)
			(stroke
				(width 0.1)
				(type default)
			)
			(layer "F.Fab")
		)
		(fp_line
			(start -0.67945 0.3048)
			(end -0.67945 -0.305054)
			(stroke
				(width 0.1)
				(type default)
			)
			(layer "F.Fab")
		)
		(fp_line
			(start -0.12065 -0.305054)
			(end -0.12065 -0.2794)
			(stroke
				(width 0.1)
				(type default)
			)
			(layer "F.Fab")
		)
		(fp_line
			(start -0.12065 -0.2794)
			(end 0.12065 -0.2794)
			(stroke
				(width 0.1)
				(type default)
			)
			(layer "F.Fab")
		)
		(fp_line
			(start -0.12065 0.2794)
			(end -0.12065 0.3048)
			(stroke
				(width 0.1)
				(type default)
			)
			(layer "F.Fab")
		)
		(fp_line
			(start -0.12065 0.3048)
			(end -0.67945 0.3048)
			(stroke
				(width 0.1)
				(type default)
			)
			(layer "F.Fab")
		)
		(fp_line
			(start 0.120396 0.2794)
			(end -0.12065 0.2794)
			(stroke
				(width 0.1)
				(type default)
			)
			(layer "F.Fab")
		)
		(fp_line
			(start 0.120396 0.3048)
			(end 0.120396 0.2794)
			(stroke
				(width 0.1)
				(type default)
			)
			(layer "F.Fab")
		)
		(fp_line
			(start 0.12065 -0.3048)
			(end 0.67945 -0.3048)
			(stroke
				(width 0.1)
				(type default)
			)
			(layer "F.Fab")
		)
		(fp_line
			(start 0.12065 -0.2794)
			(end 0.12065 -0.3048)
			(stroke
				(width 0.1)
				(type default)
			)
			(layer "F.Fab")
		)
		(fp_line
			(start 0.67945 -0.3048)
			(end 0.67945 0.3048)
			(stroke
				(width 0.1)
				(type default)
			)
			(layer "F.Fab")
		)
		(fp_line
			(start 0.67945 0.3048)
			(end 0.120396 0.3048)
			(stroke
				(width 0.1)
				(type default)
			)
			(layer "F.Fab")
		)
		(pad "1" smd circle
			(at -0.40005 0)
			(size 0 0)
			(layers "F.Cu" "F.Mask" "F.Paste")
			(net "PVDDIO_P0")
		)
		(pad "2" smd circle
			(at 0.40005 0)
			(size 0 0)
			(layers "F.Cu" "F.Mask" "F.Paste")
			(net "GND")
		)
	)
	(footprint ""
		(layer "F.Cu")
		(at 182.047134 -160.595818 90)
		(property "Reference" "R5020"
			(at 0 0 90)
			(layer "F.SilkS")
			(hide yes)
			(effects
				(font
					(size 1.27 1.27)
				)
			)
		)
		(property "Value" ""
			(at 0 0 90)
			(layer "F.Fab")
			(effects
				(font
					(size 1.27 1.27)
				)
			)
		)
		(duplicate_pad_numbers_are_jumpers no)
		(fp_line
			(start 0.7874 -0.4064)
			(end 0.7874 0.4064)
			(stroke
				(width 0.1524)
				(type default)
			)
			(layer "F.SilkS")
		)
		(fp_line
			(start -0.7874 -0.4064)
			(end 0.7874 -0.4064)
			(stroke
				(width 0.1524)
				(type default)
			)
			(layer "F.SilkS")
		)
		(fp_line
			(start 0.7874 0.4064)
			(end -0.7874 0.4064)
			(stroke
				(width 0.1524)
				(type default)
			)
			(layer "F.SilkS")
		)
		(fp_line
			(start -0.7874 0.4064)
			(end -0.7874 -0.4064)
			(stroke
				(width 0.1524)
				(type default)
			)
			(layer "F.SilkS")
		)
		(fp_line
			(start -0.12065 -0.305054)
			(end -0.12065 -0.2794)
			(stroke
				(width 0.1)
				(type default)
			)
			(layer "F.Fab")
		)
		(fp_line
			(start -0.67945 -0.305054)
			(end -0.12065 -0.305054)
			(stroke
				(width 0.1)
				(type default)
			)
			(layer "F.Fab")
		)
		(fp_line
			(start 0.67945 -0.3048)
			(end 0.67945 0.3048)
			(stroke
				(width 0.1)
				(type default)
			)
			(layer "F.Fab")
		)
		(fp_line
			(start 0.12065 -0.3048)
			(end 0.67945 -0.3048)
			(stroke
				(width 0.1)
				(type default)
			)
			(layer "F.Fab")
		)
		(fp_line
			(start 0.12065 -0.2794)
			(end 0.12065 -0.3048)
			(stroke
				(width 0.1)
				(type default)
			)
			(layer "F.Fab")
		)
		(fp_line
			(start -0.12065 -0.2794)
			(end 0.12065 -0.2794)
			(stroke
				(width 0.1)
				(type default)
			)
			(layer "F.Fab")
		)
		(fp_line
			(start 0.120396 0.2794)
			(end -0.12065 0.2794)
			(stroke
				(width 0.1)
				(type default)
			)
			(layer "F.Fab")
		)
		(fp_line
			(start -0.12065 0.2794)
			(end -0.12065 0.3048)
			(stroke
				(width 0.1)
				(type default)
			)
			(layer "F.Fab")
		)
		(fp_line
			(start 0.67945 0.3048)
			(end 0.120396 0.3048)
			(stroke
				(width 0.1)
				(type default)
			)
			(layer "F.Fab")
		)
		(fp_line
			(start 0.120396 0.3048)
			(end 0.120396 0.2794)
			(stroke
				(width 0.1)
				(type default)
			)
			(layer "F.Fab")
		)
		(fp_line
			(start -0.12065 0.3048)
			(end -0.67945 0.3048)
			(stroke
				(width 0.1)
				(type default)
			)
			(layer "F.Fab")
		)
		(fp_line
			(start -0.67945 0.3048)
			(end -0.67945 -0.305054)
			(stroke
				(width 0.1)
				(type default)
			)
			(layer "F.Fab")
		)
		(pad "1" smd circle
			(at -0.40005 0 90)
			(size 0 0)
			(layers "F.Cu" "F.Mask" "F.Paste")
			(net "PVDD11_S3_P1")
		)
		(pad "2" smd circle
			(at 0.40005 0 90)
			(size 0 0)
			(layers "F.Cu" "F.Mask" "F.Paste")
			(net "I3C_SCM_3_R_SCL")
		)
	)
	(footprint ""
		(layer "F.Cu")
		(at 170.299634 -423.870882 -90)
		(property "Reference" "U21"
			(at -0.392938 -3.18262 90)
			(unlocked yes)
			(layer "F.SilkS")
			(effects
				(font
					(size 0.7874 0.5842)
					(thickness 0.1524)
				)
				(justify left)
			)
		)
		(property "Value" ""
			(at 0 0 270)
			(layer "F.Fab")
			(effects
				(font
					(size 1.27 1.27)
				)
			)
		)
		(duplicate_pad_numbers_are_jumpers no)
		(fp_line
			(start -1.8288 2.500122)
			(end 1.8288 2.500122)
			(stroke
				(width 0.1524)
				(type default)
			)
			(layer "F.SilkS")
		)
		(fp_line
			(start 1.8288 2.500122)
			(end 1.8288 -2.500122)
			(stroke
				(width 0.1524)
				(type default)
			)
			(layer "F.SilkS")
		)
		(fp_line
			(start 0 -1.4224)
			(end -1.077722 -2.500122)
			(stroke
				(width 0.1524)
				(type default)
			)
			(layer "F.SilkS")
		)
		(fp_line
			(start -1.8288 -2.500122)
			(end -1.8288 2.500122)
			(stroke
				(width 0.1524)
				(type default)
			)
			(layer "F.SilkS")
		)
		(fp_line
			(start -1.077722 -2.500122)
			(end -1.8288 -2.500122)
			(stroke
				(width 0.1524)
				(type default)
			)
			(layer "F.SilkS")
		)
		(fp_line
			(start 1.077722 -2.500122)
			(end 0 -1.4224)
			(stroke
				(width 0.1524)
				(type default)
			)
			(layer "F.SilkS")
		)
		(fp_line
			(start 1.8288 -2.500122)
			(end 1.077722 -2.500122)
			(stroke
				(width 0.1524)
				(type default)
			)
			(layer "F.SilkS")
		)
		(fp_poly
			(pts
				(xy -4.51485 -2.535174) (xy -4.51485 -1.519174) (xy -3.49885 -2.027174)
			)
			(stroke
				(width 0)
				(type default)
			)
			(fill yes)
			(layer "F.SilkS")
		)
		(fp_line
			(start -1.999996 2.500122)
			(end 1.999996 2.500122)
			(stroke
				(width 0.1)
				(type default)
			)
			(layer "F.Fab")
		)
		(fp_line
			(start 1.999996 2.500122)
			(end 1.999996 -2.500122)
			(stroke
				(width 0.1)
				(type default)
			)
			(layer "F.Fab")
		)
		(fp_line
			(start -1.999996 -2.500122)
			(end -1.999996 2.500122)
			(stroke
				(width 0.1)
				(type default)
			)
			(layer "F.Fab")
		)
		(fp_line
			(start 1.999996 -2.500122)
			(end -1.999996 -2.500122)
			(stroke
				(width 0.1)
				(type default)
			)
			(layer "F.Fab")
		)
		(fp_poly
			(pts
				(xy -4.5085 -2.413) (xy -4.5085 -1.397) (xy -3.4925 -1.905)
			)
			(stroke
				(width 0)
				(type default)
			)
			(fill yes)
			(layer "F.Fab")
		)
		(pad "1" smd rect
			(at -2.599944 -1.905 180)
			(size 0.889 1.27)
			(layers "F.Cu" "F.Mask" "F.Paste")
			(net "Net_10833")
		)
		(pad "2" smd rect
			(at -2.599944 -0.635 180)
			(size 0.889 1.27)
			(layers "F.Cu" "F.Mask" "F.Paste")
			(net "Net_10832")
		)
		(pad "3" smd rect
			(at -2.599944 0.635 180)
			(size 0.889 1.27)
			(layers "F.Cu" "F.Mask" "F.Paste")
			(net "U21_E2")
		)
		(pad "4" smd rect
			(at -2.599944 1.905 180)
			(size 0.889 1.27)
			(layers "F.Cu" "F.Mask" "F.Paste")
			(net "GND")
		)
		(pad "5" smd rect
			(at 2.599944 1.905 180)
			(size 0.889 1.27)
			(layers "F.Cu" "F.Mask" "F.Paste")
			(net "SMB_RT_CPU1_P3_ROM_SDA")
		)
		(pad "6" smd rect
			(at 2.599944 0.635 180)
			(size 0.889 1.27)
			(layers "F.Cu" "F.Mask" "F.Paste")
			(net "SMB_RT_CPU1_P3_ROM_SCL")
		)
		(pad "7" smd rect
			(at 2.599944 -0.635 180)
			(size 0.889 1.27)
			(layers "F.Cu" "F.Mask" "F.Paste")
			(net "GND")
		)
		(pad "8" smd rect
			(at 2.599944 -1.905 180)
			(size 0.889 1.27)
			(layers "F.Cu" "F.Mask" "F.Paste")
			(net "P1V8_CPU1_RT_1D")
		)
	)
	(footprint ""
		(layer "F.Cu")
		(at 293.550086 -435.600094)
		(property "Reference" "H104"
			(at -7.357364 -3.906266 0)
			(unlocked yes)
			(layer "F.SilkS")
			(effects
				(font
					(size 0.7874 0.5842)
					(thickness 0.1524)
				)
				(justify left)
			)
		)
		(property "Value" ""
			(at 0 0 0)
			(layer "F.Fab")
			(effects
				(font
					(size 1.27 1.27)
				)
			)
		)
		(duplicate_pad_numbers_are_jumpers no)
		(pad "1" thru_hole circle
			(at 0 0)
			(size 10.0076 10.0076)
			(drill 5.6134)
			(layers "*.Cu" "*.Mask")
			(remove_unused_layers no)
			(net "GND")
			(clearance -1.9431)
		)
	)
	(footprint ""
		(layer "F.Cu")
		(at 214.613744 -23.304754 90)
		(property "Reference" "R1138"
			(at 0 0 90)
			(layer "F.SilkS")
			(hide yes)
			(effects
				(font
					(size 1.27 1.27)
				)
			)
		)
		(property "Value" ""
			(at 0 0 90)
			(layer "F.Fab")
			(effects
				(font
					(size 1.27 1.27)
				)
			)
		)
		(duplicate_pad_numbers_are_jumpers no)
		(fp_line
			(start 0.7874 -0.4064)
			(end 0.7874 0.4064)
			(stroke
				(width 0.1524)
				(type default)
			)
			(layer "F.SilkS")
		)
		(fp_line
			(start -0.7874 -0.4064)
			(end 0.7874 -0.4064)
			(stroke
				(width 0.1524)
				(type default)
			)
			(layer "F.SilkS")
		)
		(fp_line
			(start 0.7874 0.4064)
			(end -0.7874 0.4064)
			(stroke
				(width 0.1524)
				(type default)
			)
			(layer "F.SilkS")
		)
		(fp_line
			(start -0.7874 0.4064)
			(end -0.7874 -0.4064)
			(stroke
				(width 0.1524)
				(type default)
			)
			(layer "F.SilkS")
		)
		(fp_line
			(start -0.12065 -0.305054)
			(end -0.12065 -0.2794)
			(stroke
				(width 0.1)
				(type default)
			)
			(layer "F.Fab")
		)
		(fp_line
			(start -0.67945 -0.305054)
			(end -0.12065 -0.305054)
			(stroke
				(width 0.1)
				(type default)
			)
			(layer "F.Fab")
		)
		(fp_line
			(start 0.67945 -0.3048)
			(end 0.67945 0.3048)
			(stroke
				(width 0.1)
				(type default)
			)
			(layer "F.Fab")
		)
		(fp_line
			(start 0.12065 -0.3048)
			(end 0.67945 -0.3048)
			(stroke
				(width 0.1)
				(type default)
			)
			(layer "F.Fab")
		)
		(fp_line
			(start 0.12065 -0.2794)
			(end 0.12065 -0.3048)
			(stroke
				(width 0.1)
				(type default)
			)
			(layer "F.Fab")
		)
		(fp_line
			(start -0.12065 -0.2794)
			(end 0.12065 -0.2794)
			(stroke
				(width 0.1)
				(type default)
			)
			(layer "F.Fab")
		)
		(fp_line
			(start 0.120396 0.2794)
			(end -0.12065 0.2794)
			(stroke
				(width 0.1)
				(type default)
			)
			(layer "F.Fab")
		)
		(fp_line
			(start -0.12065 0.2794)
			(end -0.12065 0.3048)
			(stroke
				(width 0.1)
				(type default)
			)
			(layer "F.Fab")
		)
		(fp_line
			(start 0.67945 0.3048)
			(end 0.120396 0.3048)
			(stroke
				(width 0.1)
				(type default)
			)
			(layer "F.Fab")
		)
		(fp_line
			(start 0.120396 0.3048)
			(end 0.120396 0.2794)
			(stroke
				(width 0.1)
				(type default)
			)
			(layer "F.Fab")
		)
		(fp_line
			(start -0.12065 0.3048)
			(end -0.67945 0.3048)
			(stroke
				(width 0.1)
				(type default)
			)
			(layer "F.Fab")
		)
		(fp_line
			(start -0.67945 0.3048)
			(end -0.67945 -0.305054)
			(stroke
				(width 0.1)
				(type default)
			)
			(layer "F.Fab")
		)
		(pad "1" smd circle
			(at -0.40005 0 90)
			(size 0 0)
			(layers "F.Cu" "F.Mask" "F.Paste")
			(net "P3V3_AUX")
		)
		(pad "2" smd circle
			(at 0.40005 0 90)
			(size 0 0)
			(layers "F.Cu" "F.Mask" "F.Paste")
			(net "CLK_50M_EN")
		)
	)
	(footprint ""
		(layer "F.Cu")
		(at 241.112802 -70.143624 -90)
		(property "Reference" "R955"
			(at 0 0 270)
			(layer "F.SilkS")
			(hide yes)
			(effects
				(font
					(size 1.27 1.27)
				)
			)
		)
		(property "Value" ""
			(at 0 0 270)
			(layer "F.Fab")
			(effects
				(font
					(size 1.27 1.27)
				)
			)
		)
		(duplicate_pad_numbers_are_jumpers no)
		(fp_line
			(start -0.7874 0.4064)
			(end -0.7874 -0.4064)
			(stroke
				(width 0.1524)
				(type default)
			)
			(layer "F.SilkS")
		)
		(fp_line
			(start 0.7874 0.4064)
			(end -0.7874 0.4064)
			(stroke
				(width 0.1524)
				(type default)
			)
			(layer "F.SilkS")
		)
		(fp_line
			(start -0.7874 -0.4064)
			(end 0.7874 -0.4064)
			(stroke
				(width 0.1524)
				(type default)
			)
			(layer "F.SilkS")
		)
		(fp_line
			(start 0.7874 -0.4064)
			(end 0.7874 0.4064)
			(stroke
				(width 0.1524)
				(type default)
			)
			(layer "F.SilkS")
		)
		(fp_line
			(start -0.67945 0.3048)
			(end -0.67945 -0.305054)
			(stroke
				(width 0.1)
				(type default)
			)
			(layer "F.Fab")
		)
		(fp_line
			(start -0.12065 0.3048)
			(end -0.67945 0.3048)
			(stroke
				(width 0.1)
				(type default)
			)
			(layer "F.Fab")
		)
		(fp_line
			(start 0.120396 0.3048)
			(end 0.120396 0.2794)
			(stroke
				(width 0.1)
				(type default)
			)
			(layer "F.Fab")
		)
		(fp_line
			(start 0.67945 0.3048)
			(end 0.120396 0.3048)
			(stroke
				(width 0.1)
				(type default)
			)
			(layer "F.Fab")
		)
		(fp_line
			(start -0.12065 0.2794)
			(end -0.12065 0.3048)
			(stroke
				(width 0.1)
				(type default)
			)
			(layer "F.Fab")
		)
		(fp_line
			(start 0.120396 0.2794)
			(end -0.12065 0.2794)
			(stroke
				(width 0.1)
				(type default)
			)
			(layer "F.Fab")
		)
		(fp_line
			(start -0.12065 -0.2794)
			(end 0.12065 -0.2794)
			(stroke
				(width 0.1)
				(type default)
			)
			(layer "F.Fab")
		)
		(fp_line
			(start 0.12065 -0.2794)
			(end 0.12065 -0.3048)
			(stroke
				(width 0.1)
				(type default)
			)
			(layer "F.Fab")
		)
		(fp_line
			(start 0.12065 -0.3048)
			(end 0.67945 -0.3048)
			(stroke
				(width 0.1)
				(type default)
			)
			(layer "F.Fab")
		)
		(fp_line
			(start 0.67945 -0.3048)
			(end 0.67945 0.3048)
			(stroke
				(width 0.1)
				(type default)
			)
			(layer "F.Fab")
		)
		(fp_line
			(start -0.67945 -0.305054)
			(end -0.12065 -0.305054)
			(stroke
				(width 0.1)
				(type default)
			)
			(layer "F.Fab")
		)
		(fp_line
			(start -0.12065 -0.305054)
			(end -0.12065 -0.2794)
			(stroke
				(width 0.1)
				(type default)
			)
			(layer "F.Fab")
		)
		(pad "1" smd circle
			(at -0.40005 0 270)
			(size 0 0)
			(layers "F.Cu" "F.Mask" "F.Paste")
			(net "FM_LED_ACTIVE_E1S_0")
		)
		(pad "2" smd circle
			(at 0.40005 0 270)
			(size 0 0)
			(layers "F.Cu" "F.Mask" "F.Paste")
			(net "FM_LED_ACTIVE_E1S_0_R")
		)
	)
	(footprint ""
		(layer "F.Cu")
		(at 359.7275 -172.50029)
		(property "Reference" "PC184"
			(at 0 0 0)
			(layer "F.SilkS")
			(hide yes)
			(effects
				(font
					(size 1.27 1.27)
				)
			)
		)
		(property "Value" ""
			(at 0 0 0)
			(layer "F.Fab")
			(effects
				(font
					(size 1.27 1.27)
				)
			)
		)
		(duplicate_pad_numbers_are_jumpers no)
		(fp_line
			(start -0.7874 -0.4064)
			(end 0.7874 -0.4064)
			(stroke
				(width 0.1524)
				(type default)
			)
			(layer "F.SilkS")
		)
		(fp_line
			(start -0.7874 0.4064)
			(end -0.7874 -0.4064)
			(stroke
				(width 0.1524)
				(type default)
			)
			(layer "F.SilkS")
		)
		(fp_line
			(start 0.7874 -0.4064)
			(end 0.7874 0.4064)
			(stroke
				(width 0.1524)
				(type default)
			)
			(layer "F.SilkS")
		)
		(fp_line
			(start 0.7874 0.4064)
			(end -0.7874 0.4064)
			(stroke
				(width 0.1524)
				(type default)
			)
			(layer "F.SilkS")
		)
		(fp_line
			(start -0.67945 -0.305054)
			(end -0.12065 -0.305054)
			(stroke
				(width 0.1)
				(type default)
			)
			(layer "F.Fab")
		)
		(fp_line
			(start -0.67945 0.3048)
			(end -0.67945 -0.305054)
			(stroke
				(width 0.1)
				(type default)
			)
			(layer "F.Fab")
		)
		(fp_line
			(start -0.12065 -0.305054)
			(end -0.12065 -0.2794)
			(stroke
				(width 0.1)
				(type default)
			)
			(layer "F.Fab")
		)
		(fp_line
			(start -0.12065 -0.2794)
			(end 0.12065 -0.2794)
			(stroke
				(width 0.1)
				(type default)
			)
			(layer "F.Fab")
		)
		(fp_line
			(start -0.12065 0.2794)
			(end -0.12065 0.3048)
			(stroke
				(width 0.1)
				(type default)
			)
			(layer "F.Fab")
		)
		(fp_line
			(start -0.12065 0.3048)
			(end -0.67945 0.3048)
			(stroke
				(width 0.1)
				(type default)
			)
			(layer "F.Fab")
		)
		(fp_line
			(start 0.120396 0.2794)
			(end -0.12065 0.2794)
			(stroke
				(width 0.1)
				(type default)
			)
			(layer "F.Fab")
		)
		(fp_line
			(start 0.120396 0.3048)
			(end 0.120396 0.2794)
			(stroke
				(width 0.1)
				(type default)
			)
			(layer "F.Fab")
		)
		(fp_line
			(start 0.12065 -0.3048)
			(end 0.67945 -0.3048)
			(stroke
				(width 0.1)
				(type default)
			)
			(layer "F.Fab")
		)
		(fp_line
			(start 0.12065 -0.2794)
			(end 0.12065 -0.3048)
			(stroke
				(width 0.1)
				(type default)
			)
			(layer "F.Fab")
		)
		(fp_line
			(start 0.67945 -0.3048)
			(end 0.67945 0.3048)
			(stroke
				(width 0.1)
				(type default)
			)
			(layer "F.Fab")
		)
		(fp_line
			(start 0.67945 0.3048)
			(end 0.120396 0.3048)
			(stroke
				(width 0.1)
				(type default)
			)
			(layer "F.Fab")
		)
		(pad "1" smd circle
			(at -0.40005 0)
			(size 0 0)
			(layers "F.Cu" "F.Mask" "F.Paste")
			(net "SW_PVDDCR_CPU0_P0_SW5")
		)
		(pad "2" smd circle
			(at 0.40005 0)
			(size 0 0)
			(layers "F.Cu" "F.Mask" "F.Paste")
			(net "SW_PVDDCR_CPU0_P0_SW5_RC")
		)
	)
	(footprint ""
		(layer "F.Cu")
		(at 145.773394 -54.913784 -90)
		(property "Reference" "C1505"
			(at 0 0 270)
			(layer "F.SilkS")
			(hide yes)
			(effects
				(font
					(size 1.27 1.27)
				)
			)
		)
		(property "Value" ""
			(at 0 0 270)
			(layer "F.Fab")
			(effects
				(font
					(size 1.27 1.27)
				)
			)
		)
		(duplicate_pad_numbers_are_jumpers no)
		(fp_line
			(start -0.7874 0.4064)
			(end -0.7874 -0.4064)
			(stroke
				(width 0.1524)
				(type default)
			)
			(layer "F.SilkS")
		)
		(fp_line
			(start 0.7874 0.4064)
			(end -0.7874 0.4064)
			(stroke
				(width 0.1524)
				(type default)
			)
			(layer "F.SilkS")
		)
		(fp_line
			(start -0.7874 -0.4064)
			(end 0.7874 -0.4064)
			(stroke
				(width 0.1524)
				(type default)
			)
			(layer "F.SilkS")
		)
		(fp_line
			(start 0.7874 -0.4064)
			(end 0.7874 0.4064)
			(stroke
				(width 0.1524)
				(type default)
			)
			(layer "F.SilkS")
		)
		(fp_line
			(start -0.67945 0.3048)
			(end -0.67945 -0.305054)
			(stroke
				(width 0.1)
				(type default)
			)
			(layer "F.Fab")
		)
		(fp_line
			(start -0.12065 0.3048)
			(end -0.67945 0.3048)
			(stroke
				(width 0.1)
				(type default)
			)
			(layer "F.Fab")
		)
		(fp_line
			(start 0.120396 0.3048)
			(end 0.120396 0.2794)
			(stroke
				(width 0.1)
				(type default)
			)
			(layer "F.Fab")
		)
		(fp_line
			(start 0.67945 0.3048)
			(end 0.120396 0.3048)
			(stroke
				(width 0.1)
				(type default)
			)
			(layer "F.Fab")
		)
		(fp_line
			(start -0.12065 0.2794)
			(end -0.12065 0.3048)
			(stroke
				(width 0.1)
				(type default)
			)
			(layer "F.Fab")
		)
		(fp_line
			(start 0.120396 0.2794)
			(end -0.12065 0.2794)
			(stroke
				(width 0.1)
				(type default)
			)
			(layer "F.Fab")
		)
		(fp_line
			(start -0.12065 -0.2794)
			(end 0.12065 -0.2794)
			(stroke
				(width 0.1)
				(type default)
			)
			(layer "F.Fab")
		)
		(fp_line
			(start 0.12065 -0.2794)
			(end 0.12065 -0.3048)
			(stroke
				(width 0.1)
				(type default)
			)
			(layer "F.Fab")
		)
		(fp_line
			(start 0.12065 -0.3048)
			(end 0.67945 -0.3048)
			(stroke
				(width 0.1)
				(type default)
			)
			(layer "F.Fab")
		)
		(fp_line
			(start 0.67945 -0.3048)
			(end 0.67945 0.3048)
			(stroke
				(width 0.1)
				(type default)
			)
			(layer "F.Fab")
		)
		(fp_line
			(start -0.67945 -0.305054)
			(end -0.12065 -0.305054)
			(stroke
				(width 0.1)
				(type default)
			)
			(layer "F.Fab")
		)
		(fp_line
			(start -0.12065 -0.305054)
			(end -0.12065 -0.2794)
			(stroke
				(width 0.1)
				(type default)
			)
			(layer "F.Fab")
		)
		(pad "1" smd circle
			(at -0.40005 0 270)
			(size 0 0)
			(layers "F.Cu" "F.Mask" "F.Paste")
			(net "PVDD18_S5_P0")
		)
		(pad "2" smd circle
			(at 0.40005 0 270)
			(size 0 0)
			(layers "F.Cu" "F.Mask" "F.Paste")
			(net "GND")
		)
	)
	(footprint ""
		(layer "F.Cu")
		(at 145.161 -119.761)
		(property "Reference" "R8125"
			(at 0 0 0)
			(layer "F.SilkS")
			(hide yes)
			(effects
				(font
					(size 1.27 1.27)
				)
			)
		)
		(property "Value" ""
			(at 0 0 0)
			(layer "F.Fab")
			(effects
				(font
					(size 1.27 1.27)
				)
			)
		)
		(duplicate_pad_numbers_are_jumpers no)
		(fp_line
			(start -0.7874 -0.4064)
			(end 0.7874 -0.4064)
			(stroke
				(width 0.1524)
				(type default)
			)
			(layer "F.SilkS")
		)
		(fp_line
			(start -0.7874 0.4064)
			(end -0.7874 -0.4064)
			(stroke
				(width 0.1524)
				(type default)
			)
			(layer "F.SilkS")
		)
		(fp_line
			(start 0.7874 -0.4064)
			(end 0.7874 0.4064)
			(stroke
				(width 0.1524)
				(type default)
			)
			(layer "F.SilkS")
		)
		(fp_line
			(start 0.7874 0.4064)
			(end -0.7874 0.4064)
			(stroke
				(width 0.1524)
				(type default)
			)
			(layer "F.SilkS")
		)
		(fp_line
			(start -0.67945 -0.305054)
			(end -0.12065 -0.305054)
			(stroke
				(width 0.1)
				(type default)
			)
			(layer "F.Fab")
		)
		(fp_line
			(start -0.67945 0.3048)
			(end -0.67945 -0.305054)
			(stroke
				(width 0.1)
				(type default)
			)
			(layer "F.Fab")
		)
		(fp_line
			(start -0.12065 -0.305054)
			(end -0.12065 -0.2794)
			(stroke
				(width 0.1)
				(type default)
			)
			(layer "F.Fab")
		)
		(fp_line
			(start -0.12065 -0.2794)
			(end 0.12065 -0.2794)
			(stroke
				(width 0.1)
				(type default)
			)
			(layer "F.Fab")
		)
		(fp_line
			(start -0.12065 0.2794)
			(end -0.12065 0.3048)
			(stroke
				(width 0.1)
				(type default)
			)
			(layer "F.Fab")
		)
		(fp_line
			(start -0.12065 0.3048)
			(end -0.67945 0.3048)
			(stroke
				(width 0.1)
				(type default)
			)
			(layer "F.Fab")
		)
		(fp_line
			(start 0.120396 0.2794)
			(end -0.12065 0.2794)
			(stroke
				(width 0.1)
				(type default)
			)
			(layer "F.Fab")
		)
		(fp_line
			(start 0.120396 0.3048)
			(end 0.120396 0.2794)
			(stroke
				(width 0.1)
				(type default)
			)
			(layer "F.Fab")
		)
		(fp_line
			(start 0.12065 -0.3048)
			(end 0.67945 -0.3048)
			(stroke
				(width 0.1)
				(type default)
			)
			(layer "F.Fab")
		)
		(fp_line
			(start 0.12065 -0.2794)
			(end 0.12065 -0.3048)
			(stroke
				(width 0.1)
				(type default)
			)
			(layer "F.Fab")
		)
		(fp_line
			(start 0.67945 -0.3048)
			(end 0.67945 0.3048)
			(stroke
				(width 0.1)
				(type default)
			)
			(layer "F.Fab")
		)
		(fp_line
			(start 0.67945 0.3048)
			(end 0.120396 0.3048)
			(stroke
				(width 0.1)
				(type default)
			)
			(layer "F.Fab")
		)
		(pad "1" smd circle
			(at -0.40005 0)
			(size 0 0)
			(layers "F.Cu" "F.Mask" "F.Paste")
			(net "P3V3_AUX")
		)
		(pad "2" smd circle
			(at 0.40005 0)
			(size 0 0)
			(layers "F.Cu" "F.Mask" "F.Paste")
			(net "IRQ_UV_DETECT_N")
		)
	)
	(footprint ""
		(layer "F.Cu")
		(at 34.82848 -368.467132 90)
		(property "Reference" "PC366"
			(at 0 0 90)
			(layer "F.SilkS")
			(hide yes)
			(effects
				(font
					(size 1.27 1.27)
				)
			)
		)
		(property "Value" ""
			(at 0 0 90)
			(layer "F.Fab")
			(effects
				(font
					(size 1.27 1.27)
				)
			)
		)
		(duplicate_pad_numbers_are_jumpers no)
		(fp_line
			(start 0.7874 -0.4064)
			(end 0.7874 0.4064)
			(stroke
				(width 0.1524)
				(type default)
			)
			(layer "F.SilkS")
		)
		(fp_line
			(start -0.7874 -0.4064)
			(end 0.7874 -0.4064)
			(stroke
				(width 0.1524)
				(type default)
			)
			(layer "F.SilkS")
		)
		(fp_line
			(start 0.7874 0.4064)
			(end -0.7874 0.4064)
			(stroke
				(width 0.1524)
				(type default)
			)
			(layer "F.SilkS")
		)
		(fp_line
			(start -0.7874 0.4064)
			(end -0.7874 -0.4064)
			(stroke
				(width 0.1524)
				(type default)
			)
			(layer "F.SilkS")
		)
		(fp_line
			(start -0.12065 -0.305054)
			(end -0.12065 -0.2794)
			(stroke
				(width 0.1)
				(type default)
			)
			(layer "F.Fab")
		)
		(fp_line
			(start -0.67945 -0.305054)
			(end -0.12065 -0.305054)
			(stroke
				(width 0.1)
				(type default)
			)
			(layer "F.Fab")
		)
		(fp_line
			(start 0.67945 -0.3048)
			(end 0.67945 0.3048)
			(stroke
				(width 0.1)
				(type default)
			)
			(layer "F.Fab")
		)
		(fp_line
			(start 0.12065 -0.3048)
			(end 0.67945 -0.3048)
			(stroke
				(width 0.1)
				(type default)
			)
			(layer "F.Fab")
		)
		(fp_line
			(start 0.12065 -0.2794)
			(end 0.12065 -0.3048)
			(stroke
				(width 0.1)
				(type default)
			)
			(layer "F.Fab")
		)
		(fp_line
			(start -0.12065 -0.2794)
			(end 0.12065 -0.2794)
			(stroke
				(width 0.1)
				(type default)
			)
			(layer "F.Fab")
		)
		(fp_line
			(start 0.120396 0.2794)
			(end -0.12065 0.2794)
			(stroke
				(width 0.1)
				(type default)
			)
			(layer "F.Fab")
		)
		(fp_line
			(start -0.12065 0.2794)
			(end -0.12065 0.3048)
			(stroke
				(width 0.1)
				(type default)
			)
			(layer "F.Fab")
		)
		(fp_line
			(start 0.67945 0.3048)
			(end 0.120396 0.3048)
			(stroke
				(width 0.1)
				(type default)
			)
			(layer "F.Fab")
		)
		(fp_line
			(start 0.120396 0.3048)
			(end 0.120396 0.2794)
			(stroke
				(width 0.1)
				(type default)
			)
			(layer "F.Fab")
		)
		(fp_line
			(start -0.12065 0.3048)
			(end -0.67945 0.3048)
			(stroke
				(width 0.1)
				(type default)
			)
			(layer "F.Fab")
		)
		(fp_line
			(start -0.67945 0.3048)
			(end -0.67945 -0.305054)
			(stroke
				(width 0.1)
				(type default)
			)
			(layer "F.Fab")
		)
		(pad "1" smd circle
			(at -0.40005 0 90)
			(size 0 0)
			(layers "F.Cu" "F.Mask" "F.Paste")
			(net "PVDDCR_CPU1_P1_VCCS")
		)
		(pad "2" smd circle
			(at 0.40005 0 90)
			(size 0 0)
			(layers "F.Cu" "F.Mask" "F.Paste")
			(net "GND")
		)
	)
	(footprint ""
		(layer "F.Cu")
		(at 165.62451 -123.683014)
		(property "Reference" "R419"
			(at 0 0 0)
			(layer "F.SilkS")
			(hide yes)
			(effects
				(font
					(size 1.27 1.27)
				)
			)
		)
		(property "Value" ""
			(at 0 0 0)
			(layer "F.Fab")
			(effects
				(font
					(size 1.27 1.27)
				)
			)
		)
		(duplicate_pad_numbers_are_jumpers no)
		(fp_line
			(start -0.7874 -0.4064)
			(end 0.7874 -0.4064)
			(stroke
				(width 0.1524)
				(type default)
			)
			(layer "F.SilkS")
		)
		(fp_line
			(start -0.7874 0.4064)
			(end -0.7874 -0.4064)
			(stroke
				(width 0.1524)
				(type default)
			)
			(layer "F.SilkS")
		)
		(fp_line
			(start 0.7874 -0.4064)
			(end 0.7874 0.4064)
			(stroke
				(width 0.1524)
				(type default)
			)
			(layer "F.SilkS")
		)
		(fp_line
			(start 0.7874 0.4064)
			(end -0.7874 0.4064)
			(stroke
				(width 0.1524)
				(type default)
			)
			(layer "F.SilkS")
		)
		(fp_line
			(start -0.67945 -0.305054)
			(end -0.12065 -0.305054)
			(stroke
				(width 0.1)
				(type default)
			)
			(layer "F.Fab")
		)
		(fp_line
			(start -0.67945 0.3048)
			(end -0.67945 -0.305054)
			(stroke
				(width 0.1)
				(type default)
			)
			(layer "F.Fab")
		)
		(fp_line
			(start -0.12065 -0.305054)
			(end -0.12065 -0.2794)
			(stroke
				(width 0.1)
				(type default)
			)
			(layer "F.Fab")
		)
		(fp_line
			(start -0.12065 -0.2794)
			(end 0.12065 -0.2794)
			(stroke
				(width 0.1)
				(type default)
			)
			(layer "F.Fab")
		)
		(fp_line
			(start -0.12065 0.2794)
			(end -0.12065 0.3048)
			(stroke
				(width 0.1)
				(type default)
			)
			(layer "F.Fab")
		)
		(fp_line
			(start -0.12065 0.3048)
			(end -0.67945 0.3048)
			(stroke
				(width 0.1)
				(type default)
			)
			(layer "F.Fab")
		)
		(fp_line
			(start 0.120396 0.2794)
			(end -0.12065 0.2794)
			(stroke
				(width 0.1)
				(type default)
			)
			(layer "F.Fab")
		)
		(fp_line
			(start 0.120396 0.3048)
			(end 0.120396 0.2794)
			(stroke
				(width 0.1)
				(type default)
			)
			(layer "F.Fab")
		)
		(fp_line
			(start 0.12065 -0.3048)
			(end 0.67945 -0.3048)
			(stroke
				(width 0.1)
				(type default)
			)
			(layer "F.Fab")
		)
		(fp_line
			(start 0.12065 -0.2794)
			(end 0.12065 -0.3048)
			(stroke
				(width 0.1)
				(type default)
			)
			(layer "F.Fab")
		)
		(fp_line
			(start 0.67945 -0.3048)
			(end 0.67945 0.3048)
			(stroke
				(width 0.1)
				(type default)
			)
			(layer "F.Fab")
		)
		(fp_line
			(start 0.67945 0.3048)
			(end 0.120396 0.3048)
			(stroke
				(width 0.1)
				(type default)
			)
			(layer "F.Fab")
		)
		(pad "1" smd circle
			(at -0.40005 0)
			(size 0 0)
			(layers "F.Cu" "F.Mask" "F.Paste")
			(net "RST_SRST_PLD_BMC_N")
		)
		(pad "2" smd circle
			(at 0.40005 0)
			(size 0 0)
			(layers "F.Cu" "F.Mask" "F.Paste")
			(net "RST_SRST_PLD_BMC_R_N")
		)
	)
	(footprint ""
		(layer "F.Cu")
		(at 108.346494 -340.085426 -90)
		(property "Reference" "PC141_6"
			(at 0 0 270)
			(layer "F.SilkS")
			(hide yes)
			(effects
				(font
					(size 1.27 1.27)
				)
			)
		)
		(property "Value" ""
			(at 0 0 270)
			(layer "F.Fab")
			(effects
				(font
					(size 1.27 1.27)
				)
			)
		)
		(duplicate_pad_numbers_are_jumpers no)
		(fp_line
			(start -0.7874 0.4064)
			(end -0.7874 -0.4064)
			(stroke
				(width 0.1524)
				(type default)
			)
			(layer "F.SilkS")
		)
		(fp_line
			(start 0.7874 0.4064)
			(end -0.7874 0.4064)
			(stroke
				(width 0.1524)
				(type default)
			)
			(layer "F.SilkS")
		)
		(fp_line
			(start -0.7874 -0.4064)
			(end 0.7874 -0.4064)
			(stroke
				(width 0.1524)
				(type default)
			)
			(layer "F.SilkS")
		)
		(fp_line
			(start 0.7874 -0.4064)
			(end 0.7874 0.4064)
			(stroke
				(width 0.1524)
				(type default)
			)
			(layer "F.SilkS")
		)
		(fp_line
			(start -0.67945 0.3048)
			(end -0.67945 -0.305054)
			(stroke
				(width 0.1)
				(type default)
			)
			(layer "F.Fab")
		)
		(fp_line
			(start -0.12065 0.3048)
			(end -0.67945 0.3048)
			(stroke
				(width 0.1)
				(type default)
			)
			(layer "F.Fab")
		)
		(fp_line
			(start 0.120396 0.3048)
			(end 0.120396 0.2794)
			(stroke
				(width 0.1)
				(type default)
			)
			(layer "F.Fab")
		)
		(fp_line
			(start 0.67945 0.3048)
			(end 0.120396 0.3048)
			(stroke
				(width 0.1)
				(type default)
			)
			(layer "F.Fab")
		)
		(fp_line
			(start -0.12065 0.2794)
			(end -0.12065 0.3048)
			(stroke
				(width 0.1)
				(type default)
			)
			(layer "F.Fab")
		)
		(fp_line
			(start 0.120396 0.2794)
			(end -0.12065 0.2794)
			(stroke
				(width 0.1)
				(type default)
			)
			(layer "F.Fab")
		)
		(fp_line
			(start -0.12065 -0.2794)
			(end 0.12065 -0.2794)
			(stroke
				(width 0.1)
				(type default)
			)
			(layer "F.Fab")
		)
		(fp_line
			(start 0.12065 -0.2794)
			(end 0.12065 -0.3048)
			(stroke
				(width 0.1)
				(type default)
			)
			(layer "F.Fab")
		)
		(fp_line
			(start 0.12065 -0.3048)
			(end 0.67945 -0.3048)
			(stroke
				(width 0.1)
				(type default)
			)
			(layer "F.Fab")
		)
		(fp_line
			(start 0.67945 -0.3048)
			(end 0.67945 0.3048)
			(stroke
				(width 0.1)
				(type default)
			)
			(layer "F.Fab")
		)
		(fp_line
			(start -0.67945 -0.305054)
			(end -0.12065 -0.305054)
			(stroke
				(width 0.1)
				(type default)
			)
			(layer "F.Fab")
		)
		(fp_line
			(start -0.12065 -0.305054)
			(end -0.12065 -0.2794)
			(stroke
				(width 0.1)
				(type default)
			)
			(layer "F.Fab")
		)
		(pad "1" smd circle
			(at -0.40005 0 270)
			(size 0 0)
			(layers "F.Cu" "F.Mask" "F.Paste")
			(net "SW_P12V_AUX_PVDDCR_CPU1_P1_FLT")
		)
		(pad "2" smd circle
			(at 0.40005 0 270)
			(size 0 0)
			(layers "F.Cu" "F.Mask" "F.Paste")
			(net "GND")
		)
	)
	(footprint ""
		(layer "F.Cu")
		(at 177.81016 -389.0518)
		(property "Reference" "R1489"
			(at 0 0 0)
			(layer "F.SilkS")
			(hide yes)
			(effects
				(font
					(size 1.27 1.27)
				)
			)
		)
		(property "Value" ""
			(at 0 0 0)
			(layer "F.Fab")
			(effects
				(font
					(size 1.27 1.27)
				)
			)
		)
		(duplicate_pad_numbers_are_jumpers no)
		(fp_line
			(start -0.32512 -0.175006)
			(end 0.32512 -0.175006)
			(stroke
				(width 0.1)
				(type default)
			)
			(layer "F.Fab")
		)
		(fp_line
			(start -0.32512 0.175006)
			(end -0.32512 -0.175006)
			(stroke
				(width 0.1)
				(type default)
			)
			(layer "F.Fab")
		)
		(fp_line
			(start 0.32512 -0.175006)
			(end 0.32512 0.175006)
			(stroke
				(width 0.1)
				(type default)
			)
			(layer "F.Fab")
		)
		(fp_line
			(start 0.32512 0.175006)
			(end -0.32512 0.175006)
			(stroke
				(width 0.1)
				(type default)
			)
			(layer "F.Fab")
		)
		(pad "1" smd rect
			(at -0.2667 0)
			(size 0.3048 0.381)
			(layers "F.Cu" "F.Mask" "F.Paste")
			(net "P1V8_CPU1_RT_1D")
		)
		(pad "2" smd rect
			(at 0.2667 0 180)
			(size 0.3048 0.381)
			(layers "F.Cu" "F.Mask" "F.Paste")
			(net "JTAG_TMS_RT_CPU1_P2")
		)
	)
	(footprint ""
		(layer "F.Cu")
		(at 61.543438 -31.887922 90)
		(property "Reference" "R3874"
			(at 0 0 90)
			(layer "F.SilkS")
			(hide yes)
			(effects
				(font
					(size 1.27 1.27)
				)
			)
		)
		(property "Value" ""
			(at 0 0 90)
			(layer "F.Fab")
			(effects
				(font
					(size 1.27 1.27)
				)
			)
		)
		(duplicate_pad_numbers_are_jumpers no)
		(fp_line
			(start 0.7874 -0.4064)
			(end 0.7874 0.4064)
			(stroke
				(width 0.1524)
				(type default)
			)
			(layer "F.SilkS")
		)
		(fp_line
			(start -0.7874 -0.4064)
			(end 0.7874 -0.4064)
			(stroke
				(width 0.1524)
				(type default)
			)
			(layer "F.SilkS")
		)
		(fp_line
			(start 0.7874 0.4064)
			(end -0.7874 0.4064)
			(stroke
				(width 0.1524)
				(type default)
			)
			(layer "F.SilkS")
		)
		(fp_line
			(start -0.7874 0.4064)
			(end -0.7874 -0.4064)
			(stroke
				(width 0.1524)
				(type default)
			)
			(layer "F.SilkS")
		)
		(fp_line
			(start -0.12065 -0.305054)
			(end -0.12065 -0.2794)
			(stroke
				(width 0.1)
				(type default)
			)
			(layer "F.Fab")
		)
		(fp_line
			(start -0.67945 -0.305054)
			(end -0.12065 -0.305054)
			(stroke
				(width 0.1)
				(type default)
			)
			(layer "F.Fab")
		)
		(fp_line
			(start 0.67945 -0.3048)
			(end 0.67945 0.3048)
			(stroke
				(width 0.1)
				(type default)
			)
			(layer "F.Fab")
		)
		(fp_line
			(start 0.12065 -0.3048)
			(end 0.67945 -0.3048)
			(stroke
				(width 0.1)
				(type default)
			)
			(layer "F.Fab")
		)
		(fp_line
			(start 0.12065 -0.2794)
			(end 0.12065 -0.3048)
			(stroke
				(width 0.1)
				(type default)
			)
			(layer "F.Fab")
		)
		(fp_line
			(start -0.12065 -0.2794)
			(end 0.12065 -0.2794)
			(stroke
				(width 0.1)
				(type default)
			)
			(layer "F.Fab")
		)
		(fp_line
			(start 0.120396 0.2794)
			(end -0.12065 0.2794)
			(stroke
				(width 0.1)
				(type default)
			)
			(layer "F.Fab")
		)
		(fp_line
			(start -0.12065 0.2794)
			(end -0.12065 0.3048)
			(stroke
				(width 0.1)
				(type default)
			)
			(layer "F.Fab")
		)
		(fp_line
			(start 0.67945 0.3048)
			(end 0.120396 0.3048)
			(stroke
				(width 0.1)
				(type default)
			)
			(layer "F.Fab")
		)
		(fp_line
			(start 0.120396 0.3048)
			(end 0.120396 0.2794)
			(stroke
				(width 0.1)
				(type default)
			)
			(layer "F.Fab")
		)
		(fp_line
			(start -0.12065 0.3048)
			(end -0.67945 0.3048)
			(stroke
				(width 0.1)
				(type default)
			)
			(layer "F.Fab")
		)
		(fp_line
			(start -0.67945 0.3048)
			(end -0.67945 -0.305054)
			(stroke
				(width 0.1)
				(type default)
			)
			(layer "F.Fab")
		)
		(pad "1" smd circle
			(at -0.40005 0 90)
			(size 0 0)
			(layers "F.Cu" "F.Mask" "F.Paste")
			(net "P12V_OCP_IMON_2")
		)
		(pad "2" smd circle
			(at 0.40005 0 90)
			(size 0 0)
			(layers "F.Cu" "F.Mask" "F.Paste")
			(net "P12V_OCP_V3_2_ISENSE_MPS_TIC")
		)
	)
	(footprint ""
		(layer "F.Cu")
		(at 25.322784 -381.6858 -90)
		(property "Reference" "PL6512"
			(at 3.2258 -4.167886 90)
			(unlocked yes)
			(layer "F.SilkS")
			(effects
				(font
					(size 0.7874 0.5842)
					(thickness 0.1524)
				)
				(justify left)
			)
		)
		(property "Value" ""
			(at 0 0 270)
			(layer "F.Fab")
			(effects
				(font
					(size 1.27 1.27)
				)
			)
		)
		(duplicate_pad_numbers_are_jumpers no)
		(fp_line
			(start -3.24993 3.24993)
			(end -3.24993 2.2352)
			(stroke
				(width 0.1524)
				(type default)
			)
			(layer "F.SilkS")
		)
		(fp_line
			(start 3.24993 3.24993)
			(end -3.24993 3.24993)
			(stroke
				(width 0.1524)
				(type default)
			)
			(layer "F.SilkS")
		)
		(fp_line
			(start 3.24993 2.2352)
			(end 3.24993 3.24993)
			(stroke
				(width 0.1524)
				(type default)
			)
			(layer "F.SilkS")
		)
		(fp_line
			(start -3.24993 -2.2352)
			(end -3.24993 -3.24993)
			(stroke
				(width 0.1524)
				(type default)
			)
			(layer "F.SilkS")
		)
		(fp_line
			(start -3.24993 -3.24993)
			(end 3.24993 -3.24993)
			(stroke
				(width 0.1524)
				(type default)
			)
			(layer "F.SilkS")
		)
		(fp_line
			(start 3.24993 -3.24993)
			(end 3.24993 -2.2352)
			(stroke
				(width 0.1524)
				(type default)
			)
			(layer "F.SilkS")
		)
		(fp_line
			(start -3.24993 3.24993)
			(end -3.24993 -3.24993)
			(stroke
				(width 0.1)
				(type default)
			)
			(layer "F.Fab")
		)
		(fp_line
			(start 3.24993 3.24993)
			(end -3.24993 3.24993)
			(stroke
				(width 0.1)
				(type default)
			)
			(layer "F.Fab")
		)
		(fp_line
			(start -3.24993 -3.24993)
			(end 3.24993 -3.24993)
			(stroke
				(width 0.1)
				(type default)
			)
			(layer "F.Fab")
		)
		(fp_line
			(start 3.24993 -3.24993)
			(end 3.24993 3.24993)
			(stroke
				(width 0.1)
				(type default)
			)
			(layer "F.Fab")
		)
		(pad "1" smd rect
			(at -2.29997 0 270)
			(size 2.0066 4.2164)
			(layers "F.Cu" "F.Mask" "F.Paste")
			(net "SW_P0V9_RETIMER_CPU1_SW2")
		)
		(pad "2" smd rect
			(at 2.29997 0 270)
			(size 2.0066 4.2164)
			(layers "F.Cu" "F.Mask" "F.Paste")
			(net "P0V9_CPU1_RT_2D")
		)
	)
	(footprint ""
		(layer "F.Cu")
		(at 479.478594 -117.77472)
		(property "Reference" "DB2"
			(at 1.686814 3.227578 0)
			(unlocked yes)
			(layer "F.SilkS")
			(effects
				(font
					(size 0.7874 0.5842)
					(thickness 0.1524)
				)
				(justify left)
			)
		)
		(property "Value" ""
			(at 0 0 0)
			(layer "F.Fab")
			(effects
				(font
					(size 1.27 1.27)
				)
			)
		)
		(duplicate_pad_numbers_are_jumpers no)
		(fp_line
			(start -3.330702 -4.771136)
			(end 3.330702 -4.771136)
			(stroke
				(width 0.1524)
				(type default)
			)
			(layer "F.SilkS")
		)
		(fp_line
			(start 0 4.011168)
			(end -3.330702 -4.771136)
			(stroke
				(width 0.1524)
				(type default)
			)
			(layer "F.SilkS")
		)
		(fp_line
			(start 3.330702 -4.771136)
			(end 0 4.011168)
			(stroke
				(width 0.1524)
				(type default)
			)
			(layer "F.SilkS")
		)
		(fp_line
			(start -3.330702 -4.771136)
			(end 3.330702 -4.771136)
			(stroke
				(width 0.1)
				(type default)
			)
			(layer "F.Fab")
		)
		(fp_line
			(start 0 4.011168)
			(end -3.330702 -4.771136)
			(stroke
				(width 0.1)
				(type default)
			)
			(layer "F.Fab")
		)
		(fp_line
			(start 3.330702 -4.771136)
			(end 0 4.011168)
			(stroke
				(width 0.1)
				(type default)
			)
			(layer "F.Fab")
		)
		(pad "1" thru_hole circle
			(at 0 0)
			(size 2.159 2.159)
			(drill 1.7018)
			(layers "*.Cu" "*.Mask")
			(remove_unused_layers no)
			(net "T1_GND")
			(clearance 0.0254)
			(thermal_gap 0.0254)
		)
		(pad "2" thru_hole circle
			(at -1.27 -3.348736)
			(size 2.159 2.159)
			(drill 1.7018)
			(layers "*.Cu" "*.Mask")
			(remove_unused_layers no)
			(net "TDR_SE_45_OHM_IN1")
			(clearance 0.0254)
			(thermal_gap 0.0254)
		)
		(pad "3" thru_hole circle
			(at 1.27 -3.348736)
			(size 2.159 2.159)
			(drill 1.7018)
			(layers "*.Cu" "*.Mask")
			(remove_unused_layers no)
			(net "TDR_SE_45_OHM_IN1")
			(clearance 0.0254)
			(thermal_gap 0.0254)
		)
	)
	(footprint ""
		(layer "F.Cu")
		(at 130.638296 -151.8793 90)
		(property "Reference" "PC353"
			(at 0 0 90)
			(layer "F.SilkS")
			(hide yes)
			(effects
				(font
					(size 1.27 1.27)
				)
			)
		)
		(property "Value" ""
			(at 0 0 90)
			(layer "F.Fab")
			(effects
				(font
					(size 1.27 1.27)
				)
			)
		)
		(duplicate_pad_numbers_are_jumpers no)
		(fp_line
			(start 0.7874 -0.4064)
			(end 0.7874 0.4064)
			(stroke
				(width 0.1524)
				(type default)
			)
			(layer "F.SilkS")
		)
		(fp_line
			(start -0.7874 -0.4064)
			(end 0.7874 -0.4064)
			(stroke
				(width 0.1524)
				(type default)
			)
			(layer "F.SilkS")
		)
		(fp_line
			(start 0.7874 0.4064)
			(end -0.7874 0.4064)
			(stroke
				(width 0.1524)
				(type default)
			)
			(layer "F.SilkS")
		)
		(fp_line
			(start -0.7874 0.4064)
			(end -0.7874 -0.4064)
			(stroke
				(width 0.1524)
				(type default)
			)
			(layer "F.SilkS")
		)
		(fp_line
			(start -0.12065 -0.305054)
			(end -0.12065 -0.2794)
			(stroke
				(width 0.1)
				(type default)
			)
			(layer "F.Fab")
		)
		(fp_line
			(start -0.67945 -0.305054)
			(end -0.12065 -0.305054)
			(stroke
				(width 0.1)
				(type default)
			)
			(layer "F.Fab")
		)
		(fp_line
			(start 0.67945 -0.3048)
			(end 0.67945 0.3048)
			(stroke
				(width 0.1)
				(type default)
			)
			(layer "F.Fab")
		)
		(fp_line
			(start 0.12065 -0.3048)
			(end 0.67945 -0.3048)
			(stroke
				(width 0.1)
				(type default)
			)
			(layer "F.Fab")
		)
		(fp_line
			(start 0.12065 -0.2794)
			(end 0.12065 -0.3048)
			(stroke
				(width 0.1)
				(type default)
			)
			(layer "F.Fab")
		)
		(fp_line
			(start -0.12065 -0.2794)
			(end 0.12065 -0.2794)
			(stroke
				(width 0.1)
				(type default)
			)
			(layer "F.Fab")
		)
		(fp_line
			(start 0.120396 0.2794)
			(end -0.12065 0.2794)
			(stroke
				(width 0.1)
				(type default)
			)
			(layer "F.Fab")
		)
		(fp_line
			(start -0.12065 0.2794)
			(end -0.12065 0.3048)
			(stroke
				(width 0.1)
				(type default)
			)
			(layer "F.Fab")
		)
		(fp_line
			(start 0.67945 0.3048)
			(end 0.120396 0.3048)
			(stroke
				(width 0.1)
				(type default)
			)
			(layer "F.Fab")
		)
		(fp_line
			(start 0.120396 0.3048)
			(end 0.120396 0.2794)
			(stroke
				(width 0.1)
				(type default)
			)
			(layer "F.Fab")
		)
		(fp_line
			(start -0.12065 0.3048)
			(end -0.67945 0.3048)
			(stroke
				(width 0.1)
				(type default)
			)
			(layer "F.Fab")
		)
		(fp_line
			(start -0.67945 0.3048)
			(end -0.67945 -0.305054)
			(stroke
				(width 0.1)
				(type default)
			)
			(layer "F.Fab")
		)
		(pad "1" smd circle
			(at -0.40005 0 90)
			(size 0 0)
			(layers "F.Cu" "F.Mask" "F.Paste")
			(net "SW_PVDDCR_SOC_P1_BOOT3_RC")
		)
		(pad "2" smd circle
			(at 0.40005 0 90)
			(size 0 0)
			(layers "F.Cu" "F.Mask" "F.Paste")
			(net "SW_PVDDCR_SOC_P1_PH3")
		)
	)
	(footprint ""
		(layer "F.Cu")
		(at 221.361 -80.772 90)
		(property "Reference" "R8098"
			(at 0 0 90)
			(layer "F.SilkS")
			(hide yes)
			(effects
				(font
					(size 1.27 1.27)
				)
			)
		)
		(property "Value" ""
			(at 0 0 90)
			(layer "F.Fab")
			(effects
				(font
					(size 1.27 1.27)
				)
			)
		)
		(duplicate_pad_numbers_are_jumpers no)
		(fp_line
			(start 0.7874 -0.4064)
			(end 0.7874 0.4064)
			(stroke
				(width 0.1524)
				(type default)
			)
			(layer "F.SilkS")
		)
		(fp_line
			(start -0.7874 -0.4064)
			(end 0.7874 -0.4064)
			(stroke
				(width 0.1524)
				(type default)
			)
			(layer "F.SilkS")
		)
		(fp_line
			(start 0.7874 0.4064)
			(end -0.7874 0.4064)
			(stroke
				(width 0.1524)
				(type default)
			)
			(layer "F.SilkS")
		)
		(fp_line
			(start -0.7874 0.4064)
			(end -0.7874 -0.4064)
			(stroke
				(width 0.1524)
				(type default)
			)
			(layer "F.SilkS")
		)
		(fp_line
			(start -0.12065 -0.305054)
			(end -0.12065 -0.2794)
			(stroke
				(width 0.1)
				(type default)
			)
			(layer "F.Fab")
		)
		(fp_line
			(start -0.67945 -0.305054)
			(end -0.12065 -0.305054)
			(stroke
				(width 0.1)
				(type default)
			)
			(layer "F.Fab")
		)
		(fp_line
			(start 0.67945 -0.3048)
			(end 0.67945 0.3048)
			(stroke
				(width 0.1)
				(type default)
			)
			(layer "F.Fab")
		)
		(fp_line
			(start 0.12065 -0.3048)
			(end 0.67945 -0.3048)
			(stroke
				(width 0.1)
				(type default)
			)
			(layer "F.Fab")
		)
		(fp_line
			(start 0.12065 -0.2794)
			(end 0.12065 -0.3048)
			(stroke
				(width 0.1)
				(type default)
			)
			(layer "F.Fab")
		)
		(fp_line
			(start -0.12065 -0.2794)
			(end 0.12065 -0.2794)
			(stroke
				(width 0.1)
				(type default)
			)
			(layer "F.Fab")
		)
		(fp_line
			(start 0.120396 0.2794)
			(end -0.12065 0.2794)
			(stroke
				(width 0.1)
				(type default)
			)
			(layer "F.Fab")
		)
		(fp_line
			(start -0.12065 0.2794)
			(end -0.12065 0.3048)
			(stroke
				(width 0.1)
				(type default)
			)
			(layer "F.Fab")
		)
		(fp_line
			(start 0.67945 0.3048)
			(end 0.120396 0.3048)
			(stroke
				(width 0.1)
				(type default)
			)
			(layer "F.Fab")
		)
		(fp_line
			(start 0.120396 0.3048)
			(end 0.120396 0.2794)
			(stroke
				(width 0.1)
				(type default)
			)
			(layer "F.Fab")
		)
		(fp_line
			(start -0.12065 0.3048)
			(end -0.67945 0.3048)
			(stroke
				(width 0.1)
				(type default)
			)
			(layer "F.Fab")
		)
		(fp_line
			(start -0.67945 0.3048)
			(end -0.67945 -0.305054)
			(stroke
				(width 0.1)
				(type default)
			)
			(layer "F.Fab")
		)
		(pad "1" smd circle
			(at -0.40005 0 90)
			(size 0 0)
			(layers "F.Cu" "F.Mask" "F.Paste")
			(net "P3V3_E1S_0_R")
		)
		(pad "2" smd circle
			(at 0.40005 0 90)
			(size 0 0)
			(layers "F.Cu" "F.Mask" "F.Paste")
			(net "P3V3_E1S_PWRGD_0_R1")
		)
	)
	(footprint ""
		(layer "F.Cu")
		(at 79.114904 -396.491206 -90)
		(property "Reference" "R759"
			(at 0 0 270)
			(layer "F.SilkS")
			(hide yes)
			(effects
				(font
					(size 1.27 1.27)
				)
			)
		)
		(property "Value" ""
			(at 0 0 270)
			(layer "F.Fab")
			(effects
				(font
					(size 1.27 1.27)
				)
			)
		)
		(duplicate_pad_numbers_are_jumpers no)
		(fp_line
			(start -0.32512 0.175006)
			(end -0.32512 -0.175006)
			(stroke
				(width 0.1)
				(type default)
			)
			(layer "F.Fab")
		)
		(fp_line
			(start 0.32512 0.175006)
			(end -0.32512 0.175006)
			(stroke
				(width 0.1)
				(type default)
			)
			(layer "F.Fab")
		)
		(fp_line
			(start -0.32512 -0.175006)
			(end 0.32512 -0.175006)
			(stroke
				(width 0.1)
				(type default)
			)
			(layer "F.Fab")
		)
		(fp_line
			(start 0.32512 -0.175006)
			(end 0.32512 0.175006)
			(stroke
				(width 0.1)
				(type default)
			)
			(layer "F.Fab")
		)
		(pad "1" smd rect
			(at -0.2667 0 270)
			(size 0.3048 0.381)
			(layers "F.Cu" "F.Mask" "F.Paste")
			(net "P1V8_CPU1_RT_1D")
		)
		(pad "2" smd rect
			(at 0.2667 0 90)
			(size 0.3048 0.381)
			(layers "F.Cu" "F.Mask" "F.Paste")
			(net "JTAG_TEST_MODE_RT_CPU1_P1")
		)
	)
	(footprint ""
		(layer "F.Cu")
		(at 428.120302 -436.164736 90)
		(property "Reference" "R2833"
			(at 0 0 90)
			(layer "F.SilkS")
			(hide yes)
			(effects
				(font
					(size 1.27 1.27)
				)
			)
		)
		(property "Value" ""
			(at 0 0 90)
			(layer "F.Fab")
			(effects
				(font
					(size 1.27 1.27)
				)
			)
		)
		(duplicate_pad_numbers_are_jumpers no)
		(fp_line
			(start 0.7874 -0.4064)
			(end 0.7874 0.4064)
			(stroke
				(width 0.1524)
				(type default)
			)
			(layer "F.SilkS")
		)
		(fp_line
			(start -0.7874 -0.4064)
			(end 0.7874 -0.4064)
			(stroke
				(width 0.1524)
				(type default)
			)
			(layer "F.SilkS")
		)
		(fp_line
			(start 0.7874 0.4064)
			(end -0.7874 0.4064)
			(stroke
				(width 0.1524)
				(type default)
			)
			(layer "F.SilkS")
		)
		(fp_line
			(start -0.7874 0.4064)
			(end -0.7874 -0.4064)
			(stroke
				(width 0.1524)
				(type default)
			)
			(layer "F.SilkS")
		)
		(fp_line
			(start -0.12065 -0.305054)
			(end -0.12065 -0.2794)
			(stroke
				(width 0.1)
				(type default)
			)
			(layer "F.Fab")
		)
		(fp_line
			(start -0.67945 -0.305054)
			(end -0.12065 -0.305054)
			(stroke
				(width 0.1)
				(type default)
			)
			(layer "F.Fab")
		)
		(fp_line
			(start 0.67945 -0.3048)
			(end 0.67945 0.3048)
			(stroke
				(width 0.1)
				(type default)
			)
			(layer "F.Fab")
		)
		(fp_line
			(start 0.12065 -0.3048)
			(end 0.67945 -0.3048)
			(stroke
				(width 0.1)
				(type default)
			)
			(layer "F.Fab")
		)
		(fp_line
			(start 0.12065 -0.2794)
			(end 0.12065 -0.3048)
			(stroke
				(width 0.1)
				(type default)
			)
			(layer "F.Fab")
		)
		(fp_line
			(start -0.12065 -0.2794)
			(end 0.12065 -0.2794)
			(stroke
				(width 0.1)
				(type default)
			)
			(layer "F.Fab")
		)
		(fp_line
			(start 0.120396 0.2794)
			(end -0.12065 0.2794)
			(stroke
				(width 0.1)
				(type default)
			)
			(layer "F.Fab")
		)
		(fp_line
			(start -0.12065 0.2794)
			(end -0.12065 0.3048)
			(stroke
				(width 0.1)
				(type default)
			)
			(layer "F.Fab")
		)
		(fp_line
			(start 0.67945 0.3048)
			(end 0.120396 0.3048)
			(stroke
				(width 0.1)
				(type default)
			)
			(layer "F.Fab")
		)
		(fp_line
			(start 0.120396 0.3048)
			(end 0.120396 0.2794)
			(stroke
				(width 0.1)
				(type default)
			)
			(layer "F.Fab")
		)
		(fp_line
			(start -0.12065 0.3048)
			(end -0.67945 0.3048)
			(stroke
				(width 0.1)
				(type default)
			)
			(layer "F.Fab")
		)
		(fp_line
			(start -0.67945 0.3048)
			(end -0.67945 -0.305054)
			(stroke
				(width 0.1)
				(type default)
			)
			(layer "F.Fab")
		)
		(pad "1" smd circle
			(at -0.40005 0 90)
			(size 0 0)
			(layers "F.Cu" "F.Mask" "F.Paste")
			(net "FM_SWB_BIC_READY_N")
		)
		(pad "2" smd circle
			(at 0.40005 0 90)
			(size 0 0)
			(layers "F.Cu" "F.Mask" "F.Paste")
			(net "GND")
		)
	)
	(footprint ""
		(layer "F.Cu")
		(at 194.2211 -399.982182 180)
		(property "Reference" "PR3914"
			(at 0 0 180)
			(layer "F.SilkS")
			(hide yes)
			(effects
				(font
					(size 1.27 1.27)
				)
			)
		)
		(property "Value" ""
			(at 0 0 180)
			(layer "F.Fab")
			(effects
				(font
					(size 1.27 1.27)
				)
			)
		)
		(duplicate_pad_numbers_are_jumpers no)
		(fp_line
			(start 0.7874 0.4064)
			(end -0.7874 0.4064)
			(stroke
				(width 0.1524)
				(type default)
			)
			(layer "F.SilkS")
		)
		(fp_line
			(start 0.7874 -0.4064)
			(end 0.7874 0.4064)
			(stroke
				(width 0.1524)
				(type default)
			)
			(layer "F.SilkS")
		)
		(fp_line
			(start -0.7874 0.4064)
			(end -0.7874 -0.4064)
			(stroke
				(width 0.1524)
				(type default)
			)
			(layer "F.SilkS")
		)
		(fp_line
			(start -0.7874 -0.4064)
			(end 0.7874 -0.4064)
			(stroke
				(width 0.1524)
				(type default)
			)
			(layer "F.SilkS")
		)
		(fp_line
			(start 0.67945 0.3048)
			(end 0.120396 0.3048)
			(stroke
				(width 0.1)
				(type default)
			)
			(layer "F.Fab")
		)
		(fp_line
			(start 0.67945 -0.3048)
			(end 0.67945 0.3048)
			(stroke
				(width 0.1)
				(type default)
			)
			(layer "F.Fab")
		)
		(fp_line
			(start 0.12065 -0.2794)
			(end 0.12065 -0.3048)
			(stroke
				(width 0.1)
				(type default)
			)
			(layer "F.Fab")
		)
		(fp_line
			(start 0.12065 -0.3048)
			(end 0.67945 -0.3048)
			(stroke
				(width 0.1)
				(type default)
			)
			(layer "F.Fab")
		)
		(fp_line
			(start 0.120396 0.3048)
			(end 0.120396 0.2794)
			(stroke
				(width 0.1)
				(type default)
			)
			(layer "F.Fab")
		)
		(fp_line
			(start 0.120396 0.2794)
			(end -0.12065 0.2794)
			(stroke
				(width 0.1)
				(type default)
			)
			(layer "F.Fab")
		)
		(fp_line
			(start -0.12065 0.3048)
			(end -0.67945 0.3048)
			(stroke
				(width 0.1)
				(type default)
			)
			(layer "F.Fab")
		)
		(fp_line
			(start -0.12065 0.2794)
			(end -0.12065 0.3048)
			(stroke
				(width 0.1)
				(type default)
			)
			(layer "F.Fab")
		)
		(fp_line
			(start -0.12065 -0.2794)
			(end 0.12065 -0.2794)
			(stroke
				(width 0.1)
				(type default)
			)
			(layer "F.Fab")
		)
		(fp_line
			(start -0.12065 -0.305054)
			(end -0.12065 -0.2794)
			(stroke
				(width 0.1)
				(type default)
			)
			(layer "F.Fab")
		)
		(fp_line
			(start -0.67945 0.3048)
			(end -0.67945 -0.305054)
			(stroke
				(width 0.1)
				(type default)
			)
			(layer "F.Fab")
		)
		(fp_line
			(start -0.67945 -0.305054)
			(end -0.12065 -0.305054)
			(stroke
				(width 0.1)
				(type default)
			)
			(layer "F.Fab")
		)
		(pad "1" smd circle
			(at -0.40005 0 180)
			(size 0 0)
			(layers "F.Cu" "F.Mask" "F.Paste")
			(net "HSC_CS_1")
		)
		(pad "2" smd circle
			(at 0.40005 0 180)
			(size 0 0)
			(layers "F.Cu" "F.Mask" "F.Paste")
			(net "AGND_HSC")
		)
	)
	(footprint ""
		(layer "F.Cu")
		(at 166.920672 -350.248474)
		(property "Reference" "PC8"
			(at 0 0 0)
			(layer "F.SilkS")
			(hide yes)
			(effects
				(font
					(size 1.27 1.27)
				)
			)
		)
		(property "Value" ""
			(at 0 0 0)
			(layer "F.Fab")
			(effects
				(font
					(size 1.27 1.27)
				)
			)
		)
		(duplicate_pad_numbers_are_jumpers no)
		(fp_line
			(start -0.7874 -0.4064)
			(end 0.7874 -0.4064)
			(stroke
				(width 0.1524)
				(type default)
			)
			(layer "F.SilkS")
		)
		(fp_line
			(start -0.7874 0.4064)
			(end -0.7874 -0.4064)
			(stroke
				(width 0.1524)
				(type default)
			)
			(layer "F.SilkS")
		)
		(fp_line
			(start 0.7874 -0.4064)
			(end 0.7874 0.4064)
			(stroke
				(width 0.1524)
				(type default)
			)
			(layer "F.SilkS")
		)
		(fp_line
			(start 0.7874 0.4064)
			(end -0.7874 0.4064)
			(stroke
				(width 0.1524)
				(type default)
			)
			(layer "F.SilkS")
		)
		(fp_line
			(start -0.67945 -0.305054)
			(end -0.12065 -0.305054)
			(stroke
				(width 0.1)
				(type default)
			)
			(layer "F.Fab")
		)
		(fp_line
			(start -0.67945 0.3048)
			(end -0.67945 -0.305054)
			(stroke
				(width 0.1)
				(type default)
			)
			(layer "F.Fab")
		)
		(fp_line
			(start -0.12065 -0.305054)
			(end -0.12065 -0.2794)
			(stroke
				(width 0.1)
				(type default)
			)
			(layer "F.Fab")
		)
		(fp_line
			(start -0.12065 -0.2794)
			(end 0.12065 -0.2794)
			(stroke
				(width 0.1)
				(type default)
			)
			(layer "F.Fab")
		)
		(fp_line
			(start -0.12065 0.2794)
			(end -0.12065 0.3048)
			(stroke
				(width 0.1)
				(type default)
			)
			(layer "F.Fab")
		)
		(fp_line
			(start -0.12065 0.3048)
			(end -0.67945 0.3048)
			(stroke
				(width 0.1)
				(type default)
			)
			(layer "F.Fab")
		)
		(fp_line
			(start 0.120396 0.2794)
			(end -0.12065 0.2794)
			(stroke
				(width 0.1)
				(type default)
			)
			(layer "F.Fab")
		)
		(fp_line
			(start 0.120396 0.3048)
			(end 0.120396 0.2794)
			(stroke
				(width 0.1)
				(type default)
			)
			(layer "F.Fab")
		)
		(fp_line
			(start 0.12065 -0.3048)
			(end 0.67945 -0.3048)
			(stroke
				(width 0.1)
				(type default)
			)
			(layer "F.Fab")
		)
		(fp_line
			(start 0.12065 -0.2794)
			(end 0.12065 -0.3048)
			(stroke
				(width 0.1)
				(type default)
			)
			(layer "F.Fab")
		)
		(fp_line
			(start 0.67945 -0.3048)
			(end 0.67945 0.3048)
			(stroke
				(width 0.1)
				(type default)
			)
			(layer "F.Fab")
		)
		(fp_line
			(start 0.67945 0.3048)
			(end 0.120396 0.3048)
			(stroke
				(width 0.1)
				(type default)
			)
			(layer "F.Fab")
		)
		(pad "1" smd circle
			(at -0.40005 0)
			(size 0 0)
			(layers "F.Cu" "F.Mask" "F.Paste")
			(net "PVDD11_S3_P1_VINSEN")
		)
		(pad "2" smd circle
			(at 0.40005 0)
			(size 0 0)
			(layers "F.Cu" "F.Mask" "F.Paste")
			(net "GND")
		)
	)
	(footprint ""
		(layer "F.Cu")
		(at 359.417112 -261.747762 -90)
		(property "Reference" "C2158"
			(at 0 0 270)
			(layer "F.SilkS")
			(hide yes)
			(effects
				(font
					(size 1.27 1.27)
				)
			)
		)
		(property "Value" ""
			(at 0 0 270)
			(layer "F.Fab")
			(effects
				(font
					(size 1.27 1.27)
				)
			)
		)
		(duplicate_pad_numbers_are_jumpers no)
		(fp_line
			(start -0.7874 0.4064)
			(end -0.7874 -0.4064)
			(stroke
				(width 0.1524)
				(type default)
			)
			(layer "F.SilkS")
		)
		(fp_line
			(start 0.7874 0.4064)
			(end -0.7874 0.4064)
			(stroke
				(width 0.1524)
				(type default)
			)
			(layer "F.SilkS")
		)
		(fp_line
			(start -0.7874 -0.4064)
			(end 0.7874 -0.4064)
			(stroke
				(width 0.1524)
				(type default)
			)
			(layer "F.SilkS")
		)
		(fp_line
			(start 0.7874 -0.4064)
			(end 0.7874 0.4064)
			(stroke
				(width 0.1524)
				(type default)
			)
			(layer "F.SilkS")
		)
		(fp_line
			(start -0.67945 0.3048)
			(end -0.67945 -0.305054)
			(stroke
				(width 0.1)
				(type default)
			)
			(layer "F.Fab")
		)
		(fp_line
			(start -0.12065 0.3048)
			(end -0.67945 0.3048)
			(stroke
				(width 0.1)
				(type default)
			)
			(layer "F.Fab")
		)
		(fp_line
			(start 0.120396 0.3048)
			(end 0.120396 0.2794)
			(stroke
				(width 0.1)
				(type default)
			)
			(layer "F.Fab")
		)
		(fp_line
			(start 0.67945 0.3048)
			(end 0.120396 0.3048)
			(stroke
				(width 0.1)
				(type default)
			)
			(layer "F.Fab")
		)
		(fp_line
			(start -0.12065 0.2794)
			(end -0.12065 0.3048)
			(stroke
				(width 0.1)
				(type default)
			)
			(layer "F.Fab")
		)
		(fp_line
			(start 0.120396 0.2794)
			(end -0.12065 0.2794)
			(stroke
				(width 0.1)
				(type default)
			)
			(layer "F.Fab")
		)
		(fp_line
			(start -0.12065 -0.2794)
			(end 0.12065 -0.2794)
			(stroke
				(width 0.1)
				(type default)
			)
			(layer "F.Fab")
		)
		(fp_line
			(start 0.12065 -0.2794)
			(end 0.12065 -0.3048)
			(stroke
				(width 0.1)
				(type default)
			)
			(layer "F.Fab")
		)
		(fp_line
			(start 0.12065 -0.3048)
			(end 0.67945 -0.3048)
			(stroke
				(width 0.1)
				(type default)
			)
			(layer "F.Fab")
		)
		(fp_line
			(start 0.67945 -0.3048)
			(end 0.67945 0.3048)
			(stroke
				(width 0.1)
				(type default)
			)
			(layer "F.Fab")
		)
		(fp_line
			(start -0.67945 -0.305054)
			(end -0.12065 -0.305054)
			(stroke
				(width 0.1)
				(type default)
			)
			(layer "F.Fab")
		)
		(fp_line
			(start -0.12065 -0.305054)
			(end -0.12065 -0.2794)
			(stroke
				(width 0.1)
				(type default)
			)
			(layer "F.Fab")
		)
		(pad "1" smd circle
			(at -0.40005 0 270)
			(size 0 0)
			(layers "F.Cu" "F.Mask" "F.Paste")
			(net "PVDD11_S3_P0")
		)
		(pad "2" smd circle
			(at 0.40005 0 270)
			(size 0 0)
			(layers "F.Cu" "F.Mask" "F.Paste")
			(net "GND")
		)
	)
	(footprint ""
		(layer "F.Cu")
		(at 376.369072 -185.748168)
		(property "Reference" "PC179"
			(at 0 0 0)
			(layer "F.SilkS")
			(hide yes)
			(effects
				(font
					(size 1.27 1.27)
				)
			)
		)
		(property "Value" ""
			(at 0 0 0)
			(layer "F.Fab")
			(effects
				(font
					(size 1.27 1.27)
				)
			)
		)
		(duplicate_pad_numbers_are_jumpers no)
		(fp_line
			(start -0.7874 -0.4064)
			(end 0.7874 -0.4064)
			(stroke
				(width 0.1524)
				(type default)
			)
			(layer "F.SilkS")
		)
		(fp_line
			(start -0.7874 0.4064)
			(end -0.7874 -0.4064)
			(stroke
				(width 0.1524)
				(type default)
			)
			(layer "F.SilkS")
		)
		(fp_line
			(start 0.7874 -0.4064)
			(end 0.7874 0.4064)
			(stroke
				(width 0.1524)
				(type default)
			)
			(layer "F.SilkS")
		)
		(fp_line
			(start 0.7874 0.4064)
			(end -0.7874 0.4064)
			(stroke
				(width 0.1524)
				(type default)
			)
			(layer "F.SilkS")
		)
		(fp_line
			(start -0.67945 -0.305054)
			(end -0.12065 -0.305054)
			(stroke
				(width 0.1)
				(type default)
			)
			(layer "F.Fab")
		)
		(fp_line
			(start -0.67945 0.3048)
			(end -0.67945 -0.305054)
			(stroke
				(width 0.1)
				(type default)
			)
			(layer "F.Fab")
		)
		(fp_line
			(start -0.12065 -0.305054)
			(end -0.12065 -0.2794)
			(stroke
				(width 0.1)
				(type default)
			)
			(layer "F.Fab")
		)
		(fp_line
			(start -0.12065 -0.2794)
			(end 0.12065 -0.2794)
			(stroke
				(width 0.1)
				(type default)
			)
			(layer "F.Fab")
		)
		(fp_line
			(start -0.12065 0.2794)
			(end -0.12065 0.3048)
			(stroke
				(width 0.1)
				(type default)
			)
			(layer "F.Fab")
		)
		(fp_line
			(start -0.12065 0.3048)
			(end -0.67945 0.3048)
			(stroke
				(width 0.1)
				(type default)
			)
			(layer "F.Fab")
		)
		(fp_line
			(start 0.120396 0.2794)
			(end -0.12065 0.2794)
			(stroke
				(width 0.1)
				(type default)
			)
			(layer "F.Fab")
		)
		(fp_line
			(start 0.120396 0.3048)
			(end 0.120396 0.2794)
			(stroke
				(width 0.1)
				(type default)
			)
			(layer "F.Fab")
		)
		(fp_line
			(start 0.12065 -0.3048)
			(end 0.67945 -0.3048)
			(stroke
				(width 0.1)
				(type default)
			)
			(layer "F.Fab")
		)
		(fp_line
			(start 0.12065 -0.2794)
			(end 0.12065 -0.3048)
			(stroke
				(width 0.1)
				(type default)
			)
			(layer "F.Fab")
		)
		(fp_line
			(start 0.67945 -0.3048)
			(end 0.67945 0.3048)
			(stroke
				(width 0.1)
				(type default)
			)
			(layer "F.Fab")
		)
		(fp_line
			(start 0.67945 0.3048)
			(end 0.120396 0.3048)
			(stroke
				(width 0.1)
				(type default)
			)
			(layer "F.Fab")
		)
		(pad "1" smd circle
			(at -0.40005 0)
			(size 0 0)
			(layers "F.Cu" "F.Mask" "F.Paste")
			(net "SW_PVDDCR_CPU0_P0_SW2")
		)
		(pad "2" smd circle
			(at 0.40005 0)
			(size 0 0)
			(layers "F.Cu" "F.Mask" "F.Paste")
			(net "SW_PVDDCR_CPU0_P0_SW2_RC")
		)
	)
	(footprint ""
		(layer "F.Cu")
		(at 70.739 -52.578)
		(property "Reference" "R1172"
			(at 0 0 0)
			(layer "F.SilkS")
			(hide yes)
			(effects
				(font
					(size 1.27 1.27)
				)
			)
		)
		(property "Value" ""
			(at 0 0 0)
			(layer "F.Fab")
			(effects
				(font
					(size 1.27 1.27)
				)
			)
		)
		(duplicate_pad_numbers_are_jumpers no)
		(fp_line
			(start -0.7874 -0.4064)
			(end 0.7874 -0.4064)
			(stroke
				(width 0.1524)
				(type default)
			)
			(layer "F.SilkS")
		)
		(fp_line
			(start -0.7874 0.4064)
			(end -0.7874 -0.4064)
			(stroke
				(width 0.1524)
				(type default)
			)
			(layer "F.SilkS")
		)
		(fp_line
			(start 0.7874 -0.4064)
			(end 0.7874 0.4064)
			(stroke
				(width 0.1524)
				(type default)
			)
			(layer "F.SilkS")
		)
		(fp_line
			(start 0.7874 0.4064)
			(end -0.7874 0.4064)
			(stroke
				(width 0.1524)
				(type default)
			)
			(layer "F.SilkS")
		)
		(fp_line
			(start -0.67945 -0.305054)
			(end -0.12065 -0.305054)
			(stroke
				(width 0.1)
				(type default)
			)
			(layer "F.Fab")
		)
		(fp_line
			(start -0.67945 0.3048)
			(end -0.67945 -0.305054)
			(stroke
				(width 0.1)
				(type default)
			)
			(layer "F.Fab")
		)
		(fp_line
			(start -0.12065 -0.305054)
			(end -0.12065 -0.2794)
			(stroke
				(width 0.1)
				(type default)
			)
			(layer "F.Fab")
		)
		(fp_line
			(start -0.12065 -0.2794)
			(end 0.12065 -0.2794)
			(stroke
				(width 0.1)
				(type default)
			)
			(layer "F.Fab")
		)
		(fp_line
			(start -0.12065 0.2794)
			(end -0.12065 0.3048)
			(stroke
				(width 0.1)
				(type default)
			)
			(layer "F.Fab")
		)
		(fp_line
			(start -0.12065 0.3048)
			(end -0.67945 0.3048)
			(stroke
				(width 0.1)
				(type default)
			)
			(layer "F.Fab")
		)
		(fp_line
			(start 0.120396 0.2794)
			(end -0.12065 0.2794)
			(stroke
				(width 0.1)
				(type default)
			)
			(layer "F.Fab")
		)
		(fp_line
			(start 0.120396 0.3048)
			(end 0.120396 0.2794)
			(stroke
				(width 0.1)
				(type default)
			)
			(layer "F.Fab")
		)
		(fp_line
			(start 0.12065 -0.3048)
			(end 0.67945 -0.3048)
			(stroke
				(width 0.1)
				(type default)
			)
			(layer "F.Fab")
		)
		(fp_line
			(start 0.12065 -0.2794)
			(end 0.12065 -0.3048)
			(stroke
				(width 0.1)
				(type default)
			)
			(layer "F.Fab")
		)
		(fp_line
			(start 0.67945 -0.3048)
			(end 0.67945 0.3048)
			(stroke
				(width 0.1)
				(type default)
			)
			(layer "F.Fab")
		)
		(fp_line
			(start 0.67945 0.3048)
			(end 0.120396 0.3048)
			(stroke
				(width 0.1)
				(type default)
			)
			(layer "F.Fab")
		)
		(pad "1" smd circle
			(at -0.40005 0)
			(size 0 0)
			(layers "F.Cu" "F.Mask" "F.Paste")
			(net "P3V3_AUX")
		)
		(pad "2" smd circle
			(at 0.40005 0)
			(size 0 0)
			(layers "F.Cu" "F.Mask" "F.Paste")
			(net "OCP_V3_2_AUX_PWR_EN")
		)
	)
	(footprint ""
		(layer "F.Cu")
		(at 322.364862 -403.21484 90)
		(property "Reference" "R6808"
			(at 0 0 90)
			(layer "F.SilkS")
			(hide yes)
			(effects
				(font
					(size 1.27 1.27)
				)
			)
		)
		(property "Value" ""
			(at 0 0 90)
			(layer "F.Fab")
			(effects
				(font
					(size 1.27 1.27)
				)
			)
		)
		(duplicate_pad_numbers_are_jumpers no)
		(fp_line
			(start 0.32512 -0.175006)
			(end 0.32512 0.175006)
			(stroke
				(width 0.1)
				(type default)
			)
			(layer "F.Fab")
		)
		(fp_line
			(start -0.32512 -0.175006)
			(end 0.32512 -0.175006)
			(stroke
				(width 0.1)
				(type default)
			)
			(layer "F.Fab")
		)
		(fp_line
			(start 0.32512 0.175006)
			(end -0.32512 0.175006)
			(stroke
				(width 0.1)
				(type default)
			)
			(layer "F.Fab")
		)
		(fp_line
			(start -0.32512 0.175006)
			(end -0.32512 -0.175006)
			(stroke
				(width 0.1)
				(type default)
			)
			(layer "F.Fab")
		)
		(pad "1" smd rect
			(at -0.2667 0 90)
			(size 0.3048 0.381)
			(layers "F.Cu" "F.Mask" "F.Paste")
			(net "P1V8_CPU0_RT_1D")
		)
		(pad "2" smd rect
			(at 0.2667 0 270)
			(size 0.3048 0.381)
			(layers "F.Cu" "F.Mask" "F.Paste")
			(net "RT_CPU0_P0_VQPS")
		)
	)
	(footprint ""
		(layer "F.Cu")
		(at 111.91494 -394.166852 -90)
		(property "Reference" "R908"
			(at 0 0 270)
			(layer "F.SilkS")
			(hide yes)
			(effects
				(font
					(size 1.27 1.27)
				)
			)
		)
		(property "Value" ""
			(at 0 0 270)
			(layer "F.Fab")
			(effects
				(font
					(size 1.27 1.27)
				)
			)
		)
		(duplicate_pad_numbers_are_jumpers no)
		(fp_line
			(start -0.32512 0.175006)
			(end -0.32512 -0.175006)
			(stroke
				(width 0.1)
				(type default)
			)
			(layer "F.Fab")
		)
		(fp_line
			(start 0.32512 0.175006)
			(end -0.32512 0.175006)
			(stroke
				(width 0.1)
				(type default)
			)
			(layer "F.Fab")
		)
		(fp_line
			(start -0.32512 -0.175006)
			(end 0.32512 -0.175006)
			(stroke
				(width 0.1)
				(type default)
			)
			(layer "F.Fab")
		)
		(fp_line
			(start 0.32512 -0.175006)
			(end 0.32512 0.175006)
			(stroke
				(width 0.1)
				(type default)
			)
			(layer "F.Fab")
		)
		(pad "1" smd rect
			(at -0.2667 0 270)
			(size 0.3048 0.381)
			(layers "F.Cu" "F.Mask" "F.Paste")
			(net "RST_RT_CPU1_P3_RESET_R_N")
		)
		(pad "2" smd rect
			(at 0.2667 0 90)
			(size 0.3048 0.381)
			(layers "F.Cu" "F.Mask" "F.Paste")
			(net "GND")
		)
	)
	(footprint ""
		(layer "F.Cu")
		(at 150.502366 -57.220358)
		(property "Reference" "R3623"
			(at 0 0 0)
			(layer "F.SilkS")
			(hide yes)
			(effects
				(font
					(size 1.27 1.27)
				)
			)
		)
		(property "Value" ""
			(at 0 0 0)
			(layer "F.Fab")
			(effects
				(font
					(size 1.27 1.27)
				)
			)
		)
		(duplicate_pad_numbers_are_jumpers no)
		(fp_line
			(start -0.7874 -0.4064)
			(end 0.7874 -0.4064)
			(stroke
				(width 0.1524)
				(type default)
			)
			(layer "F.SilkS")
		)
		(fp_line
			(start -0.7874 0.4064)
			(end -0.7874 -0.4064)
			(stroke
				(width 0.1524)
				(type default)
			)
			(layer "F.SilkS")
		)
		(fp_line
			(start 0.7874 -0.4064)
			(end 0.7874 0.4064)
			(stroke
				(width 0.1524)
				(type default)
			)
			(layer "F.SilkS")
		)
		(fp_line
			(start 0.7874 0.4064)
			(end -0.7874 0.4064)
			(stroke
				(width 0.1524)
				(type default)
			)
			(layer "F.SilkS")
		)
		(fp_line
			(start -0.67945 -0.305054)
			(end -0.12065 -0.305054)
			(stroke
				(width 0.1)
				(type default)
			)
			(layer "F.Fab")
		)
		(fp_line
			(start -0.67945 0.3048)
			(end -0.67945 -0.305054)
			(stroke
				(width 0.1)
				(type default)
			)
			(layer "F.Fab")
		)
		(fp_line
			(start -0.12065 -0.305054)
			(end -0.12065 -0.2794)
			(stroke
				(width 0.1)
				(type default)
			)
			(layer "F.Fab")
		)
		(fp_line
			(start -0.12065 -0.2794)
			(end 0.12065 -0.2794)
			(stroke
				(width 0.1)
				(type default)
			)
			(layer "F.Fab")
		)
		(fp_line
			(start -0.12065 0.2794)
			(end -0.12065 0.3048)
			(stroke
				(width 0.1)
				(type default)
			)
			(layer "F.Fab")
		)
		(fp_line
			(start -0.12065 0.3048)
			(end -0.67945 0.3048)
			(stroke
				(width 0.1)
				(type default)
			)
			(layer "F.Fab")
		)
		(fp_line
			(start 0.120396 0.2794)
			(end -0.12065 0.2794)
			(stroke
				(width 0.1)
				(type default)
			)
			(layer "F.Fab")
		)
		(fp_line
			(start 0.120396 0.3048)
			(end 0.120396 0.2794)
			(stroke
				(width 0.1)
				(type default)
			)
			(layer "F.Fab")
		)
		(fp_line
			(start 0.12065 -0.3048)
			(end 0.67945 -0.3048)
			(stroke
				(width 0.1)
				(type default)
			)
			(layer "F.Fab")
		)
		(fp_line
			(start 0.12065 -0.2794)
			(end 0.12065 -0.3048)
			(stroke
				(width 0.1)
				(type default)
			)
			(layer "F.Fab")
		)
		(fp_line
			(start 0.67945 -0.3048)
			(end 0.67945 0.3048)
			(stroke
				(width 0.1)
				(type default)
			)
			(layer "F.Fab")
		)
		(fp_line
			(start 0.67945 0.3048)
			(end 0.120396 0.3048)
			(stroke
				(width 0.1)
				(type default)
			)
			(layer "F.Fab")
		)
		(pad "1" smd circle
			(at -0.40005 0)
			(size 0 0)
			(layers "F.Cu" "F.Mask" "F.Paste")
			(net "P3V3_AUX")
		)
		(pad "2" smd circle
			(at 0.40005 0)
			(size 0 0)
			(layers "F.Cu" "F.Mask" "F.Paste")
			(net "INA230_4_A1")
		)
	)
	(footprint ""
		(layer "F.Cu")
		(at 351.404936 -162.87369 -90)
		(property "Reference" "PR500"
			(at 0 0 270)
			(layer "F.SilkS")
			(hide yes)
			(effects
				(font
					(size 1.27 1.27)
				)
			)
		)
		(property "Value" ""
			(at 0 0 270)
			(layer "F.Fab")
			(effects
				(font
					(size 1.27 1.27)
				)
			)
		)
		(duplicate_pad_numbers_are_jumpers no)
		(fp_line
			(start -0.7874 0.4064)
			(end -0.7874 -0.4064)
			(stroke
				(width 0.1524)
				(type default)
			)
			(layer "F.SilkS")
		)
		(fp_line
			(start 0.7874 0.4064)
			(end -0.7874 0.4064)
			(stroke
				(width 0.1524)
				(type default)
			)
			(layer "F.SilkS")
		)
		(fp_line
			(start -0.7874 -0.4064)
			(end 0.7874 -0.4064)
			(stroke
				(width 0.1524)
				(type default)
			)
			(layer "F.SilkS")
		)
		(fp_line
			(start 0.7874 -0.4064)
			(end 0.7874 0.4064)
			(stroke
				(width 0.1524)
				(type default)
			)
			(layer "F.SilkS")
		)
		(fp_line
			(start -0.67945 0.3048)
			(end -0.67945 -0.305054)
			(stroke
				(width 0.1)
				(type default)
			)
			(layer "F.Fab")
		)
		(fp_line
			(start -0.12065 0.3048)
			(end -0.67945 0.3048)
			(stroke
				(width 0.1)
				(type default)
			)
			(layer "F.Fab")
		)
		(fp_line
			(start 0.120396 0.3048)
			(end 0.120396 0.2794)
			(stroke
				(width 0.1)
				(type default)
			)
			(layer "F.Fab")
		)
		(fp_line
			(start 0.67945 0.3048)
			(end 0.120396 0.3048)
			(stroke
				(width 0.1)
				(type default)
			)
			(layer "F.Fab")
		)
		(fp_line
			(start -0.12065 0.2794)
			(end -0.12065 0.3048)
			(stroke
				(width 0.1)
				(type default)
			)
			(layer "F.Fab")
		)
		(fp_line
			(start 0.120396 0.2794)
			(end -0.12065 0.2794)
			(stroke
				(width 0.1)
				(type default)
			)
			(layer "F.Fab")
		)
		(fp_line
			(start -0.12065 -0.2794)
			(end 0.12065 -0.2794)
			(stroke
				(width 0.1)
				(type default)
			)
			(layer "F.Fab")
		)
		(fp_line
			(start 0.12065 -0.2794)
			(end 0.12065 -0.3048)
			(stroke
				(width 0.1)
				(type default)
			)
			(layer "F.Fab")
		)
		(fp_line
			(start 0.12065 -0.3048)
			(end 0.67945 -0.3048)
			(stroke
				(width 0.1)
				(type default)
			)
			(layer "F.Fab")
		)
		(fp_line
			(start 0.67945 -0.3048)
			(end 0.67945 0.3048)
			(stroke
				(width 0.1)
				(type default)
			)
			(layer "F.Fab")
		)
		(fp_line
			(start -0.67945 -0.305054)
			(end -0.12065 -0.305054)
			(stroke
				(width 0.1)
				(type default)
			)
			(layer "F.Fab")
		)
		(fp_line
			(start -0.12065 -0.305054)
			(end -0.12065 -0.2794)
			(stroke
				(width 0.1)
				(type default)
			)
			(layer "F.Fab")
		)
		(pad "1" smd circle
			(at -0.40005 0 270)
			(size 0 0)
			(layers "F.Cu" "F.Mask" "F.Paste")
			(net "SW_PVDDCR_CPU0_P0_SW6_RC")
		)
		(pad "2" smd circle
			(at 0.40005 0 270)
			(size 0 0)
			(layers "F.Cu" "F.Mask" "F.Paste")
			(net "GND")
		)
	)
	(footprint ""
		(layer "F.Cu")
		(at 310.902096 -383.88163 -90)
		(property "Reference" "C919"
			(at 0 0 270)
			(layer "F.SilkS")
			(hide yes)
			(effects
				(font
					(size 1.27 1.27)
				)
			)
		)
		(property "Value" ""
			(at 0 0 270)
			(layer "F.Fab")
			(effects
				(font
					(size 1.27 1.27)
				)
			)
		)
		(duplicate_pad_numbers_are_jumpers no)
		(fp_line
			(start -0.299974 0.150114)
			(end -0.299974 -0.150114)
			(stroke
				(width 0.1)
				(type default)
			)
			(layer "F.Fab")
		)
		(fp_line
			(start 0.299974 0.150114)
			(end -0.299974 0.150114)
			(stroke
				(width 0.1)
				(type default)
			)
			(layer "F.Fab")
		)
		(fp_line
			(start -0.299974 -0.150114)
			(end 0.299974 -0.150114)
			(stroke
				(width 0.1)
				(type default)
			)
			(layer "F.Fab")
		)
		(fp_line
			(start 0.299974 -0.150114)
			(end 0.299974 0.150114)
			(stroke
				(width 0.1)
				(type default)
			)
			(layer "F.Fab")
		)
		(pad "1" smd rect
			(at -0.2667 0 270)
			(size 0.3048 0.381)
			(layers "F.Cu" "F.Mask" "F.Paste")
			(net "P5E_CPU0_P0_TX_C_DP<7>")
		)
		(pad "2" smd rect
			(at 0.2667 0 270)
			(size 0.3048 0.381)
			(layers "F.Cu" "F.Mask" "F.Paste")
			(net "P5E_CPU0_P0_TX_DP<7>")
		)
	)
	(footprint ""
		(layer "F.Cu")
		(at 360.81589 -390.652)
		(property "Reference" "R1018"
			(at 0 0 0)
			(layer "F.SilkS")
			(hide yes)
			(effects
				(font
					(size 1.27 1.27)
				)
			)
		)
		(property "Value" ""
			(at 0 0 0)
			(layer "F.Fab")
			(effects
				(font
					(size 1.27 1.27)
				)
			)
		)
		(duplicate_pad_numbers_are_jumpers no)
		(fp_line
			(start -0.32512 -0.175006)
			(end 0.32512 -0.175006)
			(stroke
				(width 0.1)
				(type default)
			)
			(layer "F.Fab")
		)
		(fp_line
			(start -0.32512 0.175006)
			(end -0.32512 -0.175006)
			(stroke
				(width 0.1)
				(type default)
			)
			(layer "F.Fab")
		)
		(fp_line
			(start 0.32512 -0.175006)
			(end 0.32512 0.175006)
			(stroke
				(width 0.1)
				(type default)
			)
			(layer "F.Fab")
		)
		(fp_line
			(start 0.32512 0.175006)
			(end -0.32512 0.175006)
			(stroke
				(width 0.1)
				(type default)
			)
			(layer "F.Fab")
		)
		(pad "1" smd rect
			(at -0.2667 0)
			(size 0.3048 0.381)
			(layers "F.Cu" "F.Mask" "F.Paste")
			(net "RT_CPU0_P1_ADDR1")
		)
		(pad "2" smd rect
			(at 0.2667 0 180)
			(size 0.3048 0.381)
			(layers "F.Cu" "F.Mask" "F.Paste")
			(net "GND")
		)
	)
	(footprint ""
		(layer "F.Cu")
		(at 21.938996 -389.171434 -90)
		(property "Reference" "PC6644_09P1_2"
			(at 0 0 270)
			(layer "F.SilkS")
			(hide yes)
			(effects
				(font
					(size 1.27 1.27)
				)
			)
		)
		(property "Value" ""
			(at 0 0 270)
			(layer "F.Fab")
			(effects
				(font
					(size 1.27 1.27)
				)
			)
		)
		(duplicate_pad_numbers_are_jumpers no)
		(fp_line
			(start -0.7874 0.4064)
			(end -0.7874 -0.4064)
			(stroke
				(width 0.1524)
				(type default)
			)
			(layer "F.SilkS")
		)
		(fp_line
			(start 0.7874 0.4064)
			(end -0.7874 0.4064)
			(stroke
				(width 0.1524)
				(type default)
			)
			(layer "F.SilkS")
		)
		(fp_line
			(start -0.7874 -0.4064)
			(end 0.7874 -0.4064)
			(stroke
				(width 0.1524)
				(type default)
			)
			(layer "F.SilkS")
		)
		(fp_line
			(start 0.7874 -0.4064)
			(end 0.7874 0.4064)
			(stroke
				(width 0.1524)
				(type default)
			)
			(layer "F.SilkS")
		)
		(fp_line
			(start -0.67945 0.3048)
			(end -0.67945 -0.305054)
			(stroke
				(width 0.1)
				(type default)
			)
			(layer "F.Fab")
		)
		(fp_line
			(start -0.12065 0.3048)
			(end -0.67945 0.3048)
			(stroke
				(width 0.1)
				(type default)
			)
			(layer "F.Fab")
		)
		(fp_line
			(start 0.120396 0.3048)
			(end 0.120396 0.2794)
			(stroke
				(width 0.1)
				(type default)
			)
			(layer "F.Fab")
		)
		(fp_line
			(start 0.67945 0.3048)
			(end 0.120396 0.3048)
			(stroke
				(width 0.1)
				(type default)
			)
			(layer "F.Fab")
		)
		(fp_line
			(start -0.12065 0.2794)
			(end -0.12065 0.3048)
			(stroke
				(width 0.1)
				(type default)
			)
			(layer "F.Fab")
		)
		(fp_line
			(start 0.120396 0.2794)
			(end -0.12065 0.2794)
			(stroke
				(width 0.1)
				(type default)
			)
			(layer "F.Fab")
		)
		(fp_line
			(start -0.12065 -0.2794)
			(end 0.12065 -0.2794)
			(stroke
				(width 0.1)
				(type default)
			)
			(layer "F.Fab")
		)
		(fp_line
			(start 0.12065 -0.2794)
			(end 0.12065 -0.3048)
			(stroke
				(width 0.1)
				(type default)
			)
			(layer "F.Fab")
		)
		(fp_line
			(start 0.12065 -0.3048)
			(end 0.67945 -0.3048)
			(stroke
				(width 0.1)
				(type default)
			)
			(layer "F.Fab")
		)
		(fp_line
			(start 0.67945 -0.3048)
			(end 0.67945 0.3048)
			(stroke
				(width 0.1)
				(type default)
			)
			(layer "F.Fab")
		)
		(fp_line
			(start -0.67945 -0.305054)
			(end -0.12065 -0.305054)
			(stroke
				(width 0.1)
				(type default)
			)
			(layer "F.Fab")
		)
		(fp_line
			(start -0.12065 -0.305054)
			(end -0.12065 -0.2794)
			(stroke
				(width 0.1)
				(type default)
			)
			(layer "F.Fab")
		)
		(pad "1" smd circle
			(at -0.40005 0 270)
			(size 0 0)
			(layers "F.Cu" "F.Mask" "F.Paste")
			(net "P0V9_RETIMER_CPU1_PVCC")
		)
		(pad "2" smd circle
			(at 0.40005 0 270)
			(size 0 0)
			(layers "F.Cu" "F.Mask" "F.Paste")
			(net "GND")
		)
	)
	(footprint ""
		(layer "F.Cu")
		(at 432.783488 -332.63586 -90)
		(property "Reference" "PC229"
			(at -4.97332 -7.844536 90)
			(unlocked yes)
			(layer "F.SilkS")
			(effects
				(font
					(size 0.7874 0.5842)
					(thickness 0.1524)
				)
				(justify left)
			)
		)
		(property "Value" ""
			(at 0 0 270)
			(layer "F.Fab")
			(effects
				(font
					(size 1.27 1.27)
				)
			)
		)
		(duplicate_pad_numbers_are_jumpers no)
		(fp_line
			(start -1.988058 2.750058)
			(end 2.750058 2.750058)
			(stroke
				(width 0.1524)
				(type default)
			)
			(layer "F.SilkS")
		)
		(fp_line
			(start 2.750058 2.750058)
			(end 2.750058 0.9398)
			(stroke
				(width 0.1524)
				(type default)
			)
			(layer "F.SilkS")
		)
		(fp_line
			(start -2.750058 1.988058)
			(end -1.988058 2.750058)
			(stroke
				(width 0.1524)
				(type default)
			)
			(layer "F.SilkS")
		)
		(fp_line
			(start -2.750058 0.9398)
			(end -2.750058 1.988058)
			(stroke
				(width 0.1524)
				(type default)
			)
			(layer "F.SilkS")
		)
		(fp_line
			(start 2.750058 -0.9398)
			(end 2.750058 -2.750058)
			(stroke
				(width 0.1524)
				(type default)
			)
			(layer "F.SilkS")
		)
		(fp_line
			(start -2.750058 -1.988058)
			(end -2.750058 -0.9398)
			(stroke
				(width 0.1524)
				(type default)
			)
			(layer "F.SilkS")
		)
		(fp_line
			(start -1.988058 -2.750058)
			(end -2.750058 -1.988058)
			(stroke
				(width 0.1524)
				(type default)
			)
			(layer "F.SilkS")
		)
		(fp_line
			(start 2.750058 -2.750058)
			(end -1.988058 -2.750058)
			(stroke
				(width 0.1524)
				(type default)
			)
			(layer "F.SilkS")
		)
		(fp_line
			(start -2.750058 2.750058)
			(end 2.750058 2.750058)
			(stroke
				(width 0.1)
				(type default)
			)
			(layer "F.Fab")
		)
		(fp_line
			(start 2.750058 2.750058)
			(end 2.750058 -2.750058)
			(stroke
				(width 0.1)
				(type default)
			)
			(layer "F.Fab")
		)
		(fp_line
			(start -2.750058 -2.750058)
			(end -2.750058 2.750058)
			(stroke
				(width 0.1)
				(type default)
			)
			(layer "F.Fab")
		)
		(fp_line
			(start 2.750058 -2.750058)
			(end -2.750058 -2.750058)
			(stroke
				(width 0.1)
				(type default)
			)
			(layer "F.Fab")
		)
		(pad "1" smd rect
			(at -2.199894 0)
			(size 1.6002 3.0226)
			(layers "F.Cu" "F.Mask" "F.Paste")
			(net "PVDD11_S3_P0")
		)
		(pad "2" smd rect
			(at 2.199894 0)
			(size 1.6002 3.0226)
			(layers "F.Cu" "F.Mask" "F.Paste")
			(net "GND")
		)
	)
	(footprint ""
		(layer "F.Cu")
		(at 300.022514 -24.349456)
		(property "Reference" "R1777"
			(at 0 0 0)
			(layer "F.SilkS")
			(hide yes)
			(effects
				(font
					(size 1.27 1.27)
				)
			)
		)
		(property "Value" ""
			(at 0 0 0)
			(layer "F.Fab")
			(effects
				(font
					(size 1.27 1.27)
				)
			)
		)
		(duplicate_pad_numbers_are_jumpers no)
		(fp_line
			(start -0.7874 -0.4064)
			(end 0.7874 -0.4064)
			(stroke
				(width 0.1524)
				(type default)
			)
			(layer "F.SilkS")
		)
		(fp_line
			(start -0.7874 0.4064)
			(end -0.7874 -0.4064)
			(stroke
				(width 0.1524)
				(type default)
			)
			(layer "F.SilkS")
		)
		(fp_line
			(start 0.7874 -0.4064)
			(end 0.7874 0.4064)
			(stroke
				(width 0.1524)
				(type default)
			)
			(layer "F.SilkS")
		)
		(fp_line
			(start 0.7874 0.4064)
			(end -0.7874 0.4064)
			(stroke
				(width 0.1524)
				(type default)
			)
			(layer "F.SilkS")
		)
		(fp_line
			(start -0.67945 -0.305054)
			(end -0.12065 -0.305054)
			(stroke
				(width 0.1)
				(type default)
			)
			(layer "F.Fab")
		)
		(fp_line
			(start -0.67945 0.3048)
			(end -0.67945 -0.305054)
			(stroke
				(width 0.1)
				(type default)
			)
			(layer "F.Fab")
		)
		(fp_line
			(start -0.12065 -0.305054)
			(end -0.12065 -0.2794)
			(stroke
				(width 0.1)
				(type default)
			)
			(layer "F.Fab")
		)
		(fp_line
			(start -0.12065 -0.2794)
			(end 0.12065 -0.2794)
			(stroke
				(width 0.1)
				(type default)
			)
			(layer "F.Fab")
		)
		(fp_line
			(start -0.12065 0.2794)
			(end -0.12065 0.3048)
			(stroke
				(width 0.1)
				(type default)
			)
			(layer "F.Fab")
		)
		(fp_line
			(start -0.12065 0.3048)
			(end -0.67945 0.3048)
			(stroke
				(width 0.1)
				(type default)
			)
			(layer "F.Fab")
		)
		(fp_line
			(start 0.120396 0.2794)
			(end -0.12065 0.2794)
			(stroke
				(width 0.1)
				(type default)
			)
			(layer "F.Fab")
		)
		(fp_line
			(start 0.120396 0.3048)
			(end 0.120396 0.2794)
			(stroke
				(width 0.1)
				(type default)
			)
			(layer "F.Fab")
		)
		(fp_line
			(start 0.12065 -0.3048)
			(end 0.67945 -0.3048)
			(stroke
				(width 0.1)
				(type default)
			)
			(layer "F.Fab")
		)
		(fp_line
			(start 0.12065 -0.2794)
			(end 0.12065 -0.3048)
			(stroke
				(width 0.1)
				(type default)
			)
			(layer "F.Fab")
		)
		(fp_line
			(start 0.67945 -0.3048)
			(end 0.67945 0.3048)
			(stroke
				(width 0.1)
				(type default)
			)
			(layer "F.Fab")
		)
		(fp_line
			(start 0.67945 0.3048)
			(end 0.120396 0.3048)
			(stroke
				(width 0.1)
				(type default)
			)
			(layer "F.Fab")
		)
		(pad "1" smd circle
			(at -0.40005 0)
			(size 0 0)
			(layers "F.Cu" "F.Mask" "F.Paste")
			(net "P1V5_BAT_IN")
		)
		(pad "2" smd circle
			(at 0.40005 0)
			(size 0 0)
			(layers "F.Cu" "F.Mask" "F.Paste")
			(net "BAT_LDO_EN")
		)
	)
	(footprint ""
		(layer "F.Cu")
		(at 392.840972 -385.364228)
		(property "Reference" "C873"
			(at 0 0 0)
			(layer "F.SilkS")
			(hide yes)
			(effects
				(font
					(size 1.27 1.27)
				)
			)
		)
		(property "Value" ""
			(at 0 0 0)
			(layer "F.Fab")
			(effects
				(font
					(size 1.27 1.27)
				)
			)
		)
		(duplicate_pad_numbers_are_jumpers no)
		(fp_line
			(start -0.299974 -0.150114)
			(end 0.299974 -0.150114)
			(stroke
				(width 0.1)
				(type default)
			)
			(layer "F.Fab")
		)
		(fp_line
			(start -0.299974 0.150114)
			(end -0.299974 -0.150114)
			(stroke
				(width 0.1)
				(type default)
			)
			(layer "F.Fab")
		)
		(fp_line
			(start 0.299974 -0.150114)
			(end 0.299974 0.150114)
			(stroke
				(width 0.1)
				(type default)
			)
			(layer "F.Fab")
		)
		(fp_line
			(start 0.299974 0.150114)
			(end -0.299974 0.150114)
			(stroke
				(width 0.1)
				(type default)
			)
			(layer "F.Fab")
		)
		(pad "1" smd rect
			(at -0.2667 0)
			(size 0.3048 0.381)
			(layers "F.Cu" "F.Mask" "F.Paste")
			(net "P5E_CPU0_P3_TX_C_DP<14>")
		)
		(pad "2" smd rect
			(at 0.2667 0)
			(size 0.3048 0.381)
			(layers "F.Cu" "F.Mask" "F.Paste")
			(net "P5E_CPU0_P3_TX_DP<14>")
		)
	)
	(footprint ""
		(layer "F.Cu")
		(at 341.441786 -416.899344 -90)
		(property "Reference" "C6525"
			(at 0 0 270)
			(layer "F.SilkS")
			(hide yes)
			(effects
				(font
					(size 1.27 1.27)
				)
			)
		)
		(property "Value" ""
			(at 0 0 270)
			(layer "F.Fab")
			(effects
				(font
					(size 1.27 1.27)
				)
			)
		)
		(duplicate_pad_numbers_are_jumpers no)
		(fp_line
			(start -0.299974 0.150114)
			(end -0.299974 -0.150114)
			(stroke
				(width 0.1)
				(type default)
			)
			(layer "F.Fab")
		)
		(fp_line
			(start 0.299974 0.150114)
			(end -0.299974 0.150114)
			(stroke
				(width 0.1)
				(type default)
			)
			(layer "F.Fab")
		)
		(fp_line
			(start -0.299974 -0.150114)
			(end 0.299974 -0.150114)
			(stroke
				(width 0.1)
				(type default)
			)
			(layer "F.Fab")
		)
		(fp_line
			(start 0.299974 -0.150114)
			(end 0.299974 0.150114)
			(stroke
				(width 0.1)
				(type default)
			)
			(layer "F.Fab")
		)
		(pad "1" smd rect
			(at -0.2667 0 270)
			(size 0.3048 0.381)
			(layers "F.Cu" "F.Mask" "F.Paste")
			(net "P5E_CPU0_P0_TX_BUF_C_DP<12>")
		)
		(pad "2" smd rect
			(at 0.2667 0 270)
			(size 0.3048 0.381)
			(layers "F.Cu" "F.Mask" "F.Paste")
			(net "P5E_CPU0_P0_TX_BUF_DP<12>")
		)
	)
	(footprint ""
		(layer "F.Cu")
		(at 140.886942 -107.683046)
		(property "Reference" "R336"
			(at 0 0 0)
			(layer "F.SilkS")
			(hide yes)
			(effects
				(font
					(size 1.27 1.27)
				)
			)
		)
		(property "Value" ""
			(at 0 0 0)
			(layer "F.Fab")
			(effects
				(font
					(size 1.27 1.27)
				)
			)
		)
		(duplicate_pad_numbers_are_jumpers no)
		(fp_line
			(start -0.7874 -0.4064)
			(end 0.7874 -0.4064)
			(stroke
				(width 0.1524)
				(type default)
			)
			(layer "F.SilkS")
		)
		(fp_line
			(start -0.7874 0.4064)
			(end -0.7874 -0.4064)
			(stroke
				(width 0.1524)
				(type default)
			)
			(layer "F.SilkS")
		)
		(fp_line
			(start 0.7874 -0.4064)
			(end 0.7874 0.4064)
			(stroke
				(width 0.1524)
				(type default)
			)
			(layer "F.SilkS")
		)
		(fp_line
			(start 0.7874 0.4064)
			(end -0.7874 0.4064)
			(stroke
				(width 0.1524)
				(type default)
			)
			(layer "F.SilkS")
		)
		(fp_line
			(start -0.67945 -0.305054)
			(end -0.12065 -0.305054)
			(stroke
				(width 0.1)
				(type default)
			)
			(layer "F.Fab")
		)
		(fp_line
			(start -0.67945 0.3048)
			(end -0.67945 -0.305054)
			(stroke
				(width 0.1)
				(type default)
			)
			(layer "F.Fab")
		)
		(fp_line
			(start -0.12065 -0.305054)
			(end -0.12065 -0.2794)
			(stroke
				(width 0.1)
				(type default)
			)
			(layer "F.Fab")
		)
		(fp_line
			(start -0.12065 -0.2794)
			(end 0.12065 -0.2794)
			(stroke
				(width 0.1)
				(type default)
			)
			(layer "F.Fab")
		)
		(fp_line
			(start -0.12065 0.2794)
			(end -0.12065 0.3048)
			(stroke
				(width 0.1)
				(type default)
			)
			(layer "F.Fab")
		)
		(fp_line
			(start -0.12065 0.3048)
			(end -0.67945 0.3048)
			(stroke
				(width 0.1)
				(type default)
			)
			(layer "F.Fab")
		)
		(fp_line
			(start 0.120396 0.2794)
			(end -0.12065 0.2794)
			(stroke
				(width 0.1)
				(type default)
			)
			(layer "F.Fab")
		)
		(fp_line
			(start 0.120396 0.3048)
			(end 0.120396 0.2794)
			(stroke
				(width 0.1)
				(type default)
			)
			(layer "F.Fab")
		)
		(fp_line
			(start 0.12065 -0.3048)
			(end 0.67945 -0.3048)
			(stroke
				(width 0.1)
				(type default)
			)
			(layer "F.Fab")
		)
		(fp_line
			(start 0.12065 -0.2794)
			(end 0.12065 -0.3048)
			(stroke
				(width 0.1)
				(type default)
			)
			(layer "F.Fab")
		)
		(fp_line
			(start 0.67945 -0.3048)
			(end 0.67945 0.3048)
			(stroke
				(width 0.1)
				(type default)
			)
			(layer "F.Fab")
		)
		(fp_line
			(start 0.67945 0.3048)
			(end 0.120396 0.3048)
			(stroke
				(width 0.1)
				(type default)
			)
			(layer "F.Fab")
		)
		(pad "1" smd circle
			(at -0.40005 0)
			(size 0 0)
			(layers "F.Cu" "F.Mask" "F.Paste")
			(net "P12V_AUX")
		)
		(pad "2" smd circle
			(at 0.40005 0)
			(size 0 0)
			(layers "F.Cu" "F.Mask" "F.Paste")
			(net "VR_P5V_EN_N")
		)
	)
	(footprint ""
		(layer "F.Cu")
		(at 57.378092 -255.560322 180)
		(property "Reference" "J24"
			(at 1.914906 -84.58708 0)
			(unlocked yes)
			(layer "F.SilkS")
			(effects
				(font
					(size 0.7874 0.5842)
					(thickness 0.1524)
				)
			)
		)
		(property "Value" ""
			(at 0 0 180)
			(layer "F.Fab")
			(effects
				(font
					(size 1.27 1.27)
				)
			)
		)
		(duplicate_pad_numbers_are_jumpers no)
		(fp_line
			(start 3.24993 -81.000092)
			(end 3.24993 75.401678)
			(stroke
				(width 0.1524)
				(type default)
			)
			(layer "F.SilkS")
		)
		(fp_line
			(start -3.24993 75.401678)
			(end -3.24993 62.447678)
			(stroke
				(width 0.1524)
				(type default)
			)
			(layer "F.SilkS")
		)
		(fp_line
			(start -3.24993 72.499982)
			(end 3.24993 72.499982)
			(stroke
				(width 0.1524)
				(type default)
			)
			(layer "F.SilkS")
		)
		(fp_line
			(start -3.24993 4.789678)
			(end -3.24993 1.106678)
			(stroke
				(width 0.1524)
				(type default)
			)
			(layer "F.SilkS")
		)
		(fp_line
			(start -3.24993 -58.583322)
			(end -3.24993 -72.934322)
			(stroke
				(width 0.1524)
				(type default)
			)
			(layer "F.SilkS")
		)
		(fp_line
			(start -3.24993 -72.499982)
			(end 3.24993 -72.499982)
			(stroke
				(width 0.1524)
				(type default)
			)
			(layer "F.SilkS")
		)
		(fp_poly
			(pts
				(xy -4.714494 -64.005714) (xy -3.698494 -63.497714) (xy -4.714494 -62.989714)
			)
			(stroke
				(width 0)
				(type default)
			)
			(fill yes)
			(layer "F.SilkS")
		)
		(fp_line
			(start 3.24993 81.000092)
			(end -3.24993 81.000092)
			(stroke
				(width 0.1)
				(type default)
			)
			(layer "F.Fab")
		)
		(fp_line
			(start 3.24993 -81.000092)
			(end 3.24993 81.000092)
			(stroke
				(width 0.1)
				(type default)
			)
			(layer "F.Fab")
		)
		(fp_line
			(start -3.24993 81.000092)
			(end -3.24993 -81.000092)
			(stroke
				(width 0.1)
				(type default)
			)
			(layer "F.Fab")
		)
		(fp_line
			(start -3.24993 72.499982)
			(end 3.24993 72.499982)
			(stroke
				(width 0.1)
				(type default)
			)
			(layer "F.Fab")
		)
		(fp_line
			(start -3.24993 71.000112)
			(end 3.24993 71.000112)
			(stroke
				(width 0.1)
				(type default)
			)
			(layer "F.Fab")
		)
		(fp_line
			(start -3.24993 -71.000112)
			(end 3.24993 -71.000112)
			(stroke
				(width 0.1)
				(type default)
			)
			(layer "F.Fab")
		)
		(fp_line
			(start -3.24993 -72.499982)
			(end 3.24993 -72.499982)
			(stroke
				(width 0.1)
				(type default)
			)
			(layer "F.Fab")
		)
		(fp_line
			(start -3.24993 -81.000092)
			(end 3.24993 -81.000092)
			(stroke
				(width 0.1)
				(type default)
			)
			(layer "F.Fab")
		)
		(fp_poly
			(pts
				(xy -3.41503 -63.324994) (xy -4.43103 -62.816994) (xy -4.43103 -63.832994)
			)
			(stroke
				(width 0)
				(type default)
			)
			(fill yes)
			(layer "F.Fab")
		)
		(pad "1" smd rect
			(at -2.050034 -63.324994 90)
			(size 0.519938 1.4986)
			(layers "F.Cu" "F.Mask" "F.Paste")
			(net "P12V_MEM_CPU1")
		)
		(pad "2" smd rect
			(at -2.050034 -62.47511 90)
			(size 0.519938 1.4986)
			(layers "F.Cu" "F.Mask" "F.Paste")
			(net "Net_2256")
		)
		(pad "3" smd rect
			(at -2.050034 -61.624972 90)
			(size 0.519938 1.4986)
			(layers "F.Cu" "F.Mask" "F.Paste")
			(net "P3V3_AUX")
		)
		(pad "4" smd rect
			(at -2.050034 -60.775088 90)
			(size 0.519938 1.4986)
			(layers "F.Cu" "F.Mask" "F.Paste")
			(net "I3C_SPD_DDRA_CPU1_SCL")
		)
		(pad "5" smd rect
			(at -2.050034 -59.92495 90)
			(size 0.519938 1.4986)
			(layers "F.Cu" "F.Mask" "F.Paste")
			(net "I3C_SPD_DDRA_CPU1_SDA")
		)
		(pad "6" smd rect
			(at -2.050034 -59.075066 90)
			(size 0.519938 1.4986)
			(layers "F.Cu" "F.Mask" "F.Paste")
			(net "GND")
		)
		(pad "7" smd rect
			(at -2.050034 -58.224928 90)
			(size 0.519938 1.4986)
			(layers "F.Cu" "F.Mask" "F.Paste")
			(net "M_A_CPU1_SA_DQ<0>")
		)
		(pad "8" smd rect
			(at -2.050034 -57.375044 90)
			(size 0.519938 1.4986)
			(layers "F.Cu" "F.Mask" "F.Paste")
			(net "GND")
		)
		(pad "9" smd rect
			(at -2.050034 -56.524906 90)
			(size 0.519938 1.4986)
			(layers "F.Cu" "F.Mask" "F.Paste")
			(net "M_A_CPU1_SA_DQ<1>")
		)
		(pad "10" smd rect
			(at -2.050034 -55.675022 90)
			(size 0.519938 1.4986)
			(layers "F.Cu" "F.Mask" "F.Paste")
			(net "GND")
		)
		(pad "11" smd rect
			(at -2.050034 -54.824884 90)
			(size 0.519938 1.4986)
			(layers "F.Cu" "F.Mask" "F.Paste")
			(net "M_A_CPU1_SA_DQS_DP<0>")
		)
		(pad "12" smd rect
			(at -2.050034 -53.975 90)
			(size 0.519938 1.4986)
			(layers "F.Cu" "F.Mask" "F.Paste")
			(net "M_A_CPU1_SA_DQS_DN<0>")
		)
		(pad "13" smd rect
			(at -2.050034 -53.125116 90)
			(size 0.519938 1.4986)
			(layers "F.Cu" "F.Mask" "F.Paste")
			(net "GND")
		)
		(pad "14" smd rect
			(at -2.050034 -52.274978 90)
			(size 0.519938 1.4986)
			(layers "F.Cu" "F.Mask" "F.Paste")
			(net "M_A_CPU1_SA_DQ<4>")
		)
		(pad "15" smd rect
			(at -2.050034 -51.425094 90)
			(size 0.519938 1.4986)
			(layers "F.Cu" "F.Mask" "F.Paste")
			(net "GND")
		)
		(pad "16" smd rect
			(at -2.050034 -50.574956 90)
			(size 0.519938 1.4986)
			(layers "F.Cu" "F.Mask" "F.Paste")
			(net "M_A_CPU1_SA_DQ<5>")
		)
		(pad "17" smd rect
			(at -2.050034 -49.725072 90)
			(size 0.519938 1.4986)
			(layers "F.Cu" "F.Mask" "F.Paste")
			(net "GND")
		)
		(pad "18" smd rect
			(at -2.050034 -48.874934 90)
			(size 0.519938 1.4986)
			(layers "F.Cu" "F.Mask" "F.Paste")
			(net "M_A_CPU1_SA_DQ<8>")
		)
		(pad "19" smd rect
			(at -2.050034 -48.02505 90)
			(size 0.519938 1.4986)
			(layers "F.Cu" "F.Mask" "F.Paste")
			(net "GND")
		)
		(pad "20" smd rect
			(at -2.050034 -47.174912 90)
			(size 0.519938 1.4986)
			(layers "F.Cu" "F.Mask" "F.Paste")
			(net "M_A_CPU1_SA_DQ<9>")
		)
		(pad "21" smd rect
			(at -2.050034 -46.325028 90)
			(size 0.519938 1.4986)
			(layers "F.Cu" "F.Mask" "F.Paste")
			(net "GND")
		)
		(pad "22" smd rect
			(at -2.050034 -45.47489 90)
			(size 0.519938 1.4986)
			(layers "F.Cu" "F.Mask" "F.Paste")
			(net "M_A_CPU1_SA_DQS_DP<1>")
		)
		(pad "23" smd rect
			(at -2.050034 -44.625006 90)
			(size 0.519938 1.4986)
			(layers "F.Cu" "F.Mask" "F.Paste")
			(net "M_A_CPU1_SA_DQS_DN<1>")
		)
		(pad "24" smd rect
			(at -2.050034 -43.775122 90)
			(size 0.519938 1.4986)
			(layers "F.Cu" "F.Mask" "F.Paste")
			(net "GND")
		)
		(pad "25" smd rect
			(at -2.050034 -42.924984 90)
			(size 0.519938 1.4986)
			(layers "F.Cu" "F.Mask" "F.Paste")
			(net "M_A_CPU1_SA_DQ<12>")
		)
		(pad "26" smd rect
			(at -2.050034 -42.0751 90)
			(size 0.519938 1.4986)
			(layers "F.Cu" "F.Mask" "F.Paste")
			(net "GND")
		)
		(pad "27" smd rect
			(at -2.050034 -41.224962 90)
			(size 0.519938 1.4986)
			(layers "F.Cu" "F.Mask" "F.Paste")
			(net "M_A_CPU1_SA_DQ<13>")
		)
		(pad "28" smd rect
			(at -2.050034 -40.375078 90)
			(size 0.519938 1.4986)
			(layers "F.Cu" "F.Mask" "F.Paste")
			(net "GND")
		)
		(pad "29" smd rect
			(at -2.050034 -39.52494 90)
			(size 0.519938 1.4986)
			(layers "F.Cu" "F.Mask" "F.Paste")
			(net "M_A_CPU1_SA_DQ<16>")
		)
		(pad "30" smd rect
			(at -2.050034 -38.675056 90)
			(size 0.519938 1.4986)
			(layers "F.Cu" "F.Mask" "F.Paste")
			(net "GND")
		)
		(pad "31" smd rect
			(at -2.050034 -37.824918 90)
			(size 0.519938 1.4986)
			(layers "F.Cu" "F.Mask" "F.Paste")
			(net "M_A_CPU1_SA_DQ<17>")
		)
		(pad "32" smd rect
			(at -2.050034 -36.975034 90)
			(size 0.519938 1.4986)
			(layers "F.Cu" "F.Mask" "F.Paste")
			(net "GND")
		)
		(pad "33" smd rect
			(at -2.050034 -36.124896 90)
			(size 0.519938 1.4986)
			(layers "F.Cu" "F.Mask" "F.Paste")
			(net "M_A_CPU1_SA_DQS_DP<2>")
		)
		(pad "34" smd rect
			(at -2.050034 -35.275012 90)
			(size 0.519938 1.4986)
			(layers "F.Cu" "F.Mask" "F.Paste")
			(net "M_A_CPU1_SA_DQS_DN<2>")
		)
		(pad "35" smd rect
			(at -2.050034 -34.425128 90)
			(size 0.519938 1.4986)
			(layers "F.Cu" "F.Mask" "F.Paste")
			(net "GND")
		)
		(pad "36" smd rect
			(at -2.050034 -33.57499 90)
			(size 0.519938 1.4986)
			(layers "F.Cu" "F.Mask" "F.Paste")
			(net "M_A_CPU1_SA_DQ<20>")
		)
		(pad "37" smd rect
			(at -2.050034 -32.725106 90)
			(size 0.519938 1.4986)
			(layers "F.Cu" "F.Mask" "F.Paste")
			(net "GND")
		)
		(pad "38" smd rect
			(at -2.050034 -31.874968 90)
			(size 0.519938 1.4986)
			(layers "F.Cu" "F.Mask" "F.Paste")
			(net "M_A_CPU1_SA_DQ<21>")
		)
		(pad "39" smd rect
			(at -2.050034 -31.025084 90)
			(size 0.519938 1.4986)
			(layers "F.Cu" "F.Mask" "F.Paste")
			(net "GND")
		)
		(pad "40" smd rect
			(at -2.050034 -30.174946 90)
			(size 0.519938 1.4986)
			(layers "F.Cu" "F.Mask" "F.Paste")
			(net "M_A_CPU1_SA_DQ<24>")
		)
		(pad "41" smd rect
			(at -2.050034 -29.325062 90)
			(size 0.519938 1.4986)
			(layers "F.Cu" "F.Mask" "F.Paste")
			(net "GND")
		)
		(pad "42" smd rect
			(at -2.050034 -28.474924 90)
			(size 0.519938 1.4986)
			(layers "F.Cu" "F.Mask" "F.Paste")
			(net "M_A_CPU1_SA_DQ<25>")
		)
		(pad "43" smd rect
			(at -2.050034 -27.62504 90)
			(size 0.519938 1.4986)
			(layers "F.Cu" "F.Mask" "F.Paste")
			(net "GND")
		)
		(pad "44" smd rect
			(at -2.050034 -26.774902 90)
			(size 0.519938 1.4986)
			(layers "F.Cu" "F.Mask" "F.Paste")
			(net "M_A_CPU1_SA_DQS_DP<3>")
		)
		(pad "45" smd rect
			(at -2.050034 -25.925018 90)
			(size 0.519938 1.4986)
			(layers "F.Cu" "F.Mask" "F.Paste")
			(net "M_A_CPU1_SA_DQS_DN<3>")
		)
		(pad "46" smd rect
			(at -2.050034 -25.07488 90)
			(size 0.519938 1.4986)
			(layers "F.Cu" "F.Mask" "F.Paste")
			(net "GND")
		)
		(pad "47" smd rect
			(at -2.050034 -24.224996 90)
			(size 0.519938 1.4986)
			(layers "F.Cu" "F.Mask" "F.Paste")
			(net "M_A_CPU1_SA_DQ<28>")
		)
		(pad "48" smd rect
			(at -2.050034 -23.375112 90)
			(size 0.519938 1.4986)
			(layers "F.Cu" "F.Mask" "F.Paste")
			(net "GND")
		)
		(pad "49" smd rect
			(at -2.050034 -22.524974 90)
			(size 0.519938 1.4986)
			(layers "F.Cu" "F.Mask" "F.Paste")
			(net "M_A_CPU1_SA_DQ<29>")
		)
		(pad "50" smd rect
			(at -2.050034 -21.67509 90)
			(size 0.519938 1.4986)
			(layers "F.Cu" "F.Mask" "F.Paste")
			(net "GND")
		)
		(pad "51" smd rect
			(at -2.050034 -20.824952 90)
			(size 0.519938 1.4986)
			(layers "F.Cu" "F.Mask" "F.Paste")
			(net "M_A_CPU1_SA_CB<0>")
		)
		(pad "52" smd rect
			(at -2.050034 -19.975068 90)
			(size 0.519938 1.4986)
			(layers "F.Cu" "F.Mask" "F.Paste")
			(net "GND")
		)
		(pad "53" smd rect
			(at -2.050034 -19.12493 90)
			(size 0.519938 1.4986)
			(layers "F.Cu" "F.Mask" "F.Paste")
			(net "M_A_CPU1_SA_CB<1>")
		)
		(pad "54" smd rect
			(at -2.050034 -18.275046 90)
			(size 0.519938 1.4986)
			(layers "F.Cu" "F.Mask" "F.Paste")
			(net "GND")
		)
		(pad "55" smd rect
			(at -2.050034 -17.424908 90)
			(size 0.519938 1.4986)
			(layers "F.Cu" "F.Mask" "F.Paste")
			(net "M_A_CPU1_SA_DQS_DP<4>")
		)
		(pad "56" smd rect
			(at -2.050034 -16.575024 90)
			(size 0.519938 1.4986)
			(layers "F.Cu" "F.Mask" "F.Paste")
			(net "M_A_CPU1_SA_DQS_DN<4>")
		)
		(pad "57" smd rect
			(at -2.050034 -15.724886 90)
			(size 0.519938 1.4986)
			(layers "F.Cu" "F.Mask" "F.Paste")
			(net "GND")
		)
		(pad "58" smd rect
			(at -2.050034 -14.875002 90)
			(size 0.519938 1.4986)
			(layers "F.Cu" "F.Mask" "F.Paste")
			(net "M_A_CPU1_SA_CB<4>")
		)
		(pad "59" smd rect
			(at -2.050034 -14.025118 90)
			(size 0.519938 1.4986)
			(layers "F.Cu" "F.Mask" "F.Paste")
			(net "GND")
		)
		(pad "60" smd rect
			(at -2.050034 -13.17498 90)
			(size 0.519938 1.4986)
			(layers "F.Cu" "F.Mask" "F.Paste")
			(net "M_A_CPU1_SA_CB<5>")
		)
		(pad "61" smd rect
			(at -2.050034 -12.325096 90)
			(size 0.519938 1.4986)
			(layers "F.Cu" "F.Mask" "F.Paste")
			(net "GND")
		)
		(pad "62" smd rect
			(at -2.050034 -11.474958 90)
			(size 0.519938 1.4986)
			(layers "F.Cu" "F.Mask" "F.Paste")
			(net "M_A_CPU1_ALERT_N")
		)
		(pad "63" smd rect
			(at -2.050034 -10.625074 90)
			(size 0.519938 1.4986)
			(layers "F.Cu" "F.Mask" "F.Paste")
			(net "GND")
		)
		(pad "64" smd rect
			(at -2.050034 -9.774936 90)
			(size 0.519938 1.4986)
			(layers "F.Cu" "F.Mask" "F.Paste")
			(net "M_A_CPU1_SA_CS_N<0>")
		)
		(pad "65" smd rect
			(at -2.050034 -8.925052 90)
			(size 0.519938 1.4986)
			(layers "F.Cu" "F.Mask" "F.Paste")
			(net "GND")
		)
		(pad "66" smd rect
			(at -2.050034 -8.074914 90)
			(size 0.519938 1.4986)
			(layers "F.Cu" "F.Mask" "F.Paste")
			(net "M_A_CPU1_SA_CA<0>")
		)
		(pad "67" smd rect
			(at -2.050034 -7.22503 90)
			(size 0.519938 1.4986)
			(layers "F.Cu" "F.Mask" "F.Paste")
			(net "GND")
		)
		(pad "68" smd rect
			(at -2.050034 -6.374892 90)
			(size 0.519938 1.4986)
			(layers "F.Cu" "F.Mask" "F.Paste")
			(net "M_A_CPU1_SA_CA<2>")
		)
		(pad "69" smd rect
			(at -2.050034 -5.525008 90)
			(size 0.519938 1.4986)
			(layers "F.Cu" "F.Mask" "F.Paste")
			(net "GND")
		)
		(pad "70" smd rect
			(at -2.050034 -4.675124 90)
			(size 0.519938 1.4986)
			(layers "F.Cu" "F.Mask" "F.Paste")
			(net "M_A_CPU1_SA_CA<4>")
		)
		(pad "71" smd rect
			(at -2.050034 -3.824986 90)
			(size 0.519938 1.4986)
			(layers "F.Cu" "F.Mask" "F.Paste")
			(net "GND")
		)
		(pad "72" smd rect
			(at -2.050034 -2.975102 90)
			(size 0.519938 1.4986)
			(layers "F.Cu" "F.Mask" "F.Paste")
			(net "M_A_CPU1_SA_CA<6>")
		)
		(pad "73" smd rect
			(at -2.050034 -2.124964 90)
			(size 0.519938 1.4986)
			(layers "F.Cu" "F.Mask" "F.Paste")
			(net "GND")
		)
		(pad "74" smd rect
			(at -2.050034 -1.27508 90)
			(size 0.519938 1.4986)
			(layers "F.Cu" "F.Mask" "F.Paste")
			(net "M_A_CPU1_SA_PAR")
		)
		(pad "75" smd rect
			(at -2.050034 -0.424942 90)
			(size 0.519938 1.4986)
			(layers "F.Cu" "F.Mask" "F.Paste")
			(net "GND")
		)
		(pad "76" smd rect
			(at -2.050034 5.525008 90)
			(size 0.519938 1.4986)
			(layers "F.Cu" "F.Mask" "F.Paste")
			(net "M_A_CPU1_SB_CA<0>")
		)
		(pad "77" smd rect
			(at -2.050034 6.374892 90)
			(size 0.519938 1.4986)
			(layers "F.Cu" "F.Mask" "F.Paste")
			(net "GND")
		)
		(pad "78" smd rect
			(at -2.050034 7.22503 90)
			(size 0.519938 1.4986)
			(layers "F.Cu" "F.Mask" "F.Paste")
			(net "M_A_CPU1_SB_CA<2>")
		)
		(pad "79" smd rect
			(at -2.050034 8.074914 90)
			(size 0.519938 1.4986)
			(layers "F.Cu" "F.Mask" "F.Paste")
			(net "GND")
		)
		(pad "80" smd rect
			(at -2.050034 8.925052 90)
			(size 0.519938 1.4986)
			(layers "F.Cu" "F.Mask" "F.Paste")
			(net "M_A_CPU1_SB_CA<4>")
		)
		(pad "81" smd rect
			(at -2.050034 9.774936 90)
			(size 0.519938 1.4986)
			(layers "F.Cu" "F.Mask" "F.Paste")
			(net "GND")
		)
		(pad "82" smd rect
			(at -2.050034 10.625074 90)
			(size 0.519938 1.4986)
			(layers "F.Cu" "F.Mask" "F.Paste")
			(net "M_A_CPU1_SB_CA<6>")
		)
		(pad "83" smd rect
			(at -2.050034 11.474958 90)
			(size 0.519938 1.4986)
			(layers "F.Cu" "F.Mask" "F.Paste")
			(net "GND")
		)
		(pad "84" smd rect
			(at -2.050034 12.325096 90)
			(size 0.519938 1.4986)
			(layers "F.Cu" "F.Mask" "F.Paste")
			(net "M_A_CPU1_SB_CS_N<0>")
		)
		(pad "85" smd rect
			(at -2.050034 13.17498 90)
			(size 0.519938 1.4986)
			(layers "F.Cu" "F.Mask" "F.Paste")
			(net "GND")
		)
		(pad "86" smd rect
			(at -2.050034 14.025118 90)
			(size 0.519938 1.4986)
			(layers "F.Cu" "F.Mask" "F.Paste")
			(net "M_A_CPU1_SA_RSP<0>")
		)
		(pad "87" smd rect
			(at -2.050034 14.875002 90)
			(size 0.519938 1.4986)
			(layers "F.Cu" "F.Mask" "F.Paste")
			(net "M_A_CPU1_SB_RSP<0>")
		)
		(pad "88" smd rect
			(at -2.050034 15.724886 90)
			(size 0.519938 1.4986)
			(layers "F.Cu" "F.Mask" "F.Paste")
			(net "GND")
		)
		(pad "89" smd rect
			(at -2.050034 16.575024 90)
			(size 0.519938 1.4986)
			(layers "F.Cu" "F.Mask" "F.Paste")
			(net "M_A_CPU1_SB_CB<4>")
		)
		(pad "90" smd rect
			(at -2.050034 17.424908 90)
			(size 0.519938 1.4986)
			(layers "F.Cu" "F.Mask" "F.Paste")
			(net "GND")
		)
		(pad "91" smd rect
			(at -2.050034 18.275046 90)
			(size 0.519938 1.4986)
			(layers "F.Cu" "F.Mask" "F.Paste")
			(net "M_A_CPU1_SB_CB<5>")
		)
		(pad "92" smd rect
			(at -2.050034 19.12493 90)
			(size 0.519938 1.4986)
			(layers "F.Cu" "F.Mask" "F.Paste")
			(net "GND")
		)
		(pad "93" smd rect
			(at -2.050034 19.975068 90)
			(size 0.519938 1.4986)
			(layers "F.Cu" "F.Mask" "F.Paste")
			(net "M_A_CPU1_SB_DQS_DP<9>")
		)
		(pad "94" smd rect
			(at -2.050034 20.824952 90)
			(size 0.519938 1.4986)
			(layers "F.Cu" "F.Mask" "F.Paste")
			(net "M_A_CPU1_SB_DQS_DN<9>")
		)
		(pad "95" smd rect
			(at -2.050034 21.67509 90)
			(size 0.519938 1.4986)
			(layers "F.Cu" "F.Mask" "F.Paste")
			(net "GND")
		)
		(pad "96" smd rect
			(at -2.050034 22.524974 90)
			(size 0.519938 1.4986)
			(layers "F.Cu" "F.Mask" "F.Paste")
			(net "M_A_CPU1_SB_CB<0>")
		)
		(pad "97" smd rect
			(at -2.050034 23.375112 90)
			(size 0.519938 1.4986)
			(layers "F.Cu" "F.Mask" "F.Paste")
			(net "GND")
		)
		(pad "98" smd rect
			(at -2.050034 24.224996 90)
			(size 0.519938 1.4986)
			(layers "F.Cu" "F.Mask" "F.Paste")
			(net "M_A_CPU1_SB_CB<1>")
		)
		(pad "99" smd rect
			(at -2.050034 25.07488 90)
			(size 0.519938 1.4986)
			(layers "F.Cu" "F.Mask" "F.Paste")
			(net "GND")
		)
		(pad "100" smd rect
			(at -2.050034 25.925018 90)
			(size 0.519938 1.4986)
			(layers "F.Cu" "F.Mask" "F.Paste")
			(net "M_A_CPU1_SB_DQ<0>")
		)
		(pad "101" smd rect
			(at -2.050034 26.774902 90)
			(size 0.519938 1.4986)
			(layers "F.Cu" "F.Mask" "F.Paste")
			(net "GND")
		)
		(pad "102" smd rect
			(at -2.050034 27.62504 90)
			(size 0.519938 1.4986)
			(layers "F.Cu" "F.Mask" "F.Paste")
			(net "M_A_CPU1_SB_DQ<1>")
		)
		(pad "103" smd rect
			(at -2.050034 28.474924 90)
			(size 0.519938 1.4986)
			(layers "F.Cu" "F.Mask" "F.Paste")
			(net "GND")
		)
		(pad "104" smd rect
			(at -2.050034 29.325062 90)
			(size 0.519938 1.4986)
			(layers "F.Cu" "F.Mask" "F.Paste")
			(net "M_A_CPU1_SB_DQS_DP<0>")
		)
		(pad "105" smd rect
			(at -2.050034 30.174946 90)
			(size 0.519938 1.4986)
			(layers "F.Cu" "F.Mask" "F.Paste")
			(net "M_A_CPU1_SB_DQS_DN<0>")
		)
		(pad "106" smd rect
			(at -2.050034 31.025084 90)
			(size 0.519938 1.4986)
			(layers "F.Cu" "F.Mask" "F.Paste")
			(net "GND")
		)
		(pad "107" smd rect
			(at -2.050034 31.874968 90)
			(size 0.519938 1.4986)
			(layers "F.Cu" "F.Mask" "F.Paste")
			(net "M_A_CPU1_SB_DQ<4>")
		)
		(pad "108" smd rect
			(at -2.050034 32.725106 90)
			(size 0.519938 1.4986)
			(layers "F.Cu" "F.Mask" "F.Paste")
			(net "GND")
		)
		(pad "109" smd rect
			(at -2.050034 33.57499 90)
			(size 0.519938 1.4986)
			(layers "F.Cu" "F.Mask" "F.Paste")
			(net "M_A_CPU1_SB_DQ<5>")
		)
		(pad "110" smd rect
			(at -2.050034 34.425128 90)
			(size 0.519938 1.4986)
			(layers "F.Cu" "F.Mask" "F.Paste")
			(net "GND")
		)
		(pad "111" smd rect
			(at -2.050034 35.275012 90)
			(size 0.519938 1.4986)
			(layers "F.Cu" "F.Mask" "F.Paste")
			(net "M_A_CPU1_SB_DQ<8>")
		)
		(pad "112" smd rect
			(at -2.050034 36.124896 90)
			(size 0.519938 1.4986)
			(layers "F.Cu" "F.Mask" "F.Paste")
			(net "GND")
		)
		(pad "113" smd rect
			(at -2.050034 36.975034 90)
			(size 0.519938 1.4986)
			(layers "F.Cu" "F.Mask" "F.Paste")
			(net "M_A_CPU1_SB_DQ<9>")
		)
		(pad "114" smd rect
			(at -2.050034 37.824918 90)
			(size 0.519938 1.4986)
			(layers "F.Cu" "F.Mask" "F.Paste")
			(net "GND")
		)
		(pad "115" smd rect
			(at -2.050034 38.675056 90)
			(size 0.519938 1.4986)
			(layers "F.Cu" "F.Mask" "F.Paste")
			(net "M_A_CPU1_SB_DQS_DP<1>")
		)
		(pad "116" smd rect
			(at -2.050034 39.52494 90)
			(size 0.519938 1.4986)
			(layers "F.Cu" "F.Mask" "F.Paste")
			(net "M_A_CPU1_SB_DQS_DN<1>")
		)
		(pad "117" smd rect
			(at -2.050034 40.375078 90)
			(size 0.519938 1.4986)
			(layers "F.Cu" "F.Mask" "F.Paste")
			(net "GND")
		)
		(pad "118" smd rect
			(at -2.050034 41.224962 90)
			(size 0.519938 1.4986)
			(layers "F.Cu" "F.Mask" "F.Paste")
			(net "M_A_CPU1_SB_DQ<12>")
		)
		(pad "119" smd rect
			(at -2.050034 42.0751 90)
			(size 0.519938 1.4986)
			(layers "F.Cu" "F.Mask" "F.Paste")
			(net "GND")
		)
		(pad "120" smd rect
			(at -2.050034 42.924984 90)
			(size 0.519938 1.4986)
			(layers "F.Cu" "F.Mask" "F.Paste")
			(net "M_A_CPU1_SB_DQ<13>")
		)
		(pad "121" smd rect
			(at -2.050034 43.775122 90)
			(size 0.519938 1.4986)
			(layers "F.Cu" "F.Mask" "F.Paste")
			(net "GND")
		)
		(pad "122" smd rect
			(at -2.050034 44.625006 90)
			(size 0.519938 1.4986)
			(layers "F.Cu" "F.Mask" "F.Paste")
			(net "M_A_CPU1_SB_DQ<16>")
		)
		(pad "123" smd rect
			(at -2.050034 45.47489 90)
			(size 0.519938 1.4986)
			(layers "F.Cu" "F.Mask" "F.Paste")
			(net "GND")
		)
		(pad "124" smd rect
			(at -2.050034 46.325028 90)
			(size 0.519938 1.4986)
			(layers "F.Cu" "F.Mask" "F.Paste")
			(net "M_A_CPU1_SB_DQ<17>")
		)
		(pad "125" smd rect
			(at -2.050034 47.174912 90)
			(size 0.519938 1.4986)
			(layers "F.Cu" "F.Mask" "F.Paste")
			(net "GND")
		)
		(pad "126" smd rect
			(at -2.050034 48.02505 90)
			(size 0.519938 1.4986)
			(layers "F.Cu" "F.Mask" "F.Paste")
			(net "M_A_CPU1_SB_DQS_DP<2>")
		)
		(pad "127" smd rect
			(at -2.050034 48.874934 90)
			(size 0.519938 1.4986)
			(layers "F.Cu" "F.Mask" "F.Paste")
			(net "M_A_CPU1_SB_DQS_DN<2>")
		)
		(pad "128" smd rect
			(at -2.050034 49.725072 90)
			(size 0.519938 1.4986)
			(layers "F.Cu" "F.Mask" "F.Paste")
			(net "GND")
		)
		(pad "129" smd rect
			(at -2.050034 50.574956 90)
			(size 0.519938 1.4986)
			(layers "F.Cu" "F.Mask" "F.Paste")
			(net "M_A_CPU1_SB_DQ<20>")
		)
		(pad "130" smd rect
			(at -2.050034 51.425094 90)
			(size 0.519938 1.4986)
			(layers "F.Cu" "F.Mask" "F.Paste")
			(net "GND")
		)
		(pad "131" smd rect
			(at -2.050034 52.274978 90)
			(size 0.519938 1.4986)
			(layers "F.Cu" "F.Mask" "F.Paste")
			(net "M_A_CPU1_SB_DQ<21>")
		)
		(pad "132" smd rect
			(at -2.050034 53.125116 90)
			(size 0.519938 1.4986)
			(layers "F.Cu" "F.Mask" "F.Paste")
			(net "GND")
		)
		(pad "133" smd rect
			(at -2.050034 53.975 90)
			(size 0.519938 1.4986)
			(layers "F.Cu" "F.Mask" "F.Paste")
			(net "M_A_CPU1_SB_DQ<24>")
		)
		(pad "134" smd rect
			(at -2.050034 54.824884 90)
			(size 0.519938 1.4986)
			(layers "F.Cu" "F.Mask" "F.Paste")
			(net "GND")
		)
		(pad "135" smd rect
			(at -2.050034 55.675022 90)
			(size 0.519938 1.4986)
			(layers "F.Cu" "F.Mask" "F.Paste")
			(net "M_A_CPU1_SB_DQ<25>")
		)
		(pad "136" smd rect
			(at -2.050034 56.524906 90)
			(size 0.519938 1.4986)
			(layers "F.Cu" "F.Mask" "F.Paste")
			(net "GND")
		)
		(pad "137" smd rect
			(at -2.050034 57.375044 90)
			(size 0.519938 1.4986)
			(layers "F.Cu" "F.Mask" "F.Paste")
			(net "M_A_CPU1_SB_DQS_DP<3>")
		)
		(pad "138" smd rect
			(at -2.050034 58.224928 90)
			(size 0.519938 1.4986)
			(layers "F.Cu" "F.Mask" "F.Paste")
			(net "M_A_CPU1_SB_DQS_DN<3>")
		)
		(pad "139" smd rect
			(at -2.050034 59.075066 90)
			(size 0.519938 1.4986)
			(layers "F.Cu" "F.Mask" "F.Paste")
			(net "GND")
		)
		(pad "140" smd rect
			(at -2.050034 59.92495 90)
			(size 0.519938 1.4986)
			(layers "F.Cu" "F.Mask" "F.Paste")
			(net "M_A_CPU1_SB_DQ<28>")
		)
		(pad "141" smd rect
			(at -2.050034 60.775088 90)
			(size 0.519938 1.4986)
			(layers "F.Cu" "F.Mask" "F.Paste")
			(net "GND")
		)
		(pad "142" smd rect
			(at -2.050034 61.624972 90)
			(size 0.519938 1.4986)
			(layers "F.Cu" "F.Mask" "F.Paste")
			(net "M_A_CPU1_SB_DQ<29>")
		)
		(pad "143" smd rect
			(at -2.050034 62.47511 90)
			(size 0.519938 1.4986)
			(layers "F.Cu" "F.Mask" "F.Paste")
			(net "GND")
		)
		(pad "144" smd rect
			(at -2.050034 63.324994 90)
			(size 0.519938 1.4986)
			(layers "F.Cu" "F.Mask" "F.Paste")
			(net "Net_2257")
		)
		(pad "145" smd rect
			(at 2.050034 -63.324994 90)
			(size 0.519938 1.4986)
			(layers "F.Cu" "F.Mask" "F.Paste")
			(net "P12V_MEM_CPU1")
		)
		(pad "146" smd rect
			(at 2.050034 -62.47511 90)
			(size 0.519938 1.4986)
			(layers "F.Cu" "F.Mask" "F.Paste")
			(net "P12V_MEM_CPU1")
		)
		(pad "147" smd rect
			(at 2.050034 -61.624972 90)
			(size 0.519938 1.4986)
			(layers "F.Cu" "F.Mask" "F.Paste")
			(net "PWRGD_CHA_CPU1_DIMM0")
		)
		(pad "148" smd rect
			(at 2.050034 -60.775088 90)
			(size 0.519938 1.4986)
			(layers "F.Cu" "F.Mask" "F.Paste")
			(net "PD_CHA_CPU1_DIMM0_SAA")
		)
		(pad "149" smd rect
			(at 2.050034 -59.92495 90)
			(size 0.519938 1.4986)
			(layers "F.Cu" "F.Mask" "F.Paste")
			(net "Net_2258")
		)
		(pad "150" smd rect
			(at 2.050034 -59.075066 90)
			(size 0.519938 1.4986)
			(layers "F.Cu" "F.Mask" "F.Paste")
			(net "Net_2259")
		)
		(pad "151" smd rect
			(at 2.050034 -58.224928 90)
			(size 0.519938 1.4986)
			(layers "F.Cu" "F.Mask" "F.Paste")
			(net "GND")
		)
		(pad "152" smd rect
			(at 2.050034 -57.375044 90)
			(size 0.519938 1.4986)
			(layers "F.Cu" "F.Mask" "F.Paste")
			(net "M_A_CPU1_SA_DQ<2>")
		)
		(pad "153" smd rect
			(at 2.050034 -56.524906 90)
			(size 0.519938 1.4986)
			(layers "F.Cu" "F.Mask" "F.Paste")
			(net "GND")
		)
		(pad "154" smd rect
			(at 2.050034 -55.675022 90)
			(size 0.519938 1.4986)
			(layers "F.Cu" "F.Mask" "F.Paste")
			(net "M_A_CPU1_SA_DQ<3>")
		)
		(pad "155" smd rect
			(at 2.050034 -54.824884 90)
			(size 0.519938 1.4986)
			(layers "F.Cu" "F.Mask" "F.Paste")
			(net "GND")
		)
		(pad "156" smd rect
			(at 2.050034 -53.975 90)
			(size 0.519938 1.4986)
			(layers "F.Cu" "F.Mask" "F.Paste")
			(net "M_A_CPU1_SA_DQS_DN<5>")
		)
		(pad "157" smd rect
			(at 2.050034 -53.125116 90)
			(size 0.519938 1.4986)
			(layers "F.Cu" "F.Mask" "F.Paste")
			(net "M_A_CPU1_SA_DQS_DP<5>")
		)
		(pad "158" smd rect
			(at 2.050034 -52.274978 90)
			(size 0.519938 1.4986)
			(layers "F.Cu" "F.Mask" "F.Paste")
			(net "GND")
		)
		(pad "159" smd rect
			(at 2.050034 -51.425094 90)
			(size 0.519938 1.4986)
			(layers "F.Cu" "F.Mask" "F.Paste")
			(net "M_A_CPU1_SA_DQ<6>")
		)
		(pad "160" smd rect
			(at 2.050034 -50.574956 90)
			(size 0.519938 1.4986)
			(layers "F.Cu" "F.Mask" "F.Paste")
			(net "GND")
		)
		(pad "161" smd rect
			(at 2.050034 -49.725072 90)
			(size 0.519938 1.4986)
			(layers "F.Cu" "F.Mask" "F.Paste")
			(net "M_A_CPU1_SA_DQ<7>")
		)
		(pad "162" smd rect
			(at 2.050034 -48.874934 90)
			(size 0.519938 1.4986)
			(layers "F.Cu" "F.Mask" "F.Paste")
			(net "GND")
		)
		(pad "163" smd rect
			(at 2.050034 -48.02505 90)
			(size 0.519938 1.4986)
			(layers "F.Cu" "F.Mask" "F.Paste")
			(net "M_A_CPU1_SA_DQ<10>")
		)
		(pad "164" smd rect
			(at 2.050034 -47.174912 90)
			(size 0.519938 1.4986)
			(layers "F.Cu" "F.Mask" "F.Paste")
			(net "GND")
		)
		(pad "165" smd rect
			(at 2.050034 -46.325028 90)
			(size 0.519938 1.4986)
			(layers "F.Cu" "F.Mask" "F.Paste")
			(net "M_A_CPU1_SA_DQ<11>")
		)
		(pad "166" smd rect
			(at 2.050034 -45.47489 90)
			(size 0.519938 1.4986)
			(layers "F.Cu" "F.Mask" "F.Paste")
			(net "GND")
		)
		(pad "167" smd rect
			(at 2.050034 -44.625006 90)
			(size 0.519938 1.4986)
			(layers "F.Cu" "F.Mask" "F.Paste")
			(net "M_A_CPU1_SA_DQS_DN<6>")
		)
		(pad "168" smd rect
			(at 2.050034 -43.775122 90)
			(size 0.519938 1.4986)
			(layers "F.Cu" "F.Mask" "F.Paste")
			(net "M_A_CPU1_SA_DQS_DP<6>")
		)
		(pad "169" smd rect
			(at 2.050034 -42.924984 90)
			(size 0.519938 1.4986)
			(layers "F.Cu" "F.Mask" "F.Paste")
			(net "GND")
		)
		(pad "170" smd rect
			(at 2.050034 -42.0751 90)
			(size 0.519938 1.4986)
			(layers "F.Cu" "F.Mask" "F.Paste")
			(net "M_A_CPU1_SA_DQ<14>")
		)
		(pad "171" smd rect
			(at 2.050034 -41.224962 90)
			(size 0.519938 1.4986)
			(layers "F.Cu" "F.Mask" "F.Paste")
			(net "GND")
		)
		(pad "172" smd rect
			(at 2.050034 -40.375078 90)
			(size 0.519938 1.4986)
			(layers "F.Cu" "F.Mask" "F.Paste")
			(net "M_A_CPU1_SA_DQ<15>")
		)
		(pad "173" smd rect
			(at 2.050034 -39.52494 90)
			(size 0.519938 1.4986)
			(layers "F.Cu" "F.Mask" "F.Paste")
			(net "GND")
		)
		(pad "174" smd rect
			(at 2.050034 -38.675056 90)
			(size 0.519938 1.4986)
			(layers "F.Cu" "F.Mask" "F.Paste")
			(net "M_A_CPU1_SA_DQ<18>")
		)
		(pad "175" smd rect
			(at 2.050034 -37.824918 90)
			(size 0.519938 1.4986)
			(layers "F.Cu" "F.Mask" "F.Paste")
			(net "GND")
		)
		(pad "176" smd rect
			(at 2.050034 -36.975034 90)
			(size 0.519938 1.4986)
			(layers "F.Cu" "F.Mask" "F.Paste")
			(net "M_A_CPU1_SA_DQ<19>")
		)
		(pad "177" smd rect
			(at 2.050034 -36.124896 90)
			(size 0.519938 1.4986)
			(layers "F.Cu" "F.Mask" "F.Paste")
			(net "GND")
		)
		(pad "178" smd rect
			(at 2.050034 -35.275012 90)
			(size 0.519938 1.4986)
			(layers "F.Cu" "F.Mask" "F.Paste")
			(net "M_A_CPU1_SA_DQS_DN<7>")
		)
		(pad "179" smd rect
			(at 2.050034 -34.425128 90)
			(size 0.519938 1.4986)
			(layers "F.Cu" "F.Mask" "F.Paste")
			(net "M_A_CPU1_SA_DQS_DP<7>")
		)
		(pad "180" smd rect
			(at 2.050034 -33.57499 90)
			(size 0.519938 1.4986)
			(layers "F.Cu" "F.Mask" "F.Paste")
			(net "GND")
		)
		(pad "181" smd rect
			(at 2.050034 -32.725106 90)
			(size 0.519938 1.4986)
			(layers "F.Cu" "F.Mask" "F.Paste")
			(net "M_A_CPU1_SA_DQ<22>")
		)
		(pad "182" smd rect
			(at 2.050034 -31.874968 90)
			(size 0.519938 1.4986)
			(layers "F.Cu" "F.Mask" "F.Paste")
			(net "GND")
		)
		(pad "183" smd rect
			(at 2.050034 -31.025084 90)
			(size 0.519938 1.4986)
			(layers "F.Cu" "F.Mask" "F.Paste")
			(net "M_A_CPU1_SA_DQ<23>")
		)
		(pad "184" smd rect
			(at 2.050034 -30.174946 90)
			(size 0.519938 1.4986)
			(layers "F.Cu" "F.Mask" "F.Paste")
			(net "GND")
		)
		(pad "185" smd rect
			(at 2.050034 -29.325062 90)
			(size 0.519938 1.4986)
			(layers "F.Cu" "F.Mask" "F.Paste")
			(net "M_A_CPU1_SA_DQ<26>")
		)
		(pad "186" smd rect
			(at 2.050034 -28.474924 90)
			(size 0.519938 1.4986)
			(layers "F.Cu" "F.Mask" "F.Paste")
			(net "GND")
		)
		(pad "187" smd rect
			(at 2.050034 -27.62504 90)
			(size 0.519938 1.4986)
			(layers "F.Cu" "F.Mask" "F.Paste")
			(net "M_A_CPU1_SA_DQ<27>")
		)
		(pad "188" smd rect
			(at 2.050034 -26.774902 90)
			(size 0.519938 1.4986)
			(layers "F.Cu" "F.Mask" "F.Paste")
			(net "GND")
		)
		(pad "189" smd rect
			(at 2.050034 -25.925018 90)
			(size 0.519938 1.4986)
			(layers "F.Cu" "F.Mask" "F.Paste")
			(net "M_A_CPU1_SA_DQS_DN<8>")
		)
		(pad "190" smd rect
			(at 2.050034 -25.07488 90)
			(size 0.519938 1.4986)
			(layers "F.Cu" "F.Mask" "F.Paste")
			(net "M_A_CPU1_SA_DQS_DP<8>")
		)
		(pad "191" smd rect
			(at 2.050034 -24.224996 90)
			(size 0.519938 1.4986)
			(layers "F.Cu" "F.Mask" "F.Paste")
			(net "GND")
		)
		(pad "192" smd rect
			(at 2.050034 -23.375112 90)
			(size 0.519938 1.4986)
			(layers "F.Cu" "F.Mask" "F.Paste")
			(net "M_A_CPU1_SA_DQ<30>")
		)
		(pad "193" smd rect
			(at 2.050034 -22.524974 90)
			(size 0.519938 1.4986)
			(layers "F.Cu" "F.Mask" "F.Paste")
			(net "GND")
		)
		(pad "194" smd rect
			(at 2.050034 -21.67509 90)
			(size 0.519938 1.4986)
			(layers "F.Cu" "F.Mask" "F.Paste")
			(net "M_A_CPU1_SA_DQ<31>")
		)
		(pad "195" smd rect
			(at 2.050034 -20.824952 90)
			(size 0.519938 1.4986)
			(layers "F.Cu" "F.Mask" "F.Paste")
			(net "GND")
		)
		(pad "196" smd rect
			(at 2.050034 -19.975068 90)
			(size 0.519938 1.4986)
			(layers "F.Cu" "F.Mask" "F.Paste")
			(net "M_A_CPU1_SA_CB<2>")
		)
		(pad "197" smd rect
			(at 2.050034 -19.12493 90)
			(size 0.519938 1.4986)
			(layers "F.Cu" "F.Mask" "F.Paste")
			(net "GND")
		)
		(pad "198" smd rect
			(at 2.050034 -18.275046 90)
			(size 0.519938 1.4986)
			(layers "F.Cu" "F.Mask" "F.Paste")
			(net "M_A_CPU1_SA_CB<3>")
		)
		(pad "199" smd rect
			(at 2.050034 -17.424908 90)
			(size 0.519938 1.4986)
			(layers "F.Cu" "F.Mask" "F.Paste")
			(net "GND")
		)
		(pad "200" smd rect
			(at 2.050034 -16.575024 90)
			(size 0.519938 1.4986)
			(layers "F.Cu" "F.Mask" "F.Paste")
			(net "M_A_CPU1_SA_DQS_DN<9>")
		)
		(pad "201" smd rect
			(at 2.050034 -15.724886 90)
			(size 0.519938 1.4986)
			(layers "F.Cu" "F.Mask" "F.Paste")
			(net "M_A_CPU1_SA_DQS_DP<9>")
		)
		(pad "202" smd rect
			(at 2.050034 -14.875002 90)
			(size 0.519938 1.4986)
			(layers "F.Cu" "F.Mask" "F.Paste")
			(net "GND")
		)
		(pad "203" smd rect
			(at 2.050034 -14.025118 90)
			(size 0.519938 1.4986)
			(layers "F.Cu" "F.Mask" "F.Paste")
			(net "M_A_CPU1_SA_CB<6>")
		)
		(pad "204" smd rect
			(at 2.050034 -13.17498 90)
			(size 0.519938 1.4986)
			(layers "F.Cu" "F.Mask" "F.Paste")
			(net "GND")
		)
		(pad "205" smd rect
			(at 2.050034 -12.325096 90)
			(size 0.519938 1.4986)
			(layers "F.Cu" "F.Mask" "F.Paste")
			(net "M_A_CPU1_SA_CB<7>")
		)
		(pad "206" smd rect
			(at 2.050034 -11.474958 90)
			(size 0.519938 1.4986)
			(layers "F.Cu" "F.Mask" "F.Paste")
			(net "GND")
		)
		(pad "207" smd rect
			(at 2.050034 -10.625074 90)
			(size 0.519938 1.4986)
			(layers "F.Cu" "F.Mask" "F.Paste")
			(net "M_A_CPU1_RESET_N")
		)
		(pad "208" smd rect
			(at 2.050034 -9.774936 90)
			(size 0.519938 1.4986)
			(layers "F.Cu" "F.Mask" "F.Paste")
			(net "GND")
		)
		(pad "209" smd rect
			(at 2.050034 -8.925052 90)
			(size 0.519938 1.4986)
			(layers "F.Cu" "F.Mask" "F.Paste")
			(net "M_A_CPU1_SA_CS_N<1>")
		)
		(pad "210" smd rect
			(at 2.050034 -8.074914 90)
			(size 0.519938 1.4986)
			(layers "F.Cu" "F.Mask" "F.Paste")
			(net "GND")
		)
		(pad "211" smd rect
			(at 2.050034 -7.22503 90)
			(size 0.519938 1.4986)
			(layers "F.Cu" "F.Mask" "F.Paste")
			(net "M_A_CPU1_SA_CA<1>")
		)
		(pad "212" smd rect
			(at 2.050034 -6.374892 90)
			(size 0.519938 1.4986)
			(layers "F.Cu" "F.Mask" "F.Paste")
			(net "GND")
		)
		(pad "213" smd rect
			(at 2.050034 -5.525008 90)
			(size 0.519938 1.4986)
			(layers "F.Cu" "F.Mask" "F.Paste")
			(net "M_A_CPU1_SA_CA<3>")
		)
		(pad "214" smd rect
			(at 2.050034 -4.675124 90)
			(size 0.519938 1.4986)
			(layers "F.Cu" "F.Mask" "F.Paste")
			(net "GND")
		)
		(pad "215" smd rect
			(at 2.050034 -3.824986 90)
			(size 0.519938 1.4986)
			(layers "F.Cu" "F.Mask" "F.Paste")
			(net "M_A_CPU1_SA_CA<5>")
		)
		(pad "216" smd rect
			(at 2.050034 -2.975102 90)
			(size 0.519938 1.4986)
			(layers "F.Cu" "F.Mask" "F.Paste")
			(net "GND")
		)
		(pad "217" smd rect
			(at 2.050034 -2.124964 90)
			(size 0.519938 1.4986)
			(layers "F.Cu" "F.Mask" "F.Paste")
			(net "M_A_CPU1_CLK_DP<0>")
		)
		(pad "218" smd rect
			(at 2.050034 -1.27508 90)
			(size 0.519938 1.4986)
			(layers "F.Cu" "F.Mask" "F.Paste")
			(net "M_A_CPU1_CLK_DN<0>")
		)
		(pad "219" smd rect
			(at 2.050034 -0.424942 90)
			(size 0.519938 1.4986)
			(layers "F.Cu" "F.Mask" "F.Paste")
			(net "GND")
		)
		(pad "220" smd rect
			(at 2.050034 5.525008 90)
			(size 0.519938 1.4986)
			(layers "F.Cu" "F.Mask" "F.Paste")
			(net "Net_2260")
		)
		(pad "221" smd rect
			(at 2.050034 6.374892 90)
			(size 0.519938 1.4986)
			(layers "F.Cu" "F.Mask" "F.Paste")
			(net "M_A_CPU1_SB_CA<1>")
		)
		(pad "222" smd rect
			(at 2.050034 7.22503 90)
			(size 0.519938 1.4986)
			(layers "F.Cu" "F.Mask" "F.Paste")
			(net "GND")
		)
		(pad "223" smd rect
			(at 2.050034 8.074914 90)
			(size 0.519938 1.4986)
			(layers "F.Cu" "F.Mask" "F.Paste")
			(net "M_A_CPU1_SB_CA<3>")
		)
		(pad "224" smd rect
			(at 2.050034 8.925052 90)
			(size 0.519938 1.4986)
			(layers "F.Cu" "F.Mask" "F.Paste")
			(net "GND")
		)
		(pad "225" smd rect
			(at 2.050034 9.774936 90)
			(size 0.519938 1.4986)
			(layers "F.Cu" "F.Mask" "F.Paste")
			(net "M_A_CPU1_SB_CA<5>")
		)
		(pad "226" smd rect
			(at 2.050034 10.625074 90)
			(size 0.519938 1.4986)
			(layers "F.Cu" "F.Mask" "F.Paste")
			(net "GND")
		)
		(pad "227" smd rect
			(at 2.050034 11.474958 90)
			(size 0.519938 1.4986)
			(layers "F.Cu" "F.Mask" "F.Paste")
			(net "M_A_CPU1_SB_PAR")
		)
		(pad "228" smd rect
			(at 2.050034 12.325096 90)
			(size 0.519938 1.4986)
			(layers "F.Cu" "F.Mask" "F.Paste")
			(net "GND")
		)
		(pad "229" smd rect
			(at 2.050034 13.17498 90)
			(size 0.519938 1.4986)
			(layers "F.Cu" "F.Mask" "F.Paste")
			(net "M_A_CPU1_SB_CS_N<1>")
		)
		(pad "230" smd rect
			(at 2.050034 14.025118 90)
			(size 0.519938 1.4986)
			(layers "F.Cu" "F.Mask" "F.Paste")
			(net "GND")
		)
		(pad "231" smd rect
			(at 2.050034 14.875002 90)
			(size 0.519938 1.4986)
			(layers "F.Cu" "F.Mask" "F.Paste")
			(net "Net_2261")
		)
		(pad "232" smd rect
			(at 2.050034 15.724886 90)
			(size 0.519938 1.4986)
			(layers "F.Cu" "F.Mask" "F.Paste")
			(net "Net_2262")
		)
		(pad "233" smd rect
			(at 2.050034 16.575024 90)
			(size 0.519938 1.4986)
			(layers "F.Cu" "F.Mask" "F.Paste")
			(net "GND")
		)
		(pad "234" smd rect
			(at 2.050034 17.424908 90)
			(size 0.519938 1.4986)
			(layers "F.Cu" "F.Mask" "F.Paste")
			(net "M_A_CPU1_SB_CB<6>")
		)
		(pad "235" smd rect
			(at 2.050034 18.275046 90)
			(size 0.519938 1.4986)
			(layers "F.Cu" "F.Mask" "F.Paste")
			(net "GND")
		)
		(pad "236" smd rect
			(at 2.050034 19.12493 90)
			(size 0.519938 1.4986)
			(layers "F.Cu" "F.Mask" "F.Paste")
			(net "M_A_CPU1_SB_CB<7>")
		)
		(pad "237" smd rect
			(at 2.050034 19.975068 90)
			(size 0.519938 1.4986)
			(layers "F.Cu" "F.Mask" "F.Paste")
			(net "GND")
		)
		(pad "238" smd rect
			(at 2.050034 20.824952 90)
			(size 0.519938 1.4986)
			(layers "F.Cu" "F.Mask" "F.Paste")
			(net "M_A_CPU1_SB_DQS_DN<4>")
		)
		(pad "239" smd rect
			(at 2.050034 21.67509 90)
			(size 0.519938 1.4986)
			(layers "F.Cu" "F.Mask" "F.Paste")
			(net "M_A_CPU1_SB_DQS_DP<4>")
		)
		(pad "240" smd rect
			(at 2.050034 22.524974 90)
			(size 0.519938 1.4986)
			(layers "F.Cu" "F.Mask" "F.Paste")
			(net "GND")
		)
		(pad "241" smd rect
			(at 2.050034 23.375112 90)
			(size 0.519938 1.4986)
			(layers "F.Cu" "F.Mask" "F.Paste")
			(net "M_A_CPU1_SB_CB<2>")
		)
		(pad "242" smd rect
			(at 2.050034 24.224996 90)
			(size 0.519938 1.4986)
			(layers "F.Cu" "F.Mask" "F.Paste")
			(net "GND")
		)
		(pad "243" smd rect
			(at 2.050034 25.07488 90)
			(size 0.519938 1.4986)
			(layers "F.Cu" "F.Mask" "F.Paste")
			(net "M_A_CPU1_SB_CB<3>")
		)
		(pad "244" smd rect
			(at 2.050034 25.925018 90)
			(size 0.519938 1.4986)
			(layers "F.Cu" "F.Mask" "F.Paste")
			(net "GND")
		)
		(pad "245" smd rect
			(at 2.050034 26.774902 90)
			(size 0.519938 1.4986)
			(layers "F.Cu" "F.Mask" "F.Paste")
			(net "M_A_CPU1_SB_DQ<2>")
		)
		(pad "246" smd rect
			(at 2.050034 27.62504 90)
			(size 0.519938 1.4986)
			(layers "F.Cu" "F.Mask" "F.Paste")
			(net "GND")
		)
		(pad "247" smd rect
			(at 2.050034 28.474924 90)
			(size 0.519938 1.4986)
			(layers "F.Cu" "F.Mask" "F.Paste")
			(net "M_A_CPU1_SB_DQ<3>")
		)
		(pad "248" smd rect
			(at 2.050034 29.325062 90)
			(size 0.519938 1.4986)
			(layers "F.Cu" "F.Mask" "F.Paste")
			(net "GND")
		)
		(pad "249" smd rect
			(at 2.050034 30.174946 90)
			(size 0.519938 1.4986)
			(layers "F.Cu" "F.Mask" "F.Paste")
			(net "M_A_CPU1_SB_DQS_DN<5>")
		)
		(pad "250" smd rect
			(at 2.050034 31.025084 90)
			(size 0.519938 1.4986)
			(layers "F.Cu" "F.Mask" "F.Paste")
			(net "M_A_CPU1_SB_DQS_DP<5>")
		)
		(pad "251" smd rect
			(at 2.050034 31.874968 90)
			(size 0.519938 1.4986)
			(layers "F.Cu" "F.Mask" "F.Paste")
			(net "GND")
		)
		(pad "252" smd rect
			(at 2.050034 32.725106 90)
			(size 0.519938 1.4986)
			(layers "F.Cu" "F.Mask" "F.Paste")
			(net "M_A_CPU1_SB_DQ<6>")
		)
		(pad "253" smd rect
			(at 2.050034 33.57499 90)
			(size 0.519938 1.4986)
			(layers "F.Cu" "F.Mask" "F.Paste")
			(net "GND")
		)
		(pad "254" smd rect
			(at 2.050034 34.425128 90)
			(size 0.519938 1.4986)
			(layers "F.Cu" "F.Mask" "F.Paste")
			(net "M_A_CPU1_SB_DQ<7>")
		)
		(pad "255" smd rect
			(at 2.050034 35.275012 90)
			(size 0.519938 1.4986)
			(layers "F.Cu" "F.Mask" "F.Paste")
			(net "GND")
		)
		(pad "256" smd rect
			(at 2.050034 36.124896 90)
			(size 0.519938 1.4986)
			(layers "F.Cu" "F.Mask" "F.Paste")
			(net "M_A_CPU1_SB_DQ<10>")
		)
		(pad "257" smd rect
			(at 2.050034 36.975034 90)
			(size 0.519938 1.4986)
			(layers "F.Cu" "F.Mask" "F.Paste")
			(net "GND")
		)
		(pad "258" smd rect
			(at 2.050034 37.824918 90)
			(size 0.519938 1.4986)
			(layers "F.Cu" "F.Mask" "F.Paste")
			(net "M_A_CPU1_SB_DQ<11>")
		)
		(pad "259" smd rect
			(at 2.050034 38.675056 90)
			(size 0.519938 1.4986)
			(layers "F.Cu" "F.Mask" "F.Paste")
			(net "GND")
		)
		(pad "260" smd rect
			(at 2.050034 39.52494 90)
			(size 0.519938 1.4986)
			(layers "F.Cu" "F.Mask" "F.Paste")
			(net "M_A_CPU1_SB_DQS_DN<6>")
		)
		(pad "261" smd rect
			(at 2.050034 40.375078 90)
			(size 0.519938 1.4986)
			(layers "F.Cu" "F.Mask" "F.Paste")
			(net "M_A_CPU1_SB_DQS_DP<6>")
		)
		(pad "262" smd rect
			(at 2.050034 41.224962 90)
			(size 0.519938 1.4986)
			(layers "F.Cu" "F.Mask" "F.Paste")
			(net "GND")
		)
		(pad "263" smd rect
			(at 2.050034 42.0751 90)
			(size 0.519938 1.4986)
			(layers "F.Cu" "F.Mask" "F.Paste")
			(net "M_A_CPU1_SB_DQ<14>")
		)
		(pad "264" smd rect
			(at 2.050034 42.924984 90)
			(size 0.519938 1.4986)
			(layers "F.Cu" "F.Mask" "F.Paste")
			(net "GND")
		)
		(pad "265" smd rect
			(at 2.050034 43.775122 90)
			(size 0.519938 1.4986)
			(layers "F.Cu" "F.Mask" "F.Paste")
			(net "M_A_CPU1_SB_DQ<15>")
		)
		(pad "266" smd rect
			(at 2.050034 44.625006 90)
			(size 0.519938 1.4986)
			(layers "F.Cu" "F.Mask" "F.Paste")
			(net "GND")
		)
		(pad "267" smd rect
			(at 2.050034 45.47489 90)
			(size 0.519938 1.4986)
			(layers "F.Cu" "F.Mask" "F.Paste")
			(net "M_A_CPU1_SB_DQ<18>")
		)
		(pad "268" smd rect
			(at 2.050034 46.325028 90)
			(size 0.519938 1.4986)
			(layers "F.Cu" "F.Mask" "F.Paste")
			(net "GND")
		)
		(pad "269" smd rect
			(at 2.050034 47.174912 90)
			(size 0.519938 1.4986)
			(layers "F.Cu" "F.Mask" "F.Paste")
			(net "M_A_CPU1_SB_DQ<19>")
		)
		(pad "270" smd rect
			(at 2.050034 48.02505 90)
			(size 0.519938 1.4986)
			(layers "F.Cu" "F.Mask" "F.Paste")
			(net "GND")
		)
		(pad "271" smd rect
			(at 2.050034 48.874934 90)
			(size 0.519938 1.4986)
			(layers "F.Cu" "F.Mask" "F.Paste")
			(net "M_A_CPU1_SB_DQS_DN<7>")
		)
		(pad "272" smd rect
			(at 2.050034 49.725072 90)
			(size 0.519938 1.4986)
			(layers "F.Cu" "F.Mask" "F.Paste")
			(net "M_A_CPU1_SB_DQS_DP<7>")
		)
		(pad "273" smd rect
			(at 2.050034 50.574956 90)
			(size 0.519938 1.4986)
			(layers "F.Cu" "F.Mask" "F.Paste")
			(net "GND")
		)
		(pad "274" smd rect
			(at 2.050034 51.425094 90)
			(size 0.519938 1.4986)
			(layers "F.Cu" "F.Mask" "F.Paste")
			(net "M_A_CPU1_SB_DQ<22>")
		)
		(pad "275" smd rect
			(at 2.050034 52.274978 90)
			(size 0.519938 1.4986)
			(layers "F.Cu" "F.Mask" "F.Paste")
			(net "GND")
		)
		(pad "276" smd rect
			(at 2.050034 53.125116 90)
			(size 0.519938 1.4986)
			(layers "F.Cu" "F.Mask" "F.Paste")
			(net "M_A_CPU1_SB_DQ<23>")
		)
		(pad "277" smd rect
			(at 2.050034 53.975 90)
			(size 0.519938 1.4986)
			(layers "F.Cu" "F.Mask" "F.Paste")
			(net "GND")
		)
		(pad "278" smd rect
			(at 2.050034 54.824884 90)
			(size 0.519938 1.4986)
			(layers "F.Cu" "F.Mask" "F.Paste")
			(net "M_A_CPU1_SB_DQ<26>")
		)
		(pad "279" smd rect
			(at 2.050034 55.675022 90)
			(size 0.519938 1.4986)
			(layers "F.Cu" "F.Mask" "F.Paste")
			(net "GND")
		)
		(pad "280" smd rect
			(at 2.050034 56.524906 90)
			(size 0.519938 1.4986)
			(layers "F.Cu" "F.Mask" "F.Paste")
			(net "M_A_CPU1_SB_DQ<27>")
		)
		(pad "281" smd rect
			(at 2.050034 57.375044 90)
			(size 0.519938 1.4986)
			(layers "F.Cu" "F.Mask" "F.Paste")
			(net "GND")
		)
		(pad "282" smd rect
			(at 2.050034 58.224928 90)
			(size 0.519938 1.4986)
			(layers "F.Cu" "F.Mask" "F.Paste")
			(net "M_A_CPU1_SB_DQS_DN<8>")
		)
		(pad "283" smd rect
			(at 2.050034 59.075066 90)
			(size 0.519938 1.4986)
			(layers "F.Cu" "F.Mask" "F.Paste")
			(net "M_A_CPU1_SB_DQS_DP<8>")
		)
		(pad "284" smd rect
			(at 2.050034 59.92495 90)
			(size 0.519938 1.4986)
			(layers "F.Cu" "F.Mask" "F.Paste")
			(net "GND")
		)
		(pad "285" smd rect
			(at 2.050034 60.775088 90)
			(size 0.519938 1.4986)
			(layers "F.Cu" "F.Mask" "F.Paste")
			(net "M_A_CPU1_SB_DQ<30>")
		)
		(pad "286" smd rect
			(at 2.050034 61.624972 90)
			(size 0.519938 1.4986)
			(layers "F.Cu" "F.Mask" "F.Paste")
			(net "GND")
		)
		(pad "287" smd rect
			(at 2.050034 62.47511 90)
			(size 0.519938 1.4986)
			(layers "F.Cu" "F.Mask" "F.Paste")
			(net "M_A_CPU1_SB_DQ<31>")
		)
		(pad "288" smd rect
			(at 2.050034 63.324994 90)
			(size 0.519938 1.4986)
			(layers "F.Cu" "F.Mask" "F.Paste")
			(net "GND")
		)
		(pad "G1" thru_hole oval
			(at 0 -68.97497 90)
			(size 1.7272 3.4798)
			(drill oval 1.2192 2.4638)
			(layers "*.Cu" "*.Mask")
			(remove_unused_layers no)
			(net "GND")
			(clearance 0.127)
			(thermal_gap 0.127)
		)
		(pad "G2" thru_hole oval
			(at 0 3.875024 90)
			(size 1.7272 3.4798)
			(drill oval 1.2192 2.4638)
			(layers "*.Cu" "*.Mask")
			(remove_unused_layers no)
			(net "GND")
			(clearance 0.127)
			(thermal_gap 0.127)
		)
		(pad "G3" thru_hole oval
			(at 0 68.97497 90)
			(size 1.7272 3.4798)
			(drill oval 1.2192 2.4638)
			(layers "*.Cu" "*.Mask")
			(remove_unused_layers no)
			(net "GND")
			(clearance 0.127)
			(thermal_gap 0.127)
		)
	)
	(footprint ""
		(layer "F.Cu")
		(at 304.419 -367.665)
		(property "Reference" "R8072"
			(at 0 0 0)
			(layer "F.SilkS")
			(hide yes)
			(effects
				(font
					(size 1.27 1.27)
				)
			)
		)
		(property "Value" ""
			(at 0 0 0)
			(layer "F.Fab")
			(effects
				(font
					(size 1.27 1.27)
				)
			)
		)
		(duplicate_pad_numbers_are_jumpers no)
		(fp_line
			(start -0.7874 -0.4064)
			(end 0.7874 -0.4064)
			(stroke
				(width 0.1524)
				(type default)
			)
			(layer "F.SilkS")
		)
		(fp_line
			(start -0.7874 0.4064)
			(end -0.7874 -0.4064)
			(stroke
				(width 0.1524)
				(type default)
			)
			(layer "F.SilkS")
		)
		(fp_line
			(start 0.7874 -0.4064)
			(end 0.7874 0.4064)
			(stroke
				(width 0.1524)
				(type default)
			)
			(layer "F.SilkS")
		)
		(fp_line
			(start 0.7874 0.4064)
			(end -0.7874 0.4064)
			(stroke
				(width 0.1524)
				(type default)
			)
			(layer "F.SilkS")
		)
		(fp_line
			(start -0.67945 -0.305054)
			(end -0.12065 -0.305054)
			(stroke
				(width 0.1)
				(type default)
			)
			(layer "F.Fab")
		)
		(fp_line
			(start -0.67945 0.3048)
			(end -0.67945 -0.305054)
			(stroke
				(width 0.1)
				(type default)
			)
			(layer "F.Fab")
		)
		(fp_line
			(start -0.12065 -0.305054)
			(end -0.12065 -0.2794)
			(stroke
				(width 0.1)
				(type default)
			)
			(layer "F.Fab")
		)
		(fp_line
			(start -0.12065 -0.2794)
			(end 0.12065 -0.2794)
			(stroke
				(width 0.1)
				(type default)
			)
			(layer "F.Fab")
		)
		(fp_line
			(start -0.12065 0.2794)
			(end -0.12065 0.3048)
			(stroke
				(width 0.1)
				(type default)
			)
			(layer "F.Fab")
		)
		(fp_line
			(start -0.12065 0.3048)
			(end -0.67945 0.3048)
			(stroke
				(width 0.1)
				(type default)
			)
			(layer "F.Fab")
		)
		(fp_line
			(start 0.120396 0.2794)
			(end -0.12065 0.2794)
			(stroke
				(width 0.1)
				(type default)
			)
			(layer "F.Fab")
		)
		(fp_line
			(start 0.120396 0.3048)
			(end 0.120396 0.2794)
			(stroke
				(width 0.1)
				(type default)
			)
			(layer "F.Fab")
		)
		(fp_line
			(start 0.12065 -0.3048)
			(end 0.67945 -0.3048)
			(stroke
				(width 0.1)
				(type default)
			)
			(layer "F.Fab")
		)
		(fp_line
			(start 0.12065 -0.2794)
			(end 0.12065 -0.3048)
			(stroke
				(width 0.1)
				(type default)
			)
			(layer "F.Fab")
		)
		(fp_line
			(start 0.67945 -0.3048)
			(end 0.67945 0.3048)
			(stroke
				(width 0.1)
				(type default)
			)
			(layer "F.Fab")
		)
		(fp_line
			(start 0.67945 0.3048)
			(end 0.120396 0.3048)
			(stroke
				(width 0.1)
				(type default)
			)
			(layer "F.Fab")
		)
		(pad "1" smd circle
			(at -0.40005 0)
			(size 0 0)
			(layers "F.Cu" "F.Mask" "F.Paste")
			(net "SMB_SCM_2_R5_SDA")
		)
		(pad "2" smd circle
			(at 0.40005 0)
			(size 0 0)
			(layers "F.Cu" "F.Mask" "F.Paste")
			(net "SMB_DIO_PVDDCR_CPU1_P0_R")
		)
	)
	(footprint ""
		(layer "F.Cu")
		(at 110.152942 -21.7678 -90)
		(property "Reference" "R6271"
			(at 0 0 270)
			(layer "F.SilkS")
			(hide yes)
			(effects
				(font
					(size 1.27 1.27)
				)
			)
		)
		(property "Value" ""
			(at 0 0 270)
			(layer "F.Fab")
			(effects
				(font
					(size 1.27 1.27)
				)
			)
		)
		(duplicate_pad_numbers_are_jumpers no)
		(fp_line
			(start -0.7874 0.4064)
			(end -0.7874 -0.4064)
			(stroke
				(width 0.1524)
				(type default)
			)
			(layer "F.SilkS")
		)
		(fp_line
			(start 0.7874 0.4064)
			(end -0.7874 0.4064)
			(stroke
				(width 0.1524)
				(type default)
			)
			(layer "F.SilkS")
		)
		(fp_line
			(start -0.7874 -0.4064)
			(end 0.7874 -0.4064)
			(stroke
				(width 0.1524)
				(type default)
			)
			(layer "F.SilkS")
		)
		(fp_line
			(start 0.7874 -0.4064)
			(end 0.7874 0.4064)
			(stroke
				(width 0.1524)
				(type default)
			)
			(layer "F.SilkS")
		)
		(fp_line
			(start -0.67945 0.3048)
			(end -0.67945 -0.305054)
			(stroke
				(width 0.1)
				(type default)
			)
			(layer "F.Fab")
		)
		(fp_line
			(start -0.12065 0.3048)
			(end -0.67945 0.3048)
			(stroke
				(width 0.1)
				(type default)
			)
			(layer "F.Fab")
		)
		(fp_line
			(start 0.120396 0.3048)
			(end 0.120396 0.2794)
			(stroke
				(width 0.1)
				(type default)
			)
			(layer "F.Fab")
		)
		(fp_line
			(start 0.67945 0.3048)
			(end 0.120396 0.3048)
			(stroke
				(width 0.1)
				(type default)
			)
			(layer "F.Fab")
		)
		(fp_line
			(start -0.12065 0.2794)
			(end -0.12065 0.3048)
			(stroke
				(width 0.1)
				(type default)
			)
			(layer "F.Fab")
		)
		(fp_line
			(start 0.120396 0.2794)
			(end -0.12065 0.2794)
			(stroke
				(width 0.1)
				(type default)
			)
			(layer "F.Fab")
		)
		(fp_line
			(start -0.12065 -0.2794)
			(end 0.12065 -0.2794)
			(stroke
				(width 0.1)
				(type default)
			)
			(layer "F.Fab")
		)
		(fp_line
			(start 0.12065 -0.2794)
			(end 0.12065 -0.3048)
			(stroke
				(width 0.1)
				(type default)
			)
			(layer "F.Fab")
		)
		(fp_line
			(start 0.12065 -0.3048)
			(end 0.67945 -0.3048)
			(stroke
				(width 0.1)
				(type default)
			)
			(layer "F.Fab")
		)
		(fp_line
			(start 0.67945 -0.3048)
			(end 0.67945 0.3048)
			(stroke
				(width 0.1)
				(type default)
			)
			(layer "F.Fab")
		)
		(fp_line
			(start -0.67945 -0.305054)
			(end -0.12065 -0.305054)
			(stroke
				(width 0.1)
				(type default)
			)
			(layer "F.Fab")
		)
		(fp_line
			(start -0.12065 -0.305054)
			(end -0.12065 -0.2794)
			(stroke
				(width 0.1)
				(type default)
			)
			(layer "F.Fab")
		)
		(pad "1" smd circle
			(at -0.40005 0 270)
			(size 0 0)
			(layers "F.Cu" "F.Mask" "F.Paste")
			(net "USB_HUB2_TI_USB_DP_DN1_MRP_CFG_STRAP")
		)
		(pad "2" smd circle
			(at 0.40005 0 270)
			(size 0 0)
			(layers "F.Cu" "F.Mask" "F.Paste")
			(net "USB_HUB2_MRP_CFG_STRAP")
		)
	)
	(footprint ""
		(layer "F.Cu")
		(at 115.195096 -375.49963 -90)
		(property "Reference" "C1539"
			(at 0 0 270)
			(layer "F.SilkS")
			(hide yes)
			(effects
				(font
					(size 1.27 1.27)
				)
			)
		)
		(property "Value" ""
			(at 0 0 270)
			(layer "F.Fab")
			(effects
				(font
					(size 1.27 1.27)
				)
			)
		)
		(duplicate_pad_numbers_are_jumpers no)
		(fp_line
			(start -0.299974 0.150114)
			(end -0.299974 -0.150114)
			(stroke
				(width 0.1)
				(type default)
			)
			(layer "F.Fab")
		)
		(fp_line
			(start 0.299974 0.150114)
			(end -0.299974 0.150114)
			(stroke
				(width 0.1)
				(type default)
			)
			(layer "F.Fab")
		)
		(fp_line
			(start -0.299974 -0.150114)
			(end 0.299974 -0.150114)
			(stroke
				(width 0.1)
				(type default)
			)
			(layer "F.Fab")
		)
		(fp_line
			(start 0.299974 -0.150114)
			(end 0.299974 0.150114)
			(stroke
				(width 0.1)
				(type default)
			)
			(layer "F.Fab")
		)
		(pad "1" smd rect
			(at -0.2667 0 270)
			(size 0.3048 0.381)
			(layers "F.Cu" "F.Mask" "F.Paste")
			(net "P5E_CPU1_P3_TX_C_DP<4>")
		)
		(pad "2" smd rect
			(at 0.2667 0 270)
			(size 0.3048 0.381)
			(layers "F.Cu" "F.Mask" "F.Paste")
			(net "P5E_CPU1_P3_TX_DP<4>")
		)
	)
	(footprint ""
		(layer "F.Cu")
		(at 200.035668 -78.42377 180)
		(property "Reference" "R73"
			(at 0 0 180)
			(layer "F.SilkS")
			(hide yes)
			(effects
				(font
					(size 1.27 1.27)
				)
			)
		)
		(property "Value" ""
			(at 0 0 180)
			(layer "F.Fab")
			(effects
				(font
					(size 1.27 1.27)
				)
			)
		)
		(duplicate_pad_numbers_are_jumpers no)
		(fp_line
			(start 0.7874 0.4064)
			(end -0.7874 0.4064)
			(stroke
				(width 0.1524)
				(type default)
			)
			(layer "F.SilkS")
		)
		(fp_line
			(start 0.7874 -0.4064)
			(end 0.7874 0.4064)
			(stroke
				(width 0.1524)
				(type default)
			)
			(layer "F.SilkS")
		)
		(fp_line
			(start -0.7874 0.4064)
			(end -0.7874 -0.4064)
			(stroke
				(width 0.1524)
				(type default)
			)
			(layer "F.SilkS")
		)
		(fp_line
			(start -0.7874 -0.4064)
			(end 0.7874 -0.4064)
			(stroke
				(width 0.1524)
				(type default)
			)
			(layer "F.SilkS")
		)
		(fp_line
			(start 0.67945 0.3048)
			(end 0.120396 0.3048)
			(stroke
				(width 0.1)
				(type default)
			)
			(layer "F.Fab")
		)
		(fp_line
			(start 0.67945 -0.3048)
			(end 0.67945 0.3048)
			(stroke
				(width 0.1)
				(type default)
			)
			(layer "F.Fab")
		)
		(fp_line
			(start 0.12065 -0.2794)
			(end 0.12065 -0.3048)
			(stroke
				(width 0.1)
				(type default)
			)
			(layer "F.Fab")
		)
		(fp_line
			(start 0.12065 -0.3048)
			(end 0.67945 -0.3048)
			(stroke
				(width 0.1)
				(type default)
			)
			(layer "F.Fab")
		)
		(fp_line
			(start 0.120396 0.3048)
			(end 0.120396 0.2794)
			(stroke
				(width 0.1)
				(type default)
			)
			(layer "F.Fab")
		)
		(fp_line
			(start 0.120396 0.2794)
			(end -0.12065 0.2794)
			(stroke
				(width 0.1)
				(type default)
			)
			(layer "F.Fab")
		)
		(fp_line
			(start -0.12065 0.3048)
			(end -0.67945 0.3048)
			(stroke
				(width 0.1)
				(type default)
			)
			(layer "F.Fab")
		)
		(fp_line
			(start -0.12065 0.2794)
			(end -0.12065 0.3048)
			(stroke
				(width 0.1)
				(type default)
			)
			(layer "F.Fab")
		)
		(fp_line
			(start -0.12065 -0.2794)
			(end 0.12065 -0.2794)
			(stroke
				(width 0.1)
				(type default)
			)
			(layer "F.Fab")
		)
		(fp_line
			(start -0.12065 -0.305054)
			(end -0.12065 -0.2794)
			(stroke
				(width 0.1)
				(type default)
			)
			(layer "F.Fab")
		)
		(fp_line
			(start -0.67945 0.3048)
			(end -0.67945 -0.305054)
			(stroke
				(width 0.1)
				(type default)
			)
			(layer "F.Fab")
		)
		(fp_line
			(start -0.67945 -0.305054)
			(end -0.12065 -0.305054)
			(stroke
				(width 0.1)
				(type default)
			)
			(layer "F.Fab")
		)
		(pad "1" smd circle
			(at -0.40005 0 180)
			(size 0 0)
			(layers "F.Cu" "F.Mask" "F.Paste")
			(net "NCSI_BMC_RXD1_R")
		)
		(pad "2" smd circle
			(at 0.40005 0 180)
			(size 0 0)
			(layers "F.Cu" "F.Mask" "F.Paste")
			(net "RMII_OCP_BMC_RXD_1")
		)
	)
	(footprint ""
		(layer "F.Cu")
		(at 118.5164 -36.67125 90)
		(property "Reference" "R6270"
			(at 0 0 90)
			(layer "F.SilkS")
			(hide yes)
			(effects
				(font
					(size 1.27 1.27)
				)
			)
		)
		(property "Value" ""
			(at 0 0 90)
			(layer "F.Fab")
			(effects
				(font
					(size 1.27 1.27)
				)
			)
		)
		(duplicate_pad_numbers_are_jumpers no)
		(fp_line
			(start 0.7874 -0.4064)
			(end 0.7874 0.4064)
			(stroke
				(width 0.1524)
				(type default)
			)
			(layer "F.SilkS")
		)
		(fp_line
			(start -0.7874 -0.4064)
			(end 0.7874 -0.4064)
			(stroke
				(width 0.1524)
				(type default)
			)
			(layer "F.SilkS")
		)
		(fp_line
			(start 0.7874 0.4064)
			(end -0.7874 0.4064)
			(stroke
				(width 0.1524)
				(type default)
			)
			(layer "F.SilkS")
		)
		(fp_line
			(start -0.7874 0.4064)
			(end -0.7874 -0.4064)
			(stroke
				(width 0.1524)
				(type default)
			)
			(layer "F.SilkS")
		)
		(fp_line
			(start -0.12065 -0.305054)
			(end -0.12065 -0.2794)
			(stroke
				(width 0.1)
				(type default)
			)
			(layer "F.Fab")
		)
		(fp_line
			(start -0.67945 -0.305054)
			(end -0.12065 -0.305054)
			(stroke
				(width 0.1)
				(type default)
			)
			(layer "F.Fab")
		)
		(fp_line
			(start 0.67945 -0.3048)
			(end 0.67945 0.3048)
			(stroke
				(width 0.1)
				(type default)
			)
			(layer "F.Fab")
		)
		(fp_line
			(start 0.12065 -0.3048)
			(end 0.67945 -0.3048)
			(stroke
				(width 0.1)
				(type default)
			)
			(layer "F.Fab")
		)
		(fp_line
			(start 0.12065 -0.2794)
			(end 0.12065 -0.3048)
			(stroke
				(width 0.1)
				(type default)
			)
			(layer "F.Fab")
		)
		(fp_line
			(start -0.12065 -0.2794)
			(end 0.12065 -0.2794)
			(stroke
				(width 0.1)
				(type default)
			)
			(layer "F.Fab")
		)
		(fp_line
			(start 0.120396 0.2794)
			(end -0.12065 0.2794)
			(stroke
				(width 0.1)
				(type default)
			)
			(layer "F.Fab")
		)
		(fp_line
			(start -0.12065 0.2794)
			(end -0.12065 0.3048)
			(stroke
				(width 0.1)
				(type default)
			)
			(layer "F.Fab")
		)
		(fp_line
			(start 0.67945 0.3048)
			(end 0.120396 0.3048)
			(stroke
				(width 0.1)
				(type default)
			)
			(layer "F.Fab")
		)
		(fp_line
			(start 0.120396 0.3048)
			(end 0.120396 0.2794)
			(stroke
				(width 0.1)
				(type default)
			)
			(layer "F.Fab")
		)
		(fp_line
			(start -0.12065 0.3048)
			(end -0.67945 0.3048)
			(stroke
				(width 0.1)
				(type default)
			)
			(layer "F.Fab")
		)
		(fp_line
			(start -0.67945 0.3048)
			(end -0.67945 -0.305054)
			(stroke
				(width 0.1)
				(type default)
			)
			(layer "F.Fab")
		)
		(pad "1" smd circle
			(at -0.40005 0 90)
			(size 0 0)
			(layers "F.Cu" "F.Mask" "F.Paste")
			(net "P3V3_AUX_CPU0_USB2_AVDD33")
		)
		(pad "2" smd circle
			(at 0.40005 0 90)
			(size 0 0)
			(layers "F.Cu" "F.Mask" "F.Paste")
			(net "USB_HUB2_TI_PWRCTL3_MRP_VDD33")
		)
	)
	(footprint ""
		(layer "F.Cu")
		(at 19.844258 -427.580298 90)
		(property "Reference" "R6164"
			(at 0 0 90)
			(layer "F.SilkS")
			(hide yes)
			(effects
				(font
					(size 1.27 1.27)
				)
			)
		)
		(property "Value" ""
			(at 0 0 90)
			(layer "F.Fab")
			(effects
				(font
					(size 1.27 1.27)
				)
			)
		)
		(duplicate_pad_numbers_are_jumpers no)
		(fp_line
			(start 0.7874 -0.4064)
			(end 0.7874 0.4064)
			(stroke
				(width 0.1524)
				(type default)
			)
			(layer "F.SilkS")
		)
		(fp_line
			(start -0.7874 -0.4064)
			(end 0.7874 -0.4064)
			(stroke
				(width 0.1524)
				(type default)
			)
			(layer "F.SilkS")
		)
		(fp_line
			(start 0.7874 0.4064)
			(end -0.7874 0.4064)
			(stroke
				(width 0.1524)
				(type default)
			)
			(layer "F.SilkS")
		)
		(fp_line
			(start -0.7874 0.4064)
			(end -0.7874 -0.4064)
			(stroke
				(width 0.1524)
				(type default)
			)
			(layer "F.SilkS")
		)
		(fp_line
			(start -0.12065 -0.305054)
			(end -0.12065 -0.2794)
			(stroke
				(width 0.1)
				(type default)
			)
			(layer "F.Fab")
		)
		(fp_line
			(start -0.67945 -0.305054)
			(end -0.12065 -0.305054)
			(stroke
				(width 0.1)
				(type default)
			)
			(layer "F.Fab")
		)
		(fp_line
			(start 0.67945 -0.3048)
			(end 0.67945 0.3048)
			(stroke
				(width 0.1)
				(type default)
			)
			(layer "F.Fab")
		)
		(fp_line
			(start 0.12065 -0.3048)
			(end 0.67945 -0.3048)
			(stroke
				(width 0.1)
				(type default)
			)
			(layer "F.Fab")
		)
		(fp_line
			(start 0.12065 -0.2794)
			(end 0.12065 -0.3048)
			(stroke
				(width 0.1)
				(type default)
			)
			(layer "F.Fab")
		)
		(fp_line
			(start -0.12065 -0.2794)
			(end 0.12065 -0.2794)
			(stroke
				(width 0.1)
				(type default)
			)
			(layer "F.Fab")
		)
		(fp_line
			(start 0.120396 0.2794)
			(end -0.12065 0.2794)
			(stroke
				(width 0.1)
				(type default)
			)
			(layer "F.Fab")
		)
		(fp_line
			(start -0.12065 0.2794)
			(end -0.12065 0.3048)
			(stroke
				(width 0.1)
				(type default)
			)
			(layer "F.Fab")
		)
		(fp_line
			(start 0.67945 0.3048)
			(end 0.120396 0.3048)
			(stroke
				(width 0.1)
				(type default)
			)
			(layer "F.Fab")
		)
		(fp_line
			(start 0.120396 0.3048)
			(end 0.120396 0.2794)
			(stroke
				(width 0.1)
				(type default)
			)
			(layer "F.Fab")
		)
		(fp_line
			(start -0.12065 0.3048)
			(end -0.67945 0.3048)
			(stroke
				(width 0.1)
				(type default)
			)
			(layer "F.Fab")
		)
		(fp_line
			(start -0.67945 0.3048)
			(end -0.67945 -0.305054)
			(stroke
				(width 0.1)
				(type default)
			)
			(layer "F.Fab")
		)
		(pad "1" smd circle
			(at -0.40005 0 90)
			(size 0 0)
			(layers "F.Cu" "F.Mask" "F.Paste")
			(net "FM_P2E_BUF2_EQB1")
		)
		(pad "2" smd circle
			(at 0.40005 0 90)
			(size 0 0)
			(layers "F.Cu" "F.Mask" "F.Paste")
			(net "GND")
		)
	)
	(footprint ""
		(layer "F.Cu")
		(at 288.314384 -343.712038 180)
		(property "Reference" "PC159"
			(at 0 0 180)
			(layer "F.SilkS")
			(hide yes)
			(effects
				(font
					(size 1.27 1.27)
				)
			)
		)
		(property "Value" ""
			(at 0 0 180)
			(layer "F.Fab")
			(effects
				(font
					(size 1.27 1.27)
				)
			)
		)
		(duplicate_pad_numbers_are_jumpers no)
		(fp_line
			(start 0.7874 0.4064)
			(end -0.7874 0.4064)
			(stroke
				(width 0.1524)
				(type default)
			)
			(layer "F.SilkS")
		)
		(fp_line
			(start 0.7874 -0.4064)
			(end 0.7874 0.4064)
			(stroke
				(width 0.1524)
				(type default)
			)
			(layer "F.SilkS")
		)
		(fp_line
			(start -0.7874 0.4064)
			(end -0.7874 -0.4064)
			(stroke
				(width 0.1524)
				(type default)
			)
			(layer "F.SilkS")
		)
		(fp_line
			(start -0.7874 -0.4064)
			(end 0.7874 -0.4064)
			(stroke
				(width 0.1524)
				(type default)
			)
			(layer "F.SilkS")
		)
		(fp_line
			(start 0.67945 0.3048)
			(end 0.120396 0.3048)
			(stroke
				(width 0.1)
				(type default)
			)
			(layer "F.Fab")
		)
		(fp_line
			(start 0.67945 -0.3048)
			(end 0.67945 0.3048)
			(stroke
				(width 0.1)
				(type default)
			)
			(layer "F.Fab")
		)
		(fp_line
			(start 0.12065 -0.2794)
			(end 0.12065 -0.3048)
			(stroke
				(width 0.1)
				(type default)
			)
			(layer "F.Fab")
		)
		(fp_line
			(start 0.12065 -0.3048)
			(end 0.67945 -0.3048)
			(stroke
				(width 0.1)
				(type default)
			)
			(layer "F.Fab")
		)
		(fp_line
			(start 0.120396 0.3048)
			(end 0.120396 0.2794)
			(stroke
				(width 0.1)
				(type default)
			)
			(layer "F.Fab")
		)
		(fp_line
			(start 0.120396 0.2794)
			(end -0.12065 0.2794)
			(stroke
				(width 0.1)
				(type default)
			)
			(layer "F.Fab")
		)
		(fp_line
			(start -0.12065 0.3048)
			(end -0.67945 0.3048)
			(stroke
				(width 0.1)
				(type default)
			)
			(layer "F.Fab")
		)
		(fp_line
			(start -0.12065 0.2794)
			(end -0.12065 0.3048)
			(stroke
				(width 0.1)
				(type default)
			)
			(layer "F.Fab")
		)
		(fp_line
			(start -0.12065 -0.2794)
			(end 0.12065 -0.2794)
			(stroke
				(width 0.1)
				(type default)
			)
			(layer "F.Fab")
		)
		(fp_line
			(start -0.12065 -0.305054)
			(end -0.12065 -0.2794)
			(stroke
				(width 0.1)
				(type default)
			)
			(layer "F.Fab")
		)
		(fp_line
			(start -0.67945 0.3048)
			(end -0.67945 -0.305054)
			(stroke
				(width 0.1)
				(type default)
			)
			(layer "F.Fab")
		)
		(fp_line
			(start -0.67945 -0.305054)
			(end -0.12065 -0.305054)
			(stroke
				(width 0.1)
				(type default)
			)
			(layer "F.Fab")
		)
		(pad "1" smd circle
			(at -0.40005 0 180)
			(size 0 0)
			(layers "F.Cu" "F.Mask" "F.Paste")
			(net "SW_PVDDIO_P0_SW2")
		)
		(pad "2" smd circle
			(at 0.40005 0 180)
			(size 0 0)
			(layers "F.Cu" "F.Mask" "F.Paste")
			(net "SW_PVDDIO_P0_SW2_RC")
		)
	)
	(footprint ""
		(layer "F.Cu")
		(at 179.846224 -147.086574 90)
		(property "Reference" "R70"
			(at 0 0 90)
			(layer "F.SilkS")
			(hide yes)
			(effects
				(font
					(size 1.27 1.27)
				)
			)
		)
		(property "Value" ""
			(at 0 0 90)
			(layer "F.Fab")
			(effects
				(font
					(size 1.27 1.27)
				)
			)
		)
		(duplicate_pad_numbers_are_jumpers no)
		(fp_line
			(start 0.7874 -0.4064)
			(end 0.7874 0.4064)
			(stroke
				(width 0.1524)
				(type default)
			)
			(layer "F.SilkS")
		)
		(fp_line
			(start -0.7874 -0.4064)
			(end 0.7874 -0.4064)
			(stroke
				(width 0.1524)
				(type default)
			)
			(layer "F.SilkS")
		)
		(fp_line
			(start 0.7874 0.4064)
			(end -0.7874 0.4064)
			(stroke
				(width 0.1524)
				(type default)
			)
			(layer "F.SilkS")
		)
		(fp_line
			(start -0.7874 0.4064)
			(end -0.7874 -0.4064)
			(stroke
				(width 0.1524)
				(type default)
			)
			(layer "F.SilkS")
		)
		(fp_line
			(start -0.12065 -0.305054)
			(end -0.12065 -0.2794)
			(stroke
				(width 0.1)
				(type default)
			)
			(layer "F.Fab")
		)
		(fp_line
			(start -0.67945 -0.305054)
			(end -0.12065 -0.305054)
			(stroke
				(width 0.1)
				(type default)
			)
			(layer "F.Fab")
		)
		(fp_line
			(start 0.67945 -0.3048)
			(end 0.67945 0.3048)
			(stroke
				(width 0.1)
				(type default)
			)
			(layer "F.Fab")
		)
		(fp_line
			(start 0.12065 -0.3048)
			(end 0.67945 -0.3048)
			(stroke
				(width 0.1)
				(type default)
			)
			(layer "F.Fab")
		)
		(fp_line
			(start 0.12065 -0.2794)
			(end 0.12065 -0.3048)
			(stroke
				(width 0.1)
				(type default)
			)
			(layer "F.Fab")
		)
		(fp_line
			(start -0.12065 -0.2794)
			(end 0.12065 -0.2794)
			(stroke
				(width 0.1)
				(type default)
			)
			(layer "F.Fab")
		)
		(fp_line
			(start 0.120396 0.2794)
			(end -0.12065 0.2794)
			(stroke
				(width 0.1)
				(type default)
			)
			(layer "F.Fab")
		)
		(fp_line
			(start -0.12065 0.2794)
			(end -0.12065 0.3048)
			(stroke
				(width 0.1)
				(type default)
			)
			(layer "F.Fab")
		)
		(fp_line
			(start 0.67945 0.3048)
			(end 0.120396 0.3048)
			(stroke
				(width 0.1)
				(type default)
			)
			(layer "F.Fab")
		)
		(fp_line
			(start 0.120396 0.3048)
			(end 0.120396 0.2794)
			(stroke
				(width 0.1)
				(type default)
			)
			(layer "F.Fab")
		)
		(fp_line
			(start -0.12065 0.3048)
			(end -0.67945 0.3048)
			(stroke
				(width 0.1)
				(type default)
			)
			(layer "F.Fab")
		)
		(fp_line
			(start -0.67945 0.3048)
			(end -0.67945 -0.305054)
			(stroke
				(width 0.1)
				(type default)
			)
			(layer "F.Fab")
		)
		(pad "1" smd circle
			(at -0.40005 0 90)
			(size 0 0)
			(layers "F.Cu" "F.Mask" "F.Paste")
			(net "SMB_CPU0_4_XLTR_R_SCL")
		)
		(pad "2" smd circle
			(at 0.40005 0 90)
			(size 0 0)
			(layers "F.Cu" "F.Mask" "F.Paste")
			(net "SMB_CPU0_4_XLTR_SCL")
		)
	)
	(footprint ""
		(layer "F.Cu")
		(at 427.7614 -36.642548)
		(property "Reference" "SW1"
			(at -2.2733 -7.534148 0)
			(unlocked yes)
			(layer "F.SilkS")
			(effects
				(font
					(size 0.7874 0.5842)
					(thickness 0.1524)
				)
				(justify left)
			)
		)
		(property "Value" ""
			(at 0 0 0)
			(layer "F.Fab")
			(effects
				(font
					(size 1.27 1.27)
				)
			)
		)
		(duplicate_pad_numbers_are_jumpers no)
		(fp_line
			(start -2.275078 -6.964934)
			(end -2.275078 6.964934)
			(stroke
				(width 0.1524)
				(type default)
			)
			(layer "F.SilkS")
		)
		(fp_line
			(start -2.275078 6.964934)
			(end 2.275078 6.964934)
			(stroke
				(width 0.1524)
				(type default)
			)
			(layer "F.SilkS")
		)
		(fp_line
			(start -1.8796 -5.8166)
			(end -1.8796 -5.3086)
			(stroke
				(width 0.1524)
				(type default)
			)
			(layer "F.SilkS")
		)
		(fp_line
			(start -1.8796 -5.3086)
			(end 1.9304 -5.3086)
			(stroke
				(width 0.1524)
				(type default)
			)
			(layer "F.SilkS")
		)
		(fp_line
			(start -1.8796 -4.5466)
			(end -1.8796 -4.0386)
			(stroke
				(width 0.1524)
				(type default)
			)
			(layer "F.SilkS")
		)
		(fp_line
			(start -1.8796 -4.0386)
			(end 1.9304 -4.0386)
			(stroke
				(width 0.1524)
				(type default)
			)
			(layer "F.SilkS")
		)
		(fp_line
			(start -1.8796 -3.2766)
			(end -1.8796 -2.7686)
			(stroke
				(width 0.1524)
				(type default)
			)
			(layer "F.SilkS")
		)
		(fp_line
			(start -1.8796 -2.7686)
			(end 1.9304 -2.7686)
			(stroke
				(width 0.1524)
				(type default)
			)
			(layer "F.SilkS")
		)
		(fp_line
			(start -1.8796 -2.0066)
			(end -1.8796 -1.4986)
			(stroke
				(width 0.1524)
				(type default)
			)
			(layer "F.SilkS")
		)
		(fp_line
			(start -1.8796 -1.4986)
			(end 1.9304 -1.4986)
			(stroke
				(width 0.1524)
				(type default)
			)
			(layer "F.SilkS")
		)
		(fp_line
			(start -1.8796 -0.7366)
			(end -1.8796 -0.2286)
			(stroke
				(width 0.1524)
				(type default)
			)
			(layer "F.SilkS")
		)
		(fp_line
			(start -1.8796 -0.2286)
			(end 1.9304 -0.2286)
			(stroke
				(width 0.1524)
				(type default)
			)
			(layer "F.SilkS")
		)
		(fp_line
			(start -1.8796 0.5334)
			(end -1.8796 1.0414)
			(stroke
				(width 0.1524)
				(type default)
			)
			(layer "F.SilkS")
		)
		(fp_line
			(start -1.8796 1.0414)
			(end 1.9304 1.0414)
			(stroke
				(width 0.1524)
				(type default)
			)
			(layer "F.SilkS")
		)
		(fp_line
			(start -1.8796 1.8034)
			(end -1.8796 2.3114)
			(stroke
				(width 0.1524)
				(type default)
			)
			(layer "F.SilkS")
		)
		(fp_line
			(start -1.8796 2.3114)
			(end 1.9304 2.3114)
			(stroke
				(width 0.1524)
				(type default)
			)
			(layer "F.SilkS")
		)
		(fp_line
			(start -1.8796 3.0734)
			(end -1.8796 3.5814)
			(stroke
				(width 0.1524)
				(type default)
			)
			(layer "F.SilkS")
		)
		(fp_line
			(start -1.8796 3.5814)
			(end 1.9304 3.5814)
			(stroke
				(width 0.1524)
				(type default)
			)
			(layer "F.SilkS")
		)
		(fp_line
			(start -1.8796 4.3434)
			(end -1.8796 4.8514)
			(stroke
				(width 0.1524)
				(type default)
			)
			(layer "F.SilkS")
		)
		(fp_line
			(start -1.8796 4.8514)
			(end 1.9304 4.8514)
			(stroke
				(width 0.1524)
				(type default)
			)
			(layer "F.SilkS")
		)
		(fp_line
			(start -1.8796 5.6134)
			(end -1.8796 6.1214)
			(stroke
				(width 0.1524)
				(type default)
			)
			(layer "F.SilkS")
		)
		(fp_line
			(start -1.8796 6.1214)
			(end 1.9304 6.1214)
			(stroke
				(width 0.1524)
				(type default)
			)
			(layer "F.SilkS")
		)
		(fp_line
			(start -1.122934 -6.964934)
			(end -2.275078 -6.964934)
			(stroke
				(width 0.1524)
				(type default)
			)
			(layer "F.SilkS")
		)
		(fp_line
			(start 0 -6.096)
			(end -1.122934 -6.964934)
			(stroke
				(width 0.1524)
				(type default)
			)
			(layer "F.SilkS")
		)
		(fp_line
			(start 0.0254 -5.8166)
			(end 0.0254 -5.3086)
			(stroke
				(width 0.1524)
				(type default)
			)
			(layer "F.SilkS")
		)
		(fp_line
			(start 0.0254 -4.5466)
			(end 0.0254 -4.0386)
			(stroke
				(width 0.1524)
				(type default)
			)
			(layer "F.SilkS")
		)
		(fp_line
			(start 0.0254 -3.2766)
			(end 0.0254 -2.7686)
			(stroke
				(width 0.1524)
				(type default)
			)
			(layer "F.SilkS")
		)
		(fp_line
			(start 0.0254 -2.0066)
			(end 0.0254 -1.4986)
			(stroke
				(width 0.1524)
				(type default)
			)
			(layer "F.SilkS")
		)
		(fp_line
			(start 0.0254 -0.7366)
			(end 0.0254 -0.2286)
			(stroke
				(width 0.1524)
				(type default)
			)
			(layer "F.SilkS")
		)
		(fp_line
			(start 0.0254 0.5334)
			(end 0.0254 1.0414)
			(stroke
				(width 0.1524)
				(type default)
			)
			(layer "F.SilkS")
		)
		(fp_line
			(start 0.0254 1.8034)
			(end 0.0254 2.3114)
			(stroke
				(width 0.1524)
				(type default)
			)
			(layer "F.SilkS")
		)
		(fp_line
			(start 0.0254 3.0734)
			(end 0.0254 3.5814)
			(stroke
				(width 0.1524)
				(type default)
			)
			(layer "F.SilkS")
		)
		(fp_line
			(start 0.0254 4.3434)
			(end 0.0254 4.8514)
			(stroke
				(width 0.1524)
				(type default)
			)
			(layer "F.SilkS")
		)
		(fp_line
			(start 0.0254 5.6134)
			(end 0.0254 6.1214)
			(stroke
				(width 0.1524)
				(type default)
			)
			(layer "F.SilkS")
		)
		(fp_line
			(start 1.122934 -6.964934)
			(end 0 -6.096)
			(stroke
				(width 0.1524)
				(type default)
			)
			(layer "F.SilkS")
		)
		(fp_line
			(start 1.9304 -5.8166)
			(end -1.8796 -5.8166)
			(stroke
				(width 0.1524)
				(type default)
			)
			(layer "F.SilkS")
		)
		(fp_line
			(start 1.9304 -5.3086)
			(end 1.9304 -5.8166)
			(stroke
				(width 0.1524)
				(type default)
			)
			(layer "F.SilkS")
		)
		(fp_line
			(start 1.9304 -4.5466)
			(end -1.8796 -4.5466)
			(stroke
				(width 0.1524)
				(type default)
			)
			(layer "F.SilkS")
		)
		(fp_line
			(start 1.9304 -4.0386)
			(end 1.9304 -4.5466)
			(stroke
				(width 0.1524)
				(type default)
			)
			(layer "F.SilkS")
		)
		(fp_line
			(start 1.9304 -3.2766)
			(end -1.8796 -3.2766)
			(stroke
				(width 0.1524)
				(type default)
			)
			(layer "F.SilkS")
		)
		(fp_line
			(start 1.9304 -2.7686)
			(end 1.9304 -3.2766)
			(stroke
				(width 0.1524)
				(type default)
			)
			(layer "F.SilkS")
		)
		(fp_line
			(start 1.9304 -2.0066)
			(end -1.8796 -2.0066)
			(stroke
				(width 0.1524)
				(type default)
			)
			(layer "F.SilkS")
		)
		(fp_line
			(start 1.9304 -1.4986)
			(end 1.9304 -2.0066)
			(stroke
				(width 0.1524)
				(type default)
			)
			(layer "F.SilkS")
		)
		(fp_line
			(start 1.9304 -0.7366)
			(end -1.8796 -0.7366)
			(stroke
				(width 0.1524)
				(type default)
			)
			(layer "F.SilkS")
		)
		(fp_line
			(start 1.9304 -0.2286)
			(end 1.9304 -0.7366)
			(stroke
				(width 0.1524)
				(type default)
			)
			(layer "F.SilkS")
		)
		(fp_line
			(start 1.9304 0.5334)
			(end -1.8796 0.5334)
			(stroke
				(width 0.1524)
				(type default)
			)
			(layer "F.SilkS")
		)
		(fp_line
			(start 1.9304 1.0414)
			(end 1.9304 0.5334)
			(stroke
				(width 0.1524)
				(type default)
			)
			(layer "F.SilkS")
		)
		(fp_line
			(start 1.9304 1.8034)
			(end -1.8796 1.8034)
			(stroke
				(width 0.1524)
				(type default)
			)
			(layer "F.SilkS")
		)
		(fp_line
			(start 1.9304 2.3114)
			(end 1.9304 1.8034)
			(stroke
				(width 0.1524)
				(type default)
			)
			(layer "F.SilkS")
		)
		(fp_line
			(start 1.9304 3.0734)
			(end -1.8796 3.0734)
			(stroke
				(width 0.1524)
				(type default)
			)
			(layer "F.SilkS")
		)
		(fp_line
			(start 1.9304 3.5814)
			(end 1.9304 3.0734)
			(stroke
				(width 0.1524)
				(type default)
			)
			(layer "F.SilkS")
		)
		(fp_line
			(start 1.9304 4.3434)
			(end -1.8796 4.3434)
			(stroke
				(width 0.1524)
				(type default)
			)
			(layer "F.SilkS")
		)
		(fp_line
			(start 1.9304 4.8514)
			(end 1.9304 4.3434)
			(stroke
				(width 0.1524)
				(type default)
			)
			(layer "F.SilkS")
		)
		(fp_line
			(start 1.9304 5.6134)
			(end -1.8796 5.6134)
			(stroke
				(width 0.1524)
				(type default)
			)
			(layer "F.SilkS")
		)
		(fp_line
			(start 1.9304 6.1214)
			(end 1.9304 5.6134)
			(stroke
				(width 0.1524)
				(type default)
			)
			(layer "F.SilkS")
		)
		(fp_line
			(start 2.275078 -6.964934)
			(end 1.122934 -6.964934)
			(stroke
				(width 0.1524)
				(type default)
			)
			(layer "F.SilkS")
		)
		(fp_line
			(start 2.275078 6.964934)
			(end 2.275078 -6.964934)
			(stroke
				(width 0.1524)
				(type default)
			)
			(layer "F.SilkS")
		)
		(fp_poly
			(pts
				(xy -6.40969 -5.228082) (xy -6.40969 -6.244082) (xy -5.39369 -5.736082)
			)
			(stroke
				(width 0)
				(type default)
			)
			(fill yes)
			(layer "F.SilkS")
		)
		(fp_line
			(start -2.275078 -6.964934)
			(end 2.275078 -6.964934)
			(stroke
				(width 0.1)
				(type default)
			)
			(layer "F.Fab")
		)
		(fp_line
			(start -2.275078 6.964934)
			(end -2.275078 -6.964934)
			(stroke
				(width 0.1)
				(type default)
			)
			(layer "F.Fab")
		)
		(fp_line
			(start 2.275078 -6.964934)
			(end 2.275078 6.964934)
			(stroke
				(width 0.1)
				(type default)
			)
			(layer "F.Fab")
		)
		(fp_line
			(start 2.275078 6.964934)
			(end -2.275078 6.964934)
			(stroke
				(width 0.1)
				(type default)
			)
			(layer "F.Fab")
		)
		(fp_poly
			(pts
				(xy -5.6134 -5.207) (xy -5.6134 -6.223) (xy -4.5974 -5.715)
			)
			(stroke
				(width 0)
				(type default)
			)
			(fill yes)
			(layer "F.Fab")
		)
		(pad "1" smd rect
			(at -3.81 -5.715 270)
			(size 0.762 1.27)
			(layers "F.Cu" "F.Mask" "F.Paste")
			(net "GND")
		)
		(pad "2" smd rect
			(at -3.81 -4.445 270)
			(size 0.762 1.27)
			(layers "F.Cu" "F.Mask" "F.Paste")
			(net "FM_FORCE_ALL_PWRON_ON")
		)
		(pad "3" smd rect
			(at -3.81 -3.175 270)
			(size 0.762 1.27)
			(layers "F.Cu" "F.Mask" "F.Paste")
			(net "GND")
		)
		(pad "4" smd rect
			(at -3.81 -1.905 270)
			(size 0.762 1.27)
			(layers "F.Cu" "F.Mask" "F.Paste")
			(net "PU_BIOS_USB_RECOVERY")
		)
		(pad "5" smd rect
			(at -3.81 -0.635 270)
			(size 0.762 1.27)
			(layers "F.Cu" "F.Mask" "F.Paste")
			(net "PU_FPGA_DEBUG_SW_SPARE")
		)
		(pad "6" smd rect
			(at -3.81 0.635 270)
			(size 0.762 1.27)
			(layers "F.Cu" "F.Mask" "F.Paste")
			(net "PD_BIOS_DEBUG_MODE")
		)
		(pad "7" smd rect
			(at -3.81 1.905 270)
			(size 0.762 1.27)
			(layers "F.Cu" "F.Mask" "F.Paste")
			(net "PRSNT_CPU0_N")
		)
		(pad "8" smd rect
			(at -3.81 3.175 270)
			(size 0.762 1.27)
			(layers "F.Cu" "F.Mask" "F.Paste")
			(net "PRSNT_CPU1_N")
		)
		(pad "9" smd rect
			(at -3.81 4.445 270)
			(size 0.762 1.27)
			(layers "F.Cu" "F.Mask" "F.Paste")
			(net "GND")
		)
		(pad "10" smd rect
			(at -3.81 5.715 270)
			(size 0.762 1.27)
			(layers "F.Cu" "F.Mask" "F.Paste")
			(net "PU_FPGA_DEBUG_LED_CTRL")
		)
		(pad "11" smd rect
			(at 3.81 -5.715 270)
			(size 0.762 1.27)
			(layers "F.Cu" "F.Mask" "F.Paste")
			(net "FM_SPD_CPU0_SWITCH_CTRL_N")
		)
		(pad "12" smd rect
			(at 3.81 -4.445 270)
			(size 0.762 1.27)
			(layers "F.Cu" "F.Mask" "F.Paste")
			(net "FM_FORCE_ALL_PWRON")
		)
		(pad "13" smd rect
			(at 3.81 -3.175 270)
			(size 0.762 1.27)
			(layers "F.Cu" "F.Mask" "F.Paste")
			(net "BMC_JTAG_SEL")
		)
		(pad "14" smd rect
			(at 3.81 -1.905 270)
			(size 0.762 1.27)
			(layers "F.Cu" "F.Mask" "F.Paste")
			(net "FM_BIOS_USB_RECOVERY")
		)
		(pad "15" smd rect
			(at 3.81 -0.635 270)
			(size 0.762 1.27)
			(layers "F.Cu" "F.Mask" "F.Paste")
			(net "FPGA_DEBUG_SW_SPARE")
		)
		(pad "16" smd rect
			(at 3.81 0.635 270)
			(size 0.762 1.27)
			(layers "F.Cu" "F.Mask" "F.Paste")
			(net "BIOS_DEBUG_MODE")
		)
		(pad "17" smd rect
			(at 3.81 1.905 270)
			(size 0.762 1.27)
			(layers "F.Cu" "F.Mask" "F.Paste")
			(net "FM_PRSNT_CPU0_N")
		)
		(pad "18" smd rect
			(at 3.81 3.175 270)
			(size 0.762 1.27)
			(layers "F.Cu" "F.Mask" "F.Paste")
			(net "FM_PRSNT_CPU1_N")
		)
		(pad "19" smd rect
			(at 3.81 4.445 270)
			(size 0.762 1.27)
			(layers "F.Cu" "F.Mask" "F.Paste")
			(net "FM_PASSWORD_CLEAR_N")
		)
		(pad "20" smd rect
			(at 3.81 5.715 270)
			(size 0.762 1.27)
			(layers "F.Cu" "F.Mask" "F.Paste")
			(net "FPGA_DEBUG_LED_CTRL")
		)
	)
	(footprint ""
		(layer "F.Cu")
		(at 251.06884 -92.719144 -90)
		(property "Reference" "R1641"
			(at 0 0 270)
			(layer "F.SilkS")
			(hide yes)
			(effects
				(font
					(size 1.27 1.27)
				)
			)
		)
		(property "Value" ""
			(at 0 0 270)
			(layer "F.Fab")
			(effects
				(font
					(size 1.27 1.27)
				)
			)
		)
		(duplicate_pad_numbers_are_jumpers no)
		(fp_line
			(start -0.7874 0.4064)
			(end -0.7874 -0.4064)
			(stroke
				(width 0.1524)
				(type default)
			)
			(layer "F.SilkS")
		)
		(fp_line
			(start 0.7874 0.4064)
			(end -0.7874 0.4064)
			(stroke
				(width 0.1524)
				(type default)
			)
			(layer "F.SilkS")
		)
		(fp_line
			(start -0.7874 -0.4064)
			(end 0.7874 -0.4064)
			(stroke
				(width 0.1524)
				(type default)
			)
			(layer "F.SilkS")
		)
		(fp_line
			(start 0.7874 -0.4064)
			(end 0.7874 0.4064)
			(stroke
				(width 0.1524)
				(type default)
			)
			(layer "F.SilkS")
		)
		(fp_line
			(start -0.67945 0.3048)
			(end -0.67945 -0.305054)
			(stroke
				(width 0.1)
				(type default)
			)
			(layer "F.Fab")
		)
		(fp_line
			(start -0.12065 0.3048)
			(end -0.67945 0.3048)
			(stroke
				(width 0.1)
				(type default)
			)
			(layer "F.Fab")
		)
		(fp_line
			(start 0.120396 0.3048)
			(end 0.120396 0.2794)
			(stroke
				(width 0.1)
				(type default)
			)
			(layer "F.Fab")
		)
		(fp_line
			(start 0.67945 0.3048)
			(end 0.120396 0.3048)
			(stroke
				(width 0.1)
				(type default)
			)
			(layer "F.Fab")
		)
		(fp_line
			(start -0.12065 0.2794)
			(end -0.12065 0.3048)
			(stroke
				(width 0.1)
				(type default)
			)
			(layer "F.Fab")
		)
		(fp_line
			(start 0.120396 0.2794)
			(end -0.12065 0.2794)
			(stroke
				(width 0.1)
				(type default)
			)
			(layer "F.Fab")
		)
		(fp_line
			(start -0.12065 -0.2794)
			(end 0.12065 -0.2794)
			(stroke
				(width 0.1)
				(type default)
			)
			(layer "F.Fab")
		)
		(fp_line
			(start 0.12065 -0.2794)
			(end 0.12065 -0.3048)
			(stroke
				(width 0.1)
				(type default)
			)
			(layer "F.Fab")
		)
		(fp_line
			(start 0.12065 -0.3048)
			(end 0.67945 -0.3048)
			(stroke
				(width 0.1)
				(type default)
			)
			(layer "F.Fab")
		)
		(fp_line
			(start 0.67945 -0.3048)
			(end 0.67945 0.3048)
			(stroke
				(width 0.1)
				(type default)
			)
			(layer "F.Fab")
		)
		(fp_line
			(start -0.67945 -0.305054)
			(end -0.12065 -0.305054)
			(stroke
				(width 0.1)
				(type default)
			)
			(layer "F.Fab")
		)
		(fp_line
			(start -0.12065 -0.305054)
			(end -0.12065 -0.2794)
			(stroke
				(width 0.1)
				(type default)
			)
			(layer "F.Fab")
		)
		(pad "1" smd circle
			(at -0.40005 0 270)
			(size 0 0)
			(layers "F.Cu" "F.Mask" "F.Paste")
			(net "JTAG_P0_R_DBREQ_N")
		)
		(pad "2" smd circle
			(at 0.40005 0 270)
			(size 0 0)
			(layers "F.Cu" "F.Mask" "F.Paste")
			(net "JTAG_CPU0_DBREQ_N")
		)
	)
	(footprint ""
		(layer "F.Cu")
		(at 249.896122 -380.66853)
		(property "Reference" "PR2536"
			(at 0 0 0)
			(layer "F.SilkS")
			(hide yes)
			(effects
				(font
					(size 1.27 1.27)
				)
			)
		)
		(property "Value" ""
			(at 0 0 0)
			(layer "F.Fab")
			(effects
				(font
					(size 1.27 1.27)
				)
			)
		)
		(duplicate_pad_numbers_are_jumpers no)
		(fp_line
			(start -0.7874 -0.4064)
			(end 0.7874 -0.4064)
			(stroke
				(width 0.1524)
				(type default)
			)
			(layer "F.SilkS")
		)
		(fp_line
			(start -0.7874 0.4064)
			(end -0.7874 -0.4064)
			(stroke
				(width 0.1524)
				(type default)
			)
			(layer "F.SilkS")
		)
		(fp_line
			(start 0.7874 -0.4064)
			(end 0.7874 0.4064)
			(stroke
				(width 0.1524)
				(type default)
			)
			(layer "F.SilkS")
		)
		(fp_line
			(start 0.7874 0.4064)
			(end -0.7874 0.4064)
			(stroke
				(width 0.1524)
				(type default)
			)
			(layer "F.SilkS")
		)
		(fp_line
			(start -0.67945 -0.305054)
			(end -0.12065 -0.305054)
			(stroke
				(width 0.1)
				(type default)
			)
			(layer "F.Fab")
		)
		(fp_line
			(start -0.67945 0.3048)
			(end -0.67945 -0.305054)
			(stroke
				(width 0.1)
				(type default)
			)
			(layer "F.Fab")
		)
		(fp_line
			(start -0.12065 -0.305054)
			(end -0.12065 -0.2794)
			(stroke
				(width 0.1)
				(type default)
			)
			(layer "F.Fab")
		)
		(fp_line
			(start -0.12065 -0.2794)
			(end 0.12065 -0.2794)
			(stroke
				(width 0.1)
				(type default)
			)
			(layer "F.Fab")
		)
		(fp_line
			(start -0.12065 0.2794)
			(end -0.12065 0.3048)
			(stroke
				(width 0.1)
				(type default)
			)
			(layer "F.Fab")
		)
		(fp_line
			(start -0.12065 0.3048)
			(end -0.67945 0.3048)
			(stroke
				(width 0.1)
				(type default)
			)
			(layer "F.Fab")
		)
		(fp_line
			(start 0.120396 0.2794)
			(end -0.12065 0.2794)
			(stroke
				(width 0.1)
				(type default)
			)
			(layer "F.Fab")
		)
		(fp_line
			(start 0.120396 0.3048)
			(end 0.120396 0.2794)
			(stroke
				(width 0.1)
				(type default)
			)
			(layer "F.Fab")
		)
		(fp_line
			(start 0.12065 -0.3048)
			(end 0.67945 -0.3048)
			(stroke
				(width 0.1)
				(type default)
			)
			(layer "F.Fab")
		)
		(fp_line
			(start 0.12065 -0.2794)
			(end 0.12065 -0.3048)
			(stroke
				(width 0.1)
				(type default)
			)
			(layer "F.Fab")
		)
		(fp_line
			(start 0.67945 -0.3048)
			(end 0.67945 0.3048)
			(stroke
				(width 0.1)
				(type default)
			)
			(layer "F.Fab")
		)
		(fp_line
			(start 0.67945 0.3048)
			(end 0.120396 0.3048)
			(stroke
				(width 0.1)
				(type default)
			)
			(layer "F.Fab")
		)
		(pad "1" smd circle
			(at -0.40005 0)
			(size 0 0)
			(layers "F.Cu" "F.Mask" "F.Paste")
			(net "P12V_HSC_GATE_G6")
		)
		(pad "2" smd circle
			(at 0.40005 0)
			(size 0 0)
			(layers "F.Cu" "F.Mask" "F.Paste")
			(net "P12V_HSC_GATE2")
		)
	)
	(footprint ""
		(layer "F.Cu")
		(at 215.98128 -41.341548)
		(property "Reference" "C1997"
			(at 0 0 0)
			(layer "F.SilkS")
			(hide yes)
			(effects
				(font
					(size 1.27 1.27)
				)
			)
		)
		(property "Value" ""
			(at 0 0 0)
			(layer "F.Fab")
			(effects
				(font
					(size 1.27 1.27)
				)
			)
		)
		(duplicate_pad_numbers_are_jumpers no)
		(fp_line
			(start -0.7874 -0.4064)
			(end 0.7874 -0.4064)
			(stroke
				(width 0.1524)
				(type default)
			)
			(layer "F.SilkS")
		)
		(fp_line
			(start -0.7874 0.4064)
			(end -0.7874 -0.4064)
			(stroke
				(width 0.1524)
				(type default)
			)
			(layer "F.SilkS")
		)
		(fp_line
			(start 0.7874 -0.4064)
			(end 0.7874 0.4064)
			(stroke
				(width 0.1524)
				(type default)
			)
			(layer "F.SilkS")
		)
		(fp_line
			(start 0.7874 0.4064)
			(end -0.7874 0.4064)
			(stroke
				(width 0.1524)
				(type default)
			)
			(layer "F.SilkS")
		)
		(fp_line
			(start -0.67945 -0.305054)
			(end -0.12065 -0.305054)
			(stroke
				(width 0.1)
				(type default)
			)
			(layer "F.Fab")
		)
		(fp_line
			(start -0.67945 0.3048)
			(end -0.67945 -0.305054)
			(stroke
				(width 0.1)
				(type default)
			)
			(layer "F.Fab")
		)
		(fp_line
			(start -0.12065 -0.305054)
			(end -0.12065 -0.2794)
			(stroke
				(width 0.1)
				(type default)
			)
			(layer "F.Fab")
		)
		(fp_line
			(start -0.12065 -0.2794)
			(end 0.12065 -0.2794)
			(stroke
				(width 0.1)
				(type default)
			)
			(layer "F.Fab")
		)
		(fp_line
			(start -0.12065 0.2794)
			(end -0.12065 0.3048)
			(stroke
				(width 0.1)
				(type default)
			)
			(layer "F.Fab")
		)
		(fp_line
			(start -0.12065 0.3048)
			(end -0.67945 0.3048)
			(stroke
				(width 0.1)
				(type default)
			)
			(layer "F.Fab")
		)
		(fp_line
			(start 0.120396 0.2794)
			(end -0.12065 0.2794)
			(stroke
				(width 0.1)
				(type default)
			)
			(layer "F.Fab")
		)
		(fp_line
			(start 0.120396 0.3048)
			(end 0.120396 0.2794)
			(stroke
				(width 0.1)
				(type default)
			)
			(layer "F.Fab")
		)
		(fp_line
			(start 0.12065 -0.3048)
			(end 0.67945 -0.3048)
			(stroke
				(width 0.1)
				(type default)
			)
			(layer "F.Fab")
		)
		(fp_line
			(start 0.12065 -0.2794)
			(end 0.12065 -0.3048)
			(stroke
				(width 0.1)
				(type default)
			)
			(layer "F.Fab")
		)
		(fp_line
			(start 0.67945 -0.3048)
			(end 0.67945 0.3048)
			(stroke
				(width 0.1)
				(type default)
			)
			(layer "F.Fab")
		)
		(fp_line
			(start 0.67945 0.3048)
			(end 0.120396 0.3048)
			(stroke
				(width 0.1)
				(type default)
			)
			(layer "F.Fab")
		)
		(pad "1" smd circle
			(at -0.40005 0)
			(size 0 0)
			(layers "F.Cu" "F.Mask" "F.Paste")
			(net "P3V3_AUX")
		)
		(pad "2" smd circle
			(at 0.40005 0)
			(size 0 0)
			(layers "F.Cu" "F.Mask" "F.Paste")
			(net "GND")
		)
	)
	(footprint ""
		(layer "F.Cu")
		(at 42.672 -171.831)
		(property "Reference" "R565"
			(at 0 0 0)
			(layer "F.SilkS")
			(hide yes)
			(effects
				(font
					(size 1.27 1.27)
				)
			)
		)
		(property "Value" ""
			(at 0 0 0)
			(layer "F.Fab")
			(effects
				(font
					(size 1.27 1.27)
				)
			)
		)
		(duplicate_pad_numbers_are_jumpers no)
		(fp_line
			(start -0.7874 -0.4064)
			(end 0.7874 -0.4064)
			(stroke
				(width 0.1524)
				(type default)
			)
			(layer "F.SilkS")
		)
		(fp_line
			(start -0.7874 0.4064)
			(end -0.7874 -0.4064)
			(stroke
				(width 0.1524)
				(type default)
			)
			(layer "F.SilkS")
		)
		(fp_line
			(start 0.7874 -0.4064)
			(end 0.7874 0.4064)
			(stroke
				(width 0.1524)
				(type default)
			)
			(layer "F.SilkS")
		)
		(fp_line
			(start 0.7874 0.4064)
			(end -0.7874 0.4064)
			(stroke
				(width 0.1524)
				(type default)
			)
			(layer "F.SilkS")
		)
		(fp_line
			(start -0.67945 -0.305054)
			(end -0.12065 -0.305054)
			(stroke
				(width 0.1)
				(type default)
			)
			(layer "F.Fab")
		)
		(fp_line
			(start -0.67945 0.3048)
			(end -0.67945 -0.305054)
			(stroke
				(width 0.1)
				(type default)
			)
			(layer "F.Fab")
		)
		(fp_line
			(start -0.12065 -0.305054)
			(end -0.12065 -0.2794)
			(stroke
				(width 0.1)
				(type default)
			)
			(layer "F.Fab")
		)
		(fp_line
			(start -0.12065 -0.2794)
			(end 0.12065 -0.2794)
			(stroke
				(width 0.1)
				(type default)
			)
			(layer "F.Fab")
		)
		(fp_line
			(start -0.12065 0.2794)
			(end -0.12065 0.3048)
			(stroke
				(width 0.1)
				(type default)
			)
			(layer "F.Fab")
		)
		(fp_line
			(start -0.12065 0.3048)
			(end -0.67945 0.3048)
			(stroke
				(width 0.1)
				(type default)
			)
			(layer "F.Fab")
		)
		(fp_line
			(start 0.120396 0.2794)
			(end -0.12065 0.2794)
			(stroke
				(width 0.1)
				(type default)
			)
			(layer "F.Fab")
		)
		(fp_line
			(start 0.120396 0.3048)
			(end 0.120396 0.2794)
			(stroke
				(width 0.1)
				(type default)
			)
			(layer "F.Fab")
		)
		(fp_line
			(start 0.12065 -0.3048)
			(end 0.67945 -0.3048)
			(stroke
				(width 0.1)
				(type default)
			)
			(layer "F.Fab")
		)
		(fp_line
			(start 0.12065 -0.2794)
			(end 0.12065 -0.3048)
			(stroke
				(width 0.1)
				(type default)
			)
			(layer "F.Fab")
		)
		(fp_line
			(start 0.67945 -0.3048)
			(end 0.67945 0.3048)
			(stroke
				(width 0.1)
				(type default)
			)
			(layer "F.Fab")
		)
		(fp_line
			(start 0.67945 0.3048)
			(end 0.120396 0.3048)
			(stroke
				(width 0.1)
				(type default)
			)
			(layer "F.Fab")
		)
		(pad "1" smd rect
			(at -0.40005 0 180)
			(size 0.4572 0.508)
			(layers "F.Cu" "F.Mask" "F.Paste")
			(net "I3C_0_SPD_DDRAF_CPU1_SDA")
		)
		(pad "2" smd rect
			(at 0.40005 0 180)
			(size 0.4572 0.508)
			(layers "F.Cu" "F.Mask" "F.Paste")
			(net "I3C_0_SPD_DDRAF_CPU1_R_SDA")
		)
	)
	(footprint ""
		(layer "F.Cu")
		(at 114.325908 -256.012442 90)
		(property "Reference" "C3906"
			(at 0 0 90)
			(layer "F.SilkS")
			(hide yes)
			(effects
				(font
					(size 1.27 1.27)
				)
			)
		)
		(property "Value" ""
			(at 0 0 90)
			(layer "F.Fab")
			(effects
				(font
					(size 1.27 1.27)
				)
			)
		)
		(duplicate_pad_numbers_are_jumpers no)
		(fp_line
			(start 0.7874 -0.4064)
			(end 0.7874 0.4064)
			(stroke
				(width 0.1524)
				(type default)
			)
			(layer "F.SilkS")
		)
		(fp_line
			(start -0.7874 -0.4064)
			(end 0.7874 -0.4064)
			(stroke
				(width 0.1524)
				(type default)
			)
			(layer "F.SilkS")
		)
		(fp_line
			(start 0.7874 0.4064)
			(end -0.7874 0.4064)
			(stroke
				(width 0.1524)
				(type default)
			)
			(layer "F.SilkS")
		)
		(fp_line
			(start -0.7874 0.4064)
			(end -0.7874 -0.4064)
			(stroke
				(width 0.1524)
				(type default)
			)
			(layer "F.SilkS")
		)
		(fp_line
			(start -0.12065 -0.305054)
			(end -0.12065 -0.2794)
			(stroke
				(width 0.1)
				(type default)
			)
			(layer "F.Fab")
		)
		(fp_line
			(start -0.67945 -0.305054)
			(end -0.12065 -0.305054)
			(stroke
				(width 0.1)
				(type default)
			)
			(layer "F.Fab")
		)
		(fp_line
			(start 0.67945 -0.3048)
			(end 0.67945 0.3048)
			(stroke
				(width 0.1)
				(type default)
			)
			(layer "F.Fab")
		)
		(fp_line
			(start 0.12065 -0.3048)
			(end 0.67945 -0.3048)
			(stroke
				(width 0.1)
				(type default)
			)
			(layer "F.Fab")
		)
		(fp_line
			(start 0.12065 -0.2794)
			(end 0.12065 -0.3048)
			(stroke
				(width 0.1)
				(type default)
			)
			(layer "F.Fab")
		)
		(fp_line
			(start -0.12065 -0.2794)
			(end 0.12065 -0.2794)
			(stroke
				(width 0.1)
				(type default)
			)
			(layer "F.Fab")
		)
		(fp_line
			(start 0.120396 0.2794)
			(end -0.12065 0.2794)
			(stroke
				(width 0.1)
				(type default)
			)
			(layer "F.Fab")
		)
		(fp_line
			(start -0.12065 0.2794)
			(end -0.12065 0.3048)
			(stroke
				(width 0.1)
				(type default)
			)
			(layer "F.Fab")
		)
		(fp_line
			(start 0.67945 0.3048)
			(end 0.120396 0.3048)
			(stroke
				(width 0.1)
				(type default)
			)
			(layer "F.Fab")
		)
		(fp_line
			(start 0.120396 0.3048)
			(end 0.120396 0.2794)
			(stroke
				(width 0.1)
				(type default)
			)
			(layer "F.Fab")
		)
		(fp_line
			(start -0.12065 0.3048)
			(end -0.67945 0.3048)
			(stroke
				(width 0.1)
				(type default)
			)
			(layer "F.Fab")
		)
		(fp_line
			(start -0.67945 0.3048)
			(end -0.67945 -0.305054)
			(stroke
				(width 0.1)
				(type default)
			)
			(layer "F.Fab")
		)
		(pad "1" smd circle
			(at -0.40005 0 90)
			(size 0 0)
			(layers "F.Cu" "F.Mask" "F.Paste")
			(net "PVDDCR_SOC_P1")
		)
		(pad "2" smd circle
			(at 0.40005 0 90)
			(size 0 0)
			(layers "F.Cu" "F.Mask" "F.Paste")
			(net "GND")
		)
	)
	(footprint ""
		(layer "F.Cu")
		(at 401.507198 -177.172874 90)
		(property "Reference" "PC581_SOP0_1"
			(at 0 0 90)
			(layer "F.SilkS")
			(hide yes)
			(effects
				(font
					(size 1.27 1.27)
				)
			)
		)
		(property "Value" ""
			(at 0 0 90)
			(layer "F.Fab")
			(effects
				(font
					(size 1.27 1.27)
				)
			)
		)
		(duplicate_pad_numbers_are_jumpers no)
		(fp_line
			(start 0.7874 -0.4064)
			(end 0.7874 0.4064)
			(stroke
				(width 0.1524)
				(type default)
			)
			(layer "F.SilkS")
		)
		(fp_line
			(start -0.7874 -0.4064)
			(end 0.7874 -0.4064)
			(stroke
				(width 0.1524)
				(type default)
			)
			(layer "F.SilkS")
		)
		(fp_line
			(start 0.7874 0.4064)
			(end -0.7874 0.4064)
			(stroke
				(width 0.1524)
				(type default)
			)
			(layer "F.SilkS")
		)
		(fp_line
			(start -0.7874 0.4064)
			(end -0.7874 -0.4064)
			(stroke
				(width 0.1524)
				(type default)
			)
			(layer "F.SilkS")
		)
		(fp_line
			(start -0.12065 -0.305054)
			(end -0.12065 -0.2794)
			(stroke
				(width 0.1)
				(type default)
			)
			(layer "F.Fab")
		)
		(fp_line
			(start -0.67945 -0.305054)
			(end -0.12065 -0.305054)
			(stroke
				(width 0.1)
				(type default)
			)
			(layer "F.Fab")
		)
		(fp_line
			(start 0.67945 -0.3048)
			(end 0.67945 0.3048)
			(stroke
				(width 0.1)
				(type default)
			)
			(layer "F.Fab")
		)
		(fp_line
			(start 0.12065 -0.3048)
			(end 0.67945 -0.3048)
			(stroke
				(width 0.1)
				(type default)
			)
			(layer "F.Fab")
		)
		(fp_line
			(start 0.12065 -0.2794)
			(end 0.12065 -0.3048)
			(stroke
				(width 0.1)
				(type default)
			)
			(layer "F.Fab")
		)
		(fp_line
			(start -0.12065 -0.2794)
			(end 0.12065 -0.2794)
			(stroke
				(width 0.1)
				(type default)
			)
			(layer "F.Fab")
		)
		(fp_line
			(start 0.120396 0.2794)
			(end -0.12065 0.2794)
			(stroke
				(width 0.1)
				(type default)
			)
			(layer "F.Fab")
		)
		(fp_line
			(start -0.12065 0.2794)
			(end -0.12065 0.3048)
			(stroke
				(width 0.1)
				(type default)
			)
			(layer "F.Fab")
		)
		(fp_line
			(start 0.67945 0.3048)
			(end 0.120396 0.3048)
			(stroke
				(width 0.1)
				(type default)
			)
			(layer "F.Fab")
		)
		(fp_line
			(start 0.120396 0.3048)
			(end 0.120396 0.2794)
			(stroke
				(width 0.1)
				(type default)
			)
			(layer "F.Fab")
		)
		(fp_line
			(start -0.12065 0.3048)
			(end -0.67945 0.3048)
			(stroke
				(width 0.1)
				(type default)
			)
			(layer "F.Fab")
		)
		(fp_line
			(start -0.67945 0.3048)
			(end -0.67945 -0.305054)
			(stroke
				(width 0.1)
				(type default)
			)
			(layer "F.Fab")
		)
		(pad "1" smd circle
			(at -0.40005 0 90)
			(size 0 0)
			(layers "F.Cu" "F.Mask" "F.Paste")
			(net "PVDDCR_CPU0_P0_PVCC")
		)
		(pad "2" smd circle
			(at 0.40005 0 90)
			(size 0 0)
			(layers "F.Cu" "F.Mask" "F.Paste")
			(net "GND")
		)
	)
	(footprint ""
		(layer "F.Cu")
		(at 30.484064 -80.424274 90)
		(property "Reference" "R1313"
			(at 0 0 90)
			(layer "F.SilkS")
			(hide yes)
			(effects
				(font
					(size 1.27 1.27)
				)
			)
		)
		(property "Value" ""
			(at 0 0 90)
			(layer "F.Fab")
			(effects
				(font
					(size 1.27 1.27)
				)
			)
		)
		(duplicate_pad_numbers_are_jumpers no)
		(fp_line
			(start 0.7874 -0.4064)
			(end 0.7874 0.4064)
			(stroke
				(width 0.1524)
				(type default)
			)
			(layer "F.SilkS")
		)
		(fp_line
			(start -0.7874 -0.4064)
			(end 0.7874 -0.4064)
			(stroke
				(width 0.1524)
				(type default)
			)
			(layer "F.SilkS")
		)
		(fp_line
			(start 0.7874 0.4064)
			(end -0.7874 0.4064)
			(stroke
				(width 0.1524)
				(type default)
			)
			(layer "F.SilkS")
		)
		(fp_line
			(start -0.7874 0.4064)
			(end -0.7874 -0.4064)
			(stroke
				(width 0.1524)
				(type default)
			)
			(layer "F.SilkS")
		)
		(fp_line
			(start -0.12065 -0.305054)
			(end -0.12065 -0.2794)
			(stroke
				(width 0.1)
				(type default)
			)
			(layer "F.Fab")
		)
		(fp_line
			(start -0.67945 -0.305054)
			(end -0.12065 -0.305054)
			(stroke
				(width 0.1)
				(type default)
			)
			(layer "F.Fab")
		)
		(fp_line
			(start 0.67945 -0.3048)
			(end 0.67945 0.3048)
			(stroke
				(width 0.1)
				(type default)
			)
			(layer "F.Fab")
		)
		(fp_line
			(start 0.12065 -0.3048)
			(end 0.67945 -0.3048)
			(stroke
				(width 0.1)
				(type default)
			)
			(layer "F.Fab")
		)
		(fp_line
			(start 0.12065 -0.2794)
			(end 0.12065 -0.3048)
			(stroke
				(width 0.1)
				(type default)
			)
			(layer "F.Fab")
		)
		(fp_line
			(start -0.12065 -0.2794)
			(end 0.12065 -0.2794)
			(stroke
				(width 0.1)
				(type default)
			)
			(layer "F.Fab")
		)
		(fp_line
			(start 0.120396 0.2794)
			(end -0.12065 0.2794)
			(stroke
				(width 0.1)
				(type default)
			)
			(layer "F.Fab")
		)
		(fp_line
			(start -0.12065 0.2794)
			(end -0.12065 0.3048)
			(stroke
				(width 0.1)
				(type default)
			)
			(layer "F.Fab")
		)
		(fp_line
			(start 0.67945 0.3048)
			(end 0.120396 0.3048)
			(stroke
				(width 0.1)
				(type default)
			)
			(layer "F.Fab")
		)
		(fp_line
			(start 0.120396 0.3048)
			(end 0.120396 0.2794)
			(stroke
				(width 0.1)
				(type default)
			)
			(layer "F.Fab")
		)
		(fp_line
			(start -0.12065 0.3048)
			(end -0.67945 0.3048)
			(stroke
				(width 0.1)
				(type default)
			)
			(layer "F.Fab")
		)
		(fp_line
			(start -0.67945 0.3048)
			(end -0.67945 -0.305054)
			(stroke
				(width 0.1)
				(type default)
			)
			(layer "F.Fab")
		)
		(pad "1" smd circle
			(at -0.40005 0 90)
			(size 0 0)
			(layers "F.Cu" "F.Mask" "F.Paste")
			(net "PD_U160_EN_N")
		)
		(pad "2" smd circle
			(at 0.40005 0 90)
			(size 0 0)
			(layers "F.Cu" "F.Mask" "F.Paste")
			(net "GND")
		)
	)
	(footprint ""
		(layer "F.Cu")
		(at 367.991136 -179.50561 -90)
		(property "Reference" "PR495"
			(at 0 0 270)
			(layer "F.SilkS")
			(hide yes)
			(effects
				(font
					(size 1.27 1.27)
				)
			)
		)
		(property "Value" ""
			(at 0 0 270)
			(layer "F.Fab")
			(effects
				(font
					(size 1.27 1.27)
				)
			)
		)
		(duplicate_pad_numbers_are_jumpers no)
		(fp_line
			(start -0.7874 0.4064)
			(end -0.7874 -0.4064)
			(stroke
				(width 0.1524)
				(type default)
			)
			(layer "F.SilkS")
		)
		(fp_line
			(start 0.7874 0.4064)
			(end -0.7874 0.4064)
			(stroke
				(width 0.1524)
				(type default)
			)
			(layer "F.SilkS")
		)
		(fp_line
			(start -0.7874 -0.4064)
			(end 0.7874 -0.4064)
			(stroke
				(width 0.1524)
				(type default)
			)
			(layer "F.SilkS")
		)
		(fp_line
			(start 0.7874 -0.4064)
			(end 0.7874 0.4064)
			(stroke
				(width 0.1524)
				(type default)
			)
			(layer "F.SilkS")
		)
		(fp_line
			(start -0.67945 0.3048)
			(end -0.67945 -0.305054)
			(stroke
				(width 0.1)
				(type default)
			)
			(layer "F.Fab")
		)
		(fp_line
			(start -0.12065 0.3048)
			(end -0.67945 0.3048)
			(stroke
				(width 0.1)
				(type default)
			)
			(layer "F.Fab")
		)
		(fp_line
			(start 0.120396 0.3048)
			(end 0.120396 0.2794)
			(stroke
				(width 0.1)
				(type default)
			)
			(layer "F.Fab")
		)
		(fp_line
			(start 0.67945 0.3048)
			(end 0.120396 0.3048)
			(stroke
				(width 0.1)
				(type default)
			)
			(layer "F.Fab")
		)
		(fp_line
			(start -0.12065 0.2794)
			(end -0.12065 0.3048)
			(stroke
				(width 0.1)
				(type default)
			)
			(layer "F.Fab")
		)
		(fp_line
			(start 0.120396 0.2794)
			(end -0.12065 0.2794)
			(stroke
				(width 0.1)
				(type default)
			)
			(layer "F.Fab")
		)
		(fp_line
			(start -0.12065 -0.2794)
			(end 0.12065 -0.2794)
			(stroke
				(width 0.1)
				(type default)
			)
			(layer "F.Fab")
		)
		(fp_line
			(start 0.12065 -0.2794)
			(end 0.12065 -0.3048)
			(stroke
				(width 0.1)
				(type default)
			)
			(layer "F.Fab")
		)
		(fp_line
			(start 0.12065 -0.3048)
			(end 0.67945 -0.3048)
			(stroke
				(width 0.1)
				(type default)
			)
			(layer "F.Fab")
		)
		(fp_line
			(start 0.67945 -0.3048)
			(end 0.67945 0.3048)
			(stroke
				(width 0.1)
				(type default)
			)
			(layer "F.Fab")
		)
		(fp_line
			(start -0.67945 -0.305054)
			(end -0.12065 -0.305054)
			(stroke
				(width 0.1)
				(type default)
			)
			(layer "F.Fab")
		)
		(fp_line
			(start -0.12065 -0.305054)
			(end -0.12065 -0.2794)
			(stroke
				(width 0.1)
				(type default)
			)
			(layer "F.Fab")
		)
		(pad "1" smd circle
			(at -0.40005 0 270)
			(size 0 0)
			(layers "F.Cu" "F.Mask" "F.Paste")
			(net "SW_PVDDCR_CPU0_P0_SW1_RC")
		)
		(pad "2" smd circle
			(at 0.40005 0 270)
			(size 0 0)
			(layers "F.Cu" "F.Mask" "F.Paste")
			(net "GND")
		)
	)
	(footprint ""
		(layer "F.Cu")
		(at 460.174594 -45.477176 -90)
		(property "Reference" "R6099"
			(at 0 0 270)
			(layer "F.SilkS")
			(hide yes)
			(effects
				(font
					(size 1.27 1.27)
				)
			)
		)
		(property "Value" ""
			(at 0 0 270)
			(layer "F.Fab")
			(effects
				(font
					(size 1.27 1.27)
				)
			)
		)
		(duplicate_pad_numbers_are_jumpers no)
		(fp_line
			(start -0.7874 0.4064)
			(end -0.7874 -0.4064)
			(stroke
				(width 0.1524)
				(type default)
			)
			(layer "F.SilkS")
		)
		(fp_line
			(start 0.7874 0.4064)
			(end -0.7874 0.4064)
			(stroke
				(width 0.1524)
				(type default)
			)
			(layer "F.SilkS")
		)
		(fp_line
			(start -0.7874 -0.4064)
			(end 0.7874 -0.4064)
			(stroke
				(width 0.1524)
				(type default)
			)
			(layer "F.SilkS")
		)
		(fp_line
			(start 0.7874 -0.4064)
			(end 0.7874 0.4064)
			(stroke
				(width 0.1524)
				(type default)
			)
			(layer "F.SilkS")
		)
		(fp_line
			(start -0.67945 0.3048)
			(end -0.67945 -0.305054)
			(stroke
				(width 0.1)
				(type default)
			)
			(layer "F.Fab")
		)
		(fp_line
			(start -0.12065 0.3048)
			(end -0.67945 0.3048)
			(stroke
				(width 0.1)
				(type default)
			)
			(layer "F.Fab")
		)
		(fp_line
			(start 0.120396 0.3048)
			(end 0.120396 0.2794)
			(stroke
				(width 0.1)
				(type default)
			)
			(layer "F.Fab")
		)
		(fp_line
			(start 0.67945 0.3048)
			(end 0.120396 0.3048)
			(stroke
				(width 0.1)
				(type default)
			)
			(layer "F.Fab")
		)
		(fp_line
			(start -0.12065 0.2794)
			(end -0.12065 0.3048)
			(stroke
				(width 0.1)
				(type default)
			)
			(layer "F.Fab")
		)
		(fp_line
			(start 0.120396 0.2794)
			(end -0.12065 0.2794)
			(stroke
				(width 0.1)
				(type default)
			)
			(layer "F.Fab")
		)
		(fp_line
			(start -0.12065 -0.2794)
			(end 0.12065 -0.2794)
			(stroke
				(width 0.1)
				(type default)
			)
			(layer "F.Fab")
		)
		(fp_line
			(start 0.12065 -0.2794)
			(end 0.12065 -0.3048)
			(stroke
				(width 0.1)
				(type default)
			)
			(layer "F.Fab")
		)
		(fp_line
			(start 0.12065 -0.3048)
			(end 0.67945 -0.3048)
			(stroke
				(width 0.1)
				(type default)
			)
			(layer "F.Fab")
		)
		(fp_line
			(start 0.67945 -0.3048)
			(end 0.67945 0.3048)
			(stroke
				(width 0.1)
				(type default)
			)
			(layer "F.Fab")
		)
		(fp_line
			(start -0.67945 -0.305054)
			(end -0.12065 -0.305054)
			(stroke
				(width 0.1)
				(type default)
			)
			(layer "F.Fab")
		)
		(fp_line
			(start -0.12065 -0.305054)
			(end -0.12065 -0.2794)
			(stroke
				(width 0.1)
				(type default)
			)
			(layer "F.Fab")
		)
		(pad "1" smd circle
			(at -0.40005 0 270)
			(size 0 0)
			(layers "F.Cu" "F.Mask" "F.Paste")
			(net "PWRGD_P3V3_AUX_R1")
		)
		(pad "2" smd circle
			(at 0.40005 0 270)
			(size 0 0)
			(layers "F.Cu" "F.Mask" "F.Paste")
			(net "PWRGD_P3V3_AUX")
		)
	)
	(footprint ""
		(layer "F.Cu")
		(at 453.169782 -41.757346 90)
		(property "Reference" "R1136"
			(at 0 0 90)
			(layer "F.SilkS")
			(hide yes)
			(effects
				(font
					(size 1.27 1.27)
				)
			)
		)
		(property "Value" ""
			(at 0 0 90)
			(layer "F.Fab")
			(effects
				(font
					(size 1.27 1.27)
				)
			)
		)
		(duplicate_pad_numbers_are_jumpers no)
		(fp_line
			(start 0.7874 -0.4064)
			(end 0.7874 0.4064)
			(stroke
				(width 0.1524)
				(type default)
			)
			(layer "F.SilkS")
		)
		(fp_line
			(start -0.7874 -0.4064)
			(end 0.7874 -0.4064)
			(stroke
				(width 0.1524)
				(type default)
			)
			(layer "F.SilkS")
		)
		(fp_line
			(start 0.7874 0.4064)
			(end -0.7874 0.4064)
			(stroke
				(width 0.1524)
				(type default)
			)
			(layer "F.SilkS")
		)
		(fp_line
			(start -0.7874 0.4064)
			(end -0.7874 -0.4064)
			(stroke
				(width 0.1524)
				(type default)
			)
			(layer "F.SilkS")
		)
		(fp_line
			(start -0.12065 -0.305054)
			(end -0.12065 -0.2794)
			(stroke
				(width 0.1)
				(type default)
			)
			(layer "F.Fab")
		)
		(fp_line
			(start -0.67945 -0.305054)
			(end -0.12065 -0.305054)
			(stroke
				(width 0.1)
				(type default)
			)
			(layer "F.Fab")
		)
		(fp_line
			(start 0.67945 -0.3048)
			(end 0.67945 0.3048)
			(stroke
				(width 0.1)
				(type default)
			)
			(layer "F.Fab")
		)
		(fp_line
			(start 0.12065 -0.3048)
			(end 0.67945 -0.3048)
			(stroke
				(width 0.1)
				(type default)
			)
			(layer "F.Fab")
		)
		(fp_line
			(start 0.12065 -0.2794)
			(end 0.12065 -0.3048)
			(stroke
				(width 0.1)
				(type default)
			)
			(layer "F.Fab")
		)
		(fp_line
			(start -0.12065 -0.2794)
			(end 0.12065 -0.2794)
			(stroke
				(width 0.1)
				(type default)
			)
			(layer "F.Fab")
		)
		(fp_line
			(start 0.120396 0.2794)
			(end -0.12065 0.2794)
			(stroke
				(width 0.1)
				(type default)
			)
			(layer "F.Fab")
		)
		(fp_line
			(start -0.12065 0.2794)
			(end -0.12065 0.3048)
			(stroke
				(width 0.1)
				(type default)
			)
			(layer "F.Fab")
		)
		(fp_line
			(start 0.67945 0.3048)
			(end 0.120396 0.3048)
			(stroke
				(width 0.1)
				(type default)
			)
			(layer "F.Fab")
		)
		(fp_line
			(start 0.120396 0.3048)
			(end 0.120396 0.2794)
			(stroke
				(width 0.1)
				(type default)
			)
			(layer "F.Fab")
		)
		(fp_line
			(start -0.12065 0.3048)
			(end -0.67945 0.3048)
			(stroke
				(width 0.1)
				(type default)
			)
			(layer "F.Fab")
		)
		(fp_line
			(start -0.67945 0.3048)
			(end -0.67945 -0.305054)
			(stroke
				(width 0.1)
				(type default)
			)
			(layer "F.Fab")
		)
		(pad "1" smd circle
			(at -0.40005 0 90)
			(size 0 0)
			(layers "F.Cu" "F.Mask" "F.Paste")
			(net "HP_LVC3_OCP_V3_1_P12V_PWRGD")
		)
		(pad "2" smd circle
			(at 0.40005 0 90)
			(size 0 0)
			(layers "F.Cu" "F.Mask" "F.Paste")
			(net "P3V3_OCP_EN_1_R")
		)
	)
	(footprint ""
		(layer "F.Cu")
		(at 305.819048 -46.021498)
		(property "Reference" "R3671"
			(at 0 0 0)
			(layer "F.SilkS")
			(hide yes)
			(effects
				(font
					(size 1.27 1.27)
				)
			)
		)
		(property "Value" ""
			(at 0 0 0)
			(layer "F.Fab")
			(effects
				(font
					(size 1.27 1.27)
				)
			)
		)
		(duplicate_pad_numbers_are_jumpers no)
		(fp_line
			(start -0.7874 -0.4064)
			(end 0.7874 -0.4064)
			(stroke
				(width 0.1524)
				(type default)
			)
			(layer "F.SilkS")
		)
		(fp_line
			(start -0.7874 0.4064)
			(end -0.7874 -0.4064)
			(stroke
				(width 0.1524)
				(type default)
			)
			(layer "F.SilkS")
		)
		(fp_line
			(start 0.7874 -0.4064)
			(end 0.7874 0.4064)
			(stroke
				(width 0.1524)
				(type default)
			)
			(layer "F.SilkS")
		)
		(fp_line
			(start 0.7874 0.4064)
			(end -0.7874 0.4064)
			(stroke
				(width 0.1524)
				(type default)
			)
			(layer "F.SilkS")
		)
		(fp_line
			(start -0.67945 -0.305054)
			(end -0.12065 -0.305054)
			(stroke
				(width 0.1)
				(type default)
			)
			(layer "F.Fab")
		)
		(fp_line
			(start -0.67945 0.3048)
			(end -0.67945 -0.305054)
			(stroke
				(width 0.1)
				(type default)
			)
			(layer "F.Fab")
		)
		(fp_line
			(start -0.12065 -0.305054)
			(end -0.12065 -0.2794)
			(stroke
				(width 0.1)
				(type default)
			)
			(layer "F.Fab")
		)
		(fp_line
			(start -0.12065 -0.2794)
			(end 0.12065 -0.2794)
			(stroke
				(width 0.1)
				(type default)
			)
			(layer "F.Fab")
		)
		(fp_line
			(start -0.12065 0.2794)
			(end -0.12065 0.3048)
			(stroke
				(width 0.1)
				(type default)
			)
			(layer "F.Fab")
		)
		(fp_line
			(start -0.12065 0.3048)
			(end -0.67945 0.3048)
			(stroke
				(width 0.1)
				(type default)
			)
			(layer "F.Fab")
		)
		(fp_line
			(start 0.120396 0.2794)
			(end -0.12065 0.2794)
			(stroke
				(width 0.1)
				(type default)
			)
			(layer "F.Fab")
		)
		(fp_line
			(start 0.120396 0.3048)
			(end 0.120396 0.2794)
			(stroke
				(width 0.1)
				(type default)
			)
			(layer "F.Fab")
		)
		(fp_line
			(start 0.12065 -0.3048)
			(end 0.67945 -0.3048)
			(stroke
				(width 0.1)
				(type default)
			)
			(layer "F.Fab")
		)
		(fp_line
			(start 0.12065 -0.2794)
			(end 0.12065 -0.3048)
			(stroke
				(width 0.1)
				(type default)
			)
			(layer "F.Fab")
		)
		(fp_line
			(start 0.67945 -0.3048)
			(end 0.67945 0.3048)
			(stroke
				(width 0.1)
				(type default)
			)
			(layer "F.Fab")
		)
		(fp_line
			(start 0.67945 0.3048)
			(end 0.120396 0.3048)
			(stroke
				(width 0.1)
				(type default)
			)
			(layer "F.Fab")
		)
		(pad "1" smd circle
			(at -0.40005 0)
			(size 0 0)
			(layers "F.Cu" "F.Mask" "F.Paste")
			(net "SMB_SCM_2_R4_SDA")
		)
		(pad "2" smd circle
			(at 0.40005 0)
			(size 0 0)
			(layers "F.Cu" "F.Mask" "F.Paste")
			(net "SMB_SEN_TIC_3V3AUX_SDA")
		)
	)
	(footprint ""
		(layer "F.Cu")
		(at 257.85953 -55.479442)
		(property "Reference" "PR3949"
			(at 0 0 0)
			(layer "F.SilkS")
			(hide yes)
			(effects
				(font
					(size 1.27 1.27)
				)
			)
		)
		(property "Value" ""
			(at 0 0 0)
			(layer "F.Fab")
			(effects
				(font
					(size 1.27 1.27)
				)
			)
		)
		(duplicate_pad_numbers_are_jumpers no)
		(fp_line
			(start -0.7874 -0.4064)
			(end 0.7874 -0.4064)
			(stroke
				(width 0.1524)
				(type default)
			)
			(layer "F.SilkS")
		)
		(fp_line
			(start -0.7874 0.4064)
			(end -0.7874 -0.4064)
			(stroke
				(width 0.1524)
				(type default)
			)
			(layer "F.SilkS")
		)
		(fp_line
			(start 0.7874 -0.4064)
			(end 0.7874 0.4064)
			(stroke
				(width 0.1524)
				(type default)
			)
			(layer "F.SilkS")
		)
		(fp_line
			(start 0.7874 0.4064)
			(end -0.7874 0.4064)
			(stroke
				(width 0.1524)
				(type default)
			)
			(layer "F.SilkS")
		)
		(fp_line
			(start -0.67945 -0.305054)
			(end -0.12065 -0.305054)
			(stroke
				(width 0.1)
				(type default)
			)
			(layer "F.Fab")
		)
		(fp_line
			(start -0.67945 0.3048)
			(end -0.67945 -0.305054)
			(stroke
				(width 0.1)
				(type default)
			)
			(layer "F.Fab")
		)
		(fp_line
			(start -0.12065 -0.305054)
			(end -0.12065 -0.2794)
			(stroke
				(width 0.1)
				(type default)
			)
			(layer "F.Fab")
		)
		(fp_line
			(start -0.12065 -0.2794)
			(end 0.12065 -0.2794)
			(stroke
				(width 0.1)
				(type default)
			)
			(layer "F.Fab")
		)
		(fp_line
			(start -0.12065 0.2794)
			(end -0.12065 0.3048)
			(stroke
				(width 0.1)
				(type default)
			)
			(layer "F.Fab")
		)
		(fp_line
			(start -0.12065 0.3048)
			(end -0.67945 0.3048)
			(stroke
				(width 0.1)
				(type default)
			)
			(layer "F.Fab")
		)
		(fp_line
			(start 0.120396 0.2794)
			(end -0.12065 0.2794)
			(stroke
				(width 0.1)
				(type default)
			)
			(layer "F.Fab")
		)
		(fp_line
			(start 0.120396 0.3048)
			(end 0.120396 0.2794)
			(stroke
				(width 0.1)
				(type default)
			)
			(layer "F.Fab")
		)
		(fp_line
			(start 0.12065 -0.3048)
			(end 0.67945 -0.3048)
			(stroke
				(width 0.1)
				(type default)
			)
			(layer "F.Fab")
		)
		(fp_line
			(start 0.12065 -0.2794)
			(end 0.12065 -0.3048)
			(stroke
				(width 0.1)
				(type default)
			)
			(layer "F.Fab")
		)
		(fp_line
			(start 0.67945 -0.3048)
			(end 0.67945 0.3048)
			(stroke
				(width 0.1)
				(type default)
			)
			(layer "F.Fab")
		)
		(fp_line
			(start 0.67945 0.3048)
			(end 0.120396 0.3048)
			(stroke
				(width 0.1)
				(type default)
			)
			(layer "F.Fab")
		)
		(pad "1" smd circle
			(at -0.40005 0)
			(size 0 0)
			(layers "F.Cu" "F.Mask" "F.Paste")
			(net "P12V_E1S_IMON_0")
		)
		(pad "2" smd circle
			(at 0.40005 0)
			(size 0 0)
			(layers "F.Cu" "F.Mask" "F.Paste")
			(net "GND")
		)
	)
	(footprint ""
		(layer "F.Cu")
		(at 167.11676 -117.301772)
		(property "Reference" "R6137"
			(at 0 0 0)
			(layer "F.SilkS")
			(hide yes)
			(effects
				(font
					(size 1.27 1.27)
				)
			)
		)
		(property "Value" ""
			(at 0 0 0)
			(layer "F.Fab")
			(effects
				(font
					(size 1.27 1.27)
				)
			)
		)
		(duplicate_pad_numbers_are_jumpers no)
		(fp_line
			(start -0.7874 -0.4064)
			(end 0.7874 -0.4064)
			(stroke
				(width 0.1524)
				(type default)
			)
			(layer "F.SilkS")
		)
		(fp_line
			(start -0.7874 0.4064)
			(end -0.7874 -0.4064)
			(stroke
				(width 0.1524)
				(type default)
			)
			(layer "F.SilkS")
		)
		(fp_line
			(start 0.7874 -0.4064)
			(end 0.7874 0.4064)
			(stroke
				(width 0.1524)
				(type default)
			)
			(layer "F.SilkS")
		)
		(fp_line
			(start 0.7874 0.4064)
			(end -0.7874 0.4064)
			(stroke
				(width 0.1524)
				(type default)
			)
			(layer "F.SilkS")
		)
		(fp_line
			(start -0.67945 -0.305054)
			(end -0.12065 -0.305054)
			(stroke
				(width 0.1)
				(type default)
			)
			(layer "F.Fab")
		)
		(fp_line
			(start -0.67945 0.3048)
			(end -0.67945 -0.305054)
			(stroke
				(width 0.1)
				(type default)
			)
			(layer "F.Fab")
		)
		(fp_line
			(start -0.12065 -0.305054)
			(end -0.12065 -0.2794)
			(stroke
				(width 0.1)
				(type default)
			)
			(layer "F.Fab")
		)
		(fp_line
			(start -0.12065 -0.2794)
			(end 0.12065 -0.2794)
			(stroke
				(width 0.1)
				(type default)
			)
			(layer "F.Fab")
		)
		(fp_line
			(start -0.12065 0.2794)
			(end -0.12065 0.3048)
			(stroke
				(width 0.1)
				(type default)
			)
			(layer "F.Fab")
		)
		(fp_line
			(start -0.12065 0.3048)
			(end -0.67945 0.3048)
			(stroke
				(width 0.1)
				(type default)
			)
			(layer "F.Fab")
		)
		(fp_line
			(start 0.120396 0.2794)
			(end -0.12065 0.2794)
			(stroke
				(width 0.1)
				(type default)
			)
			(layer "F.Fab")
		)
		(fp_line
			(start 0.120396 0.3048)
			(end 0.120396 0.2794)
			(stroke
				(width 0.1)
				(type default)
			)
			(layer "F.Fab")
		)
		(fp_line
			(start 0.12065 -0.3048)
			(end 0.67945 -0.3048)
			(stroke
				(width 0.1)
				(type default)
			)
			(layer "F.Fab")
		)
		(fp_line
			(start 0.12065 -0.2794)
			(end 0.12065 -0.3048)
			(stroke
				(width 0.1)
				(type default)
			)
			(layer "F.Fab")
		)
		(fp_line
			(start 0.67945 -0.3048)
			(end 0.67945 0.3048)
			(stroke
				(width 0.1)
				(type default)
			)
			(layer "F.Fab")
		)
		(fp_line
			(start 0.67945 0.3048)
			(end 0.120396 0.3048)
			(stroke
				(width 0.1)
				(type default)
			)
			(layer "F.Fab")
		)
		(pad "1" smd circle
			(at -0.40005 0)
			(size 0 0)
			(layers "F.Cu" "F.Mask" "F.Paste")
			(net "P3V3_AUX")
		)
		(pad "2" smd circle
			(at 0.40005 0)
			(size 0 0)
			(layers "F.Cu" "F.Mask" "F.Paste")
			(net "FM_BOARD_BMC_SKU_ID3")
		)
	)
	(footprint ""
		(layer "F.Cu")
		(at 200.854056 -340.655148 180)
		(property "Reference" "PU55"
			(at -5.548884 -2.521712 90)
			(unlocked yes)
			(layer "F.SilkS")
			(effects
				(font
					(size 0.7874 0.5842)
					(thickness 0.1524)
				)
				(justify left)
			)
		)
		(property "Value" ""
			(at 0 0 180)
			(layer "F.Fab")
			(effects
				(font
					(size 1.27 1.27)
				)
			)
		)
		(duplicate_pad_numbers_are_jumpers no)
		(fp_line
			(start 1.549908 -1.9812)
			(end 1.549908 -2.050034)
			(stroke
				(width 0.1524)
				(type default)
			)
			(layer "F.SilkS")
		)
		(fp_line
			(start 1.549908 -2.050034)
			(end 0.5842 -2.050034)
			(stroke
				(width 0.1524)
				(type default)
			)
			(layer "F.SilkS")
		)
		(fp_line
			(start 0 2.050034)
			(end 1.549908 2.050034)
			(stroke
				(width 0.1524)
				(type default)
			)
			(layer "F.SilkS")
		)
		(fp_line
			(start -0.5842 -2.050034)
			(end -1.549908 -2.050034)
			(stroke
				(width 0.1524)
				(type default)
			)
			(layer "F.SilkS")
		)
		(fp_line
			(start -1.549908 2.050034)
			(end -0.5842 2.050034)
			(stroke
				(width 0.1524)
				(type default)
			)
			(layer "F.SilkS")
		)
		(fp_line
			(start -1.549908 1.9812)
			(end -1.549908 2.050034)
			(stroke
				(width 0.1524)
				(type default)
			)
			(layer "F.SilkS")
		)
		(fp_line
			(start -1.549908 -2.050034)
			(end -1.549908 -1.9812)
			(stroke
				(width 0.1524)
				(type default)
			)
			(layer "F.SilkS")
		)
		(fp_poly
			(pts
				(xy -1.9304 -1.700022) (xy -2.641854 -1.344168) (xy -2.641854 -2.055876)
			)
			(stroke
				(width 0)
				(type default)
			)
			(fill yes)
			(layer "F.SilkS")
		)
		(fp_line
			(start 1.549908 2.050034)
			(end 1.549908 -2.050034)
			(stroke
				(width 0.1)
				(type default)
			)
			(layer "F.Fab")
		)
		(fp_line
			(start 1.549908 -2.050034)
			(end -1.549908 -2.050034)
			(stroke
				(width 0.1)
				(type default)
			)
			(layer "F.Fab")
		)
		(fp_line
			(start -1.549908 2.050034)
			(end 1.549908 2.050034)
			(stroke
				(width 0.1)
				(type default)
			)
			(layer "F.Fab")
		)
		(fp_line
			(start -1.549908 -2.050034)
			(end -1.549908 2.050034)
			(stroke
				(width 0.1)
				(type default)
			)
			(layer "F.Fab")
		)
		(fp_poly
			(pts
				(xy -2.9464 -2.208022) (xy -2.9464 -1.192022) (xy -1.9304 -1.700022)
			)
			(stroke
				(width 0)
				(type default)
			)
			(fill yes)
			(layer "F.Fab")
		)
		(pad "1" smd circle
			(at -1.35001 -1.700022 180)
			(size 0 0)
			(layers "F.Cu" "F.Mask" "F.Paste")
			(net "SW_PVDD_33_S5_BST")
		)
		(pad "2" smd rect
			(at -1.400048 -1.199896 270)
			(size 0.1778 0.8128)
			(layers "F.Cu" "F.Mask" "F.Paste")
			(net "GND")
		)
		(pad "3" smd rect
			(at -1.400048 -0.8001 270)
			(size 0.1778 0.8128)
			(layers "F.Cu" "F.Mask" "F.Paste")
			(net "PVDD_33_S5_CS")
		)
		(pad "4" smd rect
			(at -1.400048 -0.40005 270)
			(size 0.1778 0.8128)
			(layers "F.Cu" "F.Mask" "F.Paste")
			(net "PVDD_33_S5_MODE")
		)
		(pad "5" smd rect
			(at -1.400048 0 270)
			(size 0.1778 0.8128)
			(layers "F.Cu" "F.Mask" "F.Paste")
			(net "PVDD_33_S5_REF")
		)
		(pad "6" smd rect
			(at -1.400048 0.40005 270)
			(size 0.1778 0.8128)
			(layers "F.Cu" "F.Mask" "F.Paste")
			(net "GND")
		)
		(pad "7" smd rect
			(at -1.400048 0.8001 270)
			(size 0.1778 0.8128)
			(layers "F.Cu" "F.Mask" "F.Paste")
			(net "PVDD_33_S5_FB")
		)
		(pad "8" smd rect
			(at -1.400048 1.199896 270)
			(size 0.1778 0.8128)
			(layers "F.Cu" "F.Mask" "F.Paste")
			(net "PVDD33_S5_EN")
		)
		(pad "9" smd rect
			(at -1.400048 1.700022 270)
			(size 0.3048 0.8128)
			(layers "F.Cu" "F.Mask" "F.Paste")
			(net "PWRGD_PVDD33_S5")
		)
		(pad "10" smd rect
			(at -0.299974 1.299972 180)
			(size 0.3048 2.0066)
			(layers "F.Cu" "F.Mask" "F.Paste")
			(net "SW_P12V_AUX_PVDD_33_S5_FLT")
		)
		(pad "11_18" smd circle
			(at 1.175004 0.275082 180)
			(size 0 0)
			(layers "F.Cu" "F.Mask" "F.Paste")
			(net "GND")
		)
		(pad "19" smd rect
			(at 1.400048 -1.700022 90)
			(size 0.3048 0.8128)
			(layers "F.Cu" "F.Mask" "F.Paste")
			(net "PVDD_33_S5_VCC")
		)
		(pad "20" smd rect
			(at 0.299974 -1.299972 180)
			(size 0.3048 2.0066)
			(layers "F.Cu" "F.Mask" "F.Paste")
			(net "SW_PVDD_33_S5_SW")
		)
		(pad "21" smd rect
			(at -0.299974 -1.299972 180)
			(size 0.3048 2.0066)
			(layers "F.Cu" "F.Mask" "F.Paste")
			(net "SW_P12V_AUX_PVDD_33_S5_FLT")
		)
	)
	(footprint ""
		(layer "F.Cu")
		(at 123.767342 -16.50111 180)
		(property "Reference" "R4200"
			(at 0 0 180)
			(layer "F.SilkS")
			(hide yes)
			(effects
				(font
					(size 1.27 1.27)
				)
			)
		)
		(property "Value" ""
			(at 0 0 180)
			(layer "F.Fab")
			(effects
				(font
					(size 1.27 1.27)
				)
			)
		)
		(duplicate_pad_numbers_are_jumpers no)
		(fp_line
			(start 0.7874 0.4064)
			(end -0.7874 0.4064)
			(stroke
				(width 0.1524)
				(type default)
			)
			(layer "F.SilkS")
		)
		(fp_line
			(start 0.7874 -0.4064)
			(end 0.7874 0.4064)
			(stroke
				(width 0.1524)
				(type default)
			)
			(layer "F.SilkS")
		)
		(fp_line
			(start -0.7874 0.4064)
			(end -0.7874 -0.4064)
			(stroke
				(width 0.1524)
				(type default)
			)
			(layer "F.SilkS")
		)
		(fp_line
			(start -0.7874 -0.4064)
			(end 0.7874 -0.4064)
			(stroke
				(width 0.1524)
				(type default)
			)
			(layer "F.SilkS")
		)
		(fp_line
			(start 0.67945 0.3048)
			(end 0.120396 0.3048)
			(stroke
				(width 0.1)
				(type default)
			)
			(layer "F.Fab")
		)
		(fp_line
			(start 0.67945 -0.3048)
			(end 0.67945 0.3048)
			(stroke
				(width 0.1)
				(type default)
			)
			(layer "F.Fab")
		)
		(fp_line
			(start 0.12065 -0.2794)
			(end 0.12065 -0.3048)
			(stroke
				(width 0.1)
				(type default)
			)
			(layer "F.Fab")
		)
		(fp_line
			(start 0.12065 -0.3048)
			(end 0.67945 -0.3048)
			(stroke
				(width 0.1)
				(type default)
			)
			(layer "F.Fab")
		)
		(fp_line
			(start 0.120396 0.3048)
			(end 0.120396 0.2794)
			(stroke
				(width 0.1)
				(type default)
			)
			(layer "F.Fab")
		)
		(fp_line
			(start 0.120396 0.2794)
			(end -0.12065 0.2794)
			(stroke
				(width 0.1)
				(type default)
			)
			(layer "F.Fab")
		)
		(fp_line
			(start -0.12065 0.3048)
			(end -0.67945 0.3048)
			(stroke
				(width 0.1)
				(type default)
			)
			(layer "F.Fab")
		)
		(fp_line
			(start -0.12065 0.2794)
			(end -0.12065 0.3048)
			(stroke
				(width 0.1)
				(type default)
			)
			(layer "F.Fab")
		)
		(fp_line
			(start -0.12065 -0.2794)
			(end 0.12065 -0.2794)
			(stroke
				(width 0.1)
				(type default)
			)
			(layer "F.Fab")
		)
		(fp_line
			(start -0.12065 -0.305054)
			(end -0.12065 -0.2794)
			(stroke
				(width 0.1)
				(type default)
			)
			(layer "F.Fab")
		)
		(fp_line
			(start -0.67945 0.3048)
			(end -0.67945 -0.305054)
			(stroke
				(width 0.1)
				(type default)
			)
			(layer "F.Fab")
		)
		(fp_line
			(start -0.67945 -0.305054)
			(end -0.12065 -0.305054)
			(stroke
				(width 0.1)
				(type default)
			)
			(layer "F.Fab")
		)
		(pad "1" smd circle
			(at -0.40005 0 180)
			(size 0 0)
			(layers "F.Cu" "F.Mask" "F.Paste")
			(net "P3V3_AUX")
		)
		(pad "2" smd circle
			(at 0.40005 0 180)
			(size 0 0)
			(layers "F.Cu" "F.Mask" "F.Paste")
			(net "U273_3_ADD0")
		)
	)
	(footprint ""
		(layer "F.Cu")
		(at 384.113278 -143.250158 180)
		(property "Reference" "R8313"
			(at 0 0 180)
			(layer "F.SilkS")
			(hide yes)
			(effects
				(font
					(size 1.27 1.27)
				)
			)
		)
		(property "Value" ""
			(at 0 0 180)
			(layer "F.Fab")
			(effects
				(font
					(size 1.27 1.27)
				)
			)
		)
		(duplicate_pad_numbers_are_jumpers no)
		(fp_line
			(start 0.7874 0.4064)
			(end -0.7874 0.4064)
			(stroke
				(width 0.1524)
				(type default)
			)
			(layer "F.SilkS")
		)
		(fp_line
			(start 0.7874 -0.4064)
			(end 0.7874 0.4064)
			(stroke
				(width 0.1524)
				(type default)
			)
			(layer "F.SilkS")
		)
		(fp_line
			(start -0.7874 0.4064)
			(end -0.7874 -0.4064)
			(stroke
				(width 0.1524)
				(type default)
			)
			(layer "F.SilkS")
		)
		(fp_line
			(start -0.7874 -0.4064)
			(end 0.7874 -0.4064)
			(stroke
				(width 0.1524)
				(type default)
			)
			(layer "F.SilkS")
		)
		(fp_line
			(start 0.67945 0.3048)
			(end 0.120396 0.3048)
			(stroke
				(width 0.1)
				(type default)
			)
			(layer "F.Fab")
		)
		(fp_line
			(start 0.67945 -0.3048)
			(end 0.67945 0.3048)
			(stroke
				(width 0.1)
				(type default)
			)
			(layer "F.Fab")
		)
		(fp_line
			(start 0.12065 -0.2794)
			(end 0.12065 -0.3048)
			(stroke
				(width 0.1)
				(type default)
			)
			(layer "F.Fab")
		)
		(fp_line
			(start 0.12065 -0.3048)
			(end 0.67945 -0.3048)
			(stroke
				(width 0.1)
				(type default)
			)
			(layer "F.Fab")
		)
		(fp_line
			(start 0.120396 0.3048)
			(end 0.120396 0.2794)
			(stroke
				(width 0.1)
				(type default)
			)
			(layer "F.Fab")
		)
		(fp_line
			(start 0.120396 0.2794)
			(end -0.12065 0.2794)
			(stroke
				(width 0.1)
				(type default)
			)
			(layer "F.Fab")
		)
		(fp_line
			(start -0.12065 0.3048)
			(end -0.67945 0.3048)
			(stroke
				(width 0.1)
				(type default)
			)
			(layer "F.Fab")
		)
		(fp_line
			(start -0.12065 0.2794)
			(end -0.12065 0.3048)
			(stroke
				(width 0.1)
				(type default)
			)
			(layer "F.Fab")
		)
		(fp_line
			(start -0.12065 -0.2794)
			(end 0.12065 -0.2794)
			(stroke
				(width 0.1)
				(type default)
			)
			(layer "F.Fab")
		)
		(fp_line
			(start -0.12065 -0.305054)
			(end -0.12065 -0.2794)
			(stroke
				(width 0.1)
				(type default)
			)
			(layer "F.Fab")
		)
		(fp_line
			(start -0.67945 0.3048)
			(end -0.67945 -0.305054)
			(stroke
				(width 0.1)
				(type default)
			)
			(layer "F.Fab")
		)
		(fp_line
			(start -0.67945 -0.305054)
			(end -0.12065 -0.305054)
			(stroke
				(width 0.1)
				(type default)
			)
			(layer "F.Fab")
		)
		(pad "1" smd circle
			(at -0.40005 0 180)
			(size 0 0)
			(layers "F.Cu" "F.Mask" "F.Paste")
			(net "PVDD18_S5_P0")
		)
		(pad "2" smd circle
			(at 0.40005 0 180)
			(size 0 0)
			(layers "F.Cu" "F.Mask" "F.Paste")
			(net "PVDDCR_CPU0_P0_OCP_N_R")
		)
	)
	(footprint ""
		(layer "F.Cu")
		(at 34.633662 -419.249098 90)
		(property "Reference" "R3289"
			(at 0 0 90)
			(layer "F.SilkS")
			(hide yes)
			(effects
				(font
					(size 1.27 1.27)
				)
			)
		)
		(property "Value" ""
			(at 0 0 90)
			(layer "F.Fab")
			(effects
				(font
					(size 1.27 1.27)
				)
			)
		)
		(duplicate_pad_numbers_are_jumpers no)
		(fp_line
			(start 0.7874 -0.4064)
			(end 0.7874 0.4064)
			(stroke
				(width 0.1524)
				(type default)
			)
			(layer "F.SilkS")
		)
		(fp_line
			(start -0.7874 -0.4064)
			(end 0.7874 -0.4064)
			(stroke
				(width 0.1524)
				(type default)
			)
			(layer "F.SilkS")
		)
		(fp_line
			(start 0.7874 0.4064)
			(end -0.7874 0.4064)
			(stroke
				(width 0.1524)
				(type default)
			)
			(layer "F.SilkS")
		)
		(fp_line
			(start -0.7874 0.4064)
			(end -0.7874 -0.4064)
			(stroke
				(width 0.1524)
				(type default)
			)
			(layer "F.SilkS")
		)
		(fp_line
			(start -0.12065 -0.305054)
			(end -0.12065 -0.2794)
			(stroke
				(width 0.1)
				(type default)
			)
			(layer "F.Fab")
		)
		(fp_line
			(start -0.67945 -0.305054)
			(end -0.12065 -0.305054)
			(stroke
				(width 0.1)
				(type default)
			)
			(layer "F.Fab")
		)
		(fp_line
			(start 0.67945 -0.3048)
			(end 0.67945 0.3048)
			(stroke
				(width 0.1)
				(type default)
			)
			(layer "F.Fab")
		)
		(fp_line
			(start 0.12065 -0.3048)
			(end 0.67945 -0.3048)
			(stroke
				(width 0.1)
				(type default)
			)
			(layer "F.Fab")
		)
		(fp_line
			(start 0.12065 -0.2794)
			(end 0.12065 -0.3048)
			(stroke
				(width 0.1)
				(type default)
			)
			(layer "F.Fab")
		)
		(fp_line
			(start -0.12065 -0.2794)
			(end 0.12065 -0.2794)
			(stroke
				(width 0.1)
				(type default)
			)
			(layer "F.Fab")
		)
		(fp_line
			(start 0.120396 0.2794)
			(end -0.12065 0.2794)
			(stroke
				(width 0.1)
				(type default)
			)
			(layer "F.Fab")
		)
		(fp_line
			(start -0.12065 0.2794)
			(end -0.12065 0.3048)
			(stroke
				(width 0.1)
				(type default)
			)
			(layer "F.Fab")
		)
		(fp_line
			(start 0.67945 0.3048)
			(end 0.120396 0.3048)
			(stroke
				(width 0.1)
				(type default)
			)
			(layer "F.Fab")
		)
		(fp_line
			(start 0.120396 0.3048)
			(end 0.120396 0.2794)
			(stroke
				(width 0.1)
				(type default)
			)
			(layer "F.Fab")
		)
		(fp_line
			(start -0.12065 0.3048)
			(end -0.67945 0.3048)
			(stroke
				(width 0.1)
				(type default)
			)
			(layer "F.Fab")
		)
		(fp_line
			(start -0.67945 0.3048)
			(end -0.67945 -0.305054)
			(stroke
				(width 0.1)
				(type default)
			)
			(layer "F.Fab")
		)
		(pad "1" smd circle
			(at -0.40005 0 90)
			(size 0 0)
			(layers "F.Cu" "F.Mask" "F.Paste")
			(net "P3V3_AUX")
		)
		(pad "2" smd circle
			(at 0.40005 0 90)
			(size 0 0)
			(layers "F.Cu" "F.Mask" "F.Paste")
			(net "FM_P2E_SWA")
		)
	)
	(footprint ""
		(layer "F.Cu")
		(at 91.770454 -335.027524 -90)
		(property "Reference" "PC423_C1P1_5"
			(at 0 0 270)
			(layer "F.SilkS")
			(hide yes)
			(effects
				(font
					(size 1.27 1.27)
				)
			)
		)
		(property "Value" ""
			(at 0 0 270)
			(layer "F.Fab")
			(effects
				(font
					(size 1.27 1.27)
				)
			)
		)
		(duplicate_pad_numbers_are_jumpers no)
		(fp_line
			(start -0.7874 0.4064)
			(end -0.7874 -0.4064)
			(stroke
				(width 0.1524)
				(type default)
			)
			(layer "F.SilkS")
		)
		(fp_line
			(start 0.7874 0.4064)
			(end -0.7874 0.4064)
			(stroke
				(width 0.1524)
				(type default)
			)
			(layer "F.SilkS")
		)
		(fp_line
			(start -0.7874 -0.4064)
			(end 0.7874 -0.4064)
			(stroke
				(width 0.1524)
				(type default)
			)
			(layer "F.SilkS")
		)
		(fp_line
			(start 0.7874 -0.4064)
			(end 0.7874 0.4064)
			(stroke
				(width 0.1524)
				(type default)
			)
			(layer "F.SilkS")
		)
		(fp_line
			(start -0.67945 0.3048)
			(end -0.67945 -0.305054)
			(stroke
				(width 0.1)
				(type default)
			)
			(layer "F.Fab")
		)
		(fp_line
			(start -0.12065 0.3048)
			(end -0.67945 0.3048)
			(stroke
				(width 0.1)
				(type default)
			)
			(layer "F.Fab")
		)
		(fp_line
			(start 0.120396 0.3048)
			(end 0.120396 0.2794)
			(stroke
				(width 0.1)
				(type default)
			)
			(layer "F.Fab")
		)
		(fp_line
			(start 0.67945 0.3048)
			(end 0.120396 0.3048)
			(stroke
				(width 0.1)
				(type default)
			)
			(layer "F.Fab")
		)
		(fp_line
			(start -0.12065 0.2794)
			(end -0.12065 0.3048)
			(stroke
				(width 0.1)
				(type default)
			)
			(layer "F.Fab")
		)
		(fp_line
			(start 0.120396 0.2794)
			(end -0.12065 0.2794)
			(stroke
				(width 0.1)
				(type default)
			)
			(layer "F.Fab")
		)
		(fp_line
			(start -0.12065 -0.2794)
			(end 0.12065 -0.2794)
			(stroke
				(width 0.1)
				(type default)
			)
			(layer "F.Fab")
		)
		(fp_line
			(start 0.12065 -0.2794)
			(end 0.12065 -0.3048)
			(stroke
				(width 0.1)
				(type default)
			)
			(layer "F.Fab")
		)
		(fp_line
			(start 0.12065 -0.3048)
			(end 0.67945 -0.3048)
			(stroke
				(width 0.1)
				(type default)
			)
			(layer "F.Fab")
		)
		(fp_line
			(start 0.67945 -0.3048)
			(end 0.67945 0.3048)
			(stroke
				(width 0.1)
				(type default)
			)
			(layer "F.Fab")
		)
		(fp_line
			(start -0.67945 -0.305054)
			(end -0.12065 -0.305054)
			(stroke
				(width 0.1)
				(type default)
			)
			(layer "F.Fab")
		)
		(fp_line
			(start -0.12065 -0.305054)
			(end -0.12065 -0.2794)
			(stroke
				(width 0.1)
				(type default)
			)
			(layer "F.Fab")
		)
		(pad "1" smd circle
			(at -0.40005 0 270)
			(size 0 0)
			(layers "F.Cu" "F.Mask" "F.Paste")
			(net "PVDDCR_CPU1_P1_PVCC")
		)
		(pad "2" smd circle
			(at 0.40005 0 270)
			(size 0 0)
			(layers "F.Cu" "F.Mask" "F.Paste")
			(net "GND")
		)
	)
	(footprint ""
		(layer "F.Cu")
		(at 201.041 -128.778)
		(property "Reference" "R8021"
			(at 0 0 0)
			(layer "F.SilkS")
			(hide yes)
			(effects
				(font
					(size 1.27 1.27)
				)
			)
		)
		(property "Value" ""
			(at 0 0 0)
			(layer "F.Fab")
			(effects
				(font
					(size 1.27 1.27)
				)
			)
		)
		(duplicate_pad_numbers_are_jumpers no)
		(fp_line
			(start -0.7874 -0.4064)
			(end 0.7874 -0.4064)
			(stroke
				(width 0.1524)
				(type default)
			)
			(layer "F.SilkS")
		)
		(fp_line
			(start -0.7874 0.4064)
			(end -0.7874 -0.4064)
			(stroke
				(width 0.1524)
				(type default)
			)
			(layer "F.SilkS")
		)
		(fp_line
			(start 0.7874 -0.4064)
			(end 0.7874 0.4064)
			(stroke
				(width 0.1524)
				(type default)
			)
			(layer "F.SilkS")
		)
		(fp_line
			(start 0.7874 0.4064)
			(end -0.7874 0.4064)
			(stroke
				(width 0.1524)
				(type default)
			)
			(layer "F.SilkS")
		)
		(fp_line
			(start -0.67945 -0.305054)
			(end -0.12065 -0.305054)
			(stroke
				(width 0.1)
				(type default)
			)
			(layer "F.Fab")
		)
		(fp_line
			(start -0.67945 0.3048)
			(end -0.67945 -0.305054)
			(stroke
				(width 0.1)
				(type default)
			)
			(layer "F.Fab")
		)
		(fp_line
			(start -0.12065 -0.305054)
			(end -0.12065 -0.2794)
			(stroke
				(width 0.1)
				(type default)
			)
			(layer "F.Fab")
		)
		(fp_line
			(start -0.12065 -0.2794)
			(end 0.12065 -0.2794)
			(stroke
				(width 0.1)
				(type default)
			)
			(layer "F.Fab")
		)
		(fp_line
			(start -0.12065 0.2794)
			(end -0.12065 0.3048)
			(stroke
				(width 0.1)
				(type default)
			)
			(layer "F.Fab")
		)
		(fp_line
			(start -0.12065 0.3048)
			(end -0.67945 0.3048)
			(stroke
				(width 0.1)
				(type default)
			)
			(layer "F.Fab")
		)
		(fp_line
			(start 0.120396 0.2794)
			(end -0.12065 0.2794)
			(stroke
				(width 0.1)
				(type default)
			)
			(layer "F.Fab")
		)
		(fp_line
			(start 0.120396 0.3048)
			(end 0.120396 0.2794)
			(stroke
				(width 0.1)
				(type default)
			)
			(layer "F.Fab")
		)
		(fp_line
			(start 0.12065 -0.3048)
			(end 0.67945 -0.3048)
			(stroke
				(width 0.1)
				(type default)
			)
			(layer "F.Fab")
		)
		(fp_line
			(start 0.12065 -0.2794)
			(end 0.12065 -0.3048)
			(stroke
				(width 0.1)
				(type default)
			)
			(layer "F.Fab")
		)
		(fp_line
			(start 0.67945 -0.3048)
			(end 0.67945 0.3048)
			(stroke
				(width 0.1)
				(type default)
			)
			(layer "F.Fab")
		)
		(fp_line
			(start 0.67945 0.3048)
			(end 0.120396 0.3048)
			(stroke
				(width 0.1)
				(type default)
			)
			(layer "F.Fab")
		)
		(pad "1" smd circle
			(at -0.40005 0)
			(size 0 0)
			(layers "F.Cu" "F.Mask" "F.Paste")
			(net "FM_JTAG_BMC_OE")
		)
		(pad "2" smd circle
			(at 0.40005 0)
			(size 0 0)
			(layers "F.Cu" "F.Mask" "F.Paste")
			(net "FM_JTAG_BMC_R_OE")
		)
	)
	(footprint ""
		(layer "F.Cu")
		(at 191.897 -100.294948 90)
		(property "Reference" "R264"
			(at 0 0 90)
			(layer "F.SilkS")
			(hide yes)
			(effects
				(font
					(size 1.27 1.27)
				)
			)
		)
		(property "Value" ""
			(at 0 0 90)
			(layer "F.Fab")
			(effects
				(font
					(size 1.27 1.27)
				)
			)
		)
		(duplicate_pad_numbers_are_jumpers no)
		(fp_line
			(start 0.7874 -0.4064)
			(end 0.7874 0.4064)
			(stroke
				(width 0.1524)
				(type default)
			)
			(layer "F.SilkS")
		)
		(fp_line
			(start -0.7874 -0.4064)
			(end 0.7874 -0.4064)
			(stroke
				(width 0.1524)
				(type default)
			)
			(layer "F.SilkS")
		)
		(fp_line
			(start 0.7874 0.4064)
			(end -0.7874 0.4064)
			(stroke
				(width 0.1524)
				(type default)
			)
			(layer "F.SilkS")
		)
		(fp_line
			(start -0.7874 0.4064)
			(end -0.7874 -0.4064)
			(stroke
				(width 0.1524)
				(type default)
			)
			(layer "F.SilkS")
		)
		(fp_line
			(start -0.12065 -0.305054)
			(end -0.12065 -0.2794)
			(stroke
				(width 0.1)
				(type default)
			)
			(layer "F.Fab")
		)
		(fp_line
			(start -0.67945 -0.305054)
			(end -0.12065 -0.305054)
			(stroke
				(width 0.1)
				(type default)
			)
			(layer "F.Fab")
		)
		(fp_line
			(start 0.67945 -0.3048)
			(end 0.67945 0.3048)
			(stroke
				(width 0.1)
				(type default)
			)
			(layer "F.Fab")
		)
		(fp_line
			(start 0.12065 -0.3048)
			(end 0.67945 -0.3048)
			(stroke
				(width 0.1)
				(type default)
			)
			(layer "F.Fab")
		)
		(fp_line
			(start 0.12065 -0.2794)
			(end 0.12065 -0.3048)
			(stroke
				(width 0.1)
				(type default)
			)
			(layer "F.Fab")
		)
		(fp_line
			(start -0.12065 -0.2794)
			(end 0.12065 -0.2794)
			(stroke
				(width 0.1)
				(type default)
			)
			(layer "F.Fab")
		)
		(fp_line
			(start 0.120396 0.2794)
			(end -0.12065 0.2794)
			(stroke
				(width 0.1)
				(type default)
			)
			(layer "F.Fab")
		)
		(fp_line
			(start -0.12065 0.2794)
			(end -0.12065 0.3048)
			(stroke
				(width 0.1)
				(type default)
			)
			(layer "F.Fab")
		)
		(fp_line
			(start 0.67945 0.3048)
			(end 0.120396 0.3048)
			(stroke
				(width 0.1)
				(type default)
			)
			(layer "F.Fab")
		)
		(fp_line
			(start 0.120396 0.3048)
			(end 0.120396 0.2794)
			(stroke
				(width 0.1)
				(type default)
			)
			(layer "F.Fab")
		)
		(fp_line
			(start -0.12065 0.3048)
			(end -0.67945 0.3048)
			(stroke
				(width 0.1)
				(type default)
			)
			(layer "F.Fab")
		)
		(fp_line
			(start -0.67945 0.3048)
			(end -0.67945 -0.305054)
			(stroke
				(width 0.1)
				(type default)
			)
			(layer "F.Fab")
		)
		(pad "1" smd circle
			(at -0.40005 0 90)
			(size 0 0)
			(layers "F.Cu" "F.Mask" "F.Paste")
			(net "CPU1_CORETYPE2")
		)
		(pad "2" smd circle
			(at 0.40005 0 90)
			(size 0 0)
			(layers "F.Cu" "F.Mask" "F.Paste")
			(net "FM_CPU1_CORETYPE2")
		)
	)
	(footprint ""
		(layer "F.Cu")
		(at 229.87 -283.917898 180)
		(property "Reference" "PC6520"
			(at 0 0 180)
			(layer "F.SilkS")
			(hide yes)
			(effects
				(font
					(size 1.27 1.27)
				)
			)
		)
		(property "Value" ""
			(at 0 0 180)
			(layer "F.Fab")
			(effects
				(font
					(size 1.27 1.27)
				)
			)
		)
		(duplicate_pad_numbers_are_jumpers no)
		(fp_line
			(start 1.524 0.762)
			(end -1.524 0.762)
			(stroke
				(width 0.1524)
				(type default)
			)
			(layer "F.SilkS")
		)
		(fp_line
			(start 1.524 -0.762)
			(end 1.524 0.762)
			(stroke
				(width 0.1524)
				(type default)
			)
			(layer "F.SilkS")
		)
		(fp_line
			(start -1.524 0.762)
			(end -1.524 -0.762)
			(stroke
				(width 0.1524)
				(type default)
			)
			(layer "F.SilkS")
		)
		(fp_line
			(start -1.524 -0.762)
			(end 1.524 -0.762)
			(stroke
				(width 0.1524)
				(type default)
			)
			(layer "F.SilkS")
		)
		(fp_line
			(start 1.1049 0.724916)
			(end 1.1049 -0.724916)
			(stroke
				(width 0.1)
				(type default)
			)
			(layer "F.Fab")
		)
		(fp_line
			(start 1.1049 -0.724916)
			(end -1.1049 -0.724916)
			(stroke
				(width 0.1)
				(type default)
			)
			(layer "F.Fab")
		)
		(fp_line
			(start -1.1049 0.724916)
			(end 1.1049 0.724916)
			(stroke
				(width 0.1)
				(type default)
			)
			(layer "F.Fab")
		)
		(fp_line
			(start -1.1049 -0.724916)
			(end -1.1049 0.724916)
			(stroke
				(width 0.1)
				(type default)
			)
			(layer "F.Fab")
		)
		(pad "1" smd rect
			(at -0.889 0)
			(size 1.016 1.27)
			(layers "F.Cu" "F.Mask" "F.Paste")
			(net "SW_P12V_AUX_P1V8_RETIMER_CPU1_FLT")
		)
		(pad "2" smd rect
			(at 0.889 0)
			(size 1.016 1.27)
			(layers "F.Cu" "F.Mask" "F.Paste")
			(net "GND")
		)
	)
	(footprint ""
		(layer "F.Cu")
		(at 194.218306 -332.744572 -90)
		(property "Reference" "PC530"
			(at -4.24434 17.347692 90)
			(unlocked yes)
			(layer "F.SilkS")
			(effects
				(font
					(size 0.7874 0.5842)
					(thickness 0.1524)
				)
				(justify left)
			)
		)
		(property "Value" ""
			(at 0 0 270)
			(layer "F.Fab")
			(effects
				(font
					(size 1.27 1.27)
				)
			)
		)
		(duplicate_pad_numbers_are_jumpers no)
		(fp_line
			(start -1.988058 2.750058)
			(end 2.750058 2.750058)
			(stroke
				(width 0.1524)
				(type default)
			)
			(layer "F.SilkS")
		)
		(fp_line
			(start 2.750058 2.750058)
			(end 2.750058 0.9398)
			(stroke
				(width 0.1524)
				(type default)
			)
			(layer "F.SilkS")
		)
		(fp_line
			(start -2.750058 1.988058)
			(end -1.988058 2.750058)
			(stroke
				(width 0.1524)
				(type default)
			)
			(layer "F.SilkS")
		)
		(fp_line
			(start -2.750058 0.9398)
			(end -2.750058 1.988058)
			(stroke
				(width 0.1524)
				(type default)
			)
			(layer "F.SilkS")
		)
		(fp_line
			(start 2.750058 -0.9398)
			(end 2.750058 -2.750058)
			(stroke
				(width 0.1524)
				(type default)
			)
			(layer "F.SilkS")
		)
		(fp_line
			(start -2.750058 -1.988058)
			(end -2.750058 -0.9398)
			(stroke
				(width 0.1524)
				(type default)
			)
			(layer "F.SilkS")
		)
		(fp_line
			(start -1.988058 -2.750058)
			(end -2.750058 -1.988058)
			(stroke
				(width 0.1524)
				(type default)
			)
			(layer "F.SilkS")
		)
		(fp_line
			(start 2.750058 -2.750058)
			(end -1.988058 -2.750058)
			(stroke
				(width 0.1524)
				(type default)
			)
			(layer "F.SilkS")
		)
		(fp_line
			(start -2.750058 2.750058)
			(end 2.750058 2.750058)
			(stroke
				(width 0.1)
				(type default)
			)
			(layer "F.Fab")
		)
		(fp_line
			(start 2.750058 2.750058)
			(end 2.750058 -2.750058)
			(stroke
				(width 0.1)
				(type default)
			)
			(layer "F.Fab")
		)
		(fp_line
			(start -2.750058 -2.750058)
			(end -2.750058 2.750058)
			(stroke
				(width 0.1)
				(type default)
			)
			(layer "F.Fab")
		)
		(fp_line
			(start 2.750058 -2.750058)
			(end -2.750058 -2.750058)
			(stroke
				(width 0.1)
				(type default)
			)
			(layer "F.Fab")
		)
		(pad "1" smd rect
			(at -2.199894 0)
			(size 1.6002 3.0226)
			(layers "F.Cu" "F.Mask" "F.Paste")
			(net "PVDD11_S3_P1")
		)
		(pad "2" smd rect
			(at 2.199894 0)
			(size 1.6002 3.0226)
			(layers "F.Cu" "F.Mask" "F.Paste")
			(net "GND")
		)
	)
	(footprint ""
		(layer "F.Cu")
		(at 101.555296 -422.43248 90)
		(property "Reference" "R4187"
			(at 0 0 90)
			(layer "F.SilkS")
			(hide yes)
			(effects
				(font
					(size 1.27 1.27)
				)
			)
		)
		(property "Value" ""
			(at 0 0 90)
			(layer "F.Fab")
			(effects
				(font
					(size 1.27 1.27)
				)
			)
		)
		(duplicate_pad_numbers_are_jumpers no)
		(fp_line
			(start 0.7874 -0.4064)
			(end 0.7874 0.4064)
			(stroke
				(width 0.1524)
				(type default)
			)
			(layer "F.SilkS")
		)
		(fp_line
			(start -0.7874 -0.4064)
			(end 0.7874 -0.4064)
			(stroke
				(width 0.1524)
				(type default)
			)
			(layer "F.SilkS")
		)
		(fp_line
			(start 0.7874 0.4064)
			(end -0.7874 0.4064)
			(stroke
				(width 0.1524)
				(type default)
			)
			(layer "F.SilkS")
		)
		(fp_line
			(start -0.7874 0.4064)
			(end -0.7874 -0.4064)
			(stroke
				(width 0.1524)
				(type default)
			)
			(layer "F.SilkS")
		)
		(fp_line
			(start -0.12065 -0.305054)
			(end -0.12065 -0.2794)
			(stroke
				(width 0.1)
				(type default)
			)
			(layer "F.Fab")
		)
		(fp_line
			(start -0.67945 -0.305054)
			(end -0.12065 -0.305054)
			(stroke
				(width 0.1)
				(type default)
			)
			(layer "F.Fab")
		)
		(fp_line
			(start 0.67945 -0.3048)
			(end 0.67945 0.3048)
			(stroke
				(width 0.1)
				(type default)
			)
			(layer "F.Fab")
		)
		(fp_line
			(start 0.12065 -0.3048)
			(end 0.67945 -0.3048)
			(stroke
				(width 0.1)
				(type default)
			)
			(layer "F.Fab")
		)
		(fp_line
			(start 0.12065 -0.2794)
			(end 0.12065 -0.3048)
			(stroke
				(width 0.1)
				(type default)
			)
			(layer "F.Fab")
		)
		(fp_line
			(start -0.12065 -0.2794)
			(end 0.12065 -0.2794)
			(stroke
				(width 0.1)
				(type default)
			)
			(layer "F.Fab")
		)
		(fp_line
			(start 0.120396 0.2794)
			(end -0.12065 0.2794)
			(stroke
				(width 0.1)
				(type default)
			)
			(layer "F.Fab")
		)
		(fp_line
			(start -0.12065 0.2794)
			(end -0.12065 0.3048)
			(stroke
				(width 0.1)
				(type default)
			)
			(layer "F.Fab")
		)
		(fp_line
			(start 0.67945 0.3048)
			(end 0.120396 0.3048)
			(stroke
				(width 0.1)
				(type default)
			)
			(layer "F.Fab")
		)
		(fp_line
			(start 0.120396 0.3048)
			(end 0.120396 0.2794)
			(stroke
				(width 0.1)
				(type default)
			)
			(layer "F.Fab")
		)
		(fp_line
			(start -0.12065 0.3048)
			(end -0.67945 0.3048)
			(stroke
				(width 0.1)
				(type default)
			)
			(layer "F.Fab")
		)
		(fp_line
			(start -0.67945 0.3048)
			(end -0.67945 -0.305054)
			(stroke
				(width 0.1)
				(type default)
			)
			(layer "F.Fab")
		)
		(pad "1" smd circle
			(at -0.40005 0 90)
			(size 0 0)
			(layers "F.Cu" "F.Mask" "F.Paste")
			(net "U272_2_ADD2")
		)
		(pad "2" smd circle
			(at 0.40005 0 90)
			(size 0 0)
			(layers "F.Cu" "F.Mask" "F.Paste")
			(net "GND")
		)
	)
	(footprint ""
		(layer "F.Cu")
		(at 180.528468 -50.060098)
		(property "Reference" "C1100"
			(at 0 0 0)
			(layer "F.SilkS")
			(hide yes)
			(effects
				(font
					(size 1.27 1.27)
				)
			)
		)
		(property "Value" ""
			(at 0 0 0)
			(layer "F.Fab")
			(effects
				(font
					(size 1.27 1.27)
				)
			)
		)
		(duplicate_pad_numbers_are_jumpers no)
		(fp_line
			(start -0.299974 -0.150114)
			(end 0.299974 -0.150114)
			(stroke
				(width 0.1)
				(type default)
			)
			(layer "F.Fab")
		)
		(fp_line
			(start -0.299974 0.150114)
			(end -0.299974 -0.150114)
			(stroke
				(width 0.1)
				(type default)
			)
			(layer "F.Fab")
		)
		(fp_line
			(start 0.299974 -0.150114)
			(end 0.299974 0.150114)
			(stroke
				(width 0.1)
				(type default)
			)
			(layer "F.Fab")
		)
		(fp_line
			(start 0.299974 0.150114)
			(end -0.299974 0.150114)
			(stroke
				(width 0.1)
				(type default)
			)
			(layer "F.Fab")
		)
		(pad "1" smd rect
			(at -0.2667 0)
			(size 0.3048 0.381)
			(layers "F.Cu" "F.Mask" "F.Paste")
			(net "P3E_CPU1_P4_TX_C_DP<2>")
		)
		(pad "2" smd rect
			(at 0.2667 0)
			(size 0.3048 0.381)
			(layers "F.Cu" "F.Mask" "F.Paste")
			(net "P3E_CPU1_P4_TX_DP<2>")
		)
	)
	(footprint ""
		(layer "F.Cu")
		(at 356.033578 -169.495978 180)
		(property "Reference" "PU48"
			(at 0.486156 -7.523226 0)
			(unlocked yes)
			(layer "F.SilkS")
			(effects
				(font
					(size 0.7874 0.5842)
					(thickness 0.1524)
				)
				(justify left)
			)
		)
		(property "Value" ""
			(at 0 0 180)
			(layer "F.Fab")
			(effects
				(font
					(size 1.27 1.27)
				)
			)
		)
		(duplicate_pad_numbers_are_jumpers no)
		(fp_line
			(start 2.500122 2.999994)
			(end 2.2987 2.999994)
			(stroke
				(width 0.1524)
				(type default)
			)
			(layer "F.SilkS")
		)
		(fp_line
			(start 2.500122 2.339594)
			(end 2.500122 2.999994)
			(stroke
				(width 0.1524)
				(type default)
			)
			(layer "F.SilkS")
		)
		(fp_line
			(start 2.500122 -2.999994)
			(end 2.500122 -2.44348)
			(stroke
				(width 0.1524)
				(type default)
			)
			(layer "F.SilkS")
		)
		(fp_line
			(start 2.31394 -2.999994)
			(end 2.500122 -2.999994)
			(stroke
				(width 0.1524)
				(type default)
			)
			(layer "F.SilkS")
		)
		(fp_line
			(start -2.2987 2.999994)
			(end -2.500122 2.999994)
			(stroke
				(width 0.1524)
				(type default)
			)
			(layer "F.SilkS")
		)
		(fp_line
			(start -2.500122 2.999994)
			(end -2.500122 2.339594)
			(stroke
				(width 0.1524)
				(type default)
			)
			(layer "F.SilkS")
		)
		(fp_line
			(start -2.500122 0.6604)
			(end -2.500122 0.229108)
			(stroke
				(width 0.1524)
				(type default)
			)
			(layer "F.SilkS")
		)
		(fp_line
			(start -2.500122 -2.529078)
			(end -2.500122 -2.999994)
			(stroke
				(width 0.1524)
				(type default)
			)
			(layer "F.SilkS")
		)
		(fp_line
			(start -2.500122 -2.999994)
			(end -2.24409 -2.999994)
			(stroke
				(width 0.1524)
				(type default)
			)
			(layer "F.SilkS")
		)
		(fp_poly
			(pts
				(xy -2.712466 -2.468372) (xy -3.43662 -2.709672) (xy -2.95402 -3.192526)
			)
			(stroke
				(width 0)
				(type default)
			)
			(fill yes)
			(layer "F.SilkS")
		)
		(fp_line
			(start 2.500122 2.999994)
			(end -2.500122 2.999994)
			(stroke
				(width 0.1)
				(type default)
			)
			(layer "F.Fab")
		)
		(fp_line
			(start 2.500122 -2.999994)
			(end 2.500122 2.999994)
			(stroke
				(width 0.1)
				(type default)
			)
			(layer "F.Fab")
		)
		(fp_line
			(start -2.500122 2.999994)
			(end -2.500122 -2.999994)
			(stroke
				(width 0.1)
				(type default)
			)
			(layer "F.Fab")
		)
		(fp_line
			(start -2.500122 -2.999994)
			(end 2.500122 -2.999994)
			(stroke
				(width 0.1)
				(type default)
			)
			(layer "F.Fab")
		)
		(fp_poly
			(pts
				(xy -4.218432 -2.783078) (xy -4.218432 -1.767078) (xy -3.202432 -2.275078)
			)
			(stroke
				(width 0)
				(type default)
			)
			(fill yes)
			(layer "F.Fab")
		)
		(pad "1" smd rect
			(at -2.400046 -2.275078 270)
			(size 0.2286 0.6096)
			(layers "F.Cu" "F.Mask" "F.Paste")
			(net "PVDDCR_CPU0_P0_VOS5")
		)
		(pad "2" smd rect
			(at -2.400046 -1.82499 270)
			(size 0.2286 0.6096)
			(layers "F.Cu" "F.Mask" "F.Paste")
			(net "GND")
		)
		(pad "3" smd rect
			(at -2.400046 -1.374902 270)
			(size 0.2286 0.6096)
			(layers "F.Cu" "F.Mask" "F.Paste")
			(net "PVDDCR_CPU0_P0_VCC5")
		)
		(pad "4" smd rect
			(at -2.400046 -0.925068 270)
			(size 0.2286 0.6096)
			(layers "F.Cu" "F.Mask" "F.Paste")
			(net "PVDDCR_CPU0_P0_PVCC")
		)
		(pad "5" smd rect
			(at -2.400046 -0.47498 270)
			(size 0.2286 0.6096)
			(layers "F.Cu" "F.Mask" "F.Paste")
			(net "GND")
		)
		(pad "6" smd rect
			(at -2.400046 -0.024892 270)
			(size 0.2286 0.6096)
			(layers "F.Cu" "F.Mask" "F.Paste")
			(net "NC_PVDDCR_CPU0_P0_GL1_5")
		)
		(pad "7_9-20_24" smd circle
			(at 0 1.150112 270)
			(size 0 0)
			(layers "F.Cu" "F.Mask" "F.Paste")
			(net "GND")
		)
		(pad "10_19" smd rect
			(at 0 2.899918 270)
			(size 0.6096 4.318)
			(layers "F.Cu" "F.Mask" "F.Paste")
			(net "SW_PVDDCR_CPU0_P0_SW5")
		)
		(pad "25_29" smd rect
			(at 1.549908 -1.279906 90)
			(size 2.0574 2.3114)
			(layers "F.Cu" "F.Mask" "F.Paste")
			(net "SW_P12V_AUX_PVDDCR_CPU0_P0_FLT")
		)
		(pad "30" smd rect
			(at 2.05994 -2.899918 180)
			(size 0.2286 0.6096)
			(layers "F.Cu" "F.Mask" "F.Paste")
			(net "SW_P12V_AUX_PVDDCR_CPU0_P0_FLT")
		)
		(pad "31" smd rect
			(at 1.610106 -2.899918 180)
			(size 0.2286 0.6096)
			(layers "F.Cu" "F.Mask" "F.Paste")
			(net "NC_PVDDCR_CPU0_P0_DNC5")
		)
		(pad "32" smd rect
			(at 1.160018 -2.899918 180)
			(size 0.2286 0.6096)
			(layers "F.Cu" "F.Mask" "F.Paste")
			(net "SW_PVDDCR_CPU0_P0_PH5")
		)
		(pad "33" smd rect
			(at 0.70993 -2.899918 180)
			(size 0.2286 0.6096)
			(layers "F.Cu" "F.Mask" "F.Paste")
			(net "SW_PVDDCR_CPU0_P0_BOOT5")
		)
		(pad "34" smd rect
			(at 0.260096 -2.899918 180)
			(size 0.2286 0.6096)
			(layers "F.Cu" "F.Mask" "F.Paste")
			(net "PVDDCR_CPU0_P0_PWM5")
		)
		(pad "35" smd rect
			(at -0.189992 -2.899918 180)
			(size 0.2286 0.6096)
			(layers "F.Cu" "F.Mask" "F.Paste")
			(net "PVDDCR_CPU0_P0_VCC5")
		)
		(pad "36" smd rect
			(at -0.64008 -2.899918 180)
			(size 0.2286 0.6096)
			(layers "F.Cu" "F.Mask" "F.Paste")
			(net "PVDDCR_CPU0_P0_TEMP0")
		)
		(pad "37" smd rect
			(at -1.089914 -2.899918 180)
			(size 0.2286 0.6096)
			(layers "F.Cu" "F.Mask" "F.Paste")
			(net "PVDDCR_CPU0_P0_LSET5")
		)
		(pad "38" smd rect
			(at -1.540002 -2.899918 180)
			(size 0.2286 0.6096)
			(layers "F.Cu" "F.Mask" "F.Paste")
			(net "PVDDCR_CPU0_P0_IMON5")
		)
		(pad "39" smd rect
			(at -1.99009 -2.899918 180)
			(size 0.2286 0.6096)
			(layers "F.Cu" "F.Mask" "F.Paste")
			(net "PVDDCR_CPU0_P0_VCCS")
		)
		(pad "40" smd rect
			(at -0.87503 -1.27508 180)
			(size 1.7526 1.9558)
			(layers "F.Cu" "F.Mask" "F.Paste")
			(net "GND")
		)
		(pad "41" smd rect
			(at -1.525016 0.249936 90)
			(size 0.3048 0.4572)
			(layers "F.Cu" "F.Mask" "F.Paste")
			(net "NC_PVDDCR_CPU0_P0_GL2_5")
		)
		(zone
			(layer "F.Cu")
			(hatch none 0.5)
			(connect_pads
				(clearance 0)
			)
			(min_thickness 0.25)
			(keepout
				(tracks not_allowed)
				(vias allowed)
				(pads allowed)
				(copperpour not_allowed)
				(footprints allowed)
			)
			(placement
				(enabled no)
				(sheetname "")
			)
			(fill
				(thermal_gap 0.5)
				(thermal_bridge_width 0.5)
				(island_removal_mode 0)
			)
			(polygon
				(pts
					(xy 358.5337 -172.070776) (xy 358.5337 -171.746672) (xy 353.533456 -171.746672) (xy 353.533456 -172.076618)
					(xy 353.823778 -172.076618) (xy 353.823778 -172.040296) (xy 358.243378 -172.040296) (xy 358.243378 -172.070776)
				)
			)
		)
		(zone
			(layer "F.Cu")
			(hatch none 0.5)
			(connect_pads
				(clearance 0)
			)
			(min_thickness 0.25)
			(keepout
				(tracks not_allowed)
				(vias allowed)
				(pads allowed)
				(copperpour not_allowed)
				(footprints allowed)
			)
			(placement
				(enabled no)
				(sheetname "")
			)
			(fill
				(thermal_gap 0.5)
				(thermal_bridge_width 0.5)
				(island_removal_mode 0)
			)
			(polygon
				(pts
					(xy 355.981508 -169.249598) (xy 355.981508 -167.192198) (xy 357.835708 -167.192198) (xy 357.835708 -167.433244)
					(xy 358.078024 -167.433244) (xy 358.078024 -166.95166) (xy 354.210112 -166.95166) (xy 354.210112 -167.136572)
					(xy 355.69017 -167.136572) (xy 355.69017 -169.295572) (xy 353.533456 -169.295572) (xy 353.533456 -169.545254)
					(xy 355.698806 -169.545254) (xy 355.981508 -169.262552)
				)
			)
		)
	)
	(footprint ""
		(layer "F.Cu")
		(at 148.641562 -43.03141)
		(property "Reference" "R1703"
			(at 0 0 0)
			(layer "F.SilkS")
			(hide yes)
			(effects
				(font
					(size 1.27 1.27)
				)
			)
		)
		(property "Value" ""
			(at 0 0 0)
			(layer "F.Fab")
			(effects
				(font
					(size 1.27 1.27)
				)
			)
		)
		(duplicate_pad_numbers_are_jumpers no)
		(fp_line
			(start -0.7874 -0.4064)
			(end 0.7874 -0.4064)
			(stroke
				(width 0.1524)
				(type default)
			)
			(layer "F.SilkS")
		)
		(fp_line
			(start -0.7874 0.4064)
			(end -0.7874 -0.4064)
			(stroke
				(width 0.1524)
				(type default)
			)
			(layer "F.SilkS")
		)
		(fp_line
			(start 0.7874 -0.4064)
			(end 0.7874 0.4064)
			(stroke
				(width 0.1524)
				(type default)
			)
			(layer "F.SilkS")
		)
		(fp_line
			(start 0.7874 0.4064)
			(end -0.7874 0.4064)
			(stroke
				(width 0.1524)
				(type default)
			)
			(layer "F.SilkS")
		)
		(fp_line
			(start -0.67945 -0.305054)
			(end -0.12065 -0.305054)
			(stroke
				(width 0.1)
				(type default)
			)
			(layer "F.Fab")
		)
		(fp_line
			(start -0.67945 0.3048)
			(end -0.67945 -0.305054)
			(stroke
				(width 0.1)
				(type default)
			)
			(layer "F.Fab")
		)
		(fp_line
			(start -0.12065 -0.305054)
			(end -0.12065 -0.2794)
			(stroke
				(width 0.1)
				(type default)
			)
			(layer "F.Fab")
		)
		(fp_line
			(start -0.12065 -0.2794)
			(end 0.12065 -0.2794)
			(stroke
				(width 0.1)
				(type default)
			)
			(layer "F.Fab")
		)
		(fp_line
			(start -0.12065 0.2794)
			(end -0.12065 0.3048)
			(stroke
				(width 0.1)
				(type default)
			)
			(layer "F.Fab")
		)
		(fp_line
			(start -0.12065 0.3048)
			(end -0.67945 0.3048)
			(stroke
				(width 0.1)
				(type default)
			)
			(layer "F.Fab")
		)
		(fp_line
			(start 0.120396 0.2794)
			(end -0.12065 0.2794)
			(stroke
				(width 0.1)
				(type default)
			)
			(layer "F.Fab")
		)
		(fp_line
			(start 0.120396 0.3048)
			(end 0.120396 0.2794)
			(stroke
				(width 0.1)
				(type default)
			)
			(layer "F.Fab")
		)
		(fp_line
			(start 0.12065 -0.3048)
			(end 0.67945 -0.3048)
			(stroke
				(width 0.1)
				(type default)
			)
			(layer "F.Fab")
		)
		(fp_line
			(start 0.12065 -0.2794)
			(end 0.12065 -0.3048)
			(stroke
				(width 0.1)
				(type default)
			)
			(layer "F.Fab")
		)
		(fp_line
			(start 0.67945 -0.3048)
			(end 0.67945 0.3048)
			(stroke
				(width 0.1)
				(type default)
			)
			(layer "F.Fab")
		)
		(fp_line
			(start 0.67945 0.3048)
			(end 0.120396 0.3048)
			(stroke
				(width 0.1)
				(type default)
			)
			(layer "F.Fab")
		)
		(pad "1" smd circle
			(at -0.40005 0)
			(size 0 0)
			(layers "F.Cu" "F.Mask" "F.Paste")
			(net "P1V8_AUX")
		)
		(pad "2" smd circle
			(at 0.40005 0)
			(size 0 0)
			(layers "F.Cu" "F.Mask" "F.Paste")
			(net "SMB_M2_P1_1V8AUX_SCL_R")
		)
	)
	(footprint ""
		(layer "F.Cu")
		(at 146.571208 -50.160174)
		(property "Reference" "R1347"
			(at 0 0 0)
			(layer "F.SilkS")
			(hide yes)
			(effects
				(font
					(size 1.27 1.27)
				)
			)
		)
		(property "Value" ""
			(at 0 0 0)
			(layer "F.Fab")
			(effects
				(font
					(size 1.27 1.27)
				)
			)
		)
		(duplicate_pad_numbers_are_jumpers no)
		(fp_line
			(start -0.7874 -0.4064)
			(end 0.7874 -0.4064)
			(stroke
				(width 0.1524)
				(type default)
			)
			(layer "F.SilkS")
		)
		(fp_line
			(start -0.7874 0.4064)
			(end -0.7874 -0.4064)
			(stroke
				(width 0.1524)
				(type default)
			)
			(layer "F.SilkS")
		)
		(fp_line
			(start 0.7874 -0.4064)
			(end 0.7874 0.4064)
			(stroke
				(width 0.1524)
				(type default)
			)
			(layer "F.SilkS")
		)
		(fp_line
			(start 0.7874 0.4064)
			(end -0.7874 0.4064)
			(stroke
				(width 0.1524)
				(type default)
			)
			(layer "F.SilkS")
		)
		(fp_line
			(start -0.67945 -0.305054)
			(end -0.12065 -0.305054)
			(stroke
				(width 0.1)
				(type default)
			)
			(layer "F.Fab")
		)
		(fp_line
			(start -0.67945 0.3048)
			(end -0.67945 -0.305054)
			(stroke
				(width 0.1)
				(type default)
			)
			(layer "F.Fab")
		)
		(fp_line
			(start -0.12065 -0.305054)
			(end -0.12065 -0.2794)
			(stroke
				(width 0.1)
				(type default)
			)
			(layer "F.Fab")
		)
		(fp_line
			(start -0.12065 -0.2794)
			(end 0.12065 -0.2794)
			(stroke
				(width 0.1)
				(type default)
			)
			(layer "F.Fab")
		)
		(fp_line
			(start -0.12065 0.2794)
			(end -0.12065 0.3048)
			(stroke
				(width 0.1)
				(type default)
			)
			(layer "F.Fab")
		)
		(fp_line
			(start -0.12065 0.3048)
			(end -0.67945 0.3048)
			(stroke
				(width 0.1)
				(type default)
			)
			(layer "F.Fab")
		)
		(fp_line
			(start 0.120396 0.2794)
			(end -0.12065 0.2794)
			(stroke
				(width 0.1)
				(type default)
			)
			(layer "F.Fab")
		)
		(fp_line
			(start 0.120396 0.3048)
			(end 0.120396 0.2794)
			(stroke
				(width 0.1)
				(type default)
			)
			(layer "F.Fab")
		)
		(fp_line
			(start 0.12065 -0.3048)
			(end 0.67945 -0.3048)
			(stroke
				(width 0.1)
				(type default)
			)
			(layer "F.Fab")
		)
		(fp_line
			(start 0.12065 -0.2794)
			(end 0.12065 -0.3048)
			(stroke
				(width 0.1)
				(type default)
			)
			(layer "F.Fab")
		)
		(fp_line
			(start 0.67945 -0.3048)
			(end 0.67945 0.3048)
			(stroke
				(width 0.1)
				(type default)
			)
			(layer "F.Fab")
		)
		(fp_line
			(start 0.67945 0.3048)
			(end 0.120396 0.3048)
			(stroke
				(width 0.1)
				(type default)
			)
			(layer "F.Fab")
		)
		(pad "1" smd circle
			(at -0.40005 0)
			(size 0 0)
			(layers "F.Cu" "F.Mask" "F.Paste")
			(net "SMB_INA230_3V3AUX_SDA")
		)
		(pad "2" smd circle
			(at 0.40005 0)
			(size 0 0)
			(layers "F.Cu" "F.Mask" "F.Paste")
			(net "SMB_INA230_7_3V3AUX_SDA_R")
		)
	)
	(footprint ""
		(layer "F.Cu")
		(at 39.309294 -422.06037 180)
		(property "Reference" "R6152"
			(at 0 0 180)
			(layer "F.SilkS")
			(hide yes)
			(effects
				(font
					(size 1.27 1.27)
				)
			)
		)
		(property "Value" ""
			(at 0 0 180)
			(layer "F.Fab")
			(effects
				(font
					(size 1.27 1.27)
				)
			)
		)
		(duplicate_pad_numbers_are_jumpers no)
		(fp_line
			(start 0.32512 0.175006)
			(end -0.32512 0.175006)
			(stroke
				(width 0.1)
				(type default)
			)
			(layer "F.Fab")
		)
		(fp_line
			(start 0.32512 -0.175006)
			(end 0.32512 0.175006)
			(stroke
				(width 0.1)
				(type default)
			)
			(layer "F.Fab")
		)
		(fp_line
			(start -0.32512 0.175006)
			(end -0.32512 -0.175006)
			(stroke
				(width 0.1)
				(type default)
			)
			(layer "F.Fab")
		)
		(fp_line
			(start -0.32512 -0.175006)
			(end 0.32512 -0.175006)
			(stroke
				(width 0.1)
				(type default)
			)
			(layer "F.Fab")
		)
		(pad "1" smd rect
			(at -0.2667 0 180)
			(size 0.3048 0.381)
			(layers "F.Cu" "F.Mask" "F.Paste")
			(net "P2E_MB_BMC_TX_C_DP<0>")
		)
		(pad "2" smd rect
			(at 0.2667 0)
			(size 0.3048 0.381)
			(layers "F.Cu" "F.Mask" "F.Paste")
			(net "P2E_MB_BMC_TX_C_R1_DP<0>")
		)
	)
	(footprint ""
		(layer "F.Cu")
		(at 157.754066 -408.517344 -90)
		(property "Reference" "C6722"
			(at 0 0 270)
			(layer "F.SilkS")
			(hide yes)
			(effects
				(font
					(size 1.27 1.27)
				)
			)
		)
		(property "Value" ""
			(at 0 0 270)
			(layer "F.Fab")
			(effects
				(font
					(size 1.27 1.27)
				)
			)
		)
		(duplicate_pad_numbers_are_jumpers no)
		(fp_line
			(start -0.299974 0.150114)
			(end -0.299974 -0.150114)
			(stroke
				(width 0.1)
				(type default)
			)
			(layer "F.Fab")
		)
		(fp_line
			(start 0.299974 0.150114)
			(end -0.299974 0.150114)
			(stroke
				(width 0.1)
				(type default)
			)
			(layer "F.Fab")
		)
		(fp_line
			(start -0.299974 -0.150114)
			(end 0.299974 -0.150114)
			(stroke
				(width 0.1)
				(type default)
			)
			(layer "F.Fab")
		)
		(fp_line
			(start 0.299974 -0.150114)
			(end 0.299974 0.150114)
			(stroke
				(width 0.1)
				(type default)
			)
			(layer "F.Fab")
		)
		(pad "1" smd rect
			(at -0.2667 0 270)
			(size 0.3048 0.381)
			(layers "F.Cu" "F.Mask" "F.Paste")
			(net "P5E_CPU1_P2_TX_BUF_C_DN<14>")
		)
		(pad "2" smd rect
			(at 0.2667 0 270)
			(size 0.3048 0.381)
			(layers "F.Cu" "F.Mask" "F.Paste")
			(net "P5E_CPU1_P2_TX_BUF_DN<14>")
		)
	)
	(footprint ""
		(layer "F.Cu")
		(at 298.527724 -396.146274)
		(property "Reference" "R595"
			(at 0 0 0)
			(layer "F.SilkS")
			(hide yes)
			(effects
				(font
					(size 1.27 1.27)
				)
			)
		)
		(property "Value" ""
			(at 0 0 0)
			(layer "F.Fab")
			(effects
				(font
					(size 1.27 1.27)
				)
			)
		)
		(duplicate_pad_numbers_are_jumpers no)
		(fp_line
			(start -0.32512 -0.175006)
			(end 0.32512 -0.175006)
			(stroke
				(width 0.1)
				(type default)
			)
			(layer "F.Fab")
		)
		(fp_line
			(start -0.32512 0.175006)
			(end -0.32512 -0.175006)
			(stroke
				(width 0.1)
				(type default)
			)
			(layer "F.Fab")
		)
		(fp_line
			(start 0.32512 -0.175006)
			(end 0.32512 0.175006)
			(stroke
				(width 0.1)
				(type default)
			)
			(layer "F.Fab")
		)
		(fp_line
			(start 0.32512 0.175006)
			(end -0.32512 0.175006)
			(stroke
				(width 0.1)
				(type default)
			)
			(layer "F.Fab")
		)
		(pad "1" smd rect
			(at -0.2667 0)
			(size 0.3048 0.381)
			(layers "F.Cu" "F.Mask" "F.Paste")
			(net "CLK_100M_RETIMER_CPU0_P0_R_DP")
		)
		(pad "2" smd rect
			(at 0.2667 0 180)
			(size 0.3048 0.381)
			(layers "F.Cu" "F.Mask" "F.Paste")
			(net "CLK_100M_RETIMER_CPU0_P0_DP")
		)
	)
	(footprint ""
		(layer "F.Cu")
		(at 376.35815 -182.745634 90)
		(property "Reference" "PC478_C0P0_2"
			(at 0 0 90)
			(layer "F.SilkS")
			(hide yes)
			(effects
				(font
					(size 1.27 1.27)
				)
			)
		)
		(property "Value" ""
			(at 0 0 90)
			(layer "F.Fab")
			(effects
				(font
					(size 1.27 1.27)
				)
			)
		)
		(duplicate_pad_numbers_are_jumpers no)
		(fp_line
			(start 0.7874 -0.4064)
			(end 0.7874 0.4064)
			(stroke
				(width 0.1524)
				(type default)
			)
			(layer "F.SilkS")
		)
		(fp_line
			(start -0.7874 -0.4064)
			(end 0.7874 -0.4064)
			(stroke
				(width 0.1524)
				(type default)
			)
			(layer "F.SilkS")
		)
		(fp_line
			(start 0.7874 0.4064)
			(end -0.7874 0.4064)
			(stroke
				(width 0.1524)
				(type default)
			)
			(layer "F.SilkS")
		)
		(fp_line
			(start -0.7874 0.4064)
			(end -0.7874 -0.4064)
			(stroke
				(width 0.1524)
				(type default)
			)
			(layer "F.SilkS")
		)
		(fp_line
			(start -0.12065 -0.305054)
			(end -0.12065 -0.2794)
			(stroke
				(width 0.1)
				(type default)
			)
			(layer "F.Fab")
		)
		(fp_line
			(start -0.67945 -0.305054)
			(end -0.12065 -0.305054)
			(stroke
				(width 0.1)
				(type default)
			)
			(layer "F.Fab")
		)
		(fp_line
			(start 0.67945 -0.3048)
			(end 0.67945 0.3048)
			(stroke
				(width 0.1)
				(type default)
			)
			(layer "F.Fab")
		)
		(fp_line
			(start 0.12065 -0.3048)
			(end 0.67945 -0.3048)
			(stroke
				(width 0.1)
				(type default)
			)
			(layer "F.Fab")
		)
		(fp_line
			(start 0.12065 -0.2794)
			(end 0.12065 -0.3048)
			(stroke
				(width 0.1)
				(type default)
			)
			(layer "F.Fab")
		)
		(fp_line
			(start -0.12065 -0.2794)
			(end 0.12065 -0.2794)
			(stroke
				(width 0.1)
				(type default)
			)
			(layer "F.Fab")
		)
		(fp_line
			(start 0.120396 0.2794)
			(end -0.12065 0.2794)
			(stroke
				(width 0.1)
				(type default)
			)
			(layer "F.Fab")
		)
		(fp_line
			(start -0.12065 0.2794)
			(end -0.12065 0.3048)
			(stroke
				(width 0.1)
				(type default)
			)
			(layer "F.Fab")
		)
		(fp_line
			(start 0.67945 0.3048)
			(end 0.120396 0.3048)
			(stroke
				(width 0.1)
				(type default)
			)
			(layer "F.Fab")
		)
		(fp_line
			(start 0.120396 0.3048)
			(end 0.120396 0.2794)
			(stroke
				(width 0.1)
				(type default)
			)
			(layer "F.Fab")
		)
		(fp_line
			(start -0.12065 0.3048)
			(end -0.67945 0.3048)
			(stroke
				(width 0.1)
				(type default)
			)
			(layer "F.Fab")
		)
		(fp_line
			(start -0.67945 0.3048)
			(end -0.67945 -0.305054)
			(stroke
				(width 0.1)
				(type default)
			)
			(layer "F.Fab")
		)
		(pad "1" smd circle
			(at -0.40005 0 90)
			(size 0 0)
			(layers "F.Cu" "F.Mask" "F.Paste")
			(net "PVDDCR_CPU0_P0_PVCC")
		)
		(pad "2" smd circle
			(at 0.40005 0 90)
			(size 0 0)
			(layers "F.Cu" "F.Mask" "F.Paste")
			(net "GND")
		)
	)
	(footprint ""
		(layer "F.Cu")
		(at 285.48838 -351.368106 -90)
		(property "Reference" "PC186"
			(at 0 0 270)
			(layer "F.SilkS")
			(hide yes)
			(effects
				(font
					(size 1.27 1.27)
				)
			)
		)
		(property "Value" ""
			(at 0 0 270)
			(layer "F.Fab")
			(effects
				(font
					(size 1.27 1.27)
				)
			)
		)
		(duplicate_pad_numbers_are_jumpers no)
		(fp_line
			(start -0.7874 0.4064)
			(end -0.7874 -0.4064)
			(stroke
				(width 0.1524)
				(type default)
			)
			(layer "F.SilkS")
		)
		(fp_line
			(start 0.7874 0.4064)
			(end -0.7874 0.4064)
			(stroke
				(width 0.1524)
				(type default)
			)
			(layer "F.SilkS")
		)
		(fp_line
			(start -0.7874 -0.4064)
			(end 0.7874 -0.4064)
			(stroke
				(width 0.1524)
				(type default)
			)
			(layer "F.SilkS")
		)
		(fp_line
			(start 0.7874 -0.4064)
			(end 0.7874 0.4064)
			(stroke
				(width 0.1524)
				(type default)
			)
			(layer "F.SilkS")
		)
		(fp_line
			(start -0.67945 0.3048)
			(end -0.67945 -0.305054)
			(stroke
				(width 0.1)
				(type default)
			)
			(layer "F.Fab")
		)
		(fp_line
			(start -0.12065 0.3048)
			(end -0.67945 0.3048)
			(stroke
				(width 0.1)
				(type default)
			)
			(layer "F.Fab")
		)
		(fp_line
			(start 0.120396 0.3048)
			(end 0.120396 0.2794)
			(stroke
				(width 0.1)
				(type default)
			)
			(layer "F.Fab")
		)
		(fp_line
			(start 0.67945 0.3048)
			(end 0.120396 0.3048)
			(stroke
				(width 0.1)
				(type default)
			)
			(layer "F.Fab")
		)
		(fp_line
			(start -0.12065 0.2794)
			(end -0.12065 0.3048)
			(stroke
				(width 0.1)
				(type default)
			)
			(layer "F.Fab")
		)
		(fp_line
			(start 0.120396 0.2794)
			(end -0.12065 0.2794)
			(stroke
				(width 0.1)
				(type default)
			)
			(layer "F.Fab")
		)
		(fp_line
			(start -0.12065 -0.2794)
			(end 0.12065 -0.2794)
			(stroke
				(width 0.1)
				(type default)
			)
			(layer "F.Fab")
		)
		(fp_line
			(start 0.12065 -0.2794)
			(end 0.12065 -0.3048)
			(stroke
				(width 0.1)
				(type default)
			)
			(layer "F.Fab")
		)
		(fp_line
			(start 0.12065 -0.3048)
			(end 0.67945 -0.3048)
			(stroke
				(width 0.1)
				(type default)
			)
			(layer "F.Fab")
		)
		(fp_line
			(start 0.67945 -0.3048)
			(end 0.67945 0.3048)
			(stroke
				(width 0.1)
				(type default)
			)
			(layer "F.Fab")
		)
		(fp_line
			(start -0.67945 -0.305054)
			(end -0.12065 -0.305054)
			(stroke
				(width 0.1)
				(type default)
			)
			(layer "F.Fab")
		)
		(fp_line
			(start -0.12065 -0.305054)
			(end -0.12065 -0.2794)
			(stroke
				(width 0.1)
				(type default)
			)
			(layer "F.Fab")
		)
		(pad "1" smd circle
			(at -0.40005 0 270)
			(size 0 0)
			(layers "F.Cu" "F.Mask" "F.Paste")
			(net "SW_PVDDIO_P0_BOOT3_R")
		)
		(pad "2" smd circle
			(at 0.40005 0 270)
			(size 0 0)
			(layers "F.Cu" "F.Mask" "F.Paste")
			(net "SW_PVDDIO_P0_BOOTR3")
		)
	)
	(footprint ""
		(layer "F.Cu")
		(at 287.336992 -346.866464 -90)
		(property "Reference" "PC179_3"
			(at 0 0 270)
			(layer "F.SilkS")
			(hide yes)
			(effects
				(font
					(size 1.27 1.27)
				)
			)
		)
		(property "Value" ""
			(at 0 0 270)
			(layer "F.Fab")
			(effects
				(font
					(size 1.27 1.27)
				)
			)
		)
		(duplicate_pad_numbers_are_jumpers no)
		(fp_line
			(start -0.7874 0.4064)
			(end -0.7874 -0.4064)
			(stroke
				(width 0.1524)
				(type default)
			)
			(layer "F.SilkS")
		)
		(fp_line
			(start 0.7874 0.4064)
			(end -0.7874 0.4064)
			(stroke
				(width 0.1524)
				(type default)
			)
			(layer "F.SilkS")
		)
		(fp_line
			(start -0.7874 -0.4064)
			(end 0.7874 -0.4064)
			(stroke
				(width 0.1524)
				(type default)
			)
			(layer "F.SilkS")
		)
		(fp_line
			(start 0.7874 -0.4064)
			(end 0.7874 0.4064)
			(stroke
				(width 0.1524)
				(type default)
			)
			(layer "F.SilkS")
		)
		(fp_line
			(start -0.67945 0.3048)
			(end -0.67945 -0.305054)
			(stroke
				(width 0.1)
				(type default)
			)
			(layer "F.Fab")
		)
		(fp_line
			(start -0.12065 0.3048)
			(end -0.67945 0.3048)
			(stroke
				(width 0.1)
				(type default)
			)
			(layer "F.Fab")
		)
		(fp_line
			(start 0.120396 0.3048)
			(end 0.120396 0.2794)
			(stroke
				(width 0.1)
				(type default)
			)
			(layer "F.Fab")
		)
		(fp_line
			(start 0.67945 0.3048)
			(end 0.120396 0.3048)
			(stroke
				(width 0.1)
				(type default)
			)
			(layer "F.Fab")
		)
		(fp_line
			(start -0.12065 0.2794)
			(end -0.12065 0.3048)
			(stroke
				(width 0.1)
				(type default)
			)
			(layer "F.Fab")
		)
		(fp_line
			(start 0.120396 0.2794)
			(end -0.12065 0.2794)
			(stroke
				(width 0.1)
				(type default)
			)
			(layer "F.Fab")
		)
		(fp_line
			(start -0.12065 -0.2794)
			(end 0.12065 -0.2794)
			(stroke
				(width 0.1)
				(type default)
			)
			(layer "F.Fab")
		)
		(fp_line
			(start 0.12065 -0.2794)
			(end 0.12065 -0.3048)
			(stroke
				(width 0.1)
				(type default)
			)
			(layer "F.Fab")
		)
		(fp_line
			(start 0.12065 -0.3048)
			(end 0.67945 -0.3048)
			(stroke
				(width 0.1)
				(type default)
			)
			(layer "F.Fab")
		)
		(fp_line
			(start 0.67945 -0.3048)
			(end 0.67945 0.3048)
			(stroke
				(width 0.1)
				(type default)
			)
			(layer "F.Fab")
		)
		(fp_line
			(start -0.67945 -0.305054)
			(end -0.12065 -0.305054)
			(stroke
				(width 0.1)
				(type default)
			)
			(layer "F.Fab")
		)
		(fp_line
			(start -0.12065 -0.305054)
			(end -0.12065 -0.2794)
			(stroke
				(width 0.1)
				(type default)
			)
			(layer "F.Fab")
		)
		(pad "1" smd circle
			(at -0.40005 0 270)
			(size 0 0)
			(layers "F.Cu" "F.Mask" "F.Paste")
			(net "SW_P12V_AUX_PVDDIO_P0_FLT")
		)
		(pad "2" smd circle
			(at 0.40005 0 270)
			(size 0 0)
			(layers "F.Cu" "F.Mask" "F.Paste")
			(net "GND")
		)
	)
	(footprint ""
		(layer "F.Cu")
		(at 41.503854 -349.386398 90)
		(property "Reference" "PC432"
			(at 0 0 90)
			(layer "F.SilkS")
			(hide yes)
			(effects
				(font
					(size 1.27 1.27)
				)
			)
		)
		(property "Value" ""
			(at 0 0 90)
			(layer "F.Fab")
			(effects
				(font
					(size 1.27 1.27)
				)
			)
		)
		(duplicate_pad_numbers_are_jumpers no)
		(fp_line
			(start 0.7874 -0.4064)
			(end 0.7874 0.4064)
			(stroke
				(width 0.1524)
				(type default)
			)
			(layer "F.SilkS")
		)
		(fp_line
			(start -0.7874 -0.4064)
			(end 0.7874 -0.4064)
			(stroke
				(width 0.1524)
				(type default)
			)
			(layer "F.SilkS")
		)
		(fp_line
			(start 0.7874 0.4064)
			(end 0.498602 0.4064)
			(stroke
				(width 0.1524)
				(type default)
			)
			(layer "F.SilkS")
		)
		(fp_line
			(start -0.314198 0.4064)
			(end -0.7874 0.4064)
			(stroke
				(width 0.1524)
				(type default)
			)
			(layer "F.SilkS")
		)
		(fp_line
			(start -0.7874 0.4064)
			(end -0.7874 -0.4064)
			(stroke
				(width 0.1524)
				(type default)
			)
			(layer "F.SilkS")
		)
		(fp_line
			(start -0.12065 -0.305054)
			(end -0.12065 -0.2794)
			(stroke
				(width 0.1)
				(type default)
			)
			(layer "F.Fab")
		)
		(fp_line
			(start -0.67945 -0.305054)
			(end -0.12065 -0.305054)
			(stroke
				(width 0.1)
				(type default)
			)
			(layer "F.Fab")
		)
		(fp_line
			(start 0.67945 -0.3048)
			(end 0.67945 0.3048)
			(stroke
				(width 0.1)
				(type default)
			)
			(layer "F.Fab")
		)
		(fp_line
			(start 0.12065 -0.3048)
			(end 0.67945 -0.3048)
			(stroke
				(width 0.1)
				(type default)
			)
			(layer "F.Fab")
		)
		(fp_line
			(start 0.12065 -0.2794)
			(end 0.12065 -0.3048)
			(stroke
				(width 0.1)
				(type default)
			)
			(layer "F.Fab")
		)
		(fp_line
			(start -0.12065 -0.2794)
			(end 0.12065 -0.2794)
			(stroke
				(width 0.1)
				(type default)
			)
			(layer "F.Fab")
		)
		(fp_line
			(start 0.120396 0.2794)
			(end -0.12065 0.2794)
			(stroke
				(width 0.1)
				(type default)
			)
			(layer "F.Fab")
		)
		(fp_line
			(start -0.12065 0.2794)
			(end -0.12065 0.3048)
			(stroke
				(width 0.1)
				(type default)
			)
			(layer "F.Fab")
		)
		(fp_line
			(start 0.67945 0.3048)
			(end 0.120396 0.3048)
			(stroke
				(width 0.1)
				(type default)
			)
			(layer "F.Fab")
		)
		(fp_line
			(start 0.120396 0.3048)
			(end 0.120396 0.2794)
			(stroke
				(width 0.1)
				(type default)
			)
			(layer "F.Fab")
		)
		(fp_line
			(start -0.12065 0.3048)
			(end -0.67945 0.3048)
			(stroke
				(width 0.1)
				(type default)
			)
			(layer "F.Fab")
		)
		(fp_line
			(start -0.67945 0.3048)
			(end -0.67945 -0.305054)
			(stroke
				(width 0.1)
				(type default)
			)
			(layer "F.Fab")
		)
		(pad "1" smd circle
			(at -0.40005 0 90)
			(size 0 0)
			(layers "F.Cu" "F.Mask" "F.Paste")
			(net "PVDDIO_P1_VCC2")
		)
		(pad "2" smd circle
			(at 0.40005 0 90)
			(size 0 0)
			(layers "F.Cu" "F.Mask" "F.Paste")
			(net "GND")
		)
	)
	(footprint ""
		(layer "F.Cu")
		(at 415.798 -96.901 180)
		(property "Reference" "C8008"
			(at 0 0 180)
			(layer "F.SilkS")
			(hide yes)
			(effects
				(font
					(size 1.27 1.27)
				)
			)
		)
		(property "Value" ""
			(at 0 0 180)
			(layer "F.Fab")
			(effects
				(font
					(size 1.27 1.27)
				)
			)
		)
		(duplicate_pad_numbers_are_jumpers no)
		(fp_line
			(start 0.7874 0.4064)
			(end -0.7874 0.4064)
			(stroke
				(width 0.1524)
				(type default)
			)
			(layer "F.SilkS")
		)
		(fp_line
			(start 0.7874 -0.4064)
			(end 0.7874 0.4064)
			(stroke
				(width 0.1524)
				(type default)
			)
			(layer "F.SilkS")
		)
		(fp_line
			(start -0.7874 0.4064)
			(end -0.7874 -0.4064)
			(stroke
				(width 0.1524)
				(type default)
			)
			(layer "F.SilkS")
		)
		(fp_line
			(start -0.7874 -0.4064)
			(end 0.7874 -0.4064)
			(stroke
				(width 0.1524)
				(type default)
			)
			(layer "F.SilkS")
		)
		(fp_line
			(start 0.67945 0.3048)
			(end 0.120396 0.3048)
			(stroke
				(width 0.1)
				(type default)
			)
			(layer "F.Fab")
		)
		(fp_line
			(start 0.67945 -0.3048)
			(end 0.67945 0.3048)
			(stroke
				(width 0.1)
				(type default)
			)
			(layer "F.Fab")
		)
		(fp_line
			(start 0.12065 -0.2794)
			(end 0.12065 -0.3048)
			(stroke
				(width 0.1)
				(type default)
			)
			(layer "F.Fab")
		)
		(fp_line
			(start 0.12065 -0.3048)
			(end 0.67945 -0.3048)
			(stroke
				(width 0.1)
				(type default)
			)
			(layer "F.Fab")
		)
		(fp_line
			(start 0.120396 0.3048)
			(end 0.120396 0.2794)
			(stroke
				(width 0.1)
				(type default)
			)
			(layer "F.Fab")
		)
		(fp_line
			(start 0.120396 0.2794)
			(end -0.12065 0.2794)
			(stroke
				(width 0.1)
				(type default)
			)
			(layer "F.Fab")
		)
		(fp_line
			(start -0.12065 0.3048)
			(end -0.67945 0.3048)
			(stroke
				(width 0.1)
				(type default)
			)
			(layer "F.Fab")
		)
		(fp_line
			(start -0.12065 0.2794)
			(end -0.12065 0.3048)
			(stroke
				(width 0.1)
				(type default)
			)
			(layer "F.Fab")
		)
		(fp_line
			(start -0.12065 -0.2794)
			(end 0.12065 -0.2794)
			(stroke
				(width 0.1)
				(type default)
			)
			(layer "F.Fab")
		)
		(fp_line
			(start -0.12065 -0.305054)
			(end -0.12065 -0.2794)
			(stroke
				(width 0.1)
				(type default)
			)
			(layer "F.Fab")
		)
		(fp_line
			(start -0.67945 0.3048)
			(end -0.67945 -0.305054)
			(stroke
				(width 0.1)
				(type default)
			)
			(layer "F.Fab")
		)
		(fp_line
			(start -0.67945 -0.305054)
			(end -0.12065 -0.305054)
			(stroke
				(width 0.1)
				(type default)
			)
			(layer "F.Fab")
		)
		(pad "1" smd circle
			(at -0.40005 0 180)
			(size 0 0)
			(layers "F.Cu" "F.Mask" "F.Paste")
			(net "P3V3_OCP_SFF_R")
		)
		(pad "2" smd circle
			(at 0.40005 0 180)
			(size 0 0)
			(layers "F.Cu" "F.Mask" "F.Paste")
			(net "GND")
		)
	)
	(footprint ""
		(layer "F.Cu")
		(at 12.351004 -139.25804 90)
		(property "Reference" "R4079"
			(at 0 0 90)
			(layer "F.SilkS")
			(hide yes)
			(effects
				(font
					(size 1.27 1.27)
				)
			)
		)
		(property "Value" ""
			(at 0 0 90)
			(layer "F.Fab")
			(effects
				(font
					(size 1.27 1.27)
				)
			)
		)
		(duplicate_pad_numbers_are_jumpers no)
		(fp_line
			(start 0.7874 -0.4064)
			(end 0.7874 0.4064)
			(stroke
				(width 0.1524)
				(type default)
			)
			(layer "F.SilkS")
		)
		(fp_line
			(start -0.7874 -0.4064)
			(end 0.7874 -0.4064)
			(stroke
				(width 0.1524)
				(type default)
			)
			(layer "F.SilkS")
		)
		(fp_line
			(start 0.7874 0.4064)
			(end -0.7874 0.4064)
			(stroke
				(width 0.1524)
				(type default)
			)
			(layer "F.SilkS")
		)
		(fp_line
			(start -0.7874 0.4064)
			(end -0.7874 -0.4064)
			(stroke
				(width 0.1524)
				(type default)
			)
			(layer "F.SilkS")
		)
		(fp_line
			(start -0.12065 -0.305054)
			(end -0.12065 -0.2794)
			(stroke
				(width 0.1)
				(type default)
			)
			(layer "F.Fab")
		)
		(fp_line
			(start -0.67945 -0.305054)
			(end -0.12065 -0.305054)
			(stroke
				(width 0.1)
				(type default)
			)
			(layer "F.Fab")
		)
		(fp_line
			(start 0.67945 -0.3048)
			(end 0.67945 0.3048)
			(stroke
				(width 0.1)
				(type default)
			)
			(layer "F.Fab")
		)
		(fp_line
			(start 0.12065 -0.3048)
			(end 0.67945 -0.3048)
			(stroke
				(width 0.1)
				(type default)
			)
			(layer "F.Fab")
		)
		(fp_line
			(start 0.12065 -0.2794)
			(end 0.12065 -0.3048)
			(stroke
				(width 0.1)
				(type default)
			)
			(layer "F.Fab")
		)
		(fp_line
			(start -0.12065 -0.2794)
			(end 0.12065 -0.2794)
			(stroke
				(width 0.1)
				(type default)
			)
			(layer "F.Fab")
		)
		(fp_line
			(start 0.120396 0.2794)
			(end -0.12065 0.2794)
			(stroke
				(width 0.1)
				(type default)
			)
			(layer "F.Fab")
		)
		(fp_line
			(start -0.12065 0.2794)
			(end -0.12065 0.3048)
			(stroke
				(width 0.1)
				(type default)
			)
			(layer "F.Fab")
		)
		(fp_line
			(start 0.67945 0.3048)
			(end 0.120396 0.3048)
			(stroke
				(width 0.1)
				(type default)
			)
			(layer "F.Fab")
		)
		(fp_line
			(start 0.120396 0.3048)
			(end 0.120396 0.2794)
			(stroke
				(width 0.1)
				(type default)
			)
			(layer "F.Fab")
		)
		(fp_line
			(start -0.12065 0.3048)
			(end -0.67945 0.3048)
			(stroke
				(width 0.1)
				(type default)
			)
			(layer "F.Fab")
		)
		(fp_line
			(start -0.67945 0.3048)
			(end -0.67945 -0.305054)
			(stroke
				(width 0.1)
				(type default)
			)
			(layer "F.Fab")
		)
		(pad "1" smd circle
			(at -0.40005 0 90)
			(size 0 0)
			(layers "F.Cu" "F.Mask" "F.Paste")
			(net "FG_SS_EN")
		)
		(pad "2" smd circle
			(at 0.40005 0 90)
			(size 0 0)
			(layers "F.Cu" "F.Mask" "F.Paste")
			(net "GND")
		)
	)
	(footprint ""
		(layer "F.Cu")
		(at 166.070534 -21.783548 90)
		(property "Reference" "R87"
			(at 0 0 90)
			(layer "F.SilkS")
			(hide yes)
			(effects
				(font
					(size 1.27 1.27)
				)
			)
		)
		(property "Value" ""
			(at 0 0 90)
			(layer "F.Fab")
			(effects
				(font
					(size 1.27 1.27)
				)
			)
		)
		(duplicate_pad_numbers_are_jumpers no)
		(fp_line
			(start 0.7874 -0.4064)
			(end 0.7874 0.4064)
			(stroke
				(width 0.1524)
				(type default)
			)
			(layer "F.SilkS")
		)
		(fp_line
			(start -0.7874 -0.4064)
			(end 0.7874 -0.4064)
			(stroke
				(width 0.1524)
				(type default)
			)
			(layer "F.SilkS")
		)
		(fp_line
			(start 0.7874 0.4064)
			(end -0.7874 0.4064)
			(stroke
				(width 0.1524)
				(type default)
			)
			(layer "F.SilkS")
		)
		(fp_line
			(start -0.7874 0.4064)
			(end -0.7874 -0.4064)
			(stroke
				(width 0.1524)
				(type default)
			)
			(layer "F.SilkS")
		)
		(fp_line
			(start -0.12065 -0.305054)
			(end -0.12065 -0.2794)
			(stroke
				(width 0.1)
				(type default)
			)
			(layer "F.Fab")
		)
		(fp_line
			(start -0.67945 -0.305054)
			(end -0.12065 -0.305054)
			(stroke
				(width 0.1)
				(type default)
			)
			(layer "F.Fab")
		)
		(fp_line
			(start 0.67945 -0.3048)
			(end 0.67945 0.3048)
			(stroke
				(width 0.1)
				(type default)
			)
			(layer "F.Fab")
		)
		(fp_line
			(start 0.12065 -0.3048)
			(end 0.67945 -0.3048)
			(stroke
				(width 0.1)
				(type default)
			)
			(layer "F.Fab")
		)
		(fp_line
			(start 0.12065 -0.2794)
			(end 0.12065 -0.3048)
			(stroke
				(width 0.1)
				(type default)
			)
			(layer "F.Fab")
		)
		(fp_line
			(start -0.12065 -0.2794)
			(end 0.12065 -0.2794)
			(stroke
				(width 0.1)
				(type default)
			)
			(layer "F.Fab")
		)
		(fp_line
			(start 0.120396 0.2794)
			(end -0.12065 0.2794)
			(stroke
				(width 0.1)
				(type default)
			)
			(layer "F.Fab")
		)
		(fp_line
			(start -0.12065 0.2794)
			(end -0.12065 0.3048)
			(stroke
				(width 0.1)
				(type default)
			)
			(layer "F.Fab")
		)
		(fp_line
			(start 0.67945 0.3048)
			(end 0.120396 0.3048)
			(stroke
				(width 0.1)
				(type default)
			)
			(layer "F.Fab")
		)
		(fp_line
			(start 0.120396 0.3048)
			(end 0.120396 0.2794)
			(stroke
				(width 0.1)
				(type default)
			)
			(layer "F.Fab")
		)
		(fp_line
			(start -0.12065 0.3048)
			(end -0.67945 0.3048)
			(stroke
				(width 0.1)
				(type default)
			)
			(layer "F.Fab")
		)
		(fp_line
			(start -0.67945 0.3048)
			(end -0.67945 -0.305054)
			(stroke
				(width 0.1)
				(type default)
			)
			(layer "F.Fab")
		)
		(pad "1" smd circle
			(at -0.40005 0 90)
			(size 0 0)
			(layers "F.Cu" "F.Mask" "F.Paste")
			(net "RMII_BMC_OCP_RX_ER")
		)
		(pad "2" smd circle
			(at 0.40005 0 90)
			(size 0 0)
			(layers "F.Cu" "F.Mask" "F.Paste")
			(net "GND")
		)
	)
	(footprint ""
		(layer "F.Cu")
		(at 390.921748 -16.100298 90)
		(property "Reference" "C1549"
			(at 0 0 90)
			(layer "F.SilkS")
			(hide yes)
			(effects
				(font
					(size 1.27 1.27)
				)
			)
		)
		(property "Value" ""
			(at 0 0 90)
			(layer "F.Fab")
			(effects
				(font
					(size 1.27 1.27)
				)
			)
		)
		(duplicate_pad_numbers_are_jumpers no)
		(fp_line
			(start 0.299974 -0.150114)
			(end 0.299974 0.150114)
			(stroke
				(width 0.1)
				(type default)
			)
			(layer "F.Fab")
		)
		(fp_line
			(start -0.299974 -0.150114)
			(end 0.299974 -0.150114)
			(stroke
				(width 0.1)
				(type default)
			)
			(layer "F.Fab")
		)
		(fp_line
			(start 0.299974 0.150114)
			(end -0.299974 0.150114)
			(stroke
				(width 0.1)
				(type default)
			)
			(layer "F.Fab")
		)
		(fp_line
			(start -0.299974 0.150114)
			(end -0.299974 -0.150114)
			(stroke
				(width 0.1)
				(type default)
			)
			(layer "F.Fab")
		)
		(pad "1" smd rect
			(at -0.2667 0 90)
			(size 0.3048 0.381)
			(layers "F.Cu" "F.Mask" "F.Paste")
			(net "P5E_CPU0_G3_TX_C_DP<15>")
		)
		(pad "2" smd rect
			(at 0.2667 0 90)
			(size 0.3048 0.381)
			(layers "F.Cu" "F.Mask" "F.Paste")
			(net "P5E_CPU0_G3_TX_DP<15>")
		)
	)
	(footprint ""
		(layer "F.Cu")
		(at 319.105026 -339.647022 90)
		(property "Reference" "PR90"
			(at 0 0 90)
			(layer "F.SilkS")
			(hide yes)
			(effects
				(font
					(size 1.27 1.27)
				)
			)
		)
		(property "Value" ""
			(at 0 0 90)
			(layer "F.Fab")
			(effects
				(font
					(size 1.27 1.27)
				)
			)
		)
		(duplicate_pad_numbers_are_jumpers no)
		(fp_line
			(start 0.7874 -0.4064)
			(end 0.7874 0.4064)
			(stroke
				(width 0.1524)
				(type default)
			)
			(layer "F.SilkS")
		)
		(fp_line
			(start -0.7874 -0.4064)
			(end 0.7874 -0.4064)
			(stroke
				(width 0.1524)
				(type default)
			)
			(layer "F.SilkS")
		)
		(fp_line
			(start 0.7874 0.4064)
			(end -0.7874 0.4064)
			(stroke
				(width 0.1524)
				(type default)
			)
			(layer "F.SilkS")
		)
		(fp_line
			(start -0.7874 0.4064)
			(end -0.7874 -0.4064)
			(stroke
				(width 0.1524)
				(type default)
			)
			(layer "F.SilkS")
		)
		(fp_line
			(start -0.12065 -0.305054)
			(end -0.12065 -0.2794)
			(stroke
				(width 0.1)
				(type default)
			)
			(layer "F.Fab")
		)
		(fp_line
			(start -0.67945 -0.305054)
			(end -0.12065 -0.305054)
			(stroke
				(width 0.1)
				(type default)
			)
			(layer "F.Fab")
		)
		(fp_line
			(start 0.67945 -0.3048)
			(end 0.67945 0.3048)
			(stroke
				(width 0.1)
				(type default)
			)
			(layer "F.Fab")
		)
		(fp_line
			(start 0.12065 -0.3048)
			(end 0.67945 -0.3048)
			(stroke
				(width 0.1)
				(type default)
			)
			(layer "F.Fab")
		)
		(fp_line
			(start 0.12065 -0.2794)
			(end 0.12065 -0.3048)
			(stroke
				(width 0.1)
				(type default)
			)
			(layer "F.Fab")
		)
		(fp_line
			(start -0.12065 -0.2794)
			(end 0.12065 -0.2794)
			(stroke
				(width 0.1)
				(type default)
			)
			(layer "F.Fab")
		)
		(fp_line
			(start 0.120396 0.2794)
			(end -0.12065 0.2794)
			(stroke
				(width 0.1)
				(type default)
			)
			(layer "F.Fab")
		)
		(fp_line
			(start -0.12065 0.2794)
			(end -0.12065 0.3048)
			(stroke
				(width 0.1)
				(type default)
			)
			(layer "F.Fab")
		)
		(fp_line
			(start 0.67945 0.3048)
			(end 0.120396 0.3048)
			(stroke
				(width 0.1)
				(type default)
			)
			(layer "F.Fab")
		)
		(fp_line
			(start 0.120396 0.3048)
			(end 0.120396 0.2794)
			(stroke
				(width 0.1)
				(type default)
			)
			(layer "F.Fab")
		)
		(fp_line
			(start -0.12065 0.3048)
			(end -0.67945 0.3048)
			(stroke
				(width 0.1)
				(type default)
			)
			(layer "F.Fab")
		)
		(fp_line
			(start -0.67945 0.3048)
			(end -0.67945 -0.305054)
			(stroke
				(width 0.1)
				(type default)
			)
			(layer "F.Fab")
		)
		(pad "1" smd circle
			(at -0.40005 0 90)
			(size 0 0)
			(layers "F.Cu" "F.Mask" "F.Paste")
			(net "SW_PVDDCR_CPU1_P0_BOOT3")
		)
		(pad "2" smd circle
			(at 0.40005 0 90)
			(size 0 0)
			(layers "F.Cu" "F.Mask" "F.Paste")
			(net "SW_PVDDCR_CPU1_P0_BOOT3_R")
		)
	)
	(footprint ""
		(layer "F.Cu")
		(at 430.02835 -399.72488 180)
		(property "Reference" "R1058"
			(at 0 0 180)
			(layer "F.SilkS")
			(hide yes)
			(effects
				(font
					(size 1.27 1.27)
				)
			)
		)
		(property "Value" ""
			(at 0 0 180)
			(layer "F.Fab")
			(effects
				(font
					(size 1.27 1.27)
				)
			)
		)
		(duplicate_pad_numbers_are_jumpers no)
		(fp_line
			(start 0.32512 0.175006)
			(end -0.32512 0.175006)
			(stroke
				(width 0.1)
				(type default)
			)
			(layer "F.Fab")
		)
		(fp_line
			(start 0.32512 -0.175006)
			(end 0.32512 0.175006)
			(stroke
				(width 0.1)
				(type default)
			)
			(layer "F.Fab")
		)
		(fp_line
			(start -0.32512 0.175006)
			(end -0.32512 -0.175006)
			(stroke
				(width 0.1)
				(type default)
			)
			(layer "F.Fab")
		)
		(fp_line
			(start -0.32512 -0.175006)
			(end 0.32512 -0.175006)
			(stroke
				(width 0.1)
				(type default)
			)
			(layer "F.Fab")
		)
		(pad "1" smd rect
			(at -0.2667 0 180)
			(size 0.3048 0.381)
			(layers "F.Cu" "F.Mask" "F.Paste")
			(net "RT_CPU0_P2_ADDR2")
		)
		(pad "2" smd rect
			(at 0.2667 0)
			(size 0.3048 0.381)
			(layers "F.Cu" "F.Mask" "F.Paste")
			(net "GND")
		)
	)
	(footprint ""
		(layer "F.Cu")
		(at 197.269608 -115.657376)
		(property "Reference" "R4171"
			(at 0 0 0)
			(layer "F.SilkS")
			(hide yes)
			(effects
				(font
					(size 1.27 1.27)
				)
			)
		)
		(property "Value" ""
			(at 0 0 0)
			(layer "F.Fab")
			(effects
				(font
					(size 1.27 1.27)
				)
			)
		)
		(duplicate_pad_numbers_are_jumpers no)
		(fp_line
			(start -0.7874 -0.4064)
			(end 0.7874 -0.4064)
			(stroke
				(width 0.1524)
				(type default)
			)
			(layer "F.SilkS")
		)
		(fp_line
			(start -0.7874 0.4064)
			(end -0.7874 -0.4064)
			(stroke
				(width 0.1524)
				(type default)
			)
			(layer "F.SilkS")
		)
		(fp_line
			(start 0.7874 -0.4064)
			(end 0.7874 0.4064)
			(stroke
				(width 0.1524)
				(type default)
			)
			(layer "F.SilkS")
		)
		(fp_line
			(start 0.7874 0.4064)
			(end -0.7874 0.4064)
			(stroke
				(width 0.1524)
				(type default)
			)
			(layer "F.SilkS")
		)
		(fp_line
			(start -0.67945 -0.305054)
			(end -0.12065 -0.305054)
			(stroke
				(width 0.1)
				(type default)
			)
			(layer "F.Fab")
		)
		(fp_line
			(start -0.67945 0.3048)
			(end -0.67945 -0.305054)
			(stroke
				(width 0.1)
				(type default)
			)
			(layer "F.Fab")
		)
		(fp_line
			(start -0.12065 -0.305054)
			(end -0.12065 -0.2794)
			(stroke
				(width 0.1)
				(type default)
			)
			(layer "F.Fab")
		)
		(fp_line
			(start -0.12065 -0.2794)
			(end 0.12065 -0.2794)
			(stroke
				(width 0.1)
				(type default)
			)
			(layer "F.Fab")
		)
		(fp_line
			(start -0.12065 0.2794)
			(end -0.12065 0.3048)
			(stroke
				(width 0.1)
				(type default)
			)
			(layer "F.Fab")
		)
		(fp_line
			(start -0.12065 0.3048)
			(end -0.67945 0.3048)
			(stroke
				(width 0.1)
				(type default)
			)
			(layer "F.Fab")
		)
		(fp_line
			(start 0.120396 0.2794)
			(end -0.12065 0.2794)
			(stroke
				(width 0.1)
				(type default)
			)
			(layer "F.Fab")
		)
		(fp_line
			(start 0.120396 0.3048)
			(end 0.120396 0.2794)
			(stroke
				(width 0.1)
				(type default)
			)
			(layer "F.Fab")
		)
		(fp_line
			(start 0.12065 -0.3048)
			(end 0.67945 -0.3048)
			(stroke
				(width 0.1)
				(type default)
			)
			(layer "F.Fab")
		)
		(fp_line
			(start 0.12065 -0.2794)
			(end 0.12065 -0.3048)
			(stroke
				(width 0.1)
				(type default)
			)
			(layer "F.Fab")
		)
		(fp_line
			(start 0.67945 -0.3048)
			(end 0.67945 0.3048)
			(stroke
				(width 0.1)
				(type default)
			)
			(layer "F.Fab")
		)
		(fp_line
			(start 0.67945 0.3048)
			(end 0.120396 0.3048)
			(stroke
				(width 0.1)
				(type default)
			)
			(layer "F.Fab")
		)
		(pad "1" smd circle
			(at -0.40005 0)
			(size 0 0)
			(layers "F.Cu" "F.Mask" "F.Paste")
			(net "GPU_3V3IO_RSVD3_ISO_R")
		)
		(pad "2" smd circle
			(at 0.40005 0)
			(size 0 0)
			(layers "F.Cu" "F.Mask" "F.Paste")
			(net "GPU_3V3IO_RSVD3_ISO")
		)
	)
	(footprint ""
		(layer "F.Cu")
		(at 335.176876 -325.656448)
		(property "Reference" "PL10"
			(at -3.115056 -15.887446 0)
			(unlocked yes)
			(layer "F.SilkS")
			(effects
				(font
					(size 0.7874 0.5842)
					(thickness 0.1524)
				)
				(justify left)
			)
		)
		(property "Value" ""
			(at 0 0 0)
			(layer "F.Fab")
			(effects
				(font
					(size 1.27 1.27)
				)
			)
		)
		(duplicate_pad_numbers_are_jumpers no)
		(fp_line
			(start -3.750056 -5.500116)
			(end -2.393442 -5.500116)
			(stroke
				(width 0.1524)
				(type default)
			)
			(layer "F.SilkS")
		)
		(fp_line
			(start -3.750056 5.500116)
			(end -3.750056 -5.500116)
			(stroke
				(width 0.1524)
				(type default)
			)
			(layer "F.SilkS")
		)
		(fp_line
			(start -2.393442 5.500116)
			(end -3.750056 5.500116)
			(stroke
				(width 0.1524)
				(type default)
			)
			(layer "F.SilkS")
		)
		(fp_line
			(start 2.393442 5.500116)
			(end 3.750056 5.500116)
			(stroke
				(width 0.1524)
				(type default)
			)
			(layer "F.SilkS")
		)
		(fp_line
			(start 3.750056 -5.500116)
			(end 2.393442 -5.500116)
			(stroke
				(width 0.1524)
				(type default)
			)
			(layer "F.SilkS")
		)
		(fp_line
			(start 3.750056 5.500116)
			(end 3.750056 -5.500116)
			(stroke
				(width 0.1524)
				(type default)
			)
			(layer "F.SilkS")
		)
		(fp_poly
			(pts
				(xy -3.9116 -4.249928) (xy -4.3434 -4.034028) (xy -4.3434 -4.465828)
			)
			(stroke
				(width 0)
				(type default)
			)
			(fill yes)
			(layer "F.SilkS")
		)
		(fp_line
			(start -3.750056 -5.500116)
			(end -3.750056 5.500116)
			(stroke
				(width 0.1)
				(type default)
			)
			(layer "F.Fab")
		)
		(fp_line
			(start -3.750056 5.500116)
			(end 3.750056 5.500116)
			(stroke
				(width 0.1)
				(type default)
			)
			(layer "F.Fab")
		)
		(fp_line
			(start 3.750056 -5.500116)
			(end -3.750056 -5.500116)
			(stroke
				(width 0.1)
				(type default)
			)
			(layer "F.Fab")
		)
		(fp_line
			(start 3.750056 5.500116)
			(end 3.750056 -5.500116)
			(stroke
				(width 0.1)
				(type default)
			)
			(layer "F.Fab")
		)
		(fp_poly
			(pts
				(xy -4.9276 -4.757928) (xy -4.9276 -3.741928) (xy -3.9116 -4.249928)
			)
			(stroke
				(width 0)
				(type default)
			)
			(fill yes)
			(layer "F.Fab")
		)
		(pad "1" smd rect
			(at 0 -4.249928 270)
			(size 2.413 4.5212)
			(layers "F.Cu" "F.Mask" "F.Paste")
			(net "SW_PVDDCR_CPU1_P0_SW1")
		)
		(pad "2" smd rect
			(at 0 -1.175004 270)
			(size 1.3716 4.5212)
			(layers "F.Cu" "F.Mask" "F.Paste")
			(net "IND_CPU1_P0_CPL5")
		)
		(pad "3" smd rect
			(at 0 1.175004 270)
			(size 1.3716 4.5212)
			(layers "F.Cu" "F.Mask" "F.Paste")
			(net "IND_CPU1_P0_CPL1")
		)
		(pad "4" smd rect
			(at 0 4.249928 270)
			(size 2.413 4.5212)
			(layers "F.Cu" "F.Mask" "F.Paste")
			(net "PVDDCR_CPU1_P0")
		)
	)
	(footprint ""
		(layer "F.Cu")
		(at 303.323498 -429.2219 180)
		(property "Reference" "R4577"
			(at 0 0 180)
			(layer "F.SilkS")
			(hide yes)
			(effects
				(font
					(size 1.27 1.27)
				)
			)
		)
		(property "Value" ""
			(at 0 0 180)
			(layer "F.Fab")
			(effects
				(font
					(size 1.27 1.27)
				)
			)
		)
		(duplicate_pad_numbers_are_jumpers no)
		(fp_line
			(start 0.7874 0.4064)
			(end -0.7874 0.4064)
			(stroke
				(width 0.1524)
				(type default)
			)
			(layer "F.SilkS")
		)
		(fp_line
			(start 0.7874 -0.4064)
			(end 0.7874 0.4064)
			(stroke
				(width 0.1524)
				(type default)
			)
			(layer "F.SilkS")
		)
		(fp_line
			(start -0.7874 0.4064)
			(end -0.7874 -0.4064)
			(stroke
				(width 0.1524)
				(type default)
			)
			(layer "F.SilkS")
		)
		(fp_line
			(start -0.7874 -0.4064)
			(end 0.7874 -0.4064)
			(stroke
				(width 0.1524)
				(type default)
			)
			(layer "F.SilkS")
		)
		(fp_line
			(start 0.67945 0.3048)
			(end 0.120396 0.3048)
			(stroke
				(width 0.1)
				(type default)
			)
			(layer "F.Fab")
		)
		(fp_line
			(start 0.67945 -0.3048)
			(end 0.67945 0.3048)
			(stroke
				(width 0.1)
				(type default)
			)
			(layer "F.Fab")
		)
		(fp_line
			(start 0.12065 -0.2794)
			(end 0.12065 -0.3048)
			(stroke
				(width 0.1)
				(type default)
			)
			(layer "F.Fab")
		)
		(fp_line
			(start 0.12065 -0.3048)
			(end 0.67945 -0.3048)
			(stroke
				(width 0.1)
				(type default)
			)
			(layer "F.Fab")
		)
		(fp_line
			(start 0.120396 0.3048)
			(end 0.120396 0.2794)
			(stroke
				(width 0.1)
				(type default)
			)
			(layer "F.Fab")
		)
		(fp_line
			(start 0.120396 0.2794)
			(end -0.12065 0.2794)
			(stroke
				(width 0.1)
				(type default)
			)
			(layer "F.Fab")
		)
		(fp_line
			(start -0.12065 0.3048)
			(end -0.67945 0.3048)
			(stroke
				(width 0.1)
				(type default)
			)
			(layer "F.Fab")
		)
		(fp_line
			(start -0.12065 0.2794)
			(end -0.12065 0.3048)
			(stroke
				(width 0.1)
				(type default)
			)
			(layer "F.Fab")
		)
		(fp_line
			(start -0.12065 -0.2794)
			(end 0.12065 -0.2794)
			(stroke
				(width 0.1)
				(type default)
			)
			(layer "F.Fab")
		)
		(fp_line
			(start -0.12065 -0.305054)
			(end -0.12065 -0.2794)
			(stroke
				(width 0.1)
				(type default)
			)
			(layer "F.Fab")
		)
		(fp_line
			(start -0.67945 0.3048)
			(end -0.67945 -0.305054)
			(stroke
				(width 0.1)
				(type default)
			)
			(layer "F.Fab")
		)
		(fp_line
			(start -0.67945 -0.305054)
			(end -0.12065 -0.305054)
			(stroke
				(width 0.1)
				(type default)
			)
			(layer "F.Fab")
		)
		(pad "1" smd circle
			(at -0.40005 0 180)
			(size 0 0)
			(layers "F.Cu" "F.Mask" "F.Paste")
			(net "GPU_3V3IO_RSVD3_FFU")
		)
		(pad "2" smd circle
			(at 0.40005 0 180)
			(size 0 0)
			(layers "F.Cu" "F.Mask" "F.Paste")
			(net "GPU_3V3IO_RSVD3_FFU_ISO")
		)
	)
	(footprint ""
		(layer "F.Cu")
		(at 310.48198 -351.368106 -90)
		(property "Reference" "PC121"
			(at 0 0 270)
			(layer "F.SilkS")
			(hide yes)
			(effects
				(font
					(size 1.27 1.27)
				)
			)
		)
		(property "Value" ""
			(at 0 0 270)
			(layer "F.Fab")
			(effects
				(font
					(size 1.27 1.27)
				)
			)
		)
		(duplicate_pad_numbers_are_jumpers no)
		(fp_line
			(start -0.7874 0.4064)
			(end -0.7874 -0.4064)
			(stroke
				(width 0.1524)
				(type default)
			)
			(layer "F.SilkS")
		)
		(fp_line
			(start 0.7874 0.4064)
			(end -0.7874 0.4064)
			(stroke
				(width 0.1524)
				(type default)
			)
			(layer "F.SilkS")
		)
		(fp_line
			(start -0.7874 -0.4064)
			(end 0.7874 -0.4064)
			(stroke
				(width 0.1524)
				(type default)
			)
			(layer "F.SilkS")
		)
		(fp_line
			(start 0.7874 -0.4064)
			(end 0.7874 0.4064)
			(stroke
				(width 0.1524)
				(type default)
			)
			(layer "F.SilkS")
		)
		(fp_line
			(start -0.67945 0.3048)
			(end -0.67945 -0.305054)
			(stroke
				(width 0.1)
				(type default)
			)
			(layer "F.Fab")
		)
		(fp_line
			(start -0.12065 0.3048)
			(end -0.67945 0.3048)
			(stroke
				(width 0.1)
				(type default)
			)
			(layer "F.Fab")
		)
		(fp_line
			(start 0.120396 0.3048)
			(end 0.120396 0.2794)
			(stroke
				(width 0.1)
				(type default)
			)
			(layer "F.Fab")
		)
		(fp_line
			(start 0.67945 0.3048)
			(end 0.120396 0.3048)
			(stroke
				(width 0.1)
				(type default)
			)
			(layer "F.Fab")
		)
		(fp_line
			(start -0.12065 0.2794)
			(end -0.12065 0.3048)
			(stroke
				(width 0.1)
				(type default)
			)
			(layer "F.Fab")
		)
		(fp_line
			(start 0.120396 0.2794)
			(end -0.12065 0.2794)
			(stroke
				(width 0.1)
				(type default)
			)
			(layer "F.Fab")
		)
		(fp_line
			(start -0.12065 -0.2794)
			(end 0.12065 -0.2794)
			(stroke
				(width 0.1)
				(type default)
			)
			(layer "F.Fab")
		)
		(fp_line
			(start 0.12065 -0.2794)
			(end 0.12065 -0.3048)
			(stroke
				(width 0.1)
				(type default)
			)
			(layer "F.Fab")
		)
		(fp_line
			(start 0.12065 -0.3048)
			(end 0.67945 -0.3048)
			(stroke
				(width 0.1)
				(type default)
			)
			(layer "F.Fab")
		)
		(fp_line
			(start 0.67945 -0.3048)
			(end 0.67945 0.3048)
			(stroke
				(width 0.1)
				(type default)
			)
			(layer "F.Fab")
		)
		(fp_line
			(start -0.67945 -0.305054)
			(end -0.12065 -0.305054)
			(stroke
				(width 0.1)
				(type default)
			)
			(layer "F.Fab")
		)
		(fp_line
			(start -0.12065 -0.305054)
			(end -0.12065 -0.2794)
			(stroke
				(width 0.1)
				(type default)
			)
			(layer "F.Fab")
		)
		(pad "1" smd circle
			(at -0.40005 0 270)
			(size 0 0)
			(layers "F.Cu" "F.Mask" "F.Paste")
			(net "SW_PVDDCR_CPU1_P0_BOOT4_R")
		)
		(pad "2" smd circle
			(at 0.40005 0 270)
			(size 0 0)
			(layers "F.Cu" "F.Mask" "F.Paste")
			(net "SW_PVDDCR_CPU1_P0_BOOTR4")
		)
	)
	(footprint ""
		(layer "F.Cu")
		(at 250.55957 -69.962522 180)
		(property "Reference" "R6049"
			(at 0 0 180)
			(layer "F.SilkS")
			(hide yes)
			(effects
				(font
					(size 1.27 1.27)
				)
			)
		)
		(property "Value" ""
			(at 0 0 180)
			(layer "F.Fab")
			(effects
				(font
					(size 1.27 1.27)
				)
			)
		)
		(duplicate_pad_numbers_are_jumpers no)
		(fp_line
			(start 0.7874 0.4064)
			(end -0.7874 0.4064)
			(stroke
				(width 0.1524)
				(type default)
			)
			(layer "F.SilkS")
		)
		(fp_line
			(start 0.7874 -0.4064)
			(end 0.7874 0.4064)
			(stroke
				(width 0.1524)
				(type default)
			)
			(layer "F.SilkS")
		)
		(fp_line
			(start -0.7874 0.4064)
			(end -0.7874 -0.4064)
			(stroke
				(width 0.1524)
				(type default)
			)
			(layer "F.SilkS")
		)
		(fp_line
			(start -0.7874 -0.4064)
			(end 0.7874 -0.4064)
			(stroke
				(width 0.1524)
				(type default)
			)
			(layer "F.SilkS")
		)
		(fp_line
			(start 0.67945 0.3048)
			(end 0.120396 0.3048)
			(stroke
				(width 0.1)
				(type default)
			)
			(layer "F.Fab")
		)
		(fp_line
			(start 0.67945 -0.3048)
			(end 0.67945 0.3048)
			(stroke
				(width 0.1)
				(type default)
			)
			(layer "F.Fab")
		)
		(fp_line
			(start 0.12065 -0.2794)
			(end 0.12065 -0.3048)
			(stroke
				(width 0.1)
				(type default)
			)
			(layer "F.Fab")
		)
		(fp_line
			(start 0.12065 -0.3048)
			(end 0.67945 -0.3048)
			(stroke
				(width 0.1)
				(type default)
			)
			(layer "F.Fab")
		)
		(fp_line
			(start 0.120396 0.3048)
			(end 0.120396 0.2794)
			(stroke
				(width 0.1)
				(type default)
			)
			(layer "F.Fab")
		)
		(fp_line
			(start 0.120396 0.2794)
			(end -0.12065 0.2794)
			(stroke
				(width 0.1)
				(type default)
			)
			(layer "F.Fab")
		)
		(fp_line
			(start -0.12065 0.3048)
			(end -0.67945 0.3048)
			(stroke
				(width 0.1)
				(type default)
			)
			(layer "F.Fab")
		)
		(fp_line
			(start -0.12065 0.2794)
			(end -0.12065 0.3048)
			(stroke
				(width 0.1)
				(type default)
			)
			(layer "F.Fab")
		)
		(fp_line
			(start -0.12065 -0.2794)
			(end 0.12065 -0.2794)
			(stroke
				(width 0.1)
				(type default)
			)
			(layer "F.Fab")
		)
		(fp_line
			(start -0.12065 -0.305054)
			(end -0.12065 -0.2794)
			(stroke
				(width 0.1)
				(type default)
			)
			(layer "F.Fab")
		)
		(fp_line
			(start -0.67945 0.3048)
			(end -0.67945 -0.305054)
			(stroke
				(width 0.1)
				(type default)
			)
			(layer "F.Fab")
		)
		(fp_line
			(start -0.67945 -0.305054)
			(end -0.12065 -0.305054)
			(stroke
				(width 0.1)
				(type default)
			)
			(layer "F.Fab")
		)
		(pad "1" smd circle
			(at -0.40005 0 180)
			(size 0 0)
			(layers "F.Cu" "F.Mask" "F.Paste")
			(net "P3V3_E1S_EN_0_R")
		)
		(pad "2" smd circle
			(at 0.40005 0 180)
			(size 0 0)
			(layers "F.Cu" "F.Mask" "F.Paste")
			(net "GND")
		)
	)
	(footprint ""
		(layer "F.Cu")
		(at 299.265594 -393.04468)
		(property "Reference" "R980"
			(at 0 0 0)
			(layer "F.SilkS")
			(hide yes)
			(effects
				(font
					(size 1.27 1.27)
				)
			)
		)
		(property "Value" ""
			(at 0 0 0)
			(layer "F.Fab")
			(effects
				(font
					(size 1.27 1.27)
				)
			)
		)
		(duplicate_pad_numbers_are_jumpers no)
		(fp_line
			(start -0.32512 -0.175006)
			(end 0.32512 -0.175006)
			(stroke
				(width 0.1)
				(type default)
			)
			(layer "F.Fab")
		)
		(fp_line
			(start -0.32512 0.175006)
			(end -0.32512 -0.175006)
			(stroke
				(width 0.1)
				(type default)
			)
			(layer "F.Fab")
		)
		(fp_line
			(start 0.32512 -0.175006)
			(end 0.32512 0.175006)
			(stroke
				(width 0.1)
				(type default)
			)
			(layer "F.Fab")
		)
		(fp_line
			(start 0.32512 0.175006)
			(end -0.32512 0.175006)
			(stroke
				(width 0.1)
				(type default)
			)
			(layer "F.Fab")
		)
		(pad "1" smd rect
			(at -0.2667 0)
			(size 0.3048 0.381)
			(layers "F.Cu" "F.Mask" "F.Paste")
			(net "GPIO3_RT_CPU0_P0")
		)
		(pad "2" smd rect
			(at 0.2667 0 180)
			(size 0.3048 0.381)
			(layers "F.Cu" "F.Mask" "F.Paste")
			(net "GND")
		)
	)
	(footprint ""
		(layer "F.Cu")
		(at 22.07768 -431.421794)
		(property "Reference" "R3109"
			(at 0 0 0)
			(layer "F.SilkS")
			(hide yes)
			(effects
				(font
					(size 1.27 1.27)
				)
			)
		)
		(property "Value" ""
			(at 0 0 0)
			(layer "F.Fab")
			(effects
				(font
					(size 1.27 1.27)
				)
			)
		)
		(duplicate_pad_numbers_are_jumpers no)
		(fp_line
			(start -0.7874 -0.4064)
			(end 0.7874 -0.4064)
			(stroke
				(width 0.1524)
				(type default)
			)
			(layer "F.SilkS")
		)
		(fp_line
			(start -0.7874 0.4064)
			(end -0.7874 -0.4064)
			(stroke
				(width 0.1524)
				(type default)
			)
			(layer "F.SilkS")
		)
		(fp_line
			(start 0.7874 -0.4064)
			(end 0.7874 0.4064)
			(stroke
				(width 0.1524)
				(type default)
			)
			(layer "F.SilkS")
		)
		(fp_line
			(start 0.7874 0.4064)
			(end -0.7874 0.4064)
			(stroke
				(width 0.1524)
				(type default)
			)
			(layer "F.SilkS")
		)
		(fp_line
			(start -0.67945 -0.305054)
			(end -0.12065 -0.305054)
			(stroke
				(width 0.1)
				(type default)
			)
			(layer "F.Fab")
		)
		(fp_line
			(start -0.67945 0.3048)
			(end -0.67945 -0.305054)
			(stroke
				(width 0.1)
				(type default)
			)
			(layer "F.Fab")
		)
		(fp_line
			(start -0.12065 -0.305054)
			(end -0.12065 -0.2794)
			(stroke
				(width 0.1)
				(type default)
			)
			(layer "F.Fab")
		)
		(fp_line
			(start -0.12065 -0.2794)
			(end 0.12065 -0.2794)
			(stroke
				(width 0.1)
				(type default)
			)
			(layer "F.Fab")
		)
		(fp_line
			(start -0.12065 0.2794)
			(end -0.12065 0.3048)
			(stroke
				(width 0.1)
				(type default)
			)
			(layer "F.Fab")
		)
		(fp_line
			(start -0.12065 0.3048)
			(end -0.67945 0.3048)
			(stroke
				(width 0.1)
				(type default)
			)
			(layer "F.Fab")
		)
		(fp_line
			(start 0.120396 0.2794)
			(end -0.12065 0.2794)
			(stroke
				(width 0.1)
				(type default)
			)
			(layer "F.Fab")
		)
		(fp_line
			(start 0.120396 0.3048)
			(end 0.120396 0.2794)
			(stroke
				(width 0.1)
				(type default)
			)
			(layer "F.Fab")
		)
		(fp_line
			(start 0.12065 -0.3048)
			(end 0.67945 -0.3048)
			(stroke
				(width 0.1)
				(type default)
			)
			(layer "F.Fab")
		)
		(fp_line
			(start 0.12065 -0.2794)
			(end 0.12065 -0.3048)
			(stroke
				(width 0.1)
				(type default)
			)
			(layer "F.Fab")
		)
		(fp_line
			(start 0.67945 -0.3048)
			(end 0.67945 0.3048)
			(stroke
				(width 0.1)
				(type default)
			)
			(layer "F.Fab")
		)
		(fp_line
			(start 0.67945 0.3048)
			(end 0.120396 0.3048)
			(stroke
				(width 0.1)
				(type default)
			)
			(layer "F.Fab")
		)
		(pad "1" smd circle
			(at -0.40005 0)
			(size 0 0)
			(layers "F.Cu" "F.Mask" "F.Paste")
			(net "SMB_1_BMC_GPU_SCL")
		)
		(pad "2" smd circle
			(at 0.40005 0)
			(size 0 0)
			(layers "F.Cu" "F.Mask" "F.Paste")
			(net "SMB_1_BMC_GPU_R_SCL")
		)
	)
	(footprint ""
		(layer "F.Cu")
		(at 244.327426 -285.631636)
		(property "Reference" "PC6501"
			(at 0 0 0)
			(layer "F.SilkS")
			(hide yes)
			(effects
				(font
					(size 1.27 1.27)
				)
			)
		)
		(property "Value" ""
			(at 0 0 0)
			(layer "F.Fab")
			(effects
				(font
					(size 1.27 1.27)
				)
			)
		)
		(duplicate_pad_numbers_are_jumpers no)
		(fp_line
			(start -1.524 -0.762)
			(end 1.524 -0.762)
			(stroke
				(width 0.1524)
				(type default)
			)
			(layer "F.SilkS")
		)
		(fp_line
			(start -1.524 0.762)
			(end -1.524 -0.762)
			(stroke
				(width 0.1524)
				(type default)
			)
			(layer "F.SilkS")
		)
		(fp_line
			(start 1.524 -0.762)
			(end 1.524 0.762)
			(stroke
				(width 0.1524)
				(type default)
			)
			(layer "F.SilkS")
		)
		(fp_line
			(start 1.524 0.762)
			(end -1.524 0.762)
			(stroke
				(width 0.1524)
				(type default)
			)
			(layer "F.SilkS")
		)
		(fp_line
			(start -1.1049 -0.724916)
			(end -1.1049 0.724916)
			(stroke
				(width 0.1)
				(type default)
			)
			(layer "F.Fab")
		)
		(fp_line
			(start -1.1049 0.724916)
			(end 1.1049 0.724916)
			(stroke
				(width 0.1)
				(type default)
			)
			(layer "F.Fab")
		)
		(fp_line
			(start 1.1049 -0.724916)
			(end -1.1049 -0.724916)
			(stroke
				(width 0.1)
				(type default)
			)
			(layer "F.Fab")
		)
		(fp_line
			(start 1.1049 0.724916)
			(end 1.1049 -0.724916)
			(stroke
				(width 0.1)
				(type default)
			)
			(layer "F.Fab")
		)
		(pad "1" smd rect
			(at -0.889 0 180)
			(size 1.016 1.27)
			(layers "F.Cu" "F.Mask" "F.Paste")
			(net "SW_P12V_AUX_P1V8_RETIMER_CPU0_FLT")
		)
		(pad "2" smd rect
			(at 0.889 0 180)
			(size 1.016 1.27)
			(layers "F.Cu" "F.Mask" "F.Paste")
			(net "GND")
		)
	)
	(footprint ""
		(layer "F.Cu")
		(at 180.777134 -56.352948 180)
		(property "Reference" "R178"
			(at 0 0 180)
			(layer "F.SilkS")
			(hide yes)
			(effects
				(font
					(size 1.27 1.27)
				)
			)
		)
		(property "Value" ""
			(at 0 0 180)
			(layer "F.Fab")
			(effects
				(font
					(size 1.27 1.27)
				)
			)
		)
		(duplicate_pad_numbers_are_jumpers no)
		(fp_line
			(start 0.7874 0.4064)
			(end -0.7874 0.4064)
			(stroke
				(width 0.1524)
				(type default)
			)
			(layer "F.SilkS")
		)
		(fp_line
			(start 0.7874 -0.4064)
			(end 0.7874 0.4064)
			(stroke
				(width 0.1524)
				(type default)
			)
			(layer "F.SilkS")
		)
		(fp_line
			(start -0.7874 0.4064)
			(end -0.7874 -0.4064)
			(stroke
				(width 0.1524)
				(type default)
			)
			(layer "F.SilkS")
		)
		(fp_line
			(start -0.7874 -0.4064)
			(end 0.7874 -0.4064)
			(stroke
				(width 0.1524)
				(type default)
			)
			(layer "F.SilkS")
		)
		(fp_line
			(start 0.67945 0.3048)
			(end 0.120396 0.3048)
			(stroke
				(width 0.1)
				(type default)
			)
			(layer "F.Fab")
		)
		(fp_line
			(start 0.67945 -0.3048)
			(end 0.67945 0.3048)
			(stroke
				(width 0.1)
				(type default)
			)
			(layer "F.Fab")
		)
		(fp_line
			(start 0.12065 -0.2794)
			(end 0.12065 -0.3048)
			(stroke
				(width 0.1)
				(type default)
			)
			(layer "F.Fab")
		)
		(fp_line
			(start 0.12065 -0.3048)
			(end 0.67945 -0.3048)
			(stroke
				(width 0.1)
				(type default)
			)
			(layer "F.Fab")
		)
		(fp_line
			(start 0.120396 0.3048)
			(end 0.120396 0.2794)
			(stroke
				(width 0.1)
				(type default)
			)
			(layer "F.Fab")
		)
		(fp_line
			(start 0.120396 0.2794)
			(end -0.12065 0.2794)
			(stroke
				(width 0.1)
				(type default)
			)
			(layer "F.Fab")
		)
		(fp_line
			(start -0.12065 0.3048)
			(end -0.67945 0.3048)
			(stroke
				(width 0.1)
				(type default)
			)
			(layer "F.Fab")
		)
		(fp_line
			(start -0.12065 0.2794)
			(end -0.12065 0.3048)
			(stroke
				(width 0.1)
				(type default)
			)
			(layer "F.Fab")
		)
		(fp_line
			(start -0.12065 -0.2794)
			(end 0.12065 -0.2794)
			(stroke
				(width 0.1)
				(type default)
			)
			(layer "F.Fab")
		)
		(fp_line
			(start -0.12065 -0.305054)
			(end -0.12065 -0.2794)
			(stroke
				(width 0.1)
				(type default)
			)
			(layer "F.Fab")
		)
		(fp_line
			(start -0.67945 0.3048)
			(end -0.67945 -0.305054)
			(stroke
				(width 0.1)
				(type default)
			)
			(layer "F.Fab")
		)
		(fp_line
			(start -0.67945 -0.305054)
			(end -0.12065 -0.305054)
			(stroke
				(width 0.1)
				(type default)
			)
			(layer "F.Fab")
		)
		(pad "1" smd circle
			(at -0.40005 0 180)
			(size 0 0)
			(layers "F.Cu" "F.Mask" "F.Paste")
			(net "P3V3_AUX")
		)
		(pad "2" smd circle
			(at 0.40005 0 180)
			(size 0 0)
			(layers "F.Cu" "F.Mask" "F.Paste")
			(net "PCIE_M2_SSD0_PRSNT_N")
		)
	)
	(footprint ""
		(layer "F.Cu")
		(at 37.211 -362.077 180)
		(property "Reference" "R8252"
			(at 0 0 180)
			(layer "F.SilkS")
			(hide yes)
			(effects
				(font
					(size 1.27 1.27)
				)
			)
		)
		(property "Value" ""
			(at 0 0 180)
			(layer "F.Fab")
			(effects
				(font
					(size 1.27 1.27)
				)
			)
		)
		(duplicate_pad_numbers_are_jumpers no)
		(fp_line
			(start 0.7874 0.4064)
			(end -0.7874 0.4064)
			(stroke
				(width 0.1524)
				(type default)
			)
			(layer "F.SilkS")
		)
		(fp_line
			(start 0.7874 -0.4064)
			(end 0.7874 0.4064)
			(stroke
				(width 0.1524)
				(type default)
			)
			(layer "F.SilkS")
		)
		(fp_line
			(start -0.7874 0.4064)
			(end -0.7874 -0.4064)
			(stroke
				(width 0.1524)
				(type default)
			)
			(layer "F.SilkS")
		)
		(fp_line
			(start -0.7874 -0.4064)
			(end 0.7874 -0.4064)
			(stroke
				(width 0.1524)
				(type default)
			)
			(layer "F.SilkS")
		)
		(fp_line
			(start 0.67945 0.3048)
			(end 0.120396 0.3048)
			(stroke
				(width 0.1)
				(type default)
			)
			(layer "F.Fab")
		)
		(fp_line
			(start 0.67945 -0.3048)
			(end 0.67945 0.3048)
			(stroke
				(width 0.1)
				(type default)
			)
			(layer "F.Fab")
		)
		(fp_line
			(start 0.12065 -0.2794)
			(end 0.12065 -0.3048)
			(stroke
				(width 0.1)
				(type default)
			)
			(layer "F.Fab")
		)
		(fp_line
			(start 0.12065 -0.3048)
			(end 0.67945 -0.3048)
			(stroke
				(width 0.1)
				(type default)
			)
			(layer "F.Fab")
		)
		(fp_line
			(start 0.120396 0.3048)
			(end 0.120396 0.2794)
			(stroke
				(width 0.1)
				(type default)
			)
			(layer "F.Fab")
		)
		(fp_line
			(start 0.120396 0.2794)
			(end -0.12065 0.2794)
			(stroke
				(width 0.1)
				(type default)
			)
			(layer "F.Fab")
		)
		(fp_line
			(start -0.12065 0.3048)
			(end -0.67945 0.3048)
			(stroke
				(width 0.1)
				(type default)
			)
			(layer "F.Fab")
		)
		(fp_line
			(start -0.12065 0.2794)
			(end -0.12065 0.3048)
			(stroke
				(width 0.1)
				(type default)
			)
			(layer "F.Fab")
		)
		(fp_line
			(start -0.12065 -0.2794)
			(end 0.12065 -0.2794)
			(stroke
				(width 0.1)
				(type default)
			)
			(layer "F.Fab")
		)
		(fp_line
			(start -0.12065 -0.305054)
			(end -0.12065 -0.2794)
			(stroke
				(width 0.1)
				(type default)
			)
			(layer "F.Fab")
		)
		(fp_line
			(start -0.67945 0.3048)
			(end -0.67945 -0.305054)
			(stroke
				(width 0.1)
				(type default)
			)
			(layer "F.Fab")
		)
		(fp_line
			(start -0.67945 -0.305054)
			(end -0.12065 -0.305054)
			(stroke
				(width 0.1)
				(type default)
			)
			(layer "F.Fab")
		)
		(pad "1" smd circle
			(at -0.40005 0 180)
			(size 0 0)
			(layers "F.Cu" "F.Mask" "F.Paste")
			(net "PVDD18_S5_P1")
		)
		(pad "2" smd circle
			(at 0.40005 0 180)
			(size 0 0)
			(layers "F.Cu" "F.Mask" "F.Paste")
			(net "PVDDCR_CPU1_P1_OCP_N_R")
		)
	)
	(footprint ""
		(layer "F.Cu")
		(at 326.667876 -70.098412 90)
		(property "Reference" "D75"
			(at -3.934714 -0.691642 90)
			(unlocked yes)
			(layer "F.SilkS")
			(effects
				(font
					(size 0.7874 0.5842)
					(thickness 0.1524)
				)
				(justify left)
			)
		)
		(property "Value" ""
			(at 0 0 90)
			(layer "F.Fab")
			(effects
				(font
					(size 1.27 1.27)
				)
			)
		)
		(duplicate_pad_numbers_are_jumpers no)
		(fp_line
			(start 1.16078 -0.4826)
			(end 1.16078 0.4826)
			(stroke
				(width 0.1524)
				(type default)
			)
			(layer "F.SilkS")
		)
		(fp_line
			(start 1.03378 -0.4826)
			(end 1.03378 0.4826)
			(stroke
				(width 0.1524)
				(type default)
			)
			(layer "F.SilkS")
		)
		(fp_line
			(start 0.90678 -0.4826)
			(end 0.90678 0.4826)
			(stroke
				(width 0.1524)
				(type default)
			)
			(layer "F.SilkS")
		)
		(fp_line
			(start -0.64008 -0.4826)
			(end 1.16078 -0.4826)
			(stroke
				(width 0.1524)
				(type default)
			)
			(layer "F.SilkS")
		)
		(fp_line
			(start -0.79248 -0.4826)
			(end 1.03378 -0.4826)
			(stroke
				(width 0.1524)
				(type default)
			)
			(layer "F.SilkS")
		)
		(fp_line
			(start -0.89408 -0.4826)
			(end 0.90678 -0.4826)
			(stroke
				(width 0.1524)
				(type default)
			)
			(layer "F.SilkS")
		)
		(fp_line
			(start 1.16078 0.4826)
			(end -0.64008 0.4826)
			(stroke
				(width 0.1524)
				(type default)
			)
			(layer "F.SilkS")
		)
		(fp_line
			(start 1.03378 0.4826)
			(end -0.79248 0.4826)
			(stroke
				(width 0.1524)
				(type default)
			)
			(layer "F.SilkS")
		)
		(fp_line
			(start 0.90678 0.4826)
			(end -0.90678 0.4826)
			(stroke
				(width 0.1524)
				(type default)
			)
			(layer "F.SilkS")
		)
		(fp_line
			(start -0.90678 0.4826)
			(end -0.90678 -0.4699)
			(stroke
				(width 0.1524)
				(type default)
			)
			(layer "F.SilkS")
		)
		(fp_line
			(start 0.499872 -0.249936)
			(end 0.499872 0.249936)
			(stroke
				(width 0.1)
				(type default)
			)
			(layer "F.Fab")
		)
		(fp_line
			(start -0.499872 -0.249936)
			(end 0.499872 -0.249936)
			(stroke
				(width 0.1)
				(type default)
			)
			(layer "F.Fab")
		)
		(fp_line
			(start 0.499872 0.249936)
			(end -0.499872 0.249936)
			(stroke
				(width 0.1)
				(type default)
			)
			(layer "F.Fab")
		)
		(fp_line
			(start -0.499872 0.249936)
			(end -0.499872 -0.249936)
			(stroke
				(width 0.1)
				(type default)
			)
			(layer "F.Fab")
		)
		(pad "A" smd rect
			(at -0.47498 0 90)
			(size 0.6096 0.7112)
			(layers "F.Cu" "F.Mask" "F.Paste")
			(net "LED_PWRGD_PVDDCR_SOC_P0_R")
		)
		(pad "C" smd rect
			(at 0.47498 0 90)
			(size 0.6096 0.7112)
			(layers "F.Cu" "F.Mask" "F.Paste")
			(net "LED_PWRGD_PVDDCR_SOC_P0_D")
		)
	)
	(footprint ""
		(layer "F.Cu")
		(at 320.572384 -341.042244 180)
		(property "Reference" "PC116_3"
			(at 0 0 180)
			(layer "F.SilkS")
			(hide yes)
			(effects
				(font
					(size 1.27 1.27)
				)
			)
		)
		(property "Value" ""
			(at 0 0 180)
			(layer "F.Fab")
			(effects
				(font
					(size 1.27 1.27)
				)
			)
		)
		(duplicate_pad_numbers_are_jumpers no)
		(fp_line
			(start 0.7874 0.4064)
			(end -0.7874 0.4064)
			(stroke
				(width 0.1524)
				(type default)
			)
			(layer "F.SilkS")
		)
		(fp_line
			(start 0.7874 -0.4064)
			(end 0.7874 0.4064)
			(stroke
				(width 0.1524)
				(type default)
			)
			(layer "F.SilkS")
		)
		(fp_line
			(start -0.7874 0.4064)
			(end -0.7874 -0.4064)
			(stroke
				(width 0.1524)
				(type default)
			)
			(layer "F.SilkS")
		)
		(fp_line
			(start -0.7874 -0.4064)
			(end 0.7874 -0.4064)
			(stroke
				(width 0.1524)
				(type default)
			)
			(layer "F.SilkS")
		)
		(fp_line
			(start 0.67945 0.3048)
			(end 0.120396 0.3048)
			(stroke
				(width 0.1)
				(type default)
			)
			(layer "F.Fab")
		)
		(fp_line
			(start 0.67945 -0.3048)
			(end 0.67945 0.3048)
			(stroke
				(width 0.1)
				(type default)
			)
			(layer "F.Fab")
		)
		(fp_line
			(start 0.12065 -0.2794)
			(end 0.12065 -0.3048)
			(stroke
				(width 0.1)
				(type default)
			)
			(layer "F.Fab")
		)
		(fp_line
			(start 0.12065 -0.3048)
			(end 0.67945 -0.3048)
			(stroke
				(width 0.1)
				(type default)
			)
			(layer "F.Fab")
		)
		(fp_line
			(start 0.120396 0.3048)
			(end 0.120396 0.2794)
			(stroke
				(width 0.1)
				(type default)
			)
			(layer "F.Fab")
		)
		(fp_line
			(start 0.120396 0.2794)
			(end -0.12065 0.2794)
			(stroke
				(width 0.1)
				(type default)
			)
			(layer "F.Fab")
		)
		(fp_line
			(start -0.12065 0.3048)
			(end -0.67945 0.3048)
			(stroke
				(width 0.1)
				(type default)
			)
			(layer "F.Fab")
		)
		(fp_line
			(start -0.12065 0.2794)
			(end -0.12065 0.3048)
			(stroke
				(width 0.1)
				(type default)
			)
			(layer "F.Fab")
		)
		(fp_line
			(start -0.12065 -0.2794)
			(end 0.12065 -0.2794)
			(stroke
				(width 0.1)
				(type default)
			)
			(layer "F.Fab")
		)
		(fp_line
			(start -0.12065 -0.305054)
			(end -0.12065 -0.2794)
			(stroke
				(width 0.1)
				(type default)
			)
			(layer "F.Fab")
		)
		(fp_line
			(start -0.67945 0.3048)
			(end -0.67945 -0.305054)
			(stroke
				(width 0.1)
				(type default)
			)
			(layer "F.Fab")
		)
		(fp_line
			(start -0.67945 -0.305054)
			(end -0.12065 -0.305054)
			(stroke
				(width 0.1)
				(type default)
			)
			(layer "F.Fab")
		)
		(pad "1" smd circle
			(at -0.40005 0 180)
			(size 0 0)
			(layers "F.Cu" "F.Mask" "F.Paste")
			(net "SW_P12V_AUX_PVDDCR_CPU1_P0_FLT")
		)
		(pad "2" smd circle
			(at 0.40005 0 180)
			(size 0 0)
			(layers "F.Cu" "F.Mask" "F.Paste")
			(net "GND")
		)
	)
	(footprint ""
		(layer "F.Cu")
		(at 111.149892 -181.176168)
		(property "Reference" "PC317"
			(at 0 0 0)
			(layer "F.SilkS")
			(hide yes)
			(effects
				(font
					(size 1.27 1.27)
				)
			)
		)
		(property "Value" ""
			(at 0 0 0)
			(layer "F.Fab")
			(effects
				(font
					(size 1.27 1.27)
				)
			)
		)
		(duplicate_pad_numbers_are_jumpers no)
		(fp_line
			(start -0.7874 -0.4064)
			(end 0.7874 -0.4064)
			(stroke
				(width 0.1524)
				(type default)
			)
			(layer "F.SilkS")
		)
		(fp_line
			(start -0.7874 0.4064)
			(end -0.7874 -0.4064)
			(stroke
				(width 0.1524)
				(type default)
			)
			(layer "F.SilkS")
		)
		(fp_line
			(start 0.7874 -0.4064)
			(end 0.7874 0.4064)
			(stroke
				(width 0.1524)
				(type default)
			)
			(layer "F.SilkS")
		)
		(fp_line
			(start 0.7874 0.4064)
			(end -0.7874 0.4064)
			(stroke
				(width 0.1524)
				(type default)
			)
			(layer "F.SilkS")
		)
		(fp_line
			(start -0.67945 -0.305054)
			(end -0.12065 -0.305054)
			(stroke
				(width 0.1)
				(type default)
			)
			(layer "F.Fab")
		)
		(fp_line
			(start -0.67945 0.3048)
			(end -0.67945 -0.305054)
			(stroke
				(width 0.1)
				(type default)
			)
			(layer "F.Fab")
		)
		(fp_line
			(start -0.12065 -0.305054)
			(end -0.12065 -0.2794)
			(stroke
				(width 0.1)
				(type default)
			)
			(layer "F.Fab")
		)
		(fp_line
			(start -0.12065 -0.2794)
			(end 0.12065 -0.2794)
			(stroke
				(width 0.1)
				(type default)
			)
			(layer "F.Fab")
		)
		(fp_line
			(start -0.12065 0.2794)
			(end -0.12065 0.3048)
			(stroke
				(width 0.1)
				(type default)
			)
			(layer "F.Fab")
		)
		(fp_line
			(start -0.12065 0.3048)
			(end -0.67945 0.3048)
			(stroke
				(width 0.1)
				(type default)
			)
			(layer "F.Fab")
		)
		(fp_line
			(start 0.120396 0.2794)
			(end -0.12065 0.2794)
			(stroke
				(width 0.1)
				(type default)
			)
			(layer "F.Fab")
		)
		(fp_line
			(start 0.120396 0.3048)
			(end 0.120396 0.2794)
			(stroke
				(width 0.1)
				(type default)
			)
			(layer "F.Fab")
		)
		(fp_line
			(start 0.12065 -0.3048)
			(end 0.67945 -0.3048)
			(stroke
				(width 0.1)
				(type default)
			)
			(layer "F.Fab")
		)
		(fp_line
			(start 0.12065 -0.2794)
			(end 0.12065 -0.3048)
			(stroke
				(width 0.1)
				(type default)
			)
			(layer "F.Fab")
		)
		(fp_line
			(start 0.67945 -0.3048)
			(end 0.67945 0.3048)
			(stroke
				(width 0.1)
				(type default)
			)
			(layer "F.Fab")
		)
		(fp_line
			(start 0.67945 0.3048)
			(end 0.120396 0.3048)
			(stroke
				(width 0.1)
				(type default)
			)
			(layer "F.Fab")
		)
		(pad "1" smd circle
			(at -0.40005 0)
			(size 0 0)
			(layers "F.Cu" "F.Mask" "F.Paste")
			(net "SW_PVDDCR_CPU0_P1_SW4")
		)
		(pad "2" smd circle
			(at 0.40005 0)
			(size 0 0)
			(layers "F.Cu" "F.Mask" "F.Paste")
			(net "SW_PVDDCR_CPU0_P1_SW4_RC")
		)
	)
	(footprint ""
		(layer "F.Cu")
		(at 258.99237 -132.980176 180)
		(property "Reference" "U53"
			(at 1.11506 -3.372104 0)
			(unlocked yes)
			(layer "F.SilkS")
			(effects
				(font
					(size 0.7874 0.5842)
					(thickness 0.1524)
				)
				(justify left)
			)
		)
		(property "Value" ""
			(at 0 0 180)
			(layer "F.Fab")
			(effects
				(font
					(size 1.27 1.27)
				)
			)
		)
		(duplicate_pad_numbers_are_jumpers no)
		(fp_line
			(start 1.868932 2.549906)
			(end 1.868932 -2.549906)
			(stroke
				(width 0.1524)
				(type default)
			)
			(layer "F.SilkS")
		)
		(fp_line
			(start 1.868932 -2.549906)
			(end 1.025906 -2.549906)
			(stroke
				(width 0.1524)
				(type default)
			)
			(layer "F.SilkS")
		)
		(fp_line
			(start 1.025906 -2.549906)
			(end 0 -1.524)
			(stroke
				(width 0.1524)
				(type default)
			)
			(layer "F.SilkS")
		)
		(fp_line
			(start 0 -1.524)
			(end -1.025906 -2.549906)
			(stroke
				(width 0.1524)
				(type default)
			)
			(layer "F.SilkS")
		)
		(fp_line
			(start -1.025906 -2.549906)
			(end -1.868932 -2.549906)
			(stroke
				(width 0.1524)
				(type default)
			)
			(layer "F.SilkS")
		)
		(fp_line
			(start -1.868932 2.549906)
			(end 1.868932 2.549906)
			(stroke
				(width 0.1524)
				(type default)
			)
			(layer "F.SilkS")
		)
		(fp_line
			(start -1.868932 -2.549906)
			(end -1.868932 2.549906)
			(stroke
				(width 0.1524)
				(type default)
			)
			(layer "F.SilkS")
		)
		(fp_poly
			(pts
				(xy -2.802128 -2.775966) (xy -3.310128 -3.791966) (xy -2.294128 -3.791966)
			)
			(stroke
				(width 0)
				(type default)
			)
			(fill yes)
			(layer "F.SilkS")
		)
		(fp_line
			(start 2.249932 2.549906)
			(end 2.249932 -2.549906)
			(stroke
				(width 0.1)
				(type default)
			)
			(layer "F.Fab")
		)
		(fp_line
			(start 2.249932 -2.549906)
			(end -2.249932 -2.549906)
			(stroke
				(width 0.1)
				(type default)
			)
			(layer "F.Fab")
		)
		(fp_line
			(start -2.249932 2.549906)
			(end 2.249932 2.549906)
			(stroke
				(width 0.1)
				(type default)
			)
			(layer "F.Fab")
		)
		(fp_line
			(start -2.249932 -2.549906)
			(end -2.249932 2.549906)
			(stroke
				(width 0.1)
				(type default)
			)
			(layer "F.Fab")
		)
		(fp_poly
			(pts
				(xy -4.7752 -1.787398) (xy -4.7752 -2.803398) (xy -3.7592 -2.295398)
			)
			(stroke
				(width 0)
				(type default)
			)
			(fill yes)
			(layer "F.Fab")
		)
		(pad "1" smd rect
			(at -2.800096 -2.275078 90)
			(size 0.3556 1.6002)
			(layers "F.Cu" "F.Mask" "F.Paste")
			(net "PVDD18_S5_P0")
		)
		(pad "2" smd rect
			(at -2.800096 -1.625092 90)
			(size 0.3556 1.6002)
			(layers "F.Cu" "F.Mask" "F.Paste")
			(net "PVDD18_S5_P0")
		)
		(pad "3" smd rect
			(at -2.800096 -0.975106 90)
			(size 0.3556 1.6002)
			(layers "F.Cu" "F.Mask" "F.Paste")
			(net "SPI_CPU0_CS0_N")
		)
		(pad "4" smd rect
			(at -2.800096 -0.32512 90)
			(size 0.3556 1.6002)
			(layers "F.Cu" "F.Mask" "F.Paste")
			(net "SPI_CPU0_CLK")
		)
		(pad "5" smd rect
			(at -2.800096 0.32512 90)
			(size 0.3556 1.6002)
			(layers "F.Cu" "F.Mask" "F.Paste")
			(net "SPI_CPU0_CS1_N")
		)
		(pad "6" smd rect
			(at -2.800096 0.975106 90)
			(size 0.3556 1.6002)
			(layers "F.Cu" "F.Mask" "F.Paste")
			(net "SPI_CPU0_TPM_CS_N")
		)
		(pad "7" smd rect
			(at -2.800096 1.625092 90)
			(size 0.3556 1.6002)
			(layers "F.Cu" "F.Mask" "F.Paste")
			(net "PVDD18_S5_P0")
		)
		(pad "8" smd rect
			(at -2.800096 2.275078 90)
			(size 0.3556 1.6002)
			(layers "F.Cu" "F.Mask" "F.Paste")
			(net "PVDD18_S5_P0")
		)
		(pad "9" smd rect
			(at 2.800096 2.275078 90)
			(size 0.3556 1.6002)
			(layers "F.Cu" "F.Mask" "F.Paste")
			(net "ROM_SD_LS_OE")
		)
		(pad "10" smd rect
			(at 2.800096 1.625092 90)
			(size 0.3556 1.6002)
			(layers "F.Cu" "F.Mask" "F.Paste")
			(net "GND")
		)
		(pad "11" smd rect
			(at 2.800096 0.975106 90)
			(size 0.3556 1.6002)
			(layers "F.Cu" "F.Mask" "F.Paste")
			(net "SPI_CPU0_LVC3_R_TPM_CS_N")
		)
		(pad "12" smd rect
			(at 2.800096 0.32512 90)
			(size 0.3556 1.6002)
			(layers "F.Cu" "F.Mask" "F.Paste")
			(net "SPI_CPU0_LVC3_CS1_N")
		)
		(pad "13" smd rect
			(at 2.800096 -0.32512 90)
			(size 0.3556 1.6002)
			(layers "F.Cu" "F.Mask" "F.Paste")
			(net "SPI_CPU0_LVC3_CLK")
		)
		(pad "14" smd rect
			(at 2.800096 -0.975106 90)
			(size 0.3556 1.6002)
			(layers "F.Cu" "F.Mask" "F.Paste")
			(net "SPI_CPU0_LVC3_CS0_N")
		)
		(pad "15" smd rect
			(at 2.800096 -1.625092 90)
			(size 0.3556 1.6002)
			(layers "F.Cu" "F.Mask" "F.Paste")
			(net "P3V3_AUX")
		)
		(pad "16" smd rect
			(at 2.800096 -2.275078 90)
			(size 0.3556 1.6002)
			(layers "F.Cu" "F.Mask" "F.Paste")
			(net "PVDD18_S5_P0")
		)
	)
	(footprint ""
		(layer "F.Cu")
		(at 150.368762 -120.485662 180)
		(property "Reference" "R2222"
			(at 0 0 180)
			(layer "F.SilkS")
			(hide yes)
			(effects
				(font
					(size 1.27 1.27)
				)
			)
		)
		(property "Value" ""
			(at 0 0 180)
			(layer "F.Fab")
			(effects
				(font
					(size 1.27 1.27)
				)
			)
		)
		(duplicate_pad_numbers_are_jumpers no)
		(fp_line
			(start 0.7874 0.4064)
			(end -0.7874 0.4064)
			(stroke
				(width 0.1524)
				(type default)
			)
			(layer "F.SilkS")
		)
		(fp_line
			(start 0.7874 -0.4064)
			(end 0.7874 0.4064)
			(stroke
				(width 0.1524)
				(type default)
			)
			(layer "F.SilkS")
		)
		(fp_line
			(start -0.7874 0.4064)
			(end -0.7874 -0.4064)
			(stroke
				(width 0.1524)
				(type default)
			)
			(layer "F.SilkS")
		)
		(fp_line
			(start -0.7874 -0.4064)
			(end 0.7874 -0.4064)
			(stroke
				(width 0.1524)
				(type default)
			)
			(layer "F.SilkS")
		)
		(fp_line
			(start 0.67945 0.3048)
			(end 0.120396 0.3048)
			(stroke
				(width 0.1)
				(type default)
			)
			(layer "F.Fab")
		)
		(fp_line
			(start 0.67945 -0.3048)
			(end 0.67945 0.3048)
			(stroke
				(width 0.1)
				(type default)
			)
			(layer "F.Fab")
		)
		(fp_line
			(start 0.12065 -0.2794)
			(end 0.12065 -0.3048)
			(stroke
				(width 0.1)
				(type default)
			)
			(layer "F.Fab")
		)
		(fp_line
			(start 0.12065 -0.3048)
			(end 0.67945 -0.3048)
			(stroke
				(width 0.1)
				(type default)
			)
			(layer "F.Fab")
		)
		(fp_line
			(start 0.120396 0.3048)
			(end 0.120396 0.2794)
			(stroke
				(width 0.1)
				(type default)
			)
			(layer "F.Fab")
		)
		(fp_line
			(start 0.120396 0.2794)
			(end -0.12065 0.2794)
			(stroke
				(width 0.1)
				(type default)
			)
			(layer "F.Fab")
		)
		(fp_line
			(start -0.12065 0.3048)
			(end -0.67945 0.3048)
			(stroke
				(width 0.1)
				(type default)
			)
			(layer "F.Fab")
		)
		(fp_line
			(start -0.12065 0.2794)
			(end -0.12065 0.3048)
			(stroke
				(width 0.1)
				(type default)
			)
			(layer "F.Fab")
		)
		(fp_line
			(start -0.12065 -0.2794)
			(end 0.12065 -0.2794)
			(stroke
				(width 0.1)
				(type default)
			)
			(layer "F.Fab")
		)
		(fp_line
			(start -0.12065 -0.305054)
			(end -0.12065 -0.2794)
			(stroke
				(width 0.1)
				(type default)
			)
			(layer "F.Fab")
		)
		(fp_line
			(start -0.67945 0.3048)
			(end -0.67945 -0.305054)
			(stroke
				(width 0.1)
				(type default)
			)
			(layer "F.Fab")
		)
		(fp_line
			(start -0.67945 -0.305054)
			(end -0.12065 -0.305054)
			(stroke
				(width 0.1)
				(type default)
			)
			(layer "F.Fab")
		)
		(pad "1" smd circle
			(at -0.40005 0 180)
			(size 0 0)
			(layers "F.Cu" "F.Mask" "F.Paste")
			(net "A_P12V_STBY_FP_TRIGGER")
		)
		(pad "2" smd circle
			(at 0.40005 0 180)
			(size 0 0)
			(layers "F.Cu" "F.Mask" "F.Paste")
			(net "GND")
		)
	)
	(footprint ""
		(layer "F.Cu")
		(at 444.594234 -255.560068 180)
		(property "Reference" "J20"
			(at 1.631188 -81.796128 0)
			(unlocked yes)
			(layer "F.SilkS")
			(effects
				(font
					(size 0.7874 0.5842)
					(thickness 0.1524)
				)
			)
		)
		(property "Value" ""
			(at 0 0 180)
			(layer "F.Fab")
			(effects
				(font
					(size 1.27 1.27)
				)
			)
		)
		(duplicate_pad_numbers_are_jumpers no)
		(fp_line
			(start 3.24993 81.000092)
			(end -3.24993 81.000092)
			(stroke
				(width 0.1524)
				(type default)
			)
			(layer "F.SilkS")
		)
		(fp_line
			(start 3.24993 80.608932)
			(end 3.24993 81.000092)
			(stroke
				(width 0.1524)
				(type default)
			)
			(layer "F.SilkS")
		)
		(fp_line
			(start 3.24993 -81.000092)
			(end 3.24993 72.861932)
			(stroke
				(width 0.1524)
				(type default)
			)
			(layer "F.SilkS")
		)
		(fp_line
			(start -3.24993 81.000092)
			(end -3.24993 -73.030588)
			(stroke
				(width 0.1524)
				(type default)
			)
			(layer "F.SilkS")
		)
		(fp_line
			(start -3.24993 72.499982)
			(end 3.24993 72.499982)
			(stroke
				(width 0.1524)
				(type default)
			)
			(layer "F.SilkS")
		)
		(fp_line
			(start -3.24993 -72.499982)
			(end 3.24993 -72.499982)
			(stroke
				(width 0.1524)
				(type default)
			)
			(layer "F.SilkS")
		)
		(fp_line
			(start -3.24993 -78.186788)
			(end -3.24993 -81.000092)
			(stroke
				(width 0.1524)
				(type default)
			)
			(layer "F.SilkS")
		)
		(fp_line
			(start -3.24993 -81.000092)
			(end 3.24993 -81.000092)
			(stroke
				(width 0.1524)
				(type default)
			)
			(layer "F.SilkS")
		)
		(fp_poly
			(pts
				(xy -3.826256 -64.534034) (xy -3.37693 -63.918338) (xy -4.13893 -63.928244)
			)
			(stroke
				(width 0)
				(type default)
			)
			(fill yes)
			(layer "F.SilkS")
		)
		(fp_line
			(start 3.24993 81.000092)
			(end -3.24993 81.000092)
			(stroke
				(width 0.1)
				(type default)
			)
			(layer "F.Fab")
		)
		(fp_line
			(start 3.24993 -81.000092)
			(end 3.24993 81.000092)
			(stroke
				(width 0.1)
				(type default)
			)
			(layer "F.Fab")
		)
		(fp_line
			(start -3.24993 81.000092)
			(end -3.24993 -81.000092)
			(stroke
				(width 0.1)
				(type default)
			)
			(layer "F.Fab")
		)
		(fp_line
			(start -3.24993 72.499982)
			(end 3.24993 72.499982)
			(stroke
				(width 0.1)
				(type default)
			)
			(layer "F.Fab")
		)
		(fp_line
			(start -3.24993 71.000112)
			(end 3.24993 71.000112)
			(stroke
				(width 0.1)
				(type default)
			)
			(layer "F.Fab")
		)
		(fp_line
			(start -3.24993 -71.000112)
			(end 3.24993 -71.000112)
			(stroke
				(width 0.1)
				(type default)
			)
			(layer "F.Fab")
		)
		(fp_line
			(start -3.24993 -72.499982)
			(end 3.24993 -72.499982)
			(stroke
				(width 0.1)
				(type default)
			)
			(layer "F.Fab")
		)
		(fp_line
			(start -3.24993 -81.000092)
			(end 3.24993 -81.000092)
			(stroke
				(width 0.1)
				(type default)
			)
			(layer "F.Fab")
		)
		(fp_poly
			(pts
				(xy -3.41503 -63.324994) (xy -4.43103 -62.816994) (xy -4.43103 -63.832994)
			)
			(stroke
				(width 0)
				(type default)
			)
			(fill yes)
			(layer "F.Fab")
		)
		(pad "1" smd rect
			(at -2.050034 -63.324994 90)
			(size 0.519938 1.4986)
			(layers "F.Cu" "F.Mask" "F.Paste")
			(net "P12V_MEM_CPU0")
		)
		(pad "2" smd rect
			(at -2.050034 -62.47511 90)
			(size 0.519938 1.4986)
			(layers "F.Cu" "F.Mask" "F.Paste")
			(net "Net_2389")
		)
		(pad "3" smd rect
			(at -2.050034 -61.624972 90)
			(size 0.519938 1.4986)
			(layers "F.Cu" "F.Mask" "F.Paste")
			(net "P3V3_AUX")
		)
		(pad "4" smd rect
			(at -2.050034 -60.775088 90)
			(size 0.519938 1.4986)
			(layers "F.Cu" "F.Mask" "F.Paste")
			(net "I3C_SPD_DDRK_CPU0_SCL")
		)
		(pad "5" smd rect
			(at -2.050034 -59.92495 90)
			(size 0.519938 1.4986)
			(layers "F.Cu" "F.Mask" "F.Paste")
			(net "I3C_SPD_DDRK_CPU0_SDA")
		)
		(pad "6" smd rect
			(at -2.050034 -59.075066 90)
			(size 0.519938 1.4986)
			(layers "F.Cu" "F.Mask" "F.Paste")
			(net "GND")
		)
		(pad "7" smd rect
			(at -2.050034 -58.224928 90)
			(size 0.519938 1.4986)
			(layers "F.Cu" "F.Mask" "F.Paste")
			(net "M_K_CPU0_SA_DQ<0>")
		)
		(pad "8" smd rect
			(at -2.050034 -57.375044 90)
			(size 0.519938 1.4986)
			(layers "F.Cu" "F.Mask" "F.Paste")
			(net "GND")
		)
		(pad "9" smd rect
			(at -2.050034 -56.524906 90)
			(size 0.519938 1.4986)
			(layers "F.Cu" "F.Mask" "F.Paste")
			(net "M_K_CPU0_SA_DQ<1>")
		)
		(pad "10" smd rect
			(at -2.050034 -55.675022 90)
			(size 0.519938 1.4986)
			(layers "F.Cu" "F.Mask" "F.Paste")
			(net "GND")
		)
		(pad "11" smd rect
			(at -2.050034 -54.824884 90)
			(size 0.519938 1.4986)
			(layers "F.Cu" "F.Mask" "F.Paste")
			(net "M_K_CPU0_SA_DQS_DP<0>")
		)
		(pad "12" smd rect
			(at -2.050034 -53.975 90)
			(size 0.519938 1.4986)
			(layers "F.Cu" "F.Mask" "F.Paste")
			(net "M_K_CPU0_SA_DQS_DN<0>")
		)
		(pad "13" smd rect
			(at -2.050034 -53.125116 90)
			(size 0.519938 1.4986)
			(layers "F.Cu" "F.Mask" "F.Paste")
			(net "GND")
		)
		(pad "14" smd rect
			(at -2.050034 -52.274978 90)
			(size 0.519938 1.4986)
			(layers "F.Cu" "F.Mask" "F.Paste")
			(net "M_K_CPU0_SA_DQ<4>")
		)
		(pad "15" smd rect
			(at -2.050034 -51.425094 90)
			(size 0.519938 1.4986)
			(layers "F.Cu" "F.Mask" "F.Paste")
			(net "GND")
		)
		(pad "16" smd rect
			(at -2.050034 -50.574956 90)
			(size 0.519938 1.4986)
			(layers "F.Cu" "F.Mask" "F.Paste")
			(net "M_K_CPU0_SA_DQ<5>")
		)
		(pad "17" smd rect
			(at -2.050034 -49.725072 90)
			(size 0.519938 1.4986)
			(layers "F.Cu" "F.Mask" "F.Paste")
			(net "GND")
		)
		(pad "18" smd rect
			(at -2.050034 -48.874934 90)
			(size 0.519938 1.4986)
			(layers "F.Cu" "F.Mask" "F.Paste")
			(net "M_K_CPU0_SA_DQ<8>")
		)
		(pad "19" smd rect
			(at -2.050034 -48.02505 90)
			(size 0.519938 1.4986)
			(layers "F.Cu" "F.Mask" "F.Paste")
			(net "GND")
		)
		(pad "20" smd rect
			(at -2.050034 -47.174912 90)
			(size 0.519938 1.4986)
			(layers "F.Cu" "F.Mask" "F.Paste")
			(net "M_K_CPU0_SA_DQ<9>")
		)
		(pad "21" smd rect
			(at -2.050034 -46.325028 90)
			(size 0.519938 1.4986)
			(layers "F.Cu" "F.Mask" "F.Paste")
			(net "GND")
		)
		(pad "22" smd rect
			(at -2.050034 -45.47489 90)
			(size 0.519938 1.4986)
			(layers "F.Cu" "F.Mask" "F.Paste")
			(net "M_K_CPU0_SA_DQS_DP<1>")
		)
		(pad "23" smd rect
			(at -2.050034 -44.625006 90)
			(size 0.519938 1.4986)
			(layers "F.Cu" "F.Mask" "F.Paste")
			(net "M_K_CPU0_SA_DQS_DN<1>")
		)
		(pad "24" smd rect
			(at -2.050034 -43.775122 90)
			(size 0.519938 1.4986)
			(layers "F.Cu" "F.Mask" "F.Paste")
			(net "GND")
		)
		(pad "25" smd rect
			(at -2.050034 -42.924984 90)
			(size 0.519938 1.4986)
			(layers "F.Cu" "F.Mask" "F.Paste")
			(net "M_K_CPU0_SA_DQ<12>")
		)
		(pad "26" smd rect
			(at -2.050034 -42.0751 90)
			(size 0.519938 1.4986)
			(layers "F.Cu" "F.Mask" "F.Paste")
			(net "GND")
		)
		(pad "27" smd rect
			(at -2.050034 -41.224962 90)
			(size 0.519938 1.4986)
			(layers "F.Cu" "F.Mask" "F.Paste")
			(net "M_K_CPU0_SA_DQ<13>")
		)
		(pad "28" smd rect
			(at -2.050034 -40.375078 90)
			(size 0.519938 1.4986)
			(layers "F.Cu" "F.Mask" "F.Paste")
			(net "GND")
		)
		(pad "29" smd rect
			(at -2.050034 -39.52494 90)
			(size 0.519938 1.4986)
			(layers "F.Cu" "F.Mask" "F.Paste")
			(net "M_K_CPU0_SA_DQ<16>")
		)
		(pad "30" smd rect
			(at -2.050034 -38.675056 90)
			(size 0.519938 1.4986)
			(layers "F.Cu" "F.Mask" "F.Paste")
			(net "GND")
		)
		(pad "31" smd rect
			(at -2.050034 -37.824918 90)
			(size 0.519938 1.4986)
			(layers "F.Cu" "F.Mask" "F.Paste")
			(net "M_K_CPU0_SA_DQ<17>")
		)
		(pad "32" smd rect
			(at -2.050034 -36.975034 90)
			(size 0.519938 1.4986)
			(layers "F.Cu" "F.Mask" "F.Paste")
			(net "GND")
		)
		(pad "33" smd rect
			(at -2.050034 -36.124896 90)
			(size 0.519938 1.4986)
			(layers "F.Cu" "F.Mask" "F.Paste")
			(net "M_K_CPU0_SA_DQS_DP<2>")
		)
		(pad "34" smd rect
			(at -2.050034 -35.275012 90)
			(size 0.519938 1.4986)
			(layers "F.Cu" "F.Mask" "F.Paste")
			(net "M_K_CPU0_SA_DQS_DN<2>")
		)
		(pad "35" smd rect
			(at -2.050034 -34.425128 90)
			(size 0.519938 1.4986)
			(layers "F.Cu" "F.Mask" "F.Paste")
			(net "GND")
		)
		(pad "36" smd rect
			(at -2.050034 -33.57499 90)
			(size 0.519938 1.4986)
			(layers "F.Cu" "F.Mask" "F.Paste")
			(net "M_K_CPU0_SA_DQ<20>")
		)
		(pad "37" smd rect
			(at -2.050034 -32.725106 90)
			(size 0.519938 1.4986)
			(layers "F.Cu" "F.Mask" "F.Paste")
			(net "GND")
		)
		(pad "38" smd rect
			(at -2.050034 -31.874968 90)
			(size 0.519938 1.4986)
			(layers "F.Cu" "F.Mask" "F.Paste")
			(net "M_K_CPU0_SA_DQ<21>")
		)
		(pad "39" smd rect
			(at -2.050034 -31.025084 90)
			(size 0.519938 1.4986)
			(layers "F.Cu" "F.Mask" "F.Paste")
			(net "GND")
		)
		(pad "40" smd rect
			(at -2.050034 -30.174946 90)
			(size 0.519938 1.4986)
			(layers "F.Cu" "F.Mask" "F.Paste")
			(net "M_K_CPU0_SA_DQ<24>")
		)
		(pad "41" smd rect
			(at -2.050034 -29.325062 90)
			(size 0.519938 1.4986)
			(layers "F.Cu" "F.Mask" "F.Paste")
			(net "GND")
		)
		(pad "42" smd rect
			(at -2.050034 -28.474924 90)
			(size 0.519938 1.4986)
			(layers "F.Cu" "F.Mask" "F.Paste")
			(net "M_K_CPU0_SA_DQ<25>")
		)
		(pad "43" smd rect
			(at -2.050034 -27.62504 90)
			(size 0.519938 1.4986)
			(layers "F.Cu" "F.Mask" "F.Paste")
			(net "GND")
		)
		(pad "44" smd rect
			(at -2.050034 -26.774902 90)
			(size 0.519938 1.4986)
			(layers "F.Cu" "F.Mask" "F.Paste")
			(net "M_K_CPU0_SA_DQS_DP<3>")
		)
		(pad "45" smd rect
			(at -2.050034 -25.925018 90)
			(size 0.519938 1.4986)
			(layers "F.Cu" "F.Mask" "F.Paste")
			(net "M_K_CPU0_SA_DQS_DN<3>")
		)
		(pad "46" smd rect
			(at -2.050034 -25.07488 90)
			(size 0.519938 1.4986)
			(layers "F.Cu" "F.Mask" "F.Paste")
			(net "GND")
		)
		(pad "47" smd rect
			(at -2.050034 -24.224996 90)
			(size 0.519938 1.4986)
			(layers "F.Cu" "F.Mask" "F.Paste")
			(net "M_K_CPU0_SA_DQ<28>")
		)
		(pad "48" smd rect
			(at -2.050034 -23.375112 90)
			(size 0.519938 1.4986)
			(layers "F.Cu" "F.Mask" "F.Paste")
			(net "GND")
		)
		(pad "49" smd rect
			(at -2.050034 -22.524974 90)
			(size 0.519938 1.4986)
			(layers "F.Cu" "F.Mask" "F.Paste")
			(net "M_K_CPU0_SA_DQ<29>")
		)
		(pad "50" smd rect
			(at -2.050034 -21.67509 90)
			(size 0.519938 1.4986)
			(layers "F.Cu" "F.Mask" "F.Paste")
			(net "GND")
		)
		(pad "51" smd rect
			(at -2.050034 -20.824952 90)
			(size 0.519938 1.4986)
			(layers "F.Cu" "F.Mask" "F.Paste")
			(net "M_K_CPU0_SA_CB<0>")
		)
		(pad "52" smd rect
			(at -2.050034 -19.975068 90)
			(size 0.519938 1.4986)
			(layers "F.Cu" "F.Mask" "F.Paste")
			(net "GND")
		)
		(pad "53" smd rect
			(at -2.050034 -19.12493 90)
			(size 0.519938 1.4986)
			(layers "F.Cu" "F.Mask" "F.Paste")
			(net "M_K_CPU0_SA_CB<1>")
		)
		(pad "54" smd rect
			(at -2.050034 -18.275046 90)
			(size 0.519938 1.4986)
			(layers "F.Cu" "F.Mask" "F.Paste")
			(net "GND")
		)
		(pad "55" smd rect
			(at -2.050034 -17.424908 90)
			(size 0.519938 1.4986)
			(layers "F.Cu" "F.Mask" "F.Paste")
			(net "M_K_CPU0_SA_DQS_DP<4>")
		)
		(pad "56" smd rect
			(at -2.050034 -16.575024 90)
			(size 0.519938 1.4986)
			(layers "F.Cu" "F.Mask" "F.Paste")
			(net "M_K_CPU0_SA_DQS_DN<4>")
		)
		(pad "57" smd rect
			(at -2.050034 -15.724886 90)
			(size 0.519938 1.4986)
			(layers "F.Cu" "F.Mask" "F.Paste")
			(net "GND")
		)
		(pad "58" smd rect
			(at -2.050034 -14.875002 90)
			(size 0.519938 1.4986)
			(layers "F.Cu" "F.Mask" "F.Paste")
			(net "M_K_CPU0_SA_CB<4>")
		)
		(pad "59" smd rect
			(at -2.050034 -14.025118 90)
			(size 0.519938 1.4986)
			(layers "F.Cu" "F.Mask" "F.Paste")
			(net "GND")
		)
		(pad "60" smd rect
			(at -2.050034 -13.17498 90)
			(size 0.519938 1.4986)
			(layers "F.Cu" "F.Mask" "F.Paste")
			(net "M_K_CPU0_SA_CB<5>")
		)
		(pad "61" smd rect
			(at -2.050034 -12.325096 90)
			(size 0.519938 1.4986)
			(layers "F.Cu" "F.Mask" "F.Paste")
			(net "GND")
		)
		(pad "62" smd rect
			(at -2.050034 -11.474958 90)
			(size 0.519938 1.4986)
			(layers "F.Cu" "F.Mask" "F.Paste")
			(net "M_K_CPU0_ALERT_N")
		)
		(pad "63" smd rect
			(at -2.050034 -10.625074 90)
			(size 0.519938 1.4986)
			(layers "F.Cu" "F.Mask" "F.Paste")
			(net "GND")
		)
		(pad "64" smd rect
			(at -2.050034 -9.774936 90)
			(size 0.519938 1.4986)
			(layers "F.Cu" "F.Mask" "F.Paste")
			(net "M_K_CPU0_SA_CS_N<0>")
		)
		(pad "65" smd rect
			(at -2.050034 -8.925052 90)
			(size 0.519938 1.4986)
			(layers "F.Cu" "F.Mask" "F.Paste")
			(net "GND")
		)
		(pad "66" smd rect
			(at -2.050034 -8.074914 90)
			(size 0.519938 1.4986)
			(layers "F.Cu" "F.Mask" "F.Paste")
			(net "M_K_CPU0_SA_CA<0>")
		)
		(pad "67" smd rect
			(at -2.050034 -7.22503 90)
			(size 0.519938 1.4986)
			(layers "F.Cu" "F.Mask" "F.Paste")
			(net "GND")
		)
		(pad "68" smd rect
			(at -2.050034 -6.374892 90)
			(size 0.519938 1.4986)
			(layers "F.Cu" "F.Mask" "F.Paste")
			(net "M_K_CPU0_SA_CA<2>")
		)
		(pad "69" smd rect
			(at -2.050034 -5.525008 90)
			(size 0.519938 1.4986)
			(layers "F.Cu" "F.Mask" "F.Paste")
			(net "GND")
		)
		(pad "70" smd rect
			(at -2.050034 -4.675124 90)
			(size 0.519938 1.4986)
			(layers "F.Cu" "F.Mask" "F.Paste")
			(net "M_K_CPU0_SA_CA<4>")
		)
		(pad "71" smd rect
			(at -2.050034 -3.824986 90)
			(size 0.519938 1.4986)
			(layers "F.Cu" "F.Mask" "F.Paste")
			(net "GND")
		)
		(pad "72" smd rect
			(at -2.050034 -2.975102 90)
			(size 0.519938 1.4986)
			(layers "F.Cu" "F.Mask" "F.Paste")
			(net "M_K_CPU0_SA_CA<6>")
		)
		(pad "73" smd rect
			(at -2.050034 -2.124964 90)
			(size 0.519938 1.4986)
			(layers "F.Cu" "F.Mask" "F.Paste")
			(net "GND")
		)
		(pad "74" smd rect
			(at -2.050034 -1.27508 90)
			(size 0.519938 1.4986)
			(layers "F.Cu" "F.Mask" "F.Paste")
			(net "M_K_CPU0_SA_PAR")
		)
		(pad "75" smd rect
			(at -2.050034 -0.424942 90)
			(size 0.519938 1.4986)
			(layers "F.Cu" "F.Mask" "F.Paste")
			(net "GND")
		)
		(pad "76" smd rect
			(at -2.050034 5.525008 90)
			(size 0.519938 1.4986)
			(layers "F.Cu" "F.Mask" "F.Paste")
			(net "M_K_CPU0_SB_CA<0>")
		)
		(pad "77" smd rect
			(at -2.050034 6.374892 90)
			(size 0.519938 1.4986)
			(layers "F.Cu" "F.Mask" "F.Paste")
			(net "GND")
		)
		(pad "78" smd rect
			(at -2.050034 7.22503 90)
			(size 0.519938 1.4986)
			(layers "F.Cu" "F.Mask" "F.Paste")
			(net "M_K_CPU0_SB_CA<2>")
		)
		(pad "79" smd rect
			(at -2.050034 8.074914 90)
			(size 0.519938 1.4986)
			(layers "F.Cu" "F.Mask" "F.Paste")
			(net "GND")
		)
		(pad "80" smd rect
			(at -2.050034 8.925052 90)
			(size 0.519938 1.4986)
			(layers "F.Cu" "F.Mask" "F.Paste")
			(net "M_K_CPU0_SB_CA<4>")
		)
		(pad "81" smd rect
			(at -2.050034 9.774936 90)
			(size 0.519938 1.4986)
			(layers "F.Cu" "F.Mask" "F.Paste")
			(net "GND")
		)
		(pad "82" smd rect
			(at -2.050034 10.625074 90)
			(size 0.519938 1.4986)
			(layers "F.Cu" "F.Mask" "F.Paste")
			(net "M_K_CPU0_SB_CA<6>")
		)
		(pad "83" smd rect
			(at -2.050034 11.474958 90)
			(size 0.519938 1.4986)
			(layers "F.Cu" "F.Mask" "F.Paste")
			(net "GND")
		)
		(pad "84" smd rect
			(at -2.050034 12.325096 90)
			(size 0.519938 1.4986)
			(layers "F.Cu" "F.Mask" "F.Paste")
			(net "M_K_CPU0_SB_CS_N<0>")
		)
		(pad "85" smd rect
			(at -2.050034 13.17498 90)
			(size 0.519938 1.4986)
			(layers "F.Cu" "F.Mask" "F.Paste")
			(net "GND")
		)
		(pad "86" smd rect
			(at -2.050034 14.025118 90)
			(size 0.519938 1.4986)
			(layers "F.Cu" "F.Mask" "F.Paste")
			(net "M_K_CPU0_SA_RSP<0>")
		)
		(pad "87" smd rect
			(at -2.050034 14.875002 90)
			(size 0.519938 1.4986)
			(layers "F.Cu" "F.Mask" "F.Paste")
			(net "M_K_CPU0_SB_RSP<0>")
		)
		(pad "88" smd rect
			(at -2.050034 15.724886 90)
			(size 0.519938 1.4986)
			(layers "F.Cu" "F.Mask" "F.Paste")
			(net "GND")
		)
		(pad "89" smd rect
			(at -2.050034 16.575024 90)
			(size 0.519938 1.4986)
			(layers "F.Cu" "F.Mask" "F.Paste")
			(net "M_K_CPU0_SB_CB<4>")
		)
		(pad "90" smd rect
			(at -2.050034 17.424908 90)
			(size 0.519938 1.4986)
			(layers "F.Cu" "F.Mask" "F.Paste")
			(net "GND")
		)
		(pad "91" smd rect
			(at -2.050034 18.275046 90)
			(size 0.519938 1.4986)
			(layers "F.Cu" "F.Mask" "F.Paste")
			(net "M_K_CPU0_SB_CB<5>")
		)
		(pad "92" smd rect
			(at -2.050034 19.12493 90)
			(size 0.519938 1.4986)
			(layers "F.Cu" "F.Mask" "F.Paste")
			(net "GND")
		)
		(pad "93" smd rect
			(at -2.050034 19.975068 90)
			(size 0.519938 1.4986)
			(layers "F.Cu" "F.Mask" "F.Paste")
			(net "M_K_CPU0_SB_DQS_DP<9>")
		)
		(pad "94" smd rect
			(at -2.050034 20.824952 90)
			(size 0.519938 1.4986)
			(layers "F.Cu" "F.Mask" "F.Paste")
			(net "M_K_CPU0_SB_DQS_DN<9>")
		)
		(pad "95" smd rect
			(at -2.050034 21.67509 90)
			(size 0.519938 1.4986)
			(layers "F.Cu" "F.Mask" "F.Paste")
			(net "GND")
		)
		(pad "96" smd rect
			(at -2.050034 22.524974 90)
			(size 0.519938 1.4986)
			(layers "F.Cu" "F.Mask" "F.Paste")
			(net "M_K_CPU0_SB_CB<0>")
		)
		(pad "97" smd rect
			(at -2.050034 23.375112 90)
			(size 0.519938 1.4986)
			(layers "F.Cu" "F.Mask" "F.Paste")
			(net "GND")
		)
		(pad "98" smd rect
			(at -2.050034 24.224996 90)
			(size 0.519938 1.4986)
			(layers "F.Cu" "F.Mask" "F.Paste")
			(net "M_K_CPU0_SB_CB<1>")
		)
		(pad "99" smd rect
			(at -2.050034 25.07488 90)
			(size 0.519938 1.4986)
			(layers "F.Cu" "F.Mask" "F.Paste")
			(net "GND")
		)
		(pad "100" smd rect
			(at -2.050034 25.925018 90)
			(size 0.519938 1.4986)
			(layers "F.Cu" "F.Mask" "F.Paste")
			(net "M_K_CPU0_SB_DQ<0>")
		)
		(pad "101" smd rect
			(at -2.050034 26.774902 90)
			(size 0.519938 1.4986)
			(layers "F.Cu" "F.Mask" "F.Paste")
			(net "GND")
		)
		(pad "102" smd rect
			(at -2.050034 27.62504 90)
			(size 0.519938 1.4986)
			(layers "F.Cu" "F.Mask" "F.Paste")
			(net "M_K_CPU0_SB_DQ<1>")
		)
		(pad "103" smd rect
			(at -2.050034 28.474924 90)
			(size 0.519938 1.4986)
			(layers "F.Cu" "F.Mask" "F.Paste")
			(net "GND")
		)
		(pad "104" smd rect
			(at -2.050034 29.325062 90)
			(size 0.519938 1.4986)
			(layers "F.Cu" "F.Mask" "F.Paste")
			(net "M_K_CPU0_SB_DQS_DP<0>")
		)
		(pad "105" smd rect
			(at -2.050034 30.174946 90)
			(size 0.519938 1.4986)
			(layers "F.Cu" "F.Mask" "F.Paste")
			(net "M_K_CPU0_SB_DQS_DN<0>")
		)
		(pad "106" smd rect
			(at -2.050034 31.025084 90)
			(size 0.519938 1.4986)
			(layers "F.Cu" "F.Mask" "F.Paste")
			(net "GND")
		)
		(pad "107" smd rect
			(at -2.050034 31.874968 90)
			(size 0.519938 1.4986)
			(layers "F.Cu" "F.Mask" "F.Paste")
			(net "M_K_CPU0_SB_DQ<4>")
		)
		(pad "108" smd rect
			(at -2.050034 32.725106 90)
			(size 0.519938 1.4986)
			(layers "F.Cu" "F.Mask" "F.Paste")
			(net "GND")
		)
		(pad "109" smd rect
			(at -2.050034 33.57499 90)
			(size 0.519938 1.4986)
			(layers "F.Cu" "F.Mask" "F.Paste")
			(net "M_K_CPU0_SB_DQ<5>")
		)
		(pad "110" smd rect
			(at -2.050034 34.425128 90)
			(size 0.519938 1.4986)
			(layers "F.Cu" "F.Mask" "F.Paste")
			(net "GND")
		)
		(pad "111" smd rect
			(at -2.050034 35.275012 90)
			(size 0.519938 1.4986)
			(layers "F.Cu" "F.Mask" "F.Paste")
			(net "M_K_CPU0_SB_DQ<8>")
		)
		(pad "112" smd rect
			(at -2.050034 36.124896 90)
			(size 0.519938 1.4986)
			(layers "F.Cu" "F.Mask" "F.Paste")
			(net "GND")
		)
		(pad "113" smd rect
			(at -2.050034 36.975034 90)
			(size 0.519938 1.4986)
			(layers "F.Cu" "F.Mask" "F.Paste")
			(net "M_K_CPU0_SB_DQ<9>")
		)
		(pad "114" smd rect
			(at -2.050034 37.824918 90)
			(size 0.519938 1.4986)
			(layers "F.Cu" "F.Mask" "F.Paste")
			(net "GND")
		)
		(pad "115" smd rect
			(at -2.050034 38.675056 90)
			(size 0.519938 1.4986)
			(layers "F.Cu" "F.Mask" "F.Paste")
			(net "M_K_CPU0_SB_DQS_DP<1>")
		)
		(pad "116" smd rect
			(at -2.050034 39.52494 90)
			(size 0.519938 1.4986)
			(layers "F.Cu" "F.Mask" "F.Paste")
			(net "M_K_CPU0_SB_DQS_DN<1>")
		)
		(pad "117" smd rect
			(at -2.050034 40.375078 90)
			(size 0.519938 1.4986)
			(layers "F.Cu" "F.Mask" "F.Paste")
			(net "GND")
		)
		(pad "118" smd rect
			(at -2.050034 41.224962 90)
			(size 0.519938 1.4986)
			(layers "F.Cu" "F.Mask" "F.Paste")
			(net "M_K_CPU0_SB_DQ<12>")
		)
		(pad "119" smd rect
			(at -2.050034 42.0751 90)
			(size 0.519938 1.4986)
			(layers "F.Cu" "F.Mask" "F.Paste")
			(net "GND")
		)
		(pad "120" smd rect
			(at -2.050034 42.924984 90)
			(size 0.519938 1.4986)
			(layers "F.Cu" "F.Mask" "F.Paste")
			(net "M_K_CPU0_SB_DQ<13>")
		)
		(pad "121" smd rect
			(at -2.050034 43.775122 90)
			(size 0.519938 1.4986)
			(layers "F.Cu" "F.Mask" "F.Paste")
			(net "GND")
		)
		(pad "122" smd rect
			(at -2.050034 44.625006 90)
			(size 0.519938 1.4986)
			(layers "F.Cu" "F.Mask" "F.Paste")
			(net "M_K_CPU0_SB_DQ<16>")
		)
		(pad "123" smd rect
			(at -2.050034 45.47489 90)
			(size 0.519938 1.4986)
			(layers "F.Cu" "F.Mask" "F.Paste")
			(net "GND")
		)
		(pad "124" smd rect
			(at -2.050034 46.325028 90)
			(size 0.519938 1.4986)
			(layers "F.Cu" "F.Mask" "F.Paste")
			(net "M_K_CPU0_SB_DQ<17>")
		)
		(pad "125" smd rect
			(at -2.050034 47.174912 90)
			(size 0.519938 1.4986)
			(layers "F.Cu" "F.Mask" "F.Paste")
			(net "GND")
		)
		(pad "126" smd rect
			(at -2.050034 48.02505 90)
			(size 0.519938 1.4986)
			(layers "F.Cu" "F.Mask" "F.Paste")
			(net "M_K_CPU0_SB_DQS_DP<2>")
		)
		(pad "127" smd rect
			(at -2.050034 48.874934 90)
			(size 0.519938 1.4986)
			(layers "F.Cu" "F.Mask" "F.Paste")
			(net "M_K_CPU0_SB_DQS_DN<2>")
		)
		(pad "128" smd rect
			(at -2.050034 49.725072 90)
			(size 0.519938 1.4986)
			(layers "F.Cu" "F.Mask" "F.Paste")
			(net "GND")
		)
		(pad "129" smd rect
			(at -2.050034 50.574956 90)
			(size 0.519938 1.4986)
			(layers "F.Cu" "F.Mask" "F.Paste")
			(net "M_K_CPU0_SB_DQ<20>")
		)
		(pad "130" smd rect
			(at -2.050034 51.425094 90)
			(size 0.519938 1.4986)
			(layers "F.Cu" "F.Mask" "F.Paste")
			(net "GND")
		)
		(pad "131" smd rect
			(at -2.050034 52.274978 90)
			(size 0.519938 1.4986)
			(layers "F.Cu" "F.Mask" "F.Paste")
			(net "M_K_CPU0_SB_DQ<21>")
		)
		(pad "132" smd rect
			(at -2.050034 53.125116 90)
			(size 0.519938 1.4986)
			(layers "F.Cu" "F.Mask" "F.Paste")
			(net "GND")
		)
		(pad "133" smd rect
			(at -2.050034 53.975 90)
			(size 0.519938 1.4986)
			(layers "F.Cu" "F.Mask" "F.Paste")
			(net "M_K_CPU0_SB_DQ<24>")
		)
		(pad "134" smd rect
			(at -2.050034 54.824884 90)
			(size 0.519938 1.4986)
			(layers "F.Cu" "F.Mask" "F.Paste")
			(net "GND")
		)
		(pad "135" smd rect
			(at -2.050034 55.675022 90)
			(size 0.519938 1.4986)
			(layers "F.Cu" "F.Mask" "F.Paste")
			(net "M_K_CPU0_SB_DQ<25>")
		)
		(pad "136" smd rect
			(at -2.050034 56.524906 90)
			(size 0.519938 1.4986)
			(layers "F.Cu" "F.Mask" "F.Paste")
			(net "GND")
		)
		(pad "137" smd rect
			(at -2.050034 57.375044 90)
			(size 0.519938 1.4986)
			(layers "F.Cu" "F.Mask" "F.Paste")
			(net "M_K_CPU0_SB_DQS_DP<3>")
		)
		(pad "138" smd rect
			(at -2.050034 58.224928 90)
			(size 0.519938 1.4986)
			(layers "F.Cu" "F.Mask" "F.Paste")
			(net "M_K_CPU0_SB_DQS_DN<3>")
		)
		(pad "139" smd rect
			(at -2.050034 59.075066 90)
			(size 0.519938 1.4986)
			(layers "F.Cu" "F.Mask" "F.Paste")
			(net "GND")
		)
		(pad "140" smd rect
			(at -2.050034 59.92495 90)
			(size 0.519938 1.4986)
			(layers "F.Cu" "F.Mask" "F.Paste")
			(net "M_K_CPU0_SB_DQ<28>")
		)
		(pad "141" smd rect
			(at -2.050034 60.775088 90)
			(size 0.519938 1.4986)
			(layers "F.Cu" "F.Mask" "F.Paste")
			(net "GND")
		)
		(pad "142" smd rect
			(at -2.050034 61.624972 90)
			(size 0.519938 1.4986)
			(layers "F.Cu" "F.Mask" "F.Paste")
			(net "M_K_CPU0_SB_DQ<29>")
		)
		(pad "143" smd rect
			(at -2.050034 62.47511 90)
			(size 0.519938 1.4986)
			(layers "F.Cu" "F.Mask" "F.Paste")
			(net "GND")
		)
		(pad "144" smd rect
			(at -2.050034 63.324994 90)
			(size 0.519938 1.4986)
			(layers "F.Cu" "F.Mask" "F.Paste")
			(net "Net_2390")
		)
		(pad "145" smd rect
			(at 2.050034 -63.324994 90)
			(size 0.519938 1.4986)
			(layers "F.Cu" "F.Mask" "F.Paste")
			(net "P12V_MEM_CPU0")
		)
		(pad "146" smd rect
			(at 2.050034 -62.47511 90)
			(size 0.519938 1.4986)
			(layers "F.Cu" "F.Mask" "F.Paste")
			(net "P12V_MEM_CPU0")
		)
		(pad "147" smd rect
			(at 2.050034 -61.624972 90)
			(size 0.519938 1.4986)
			(layers "F.Cu" "F.Mask" "F.Paste")
			(net "PWRGD_CHK_CPU0_DIMM")
		)
		(pad "148" smd rect
			(at 2.050034 -60.775088 90)
			(size 0.519938 1.4986)
			(layers "F.Cu" "F.Mask" "F.Paste")
			(net "PD_CHK_CPU0_DIMM_SAA")
		)
		(pad "149" smd rect
			(at 2.050034 -59.92495 90)
			(size 0.519938 1.4986)
			(layers "F.Cu" "F.Mask" "F.Paste")
			(net "Net_2391")
		)
		(pad "150" smd rect
			(at 2.050034 -59.075066 90)
			(size 0.519938 1.4986)
			(layers "F.Cu" "F.Mask" "F.Paste")
			(net "Net_2392")
		)
		(pad "151" smd rect
			(at 2.050034 -58.224928 90)
			(size 0.519938 1.4986)
			(layers "F.Cu" "F.Mask" "F.Paste")
			(net "GND")
		)
		(pad "152" smd rect
			(at 2.050034 -57.375044 90)
			(size 0.519938 1.4986)
			(layers "F.Cu" "F.Mask" "F.Paste")
			(net "M_K_CPU0_SA_DQ<2>")
		)
		(pad "153" smd rect
			(at 2.050034 -56.524906 90)
			(size 0.519938 1.4986)
			(layers "F.Cu" "F.Mask" "F.Paste")
			(net "GND")
		)
		(pad "154" smd rect
			(at 2.050034 -55.675022 90)
			(size 0.519938 1.4986)
			(layers "F.Cu" "F.Mask" "F.Paste")
			(net "M_K_CPU0_SA_DQ<3>")
		)
		(pad "155" smd rect
			(at 2.050034 -54.824884 90)
			(size 0.519938 1.4986)
			(layers "F.Cu" "F.Mask" "F.Paste")
			(net "GND")
		)
		(pad "156" smd rect
			(at 2.050034 -53.975 90)
			(size 0.519938 1.4986)
			(layers "F.Cu" "F.Mask" "F.Paste")
			(net "M_K_CPU0_SA_DQS_DN<5>")
		)
		(pad "157" smd rect
			(at 2.050034 -53.125116 90)
			(size 0.519938 1.4986)
			(layers "F.Cu" "F.Mask" "F.Paste")
			(net "M_K_CPU0_SA_DQS_DP<5>")
		)
		(pad "158" smd rect
			(at 2.050034 -52.274978 90)
			(size 0.519938 1.4986)
			(layers "F.Cu" "F.Mask" "F.Paste")
			(net "GND")
		)
		(pad "159" smd rect
			(at 2.050034 -51.425094 90)
			(size 0.519938 1.4986)
			(layers "F.Cu" "F.Mask" "F.Paste")
			(net "M_K_CPU0_SA_DQ<6>")
		)
		(pad "160" smd rect
			(at 2.050034 -50.574956 90)
			(size 0.519938 1.4986)
			(layers "F.Cu" "F.Mask" "F.Paste")
			(net "GND")
		)
		(pad "161" smd rect
			(at 2.050034 -49.725072 90)
			(size 0.519938 1.4986)
			(layers "F.Cu" "F.Mask" "F.Paste")
			(net "M_K_CPU0_SA_DQ<7>")
		)
		(pad "162" smd rect
			(at 2.050034 -48.874934 90)
			(size 0.519938 1.4986)
			(layers "F.Cu" "F.Mask" "F.Paste")
			(net "GND")
		)
		(pad "163" smd rect
			(at 2.050034 -48.02505 90)
			(size 0.519938 1.4986)
			(layers "F.Cu" "F.Mask" "F.Paste")
			(net "M_K_CPU0_SA_DQ<10>")
		)
		(pad "164" smd rect
			(at 2.050034 -47.174912 90)
			(size 0.519938 1.4986)
			(layers "F.Cu" "F.Mask" "F.Paste")
			(net "GND")
		)
		(pad "165" smd rect
			(at 2.050034 -46.325028 90)
			(size 0.519938 1.4986)
			(layers "F.Cu" "F.Mask" "F.Paste")
			(net "M_K_CPU0_SA_DQ<11>")
		)
		(pad "166" smd rect
			(at 2.050034 -45.47489 90)
			(size 0.519938 1.4986)
			(layers "F.Cu" "F.Mask" "F.Paste")
			(net "GND")
		)
		(pad "167" smd rect
			(at 2.050034 -44.625006 90)
			(size 0.519938 1.4986)
			(layers "F.Cu" "F.Mask" "F.Paste")
			(net "M_K_CPU0_SA_DQS_DN<6>")
		)
		(pad "168" smd rect
			(at 2.050034 -43.775122 90)
			(size 0.519938 1.4986)
			(layers "F.Cu" "F.Mask" "F.Paste")
			(net "M_K_CPU0_SA_DQS_DP<6>")
		)
		(pad "169" smd rect
			(at 2.050034 -42.924984 90)
			(size 0.519938 1.4986)
			(layers "F.Cu" "F.Mask" "F.Paste")
			(net "GND")
		)
		(pad "170" smd rect
			(at 2.050034 -42.0751 90)
			(size 0.519938 1.4986)
			(layers "F.Cu" "F.Mask" "F.Paste")
			(net "M_K_CPU0_SA_DQ<14>")
		)
		(pad "171" smd rect
			(at 2.050034 -41.224962 90)
			(size 0.519938 1.4986)
			(layers "F.Cu" "F.Mask" "F.Paste")
			(net "GND")
		)
		(pad "172" smd rect
			(at 2.050034 -40.375078 90)
			(size 0.519938 1.4986)
			(layers "F.Cu" "F.Mask" "F.Paste")
			(net "M_K_CPU0_SA_DQ<15>")
		)
		(pad "173" smd rect
			(at 2.050034 -39.52494 90)
			(size 0.519938 1.4986)
			(layers "F.Cu" "F.Mask" "F.Paste")
			(net "GND")
		)
		(pad "174" smd rect
			(at 2.050034 -38.675056 90)
			(size 0.519938 1.4986)
			(layers "F.Cu" "F.Mask" "F.Paste")
			(net "M_K_CPU0_SA_DQ<18>")
		)
		(pad "175" smd rect
			(at 2.050034 -37.824918 90)
			(size 0.519938 1.4986)
			(layers "F.Cu" "F.Mask" "F.Paste")
			(net "GND")
		)
		(pad "176" smd rect
			(at 2.050034 -36.975034 90)
			(size 0.519938 1.4986)
			(layers "F.Cu" "F.Mask" "F.Paste")
			(net "M_K_CPU0_SA_DQ<19>")
		)
		(pad "177" smd rect
			(at 2.050034 -36.124896 90)
			(size 0.519938 1.4986)
			(layers "F.Cu" "F.Mask" "F.Paste")
			(net "GND")
		)
		(pad "178" smd rect
			(at 2.050034 -35.275012 90)
			(size 0.519938 1.4986)
			(layers "F.Cu" "F.Mask" "F.Paste")
			(net "M_K_CPU0_SA_DQS_DN<7>")
		)
		(pad "179" smd rect
			(at 2.050034 -34.425128 90)
			(size 0.519938 1.4986)
			(layers "F.Cu" "F.Mask" "F.Paste")
			(net "M_K_CPU0_SA_DQS_DP<7>")
		)
		(pad "180" smd rect
			(at 2.050034 -33.57499 90)
			(size 0.519938 1.4986)
			(layers "F.Cu" "F.Mask" "F.Paste")
			(net "GND")
		)
		(pad "181" smd rect
			(at 2.050034 -32.725106 90)
			(size 0.519938 1.4986)
			(layers "F.Cu" "F.Mask" "F.Paste")
			(net "M_K_CPU0_SA_DQ<22>")
		)
		(pad "182" smd rect
			(at 2.050034 -31.874968 90)
			(size 0.519938 1.4986)
			(layers "F.Cu" "F.Mask" "F.Paste")
			(net "GND")
		)
		(pad "183" smd rect
			(at 2.050034 -31.025084 90)
			(size 0.519938 1.4986)
			(layers "F.Cu" "F.Mask" "F.Paste")
			(net "M_K_CPU0_SA_DQ<23>")
		)
		(pad "184" smd rect
			(at 2.050034 -30.174946 90)
			(size 0.519938 1.4986)
			(layers "F.Cu" "F.Mask" "F.Paste")
			(net "GND")
		)
		(pad "185" smd rect
			(at 2.050034 -29.325062 90)
			(size 0.519938 1.4986)
			(layers "F.Cu" "F.Mask" "F.Paste")
			(net "M_K_CPU0_SA_DQ<26>")
		)
		(pad "186" smd rect
			(at 2.050034 -28.474924 90)
			(size 0.519938 1.4986)
			(layers "F.Cu" "F.Mask" "F.Paste")
			(net "GND")
		)
		(pad "187" smd rect
			(at 2.050034 -27.62504 90)
			(size 0.519938 1.4986)
			(layers "F.Cu" "F.Mask" "F.Paste")
			(net "M_K_CPU0_SA_DQ<27>")
		)
		(pad "188" smd rect
			(at 2.050034 -26.774902 90)
			(size 0.519938 1.4986)
			(layers "F.Cu" "F.Mask" "F.Paste")
			(net "GND")
		)
		(pad "189" smd rect
			(at 2.050034 -25.925018 90)
			(size 0.519938 1.4986)
			(layers "F.Cu" "F.Mask" "F.Paste")
			(net "M_K_CPU0_SA_DQS_DN<8>")
		)
		(pad "190" smd rect
			(at 2.050034 -25.07488 90)
			(size 0.519938 1.4986)
			(layers "F.Cu" "F.Mask" "F.Paste")
			(net "M_K_CPU0_SA_DQS_DP<8>")
		)
		(pad "191" smd rect
			(at 2.050034 -24.224996 90)
			(size 0.519938 1.4986)
			(layers "F.Cu" "F.Mask" "F.Paste")
			(net "GND")
		)
		(pad "192" smd rect
			(at 2.050034 -23.375112 90)
			(size 0.519938 1.4986)
			(layers "F.Cu" "F.Mask" "F.Paste")
			(net "M_K_CPU0_SA_DQ<30>")
		)
		(pad "193" smd rect
			(at 2.050034 -22.524974 90)
			(size 0.519938 1.4986)
			(layers "F.Cu" "F.Mask" "F.Paste")
			(net "GND")
		)
		(pad "194" smd rect
			(at 2.050034 -21.67509 90)
			(size 0.519938 1.4986)
			(layers "F.Cu" "F.Mask" "F.Paste")
			(net "M_K_CPU0_SA_DQ<31>")
		)
		(pad "195" smd rect
			(at 2.050034 -20.824952 90)
			(size 0.519938 1.4986)
			(layers "F.Cu" "F.Mask" "F.Paste")
			(net "GND")
		)
		(pad "196" smd rect
			(at 2.050034 -19.975068 90)
			(size 0.519938 1.4986)
			(layers "F.Cu" "F.Mask" "F.Paste")
			(net "M_K_CPU0_SA_CB<2>")
		)
		(pad "197" smd rect
			(at 2.050034 -19.12493 90)
			(size 0.519938 1.4986)
			(layers "F.Cu" "F.Mask" "F.Paste")
			(net "GND")
		)
		(pad "198" smd rect
			(at 2.050034 -18.275046 90)
			(size 0.519938 1.4986)
			(layers "F.Cu" "F.Mask" "F.Paste")
			(net "M_K_CPU0_SA_CB<3>")
		)
		(pad "199" smd rect
			(at 2.050034 -17.424908 90)
			(size 0.519938 1.4986)
			(layers "F.Cu" "F.Mask" "F.Paste")
			(net "GND")
		)
		(pad "200" smd rect
			(at 2.050034 -16.575024 90)
			(size 0.519938 1.4986)
			(layers "F.Cu" "F.Mask" "F.Paste")
			(net "M_K_CPU0_SA_DQS_DN<9>")
		)
		(pad "201" smd rect
			(at 2.050034 -15.724886 90)
			(size 0.519938 1.4986)
			(layers "F.Cu" "F.Mask" "F.Paste")
			(net "M_K_CPU0_SA_DQS_DP<9>")
		)
		(pad "202" smd rect
			(at 2.050034 -14.875002 90)
			(size 0.519938 1.4986)
			(layers "F.Cu" "F.Mask" "F.Paste")
			(net "GND")
		)
		(pad "203" smd rect
			(at 2.050034 -14.025118 90)
			(size 0.519938 1.4986)
			(layers "F.Cu" "F.Mask" "F.Paste")
			(net "M_K_CPU0_SA_CB<6>")
		)
		(pad "204" smd rect
			(at 2.050034 -13.17498 90)
			(size 0.519938 1.4986)
			(layers "F.Cu" "F.Mask" "F.Paste")
			(net "GND")
		)
		(pad "205" smd rect
			(at 2.050034 -12.325096 90)
			(size 0.519938 1.4986)
			(layers "F.Cu" "F.Mask" "F.Paste")
			(net "M_K_CPU0_SA_CB<7>")
		)
		(pad "206" smd rect
			(at 2.050034 -11.474958 90)
			(size 0.519938 1.4986)
			(layers "F.Cu" "F.Mask" "F.Paste")
			(net "GND")
		)
		(pad "207" smd rect
			(at 2.050034 -10.625074 90)
			(size 0.519938 1.4986)
			(layers "F.Cu" "F.Mask" "F.Paste")
			(net "M_K_CPU0_RESET_N")
		)
		(pad "208" smd rect
			(at 2.050034 -9.774936 90)
			(size 0.519938 1.4986)
			(layers "F.Cu" "F.Mask" "F.Paste")
			(net "GND")
		)
		(pad "209" smd rect
			(at 2.050034 -8.925052 90)
			(size 0.519938 1.4986)
			(layers "F.Cu" "F.Mask" "F.Paste")
			(net "M_K_CPU0_SA_CS_N<1>")
		)
		(pad "210" smd rect
			(at 2.050034 -8.074914 90)
			(size 0.519938 1.4986)
			(layers "F.Cu" "F.Mask" "F.Paste")
			(net "GND")
		)
		(pad "211" smd rect
			(at 2.050034 -7.22503 90)
			(size 0.519938 1.4986)
			(layers "F.Cu" "F.Mask" "F.Paste")
			(net "M_K_CPU0_SA_CA<1>")
		)
		(pad "212" smd rect
			(at 2.050034 -6.374892 90)
			(size 0.519938 1.4986)
			(layers "F.Cu" "F.Mask" "F.Paste")
			(net "GND")
		)
		(pad "213" smd rect
			(at 2.050034 -5.525008 90)
			(size 0.519938 1.4986)
			(layers "F.Cu" "F.Mask" "F.Paste")
			(net "M_K_CPU0_SA_CA<3>")
		)
		(pad "214" smd rect
			(at 2.050034 -4.675124 90)
			(size 0.519938 1.4986)
			(layers "F.Cu" "F.Mask" "F.Paste")
			(net "GND")
		)
		(pad "215" smd rect
			(at 2.050034 -3.824986 90)
			(size 0.519938 1.4986)
			(layers "F.Cu" "F.Mask" "F.Paste")
			(net "M_K_CPU0_SA_CA<5>")
		)
		(pad "216" smd rect
			(at 2.050034 -2.975102 90)
			(size 0.519938 1.4986)
			(layers "F.Cu" "F.Mask" "F.Paste")
			(net "GND")
		)
		(pad "217" smd rect
			(at 2.050034 -2.124964 90)
			(size 0.519938 1.4986)
			(layers "F.Cu" "F.Mask" "F.Paste")
			(net "M_K_CPU0_CLK_DP<0>")
		)
		(pad "218" smd rect
			(at 2.050034 -1.27508 90)
			(size 0.519938 1.4986)
			(layers "F.Cu" "F.Mask" "F.Paste")
			(net "M_K_CPU0_CLK_DN<0>")
		)
		(pad "219" smd rect
			(at 2.050034 -0.424942 90)
			(size 0.519938 1.4986)
			(layers "F.Cu" "F.Mask" "F.Paste")
			(net "GND")
		)
		(pad "220" smd rect
			(at 2.050034 5.525008 90)
			(size 0.519938 1.4986)
			(layers "F.Cu" "F.Mask" "F.Paste")
			(net "Net_2393")
		)
		(pad "221" smd rect
			(at 2.050034 6.374892 90)
			(size 0.519938 1.4986)
			(layers "F.Cu" "F.Mask" "F.Paste")
			(net "M_K_CPU0_SB_CA<1>")
		)
		(pad "222" smd rect
			(at 2.050034 7.22503 90)
			(size 0.519938 1.4986)
			(layers "F.Cu" "F.Mask" "F.Paste")
			(net "GND")
		)
		(pad "223" smd rect
			(at 2.050034 8.074914 90)
			(size 0.519938 1.4986)
			(layers "F.Cu" "F.Mask" "F.Paste")
			(net "M_K_CPU0_SB_CA<3>")
		)
		(pad "224" smd rect
			(at 2.050034 8.925052 90)
			(size 0.519938 1.4986)
			(layers "F.Cu" "F.Mask" "F.Paste")
			(net "GND")
		)
		(pad "225" smd rect
			(at 2.050034 9.774936 90)
			(size 0.519938 1.4986)
			(layers "F.Cu" "F.Mask" "F.Paste")
			(net "M_K_CPU0_SB_CA<5>")
		)
		(pad "226" smd rect
			(at 2.050034 10.625074 90)
			(size 0.519938 1.4986)
			(layers "F.Cu" "F.Mask" "F.Paste")
			(net "GND")
		)
		(pad "227" smd rect
			(at 2.050034 11.474958 90)
			(size 0.519938 1.4986)
			(layers "F.Cu" "F.Mask" "F.Paste")
			(net "M_K_CPU0_SB_PAR")
		)
		(pad "228" smd rect
			(at 2.050034 12.325096 90)
			(size 0.519938 1.4986)
			(layers "F.Cu" "F.Mask" "F.Paste")
			(net "GND")
		)
		(pad "229" smd rect
			(at 2.050034 13.17498 90)
			(size 0.519938 1.4986)
			(layers "F.Cu" "F.Mask" "F.Paste")
			(net "M_K_CPU0_SB_CS_N<1>")
		)
		(pad "230" smd rect
			(at 2.050034 14.025118 90)
			(size 0.519938 1.4986)
			(layers "F.Cu" "F.Mask" "F.Paste")
			(net "GND")
		)
		(pad "231" smd rect
			(at 2.050034 14.875002 90)
			(size 0.519938 1.4986)
			(layers "F.Cu" "F.Mask" "F.Paste")
			(net "Net_2394")
		)
		(pad "232" smd rect
			(at 2.050034 15.724886 90)
			(size 0.519938 1.4986)
			(layers "F.Cu" "F.Mask" "F.Paste")
			(net "Net_2395")
		)
		(pad "233" smd rect
			(at 2.050034 16.575024 90)
			(size 0.519938 1.4986)
			(layers "F.Cu" "F.Mask" "F.Paste")
			(net "GND")
		)
		(pad "234" smd rect
			(at 2.050034 17.424908 90)
			(size 0.519938 1.4986)
			(layers "F.Cu" "F.Mask" "F.Paste")
			(net "M_K_CPU0_SB_CB<6>")
		)
		(pad "235" smd rect
			(at 2.050034 18.275046 90)
			(size 0.519938 1.4986)
			(layers "F.Cu" "F.Mask" "F.Paste")
			(net "GND")
		)
		(pad "236" smd rect
			(at 2.050034 19.12493 90)
			(size 0.519938 1.4986)
			(layers "F.Cu" "F.Mask" "F.Paste")
			(net "M_K_CPU0_SB_CB<7>")
		)
		(pad "237" smd rect
			(at 2.050034 19.975068 90)
			(size 0.519938 1.4986)
			(layers "F.Cu" "F.Mask" "F.Paste")
			(net "GND")
		)
		(pad "238" smd rect
			(at 2.050034 20.824952 90)
			(size 0.519938 1.4986)
			(layers "F.Cu" "F.Mask" "F.Paste")
			(net "M_K_CPU0_SB_DQS_DN<4>")
		)
		(pad "239" smd rect
			(at 2.050034 21.67509 90)
			(size 0.519938 1.4986)
			(layers "F.Cu" "F.Mask" "F.Paste")
			(net "M_K_CPU0_SB_DQS_DP<4>")
		)
		(pad "240" smd rect
			(at 2.050034 22.524974 90)
			(size 0.519938 1.4986)
			(layers "F.Cu" "F.Mask" "F.Paste")
			(net "GND")
		)
		(pad "241" smd rect
			(at 2.050034 23.375112 90)
			(size 0.519938 1.4986)
			(layers "F.Cu" "F.Mask" "F.Paste")
			(net "M_K_CPU0_SB_CB<2>")
		)
		(pad "242" smd rect
			(at 2.050034 24.224996 90)
			(size 0.519938 1.4986)
			(layers "F.Cu" "F.Mask" "F.Paste")
			(net "GND")
		)
		(pad "243" smd rect
			(at 2.050034 25.07488 90)
			(size 0.519938 1.4986)
			(layers "F.Cu" "F.Mask" "F.Paste")
			(net "M_K_CPU0_SB_CB<3>")
		)
		(pad "244" smd rect
			(at 2.050034 25.925018 90)
			(size 0.519938 1.4986)
			(layers "F.Cu" "F.Mask" "F.Paste")
			(net "GND")
		)
		(pad "245" smd rect
			(at 2.050034 26.774902 90)
			(size 0.519938 1.4986)
			(layers "F.Cu" "F.Mask" "F.Paste")
			(net "M_K_CPU0_SB_DQ<2>")
		)
		(pad "246" smd rect
			(at 2.050034 27.62504 90)
			(size 0.519938 1.4986)
			(layers "F.Cu" "F.Mask" "F.Paste")
			(net "GND")
		)
		(pad "247" smd rect
			(at 2.050034 28.474924 90)
			(size 0.519938 1.4986)
			(layers "F.Cu" "F.Mask" "F.Paste")
			(net "M_K_CPU0_SB_DQ<3>")
		)
		(pad "248" smd rect
			(at 2.050034 29.325062 90)
			(size 0.519938 1.4986)
			(layers "F.Cu" "F.Mask" "F.Paste")
			(net "GND")
		)
		(pad "249" smd rect
			(at 2.050034 30.174946 90)
			(size 0.519938 1.4986)
			(layers "F.Cu" "F.Mask" "F.Paste")
			(net "M_K_CPU0_SB_DQS_DN<5>")
		)
		(pad "250" smd rect
			(at 2.050034 31.025084 90)
			(size 0.519938 1.4986)
			(layers "F.Cu" "F.Mask" "F.Paste")
			(net "M_K_CPU0_SB_DQS_DP<5>")
		)
		(pad "251" smd rect
			(at 2.050034 31.874968 90)
			(size 0.519938 1.4986)
			(layers "F.Cu" "F.Mask" "F.Paste")
			(net "GND")
		)
		(pad "252" smd rect
			(at 2.050034 32.725106 90)
			(size 0.519938 1.4986)
			(layers "F.Cu" "F.Mask" "F.Paste")
			(net "M_K_CPU0_SB_DQ<6>")
		)
		(pad "253" smd rect
			(at 2.050034 33.57499 90)
			(size 0.519938 1.4986)
			(layers "F.Cu" "F.Mask" "F.Paste")
			(net "GND")
		)
		(pad "254" smd rect
			(at 2.050034 34.425128 90)
			(size 0.519938 1.4986)
			(layers "F.Cu" "F.Mask" "F.Paste")
			(net "M_K_CPU0_SB_DQ<7>")
		)
		(pad "255" smd rect
			(at 2.050034 35.275012 90)
			(size 0.519938 1.4986)
			(layers "F.Cu" "F.Mask" "F.Paste")
			(net "GND")
		)
		(pad "256" smd rect
			(at 2.050034 36.124896 90)
			(size 0.519938 1.4986)
			(layers "F.Cu" "F.Mask" "F.Paste")
			(net "M_K_CPU0_SB_DQ<10>")
		)
		(pad "257" smd rect
			(at 2.050034 36.975034 90)
			(size 0.519938 1.4986)
			(layers "F.Cu" "F.Mask" "F.Paste")
			(net "GND")
		)
		(pad "258" smd rect
			(at 2.050034 37.824918 90)
			(size 0.519938 1.4986)
			(layers "F.Cu" "F.Mask" "F.Paste")
			(net "M_K_CPU0_SB_DQ<11>")
		)
		(pad "259" smd rect
			(at 2.050034 38.675056 90)
			(size 0.519938 1.4986)
			(layers "F.Cu" "F.Mask" "F.Paste")
			(net "GND")
		)
		(pad "260" smd rect
			(at 2.050034 39.52494 90)
			(size 0.519938 1.4986)
			(layers "F.Cu" "F.Mask" "F.Paste")
			(net "M_K_CPU0_SB_DQS_DN<6>")
		)
		(pad "261" smd rect
			(at 2.050034 40.375078 90)
			(size 0.519938 1.4986)
			(layers "F.Cu" "F.Mask" "F.Paste")
			(net "M_K_CPU0_SB_DQS_DP<6>")
		)
		(pad "262" smd rect
			(at 2.050034 41.224962 90)
			(size 0.519938 1.4986)
			(layers "F.Cu" "F.Mask" "F.Paste")
			(net "GND")
		)
		(pad "263" smd rect
			(at 2.050034 42.0751 90)
			(size 0.519938 1.4986)
			(layers "F.Cu" "F.Mask" "F.Paste")
			(net "M_K_CPU0_SB_DQ<14>")
		)
		(pad "264" smd rect
			(at 2.050034 42.924984 90)
			(size 0.519938 1.4986)
			(layers "F.Cu" "F.Mask" "F.Paste")
			(net "GND")
		)
		(pad "265" smd rect
			(at 2.050034 43.775122 90)
			(size 0.519938 1.4986)
			(layers "F.Cu" "F.Mask" "F.Paste")
			(net "M_K_CPU0_SB_DQ<15>")
		)
		(pad "266" smd rect
			(at 2.050034 44.625006 90)
			(size 0.519938 1.4986)
			(layers "F.Cu" "F.Mask" "F.Paste")
			(net "GND")
		)
		(pad "267" smd rect
			(at 2.050034 45.47489 90)
			(size 0.519938 1.4986)
			(layers "F.Cu" "F.Mask" "F.Paste")
			(net "M_K_CPU0_SB_DQ<18>")
		)
		(pad "268" smd rect
			(at 2.050034 46.325028 90)
			(size 0.519938 1.4986)
			(layers "F.Cu" "F.Mask" "F.Paste")
			(net "GND")
		)
		(pad "269" smd rect
			(at 2.050034 47.174912 90)
			(size 0.519938 1.4986)
			(layers "F.Cu" "F.Mask" "F.Paste")
			(net "M_K_CPU0_SB_DQ<19>")
		)
		(pad "270" smd rect
			(at 2.050034 48.02505 90)
			(size 0.519938 1.4986)
			(layers "F.Cu" "F.Mask" "F.Paste")
			(net "GND")
		)
		(pad "271" smd rect
			(at 2.050034 48.874934 90)
			(size 0.519938 1.4986)
			(layers "F.Cu" "F.Mask" "F.Paste")
			(net "M_K_CPU0_SB_DQS_DN<7>")
		)
		(pad "272" smd rect
			(at 2.050034 49.725072 90)
			(size 0.519938 1.4986)
			(layers "F.Cu" "F.Mask" "F.Paste")
			(net "M_K_CPU0_SB_DQS_DP<7>")
		)
		(pad "273" smd rect
			(at 2.050034 50.574956 90)
			(size 0.519938 1.4986)
			(layers "F.Cu" "F.Mask" "F.Paste")
			(net "GND")
		)
		(pad "274" smd rect
			(at 2.050034 51.425094 90)
			(size 0.519938 1.4986)
			(layers "F.Cu" "F.Mask" "F.Paste")
			(net "M_K_CPU0_SB_DQ<22>")
		)
		(pad "275" smd rect
			(at 2.050034 52.274978 90)
			(size 0.519938 1.4986)
			(layers "F.Cu" "F.Mask" "F.Paste")
			(net "GND")
		)
		(pad "276" smd rect
			(at 2.050034 53.125116 90)
			(size 0.519938 1.4986)
			(layers "F.Cu" "F.Mask" "F.Paste")
			(net "M_K_CPU0_SB_DQ<23>")
		)
		(pad "277" smd rect
			(at 2.050034 53.975 90)
			(size 0.519938 1.4986)
			(layers "F.Cu" "F.Mask" "F.Paste")
			(net "GND")
		)
		(pad "278" smd rect
			(at 2.050034 54.824884 90)
			(size 0.519938 1.4986)
			(layers "F.Cu" "F.Mask" "F.Paste")
			(net "M_K_CPU0_SB_DQ<26>")
		)
		(pad "279" smd rect
			(at 2.050034 55.675022 90)
			(size 0.519938 1.4986)
			(layers "F.Cu" "F.Mask" "F.Paste")
			(net "GND")
		)
		(pad "280" smd rect
			(at 2.050034 56.524906 90)
			(size 0.519938 1.4986)
			(layers "F.Cu" "F.Mask" "F.Paste")
			(net "M_K_CPU0_SB_DQ<27>")
		)
		(pad "281" smd rect
			(at 2.050034 57.375044 90)
			(size 0.519938 1.4986)
			(layers "F.Cu" "F.Mask" "F.Paste")
			(net "GND")
		)
		(pad "282" smd rect
			(at 2.050034 58.224928 90)
			(size 0.519938 1.4986)
			(layers "F.Cu" "F.Mask" "F.Paste")
			(net "M_K_CPU0_SB_DQS_DN<8>")
		)
		(pad "283" smd rect
			(at 2.050034 59.075066 90)
			(size 0.519938 1.4986)
			(layers "F.Cu" "F.Mask" "F.Paste")
			(net "M_K_CPU0_SB_DQS_DP<8>")
		)
		(pad "284" smd rect
			(at 2.050034 59.92495 90)
			(size 0.519938 1.4986)
			(layers "F.Cu" "F.Mask" "F.Paste")
			(net "GND")
		)
		(pad "285" smd rect
			(at 2.050034 60.775088 90)
			(size 0.519938 1.4986)
			(layers "F.Cu" "F.Mask" "F.Paste")
			(net "M_K_CPU0_SB_DQ<30>")
		)
		(pad "286" smd rect
			(at 2.050034 61.624972 90)
			(size 0.519938 1.4986)
			(layers "F.Cu" "F.Mask" "F.Paste")
			(net "GND")
		)
		(pad "287" smd rect
			(at 2.050034 62.47511 90)
			(size 0.519938 1.4986)
			(layers "F.Cu" "F.Mask" "F.Paste")
			(net "M_K_CPU0_SB_DQ<31>")
		)
		(pad "288" smd rect
			(at 2.050034 63.324994 90)
			(size 0.519938 1.4986)
			(layers "F.Cu" "F.Mask" "F.Paste")
			(net "GND")
		)
		(pad "G1" thru_hole oval
			(at 0 -68.97497 90)
			(size 1.7272 3.4798)
			(drill oval 1.2192 2.4638)
			(layers "*.Cu" "*.Mask")
			(remove_unused_layers no)
			(net "GND")
			(clearance 0.127)
			(thermal_gap 0.127)
		)
		(pad "G2" thru_hole oval
			(at 0 3.875024 90)
			(size 1.7272 3.4798)
			(drill oval 1.2192 2.4638)
			(layers "*.Cu" "*.Mask")
			(remove_unused_layers no)
			(net "GND")
			(clearance 0.127)
			(thermal_gap 0.127)
		)
		(pad "G3" thru_hole oval
			(at 0 68.97497 90)
			(size 1.7272 3.4798)
			(drill oval 1.2192 2.4638)
			(layers "*.Cu" "*.Mask")
			(remove_unused_layers no)
			(net "GND")
			(clearance 0.127)
			(thermal_gap 0.127)
		)
	)
	(footprint ""
		(layer "F.Cu")
		(at 351.410778 -158.474156 -90)
		(property "Reference" "PC151"
			(at 0 0 270)
			(layer "F.SilkS")
			(hide yes)
			(effects
				(font
					(size 1.27 1.27)
				)
			)
		)
		(property "Value" ""
			(at 0 0 270)
			(layer "F.Fab")
			(effects
				(font
					(size 1.27 1.27)
				)
			)
		)
		(duplicate_pad_numbers_are_jumpers no)
		(fp_line
			(start -0.7874 0.4064)
			(end -0.7874 -0.4064)
			(stroke
				(width 0.1524)
				(type default)
			)
			(layer "F.SilkS")
		)
		(fp_line
			(start -0.174244 0.4064)
			(end -0.7874 0.4064)
			(stroke
				(width 0.1524)
				(type default)
			)
			(layer "F.SilkS")
		)
		(fp_line
			(start 0.7874 0.4064)
			(end 0.359156 0.4064)
			(stroke
				(width 0.1524)
				(type default)
			)
			(layer "F.SilkS")
		)
		(fp_line
			(start -0.7874 -0.4064)
			(end 0.7874 -0.4064)
			(stroke
				(width 0.1524)
				(type default)
			)
			(layer "F.SilkS")
		)
		(fp_line
			(start 0.7874 -0.4064)
			(end 0.7874 0.4064)
			(stroke
				(width 0.1524)
				(type default)
			)
			(layer "F.SilkS")
		)
		(fp_line
			(start -0.67945 0.3048)
			(end -0.67945 -0.305054)
			(stroke
				(width 0.1)
				(type default)
			)
			(layer "F.Fab")
		)
		(fp_line
			(start -0.12065 0.3048)
			(end -0.67945 0.3048)
			(stroke
				(width 0.1)
				(type default)
			)
			(layer "F.Fab")
		)
		(fp_line
			(start 0.120396 0.3048)
			(end 0.120396 0.2794)
			(stroke
				(width 0.1)
				(type default)
			)
			(layer "F.Fab")
		)
		(fp_line
			(start 0.67945 0.3048)
			(end 0.120396 0.3048)
			(stroke
				(width 0.1)
				(type default)
			)
			(layer "F.Fab")
		)
		(fp_line
			(start -0.12065 0.2794)
			(end -0.12065 0.3048)
			(stroke
				(width 0.1)
				(type default)
			)
			(layer "F.Fab")
		)
		(fp_line
			(start 0.120396 0.2794)
			(end -0.12065 0.2794)
			(stroke
				(width 0.1)
				(type default)
			)
			(layer "F.Fab")
		)
		(fp_line
			(start -0.12065 -0.2794)
			(end 0.12065 -0.2794)
			(stroke
				(width 0.1)
				(type default)
			)
			(layer "F.Fab")
		)
		(fp_line
			(start 0.12065 -0.2794)
			(end 0.12065 -0.3048)
			(stroke
				(width 0.1)
				(type default)
			)
			(layer "F.Fab")
		)
		(fp_line
			(start 0.12065 -0.3048)
			(end 0.67945 -0.3048)
			(stroke
				(width 0.1)
				(type default)
			)
			(layer "F.Fab")
		)
		(fp_line
			(start 0.67945 -0.3048)
			(end 0.67945 0.3048)
			(stroke
				(width 0.1)
				(type default)
			)
			(layer "F.Fab")
		)
		(fp_line
			(start -0.67945 -0.305054)
			(end -0.12065 -0.305054)
			(stroke
				(width 0.1)
				(type default)
			)
			(layer "F.Fab")
		)
		(fp_line
			(start -0.12065 -0.305054)
			(end -0.12065 -0.2794)
			(stroke
				(width 0.1)
				(type default)
			)
			(layer "F.Fab")
		)
		(pad "1" smd circle
			(at -0.40005 0 270)
			(size 0 0)
			(layers "F.Cu" "F.Mask" "F.Paste")
			(net "PVDDCR_CPU0_P0_VCC6")
		)
		(pad "2" smd circle
			(at 0.40005 0 270)
			(size 0 0)
			(layers "F.Cu" "F.Mask" "F.Paste")
			(net "GND")
		)
	)
	(footprint ""
		(layer "F.Cu")
		(at 439.072782 -433.49926 90)
		(property "Reference" "R3472"
			(at 0 0 90)
			(layer "F.SilkS")
			(hide yes)
			(effects
				(font
					(size 1.27 1.27)
				)
			)
		)
		(property "Value" ""
			(at 0 0 90)
			(layer "F.Fab")
			(effects
				(font
					(size 1.27 1.27)
				)
			)
		)
		(duplicate_pad_numbers_are_jumpers no)
		(fp_line
			(start 0.7874 -0.4064)
			(end 0.7874 0.4064)
			(stroke
				(width 0.1524)
				(type default)
			)
			(layer "F.SilkS")
		)
		(fp_line
			(start -0.7874 -0.4064)
			(end 0.7874 -0.4064)
			(stroke
				(width 0.1524)
				(type default)
			)
			(layer "F.SilkS")
		)
		(fp_line
			(start 0.7874 0.4064)
			(end -0.7874 0.4064)
			(stroke
				(width 0.1524)
				(type default)
			)
			(layer "F.SilkS")
		)
		(fp_line
			(start -0.7874 0.4064)
			(end -0.7874 -0.4064)
			(stroke
				(width 0.1524)
				(type default)
			)
			(layer "F.SilkS")
		)
		(fp_line
			(start -0.12065 -0.305054)
			(end -0.12065 -0.2794)
			(stroke
				(width 0.1)
				(type default)
			)
			(layer "F.Fab")
		)
		(fp_line
			(start -0.67945 -0.305054)
			(end -0.12065 -0.305054)
			(stroke
				(width 0.1)
				(type default)
			)
			(layer "F.Fab")
		)
		(fp_line
			(start 0.67945 -0.3048)
			(end 0.67945 0.3048)
			(stroke
				(width 0.1)
				(type default)
			)
			(layer "F.Fab")
		)
		(fp_line
			(start 0.12065 -0.3048)
			(end 0.67945 -0.3048)
			(stroke
				(width 0.1)
				(type default)
			)
			(layer "F.Fab")
		)
		(fp_line
			(start 0.12065 -0.2794)
			(end 0.12065 -0.3048)
			(stroke
				(width 0.1)
				(type default)
			)
			(layer "F.Fab")
		)
		(fp_line
			(start -0.12065 -0.2794)
			(end 0.12065 -0.2794)
			(stroke
				(width 0.1)
				(type default)
			)
			(layer "F.Fab")
		)
		(fp_line
			(start 0.120396 0.2794)
			(end -0.12065 0.2794)
			(stroke
				(width 0.1)
				(type default)
			)
			(layer "F.Fab")
		)
		(fp_line
			(start -0.12065 0.2794)
			(end -0.12065 0.3048)
			(stroke
				(width 0.1)
				(type default)
			)
			(layer "F.Fab")
		)
		(fp_line
			(start 0.67945 0.3048)
			(end 0.120396 0.3048)
			(stroke
				(width 0.1)
				(type default)
			)
			(layer "F.Fab")
		)
		(fp_line
			(start 0.120396 0.3048)
			(end 0.120396 0.2794)
			(stroke
				(width 0.1)
				(type default)
			)
			(layer "F.Fab")
		)
		(fp_line
			(start -0.12065 0.3048)
			(end -0.67945 0.3048)
			(stroke
				(width 0.1)
				(type default)
			)
			(layer "F.Fab")
		)
		(fp_line
			(start -0.67945 0.3048)
			(end -0.67945 -0.305054)
			(stroke
				(width 0.1)
				(type default)
			)
			(layer "F.Fab")
		)
		(pad "1" smd circle
			(at -0.40005 0 90)
			(size 0 0)
			(layers "F.Cu" "F.Mask" "F.Paste")
			(net "GND")
		)
		(pad "2" smd circle
			(at 0.40005 0 90)
			(size 0 0)
			(layers "F.Cu" "F.Mask" "F.Paste")
			(net "GPU_WP_HW_CTRL_ISO_N")
		)
	)
	(footprint ""
		(layer "F.Cu")
		(at 297.486324 -119.339614 180)
		(property "Reference" "R3395"
			(at 0 0 180)
			(layer "F.SilkS")
			(hide yes)
			(effects
				(font
					(size 1.27 1.27)
				)
			)
		)
		(property "Value" ""
			(at 0 0 180)
			(layer "F.Fab")
			(effects
				(font
					(size 1.27 1.27)
				)
			)
		)
		(duplicate_pad_numbers_are_jumpers no)
		(fp_line
			(start 0.7874 0.4064)
			(end -0.7874 0.4064)
			(stroke
				(width 0.1524)
				(type default)
			)
			(layer "F.SilkS")
		)
		(fp_line
			(start 0.7874 -0.4064)
			(end 0.7874 0.4064)
			(stroke
				(width 0.1524)
				(type default)
			)
			(layer "F.SilkS")
		)
		(fp_line
			(start -0.7874 0.4064)
			(end -0.7874 -0.4064)
			(stroke
				(width 0.1524)
				(type default)
			)
			(layer "F.SilkS")
		)
		(fp_line
			(start -0.7874 -0.4064)
			(end 0.7874 -0.4064)
			(stroke
				(width 0.1524)
				(type default)
			)
			(layer "F.SilkS")
		)
		(fp_line
			(start 0.67945 0.3048)
			(end 0.120396 0.3048)
			(stroke
				(width 0.1)
				(type default)
			)
			(layer "F.Fab")
		)
		(fp_line
			(start 0.67945 -0.3048)
			(end 0.67945 0.3048)
			(stroke
				(width 0.1)
				(type default)
			)
			(layer "F.Fab")
		)
		(fp_line
			(start 0.12065 -0.2794)
			(end 0.12065 -0.3048)
			(stroke
				(width 0.1)
				(type default)
			)
			(layer "F.Fab")
		)
		(fp_line
			(start 0.12065 -0.3048)
			(end 0.67945 -0.3048)
			(stroke
				(width 0.1)
				(type default)
			)
			(layer "F.Fab")
		)
		(fp_line
			(start 0.120396 0.3048)
			(end 0.120396 0.2794)
			(stroke
				(width 0.1)
				(type default)
			)
			(layer "F.Fab")
		)
		(fp_line
			(start 0.120396 0.2794)
			(end -0.12065 0.2794)
			(stroke
				(width 0.1)
				(type default)
			)
			(layer "F.Fab")
		)
		(fp_line
			(start -0.12065 0.3048)
			(end -0.67945 0.3048)
			(stroke
				(width 0.1)
				(type default)
			)
			(layer "F.Fab")
		)
		(fp_line
			(start -0.12065 0.2794)
			(end -0.12065 0.3048)
			(stroke
				(width 0.1)
				(type default)
			)
			(layer "F.Fab")
		)
		(fp_line
			(start -0.12065 -0.2794)
			(end 0.12065 -0.2794)
			(stroke
				(width 0.1)
				(type default)
			)
			(layer "F.Fab")
		)
		(fp_line
			(start -0.12065 -0.305054)
			(end -0.12065 -0.2794)
			(stroke
				(width 0.1)
				(type default)
			)
			(layer "F.Fab")
		)
		(fp_line
			(start -0.67945 0.3048)
			(end -0.67945 -0.305054)
			(stroke
				(width 0.1)
				(type default)
			)
			(layer "F.Fab")
		)
		(fp_line
			(start -0.67945 -0.305054)
			(end -0.12065 -0.305054)
			(stroke
				(width 0.1)
				(type default)
			)
			(layer "F.Fab")
		)
		(pad "1" smd circle
			(at -0.40005 0 180)
			(size 0 0)
			(layers "F.Cu" "F.Mask" "F.Paste")
			(net "P3V3_AUX")
		)
		(pad "2" smd circle
			(at 0.40005 0 180)
			(size 0 0)
			(layers "F.Cu" "F.Mask" "F.Paste")
			(net "SMB_INA230_3V3AUX_SCL")
		)
	)
	(footprint ""
		(layer "F.Cu")
		(at 257.84048 -51.587146)
		(property "Reference" "PR3944"
			(at 0 0 0)
			(layer "F.SilkS")
			(hide yes)
			(effects
				(font
					(size 1.27 1.27)
				)
			)
		)
		(property "Value" ""
			(at 0 0 0)
			(layer "F.Fab")
			(effects
				(font
					(size 1.27 1.27)
				)
			)
		)
		(duplicate_pad_numbers_are_jumpers no)
		(fp_line
			(start -0.7874 -0.4064)
			(end 0.7874 -0.4064)
			(stroke
				(width 0.1524)
				(type default)
			)
			(layer "F.SilkS")
		)
		(fp_line
			(start -0.7874 0.4064)
			(end -0.7874 -0.4064)
			(stroke
				(width 0.1524)
				(type default)
			)
			(layer "F.SilkS")
		)
		(fp_line
			(start 0.7874 -0.4064)
			(end 0.7874 0.4064)
			(stroke
				(width 0.1524)
				(type default)
			)
			(layer "F.SilkS")
		)
		(fp_line
			(start 0.7874 0.4064)
			(end -0.7874 0.4064)
			(stroke
				(width 0.1524)
				(type default)
			)
			(layer "F.SilkS")
		)
		(fp_line
			(start -0.67945 -0.305054)
			(end -0.12065 -0.305054)
			(stroke
				(width 0.1)
				(type default)
			)
			(layer "F.Fab")
		)
		(fp_line
			(start -0.67945 0.3048)
			(end -0.67945 -0.305054)
			(stroke
				(width 0.1)
				(type default)
			)
			(layer "F.Fab")
		)
		(fp_line
			(start -0.12065 -0.305054)
			(end -0.12065 -0.2794)
			(stroke
				(width 0.1)
				(type default)
			)
			(layer "F.Fab")
		)
		(fp_line
			(start -0.12065 -0.2794)
			(end 0.12065 -0.2794)
			(stroke
				(width 0.1)
				(type default)
			)
			(layer "F.Fab")
		)
		(fp_line
			(start -0.12065 0.2794)
			(end -0.12065 0.3048)
			(stroke
				(width 0.1)
				(type default)
			)
			(layer "F.Fab")
		)
		(fp_line
			(start -0.12065 0.3048)
			(end -0.67945 0.3048)
			(stroke
				(width 0.1)
				(type default)
			)
			(layer "F.Fab")
		)
		(fp_line
			(start 0.120396 0.2794)
			(end -0.12065 0.2794)
			(stroke
				(width 0.1)
				(type default)
			)
			(layer "F.Fab")
		)
		(fp_line
			(start 0.120396 0.3048)
			(end 0.120396 0.2794)
			(stroke
				(width 0.1)
				(type default)
			)
			(layer "F.Fab")
		)
		(fp_line
			(start 0.12065 -0.3048)
			(end 0.67945 -0.3048)
			(stroke
				(width 0.1)
				(type default)
			)
			(layer "F.Fab")
		)
		(fp_line
			(start 0.12065 -0.2794)
			(end 0.12065 -0.3048)
			(stroke
				(width 0.1)
				(type default)
			)
			(layer "F.Fab")
		)
		(fp_line
			(start 0.67945 -0.3048)
			(end 0.67945 0.3048)
			(stroke
				(width 0.1)
				(type default)
			)
			(layer "F.Fab")
		)
		(fp_line
			(start 0.67945 0.3048)
			(end 0.120396 0.3048)
			(stroke
				(width 0.1)
				(type default)
			)
			(layer "F.Fab")
		)
		(pad "1" smd circle
			(at -0.40005 0)
			(size 0 0)
			(layers "F.Cu" "F.Mask" "F.Paste")
			(net "P12V_E1S_ISET_0")
		)
		(pad "2" smd circle
			(at 0.40005 0)
			(size 0 0)
			(layers "F.Cu" "F.Mask" "F.Paste")
			(net "GND")
		)
	)
	(footprint ""
		(layer "F.Cu")
		(at 285.881064 -418.323014)
		(property "Reference" "U314"
			(at -0.34671 3.762248 0)
			(unlocked yes)
			(layer "F.SilkS")
			(effects
				(font
					(size 0.7874 0.5842)
					(thickness 0.1524)
				)
			)
		)
		(property "Value" ""
			(at 0 0 0)
			(layer "F.Fab")
			(effects
				(font
					(size 1.27 1.27)
				)
			)
		)
		(duplicate_pad_numbers_are_jumpers no)
		(fp_line
			(start -2.500122 -2.500122)
			(end -2.500122 -2.01676)
			(stroke
				(width 0.1524)
				(type default)
			)
			(layer "F.SilkS")
		)
		(fp_line
			(start -2.500122 2.01676)
			(end -2.500122 2.500122)
			(stroke
				(width 0.1524)
				(type default)
			)
			(layer "F.SilkS")
		)
		(fp_line
			(start -2.500122 2.500122)
			(end -2.01676 2.500122)
			(stroke
				(width 0.1524)
				(type default)
			)
			(layer "F.SilkS")
		)
		(fp_line
			(start -2.01676 -2.500122)
			(end -2.500122 -2.500122)
			(stroke
				(width 0.1524)
				(type default)
			)
			(layer "F.SilkS")
		)
		(fp_line
			(start 2.01676 2.500122)
			(end 2.500122 2.500122)
			(stroke
				(width 0.1524)
				(type default)
			)
			(layer "F.SilkS")
		)
		(fp_line
			(start 2.500122 -2.500122)
			(end 2.01676 -2.500122)
			(stroke
				(width 0.1524)
				(type default)
			)
			(layer "F.SilkS")
		)
		(fp_line
			(start 2.500122 -2.01676)
			(end 2.500122 -2.500122)
			(stroke
				(width 0.1524)
				(type default)
			)
			(layer "F.SilkS")
		)
		(fp_line
			(start 2.500122 2.500122)
			(end 2.500122 2.01676)
			(stroke
				(width 0.1524)
				(type default)
			)
			(layer "F.SilkS")
		)
		(fp_poly
			(pts
				(xy -4.299458 -1.75006) (xy -5.494782 -1.152398) (xy -5.494782 -2.347722)
			)
			(stroke
				(width 0)
				(type default)
			)
			(fill yes)
			(layer "F.SilkS")
		)
		(fp_line
			(start -2.500122 -2.500122)
			(end -2.500122 2.500122)
			(stroke
				(width 0.1)
				(type default)
			)
			(layer "F.Fab")
		)
		(fp_line
			(start -2.500122 2.500122)
			(end 2.500122 2.500122)
			(stroke
				(width 0.1)
				(type default)
			)
			(layer "F.Fab")
		)
		(fp_line
			(start 2.500122 -2.500122)
			(end -2.500122 -2.500122)
			(stroke
				(width 0.1)
				(type default)
			)
			(layer "F.Fab")
		)
		(fp_line
			(start 2.500122 2.500122)
			(end 2.500122 -2.500122)
			(stroke
				(width 0.1)
				(type default)
			)
			(layer "F.Fab")
		)
		(fp_poly
			(pts
				(xy -3.044698 -1.75006) (xy -4.240022 -1.152398) (xy -4.240022 -2.347722)
			)
			(stroke
				(width 0)
				(type default)
			)
			(fill yes)
			(layer "F.Fab")
		)
		(pad "1" smd rect
			(at -2.3749 -1.75006 270)
			(size 0.254 0.5588)
			(layers "F.Cu" "F.Mask" "F.Paste")
			(net "FM_9ZXL045_P0_DEV_EN")
		)
		(pad "2" smd rect
			(at -2.3749 -1.249934 270)
			(size 0.254 0.5588)
			(layers "F.Cu" "F.Mask" "F.Paste")
			(net "P3V3_9ZXL045_P0_VDDR")
		)
		(pad "3" smd rect
			(at -2.3749 -0.750062 270)
			(size 0.254 0.5588)
			(layers "F.Cu" "F.Mask" "F.Paste")
			(net "CLK_100M_CPU0_CLK13_DP")
		)
		(pad "4" smd rect
			(at -2.3749 -0.249936 270)
			(size 0.254 0.5588)
			(layers "F.Cu" "F.Mask" "F.Paste")
			(net "CLK_100M_CPU0_CLK13_DN")
		)
		(pad "5" smd rect
			(at -2.3749 0.249936 270)
			(size 0.254 0.5588)
			(layers "F.Cu" "F.Mask" "F.Paste")
			(net "CLK_9ZXL045_P0_SADR0")
		)
		(pad "6" smd rect
			(at -2.3749 0.750062 270)
			(size 0.254 0.5588)
			(layers "F.Cu" "F.Mask" "F.Paste")
			(net "SMB_9ZXL045_P0_SDA")
		)
		(pad "7" smd rect
			(at -2.3749 1.249934 270)
			(size 0.254 0.5588)
			(layers "F.Cu" "F.Mask" "F.Paste")
			(net "SMB_9ZXL045_P0_SCL")
		)
		(pad "8" smd rect
			(at -2.3749 1.75006 270)
			(size 0.254 0.5588)
			(layers "F.Cu" "F.Mask" "F.Paste")
			(net "NC_U314_FBOUT_N")
		)
		(pad "9" smd rect
			(at -1.75006 2.3749)
			(size 0.254 0.5588)
			(layers "F.Cu" "F.Mask" "F.Paste")
			(net "NC_U314_FBOUT")
		)
		(pad "10" smd rect
			(at -1.249934 2.3749)
			(size 0.254 0.5588)
			(layers "F.Cu" "F.Mask" "F.Paste")
			(net "NC_U314_NC0")
		)
		(pad "11" smd rect
			(at -0.750062 2.3749)
			(size 0.254 0.5588)
			(layers "F.Cu" "F.Mask" "F.Paste")
			(net "NC_U314_NC1")
		)
		(pad "12" smd rect
			(at -0.249936 2.3749)
			(size 0.254 0.5588)
			(layers "F.Cu" "F.Mask" "F.Paste")
			(net "P3V3_9ZXL045_P0_VDD")
		)
		(pad "13" smd rect
			(at 0.249936 2.3749)
			(size 0.254 0.5588)
			(layers "F.Cu" "F.Mask" "F.Paste")
			(net "CLK_100M_RETIMER_CPU0_P0_R_DP")
		)
		(pad "14" smd rect
			(at 0.750062 2.3749)
			(size 0.254 0.5588)
			(layers "F.Cu" "F.Mask" "F.Paste")
			(net "CLK_100M_RETIMER_CPU0_P0_R_DN")
		)
		(pad "15" smd rect
			(at 1.249934 2.3749)
			(size 0.254 0.5588)
			(layers "F.Cu" "F.Mask" "F.Paste")
			(net "FM_9ZXL045_P0_0_OE_N")
		)
		(pad "16" smd rect
			(at 1.75006 2.3749)
			(size 0.254 0.5588)
			(layers "F.Cu" "F.Mask" "F.Paste")
			(net "P3V3_9ZXL045_P0_VDD")
		)
		(pad "17" smd rect
			(at 2.3749 1.75006 90)
			(size 0.254 0.5588)
			(layers "F.Cu" "F.Mask" "F.Paste")
			(net "NC_U314_NC2")
		)
		(pad "18" smd rect
			(at 2.3749 1.249934 90)
			(size 0.254 0.5588)
			(layers "F.Cu" "F.Mask" "F.Paste")
			(net "FM_9ZXL045_P0_1_OE_N")
		)
		(pad "19" smd rect
			(at 2.3749 0.750062 90)
			(size 0.254 0.5588)
			(layers "F.Cu" "F.Mask" "F.Paste")
			(net "CLK_100M_RETIMER_CPU0_P1_R_DP")
		)
		(pad "20" smd rect
			(at 2.3749 0.249936 90)
			(size 0.254 0.5588)
			(layers "F.Cu" "F.Mask" "F.Paste")
			(net "CLK_100M_RETIMER_CPU0_P1_R_DN")
		)
		(pad "21" smd rect
			(at 2.3749 -0.249936 90)
			(size 0.254 0.5588)
			(layers "F.Cu" "F.Mask" "F.Paste")
			(net "P3V3_9ZXL045_P0_VDD")
		)
		(pad "22" smd rect
			(at 2.3749 -0.750062 90)
			(size 0.254 0.5588)
			(layers "F.Cu" "F.Mask" "F.Paste")
			(net "CLK_100M_RETIMER_CPU0_P2_R_DP")
		)
		(pad "23" smd rect
			(at 2.3749 -1.249934 90)
			(size 0.254 0.5588)
			(layers "F.Cu" "F.Mask" "F.Paste")
			(net "CLK_100M_RETIMER_CPU0_P2_R_DN")
		)
		(pad "24" smd rect
			(at 2.3749 -1.75006 90)
			(size 0.254 0.5588)
			(layers "F.Cu" "F.Mask" "F.Paste")
			(net "FM_9ZXL045_P0_2_OE_N")
		)
		(pad "25" smd rect
			(at 1.75006 -2.3749 180)
			(size 0.254 0.5588)
			(layers "F.Cu" "F.Mask" "F.Paste")
			(net "P3V3_9ZXL045_P0_VDD")
		)
		(pad "26" smd rect
			(at 1.249934 -2.3749 180)
			(size 0.254 0.5588)
			(layers "F.Cu" "F.Mask" "F.Paste")
			(net "FM_9ZXL045_P0_3_OE_N")
		)
		(pad "27" smd rect
			(at 0.750062 -2.3749 180)
			(size 0.254 0.5588)
			(layers "F.Cu" "F.Mask" "F.Paste")
			(net "CLK_100M_RETIMER_CPU0_P3_R_DP")
		)
		(pad "28" smd rect
			(at 0.249936 -2.3749 180)
			(size 0.254 0.5588)
			(layers "F.Cu" "F.Mask" "F.Paste")
			(net "CLK_100M_RETIMER_CPU0_P3_R_DN")
		)
		(pad "29" smd rect
			(at -0.249936 -2.3749 180)
			(size 0.254 0.5588)
			(layers "F.Cu" "F.Mask" "F.Paste")
			(net "P3V3_9ZXL045_P0_VDD")
		)
		(pad "30" smd rect
			(at -0.750062 -2.3749 180)
			(size 0.254 0.5588)
			(layers "F.Cu" "F.Mask" "F.Paste")
			(net "NC_U314_NC3")
		)
		(pad "31" smd rect
			(at -1.249934 -2.3749 180)
			(size 0.254 0.5588)
			(layers "F.Cu" "F.Mask" "F.Paste")
			(net "P3V3_9ZXL045_P0_VDDA")
		)
		(pad "32" smd rect
			(at -1.75006 -2.3749 180)
			(size 0.254 0.5588)
			(layers "F.Cu" "F.Mask" "F.Paste")
			(net "CLK_9ZXL045_P0_HIBW")
		)
		(pad "33" smd rect
			(at 0 0)
			(size 3.1496 3.1496)
			(layers "F.Cu" "F.Mask" "F.Paste")
			(net "GND")
		)
		(zone
			(layer "F.Cu")
			(hatch none 0.5)
			(connect_pads
				(clearance 0)
			)
			(min_thickness 0.25)
			(keepout
				(tracks not_allowed)
				(vias allowed)
				(pads allowed)
				(copperpour not_allowed)
				(footprints allowed)
			)
			(placement
				(enabled no)
				(sheetname "")
			)
			(fill
				(thermal_gap 0.5)
				(thermal_bridge_width 0.5)
				(island_removal_mode 0)
			)
			(polygon
				(pts
					(xy 283.836364 -416.278314) (xy 283.836364 -419.547548) (xy 284.255464 -419.547548) (xy 284.255464 -416.697414)
					(xy 287.506664 -416.697414) (xy 287.506664 -419.948614) (xy 284.255464 -419.948614) (xy 284.255464 -419.572948)
					(xy 283.836364 -419.572948) (xy 283.836364 -420.367714) (xy 287.925764 -420.367714) (xy 287.925764 -416.278314)
				)
			)
		)
	)
	(footprint ""
		(layer "F.Cu")
		(at 372.937278 -141.472158)
		(property "Reference" "R8317"
			(at 0 0 0)
			(layer "F.SilkS")
			(hide yes)
			(effects
				(font
					(size 1.27 1.27)
				)
			)
		)
		(property "Value" ""
			(at 0 0 0)
			(layer "F.Fab")
			(effects
				(font
					(size 1.27 1.27)
				)
			)
		)
		(duplicate_pad_numbers_are_jumpers no)
		(fp_line
			(start -0.7874 -0.4064)
			(end 0.7874 -0.4064)
			(stroke
				(width 0.1524)
				(type default)
			)
			(layer "F.SilkS")
		)
		(fp_line
			(start -0.7874 0.4064)
			(end -0.7874 -0.4064)
			(stroke
				(width 0.1524)
				(type default)
			)
			(layer "F.SilkS")
		)
		(fp_line
			(start 0.7874 -0.4064)
			(end 0.7874 0.4064)
			(stroke
				(width 0.1524)
				(type default)
			)
			(layer "F.SilkS")
		)
		(fp_line
			(start 0.7874 0.4064)
			(end -0.7874 0.4064)
			(stroke
				(width 0.1524)
				(type default)
			)
			(layer "F.SilkS")
		)
		(fp_line
			(start -0.67945 -0.305054)
			(end -0.12065 -0.305054)
			(stroke
				(width 0.1)
				(type default)
			)
			(layer "F.Fab")
		)
		(fp_line
			(start -0.67945 0.3048)
			(end -0.67945 -0.305054)
			(stroke
				(width 0.1)
				(type default)
			)
			(layer "F.Fab")
		)
		(fp_line
			(start -0.12065 -0.305054)
			(end -0.12065 -0.2794)
			(stroke
				(width 0.1)
				(type default)
			)
			(layer "F.Fab")
		)
		(fp_line
			(start -0.12065 -0.2794)
			(end 0.12065 -0.2794)
			(stroke
				(width 0.1)
				(type default)
			)
			(layer "F.Fab")
		)
		(fp_line
			(start -0.12065 0.2794)
			(end -0.12065 0.3048)
			(stroke
				(width 0.1)
				(type default)
			)
			(layer "F.Fab")
		)
		(fp_line
			(start -0.12065 0.3048)
			(end -0.67945 0.3048)
			(stroke
				(width 0.1)
				(type default)
			)
			(layer "F.Fab")
		)
		(fp_line
			(start 0.120396 0.2794)
			(end -0.12065 0.2794)
			(stroke
				(width 0.1)
				(type default)
			)
			(layer "F.Fab")
		)
		(fp_line
			(start 0.120396 0.3048)
			(end 0.120396 0.2794)
			(stroke
				(width 0.1)
				(type default)
			)
			(layer "F.Fab")
		)
		(fp_line
			(start 0.12065 -0.3048)
			(end 0.67945 -0.3048)
			(stroke
				(width 0.1)
				(type default)
			)
			(layer "F.Fab")
		)
		(fp_line
			(start 0.12065 -0.2794)
			(end 0.12065 -0.3048)
			(stroke
				(width 0.1)
				(type default)
			)
			(layer "F.Fab")
		)
		(fp_line
			(start 0.67945 -0.3048)
			(end 0.67945 0.3048)
			(stroke
				(width 0.1)
				(type default)
			)
			(layer "F.Fab")
		)
		(fp_line
			(start 0.67945 0.3048)
			(end 0.120396 0.3048)
			(stroke
				(width 0.1)
				(type default)
			)
			(layer "F.Fab")
		)
		(pad "1" smd circle
			(at -0.40005 0)
			(size 0 0)
			(layers "F.Cu" "F.Mask" "F.Paste")
			(net "PVDD18_S5_P0")
		)
		(pad "2" smd circle
			(at 0.40005 0)
			(size 0 0)
			(layers "F.Cu" "F.Mask" "F.Paste")
			(net "PVDDCR_CPU0_P0_RESET_N_R")
		)
	)
	(footprint ""
		(layer "F.Cu")
		(at 336.844894 -339.625432 -90)
		(property "Reference" "PC92"
			(at 0 0 270)
			(layer "F.SilkS")
			(hide yes)
			(effects
				(font
					(size 1.27 1.27)
				)
			)
		)
		(property "Value" ""
			(at 0 0 270)
			(layer "F.Fab")
			(effects
				(font
					(size 1.27 1.27)
				)
			)
		)
		(duplicate_pad_numbers_are_jumpers no)
		(fp_line
			(start -0.7874 0.4064)
			(end -0.7874 -0.4064)
			(stroke
				(width 0.1524)
				(type default)
			)
			(layer "F.SilkS")
		)
		(fp_line
			(start 0.7874 0.4064)
			(end -0.7874 0.4064)
			(stroke
				(width 0.1524)
				(type default)
			)
			(layer "F.SilkS")
		)
		(fp_line
			(start -0.7874 -0.4064)
			(end 0.7874 -0.4064)
			(stroke
				(width 0.1524)
				(type default)
			)
			(layer "F.SilkS")
		)
		(fp_line
			(start 0.7874 -0.4064)
			(end 0.7874 0.4064)
			(stroke
				(width 0.1524)
				(type default)
			)
			(layer "F.SilkS")
		)
		(fp_line
			(start -0.67945 0.3048)
			(end -0.67945 -0.305054)
			(stroke
				(width 0.1)
				(type default)
			)
			(layer "F.Fab")
		)
		(fp_line
			(start -0.12065 0.3048)
			(end -0.67945 0.3048)
			(stroke
				(width 0.1)
				(type default)
			)
			(layer "F.Fab")
		)
		(fp_line
			(start 0.120396 0.3048)
			(end 0.120396 0.2794)
			(stroke
				(width 0.1)
				(type default)
			)
			(layer "F.Fab")
		)
		(fp_line
			(start 0.67945 0.3048)
			(end 0.120396 0.3048)
			(stroke
				(width 0.1)
				(type default)
			)
			(layer "F.Fab")
		)
		(fp_line
			(start -0.12065 0.2794)
			(end -0.12065 0.3048)
			(stroke
				(width 0.1)
				(type default)
			)
			(layer "F.Fab")
		)
		(fp_line
			(start 0.120396 0.2794)
			(end -0.12065 0.2794)
			(stroke
				(width 0.1)
				(type default)
			)
			(layer "F.Fab")
		)
		(fp_line
			(start -0.12065 -0.2794)
			(end 0.12065 -0.2794)
			(stroke
				(width 0.1)
				(type default)
			)
			(layer "F.Fab")
		)
		(fp_line
			(start 0.12065 -0.2794)
			(end 0.12065 -0.3048)
			(stroke
				(width 0.1)
				(type default)
			)
			(layer "F.Fab")
		)
		(fp_line
			(start 0.12065 -0.3048)
			(end 0.67945 -0.3048)
			(stroke
				(width 0.1)
				(type default)
			)
			(layer "F.Fab")
		)
		(fp_line
			(start 0.67945 -0.3048)
			(end 0.67945 0.3048)
			(stroke
				(width 0.1)
				(type default)
			)
			(layer "F.Fab")
		)
		(fp_line
			(start -0.67945 -0.305054)
			(end -0.12065 -0.305054)
			(stroke
				(width 0.1)
				(type default)
			)
			(layer "F.Fab")
		)
		(fp_line
			(start -0.12065 -0.305054)
			(end -0.12065 -0.2794)
			(stroke
				(width 0.1)
				(type default)
			)
			(layer "F.Fab")
		)
		(pad "1" smd circle
			(at -0.40005 0 270)
			(size 0 0)
			(layers "F.Cu" "F.Mask" "F.Paste")
			(net "SW_PVDDCR_CPU1_P0_BOOT1_R")
		)
		(pad "2" smd circle
			(at 0.40005 0 270)
			(size 0 0)
			(layers "F.Cu" "F.Mask" "F.Paste")
			(net "SW_PVDDCR_CPU1_P0_BOOTR1")
		)
	)
	(footprint ""
		(layer "F.Cu")
		(at 39.15029 -425.256706)
		(property "Reference" "C1869"
			(at 0 0 0)
			(layer "F.SilkS")
			(hide yes)
			(effects
				(font
					(size 1.27 1.27)
				)
			)
		)
		(property "Value" ""
			(at 0 0 0)
			(layer "F.Fab")
			(effects
				(font
					(size 1.27 1.27)
				)
			)
		)
		(duplicate_pad_numbers_are_jumpers no)
		(fp_line
			(start -0.7874 -0.4064)
			(end -0.33909 -0.4064)
			(stroke
				(width 0.1524)
				(type default)
			)
			(layer "F.SilkS")
		)
		(fp_line
			(start 0.7874 -0.294894)
			(end 0.7874 0.4064)
			(stroke
				(width 0.1524)
				(type default)
			)
			(layer "F.SilkS")
		)
		(fp_line
			(start 0.7874 0.4064)
			(end -0.7874 0.4064)
			(stroke
				(width 0.1524)
				(type default)
			)
			(layer "F.SilkS")
		)
		(fp_line
			(start -0.6858 -0.3048)
			(end -0.1016 -0.3048)
			(stroke
				(width 0.1)
				(type default)
			)
			(layer "F.Fab")
		)
		(fp_line
			(start -0.6858 0.3048)
			(end -0.6858 -0.3048)
			(stroke
				(width 0.1)
				(type default)
			)
			(layer "F.Fab")
		)
		(fp_line
			(start -0.1016 -0.3048)
			(end -0.1016 -0.2794)
			(stroke
				(width 0.1)
				(type default)
			)
			(layer "F.Fab")
		)
		(fp_line
			(start -0.1016 -0.2794)
			(end 0.1016 -0.2794)
			(stroke
				(width 0.1)
				(type default)
			)
			(layer "F.Fab")
		)
		(fp_line
			(start -0.1016 0.2794)
			(end -0.1016 0.3048)
			(stroke
				(width 0.1)
				(type default)
			)
			(layer "F.Fab")
		)
		(fp_line
			(start -0.1016 0.3048)
			(end -0.6858 0.3048)
			(stroke
				(width 0.1)
				(type default)
			)
			(layer "F.Fab")
		)
		(fp_line
			(start 0.1016 -0.3048)
			(end 0.6858 -0.3048)
			(stroke
				(width 0.1)
				(type default)
			)
			(layer "F.Fab")
		)
		(fp_line
			(start 0.1016 -0.2794)
			(end 0.1016 -0.3048)
			(stroke
				(width 0.1)
				(type default)
			)
			(layer "F.Fab")
		)
		(fp_line
			(start 0.1016 0.2794)
			(end -0.1016 0.2794)
			(stroke
				(width 0.1)
				(type default)
			)
			(layer "F.Fab")
		)
		(fp_line
			(start 0.1016 0.3048)
			(end 0.1016 0.2794)
			(stroke
				(width 0.1)
				(type default)
			)
			(layer "F.Fab")
		)
		(fp_line
			(start 0.6858 -0.3048)
			(end 0.6858 0.3048)
			(stroke
				(width 0.1)
				(type default)
			)
			(layer "F.Fab")
		)
		(fp_line
			(start 0.6858 0.3048)
			(end 0.1016 0.3048)
			(stroke
				(width 0.1)
				(type default)
			)
			(layer "F.Fab")
		)
		(pad "1" smd rect
			(at -0.40005 0 180)
			(size 0.4572 0.508)
			(layers "F.Cu" "F.Mask" "F.Paste")
			(net "P2E_MB_BMC_RX_BUF_C_DN<0>")
		)
		(pad "2" smd rect
			(at 0.40005 0 180)
			(size 0.4572 0.508)
			(layers "F.Cu" "F.Mask" "F.Paste")
			(net "P2E_MB_BMC_RX_BUF_DN<0>")
		)
	)
	(footprint ""
		(layer "F.Cu")
		(at 430.827434 -98.175064 180)
		(property "Reference" "R3645"
			(at 2.202434 2.636266 0)
			(unlocked yes)
			(layer "F.SilkS")
			(effects
				(font
					(size 0.7874 0.5842)
					(thickness 0.1524)
				)
				(justify left)
			)
		)
		(property "Value" ""
			(at 0 0 180)
			(layer "F.Fab")
			(effects
				(font
					(size 1.27 1.27)
				)
			)
		)
		(duplicate_pad_numbers_are_jumpers no)
		(fp_line
			(start 3.937508 1.8796)
			(end 3.937508 -1.8796)
			(stroke
				(width 0.1524)
				(type default)
			)
			(layer "F.SilkS")
		)
		(fp_line
			(start 3.937508 -1.8796)
			(end -3.937508 -1.8796)
			(stroke
				(width 0.1524)
				(type default)
			)
			(layer "F.SilkS")
		)
		(fp_line
			(start -3.937508 1.8796)
			(end 3.937508 1.8796)
			(stroke
				(width 0.1524)
				(type default)
			)
			(layer "F.SilkS")
		)
		(fp_line
			(start -3.937508 -1.8796)
			(end -3.937508 1.8796)
			(stroke
				(width 0.1524)
				(type default)
			)
			(layer "F.SilkS")
		)
		(fp_line
			(start 3.275076 1.674876)
			(end 3.275076 -1.674876)
			(stroke
				(width 0.1)
				(type default)
			)
			(layer "F.Fab")
		)
		(fp_line
			(start 3.275076 -1.674876)
			(end -3.275076 -1.674876)
			(stroke
				(width 0.1)
				(type default)
			)
			(layer "F.Fab")
		)
		(fp_line
			(start -3.275076 1.674876)
			(end 3.275076 1.674876)
			(stroke
				(width 0.1)
				(type default)
			)
			(layer "F.Fab")
		)
		(fp_line
			(start -3.275076 -1.674876)
			(end -3.275076 1.674876)
			(stroke
				(width 0.1)
				(type default)
			)
			(layer "F.Fab")
		)
		(pad "1" smd rect
			(at -2.350008 0 180)
			(size 2.921 3.5052)
			(layers "F.Cu" "F.Mask" "F.Paste")
			(net "P3V3_OCP_SFF")
		)
		(pad "2" smd rect
			(at 2.350008 0 180)
			(size 2.921 3.5052)
			(layers "F.Cu" "F.Mask" "F.Paste")
			(net "P3V3_OCP_SFF_R")
		)
	)
	(footprint ""
		(layer "F.Cu")
		(at 412.743904 -159.116014 90)
		(property "Reference" "PC612"
			(at 0 0 90)
			(layer "F.SilkS")
			(hide yes)
			(effects
				(font
					(size 1.27 1.27)
				)
			)
		)
		(property "Value" ""
			(at 0 0 90)
			(layer "F.Fab")
			(effects
				(font
					(size 1.27 1.27)
				)
			)
		)
		(duplicate_pad_numbers_are_jumpers no)
		(fp_line
			(start 0.7874 -0.4064)
			(end 0.7874 0.4064)
			(stroke
				(width 0.1524)
				(type default)
			)
			(layer "F.SilkS")
		)
		(fp_line
			(start -0.7874 -0.4064)
			(end 0.7874 -0.4064)
			(stroke
				(width 0.1524)
				(type default)
			)
			(layer "F.SilkS")
		)
		(fp_line
			(start 0.7874 0.4064)
			(end -0.7874 0.4064)
			(stroke
				(width 0.1524)
				(type default)
			)
			(layer "F.SilkS")
		)
		(fp_line
			(start -0.7874 0.4064)
			(end -0.7874 -0.4064)
			(stroke
				(width 0.1524)
				(type default)
			)
			(layer "F.SilkS")
		)
		(fp_line
			(start -0.12065 -0.305054)
			(end -0.12065 -0.2794)
			(stroke
				(width 0.1)
				(type default)
			)
			(layer "F.Fab")
		)
		(fp_line
			(start -0.67945 -0.305054)
			(end -0.12065 -0.305054)
			(stroke
				(width 0.1)
				(type default)
			)
			(layer "F.Fab")
		)
		(fp_line
			(start 0.67945 -0.3048)
			(end 0.67945 0.3048)
			(stroke
				(width 0.1)
				(type default)
			)
			(layer "F.Fab")
		)
		(fp_line
			(start 0.12065 -0.3048)
			(end 0.67945 -0.3048)
			(stroke
				(width 0.1)
				(type default)
			)
			(layer "F.Fab")
		)
		(fp_line
			(start 0.12065 -0.2794)
			(end 0.12065 -0.3048)
			(stroke
				(width 0.1)
				(type default)
			)
			(layer "F.Fab")
		)
		(fp_line
			(start -0.12065 -0.2794)
			(end 0.12065 -0.2794)
			(stroke
				(width 0.1)
				(type default)
			)
			(layer "F.Fab")
		)
		(fp_line
			(start 0.120396 0.2794)
			(end -0.12065 0.2794)
			(stroke
				(width 0.1)
				(type default)
			)
			(layer "F.Fab")
		)
		(fp_line
			(start -0.12065 0.2794)
			(end -0.12065 0.3048)
			(stroke
				(width 0.1)
				(type default)
			)
			(layer "F.Fab")
		)
		(fp_line
			(start 0.67945 0.3048)
			(end 0.120396 0.3048)
			(stroke
				(width 0.1)
				(type default)
			)
			(layer "F.Fab")
		)
		(fp_line
			(start 0.120396 0.3048)
			(end 0.120396 0.2794)
			(stroke
				(width 0.1)
				(type default)
			)
			(layer "F.Fab")
		)
		(fp_line
			(start -0.12065 0.3048)
			(end -0.67945 0.3048)
			(stroke
				(width 0.1)
				(type default)
			)
			(layer "F.Fab")
		)
		(fp_line
			(start -0.67945 0.3048)
			(end -0.67945 -0.305054)
			(stroke
				(width 0.1)
				(type default)
			)
			(layer "F.Fab")
		)
		(pad "1" smd circle
			(at -0.40005 0 90)
			(size 0 0)
			(layers "F.Cu" "F.Mask" "F.Paste")
			(net "SW_PVDDCR_SOC_P0_BOOT3_RC")
		)
		(pad "2" smd circle
			(at 0.40005 0 90)
			(size 0 0)
			(layers "F.Cu" "F.Mask" "F.Paste")
			(net "SW_PVDDCR_SOC_P0_PH3")
		)
	)
	(footprint ""
		(layer "F.Cu")
		(at 75.65009 -440.489848)
		(property "Reference" "J111"
			(at 14.3637 23.187152 0)
			(unlocked yes)
			(layer "F.SilkS")
			(effects
				(font
					(size 0.7874 0.5842)
					(thickness 0.1524)
				)
				(justify left)
			)
		)
		(property "Value" ""
			(at 0 0 0)
			(layer "F.Fab")
			(effects
				(font
					(size 1.27 1.27)
				)
			)
		)
		(duplicate_pad_numbers_are_jumpers no)
		(fp_line
			(start -1.249934 -1.500124)
			(end 15.649956 -1.500124)
			(stroke
				(width 0.1524)
				(type default)
			)
			(layer "F.SilkS")
		)
		(fp_line
			(start -1.249934 18.595848)
			(end -1.249934 19.400012)
			(stroke
				(width 0.1524)
				(type default)
			)
			(layer "F.SilkS")
		)
		(fp_line
			(start -1.249934 19.400012)
			(end 15.649956 19.400012)
			(stroke
				(width 0.1524)
				(type default)
			)
			(layer "F.SilkS")
		)
		(fp_line
			(start 0.0254 -0.9144)
			(end 1.0414 -0.9144)
			(stroke
				(width 0.1524)
				(type default)
			)
			(layer "F.SilkS")
		)
		(fp_line
			(start 0.5334 -1.4224)
			(end 0.0254 -0.9144)
			(stroke
				(width 0.1524)
				(type default)
			)
			(layer "F.SilkS")
		)
		(fp_line
			(start 0.5334 -1.4224)
			(end 0.5334 -0.5588)
			(stroke
				(width 0.1524)
				(type default)
			)
			(layer "F.SilkS")
		)
		(fp_line
			(start 0.5334 -0.5588)
			(end 1.8034 -0.5588)
			(stroke
				(width 0.1524)
				(type default)
			)
			(layer "F.SilkS")
		)
		(fp_line
			(start 1.0414 -0.9144)
			(end 0.5334 -1.4224)
			(stroke
				(width 0.1524)
				(type default)
			)
			(layer "F.SilkS")
		)
		(fp_line
			(start 1.8034 -0.5588)
			(end 2.032 -0.7874)
			(stroke
				(width 0.1524)
				(type default)
			)
			(layer "F.SilkS")
		)
		(fp_line
			(start 15.649956 19.400012)
			(end 15.649956 -0.484124)
			(stroke
				(width 0.1524)
				(type default)
			)
			(layer "F.SilkS")
		)
		(fp_line
			(start 18.64995 -0.484124)
			(end 18.64995 22.400006)
			(stroke
				(width 0.1524)
				(type default)
			)
			(layer "F.SilkS")
		)
		(fp_line
			(start 18.64995 22.400006)
			(end -0.84709 22.400006)
			(stroke
				(width 0.1524)
				(type default)
			)
			(layer "F.SilkS")
		)
		(fp_poly
			(pts
				(xy -1.019048 0) (xy -2.035048 0.508) (xy -2.035048 -0.508)
			)
			(stroke
				(width 0)
				(type default)
			)
			(fill yes)
			(layer "F.SilkS")
		)
		(fp_line
			(start -4.249928 -11.999976)
			(end 18.64995 -11.999976)
			(stroke
				(width 0.1524)
				(type default)
			)
			(layer "B.SilkS")
		)
		(fp_line
			(start -4.249928 -0.809752)
			(end -4.249928 -11.999976)
			(stroke
				(width 0.1524)
				(type default)
			)
			(layer "B.SilkS")
		)
		(fp_line
			(start -4.249928 22.400006)
			(end -4.249928 17.325848)
			(stroke
				(width 0.1524)
				(type default)
			)
			(layer "B.SilkS")
		)
		(fp_line
			(start -2.67589 22.400006)
			(end -4.249928 22.400006)
			(stroke
				(width 0.1524)
				(type default)
			)
			(layer "B.SilkS")
		)
		(fp_line
			(start 18.64995 -11.999976)
			(end 18.64995 15.685008)
			(stroke
				(width 0.1524)
				(type default)
			)
			(layer "B.SilkS")
		)
		(fp_line
			(start 18.64995 16.944848)
			(end 18.64995 22.400006)
			(stroke
				(width 0.1524)
				(type default)
			)
			(layer "B.SilkS")
		)
		(fp_line
			(start 18.64995 22.400006)
			(end 3.14071 22.400006)
			(stroke
				(width 0.1524)
				(type default)
			)
			(layer "B.SilkS")
		)
		(fp_line
			(start -4.249928 -11.999976)
			(end 18.64995 -11.999976)
			(stroke
				(width 0.1)
				(type default)
			)
			(layer "B.Fab")
		)
		(fp_line
			(start -4.249928 22.400006)
			(end -4.249928 -11.999976)
			(stroke
				(width 0.1)
				(type default)
			)
			(layer "B.Fab")
		)
		(fp_line
			(start 18.64995 -11.999976)
			(end 18.64995 22.400006)
			(stroke
				(width 0.1)
				(type default)
			)
			(layer "B.Fab")
		)
		(fp_line
			(start 18.64995 22.400006)
			(end -4.249928 22.400006)
			(stroke
				(width 0.1)
				(type default)
			)
			(layer "B.Fab")
		)
		(fp_line
			(start -1.249934 -8.999982)
			(end -1.249934 19.400012)
			(stroke
				(width 0.1)
				(type default)
			)
			(layer "F.Fab")
		)
		(fp_line
			(start -1.249934 19.400012)
			(end 15.649956 19.400012)
			(stroke
				(width 0.1)
				(type default)
			)
			(layer "F.Fab")
		)
		(fp_line
			(start 15.649956 -8.999982)
			(end -1.249934 -8.999982)
			(stroke
				(width 0.1)
				(type default)
			)
			(layer "F.Fab")
		)
		(fp_line
			(start 15.649956 19.400012)
			(end 15.649956 -8.999982)
			(stroke
				(width 0.1)
				(type default)
			)
			(layer "F.Fab")
		)
		(fp_poly
			(pts
				(xy -2.670048 -0.508) (xy -2.670048 0.508) (xy -1.654048 0)
			)
			(stroke
				(width 0)
				(type default)
			)
			(fill yes)
			(layer "F.Fab")
		)
		(fp_text user "1"
			(at 0.111252 19.8628 90)
			(unlocked yes)
			(layer "F.SilkS")
			(effects
				(font
					(size 0.7874 0.5842)
					(thickness 0.1524)
				)
			)
		)
		(fp_text user "2"
			(at 2.111248 19.8628 90)
			(unlocked yes)
			(layer "F.SilkS")
			(effects
				(font
					(size 0.7874 0.5842)
					(thickness 0.1524)
				)
			)
		)
		(fp_text user "EDGE OF DAUGHTER CARD"
			(at 2.2479 -0.899668 0)
			(unlocked yes)
			(layer "F.SilkS")
			(effects
				(font
					(size 0.635 0.4064)
					(thickness 0.1524)
				)
				(justify left)
			)
		)
		(fp_text user "PRESS-FIT"
			(at 2.425192 25.863804 0)
			(unlocked yes)
			(layer "F.SilkS")
			(effects
				(font
					(size 1.905 1.4224)
					(thickness 0.1524)
				)
				(justify left)
			)
		)
		(fp_text user "3"
			(at 4.111244 19.8628 90)
			(unlocked yes)
			(layer "F.SilkS")
			(effects
				(font
					(size 0.7874 0.5842)
					(thickness 0.1524)
				)
			)
		)
		(fp_text user "4"
			(at 6.11124 19.8628 90)
			(unlocked yes)
			(layer "F.SilkS")
			(effects
				(font
					(size 0.7874 0.5842)
					(thickness 0.1524)
				)
			)
		)
		(fp_text user "5"
			(at 8.111236 19.8628 90)
			(unlocked yes)
			(layer "F.SilkS")
			(effects
				(font
					(size 0.7874 0.5842)
					(thickness 0.1524)
				)
			)
		)
		(fp_text user "6"
			(at 10.111232 19.8628 90)
			(unlocked yes)
			(layer "F.SilkS")
			(effects
				(font
					(size 0.7874 0.5842)
					(thickness 0.1524)
				)
			)
		)
		(fp_text user "7"
			(at 12.111228 19.8628 90)
			(unlocked yes)
			(layer "F.SilkS")
			(effects
				(font
					(size 0.7874 0.5842)
					(thickness 0.1524)
				)
			)
		)
		(fp_text user "8"
			(at 14.111224 19.8628 90)
			(unlocked yes)
			(layer "F.SilkS")
			(effects
				(font
					(size 0.7874 0.5842)
					(thickness 0.1524)
				)
			)
		)
		(fp_text user "B"
			(at 16.524478 1.453896 90)
			(unlocked yes)
			(layer "F.SilkS")
			(effects
				(font
					(size 0.7874 0.5842)
					(thickness 0.1524)
				)
			)
		)
		(fp_text user "C"
			(at 16.524478 2.654046 90)
			(unlocked yes)
			(layer "F.SilkS")
			(effects
				(font
					(size 0.7874 0.5842)
					(thickness 0.1524)
				)
			)
		)
		(fp_text user "D"
			(at 16.524478 3.853942 90)
			(unlocked yes)
			(layer "F.SilkS")
			(effects
				(font
					(size 0.7874 0.5842)
					(thickness 0.1524)
				)
			)
		)
		(fp_text user "E"
			(at 16.524478 5.054092 90)
			(unlocked yes)
			(layer "F.SilkS")
			(effects
				(font
					(size 0.7874 0.5842)
					(thickness 0.1524)
				)
			)
		)
		(fp_text user "F"
			(at 16.524478 6.253988 90)
			(unlocked yes)
			(layer "F.SilkS")
			(effects
				(font
					(size 0.7874 0.5842)
					(thickness 0.1524)
				)
			)
		)
		(fp_text user "G"
			(at 16.524478 7.453884 90)
			(unlocked yes)
			(layer "F.SilkS")
			(effects
				(font
					(size 0.7874 0.5842)
					(thickness 0.1524)
				)
			)
		)
		(fp_text user "H"
			(at 16.524478 8.654034 90)
			(unlocked yes)
			(layer "F.SilkS")
			(effects
				(font
					(size 0.7874 0.5842)
					(thickness 0.1524)
				)
			)
		)
		(fp_text user "I"
			(at 16.524478 9.85393 90)
			(unlocked yes)
			(layer "F.SilkS")
			(effects
				(font
					(size 0.7874 0.5842)
					(thickness 0.1524)
				)
			)
		)
		(fp_text user "J"
			(at 16.524478 11.05408 90)
			(unlocked yes)
			(layer "F.SilkS")
			(effects
				(font
					(size 0.7874 0.5842)
					(thickness 0.1524)
				)
			)
		)
		(fp_text user "K"
			(at 16.524478 12.253976 90)
			(unlocked yes)
			(layer "F.SilkS")
			(effects
				(font
					(size 0.7874 0.5842)
					(thickness 0.1524)
				)
			)
		)
		(fp_text user "L"
			(at 16.524478 13.454126 90)
			(unlocked yes)
			(layer "F.SilkS")
			(effects
				(font
					(size 0.7874 0.5842)
					(thickness 0.1524)
				)
			)
		)
		(fp_text user "M"
			(at 16.524478 14.654022 90)
			(unlocked yes)
			(layer "F.SilkS")
			(effects
				(font
					(size 0.7874 0.5842)
					(thickness 0.1524)
				)
			)
		)
		(fp_text user "N"
			(at 16.524478 15.853918 90)
			(unlocked yes)
			(layer "F.SilkS")
			(effects
				(font
					(size 0.7874 0.5842)
					(thickness 0.1524)
				)
			)
		)
		(fp_text user "A"
			(at -1.199134 0 90)
			(unlocked yes)
			(layer "B.SilkS")
			(effects
				(font
					(size 0.7874 0.5842)
					(thickness 0.1524)
				)
				(justify mirror)
			)
		)
		(fp_text user "G"
			(at -1.173734 7.4168 90)
			(unlocked yes)
			(layer "B.SilkS")
			(effects
				(font
					(size 0.7874 0.5842)
					(thickness 0.1524)
				)
				(justify mirror)
			)
		)
		(fp_text user "H"
			(at -1.148334 8.636 90)
			(unlocked yes)
			(layer "B.SilkS")
			(effects
				(font
					(size 0.7874 0.5842)
					(thickness 0.1524)
				)
				(justify mirror)
			)
		)
		(fp_text user "B"
			(at -1.14681 1.326896 90)
			(unlocked yes)
			(layer "B.SilkS")
			(effects
				(font
					(size 0.7874 0.5842)
					(thickness 0.1524)
				)
				(justify mirror)
			)
		)
		(fp_text user "C"
			(at -1.14681 2.527046 90)
			(unlocked yes)
			(layer "B.SilkS")
			(effects
				(font
					(size 0.7874 0.5842)
					(thickness 0.1524)
				)
				(justify mirror)
			)
		)
		(fp_text user "D"
			(at -1.14681 3.726942 90)
			(unlocked yes)
			(layer "B.SilkS")
			(effects
				(font
					(size 0.7874 0.5842)
					(thickness 0.1524)
				)
				(justify mirror)
			)
		)
		(fp_text user "E"
			(at -1.14681 4.927092 90)
			(unlocked yes)
			(layer "B.SilkS")
			(effects
				(font
					(size 0.7874 0.5842)
					(thickness 0.1524)
				)
				(justify mirror)
			)
		)
		(fp_text user "F"
			(at -1.14681 6.126988 90)
			(unlocked yes)
			(layer "B.SilkS")
			(effects
				(font
					(size 0.7874 0.5842)
					(thickness 0.1524)
				)
				(justify mirror)
			)
		)
		(fp_text user "I"
			(at -1.14681 9.72693 90)
			(unlocked yes)
			(layer "B.SilkS")
			(effects
				(font
					(size 0.7874 0.5842)
					(thickness 0.1524)
				)
				(justify mirror)
			)
		)
		(fp_text user "J"
			(at -1.14681 10.92708 90)
			(unlocked yes)
			(layer "B.SilkS")
			(effects
				(font
					(size 0.7874 0.5842)
					(thickness 0.1524)
				)
				(justify mirror)
			)
		)
		(fp_text user "K"
			(at -1.14681 12.126976 90)
			(unlocked yes)
			(layer "B.SilkS")
			(effects
				(font
					(size 0.7874 0.5842)
					(thickness 0.1524)
				)
				(justify mirror)
			)
		)
		(fp_text user "L"
			(at -1.14681 13.327126 90)
			(unlocked yes)
			(layer "B.SilkS")
			(effects
				(font
					(size 0.7874 0.5842)
					(thickness 0.1524)
				)
				(justify mirror)
			)
		)
		(fp_text user "M"
			(at -1.14681 14.527022 90)
			(unlocked yes)
			(layer "B.SilkS")
			(effects
				(font
					(size 0.7874 0.5842)
					(thickness 0.1524)
				)
				(justify mirror)
			)
		)
		(fp_text user "N"
			(at -1.14681 15.726918 90)
			(unlocked yes)
			(layer "B.SilkS")
			(effects
				(font
					(size 0.7874 0.5842)
					(thickness 0.1524)
				)
				(justify mirror)
			)
		)
		(fp_text user "1"
			(at 0.060452 16.764 90)
			(unlocked yes)
			(layer "B.SilkS")
			(effects
				(font
					(size 0.7874 0.5842)
					(thickness 0.1524)
				)
				(justify mirror)
			)
		)
		(fp_text user "2"
			(at 2.060448 16.764 90)
			(unlocked yes)
			(layer "B.SilkS")
			(effects
				(font
					(size 0.7874 0.5842)
					(thickness 0.1524)
				)
				(justify mirror)
			)
		)
		(fp_text user "3"
			(at 4.060444 16.764 90)
			(unlocked yes)
			(layer "B.SilkS")
			(effects
				(font
					(size 0.7874 0.5842)
					(thickness 0.1524)
				)
				(justify mirror)
			)
		)
		(fp_text user "4"
			(at 6.06044 16.764 90)
			(unlocked yes)
			(layer "B.SilkS")
			(effects
				(font
					(size 0.7874 0.5842)
					(thickness 0.1524)
				)
				(justify mirror)
			)
		)
		(fp_text user "5"
			(at 8.060436 16.764 90)
			(unlocked yes)
			(layer "B.SilkS")
			(effects
				(font
					(size 0.7874 0.5842)
					(thickness 0.1524)
				)
				(justify mirror)
			)
		)
		(fp_text user "6"
			(at 10.060432 16.764 90)
			(unlocked yes)
			(layer "B.SilkS")
			(effects
				(font
					(size 0.7874 0.5842)
					(thickness 0.1524)
				)
				(justify mirror)
			)
		)
		(fp_text user "7"
			(at 12.060428 16.764 90)
			(unlocked yes)
			(layer "B.SilkS")
			(effects
				(font
					(size 0.7874 0.5842)
					(thickness 0.1524)
				)
				(justify mirror)
			)
		)
		(fp_text user "8"
			(at 14.060424 16.764 90)
			(unlocked yes)
			(layer "B.SilkS")
			(effects
				(font
					(size 0.7874 0.5842)
					(thickness 0.1524)
				)
				(justify mirror)
			)
		)
		(fp_text user "PRESS-FIT"
			(at 17.23771 -0.0762 90)
			(unlocked yes)
			(layer "B.SilkS")
			(effects
				(font
					(size 1.905 1.4224)
					(thickness 0.1524)
				)
				(justify left mirror)
			)
		)
		(fp_text user "A"
			(at -1.199134 0 90)
			(unlocked yes)
			(layer "B.Fab")
			(effects
				(font
					(size 0.7874 0.5842)
					(thickness 0.1524)
				)
				(justify mirror)
			)
		)
		(fp_text user "G"
			(at -1.173734 7.4168 90)
			(unlocked yes)
			(layer "B.Fab")
			(effects
				(font
					(size 0.7874 0.5842)
					(thickness 0.1524)
				)
				(justify mirror)
			)
		)
		(fp_text user "H"
			(at -1.148334 8.636 90)
			(unlocked yes)
			(layer "B.Fab")
			(effects
				(font
					(size 0.7874 0.5842)
					(thickness 0.1524)
				)
				(justify mirror)
			)
		)
		(fp_text user "B"
			(at -1.14681 1.326896 90)
			(unlocked yes)
			(layer "B.Fab")
			(effects
				(font
					(size 0.7874 0.5842)
					(thickness 0.1524)
				)
				(justify mirror)
			)
		)
		(fp_text user "C"
			(at -1.14681 2.527046 90)
			(unlocked yes)
			(layer "B.Fab")
			(effects
				(font
					(size 0.7874 0.5842)
					(thickness 0.1524)
				)
				(justify mirror)
			)
		)
		(fp_text user "D"
			(at -1.14681 3.726942 90)
			(unlocked yes)
			(layer "B.Fab")
			(effects
				(font
					(size 0.7874 0.5842)
					(thickness 0.1524)
				)
				(justify mirror)
			)
		)
		(fp_text user "E"
			(at -1.14681 4.927092 90)
			(unlocked yes)
			(layer "B.Fab")
			(effects
				(font
					(size 0.7874 0.5842)
					(thickness 0.1524)
				)
				(justify mirror)
			)
		)
		(fp_text user "F"
			(at -1.14681 6.126988 90)
			(unlocked yes)
			(layer "B.Fab")
			(effects
				(font
					(size 0.7874 0.5842)
					(thickness 0.1524)
				)
				(justify mirror)
			)
		)
		(fp_text user "I"
			(at -1.14681 9.72693 90)
			(unlocked yes)
			(layer "B.Fab")
			(effects
				(font
					(size 0.7874 0.5842)
					(thickness 0.1524)
				)
				(justify mirror)
			)
		)
		(fp_text user "J"
			(at -1.14681 10.92708 90)
			(unlocked yes)
			(layer "B.Fab")
			(effects
				(font
					(size 0.7874 0.5842)
					(thickness 0.1524)
				)
				(justify mirror)
			)
		)
		(fp_text user "K"
			(at -1.14681 12.126976 90)
			(unlocked yes)
			(layer "B.Fab")
			(effects
				(font
					(size 0.7874 0.5842)
					(thickness 0.1524)
				)
				(justify mirror)
			)
		)
		(fp_text user "L"
			(at -1.14681 13.327126 90)
			(unlocked yes)
			(layer "B.Fab")
			(effects
				(font
					(size 0.7874 0.5842)
					(thickness 0.1524)
				)
				(justify mirror)
			)
		)
		(fp_text user "M"
			(at -1.14681 14.527022 90)
			(unlocked yes)
			(layer "B.Fab")
			(effects
				(font
					(size 0.7874 0.5842)
					(thickness 0.1524)
				)
				(justify mirror)
			)
		)
		(fp_text user "N"
			(at -1.14681 15.726918 90)
			(unlocked yes)
			(layer "B.Fab")
			(effects
				(font
					(size 0.7874 0.5842)
					(thickness 0.1524)
				)
				(justify mirror)
			)
		)
		(fp_text user "1"
			(at 0.060452 16.764 90)
			(unlocked yes)
			(layer "B.Fab")
			(effects
				(font
					(size 0.7874 0.5842)
					(thickness 0.1524)
				)
				(justify mirror)
			)
		)
		(fp_text user "2"
			(at 2.060448 16.764 90)
			(unlocked yes)
			(layer "B.Fab")
			(effects
				(font
					(size 0.7874 0.5842)
					(thickness 0.1524)
				)
				(justify mirror)
			)
		)
		(fp_text user "3"
			(at 4.060444 16.764 90)
			(unlocked yes)
			(layer "B.Fab")
			(effects
				(font
					(size 0.7874 0.5842)
					(thickness 0.1524)
				)
				(justify mirror)
			)
		)
		(fp_text user "4"
			(at 6.06044 16.764 90)
			(unlocked yes)
			(layer "B.Fab")
			(effects
				(font
					(size 0.7874 0.5842)
					(thickness 0.1524)
				)
				(justify mirror)
			)
		)
		(fp_text user "5"
			(at 8.060436 16.764 90)
			(unlocked yes)
			(layer "B.Fab")
			(effects
				(font
					(size 0.7874 0.5842)
					(thickness 0.1524)
				)
				(justify mirror)
			)
		)
		(fp_text user "6"
			(at 10.060432 16.764 90)
			(unlocked yes)
			(layer "B.Fab")
			(effects
				(font
					(size 0.7874 0.5842)
					(thickness 0.1524)
				)
				(justify mirror)
			)
		)
		(fp_text user "7"
			(at 12.060428 16.764 90)
			(unlocked yes)
			(layer "B.Fab")
			(effects
				(font
					(size 0.7874 0.5842)
					(thickness 0.1524)
				)
				(justify mirror)
			)
		)
		(fp_text user "8"
			(at 14.060424 16.764 90)
			(unlocked yes)
			(layer "B.Fab")
			(effects
				(font
					(size 0.7874 0.5842)
					(thickness 0.1524)
				)
				(justify mirror)
			)
		)
		(fp_text user "PRESS-FIT"
			(at 17.23771 -0.0762 90)
			(unlocked yes)
			(layer "B.Fab")
			(effects
				(font
					(size 1.905 1.4224)
					(thickness 0.1524)
				)
				(justify left mirror)
			)
		)
		(fp_text user "B"
			(at -2.253742 1.199896 90)
			(unlocked yes)
			(layer "F.Fab")
			(effects
				(font
					(size 0.7874 0.5842)
					(thickness 0.1524)
				)
			)
		)
		(fp_text user "C"
			(at -2.253742 2.400046 90)
			(unlocked yes)
			(layer "F.Fab")
			(effects
				(font
					(size 0.7874 0.5842)
					(thickness 0.1524)
				)
			)
		)
		(fp_text user "D"
			(at -2.253742 3.599942 90)
			(unlocked yes)
			(layer "F.Fab")
			(effects
				(font
					(size 0.7874 0.5842)
					(thickness 0.1524)
				)
			)
		)
		(fp_text user "E"
			(at -2.253742 4.800092 90)
			(unlocked yes)
			(layer "F.Fab")
			(effects
				(font
					(size 0.7874 0.5842)
					(thickness 0.1524)
				)
			)
		)
		(fp_text user "F"
			(at -2.253742 5.999988 90)
			(unlocked yes)
			(layer "F.Fab")
			(effects
				(font
					(size 0.7874 0.5842)
					(thickness 0.1524)
				)
			)
		)
		(fp_text user "G"
			(at -2.253742 7.199884 90)
			(unlocked yes)
			(layer "F.Fab")
			(effects
				(font
					(size 0.7874 0.5842)
					(thickness 0.1524)
				)
			)
		)
		(fp_text user "H"
			(at -2.253742 8.400034 90)
			(unlocked yes)
			(layer "F.Fab")
			(effects
				(font
					(size 0.7874 0.5842)
					(thickness 0.1524)
				)
			)
		)
		(fp_text user "I"
			(at -2.253742 9.59993 90)
			(unlocked yes)
			(layer "F.Fab")
			(effects
				(font
					(size 0.7874 0.5842)
					(thickness 0.1524)
				)
			)
		)
		(fp_text user "J"
			(at -2.253742 10.80008 90)
			(unlocked yes)
			(layer "F.Fab")
			(effects
				(font
					(size 0.7874 0.5842)
					(thickness 0.1524)
				)
			)
		)
		(fp_text user "K"
			(at -2.253742 11.999976 90)
			(unlocked yes)
			(layer "F.Fab")
			(effects
				(font
					(size 0.7874 0.5842)
					(thickness 0.1524)
				)
			)
		)
		(fp_text user "L"
			(at -2.253742 13.200126 90)
			(unlocked yes)
			(layer "F.Fab")
			(effects
				(font
					(size 0.7874 0.5842)
					(thickness 0.1524)
				)
			)
		)
		(fp_text user "M"
			(at -2.253742 14.400022 90)
			(unlocked yes)
			(layer "F.Fab")
			(effects
				(font
					(size 0.7874 0.5842)
					(thickness 0.1524)
				)
			)
		)
		(fp_text user "N"
			(at -2.253742 15.599918 90)
			(unlocked yes)
			(layer "F.Fab")
			(effects
				(font
					(size 0.7874 0.5842)
					(thickness 0.1524)
				)
			)
		)
		(fp_text user "1"
			(at 0.111252 19.8628 90)
			(unlocked yes)
			(layer "F.Fab")
			(effects
				(font
					(size 0.7874 0.5842)
					(thickness 0.1524)
				)
			)
		)
		(fp_text user "2"
			(at 2.111248 19.8628 90)
			(unlocked yes)
			(layer "F.Fab")
			(effects
				(font
					(size 0.7874 0.5842)
					(thickness 0.1524)
				)
			)
		)
		(fp_text user "3"
			(at 4.111244 19.8628 90)
			(unlocked yes)
			(layer "F.Fab")
			(effects
				(font
					(size 0.7874 0.5842)
					(thickness 0.1524)
				)
			)
		)
		(fp_text user "4"
			(at 6.11124 19.8628 90)
			(unlocked yes)
			(layer "F.Fab")
			(effects
				(font
					(size 0.7874 0.5842)
					(thickness 0.1524)
				)
			)
		)
		(fp_text user "5"
			(at 8.111236 19.8628 90)
			(unlocked yes)
			(layer "F.Fab")
			(effects
				(font
					(size 0.7874 0.5842)
					(thickness 0.1524)
				)
			)
		)
		(fp_text user "6"
			(at 10.111232 19.8628 90)
			(unlocked yes)
			(layer "F.Fab")
			(effects
				(font
					(size 0.7874 0.5842)
					(thickness 0.1524)
				)
			)
		)
		(fp_text user "7"
			(at 12.111228 19.8628 90)
			(unlocked yes)
			(layer "F.Fab")
			(effects
				(font
					(size 0.7874 0.5842)
					(thickness 0.1524)
				)
			)
		)
		(fp_text user "8"
			(at 14.111224 19.8628 90)
			(unlocked yes)
			(layer "F.Fab")
			(effects
				(font
					(size 0.7874 0.5842)
					(thickness 0.1524)
				)
			)
		)
		(fp_text user "PRESS-FIT"
			(at 17.240758 16.521684 90)
			(unlocked yes)
			(layer "F.Fab")
			(effects
				(font
					(size 1.905 1.4224)
					(thickness 0.1524)
				)
				(justify left)
			)
		)
		(pad "A1" thru_hole rect
			(at 0 0 180)
			(size 0.766318 0.766318)
			(drill 0.359918)
			(layers "*.Cu" "*.Mask")
			(remove_unused_layers no)
			(net "GPU_PEX_STRAP1")
			(clearance 0.0508)
			(thermal_gap 0.0508)
			(padstack
				(mode front_inner_back)
				(layer "Inner"
					(shape circle)
					(size 0.766318 0.766318)
					(clearance 0.0508)
				)
				(layer "B.Cu"
					(shape rect)
					(size 0.766318 0.766318)
					(clearance 0.0508)
				)
			)
		)
		(pad "A2" thru_hole circle
			(at 1.999996 0.199898 180)
			(size 0.906272 0.906272)
			(drill 0.499872)
			(layers "*.Cu" "*.Mask")
			(remove_unused_layers no)
			(net "GND")
			(clearance 0.0508)
			(thermal_gap 0.0508)
		)
		(pad "A3" thru_hole circle
			(at 3.999992 0 180)
			(size 0.766318 0.766318)
			(drill 0.359918)
			(layers "*.Cu" "*.Mask")
			(remove_unused_layers no)
			(net "GPU_BASE_ID0")
			(clearance 0.0508)
			(thermal_gap 0.0508)
		)
		(pad "A4" thru_hole circle
			(at 5.999988 0.199898 180)
			(size 0.906272 0.906272)
			(drill 0.499872)
			(layers "*.Cu" "*.Mask")
			(remove_unused_layers no)
			(net "GND")
			(clearance 0.0508)
			(thermal_gap 0.0508)
		)
		(pad "A5" thru_hole circle
			(at 7.999984 0 180)
			(size 0.766318 0.766318)
			(drill 0.359918)
			(layers "*.Cu" "*.Mask")
			(remove_unused_layers no)
			(net "GPU_PEX_STRAP0")
			(clearance 0.0508)
			(thermal_gap 0.0508)
		)
		(pad "A6" thru_hole circle
			(at 9.99998 0.199898 180)
			(size 0.906272 0.906272)
			(drill 0.499872)
			(layers "*.Cu" "*.Mask")
			(remove_unused_layers no)
			(net "GND")
			(clearance 0.0508)
			(thermal_gap 0.0508)
		)
		(pad "A7" thru_hole circle
			(at 11.999976 0 180)
			(size 0.766318 0.766318)
			(drill 0.359918)
			(layers "*.Cu" "*.Mask")
			(remove_unused_layers no)
			(net "GPU_FPGA_RST_R_BUF_N")
			(clearance 0.0508)
			(thermal_gap 0.0508)
		)
		(pad "A8" thru_hole circle
			(at 13.999972 0.199898 180)
			(size 0.906272 0.906272)
			(drill 0.499872)
			(layers "*.Cu" "*.Mask")
			(remove_unused_layers no)
			(net "GND")
			(clearance 0.0508)
			(thermal_gap 0.0508)
		)
		(pad "B1" thru_hole circle
			(at 0 1.199896 180)
			(size 0.906272 0.906272)
			(drill 0.499872)
			(layers "*.Cu" "*.Mask")
			(remove_unused_layers no)
			(net "GND")
			(clearance 0.0508)
			(thermal_gap 0.0508)
		)
		(pad "B3" thru_hole circle
			(at 3.999992 1.199896 180)
			(size 0.906272 0.906272)
			(drill 0.499872)
			(layers "*.Cu" "*.Mask")
			(remove_unused_layers no)
			(net "GND")
			(clearance 0.0508)
			(thermal_gap 0.0508)
		)
		(pad "B5" thru_hole circle
			(at 7.999984 1.199896 180)
			(size 0.906272 0.906272)
			(drill 0.499872)
			(layers "*.Cu" "*.Mask")
			(remove_unused_layers no)
			(net "GND")
			(clearance 0.0508)
			(thermal_gap 0.0508)
		)
		(pad "B7" thru_hole circle
			(at 11.999976 1.199896 180)
			(size 0.906272 0.906272)
			(drill 0.499872)
			(layers "*.Cu" "*.Mask")
			(remove_unused_layers no)
			(net "GND")
			(clearance 0.0508)
			(thermal_gap 0.0508)
		)
		(pad "D2" thru_hole circle
			(at 1.999996 3.800094 180)
			(size 0.906272 0.906272)
			(drill 0.499872)
			(layers "*.Cu" "*.Mask")
			(remove_unused_layers no)
			(net "GND")
			(clearance 0.0508)
			(thermal_gap 0.0508)
		)
		(pad "D4" thru_hole circle
			(at 5.999988 3.800094 180)
			(size 0.906272 0.906272)
			(drill 0.499872)
			(layers "*.Cu" "*.Mask")
			(remove_unused_layers no)
			(net "GND")
			(clearance 0.0508)
			(thermal_gap 0.0508)
		)
		(pad "D6" thru_hole circle
			(at 9.99998 3.800094 180)
			(size 0.906272 0.906272)
			(drill 0.499872)
			(layers "*.Cu" "*.Mask")
			(remove_unused_layers no)
			(net "GND")
			(clearance 0.0508)
			(thermal_gap 0.0508)
		)
		(pad "D8" thru_hole circle
			(at 13.999972 3.800094 180)
			(size 0.906272 0.906272)
			(drill 0.499872)
			(layers "*.Cu" "*.Mask")
			(remove_unused_layers no)
			(net "GND")
			(clearance 0.0508)
			(thermal_gap 0.0508)
		)
		(pad "E1" thru_hole circle
			(at 0 4.800092 180)
			(size 0.906272 0.906272)
			(drill 0.499872)
			(layers "*.Cu" "*.Mask")
			(remove_unused_layers no)
			(net "GND")
			(clearance 0.0508)
			(thermal_gap 0.0508)
		)
		(pad "E3" thru_hole circle
			(at 3.999992 4.800092 180)
			(size 0.906272 0.906272)
			(drill 0.499872)
			(layers "*.Cu" "*.Mask")
			(remove_unused_layers no)
			(net "GND")
			(clearance 0.0508)
			(thermal_gap 0.0508)
		)
		(pad "E5" thru_hole circle
			(at 7.999984 4.800092 180)
			(size 0.906272 0.906272)
			(drill 0.499872)
			(layers "*.Cu" "*.Mask")
			(remove_unused_layers no)
			(net "GND")
			(clearance 0.0508)
			(thermal_gap 0.0508)
		)
		(pad "E7" thru_hole circle
			(at 11.999976 4.800092 180)
			(size 0.906272 0.906272)
			(drill 0.499872)
			(layers "*.Cu" "*.Mask")
			(remove_unused_layers no)
			(net "GND")
			(clearance 0.0508)
			(thermal_gap 0.0508)
		)
		(pad "G2" thru_hole circle
			(at 1.999996 7.400036 180)
			(size 0.906272 0.906272)
			(drill 0.499872)
			(layers "*.Cu" "*.Mask")
			(remove_unused_layers no)
			(net "GND")
			(clearance 0.0508)
			(thermal_gap 0.0508)
		)
		(pad "G4" thru_hole circle
			(at 5.999988 7.400036 180)
			(size 0.906272 0.906272)
			(drill 0.499872)
			(layers "*.Cu" "*.Mask")
			(remove_unused_layers no)
			(net "GND")
			(clearance 0.0508)
			(thermal_gap 0.0508)
		)
		(pad "G6" thru_hole circle
			(at 9.99998 7.400036 180)
			(size 0.906272 0.906272)
			(drill 0.499872)
			(layers "*.Cu" "*.Mask")
			(remove_unused_layers no)
			(net "GND")
			(clearance 0.0508)
			(thermal_gap 0.0508)
		)
		(pad "G8" thru_hole circle
			(at 13.999972 7.400036 180)
			(size 0.906272 0.906272)
			(drill 0.499872)
			(layers "*.Cu" "*.Mask")
			(remove_unused_layers no)
			(net "GND")
			(clearance 0.0508)
			(thermal_gap 0.0508)
		)
		(pad "H1" thru_hole circle
			(at 0 8.400034 180)
			(size 0.906272 0.906272)
			(drill 0.499872)
			(layers "*.Cu" "*.Mask")
			(remove_unused_layers no)
			(net "GND")
			(clearance 0.0508)
			(thermal_gap 0.0508)
		)
		(pad "H3" thru_hole circle
			(at 3.999992 8.400034 180)
			(size 0.906272 0.906272)
			(drill 0.499872)
			(layers "*.Cu" "*.Mask")
			(remove_unused_layers no)
			(net "GND")
			(clearance 0.0508)
			(thermal_gap 0.0508)
		)
		(pad "H5" thru_hole circle
			(at 7.999984 8.400034 180)
			(size 0.906272 0.906272)
			(drill 0.499872)
			(layers "*.Cu" "*.Mask")
			(remove_unused_layers no)
			(net "GND")
			(clearance 0.0508)
			(thermal_gap 0.0508)
		)
		(pad "H7" thru_hole circle
			(at 11.999976 8.400034 180)
			(size 0.906272 0.906272)
			(drill 0.499872)
			(layers "*.Cu" "*.Mask")
			(remove_unused_layers no)
			(net "GND")
			(clearance 0.0508)
			(thermal_gap 0.0508)
		)
		(pad "J2" thru_hole circle
			(at 1.999996 10.999978 180)
			(size 0.906272 0.906272)
			(drill 0.499872)
			(layers "*.Cu" "*.Mask")
			(remove_unused_layers no)
			(net "GND")
			(clearance 0.0508)
			(thermal_gap 0.0508)
		)
		(pad "J4" thru_hole circle
			(at 5.999988 10.999978 180)
			(size 0.906272 0.906272)
			(drill 0.499872)
			(layers "*.Cu" "*.Mask")
			(remove_unused_layers no)
			(net "GND")
			(clearance 0.0508)
			(thermal_gap 0.0508)
		)
		(pad "J6" thru_hole circle
			(at 9.99998 10.999978 180)
			(size 0.906272 0.906272)
			(drill 0.499872)
			(layers "*.Cu" "*.Mask")
			(remove_unused_layers no)
			(net "GND")
			(clearance 0.0508)
			(thermal_gap 0.0508)
		)
		(pad "J8" thru_hole circle
			(at 13.999972 10.999978 180)
			(size 0.906272 0.906272)
			(drill 0.499872)
			(layers "*.Cu" "*.Mask")
			(remove_unused_layers no)
			(net "GND")
			(clearance 0.0508)
			(thermal_gap 0.0508)
		)
		(pad "K1" thru_hole circle
			(at 0 11.999976 180)
			(size 0.906272 0.906272)
			(drill 0.499872)
			(layers "*.Cu" "*.Mask")
			(remove_unused_layers no)
			(net "GND")
			(clearance 0.0508)
			(thermal_gap 0.0508)
		)
		(pad "K3" thru_hole circle
			(at 3.999992 11.999976 180)
			(size 0.906272 0.906272)
			(drill 0.499872)
			(layers "*.Cu" "*.Mask")
			(remove_unused_layers no)
			(net "GND")
			(clearance 0.0508)
			(thermal_gap 0.0508)
		)
		(pad "K5" thru_hole circle
			(at 7.999984 11.999976 180)
			(size 0.906272 0.906272)
			(drill 0.499872)
			(layers "*.Cu" "*.Mask")
			(remove_unused_layers no)
			(net "GND")
			(clearance 0.0508)
			(thermal_gap 0.0508)
		)
		(pad "K7" thru_hole circle
			(at 11.999976 11.999976 180)
			(size 0.906272 0.906272)
			(drill 0.499872)
			(layers "*.Cu" "*.Mask")
			(remove_unused_layers no)
			(net "GND")
			(clearance 0.0508)
			(thermal_gap 0.0508)
		)
		(pad "M2" thru_hole circle
			(at 1.999996 14.59992 180)
			(size 0.906272 0.906272)
			(drill 0.499872)
			(layers "*.Cu" "*.Mask")
			(remove_unused_layers no)
			(net "GND")
			(clearance 0.0508)
			(thermal_gap 0.0508)
		)
		(pad "M4" thru_hole circle
			(at 5.999988 14.59992 180)
			(size 0.906272 0.906272)
			(drill 0.499872)
			(layers "*.Cu" "*.Mask")
			(remove_unused_layers no)
			(net "GND")
			(clearance 0.0508)
			(thermal_gap 0.0508)
		)
		(pad "M6" thru_hole circle
			(at 9.99998 14.59992 180)
			(size 0.906272 0.906272)
			(drill 0.499872)
			(layers "*.Cu" "*.Mask")
			(remove_unused_layers no)
			(net "GND")
			(clearance 0.0508)
			(thermal_gap 0.0508)
		)
		(pad "M8" thru_hole circle
			(at 13.999972 14.59992 180)
			(size 0.906272 0.906272)
			(drill 0.499872)
			(layers "*.Cu" "*.Mask")
			(remove_unused_layers no)
			(net "GND")
			(clearance 0.0508)
			(thermal_gap 0.0508)
		)
		(pad "N1" thru_hole circle
			(at 0 15.599918 180)
			(size 0.906272 0.906272)
			(drill 0.499872)
			(layers "*.Cu" "*.Mask")
			(remove_unused_layers no)
			(net "GND")
			(clearance 0.0508)
			(thermal_gap 0.0508)
		)
		(pad "N2" thru_hole circle
			(at 1.999996 15.80007 180)
			(size 0.766318 0.766318)
			(drill 0.359918)
			(layers "*.Cu" "*.Mask")
			(remove_unused_layers no)
			(net "GPU_PRSNT_N")
			(clearance 0.0508)
			(thermal_gap 0.0508)
		)
		(pad "N3" thru_hole circle
			(at 3.999992 15.599918 180)
			(size 0.906272 0.906272)
			(drill 0.499872)
			(layers "*.Cu" "*.Mask")
			(remove_unused_layers no)
			(net "GND")
			(clearance 0.0508)
			(thermal_gap 0.0508)
		)
		(pad "N4" thru_hole circle
			(at 5.999988 15.80007 180)
			(size 0.766318 0.766318)
			(drill 0.359918)
			(layers "*.Cu" "*.Mask")
			(remove_unused_layers no)
			(net "FM_GPU_PWR_EN_R_BUF")
			(clearance 0.0508)
			(thermal_gap 0.0508)
		)
		(pad "N5" thru_hole circle
			(at 7.999984 15.599918 180)
			(size 0.906272 0.906272)
			(drill 0.499872)
			(layers "*.Cu" "*.Mask")
			(remove_unused_layers no)
			(net "GND")
			(clearance 0.0508)
			(thermal_gap 0.0508)
		)
		(pad "N6" thru_hole circle
			(at 9.99998 15.80007 180)
			(size 0.766318 0.766318)
			(drill 0.359918)
			(layers "*.Cu" "*.Mask")
			(remove_unused_layers no)
			(net "FM_GPU_PWRGD")
			(clearance 0.0508)
			(thermal_gap 0.0508)
		)
		(pad "N7" thru_hole circle
			(at 11.999976 15.599918 180)
			(size 0.906272 0.906272)
			(drill 0.499872)
			(layers "*.Cu" "*.Mask")
			(remove_unused_layers no)
			(net "GND")
			(clearance 0.0508)
			(thermal_gap 0.0508)
		)
		(pad "N8" thru_hole circle
			(at 13.999972 15.80007 180)
			(size 0.766318 0.766318)
			(drill 0.359918)
			(layers "*.Cu" "*.Mask")
			(remove_unused_layers no)
			(net "GPU_BASE_ID1")
			(clearance 0.0508)
			(thermal_gap 0.0508)
		)
		(zone
			(layer "B.Cu")
			(hatch none 0.5)
			(connect_pads
				(clearance 0)
			)
			(min_thickness 0.25)
			(keepout
				(tracks allowed)
				(vias not_allowed)
				(pads allowed)
				(copperpour not_allowed)
				(footprints allowed)
			)
			(placement
				(enabled no)
				(sheetname "")
			)
			(fill
				(thermal_gap 0.5)
				(thermal_bridge_width 0.5)
				(island_removal_mode 0)
			)
			(polygon
				(pts
					(xy 75.14209 -424.246548) (xy 90.16619 -424.246548) (xy 90.16619 -440.934348) (xy 75.14209 -440.934348)
				)
			)
		)
	)
	(footprint ""
		(layer "F.Cu")
		(at 35.15868 -432.056794 180)
		(property "Reference" "R3110"
			(at 0 0 180)
			(layer "F.SilkS")
			(hide yes)
			(effects
				(font
					(size 1.27 1.27)
				)
			)
		)
		(property "Value" ""
			(at 0 0 180)
			(layer "F.Fab")
			(effects
				(font
					(size 1.27 1.27)
				)
			)
		)
		(duplicate_pad_numbers_are_jumpers no)
		(fp_line
			(start 0.7874 0.4064)
			(end -0.7874 0.4064)
			(stroke
				(width 0.1524)
				(type default)
			)
			(layer "F.SilkS")
		)
		(fp_line
			(start 0.7874 -0.4064)
			(end 0.7874 0.4064)
			(stroke
				(width 0.1524)
				(type default)
			)
			(layer "F.SilkS")
		)
		(fp_line
			(start -0.7874 0.4064)
			(end -0.7874 -0.4064)
			(stroke
				(width 0.1524)
				(type default)
			)
			(layer "F.SilkS")
		)
		(fp_line
			(start -0.7874 -0.4064)
			(end 0.7874 -0.4064)
			(stroke
				(width 0.1524)
				(type default)
			)
			(layer "F.SilkS")
		)
		(fp_line
			(start 0.67945 0.3048)
			(end 0.120396 0.3048)
			(stroke
				(width 0.1)
				(type default)
			)
			(layer "F.Fab")
		)
		(fp_line
			(start 0.67945 -0.3048)
			(end 0.67945 0.3048)
			(stroke
				(width 0.1)
				(type default)
			)
			(layer "F.Fab")
		)
		(fp_line
			(start 0.12065 -0.2794)
			(end 0.12065 -0.3048)
			(stroke
				(width 0.1)
				(type default)
			)
			(layer "F.Fab")
		)
		(fp_line
			(start 0.12065 -0.3048)
			(end 0.67945 -0.3048)
			(stroke
				(width 0.1)
				(type default)
			)
			(layer "F.Fab")
		)
		(fp_line
			(start 0.120396 0.3048)
			(end 0.120396 0.2794)
			(stroke
				(width 0.1)
				(type default)
			)
			(layer "F.Fab")
		)
		(fp_line
			(start 0.120396 0.2794)
			(end -0.12065 0.2794)
			(stroke
				(width 0.1)
				(type default)
			)
			(layer "F.Fab")
		)
		(fp_line
			(start -0.12065 0.3048)
			(end -0.67945 0.3048)
			(stroke
				(width 0.1)
				(type default)
			)
			(layer "F.Fab")
		)
		(fp_line
			(start -0.12065 0.2794)
			(end -0.12065 0.3048)
			(stroke
				(width 0.1)
				(type default)
			)
			(layer "F.Fab")
		)
		(fp_line
			(start -0.12065 -0.2794)
			(end 0.12065 -0.2794)
			(stroke
				(width 0.1)
				(type default)
			)
			(layer "F.Fab")
		)
		(fp_line
			(start -0.12065 -0.305054)
			(end -0.12065 -0.2794)
			(stroke
				(width 0.1)
				(type default)
			)
			(layer "F.Fab")
		)
		(fp_line
			(start -0.67945 0.3048)
			(end -0.67945 -0.305054)
			(stroke
				(width 0.1)
				(type default)
			)
			(layer "F.Fab")
		)
		(fp_line
			(start -0.67945 -0.305054)
			(end -0.12065 -0.305054)
			(stroke
				(width 0.1)
				(type default)
			)
			(layer "F.Fab")
		)
		(pad "1" smd circle
			(at -0.40005 0 180)
			(size 0 0)
			(layers "F.Cu" "F.Mask" "F.Paste")
			(net "SMB_1_BMC_GPU_SDA")
		)
		(pad "2" smd circle
			(at 0.40005 0 180)
			(size 0 0)
			(layers "F.Cu" "F.Mask" "F.Paste")
			(net "SMB_1_BMC_GPU_R_SDA")
		)
	)
	(footprint ""
		(layer "F.Cu")
		(at 215.956134 -34.508948 180)
		(property "Reference" "R3592"
			(at 0 0 180)
			(layer "F.SilkS")
			(hide yes)
			(effects
				(font
					(size 1.27 1.27)
				)
			)
		)
		(property "Value" ""
			(at 0 0 180)
			(layer "F.Fab")
			(effects
				(font
					(size 1.27 1.27)
				)
			)
		)
		(duplicate_pad_numbers_are_jumpers no)
		(fp_line
			(start 0.7874 0.4064)
			(end -0.7874 0.4064)
			(stroke
				(width 0.1524)
				(type default)
			)
			(layer "F.SilkS")
		)
		(fp_line
			(start 0.7874 -0.4064)
			(end 0.7874 0.4064)
			(stroke
				(width 0.1524)
				(type default)
			)
			(layer "F.SilkS")
		)
		(fp_line
			(start -0.7874 0.4064)
			(end -0.7874 -0.4064)
			(stroke
				(width 0.1524)
				(type default)
			)
			(layer "F.SilkS")
		)
		(fp_line
			(start -0.7874 -0.4064)
			(end 0.7874 -0.4064)
			(stroke
				(width 0.1524)
				(type default)
			)
			(layer "F.SilkS")
		)
		(fp_line
			(start 0.67945 0.3048)
			(end 0.120396 0.3048)
			(stroke
				(width 0.1)
				(type default)
			)
			(layer "F.Fab")
		)
		(fp_line
			(start 0.67945 -0.3048)
			(end 0.67945 0.3048)
			(stroke
				(width 0.1)
				(type default)
			)
			(layer "F.Fab")
		)
		(fp_line
			(start 0.12065 -0.2794)
			(end 0.12065 -0.3048)
			(stroke
				(width 0.1)
				(type default)
			)
			(layer "F.Fab")
		)
		(fp_line
			(start 0.12065 -0.3048)
			(end 0.67945 -0.3048)
			(stroke
				(width 0.1)
				(type default)
			)
			(layer "F.Fab")
		)
		(fp_line
			(start 0.120396 0.3048)
			(end 0.120396 0.2794)
			(stroke
				(width 0.1)
				(type default)
			)
			(layer "F.Fab")
		)
		(fp_line
			(start 0.120396 0.2794)
			(end -0.12065 0.2794)
			(stroke
				(width 0.1)
				(type default)
			)
			(layer "F.Fab")
		)
		(fp_line
			(start -0.12065 0.3048)
			(end -0.67945 0.3048)
			(stroke
				(width 0.1)
				(type default)
			)
			(layer "F.Fab")
		)
		(fp_line
			(start -0.12065 0.2794)
			(end -0.12065 0.3048)
			(stroke
				(width 0.1)
				(type default)
			)
			(layer "F.Fab")
		)
		(fp_line
			(start -0.12065 -0.2794)
			(end 0.12065 -0.2794)
			(stroke
				(width 0.1)
				(type default)
			)
			(layer "F.Fab")
		)
		(fp_line
			(start -0.12065 -0.305054)
			(end -0.12065 -0.2794)
			(stroke
				(width 0.1)
				(type default)
			)
			(layer "F.Fab")
		)
		(fp_line
			(start -0.67945 0.3048)
			(end -0.67945 -0.305054)
			(stroke
				(width 0.1)
				(type default)
			)
			(layer "F.Fab")
		)
		(fp_line
			(start -0.67945 -0.305054)
			(end -0.12065 -0.305054)
			(stroke
				(width 0.1)
				(type default)
			)
			(layer "F.Fab")
		)
		(pad "1" smd circle
			(at -0.40005 0 180)
			(size 0 0)
			(layers "F.Cu" "F.Mask" "F.Paste")
			(net "SMB_INA230_3V3AUX_SCL")
		)
		(pad "2" smd circle
			(at 0.40005 0 180)
			(size 0 0)
			(layers "F.Cu" "F.Mask" "F.Paste")
			(net "SMB_INA230_5_3V3AUX_SCL_R")
		)
	)
	(footprint ""
		(layer "F.Cu")
		(at 145.050002 -81.018888 -90)
		(property "Reference" "PR6006"
			(at 0 0 270)
			(layer "F.SilkS")
			(hide yes)
			(effects
				(font
					(size 1.27 1.27)
				)
			)
		)
		(property "Value" ""
			(at 0 0 270)
			(layer "F.Fab")
			(effects
				(font
					(size 1.27 1.27)
				)
			)
		)
		(duplicate_pad_numbers_are_jumpers no)
		(fp_line
			(start -0.7874 0.4064)
			(end -0.7874 -0.4064)
			(stroke
				(width 0.1524)
				(type default)
			)
			(layer "F.SilkS")
		)
		(fp_line
			(start 0.7874 0.4064)
			(end -0.7874 0.4064)
			(stroke
				(width 0.1524)
				(type default)
			)
			(layer "F.SilkS")
		)
		(fp_line
			(start -0.7874 -0.4064)
			(end 0.7874 -0.4064)
			(stroke
				(width 0.1524)
				(type default)
			)
			(layer "F.SilkS")
		)
		(fp_line
			(start 0.7874 -0.4064)
			(end 0.7874 0.4064)
			(stroke
				(width 0.1524)
				(type default)
			)
			(layer "F.SilkS")
		)
		(fp_line
			(start -0.67945 0.3048)
			(end -0.67945 -0.305054)
			(stroke
				(width 0.1)
				(type default)
			)
			(layer "F.Fab")
		)
		(fp_line
			(start -0.12065 0.3048)
			(end -0.67945 0.3048)
			(stroke
				(width 0.1)
				(type default)
			)
			(layer "F.Fab")
		)
		(fp_line
			(start 0.120396 0.3048)
			(end 0.120396 0.2794)
			(stroke
				(width 0.1)
				(type default)
			)
			(layer "F.Fab")
		)
		(fp_line
			(start 0.67945 0.3048)
			(end 0.120396 0.3048)
			(stroke
				(width 0.1)
				(type default)
			)
			(layer "F.Fab")
		)
		(fp_line
			(start -0.12065 0.2794)
			(end -0.12065 0.3048)
			(stroke
				(width 0.1)
				(type default)
			)
			(layer "F.Fab")
		)
		(fp_line
			(start 0.120396 0.2794)
			(end -0.12065 0.2794)
			(stroke
				(width 0.1)
				(type default)
			)
			(layer "F.Fab")
		)
		(fp_line
			(start -0.12065 -0.2794)
			(end 0.12065 -0.2794)
			(stroke
				(width 0.1)
				(type default)
			)
			(layer "F.Fab")
		)
		(fp_line
			(start 0.12065 -0.2794)
			(end 0.12065 -0.3048)
			(stroke
				(width 0.1)
				(type default)
			)
			(layer "F.Fab")
		)
		(fp_line
			(start 0.12065 -0.3048)
			(end 0.67945 -0.3048)
			(stroke
				(width 0.1)
				(type default)
			)
			(layer "F.Fab")
		)
		(fp_line
			(start 0.67945 -0.3048)
			(end 0.67945 0.3048)
			(stroke
				(width 0.1)
				(type default)
			)
			(layer "F.Fab")
		)
		(fp_line
			(start -0.67945 -0.305054)
			(end -0.12065 -0.305054)
			(stroke
				(width 0.1)
				(type default)
			)
			(layer "F.Fab")
		)
		(fp_line
			(start -0.12065 -0.305054)
			(end -0.12065 -0.2794)
			(stroke
				(width 0.1)
				(type default)
			)
			(layer "F.Fab")
		)
		(pad "1" smd circle
			(at -0.40005 0 270)
			(size 0 0)
			(layers "F.Cu" "F.Mask" "F.Paste")
			(net "GND")
		)
		(pad "2" smd circle
			(at 0.40005 0 270)
			(size 0 0)
			(layers "F.Cu" "F.Mask" "F.Paste")
			(net "P1V8_AUX_MODE")
		)
	)
	(footprint ""
		(layer "F.Cu")
		(at 162.57143 -76.13142)
		(property "Reference" "Q4"
			(at -1.4224 -1.768348 0)
			(unlocked yes)
			(layer "F.SilkS")
			(effects
				(font
					(size 0.7874 0.5842)
					(thickness 0.1524)
				)
				(justify left)
			)
		)
		(property "Value" ""
			(at 0 0 0)
			(layer "F.Fab")
			(effects
				(font
					(size 1.27 1.27)
				)
			)
		)
		(duplicate_pad_numbers_are_jumpers no)
		(fp_line
			(start -1.332738 -1.100074)
			(end -0.4826 -1.100074)
			(stroke
				(width 0.1524)
				(type default)
			)
			(layer "F.SilkS")
		)
		(fp_line
			(start -1.332738 1.100074)
			(end -1.332738 -1.100074)
			(stroke
				(width 0.1524)
				(type default)
			)
			(layer "F.SilkS")
		)
		(fp_line
			(start -0.4826 -1.100074)
			(end 0 -0.541274)
			(stroke
				(width 0.1524)
				(type default)
			)
			(layer "F.SilkS")
		)
		(fp_line
			(start 0 -0.541274)
			(end 0.4826 -1.100074)
			(stroke
				(width 0.1524)
				(type default)
			)
			(layer "F.SilkS")
		)
		(fp_line
			(start 0.4826 -1.100074)
			(end 1.332738 -1.100074)
			(stroke
				(width 0.1524)
				(type default)
			)
			(layer "F.SilkS")
		)
		(fp_line
			(start 1.332738 -1.100074)
			(end 1.332738 1.100074)
			(stroke
				(width 0.1524)
				(type default)
			)
			(layer "F.SilkS")
		)
		(fp_line
			(start 1.332738 1.100074)
			(end -1.332738 1.100074)
			(stroke
				(width 0.1524)
				(type default)
			)
			(layer "F.SilkS")
		)
		(fp_poly
			(pts
				(xy -1.489456 -1.189482) (xy -2.23393 -1.43764) (xy -1.737614 -1.933956)
			)
			(stroke
				(width 0)
				(type default)
			)
			(fill yes)
			(layer "F.SilkS")
		)
		(fp_line
			(start -0.674878 -1.100074)
			(end 0.674878 -1.100074)
			(stroke
				(width 0.1)
				(type default)
			)
			(layer "F.Fab")
		)
		(fp_line
			(start -0.674878 1.100074)
			(end -0.674878 -1.100074)
			(stroke
				(width 0.1)
				(type default)
			)
			(layer "F.Fab")
		)
		(fp_line
			(start 0.674878 -1.100074)
			(end 0.674878 1.100074)
			(stroke
				(width 0.1)
				(type default)
			)
			(layer "F.Fab")
		)
		(fp_line
			(start 0.674878 1.100074)
			(end -0.674878 1.100074)
			(stroke
				(width 0.1)
				(type default)
			)
			(layer "F.Fab")
		)
		(fp_poly
			(pts
				(xy -2.2352 -0.298958) (xy -2.2352 -1.001014) (xy -1.533144 -0.649986)
			)
			(stroke
				(width 0)
				(type default)
			)
			(fill yes)
			(layer "F.Fab")
		)
		(pad "1" smd rect
			(at -0.94996 -0.649986 90)
			(size 0.4318 0.508)
			(layers "F.Cu" "F.Mask" "F.Paste")
			(net "GND")
		)
		(pad "2" smd rect
			(at -0.94996 0 90)
			(size 0.4318 0.508)
			(layers "F.Cu" "F.Mask" "F.Paste")
			(net "IRQ_LVC3_WAKE_N")
		)
		(pad "3" smd rect
			(at -0.94996 0.649986 90)
			(size 0.4318 0.508)
			(layers "F.Cu" "F.Mask" "F.Paste")
			(net "IRQ_WAKE_R_N")
		)
		(pad "4" smd rect
			(at 0.94996 0.649986 90)
			(size 0.4318 0.508)
			(layers "F.Cu" "F.Mask" "F.Paste")
			(net "GND")
		)
		(pad "5" smd rect
			(at 0.94996 0 90)
			(size 0.4318 0.508)
			(layers "F.Cu" "F.Mask" "F.Paste")
			(net "IRQ_LVC3_WAKE")
		)
		(pad "6" smd rect
			(at 0.94996 -0.649986 90)
			(size 0.4318 0.508)
			(layers "F.Cu" "F.Mask" "F.Paste")
			(net "IRQ_LVC3_WAKE")
		)
	)
	(footprint ""
		(layer "F.Cu")
		(at 444.621666 -402.81987)
		(property "Reference" "PR6553"
			(at 0 0 0)
			(layer "F.SilkS")
			(hide yes)
			(effects
				(font
					(size 1.27 1.27)
				)
			)
		)
		(property "Value" ""
			(at 0 0 0)
			(layer "F.Fab")
			(effects
				(font
					(size 1.27 1.27)
				)
			)
		)
		(duplicate_pad_numbers_are_jumpers no)
		(fp_line
			(start -0.7874 -0.4064)
			(end 0.7874 -0.4064)
			(stroke
				(width 0.1524)
				(type default)
			)
			(layer "F.SilkS")
		)
		(fp_line
			(start -0.7874 0.4064)
			(end -0.7874 -0.4064)
			(stroke
				(width 0.1524)
				(type default)
			)
			(layer "F.SilkS")
		)
		(fp_line
			(start 0.7874 -0.4064)
			(end 0.7874 0.4064)
			(stroke
				(width 0.1524)
				(type default)
			)
			(layer "F.SilkS")
		)
		(fp_line
			(start 0.7874 0.4064)
			(end -0.7874 0.4064)
			(stroke
				(width 0.1524)
				(type default)
			)
			(layer "F.SilkS")
		)
		(fp_line
			(start -0.67945 -0.305054)
			(end -0.12065 -0.305054)
			(stroke
				(width 0.1)
				(type default)
			)
			(layer "F.Fab")
		)
		(fp_line
			(start -0.67945 0.3048)
			(end -0.67945 -0.305054)
			(stroke
				(width 0.1)
				(type default)
			)
			(layer "F.Fab")
		)
		(fp_line
			(start -0.12065 -0.305054)
			(end -0.12065 -0.2794)
			(stroke
				(width 0.1)
				(type default)
			)
			(layer "F.Fab")
		)
		(fp_line
			(start -0.12065 -0.2794)
			(end 0.12065 -0.2794)
			(stroke
				(width 0.1)
				(type default)
			)
			(layer "F.Fab")
		)
		(fp_line
			(start -0.12065 0.2794)
			(end -0.12065 0.3048)
			(stroke
				(width 0.1)
				(type default)
			)
			(layer "F.Fab")
		)
		(fp_line
			(start -0.12065 0.3048)
			(end -0.67945 0.3048)
			(stroke
				(width 0.1)
				(type default)
			)
			(layer "F.Fab")
		)
		(fp_line
			(start 0.120396 0.2794)
			(end -0.12065 0.2794)
			(stroke
				(width 0.1)
				(type default)
			)
			(layer "F.Fab")
		)
		(fp_line
			(start 0.120396 0.3048)
			(end 0.120396 0.2794)
			(stroke
				(width 0.1)
				(type default)
			)
			(layer "F.Fab")
		)
		(fp_line
			(start 0.12065 -0.3048)
			(end 0.67945 -0.3048)
			(stroke
				(width 0.1)
				(type default)
			)
			(layer "F.Fab")
		)
		(fp_line
			(start 0.12065 -0.2794)
			(end 0.12065 -0.3048)
			(stroke
				(width 0.1)
				(type default)
			)
			(layer "F.Fab")
		)
		(fp_line
			(start 0.67945 -0.3048)
			(end 0.67945 0.3048)
			(stroke
				(width 0.1)
				(type default)
			)
			(layer "F.Fab")
		)
		(fp_line
			(start 0.67945 0.3048)
			(end 0.120396 0.3048)
			(stroke
				(width 0.1)
				(type default)
			)
			(layer "F.Fab")
		)
		(pad "1" smd circle
			(at -0.40005 0)
			(size 0 0)
			(layers "F.Cu" "F.Mask" "F.Paste")
			(net "P0V9_RETIMER_CPU0_LSET1")
		)
		(pad "2" smd circle
			(at 0.40005 0)
			(size 0 0)
			(layers "F.Cu" "F.Mask" "F.Paste")
			(net "GND")
		)
	)
	(footprint ""
		(layer "F.Cu")
		(at 36.319968 -133.857238)
		(property "Reference" "R4514"
			(at 0 0 0)
			(layer "F.SilkS")
			(hide yes)
			(effects
				(font
					(size 1.27 1.27)
				)
			)
		)
		(property "Value" ""
			(at 0 0 0)
			(layer "F.Fab")
			(effects
				(font
					(size 1.27 1.27)
				)
			)
		)
		(duplicate_pad_numbers_are_jumpers no)
		(fp_line
			(start -0.7874 -0.4064)
			(end 0.7874 -0.4064)
			(stroke
				(width 0.1524)
				(type default)
			)
			(layer "F.SilkS")
		)
		(fp_line
			(start -0.7874 0.4064)
			(end -0.7874 -0.4064)
			(stroke
				(width 0.1524)
				(type default)
			)
			(layer "F.SilkS")
		)
		(fp_line
			(start 0.7874 -0.4064)
			(end 0.7874 0.4064)
			(stroke
				(width 0.1524)
				(type default)
			)
			(layer "F.SilkS")
		)
		(fp_line
			(start 0.7874 0.4064)
			(end -0.7874 0.4064)
			(stroke
				(width 0.1524)
				(type default)
			)
			(layer "F.SilkS")
		)
		(fp_line
			(start -0.67945 -0.305054)
			(end -0.12065 -0.305054)
			(stroke
				(width 0.1)
				(type default)
			)
			(layer "F.Fab")
		)
		(fp_line
			(start -0.67945 0.3048)
			(end -0.67945 -0.305054)
			(stroke
				(width 0.1)
				(type default)
			)
			(layer "F.Fab")
		)
		(fp_line
			(start -0.12065 -0.305054)
			(end -0.12065 -0.2794)
			(stroke
				(width 0.1)
				(type default)
			)
			(layer "F.Fab")
		)
		(fp_line
			(start -0.12065 -0.2794)
			(end 0.12065 -0.2794)
			(stroke
				(width 0.1)
				(type default)
			)
			(layer "F.Fab")
		)
		(fp_line
			(start -0.12065 0.2794)
			(end -0.12065 0.3048)
			(stroke
				(width 0.1)
				(type default)
			)
			(layer "F.Fab")
		)
		(fp_line
			(start -0.12065 0.3048)
			(end -0.67945 0.3048)
			(stroke
				(width 0.1)
				(type default)
			)
			(layer "F.Fab")
		)
		(fp_line
			(start 0.120396 0.2794)
			(end -0.12065 0.2794)
			(stroke
				(width 0.1)
				(type default)
			)
			(layer "F.Fab")
		)
		(fp_line
			(start 0.120396 0.3048)
			(end 0.120396 0.2794)
			(stroke
				(width 0.1)
				(type default)
			)
			(layer "F.Fab")
		)
		(fp_line
			(start 0.12065 -0.3048)
			(end 0.67945 -0.3048)
			(stroke
				(width 0.1)
				(type default)
			)
			(layer "F.Fab")
		)
		(fp_line
			(start 0.12065 -0.2794)
			(end 0.12065 -0.3048)
			(stroke
				(width 0.1)
				(type default)
			)
			(layer "F.Fab")
		)
		(fp_line
			(start 0.67945 -0.3048)
			(end 0.67945 0.3048)
			(stroke
				(width 0.1)
				(type default)
			)
			(layer "F.Fab")
		)
		(fp_line
			(start 0.67945 0.3048)
			(end 0.120396 0.3048)
			(stroke
				(width 0.1)
				(type default)
			)
			(layer "F.Fab")
		)
		(pad "1" smd circle
			(at -0.40005 0)
			(size 0 0)
			(layers "F.Cu" "F.Mask" "F.Paste")
			(net "CLK_GEN2_GPU_FPGA_OE_R2_N")
		)
		(pad "2" smd circle
			(at 0.40005 0)
			(size 0 0)
			(layers "F.Cu" "F.Mask" "F.Paste")
			(net "GND")
		)
	)
	(footprint ""
		(layer "F.Cu")
		(at 103.729282 -339.939376)
		(property "Reference" "PU33"
			(at -3.018282 -7.632954 0)
			(unlocked yes)
			(layer "F.SilkS")
			(effects
				(font
					(size 0.7874 0.5842)
					(thickness 0.1524)
				)
				(justify left)
			)
		)
		(property "Value" ""
			(at 0 0 0)
			(layer "F.Fab")
			(effects
				(font
					(size 1.27 1.27)
				)
			)
		)
		(duplicate_pad_numbers_are_jumpers no)
		(fp_line
			(start -2.500122 -2.999994)
			(end -2.24409 -2.999994)
			(stroke
				(width 0.1524)
				(type default)
			)
			(layer "F.SilkS")
		)
		(fp_line
			(start -2.500122 -2.529078)
			(end -2.500122 -2.999994)
			(stroke
				(width 0.1524)
				(type default)
			)
			(layer "F.SilkS")
		)
		(fp_line
			(start -2.500122 0.6604)
			(end -2.500122 0.229108)
			(stroke
				(width 0.1524)
				(type default)
			)
			(layer "F.SilkS")
		)
		(fp_line
			(start -2.500122 2.999994)
			(end -2.500122 2.339594)
			(stroke
				(width 0.1524)
				(type default)
			)
			(layer "F.SilkS")
		)
		(fp_line
			(start -2.2987 2.999994)
			(end -2.500122 2.999994)
			(stroke
				(width 0.1524)
				(type default)
			)
			(layer "F.SilkS")
		)
		(fp_line
			(start 2.31394 -2.999994)
			(end 2.500122 -2.999994)
			(stroke
				(width 0.1524)
				(type default)
			)
			(layer "F.SilkS")
		)
		(fp_line
			(start 2.500122 -2.999994)
			(end 2.500122 -2.44348)
			(stroke
				(width 0.1524)
				(type default)
			)
			(layer "F.SilkS")
		)
		(fp_line
			(start 2.500122 2.339594)
			(end 2.500122 2.999994)
			(stroke
				(width 0.1524)
				(type default)
			)
			(layer "F.SilkS")
		)
		(fp_line
			(start 2.500122 2.999994)
			(end 2.2987 2.999994)
			(stroke
				(width 0.1524)
				(type default)
			)
			(layer "F.SilkS")
		)
		(fp_poly
			(pts
				(xy -2.770124 -2.400046) (xy -3.443732 -2.624582) (xy -2.99466 -3.073654)
			)
			(stroke
				(width 0)
				(type default)
			)
			(fill yes)
			(layer "F.SilkS")
		)
		(fp_line
			(start -2.500122 -2.999994)
			(end 2.500122 -2.999994)
			(stroke
				(width 0.1)
				(type default)
			)
			(layer "F.Fab")
		)
		(fp_line
			(start -2.500122 2.999994)
			(end -2.500122 -2.999994)
			(stroke
				(width 0.1)
				(type default)
			)
			(layer "F.Fab")
		)
		(fp_line
			(start 2.500122 -2.999994)
			(end 2.500122 2.999994)
			(stroke
				(width 0.1)
				(type default)
			)
			(layer "F.Fab")
		)
		(fp_line
			(start 2.500122 2.999994)
			(end -2.500122 2.999994)
			(stroke
				(width 0.1)
				(type default)
			)
			(layer "F.Fab")
		)
		(fp_poly
			(pts
				(xy -4.218432 -2.783078) (xy -4.218432 -1.767078) (xy -3.202432 -2.275078)
			)
			(stroke
				(width 0)
				(type default)
			)
			(fill yes)
			(layer "F.Fab")
		)
		(pad "1" smd rect
			(at -2.400046 -2.275078 90)
			(size 0.2286 0.6096)
			(layers "F.Cu" "F.Mask" "F.Paste")
			(net "PVDDCR_CPU1_P1_VOS6")
		)
		(pad "2" smd rect
			(at -2.400046 -1.82499 90)
			(size 0.2286 0.6096)
			(layers "F.Cu" "F.Mask" "F.Paste")
			(net "GND")
		)
		(pad "3" smd rect
			(at -2.400046 -1.374902 90)
			(size 0.2286 0.6096)
			(layers "F.Cu" "F.Mask" "F.Paste")
			(net "PVDDCR_CPU1_P1_VCC6")
		)
		(pad "4" smd rect
			(at -2.400046 -0.925068 90)
			(size 0.2286 0.6096)
			(layers "F.Cu" "F.Mask" "F.Paste")
			(net "PVDDCR_CPU1_P1_PVCC")
		)
		(pad "5" smd rect
			(at -2.400046 -0.47498 90)
			(size 0.2286 0.6096)
			(layers "F.Cu" "F.Mask" "F.Paste")
			(net "GND")
		)
		(pad "6" smd rect
			(at -2.400046 -0.024892 90)
			(size 0.2286 0.6096)
			(layers "F.Cu" "F.Mask" "F.Paste")
			(net "NC_PVDDCR_CPU1_P1_GL1_6")
		)
		(pad "7_9-20_24" smd circle
			(at 0 1.150112 90)
			(size 0 0)
			(layers "F.Cu" "F.Mask" "F.Paste")
			(net "GND")
		)
		(pad "10_19" smd rect
			(at 0 2.899918 90)
			(size 0.6096 4.318)
			(layers "F.Cu" "F.Mask" "F.Paste")
			(net "SW_PVDDCR_CPU1_P1_SW6")
		)
		(pad "25_29" smd rect
			(at 1.549908 -1.279906 270)
			(size 2.0574 2.3114)
			(layers "F.Cu" "F.Mask" "F.Paste")
			(net "SW_P12V_AUX_PVDDCR_CPU1_P1_FLT")
		)
		(pad "30" smd rect
			(at 2.05994 -2.899918)
			(size 0.2286 0.6096)
			(layers "F.Cu" "F.Mask" "F.Paste")
			(net "SW_P12V_AUX_PVDDCR_CPU1_P1_FLT")
		)
		(pad "31" smd rect
			(at 1.610106 -2.899918)
			(size 0.2286 0.6096)
			(layers "F.Cu" "F.Mask" "F.Paste")
			(net "NC_PVDDCR_CPU1_P1_DNC6")
		)
		(pad "32" smd rect
			(at 1.160018 -2.899918)
			(size 0.2286 0.6096)
			(layers "F.Cu" "F.Mask" "F.Paste")
			(net "SW_PVDDCR_CPU1_P1_BOOTR6")
		)
		(pad "33" smd rect
			(at 0.70993 -2.899918)
			(size 0.2286 0.6096)
			(layers "F.Cu" "F.Mask" "F.Paste")
			(net "SW_PVDDCR_CPU1_P1_BOOT6")
		)
		(pad "34" smd rect
			(at 0.260096 -2.899918)
			(size 0.2286 0.6096)
			(layers "F.Cu" "F.Mask" "F.Paste")
			(net "PVDDCR_CPU1_P1_PWM6")
		)
		(pad "35" smd rect
			(at -0.189992 -2.899918)
			(size 0.2286 0.6096)
			(layers "F.Cu" "F.Mask" "F.Paste")
			(net "PVDDCR_CPU1_P1_VCC6")
		)
		(pad "36" smd rect
			(at -0.64008 -2.899918)
			(size 0.2286 0.6096)
			(layers "F.Cu" "F.Mask" "F.Paste")
			(net "PVDDCR_CPU1_P1_TEMP0")
		)
		(pad "37" smd rect
			(at -1.089914 -2.899918)
			(size 0.2286 0.6096)
			(layers "F.Cu" "F.Mask" "F.Paste")
			(net "PVDDCR_CPU1_P1_LSET6")
		)
		(pad "38" smd rect
			(at -1.540002 -2.899918)
			(size 0.2286 0.6096)
			(layers "F.Cu" "F.Mask" "F.Paste")
			(net "PVDDCR_CPU1_P1_IMON6")
		)
		(pad "39" smd rect
			(at -1.99009 -2.899918)
			(size 0.2286 0.6096)
			(layers "F.Cu" "F.Mask" "F.Paste")
			(net "PVDDCR_CPU1_P1_VCCS")
		)
		(pad "40" smd rect
			(at -0.87503 -1.27508)
			(size 1.7526 1.9558)
			(layers "F.Cu" "F.Mask" "F.Paste")
			(net "GND")
		)
		(pad "41" smd rect
			(at -1.525016 0.249936 270)
			(size 0.3048 0.4572)
			(layers "F.Cu" "F.Mask" "F.Paste")
			(net "NC_PVDDCR_CPU1_P1_GL2_6")
		)
		(zone
			(layer "F.Cu")
			(hatch none 0.5)
			(connect_pads
				(clearance 0)
			)
			(min_thickness 0.25)
			(keepout
				(tracks not_allowed)
				(vias allowed)
				(pads allowed)
				(copperpour not_allowed)
				(footprints allowed)
			)
			(placement
				(enabled no)
				(sheetname "")
			)
			(fill
				(thermal_gap 0.5)
				(thermal_bridge_width 0.5)
				(island_removal_mode 0)
			)
			(polygon
				(pts
					(xy 101.22916 -337.356196) (xy 101.22916 -337.688682) (xy 106.229404 -337.688682) (xy 106.229404 -337.362038)
					(xy 105.939082 -337.362038) (xy 105.939082 -337.395058) (xy 101.519482 -337.395058) (xy 101.519482 -337.356196)
				)
			)
		)
		(zone
			(layer "F.Cu")
			(hatch none 0.5)
			(connect_pads
				(clearance 0)
			)
			(min_thickness 0.25)
			(keepout
				(tracks not_allowed)
				(vias allowed)
				(pads allowed)
				(copperpour not_allowed)
				(footprints allowed)
			)
			(placement
				(enabled no)
				(sheetname "")
			)
			(fill
				(thermal_gap 0.5)
				(thermal_bridge_width 0.5)
				(island_removal_mode 0)
			)
			(polygon
				(pts
					(xy 103.781352 -340.185756) (xy 103.781352 -342.243156) (xy 101.927152 -342.243156) (xy 101.927152 -342.00211)
					(xy 101.684836 -342.00211) (xy 101.684836 -342.483694) (xy 105.512616 -342.483694) (xy 105.512616 -342.298782)
					(xy 104.07269 -342.298782) (xy 104.07269 -340.139782) (xy 106.229404 -340.139782) (xy 106.229404 -339.8901)
					(xy 104.077008 -339.8901)
				)
			)
		)
	)
	(footprint ""
		(layer "F.Cu")
		(at 454.847452 -19.427698 -90)
		(property "Reference" "R3797"
			(at 0 0 270)
			(layer "F.SilkS")
			(hide yes)
			(effects
				(font
					(size 1.27 1.27)
				)
			)
		)
		(property "Value" ""
			(at 0 0 270)
			(layer "F.Fab")
			(effects
				(font
					(size 1.27 1.27)
				)
			)
		)
		(duplicate_pad_numbers_are_jumpers no)
		(fp_line
			(start -0.7874 0.4064)
			(end -0.7874 -0.4064)
			(stroke
				(width 0.1524)
				(type default)
			)
			(layer "F.SilkS")
		)
		(fp_line
			(start 0.7874 0.4064)
			(end -0.7874 0.4064)
			(stroke
				(width 0.1524)
				(type default)
			)
			(layer "F.SilkS")
		)
		(fp_line
			(start -0.7874 -0.4064)
			(end 0.7874 -0.4064)
			(stroke
				(width 0.1524)
				(type default)
			)
			(layer "F.SilkS")
		)
		(fp_line
			(start 0.7874 -0.4064)
			(end 0.7874 0.4064)
			(stroke
				(width 0.1524)
				(type default)
			)
			(layer "F.SilkS")
		)
		(fp_line
			(start -0.67945 0.3048)
			(end -0.67945 -0.305054)
			(stroke
				(width 0.1)
				(type default)
			)
			(layer "F.Fab")
		)
		(fp_line
			(start -0.12065 0.3048)
			(end -0.67945 0.3048)
			(stroke
				(width 0.1)
				(type default)
			)
			(layer "F.Fab")
		)
		(fp_line
			(start 0.120396 0.3048)
			(end 0.120396 0.2794)
			(stroke
				(width 0.1)
				(type default)
			)
			(layer "F.Fab")
		)
		(fp_line
			(start 0.67945 0.3048)
			(end 0.120396 0.3048)
			(stroke
				(width 0.1)
				(type default)
			)
			(layer "F.Fab")
		)
		(fp_line
			(start -0.12065 0.2794)
			(end -0.12065 0.3048)
			(stroke
				(width 0.1)
				(type default)
			)
			(layer "F.Fab")
		)
		(fp_line
			(start 0.120396 0.2794)
			(end -0.12065 0.2794)
			(stroke
				(width 0.1)
				(type default)
			)
			(layer "F.Fab")
		)
		(fp_line
			(start -0.12065 -0.2794)
			(end 0.12065 -0.2794)
			(stroke
				(width 0.1)
				(type default)
			)
			(layer "F.Fab")
		)
		(fp_line
			(start 0.12065 -0.2794)
			(end 0.12065 -0.3048)
			(stroke
				(width 0.1)
				(type default)
			)
			(layer "F.Fab")
		)
		(fp_line
			(start 0.12065 -0.3048)
			(end 0.67945 -0.3048)
			(stroke
				(width 0.1)
				(type default)
			)
			(layer "F.Fab")
		)
		(fp_line
			(start 0.67945 -0.3048)
			(end 0.67945 0.3048)
			(stroke
				(width 0.1)
				(type default)
			)
			(layer "F.Fab")
		)
		(fp_line
			(start -0.67945 -0.305054)
			(end -0.12065 -0.305054)
			(stroke
				(width 0.1)
				(type default)
			)
			(layer "F.Fab")
		)
		(fp_line
			(start -0.12065 -0.305054)
			(end -0.12065 -0.2794)
			(stroke
				(width 0.1)
				(type default)
			)
			(layer "F.Fab")
		)
		(pad "1" smd circle
			(at -0.40005 0 270)
			(size 0 0)
			(layers "F.Cu" "F.Mask" "F.Paste")
			(net "P3V3_AUX")
		)
		(pad "2" smd circle
			(at 0.40005 0 270)
			(size 0 0)
			(layers "F.Cu" "F.Mask" "F.Paste")
			(net "HP_LVC3_OCP_V3_1_P12V_PWRGD")
		)
	)
	(footprint ""
		(layer "F.Cu")
		(at 145.474944 -59.898534)
		(property "Reference" "R1622"
			(at 0 0 0)
			(layer "F.SilkS")
			(hide yes)
			(effects
				(font
					(size 1.27 1.27)
				)
			)
		)
		(property "Value" ""
			(at 0 0 0)
			(layer "F.Fab")
			(effects
				(font
					(size 1.27 1.27)
				)
			)
		)
		(duplicate_pad_numbers_are_jumpers no)
		(fp_line
			(start -0.7874 -0.4064)
			(end 0.7874 -0.4064)
			(stroke
				(width 0.1524)
				(type default)
			)
			(layer "F.SilkS")
		)
		(fp_line
			(start -0.7874 0.4064)
			(end -0.7874 -0.4064)
			(stroke
				(width 0.1524)
				(type default)
			)
			(layer "F.SilkS")
		)
		(fp_line
			(start 0.7874 -0.4064)
			(end 0.7874 0.4064)
			(stroke
				(width 0.1524)
				(type default)
			)
			(layer "F.SilkS")
		)
		(fp_line
			(start 0.7874 0.4064)
			(end -0.7874 0.4064)
			(stroke
				(width 0.1524)
				(type default)
			)
			(layer "F.SilkS")
		)
		(fp_line
			(start -0.67945 -0.305054)
			(end -0.12065 -0.305054)
			(stroke
				(width 0.1)
				(type default)
			)
			(layer "F.Fab")
		)
		(fp_line
			(start -0.67945 0.3048)
			(end -0.67945 -0.305054)
			(stroke
				(width 0.1)
				(type default)
			)
			(layer "F.Fab")
		)
		(fp_line
			(start -0.12065 -0.305054)
			(end -0.12065 -0.2794)
			(stroke
				(width 0.1)
				(type default)
			)
			(layer "F.Fab")
		)
		(fp_line
			(start -0.12065 -0.2794)
			(end 0.12065 -0.2794)
			(stroke
				(width 0.1)
				(type default)
			)
			(layer "F.Fab")
		)
		(fp_line
			(start -0.12065 0.2794)
			(end -0.12065 0.3048)
			(stroke
				(width 0.1)
				(type default)
			)
			(layer "F.Fab")
		)
		(fp_line
			(start -0.12065 0.3048)
			(end -0.67945 0.3048)
			(stroke
				(width 0.1)
				(type default)
			)
			(layer "F.Fab")
		)
		(fp_line
			(start 0.120396 0.2794)
			(end -0.12065 0.2794)
			(stroke
				(width 0.1)
				(type default)
			)
			(layer "F.Fab")
		)
		(fp_line
			(start 0.120396 0.3048)
			(end 0.120396 0.2794)
			(stroke
				(width 0.1)
				(type default)
			)
			(layer "F.Fab")
		)
		(fp_line
			(start 0.12065 -0.3048)
			(end 0.67945 -0.3048)
			(stroke
				(width 0.1)
				(type default)
			)
			(layer "F.Fab")
		)
		(fp_line
			(start 0.12065 -0.2794)
			(end 0.12065 -0.3048)
			(stroke
				(width 0.1)
				(type default)
			)
			(layer "F.Fab")
		)
		(fp_line
			(start 0.67945 -0.3048)
			(end 0.67945 0.3048)
			(stroke
				(width 0.1)
				(type default)
			)
			(layer "F.Fab")
		)
		(fp_line
			(start 0.67945 0.3048)
			(end 0.120396 0.3048)
			(stroke
				(width 0.1)
				(type default)
			)
			(layer "F.Fab")
		)
		(pad "1" smd circle
			(at -0.40005 0)
			(size 0 0)
			(layers "F.Cu" "F.Mask" "F.Paste")
			(net "P3V3_AUX")
		)
		(pad "2" smd circle
			(at 0.40005 0)
			(size 0 0)
			(layers "F.Cu" "F.Mask" "F.Paste")
			(net "JTAG_BMC_OE_N")
		)
	)
	(footprint ""
		(layer "F.Cu")
		(at 105.670096 -173.5201 90)
		(property "Reference" "PC301"
			(at 0 0 90)
			(layer "F.SilkS")
			(hide yes)
			(effects
				(font
					(size 1.27 1.27)
				)
			)
		)
		(property "Value" ""
			(at 0 0 90)
			(layer "F.Fab")
			(effects
				(font
					(size 1.27 1.27)
				)
			)
		)
		(duplicate_pad_numbers_are_jumpers no)
		(fp_line
			(start 0.7874 -0.4064)
			(end 0.7874 0.4064)
			(stroke
				(width 0.1524)
				(type default)
			)
			(layer "F.SilkS")
		)
		(fp_line
			(start -0.7874 -0.4064)
			(end 0.7874 -0.4064)
			(stroke
				(width 0.1524)
				(type default)
			)
			(layer "F.SilkS")
		)
		(fp_line
			(start 0.7874 0.4064)
			(end -0.7874 0.4064)
			(stroke
				(width 0.1524)
				(type default)
			)
			(layer "F.SilkS")
		)
		(fp_line
			(start -0.7874 0.4064)
			(end -0.7874 -0.4064)
			(stroke
				(width 0.1524)
				(type default)
			)
			(layer "F.SilkS")
		)
		(fp_line
			(start -0.12065 -0.305054)
			(end -0.12065 -0.2794)
			(stroke
				(width 0.1)
				(type default)
			)
			(layer "F.Fab")
		)
		(fp_line
			(start -0.67945 -0.305054)
			(end -0.12065 -0.305054)
			(stroke
				(width 0.1)
				(type default)
			)
			(layer "F.Fab")
		)
		(fp_line
			(start 0.67945 -0.3048)
			(end 0.67945 0.3048)
			(stroke
				(width 0.1)
				(type default)
			)
			(layer "F.Fab")
		)
		(fp_line
			(start 0.12065 -0.3048)
			(end 0.67945 -0.3048)
			(stroke
				(width 0.1)
				(type default)
			)
			(layer "F.Fab")
		)
		(fp_line
			(start 0.12065 -0.2794)
			(end 0.12065 -0.3048)
			(stroke
				(width 0.1)
				(type default)
			)
			(layer "F.Fab")
		)
		(fp_line
			(start -0.12065 -0.2794)
			(end 0.12065 -0.2794)
			(stroke
				(width 0.1)
				(type default)
			)
			(layer "F.Fab")
		)
		(fp_line
			(start 0.120396 0.2794)
			(end -0.12065 0.2794)
			(stroke
				(width 0.1)
				(type default)
			)
			(layer "F.Fab")
		)
		(fp_line
			(start -0.12065 0.2794)
			(end -0.12065 0.3048)
			(stroke
				(width 0.1)
				(type default)
			)
			(layer "F.Fab")
		)
		(fp_line
			(start 0.67945 0.3048)
			(end 0.120396 0.3048)
			(stroke
				(width 0.1)
				(type default)
			)
			(layer "F.Fab")
		)
		(fp_line
			(start 0.120396 0.3048)
			(end 0.120396 0.2794)
			(stroke
				(width 0.1)
				(type default)
			)
			(layer "F.Fab")
		)
		(fp_line
			(start -0.12065 0.3048)
			(end -0.67945 0.3048)
			(stroke
				(width 0.1)
				(type default)
			)
			(layer "F.Fab")
		)
		(fp_line
			(start -0.67945 0.3048)
			(end -0.67945 -0.305054)
			(stroke
				(width 0.1)
				(type default)
			)
			(layer "F.Fab")
		)
		(pad "1" smd circle
			(at -0.40005 0 90)
			(size 0 0)
			(layers "F.Cu" "F.Mask" "F.Paste")
			(net "SW_PVDDCR_CPU0_P1_BOOT4_RC")
		)
		(pad "2" smd circle
			(at 0.40005 0 90)
			(size 0 0)
			(layers "F.Cu" "F.Mask" "F.Paste")
			(net "SW_PVDDCR_CPU0_P1_PH4")
		)
	)
	(footprint ""
		(layer "F.Cu")
		(at 180.3908 -390.779)
		(property "Reference" "R1427"
			(at 0 0 0)
			(layer "F.SilkS")
			(hide yes)
			(effects
				(font
					(size 1.27 1.27)
				)
			)
		)
		(property "Value" ""
			(at 0 0 0)
			(layer "F.Fab")
			(effects
				(font
					(size 1.27 1.27)
				)
			)
		)
		(duplicate_pad_numbers_are_jumpers no)
		(fp_line
			(start -0.32512 -0.175006)
			(end 0.32512 -0.175006)
			(stroke
				(width 0.1)
				(type default)
			)
			(layer "F.Fab")
		)
		(fp_line
			(start -0.32512 0.175006)
			(end -0.32512 -0.175006)
			(stroke
				(width 0.1)
				(type default)
			)
			(layer "F.Fab")
		)
		(fp_line
			(start 0.32512 -0.175006)
			(end 0.32512 0.175006)
			(stroke
				(width 0.1)
				(type default)
			)
			(layer "F.Fab")
		)
		(fp_line
			(start 0.32512 0.175006)
			(end -0.32512 0.175006)
			(stroke
				(width 0.1)
				(type default)
			)
			(layer "F.Fab")
		)
		(pad "1" smd rect
			(at -0.2667 0)
			(size 0.3048 0.381)
			(layers "F.Cu" "F.Mask" "F.Paste")
			(net "RXDET_BYP_RT_CPU1_P2")
		)
		(pad "2" smd rect
			(at 0.2667 0 180)
			(size 0.3048 0.381)
			(layers "F.Cu" "F.Mask" "F.Paste")
			(net "GND")
		)
	)
	(footprint ""
		(layer "F.Cu")
		(at 393.225782 -416.899344 -90)
		(property "Reference" "C6579"
			(at 0 0 270)
			(layer "F.SilkS")
			(hide yes)
			(effects
				(font
					(size 1.27 1.27)
				)
			)
		)
		(property "Value" ""
			(at 0 0 270)
			(layer "F.Fab")
			(effects
				(font
					(size 1.27 1.27)
				)
			)
		)
		(duplicate_pad_numbers_are_jumpers no)
		(fp_line
			(start -0.299974 0.150114)
			(end -0.299974 -0.150114)
			(stroke
				(width 0.1)
				(type default)
			)
			(layer "F.Fab")
		)
		(fp_line
			(start 0.299974 0.150114)
			(end -0.299974 0.150114)
			(stroke
				(width 0.1)
				(type default)
			)
			(layer "F.Fab")
		)
		(fp_line
			(start -0.299974 -0.150114)
			(end 0.299974 -0.150114)
			(stroke
				(width 0.1)
				(type default)
			)
			(layer "F.Fab")
		)
		(fp_line
			(start 0.299974 -0.150114)
			(end 0.299974 0.150114)
			(stroke
				(width 0.1)
				(type default)
			)
			(layer "F.Fab")
		)
		(pad "1" smd rect
			(at -0.2667 0 270)
			(size 0.3048 0.381)
			(layers "F.Cu" "F.Mask" "F.Paste")
			(net "P5E_CPU0_P2_TX_BUF_C_DP<7>")
		)
		(pad "2" smd rect
			(at 0.2667 0 270)
			(size 0.3048 0.381)
			(layers "F.Cu" "F.Mask" "F.Paste")
			(net "P5E_CPU0_P2_TX_BUF_DP<7>")
		)
	)
	(footprint ""
		(layer "F.Cu")
		(at 372.937278 -138.424158)
		(property "Reference" "R8300"
			(at 0 0 0)
			(layer "F.SilkS")
			(hide yes)
			(effects
				(font
					(size 1.27 1.27)
				)
			)
		)
		(property "Value" ""
			(at 0 0 0)
			(layer "F.Fab")
			(effects
				(font
					(size 1.27 1.27)
				)
			)
		)
		(duplicate_pad_numbers_are_jumpers no)
		(fp_line
			(start -0.7874 -0.4064)
			(end 0.7874 -0.4064)
			(stroke
				(width 0.1524)
				(type default)
			)
			(layer "F.SilkS")
		)
		(fp_line
			(start -0.7874 0.4064)
			(end -0.7874 -0.4064)
			(stroke
				(width 0.1524)
				(type default)
			)
			(layer "F.SilkS")
		)
		(fp_line
			(start 0.7874 -0.4064)
			(end 0.7874 0.4064)
			(stroke
				(width 0.1524)
				(type default)
			)
			(layer "F.SilkS")
		)
		(fp_line
			(start 0.7874 0.4064)
			(end -0.7874 0.4064)
			(stroke
				(width 0.1524)
				(type default)
			)
			(layer "F.SilkS")
		)
		(fp_line
			(start -0.67945 -0.305054)
			(end -0.12065 -0.305054)
			(stroke
				(width 0.1)
				(type default)
			)
			(layer "F.Fab")
		)
		(fp_line
			(start -0.67945 0.3048)
			(end -0.67945 -0.305054)
			(stroke
				(width 0.1)
				(type default)
			)
			(layer "F.Fab")
		)
		(fp_line
			(start -0.12065 -0.305054)
			(end -0.12065 -0.2794)
			(stroke
				(width 0.1)
				(type default)
			)
			(layer "F.Fab")
		)
		(fp_line
			(start -0.12065 -0.2794)
			(end 0.12065 -0.2794)
			(stroke
				(width 0.1)
				(type default)
			)
			(layer "F.Fab")
		)
		(fp_line
			(start -0.12065 0.2794)
			(end -0.12065 0.3048)
			(stroke
				(width 0.1)
				(type default)
			)
			(layer "F.Fab")
		)
		(fp_line
			(start -0.12065 0.3048)
			(end -0.67945 0.3048)
			(stroke
				(width 0.1)
				(type default)
			)
			(layer "F.Fab")
		)
		(fp_line
			(start 0.120396 0.2794)
			(end -0.12065 0.2794)
			(stroke
				(width 0.1)
				(type default)
			)
			(layer "F.Fab")
		)
		(fp_line
			(start 0.120396 0.3048)
			(end 0.120396 0.2794)
			(stroke
				(width 0.1)
				(type default)
			)
			(layer "F.Fab")
		)
		(fp_line
			(start 0.12065 -0.3048)
			(end 0.67945 -0.3048)
			(stroke
				(width 0.1)
				(type default)
			)
			(layer "F.Fab")
		)
		(fp_line
			(start 0.12065 -0.2794)
			(end 0.12065 -0.3048)
			(stroke
				(width 0.1)
				(type default)
			)
			(layer "F.Fab")
		)
		(fp_line
			(start 0.67945 -0.3048)
			(end 0.67945 0.3048)
			(stroke
				(width 0.1)
				(type default)
			)
			(layer "F.Fab")
		)
		(fp_line
			(start 0.67945 0.3048)
			(end 0.120396 0.3048)
			(stroke
				(width 0.1)
				(type default)
			)
			(layer "F.Fab")
		)
		(pad "1" smd circle
			(at -0.40005 0)
			(size 0 0)
			(layers "F.Cu" "F.Mask" "F.Paste")
			(net "P3V3_AUX")
		)
		(pad "2" smd circle
			(at 0.40005 0)
			(size 0 0)
			(layers "F.Cu" "F.Mask" "F.Paste")
			(net "PWRGD_PVDDCR_CPU0_P0_R")
		)
	)
	(footprint ""
		(layer "F.Cu")
		(at 288.87928 -394.985748 -90)
		(property "Reference" "C1072"
			(at 0 0 270)
			(layer "F.SilkS")
			(hide yes)
			(effects
				(font
					(size 1.27 1.27)
				)
			)
		)
		(property "Value" ""
			(at 0 0 270)
			(layer "F.Fab")
			(effects
				(font
					(size 1.27 1.27)
				)
			)
		)
		(duplicate_pad_numbers_are_jumpers no)
		(fp_line
			(start -0.299974 0.150114)
			(end -0.299974 -0.150114)
			(stroke
				(width 0.1)
				(type default)
			)
			(layer "F.Fab")
		)
		(fp_line
			(start 0.299974 0.150114)
			(end -0.299974 0.150114)
			(stroke
				(width 0.1)
				(type default)
			)
			(layer "F.Fab")
		)
		(fp_line
			(start -0.299974 -0.150114)
			(end 0.299974 -0.150114)
			(stroke
				(width 0.1)
				(type default)
			)
			(layer "F.Fab")
		)
		(fp_line
			(start 0.299974 -0.150114)
			(end 0.299974 0.150114)
			(stroke
				(width 0.1)
				(type default)
			)
			(layer "F.Fab")
		)
		(pad "1" smd rect
			(at -0.2667 0 270)
			(size 0.3048 0.381)
			(layers "F.Cu" "F.Mask" "F.Paste")
			(net "P3V3_AUX")
		)
		(pad "2" smd rect
			(at 0.2667 0 270)
			(size 0.3048 0.381)
			(layers "F.Cu" "F.Mask" "F.Paste")
			(net "GND")
		)
	)
	(footprint ""
		(layer "F.Cu")
		(at 352.05543 -433.841652 180)
		(property "Reference" "R4555"
			(at 0 0 180)
			(layer "F.SilkS")
			(hide yes)
			(effects
				(font
					(size 1.27 1.27)
				)
			)
		)
		(property "Value" ""
			(at 0 0 180)
			(layer "F.Fab")
			(effects
				(font
					(size 1.27 1.27)
				)
			)
		)
		(duplicate_pad_numbers_are_jumpers no)
		(fp_line
			(start 0.7874 0.4064)
			(end -0.7874 0.4064)
			(stroke
				(width 0.1524)
				(type default)
			)
			(layer "F.SilkS")
		)
		(fp_line
			(start 0.7874 -0.4064)
			(end 0.7874 0.4064)
			(stroke
				(width 0.1524)
				(type default)
			)
			(layer "F.SilkS")
		)
		(fp_line
			(start -0.7874 0.4064)
			(end -0.7874 -0.4064)
			(stroke
				(width 0.1524)
				(type default)
			)
			(layer "F.SilkS")
		)
		(fp_line
			(start -0.7874 -0.4064)
			(end 0.7874 -0.4064)
			(stroke
				(width 0.1524)
				(type default)
			)
			(layer "F.SilkS")
		)
		(fp_line
			(start 0.67945 0.3048)
			(end 0.120396 0.3048)
			(stroke
				(width 0.1)
				(type default)
			)
			(layer "F.Fab")
		)
		(fp_line
			(start 0.67945 -0.3048)
			(end 0.67945 0.3048)
			(stroke
				(width 0.1)
				(type default)
			)
			(layer "F.Fab")
		)
		(fp_line
			(start 0.12065 -0.2794)
			(end 0.12065 -0.3048)
			(stroke
				(width 0.1)
				(type default)
			)
			(layer "F.Fab")
		)
		(fp_line
			(start 0.12065 -0.3048)
			(end 0.67945 -0.3048)
			(stroke
				(width 0.1)
				(type default)
			)
			(layer "F.Fab")
		)
		(fp_line
			(start 0.120396 0.3048)
			(end 0.120396 0.2794)
			(stroke
				(width 0.1)
				(type default)
			)
			(layer "F.Fab")
		)
		(fp_line
			(start 0.120396 0.2794)
			(end -0.12065 0.2794)
			(stroke
				(width 0.1)
				(type default)
			)
			(layer "F.Fab")
		)
		(fp_line
			(start -0.12065 0.3048)
			(end -0.67945 0.3048)
			(stroke
				(width 0.1)
				(type default)
			)
			(layer "F.Fab")
		)
		(fp_line
			(start -0.12065 0.2794)
			(end -0.12065 0.3048)
			(stroke
				(width 0.1)
				(type default)
			)
			(layer "F.Fab")
		)
		(fp_line
			(start -0.12065 -0.2794)
			(end 0.12065 -0.2794)
			(stroke
				(width 0.1)
				(type default)
			)
			(layer "F.Fab")
		)
		(fp_line
			(start -0.12065 -0.305054)
			(end -0.12065 -0.2794)
			(stroke
				(width 0.1)
				(type default)
			)
			(layer "F.Fab")
		)
		(fp_line
			(start -0.67945 0.3048)
			(end -0.67945 -0.305054)
			(stroke
				(width 0.1)
				(type default)
			)
			(layer "F.Fab")
		)
		(fp_line
			(start -0.67945 -0.305054)
			(end -0.12065 -0.305054)
			(stroke
				(width 0.1)
				(type default)
			)
			(layer "F.Fab")
		)
		(pad "1" smd circle
			(at -0.40005 0 180)
			(size 0 0)
			(layers "F.Cu" "F.Mask" "F.Paste")
			(net "SWB_HSC_EN_BUF_R")
		)
		(pad "2" smd circle
			(at 0.40005 0 180)
			(size 0 0)
			(layers "F.Cu" "F.Mask" "F.Paste")
			(net "GND")
		)
	)
	(footprint ""
		(layer "F.Cu")
		(at 211.572348 -14.892528)
		(property "Reference" "C1275"
			(at 0 0 0)
			(layer "F.SilkS")
			(hide yes)
			(effects
				(font
					(size 1.27 1.27)
				)
			)
		)
		(property "Value" ""
			(at 0 0 0)
			(layer "F.Fab")
			(effects
				(font
					(size 1.27 1.27)
				)
			)
		)
		(duplicate_pad_numbers_are_jumpers no)
		(fp_line
			(start -0.7874 -0.4064)
			(end 0.7874 -0.4064)
			(stroke
				(width 0.1524)
				(type default)
			)
			(layer "F.SilkS")
		)
		(fp_line
			(start -0.7874 0.4064)
			(end -0.7874 -0.4064)
			(stroke
				(width 0.1524)
				(type default)
			)
			(layer "F.SilkS")
		)
		(fp_line
			(start 0.7874 -0.4064)
			(end 0.7874 0.4064)
			(stroke
				(width 0.1524)
				(type default)
			)
			(layer "F.SilkS")
		)
		(fp_line
			(start 0.7874 0.4064)
			(end -0.7874 0.4064)
			(stroke
				(width 0.1524)
				(type default)
			)
			(layer "F.SilkS")
		)
		(fp_line
			(start -0.67945 -0.305054)
			(end -0.12065 -0.305054)
			(stroke
				(width 0.1)
				(type default)
			)
			(layer "F.Fab")
		)
		(fp_line
			(start -0.67945 0.3048)
			(end -0.67945 -0.305054)
			(stroke
				(width 0.1)
				(type default)
			)
			(layer "F.Fab")
		)
		(fp_line
			(start -0.12065 -0.305054)
			(end -0.12065 -0.2794)
			(stroke
				(width 0.1)
				(type default)
			)
			(layer "F.Fab")
		)
		(fp_line
			(start -0.12065 -0.2794)
			(end 0.12065 -0.2794)
			(stroke
				(width 0.1)
				(type default)
			)
			(layer "F.Fab")
		)
		(fp_line
			(start -0.12065 0.2794)
			(end -0.12065 0.3048)
			(stroke
				(width 0.1)
				(type default)
			)
			(layer "F.Fab")
		)
		(fp_line
			(start -0.12065 0.3048)
			(end -0.67945 0.3048)
			(stroke
				(width 0.1)
				(type default)
			)
			(layer "F.Fab")
		)
		(fp_line
			(start 0.120396 0.2794)
			(end -0.12065 0.2794)
			(stroke
				(width 0.1)
				(type default)
			)
			(layer "F.Fab")
		)
		(fp_line
			(start 0.120396 0.3048)
			(end 0.120396 0.2794)
			(stroke
				(width 0.1)
				(type default)
			)
			(layer "F.Fab")
		)
		(fp_line
			(start 0.12065 -0.3048)
			(end 0.67945 -0.3048)
			(stroke
				(width 0.1)
				(type default)
			)
			(layer "F.Fab")
		)
		(fp_line
			(start 0.12065 -0.2794)
			(end 0.12065 -0.3048)
			(stroke
				(width 0.1)
				(type default)
			)
			(layer "F.Fab")
		)
		(fp_line
			(start 0.67945 -0.3048)
			(end 0.67945 0.3048)
			(stroke
				(width 0.1)
				(type default)
			)
			(layer "F.Fab")
		)
		(fp_line
			(start 0.67945 0.3048)
			(end 0.120396 0.3048)
			(stroke
				(width 0.1)
				(type default)
			)
			(layer "F.Fab")
		)
		(pad "1" smd circle
			(at -0.40005 0)
			(size 0 0)
			(layers "F.Cu" "F.Mask" "F.Paste")
			(net "P3V3_AUX")
		)
		(pad "2" smd circle
			(at 0.40005 0)
			(size 0 0)
			(layers "F.Cu" "F.Mask" "F.Paste")
			(net "GND")
		)
	)
	(footprint ""
		(layer "F.Cu")
		(at 286.0675 -409.277058 -90)
		(property "Reference" "Q6001"
			(at 1.861566 -2.29997 90)
			(unlocked yes)
			(layer "F.SilkS")
			(effects
				(font
					(size 0.7874 0.5842)
					(thickness 0.1524)
				)
				(justify left)
			)
		)
		(property "Value" ""
			(at 0 0 270)
			(layer "F.Fab")
			(effects
				(font
					(size 1.27 1.27)
				)
			)
		)
		(duplicate_pad_numbers_are_jumpers no)
		(fp_line
			(start -1.905 1.651)
			(end -1.905 -1.651)
			(stroke
				(width 0.1524)
				(type default)
			)
			(layer "F.SilkS")
		)
		(fp_line
			(start 1.905 1.651)
			(end -1.905 1.651)
			(stroke
				(width 0.1524)
				(type default)
			)
			(layer "F.SilkS")
		)
		(fp_line
			(start -1.905 -1.651)
			(end 1.905 -1.651)
			(stroke
				(width 0.1524)
				(type default)
			)
			(layer "F.SilkS")
		)
		(fp_line
			(start 1.905 -1.651)
			(end 1.905 1.651)
			(stroke
				(width 0.1524)
				(type default)
			)
			(layer "F.SilkS")
		)
		(fp_line
			(start -0.649986 1.524)
			(end -0.649986 1.169924)
			(stroke
				(width 0.1)
				(type default)
			)
			(layer "F.Fab")
		)
		(fp_line
			(start 0.6985 1.524)
			(end -0.649986 1.524)
			(stroke
				(width 0.1)
				(type default)
			)
			(layer "F.Fab")
		)
		(fp_line
			(start -1.249934 1.169924)
			(end -1.249934 0.729996)
			(stroke
				(width 0.1)
				(type default)
			)
			(layer "F.Fab")
		)
		(fp_line
			(start -0.649986 1.169924)
			(end -1.249934 1.169924)
			(stroke
				(width 0.1)
				(type default)
			)
			(layer "F.Fab")
		)
		(fp_line
			(start -1.249934 0.729996)
			(end -0.6985 0.729996)
			(stroke
				(width 0.1)
				(type default)
			)
			(layer "F.Fab")
		)
		(fp_line
			(start -0.6985 0.729996)
			(end -0.6985 -0.729996)
			(stroke
				(width 0.1)
				(type default)
			)
			(layer "F.Fab")
		)
		(fp_line
			(start 0.6985 0.219964)
			(end 0.6985 1.524)
			(stroke
				(width 0.1)
				(type default)
			)
			(layer "F.Fab")
		)
		(fp_line
			(start 1.249934 0.219964)
			(end 0.6985 0.219964)
			(stroke
				(width 0.1)
				(type default)
			)
			(layer "F.Fab")
		)
		(fp_line
			(start 0.6985 -0.219964)
			(end 1.249934 -0.219964)
			(stroke
				(width 0.1)
				(type default)
			)
			(layer "F.Fab")
		)
		(fp_line
			(start 1.249934 -0.219964)
			(end 1.249934 0.219964)
			(stroke
				(width 0.1)
				(type default)
			)
			(layer "F.Fab")
		)
		(fp_line
			(start -1.249934 -0.729996)
			(end -1.249934 -1.169924)
			(stroke
				(width 0.1)
				(type default)
			)
			(layer "F.Fab")
		)
		(fp_line
			(start -0.6985 -0.729996)
			(end -1.249934 -0.729996)
			(stroke
				(width 0.1)
				(type default)
			)
			(layer "F.Fab")
		)
		(fp_line
			(start -1.249934 -1.169924)
			(end -0.649986 -1.169924)
			(stroke
				(width 0.1)
				(type default)
			)
			(layer "F.Fab")
		)
		(fp_line
			(start -0.649986 -1.169924)
			(end -0.649986 -1.524)
			(stroke
				(width 0.1)
				(type default)
			)
			(layer "F.Fab")
		)
		(fp_line
			(start -0.649986 -1.524)
			(end 0.6985 -1.524)
			(stroke
				(width 0.1)
				(type default)
			)
			(layer "F.Fab")
		)
		(fp_line
			(start 0.6985 -1.524)
			(end 0.6985 -0.219964)
			(stroke
				(width 0.1)
				(type default)
			)
			(layer "F.Fab")
		)
		(pad "B" smd rect
			(at -1.1176 -1.016 180)
			(size 1.016 1.27)
			(layers "F.Cu" "F.Mask" "F.Paste")
			(net "P12V_HSC_TEMP_R")
		)
		(pad "C" smd rect
			(at 1.1176 0 180)
			(size 1.016 1.27)
			(layers "F.Cu" "F.Mask" "F.Paste")
			(net "P12V_HSC_TEMP_R")
		)
		(pad "E" smd rect
			(at -1.1176 1.016 180)
			(size 1.016 1.27)
			(layers "F.Cu" "F.Mask" "F.Paste")
			(net "P12V_HSC_TEMP_E")
		)
	)
	(footprint ""
		(layer "F.Cu")
		(at 220.190822 -57.851802 180)
		(property "Reference" "R3758"
			(at 0 0 180)
			(layer "F.SilkS")
			(hide yes)
			(effects
				(font
					(size 1.27 1.27)
				)
			)
		)
		(property "Value" ""
			(at 0 0 180)
			(layer "F.Fab")
			(effects
				(font
					(size 1.27 1.27)
				)
			)
		)
		(duplicate_pad_numbers_are_jumpers no)
		(fp_line
			(start 0.7874 0.4064)
			(end -0.7874 0.4064)
			(stroke
				(width 0.1524)
				(type default)
			)
			(layer "F.SilkS")
		)
		(fp_line
			(start 0.7874 -0.4064)
			(end 0.7874 0.4064)
			(stroke
				(width 0.1524)
				(type default)
			)
			(layer "F.SilkS")
		)
		(fp_line
			(start -0.7874 0.4064)
			(end -0.7874 -0.4064)
			(stroke
				(width 0.1524)
				(type default)
			)
			(layer "F.SilkS")
		)
		(fp_line
			(start -0.7874 -0.4064)
			(end 0.7874 -0.4064)
			(stroke
				(width 0.1524)
				(type default)
			)
			(layer "F.SilkS")
		)
		(fp_line
			(start 0.67945 0.3048)
			(end 0.120396 0.3048)
			(stroke
				(width 0.1)
				(type default)
			)
			(layer "F.Fab")
		)
		(fp_line
			(start 0.67945 -0.3048)
			(end 0.67945 0.3048)
			(stroke
				(width 0.1)
				(type default)
			)
			(layer "F.Fab")
		)
		(fp_line
			(start 0.12065 -0.2794)
			(end 0.12065 -0.3048)
			(stroke
				(width 0.1)
				(type default)
			)
			(layer "F.Fab")
		)
		(fp_line
			(start 0.12065 -0.3048)
			(end 0.67945 -0.3048)
			(stroke
				(width 0.1)
				(type default)
			)
			(layer "F.Fab")
		)
		(fp_line
			(start 0.120396 0.3048)
			(end 0.120396 0.2794)
			(stroke
				(width 0.1)
				(type default)
			)
			(layer "F.Fab")
		)
		(fp_line
			(start 0.120396 0.2794)
			(end -0.12065 0.2794)
			(stroke
				(width 0.1)
				(type default)
			)
			(layer "F.Fab")
		)
		(fp_line
			(start -0.12065 0.3048)
			(end -0.67945 0.3048)
			(stroke
				(width 0.1)
				(type default)
			)
			(layer "F.Fab")
		)
		(fp_line
			(start -0.12065 0.2794)
			(end -0.12065 0.3048)
			(stroke
				(width 0.1)
				(type default)
			)
			(layer "F.Fab")
		)
		(fp_line
			(start -0.12065 -0.2794)
			(end 0.12065 -0.2794)
			(stroke
				(width 0.1)
				(type default)
			)
			(layer "F.Fab")
		)
		(fp_line
			(start -0.12065 -0.305054)
			(end -0.12065 -0.2794)
			(stroke
				(width 0.1)
				(type default)
			)
			(layer "F.Fab")
		)
		(fp_line
			(start -0.67945 0.3048)
			(end -0.67945 -0.305054)
			(stroke
				(width 0.1)
				(type default)
			)
			(layer "F.Fab")
		)
		(fp_line
			(start -0.67945 -0.305054)
			(end -0.12065 -0.305054)
			(stroke
				(width 0.1)
				(type default)
			)
			(layer "F.Fab")
		)
		(pad "1" smd circle
			(at -0.40005 0 180)
			(size 0 0)
			(layers "F.Cu" "F.Mask" "F.Paste")
			(net "P3V3_E1S_0_R")
		)
		(pad "2" smd circle
			(at 0.40005 0 180)
			(size 0 0)
			(layers "F.Cu" "F.Mask" "F.Paste")
			(net "VSENSE_P3V3_INA230_2_INP")
		)
	)
	(footprint ""
		(layer "F.Cu")
		(at 21.81987 -385.91109 180)
		(property "Reference" "PC6641"
			(at 0 0 180)
			(layer "F.SilkS")
			(hide yes)
			(effects
				(font
					(size 1.27 1.27)
				)
			)
		)
		(property "Value" ""
			(at 0 0 180)
			(layer "F.Fab")
			(effects
				(font
					(size 1.27 1.27)
				)
			)
		)
		(duplicate_pad_numbers_are_jumpers no)
		(fp_line
			(start 0.7874 0.4064)
			(end -0.7874 0.4064)
			(stroke
				(width 0.1524)
				(type default)
			)
			(layer "F.SilkS")
		)
		(fp_line
			(start 0.7874 -0.4064)
			(end 0.7874 0.4064)
			(stroke
				(width 0.1524)
				(type default)
			)
			(layer "F.SilkS")
		)
		(fp_line
			(start -0.7874 0.4064)
			(end -0.7874 -0.4064)
			(stroke
				(width 0.1524)
				(type default)
			)
			(layer "F.SilkS")
		)
		(fp_line
			(start -0.7874 -0.4064)
			(end 0.7874 -0.4064)
			(stroke
				(width 0.1524)
				(type default)
			)
			(layer "F.SilkS")
		)
		(fp_line
			(start 0.67945 0.3048)
			(end 0.120396 0.3048)
			(stroke
				(width 0.1)
				(type default)
			)
			(layer "F.Fab")
		)
		(fp_line
			(start 0.67945 -0.3048)
			(end 0.67945 0.3048)
			(stroke
				(width 0.1)
				(type default)
			)
			(layer "F.Fab")
		)
		(fp_line
			(start 0.12065 -0.2794)
			(end 0.12065 -0.3048)
			(stroke
				(width 0.1)
				(type default)
			)
			(layer "F.Fab")
		)
		(fp_line
			(start 0.12065 -0.3048)
			(end 0.67945 -0.3048)
			(stroke
				(width 0.1)
				(type default)
			)
			(layer "F.Fab")
		)
		(fp_line
			(start 0.120396 0.3048)
			(end 0.120396 0.2794)
			(stroke
				(width 0.1)
				(type default)
			)
			(layer "F.Fab")
		)
		(fp_line
			(start 0.120396 0.2794)
			(end -0.12065 0.2794)
			(stroke
				(width 0.1)
				(type default)
			)
			(layer "F.Fab")
		)
		(fp_line
			(start -0.12065 0.3048)
			(end -0.67945 0.3048)
			(stroke
				(width 0.1)
				(type default)
			)
			(layer "F.Fab")
		)
		(fp_line
			(start -0.12065 0.2794)
			(end -0.12065 0.3048)
			(stroke
				(width 0.1)
				(type default)
			)
			(layer "F.Fab")
		)
		(fp_line
			(start -0.12065 -0.2794)
			(end 0.12065 -0.2794)
			(stroke
				(width 0.1)
				(type default)
			)
			(layer "F.Fab")
		)
		(fp_line
			(start -0.12065 -0.305054)
			(end -0.12065 -0.2794)
			(stroke
				(width 0.1)
				(type default)
			)
			(layer "F.Fab")
		)
		(fp_line
			(start -0.67945 0.3048)
			(end -0.67945 -0.305054)
			(stroke
				(width 0.1)
				(type default)
			)
			(layer "F.Fab")
		)
		(fp_line
			(start -0.67945 -0.305054)
			(end -0.12065 -0.305054)
			(stroke
				(width 0.1)
				(type default)
			)
			(layer "F.Fab")
		)
		(pad "1" smd circle
			(at -0.40005 0 180)
			(size 0 0)
			(layers "F.Cu" "F.Mask" "F.Paste")
			(net "SW_P0V9_RETIMER_CPU1_SW2")
		)
		(pad "2" smd circle
			(at 0.40005 0 180)
			(size 0 0)
			(layers "F.Cu" "F.Mask" "F.Paste")
			(net "SW_P0V9_RETIMER_CPU1_SW2_RC")
		)
	)
	(footprint ""
		(layer "F.Cu")
		(at 442.134752 -389.281416 90)
		(property "Reference" "PC6565"
			(at 0 0 90)
			(layer "F.SilkS")
			(hide yes)
			(effects
				(font
					(size 1.27 1.27)
				)
			)
		)
		(property "Value" ""
			(at 0 0 90)
			(layer "F.Fab")
			(effects
				(font
					(size 1.27 1.27)
				)
			)
		)
		(duplicate_pad_numbers_are_jumpers no)
		(fp_line
			(start 0.7874 -0.4064)
			(end 0.7874 0.4064)
			(stroke
				(width 0.1524)
				(type default)
			)
			(layer "F.SilkS")
		)
		(fp_line
			(start -0.7874 -0.4064)
			(end 0.7874 -0.4064)
			(stroke
				(width 0.1524)
				(type default)
			)
			(layer "F.SilkS")
		)
		(fp_line
			(start 0.7874 0.4064)
			(end -0.7874 0.4064)
			(stroke
				(width 0.1524)
				(type default)
			)
			(layer "F.SilkS")
		)
		(fp_line
			(start -0.7874 0.4064)
			(end -0.7874 -0.4064)
			(stroke
				(width 0.1524)
				(type default)
			)
			(layer "F.SilkS")
		)
		(fp_line
			(start -0.12065 -0.305054)
			(end -0.12065 -0.2794)
			(stroke
				(width 0.1)
				(type default)
			)
			(layer "F.Fab")
		)
		(fp_line
			(start -0.67945 -0.305054)
			(end -0.12065 -0.305054)
			(stroke
				(width 0.1)
				(type default)
			)
			(layer "F.Fab")
		)
		(fp_line
			(start 0.67945 -0.3048)
			(end 0.67945 0.3048)
			(stroke
				(width 0.1)
				(type default)
			)
			(layer "F.Fab")
		)
		(fp_line
			(start 0.12065 -0.3048)
			(end 0.67945 -0.3048)
			(stroke
				(width 0.1)
				(type default)
			)
			(layer "F.Fab")
		)
		(fp_line
			(start 0.12065 -0.2794)
			(end 0.12065 -0.3048)
			(stroke
				(width 0.1)
				(type default)
			)
			(layer "F.Fab")
		)
		(fp_line
			(start -0.12065 -0.2794)
			(end 0.12065 -0.2794)
			(stroke
				(width 0.1)
				(type default)
			)
			(layer "F.Fab")
		)
		(fp_line
			(start 0.120396 0.2794)
			(end -0.12065 0.2794)
			(stroke
				(width 0.1)
				(type default)
			)
			(layer "F.Fab")
		)
		(fp_line
			(start -0.12065 0.2794)
			(end -0.12065 0.3048)
			(stroke
				(width 0.1)
				(type default)
			)
			(layer "F.Fab")
		)
		(fp_line
			(start 0.67945 0.3048)
			(end 0.120396 0.3048)
			(stroke
				(width 0.1)
				(type default)
			)
			(layer "F.Fab")
		)
		(fp_line
			(start 0.120396 0.3048)
			(end 0.120396 0.2794)
			(stroke
				(width 0.1)
				(type default)
			)
			(layer "F.Fab")
		)
		(fp_line
			(start -0.12065 0.3048)
			(end -0.67945 0.3048)
			(stroke
				(width 0.1)
				(type default)
			)
			(layer "F.Fab")
		)
		(fp_line
			(start -0.67945 0.3048)
			(end -0.67945 -0.305054)
			(stroke
				(width 0.1)
				(type default)
			)
			(layer "F.Fab")
		)
		(pad "1" smd circle
			(at -0.40005 0 90)
			(size 0 0)
			(layers "F.Cu" "F.Mask" "F.Paste")
			(net "P0V9_CPU0_RT_2D")
		)
		(pad "2" smd circle
			(at 0.40005 0 90)
			(size 0 0)
			(layers "F.Cu" "F.Mask" "F.Paste")
			(net "GND")
		)
	)
	(footprint ""
		(layer "F.Cu")
		(at 221.28226 -98.11004 90)
		(property "Reference" "R1509"
			(at 0 0 90)
			(layer "F.SilkS")
			(hide yes)
			(effects
				(font
					(size 1.27 1.27)
				)
			)
		)
		(property "Value" ""
			(at 0 0 90)
			(layer "F.Fab")
			(effects
				(font
					(size 1.27 1.27)
				)
			)
		)
		(duplicate_pad_numbers_are_jumpers no)
		(fp_line
			(start 0.7874 -0.4064)
			(end 0.7874 0.4064)
			(stroke
				(width 0.1524)
				(type default)
			)
			(layer "F.SilkS")
		)
		(fp_line
			(start -0.7874 -0.4064)
			(end 0.7874 -0.4064)
			(stroke
				(width 0.1524)
				(type default)
			)
			(layer "F.SilkS")
		)
		(fp_line
			(start 0.7874 0.4064)
			(end -0.7874 0.4064)
			(stroke
				(width 0.1524)
				(type default)
			)
			(layer "F.SilkS")
		)
		(fp_line
			(start -0.7874 0.4064)
			(end -0.7874 -0.4064)
			(stroke
				(width 0.1524)
				(type default)
			)
			(layer "F.SilkS")
		)
		(fp_line
			(start -0.12065 -0.305054)
			(end -0.12065 -0.2794)
			(stroke
				(width 0.1)
				(type default)
			)
			(layer "F.Fab")
		)
		(fp_line
			(start -0.67945 -0.305054)
			(end -0.12065 -0.305054)
			(stroke
				(width 0.1)
				(type default)
			)
			(layer "F.Fab")
		)
		(fp_line
			(start 0.67945 -0.3048)
			(end 0.67945 0.3048)
			(stroke
				(width 0.1)
				(type default)
			)
			(layer "F.Fab")
		)
		(fp_line
			(start 0.12065 -0.3048)
			(end 0.67945 -0.3048)
			(stroke
				(width 0.1)
				(type default)
			)
			(layer "F.Fab")
		)
		(fp_line
			(start 0.12065 -0.2794)
			(end 0.12065 -0.3048)
			(stroke
				(width 0.1)
				(type default)
			)
			(layer "F.Fab")
		)
		(fp_line
			(start -0.12065 -0.2794)
			(end 0.12065 -0.2794)
			(stroke
				(width 0.1)
				(type default)
			)
			(layer "F.Fab")
		)
		(fp_line
			(start 0.120396 0.2794)
			(end -0.12065 0.2794)
			(stroke
				(width 0.1)
				(type default)
			)
			(layer "F.Fab")
		)
		(fp_line
			(start -0.12065 0.2794)
			(end -0.12065 0.3048)
			(stroke
				(width 0.1)
				(type default)
			)
			(layer "F.Fab")
		)
		(fp_line
			(start 0.67945 0.3048)
			(end 0.120396 0.3048)
			(stroke
				(width 0.1)
				(type default)
			)
			(layer "F.Fab")
		)
		(fp_line
			(start 0.120396 0.3048)
			(end 0.120396 0.2794)
			(stroke
				(width 0.1)
				(type default)
			)
			(layer "F.Fab")
		)
		(fp_line
			(start -0.12065 0.3048)
			(end -0.67945 0.3048)
			(stroke
				(width 0.1)
				(type default)
			)
			(layer "F.Fab")
		)
		(fp_line
			(start -0.67945 0.3048)
			(end -0.67945 -0.305054)
			(stroke
				(width 0.1)
				(type default)
			)
			(layer "F.Fab")
		)
		(pad "1" smd circle
			(at -0.40005 0 90)
			(size 0 0)
			(layers "F.Cu" "F.Mask" "F.Paste")
			(net "HP_LVC3_OCP_V3_1_P12V_PWRGD")
		)
		(pad "2" smd circle
			(at 0.40005 0 90)
			(size 0 0)
			(layers "F.Cu" "F.Mask" "F.Paste")
			(net "HP_LVC3_OCP_V3_1_P12V_R2_PWRGD")
		)
	)
	(footprint ""
		(layer "F.Cu")
		(at 346.653866 -416.899344 -90)
		(property "Reference" "C6530"
			(at 0 0 270)
			(layer "F.SilkS")
			(hide yes)
			(effects
				(font
					(size 1.27 1.27)
				)
			)
		)
		(property "Value" ""
			(at 0 0 270)
			(layer "F.Fab")
			(effects
				(font
					(size 1.27 1.27)
				)
			)
		)
		(duplicate_pad_numbers_are_jumpers no)
		(fp_line
			(start -0.299974 0.150114)
			(end -0.299974 -0.150114)
			(stroke
				(width 0.1)
				(type default)
			)
			(layer "F.Fab")
		)
		(fp_line
			(start 0.299974 0.150114)
			(end -0.299974 0.150114)
			(stroke
				(width 0.1)
				(type default)
			)
			(layer "F.Fab")
		)
		(fp_line
			(start -0.299974 -0.150114)
			(end 0.299974 -0.150114)
			(stroke
				(width 0.1)
				(type default)
			)
			(layer "F.Fab")
		)
		(fp_line
			(start 0.299974 -0.150114)
			(end 0.299974 0.150114)
			(stroke
				(width 0.1)
				(type default)
			)
			(layer "F.Fab")
		)
		(pad "1" smd rect
			(at -0.2667 0 270)
			(size 0.3048 0.381)
			(layers "F.Cu" "F.Mask" "F.Paste")
			(net "P5E_CPU0_P0_TX_BUF_C_DN<14>")
		)
		(pad "2" smd rect
			(at 0.2667 0 270)
			(size 0.3048 0.381)
			(layers "F.Cu" "F.Mask" "F.Paste")
			(net "P5E_CPU0_P0_TX_BUF_DN<14>")
		)
	)
	(footprint ""
		(layer "F.Cu")
		(at 169.1894 -333.375508)
		(property "Reference" "TP18"
			(at -2.305812 -5.26923 0)
			(unlocked yes)
			(layer "F.SilkS")
			(effects
				(font
					(size 0.7874 0.5842)
					(thickness 0.1524)
				)
				(justify left)
			)
		)
		(property "Value" ""
			(at 0 0 0)
			(layer "F.Fab")
			(effects
				(font
					(size 1.27 1.27)
				)
			)
		)
		(duplicate_pad_numbers_are_jumpers no)
		(pad "1" smd circle
			(at 0 0)
			(size 0.762 0.762)
			(layers "F.Cu" "F.Mask" "F.Paste")
			(net "VSENSE_PVDD11_S3_P1_DP")
		)
	)
	(footprint ""
		(layer "F.Cu")
		(at 178.689 -100.294948 90)
		(property "Reference" "R243"
			(at 0 0 90)
			(layer "F.SilkS")
			(hide yes)
			(effects
				(font
					(size 1.27 1.27)
				)
			)
		)
		(property "Value" ""
			(at 0 0 90)
			(layer "F.Fab")
			(effects
				(font
					(size 1.27 1.27)
				)
			)
		)
		(duplicate_pad_numbers_are_jumpers no)
		(fp_line
			(start 0.7874 -0.4064)
			(end 0.7874 0.4064)
			(stroke
				(width 0.1524)
				(type default)
			)
			(layer "F.SilkS")
		)
		(fp_line
			(start -0.7874 -0.4064)
			(end 0.7874 -0.4064)
			(stroke
				(width 0.1524)
				(type default)
			)
			(layer "F.SilkS")
		)
		(fp_line
			(start 0.7874 0.4064)
			(end -0.7874 0.4064)
			(stroke
				(width 0.1524)
				(type default)
			)
			(layer "F.SilkS")
		)
		(fp_line
			(start -0.7874 0.4064)
			(end -0.7874 -0.4064)
			(stroke
				(width 0.1524)
				(type default)
			)
			(layer "F.SilkS")
		)
		(fp_line
			(start -0.12065 -0.305054)
			(end -0.12065 -0.2794)
			(stroke
				(width 0.1)
				(type default)
			)
			(layer "F.Fab")
		)
		(fp_line
			(start -0.67945 -0.305054)
			(end -0.12065 -0.305054)
			(stroke
				(width 0.1)
				(type default)
			)
			(layer "F.Fab")
		)
		(fp_line
			(start 0.67945 -0.3048)
			(end 0.67945 0.3048)
			(stroke
				(width 0.1)
				(type default)
			)
			(layer "F.Fab")
		)
		(fp_line
			(start 0.12065 -0.3048)
			(end 0.67945 -0.3048)
			(stroke
				(width 0.1)
				(type default)
			)
			(layer "F.Fab")
		)
		(fp_line
			(start 0.12065 -0.2794)
			(end 0.12065 -0.3048)
			(stroke
				(width 0.1)
				(type default)
			)
			(layer "F.Fab")
		)
		(fp_line
			(start -0.12065 -0.2794)
			(end 0.12065 -0.2794)
			(stroke
				(width 0.1)
				(type default)
			)
			(layer "F.Fab")
		)
		(fp_line
			(start 0.120396 0.2794)
			(end -0.12065 0.2794)
			(stroke
				(width 0.1)
				(type default)
			)
			(layer "F.Fab")
		)
		(fp_line
			(start -0.12065 0.2794)
			(end -0.12065 0.3048)
			(stroke
				(width 0.1)
				(type default)
			)
			(layer "F.Fab")
		)
		(fp_line
			(start 0.67945 0.3048)
			(end 0.120396 0.3048)
			(stroke
				(width 0.1)
				(type default)
			)
			(layer "F.Fab")
		)
		(fp_line
			(start 0.120396 0.3048)
			(end 0.120396 0.2794)
			(stroke
				(width 0.1)
				(type default)
			)
			(layer "F.Fab")
		)
		(fp_line
			(start -0.12065 0.3048)
			(end -0.67945 0.3048)
			(stroke
				(width 0.1)
				(type default)
			)
			(layer "F.Fab")
		)
		(fp_line
			(start -0.67945 0.3048)
			(end -0.67945 -0.305054)
			(stroke
				(width 0.1)
				(type default)
			)
			(layer "F.Fab")
		)
		(pad "1" smd circle
			(at -0.40005 0 90)
			(size 0 0)
			(layers "F.Cu" "F.Mask" "F.Paste")
			(net "FM_SMM_CRASHDUMP")
		)
		(pad "2" smd circle
			(at 0.40005 0 90)
			(size 0 0)
			(layers "F.Cu" "F.Mask" "F.Paste")
			(net "FM_SMM_CRASHDUMP_R")
		)
	)
	(footprint ""
		(layer "F.Cu")
		(at 152.848818 -34.647632)
		(property "Reference" "R1180"
			(at 0 0 0)
			(layer "F.SilkS")
			(hide yes)
			(effects
				(font
					(size 1.27 1.27)
				)
			)
		)
		(property "Value" ""
			(at 0 0 0)
			(layer "F.Fab")
			(effects
				(font
					(size 1.27 1.27)
				)
			)
		)
		(duplicate_pad_numbers_are_jumpers no)
		(fp_line
			(start -0.7874 -0.4064)
			(end 0.7874 -0.4064)
			(stroke
				(width 0.1524)
				(type default)
			)
			(layer "F.SilkS")
		)
		(fp_line
			(start -0.7874 0.4064)
			(end -0.7874 -0.4064)
			(stroke
				(width 0.1524)
				(type default)
			)
			(layer "F.SilkS")
		)
		(fp_line
			(start 0.7874 -0.4064)
			(end 0.7874 0.4064)
			(stroke
				(width 0.1524)
				(type default)
			)
			(layer "F.SilkS")
		)
		(fp_line
			(start 0.7874 0.4064)
			(end -0.7874 0.4064)
			(stroke
				(width 0.1524)
				(type default)
			)
			(layer "F.SilkS")
		)
		(fp_line
			(start -0.67945 -0.305054)
			(end -0.12065 -0.305054)
			(stroke
				(width 0.1)
				(type default)
			)
			(layer "F.Fab")
		)
		(fp_line
			(start -0.67945 0.3048)
			(end -0.67945 -0.305054)
			(stroke
				(width 0.1)
				(type default)
			)
			(layer "F.Fab")
		)
		(fp_line
			(start -0.12065 -0.305054)
			(end -0.12065 -0.2794)
			(stroke
				(width 0.1)
				(type default)
			)
			(layer "F.Fab")
		)
		(fp_line
			(start -0.12065 -0.2794)
			(end 0.12065 -0.2794)
			(stroke
				(width 0.1)
				(type default)
			)
			(layer "F.Fab")
		)
		(fp_line
			(start -0.12065 0.2794)
			(end -0.12065 0.3048)
			(stroke
				(width 0.1)
				(type default)
			)
			(layer "F.Fab")
		)
		(fp_line
			(start -0.12065 0.3048)
			(end -0.67945 0.3048)
			(stroke
				(width 0.1)
				(type default)
			)
			(layer "F.Fab")
		)
		(fp_line
			(start 0.120396 0.2794)
			(end -0.12065 0.2794)
			(stroke
				(width 0.1)
				(type default)
			)
			(layer "F.Fab")
		)
		(fp_line
			(start 0.120396 0.3048)
			(end 0.120396 0.2794)
			(stroke
				(width 0.1)
				(type default)
			)
			(layer "F.Fab")
		)
		(fp_line
			(start 0.12065 -0.3048)
			(end 0.67945 -0.3048)
			(stroke
				(width 0.1)
				(type default)
			)
			(layer "F.Fab")
		)
		(fp_line
			(start 0.12065 -0.2794)
			(end 0.12065 -0.3048)
			(stroke
				(width 0.1)
				(type default)
			)
			(layer "F.Fab")
		)
		(fp_line
			(start 0.67945 -0.3048)
			(end 0.67945 0.3048)
			(stroke
				(width 0.1)
				(type default)
			)
			(layer "F.Fab")
		)
		(fp_line
			(start 0.67945 0.3048)
			(end 0.120396 0.3048)
			(stroke
				(width 0.1)
				(type default)
			)
			(layer "F.Fab")
		)
		(pad "1" smd circle
			(at -0.40005 0)
			(size 0 0)
			(layers "F.Cu" "F.Mask" "F.Paste")
			(net "HP_LVC3_OCP_V3_2_R_EN")
		)
		(pad "2" smd circle
			(at 0.40005 0)
			(size 0 0)
			(layers "F.Cu" "F.Mask" "F.Paste")
			(net "HP_LVC3_OCP_V3_2_P12V_PWRGD")
		)
	)
	(footprint ""
		(layer "F.Cu")
		(at 331.653642 -142.293086 180)
		(property "Reference" "PR448"
			(at 0 0 180)
			(layer "F.SilkS")
			(hide yes)
			(effects
				(font
					(size 1.27 1.27)
				)
			)
		)
		(property "Value" ""
			(at 0 0 180)
			(layer "F.Fab")
			(effects
				(font
					(size 1.27 1.27)
				)
			)
		)
		(duplicate_pad_numbers_are_jumpers no)
		(fp_line
			(start 0.7874 0.4064)
			(end -0.7874 0.4064)
			(stroke
				(width 0.1524)
				(type default)
			)
			(layer "F.SilkS")
		)
		(fp_line
			(start 0.7874 -0.4064)
			(end 0.7874 0.4064)
			(stroke
				(width 0.1524)
				(type default)
			)
			(layer "F.SilkS")
		)
		(fp_line
			(start -0.7874 0.4064)
			(end -0.7874 -0.4064)
			(stroke
				(width 0.1524)
				(type default)
			)
			(layer "F.SilkS")
		)
		(fp_line
			(start -0.7874 -0.4064)
			(end 0.7874 -0.4064)
			(stroke
				(width 0.1524)
				(type default)
			)
			(layer "F.SilkS")
		)
		(fp_line
			(start 0.67945 0.3048)
			(end 0.120396 0.3048)
			(stroke
				(width 0.1)
				(type default)
			)
			(layer "F.Fab")
		)
		(fp_line
			(start 0.67945 -0.3048)
			(end 0.67945 0.3048)
			(stroke
				(width 0.1)
				(type default)
			)
			(layer "F.Fab")
		)
		(fp_line
			(start 0.12065 -0.2794)
			(end 0.12065 -0.3048)
			(stroke
				(width 0.1)
				(type default)
			)
			(layer "F.Fab")
		)
		(fp_line
			(start 0.12065 -0.3048)
			(end 0.67945 -0.3048)
			(stroke
				(width 0.1)
				(type default)
			)
			(layer "F.Fab")
		)
		(fp_line
			(start 0.120396 0.3048)
			(end 0.120396 0.2794)
			(stroke
				(width 0.1)
				(type default)
			)
			(layer "F.Fab")
		)
		(fp_line
			(start 0.120396 0.2794)
			(end -0.12065 0.2794)
			(stroke
				(width 0.1)
				(type default)
			)
			(layer "F.Fab")
		)
		(fp_line
			(start -0.12065 0.3048)
			(end -0.67945 0.3048)
			(stroke
				(width 0.1)
				(type default)
			)
			(layer "F.Fab")
		)
		(fp_line
			(start -0.12065 0.2794)
			(end -0.12065 0.3048)
			(stroke
				(width 0.1)
				(type default)
			)
			(layer "F.Fab")
		)
		(fp_line
			(start -0.12065 -0.2794)
			(end 0.12065 -0.2794)
			(stroke
				(width 0.1)
				(type default)
			)
			(layer "F.Fab")
		)
		(fp_line
			(start -0.12065 -0.305054)
			(end -0.12065 -0.2794)
			(stroke
				(width 0.1)
				(type default)
			)
			(layer "F.Fab")
		)
		(fp_line
			(start -0.67945 0.3048)
			(end -0.67945 -0.305054)
			(stroke
				(width 0.1)
				(type default)
			)
			(layer "F.Fab")
		)
		(fp_line
			(start -0.67945 -0.305054)
			(end -0.12065 -0.305054)
			(stroke
				(width 0.1)
				(type default)
			)
			(layer "F.Fab")
		)
		(pad "1" smd circle
			(at -0.40005 0 180)
			(size 0 0)
			(layers "F.Cu" "F.Mask" "F.Paste")
			(net "PVDD18_S5_P0_CS")
		)
		(pad "2" smd circle
			(at 0.40005 0 180)
			(size 0 0)
			(layers "F.Cu" "F.Mask" "F.Paste")
			(net "GND")
		)
	)
	(footprint ""
		(layer "F.Cu")
		(at 329.355958 -194.052952 -90)
		(property "Reference" "R357"
			(at 0 0 270)
			(layer "F.SilkS")
			(hide yes)
			(effects
				(font
					(size 1.27 1.27)
				)
			)
		)
		(property "Value" ""
			(at 0 0 270)
			(layer "F.Fab")
			(effects
				(font
					(size 1.27 1.27)
				)
			)
		)
		(duplicate_pad_numbers_are_jumpers no)
		(fp_line
			(start -0.7874 0.4064)
			(end -0.7874 -0.4064)
			(stroke
				(width 0.1524)
				(type default)
			)
			(layer "F.SilkS")
		)
		(fp_line
			(start 0.7874 0.4064)
			(end -0.7874 0.4064)
			(stroke
				(width 0.1524)
				(type default)
			)
			(layer "F.SilkS")
		)
		(fp_line
			(start -0.7874 -0.4064)
			(end 0.7874 -0.4064)
			(stroke
				(width 0.1524)
				(type default)
			)
			(layer "F.SilkS")
		)
		(fp_line
			(start 0.7874 -0.4064)
			(end 0.7874 0.4064)
			(stroke
				(width 0.1524)
				(type default)
			)
			(layer "F.SilkS")
		)
		(fp_line
			(start -0.67945 0.3048)
			(end -0.67945 -0.305054)
			(stroke
				(width 0.1)
				(type default)
			)
			(layer "F.Fab")
		)
		(fp_line
			(start -0.12065 0.3048)
			(end -0.67945 0.3048)
			(stroke
				(width 0.1)
				(type default)
			)
			(layer "F.Fab")
		)
		(fp_line
			(start 0.120396 0.3048)
			(end 0.120396 0.2794)
			(stroke
				(width 0.1)
				(type default)
			)
			(layer "F.Fab")
		)
		(fp_line
			(start 0.67945 0.3048)
			(end 0.120396 0.3048)
			(stroke
				(width 0.1)
				(type default)
			)
			(layer "F.Fab")
		)
		(fp_line
			(start -0.12065 0.2794)
			(end -0.12065 0.3048)
			(stroke
				(width 0.1)
				(type default)
			)
			(layer "F.Fab")
		)
		(fp_line
			(start 0.120396 0.2794)
			(end -0.12065 0.2794)
			(stroke
				(width 0.1)
				(type default)
			)
			(layer "F.Fab")
		)
		(fp_line
			(start -0.12065 -0.2794)
			(end 0.12065 -0.2794)
			(stroke
				(width 0.1)
				(type default)
			)
			(layer "F.Fab")
		)
		(fp_line
			(start 0.12065 -0.2794)
			(end 0.12065 -0.3048)
			(stroke
				(width 0.1)
				(type default)
			)
			(layer "F.Fab")
		)
		(fp_line
			(start 0.12065 -0.3048)
			(end 0.67945 -0.3048)
			(stroke
				(width 0.1)
				(type default)
			)
			(layer "F.Fab")
		)
		(fp_line
			(start 0.67945 -0.3048)
			(end 0.67945 0.3048)
			(stroke
				(width 0.1)
				(type default)
			)
			(layer "F.Fab")
		)
		(fp_line
			(start -0.67945 -0.305054)
			(end -0.12065 -0.305054)
			(stroke
				(width 0.1)
				(type default)
			)
			(layer "F.Fab")
		)
		(fp_line
			(start -0.12065 -0.305054)
			(end -0.12065 -0.2794)
			(stroke
				(width 0.1)
				(type default)
			)
			(layer "F.Fab")
		)
		(pad "1" smd circle
			(at -0.40005 0 270)
			(size 0 0)
			(layers "F.Cu" "F.Mask" "F.Paste")
			(net "CPU0_XTRIG_R2_L7")
		)
		(pad "2" smd circle
			(at 0.40005 0 270)
			(size 0 0)
			(layers "F.Cu" "F.Mask" "F.Paste")
			(net "CPU0_XTRIG_L7")
		)
	)
	(footprint ""
		(layer "F.Cu")
		(at 205.25105 -107.362498)
		(property "Reference" "C5016"
			(at 0 0 0)
			(layer "F.SilkS")
			(hide yes)
			(effects
				(font
					(size 1.27 1.27)
				)
			)
		)
		(property "Value" ""
			(at 0 0 0)
			(layer "F.Fab")
			(effects
				(font
					(size 1.27 1.27)
				)
			)
		)
		(duplicate_pad_numbers_are_jumpers no)
		(fp_line
			(start -0.7874 -0.4064)
			(end 0.7874 -0.4064)
			(stroke
				(width 0.1524)
				(type default)
			)
			(layer "F.SilkS")
		)
		(fp_line
			(start -0.7874 0.4064)
			(end -0.7874 -0.4064)
			(stroke
				(width 0.1524)
				(type default)
			)
			(layer "F.SilkS")
		)
		(fp_line
			(start 0.7874 -0.4064)
			(end 0.7874 0.4064)
			(stroke
				(width 0.1524)
				(type default)
			)
			(layer "F.SilkS")
		)
		(fp_line
			(start 0.7874 0.4064)
			(end -0.7874 0.4064)
			(stroke
				(width 0.1524)
				(type default)
			)
			(layer "F.SilkS")
		)
		(fp_line
			(start -0.67945 -0.305054)
			(end -0.12065 -0.305054)
			(stroke
				(width 0.1)
				(type default)
			)
			(layer "F.Fab")
		)
		(fp_line
			(start -0.67945 0.3048)
			(end -0.67945 -0.305054)
			(stroke
				(width 0.1)
				(type default)
			)
			(layer "F.Fab")
		)
		(fp_line
			(start -0.12065 -0.305054)
			(end -0.12065 -0.2794)
			(stroke
				(width 0.1)
				(type default)
			)
			(layer "F.Fab")
		)
		(fp_line
			(start -0.12065 -0.2794)
			(end 0.12065 -0.2794)
			(stroke
				(width 0.1)
				(type default)
			)
			(layer "F.Fab")
		)
		(fp_line
			(start -0.12065 0.2794)
			(end -0.12065 0.3048)
			(stroke
				(width 0.1)
				(type default)
			)
			(layer "F.Fab")
		)
		(fp_line
			(start -0.12065 0.3048)
			(end -0.67945 0.3048)
			(stroke
				(width 0.1)
				(type default)
			)
			(layer "F.Fab")
		)
		(fp_line
			(start 0.120396 0.2794)
			(end -0.12065 0.2794)
			(stroke
				(width 0.1)
				(type default)
			)
			(layer "F.Fab")
		)
		(fp_line
			(start 0.120396 0.3048)
			(end 0.120396 0.2794)
			(stroke
				(width 0.1)
				(type default)
			)
			(layer "F.Fab")
		)
		(fp_line
			(start 0.12065 -0.3048)
			(end 0.67945 -0.3048)
			(stroke
				(width 0.1)
				(type default)
			)
			(layer "F.Fab")
		)
		(fp_line
			(start 0.12065 -0.2794)
			(end 0.12065 -0.3048)
			(stroke
				(width 0.1)
				(type default)
			)
			(layer "F.Fab")
		)
		(fp_line
			(start 0.67945 -0.3048)
			(end 0.67945 0.3048)
			(stroke
				(width 0.1)
				(type default)
			)
			(layer "F.Fab")
		)
		(fp_line
			(start 0.67945 0.3048)
			(end 0.120396 0.3048)
			(stroke
				(width 0.1)
				(type default)
			)
			(layer "F.Fab")
		)
		(pad "1" smd circle
			(at -0.40005 0)
			(size 0 0)
			(layers "F.Cu" "F.Mask" "F.Paste")
			(net "PWRGD_PVDD18_S5_R_P1")
		)
		(pad "2" smd circle
			(at 0.40005 0)
			(size 0 0)
			(layers "F.Cu" "F.Mask" "F.Paste")
			(net "GND")
		)
	)
	(footprint ""
		(layer "F.Cu")
		(at 398.069562 -397.726154 180)
		(property "Reference" "R1413"
			(at 0 0 180)
			(layer "F.SilkS")
			(hide yes)
			(effects
				(font
					(size 1.27 1.27)
				)
			)
		)
		(property "Value" ""
			(at 0 0 180)
			(layer "F.Fab")
			(effects
				(font
					(size 1.27 1.27)
				)
			)
		)
		(duplicate_pad_numbers_are_jumpers no)
		(fp_line
			(start 0.32512 0.175006)
			(end -0.32512 0.175006)
			(stroke
				(width 0.1)
				(type default)
			)
			(layer "F.Fab")
		)
		(fp_line
			(start 0.32512 -0.175006)
			(end 0.32512 0.175006)
			(stroke
				(width 0.1)
				(type default)
			)
			(layer "F.Fab")
		)
		(fp_line
			(start -0.32512 0.175006)
			(end -0.32512 -0.175006)
			(stroke
				(width 0.1)
				(type default)
			)
			(layer "F.Fab")
		)
		(fp_line
			(start -0.32512 -0.175006)
			(end 0.32512 -0.175006)
			(stroke
				(width 0.1)
				(type default)
			)
			(layer "F.Fab")
		)
		(pad "1" smd rect
			(at -0.2667 0 180)
			(size 0.3048 0.381)
			(layers "F.Cu" "F.Mask" "F.Paste")
			(net "P1V8_CPU0_RT_1D")
		)
		(pad "2" smd rect
			(at 0.2667 0)
			(size 0.3048 0.381)
			(layers "F.Cu" "F.Mask" "F.Paste")
			(net "RXDET_BYP_RT_CPU0_P3")
		)
	)
	(footprint ""
		(layer "F.Cu")
		(at 299.543724 -395.066774 -90)
		(property "Reference" "R623"
			(at 0 0 270)
			(layer "F.SilkS")
			(hide yes)
			(effects
				(font
					(size 1.27 1.27)
				)
			)
		)
		(property "Value" ""
			(at 0 0 270)
			(layer "F.Fab")
			(effects
				(font
					(size 1.27 1.27)
				)
			)
		)
		(duplicate_pad_numbers_are_jumpers no)
		(fp_line
			(start -0.32512 0.175006)
			(end -0.32512 -0.175006)
			(stroke
				(width 0.1)
				(type default)
			)
			(layer "F.Fab")
		)
		(fp_line
			(start 0.32512 0.175006)
			(end -0.32512 0.175006)
			(stroke
				(width 0.1)
				(type default)
			)
			(layer "F.Fab")
		)
		(fp_line
			(start -0.32512 -0.175006)
			(end 0.32512 -0.175006)
			(stroke
				(width 0.1)
				(type default)
			)
			(layer "F.Fab")
		)
		(fp_line
			(start 0.32512 -0.175006)
			(end 0.32512 0.175006)
			(stroke
				(width 0.1)
				(type default)
			)
			(layer "F.Fab")
		)
		(pad "1" smd rect
			(at -0.2667 0 270)
			(size 0.3048 0.381)
			(layers "F.Cu" "F.Mask" "F.Paste")
			(net "CLK_100M_RETIMER_CPU0_P0_DN")
		)
		(pad "2" smd rect
			(at 0.2667 0 90)
			(size 0.3048 0.381)
			(layers "F.Cu" "F.Mask" "F.Paste")
			(net "GND")
		)
	)
	(footprint ""
		(layer "F.Cu")
		(at 440.78525 6.149848 180)
		(property "Reference" "J66"
			(at -4.541266 -1.222756 90)
			(unlocked yes)
			(layer "F.SilkS")
			(effects
				(font
					(size 0.7874 0.5842)
					(thickness 0.1524)
				)
				(justify left)
			)
		)
		(property "Value" ""
			(at 0 0 180)
			(layer "F.Fab")
			(effects
				(font
					(size 1.27 1.27)
				)
			)
		)
		(duplicate_pad_numbers_are_jumpers no)
		(fp_line
			(start 1.2192 2.06756)
			(end -1.2192 2.06756)
			(stroke
				(width 0.1524)
				(type default)
			)
			(layer "F.SilkS")
		)
		(fp_line
			(start 1.2192 -2.06756)
			(end 1.2192 2.06756)
			(stroke
				(width 0.1524)
				(type default)
			)
			(layer "F.SilkS")
		)
		(fp_line
			(start -1.2192 2.06756)
			(end -1.2192 -2.06756)
			(stroke
				(width 0.1524)
				(type default)
			)
			(layer "F.SilkS")
		)
		(fp_line
			(start -1.2192 -2.06756)
			(end 1.2192 -2.06756)
			(stroke
				(width 0.1524)
				(type default)
			)
			(layer "F.SilkS")
		)
		(pad "" np_thru_hole circle
			(at -2.8829 -1.27 90)
			(size 1.0414 1.0414)
			(drill 1.0414)
			(layers "*.Cu" "*.Mask")
			(clearance 0.381)
			(thermal_gap 0.381)
		)
		(pad "" np_thru_hole circle
			(at -2.8829 1.27 90)
			(size 1.0414 1.0414)
			(drill 1.0414)
			(layers "*.Cu" "*.Mask")
			(clearance 0.381)
			(thermal_gap 0.381)
		)
		(pad "" np_thru_hole circle
			(at 3.4671 -1.27 90)
			(size 1.0414 1.0414)
			(drill 1.0414)
			(layers "*.Cu" "*.Mask")
			(clearance 0.381)
			(thermal_gap 0.381)
		)
		(pad "" np_thru_hole circle
			(at 3.4671 1.27 90)
			(size 1.0414 1.0414)
			(drill 1.0414)
			(layers "*.Cu" "*.Mask")
			(clearance 0.381)
			(thermal_gap 0.381)
		)
		(pad "1" smd rect
			(at 0.8255 -0.249936 90)
			(size 0.3048 0.508)
			(layers "F.Cu" "F.Mask" "F.Paste")
			(net "DELTA_L_85_5INCH_IN2_DP")
		)
		(pad "2" smd rect
			(at 0.8255 0.249936 90)
			(size 0.3048 0.508)
			(layers "F.Cu" "F.Mask" "F.Paste")
			(net "DELTA_L_85_5INCH_IN2_DN")
		)
		(pad "3" smd circle
			(at 0 0 180)
			(size 0 0)
			(layers "F.Cu" "F.Mask" "F.Paste")
			(net "DELTA_L_GND_1")
		)
		(zone
			(layer "F.Cu")
			(hatch none 0.5)
			(connect_pads
				(clearance 0)
			)
			(min_thickness 0.25)
			(keepout
				(tracks not_allowed)
				(vias allowed)
				(pads allowed)
				(copperpour not_allowed)
				(footprints allowed)
			)
			(placement
				(enabled no)
				(sheetname "")
			)
			(fill
				(thermal_gap 0.5)
				(thermal_bridge_width 0.5)
				(island_removal_mode 0)
			)
			(polygon
				(pts
					(xy 439.66765 6.698488) (xy 439.66765 6.602984) (xy 440.26455 6.602984) (xy 440.26455 6.196584)
					(xy 439.66765 6.196584) (xy 439.66765 6.103112) (xy 440.26455 6.103112) (xy 440.26455 5.696712)
					(xy 439.66765 5.696712) (xy 439.66765 5.601208) (xy 440.36615 5.601208) (xy 440.36615 6.698488)
				)
			)
		)
		(zone
			(layers "F.Cu" "B.Cu" "In1.Cu" "In2.Cu" "In3.Cu" "In4.Cu" "In5.Cu" "In6.Cu"
				"In7.Cu" "In8.Cu" "In9.Cu" "In10.Cu" "In11.Cu" "In12.Cu" "In13.Cu" "In14.Cu"
				"In15.Cu" "In16.Cu"
			)
			(hatch none 0.5)
			(connect_pads
				(clearance 0)
			)
			(min_thickness 0.25)
			(keepout
				(tracks not_allowed)
				(vias allowed)
				(pads allowed)
				(copperpour not_allowed)
				(footprints allowed)
			)
			(placement
				(enabled no)
				(sheetname "")
			)
			(fill
				(thermal_gap 0.5)
				(thermal_bridge_width 0.5)
				(island_removal_mode 0)
			)
			(polygon
				(pts
					(arc
						(start 438.24525 4.879848)
						(mid 436.39105 4.879848)
						(end 438.24525 4.879848)
					)
				)
			)
		)
		(zone
			(layers "F.Cu" "B.Cu" "In1.Cu" "In2.Cu" "In3.Cu" "In4.Cu" "In5.Cu" "In6.Cu"
				"In7.Cu" "In8.Cu" "In9.Cu" "In10.Cu" "In11.Cu" "In12.Cu" "In13.Cu" "In14.Cu"
				"In15.Cu" "In16.Cu"
			)
			(hatch none 0.5)
			(connect_pads
				(clearance 0)
			)
			(min_thickness 0.25)
			(keepout
				(tracks not_allowed)
				(vias allowed)
				(pads allowed)
				(copperpour not_allowed)
				(footprints allowed)
			)
			(placement
				(enabled no)
				(sheetname "")
			)
			(fill
				(thermal_gap 0.5)
				(thermal_bridge_width 0.5)
				(island_removal_mode 0)
			)
			(polygon
				(pts
					(arc
						(start 438.24525 7.419848)
						(mid 436.39105 7.419848)
						(end 438.24525 7.419848)
					)
				)
			)
		)
		(zone
			(layers "F.Cu" "B.Cu" "In1.Cu" "In2.Cu" "In3.Cu" "In4.Cu" "In5.Cu" "In6.Cu"
				"In7.Cu" "In8.Cu" "In9.Cu" "In10.Cu" "In11.Cu" "In12.Cu" "In13.Cu" "In14.Cu"
				"In15.Cu" "In16.Cu"
			)
			(hatch none 0.5)
			(connect_pads
				(clearance 0)
			)
			(min_thickness 0.25)
			(keepout
				(tracks not_allowed)
				(vias allowed)
				(pads allowed)
				(copperpour not_allowed)
				(footprints allowed)
			)
			(placement
				(enabled no)
				(sheetname "")
			)
			(fill
				(thermal_gap 0.5)
				(thermal_bridge_width 0.5)
				(island_removal_mode 0)
			)
			(polygon
				(pts
					(arc
						(start 444.59525 4.879848)
						(mid 442.74105 4.879848)
						(end 444.59525 4.879848)
					)
				)
			)
		)
		(zone
			(layers "F.Cu" "B.Cu" "In1.Cu" "In2.Cu" "In3.Cu" "In4.Cu" "In5.Cu" "In6.Cu"
				"In7.Cu" "In8.Cu" "In9.Cu" "In10.Cu" "In11.Cu" "In12.Cu" "In13.Cu" "In14.Cu"
				"In15.Cu" "In16.Cu"
			)
			(hatch none 0.5)
			(connect_pads
				(clearance 0)
			)
			(min_thickness 0.25)
			(keepout
				(tracks not_allowed)
				(vias allowed)
				(pads allowed)
				(copperpour not_allowed)
				(footprints allowed)
			)
			(placement
				(enabled no)
				(sheetname "")
			)
			(fill
				(thermal_gap 0.5)
				(thermal_bridge_width 0.5)
				(island_removal_mode 0)
			)
			(polygon
				(pts
					(arc
						(start 444.59525 7.419848)
						(mid 442.74105 7.419848)
						(end 444.59525 7.419848)
					)
				)
			)
		)
	)
	(footprint ""
		(layer "F.Cu")
		(at 50.20183 -33.575498 90)
		(property "Reference" "R3205"
			(at 0 0 90)
			(layer "F.SilkS")
			(hide yes)
			(effects
				(font
					(size 1.27 1.27)
				)
			)
		)
		(property "Value" ""
			(at 0 0 90)
			(layer "F.Fab")
			(effects
				(font
					(size 1.27 1.27)
				)
			)
		)
		(duplicate_pad_numbers_are_jumpers no)
		(fp_line
			(start 0.7874 -0.4064)
			(end 0.7874 0.4064)
			(stroke
				(width 0.1524)
				(type default)
			)
			(layer "F.SilkS")
		)
		(fp_line
			(start -0.7874 -0.4064)
			(end 0.7874 -0.4064)
			(stroke
				(width 0.1524)
				(type default)
			)
			(layer "F.SilkS")
		)
		(fp_line
			(start 0.7874 0.4064)
			(end -0.7874 0.4064)
			(stroke
				(width 0.1524)
				(type default)
			)
			(layer "F.SilkS")
		)
		(fp_line
			(start -0.7874 0.4064)
			(end -0.7874 -0.4064)
			(stroke
				(width 0.1524)
				(type default)
			)
			(layer "F.SilkS")
		)
		(fp_line
			(start -0.12065 -0.305054)
			(end -0.12065 -0.2794)
			(stroke
				(width 0.1)
				(type default)
			)
			(layer "F.Fab")
		)
		(fp_line
			(start -0.67945 -0.305054)
			(end -0.12065 -0.305054)
			(stroke
				(width 0.1)
				(type default)
			)
			(layer "F.Fab")
		)
		(fp_line
			(start 0.67945 -0.3048)
			(end 0.67945 0.3048)
			(stroke
				(width 0.1)
				(type default)
			)
			(layer "F.Fab")
		)
		(fp_line
			(start 0.12065 -0.3048)
			(end 0.67945 -0.3048)
			(stroke
				(width 0.1)
				(type default)
			)
			(layer "F.Fab")
		)
		(fp_line
			(start 0.12065 -0.2794)
			(end 0.12065 -0.3048)
			(stroke
				(width 0.1)
				(type default)
			)
			(layer "F.Fab")
		)
		(fp_line
			(start -0.12065 -0.2794)
			(end 0.12065 -0.2794)
			(stroke
				(width 0.1)
				(type default)
			)
			(layer "F.Fab")
		)
		(fp_line
			(start 0.120396 0.2794)
			(end -0.12065 0.2794)
			(stroke
				(width 0.1)
				(type default)
			)
			(layer "F.Fab")
		)
		(fp_line
			(start -0.12065 0.2794)
			(end -0.12065 0.3048)
			(stroke
				(width 0.1)
				(type default)
			)
			(layer "F.Fab")
		)
		(fp_line
			(start 0.67945 0.3048)
			(end 0.120396 0.3048)
			(stroke
				(width 0.1)
				(type default)
			)
			(layer "F.Fab")
		)
		(fp_line
			(start 0.120396 0.3048)
			(end 0.120396 0.2794)
			(stroke
				(width 0.1)
				(type default)
			)
			(layer "F.Fab")
		)
		(fp_line
			(start -0.12065 0.3048)
			(end -0.67945 0.3048)
			(stroke
				(width 0.1)
				(type default)
			)
			(layer "F.Fab")
		)
		(fp_line
			(start -0.67945 0.3048)
			(end -0.67945 -0.305054)
			(stroke
				(width 0.1)
				(type default)
			)
			(layer "F.Fab")
		)
		(pad "1" smd circle
			(at -0.40005 0 90)
			(size 0 0)
			(layers "F.Cu" "F.Mask" "F.Paste")
			(net "FB_BMC_ISOLATE_R2")
		)
		(pad "2" smd circle
			(at 0.40005 0 90)
			(size 0 0)
			(layers "F.Cu" "F.Mask" "F.Paste")
			(net "FB_BMC_ISOLATE1")
		)
	)
	(footprint ""
		(layer "F.Cu")
		(at 187.569348 -349.58655 90)
		(property "Reference" "PR519"
			(at 0 0 90)
			(layer "F.SilkS")
			(hide yes)
			(effects
				(font
					(size 1.27 1.27)
				)
			)
		)
		(property "Value" ""
			(at 0 0 90)
			(layer "F.Fab")
			(effects
				(font
					(size 1.27 1.27)
				)
			)
		)
		(duplicate_pad_numbers_are_jumpers no)
		(fp_line
			(start 0.7874 -0.4064)
			(end 0.7874 0.4064)
			(stroke
				(width 0.1524)
				(type default)
			)
			(layer "F.SilkS")
		)
		(fp_line
			(start -0.7874 -0.4064)
			(end 0.7874 -0.4064)
			(stroke
				(width 0.1524)
				(type default)
			)
			(layer "F.SilkS")
		)
		(fp_line
			(start 0.7874 0.4064)
			(end -0.7874 0.4064)
			(stroke
				(width 0.1524)
				(type default)
			)
			(layer "F.SilkS")
		)
		(fp_line
			(start -0.7874 0.4064)
			(end -0.7874 -0.4064)
			(stroke
				(width 0.1524)
				(type default)
			)
			(layer "F.SilkS")
		)
		(fp_line
			(start -0.12065 -0.305054)
			(end -0.12065 -0.2794)
			(stroke
				(width 0.1)
				(type default)
			)
			(layer "F.Fab")
		)
		(fp_line
			(start -0.67945 -0.305054)
			(end -0.12065 -0.305054)
			(stroke
				(width 0.1)
				(type default)
			)
			(layer "F.Fab")
		)
		(fp_line
			(start 0.67945 -0.3048)
			(end 0.67945 0.3048)
			(stroke
				(width 0.1)
				(type default)
			)
			(layer "F.Fab")
		)
		(fp_line
			(start 0.12065 -0.3048)
			(end 0.67945 -0.3048)
			(stroke
				(width 0.1)
				(type default)
			)
			(layer "F.Fab")
		)
		(fp_line
			(start 0.12065 -0.2794)
			(end 0.12065 -0.3048)
			(stroke
				(width 0.1)
				(type default)
			)
			(layer "F.Fab")
		)
		(fp_line
			(start -0.12065 -0.2794)
			(end 0.12065 -0.2794)
			(stroke
				(width 0.1)
				(type default)
			)
			(layer "F.Fab")
		)
		(fp_line
			(start 0.120396 0.2794)
			(end -0.12065 0.2794)
			(stroke
				(width 0.1)
				(type default)
			)
			(layer "F.Fab")
		)
		(fp_line
			(start -0.12065 0.2794)
			(end -0.12065 0.3048)
			(stroke
				(width 0.1)
				(type default)
			)
			(layer "F.Fab")
		)
		(fp_line
			(start 0.67945 0.3048)
			(end 0.120396 0.3048)
			(stroke
				(width 0.1)
				(type default)
			)
			(layer "F.Fab")
		)
		(fp_line
			(start 0.120396 0.3048)
			(end 0.120396 0.2794)
			(stroke
				(width 0.1)
				(type default)
			)
			(layer "F.Fab")
		)
		(fp_line
			(start -0.12065 0.3048)
			(end -0.67945 0.3048)
			(stroke
				(width 0.1)
				(type default)
			)
			(layer "F.Fab")
		)
		(fp_line
			(start -0.67945 0.3048)
			(end -0.67945 -0.305054)
			(stroke
				(width 0.1)
				(type default)
			)
			(layer "F.Fab")
		)
		(pad "1" smd circle
			(at -0.40005 0 90)
			(size 0 0)
			(layers "F.Cu" "F.Mask" "F.Paste")
			(net "SW_PVDD11_S3_P1_SW2_RC")
		)
		(pad "2" smd circle
			(at 0.40005 0 90)
			(size 0 0)
			(layers "F.Cu" "F.Mask" "F.Paste")
			(net "GND")
		)
	)
	(footprint ""
		(layer "F.Cu")
		(at 201.676 -92.964)
		(property "Reference" "D8006"
			(at 4.037076 -0.588518 0)
			(unlocked yes)
			(layer "F.SilkS")
			(effects
				(font
					(size 0.7874 0.5842)
					(thickness 0.1524)
				)
				(justify left)
			)
		)
		(property "Value" ""
			(at 0 0 0)
			(layer "F.Fab")
			(effects
				(font
					(size 1.27 1.27)
				)
			)
		)
		(duplicate_pad_numbers_are_jumpers no)
		(fp_line
			(start -2.050796 -0.700024)
			(end 2.050796 -0.700024)
			(stroke
				(width 0.1524)
				(type default)
			)
			(layer "F.SilkS")
		)
		(fp_line
			(start -2.050796 0.700024)
			(end -2.050796 -0.700024)
			(stroke
				(width 0.1524)
				(type default)
			)
			(layer "F.SilkS")
		)
		(fp_line
			(start -0.30607 -0.500126)
			(end -0.30607 0.500126)
			(stroke
				(width 0.1524)
				(type default)
			)
			(layer "F.SilkS")
		)
		(fp_line
			(start -0.30607 0.500126)
			(end 0.193802 0)
			(stroke
				(width 0.1524)
				(type default)
			)
			(layer "F.SilkS")
		)
		(fp_line
			(start 0.193802 0)
			(end -0.30607 -0.500126)
			(stroke
				(width 0.1524)
				(type default)
			)
			(layer "F.SilkS")
		)
		(fp_line
			(start 0.293878 -0.500126)
			(end 0.293878 0.500126)
			(stroke
				(width 0.1524)
				(type default)
			)
			(layer "F.SilkS")
		)
		(fp_line
			(start 2.050796 -0.700024)
			(end 2.050796 0.700024)
			(stroke
				(width 0.1524)
				(type default)
			)
			(layer "F.SilkS")
		)
		(fp_line
			(start 2.050796 0.700024)
			(end -2.050796 0.700024)
			(stroke
				(width 0.1524)
				(type default)
			)
			(layer "F.SilkS")
		)
		(fp_line
			(start 2.051304 0.635)
			(end 2.152904 0.635)
			(stroke
				(width 0.1524)
				(type default)
			)
			(layer "F.SilkS")
		)
		(fp_line
			(start 2.051304 0.6985)
			(end 2.051304 0.635)
			(stroke
				(width 0.1524)
				(type default)
			)
			(layer "F.SilkS")
		)
		(fp_line
			(start 2.064004 -0.6985)
			(end 2.229104 -0.6985)
			(stroke
				(width 0.1524)
				(type default)
			)
			(layer "F.SilkS")
		)
		(fp_line
			(start 2.064004 -0.6731)
			(end 2.064004 -0.6985)
			(stroke
				(width 0.1524)
				(type default)
			)
			(layer "F.SilkS")
		)
		(fp_line
			(start 2.152904 -0.6985)
			(end 2.343404 -0.6985)
			(stroke
				(width 0.1524)
				(type default)
			)
			(layer "F.SilkS")
		)
		(fp_line
			(start 2.152904 0.635)
			(end 2.152904 -0.6985)
			(stroke
				(width 0.1524)
				(type default)
			)
			(layer "F.SilkS")
		)
		(fp_line
			(start 2.229104 -0.6985)
			(end 2.229104 0.6985)
			(stroke
				(width 0.1524)
				(type default)
			)
			(layer "F.SilkS")
		)
		(fp_line
			(start 2.229104 0.6985)
			(end 2.051304 0.6985)
			(stroke
				(width 0.1524)
				(type default)
			)
			(layer "F.SilkS")
		)
		(fp_line
			(start 2.343404 -0.6985)
			(end 2.343404 0.6985)
			(stroke
				(width 0.1524)
				(type default)
			)
			(layer "F.SilkS")
		)
		(fp_line
			(start 2.343404 0.6985)
			(end 2.216404 0.6985)
			(stroke
				(width 0.1524)
				(type default)
			)
			(layer "F.SilkS")
		)
		(fp_line
			(start -0.899922 -0.700024)
			(end 0.899922 -0.700024)
			(stroke
				(width 0.1)
				(type default)
			)
			(layer "F.Fab")
		)
		(fp_line
			(start -0.899922 0.700024)
			(end -0.899922 -0.700024)
			(stroke
				(width 0.1)
				(type default)
			)
			(layer "F.Fab")
		)
		(fp_line
			(start 0.899922 -0.700024)
			(end 0.899922 0.700024)
			(stroke
				(width 0.1)
				(type default)
			)
			(layer "F.Fab")
		)
		(fp_line
			(start 0.899922 0.700024)
			(end -0.899922 0.700024)
			(stroke
				(width 0.1)
				(type default)
			)
			(layer "F.Fab")
		)
		(fp_text user "+"
			(at -2.066544 -0.757682 90)
			(unlocked yes)
			(layer "F.SilkS")
			(effects
				(font
					(size 1.905 1.4224)
					(thickness 0.1524)
				)
				(justify left)
			)
		)
		(fp_text user "-"
			(at 3.880104 0.23495 180)
			(unlocked yes)
			(layer "F.SilkS")
			(effects
				(font
					(size 1.905 1.4224)
					(thickness 0.1524)
				)
				(justify left)
			)
		)
		(fp_text user "+"
			(at -3.123946 0.762 90)
			(unlocked yes)
			(layer "F.Fab")
			(effects
				(font
					(size 1.905 1.4224)
					(thickness 0.1524)
				)
				(justify left)
			)
		)
		(fp_text user "-"
			(at 3.880104 0.23495 180)
			(unlocked yes)
			(layer "F.Fab")
			(effects
				(font
					(size 1.905 1.4224)
					(thickness 0.1524)
				)
				(justify left)
			)
		)
		(pad "1" smd rect
			(at -1.199896 0 270)
			(size 0.6604 1.3716)
			(layers "F.Cu" "F.Mask" "F.Paste")
			(net "PWRGD_CHGL_CPU1_R1")
		)
		(pad "2" smd rect
			(at 1.199896 0 90)
			(size 0.6604 1.3716)
			(layers "F.Cu" "F.Mask" "F.Paste")
			(net "P3V3_AUX")
		)
	)
	(footprint ""
		(layer "F.Cu")
		(at 215.904064 -23.304754 -90)
		(property "Reference" "R1139"
			(at 0 0 270)
			(layer "F.SilkS")
			(hide yes)
			(effects
				(font
					(size 1.27 1.27)
				)
			)
		)
		(property "Value" ""
			(at 0 0 270)
			(layer "F.Fab")
			(effects
				(font
					(size 1.27 1.27)
				)
			)
		)
		(duplicate_pad_numbers_are_jumpers no)
		(fp_line
			(start -0.7874 0.4064)
			(end -0.7874 -0.4064)
			(stroke
				(width 0.1524)
				(type default)
			)
			(layer "F.SilkS")
		)
		(fp_line
			(start 0.7874 0.4064)
			(end -0.7874 0.4064)
			(stroke
				(width 0.1524)
				(type default)
			)
			(layer "F.SilkS")
		)
		(fp_line
			(start -0.7874 -0.4064)
			(end 0.7874 -0.4064)
			(stroke
				(width 0.1524)
				(type default)
			)
			(layer "F.SilkS")
		)
		(fp_line
			(start 0.7874 -0.4064)
			(end 0.7874 0.4064)
			(stroke
				(width 0.1524)
				(type default)
			)
			(layer "F.SilkS")
		)
		(fp_line
			(start -0.67945 0.3048)
			(end -0.67945 -0.305054)
			(stroke
				(width 0.1)
				(type default)
			)
			(layer "F.Fab")
		)
		(fp_line
			(start -0.12065 0.3048)
			(end -0.67945 0.3048)
			(stroke
				(width 0.1)
				(type default)
			)
			(layer "F.Fab")
		)
		(fp_line
			(start 0.120396 0.3048)
			(end 0.120396 0.2794)
			(stroke
				(width 0.1)
				(type default)
			)
			(layer "F.Fab")
		)
		(fp_line
			(start 0.67945 0.3048)
			(end 0.120396 0.3048)
			(stroke
				(width 0.1)
				(type default)
			)
			(layer "F.Fab")
		)
		(fp_line
			(start -0.12065 0.2794)
			(end -0.12065 0.3048)
			(stroke
				(width 0.1)
				(type default)
			)
			(layer "F.Fab")
		)
		(fp_line
			(start 0.120396 0.2794)
			(end -0.12065 0.2794)
			(stroke
				(width 0.1)
				(type default)
			)
			(layer "F.Fab")
		)
		(fp_line
			(start -0.12065 -0.2794)
			(end 0.12065 -0.2794)
			(stroke
				(width 0.1)
				(type default)
			)
			(layer "F.Fab")
		)
		(fp_line
			(start 0.12065 -0.2794)
			(end 0.12065 -0.3048)
			(stroke
				(width 0.1)
				(type default)
			)
			(layer "F.Fab")
		)
		(fp_line
			(start 0.12065 -0.3048)
			(end 0.67945 -0.3048)
			(stroke
				(width 0.1)
				(type default)
			)
			(layer "F.Fab")
		)
		(fp_line
			(start 0.67945 -0.3048)
			(end 0.67945 0.3048)
			(stroke
				(width 0.1)
				(type default)
			)
			(layer "F.Fab")
		)
		(fp_line
			(start -0.67945 -0.305054)
			(end -0.12065 -0.305054)
			(stroke
				(width 0.1)
				(type default)
			)
			(layer "F.Fab")
		)
		(fp_line
			(start -0.12065 -0.305054)
			(end -0.12065 -0.2794)
			(stroke
				(width 0.1)
				(type default)
			)
			(layer "F.Fab")
		)
		(pad "1" smd circle
			(at -0.40005 0 270)
			(size 0 0)
			(layers "F.Cu" "F.Mask" "F.Paste")
			(net "CLK_50M_RMII")
		)
		(pad "2" smd circle
			(at 0.40005 0 270)
			(size 0 0)
			(layers "F.Cu" "F.Mask" "F.Paste")
			(net "CLK_50M_RMII_R")
		)
	)
	(footprint ""
		(layer "F.Cu")
		(at 19.666458 -418.690298 90)
		(property "Reference" "R6175"
			(at 0 0 90)
			(layer "F.SilkS")
			(hide yes)
			(effects
				(font
					(size 1.27 1.27)
				)
			)
		)
		(property "Value" ""
			(at 0 0 90)
			(layer "F.Fab")
			(effects
				(font
					(size 1.27 1.27)
				)
			)
		)
		(duplicate_pad_numbers_are_jumpers no)
		(fp_line
			(start 0.7874 -0.4064)
			(end 0.7874 0.4064)
			(stroke
				(width 0.1524)
				(type default)
			)
			(layer "F.SilkS")
		)
		(fp_line
			(start -0.7874 -0.4064)
			(end 0.7874 -0.4064)
			(stroke
				(width 0.1524)
				(type default)
			)
			(layer "F.SilkS")
		)
		(fp_line
			(start 0.7874 0.4064)
			(end -0.7874 0.4064)
			(stroke
				(width 0.1524)
				(type default)
			)
			(layer "F.SilkS")
		)
		(fp_line
			(start -0.7874 0.4064)
			(end -0.7874 -0.4064)
			(stroke
				(width 0.1524)
				(type default)
			)
			(layer "F.SilkS")
		)
		(fp_line
			(start -0.12065 -0.305054)
			(end -0.12065 -0.2794)
			(stroke
				(width 0.1)
				(type default)
			)
			(layer "F.Fab")
		)
		(fp_line
			(start -0.67945 -0.305054)
			(end -0.12065 -0.305054)
			(stroke
				(width 0.1)
				(type default)
			)
			(layer "F.Fab")
		)
		(fp_line
			(start 0.67945 -0.3048)
			(end 0.67945 0.3048)
			(stroke
				(width 0.1)
				(type default)
			)
			(layer "F.Fab")
		)
		(fp_line
			(start 0.12065 -0.3048)
			(end 0.67945 -0.3048)
			(stroke
				(width 0.1)
				(type default)
			)
			(layer "F.Fab")
		)
		(fp_line
			(start 0.12065 -0.2794)
			(end 0.12065 -0.3048)
			(stroke
				(width 0.1)
				(type default)
			)
			(layer "F.Fab")
		)
		(fp_line
			(start -0.12065 -0.2794)
			(end 0.12065 -0.2794)
			(stroke
				(width 0.1)
				(type default)
			)
			(layer "F.Fab")
		)
		(fp_line
			(start 0.120396 0.2794)
			(end -0.12065 0.2794)
			(stroke
				(width 0.1)
				(type default)
			)
			(layer "F.Fab")
		)
		(fp_line
			(start -0.12065 0.2794)
			(end -0.12065 0.3048)
			(stroke
				(width 0.1)
				(type default)
			)
			(layer "F.Fab")
		)
		(fp_line
			(start 0.67945 0.3048)
			(end 0.120396 0.3048)
			(stroke
				(width 0.1)
				(type default)
			)
			(layer "F.Fab")
		)
		(fp_line
			(start 0.120396 0.3048)
			(end 0.120396 0.2794)
			(stroke
				(width 0.1)
				(type default)
			)
			(layer "F.Fab")
		)
		(fp_line
			(start -0.12065 0.3048)
			(end -0.67945 0.3048)
			(stroke
				(width 0.1)
				(type default)
			)
			(layer "F.Fab")
		)
		(fp_line
			(start -0.67945 0.3048)
			(end -0.67945 -0.305054)
			(stroke
				(width 0.1)
				(type default)
			)
			(layer "F.Fab")
		)
		(pad "1" smd circle
			(at -0.40005 0 90)
			(size 0 0)
			(layers "F.Cu" "F.Mask" "F.Paste")
			(net "P3V3_AUX")
		)
		(pad "2" smd circle
			(at 0.40005 0 90)
			(size 0 0)
			(layers "F.Cu" "F.Mask" "F.Paste")
			(net "FM_P2E_BUF2_RXDET")
		)
	)
	(footprint ""
		(layer "F.Cu")
		(at 80.924146 -24.346408 180)
		(property "Reference" "C40"
			(at 0 0 180)
			(layer "F.SilkS")
			(hide yes)
			(effects
				(font
					(size 1.27 1.27)
				)
			)
		)
		(property "Value" ""
			(at 0 0 180)
			(layer "F.Fab")
			(effects
				(font
					(size 1.27 1.27)
				)
			)
		)
		(duplicate_pad_numbers_are_jumpers no)
		(fp_line
			(start 0.7874 0.4064)
			(end -0.7874 0.4064)
			(stroke
				(width 0.1524)
				(type default)
			)
			(layer "F.SilkS")
		)
		(fp_line
			(start 0.7874 -0.4064)
			(end 0.7874 0.4064)
			(stroke
				(width 0.1524)
				(type default)
			)
			(layer "F.SilkS")
		)
		(fp_line
			(start -0.7874 0.4064)
			(end -0.7874 -0.4064)
			(stroke
				(width 0.1524)
				(type default)
			)
			(layer "F.SilkS")
		)
		(fp_line
			(start -0.7874 -0.4064)
			(end 0.7874 -0.4064)
			(stroke
				(width 0.1524)
				(type default)
			)
			(layer "F.SilkS")
		)
		(fp_line
			(start 0.67945 0.3048)
			(end 0.120396 0.3048)
			(stroke
				(width 0.1)
				(type default)
			)
			(layer "F.Fab")
		)
		(fp_line
			(start 0.67945 -0.3048)
			(end 0.67945 0.3048)
			(stroke
				(width 0.1)
				(type default)
			)
			(layer "F.Fab")
		)
		(fp_line
			(start 0.12065 -0.2794)
			(end 0.12065 -0.3048)
			(stroke
				(width 0.1)
				(type default)
			)
			(layer "F.Fab")
		)
		(fp_line
			(start 0.12065 -0.3048)
			(end 0.67945 -0.3048)
			(stroke
				(width 0.1)
				(type default)
			)
			(layer "F.Fab")
		)
		(fp_line
			(start 0.120396 0.3048)
			(end 0.120396 0.2794)
			(stroke
				(width 0.1)
				(type default)
			)
			(layer "F.Fab")
		)
		(fp_line
			(start 0.120396 0.2794)
			(end -0.12065 0.2794)
			(stroke
				(width 0.1)
				(type default)
			)
			(layer "F.Fab")
		)
		(fp_line
			(start -0.12065 0.3048)
			(end -0.67945 0.3048)
			(stroke
				(width 0.1)
				(type default)
			)
			(layer "F.Fab")
		)
		(fp_line
			(start -0.12065 0.2794)
			(end -0.12065 0.3048)
			(stroke
				(width 0.1)
				(type default)
			)
			(layer "F.Fab")
		)
		(fp_line
			(start -0.12065 -0.2794)
			(end 0.12065 -0.2794)
			(stroke
				(width 0.1)
				(type default)
			)
			(layer "F.Fab")
		)
		(fp_line
			(start -0.12065 -0.305054)
			(end -0.12065 -0.2794)
			(stroke
				(width 0.1)
				(type default)
			)
			(layer "F.Fab")
		)
		(fp_line
			(start -0.67945 0.3048)
			(end -0.67945 -0.305054)
			(stroke
				(width 0.1)
				(type default)
			)
			(layer "F.Fab")
		)
		(fp_line
			(start -0.67945 -0.305054)
			(end -0.12065 -0.305054)
			(stroke
				(width 0.1)
				(type default)
			)
			(layer "F.Fab")
		)
		(pad "1" smd circle
			(at -0.40005 0 180)
			(size 0 0)
			(layers "F.Cu" "F.Mask" "F.Paste")
			(net "P12V_OCP_V3_2")
		)
		(pad "2" smd circle
			(at 0.40005 0 180)
			(size 0 0)
			(layers "F.Cu" "F.Mask" "F.Paste")
			(net "P12V_OCP_GATE_2")
		)
	)
	(footprint ""
		(layer "F.Cu")
		(at 462.147666 -380.13767 -90)
		(property "Reference" "PC6572"
			(at 4.62534 2.153666 0)
			(unlocked yes)
			(layer "F.SilkS")
			(effects
				(font
					(size 0.7874 0.5842)
					(thickness 0.1524)
				)
				(justify left)
			)
		)
		(property "Value" ""
			(at 0 0 270)
			(layer "F.Fab")
			(effects
				(font
					(size 1.27 1.27)
				)
			)
		)
		(duplicate_pad_numbers_are_jumpers no)
		(fp_line
			(start -1.988058 2.750058)
			(end 2.750058 2.750058)
			(stroke
				(width 0.1524)
				(type default)
			)
			(layer "F.SilkS")
		)
		(fp_line
			(start 2.750058 2.750058)
			(end 2.750058 0.9398)
			(stroke
				(width 0.1524)
				(type default)
			)
			(layer "F.SilkS")
		)
		(fp_line
			(start -2.750058 1.988058)
			(end -1.988058 2.750058)
			(stroke
				(width 0.1524)
				(type default)
			)
			(layer "F.SilkS")
		)
		(fp_line
			(start -2.750058 0.9398)
			(end -2.750058 1.988058)
			(stroke
				(width 0.1524)
				(type default)
			)
			(layer "F.SilkS")
		)
		(fp_line
			(start 2.750058 -0.9398)
			(end 2.750058 -2.750058)
			(stroke
				(width 0.1524)
				(type default)
			)
			(layer "F.SilkS")
		)
		(fp_line
			(start -2.750058 -1.988058)
			(end -2.750058 -0.9398)
			(stroke
				(width 0.1524)
				(type default)
			)
			(layer "F.SilkS")
		)
		(fp_line
			(start -1.988058 -2.750058)
			(end -2.750058 -1.988058)
			(stroke
				(width 0.1524)
				(type default)
			)
			(layer "F.SilkS")
		)
		(fp_line
			(start 2.750058 -2.750058)
			(end -1.988058 -2.750058)
			(stroke
				(width 0.1524)
				(type default)
			)
			(layer "F.SilkS")
		)
		(fp_line
			(start -2.750058 2.750058)
			(end 2.750058 2.750058)
			(stroke
				(width 0.1)
				(type default)
			)
			(layer "F.Fab")
		)
		(fp_line
			(start 2.750058 2.750058)
			(end 2.750058 -2.750058)
			(stroke
				(width 0.1)
				(type default)
			)
			(layer "F.Fab")
		)
		(fp_line
			(start -2.750058 -2.750058)
			(end -2.750058 2.750058)
			(stroke
				(width 0.1)
				(type default)
			)
			(layer "F.Fab")
		)
		(fp_line
			(start 2.750058 -2.750058)
			(end -2.750058 -2.750058)
			(stroke
				(width 0.1)
				(type default)
			)
			(layer "F.Fab")
		)
		(pad "1" smd rect
			(at -2.199894 0)
			(size 1.6002 3.0226)
			(layers "F.Cu" "F.Mask" "F.Paste")
			(net "P0V9_CPU0_RT_2D")
		)
		(pad "2" smd rect
			(at 2.199894 0)
			(size 1.6002 3.0226)
			(layers "F.Cu" "F.Mask" "F.Paste")
			(net "GND")
		)
	)
	(footprint ""
		(layer "F.Cu")
		(at 80.762094 -152.999694 90)
		(property "Reference" "PC8003"
			(at 0 0 90)
			(layer "F.SilkS")
			(hide yes)
			(effects
				(font
					(size 1.27 1.27)
				)
			)
		)
		(property "Value" ""
			(at 0 0 90)
			(layer "F.Fab")
			(effects
				(font
					(size 1.27 1.27)
				)
			)
		)
		(duplicate_pad_numbers_are_jumpers no)
		(fp_line
			(start 1.524 -0.762)
			(end 1.524 0.762)
			(stroke
				(width 0.1524)
				(type default)
			)
			(layer "F.SilkS")
		)
		(fp_line
			(start -1.524 -0.762)
			(end 1.524 -0.762)
			(stroke
				(width 0.1524)
				(type default)
			)
			(layer "F.SilkS")
		)
		(fp_line
			(start 1.524 0.762)
			(end -1.524 0.762)
			(stroke
				(width 0.1524)
				(type default)
			)
			(layer "F.SilkS")
		)
		(fp_line
			(start -1.524 0.762)
			(end -1.524 -0.762)
			(stroke
				(width 0.1524)
				(type default)
			)
			(layer "F.SilkS")
		)
		(fp_line
			(start 1.1049 -0.724916)
			(end -1.1049 -0.724916)
			(stroke
				(width 0.1)
				(type default)
			)
			(layer "F.Fab")
		)
		(fp_line
			(start -1.1049 -0.724916)
			(end -1.1049 0.724916)
			(stroke
				(width 0.1)
				(type default)
			)
			(layer "F.Fab")
		)
		(fp_line
			(start 1.1049 0.724916)
			(end 1.1049 -0.724916)
			(stroke
				(width 0.1)
				(type default)
			)
			(layer "F.Fab")
		)
		(fp_line
			(start -1.1049 0.724916)
			(end 1.1049 0.724916)
			(stroke
				(width 0.1)
				(type default)
			)
			(layer "F.Fab")
		)
		(pad "1" smd rect
			(at -0.889 0 270)
			(size 1.016 1.27)
			(layers "F.Cu" "F.Mask" "F.Paste")
			(net "SW_P12V_AUX_PVDD18_S5_P1_FLT")
		)
		(pad "2" smd rect
			(at 0.889 0 270)
			(size 1.016 1.27)
			(layers "F.Cu" "F.Mask" "F.Paste")
			(net "GND")
		)
	)
	(footprint ""
		(layer "F.Cu")
		(at 114.327178 -261.748016 -90)
		(property "Reference" "C2501"
			(at 0 0 270)
			(layer "F.SilkS")
			(hide yes)
			(effects
				(font
					(size 1.27 1.27)
				)
			)
		)
		(property "Value" ""
			(at 0 0 270)
			(layer "F.Fab")
			(effects
				(font
					(size 1.27 1.27)
				)
			)
		)
		(duplicate_pad_numbers_are_jumpers no)
		(fp_line
			(start -0.7874 0.4064)
			(end -0.7874 -0.4064)
			(stroke
				(width 0.1524)
				(type default)
			)
			(layer "F.SilkS")
		)
		(fp_line
			(start 0.7874 0.4064)
			(end -0.7874 0.4064)
			(stroke
				(width 0.1524)
				(type default)
			)
			(layer "F.SilkS")
		)
		(fp_line
			(start -0.7874 -0.4064)
			(end 0.7874 -0.4064)
			(stroke
				(width 0.1524)
				(type default)
			)
			(layer "F.SilkS")
		)
		(fp_line
			(start 0.7874 -0.4064)
			(end 0.7874 0.4064)
			(stroke
				(width 0.1524)
				(type default)
			)
			(layer "F.SilkS")
		)
		(fp_line
			(start -0.67945 0.3048)
			(end -0.67945 -0.305054)
			(stroke
				(width 0.1)
				(type default)
			)
			(layer "F.Fab")
		)
		(fp_line
			(start -0.12065 0.3048)
			(end -0.67945 0.3048)
			(stroke
				(width 0.1)
				(type default)
			)
			(layer "F.Fab")
		)
		(fp_line
			(start 0.120396 0.3048)
			(end 0.120396 0.2794)
			(stroke
				(width 0.1)
				(type default)
			)
			(layer "F.Fab")
		)
		(fp_line
			(start 0.67945 0.3048)
			(end 0.120396 0.3048)
			(stroke
				(width 0.1)
				(type default)
			)
			(layer "F.Fab")
		)
		(fp_line
			(start -0.12065 0.2794)
			(end -0.12065 0.3048)
			(stroke
				(width 0.1)
				(type default)
			)
			(layer "F.Fab")
		)
		(fp_line
			(start 0.120396 0.2794)
			(end -0.12065 0.2794)
			(stroke
				(width 0.1)
				(type default)
			)
			(layer "F.Fab")
		)
		(fp_line
			(start -0.12065 -0.2794)
			(end 0.12065 -0.2794)
			(stroke
				(width 0.1)
				(type default)
			)
			(layer "F.Fab")
		)
		(fp_line
			(start 0.12065 -0.2794)
			(end 0.12065 -0.3048)
			(stroke
				(width 0.1)
				(type default)
			)
			(layer "F.Fab")
		)
		(fp_line
			(start 0.12065 -0.3048)
			(end 0.67945 -0.3048)
			(stroke
				(width 0.1)
				(type default)
			)
			(layer "F.Fab")
		)
		(fp_line
			(start 0.67945 -0.3048)
			(end 0.67945 0.3048)
			(stroke
				(width 0.1)
				(type default)
			)
			(layer "F.Fab")
		)
		(fp_line
			(start -0.67945 -0.305054)
			(end -0.12065 -0.305054)
			(stroke
				(width 0.1)
				(type default)
			)
			(layer "F.Fab")
		)
		(fp_line
			(start -0.12065 -0.305054)
			(end -0.12065 -0.2794)
			(stroke
				(width 0.1)
				(type default)
			)
			(layer "F.Fab")
		)
		(pad "1" smd circle
			(at -0.40005 0 270)
			(size 0 0)
			(layers "F.Cu" "F.Mask" "F.Paste")
			(net "PVDD11_S3_P1")
		)
		(pad "2" smd circle
			(at 0.40005 0 270)
			(size 0 0)
			(layers "F.Cu" "F.Mask" "F.Paste")
			(net "GND")
		)
	)
	(footprint ""
		(layer "F.Cu")
		(at 248.46915 -271.267936 180)
		(property "Reference" "PL6500"
			(at 5.77215 -3.197606 0)
			(unlocked yes)
			(layer "F.SilkS")
			(effects
				(font
					(size 0.7874 0.5842)
					(thickness 0.1524)
				)
				(justify left)
			)
		)
		(property "Value" ""
			(at 0 0 180)
			(layer "F.Fab")
			(effects
				(font
					(size 1.27 1.27)
				)
			)
		)
		(duplicate_pad_numbers_are_jumpers no)
		(fp_line
			(start 2.249932 2.249932)
			(end -2.249932 2.249932)
			(stroke
				(width 0.1524)
				(type default)
			)
			(layer "F.SilkS")
		)
		(fp_line
			(start 2.249932 1.3843)
			(end 2.249932 2.249932)
			(stroke
				(width 0.1524)
				(type default)
			)
			(layer "F.SilkS")
		)
		(fp_line
			(start 2.249932 -2.249932)
			(end 2.249932 -1.3843)
			(stroke
				(width 0.1524)
				(type default)
			)
			(layer "F.SilkS")
		)
		(fp_line
			(start -2.249932 2.249932)
			(end -2.249932 1.3843)
			(stroke
				(width 0.1524)
				(type default)
			)
			(layer "F.SilkS")
		)
		(fp_line
			(start -2.249932 -1.3843)
			(end -2.249932 -2.249932)
			(stroke
				(width 0.1524)
				(type default)
			)
			(layer "F.SilkS")
		)
		(fp_line
			(start -2.249932 -2.249932)
			(end 2.249932 -2.249932)
			(stroke
				(width 0.1524)
				(type default)
			)
			(layer "F.SilkS")
		)
		(fp_line
			(start 2.249932 2.249932)
			(end -2.249932 2.249932)
			(stroke
				(width 0.1)
				(type default)
			)
			(layer "F.Fab")
		)
		(fp_line
			(start 2.249932 -2.249932)
			(end 2.249932 2.249932)
			(stroke
				(width 0.1)
				(type default)
			)
			(layer "F.Fab")
		)
		(fp_line
			(start -2.249932 2.249932)
			(end -2.249932 -2.249932)
			(stroke
				(width 0.1)
				(type default)
			)
			(layer "F.Fab")
		)
		(fp_line
			(start -2.249932 -2.249932)
			(end 2.249932 -2.249932)
			(stroke
				(width 0.1)
				(type default)
			)
			(layer "F.Fab")
		)
		(pad "1" smd rect
			(at -1.82499 0 180)
			(size 1.0668 2.5146)
			(layers "F.Cu" "F.Mask" "F.Paste")
			(net "P12V_AUX")
		)
		(pad "2" smd rect
			(at 1.82499 0 180)
			(size 1.0668 2.5146)
			(layers "F.Cu" "F.Mask" "F.Paste")
			(net "SW_P12V_AUX_P1V8_RETIMER_CPU0_FLT")
		)
	)
	(footprint ""
		(layer "F.Cu")
		(at 159.18307 -76.53147 -90)
		(property "Reference" "R994"
			(at 0 0 270)
			(layer "F.SilkS")
			(hide yes)
			(effects
				(font
					(size 1.27 1.27)
				)
			)
		)
		(property "Value" ""
			(at 0 0 270)
			(layer "F.Fab")
			(effects
				(font
					(size 1.27 1.27)
				)
			)
		)
		(duplicate_pad_numbers_are_jumpers no)
		(fp_line
			(start -0.7874 0.4064)
			(end -0.7874 -0.4064)
			(stroke
				(width 0.1524)
				(type default)
			)
			(layer "F.SilkS")
		)
		(fp_line
			(start 0.7874 0.4064)
			(end -0.7874 0.4064)
			(stroke
				(width 0.1524)
				(type default)
			)
			(layer "F.SilkS")
		)
		(fp_line
			(start -0.7874 -0.4064)
			(end 0.7874 -0.4064)
			(stroke
				(width 0.1524)
				(type default)
			)
			(layer "F.SilkS")
		)
		(fp_line
			(start 0.7874 -0.4064)
			(end 0.7874 0.4064)
			(stroke
				(width 0.1524)
				(type default)
			)
			(layer "F.SilkS")
		)
		(fp_line
			(start -0.67945 0.3048)
			(end -0.67945 -0.305054)
			(stroke
				(width 0.1)
				(type default)
			)
			(layer "F.Fab")
		)
		(fp_line
			(start -0.12065 0.3048)
			(end -0.67945 0.3048)
			(stroke
				(width 0.1)
				(type default)
			)
			(layer "F.Fab")
		)
		(fp_line
			(start 0.120396 0.3048)
			(end 0.120396 0.2794)
			(stroke
				(width 0.1)
				(type default)
			)
			(layer "F.Fab")
		)
		(fp_line
			(start 0.67945 0.3048)
			(end 0.120396 0.3048)
			(stroke
				(width 0.1)
				(type default)
			)
			(layer "F.Fab")
		)
		(fp_line
			(start -0.12065 0.2794)
			(end -0.12065 0.3048)
			(stroke
				(width 0.1)
				(type default)
			)
			(layer "F.Fab")
		)
		(fp_line
			(start 0.120396 0.2794)
			(end -0.12065 0.2794)
			(stroke
				(width 0.1)
				(type default)
			)
			(layer "F.Fab")
		)
		(fp_line
			(start -0.12065 -0.2794)
			(end 0.12065 -0.2794)
			(stroke
				(width 0.1)
				(type default)
			)
			(layer "F.Fab")
		)
		(fp_line
			(start 0.12065 -0.2794)
			(end 0.12065 -0.3048)
			(stroke
				(width 0.1)
				(type default)
			)
			(layer "F.Fab")
		)
		(fp_line
			(start 0.12065 -0.3048)
			(end 0.67945 -0.3048)
			(stroke
				(width 0.1)
				(type default)
			)
			(layer "F.Fab")
		)
		(fp_line
			(start 0.67945 -0.3048)
			(end 0.67945 0.3048)
			(stroke
				(width 0.1)
				(type default)
			)
			(layer "F.Fab")
		)
		(fp_line
			(start -0.67945 -0.305054)
			(end -0.12065 -0.305054)
			(stroke
				(width 0.1)
				(type default)
			)
			(layer "F.Fab")
		)
		(fp_line
			(start -0.12065 -0.305054)
			(end -0.12065 -0.2794)
			(stroke
				(width 0.1)
				(type default)
			)
			(layer "F.Fab")
		)
		(pad "1" smd circle
			(at -0.40005 0 270)
			(size 0 0)
			(layers "F.Cu" "F.Mask" "F.Paste")
			(net "P3V3_AUX")
		)
		(pad "2" smd circle
			(at 0.40005 0 270)
			(size 0 0)
			(layers "F.Cu" "F.Mask" "F.Paste")
			(net "IRQ_LVC3_WAKE_N")
		)
	)
	(footprint ""
		(layer "F.Cu")
		(at 428.120302 -434.386736 90)
		(property "Reference" "R2933"
			(at 0 0 90)
			(layer "F.SilkS")
			(hide yes)
			(effects
				(font
					(size 1.27 1.27)
				)
			)
		)
		(property "Value" ""
			(at 0 0 90)
			(layer "F.Fab")
			(effects
				(font
					(size 1.27 1.27)
				)
			)
		)
		(duplicate_pad_numbers_are_jumpers no)
		(fp_line
			(start 0.7874 -0.4064)
			(end 0.7874 0.4064)
			(stroke
				(width 0.1524)
				(type default)
			)
			(layer "F.SilkS")
		)
		(fp_line
			(start -0.7874 -0.4064)
			(end 0.7874 -0.4064)
			(stroke
				(width 0.1524)
				(type default)
			)
			(layer "F.SilkS")
		)
		(fp_line
			(start 0.7874 0.4064)
			(end -0.7874 0.4064)
			(stroke
				(width 0.1524)
				(type default)
			)
			(layer "F.SilkS")
		)
		(fp_line
			(start -0.7874 0.4064)
			(end -0.7874 -0.4064)
			(stroke
				(width 0.1524)
				(type default)
			)
			(layer "F.SilkS")
		)
		(fp_line
			(start -0.12065 -0.305054)
			(end -0.12065 -0.2794)
			(stroke
				(width 0.1)
				(type default)
			)
			(layer "F.Fab")
		)
		(fp_line
			(start -0.67945 -0.305054)
			(end -0.12065 -0.305054)
			(stroke
				(width 0.1)
				(type default)
			)
			(layer "F.Fab")
		)
		(fp_line
			(start 0.67945 -0.3048)
			(end 0.67945 0.3048)
			(stroke
				(width 0.1)
				(type default)
			)
			(layer "F.Fab")
		)
		(fp_line
			(start 0.12065 -0.3048)
			(end 0.67945 -0.3048)
			(stroke
				(width 0.1)
				(type default)
			)
			(layer "F.Fab")
		)
		(fp_line
			(start 0.12065 -0.2794)
			(end 0.12065 -0.3048)
			(stroke
				(width 0.1)
				(type default)
			)
			(layer "F.Fab")
		)
		(fp_line
			(start -0.12065 -0.2794)
			(end 0.12065 -0.2794)
			(stroke
				(width 0.1)
				(type default)
			)
			(layer "F.Fab")
		)
		(fp_line
			(start 0.120396 0.2794)
			(end -0.12065 0.2794)
			(stroke
				(width 0.1)
				(type default)
			)
			(layer "F.Fab")
		)
		(fp_line
			(start -0.12065 0.2794)
			(end -0.12065 0.3048)
			(stroke
				(width 0.1)
				(type default)
			)
			(layer "F.Fab")
		)
		(fp_line
			(start 0.67945 0.3048)
			(end 0.120396 0.3048)
			(stroke
				(width 0.1)
				(type default)
			)
			(layer "F.Fab")
		)
		(fp_line
			(start 0.120396 0.3048)
			(end 0.120396 0.2794)
			(stroke
				(width 0.1)
				(type default)
			)
			(layer "F.Fab")
		)
		(fp_line
			(start -0.12065 0.3048)
			(end -0.67945 0.3048)
			(stroke
				(width 0.1)
				(type default)
			)
			(layer "F.Fab")
		)
		(fp_line
			(start -0.67945 0.3048)
			(end -0.67945 -0.305054)
			(stroke
				(width 0.1)
				(type default)
			)
			(layer "F.Fab")
		)
		(pad "1" smd circle
			(at -0.40005 0 90)
			(size 0 0)
			(layers "F.Cu" "F.Mask" "F.Paste")
			(net "P3V3_AUX")
		)
		(pad "2" smd circle
			(at 0.40005 0 90)
			(size 0 0)
			(layers "F.Cu" "F.Mask" "F.Paste")
			(net "FM_SWB_BIC_READY_ISO_N")
		)
	)
	(footprint ""
		(layer "F.Cu")
		(at 418.11194 -105.207308 180)
		(property "Reference" "PC2159"
			(at 0 0 180)
			(layer "F.SilkS")
			(hide yes)
			(effects
				(font
					(size 1.27 1.27)
				)
			)
		)
		(property "Value" ""
			(at 0 0 180)
			(layer "F.Fab")
			(effects
				(font
					(size 1.27 1.27)
				)
			)
		)
		(duplicate_pad_numbers_are_jumpers no)
		(fp_line
			(start 0.7874 0.4064)
			(end -0.7874 0.4064)
			(stroke
				(width 0.1524)
				(type default)
			)
			(layer "F.SilkS")
		)
		(fp_line
			(start 0.7874 -0.4064)
			(end 0.7874 0.4064)
			(stroke
				(width 0.1524)
				(type default)
			)
			(layer "F.SilkS")
		)
		(fp_line
			(start -0.7874 0.4064)
			(end -0.7874 -0.4064)
			(stroke
				(width 0.1524)
				(type default)
			)
			(layer "F.SilkS")
		)
		(fp_line
			(start -0.7874 -0.4064)
			(end 0.7874 -0.4064)
			(stroke
				(width 0.1524)
				(type default)
			)
			(layer "F.SilkS")
		)
		(fp_line
			(start 0.67945 0.3048)
			(end 0.120396 0.3048)
			(stroke
				(width 0.1)
				(type default)
			)
			(layer "F.Fab")
		)
		(fp_line
			(start 0.67945 -0.3048)
			(end 0.67945 0.3048)
			(stroke
				(width 0.1)
				(type default)
			)
			(layer "F.Fab")
		)
		(fp_line
			(start 0.12065 -0.2794)
			(end 0.12065 -0.3048)
			(stroke
				(width 0.1)
				(type default)
			)
			(layer "F.Fab")
		)
		(fp_line
			(start 0.12065 -0.3048)
			(end 0.67945 -0.3048)
			(stroke
				(width 0.1)
				(type default)
			)
			(layer "F.Fab")
		)
		(fp_line
			(start 0.120396 0.3048)
			(end 0.120396 0.2794)
			(stroke
				(width 0.1)
				(type default)
			)
			(layer "F.Fab")
		)
		(fp_line
			(start 0.120396 0.2794)
			(end -0.12065 0.2794)
			(stroke
				(width 0.1)
				(type default)
			)
			(layer "F.Fab")
		)
		(fp_line
			(start -0.12065 0.3048)
			(end -0.67945 0.3048)
			(stroke
				(width 0.1)
				(type default)
			)
			(layer "F.Fab")
		)
		(fp_line
			(start -0.12065 0.2794)
			(end -0.12065 0.3048)
			(stroke
				(width 0.1)
				(type default)
			)
			(layer "F.Fab")
		)
		(fp_line
			(start -0.12065 -0.2794)
			(end 0.12065 -0.2794)
			(stroke
				(width 0.1)
				(type default)
			)
			(layer "F.Fab")
		)
		(fp_line
			(start -0.12065 -0.305054)
			(end -0.12065 -0.2794)
			(stroke
				(width 0.1)
				(type default)
			)
			(layer "F.Fab")
		)
		(fp_line
			(start -0.67945 0.3048)
			(end -0.67945 -0.305054)
			(stroke
				(width 0.1)
				(type default)
			)
			(layer "F.Fab")
		)
		(fp_line
			(start -0.67945 -0.305054)
			(end -0.12065 -0.305054)
			(stroke
				(width 0.1)
				(type default)
			)
			(layer "F.Fab")
		)
		(pad "1" smd circle
			(at -0.40005 0 180)
			(size 0 0)
			(layers "F.Cu" "F.Mask" "F.Paste")
			(net "P3V3_AUX")
		)
		(pad "2" smd circle
			(at 0.40005 0 180)
			(size 0 0)
			(layers "F.Cu" "F.Mask" "F.Paste")
			(net "GND")
		)
	)
	(footprint ""
		(layer "F.Cu")
		(at 357.284782 -413.046418 180)
		(property "Reference" "R4156"
			(at 0 0 180)
			(layer "F.SilkS")
			(hide yes)
			(effects
				(font
					(size 1.27 1.27)
				)
			)
		)
		(property "Value" ""
			(at 0 0 180)
			(layer "F.Fab")
			(effects
				(font
					(size 1.27 1.27)
				)
			)
		)
		(duplicate_pad_numbers_are_jumpers no)
		(fp_line
			(start 0.7874 0.4064)
			(end -0.7874 0.4064)
			(stroke
				(width 0.1524)
				(type default)
			)
			(layer "F.SilkS")
		)
		(fp_line
			(start 0.7874 -0.4064)
			(end 0.7874 0.4064)
			(stroke
				(width 0.1524)
				(type default)
			)
			(layer "F.SilkS")
		)
		(fp_line
			(start -0.7874 0.4064)
			(end -0.7874 -0.4064)
			(stroke
				(width 0.1524)
				(type default)
			)
			(layer "F.SilkS")
		)
		(fp_line
			(start -0.7874 -0.4064)
			(end 0.7874 -0.4064)
			(stroke
				(width 0.1524)
				(type default)
			)
			(layer "F.SilkS")
		)
		(fp_line
			(start 0.67945 0.3048)
			(end 0.120396 0.3048)
			(stroke
				(width 0.1)
				(type default)
			)
			(layer "F.Fab")
		)
		(fp_line
			(start 0.67945 -0.3048)
			(end 0.67945 0.3048)
			(stroke
				(width 0.1)
				(type default)
			)
			(layer "F.Fab")
		)
		(fp_line
			(start 0.12065 -0.2794)
			(end 0.12065 -0.3048)
			(stroke
				(width 0.1)
				(type default)
			)
			(layer "F.Fab")
		)
		(fp_line
			(start 0.12065 -0.3048)
			(end 0.67945 -0.3048)
			(stroke
				(width 0.1)
				(type default)
			)
			(layer "F.Fab")
		)
		(fp_line
			(start 0.120396 0.3048)
			(end 0.120396 0.2794)
			(stroke
				(width 0.1)
				(type default)
			)
			(layer "F.Fab")
		)
		(fp_line
			(start 0.120396 0.2794)
			(end -0.12065 0.2794)
			(stroke
				(width 0.1)
				(type default)
			)
			(layer "F.Fab")
		)
		(fp_line
			(start -0.12065 0.3048)
			(end -0.67945 0.3048)
			(stroke
				(width 0.1)
				(type default)
			)
			(layer "F.Fab")
		)
		(fp_line
			(start -0.12065 0.2794)
			(end -0.12065 0.3048)
			(stroke
				(width 0.1)
				(type default)
			)
			(layer "F.Fab")
		)
		(fp_line
			(start -0.12065 -0.2794)
			(end 0.12065 -0.2794)
			(stroke
				(width 0.1)
				(type default)
			)
			(layer "F.Fab")
		)
		(fp_line
			(start -0.12065 -0.305054)
			(end -0.12065 -0.2794)
			(stroke
				(width 0.1)
				(type default)
			)
			(layer "F.Fab")
		)
		(fp_line
			(start -0.67945 0.3048)
			(end -0.67945 -0.305054)
			(stroke
				(width 0.1)
				(type default)
			)
			(layer "F.Fab")
		)
		(fp_line
			(start -0.67945 -0.305054)
			(end -0.12065 -0.305054)
			(stroke
				(width 0.1)
				(type default)
			)
			(layer "F.Fab")
		)
		(pad "1" smd circle
			(at -0.40005 0 180)
			(size 0 0)
			(layers "F.Cu" "F.Mask" "F.Paste")
			(net "P3V3_AUX")
		)
		(pad "2" smd circle
			(at 0.40005 0 180)
			(size 0 0)
			(layers "F.Cu" "F.Mask" "F.Paste")
			(net "PRSNT_CABLE_GPU_A1_ISO_N")
		)
	)
	(footprint ""
		(layer "F.Cu")
		(at 179.24272 -349.56115 90)
		(property "Reference" "PR520"
			(at 0 0 90)
			(layer "F.SilkS")
			(hide yes)
			(effects
				(font
					(size 1.27 1.27)
				)
			)
		)
		(property "Value" ""
			(at 0 0 90)
			(layer "F.Fab")
			(effects
				(font
					(size 1.27 1.27)
				)
			)
		)
		(duplicate_pad_numbers_are_jumpers no)
		(fp_line
			(start 0.7874 -0.4064)
			(end 0.7874 0.4064)
			(stroke
				(width 0.1524)
				(type default)
			)
			(layer "F.SilkS")
		)
		(fp_line
			(start -0.7874 -0.4064)
			(end 0.7874 -0.4064)
			(stroke
				(width 0.1524)
				(type default)
			)
			(layer "F.SilkS")
		)
		(fp_line
			(start 0.7874 0.4064)
			(end -0.7874 0.4064)
			(stroke
				(width 0.1524)
				(type default)
			)
			(layer "F.SilkS")
		)
		(fp_line
			(start -0.7874 0.4064)
			(end -0.7874 -0.4064)
			(stroke
				(width 0.1524)
				(type default)
			)
			(layer "F.SilkS")
		)
		(fp_line
			(start -0.12065 -0.305054)
			(end -0.12065 -0.2794)
			(stroke
				(width 0.1)
				(type default)
			)
			(layer "F.Fab")
		)
		(fp_line
			(start -0.67945 -0.305054)
			(end -0.12065 -0.305054)
			(stroke
				(width 0.1)
				(type default)
			)
			(layer "F.Fab")
		)
		(fp_line
			(start 0.67945 -0.3048)
			(end 0.67945 0.3048)
			(stroke
				(width 0.1)
				(type default)
			)
			(layer "F.Fab")
		)
		(fp_line
			(start 0.12065 -0.3048)
			(end 0.67945 -0.3048)
			(stroke
				(width 0.1)
				(type default)
			)
			(layer "F.Fab")
		)
		(fp_line
			(start 0.12065 -0.2794)
			(end 0.12065 -0.3048)
			(stroke
				(width 0.1)
				(type default)
			)
			(layer "F.Fab")
		)
		(fp_line
			(start -0.12065 -0.2794)
			(end 0.12065 -0.2794)
			(stroke
				(width 0.1)
				(type default)
			)
			(layer "F.Fab")
		)
		(fp_line
			(start 0.120396 0.2794)
			(end -0.12065 0.2794)
			(stroke
				(width 0.1)
				(type default)
			)
			(layer "F.Fab")
		)
		(fp_line
			(start -0.12065 0.2794)
			(end -0.12065 0.3048)
			(stroke
				(width 0.1)
				(type default)
			)
			(layer "F.Fab")
		)
		(fp_line
			(start 0.67945 0.3048)
			(end 0.120396 0.3048)
			(stroke
				(width 0.1)
				(type default)
			)
			(layer "F.Fab")
		)
		(fp_line
			(start 0.120396 0.3048)
			(end 0.120396 0.2794)
			(stroke
				(width 0.1)
				(type default)
			)
			(layer "F.Fab")
		)
		(fp_line
			(start -0.12065 0.3048)
			(end -0.67945 0.3048)
			(stroke
				(width 0.1)
				(type default)
			)
			(layer "F.Fab")
		)
		(fp_line
			(start -0.67945 0.3048)
			(end -0.67945 -0.305054)
			(stroke
				(width 0.1)
				(type default)
			)
			(layer "F.Fab")
		)
		(pad "1" smd circle
			(at -0.40005 0 90)
			(size 0 0)
			(layers "F.Cu" "F.Mask" "F.Paste")
			(net "SW_PVDD11_S3_P1_SW1_RC")
		)
		(pad "2" smd circle
			(at 0.40005 0 90)
			(size 0 0)
			(layers "F.Cu" "F.Mask" "F.Paste")
			(net "GND")
		)
	)
	(footprint ""
		(layer "F.Cu")
		(at 80.223106 -57.874154 180)
		(property "Reference" "R3571"
			(at 0 0 180)
			(layer "F.SilkS")
			(hide yes)
			(effects
				(font
					(size 1.27 1.27)
				)
			)
		)
		(property "Value" ""
			(at 0 0 180)
			(layer "F.Fab")
			(effects
				(font
					(size 1.27 1.27)
				)
			)
		)
		(duplicate_pad_numbers_are_jumpers no)
		(fp_line
			(start 0.7874 0.4064)
			(end -0.7874 0.4064)
			(stroke
				(width 0.1524)
				(type default)
			)
			(layer "F.SilkS")
		)
		(fp_line
			(start 0.7874 -0.4064)
			(end 0.7874 0.4064)
			(stroke
				(width 0.1524)
				(type default)
			)
			(layer "F.SilkS")
		)
		(fp_line
			(start -0.7874 0.4064)
			(end -0.7874 -0.4064)
			(stroke
				(width 0.1524)
				(type default)
			)
			(layer "F.SilkS")
		)
		(fp_line
			(start -0.7874 -0.4064)
			(end 0.7874 -0.4064)
			(stroke
				(width 0.1524)
				(type default)
			)
			(layer "F.SilkS")
		)
		(fp_line
			(start 0.67945 0.3048)
			(end 0.120396 0.3048)
			(stroke
				(width 0.1)
				(type default)
			)
			(layer "F.Fab")
		)
		(fp_line
			(start 0.67945 -0.3048)
			(end 0.67945 0.3048)
			(stroke
				(width 0.1)
				(type default)
			)
			(layer "F.Fab")
		)
		(fp_line
			(start 0.12065 -0.2794)
			(end 0.12065 -0.3048)
			(stroke
				(width 0.1)
				(type default)
			)
			(layer "F.Fab")
		)
		(fp_line
			(start 0.12065 -0.3048)
			(end 0.67945 -0.3048)
			(stroke
				(width 0.1)
				(type default)
			)
			(layer "F.Fab")
		)
		(fp_line
			(start 0.120396 0.3048)
			(end 0.120396 0.2794)
			(stroke
				(width 0.1)
				(type default)
			)
			(layer "F.Fab")
		)
		(fp_line
			(start 0.120396 0.2794)
			(end -0.12065 0.2794)
			(stroke
				(width 0.1)
				(type default)
			)
			(layer "F.Fab")
		)
		(fp_line
			(start -0.12065 0.3048)
			(end -0.67945 0.3048)
			(stroke
				(width 0.1)
				(type default)
			)
			(layer "F.Fab")
		)
		(fp_line
			(start -0.12065 0.2794)
			(end -0.12065 0.3048)
			(stroke
				(width 0.1)
				(type default)
			)
			(layer "F.Fab")
		)
		(fp_line
			(start -0.12065 -0.2794)
			(end 0.12065 -0.2794)
			(stroke
				(width 0.1)
				(type default)
			)
			(layer "F.Fab")
		)
		(fp_line
			(start -0.12065 -0.305054)
			(end -0.12065 -0.2794)
			(stroke
				(width 0.1)
				(type default)
			)
			(layer "F.Fab")
		)
		(fp_line
			(start -0.67945 0.3048)
			(end -0.67945 -0.305054)
			(stroke
				(width 0.1)
				(type default)
			)
			(layer "F.Fab")
		)
		(fp_line
			(start -0.67945 -0.305054)
			(end -0.12065 -0.305054)
			(stroke
				(width 0.1)
				(type default)
			)
			(layer "F.Fab")
		)
		(pad "1" smd circle
			(at -0.40005 0 180)
			(size 0 0)
			(layers "F.Cu" "F.Mask" "F.Paste")
			(net "P3V3_OCP_V3_2")
		)
		(pad "2" smd circle
			(at 0.40005 0 180)
			(size 0 0)
			(layers "F.Cu" "F.Mask" "F.Paste")
			(net "VSENSE_P12V_INA230_3_INN")
		)
	)
	(footprint ""
		(layer "F.Cu")
		(at 400.407378 -327.395332 180)
		(property "Reference" "R466"
			(at 0 0 180)
			(layer "F.SilkS")
			(hide yes)
			(effects
				(font
					(size 1.27 1.27)
				)
			)
		)
		(property "Value" ""
			(at 0 0 180)
			(layer "F.Fab")
			(effects
				(font
					(size 1.27 1.27)
				)
			)
		)
		(duplicate_pad_numbers_are_jumpers no)
		(fp_line
			(start 0.7874 0.4064)
			(end -0.7874 0.4064)
			(stroke
				(width 0.1524)
				(type default)
			)
			(layer "F.SilkS")
		)
		(fp_line
			(start 0.7874 -0.4064)
			(end 0.7874 0.4064)
			(stroke
				(width 0.1524)
				(type default)
			)
			(layer "F.SilkS")
		)
		(fp_line
			(start -0.7874 0.4064)
			(end -0.7874 -0.4064)
			(stroke
				(width 0.1524)
				(type default)
			)
			(layer "F.SilkS")
		)
		(fp_line
			(start -0.7874 -0.4064)
			(end 0.7874 -0.4064)
			(stroke
				(width 0.1524)
				(type default)
			)
			(layer "F.SilkS")
		)
		(fp_line
			(start 0.67945 0.3048)
			(end 0.120396 0.3048)
			(stroke
				(width 0.1)
				(type default)
			)
			(layer "F.Fab")
		)
		(fp_line
			(start 0.67945 -0.3048)
			(end 0.67945 0.3048)
			(stroke
				(width 0.1)
				(type default)
			)
			(layer "F.Fab")
		)
		(fp_line
			(start 0.12065 -0.2794)
			(end 0.12065 -0.3048)
			(stroke
				(width 0.1)
				(type default)
			)
			(layer "F.Fab")
		)
		(fp_line
			(start 0.12065 -0.3048)
			(end 0.67945 -0.3048)
			(stroke
				(width 0.1)
				(type default)
			)
			(layer "F.Fab")
		)
		(fp_line
			(start 0.120396 0.3048)
			(end 0.120396 0.2794)
			(stroke
				(width 0.1)
				(type default)
			)
			(layer "F.Fab")
		)
		(fp_line
			(start 0.120396 0.2794)
			(end -0.12065 0.2794)
			(stroke
				(width 0.1)
				(type default)
			)
			(layer "F.Fab")
		)
		(fp_line
			(start -0.12065 0.3048)
			(end -0.67945 0.3048)
			(stroke
				(width 0.1)
				(type default)
			)
			(layer "F.Fab")
		)
		(fp_line
			(start -0.12065 0.2794)
			(end -0.12065 0.3048)
			(stroke
				(width 0.1)
				(type default)
			)
			(layer "F.Fab")
		)
		(fp_line
			(start -0.12065 -0.2794)
			(end 0.12065 -0.2794)
			(stroke
				(width 0.1)
				(type default)
			)
			(layer "F.Fab")
		)
		(fp_line
			(start -0.12065 -0.305054)
			(end -0.12065 -0.2794)
			(stroke
				(width 0.1)
				(type default)
			)
			(layer "F.Fab")
		)
		(fp_line
			(start -0.67945 0.3048)
			(end -0.67945 -0.305054)
			(stroke
				(width 0.1)
				(type default)
			)
			(layer "F.Fab")
		)
		(fp_line
			(start -0.67945 -0.305054)
			(end -0.12065 -0.305054)
			(stroke
				(width 0.1)
				(type default)
			)
			(layer "F.Fab")
		)
		(pad "1" smd circle
			(at -0.40005 0 180)
			(size 0 0)
			(layers "F.Cu" "F.Mask" "F.Paste")
			(net "SPI_CPU0_D2")
		)
		(pad "2" smd circle
			(at 0.40005 0 180)
			(size 0 0)
			(layers "F.Cu" "F.Mask" "F.Paste")
			(net "SPI_CPU0_R_D2")
		)
	)
	(footprint ""
		(layer "F.Cu")
		(at 182.664608 -413.786574 -90)
		(property "Reference" "R2921"
			(at 0 0 270)
			(layer "F.SilkS")
			(hide yes)
			(effects
				(font
					(size 1.27 1.27)
				)
			)
		)
		(property "Value" ""
			(at 0 0 270)
			(layer "F.Fab")
			(effects
				(font
					(size 1.27 1.27)
				)
			)
		)
		(duplicate_pad_numbers_are_jumpers no)
		(fp_line
			(start -0.7874 0.4064)
			(end -0.7874 -0.4064)
			(stroke
				(width 0.1524)
				(type default)
			)
			(layer "F.SilkS")
		)
		(fp_line
			(start 0.7874 0.4064)
			(end -0.7874 0.4064)
			(stroke
				(width 0.1524)
				(type default)
			)
			(layer "F.SilkS")
		)
		(fp_line
			(start -0.7874 -0.4064)
			(end 0.7874 -0.4064)
			(stroke
				(width 0.1524)
				(type default)
			)
			(layer "F.SilkS")
		)
		(fp_line
			(start 0.7874 -0.4064)
			(end 0.7874 0.4064)
			(stroke
				(width 0.1524)
				(type default)
			)
			(layer "F.SilkS")
		)
		(fp_line
			(start -0.67945 0.3048)
			(end -0.67945 -0.305054)
			(stroke
				(width 0.1)
				(type default)
			)
			(layer "F.Fab")
		)
		(fp_line
			(start -0.12065 0.3048)
			(end -0.67945 0.3048)
			(stroke
				(width 0.1)
				(type default)
			)
			(layer "F.Fab")
		)
		(fp_line
			(start 0.120396 0.3048)
			(end 0.120396 0.2794)
			(stroke
				(width 0.1)
				(type default)
			)
			(layer "F.Fab")
		)
		(fp_line
			(start 0.67945 0.3048)
			(end 0.120396 0.3048)
			(stroke
				(width 0.1)
				(type default)
			)
			(layer "F.Fab")
		)
		(fp_line
			(start -0.12065 0.2794)
			(end -0.12065 0.3048)
			(stroke
				(width 0.1)
				(type default)
			)
			(layer "F.Fab")
		)
		(fp_line
			(start 0.120396 0.2794)
			(end -0.12065 0.2794)
			(stroke
				(width 0.1)
				(type default)
			)
			(layer "F.Fab")
		)
		(fp_line
			(start -0.12065 -0.2794)
			(end 0.12065 -0.2794)
			(stroke
				(width 0.1)
				(type default)
			)
			(layer "F.Fab")
		)
		(fp_line
			(start 0.12065 -0.2794)
			(end 0.12065 -0.3048)
			(stroke
				(width 0.1)
				(type default)
			)
			(layer "F.Fab")
		)
		(fp_line
			(start 0.12065 -0.3048)
			(end 0.67945 -0.3048)
			(stroke
				(width 0.1)
				(type default)
			)
			(layer "F.Fab")
		)
		(fp_line
			(start 0.67945 -0.3048)
			(end 0.67945 0.3048)
			(stroke
				(width 0.1)
				(type default)
			)
			(layer "F.Fab")
		)
		(fp_line
			(start -0.67945 -0.305054)
			(end -0.12065 -0.305054)
			(stroke
				(width 0.1)
				(type default)
			)
			(layer "F.Fab")
		)
		(fp_line
			(start -0.12065 -0.305054)
			(end -0.12065 -0.2794)
			(stroke
				(width 0.1)
				(type default)
			)
			(layer "F.Fab")
		)
		(pad "1" smd circle
			(at -0.40005 0 270)
			(size 0 0)
			(layers "F.Cu" "F.Mask" "F.Paste")
			(net "P3V3_AUX")
		)
		(pad "2" smd circle
			(at 0.40005 0 270)
			(size 0 0)
			(layers "F.Cu" "F.Mask" "F.Paste")
			(net "RST_SMB_SWITCH_N")
		)
	)
	(footprint ""
		(layer "F.Cu")
		(at 185.801 -92.674948 90)
		(property "Reference" "R6075"
			(at 0 0 90)
			(layer "F.SilkS")
			(hide yes)
			(effects
				(font
					(size 1.27 1.27)
				)
			)
		)
		(property "Value" ""
			(at 0 0 90)
			(layer "F.Fab")
			(effects
				(font
					(size 1.27 1.27)
				)
			)
		)
		(duplicate_pad_numbers_are_jumpers no)
		(fp_line
			(start 0.7874 -0.4064)
			(end 0.7874 0.4064)
			(stroke
				(width 0.1524)
				(type default)
			)
			(layer "F.SilkS")
		)
		(fp_line
			(start -0.7874 -0.4064)
			(end 0.7874 -0.4064)
			(stroke
				(width 0.1524)
				(type default)
			)
			(layer "F.SilkS")
		)
		(fp_line
			(start 0.7874 0.4064)
			(end -0.7874 0.4064)
			(stroke
				(width 0.1524)
				(type default)
			)
			(layer "F.SilkS")
		)
		(fp_line
			(start -0.7874 0.4064)
			(end -0.7874 -0.4064)
			(stroke
				(width 0.1524)
				(type default)
			)
			(layer "F.SilkS")
		)
		(fp_line
			(start -0.12065 -0.305054)
			(end -0.12065 -0.2794)
			(stroke
				(width 0.1)
				(type default)
			)
			(layer "F.Fab")
		)
		(fp_line
			(start -0.67945 -0.305054)
			(end -0.12065 -0.305054)
			(stroke
				(width 0.1)
				(type default)
			)
			(layer "F.Fab")
		)
		(fp_line
			(start 0.67945 -0.3048)
			(end 0.67945 0.3048)
			(stroke
				(width 0.1)
				(type default)
			)
			(layer "F.Fab")
		)
		(fp_line
			(start 0.12065 -0.3048)
			(end 0.67945 -0.3048)
			(stroke
				(width 0.1)
				(type default)
			)
			(layer "F.Fab")
		)
		(fp_line
			(start 0.12065 -0.2794)
			(end 0.12065 -0.3048)
			(stroke
				(width 0.1)
				(type default)
			)
			(layer "F.Fab")
		)
		(fp_line
			(start -0.12065 -0.2794)
			(end 0.12065 -0.2794)
			(stroke
				(width 0.1)
				(type default)
			)
			(layer "F.Fab")
		)
		(fp_line
			(start 0.120396 0.2794)
			(end -0.12065 0.2794)
			(stroke
				(width 0.1)
				(type default)
			)
			(layer "F.Fab")
		)
		(fp_line
			(start -0.12065 0.2794)
			(end -0.12065 0.3048)
			(stroke
				(width 0.1)
				(type default)
			)
			(layer "F.Fab")
		)
		(fp_line
			(start 0.67945 0.3048)
			(end 0.120396 0.3048)
			(stroke
				(width 0.1)
				(type default)
			)
			(layer "F.Fab")
		)
		(fp_line
			(start 0.120396 0.3048)
			(end 0.120396 0.2794)
			(stroke
				(width 0.1)
				(type default)
			)
			(layer "F.Fab")
		)
		(fp_line
			(start -0.12065 0.3048)
			(end -0.67945 0.3048)
			(stroke
				(width 0.1)
				(type default)
			)
			(layer "F.Fab")
		)
		(fp_line
			(start -0.67945 0.3048)
			(end -0.67945 -0.305054)
			(stroke
				(width 0.1)
				(type default)
			)
			(layer "F.Fab")
		)
		(pad "1" smd circle
			(at -0.40005 0 90)
			(size 0 0)
			(layers "F.Cu" "F.Mask" "F.Paste")
			(net "LED_HDD_ACTIVITY_B_N")
		)
		(pad "2" smd circle
			(at 0.40005 0 90)
			(size 0 0)
			(layers "F.Cu" "F.Mask" "F.Paste")
			(net "LED_HDD_ACTIVITY_B_PLD_N")
		)
	)
	(footprint ""
		(layer "F.Cu")
		(at 69.741034 -376.982228)
		(property "Reference" "C808"
			(at 0 0 0)
			(layer "F.SilkS")
			(hide yes)
			(effects
				(font
					(size 1.27 1.27)
				)
			)
		)
		(property "Value" ""
			(at 0 0 0)
			(layer "F.Fab")
			(effects
				(font
					(size 1.27 1.27)
				)
			)
		)
		(duplicate_pad_numbers_are_jumpers no)
		(fp_line
			(start -0.299974 -0.150114)
			(end 0.299974 -0.150114)
			(stroke
				(width 0.1)
				(type default)
			)
			(layer "F.Fab")
		)
		(fp_line
			(start -0.299974 0.150114)
			(end -0.299974 -0.150114)
			(stroke
				(width 0.1)
				(type default)
			)
			(layer "F.Fab")
		)
		(fp_line
			(start 0.299974 -0.150114)
			(end 0.299974 0.150114)
			(stroke
				(width 0.1)
				(type default)
			)
			(layer "F.Fab")
		)
		(fp_line
			(start 0.299974 0.150114)
			(end -0.299974 0.150114)
			(stroke
				(width 0.1)
				(type default)
			)
			(layer "F.Fab")
		)
		(pad "1" smd rect
			(at -0.2667 0)
			(size 0.3048 0.381)
			(layers "F.Cu" "F.Mask" "F.Paste")
			(net "P5E_CPU1_P0_TX_C_DN<14>")
		)
		(pad "2" smd rect
			(at 0.2667 0)
			(size 0.3048 0.381)
			(layers "F.Cu" "F.Mask" "F.Paste")
			(net "P5E_CPU1_P0_TX_DN<14>")
		)
	)
	(footprint ""
		(layer "F.Cu")
		(at 119.37365 -437.843422 -90)
		(property "Reference" "U257"
			(at 1.368044 1.755648 90)
			(unlocked yes)
			(layer "F.SilkS")
			(effects
				(font
					(size 0.7874 0.5842)
					(thickness 0.1524)
				)
				(justify left)
			)
		)
		(property "Value" ""
			(at 0 0 270)
			(layer "F.Fab")
			(effects
				(font
					(size 1.27 1.27)
				)
			)
		)
		(duplicate_pad_numbers_are_jumpers no)
		(fp_line
			(start -1.38176 1.100074)
			(end 1.38176 1.100074)
			(stroke
				(width 0.1524)
				(type default)
			)
			(layer "F.SilkS")
		)
		(fp_line
			(start 1.38176 1.100074)
			(end 1.38176 -1.100074)
			(stroke
				(width 0.1524)
				(type default)
			)
			(layer "F.SilkS")
		)
		(fp_line
			(start 0 -0.508)
			(end -0.592074 -1.100074)
			(stroke
				(width 0.1524)
				(type default)
			)
			(layer "F.SilkS")
		)
		(fp_line
			(start -1.38176 -1.100074)
			(end -1.38176 1.100074)
			(stroke
				(width 0.1524)
				(type default)
			)
			(layer "F.SilkS")
		)
		(fp_line
			(start -0.592074 -1.100074)
			(end -1.38176 -1.100074)
			(stroke
				(width 0.1524)
				(type default)
			)
			(layer "F.SilkS")
		)
		(fp_line
			(start 0.592074 -1.100074)
			(end 0 -0.508)
			(stroke
				(width 0.1524)
				(type default)
			)
			(layer "F.SilkS")
		)
		(fp_line
			(start 1.38176 -1.100074)
			(end 0.592074 -1.100074)
			(stroke
				(width 0.1524)
				(type default)
			)
			(layer "F.SilkS")
		)
		(fp_poly
			(pts
				(xy -1.998472 -1.387094) (xy -1.687068 -1.698498) (xy -1.531112 -1.231138)
			)
			(stroke
				(width 0)
				(type default)
			)
			(fill yes)
			(layer "F.SilkS")
		)
		(fp_line
			(start -0.674878 1.100074)
			(end 0.674878 1.100074)
			(stroke
				(width 0.1)
				(type default)
			)
			(layer "F.Fab")
		)
		(fp_line
			(start 0.674878 1.100074)
			(end 0.674878 -1.100074)
			(stroke
				(width 0.1)
				(type default)
			)
			(layer "F.Fab")
		)
		(fp_line
			(start -0.674878 -1.100074)
			(end -0.674878 1.100074)
			(stroke
				(width 0.1)
				(type default)
			)
			(layer "F.Fab")
		)
		(fp_line
			(start 0.674878 -1.100074)
			(end -0.674878 -1.100074)
			(stroke
				(width 0.1)
				(type default)
			)
			(layer "F.Fab")
		)
		(fp_poly
			(pts
				(xy -1.9431 -0.870204) (xy -1.50241 -0.649986) (xy -1.9431 -0.429768)
			)
			(stroke
				(width 0)
				(type default)
			)
			(fill yes)
			(layer "F.Fab")
		)
		(pad "1" smd rect
			(at -0.94996 -0.649986 180)
			(size 0.4318 0.6096)
			(layers "F.Cu" "F.Mask" "F.Paste")
			(net "GPU_FPGA_EROT_RECOV_N")
		)
		(pad "2" smd rect
			(at -0.94996 0 180)
			(size 0.4318 0.6096)
			(layers "F.Cu" "F.Mask" "F.Paste")
			(net "GND")
		)
		(pad "3" smd rect
			(at -0.94996 0.649986 180)
			(size 0.4318 0.6096)
			(layers "F.Cu" "F.Mask" "F.Paste")
			(net "GND")
		)
		(pad "4" smd rect
			(at 0.94996 0.649986 180)
			(size 0.4318 0.6096)
			(layers "F.Cu" "F.Mask" "F.Paste")
			(net "NC_U257_2Y")
		)
		(pad "5" smd rect
			(at 0.94996 0 180)
			(size 0.4318 0.6096)
			(layers "F.Cu" "F.Mask" "F.Paste")
			(net "P3V3_AUX")
		)
		(pad "6" smd rect
			(at 0.94996 -0.649986 180)
			(size 0.4318 0.6096)
			(layers "F.Cu" "F.Mask" "F.Paste")
			(net "GPU_FPGA_EROT_RECOV_BUF_R_N")
		)
	)
	(footprint ""
		(layer "F.Cu")
		(at 209.78622 -137.127488 180)
		(property "Reference" "U158"
			(at -0.62992 2.298192 0)
			(unlocked yes)
			(layer "F.SilkS")
			(effects
				(font
					(size 0.7874 0.5842)
					(thickness 0.1524)
				)
				(justify left)
			)
		)
		(property "Value" ""
			(at 0 0 180)
			(layer "F.Fab")
			(effects
				(font
					(size 1.27 1.27)
				)
			)
		)
		(duplicate_pad_numbers_are_jumpers no)
		(fp_line
			(start 1.603248 1.500124)
			(end -1.603248 1.500124)
			(stroke
				(width 0.1524)
				(type default)
			)
			(layer "F.SilkS")
		)
		(fp_line
			(start 1.603248 -1.500124)
			(end 1.603248 1.500124)
			(stroke
				(width 0.1524)
				(type default)
			)
			(layer "F.SilkS")
		)
		(fp_line
			(start -1.603248 1.500124)
			(end -1.603248 -1.500124)
			(stroke
				(width 0.1524)
				(type default)
			)
			(layer "F.SilkS")
		)
		(fp_line
			(start -1.603248 -1.500124)
			(end 1.603248 -1.500124)
			(stroke
				(width 0.1524)
				(type default)
			)
			(layer "F.SilkS")
		)
		(fp_line
			(start 1.249934 0.219964)
			(end 1.249934 -0.219964)
			(stroke
				(width 0.1)
				(type default)
			)
			(layer "F.Fab")
		)
		(fp_line
			(start 1.249934 -0.219964)
			(end 0.700024 -0.219964)
			(stroke
				(width 0.1)
				(type default)
			)
			(layer "F.Fab")
		)
		(fp_line
			(start 0.700024 1.500124)
			(end 0.700024 0.219964)
			(stroke
				(width 0.1)
				(type default)
			)
			(layer "F.Fab")
		)
		(fp_line
			(start 0.700024 0.219964)
			(end 1.249934 0.219964)
			(stroke
				(width 0.1)
				(type default)
			)
			(layer "F.Fab")
		)
		(fp_line
			(start 0.700024 -0.219964)
			(end 0.700024 -1.500124)
			(stroke
				(width 0.1)
				(type default)
			)
			(layer "F.Fab")
		)
		(fp_line
			(start 0.700024 -1.500124)
			(end -0.700024 -1.500124)
			(stroke
				(width 0.1)
				(type default)
			)
			(layer "F.Fab")
		)
		(fp_line
			(start -0.6985 0.729996)
			(end -1.249934 0.729996)
			(stroke
				(width 0.1)
				(type default)
			)
			(layer "F.Fab")
		)
		(fp_line
			(start -0.6985 -0.729996)
			(end -0.6985 0.729996)
			(stroke
				(width 0.1)
				(type default)
			)
			(layer "F.Fab")
		)
		(fp_line
			(start -0.700024 1.500124)
			(end 0.700024 1.500124)
			(stroke
				(width 0.1)
				(type default)
			)
			(layer "F.Fab")
		)
		(fp_line
			(start -0.700024 1.169924)
			(end -0.700024 1.500124)
			(stroke
				(width 0.1)
				(type default)
			)
			(layer "F.Fab")
		)
		(fp_line
			(start -0.700024 -1.169924)
			(end -1.249934 -1.169924)
			(stroke
				(width 0.1)
				(type default)
			)
			(layer "F.Fab")
		)
		(fp_line
			(start -0.700024 -1.500124)
			(end -0.700024 -1.169924)
			(stroke
				(width 0.1)
				(type default)
			)
			(layer "F.Fab")
		)
		(fp_line
			(start -1.249934 1.169924)
			(end -0.700024 1.169924)
			(stroke
				(width 0.1)
				(type default)
			)
			(layer "F.Fab")
		)
		(fp_line
			(start -1.249934 0.729996)
			(end -1.249934 1.169924)
			(stroke
				(width 0.1)
				(type default)
			)
			(layer "F.Fab")
		)
		(fp_line
			(start -1.249934 -0.729996)
			(end -0.6985 -0.729996)
			(stroke
				(width 0.1)
				(type default)
			)
			(layer "F.Fab")
		)
		(fp_line
			(start -1.249934 -1.169924)
			(end -1.249934 -0.729996)
			(stroke
				(width 0.1)
				(type default)
			)
			(layer "F.Fab")
		)
		(fp_rect
			(start 0.700024 -1.500124)
			(end -0.700024 1.500124)
			(stroke
				(width 0)
				(type default)
			)
			(fill no)
			(layer "F.Fab")
		)
		(pad "D" smd rect
			(at 0.999998 0 90)
			(size 0.8128 0.9144)
			(layers "F.Cu" "F.Mask" "F.Paste")
			(net "FM_P12V_HSC_EN_N")
		)
		(pad "G" smd rect
			(at -0.999998 -0.94996 90)
			(size 0.8128 0.9144)
			(layers "F.Cu" "F.Mask" "F.Paste")
			(net "FM_P12V_HSC_EN_R")
		)
		(pad "S" smd rect
			(at -0.999998 0.94996 90)
			(size 0.8128 0.9144)
			(layers "F.Cu" "F.Mask" "F.Paste")
			(net "GND")
		)
	)
	(footprint ""
		(layer "F.Cu")
		(at 39.95039 -426.563536 180)
		(property "Reference" "C6007"
			(at 0 0 180)
			(layer "F.SilkS")
			(hide yes)
			(effects
				(font
					(size 1.27 1.27)
				)
			)
		)
		(property "Value" ""
			(at 0 0 180)
			(layer "F.Fab")
			(effects
				(font
					(size 1.27 1.27)
				)
			)
		)
		(duplicate_pad_numbers_are_jumpers no)
		(fp_line
			(start 0.7874 0.4064)
			(end -0.7874 0.4064)
			(stroke
				(width 0.1524)
				(type default)
			)
			(layer "F.SilkS")
		)
		(fp_line
			(start 0.7874 -0.275336)
			(end 0.7874 0.4064)
			(stroke
				(width 0.1524)
				(type default)
			)
			(layer "F.SilkS")
		)
		(fp_line
			(start -0.7874 -0.4064)
			(end -0.35941 -0.4064)
			(stroke
				(width 0.1524)
				(type default)
			)
			(layer "F.SilkS")
		)
		(fp_line
			(start 0.6858 0.3048)
			(end 0.1016 0.3048)
			(stroke
				(width 0.1)
				(type default)
			)
			(layer "F.Fab")
		)
		(fp_line
			(start 0.6858 -0.3048)
			(end 0.6858 0.3048)
			(stroke
				(width 0.1)
				(type default)
			)
			(layer "F.Fab")
		)
		(fp_line
			(start 0.1016 0.3048)
			(end 0.1016 0.2794)
			(stroke
				(width 0.1)
				(type default)
			)
			(layer "F.Fab")
		)
		(fp_line
			(start 0.1016 0.2794)
			(end -0.1016 0.2794)
			(stroke
				(width 0.1)
				(type default)
			)
			(layer "F.Fab")
		)
		(fp_line
			(start 0.1016 -0.2794)
			(end 0.1016 -0.3048)
			(stroke
				(width 0.1)
				(type default)
			)
			(layer "F.Fab")
		)
		(fp_line
			(start 0.1016 -0.3048)
			(end 0.6858 -0.3048)
			(stroke
				(width 0.1)
				(type default)
			)
			(layer "F.Fab")
		)
		(fp_line
			(start -0.1016 0.3048)
			(end -0.6858 0.3048)
			(stroke
				(width 0.1)
				(type default)
			)
			(layer "F.Fab")
		)
		(fp_line
			(start -0.1016 0.2794)
			(end -0.1016 0.3048)
			(stroke
				(width 0.1)
				(type default)
			)
			(layer "F.Fab")
		)
		(fp_line
			(start -0.1016 -0.2794)
			(end 0.1016 -0.2794)
			(stroke
				(width 0.1)
				(type default)
			)
			(layer "F.Fab")
		)
		(fp_line
			(start -0.1016 -0.3048)
			(end -0.1016 -0.2794)
			(stroke
				(width 0.1)
				(type default)
			)
			(layer "F.Fab")
		)
		(fp_line
			(start -0.6858 0.3048)
			(end -0.6858 -0.3048)
			(stroke
				(width 0.1)
				(type default)
			)
			(layer "F.Fab")
		)
		(fp_line
			(start -0.6858 -0.3048)
			(end -0.1016 -0.3048)
			(stroke
				(width 0.1)
				(type default)
			)
			(layer "F.Fab")
		)
		(pad "1" smd rect
			(at -0.40005 0)
			(size 0.4572 0.508)
			(layers "F.Cu" "F.Mask" "F.Paste")
			(net "P2E_MB_BMC_RX_BUF2_C_DP<0>")
		)
		(pad "2" smd rect
			(at 0.40005 0)
			(size 0.4572 0.508)
			(layers "F.Cu" "F.Mask" "F.Paste")
			(net "P2E_MB_BMC_RX_BUF_DP<0>")
		)
	)
	(footprint ""
		(layer "F.Cu")
		(at 101.421946 -54.882034 90)
		(property "Reference" "R6321"
			(at 0 0 90)
			(layer "F.SilkS")
			(hide yes)
			(effects
				(font
					(size 1.27 1.27)
				)
			)
		)
		(property "Value" ""
			(at 0 0 90)
			(layer "F.Fab")
			(effects
				(font
					(size 1.27 1.27)
				)
			)
		)
		(duplicate_pad_numbers_are_jumpers no)
		(fp_line
			(start 0.7874 -0.4064)
			(end 0.7874 0.4064)
			(stroke
				(width 0.1524)
				(type default)
			)
			(layer "F.SilkS")
		)
		(fp_line
			(start -0.7874 -0.4064)
			(end 0.7874 -0.4064)
			(stroke
				(width 0.1524)
				(type default)
			)
			(layer "F.SilkS")
		)
		(fp_line
			(start 0.7874 0.4064)
			(end -0.7874 0.4064)
			(stroke
				(width 0.1524)
				(type default)
			)
			(layer "F.SilkS")
		)
		(fp_line
			(start -0.7874 0.4064)
			(end -0.7874 -0.4064)
			(stroke
				(width 0.1524)
				(type default)
			)
			(layer "F.SilkS")
		)
		(fp_line
			(start -0.12065 -0.305054)
			(end -0.12065 -0.2794)
			(stroke
				(width 0.1)
				(type default)
			)
			(layer "F.Fab")
		)
		(fp_line
			(start -0.67945 -0.305054)
			(end -0.12065 -0.305054)
			(stroke
				(width 0.1)
				(type default)
			)
			(layer "F.Fab")
		)
		(fp_line
			(start 0.67945 -0.3048)
			(end 0.67945 0.3048)
			(stroke
				(width 0.1)
				(type default)
			)
			(layer "F.Fab")
		)
		(fp_line
			(start 0.12065 -0.3048)
			(end 0.67945 -0.3048)
			(stroke
				(width 0.1)
				(type default)
			)
			(layer "F.Fab")
		)
		(fp_line
			(start 0.12065 -0.2794)
			(end 0.12065 -0.3048)
			(stroke
				(width 0.1)
				(type default)
			)
			(layer "F.Fab")
		)
		(fp_line
			(start -0.12065 -0.2794)
			(end 0.12065 -0.2794)
			(stroke
				(width 0.1)
				(type default)
			)
			(layer "F.Fab")
		)
		(fp_line
			(start 0.120396 0.2794)
			(end -0.12065 0.2794)
			(stroke
				(width 0.1)
				(type default)
			)
			(layer "F.Fab")
		)
		(fp_line
			(start -0.12065 0.2794)
			(end -0.12065 0.3048)
			(stroke
				(width 0.1)
				(type default)
			)
			(layer "F.Fab")
		)
		(fp_line
			(start 0.67945 0.3048)
			(end 0.120396 0.3048)
			(stroke
				(width 0.1)
				(type default)
			)
			(layer "F.Fab")
		)
		(fp_line
			(start 0.120396 0.3048)
			(end 0.120396 0.2794)
			(stroke
				(width 0.1)
				(type default)
			)
			(layer "F.Fab")
		)
		(fp_line
			(start -0.12065 0.3048)
			(end -0.67945 0.3048)
			(stroke
				(width 0.1)
				(type default)
			)
			(layer "F.Fab")
		)
		(fp_line
			(start -0.67945 0.3048)
			(end -0.67945 -0.305054)
			(stroke
				(width 0.1)
				(type default)
			)
			(layer "F.Fab")
		)
		(pad "1" smd circle
			(at -0.40005 0 90)
			(size 0 0)
			(layers "F.Cu" "F.Mask" "F.Paste")
			(net "USB_HUB2_MRP_RESET_N")
		)
		(pad "2" smd circle
			(at 0.40005 0 90)
			(size 0 0)
			(layers "F.Cu" "F.Mask" "F.Paste")
			(net "GND")
		)
	)
	(footprint ""
		(layer "F.Cu")
		(at 111.422942 -19.9898 -90)
		(property "Reference" "R6260"
			(at 0 0 270)
			(layer "F.SilkS")
			(hide yes)
			(effects
				(font
					(size 1.27 1.27)
				)
			)
		)
		(property "Value" ""
			(at 0 0 270)
			(layer "F.Fab")
			(effects
				(font
					(size 1.27 1.27)
				)
			)
		)
		(duplicate_pad_numbers_are_jumpers no)
		(fp_line
			(start -0.7874 0.4064)
			(end -0.7874 -0.4064)
			(stroke
				(width 0.1524)
				(type default)
			)
			(layer "F.SilkS")
		)
		(fp_line
			(start 0.7874 0.4064)
			(end -0.7874 0.4064)
			(stroke
				(width 0.1524)
				(type default)
			)
			(layer "F.SilkS")
		)
		(fp_line
			(start -0.7874 -0.4064)
			(end 0.7874 -0.4064)
			(stroke
				(width 0.1524)
				(type default)
			)
			(layer "F.SilkS")
		)
		(fp_line
			(start 0.7874 -0.4064)
			(end 0.7874 0.4064)
			(stroke
				(width 0.1524)
				(type default)
			)
			(layer "F.SilkS")
		)
		(fp_line
			(start -0.67945 0.3048)
			(end -0.67945 -0.305054)
			(stroke
				(width 0.1)
				(type default)
			)
			(layer "F.Fab")
		)
		(fp_line
			(start -0.12065 0.3048)
			(end -0.67945 0.3048)
			(stroke
				(width 0.1)
				(type default)
			)
			(layer "F.Fab")
		)
		(fp_line
			(start 0.120396 0.3048)
			(end 0.120396 0.2794)
			(stroke
				(width 0.1)
				(type default)
			)
			(layer "F.Fab")
		)
		(fp_line
			(start 0.67945 0.3048)
			(end 0.120396 0.3048)
			(stroke
				(width 0.1)
				(type default)
			)
			(layer "F.Fab")
		)
		(fp_line
			(start -0.12065 0.2794)
			(end -0.12065 0.3048)
			(stroke
				(width 0.1)
				(type default)
			)
			(layer "F.Fab")
		)
		(fp_line
			(start 0.120396 0.2794)
			(end -0.12065 0.2794)
			(stroke
				(width 0.1)
				(type default)
			)
			(layer "F.Fab")
		)
		(fp_line
			(start -0.12065 -0.2794)
			(end 0.12065 -0.2794)
			(stroke
				(width 0.1)
				(type default)
			)
			(layer "F.Fab")
		)
		(fp_line
			(start 0.12065 -0.2794)
			(end 0.12065 -0.3048)
			(stroke
				(width 0.1)
				(type default)
			)
			(layer "F.Fab")
		)
		(fp_line
			(start 0.12065 -0.3048)
			(end 0.67945 -0.3048)
			(stroke
				(width 0.1)
				(type default)
			)
			(layer "F.Fab")
		)
		(fp_line
			(start 0.67945 -0.3048)
			(end 0.67945 0.3048)
			(stroke
				(width 0.1)
				(type default)
			)
			(layer "F.Fab")
		)
		(fp_line
			(start -0.67945 -0.305054)
			(end -0.12065 -0.305054)
			(stroke
				(width 0.1)
				(type default)
			)
			(layer "F.Fab")
		)
		(fp_line
			(start -0.12065 -0.305054)
			(end -0.12065 -0.2794)
			(stroke
				(width 0.1)
				(type default)
			)
			(layer "F.Fab")
		)
		(pad "1" smd circle
			(at -0.40005 0 270)
			(size 0 0)
			(layers "F.Cu" "F.Mask" "F.Paste")
			(net "USB_HUB2_TI_VDD_MRP_USB3DN_TXDM1")
		)
		(pad "2" smd circle
			(at 0.40005 0 270)
			(size 0 0)
			(layers "F.Cu" "F.Mask" "F.Paste")
			(net "P1V2_CPU0_USB2_DVDD12")
		)
	)
	(footprint ""
		(layer "F.Cu")
		(at 178.044602 -32.950912 90)
		(property "Reference" "PR3999"
			(at 0 0 90)
			(layer "F.SilkS")
			(hide yes)
			(effects
				(font
					(size 1.27 1.27)
				)
			)
		)
		(property "Value" ""
			(at 0 0 90)
			(layer "F.Fab")
			(effects
				(font
					(size 1.27 1.27)
				)
			)
		)
		(duplicate_pad_numbers_are_jumpers no)
		(fp_line
			(start 0.7874 -0.4064)
			(end 0.7874 0.4064)
			(stroke
				(width 0.1524)
				(type default)
			)
			(layer "F.SilkS")
		)
		(fp_line
			(start -0.7874 -0.4064)
			(end 0.7874 -0.4064)
			(stroke
				(width 0.1524)
				(type default)
			)
			(layer "F.SilkS")
		)
		(fp_line
			(start 0.7874 0.4064)
			(end -0.7874 0.4064)
			(stroke
				(width 0.1524)
				(type default)
			)
			(layer "F.SilkS")
		)
		(fp_line
			(start -0.7874 0.4064)
			(end -0.7874 -0.4064)
			(stroke
				(width 0.1524)
				(type default)
			)
			(layer "F.SilkS")
		)
		(fp_line
			(start -0.12065 -0.305054)
			(end -0.12065 -0.2794)
			(stroke
				(width 0.1)
				(type default)
			)
			(layer "F.Fab")
		)
		(fp_line
			(start -0.67945 -0.305054)
			(end -0.12065 -0.305054)
			(stroke
				(width 0.1)
				(type default)
			)
			(layer "F.Fab")
		)
		(fp_line
			(start 0.67945 -0.3048)
			(end 0.67945 0.3048)
			(stroke
				(width 0.1)
				(type default)
			)
			(layer "F.Fab")
		)
		(fp_line
			(start 0.12065 -0.3048)
			(end 0.67945 -0.3048)
			(stroke
				(width 0.1)
				(type default)
			)
			(layer "F.Fab")
		)
		(fp_line
			(start 0.12065 -0.2794)
			(end 0.12065 -0.3048)
			(stroke
				(width 0.1)
				(type default)
			)
			(layer "F.Fab")
		)
		(fp_line
			(start -0.12065 -0.2794)
			(end 0.12065 -0.2794)
			(stroke
				(width 0.1)
				(type default)
			)
			(layer "F.Fab")
		)
		(fp_line
			(start 0.120396 0.2794)
			(end -0.12065 0.2794)
			(stroke
				(width 0.1)
				(type default)
			)
			(layer "F.Fab")
		)
		(fp_line
			(start -0.12065 0.2794)
			(end -0.12065 0.3048)
			(stroke
				(width 0.1)
				(type default)
			)
			(layer "F.Fab")
		)
		(fp_line
			(start 0.67945 0.3048)
			(end 0.120396 0.3048)
			(stroke
				(width 0.1)
				(type default)
			)
			(layer "F.Fab")
		)
		(fp_line
			(start 0.120396 0.3048)
			(end 0.120396 0.2794)
			(stroke
				(width 0.1)
				(type default)
			)
			(layer "F.Fab")
		)
		(fp_line
			(start -0.12065 0.3048)
			(end -0.67945 0.3048)
			(stroke
				(width 0.1)
				(type default)
			)
			(layer "F.Fab")
		)
		(fp_line
			(start -0.67945 0.3048)
			(end -0.67945 -0.305054)
			(stroke
				(width 0.1)
				(type default)
			)
			(layer "F.Fab")
		)
		(pad "1" smd circle
			(at -0.40005 0 90)
			(size 0 0)
			(layers "F.Cu" "F.Mask" "F.Paste")
			(net "P12V_SCM_ISET")
		)
		(pad "2" smd circle
			(at 0.40005 0 90)
			(size 0 0)
			(layers "F.Cu" "F.Mask" "F.Paste")
			(net "GND")
		)
	)
	(footprint ""
		(layer "F.Cu")
		(at 22.479 -366.903)
		(property "Reference" "R1321"
			(at 0 0 0)
			(layer "F.SilkS")
			(hide yes)
			(effects
				(font
					(size 1.27 1.27)
				)
			)
		)
		(property "Value" ""
			(at 0 0 0)
			(layer "F.Fab")
			(effects
				(font
					(size 1.27 1.27)
				)
			)
		)
		(duplicate_pad_numbers_are_jumpers no)
		(fp_line
			(start -0.7874 -0.4064)
			(end 0.7874 -0.4064)
			(stroke
				(width 0.1524)
				(type default)
			)
			(layer "F.SilkS")
		)
		(fp_line
			(start -0.7874 0.4064)
			(end -0.7874 -0.4064)
			(stroke
				(width 0.1524)
				(type default)
			)
			(layer "F.SilkS")
		)
		(fp_line
			(start 0.7874 -0.4064)
			(end 0.7874 0.4064)
			(stroke
				(width 0.1524)
				(type default)
			)
			(layer "F.SilkS")
		)
		(fp_line
			(start 0.7874 0.4064)
			(end -0.7874 0.4064)
			(stroke
				(width 0.1524)
				(type default)
			)
			(layer "F.SilkS")
		)
		(fp_line
			(start -0.67945 -0.305054)
			(end -0.12065 -0.305054)
			(stroke
				(width 0.1)
				(type default)
			)
			(layer "F.Fab")
		)
		(fp_line
			(start -0.67945 0.3048)
			(end -0.67945 -0.305054)
			(stroke
				(width 0.1)
				(type default)
			)
			(layer "F.Fab")
		)
		(fp_line
			(start -0.12065 -0.305054)
			(end -0.12065 -0.2794)
			(stroke
				(width 0.1)
				(type default)
			)
			(layer "F.Fab")
		)
		(fp_line
			(start -0.12065 -0.2794)
			(end 0.12065 -0.2794)
			(stroke
				(width 0.1)
				(type default)
			)
			(layer "F.Fab")
		)
		(fp_line
			(start -0.12065 0.2794)
			(end -0.12065 0.3048)
			(stroke
				(width 0.1)
				(type default)
			)
			(layer "F.Fab")
		)
		(fp_line
			(start -0.12065 0.3048)
			(end -0.67945 0.3048)
			(stroke
				(width 0.1)
				(type default)
			)
			(layer "F.Fab")
		)
		(fp_line
			(start 0.120396 0.2794)
			(end -0.12065 0.2794)
			(stroke
				(width 0.1)
				(type default)
			)
			(layer "F.Fab")
		)
		(fp_line
			(start 0.120396 0.3048)
			(end 0.120396 0.2794)
			(stroke
				(width 0.1)
				(type default)
			)
			(layer "F.Fab")
		)
		(fp_line
			(start 0.12065 -0.3048)
			(end 0.67945 -0.3048)
			(stroke
				(width 0.1)
				(type default)
			)
			(layer "F.Fab")
		)
		(fp_line
			(start 0.12065 -0.2794)
			(end 0.12065 -0.3048)
			(stroke
				(width 0.1)
				(type default)
			)
			(layer "F.Fab")
		)
		(fp_line
			(start 0.67945 -0.3048)
			(end 0.67945 0.3048)
			(stroke
				(width 0.1)
				(type default)
			)
			(layer "F.Fab")
		)
		(fp_line
			(start 0.67945 0.3048)
			(end 0.120396 0.3048)
			(stroke
				(width 0.1)
				(type default)
			)
			(layer "F.Fab")
		)
		(pad "1" smd circle
			(at -0.40005 0)
			(size 0 0)
			(layers "F.Cu" "F.Mask" "F.Paste")
			(net "SMB_VR_3V3STBY_SCL")
		)
		(pad "2" smd circle
			(at 0.40005 0)
			(size 0 0)
			(layers "F.Cu" "F.Mask" "F.Paste")
			(net "SMB_SCM_2_R1_SCL")
		)
	)
	(footprint ""
		(layer "F.Cu")
		(at 105.222548 -386.7912 90)
		(property "Reference" "R746"
			(at 0 0 90)
			(layer "F.SilkS")
			(hide yes)
			(effects
				(font
					(size 1.27 1.27)
				)
			)
		)
		(property "Value" ""
			(at 0 0 90)
			(layer "F.Fab")
			(effects
				(font
					(size 1.27 1.27)
				)
			)
		)
		(duplicate_pad_numbers_are_jumpers no)
		(fp_line
			(start 0.32512 -0.175006)
			(end 0.32512 0.175006)
			(stroke
				(width 0.1)
				(type default)
			)
			(layer "F.Fab")
		)
		(fp_line
			(start -0.32512 -0.175006)
			(end 0.32512 -0.175006)
			(stroke
				(width 0.1)
				(type default)
			)
			(layer "F.Fab")
		)
		(fp_line
			(start 0.32512 0.175006)
			(end -0.32512 0.175006)
			(stroke
				(width 0.1)
				(type default)
			)
			(layer "F.Fab")
		)
		(fp_line
			(start -0.32512 0.175006)
			(end -0.32512 -0.175006)
			(stroke
				(width 0.1)
				(type default)
			)
			(layer "F.Fab")
		)
		(pad "1" smd rect
			(at -0.2667 0 90)
			(size 0.3048 0.381)
			(layers "F.Cu" "F.Mask" "F.Paste")
			(net "RT_CPU1_P1_ADDR2")
		)
		(pad "2" smd rect
			(at 0.2667 0 270)
			(size 0.3048 0.381)
			(layers "F.Cu" "F.Mask" "F.Paste")
			(net "GND")
		)
	)
	(footprint ""
		(layer "F.Cu")
		(at 42.33926 -379.56236)
		(property "Reference" "R675"
			(at 0 0 0)
			(layer "F.SilkS")
			(hide yes)
			(effects
				(font
					(size 1.27 1.27)
				)
			)
		)
		(property "Value" ""
			(at 0 0 0)
			(layer "F.Fab")
			(effects
				(font
					(size 1.27 1.27)
				)
			)
		)
		(duplicate_pad_numbers_are_jumpers no)
		(fp_line
			(start -0.32512 -0.175006)
			(end 0.32512 -0.175006)
			(stroke
				(width 0.1)
				(type default)
			)
			(layer "F.Fab")
		)
		(fp_line
			(start -0.32512 0.175006)
			(end -0.32512 -0.175006)
			(stroke
				(width 0.1)
				(type default)
			)
			(layer "F.Fab")
		)
		(fp_line
			(start 0.32512 -0.175006)
			(end 0.32512 0.175006)
			(stroke
				(width 0.1)
				(type default)
			)
			(layer "F.Fab")
		)
		(fp_line
			(start 0.32512 0.175006)
			(end -0.32512 0.175006)
			(stroke
				(width 0.1)
				(type default)
			)
			(layer "F.Fab")
		)
		(pad "1" smd rect
			(at -0.2667 0)
			(size 0.3048 0.381)
			(layers "F.Cu" "F.Mask" "F.Paste")
			(net "SMB_RT_CPU1_P0_ROM_MUX_1D_SDA")
		)
		(pad "2" smd rect
			(at 0.2667 0 180)
			(size 0.3048 0.381)
			(layers "F.Cu" "F.Mask" "F.Paste")
			(net "SMB_RT_CPU1_P0_ROM_MUX_1D_R_SDA")
		)
	)
	(footprint ""
		(layer "F.Cu")
		(at 438.056782 -439.12536 90)
		(property "Reference" "R4161"
			(at 0 0 90)
			(layer "F.SilkS")
			(hide yes)
			(effects
				(font
					(size 1.27 1.27)
				)
			)
		)
		(property "Value" ""
			(at 0 0 90)
			(layer "F.Fab")
			(effects
				(font
					(size 1.27 1.27)
				)
			)
		)
		(duplicate_pad_numbers_are_jumpers no)
		(fp_line
			(start 0.7874 -0.4064)
			(end 0.7874 0.4064)
			(stroke
				(width 0.1524)
				(type default)
			)
			(layer "F.SilkS")
		)
		(fp_line
			(start -0.7874 -0.4064)
			(end 0.7874 -0.4064)
			(stroke
				(width 0.1524)
				(type default)
			)
			(layer "F.SilkS")
		)
		(fp_line
			(start 0.7874 0.4064)
			(end -0.7874 0.4064)
			(stroke
				(width 0.1524)
				(type default)
			)
			(layer "F.SilkS")
		)
		(fp_line
			(start -0.7874 0.4064)
			(end -0.7874 -0.4064)
			(stroke
				(width 0.1524)
				(type default)
			)
			(layer "F.SilkS")
		)
		(fp_line
			(start -0.12065 -0.305054)
			(end -0.12065 -0.2794)
			(stroke
				(width 0.1)
				(type default)
			)
			(layer "F.Fab")
		)
		(fp_line
			(start -0.67945 -0.305054)
			(end -0.12065 -0.305054)
			(stroke
				(width 0.1)
				(type default)
			)
			(layer "F.Fab")
		)
		(fp_line
			(start 0.67945 -0.3048)
			(end 0.67945 0.3048)
			(stroke
				(width 0.1)
				(type default)
			)
			(layer "F.Fab")
		)
		(fp_line
			(start 0.12065 -0.3048)
			(end 0.67945 -0.3048)
			(stroke
				(width 0.1)
				(type default)
			)
			(layer "F.Fab")
		)
		(fp_line
			(start 0.12065 -0.2794)
			(end 0.12065 -0.3048)
			(stroke
				(width 0.1)
				(type default)
			)
			(layer "F.Fab")
		)
		(fp_line
			(start -0.12065 -0.2794)
			(end 0.12065 -0.2794)
			(stroke
				(width 0.1)
				(type default)
			)
			(layer "F.Fab")
		)
		(fp_line
			(start 0.120396 0.2794)
			(end -0.12065 0.2794)
			(stroke
				(width 0.1)
				(type default)
			)
			(layer "F.Fab")
		)
		(fp_line
			(start -0.12065 0.2794)
			(end -0.12065 0.3048)
			(stroke
				(width 0.1)
				(type default)
			)
			(layer "F.Fab")
		)
		(fp_line
			(start 0.67945 0.3048)
			(end 0.120396 0.3048)
			(stroke
				(width 0.1)
				(type default)
			)
			(layer "F.Fab")
		)
		(fp_line
			(start 0.120396 0.3048)
			(end 0.120396 0.2794)
			(stroke
				(width 0.1)
				(type default)
			)
			(layer "F.Fab")
		)
		(fp_line
			(start -0.12065 0.3048)
			(end -0.67945 0.3048)
			(stroke
				(width 0.1)
				(type default)
			)
			(layer "F.Fab")
		)
		(fp_line
			(start -0.67945 0.3048)
			(end -0.67945 -0.305054)
			(stroke
				(width 0.1)
				(type default)
			)
			(layer "F.Fab")
		)
		(pad "1" smd circle
			(at -0.40005 0 90)
			(size 0 0)
			(layers "F.Cu" "F.Mask" "F.Paste")
			(net "GPU_3V3IO_RSVD4")
		)
		(pad "2" smd circle
			(at 0.40005 0 90)
			(size 0 0)
			(layers "F.Cu" "F.Mask" "F.Paste")
			(net "GND")
		)
	)
	(footprint ""
		(layer "F.Cu")
		(at 111.76 -407.4668)
		(property "Reference" "R6803"
			(at 0 0 0)
			(layer "F.SilkS")
			(hide yes)
			(effects
				(font
					(size 1.27 1.27)
				)
			)
		)
		(property "Value" ""
			(at 0 0 0)
			(layer "F.Fab")
			(effects
				(font
					(size 1.27 1.27)
				)
			)
		)
		(duplicate_pad_numbers_are_jumpers no)
		(fp_line
			(start -0.7874 -0.4064)
			(end 0.7874 -0.4064)
			(stroke
				(width 0.1524)
				(type default)
			)
			(layer "F.SilkS")
		)
		(fp_line
			(start -0.7874 0.4064)
			(end -0.7874 -0.4064)
			(stroke
				(width 0.1524)
				(type default)
			)
			(layer "F.SilkS")
		)
		(fp_line
			(start 0.7874 -0.4064)
			(end 0.7874 0.4064)
			(stroke
				(width 0.1524)
				(type default)
			)
			(layer "F.SilkS")
		)
		(fp_line
			(start 0.7874 0.4064)
			(end -0.7874 0.4064)
			(stroke
				(width 0.1524)
				(type default)
			)
			(layer "F.SilkS")
		)
		(fp_line
			(start -0.67945 -0.305054)
			(end -0.12065 -0.305054)
			(stroke
				(width 0.1)
				(type default)
			)
			(layer "F.Fab")
		)
		(fp_line
			(start -0.67945 0.3048)
			(end -0.67945 -0.305054)
			(stroke
				(width 0.1)
				(type default)
			)
			(layer "F.Fab")
		)
		(fp_line
			(start -0.12065 -0.305054)
			(end -0.12065 -0.2794)
			(stroke
				(width 0.1)
				(type default)
			)
			(layer "F.Fab")
		)
		(fp_line
			(start -0.12065 -0.2794)
			(end 0.12065 -0.2794)
			(stroke
				(width 0.1)
				(type default)
			)
			(layer "F.Fab")
		)
		(fp_line
			(start -0.12065 0.2794)
			(end -0.12065 0.3048)
			(stroke
				(width 0.1)
				(type default)
			)
			(layer "F.Fab")
		)
		(fp_line
			(start -0.12065 0.3048)
			(end -0.67945 0.3048)
			(stroke
				(width 0.1)
				(type default)
			)
			(layer "F.Fab")
		)
		(fp_line
			(start 0.120396 0.2794)
			(end -0.12065 0.2794)
			(stroke
				(width 0.1)
				(type default)
			)
			(layer "F.Fab")
		)
		(fp_line
			(start 0.120396 0.3048)
			(end 0.120396 0.2794)
			(stroke
				(width 0.1)
				(type default)
			)
			(layer "F.Fab")
		)
		(fp_line
			(start 0.12065 -0.3048)
			(end 0.67945 -0.3048)
			(stroke
				(width 0.1)
				(type default)
			)
			(layer "F.Fab")
		)
		(fp_line
			(start 0.12065 -0.2794)
			(end 0.12065 -0.3048)
			(stroke
				(width 0.1)
				(type default)
			)
			(layer "F.Fab")
		)
		(fp_line
			(start 0.67945 -0.3048)
			(end 0.67945 0.3048)
			(stroke
				(width 0.1)
				(type default)
			)
			(layer "F.Fab")
		)
		(fp_line
			(start 0.67945 0.3048)
			(end 0.120396 0.3048)
			(stroke
				(width 0.1)
				(type default)
			)
			(layer "F.Fab")
		)
		(pad "1" smd circle
			(at -0.40005 0)
			(size 0 0)
			(layers "F.Cu" "F.Mask" "F.Paste")
			(net "FM_9ZXL045_P1_3_OE_N")
		)
		(pad "2" smd circle
			(at 0.40005 0)
			(size 0 0)
			(layers "F.Cu" "F.Mask" "F.Paste")
			(net "GND")
		)
	)
	(footprint ""
		(layer "F.Cu")
		(at 37.338 -366.776 -90)
		(property "Reference" "PR603"
			(at 0 0 270)
			(layer "F.SilkS")
			(hide yes)
			(effects
				(font
					(size 1.27 1.27)
				)
			)
		)
		(property "Value" ""
			(at 0 0 270)
			(layer "F.Fab")
			(effects
				(font
					(size 1.27 1.27)
				)
			)
		)
		(duplicate_pad_numbers_are_jumpers no)
		(fp_line
			(start -0.7874 0.4064)
			(end -0.7874 -0.4064)
			(stroke
				(width 0.1524)
				(type default)
			)
			(layer "F.SilkS")
		)
		(fp_line
			(start 0.7874 0.4064)
			(end -0.7874 0.4064)
			(stroke
				(width 0.1524)
				(type default)
			)
			(layer "F.SilkS")
		)
		(fp_line
			(start -0.7874 -0.4064)
			(end 0.7874 -0.4064)
			(stroke
				(width 0.1524)
				(type default)
			)
			(layer "F.SilkS")
		)
		(fp_line
			(start 0.7874 -0.4064)
			(end 0.7874 0.4064)
			(stroke
				(width 0.1524)
				(type default)
			)
			(layer "F.SilkS")
		)
		(fp_line
			(start -0.67945 0.3048)
			(end -0.67945 -0.305054)
			(stroke
				(width 0.1)
				(type default)
			)
			(layer "F.Fab")
		)
		(fp_line
			(start -0.12065 0.3048)
			(end -0.67945 0.3048)
			(stroke
				(width 0.1)
				(type default)
			)
			(layer "F.Fab")
		)
		(fp_line
			(start 0.120396 0.3048)
			(end 0.120396 0.2794)
			(stroke
				(width 0.1)
				(type default)
			)
			(layer "F.Fab")
		)
		(fp_line
			(start 0.67945 0.3048)
			(end 0.120396 0.3048)
			(stroke
				(width 0.1)
				(type default)
			)
			(layer "F.Fab")
		)
		(fp_line
			(start -0.12065 0.2794)
			(end -0.12065 0.3048)
			(stroke
				(width 0.1)
				(type default)
			)
			(layer "F.Fab")
		)
		(fp_line
			(start 0.120396 0.2794)
			(end -0.12065 0.2794)
			(stroke
				(width 0.1)
				(type default)
			)
			(layer "F.Fab")
		)
		(fp_line
			(start -0.12065 -0.2794)
			(end 0.12065 -0.2794)
			(stroke
				(width 0.1)
				(type default)
			)
			(layer "F.Fab")
		)
		(fp_line
			(start 0.12065 -0.2794)
			(end 0.12065 -0.3048)
			(stroke
				(width 0.1)
				(type default)
			)
			(layer "F.Fab")
		)
		(fp_line
			(start 0.12065 -0.3048)
			(end 0.67945 -0.3048)
			(stroke
				(width 0.1)
				(type default)
			)
			(layer "F.Fab")
		)
		(fp_line
			(start 0.67945 -0.3048)
			(end 0.67945 0.3048)
			(stroke
				(width 0.1)
				(type default)
			)
			(layer "F.Fab")
		)
		(fp_line
			(start -0.67945 -0.305054)
			(end -0.12065 -0.305054)
			(stroke
				(width 0.1)
				(type default)
			)
			(layer "F.Fab")
		)
		(fp_line
			(start -0.12065 -0.305054)
			(end -0.12065 -0.2794)
			(stroke
				(width 0.1)
				(type default)
			)
			(layer "F.Fab")
		)
		(pad "1" smd circle
			(at -0.40005 0 270)
			(size 0 0)
			(layers "F.Cu" "F.Mask" "F.Paste")
			(net "PVDDCR_CPU1_P1_VINSEN")
		)
		(pad "2" smd circle
			(at 0.40005 0 270)
			(size 0 0)
			(layers "F.Cu" "F.Mask" "F.Paste")
			(net "GND")
		)
	)
	(footprint ""
		(layer "F.Cu")
		(at 119.379492 -174.927768)
		(property "Reference" "PC141"
			(at 0 0 0)
			(layer "F.SilkS")
			(hide yes)
			(effects
				(font
					(size 1.27 1.27)
				)
			)
		)
		(property "Value" ""
			(at 0 0 0)
			(layer "F.Fab")
			(effects
				(font
					(size 1.27 1.27)
				)
			)
		)
		(duplicate_pad_numbers_are_jumpers no)
		(fp_line
			(start -0.7874 -0.4064)
			(end 0.7874 -0.4064)
			(stroke
				(width 0.1524)
				(type default)
			)
			(layer "F.SilkS")
		)
		(fp_line
			(start -0.7874 0.4064)
			(end -0.7874 -0.4064)
			(stroke
				(width 0.1524)
				(type default)
			)
			(layer "F.SilkS")
		)
		(fp_line
			(start 0.7874 -0.4064)
			(end 0.7874 0.4064)
			(stroke
				(width 0.1524)
				(type default)
			)
			(layer "F.SilkS")
		)
		(fp_line
			(start 0.7874 0.4064)
			(end -0.7874 0.4064)
			(stroke
				(width 0.1524)
				(type default)
			)
			(layer "F.SilkS")
		)
		(fp_line
			(start -0.67945 -0.305054)
			(end -0.12065 -0.305054)
			(stroke
				(width 0.1)
				(type default)
			)
			(layer "F.Fab")
		)
		(fp_line
			(start -0.67945 0.3048)
			(end -0.67945 -0.305054)
			(stroke
				(width 0.1)
				(type default)
			)
			(layer "F.Fab")
		)
		(fp_line
			(start -0.12065 -0.305054)
			(end -0.12065 -0.2794)
			(stroke
				(width 0.1)
				(type default)
			)
			(layer "F.Fab")
		)
		(fp_line
			(start -0.12065 -0.2794)
			(end 0.12065 -0.2794)
			(stroke
				(width 0.1)
				(type default)
			)
			(layer "F.Fab")
		)
		(fp_line
			(start -0.12065 0.2794)
			(end -0.12065 0.3048)
			(stroke
				(width 0.1)
				(type default)
			)
			(layer "F.Fab")
		)
		(fp_line
			(start -0.12065 0.3048)
			(end -0.67945 0.3048)
			(stroke
				(width 0.1)
				(type default)
			)
			(layer "F.Fab")
		)
		(fp_line
			(start 0.120396 0.2794)
			(end -0.12065 0.2794)
			(stroke
				(width 0.1)
				(type default)
			)
			(layer "F.Fab")
		)
		(fp_line
			(start 0.120396 0.3048)
			(end 0.120396 0.2794)
			(stroke
				(width 0.1)
				(type default)
			)
			(layer "F.Fab")
		)
		(fp_line
			(start 0.12065 -0.3048)
			(end 0.67945 -0.3048)
			(stroke
				(width 0.1)
				(type default)
			)
			(layer "F.Fab")
		)
		(fp_line
			(start 0.12065 -0.2794)
			(end 0.12065 -0.3048)
			(stroke
				(width 0.1)
				(type default)
			)
			(layer "F.Fab")
		)
		(fp_line
			(start 0.67945 -0.3048)
			(end 0.67945 0.3048)
			(stroke
				(width 0.1)
				(type default)
			)
			(layer "F.Fab")
		)
		(fp_line
			(start 0.67945 0.3048)
			(end 0.120396 0.3048)
			(stroke
				(width 0.1)
				(type default)
			)
			(layer "F.Fab")
		)
		(pad "1" smd circle
			(at -0.40005 0)
			(size 0 0)
			(layers "F.Cu" "F.Mask" "F.Paste")
			(net "SW_PVDDCR_SOC_P1_SW1")
		)
		(pad "2" smd circle
			(at 0.40005 0)
			(size 0 0)
			(layers "F.Cu" "F.Mask" "F.Paste")
			(net "SW_PVDDCR_SOC_P1_SW1_RC")
		)
	)
	(footprint ""
		(layer "F.Cu")
		(at 453.054212 -23.603458)
		(property "Reference" "PC4056"
			(at 0 0 0)
			(layer "F.SilkS")
			(hide yes)
			(effects
				(font
					(size 1.27 1.27)
				)
			)
		)
		(property "Value" ""
			(at 0 0 0)
			(layer "F.Fab")
			(effects
				(font
					(size 1.27 1.27)
				)
			)
		)
		(duplicate_pad_numbers_are_jumpers no)
		(fp_line
			(start -0.7874 -0.4064)
			(end 0.7874 -0.4064)
			(stroke
				(width 0.1524)
				(type default)
			)
			(layer "F.SilkS")
		)
		(fp_line
			(start -0.7874 0.4064)
			(end -0.7874 -0.4064)
			(stroke
				(width 0.1524)
				(type default)
			)
			(layer "F.SilkS")
		)
		(fp_line
			(start 0.7874 -0.4064)
			(end 0.7874 0.4064)
			(stroke
				(width 0.1524)
				(type default)
			)
			(layer "F.SilkS")
		)
		(fp_line
			(start 0.7874 0.4064)
			(end -0.7874 0.4064)
			(stroke
				(width 0.1524)
				(type default)
			)
			(layer "F.SilkS")
		)
		(fp_line
			(start -0.67945 -0.305054)
			(end -0.12065 -0.305054)
			(stroke
				(width 0.1)
				(type default)
			)
			(layer "F.Fab")
		)
		(fp_line
			(start -0.67945 0.3048)
			(end -0.67945 -0.305054)
			(stroke
				(width 0.1)
				(type default)
			)
			(layer "F.Fab")
		)
		(fp_line
			(start -0.12065 -0.305054)
			(end -0.12065 -0.2794)
			(stroke
				(width 0.1)
				(type default)
			)
			(layer "F.Fab")
		)
		(fp_line
			(start -0.12065 -0.2794)
			(end 0.12065 -0.2794)
			(stroke
				(width 0.1)
				(type default)
			)
			(layer "F.Fab")
		)
		(fp_line
			(start -0.12065 0.2794)
			(end -0.12065 0.3048)
			(stroke
				(width 0.1)
				(type default)
			)
			(layer "F.Fab")
		)
		(fp_line
			(start -0.12065 0.3048)
			(end -0.67945 0.3048)
			(stroke
				(width 0.1)
				(type default)
			)
			(layer "F.Fab")
		)
		(fp_line
			(start 0.120396 0.2794)
			(end -0.12065 0.2794)
			(stroke
				(width 0.1)
				(type default)
			)
			(layer "F.Fab")
		)
		(fp_line
			(start 0.120396 0.3048)
			(end 0.120396 0.2794)
			(stroke
				(width 0.1)
				(type default)
			)
			(layer "F.Fab")
		)
		(fp_line
			(start 0.12065 -0.3048)
			(end 0.67945 -0.3048)
			(stroke
				(width 0.1)
				(type default)
			)
			(layer "F.Fab")
		)
		(fp_line
			(start 0.12065 -0.2794)
			(end 0.12065 -0.3048)
			(stroke
				(width 0.1)
				(type default)
			)
			(layer "F.Fab")
		)
		(fp_line
			(start 0.67945 -0.3048)
			(end 0.67945 0.3048)
			(stroke
				(width 0.1)
				(type default)
			)
			(layer "F.Fab")
		)
		(fp_line
			(start 0.67945 0.3048)
			(end 0.120396 0.3048)
			(stroke
				(width 0.1)
				(type default)
			)
			(layer "F.Fab")
		)
		(pad "1" smd circle
			(at -0.40005 0)
			(size 0 0)
			(layers "F.Cu" "F.Mask" "F.Paste")
			(net "P12V_OCP_GATE_1")
		)
		(pad "2" smd circle
			(at 0.40005 0)
			(size 0 0)
			(layers "F.Cu" "F.Mask" "F.Paste")
			(net "GND")
		)
	)
	(footprint ""
		(layer "F.Cu")
		(at 294.421052 -117.269514)
		(property "Reference" "R2565"
			(at 0 0 0)
			(layer "F.SilkS")
			(hide yes)
			(effects
				(font
					(size 1.27 1.27)
				)
			)
		)
		(property "Value" ""
			(at 0 0 0)
			(layer "F.Fab")
			(effects
				(font
					(size 1.27 1.27)
				)
			)
		)
		(duplicate_pad_numbers_are_jumpers no)
		(fp_line
			(start -0.7874 -0.4064)
			(end 0.7874 -0.4064)
			(stroke
				(width 0.1524)
				(type default)
			)
			(layer "F.SilkS")
		)
		(fp_line
			(start -0.7874 0.4064)
			(end -0.7874 -0.4064)
			(stroke
				(width 0.1524)
				(type default)
			)
			(layer "F.SilkS")
		)
		(fp_line
			(start 0.7874 -0.4064)
			(end 0.7874 0.4064)
			(stroke
				(width 0.1524)
				(type default)
			)
			(layer "F.SilkS")
		)
		(fp_line
			(start 0.7874 0.4064)
			(end -0.7874 0.4064)
			(stroke
				(width 0.1524)
				(type default)
			)
			(layer "F.SilkS")
		)
		(fp_line
			(start -0.67945 -0.305054)
			(end -0.12065 -0.305054)
			(stroke
				(width 0.1)
				(type default)
			)
			(layer "F.Fab")
		)
		(fp_line
			(start -0.67945 0.3048)
			(end -0.67945 -0.305054)
			(stroke
				(width 0.1)
				(type default)
			)
			(layer "F.Fab")
		)
		(fp_line
			(start -0.12065 -0.305054)
			(end -0.12065 -0.2794)
			(stroke
				(width 0.1)
				(type default)
			)
			(layer "F.Fab")
		)
		(fp_line
			(start -0.12065 -0.2794)
			(end 0.12065 -0.2794)
			(stroke
				(width 0.1)
				(type default)
			)
			(layer "F.Fab")
		)
		(fp_line
			(start -0.12065 0.2794)
			(end -0.12065 0.3048)
			(stroke
				(width 0.1)
				(type default)
			)
			(layer "F.Fab")
		)
		(fp_line
			(start -0.12065 0.3048)
			(end -0.67945 0.3048)
			(stroke
				(width 0.1)
				(type default)
			)
			(layer "F.Fab")
		)
		(fp_line
			(start 0.120396 0.2794)
			(end -0.12065 0.2794)
			(stroke
				(width 0.1)
				(type default)
			)
			(layer "F.Fab")
		)
		(fp_line
			(start 0.120396 0.3048)
			(end 0.120396 0.2794)
			(stroke
				(width 0.1)
				(type default)
			)
			(layer "F.Fab")
		)
		(fp_line
			(start 0.12065 -0.3048)
			(end 0.67945 -0.3048)
			(stroke
				(width 0.1)
				(type default)
			)
			(layer "F.Fab")
		)
		(fp_line
			(start 0.12065 -0.2794)
			(end 0.12065 -0.3048)
			(stroke
				(width 0.1)
				(type default)
			)
			(layer "F.Fab")
		)
		(fp_line
			(start 0.67945 -0.3048)
			(end 0.67945 0.3048)
			(stroke
				(width 0.1)
				(type default)
			)
			(layer "F.Fab")
		)
		(fp_line
			(start 0.67945 0.3048)
			(end 0.120396 0.3048)
			(stroke
				(width 0.1)
				(type default)
			)
			(layer "F.Fab")
		)
		(pad "1" smd circle
			(at -0.40005 0)
			(size 0 0)
			(layers "F.Cu" "F.Mask" "F.Paste")
			(net "SMB_FRU_3V3AUX_SCL_R")
		)
		(pad "2" smd circle
			(at 0.40005 0)
			(size 0 0)
			(layers "F.Cu" "F.Mask" "F.Paste")
			(net "SMB_FRU_3V3AUX_SCL")
		)
	)
	(footprint ""
		(layer "F.Cu")
		(at 218.31681 -135.78459)
		(property "Reference" "Q64"
			(at -1.4224 -2.327148 0)
			(unlocked yes)
			(layer "F.SilkS")
			(effects
				(font
					(size 0.7874 0.5842)
					(thickness 0.1524)
				)
			)
		)
		(property "Value" ""
			(at 0 0 0)
			(layer "F.Fab")
			(effects
				(font
					(size 1.27 1.27)
				)
			)
		)
		(duplicate_pad_numbers_are_jumpers no)
		(fp_line
			(start -1.949958 -1.610106)
			(end 1.949958 -1.610106)
			(stroke
				(width 0.1524)
				(type default)
			)
			(layer "F.SilkS")
		)
		(fp_line
			(start -1.949958 1.610106)
			(end -1.949958 -1.610106)
			(stroke
				(width 0.1524)
				(type default)
			)
			(layer "F.SilkS")
		)
		(fp_line
			(start 1.949958 -1.560068)
			(end 1.949958 1.610106)
			(stroke
				(width 0.1524)
				(type default)
			)
			(layer "F.SilkS")
		)
		(fp_line
			(start 1.949958 1.610106)
			(end -1.949958 1.610106)
			(stroke
				(width 0.1524)
				(type default)
			)
			(layer "F.SilkS")
		)
		(fp_line
			(start -0.750062 -1.560068)
			(end 0.750062 -1.560068)
			(stroke
				(width 0.1)
				(type default)
			)
			(layer "F.Fab")
		)
		(fp_line
			(start -0.750062 1.560068)
			(end -0.750062 -1.560068)
			(stroke
				(width 0.1)
				(type default)
			)
			(layer "F.Fab")
		)
		(fp_line
			(start 0.750062 -1.560068)
			(end 0.750062 1.560068)
			(stroke
				(width 0.1)
				(type default)
			)
			(layer "F.Fab")
		)
		(fp_line
			(start 0.750062 1.560068)
			(end -0.750062 1.560068)
			(stroke
				(width 0.1)
				(type default)
			)
			(layer "F.Fab")
		)
		(pad "D" smd rect
			(at 1.100074 0 270)
			(size 1.016 1.4224)
			(layers "F.Cu" "F.Mask" "F.Paste")
			(net "FM_PLD_CPU1_PRSNT_HDT_N")
		)
		(pad "G" smd rect
			(at -1.100074 -0.94996 270)
			(size 1.016 1.4224)
			(layers "F.Cu" "F.Mask" "F.Paste")
			(net "CPU1_HDT_BYPASS_SEL")
		)
		(pad "S" smd rect
			(at -1.100074 0.94996 270)
			(size 1.016 1.4224)
			(layers "F.Cu" "F.Mask" "F.Paste")
			(net "GND")
		)
	)
	(footprint ""
		(layer "F.Cu")
		(at 365.835692 -256.505202 180)
		(property "Reference" "C2551"
			(at 0 0 180)
			(layer "F.SilkS")
			(hide yes)
			(effects
				(font
					(size 1.27 1.27)
				)
			)
		)
		(property "Value" ""
			(at 0 0 180)
			(layer "F.Fab")
			(effects
				(font
					(size 1.27 1.27)
				)
			)
		)
		(duplicate_pad_numbers_are_jumpers no)
		(fp_line
			(start 0.7874 0.4064)
			(end -0.7874 0.4064)
			(stroke
				(width 0.1524)
				(type default)
			)
			(layer "F.SilkS")
		)
		(fp_line
			(start 0.7874 -0.4064)
			(end 0.7874 0.4064)
			(stroke
				(width 0.1524)
				(type default)
			)
			(layer "F.SilkS")
		)
		(fp_line
			(start -0.7874 0.4064)
			(end -0.7874 -0.4064)
			(stroke
				(width 0.1524)
				(type default)
			)
			(layer "F.SilkS")
		)
		(fp_line
			(start -0.7874 -0.4064)
			(end 0.7874 -0.4064)
			(stroke
				(width 0.1524)
				(type default)
			)
			(layer "F.SilkS")
		)
		(fp_line
			(start 0.67945 0.3048)
			(end 0.120396 0.3048)
			(stroke
				(width 0.1)
				(type default)
			)
			(layer "F.Fab")
		)
		(fp_line
			(start 0.67945 -0.3048)
			(end 0.67945 0.3048)
			(stroke
				(width 0.1)
				(type default)
			)
			(layer "F.Fab")
		)
		(fp_line
			(start 0.12065 -0.2794)
			(end 0.12065 -0.3048)
			(stroke
				(width 0.1)
				(type default)
			)
			(layer "F.Fab")
		)
		(fp_line
			(start 0.12065 -0.3048)
			(end 0.67945 -0.3048)
			(stroke
				(width 0.1)
				(type default)
			)
			(layer "F.Fab")
		)
		(fp_line
			(start 0.120396 0.3048)
			(end 0.120396 0.2794)
			(stroke
				(width 0.1)
				(type default)
			)
			(layer "F.Fab")
		)
		(fp_line
			(start 0.120396 0.2794)
			(end -0.12065 0.2794)
			(stroke
				(width 0.1)
				(type default)
			)
			(layer "F.Fab")
		)
		(fp_line
			(start -0.12065 0.3048)
			(end -0.67945 0.3048)
			(stroke
				(width 0.1)
				(type default)
			)
			(layer "F.Fab")
		)
		(fp_line
			(start -0.12065 0.2794)
			(end -0.12065 0.3048)
			(stroke
				(width 0.1)
				(type default)
			)
			(layer "F.Fab")
		)
		(fp_line
			(start -0.12065 -0.2794)
			(end 0.12065 -0.2794)
			(stroke
				(width 0.1)
				(type default)
			)
			(layer "F.Fab")
		)
		(fp_line
			(start -0.12065 -0.305054)
			(end -0.12065 -0.2794)
			(stroke
				(width 0.1)
				(type default)
			)
			(layer "F.Fab")
		)
		(fp_line
			(start -0.67945 0.3048)
			(end -0.67945 -0.305054)
			(stroke
				(width 0.1)
				(type default)
			)
			(layer "F.Fab")
		)
		(fp_line
			(start -0.67945 -0.305054)
			(end -0.12065 -0.305054)
			(stroke
				(width 0.1)
				(type default)
			)
			(layer "F.Fab")
		)
		(pad "1" smd circle
			(at -0.40005 0 180)
			(size 0 0)
			(layers "F.Cu" "F.Mask" "F.Paste")
			(net "PVDDCR_SOC_P0")
		)
		(pad "2" smd circle
			(at 0.40005 0 180)
			(size 0 0)
			(layers "F.Cu" "F.Mask" "F.Paste")
			(net "GND")
		)
	)
	(footprint ""
		(layer "F.Cu")
		(at 35.132772 -434.128164)
		(property "Reference" "R2898"
			(at 0 0 0)
			(layer "F.SilkS")
			(hide yes)
			(effects
				(font
					(size 1.27 1.27)
				)
			)
		)
		(property "Value" ""
			(at 0 0 0)
			(layer "F.Fab")
			(effects
				(font
					(size 1.27 1.27)
				)
			)
		)
		(duplicate_pad_numbers_are_jumpers no)
		(fp_line
			(start -0.7874 -0.4064)
			(end 0.7874 -0.4064)
			(stroke
				(width 0.1524)
				(type default)
			)
			(layer "F.SilkS")
		)
		(fp_line
			(start -0.7874 0.4064)
			(end -0.7874 -0.4064)
			(stroke
				(width 0.1524)
				(type default)
			)
			(layer "F.SilkS")
		)
		(fp_line
			(start 0.7874 -0.4064)
			(end 0.7874 0.4064)
			(stroke
				(width 0.1524)
				(type default)
			)
			(layer "F.SilkS")
		)
		(fp_line
			(start 0.7874 0.4064)
			(end -0.7874 0.4064)
			(stroke
				(width 0.1524)
				(type default)
			)
			(layer "F.SilkS")
		)
		(fp_line
			(start -0.67945 -0.305054)
			(end -0.12065 -0.305054)
			(stroke
				(width 0.1)
				(type default)
			)
			(layer "F.Fab")
		)
		(fp_line
			(start -0.67945 0.3048)
			(end -0.67945 -0.305054)
			(stroke
				(width 0.1)
				(type default)
			)
			(layer "F.Fab")
		)
		(fp_line
			(start -0.12065 -0.305054)
			(end -0.12065 -0.2794)
			(stroke
				(width 0.1)
				(type default)
			)
			(layer "F.Fab")
		)
		(fp_line
			(start -0.12065 -0.2794)
			(end 0.12065 -0.2794)
			(stroke
				(width 0.1)
				(type default)
			)
			(layer "F.Fab")
		)
		(fp_line
			(start -0.12065 0.2794)
			(end -0.12065 0.3048)
			(stroke
				(width 0.1)
				(type default)
			)
			(layer "F.Fab")
		)
		(fp_line
			(start -0.12065 0.3048)
			(end -0.67945 0.3048)
			(stroke
				(width 0.1)
				(type default)
			)
			(layer "F.Fab")
		)
		(fp_line
			(start 0.120396 0.2794)
			(end -0.12065 0.2794)
			(stroke
				(width 0.1)
				(type default)
			)
			(layer "F.Fab")
		)
		(fp_line
			(start 0.120396 0.3048)
			(end 0.120396 0.2794)
			(stroke
				(width 0.1)
				(type default)
			)
			(layer "F.Fab")
		)
		(fp_line
			(start 0.12065 -0.3048)
			(end 0.67945 -0.3048)
			(stroke
				(width 0.1)
				(type default)
			)
			(layer "F.Fab")
		)
		(fp_line
			(start 0.12065 -0.2794)
			(end 0.12065 -0.3048)
			(stroke
				(width 0.1)
				(type default)
			)
			(layer "F.Fab")
		)
		(fp_line
			(start 0.67945 -0.3048)
			(end 0.67945 0.3048)
			(stroke
				(width 0.1)
				(type default)
			)
			(layer "F.Fab")
		)
		(fp_line
			(start 0.67945 0.3048)
			(end 0.120396 0.3048)
			(stroke
				(width 0.1)
				(type default)
			)
			(layer "F.Fab")
		)
		(pad "1" smd circle
			(at -0.40005 0)
			(size 0 0)
			(layers "F.Cu" "F.Mask" "F.Paste")
			(net "SMB_1_BMC_GPU_BUF_R_SDA")
		)
		(pad "2" smd circle
			(at 0.40005 0)
			(size 0 0)
			(layers "F.Cu" "F.Mask" "F.Paste")
			(net "SMB_1_BMC_GPU_BUF_SDA")
		)
	)
	(footprint ""
		(layer "F.Cu")
		(at 305.826922 -47.991268)
		(property "Reference" "R3689"
			(at 0 0 0)
			(layer "F.SilkS")
			(hide yes)
			(effects
				(font
					(size 1.27 1.27)
				)
			)
		)
		(property "Value" ""
			(at 0 0 0)
			(layer "F.Fab")
			(effects
				(font
					(size 1.27 1.27)
				)
			)
		)
		(duplicate_pad_numbers_are_jumpers no)
		(fp_line
			(start -0.7874 -0.4064)
			(end 0.7874 -0.4064)
			(stroke
				(width 0.1524)
				(type default)
			)
			(layer "F.SilkS")
		)
		(fp_line
			(start -0.7874 0.4064)
			(end -0.7874 -0.4064)
			(stroke
				(width 0.1524)
				(type default)
			)
			(layer "F.SilkS")
		)
		(fp_line
			(start 0.7874 -0.4064)
			(end 0.7874 0.4064)
			(stroke
				(width 0.1524)
				(type default)
			)
			(layer "F.SilkS")
		)
		(fp_line
			(start 0.7874 0.4064)
			(end -0.7874 0.4064)
			(stroke
				(width 0.1524)
				(type default)
			)
			(layer "F.SilkS")
		)
		(fp_line
			(start -0.67945 -0.305054)
			(end -0.12065 -0.305054)
			(stroke
				(width 0.1)
				(type default)
			)
			(layer "F.Fab")
		)
		(fp_line
			(start -0.67945 0.3048)
			(end -0.67945 -0.305054)
			(stroke
				(width 0.1)
				(type default)
			)
			(layer "F.Fab")
		)
		(fp_line
			(start -0.12065 -0.305054)
			(end -0.12065 -0.2794)
			(stroke
				(width 0.1)
				(type default)
			)
			(layer "F.Fab")
		)
		(fp_line
			(start -0.12065 -0.2794)
			(end 0.12065 -0.2794)
			(stroke
				(width 0.1)
				(type default)
			)
			(layer "F.Fab")
		)
		(fp_line
			(start -0.12065 0.2794)
			(end -0.12065 0.3048)
			(stroke
				(width 0.1)
				(type default)
			)
			(layer "F.Fab")
		)
		(fp_line
			(start -0.12065 0.3048)
			(end -0.67945 0.3048)
			(stroke
				(width 0.1)
				(type default)
			)
			(layer "F.Fab")
		)
		(fp_line
			(start 0.120396 0.2794)
			(end -0.12065 0.2794)
			(stroke
				(width 0.1)
				(type default)
			)
			(layer "F.Fab")
		)
		(fp_line
			(start 0.120396 0.3048)
			(end 0.120396 0.2794)
			(stroke
				(width 0.1)
				(type default)
			)
			(layer "F.Fab")
		)
		(fp_line
			(start 0.12065 -0.3048)
			(end 0.67945 -0.3048)
			(stroke
				(width 0.1)
				(type default)
			)
			(layer "F.Fab")
		)
		(fp_line
			(start 0.12065 -0.2794)
			(end 0.12065 -0.3048)
			(stroke
				(width 0.1)
				(type default)
			)
			(layer "F.Fab")
		)
		(fp_line
			(start 0.67945 -0.3048)
			(end 0.67945 0.3048)
			(stroke
				(width 0.1)
				(type default)
			)
			(layer "F.Fab")
		)
		(fp_line
			(start 0.67945 0.3048)
			(end 0.120396 0.3048)
			(stroke
				(width 0.1)
				(type default)
			)
			(layer "F.Fab")
		)
		(pad "1" smd circle
			(at -0.40005 0)
			(size 0 0)
			(layers "F.Cu" "F.Mask" "F.Paste")
			(net "P3V3_ADC128_VCC")
		)
		(pad "2" smd circle
			(at 0.40005 0)
			(size 0 0)
			(layers "F.Cu" "F.Mask" "F.Paste")
			(net "ADC128_VREF")
		)
	)
	(footprint ""
		(layer "F.Cu")
		(at 400.518122 -172.3136 -90)
		(property "Reference" "PC577_7"
			(at 0 0 270)
			(layer "F.SilkS")
			(hide yes)
			(effects
				(font
					(size 1.27 1.27)
				)
			)
		)
		(property "Value" ""
			(at 0 0 270)
			(layer "F.Fab")
			(effects
				(font
					(size 1.27 1.27)
				)
			)
		)
		(duplicate_pad_numbers_are_jumpers no)
		(fp_line
			(start -0.7874 0.4064)
			(end -0.7874 -0.4064)
			(stroke
				(width 0.1524)
				(type default)
			)
			(layer "F.SilkS")
		)
		(fp_line
			(start 0.7874 0.4064)
			(end -0.7874 0.4064)
			(stroke
				(width 0.1524)
				(type default)
			)
			(layer "F.SilkS")
		)
		(fp_line
			(start -0.7874 -0.4064)
			(end 0.7874 -0.4064)
			(stroke
				(width 0.1524)
				(type default)
			)
			(layer "F.SilkS")
		)
		(fp_line
			(start 0.7874 -0.4064)
			(end 0.7874 0.4064)
			(stroke
				(width 0.1524)
				(type default)
			)
			(layer "F.SilkS")
		)
		(fp_line
			(start -0.67945 0.3048)
			(end -0.67945 -0.305054)
			(stroke
				(width 0.1)
				(type default)
			)
			(layer "F.Fab")
		)
		(fp_line
			(start -0.12065 0.3048)
			(end -0.67945 0.3048)
			(stroke
				(width 0.1)
				(type default)
			)
			(layer "F.Fab")
		)
		(fp_line
			(start 0.120396 0.3048)
			(end 0.120396 0.2794)
			(stroke
				(width 0.1)
				(type default)
			)
			(layer "F.Fab")
		)
		(fp_line
			(start 0.67945 0.3048)
			(end 0.120396 0.3048)
			(stroke
				(width 0.1)
				(type default)
			)
			(layer "F.Fab")
		)
		(fp_line
			(start -0.12065 0.2794)
			(end -0.12065 0.3048)
			(stroke
				(width 0.1)
				(type default)
			)
			(layer "F.Fab")
		)
		(fp_line
			(start 0.120396 0.2794)
			(end -0.12065 0.2794)
			(stroke
				(width 0.1)
				(type default)
			)
			(layer "F.Fab")
		)
		(fp_line
			(start -0.12065 -0.2794)
			(end 0.12065 -0.2794)
			(stroke
				(width 0.1)
				(type default)
			)
			(layer "F.Fab")
		)
		(fp_line
			(start 0.12065 -0.2794)
			(end 0.12065 -0.3048)
			(stroke
				(width 0.1)
				(type default)
			)
			(layer "F.Fab")
		)
		(fp_line
			(start 0.12065 -0.3048)
			(end 0.67945 -0.3048)
			(stroke
				(width 0.1)
				(type default)
			)
			(layer "F.Fab")
		)
		(fp_line
			(start 0.67945 -0.3048)
			(end 0.67945 0.3048)
			(stroke
				(width 0.1)
				(type default)
			)
			(layer "F.Fab")
		)
		(fp_line
			(start -0.67945 -0.305054)
			(end -0.12065 -0.305054)
			(stroke
				(width 0.1)
				(type default)
			)
			(layer "F.Fab")
		)
		(fp_line
			(start -0.12065 -0.305054)
			(end -0.12065 -0.2794)
			(stroke
				(width 0.1)
				(type default)
			)
			(layer "F.Fab")
		)
		(pad "1" smd circle
			(at -0.40005 0 270)
			(size 0 0)
			(layers "F.Cu" "F.Mask" "F.Paste")
			(net "PVDDCR_CPU0_P0_VCCS")
		)
		(pad "2" smd circle
			(at 0.40005 0 270)
			(size 0 0)
			(layers "F.Cu" "F.Mask" "F.Paste")
			(net "GND")
		)
	)
	(footprint ""
		(layer "F.Cu")
		(at 65.861438 -22.235922 180)
		(property "Reference" "PR3850"
			(at 0 0 180)
			(layer "F.SilkS")
			(hide yes)
			(effects
				(font
					(size 1.27 1.27)
				)
			)
		)
		(property "Value" ""
			(at 0 0 180)
			(layer "F.Fab")
			(effects
				(font
					(size 1.27 1.27)
				)
			)
		)
		(duplicate_pad_numbers_are_jumpers no)
		(fp_line
			(start 0.7874 0.4064)
			(end -0.7874 0.4064)
			(stroke
				(width 0.1524)
				(type default)
			)
			(layer "F.SilkS")
		)
		(fp_line
			(start 0.7874 -0.4064)
			(end 0.7874 0.4064)
			(stroke
				(width 0.1524)
				(type default)
			)
			(layer "F.SilkS")
		)
		(fp_line
			(start -0.7874 0.4064)
			(end -0.7874 -0.4064)
			(stroke
				(width 0.1524)
				(type default)
			)
			(layer "F.SilkS")
		)
		(fp_line
			(start -0.7874 -0.4064)
			(end 0.7874 -0.4064)
			(stroke
				(width 0.1524)
				(type default)
			)
			(layer "F.SilkS")
		)
		(fp_line
			(start 0.67945 0.3048)
			(end 0.120396 0.3048)
			(stroke
				(width 0.1)
				(type default)
			)
			(layer "F.Fab")
		)
		(fp_line
			(start 0.67945 -0.3048)
			(end 0.67945 0.3048)
			(stroke
				(width 0.1)
				(type default)
			)
			(layer "F.Fab")
		)
		(fp_line
			(start 0.12065 -0.2794)
			(end 0.12065 -0.3048)
			(stroke
				(width 0.1)
				(type default)
			)
			(layer "F.Fab")
		)
		(fp_line
			(start 0.12065 -0.3048)
			(end 0.67945 -0.3048)
			(stroke
				(width 0.1)
				(type default)
			)
			(layer "F.Fab")
		)
		(fp_line
			(start 0.120396 0.3048)
			(end 0.120396 0.2794)
			(stroke
				(width 0.1)
				(type default)
			)
			(layer "F.Fab")
		)
		(fp_line
			(start 0.120396 0.2794)
			(end -0.12065 0.2794)
			(stroke
				(width 0.1)
				(type default)
			)
			(layer "F.Fab")
		)
		(fp_line
			(start -0.12065 0.3048)
			(end -0.67945 0.3048)
			(stroke
				(width 0.1)
				(type default)
			)
			(layer "F.Fab")
		)
		(fp_line
			(start -0.12065 0.2794)
			(end -0.12065 0.3048)
			(stroke
				(width 0.1)
				(type default)
			)
			(layer "F.Fab")
		)
		(fp_line
			(start -0.12065 -0.2794)
			(end 0.12065 -0.2794)
			(stroke
				(width 0.1)
				(type default)
			)
			(layer "F.Fab")
		)
		(fp_line
			(start -0.12065 -0.305054)
			(end -0.12065 -0.2794)
			(stroke
				(width 0.1)
				(type default)
			)
			(layer "F.Fab")
		)
		(fp_line
			(start -0.67945 0.3048)
			(end -0.67945 -0.305054)
			(stroke
				(width 0.1)
				(type default)
			)
			(layer "F.Fab")
		)
		(fp_line
			(start -0.67945 -0.305054)
			(end -0.12065 -0.305054)
			(stroke
				(width 0.1)
				(type default)
			)
			(layer "F.Fab")
		)
		(pad "1" smd circle
			(at -0.40005 0 180)
			(size 0 0)
			(layers "F.Cu" "F.Mask" "F.Paste")
			(net "P12V_OCP_V3_2")
		)
		(pad "2" smd circle
			(at 0.40005 0 180)
			(size 0 0)
			(layers "F.Cu" "F.Mask" "F.Paste")
			(net "P12V_OCP_AVIN_PD_2")
		)
	)
	(footprint ""
		(layer "F.Cu")
		(at 297.486324 -113.751614 180)
		(property "Reference" "R2984"
			(at 0 0 180)
			(layer "F.SilkS")
			(hide yes)
			(effects
				(font
					(size 1.27 1.27)
				)
			)
		)
		(property "Value" ""
			(at 0 0 180)
			(layer "F.Fab")
			(effects
				(font
					(size 1.27 1.27)
				)
			)
		)
		(duplicate_pad_numbers_are_jumpers no)
		(fp_line
			(start 0.7874 0.4064)
			(end -0.7874 0.4064)
			(stroke
				(width 0.1524)
				(type default)
			)
			(layer "F.SilkS")
		)
		(fp_line
			(start 0.7874 -0.4064)
			(end 0.7874 0.4064)
			(stroke
				(width 0.1524)
				(type default)
			)
			(layer "F.SilkS")
		)
		(fp_line
			(start -0.7874 0.4064)
			(end -0.7874 -0.4064)
			(stroke
				(width 0.1524)
				(type default)
			)
			(layer "F.SilkS")
		)
		(fp_line
			(start -0.7874 -0.4064)
			(end 0.7874 -0.4064)
			(stroke
				(width 0.1524)
				(type default)
			)
			(layer "F.SilkS")
		)
		(fp_line
			(start 0.67945 0.3048)
			(end 0.120396 0.3048)
			(stroke
				(width 0.1)
				(type default)
			)
			(layer "F.Fab")
		)
		(fp_line
			(start 0.67945 -0.3048)
			(end 0.67945 0.3048)
			(stroke
				(width 0.1)
				(type default)
			)
			(layer "F.Fab")
		)
		(fp_line
			(start 0.12065 -0.2794)
			(end 0.12065 -0.3048)
			(stroke
				(width 0.1)
				(type default)
			)
			(layer "F.Fab")
		)
		(fp_line
			(start 0.12065 -0.3048)
			(end 0.67945 -0.3048)
			(stroke
				(width 0.1)
				(type default)
			)
			(layer "F.Fab")
		)
		(fp_line
			(start 0.120396 0.3048)
			(end 0.120396 0.2794)
			(stroke
				(width 0.1)
				(type default)
			)
			(layer "F.Fab")
		)
		(fp_line
			(start 0.120396 0.2794)
			(end -0.12065 0.2794)
			(stroke
				(width 0.1)
				(type default)
			)
			(layer "F.Fab")
		)
		(fp_line
			(start -0.12065 0.3048)
			(end -0.67945 0.3048)
			(stroke
				(width 0.1)
				(type default)
			)
			(layer "F.Fab")
		)
		(fp_line
			(start -0.12065 0.2794)
			(end -0.12065 0.3048)
			(stroke
				(width 0.1)
				(type default)
			)
			(layer "F.Fab")
		)
		(fp_line
			(start -0.12065 -0.2794)
			(end 0.12065 -0.2794)
			(stroke
				(width 0.1)
				(type default)
			)
			(layer "F.Fab")
		)
		(fp_line
			(start -0.12065 -0.305054)
			(end -0.12065 -0.2794)
			(stroke
				(width 0.1)
				(type default)
			)
			(layer "F.Fab")
		)
		(fp_line
			(start -0.67945 0.3048)
			(end -0.67945 -0.305054)
			(stroke
				(width 0.1)
				(type default)
			)
			(layer "F.Fab")
		)
		(fp_line
			(start -0.67945 -0.305054)
			(end -0.12065 -0.305054)
			(stroke
				(width 0.1)
				(type default)
			)
			(layer "F.Fab")
		)
		(pad "1" smd circle
			(at -0.40005 0 180)
			(size 0 0)
			(layers "F.Cu" "F.Mask" "F.Paste")
			(net "P3V3_AUX")
		)
		(pad "2" smd circle
			(at 0.40005 0 180)
			(size 0 0)
			(layers "F.Cu" "F.Mask" "F.Paste")
			(net "SMB_BMC_SWB_SCL")
		)
	)
	(footprint ""
		(layer "F.Cu")
		(at 407.12644 -378.95403 -90)
		(property "Reference" "C857"
			(at 0 0 270)
			(layer "F.SilkS")
			(hide yes)
			(effects
				(font
					(size 1.27 1.27)
				)
			)
		)
		(property "Value" ""
			(at 0 0 270)
			(layer "F.Fab")
			(effects
				(font
					(size 1.27 1.27)
				)
			)
		)
		(duplicate_pad_numbers_are_jumpers no)
		(fp_line
			(start -0.299974 0.150114)
			(end -0.299974 -0.150114)
			(stroke
				(width 0.1)
				(type default)
			)
			(layer "F.Fab")
		)
		(fp_line
			(start 0.299974 0.150114)
			(end -0.299974 0.150114)
			(stroke
				(width 0.1)
				(type default)
			)
			(layer "F.Fab")
		)
		(fp_line
			(start -0.299974 -0.150114)
			(end 0.299974 -0.150114)
			(stroke
				(width 0.1)
				(type default)
			)
			(layer "F.Fab")
		)
		(fp_line
			(start 0.299974 -0.150114)
			(end 0.299974 0.150114)
			(stroke
				(width 0.1)
				(type default)
			)
			(layer "F.Fab")
		)
		(pad "1" smd rect
			(at -0.2667 0 270)
			(size 0.3048 0.381)
			(layers "F.Cu" "F.Mask" "F.Paste")
			(net "P5E_CPU0_P2_TX_C_DP<6>")
		)
		(pad "2" smd rect
			(at 0.2667 0 270)
			(size 0.3048 0.381)
			(layers "F.Cu" "F.Mask" "F.Paste")
			(net "P5E_CPU0_P2_TX_DP<6>")
		)
	)
	(footprint ""
		(layer "F.Cu")
		(at 436.052722 -409.68676)
		(property "Reference" "R1401"
			(at 0 0 0)
			(layer "F.SilkS")
			(hide yes)
			(effects
				(font
					(size 1.27 1.27)
				)
			)
		)
		(property "Value" ""
			(at 0 0 0)
			(layer "F.Fab")
			(effects
				(font
					(size 1.27 1.27)
				)
			)
		)
		(duplicate_pad_numbers_are_jumpers no)
		(fp_line
			(start -0.32512 -0.175006)
			(end 0.32512 -0.175006)
			(stroke
				(width 0.1)
				(type default)
			)
			(layer "F.Fab")
		)
		(fp_line
			(start -0.32512 0.175006)
			(end -0.32512 -0.175006)
			(stroke
				(width 0.1)
				(type default)
			)
			(layer "F.Fab")
		)
		(fp_line
			(start 0.32512 -0.175006)
			(end 0.32512 0.175006)
			(stroke
				(width 0.1)
				(type default)
			)
			(layer "F.Fab")
		)
		(fp_line
			(start 0.32512 0.175006)
			(end -0.32512 0.175006)
			(stroke
				(width 0.1)
				(type default)
			)
			(layer "F.Fab")
		)
		(pad "1" smd rect
			(at -0.2667 0)
			(size 0.3048 0.381)
			(layers "F.Cu" "F.Mask" "F.Paste")
			(net "JTAG_TCK_RT_CPU0_P2")
		)
		(pad "2" smd rect
			(at 0.2667 0 180)
			(size 0.3048 0.381)
			(layers "F.Cu" "F.Mask" "F.Paste")
			(net "GND")
		)
	)
	(footprint ""
		(layer "F.Cu")
		(at 105.84561 -65.57391)
		(property "Reference" "R6218"
			(at 0 0 0)
			(layer "F.SilkS")
			(hide yes)
			(effects
				(font
					(size 1.27 1.27)
				)
			)
		)
		(property "Value" ""
			(at 0 0 0)
			(layer "F.Fab")
			(effects
				(font
					(size 1.27 1.27)
				)
			)
		)
		(duplicate_pad_numbers_are_jumpers no)
		(fp_line
			(start -0.7874 -0.4064)
			(end 0.7874 -0.4064)
			(stroke
				(width 0.1524)
				(type default)
			)
			(layer "F.SilkS")
		)
		(fp_line
			(start -0.7874 0.4064)
			(end -0.7874 -0.4064)
			(stroke
				(width 0.1524)
				(type default)
			)
			(layer "F.SilkS")
		)
		(fp_line
			(start 0.7874 -0.4064)
			(end 0.7874 0.4064)
			(stroke
				(width 0.1524)
				(type default)
			)
			(layer "F.SilkS")
		)
		(fp_line
			(start 0.7874 0.4064)
			(end -0.7874 0.4064)
			(stroke
				(width 0.1524)
				(type default)
			)
			(layer "F.SilkS")
		)
		(fp_line
			(start -0.67945 -0.305054)
			(end -0.12065 -0.305054)
			(stroke
				(width 0.1)
				(type default)
			)
			(layer "F.Fab")
		)
		(fp_line
			(start -0.67945 0.3048)
			(end -0.67945 -0.305054)
			(stroke
				(width 0.1)
				(type default)
			)
			(layer "F.Fab")
		)
		(fp_line
			(start -0.12065 -0.305054)
			(end -0.12065 -0.2794)
			(stroke
				(width 0.1)
				(type default)
			)
			(layer "F.Fab")
		)
		(fp_line
			(start -0.12065 -0.2794)
			(end 0.12065 -0.2794)
			(stroke
				(width 0.1)
				(type default)
			)
			(layer "F.Fab")
		)
		(fp_line
			(start -0.12065 0.2794)
			(end -0.12065 0.3048)
			(stroke
				(width 0.1)
				(type default)
			)
			(layer "F.Fab")
		)
		(fp_line
			(start -0.12065 0.3048)
			(end -0.67945 0.3048)
			(stroke
				(width 0.1)
				(type default)
			)
			(layer "F.Fab")
		)
		(fp_line
			(start 0.120396 0.2794)
			(end -0.12065 0.2794)
			(stroke
				(width 0.1)
				(type default)
			)
			(layer "F.Fab")
		)
		(fp_line
			(start 0.120396 0.3048)
			(end 0.120396 0.2794)
			(stroke
				(width 0.1)
				(type default)
			)
			(layer "F.Fab")
		)
		(fp_line
			(start 0.12065 -0.3048)
			(end 0.67945 -0.3048)
			(stroke
				(width 0.1)
				(type default)
			)
			(layer "F.Fab")
		)
		(fp_line
			(start 0.12065 -0.2794)
			(end 0.12065 -0.3048)
			(stroke
				(width 0.1)
				(type default)
			)
			(layer "F.Fab")
		)
		(fp_line
			(start 0.67945 -0.3048)
			(end 0.67945 0.3048)
			(stroke
				(width 0.1)
				(type default)
			)
			(layer "F.Fab")
		)
		(fp_line
			(start 0.67945 0.3048)
			(end 0.120396 0.3048)
			(stroke
				(width 0.1)
				(type default)
			)
			(layer "F.Fab")
		)
		(pad "1" smd circle
			(at -0.40005 0)
			(size 0 0)
			(layers "F.Cu" "F.Mask" "F.Paste")
			(net "P3V3_AUX")
		)
		(pad "2" smd circle
			(at 0.40005 0)
			(size 0 0)
			(layers "F.Cu" "F.Mask" "F.Paste")
			(net "USB_CPU0_ADD_A1")
		)
	)
	(footprint ""
		(layer "F.Cu")
		(at 69.493638 -386.44068 90)
		(property "Reference" "C117"
			(at 0 0 90)
			(layer "F.SilkS")
			(hide yes)
			(effects
				(font
					(size 1.27 1.27)
				)
			)
		)
		(property "Value" ""
			(at 0 0 90)
			(layer "F.Fab")
			(effects
				(font
					(size 1.27 1.27)
				)
			)
		)
		(duplicate_pad_numbers_are_jumpers no)
		(fp_line
			(start 0.7874 -0.4064)
			(end 0.7874 0.4064)
			(stroke
				(width 0.1524)
				(type default)
			)
			(layer "F.SilkS")
		)
		(fp_line
			(start -0.7874 -0.4064)
			(end 0.7874 -0.4064)
			(stroke
				(width 0.1524)
				(type default)
			)
			(layer "F.SilkS")
		)
		(fp_line
			(start 0.7874 0.4064)
			(end -0.7874 0.4064)
			(stroke
				(width 0.1524)
				(type default)
			)
			(layer "F.SilkS")
		)
		(fp_line
			(start -0.7874 0.4064)
			(end -0.7874 -0.4064)
			(stroke
				(width 0.1524)
				(type default)
			)
			(layer "F.SilkS")
		)
		(fp_line
			(start -0.12065 -0.305054)
			(end -0.12065 -0.2794)
			(stroke
				(width 0.1)
				(type default)
			)
			(layer "F.Fab")
		)
		(fp_line
			(start -0.67945 -0.305054)
			(end -0.12065 -0.305054)
			(stroke
				(width 0.1)
				(type default)
			)
			(layer "F.Fab")
		)
		(fp_line
			(start 0.67945 -0.3048)
			(end 0.67945 0.3048)
			(stroke
				(width 0.1)
				(type default)
			)
			(layer "F.Fab")
		)
		(fp_line
			(start 0.12065 -0.3048)
			(end 0.67945 -0.3048)
			(stroke
				(width 0.1)
				(type default)
			)
			(layer "F.Fab")
		)
		(fp_line
			(start 0.12065 -0.2794)
			(end 0.12065 -0.3048)
			(stroke
				(width 0.1)
				(type default)
			)
			(layer "F.Fab")
		)
		(fp_line
			(start -0.12065 -0.2794)
			(end 0.12065 -0.2794)
			(stroke
				(width 0.1)
				(type default)
			)
			(layer "F.Fab")
		)
		(fp_line
			(start 0.120396 0.2794)
			(end -0.12065 0.2794)
			(stroke
				(width 0.1)
				(type default)
			)
			(layer "F.Fab")
		)
		(fp_line
			(start -0.12065 0.2794)
			(end -0.12065 0.3048)
			(stroke
				(width 0.1)
				(type default)
			)
			(layer "F.Fab")
		)
		(fp_line
			(start 0.67945 0.3048)
			(end 0.120396 0.3048)
			(stroke
				(width 0.1)
				(type default)
			)
			(layer "F.Fab")
		)
		(fp_line
			(start 0.120396 0.3048)
			(end 0.120396 0.2794)
			(stroke
				(width 0.1)
				(type default)
			)
			(layer "F.Fab")
		)
		(fp_line
			(start -0.12065 0.3048)
			(end -0.67945 0.3048)
			(stroke
				(width 0.1)
				(type default)
			)
			(layer "F.Fab")
		)
		(fp_line
			(start -0.67945 0.3048)
			(end -0.67945 -0.305054)
			(stroke
				(width 0.1)
				(type default)
			)
			(layer "F.Fab")
		)
		(pad "1" smd circle
			(at -0.40005 0 90)
			(size 0 0)
			(layers "F.Cu" "F.Mask" "F.Paste")
			(net "P1V8_CPU1_RT0_1A")
		)
		(pad "2" smd circle
			(at 0.40005 0 90)
			(size 0 0)
			(layers "F.Cu" "F.Mask" "F.Paste")
			(net "GND")
		)
	)
	(footprint ""
		(layer "F.Cu")
		(at 270.312134 -421.23868 90)
		(property "Reference" "C1797"
			(at 0 0 90)
			(layer "F.SilkS")
			(hide yes)
			(effects
				(font
					(size 1.27 1.27)
				)
			)
		)
		(property "Value" ""
			(at 0 0 90)
			(layer "F.Fab")
			(effects
				(font
					(size 1.27 1.27)
				)
			)
		)
		(duplicate_pad_numbers_are_jumpers no)
		(fp_line
			(start 0.7874 -0.4064)
			(end 0.7874 0.4064)
			(stroke
				(width 0.1524)
				(type default)
			)
			(layer "F.SilkS")
		)
		(fp_line
			(start -0.7874 -0.4064)
			(end 0.7874 -0.4064)
			(stroke
				(width 0.1524)
				(type default)
			)
			(layer "F.SilkS")
		)
		(fp_line
			(start 0.7874 0.4064)
			(end -0.7874 0.4064)
			(stroke
				(width 0.1524)
				(type default)
			)
			(layer "F.SilkS")
		)
		(fp_line
			(start -0.7874 0.4064)
			(end -0.7874 -0.4064)
			(stroke
				(width 0.1524)
				(type default)
			)
			(layer "F.SilkS")
		)
		(fp_line
			(start -0.12065 -0.305054)
			(end -0.12065 -0.2794)
			(stroke
				(width 0.1)
				(type default)
			)
			(layer "F.Fab")
		)
		(fp_line
			(start -0.67945 -0.305054)
			(end -0.12065 -0.305054)
			(stroke
				(width 0.1)
				(type default)
			)
			(layer "F.Fab")
		)
		(fp_line
			(start 0.67945 -0.3048)
			(end 0.67945 0.3048)
			(stroke
				(width 0.1)
				(type default)
			)
			(layer "F.Fab")
		)
		(fp_line
			(start 0.12065 -0.3048)
			(end 0.67945 -0.3048)
			(stroke
				(width 0.1)
				(type default)
			)
			(layer "F.Fab")
		)
		(fp_line
			(start 0.12065 -0.2794)
			(end 0.12065 -0.3048)
			(stroke
				(width 0.1)
				(type default)
			)
			(layer "F.Fab")
		)
		(fp_line
			(start -0.12065 -0.2794)
			(end 0.12065 -0.2794)
			(stroke
				(width 0.1)
				(type default)
			)
			(layer "F.Fab")
		)
		(fp_line
			(start 0.120396 0.2794)
			(end -0.12065 0.2794)
			(stroke
				(width 0.1)
				(type default)
			)
			(layer "F.Fab")
		)
		(fp_line
			(start -0.12065 0.2794)
			(end -0.12065 0.3048)
			(stroke
				(width 0.1)
				(type default)
			)
			(layer "F.Fab")
		)
		(fp_line
			(start 0.67945 0.3048)
			(end 0.120396 0.3048)
			(stroke
				(width 0.1)
				(type default)
			)
			(layer "F.Fab")
		)
		(fp_line
			(start 0.120396 0.3048)
			(end 0.120396 0.2794)
			(stroke
				(width 0.1)
				(type default)
			)
			(layer "F.Fab")
		)
		(fp_line
			(start -0.12065 0.3048)
			(end -0.67945 0.3048)
			(stroke
				(width 0.1)
				(type default)
			)
			(layer "F.Fab")
		)
		(fp_line
			(start -0.67945 0.3048)
			(end -0.67945 -0.305054)
			(stroke
				(width 0.1)
				(type default)
			)
			(layer "F.Fab")
		)
		(pad "1" smd circle
			(at -0.40005 0 90)
			(size 0 0)
			(layers "F.Cu" "F.Mask" "F.Paste")
			(net "PDB_PRSNT_R_N")
		)
		(pad "2" smd circle
			(at 0.40005 0 90)
			(size 0 0)
			(layers "F.Cu" "F.Mask" "F.Paste")
			(net "GND")
		)
	)
	(footprint ""
		(layer "F.Cu")
		(at 119.349774 -165.109398 90)
		(property "Reference" "PC326_2"
			(at 0 0 90)
			(layer "F.SilkS")
			(hide yes)
			(effects
				(font
					(size 1.27 1.27)
				)
			)
		)
		(property "Value" ""
			(at 0 0 90)
			(layer "F.Fab")
			(effects
				(font
					(size 1.27 1.27)
				)
			)
		)
		(duplicate_pad_numbers_are_jumpers no)
		(fp_line
			(start 0.7874 -0.4064)
			(end 0.7874 0.4064)
			(stroke
				(width 0.1524)
				(type default)
			)
			(layer "F.SilkS")
		)
		(fp_line
			(start -0.7874 -0.4064)
			(end 0.7874 -0.4064)
			(stroke
				(width 0.1524)
				(type default)
			)
			(layer "F.SilkS")
		)
		(fp_line
			(start 0.7874 0.4064)
			(end -0.7874 0.4064)
			(stroke
				(width 0.1524)
				(type default)
			)
			(layer "F.SilkS")
		)
		(fp_line
			(start -0.7874 0.4064)
			(end -0.7874 -0.4064)
			(stroke
				(width 0.1524)
				(type default)
			)
			(layer "F.SilkS")
		)
		(fp_line
			(start -0.12065 -0.305054)
			(end -0.12065 -0.2794)
			(stroke
				(width 0.1)
				(type default)
			)
			(layer "F.Fab")
		)
		(fp_line
			(start -0.67945 -0.305054)
			(end -0.12065 -0.305054)
			(stroke
				(width 0.1)
				(type default)
			)
			(layer "F.Fab")
		)
		(fp_line
			(start 0.67945 -0.3048)
			(end 0.67945 0.3048)
			(stroke
				(width 0.1)
				(type default)
			)
			(layer "F.Fab")
		)
		(fp_line
			(start 0.12065 -0.3048)
			(end 0.67945 -0.3048)
			(stroke
				(width 0.1)
				(type default)
			)
			(layer "F.Fab")
		)
		(fp_line
			(start 0.12065 -0.2794)
			(end 0.12065 -0.3048)
			(stroke
				(width 0.1)
				(type default)
			)
			(layer "F.Fab")
		)
		(fp_line
			(start -0.12065 -0.2794)
			(end 0.12065 -0.2794)
			(stroke
				(width 0.1)
				(type default)
			)
			(layer "F.Fab")
		)
		(fp_line
			(start 0.120396 0.2794)
			(end -0.12065 0.2794)
			(stroke
				(width 0.1)
				(type default)
			)
			(layer "F.Fab")
		)
		(fp_line
			(start -0.12065 0.2794)
			(end -0.12065 0.3048)
			(stroke
				(width 0.1)
				(type default)
			)
			(layer "F.Fab")
		)
		(fp_line
			(start 0.67945 0.3048)
			(end 0.120396 0.3048)
			(stroke
				(width 0.1)
				(type default)
			)
			(layer "F.Fab")
		)
		(fp_line
			(start 0.120396 0.3048)
			(end 0.120396 0.2794)
			(stroke
				(width 0.1)
				(type default)
			)
			(layer "F.Fab")
		)
		(fp_line
			(start -0.12065 0.3048)
			(end -0.67945 0.3048)
			(stroke
				(width 0.1)
				(type default)
			)
			(layer "F.Fab")
		)
		(fp_line
			(start -0.67945 0.3048)
			(end -0.67945 -0.305054)
			(stroke
				(width 0.1)
				(type default)
			)
			(layer "F.Fab")
		)
		(pad "1" smd circle
			(at -0.40005 0 90)
			(size 0 0)
			(layers "F.Cu" "F.Mask" "F.Paste")
			(net "SW_P12V_AUX_PVDDCR_SOC_P1_FLT")
		)
		(pad "2" smd circle
			(at 0.40005 0 90)
			(size 0 0)
			(layers "F.Cu" "F.Mask" "F.Paste")
			(net "GND")
		)
	)
	(footprint ""
		(layer "F.Cu")
		(at 215.9 -97.79 180)
		(property "Reference" "R9031"
			(at 0 0 180)
			(layer "F.SilkS")
			(hide yes)
			(effects
				(font
					(size 1.27 1.27)
				)
			)
		)
		(property "Value" ""
			(at 0 0 180)
			(layer "F.Fab")
			(effects
				(font
					(size 1.27 1.27)
				)
			)
		)
		(duplicate_pad_numbers_are_jumpers no)
		(fp_line
			(start 0.7874 0.4064)
			(end -0.7874 0.4064)
			(stroke
				(width 0.1524)
				(type default)
			)
			(layer "F.SilkS")
		)
		(fp_line
			(start 0.7874 -0.4064)
			(end 0.7874 0.4064)
			(stroke
				(width 0.1524)
				(type default)
			)
			(layer "F.SilkS")
		)
		(fp_line
			(start -0.7874 0.4064)
			(end -0.7874 -0.4064)
			(stroke
				(width 0.1524)
				(type default)
			)
			(layer "F.SilkS")
		)
		(fp_line
			(start -0.7874 -0.4064)
			(end 0.7874 -0.4064)
			(stroke
				(width 0.1524)
				(type default)
			)
			(layer "F.SilkS")
		)
		(fp_line
			(start 0.67945 0.3048)
			(end 0.120396 0.3048)
			(stroke
				(width 0.1)
				(type default)
			)
			(layer "F.Fab")
		)
		(fp_line
			(start 0.67945 -0.3048)
			(end 0.67945 0.3048)
			(stroke
				(width 0.1)
				(type default)
			)
			(layer "F.Fab")
		)
		(fp_line
			(start 0.12065 -0.2794)
			(end 0.12065 -0.3048)
			(stroke
				(width 0.1)
				(type default)
			)
			(layer "F.Fab")
		)
		(fp_line
			(start 0.12065 -0.3048)
			(end 0.67945 -0.3048)
			(stroke
				(width 0.1)
				(type default)
			)
			(layer "F.Fab")
		)
		(fp_line
			(start 0.120396 0.3048)
			(end 0.120396 0.2794)
			(stroke
				(width 0.1)
				(type default)
			)
			(layer "F.Fab")
		)
		(fp_line
			(start 0.120396 0.2794)
			(end -0.12065 0.2794)
			(stroke
				(width 0.1)
				(type default)
			)
			(layer "F.Fab")
		)
		(fp_line
			(start -0.12065 0.3048)
			(end -0.67945 0.3048)
			(stroke
				(width 0.1)
				(type default)
			)
			(layer "F.Fab")
		)
		(fp_line
			(start -0.12065 0.2794)
			(end -0.12065 0.3048)
			(stroke
				(width 0.1)
				(type default)
			)
			(layer "F.Fab")
		)
		(fp_line
			(start -0.12065 -0.2794)
			(end 0.12065 -0.2794)
			(stroke
				(width 0.1)
				(type default)
			)
			(layer "F.Fab")
		)
		(fp_line
			(start -0.12065 -0.305054)
			(end -0.12065 -0.2794)
			(stroke
				(width 0.1)
				(type default)
			)
			(layer "F.Fab")
		)
		(fp_line
			(start -0.67945 0.3048)
			(end -0.67945 -0.305054)
			(stroke
				(width 0.1)
				(type default)
			)
			(layer "F.Fab")
		)
		(fp_line
			(start -0.67945 -0.305054)
			(end -0.12065 -0.305054)
			(stroke
				(width 0.1)
				(type default)
			)
			(layer "F.Fab")
		)
		(pad "1" smd circle
			(at -0.40005 0 180)
			(size 0 0)
			(layers "F.Cu" "F.Mask" "F.Paste")
			(net "OCP_SFF_AUX_PWR_EN_R3")
		)
		(pad "2" smd circle
			(at 0.40005 0 180)
			(size 0 0)
			(layers "F.Cu" "F.Mask" "F.Paste")
			(net "OCP_SFF_AUX_PWR_EN")
		)
	)
	(footprint ""
		(layer "F.Cu")
		(at 212.471508 5.082794)
		(property "Reference" "J79"
			(at -4.52374 0.838708 90)
			(unlocked yes)
			(layer "F.SilkS")
			(effects
				(font
					(size 0.7874 0.5842)
					(thickness 0.1524)
				)
				(justify left)
			)
		)
		(property "Value" ""
			(at 0 0 0)
			(layer "F.Fab")
			(effects
				(font
					(size 1.27 1.27)
				)
			)
		)
		(duplicate_pad_numbers_are_jumpers no)
		(fp_line
			(start -1.2192 -2.06756)
			(end 1.2192 -2.06756)
			(stroke
				(width 0.1524)
				(type default)
			)
			(layer "F.SilkS")
		)
		(fp_line
			(start -1.2192 2.06756)
			(end -1.2192 -2.06756)
			(stroke
				(width 0.1524)
				(type default)
			)
			(layer "F.SilkS")
		)
		(fp_line
			(start 1.2192 -2.06756)
			(end 1.2192 2.06756)
			(stroke
				(width 0.1524)
				(type default)
			)
			(layer "F.SilkS")
		)
		(fp_line
			(start 1.2192 2.06756)
			(end -1.2192 2.06756)
			(stroke
				(width 0.1524)
				(type default)
			)
			(layer "F.SilkS")
		)
		(pad "" np_thru_hole circle
			(at -2.8829 -1.27 270)
			(size 1.0414 1.0414)
			(drill 1.0414)
			(layers "*.Cu" "*.Mask")
			(clearance 0.381)
			(thermal_gap 0.381)
		)
		(pad "" np_thru_hole circle
			(at -2.8829 1.27 270)
			(size 1.0414 1.0414)
			(drill 1.0414)
			(layers "*.Cu" "*.Mask")
			(clearance 0.381)
			(thermal_gap 0.381)
		)
		(pad "" np_thru_hole circle
			(at 3.4671 -1.27 270)
			(size 1.0414 1.0414)
			(drill 1.0414)
			(layers "*.Cu" "*.Mask")
			(clearance 0.381)
			(thermal_gap 0.381)
		)
		(pad "" np_thru_hole circle
			(at 3.4671 1.27 270)
			(size 1.0414 1.0414)
			(drill 1.0414)
			(layers "*.Cu" "*.Mask")
			(clearance 0.381)
			(thermal_gap 0.381)
		)
		(pad "1" smd rect
			(at 0.8255 -0.249936 270)
			(size 0.3048 0.508)
			(layers "F.Cu" "F.Mask" "F.Paste")
			(net "DELTA_L_85_10INCH_IN3_DP")
		)
		(pad "2" smd rect
			(at 0.8255 0.249936 270)
			(size 0.3048 0.508)
			(layers "F.Cu" "F.Mask" "F.Paste")
			(net "DELTA_L_85_10INCH_IN3_DN")
		)
		(pad "3" smd circle
			(at 0 0)
			(size 0 0)
			(layers "F.Cu" "F.Mask" "F.Paste")
			(net "DELTA_L_GND_1")
		)
		(zone
			(layer "F.Cu")
			(hatch none 0.5)
			(connect_pads
				(clearance 0)
			)
			(min_thickness 0.25)
			(keepout
				(tracks not_allowed)
				(vias allowed)
				(pads allowed)
				(copperpour not_allowed)
				(footprints allowed)
			)
			(placement
				(enabled no)
				(sheetname "")
			)
			(fill
				(thermal_gap 0.5)
				(thermal_bridge_width 0.5)
				(island_removal_mode 0)
			)
			(polygon
				(pts
					(xy 213.589108 4.534154) (xy 213.589108 4.629658) (xy 212.992208 4.629658) (xy 212.992208 5.036058)
					(xy 213.589108 5.036058) (xy 213.589108 5.12953) (xy 212.992208 5.12953) (xy 212.992208 5.53593)
					(xy 213.589108 5.53593) (xy 213.589108 5.631434) (xy 212.890608 5.631434) (xy 212.890608 4.534154)
				)
			)
		)
		(zone
			(layers "F.Cu" "B.Cu" "In1.Cu" "In2.Cu" "In3.Cu" "In4.Cu" "In5.Cu" "In6.Cu"
				"In7.Cu" "In8.Cu" "In9.Cu" "In10.Cu" "In11.Cu" "In12.Cu" "In13.Cu" "In14.Cu"
				"In15.Cu" "In16.Cu"
			)
			(hatch none 0.5)
			(connect_pads
				(clearance 0)
			)
			(min_thickness 0.25)
			(keepout
				(tracks not_allowed)
				(vias allowed)
				(pads allowed)
				(copperpour not_allowed)
				(footprints allowed)
			)
			(placement
				(enabled no)
				(sheetname "")
			)
			(fill
				(thermal_gap 0.5)
				(thermal_bridge_width 0.5)
				(island_removal_mode 0)
			)
			(polygon
				(pts
					(arc
						(start 210.515708 3.812794)
						(mid 208.661508 3.812794)
						(end 210.515708 3.812794)
					)
				)
			)
		)
		(zone
			(layers "F.Cu" "B.Cu" "In1.Cu" "In2.Cu" "In3.Cu" "In4.Cu" "In5.Cu" "In6.Cu"
				"In7.Cu" "In8.Cu" "In9.Cu" "In10.Cu" "In11.Cu" "In12.Cu" "In13.Cu" "In14.Cu"
				"In15.Cu" "In16.Cu"
			)
			(hatch none 0.5)
			(connect_pads
				(clearance 0)
			)
			(min_thickness 0.25)
			(keepout
				(tracks not_allowed)
				(vias allowed)
				(pads allowed)
				(copperpour not_allowed)
				(footprints allowed)
			)
			(placement
				(enabled no)
				(sheetname "")
			)
			(fill
				(thermal_gap 0.5)
				(thermal_bridge_width 0.5)
				(island_removal_mode 0)
			)
			(polygon
				(pts
					(arc
						(start 210.515708 6.352794)
						(mid 208.661508 6.352794)
						(end 210.515708 6.352794)
					)
				)
			)
		)
		(zone
			(layers "F.Cu" "B.Cu" "In1.Cu" "In2.Cu" "In3.Cu" "In4.Cu" "In5.Cu" "In6.Cu"
				"In7.Cu" "In8.Cu" "In9.Cu" "In10.Cu" "In11.Cu" "In12.Cu" "In13.Cu" "In14.Cu"
				"In15.Cu" "In16.Cu"
			)
			(hatch none 0.5)
			(connect_pads
				(clearance 0)
			)
			(min_thickness 0.25)
			(keepout
				(tracks not_allowed)
				(vias allowed)
				(pads allowed)
				(copperpour not_allowed)
				(footprints allowed)
			)
			(placement
				(enabled no)
				(sheetname "")
			)
			(fill
				(thermal_gap 0.5)
				(thermal_bridge_width 0.5)
				(island_removal_mode 0)
			)
			(polygon
				(pts
					(arc
						(start 216.865708 3.812794)
						(mid 215.011508 3.812794)
						(end 216.865708 3.812794)
					)
				)
			)
		)
		(zone
			(layers "F.Cu" "B.Cu" "In1.Cu" "In2.Cu" "In3.Cu" "In4.Cu" "In5.Cu" "In6.Cu"
				"In7.Cu" "In8.Cu" "In9.Cu" "In10.Cu" "In11.Cu" "In12.Cu" "In13.Cu" "In14.Cu"
				"In15.Cu" "In16.Cu"
			)
			(hatch none 0.5)
			(connect_pads
				(clearance 0)
			)
			(min_thickness 0.25)
			(keepout
				(tracks not_allowed)
				(vias allowed)
				(pads allowed)
				(copperpour not_allowed)
				(footprints allowed)
			)
			(placement
				(enabled no)
				(sheetname "")
			)
			(fill
				(thermal_gap 0.5)
				(thermal_bridge_width 0.5)
				(island_removal_mode 0)
			)
			(polygon
				(pts
					(arc
						(start 216.865708 6.352794)
						(mid 215.011508 6.352794)
						(end 216.865708 6.352794)
					)
				)
			)
		)
	)
	(footprint ""
		(layer "F.Cu")
		(at 299.903896 -381.41783 -90)
		(property "Reference" "C928"
			(at 0 0 270)
			(layer "F.SilkS")
			(hide yes)
			(effects
				(font
					(size 1.27 1.27)
				)
			)
		)
		(property "Value" ""
			(at 0 0 270)
			(layer "F.Fab")
			(effects
				(font
					(size 1.27 1.27)
				)
			)
		)
		(duplicate_pad_numbers_are_jumpers no)
		(fp_line
			(start -0.299974 0.150114)
			(end -0.299974 -0.150114)
			(stroke
				(width 0.1)
				(type default)
			)
			(layer "F.Fab")
		)
		(fp_line
			(start 0.299974 0.150114)
			(end -0.299974 0.150114)
			(stroke
				(width 0.1)
				(type default)
			)
			(layer "F.Fab")
		)
		(fp_line
			(start -0.299974 -0.150114)
			(end 0.299974 -0.150114)
			(stroke
				(width 0.1)
				(type default)
			)
			(layer "F.Fab")
		)
		(fp_line
			(start 0.299974 -0.150114)
			(end 0.299974 0.150114)
			(stroke
				(width 0.1)
				(type default)
			)
			(layer "F.Fab")
		)
		(pad "1" smd rect
			(at -0.2667 0 270)
			(size 0.3048 0.381)
			(layers "F.Cu" "F.Mask" "F.Paste")
			(net "P5E_CPU0_P0_TX_C_DN<2>")
		)
		(pad "2" smd rect
			(at 0.2667 0 270)
			(size 0.3048 0.381)
			(layers "F.Cu" "F.Mask" "F.Paste")
			(net "P5E_CPU0_P0_TX_DN<2>")
		)
	)
	(footprint ""
		(layer "F.Cu")
		(at 58.191654 -346.719398 -90)
		(property "Reference" "PC401_C1P1_4"
			(at 0 0 270)
			(layer "F.SilkS")
			(hide yes)
			(effects
				(font
					(size 1.27 1.27)
				)
			)
		)
		(property "Value" ""
			(at 0 0 270)
			(layer "F.Fab")
			(effects
				(font
					(size 1.27 1.27)
				)
			)
		)
		(duplicate_pad_numbers_are_jumpers no)
		(fp_line
			(start -0.7874 0.4064)
			(end -0.7874 -0.4064)
			(stroke
				(width 0.1524)
				(type default)
			)
			(layer "F.SilkS")
		)
		(fp_line
			(start 0.7874 0.4064)
			(end -0.7874 0.4064)
			(stroke
				(width 0.1524)
				(type default)
			)
			(layer "F.SilkS")
		)
		(fp_line
			(start -0.7874 -0.4064)
			(end 0.7874 -0.4064)
			(stroke
				(width 0.1524)
				(type default)
			)
			(layer "F.SilkS")
		)
		(fp_line
			(start 0.7874 -0.4064)
			(end 0.7874 0.4064)
			(stroke
				(width 0.1524)
				(type default)
			)
			(layer "F.SilkS")
		)
		(fp_line
			(start -0.67945 0.3048)
			(end -0.67945 -0.305054)
			(stroke
				(width 0.1)
				(type default)
			)
			(layer "F.Fab")
		)
		(fp_line
			(start -0.12065 0.3048)
			(end -0.67945 0.3048)
			(stroke
				(width 0.1)
				(type default)
			)
			(layer "F.Fab")
		)
		(fp_line
			(start 0.120396 0.3048)
			(end 0.120396 0.2794)
			(stroke
				(width 0.1)
				(type default)
			)
			(layer "F.Fab")
		)
		(fp_line
			(start 0.67945 0.3048)
			(end 0.120396 0.3048)
			(stroke
				(width 0.1)
				(type default)
			)
			(layer "F.Fab")
		)
		(fp_line
			(start -0.12065 0.2794)
			(end -0.12065 0.3048)
			(stroke
				(width 0.1)
				(type default)
			)
			(layer "F.Fab")
		)
		(fp_line
			(start 0.120396 0.2794)
			(end -0.12065 0.2794)
			(stroke
				(width 0.1)
				(type default)
			)
			(layer "F.Fab")
		)
		(fp_line
			(start -0.12065 -0.2794)
			(end 0.12065 -0.2794)
			(stroke
				(width 0.1)
				(type default)
			)
			(layer "F.Fab")
		)
		(fp_line
			(start 0.12065 -0.2794)
			(end 0.12065 -0.3048)
			(stroke
				(width 0.1)
				(type default)
			)
			(layer "F.Fab")
		)
		(fp_line
			(start 0.12065 -0.3048)
			(end 0.67945 -0.3048)
			(stroke
				(width 0.1)
				(type default)
			)
			(layer "F.Fab")
		)
		(fp_line
			(start 0.67945 -0.3048)
			(end 0.67945 0.3048)
			(stroke
				(width 0.1)
				(type default)
			)
			(layer "F.Fab")
		)
		(fp_line
			(start -0.67945 -0.305054)
			(end -0.12065 -0.305054)
			(stroke
				(width 0.1)
				(type default)
			)
			(layer "F.Fab")
		)
		(fp_line
			(start -0.12065 -0.305054)
			(end -0.12065 -0.2794)
			(stroke
				(width 0.1)
				(type default)
			)
			(layer "F.Fab")
		)
		(pad "1" smd circle
			(at -0.40005 0 270)
			(size 0 0)
			(layers "F.Cu" "F.Mask" "F.Paste")
			(net "PVDDCR_CPU1_P1_PVCC")
		)
		(pad "2" smd circle
			(at 0.40005 0 270)
			(size 0 0)
			(layers "F.Cu" "F.Mask" "F.Paste")
			(net "GND")
		)
	)
	(footprint ""
		(layer "F.Cu")
		(at 150.502366 -56.204358)
		(property "Reference" "R3611"
			(at 0 0 0)
			(layer "F.SilkS")
			(hide yes)
			(effects
				(font
					(size 1.27 1.27)
				)
			)
		)
		(property "Value" ""
			(at 0 0 0)
			(layer "F.Fab")
			(effects
				(font
					(size 1.27 1.27)
				)
			)
		)
		(duplicate_pad_numbers_are_jumpers no)
		(fp_line
			(start -0.7874 -0.4064)
			(end 0.7874 -0.4064)
			(stroke
				(width 0.1524)
				(type default)
			)
			(layer "F.SilkS")
		)
		(fp_line
			(start -0.7874 0.4064)
			(end -0.7874 -0.4064)
			(stroke
				(width 0.1524)
				(type default)
			)
			(layer "F.SilkS")
		)
		(fp_line
			(start 0.7874 -0.4064)
			(end 0.7874 0.4064)
			(stroke
				(width 0.1524)
				(type default)
			)
			(layer "F.SilkS")
		)
		(fp_line
			(start 0.7874 0.4064)
			(end -0.7874 0.4064)
			(stroke
				(width 0.1524)
				(type default)
			)
			(layer "F.SilkS")
		)
		(fp_line
			(start -0.67945 -0.305054)
			(end -0.12065 -0.305054)
			(stroke
				(width 0.1)
				(type default)
			)
			(layer "F.Fab")
		)
		(fp_line
			(start -0.67945 0.3048)
			(end -0.67945 -0.305054)
			(stroke
				(width 0.1)
				(type default)
			)
			(layer "F.Fab")
		)
		(fp_line
			(start -0.12065 -0.305054)
			(end -0.12065 -0.2794)
			(stroke
				(width 0.1)
				(type default)
			)
			(layer "F.Fab")
		)
		(fp_line
			(start -0.12065 -0.2794)
			(end 0.12065 -0.2794)
			(stroke
				(width 0.1)
				(type default)
			)
			(layer "F.Fab")
		)
		(fp_line
			(start -0.12065 0.2794)
			(end -0.12065 0.3048)
			(stroke
				(width 0.1)
				(type default)
			)
			(layer "F.Fab")
		)
		(fp_line
			(start -0.12065 0.3048)
			(end -0.67945 0.3048)
			(stroke
				(width 0.1)
				(type default)
			)
			(layer "F.Fab")
		)
		(fp_line
			(start 0.120396 0.2794)
			(end -0.12065 0.2794)
			(stroke
				(width 0.1)
				(type default)
			)
			(layer "F.Fab")
		)
		(fp_line
			(start 0.120396 0.3048)
			(end 0.120396 0.2794)
			(stroke
				(width 0.1)
				(type default)
			)
			(layer "F.Fab")
		)
		(fp_line
			(start 0.12065 -0.3048)
			(end 0.67945 -0.3048)
			(stroke
				(width 0.1)
				(type default)
			)
			(layer "F.Fab")
		)
		(fp_line
			(start 0.12065 -0.2794)
			(end 0.12065 -0.3048)
			(stroke
				(width 0.1)
				(type default)
			)
			(layer "F.Fab")
		)
		(fp_line
			(start 0.67945 -0.3048)
			(end 0.67945 0.3048)
			(stroke
				(width 0.1)
				(type default)
			)
			(layer "F.Fab")
		)
		(fp_line
			(start 0.67945 0.3048)
			(end 0.120396 0.3048)
			(stroke
				(width 0.1)
				(type default)
			)
			(layer "F.Fab")
		)
		(pad "1" smd circle
			(at -0.40005 0)
			(size 0 0)
			(layers "F.Cu" "F.Mask" "F.Paste")
			(net "GND")
		)
		(pad "2" smd circle
			(at 0.40005 0)
			(size 0 0)
			(layers "F.Cu" "F.Mask" "F.Paste")
			(net "INA230_4_A0")
		)
	)
	(footprint ""
		(layer "F.Cu")
		(at 174.635922 -25.846532 180)
		(property "Reference" "PC2239"
			(at 0 0 180)
			(layer "F.SilkS")
			(hide yes)
			(effects
				(font
					(size 1.27 1.27)
				)
			)
		)
		(property "Value" ""
			(at 0 0 180)
			(layer "F.Fab")
			(effects
				(font
					(size 1.27 1.27)
				)
			)
		)
		(duplicate_pad_numbers_are_jumpers no)
		(fp_line
			(start 1.2954 0.5842)
			(end -1.2954 0.5842)
			(stroke
				(width 0.1524)
				(type default)
			)
			(layer "F.SilkS")
		)
		(fp_line
			(start 1.2954 -0.5842)
			(end 1.2954 0.5842)
			(stroke
				(width 0.1524)
				(type default)
			)
			(layer "F.SilkS")
		)
		(fp_line
			(start -1.2954 0.5842)
			(end -1.2954 -0.5842)
			(stroke
				(width 0.1524)
				(type default)
			)
			(layer "F.SilkS")
		)
		(fp_line
			(start -1.2954 -0.5842)
			(end 1.2954 -0.5842)
			(stroke
				(width 0.1524)
				(type default)
			)
			(layer "F.SilkS")
		)
		(fp_line
			(start 1.1938 0.4064)
			(end 0.8636 0.4064)
			(stroke
				(width 0.1)
				(type default)
			)
			(layer "F.Fab")
		)
		(fp_line
			(start 1.1938 -0.4064)
			(end 1.1938 0.4064)
			(stroke
				(width 0.1)
				(type default)
			)
			(layer "F.Fab")
		)
		(fp_line
			(start 0.8636 0.4572)
			(end -0.8636 0.4572)
			(stroke
				(width 0.1)
				(type default)
			)
			(layer "F.Fab")
		)
		(fp_line
			(start 0.8636 0.4064)
			(end 0.8636 0.4572)
			(stroke
				(width 0.1)
				(type default)
			)
			(layer "F.Fab")
		)
		(fp_line
			(start 0.8636 -0.4064)
			(end 1.1938 -0.4064)
			(stroke
				(width 0.1)
				(type default)
			)
			(layer "F.Fab")
		)
		(fp_line
			(start 0.8636 -0.4572)
			(end 0.8636 -0.4064)
			(stroke
				(width 0.1)
				(type default)
			)
			(layer "F.Fab")
		)
		(fp_line
			(start -0.8636 0.4572)
			(end -0.8636 0.4064)
			(stroke
				(width 0.1)
				(type default)
			)
			(layer "F.Fab")
		)
		(fp_line
			(start -0.8636 0.4064)
			(end -1.1938 0.4064)
			(stroke
				(width 0.1)
				(type default)
			)
			(layer "F.Fab")
		)
		(fp_line
			(start -0.8636 -0.4064)
			(end -0.8636 -0.4572)
			(stroke
				(width 0.1)
				(type default)
			)
			(layer "F.Fab")
		)
		(fp_line
			(start -0.8636 -0.4572)
			(end 0.8636 -0.4572)
			(stroke
				(width 0.1)
				(type default)
			)
			(layer "F.Fab")
		)
		(fp_line
			(start -1.1938 0.4064)
			(end -1.1938 -0.4064)
			(stroke
				(width 0.1)
				(type default)
			)
			(layer "F.Fab")
		)
		(fp_line
			(start -1.1938 -0.4064)
			(end -0.8636 -0.4064)
			(stroke
				(width 0.1)
				(type default)
			)
			(layer "F.Fab")
		)
		(pad "1" smd rect
			(at -0.7366 0 90)
			(size 0.7112 0.8128)
			(layers "F.Cu" "F.Mask" "F.Paste")
			(net "P12V_SCM_AVIN_PD")
		)
		(pad "2" smd rect
			(at 0.7366 0 90)
			(size 0.7112 0.8128)
			(layers "F.Cu" "F.Mask" "F.Paste")
			(net "GND")
		)
	)
	(footprint ""
		(layer "F.Cu")
		(at 360.40949 -395.1732 90)
		(property "Reference" "R1014"
			(at 0 0 90)
			(layer "F.SilkS")
			(hide yes)
			(effects
				(font
					(size 1.27 1.27)
				)
			)
		)
		(property "Value" ""
			(at 0 0 90)
			(layer "F.Fab")
			(effects
				(font
					(size 1.27 1.27)
				)
			)
		)
		(duplicate_pad_numbers_are_jumpers no)
		(fp_line
			(start 0.32512 -0.175006)
			(end 0.32512 0.175006)
			(stroke
				(width 0.1)
				(type default)
			)
			(layer "F.Fab")
		)
		(fp_line
			(start -0.32512 -0.175006)
			(end 0.32512 -0.175006)
			(stroke
				(width 0.1)
				(type default)
			)
			(layer "F.Fab")
		)
		(fp_line
			(start 0.32512 0.175006)
			(end -0.32512 0.175006)
			(stroke
				(width 0.1)
				(type default)
			)
			(layer "F.Fab")
		)
		(fp_line
			(start -0.32512 0.175006)
			(end -0.32512 -0.175006)
			(stroke
				(width 0.1)
				(type default)
			)
			(layer "F.Fab")
		)
		(pad "1" smd rect
			(at -0.2667 0 90)
			(size 0.3048 0.381)
			(layers "F.Cu" "F.Mask" "F.Paste")
			(net "RT_CPU0_P1_ADDR3")
		)
		(pad "2" smd rect
			(at 0.2667 0 270)
			(size 0.3048 0.381)
			(layers "F.Cu" "F.Mask" "F.Paste")
			(net "GND")
		)
	)
	(footprint ""
		(layer "F.Cu")
		(at 27.73553 -422.330626)
		(property "Reference" "C6006"
			(at 0 0 0)
			(layer "F.SilkS")
			(hide yes)
			(effects
				(font
					(size 1.27 1.27)
				)
			)
		)
		(property "Value" ""
			(at 0 0 0)
			(layer "F.Fab")
			(effects
				(font
					(size 1.27 1.27)
				)
			)
		)
		(duplicate_pad_numbers_are_jumpers no)
		(fp_line
			(start -0.7874 -0.4064)
			(end 0.7874 -0.4064)
			(stroke
				(width 0.1524)
				(type default)
			)
			(layer "F.SilkS")
		)
		(fp_line
			(start -0.35433 0.4064)
			(end -0.7874 0.4064)
			(stroke
				(width 0.1524)
				(type default)
			)
			(layer "F.SilkS")
		)
		(fp_line
			(start 0.7874 -0.4064)
			(end 0.7874 0.284226)
			(stroke
				(width 0.1524)
				(type default)
			)
			(layer "F.SilkS")
		)
		(fp_line
			(start -0.6858 -0.3048)
			(end -0.1016 -0.3048)
			(stroke
				(width 0.1)
				(type default)
			)
			(layer "F.Fab")
		)
		(fp_line
			(start -0.6858 0.3048)
			(end -0.6858 -0.3048)
			(stroke
				(width 0.1)
				(type default)
			)
			(layer "F.Fab")
		)
		(fp_line
			(start -0.1016 -0.3048)
			(end -0.1016 -0.2794)
			(stroke
				(width 0.1)
				(type default)
			)
			(layer "F.Fab")
		)
		(fp_line
			(start -0.1016 -0.2794)
			(end 0.1016 -0.2794)
			(stroke
				(width 0.1)
				(type default)
			)
			(layer "F.Fab")
		)
		(fp_line
			(start -0.1016 0.2794)
			(end -0.1016 0.3048)
			(stroke
				(width 0.1)
				(type default)
			)
			(layer "F.Fab")
		)
		(fp_line
			(start -0.1016 0.3048)
			(end -0.6858 0.3048)
			(stroke
				(width 0.1)
				(type default)
			)
			(layer "F.Fab")
		)
		(fp_line
			(start 0.1016 -0.3048)
			(end 0.6858 -0.3048)
			(stroke
				(width 0.1)
				(type default)
			)
			(layer "F.Fab")
		)
		(fp_line
			(start 0.1016 -0.2794)
			(end 0.1016 -0.3048)
			(stroke
				(width 0.1)
				(type default)
			)
			(layer "F.Fab")
		)
		(fp_line
			(start 0.1016 0.2794)
			(end -0.1016 0.2794)
			(stroke
				(width 0.1)
				(type default)
			)
			(layer "F.Fab")
		)
		(fp_line
			(start 0.1016 0.3048)
			(end 0.1016 0.2794)
			(stroke
				(width 0.1)
				(type default)
			)
			(layer "F.Fab")
		)
		(fp_line
			(start 0.6858 -0.3048)
			(end 0.6858 0.3048)
			(stroke
				(width 0.1)
				(type default)
			)
			(layer "F.Fab")
		)
		(fp_line
			(start 0.6858 0.3048)
			(end 0.1016 0.3048)
			(stroke
				(width 0.1)
				(type default)
			)
			(layer "F.Fab")
		)
		(pad "1" smd rect
			(at -0.40005 0 180)
			(size 0.4572 0.508)
			(layers "F.Cu" "F.Mask" "F.Paste")
			(net "P2E_MB_BMC_TX_BUF2_DN<0>")
		)
		(pad "2" smd rect
			(at 0.40005 0 180)
			(size 0.4572 0.508)
			(layers "F.Cu" "F.Mask" "F.Paste")
			(net "P2E_MB_BMC_TX_BUF_C_DN<0>")
		)
	)
	(footprint ""
		(layer "F.Cu")
		(at 120.631712 -71.337932)
		(property "Reference" "PR6008"
			(at 0 0 0)
			(layer "F.SilkS")
			(hide yes)
			(effects
				(font
					(size 1.27 1.27)
				)
			)
		)
		(property "Value" ""
			(at 0 0 0)
			(layer "F.Fab")
			(effects
				(font
					(size 1.27 1.27)
				)
			)
		)
		(duplicate_pad_numbers_are_jumpers no)
		(fp_line
			(start -0.7874 -0.4064)
			(end 0.7874 -0.4064)
			(stroke
				(width 0.1524)
				(type default)
			)
			(layer "F.SilkS")
		)
		(fp_line
			(start -0.7874 0.4064)
			(end -0.7874 -0.4064)
			(stroke
				(width 0.1524)
				(type default)
			)
			(layer "F.SilkS")
		)
		(fp_line
			(start 0.7874 -0.4064)
			(end 0.7874 0.4064)
			(stroke
				(width 0.1524)
				(type default)
			)
			(layer "F.SilkS")
		)
		(fp_line
			(start 0.7874 0.4064)
			(end -0.7874 0.4064)
			(stroke
				(width 0.1524)
				(type default)
			)
			(layer "F.SilkS")
		)
		(fp_line
			(start -0.67945 -0.305054)
			(end -0.12065 -0.305054)
			(stroke
				(width 0.1)
				(type default)
			)
			(layer "F.Fab")
		)
		(fp_line
			(start -0.67945 0.3048)
			(end -0.67945 -0.305054)
			(stroke
				(width 0.1)
				(type default)
			)
			(layer "F.Fab")
		)
		(fp_line
			(start -0.12065 -0.305054)
			(end -0.12065 -0.2794)
			(stroke
				(width 0.1)
				(type default)
			)
			(layer "F.Fab")
		)
		(fp_line
			(start -0.12065 -0.2794)
			(end 0.12065 -0.2794)
			(stroke
				(width 0.1)
				(type default)
			)
			(layer "F.Fab")
		)
		(fp_line
			(start -0.12065 0.2794)
			(end -0.12065 0.3048)
			(stroke
				(width 0.1)
				(type default)
			)
			(layer "F.Fab")
		)
		(fp_line
			(start -0.12065 0.3048)
			(end -0.67945 0.3048)
			(stroke
				(width 0.1)
				(type default)
			)
			(layer "F.Fab")
		)
		(fp_line
			(start 0.120396 0.2794)
			(end -0.12065 0.2794)
			(stroke
				(width 0.1)
				(type default)
			)
			(layer "F.Fab")
		)
		(fp_line
			(start 0.120396 0.3048)
			(end 0.120396 0.2794)
			(stroke
				(width 0.1)
				(type default)
			)
			(layer "F.Fab")
		)
		(fp_line
			(start 0.12065 -0.3048)
			(end 0.67945 -0.3048)
			(stroke
				(width 0.1)
				(type default)
			)
			(layer "F.Fab")
		)
		(fp_line
			(start 0.12065 -0.2794)
			(end 0.12065 -0.3048)
			(stroke
				(width 0.1)
				(type default)
			)
			(layer "F.Fab")
		)
		(fp_line
			(start 0.67945 -0.3048)
			(end 0.67945 0.3048)
			(stroke
				(width 0.1)
				(type default)
			)
			(layer "F.Fab")
		)
		(fp_line
			(start 0.67945 0.3048)
			(end 0.120396 0.3048)
			(stroke
				(width 0.1)
				(type default)
			)
			(layer "F.Fab")
		)
		(pad "1" smd circle
			(at -0.40005 0)
			(size 0 0)
			(layers "F.Cu" "F.Mask" "F.Paste")
			(net "P1V2_AUX_FB")
		)
		(pad "2" smd circle
			(at 0.40005 0)
			(size 0 0)
			(layers "F.Cu" "F.Mask" "F.Paste")
			(net "P1V2_AUX")
		)
	)
	(footprint ""
		(layer "F.Cu")
		(at 432.308 -408.2796)
		(property "Reference" "R1479"
			(at 0 0 0)
			(layer "F.SilkS")
			(hide yes)
			(effects
				(font
					(size 1.27 1.27)
				)
			)
		)
		(property "Value" ""
			(at 0 0 0)
			(layer "F.Fab")
			(effects
				(font
					(size 1.27 1.27)
				)
			)
		)
		(duplicate_pad_numbers_are_jumpers no)
		(fp_line
			(start -0.32512 -0.175006)
			(end 0.32512 -0.175006)
			(stroke
				(width 0.1)
				(type default)
			)
			(layer "F.Fab")
		)
		(fp_line
			(start -0.32512 0.175006)
			(end -0.32512 -0.175006)
			(stroke
				(width 0.1)
				(type default)
			)
			(layer "F.Fab")
		)
		(fp_line
			(start 0.32512 -0.175006)
			(end 0.32512 0.175006)
			(stroke
				(width 0.1)
				(type default)
			)
			(layer "F.Fab")
		)
		(fp_line
			(start 0.32512 0.175006)
			(end -0.32512 0.175006)
			(stroke
				(width 0.1)
				(type default)
			)
			(layer "F.Fab")
		)
		(pad "1" smd rect
			(at -0.2667 0)
			(size 0.3048 0.381)
			(layers "F.Cu" "F.Mask" "F.Paste")
			(net "P1V8_CPU0_RT_1D")
		)
		(pad "2" smd rect
			(at 0.2667 0 180)
			(size 0.3048 0.381)
			(layers "F.Cu" "F.Mask" "F.Paste")
			(net "JTAG_TCK_RT_CPU0_P2")
		)
	)
	(footprint ""
		(layer "F.Cu")
		(at 320.325496 -381.41783 -90)
		(property "Reference" "C910"
			(at 0 0 270)
			(layer "F.SilkS")
			(hide yes)
			(effects
				(font
					(size 1.27 1.27)
				)
			)
		)
		(property "Value" ""
			(at 0 0 270)
			(layer "F.Fab")
			(effects
				(font
					(size 1.27 1.27)
				)
			)
		)
		(duplicate_pad_numbers_are_jumpers no)
		(fp_line
			(start -0.299974 0.150114)
			(end -0.299974 -0.150114)
			(stroke
				(width 0.1)
				(type default)
			)
			(layer "F.Fab")
		)
		(fp_line
			(start 0.299974 0.150114)
			(end -0.299974 0.150114)
			(stroke
				(width 0.1)
				(type default)
			)
			(layer "F.Fab")
		)
		(fp_line
			(start -0.299974 -0.150114)
			(end 0.299974 -0.150114)
			(stroke
				(width 0.1)
				(type default)
			)
			(layer "F.Fab")
		)
		(fp_line
			(start 0.299974 -0.150114)
			(end 0.299974 0.150114)
			(stroke
				(width 0.1)
				(type default)
			)
			(layer "F.Fab")
		)
		(pad "1" smd rect
			(at -0.2667 0 270)
			(size 0.3048 0.381)
			(layers "F.Cu" "F.Mask" "F.Paste")
			(net "P5E_CPU0_P0_TX_C_DN<11>")
		)
		(pad "2" smd rect
			(at 0.2667 0 270)
			(size 0.3048 0.381)
			(layers "F.Cu" "F.Mask" "F.Paste")
			(net "P5E_CPU0_P0_TX_DN<11>")
		)
	)
	(footprint ""
		(layer "F.Cu")
		(at 20.00504 -333.295244 180)
		(property "Reference" "TP12"
			(at 6.88848 0.856742 0)
			(unlocked yes)
			(layer "F.SilkS")
			(effects
				(font
					(size 0.7874 0.5842)
					(thickness 0.1524)
				)
				(justify left)
			)
		)
		(property "Value" ""
			(at 0 0 180)
			(layer "F.Fab")
			(effects
				(font
					(size 1.27 1.27)
				)
			)
		)
		(duplicate_pad_numbers_are_jumpers no)
		(pad "1" smd circle
			(at 0 0 180)
			(size 0.762 0.762)
			(layers "F.Cu" "F.Mask" "F.Paste")
			(net "VSENSE_VSS_SENSE_B_P1")
		)
	)
	(footprint ""
		(layer "F.Cu")
		(at 167.132 -108.168948 180)
		(property "Reference" "R49"
			(at 0 0 180)
			(layer "F.SilkS")
			(hide yes)
			(effects
				(font
					(size 1.27 1.27)
				)
			)
		)
		(property "Value" ""
			(at 0 0 180)
			(layer "F.Fab")
			(effects
				(font
					(size 1.27 1.27)
				)
			)
		)
		(duplicate_pad_numbers_are_jumpers no)
		(fp_line
			(start 0.7874 0.4064)
			(end -0.7874 0.4064)
			(stroke
				(width 0.1524)
				(type default)
			)
			(layer "F.SilkS")
		)
		(fp_line
			(start 0.7874 -0.4064)
			(end 0.7874 0.4064)
			(stroke
				(width 0.1524)
				(type default)
			)
			(layer "F.SilkS")
		)
		(fp_line
			(start -0.7874 0.4064)
			(end -0.7874 -0.4064)
			(stroke
				(width 0.1524)
				(type default)
			)
			(layer "F.SilkS")
		)
		(fp_line
			(start -0.7874 -0.4064)
			(end 0.7874 -0.4064)
			(stroke
				(width 0.1524)
				(type default)
			)
			(layer "F.SilkS")
		)
		(fp_line
			(start 0.67945 0.3048)
			(end 0.120396 0.3048)
			(stroke
				(width 0.1)
				(type default)
			)
			(layer "F.Fab")
		)
		(fp_line
			(start 0.67945 -0.3048)
			(end 0.67945 0.3048)
			(stroke
				(width 0.1)
				(type default)
			)
			(layer "F.Fab")
		)
		(fp_line
			(start 0.12065 -0.2794)
			(end 0.12065 -0.3048)
			(stroke
				(width 0.1)
				(type default)
			)
			(layer "F.Fab")
		)
		(fp_line
			(start 0.12065 -0.3048)
			(end 0.67945 -0.3048)
			(stroke
				(width 0.1)
				(type default)
			)
			(layer "F.Fab")
		)
		(fp_line
			(start 0.120396 0.3048)
			(end 0.120396 0.2794)
			(stroke
				(width 0.1)
				(type default)
			)
			(layer "F.Fab")
		)
		(fp_line
			(start 0.120396 0.2794)
			(end -0.12065 0.2794)
			(stroke
				(width 0.1)
				(type default)
			)
			(layer "F.Fab")
		)
		(fp_line
			(start -0.12065 0.3048)
			(end -0.67945 0.3048)
			(stroke
				(width 0.1)
				(type default)
			)
			(layer "F.Fab")
		)
		(fp_line
			(start -0.12065 0.2794)
			(end -0.12065 0.3048)
			(stroke
				(width 0.1)
				(type default)
			)
			(layer "F.Fab")
		)
		(fp_line
			(start -0.12065 -0.2794)
			(end 0.12065 -0.2794)
			(stroke
				(width 0.1)
				(type default)
			)
			(layer "F.Fab")
		)
		(fp_line
			(start -0.12065 -0.305054)
			(end -0.12065 -0.2794)
			(stroke
				(width 0.1)
				(type default)
			)
			(layer "F.Fab")
		)
		(fp_line
			(start -0.67945 0.3048)
			(end -0.67945 -0.305054)
			(stroke
				(width 0.1)
				(type default)
			)
			(layer "F.Fab")
		)
		(fp_line
			(start -0.67945 -0.305054)
			(end -0.12065 -0.305054)
			(stroke
				(width 0.1)
				(type default)
			)
			(layer "F.Fab")
		)
		(pad "1" smd circle
			(at -0.40005 0 180)
			(size 0 0)
			(layers "F.Cu" "F.Mask" "F.Paste")
			(net "SCM_JTAG_MUX_R_S0")
		)
		(pad "2" smd circle
			(at 0.40005 0 180)
			(size 0 0)
			(layers "F.Cu" "F.Mask" "F.Paste")
			(net "SCM_JTAG_MUX_S0")
		)
	)
	(footprint ""
		(layer "F.Cu")
		(at 194.904106 -351.409254 -90)
		(property "Reference" "PC512_2"
			(at 0 0 270)
			(layer "F.SilkS")
			(hide yes)
			(effects
				(font
					(size 1.27 1.27)
				)
			)
		)
		(property "Value" ""
			(at 0 0 270)
			(layer "F.Fab")
			(effects
				(font
					(size 1.27 1.27)
				)
			)
		)
		(duplicate_pad_numbers_are_jumpers no)
		(fp_line
			(start -0.7874 0.4064)
			(end -0.7874 -0.4064)
			(stroke
				(width 0.1524)
				(type default)
			)
			(layer "F.SilkS")
		)
		(fp_line
			(start 0.7874 0.4064)
			(end -0.7874 0.4064)
			(stroke
				(width 0.1524)
				(type default)
			)
			(layer "F.SilkS")
		)
		(fp_line
			(start -0.7874 -0.4064)
			(end 0.7874 -0.4064)
			(stroke
				(width 0.1524)
				(type default)
			)
			(layer "F.SilkS")
		)
		(fp_line
			(start 0.7874 -0.4064)
			(end 0.7874 0.4064)
			(stroke
				(width 0.1524)
				(type default)
			)
			(layer "F.SilkS")
		)
		(fp_line
			(start -0.67945 0.3048)
			(end -0.67945 -0.305054)
			(stroke
				(width 0.1)
				(type default)
			)
			(layer "F.Fab")
		)
		(fp_line
			(start -0.12065 0.3048)
			(end -0.67945 0.3048)
			(stroke
				(width 0.1)
				(type default)
			)
			(layer "F.Fab")
		)
		(fp_line
			(start 0.120396 0.3048)
			(end 0.120396 0.2794)
			(stroke
				(width 0.1)
				(type default)
			)
			(layer "F.Fab")
		)
		(fp_line
			(start 0.67945 0.3048)
			(end 0.120396 0.3048)
			(stroke
				(width 0.1)
				(type default)
			)
			(layer "F.Fab")
		)
		(fp_line
			(start -0.12065 0.2794)
			(end -0.12065 0.3048)
			(stroke
				(width 0.1)
				(type default)
			)
			(layer "F.Fab")
		)
		(fp_line
			(start 0.120396 0.2794)
			(end -0.12065 0.2794)
			(stroke
				(width 0.1)
				(type default)
			)
			(layer "F.Fab")
		)
		(fp_line
			(start -0.12065 -0.2794)
			(end 0.12065 -0.2794)
			(stroke
				(width 0.1)
				(type default)
			)
			(layer "F.Fab")
		)
		(fp_line
			(start 0.12065 -0.2794)
			(end 0.12065 -0.3048)
			(stroke
				(width 0.1)
				(type default)
			)
			(layer "F.Fab")
		)
		(fp_line
			(start 0.12065 -0.3048)
			(end 0.67945 -0.3048)
			(stroke
				(width 0.1)
				(type default)
			)
			(layer "F.Fab")
		)
		(fp_line
			(start 0.67945 -0.3048)
			(end 0.67945 0.3048)
			(stroke
				(width 0.1)
				(type default)
			)
			(layer "F.Fab")
		)
		(fp_line
			(start -0.67945 -0.305054)
			(end -0.12065 -0.305054)
			(stroke
				(width 0.1)
				(type default)
			)
			(layer "F.Fab")
		)
		(fp_line
			(start -0.12065 -0.305054)
			(end -0.12065 -0.2794)
			(stroke
				(width 0.1)
				(type default)
			)
			(layer "F.Fab")
		)
		(pad "1" smd circle
			(at -0.40005 0 270)
			(size 0 0)
			(layers "F.Cu" "F.Mask" "F.Paste")
			(net "SW_P12V_AUX_PVDD11_S3_P1_FLT")
		)
		(pad "2" smd circle
			(at 0.40005 0 270)
			(size 0 0)
			(layers "F.Cu" "F.Mask" "F.Paste")
			(net "GND")
		)
	)
	(footprint ""
		(layer "F.Cu")
		(at 354.247704 -164.844222 90)
		(property "Reference" "PC574"
			(at 0 0 90)
			(layer "F.SilkS")
			(hide yes)
			(effects
				(font
					(size 1.27 1.27)
				)
			)
		)
		(property "Value" ""
			(at 0 0 90)
			(layer "F.Fab")
			(effects
				(font
					(size 1.27 1.27)
				)
			)
		)
		(duplicate_pad_numbers_are_jumpers no)
		(fp_line
			(start 0.7874 -0.4064)
			(end 0.7874 0.4064)
			(stroke
				(width 0.1524)
				(type default)
			)
			(layer "F.SilkS")
		)
		(fp_line
			(start -0.7874 -0.4064)
			(end 0.7874 -0.4064)
			(stroke
				(width 0.1524)
				(type default)
			)
			(layer "F.SilkS")
		)
		(fp_line
			(start 0.7874 0.4064)
			(end -0.7874 0.4064)
			(stroke
				(width 0.1524)
				(type default)
			)
			(layer "F.SilkS")
		)
		(fp_line
			(start -0.7874 0.4064)
			(end -0.7874 -0.4064)
			(stroke
				(width 0.1524)
				(type default)
			)
			(layer "F.SilkS")
		)
		(fp_line
			(start -0.12065 -0.305054)
			(end -0.12065 -0.2794)
			(stroke
				(width 0.1)
				(type default)
			)
			(layer "F.Fab")
		)
		(fp_line
			(start -0.67945 -0.305054)
			(end -0.12065 -0.305054)
			(stroke
				(width 0.1)
				(type default)
			)
			(layer "F.Fab")
		)
		(fp_line
			(start 0.67945 -0.3048)
			(end 0.67945 0.3048)
			(stroke
				(width 0.1)
				(type default)
			)
			(layer "F.Fab")
		)
		(fp_line
			(start 0.12065 -0.3048)
			(end 0.67945 -0.3048)
			(stroke
				(width 0.1)
				(type default)
			)
			(layer "F.Fab")
		)
		(fp_line
			(start 0.12065 -0.2794)
			(end 0.12065 -0.3048)
			(stroke
				(width 0.1)
				(type default)
			)
			(layer "F.Fab")
		)
		(fp_line
			(start -0.12065 -0.2794)
			(end 0.12065 -0.2794)
			(stroke
				(width 0.1)
				(type default)
			)
			(layer "F.Fab")
		)
		(fp_line
			(start 0.120396 0.2794)
			(end -0.12065 0.2794)
			(stroke
				(width 0.1)
				(type default)
			)
			(layer "F.Fab")
		)
		(fp_line
			(start -0.12065 0.2794)
			(end -0.12065 0.3048)
			(stroke
				(width 0.1)
				(type default)
			)
			(layer "F.Fab")
		)
		(fp_line
			(start 0.67945 0.3048)
			(end 0.120396 0.3048)
			(stroke
				(width 0.1)
				(type default)
			)
			(layer "F.Fab")
		)
		(fp_line
			(start 0.120396 0.3048)
			(end 0.120396 0.2794)
			(stroke
				(width 0.1)
				(type default)
			)
			(layer "F.Fab")
		)
		(fp_line
			(start -0.12065 0.3048)
			(end -0.67945 0.3048)
			(stroke
				(width 0.1)
				(type default)
			)
			(layer "F.Fab")
		)
		(fp_line
			(start -0.67945 0.3048)
			(end -0.67945 -0.305054)
			(stroke
				(width 0.1)
				(type default)
			)
			(layer "F.Fab")
		)
		(pad "1" smd circle
			(at -0.40005 0 90)
			(size 0 0)
			(layers "F.Cu" "F.Mask" "F.Paste")
			(net "SW_PVDDCR_CPU0_P0_BOOT5_RC")
		)
		(pad "2" smd circle
			(at 0.40005 0 90)
			(size 0 0)
			(layers "F.Cu" "F.Mask" "F.Paste")
			(net "SW_PVDDCR_CPU0_P0_PH5")
		)
	)
	(footprint ""
		(layer "F.Cu")
		(at 168.402762 -419.1508 90)
		(property "Reference" "R698"
			(at 0 0 90)
			(layer "F.SilkS")
			(hide yes)
			(effects
				(font
					(size 1.27 1.27)
				)
			)
		)
		(property "Value" ""
			(at 0 0 90)
			(layer "F.Fab")
			(effects
				(font
					(size 1.27 1.27)
				)
			)
		)
		(duplicate_pad_numbers_are_jumpers no)
		(fp_line
			(start 0.32512 -0.175006)
			(end 0.32512 0.175006)
			(stroke
				(width 0.1)
				(type default)
			)
			(layer "F.Fab")
		)
		(fp_line
			(start -0.32512 -0.175006)
			(end 0.32512 -0.175006)
			(stroke
				(width 0.1)
				(type default)
			)
			(layer "F.Fab")
		)
		(fp_line
			(start 0.32512 0.175006)
			(end -0.32512 0.175006)
			(stroke
				(width 0.1)
				(type default)
			)
			(layer "F.Fab")
		)
		(fp_line
			(start -0.32512 0.175006)
			(end -0.32512 -0.175006)
			(stroke
				(width 0.1)
				(type default)
			)
			(layer "F.Fab")
		)
		(pad "1" smd rect
			(at -0.2667 0 90)
			(size 0.3048 0.381)
			(layers "F.Cu" "F.Mask" "F.Paste")
			(net "SMB_RT_CPU1_P3_ROM_R_SDA")
		)
		(pad "2" smd rect
			(at 0.2667 0 270)
			(size 0.3048 0.381)
			(layers "F.Cu" "F.Mask" "F.Paste")
			(net "SMB_RT_CPU1_P3_ROM_SDA")
		)
	)
	(footprint ""
		(layer "F.Cu")
		(at 271.080484 -113.156746)
		(property "Reference" "R3732"
			(at 0 0 0)
			(layer "F.SilkS")
			(hide yes)
			(effects
				(font
					(size 1.27 1.27)
				)
			)
		)
		(property "Value" ""
			(at 0 0 0)
			(layer "F.Fab")
			(effects
				(font
					(size 1.27 1.27)
				)
			)
		)
		(duplicate_pad_numbers_are_jumpers no)
		(fp_line
			(start -0.7874 -0.4064)
			(end 0.7874 -0.4064)
			(stroke
				(width 0.1524)
				(type default)
			)
			(layer "F.SilkS")
		)
		(fp_line
			(start -0.7874 0.4064)
			(end -0.7874 -0.4064)
			(stroke
				(width 0.1524)
				(type default)
			)
			(layer "F.SilkS")
		)
		(fp_line
			(start 0.7874 -0.4064)
			(end 0.7874 0.4064)
			(stroke
				(width 0.1524)
				(type default)
			)
			(layer "F.SilkS")
		)
		(fp_line
			(start 0.7874 0.4064)
			(end -0.7874 0.4064)
			(stroke
				(width 0.1524)
				(type default)
			)
			(layer "F.SilkS")
		)
		(fp_line
			(start -0.67945 -0.305054)
			(end -0.12065 -0.305054)
			(stroke
				(width 0.1)
				(type default)
			)
			(layer "F.Fab")
		)
		(fp_line
			(start -0.67945 0.3048)
			(end -0.67945 -0.305054)
			(stroke
				(width 0.1)
				(type default)
			)
			(layer "F.Fab")
		)
		(fp_line
			(start -0.12065 -0.305054)
			(end -0.12065 -0.2794)
			(stroke
				(width 0.1)
				(type default)
			)
			(layer "F.Fab")
		)
		(fp_line
			(start -0.12065 -0.2794)
			(end 0.12065 -0.2794)
			(stroke
				(width 0.1)
				(type default)
			)
			(layer "F.Fab")
		)
		(fp_line
			(start -0.12065 0.2794)
			(end -0.12065 0.3048)
			(stroke
				(width 0.1)
				(type default)
			)
			(layer "F.Fab")
		)
		(fp_line
			(start -0.12065 0.3048)
			(end -0.67945 0.3048)
			(stroke
				(width 0.1)
				(type default)
			)
			(layer "F.Fab")
		)
		(fp_line
			(start 0.120396 0.2794)
			(end -0.12065 0.2794)
			(stroke
				(width 0.1)
				(type default)
			)
			(layer "F.Fab")
		)
		(fp_line
			(start 0.120396 0.3048)
			(end 0.120396 0.2794)
			(stroke
				(width 0.1)
				(type default)
			)
			(layer "F.Fab")
		)
		(fp_line
			(start 0.12065 -0.3048)
			(end 0.67945 -0.3048)
			(stroke
				(width 0.1)
				(type default)
			)
			(layer "F.Fab")
		)
		(fp_line
			(start 0.12065 -0.2794)
			(end 0.12065 -0.3048)
			(stroke
				(width 0.1)
				(type default)
			)
			(layer "F.Fab")
		)
		(fp_line
			(start 0.67945 -0.3048)
			(end 0.67945 0.3048)
			(stroke
				(width 0.1)
				(type default)
			)
			(layer "F.Fab")
		)
		(fp_line
			(start 0.67945 0.3048)
			(end 0.120396 0.3048)
			(stroke
				(width 0.1)
				(type default)
			)
			(layer "F.Fab")
		)
		(pad "1" smd circle
			(at -0.40005 0)
			(size 0 0)
			(layers "F.Cu" "F.Mask" "F.Paste")
			(net "P3V3_AUX")
		)
		(pad "2" smd circle
			(at 0.40005 0)
			(size 0 0)
			(layers "F.Cu" "F.Mask" "F.Paste")
			(net "SMB_LM75_3_3V3AUX_SDA")
		)
	)
	(footprint ""
		(layer "F.Cu")
		(at 322.837048 -40.144954 180)
		(property "Reference" "R3688"
			(at 0 0 180)
			(layer "F.SilkS")
			(hide yes)
			(effects
				(font
					(size 1.27 1.27)
				)
			)
		)
		(property "Value" ""
			(at 0 0 180)
			(layer "F.Fab")
			(effects
				(font
					(size 1.27 1.27)
				)
			)
		)
		(duplicate_pad_numbers_are_jumpers no)
		(fp_line
			(start 0.7874 0.4064)
			(end -0.7874 0.4064)
			(stroke
				(width 0.1524)
				(type default)
			)
			(layer "F.SilkS")
		)
		(fp_line
			(start 0.7874 -0.4064)
			(end 0.7874 0.4064)
			(stroke
				(width 0.1524)
				(type default)
			)
			(layer "F.SilkS")
		)
		(fp_line
			(start -0.7874 0.4064)
			(end -0.7874 -0.4064)
			(stroke
				(width 0.1524)
				(type default)
			)
			(layer "F.SilkS")
		)
		(fp_line
			(start -0.7874 -0.4064)
			(end 0.7874 -0.4064)
			(stroke
				(width 0.1524)
				(type default)
			)
			(layer "F.SilkS")
		)
		(fp_line
			(start 0.67945 0.3048)
			(end 0.120396 0.3048)
			(stroke
				(width 0.1)
				(type default)
			)
			(layer "F.Fab")
		)
		(fp_line
			(start 0.67945 -0.3048)
			(end 0.67945 0.3048)
			(stroke
				(width 0.1)
				(type default)
			)
			(layer "F.Fab")
		)
		(fp_line
			(start 0.12065 -0.2794)
			(end 0.12065 -0.3048)
			(stroke
				(width 0.1)
				(type default)
			)
			(layer "F.Fab")
		)
		(fp_line
			(start 0.12065 -0.3048)
			(end 0.67945 -0.3048)
			(stroke
				(width 0.1)
				(type default)
			)
			(layer "F.Fab")
		)
		(fp_line
			(start 0.120396 0.3048)
			(end 0.120396 0.2794)
			(stroke
				(width 0.1)
				(type default)
			)
			(layer "F.Fab")
		)
		(fp_line
			(start 0.120396 0.2794)
			(end -0.12065 0.2794)
			(stroke
				(width 0.1)
				(type default)
			)
			(layer "F.Fab")
		)
		(fp_line
			(start -0.12065 0.3048)
			(end -0.67945 0.3048)
			(stroke
				(width 0.1)
				(type default)
			)
			(layer "F.Fab")
		)
		(fp_line
			(start -0.12065 0.2794)
			(end -0.12065 0.3048)
			(stroke
				(width 0.1)
				(type default)
			)
			(layer "F.Fab")
		)
		(fp_line
			(start -0.12065 -0.2794)
			(end 0.12065 -0.2794)
			(stroke
				(width 0.1)
				(type default)
			)
			(layer "F.Fab")
		)
		(fp_line
			(start -0.12065 -0.305054)
			(end -0.12065 -0.2794)
			(stroke
				(width 0.1)
				(type default)
			)
			(layer "F.Fab")
		)
		(fp_line
			(start -0.67945 0.3048)
			(end -0.67945 -0.305054)
			(stroke
				(width 0.1)
				(type default)
			)
			(layer "F.Fab")
		)
		(fp_line
			(start -0.67945 -0.305054)
			(end -0.12065 -0.305054)
			(stroke
				(width 0.1)
				(type default)
			)
			(layer "F.Fab")
		)
		(pad "1" smd rect
			(at -0.40005 0)
			(size 0.4572 0.508)
			(layers "F.Cu" "F.Mask" "F.Paste")
			(net "P1V581_PDB_ADC")
		)
		(pad "2" smd rect
			(at 0.40005 0)
			(size 0.4572 0.508)
			(layers "F.Cu" "F.Mask" "F.Paste")
			(net "P3V3_PDB_AUX_ADC_TIC")
		)
	)
	(footprint ""
		(layer "F.Cu")
		(at 355.616002 -256.012188 90)
		(property "Reference" "C2562"
			(at 0 0 90)
			(layer "F.SilkS")
			(hide yes)
			(effects
				(font
					(size 1.27 1.27)
				)
			)
		)
		(property "Value" ""
			(at 0 0 90)
			(layer "F.Fab")
			(effects
				(font
					(size 1.27 1.27)
				)
			)
		)
		(duplicate_pad_numbers_are_jumpers no)
		(fp_line
			(start 0.7874 -0.4064)
			(end 0.7874 0.4064)
			(stroke
				(width 0.1524)
				(type default)
			)
			(layer "F.SilkS")
		)
		(fp_line
			(start -0.7874 -0.4064)
			(end 0.7874 -0.4064)
			(stroke
				(width 0.1524)
				(type default)
			)
			(layer "F.SilkS")
		)
		(fp_line
			(start 0.7874 0.4064)
			(end -0.7874 0.4064)
			(stroke
				(width 0.1524)
				(type default)
			)
			(layer "F.SilkS")
		)
		(fp_line
			(start -0.7874 0.4064)
			(end -0.7874 -0.4064)
			(stroke
				(width 0.1524)
				(type default)
			)
			(layer "F.SilkS")
		)
		(fp_line
			(start -0.12065 -0.305054)
			(end -0.12065 -0.2794)
			(stroke
				(width 0.1)
				(type default)
			)
			(layer "F.Fab")
		)
		(fp_line
			(start -0.67945 -0.305054)
			(end -0.12065 -0.305054)
			(stroke
				(width 0.1)
				(type default)
			)
			(layer "F.Fab")
		)
		(fp_line
			(start 0.67945 -0.3048)
			(end 0.67945 0.3048)
			(stroke
				(width 0.1)
				(type default)
			)
			(layer "F.Fab")
		)
		(fp_line
			(start 0.12065 -0.3048)
			(end 0.67945 -0.3048)
			(stroke
				(width 0.1)
				(type default)
			)
			(layer "F.Fab")
		)
		(fp_line
			(start 0.12065 -0.2794)
			(end 0.12065 -0.3048)
			(stroke
				(width 0.1)
				(type default)
			)
			(layer "F.Fab")
		)
		(fp_line
			(start -0.12065 -0.2794)
			(end 0.12065 -0.2794)
			(stroke
				(width 0.1)
				(type default)
			)
			(layer "F.Fab")
		)
		(fp_line
			(start 0.120396 0.2794)
			(end -0.12065 0.2794)
			(stroke
				(width 0.1)
				(type default)
			)
			(layer "F.Fab")
		)
		(fp_line
			(start -0.12065 0.2794)
			(end -0.12065 0.3048)
			(stroke
				(width 0.1)
				(type default)
			)
			(layer "F.Fab")
		)
		(fp_line
			(start 0.67945 0.3048)
			(end 0.120396 0.3048)
			(stroke
				(width 0.1)
				(type default)
			)
			(layer "F.Fab")
		)
		(fp_line
			(start 0.120396 0.3048)
			(end 0.120396 0.2794)
			(stroke
				(width 0.1)
				(type default)
			)
			(layer "F.Fab")
		)
		(fp_line
			(start -0.12065 0.3048)
			(end -0.67945 0.3048)
			(stroke
				(width 0.1)
				(type default)
			)
			(layer "F.Fab")
		)
		(fp_line
			(start -0.67945 0.3048)
			(end -0.67945 -0.305054)
			(stroke
				(width 0.1)
				(type default)
			)
			(layer "F.Fab")
		)
		(pad "1" smd circle
			(at -0.40005 0 90)
			(size 0 0)
			(layers "F.Cu" "F.Mask" "F.Paste")
			(net "PVDDCR_SOC_P0")
		)
		(pad "2" smd circle
			(at 0.40005 0 90)
			(size 0 0)
			(layers "F.Cu" "F.Mask" "F.Paste")
			(net "GND")
		)
	)
	(footprint ""
		(layer "F.Cu")
		(at 321.107308 -105.44175)
		(property "Reference" "R1317"
			(at 0 0 0)
			(layer "F.SilkS")
			(hide yes)
			(effects
				(font
					(size 1.27 1.27)
				)
			)
		)
		(property "Value" ""
			(at 0 0 0)
			(layer "F.Fab")
			(effects
				(font
					(size 1.27 1.27)
				)
			)
		)
		(duplicate_pad_numbers_are_jumpers no)
		(fp_line
			(start -0.7874 -0.4064)
			(end 0.7874 -0.4064)
			(stroke
				(width 0.1524)
				(type default)
			)
			(layer "F.SilkS")
		)
		(fp_line
			(start -0.7874 0.4064)
			(end -0.7874 -0.4064)
			(stroke
				(width 0.1524)
				(type default)
			)
			(layer "F.SilkS")
		)
		(fp_line
			(start 0.7874 -0.4064)
			(end 0.7874 0.4064)
			(stroke
				(width 0.1524)
				(type default)
			)
			(layer "F.SilkS")
		)
		(fp_line
			(start 0.7874 0.4064)
			(end -0.7874 0.4064)
			(stroke
				(width 0.1524)
				(type default)
			)
			(layer "F.SilkS")
		)
		(fp_line
			(start -0.67945 -0.305054)
			(end -0.12065 -0.305054)
			(stroke
				(width 0.1)
				(type default)
			)
			(layer "F.Fab")
		)
		(fp_line
			(start -0.67945 0.3048)
			(end -0.67945 -0.305054)
			(stroke
				(width 0.1)
				(type default)
			)
			(layer "F.Fab")
		)
		(fp_line
			(start -0.12065 -0.305054)
			(end -0.12065 -0.2794)
			(stroke
				(width 0.1)
				(type default)
			)
			(layer "F.Fab")
		)
		(fp_line
			(start -0.12065 -0.2794)
			(end 0.12065 -0.2794)
			(stroke
				(width 0.1)
				(type default)
			)
			(layer "F.Fab")
		)
		(fp_line
			(start -0.12065 0.2794)
			(end -0.12065 0.3048)
			(stroke
				(width 0.1)
				(type default)
			)
			(layer "F.Fab")
		)
		(fp_line
			(start -0.12065 0.3048)
			(end -0.67945 0.3048)
			(stroke
				(width 0.1)
				(type default)
			)
			(layer "F.Fab")
		)
		(fp_line
			(start 0.120396 0.2794)
			(end -0.12065 0.2794)
			(stroke
				(width 0.1)
				(type default)
			)
			(layer "F.Fab")
		)
		(fp_line
			(start 0.120396 0.3048)
			(end 0.120396 0.2794)
			(stroke
				(width 0.1)
				(type default)
			)
			(layer "F.Fab")
		)
		(fp_line
			(start 0.12065 -0.3048)
			(end 0.67945 -0.3048)
			(stroke
				(width 0.1)
				(type default)
			)
			(layer "F.Fab")
		)
		(fp_line
			(start 0.12065 -0.2794)
			(end 0.12065 -0.3048)
			(stroke
				(width 0.1)
				(type default)
			)
			(layer "F.Fab")
		)
		(fp_line
			(start 0.67945 -0.3048)
			(end 0.67945 0.3048)
			(stroke
				(width 0.1)
				(type default)
			)
			(layer "F.Fab")
		)
		(fp_line
			(start 0.67945 0.3048)
			(end 0.120396 0.3048)
			(stroke
				(width 0.1)
				(type default)
			)
			(layer "F.Fab")
		)
		(pad "1" smd circle
			(at -0.40005 0)
			(size 0 0)
			(layers "F.Cu" "F.Mask" "F.Paste")
			(net "P3V3_AUX")
		)
		(pad "2" smd circle
			(at 0.40005 0)
			(size 0 0)
			(layers "F.Cu" "F.Mask" "F.Paste")
			(net "INA230_8_A1")
		)
	)
	(footprint ""
		(layer "F.Cu")
		(at 234.952286 -257.70713 180)
		(property "Reference" ""
			(at 0 0 180)
			(layer "F.SilkS")
			(hide yes)
			(effects
				(font
					(size 1.27 1.27)
				)
			)
		)
		(property "Value" ""
			(at 0 0 180)
			(layer "F.Fab")
			(effects
				(font
					(size 1.27 1.27)
				)
			)
		)
		(duplicate_pad_numbers_are_jumpers no)
		(pad "1" smd circle
			(at 0 0 180)
			(size 0.9906 0.9906)
			(layers "F.Cu" "F.Mask" "F.Paste")
			(net "Net_49")
		)
		(zone
			(layer "F.Cu")
			(hatch none 0.5)
			(connect_pads
				(clearance 0)
			)
			(min_thickness 0.25)
			(keepout
				(tracks not_allowed)
				(vias allowed)
				(pads allowed)
				(copperpour not_allowed)
				(footprints allowed)
			)
			(placement
				(enabled no)
				(sheetname "")
			)
			(fill
				(thermal_gap 0.5)
				(thermal_bridge_width 0.5)
				(island_removal_mode 0)
			)
			(polygon
				(pts
					(arc
						(start 236.577886 -257.70713)
						(mid 233.326686 -257.70713)
						(end 236.577886 -257.70713)
					)
				)
			)
		)
	)
	(footprint ""
		(layer "F.Cu")
		(at 123.825 -321.655948 90)
		(property "Reference" "R4306"
			(at 0 0 90)
			(layer "F.SilkS")
			(hide yes)
			(effects
				(font
					(size 1.27 1.27)
				)
			)
		)
		(property "Value" ""
			(at 0 0 90)
			(layer "F.Fab")
			(effects
				(font
					(size 1.27 1.27)
				)
			)
		)
		(duplicate_pad_numbers_are_jumpers no)
		(fp_line
			(start -0.422148 -0.4064)
			(end 0.416052 -0.4064)
			(stroke
				(width 0.1524)
				(type default)
			)
			(layer "F.SilkS")
		)
		(fp_line
			(start 0.7874 0.0254)
			(end 0.7874 0.4064)
			(stroke
				(width 0.1524)
				(type default)
			)
			(layer "F.SilkS")
		)
		(fp_line
			(start 0.7874 0.4064)
			(end -0.7874 0.4064)
			(stroke
				(width 0.1524)
				(type default)
			)
			(layer "F.SilkS")
		)
		(fp_line
			(start -0.7874 0.4064)
			(end -0.7874 0.0254)
			(stroke
				(width 0.1524)
				(type default)
			)
			(layer "F.SilkS")
		)
		(fp_line
			(start -0.12065 -0.305054)
			(end -0.12065 -0.2794)
			(stroke
				(width 0.1)
				(type default)
			)
			(layer "F.Fab")
		)
		(fp_line
			(start -0.67945 -0.305054)
			(end -0.12065 -0.305054)
			(stroke
				(width 0.1)
				(type default)
			)
			(layer "F.Fab")
		)
		(fp_line
			(start 0.67945 -0.3048)
			(end 0.67945 0.3048)
			(stroke
				(width 0.1)
				(type default)
			)
			(layer "F.Fab")
		)
		(fp_line
			(start 0.12065 -0.3048)
			(end 0.67945 -0.3048)
			(stroke
				(width 0.1)
				(type default)
			)
			(layer "F.Fab")
		)
		(fp_line
			(start 0.12065 -0.2794)
			(end 0.12065 -0.3048)
			(stroke
				(width 0.1)
				(type default)
			)
			(layer "F.Fab")
		)
		(fp_line
			(start -0.12065 -0.2794)
			(end 0.12065 -0.2794)
			(stroke
				(width 0.1)
				(type default)
			)
			(layer "F.Fab")
		)
		(fp_line
			(start 0.120396 0.2794)
			(end -0.12065 0.2794)
			(stroke
				(width 0.1)
				(type default)
			)
			(layer "F.Fab")
		)
		(fp_line
			(start -0.12065 0.2794)
			(end -0.12065 0.3048)
			(stroke
				(width 0.1)
				(type default)
			)
			(layer "F.Fab")
		)
		(fp_line
			(start 0.67945 0.3048)
			(end 0.120396 0.3048)
			(stroke
				(width 0.1)
				(type default)
			)
			(layer "F.Fab")
		)
		(fp_line
			(start 0.120396 0.3048)
			(end 0.120396 0.2794)
			(stroke
				(width 0.1)
				(type default)
			)
			(layer "F.Fab")
		)
		(fp_line
			(start -0.12065 0.3048)
			(end -0.67945 0.3048)
			(stroke
				(width 0.1)
				(type default)
			)
			(layer "F.Fab")
		)
		(fp_line
			(start -0.67945 0.3048)
			(end -0.67945 -0.305054)
			(stroke
				(width 0.1)
				(type default)
			)
			(layer "F.Fab")
		)
		(pad "1" smd circle
			(at -0.40005 0 90)
			(size 0 0)
			(layers "F.Cu" "F.Mask" "F.Paste")
			(net "CLK_100M_CPU1_CLK12_R_DN")
		)
		(pad "2" smd circle
			(at 0.40005 0 90)
			(size 0 0)
			(layers "F.Cu" "F.Mask" "F.Paste")
			(net "CLK_100M_CPU1_CLK12_DN")
		)
	)
	(footprint ""
		(layer "F.Cu")
		(at 9.29513 -98.184208 -90)
		(property "Reference" "C2030"
			(at 0 0 270)
			(layer "F.SilkS")
			(hide yes)
			(effects
				(font
					(size 1.27 1.27)
				)
			)
		)
		(property "Value" ""
			(at 0 0 270)
			(layer "F.Fab")
			(effects
				(font
					(size 1.27 1.27)
				)
			)
		)
		(duplicate_pad_numbers_are_jumpers no)
		(fp_line
			(start -0.7874 0.4064)
			(end -0.7874 -0.4064)
			(stroke
				(width 0.1524)
				(type default)
			)
			(layer "F.SilkS")
		)
		(fp_line
			(start 0.7874 0.4064)
			(end -0.7874 0.4064)
			(stroke
				(width 0.1524)
				(type default)
			)
			(layer "F.SilkS")
		)
		(fp_line
			(start -0.7874 -0.4064)
			(end 0.7874 -0.4064)
			(stroke
				(width 0.1524)
				(type default)
			)
			(layer "F.SilkS")
		)
		(fp_line
			(start 0.7874 -0.4064)
			(end 0.7874 0.4064)
			(stroke
				(width 0.1524)
				(type default)
			)
			(layer "F.SilkS")
		)
		(fp_line
			(start -0.67945 0.3048)
			(end -0.67945 -0.305054)
			(stroke
				(width 0.1)
				(type default)
			)
			(layer "F.Fab")
		)
		(fp_line
			(start -0.12065 0.3048)
			(end -0.67945 0.3048)
			(stroke
				(width 0.1)
				(type default)
			)
			(layer "F.Fab")
		)
		(fp_line
			(start 0.120396 0.3048)
			(end 0.120396 0.2794)
			(stroke
				(width 0.1)
				(type default)
			)
			(layer "F.Fab")
		)
		(fp_line
			(start 0.67945 0.3048)
			(end 0.120396 0.3048)
			(stroke
				(width 0.1)
				(type default)
			)
			(layer "F.Fab")
		)
		(fp_line
			(start -0.12065 0.2794)
			(end -0.12065 0.3048)
			(stroke
				(width 0.1)
				(type default)
			)
			(layer "F.Fab")
		)
		(fp_line
			(start 0.120396 0.2794)
			(end -0.12065 0.2794)
			(stroke
				(width 0.1)
				(type default)
			)
			(layer "F.Fab")
		)
		(fp_line
			(start -0.12065 -0.2794)
			(end 0.12065 -0.2794)
			(stroke
				(width 0.1)
				(type default)
			)
			(layer "F.Fab")
		)
		(fp_line
			(start 0.12065 -0.2794)
			(end 0.12065 -0.3048)
			(stroke
				(width 0.1)
				(type default)
			)
			(layer "F.Fab")
		)
		(fp_line
			(start 0.12065 -0.3048)
			(end 0.67945 -0.3048)
			(stroke
				(width 0.1)
				(type default)
			)
			(layer "F.Fab")
		)
		(fp_line
			(start 0.67945 -0.3048)
			(end 0.67945 0.3048)
			(stroke
				(width 0.1)
				(type default)
			)
			(layer "F.Fab")
		)
		(fp_line
			(start -0.67945 -0.305054)
			(end -0.12065 -0.305054)
			(stroke
				(width 0.1)
				(type default)
			)
			(layer "F.Fab")
		)
		(fp_line
			(start -0.12065 -0.305054)
			(end -0.12065 -0.2794)
			(stroke
				(width 0.1)
				(type default)
			)
			(layer "F.Fab")
		)
		(pad "1" smd circle
			(at -0.40005 0 270)
			(size 0 0)
			(layers "F.Cu" "F.Mask" "F.Paste")
			(net "USB_HUB_XTAL_OUT")
		)
		(pad "2" smd circle
			(at 0.40005 0 270)
			(size 0 0)
			(layers "F.Cu" "F.Mask" "F.Paste")
			(net "GND")
		)
	)
	(footprint ""
		(layer "F.Cu")
		(at 442.077602 -429.37811 -90)
		(property "Reference" "R646"
			(at 0 0 270)
			(layer "F.SilkS")
			(hide yes)
			(effects
				(font
					(size 1.27 1.27)
				)
			)
		)
		(property "Value" ""
			(at 0 0 270)
			(layer "F.Fab")
			(effects
				(font
					(size 1.27 1.27)
				)
			)
		)
		(duplicate_pad_numbers_are_jumpers no)
		(fp_line
			(start -0.7874 0.4064)
			(end -0.7874 -0.4064)
			(stroke
				(width 0.1524)
				(type default)
			)
			(layer "F.SilkS")
		)
		(fp_line
			(start 0.7874 0.4064)
			(end -0.7874 0.4064)
			(stroke
				(width 0.1524)
				(type default)
			)
			(layer "F.SilkS")
		)
		(fp_line
			(start -0.7874 -0.4064)
			(end 0.7874 -0.4064)
			(stroke
				(width 0.1524)
				(type default)
			)
			(layer "F.SilkS")
		)
		(fp_line
			(start 0.7874 -0.4064)
			(end 0.7874 0.4064)
			(stroke
				(width 0.1524)
				(type default)
			)
			(layer "F.SilkS")
		)
		(fp_line
			(start -0.67945 0.3048)
			(end -0.67945 -0.305054)
			(stroke
				(width 0.1)
				(type default)
			)
			(layer "F.Fab")
		)
		(fp_line
			(start -0.12065 0.3048)
			(end -0.67945 0.3048)
			(stroke
				(width 0.1)
				(type default)
			)
			(layer "F.Fab")
		)
		(fp_line
			(start 0.120396 0.3048)
			(end 0.120396 0.2794)
			(stroke
				(width 0.1)
				(type default)
			)
			(layer "F.Fab")
		)
		(fp_line
			(start 0.67945 0.3048)
			(end 0.120396 0.3048)
			(stroke
				(width 0.1)
				(type default)
			)
			(layer "F.Fab")
		)
		(fp_line
			(start -0.12065 0.2794)
			(end -0.12065 0.3048)
			(stroke
				(width 0.1)
				(type default)
			)
			(layer "F.Fab")
		)
		(fp_line
			(start 0.120396 0.2794)
			(end -0.12065 0.2794)
			(stroke
				(width 0.1)
				(type default)
			)
			(layer "F.Fab")
		)
		(fp_line
			(start -0.12065 -0.2794)
			(end 0.12065 -0.2794)
			(stroke
				(width 0.1)
				(type default)
			)
			(layer "F.Fab")
		)
		(fp_line
			(start 0.12065 -0.2794)
			(end 0.12065 -0.3048)
			(stroke
				(width 0.1)
				(type default)
			)
			(layer "F.Fab")
		)
		(fp_line
			(start 0.12065 -0.3048)
			(end 0.67945 -0.3048)
			(stroke
				(width 0.1)
				(type default)
			)
			(layer "F.Fab")
		)
		(fp_line
			(start 0.67945 -0.3048)
			(end 0.67945 0.3048)
			(stroke
				(width 0.1)
				(type default)
			)
			(layer "F.Fab")
		)
		(fp_line
			(start -0.67945 -0.305054)
			(end -0.12065 -0.305054)
			(stroke
				(width 0.1)
				(type default)
			)
			(layer "F.Fab")
		)
		(fp_line
			(start -0.12065 -0.305054)
			(end -0.12065 -0.2794)
			(stroke
				(width 0.1)
				(type default)
			)
			(layer "F.Fab")
		)
		(pad "1" smd circle
			(at -0.40005 0 270)
			(size 0 0)
			(layers "F.Cu" "F.Mask" "F.Paste")
			(net "P0V9_RETIMER_CPU0_PMSCL")
		)
		(pad "2" smd circle
			(at 0.40005 0 270)
			(size 0 0)
			(layers "F.Cu" "F.Mask" "F.Paste")
			(net "P0V9_RETIMER_CPU0_PMSCL_R")
		)
	)
	(footprint ""
		(layer "F.Cu")
		(at 390.713722 -177.532284)
		(property "Reference" "PR347"
			(at 0 0 0)
			(layer "F.SilkS")
			(hide yes)
			(effects
				(font
					(size 1.27 1.27)
				)
			)
		)
		(property "Value" ""
			(at 0 0 0)
			(layer "F.Fab")
			(effects
				(font
					(size 1.27 1.27)
				)
			)
		)
		(duplicate_pad_numbers_are_jumpers no)
		(fp_line
			(start -0.7874 -0.4064)
			(end 0.7874 -0.4064)
			(stroke
				(width 0.1524)
				(type default)
			)
			(layer "F.SilkS")
		)
		(fp_line
			(start -0.7874 0.4064)
			(end -0.7874 -0.4064)
			(stroke
				(width 0.1524)
				(type default)
			)
			(layer "F.SilkS")
		)
		(fp_line
			(start 0.7874 -0.4064)
			(end 0.7874 0.4064)
			(stroke
				(width 0.1524)
				(type default)
			)
			(layer "F.SilkS")
		)
		(fp_line
			(start 0.7874 0.4064)
			(end -0.7874 0.4064)
			(stroke
				(width 0.1524)
				(type default)
			)
			(layer "F.SilkS")
		)
		(fp_line
			(start -0.67945 -0.305054)
			(end -0.12065 -0.305054)
			(stroke
				(width 0.1)
				(type default)
			)
			(layer "F.Fab")
		)
		(fp_line
			(start -0.67945 0.3048)
			(end -0.67945 -0.305054)
			(stroke
				(width 0.1)
				(type default)
			)
			(layer "F.Fab")
		)
		(fp_line
			(start -0.12065 -0.305054)
			(end -0.12065 -0.2794)
			(stroke
				(width 0.1)
				(type default)
			)
			(layer "F.Fab")
		)
		(fp_line
			(start -0.12065 -0.2794)
			(end 0.12065 -0.2794)
			(stroke
				(width 0.1)
				(type default)
			)
			(layer "F.Fab")
		)
		(fp_line
			(start -0.12065 0.2794)
			(end -0.12065 0.3048)
			(stroke
				(width 0.1)
				(type default)
			)
			(layer "F.Fab")
		)
		(fp_line
			(start -0.12065 0.3048)
			(end -0.67945 0.3048)
			(stroke
				(width 0.1)
				(type default)
			)
			(layer "F.Fab")
		)
		(fp_line
			(start 0.120396 0.2794)
			(end -0.12065 0.2794)
			(stroke
				(width 0.1)
				(type default)
			)
			(layer "F.Fab")
		)
		(fp_line
			(start 0.120396 0.3048)
			(end 0.120396 0.2794)
			(stroke
				(width 0.1)
				(type default)
			)
			(layer "F.Fab")
		)
		(fp_line
			(start 0.12065 -0.3048)
			(end 0.67945 -0.3048)
			(stroke
				(width 0.1)
				(type default)
			)
			(layer "F.Fab")
		)
		(fp_line
			(start 0.12065 -0.2794)
			(end 0.12065 -0.3048)
			(stroke
				(width 0.1)
				(type default)
			)
			(layer "F.Fab")
		)
		(fp_line
			(start 0.67945 -0.3048)
			(end 0.67945 0.3048)
			(stroke
				(width 0.1)
				(type default)
			)
			(layer "F.Fab")
		)
		(fp_line
			(start 0.67945 0.3048)
			(end 0.120396 0.3048)
			(stroke
				(width 0.1)
				(type default)
			)
			(layer "F.Fab")
		)
		(pad "1" smd circle
			(at -0.40005 0)
			(size 0 0)
			(layers "F.Cu" "F.Mask" "F.Paste")
			(net "GND")
		)
		(pad "2" smd circle
			(at 0.40005 0)
			(size 0 0)
			(layers "F.Cu" "F.Mask" "F.Paste")
			(net "PVDDCR_CPU0_P0_LSET4")
		)
	)
	(footprint ""
		(layer "F.Cu")
		(at 27.598878 -16.099536 90)
		(property "Reference" "C687"
			(at 0 0 90)
			(layer "F.SilkS")
			(hide yes)
			(effects
				(font
					(size 1.27 1.27)
				)
			)
		)
		(property "Value" ""
			(at 0 0 90)
			(layer "F.Fab")
			(effects
				(font
					(size 1.27 1.27)
				)
			)
		)
		(duplicate_pad_numbers_are_jumpers no)
		(fp_line
			(start 0.299974 -0.150114)
			(end 0.299974 0.150114)
			(stroke
				(width 0.1)
				(type default)
			)
			(layer "F.Fab")
		)
		(fp_line
			(start -0.299974 -0.150114)
			(end 0.299974 -0.150114)
			(stroke
				(width 0.1)
				(type default)
			)
			(layer "F.Fab")
		)
		(fp_line
			(start 0.299974 0.150114)
			(end -0.299974 0.150114)
			(stroke
				(width 0.1)
				(type default)
			)
			(layer "F.Fab")
		)
		(fp_line
			(start -0.299974 0.150114)
			(end -0.299974 -0.150114)
			(stroke
				(width 0.1)
				(type default)
			)
			(layer "F.Fab")
		)
		(pad "1" smd rect
			(at -0.2667 0 90)
			(size 0.3048 0.381)
			(layers "F.Cu" "F.Mask" "F.Paste")
			(net "P5E_CPU1_G1_TX_C_DP<11>")
		)
		(pad "2" smd rect
			(at 0.2667 0 90)
			(size 0.3048 0.381)
			(layers "F.Cu" "F.Mask" "F.Paste")
			(net "P5E_CPU1_G1_TX_DP<11>")
		)
	)
	(footprint ""
		(layer "F.Cu")
		(at 265.201908 -418.13607)
		(property "Reference" "R4901"
			(at 0 0 0)
			(layer "F.SilkS")
			(hide yes)
			(effects
				(font
					(size 1.27 1.27)
				)
			)
		)
		(property "Value" ""
			(at 0 0 0)
			(layer "F.Fab")
			(effects
				(font
					(size 1.27 1.27)
				)
			)
		)
		(duplicate_pad_numbers_are_jumpers no)
		(fp_line
			(start -0.7874 -0.4064)
			(end 0.7874 -0.4064)
			(stroke
				(width 0.1524)
				(type default)
			)
			(layer "F.SilkS")
		)
		(fp_line
			(start -0.7874 0.4064)
			(end -0.7874 -0.4064)
			(stroke
				(width 0.1524)
				(type default)
			)
			(layer "F.SilkS")
		)
		(fp_line
			(start 0.7874 -0.4064)
			(end 0.7874 0.4064)
			(stroke
				(width 0.1524)
				(type default)
			)
			(layer "F.SilkS")
		)
		(fp_line
			(start 0.7874 0.4064)
			(end -0.7874 0.4064)
			(stroke
				(width 0.1524)
				(type default)
			)
			(layer "F.SilkS")
		)
		(fp_line
			(start -0.67945 -0.305054)
			(end -0.12065 -0.305054)
			(stroke
				(width 0.1)
				(type default)
			)
			(layer "F.Fab")
		)
		(fp_line
			(start -0.67945 0.3048)
			(end -0.67945 -0.305054)
			(stroke
				(width 0.1)
				(type default)
			)
			(layer "F.Fab")
		)
		(fp_line
			(start -0.12065 -0.305054)
			(end -0.12065 -0.2794)
			(stroke
				(width 0.1)
				(type default)
			)
			(layer "F.Fab")
		)
		(fp_line
			(start -0.12065 -0.2794)
			(end 0.12065 -0.2794)
			(stroke
				(width 0.1)
				(type default)
			)
			(layer "F.Fab")
		)
		(fp_line
			(start -0.12065 0.2794)
			(end -0.12065 0.3048)
			(stroke
				(width 0.1)
				(type default)
			)
			(layer "F.Fab")
		)
		(fp_line
			(start -0.12065 0.3048)
			(end -0.67945 0.3048)
			(stroke
				(width 0.1)
				(type default)
			)
			(layer "F.Fab")
		)
		(fp_line
			(start 0.120396 0.2794)
			(end -0.12065 0.2794)
			(stroke
				(width 0.1)
				(type default)
			)
			(layer "F.Fab")
		)
		(fp_line
			(start 0.120396 0.3048)
			(end 0.120396 0.2794)
			(stroke
				(width 0.1)
				(type default)
			)
			(layer "F.Fab")
		)
		(fp_line
			(start 0.12065 -0.3048)
			(end 0.67945 -0.3048)
			(stroke
				(width 0.1)
				(type default)
			)
			(layer "F.Fab")
		)
		(fp_line
			(start 0.12065 -0.2794)
			(end 0.12065 -0.3048)
			(stroke
				(width 0.1)
				(type default)
			)
			(layer "F.Fab")
		)
		(fp_line
			(start 0.67945 -0.3048)
			(end 0.67945 0.3048)
			(stroke
				(width 0.1)
				(type default)
			)
			(layer "F.Fab")
		)
		(fp_line
			(start 0.67945 0.3048)
			(end 0.120396 0.3048)
			(stroke
				(width 0.1)
				(type default)
			)
			(layer "F.Fab")
		)
		(pad "1" smd circle
			(at -0.40005 0)
			(size 0 0)
			(layers "F.Cu" "F.Mask" "F.Paste")
			(net "P12V_PSU_FUSE")
		)
		(pad "2" smd circle
			(at 0.40005 0)
			(size 0 0)
			(layers "F.Cu" "F.Mask" "F.Paste")
			(net "HSC_EN")
		)
	)
	(footprint ""
		(layer "F.Cu")
		(at 227.949252 -290.341812 89.946)
		(property "Reference" "PR6526"
			(at 0 0 89.946)
			(layer "F.SilkS")
			(hide yes)
			(effects
				(font
					(size 1.27 1.27)
				)
			)
		)
		(property "Value" ""
			(at 0 0 89.946)
			(layer "F.Fab")
			(effects
				(font
					(size 1.27 1.27)
				)
			)
		)
		(duplicate_pad_numbers_are_jumpers no)
		(fp_line
			(start -0.787275 -0.40642)
			(end 0.787525 -0.40638)
			(stroke
				(width 0.1524)
				(type default)
			)
			(layer "F.SilkS")
		)
		(fp_line
			(start 0.787525 -0.40638)
			(end 0.787275 0.40642)
			(stroke
				(width 0.1524)
				(type default)
			)
			(layer "F.SilkS")
		)
		(fp_line
			(start -0.787525 0.40638)
			(end -0.787275 -0.40642)
			(stroke
				(width 0.1524)
				(type default)
			)
			(layer "F.SilkS")
		)
		(fp_line
			(start 0.787275 0.40642)
			(end -0.787525 0.40638)
			(stroke
				(width 0.1524)
				(type default)
			)
			(layer "F.SilkS")
		)
		(fp_line
			(start -0.679484 -0.305176)
			(end -0.120683 -0.30494)
			(stroke
				(width 0.1)
				(type default)
			)
			(layer "F.Fab")
		)
		(fp_line
			(start -0.120683 -0.30494)
			(end -0.120659 -0.279286)
			(stroke
				(width 0.1)
				(type default)
			)
			(layer "F.Fab")
		)
		(fp_line
			(start 0.120617 -0.304914)
			(end 0.679417 -0.304678)
			(stroke
				(width 0.1)
				(type default)
			)
			(layer "F.Fab")
		)
		(fp_line
			(start 0.679417 -0.304678)
			(end 0.679484 0.304922)
			(stroke
				(width 0.1)
				(type default)
			)
			(layer "F.Fab")
		)
		(fp_line
			(start 0.120641 -0.279514)
			(end 0.120617 -0.304914)
			(stroke
				(width 0.1)
				(type default)
			)
			(layer "F.Fab")
		)
		(fp_line
			(start -0.120659 -0.279286)
			(end 0.120641 -0.279514)
			(stroke
				(width 0.1)
				(type default)
			)
			(layer "F.Fab")
		)
		(fp_line
			(start 0.120405 0.279287)
			(end -0.120641 0.279514)
			(stroke
				(width 0.1)
				(type default)
			)
			(layer "F.Fab")
		)
		(fp_line
			(start -0.120641 0.279514)
			(end -0.120617 0.304914)
			(stroke
				(width 0.1)
				(type default)
			)
			(layer "F.Fab")
		)
		(fp_line
			(start -0.679417 0.304678)
			(end -0.679484 -0.305176)
			(stroke
				(width 0.1)
				(type default)
			)
			(layer "F.Fab")
		)
		(fp_line
			(start 0.120429 0.304687)
			(end 0.120405 0.279287)
			(stroke
				(width 0.1)
				(type default)
			)
			(layer "F.Fab")
		)
		(fp_line
			(start -0.120617 0.304914)
			(end -0.679417 0.304678)
			(stroke
				(width 0.1)
				(type default)
			)
			(layer "F.Fab")
		)
		(fp_line
			(start 0.679484 0.304922)
			(end 0.120429 0.304687)
			(stroke
				(width 0.1)
				(type default)
			)
			(layer "F.Fab")
		)
		(pad "1" smd circle
			(at -0.40005 0 89.946)
			(size 0 0)
			(layers "F.Cu" "F.Mask" "F.Paste")
			(net "P1V8_RETIMER_CPU1_FB")
		)
		(pad "2" smd circle
			(at 0.40005 0 89.946)
			(size 0 0)
			(layers "F.Cu" "F.Mask" "F.Paste")
			(net "GND")
		)
	)
	(footprint ""
		(layer "F.Cu")
		(at 26.226516 -39.037514)
		(property "Reference" "C1106"
			(at 0 0 0)
			(layer "F.SilkS")
			(hide yes)
			(effects
				(font
					(size 1.27 1.27)
				)
			)
		)
		(property "Value" ""
			(at 0 0 0)
			(layer "F.Fab")
			(effects
				(font
					(size 1.27 1.27)
				)
			)
		)
		(duplicate_pad_numbers_are_jumpers no)
		(fp_line
			(start -0.7874 -0.4064)
			(end 0.7874 -0.4064)
			(stroke
				(width 0.1524)
				(type default)
			)
			(layer "F.SilkS")
		)
		(fp_line
			(start -0.7874 0.4064)
			(end -0.7874 -0.4064)
			(stroke
				(width 0.1524)
				(type default)
			)
			(layer "F.SilkS")
		)
		(fp_line
			(start 0.7874 -0.4064)
			(end 0.7874 0.4064)
			(stroke
				(width 0.1524)
				(type default)
			)
			(layer "F.SilkS")
		)
		(fp_line
			(start 0.7874 0.4064)
			(end -0.7874 0.4064)
			(stroke
				(width 0.1524)
				(type default)
			)
			(layer "F.SilkS")
		)
		(fp_line
			(start -0.67945 -0.305054)
			(end -0.12065 -0.305054)
			(stroke
				(width 0.1)
				(type default)
			)
			(layer "F.Fab")
		)
		(fp_line
			(start -0.67945 0.3048)
			(end -0.67945 -0.305054)
			(stroke
				(width 0.1)
				(type default)
			)
			(layer "F.Fab")
		)
		(fp_line
			(start -0.12065 -0.305054)
			(end -0.12065 -0.2794)
			(stroke
				(width 0.1)
				(type default)
			)
			(layer "F.Fab")
		)
		(fp_line
			(start -0.12065 -0.2794)
			(end 0.12065 -0.2794)
			(stroke
				(width 0.1)
				(type default)
			)
			(layer "F.Fab")
		)
		(fp_line
			(start -0.12065 0.2794)
			(end -0.12065 0.3048)
			(stroke
				(width 0.1)
				(type default)
			)
			(layer "F.Fab")
		)
		(fp_line
			(start -0.12065 0.3048)
			(end -0.67945 0.3048)
			(stroke
				(width 0.1)
				(type default)
			)
			(layer "F.Fab")
		)
		(fp_line
			(start 0.120396 0.2794)
			(end -0.12065 0.2794)
			(stroke
				(width 0.1)
				(type default)
			)
			(layer "F.Fab")
		)
		(fp_line
			(start 0.120396 0.3048)
			(end 0.120396 0.2794)
			(stroke
				(width 0.1)
				(type default)
			)
			(layer "F.Fab")
		)
		(fp_line
			(start 0.12065 -0.3048)
			(end 0.67945 -0.3048)
			(stroke
				(width 0.1)
				(type default)
			)
			(layer "F.Fab")
		)
		(fp_line
			(start 0.12065 -0.2794)
			(end 0.12065 -0.3048)
			(stroke
				(width 0.1)
				(type default)
			)
			(layer "F.Fab")
		)
		(fp_line
			(start 0.67945 -0.3048)
			(end 0.67945 0.3048)
			(stroke
				(width 0.1)
				(type default)
			)
			(layer "F.Fab")
		)
		(fp_line
			(start 0.67945 0.3048)
			(end 0.120396 0.3048)
			(stroke
				(width 0.1)
				(type default)
			)
			(layer "F.Fab")
		)
		(pad "1" smd circle
			(at -0.40005 0)
			(size 0 0)
			(layers "F.Cu" "F.Mask" "F.Paste")
			(net "P3V3_AUX")
		)
		(pad "2" smd circle
			(at 0.40005 0)
			(size 0 0)
			(layers "F.Cu" "F.Mask" "F.Paste")
			(net "GND")
		)
	)
	(footprint ""
		(layer "F.Cu")
		(at 370.889276 -178.0921 90)
		(property "Reference" "PC490"
			(at 0 0 90)
			(layer "F.SilkS")
			(hide yes)
			(effects
				(font
					(size 1.27 1.27)
				)
			)
		)
		(property "Value" ""
			(at 0 0 90)
			(layer "F.Fab")
			(effects
				(font
					(size 1.27 1.27)
				)
			)
		)
		(duplicate_pad_numbers_are_jumpers no)
		(fp_line
			(start 0.7874 -0.4064)
			(end 0.7874 0.4064)
			(stroke
				(width 0.1524)
				(type default)
			)
			(layer "F.SilkS")
		)
		(fp_line
			(start -0.7874 -0.4064)
			(end 0.7874 -0.4064)
			(stroke
				(width 0.1524)
				(type default)
			)
			(layer "F.SilkS")
		)
		(fp_line
			(start 0.7874 0.4064)
			(end -0.7874 0.4064)
			(stroke
				(width 0.1524)
				(type default)
			)
			(layer "F.SilkS")
		)
		(fp_line
			(start -0.7874 0.4064)
			(end -0.7874 -0.4064)
			(stroke
				(width 0.1524)
				(type default)
			)
			(layer "F.SilkS")
		)
		(fp_line
			(start -0.12065 -0.305054)
			(end -0.12065 -0.2794)
			(stroke
				(width 0.1)
				(type default)
			)
			(layer "F.Fab")
		)
		(fp_line
			(start -0.67945 -0.305054)
			(end -0.12065 -0.305054)
			(stroke
				(width 0.1)
				(type default)
			)
			(layer "F.Fab")
		)
		(fp_line
			(start 0.67945 -0.3048)
			(end 0.67945 0.3048)
			(stroke
				(width 0.1)
				(type default)
			)
			(layer "F.Fab")
		)
		(fp_line
			(start 0.12065 -0.3048)
			(end 0.67945 -0.3048)
			(stroke
				(width 0.1)
				(type default)
			)
			(layer "F.Fab")
		)
		(fp_line
			(start 0.12065 -0.2794)
			(end 0.12065 -0.3048)
			(stroke
				(width 0.1)
				(type default)
			)
			(layer "F.Fab")
		)
		(fp_line
			(start -0.12065 -0.2794)
			(end 0.12065 -0.2794)
			(stroke
				(width 0.1)
				(type default)
			)
			(layer "F.Fab")
		)
		(fp_line
			(start 0.120396 0.2794)
			(end -0.12065 0.2794)
			(stroke
				(width 0.1)
				(type default)
			)
			(layer "F.Fab")
		)
		(fp_line
			(start -0.12065 0.2794)
			(end -0.12065 0.3048)
			(stroke
				(width 0.1)
				(type default)
			)
			(layer "F.Fab")
		)
		(fp_line
			(start 0.67945 0.3048)
			(end 0.120396 0.3048)
			(stroke
				(width 0.1)
				(type default)
			)
			(layer "F.Fab")
		)
		(fp_line
			(start 0.120396 0.3048)
			(end 0.120396 0.2794)
			(stroke
				(width 0.1)
				(type default)
			)
			(layer "F.Fab")
		)
		(fp_line
			(start -0.12065 0.3048)
			(end -0.67945 0.3048)
			(stroke
				(width 0.1)
				(type default)
			)
			(layer "F.Fab")
		)
		(fp_line
			(start -0.67945 0.3048)
			(end -0.67945 -0.305054)
			(stroke
				(width 0.1)
				(type default)
			)
			(layer "F.Fab")
		)
		(pad "1" smd circle
			(at -0.40005 0 90)
			(size 0 0)
			(layers "F.Cu" "F.Mask" "F.Paste")
			(net "SW_PVDDCR_CPU0_P0_BOOT2_RC")
		)
		(pad "2" smd circle
			(at 0.40005 0 90)
			(size 0 0)
			(layers "F.Cu" "F.Mask" "F.Paste")
			(net "SW_PVDDCR_CPU0_P0_PH2")
		)
	)
	(footprint ""
		(layer "F.Cu")
		(at 83.621626 -58.452004 90)
		(property "Reference" "R3633"
			(at -4.884674 -1.833626 0)
			(unlocked yes)
			(layer "F.SilkS")
			(effects
				(font
					(size 0.7874 0.5842)
					(thickness 0.1524)
				)
				(justify left)
			)
		)
		(property "Value" ""
			(at 0 0 90)
			(layer "F.Fab")
			(effects
				(font
					(size 1.27 1.27)
				)
			)
		)
		(duplicate_pad_numbers_are_jumpers no)
		(fp_line
			(start 3.937508 -1.8796)
			(end -3.937508 -1.8796)
			(stroke
				(width 0.1524)
				(type default)
			)
			(layer "F.SilkS")
		)
		(fp_line
			(start -3.937508 -1.8796)
			(end -3.937508 1.8796)
			(stroke
				(width 0.1524)
				(type default)
			)
			(layer "F.SilkS")
		)
		(fp_line
			(start 3.937508 1.8796)
			(end 3.937508 -1.8796)
			(stroke
				(width 0.1524)
				(type default)
			)
			(layer "F.SilkS")
		)
		(fp_line
			(start -3.937508 1.8796)
			(end 3.937508 1.8796)
			(stroke
				(width 0.1524)
				(type default)
			)
			(layer "F.SilkS")
		)
		(fp_line
			(start 3.275076 -1.674876)
			(end -3.275076 -1.674876)
			(stroke
				(width 0.1)
				(type default)
			)
			(layer "F.Fab")
		)
		(fp_line
			(start -3.275076 -1.674876)
			(end -3.275076 1.674876)
			(stroke
				(width 0.1)
				(type default)
			)
			(layer "F.Fab")
		)
		(fp_line
			(start 3.275076 1.674876)
			(end 3.275076 -1.674876)
			(stroke
				(width 0.1)
				(type default)
			)
			(layer "F.Fab")
		)
		(fp_line
			(start -3.275076 1.674876)
			(end 3.275076 1.674876)
			(stroke
				(width 0.1)
				(type default)
			)
			(layer "F.Fab")
		)
		(pad "1" smd rect
			(at -2.350008 0 90)
			(size 2.921 3.5052)
			(layers "F.Cu" "F.Mask" "F.Paste")
			(net "P3V3_OCP_V3_2")
		)
		(pad "2" smd rect
			(at 2.350008 0 90)
			(size 2.921 3.5052)
			(layers "F.Cu" "F.Mask" "F.Paste")
			(net "P3V3_OCP_V3_2_R")
		)
	)
	(footprint ""
		(layer "F.Cu")
		(at 287.87217 -351.100644)
		(property "Reference" "PC149_2"
			(at 0 0 0)
			(layer "F.SilkS")
			(hide yes)
			(effects
				(font
					(size 1.27 1.27)
				)
			)
		)
		(property "Value" ""
			(at 0 0 0)
			(layer "F.Fab")
			(effects
				(font
					(size 1.27 1.27)
				)
			)
		)
		(duplicate_pad_numbers_are_jumpers no)
		(fp_line
			(start -0.7874 -0.4064)
			(end 0.7874 -0.4064)
			(stroke
				(width 0.1524)
				(type default)
			)
			(layer "F.SilkS")
		)
		(fp_line
			(start -0.7874 0.4064)
			(end -0.7874 -0.4064)
			(stroke
				(width 0.1524)
				(type default)
			)
			(layer "F.SilkS")
		)
		(fp_line
			(start 0.7874 -0.4064)
			(end 0.7874 0.4064)
			(stroke
				(width 0.1524)
				(type default)
			)
			(layer "F.SilkS")
		)
		(fp_line
			(start 0.7874 0.4064)
			(end -0.7874 0.4064)
			(stroke
				(width 0.1524)
				(type default)
			)
			(layer "F.SilkS")
		)
		(fp_line
			(start -0.67945 -0.305054)
			(end -0.12065 -0.305054)
			(stroke
				(width 0.1)
				(type default)
			)
			(layer "F.Fab")
		)
		(fp_line
			(start -0.67945 0.3048)
			(end -0.67945 -0.305054)
			(stroke
				(width 0.1)
				(type default)
			)
			(layer "F.Fab")
		)
		(fp_line
			(start -0.12065 -0.305054)
			(end -0.12065 -0.2794)
			(stroke
				(width 0.1)
				(type default)
			)
			(layer "F.Fab")
		)
		(fp_line
			(start -0.12065 -0.2794)
			(end 0.12065 -0.2794)
			(stroke
				(width 0.1)
				(type default)
			)
			(layer "F.Fab")
		)
		(fp_line
			(start -0.12065 0.2794)
			(end -0.12065 0.3048)
			(stroke
				(width 0.1)
				(type default)
			)
			(layer "F.Fab")
		)
		(fp_line
			(start -0.12065 0.3048)
			(end -0.67945 0.3048)
			(stroke
				(width 0.1)
				(type default)
			)
			(layer "F.Fab")
		)
		(fp_line
			(start 0.120396 0.2794)
			(end -0.12065 0.2794)
			(stroke
				(width 0.1)
				(type default)
			)
			(layer "F.Fab")
		)
		(fp_line
			(start 0.120396 0.3048)
			(end 0.120396 0.2794)
			(stroke
				(width 0.1)
				(type default)
			)
			(layer "F.Fab")
		)
		(fp_line
			(start 0.12065 -0.3048)
			(end 0.67945 -0.3048)
			(stroke
				(width 0.1)
				(type default)
			)
			(layer "F.Fab")
		)
		(fp_line
			(start 0.12065 -0.2794)
			(end 0.12065 -0.3048)
			(stroke
				(width 0.1)
				(type default)
			)
			(layer "F.Fab")
		)
		(fp_line
			(start 0.67945 -0.3048)
			(end 0.67945 0.3048)
			(stroke
				(width 0.1)
				(type default)
			)
			(layer "F.Fab")
		)
		(fp_line
			(start 0.67945 0.3048)
			(end 0.120396 0.3048)
			(stroke
				(width 0.1)
				(type default)
			)
			(layer "F.Fab")
		)
		(pad "1" smd circle
			(at -0.40005 0)
			(size 0 0)
			(layers "F.Cu" "F.Mask" "F.Paste")
			(net "SW_P12V_AUX_PVDDIO_P0_FLT")
		)
		(pad "2" smd circle
			(at 0.40005 0)
			(size 0 0)
			(layers "F.Cu" "F.Mask" "F.Paste")
			(net "GND")
		)
	)
	(footprint ""
		(layer "F.Cu")
		(at 386.211826 -57.2135 180)
		(property "Reference" "R1627"
			(at 0 0 180)
			(layer "F.SilkS")
			(hide yes)
			(effects
				(font
					(size 1.27 1.27)
				)
			)
		)
		(property "Value" ""
			(at 0 0 180)
			(layer "F.Fab")
			(effects
				(font
					(size 1.27 1.27)
				)
			)
		)
		(duplicate_pad_numbers_are_jumpers no)
		(fp_line
			(start 0.7874 0.4064)
			(end -0.7874 0.4064)
			(stroke
				(width 0.1524)
				(type default)
			)
			(layer "F.SilkS")
		)
		(fp_line
			(start 0.7874 -0.4064)
			(end 0.7874 0.4064)
			(stroke
				(width 0.1524)
				(type default)
			)
			(layer "F.SilkS")
		)
		(fp_line
			(start -0.7874 0.4064)
			(end -0.7874 -0.4064)
			(stroke
				(width 0.1524)
				(type default)
			)
			(layer "F.SilkS")
		)
		(fp_line
			(start -0.7874 -0.4064)
			(end 0.7874 -0.4064)
			(stroke
				(width 0.1524)
				(type default)
			)
			(layer "F.SilkS")
		)
		(fp_line
			(start 0.67945 0.3048)
			(end 0.120396 0.3048)
			(stroke
				(width 0.1)
				(type default)
			)
			(layer "F.Fab")
		)
		(fp_line
			(start 0.67945 -0.3048)
			(end 0.67945 0.3048)
			(stroke
				(width 0.1)
				(type default)
			)
			(layer "F.Fab")
		)
		(fp_line
			(start 0.12065 -0.2794)
			(end 0.12065 -0.3048)
			(stroke
				(width 0.1)
				(type default)
			)
			(layer "F.Fab")
		)
		(fp_line
			(start 0.12065 -0.3048)
			(end 0.67945 -0.3048)
			(stroke
				(width 0.1)
				(type default)
			)
			(layer "F.Fab")
		)
		(fp_line
			(start 0.120396 0.3048)
			(end 0.120396 0.2794)
			(stroke
				(width 0.1)
				(type default)
			)
			(layer "F.Fab")
		)
		(fp_line
			(start 0.120396 0.2794)
			(end -0.12065 0.2794)
			(stroke
				(width 0.1)
				(type default)
			)
			(layer "F.Fab")
		)
		(fp_line
			(start -0.12065 0.3048)
			(end -0.67945 0.3048)
			(stroke
				(width 0.1)
				(type default)
			)
			(layer "F.Fab")
		)
		(fp_line
			(start -0.12065 0.2794)
			(end -0.12065 0.3048)
			(stroke
				(width 0.1)
				(type default)
			)
			(layer "F.Fab")
		)
		(fp_line
			(start -0.12065 -0.2794)
			(end 0.12065 -0.2794)
			(stroke
				(width 0.1)
				(type default)
			)
			(layer "F.Fab")
		)
		(fp_line
			(start -0.12065 -0.305054)
			(end -0.12065 -0.2794)
			(stroke
				(width 0.1)
				(type default)
			)
			(layer "F.Fab")
		)
		(fp_line
			(start -0.67945 0.3048)
			(end -0.67945 -0.305054)
			(stroke
				(width 0.1)
				(type default)
			)
			(layer "F.Fab")
		)
		(fp_line
			(start -0.67945 -0.305054)
			(end -0.12065 -0.305054)
			(stroke
				(width 0.1)
				(type default)
			)
			(layer "F.Fab")
		)
		(pad "1" smd circle
			(at -0.40005 0 180)
			(size 0 0)
			(layers "F.Cu" "F.Mask" "F.Paste")
			(net "PVDD18_S5_P0")
		)
		(pad "2" smd circle
			(at 0.40005 0 180)
			(size 0 0)
			(layers "F.Cu" "F.Mask" "F.Paste")
			(net "HDT_HDR_TDI")
		)
	)
	(footprint ""
		(layer "F.Cu")
		(at 104.267 -415.798)
		(property "Reference" "R578"
			(at 0 0 0)
			(layer "F.SilkS")
			(hide yes)
			(effects
				(font
					(size 1.27 1.27)
				)
			)
		)
		(property "Value" ""
			(at 0 0 0)
			(layer "F.Fab")
			(effects
				(font
					(size 1.27 1.27)
				)
			)
		)
		(duplicate_pad_numbers_are_jumpers no)
		(fp_line
			(start -0.7874 -0.4064)
			(end 0.7874 -0.4064)
			(stroke
				(width 0.1524)
				(type default)
			)
			(layer "F.SilkS")
		)
		(fp_line
			(start -0.7874 0.4064)
			(end -0.7874 -0.4064)
			(stroke
				(width 0.1524)
				(type default)
			)
			(layer "F.SilkS")
		)
		(fp_line
			(start 0.7874 -0.4064)
			(end 0.7874 0.4064)
			(stroke
				(width 0.1524)
				(type default)
			)
			(layer "F.SilkS")
		)
		(fp_line
			(start 0.7874 0.4064)
			(end -0.7874 0.4064)
			(stroke
				(width 0.1524)
				(type default)
			)
			(layer "F.SilkS")
		)
		(fp_line
			(start -0.67945 -0.305054)
			(end -0.12065 -0.305054)
			(stroke
				(width 0.1)
				(type default)
			)
			(layer "F.Fab")
		)
		(fp_line
			(start -0.67945 0.3048)
			(end -0.67945 -0.305054)
			(stroke
				(width 0.1)
				(type default)
			)
			(layer "F.Fab")
		)
		(fp_line
			(start -0.12065 -0.305054)
			(end -0.12065 -0.2794)
			(stroke
				(width 0.1)
				(type default)
			)
			(layer "F.Fab")
		)
		(fp_line
			(start -0.12065 -0.2794)
			(end 0.12065 -0.2794)
			(stroke
				(width 0.1)
				(type default)
			)
			(layer "F.Fab")
		)
		(fp_line
			(start -0.12065 0.2794)
			(end -0.12065 0.3048)
			(stroke
				(width 0.1)
				(type default)
			)
			(layer "F.Fab")
		)
		(fp_line
			(start -0.12065 0.3048)
			(end -0.67945 0.3048)
			(stroke
				(width 0.1)
				(type default)
			)
			(layer "F.Fab")
		)
		(fp_line
			(start 0.120396 0.2794)
			(end -0.12065 0.2794)
			(stroke
				(width 0.1)
				(type default)
			)
			(layer "F.Fab")
		)
		(fp_line
			(start 0.120396 0.3048)
			(end 0.120396 0.2794)
			(stroke
				(width 0.1)
				(type default)
			)
			(layer "F.Fab")
		)
		(fp_line
			(start 0.12065 -0.3048)
			(end 0.67945 -0.3048)
			(stroke
				(width 0.1)
				(type default)
			)
			(layer "F.Fab")
		)
		(fp_line
			(start 0.12065 -0.2794)
			(end 0.12065 -0.3048)
			(stroke
				(width 0.1)
				(type default)
			)
			(layer "F.Fab")
		)
		(fp_line
			(start 0.67945 -0.3048)
			(end 0.67945 0.3048)
			(stroke
				(width 0.1)
				(type default)
			)
			(layer "F.Fab")
		)
		(fp_line
			(start 0.67945 0.3048)
			(end 0.120396 0.3048)
			(stroke
				(width 0.1)
				(type default)
			)
			(layer "F.Fab")
		)
		(pad "1" smd circle
			(at -0.40005 0)
			(size 0 0)
			(layers "F.Cu" "F.Mask" "F.Paste")
			(net "P3V3_AUX")
		)
		(pad "2" smd circle
			(at 0.40005 0)
			(size 0 0)
			(layers "F.Cu" "F.Mask" "F.Paste")
			(net "CLK_9ZXL045_P1_SADR0")
		)
	)
	(footprint ""
		(layer "F.Cu")
		(at 362.025438 -411.354016)
		(property "Reference" "R9002"
			(at 0 0 0)
			(layer "F.SilkS")
			(hide yes)
			(effects
				(font
					(size 1.27 1.27)
				)
			)
		)
		(property "Value" ""
			(at 0 0 0)
			(layer "F.Fab")
			(effects
				(font
					(size 1.27 1.27)
				)
			)
		)
		(duplicate_pad_numbers_are_jumpers no)
		(fp_line
			(start -0.7874 -0.4064)
			(end 0.7874 -0.4064)
			(stroke
				(width 0.1524)
				(type default)
			)
			(layer "F.SilkS")
		)
		(fp_line
			(start -0.7874 0.4064)
			(end -0.7874 -0.4064)
			(stroke
				(width 0.1524)
				(type default)
			)
			(layer "F.SilkS")
		)
		(fp_line
			(start 0.7874 -0.4064)
			(end 0.7874 0.4064)
			(stroke
				(width 0.1524)
				(type default)
			)
			(layer "F.SilkS")
		)
		(fp_line
			(start 0.7874 0.4064)
			(end -0.7874 0.4064)
			(stroke
				(width 0.1524)
				(type default)
			)
			(layer "F.SilkS")
		)
		(fp_line
			(start -0.67945 -0.305054)
			(end -0.12065 -0.305054)
			(stroke
				(width 0.1)
				(type default)
			)
			(layer "F.Fab")
		)
		(fp_line
			(start -0.67945 0.3048)
			(end -0.67945 -0.305054)
			(stroke
				(width 0.1)
				(type default)
			)
			(layer "F.Fab")
		)
		(fp_line
			(start -0.12065 -0.305054)
			(end -0.12065 -0.2794)
			(stroke
				(width 0.1)
				(type default)
			)
			(layer "F.Fab")
		)
		(fp_line
			(start -0.12065 -0.2794)
			(end 0.12065 -0.2794)
			(stroke
				(width 0.1)
				(type default)
			)
			(layer "F.Fab")
		)
		(fp_line
			(start -0.12065 0.2794)
			(end -0.12065 0.3048)
			(stroke
				(width 0.1)
				(type default)
			)
			(layer "F.Fab")
		)
		(fp_line
			(start -0.12065 0.3048)
			(end -0.67945 0.3048)
			(stroke
				(width 0.1)
				(type default)
			)
			(layer "F.Fab")
		)
		(fp_line
			(start 0.120396 0.2794)
			(end -0.12065 0.2794)
			(stroke
				(width 0.1)
				(type default)
			)
			(layer "F.Fab")
		)
		(fp_line
			(start 0.120396 0.3048)
			(end 0.120396 0.2794)
			(stroke
				(width 0.1)
				(type default)
			)
			(layer "F.Fab")
		)
		(fp_line
			(start 0.12065 -0.3048)
			(end 0.67945 -0.3048)
			(stroke
				(width 0.1)
				(type default)
			)
			(layer "F.Fab")
		)
		(fp_line
			(start 0.12065 -0.2794)
			(end 0.12065 -0.3048)
			(stroke
				(width 0.1)
				(type default)
			)
			(layer "F.Fab")
		)
		(fp_line
			(start 0.67945 -0.3048)
			(end 0.67945 0.3048)
			(stroke
				(width 0.1)
				(type default)
			)
			(layer "F.Fab")
		)
		(fp_line
			(start 0.67945 0.3048)
			(end 0.120396 0.3048)
			(stroke
				(width 0.1)
				(type default)
			)
			(layer "F.Fab")
		)
		(pad "1" smd circle
			(at -0.40005 0)
			(size 0 0)
			(layers "F.Cu" "F.Mask" "F.Paste")
			(net "P3V3_AUX")
		)
		(pad "2" smd circle
			(at 0.40005 0)
			(size 0 0)
			(layers "F.Cu" "F.Mask" "F.Paste")
			(net "PRSNT_CABLE_SWB_B1_N")
		)
	)
	(footprint ""
		(layer "F.Cu")
		(at 359.568242 -406.567386 -90)
		(property "Reference" "R9016"
			(at 0 0 270)
			(layer "F.SilkS")
			(hide yes)
			(effects
				(font
					(size 1.27 1.27)
				)
			)
		)
		(property "Value" ""
			(at 0 0 270)
			(layer "F.Fab")
			(effects
				(font
					(size 1.27 1.27)
				)
			)
		)
		(duplicate_pad_numbers_are_jumpers no)
		(fp_line
			(start -0.7874 0.4064)
			(end -0.7874 -0.4064)
			(stroke
				(width 0.1524)
				(type default)
			)
			(layer "F.SilkS")
		)
		(fp_line
			(start 0.7874 0.4064)
			(end -0.7874 0.4064)
			(stroke
				(width 0.1524)
				(type default)
			)
			(layer "F.SilkS")
		)
		(fp_line
			(start -0.7874 -0.4064)
			(end 0.7874 -0.4064)
			(stroke
				(width 0.1524)
				(type default)
			)
			(layer "F.SilkS")
		)
		(fp_line
			(start 0.7874 -0.4064)
			(end 0.7874 0.4064)
			(stroke
				(width 0.1524)
				(type default)
			)
			(layer "F.SilkS")
		)
		(fp_line
			(start -0.67945 0.3048)
			(end -0.67945 -0.305054)
			(stroke
				(width 0.1)
				(type default)
			)
			(layer "F.Fab")
		)
		(fp_line
			(start -0.12065 0.3048)
			(end -0.67945 0.3048)
			(stroke
				(width 0.1)
				(type default)
			)
			(layer "F.Fab")
		)
		(fp_line
			(start 0.120396 0.3048)
			(end 0.120396 0.2794)
			(stroke
				(width 0.1)
				(type default)
			)
			(layer "F.Fab")
		)
		(fp_line
			(start 0.67945 0.3048)
			(end 0.120396 0.3048)
			(stroke
				(width 0.1)
				(type default)
			)
			(layer "F.Fab")
		)
		(fp_line
			(start -0.12065 0.2794)
			(end -0.12065 0.3048)
			(stroke
				(width 0.1)
				(type default)
			)
			(layer "F.Fab")
		)
		(fp_line
			(start 0.120396 0.2794)
			(end -0.12065 0.2794)
			(stroke
				(width 0.1)
				(type default)
			)
			(layer "F.Fab")
		)
		(fp_line
			(start -0.12065 -0.2794)
			(end 0.12065 -0.2794)
			(stroke
				(width 0.1)
				(type default)
			)
			(layer "F.Fab")
		)
		(fp_line
			(start 0.12065 -0.2794)
			(end 0.12065 -0.3048)
			(stroke
				(width 0.1)
				(type default)
			)
			(layer "F.Fab")
		)
		(fp_line
			(start 0.12065 -0.3048)
			(end 0.67945 -0.3048)
			(stroke
				(width 0.1)
				(type default)
			)
			(layer "F.Fab")
		)
		(fp_line
			(start 0.67945 -0.3048)
			(end 0.67945 0.3048)
			(stroke
				(width 0.1)
				(type default)
			)
			(layer "F.Fab")
		)
		(fp_line
			(start -0.67945 -0.305054)
			(end -0.12065 -0.305054)
			(stroke
				(width 0.1)
				(type default)
			)
			(layer "F.Fab")
		)
		(fp_line
			(start -0.12065 -0.305054)
			(end -0.12065 -0.2794)
			(stroke
				(width 0.1)
				(type default)
			)
			(layer "F.Fab")
		)
		(pad "1" smd circle
			(at -0.40005 0 270)
			(size 0 0)
			(layers "F.Cu" "F.Mask" "F.Paste")
			(net "P3V3_AUX")
		)
		(pad "2" smd circle
			(at 0.40005 0 270)
			(size 0 0)
			(layers "F.Cu" "F.Mask" "F.Paste")
			(net "PRSNT_CABLE_GPU_A3")
		)
	)
	(footprint ""
		(layer "F.Cu")
		(at 54.716172 -167.14597)
		(property "Reference" "H8028"
			(at -5.808218 -4.25069 0)
			(unlocked yes)
			(layer "F.SilkS")
			(effects
				(font
					(size 0.7874 0.5842)
					(thickness 0.1524)
				)
				(justify left)
			)
		)
		(property "Value" ""
			(at 0 0 0)
			(layer "F.Fab")
			(effects
				(font
					(size 1.27 1.27)
				)
			)
		)
		(duplicate_pad_numbers_are_jumpers no)
		(pad "1" thru_hole circle
			(at 0 0)
			(size 6.1976 6.1976)
			(drill 3.7338)
			(layers "*.Cu" "*.Mask")
			(remove_unused_layers no)
			(net "GND")
			(clearance -0.9779)
			(padstack
				(mode front_inner_back)
				(layer "Inner"
					(shape circle)
					(size 5.5372 5.5372)
					(clearance -0.6477)
				)
				(layer "B.Cu"
					(shape circle)
					(size 6.1976 6.1976)
					(clearance -0.9779)
				)
			)
		)
	)
	(footprint ""
		(layer "F.Cu")
		(at 389.653018 -402.7424 -90)
		(property "Reference" "R1124"
			(at 0 0 270)
			(layer "F.SilkS")
			(hide yes)
			(effects
				(font
					(size 1.27 1.27)
				)
			)
		)
		(property "Value" ""
			(at 0 0 270)
			(layer "F.Fab")
			(effects
				(font
					(size 1.27 1.27)
				)
			)
		)
		(duplicate_pad_numbers_are_jumpers no)
		(fp_line
			(start -0.32512 0.175006)
			(end -0.32512 -0.175006)
			(stroke
				(width 0.1)
				(type default)
			)
			(layer "F.Fab")
		)
		(fp_line
			(start 0.32512 0.175006)
			(end -0.32512 0.175006)
			(stroke
				(width 0.1)
				(type default)
			)
			(layer "F.Fab")
		)
		(fp_line
			(start -0.32512 -0.175006)
			(end 0.32512 -0.175006)
			(stroke
				(width 0.1)
				(type default)
			)
			(layer "F.Fab")
		)
		(fp_line
			(start 0.32512 -0.175006)
			(end 0.32512 0.175006)
			(stroke
				(width 0.1)
				(type default)
			)
			(layer "F.Fab")
		)
		(pad "1" smd rect
			(at -0.2667 0 270)
			(size 0.3048 0.381)
			(layers "F.Cu" "F.Mask" "F.Paste")
			(net "RT_CPU0_P3_VQPS")
		)
		(pad "2" smd rect
			(at 0.2667 0 90)
			(size 0.3048 0.381)
			(layers "F.Cu" "F.Mask" "F.Paste")
			(net "GND")
		)
	)
	(footprint ""
		(layer "F.Cu")
		(at 22.07768 -432.437794)
		(property "Reference" "R3523"
			(at 0 0 0)
			(layer "F.SilkS")
			(hide yes)
			(effects
				(font
					(size 1.27 1.27)
				)
			)
		)
		(property "Value" ""
			(at 0 0 0)
			(layer "F.Fab")
			(effects
				(font
					(size 1.27 1.27)
				)
			)
		)
		(duplicate_pad_numbers_are_jumpers no)
		(fp_line
			(start -0.7874 -0.4064)
			(end 0.7874 -0.4064)
			(stroke
				(width 0.1524)
				(type default)
			)
			(layer "F.SilkS")
		)
		(fp_line
			(start -0.7874 0.4064)
			(end -0.7874 -0.4064)
			(stroke
				(width 0.1524)
				(type default)
			)
			(layer "F.SilkS")
		)
		(fp_line
			(start 0.7874 -0.4064)
			(end 0.7874 0.4064)
			(stroke
				(width 0.1524)
				(type default)
			)
			(layer "F.SilkS")
		)
		(fp_line
			(start 0.7874 0.4064)
			(end -0.7874 0.4064)
			(stroke
				(width 0.1524)
				(type default)
			)
			(layer "F.SilkS")
		)
		(fp_line
			(start -0.67945 -0.305054)
			(end -0.12065 -0.305054)
			(stroke
				(width 0.1)
				(type default)
			)
			(layer "F.Fab")
		)
		(fp_line
			(start -0.67945 0.3048)
			(end -0.67945 -0.305054)
			(stroke
				(width 0.1)
				(type default)
			)
			(layer "F.Fab")
		)
		(fp_line
			(start -0.12065 -0.305054)
			(end -0.12065 -0.2794)
			(stroke
				(width 0.1)
				(type default)
			)
			(layer "F.Fab")
		)
		(fp_line
			(start -0.12065 -0.2794)
			(end 0.12065 -0.2794)
			(stroke
				(width 0.1)
				(type default)
			)
			(layer "F.Fab")
		)
		(fp_line
			(start -0.12065 0.2794)
			(end -0.12065 0.3048)
			(stroke
				(width 0.1)
				(type default)
			)
			(layer "F.Fab")
		)
		(fp_line
			(start -0.12065 0.3048)
			(end -0.67945 0.3048)
			(stroke
				(width 0.1)
				(type default)
			)
			(layer "F.Fab")
		)
		(fp_line
			(start 0.120396 0.2794)
			(end -0.12065 0.2794)
			(stroke
				(width 0.1)
				(type default)
			)
			(layer "F.Fab")
		)
		(fp_line
			(start 0.120396 0.3048)
			(end 0.120396 0.2794)
			(stroke
				(width 0.1)
				(type default)
			)
			(layer "F.Fab")
		)
		(fp_line
			(start 0.12065 -0.3048)
			(end 0.67945 -0.3048)
			(stroke
				(width 0.1)
				(type default)
			)
			(layer "F.Fab")
		)
		(fp_line
			(start 0.12065 -0.2794)
			(end 0.12065 -0.3048)
			(stroke
				(width 0.1)
				(type default)
			)
			(layer "F.Fab")
		)
		(fp_line
			(start 0.67945 -0.3048)
			(end 0.67945 0.3048)
			(stroke
				(width 0.1)
				(type default)
			)
			(layer "F.Fab")
		)
		(fp_line
			(start 0.67945 0.3048)
			(end 0.120396 0.3048)
			(stroke
				(width 0.1)
				(type default)
			)
			(layer "F.Fab")
		)
		(pad "1" smd circle
			(at -0.40005 0)
			(size 0 0)
			(layers "F.Cu" "F.Mask" "F.Paste")
			(net "P3V3_AUX")
		)
		(pad "2" smd circle
			(at 0.40005 0)
			(size 0 0)
			(layers "F.Cu" "F.Mask" "F.Paste")
			(net "SMB_1_BMC_GPU_BUF_R_SCL")
		)
	)
	(footprint ""
		(layer "F.Cu")
		(at 160.057338 -20.068794 -90)
		(property "Reference" "C2077"
			(at 0 0 270)
			(layer "F.SilkS")
			(hide yes)
			(effects
				(font
					(size 1.27 1.27)
				)
			)
		)
		(property "Value" ""
			(at 0 0 270)
			(layer "F.Fab")
			(effects
				(font
					(size 1.27 1.27)
				)
			)
		)
		(duplicate_pad_numbers_are_jumpers no)
		(fp_line
			(start -0.299974 0.150114)
			(end -0.299974 -0.150114)
			(stroke
				(width 0.1)
				(type default)
			)
			(layer "F.Fab")
		)
		(fp_line
			(start 0.299974 0.150114)
			(end -0.299974 0.150114)
			(stroke
				(width 0.1)
				(type default)
			)
			(layer "F.Fab")
		)
		(fp_line
			(start -0.299974 -0.150114)
			(end 0.299974 -0.150114)
			(stroke
				(width 0.1)
				(type default)
			)
			(layer "F.Fab")
		)
		(fp_line
			(start 0.299974 -0.150114)
			(end 0.299974 0.150114)
			(stroke
				(width 0.1)
				(type default)
			)
			(layer "F.Fab")
		)
		(pad "1" smd rect
			(at -0.2667 0 270)
			(size 0.3048 0.381)
			(layers "F.Cu" "F.Mask" "F.Paste")
			(net "P2E_CPU0_P5_TX_DP")
		)
		(pad "2" smd rect
			(at 0.2667 0 270)
			(size 0.3048 0.381)
			(layers "F.Cu" "F.Mask" "F.Paste")
			(net "P2E_CPU0_P5_TX_C_DP")
		)
	)
	(footprint ""
		(layer "F.Cu")
		(at 69.33057 -168.93032 90)
		(property "Reference" "PC126_C0P1_6"
			(at 0 0 90)
			(layer "F.SilkS")
			(hide yes)
			(effects
				(font
					(size 1.27 1.27)
				)
			)
		)
		(property "Value" ""
			(at 0 0 90)
			(layer "F.Fab")
			(effects
				(font
					(size 1.27 1.27)
				)
			)
		)
		(duplicate_pad_numbers_are_jumpers no)
		(fp_line
			(start 0.7874 -0.4064)
			(end 0.7874 0.4064)
			(stroke
				(width 0.1524)
				(type default)
			)
			(layer "F.SilkS")
		)
		(fp_line
			(start -0.7874 -0.4064)
			(end 0.7874 -0.4064)
			(stroke
				(width 0.1524)
				(type default)
			)
			(layer "F.SilkS")
		)
		(fp_line
			(start 0.7874 0.4064)
			(end -0.7874 0.4064)
			(stroke
				(width 0.1524)
				(type default)
			)
			(layer "F.SilkS")
		)
		(fp_line
			(start -0.7874 0.4064)
			(end -0.7874 -0.4064)
			(stroke
				(width 0.1524)
				(type default)
			)
			(layer "F.SilkS")
		)
		(fp_line
			(start -0.12065 -0.305054)
			(end -0.12065 -0.2794)
			(stroke
				(width 0.1)
				(type default)
			)
			(layer "F.Fab")
		)
		(fp_line
			(start -0.67945 -0.305054)
			(end -0.12065 -0.305054)
			(stroke
				(width 0.1)
				(type default)
			)
			(layer "F.Fab")
		)
		(fp_line
			(start 0.67945 -0.3048)
			(end 0.67945 0.3048)
			(stroke
				(width 0.1)
				(type default)
			)
			(layer "F.Fab")
		)
		(fp_line
			(start 0.12065 -0.3048)
			(end 0.67945 -0.3048)
			(stroke
				(width 0.1)
				(type default)
			)
			(layer "F.Fab")
		)
		(fp_line
			(start 0.12065 -0.2794)
			(end 0.12065 -0.3048)
			(stroke
				(width 0.1)
				(type default)
			)
			(layer "F.Fab")
		)
		(fp_line
			(start -0.12065 -0.2794)
			(end 0.12065 -0.2794)
			(stroke
				(width 0.1)
				(type default)
			)
			(layer "F.Fab")
		)
		(fp_line
			(start 0.120396 0.2794)
			(end -0.12065 0.2794)
			(stroke
				(width 0.1)
				(type default)
			)
			(layer "F.Fab")
		)
		(fp_line
			(start -0.12065 0.2794)
			(end -0.12065 0.3048)
			(stroke
				(width 0.1)
				(type default)
			)
			(layer "F.Fab")
		)
		(fp_line
			(start 0.67945 0.3048)
			(end 0.120396 0.3048)
			(stroke
				(width 0.1)
				(type default)
			)
			(layer "F.Fab")
		)
		(fp_line
			(start 0.120396 0.3048)
			(end 0.120396 0.2794)
			(stroke
				(width 0.1)
				(type default)
			)
			(layer "F.Fab")
		)
		(fp_line
			(start -0.12065 0.3048)
			(end -0.67945 0.3048)
			(stroke
				(width 0.1)
				(type default)
			)
			(layer "F.Fab")
		)
		(fp_line
			(start -0.67945 0.3048)
			(end -0.67945 -0.305054)
			(stroke
				(width 0.1)
				(type default)
			)
			(layer "F.Fab")
		)
		(pad "1" smd circle
			(at -0.40005 0 90)
			(size 0 0)
			(layers "F.Cu" "F.Mask" "F.Paste")
			(net "PVDDCR_CPU0_P1_PVCC")
		)
		(pad "2" smd circle
			(at 0.40005 0 90)
			(size 0 0)
			(layers "F.Cu" "F.Mask" "F.Paste")
			(net "GND")
		)
	)
	(footprint ""
		(layer "F.Cu")
		(at 90.68181 -182.675784 180)
		(property "Reference" "PU26"
			(at -0.51816 -6.641338 0)
			(unlocked yes)
			(layer "F.SilkS")
			(effects
				(font
					(size 0.7874 0.5842)
					(thickness 0.1524)
				)
				(justify left)
			)
		)
		(property "Value" ""
			(at 0 0 180)
			(layer "F.Fab")
			(effects
				(font
					(size 1.27 1.27)
				)
			)
		)
		(duplicate_pad_numbers_are_jumpers no)
		(fp_line
			(start 2.500122 2.999994)
			(end 2.2987 2.999994)
			(stroke
				(width 0.1524)
				(type default)
			)
			(layer "F.SilkS")
		)
		(fp_line
			(start 2.500122 2.339594)
			(end 2.500122 2.999994)
			(stroke
				(width 0.1524)
				(type default)
			)
			(layer "F.SilkS")
		)
		(fp_line
			(start 2.500122 -2.999994)
			(end 2.500122 -2.44348)
			(stroke
				(width 0.1524)
				(type default)
			)
			(layer "F.SilkS")
		)
		(fp_line
			(start 2.31394 -2.999994)
			(end 2.500122 -2.999994)
			(stroke
				(width 0.1524)
				(type default)
			)
			(layer "F.SilkS")
		)
		(fp_line
			(start -2.2987 2.999994)
			(end -2.500122 2.999994)
			(stroke
				(width 0.1524)
				(type default)
			)
			(layer "F.SilkS")
		)
		(fp_line
			(start -2.500122 2.999994)
			(end -2.500122 2.339594)
			(stroke
				(width 0.1524)
				(type default)
			)
			(layer "F.SilkS")
		)
		(fp_line
			(start -2.500122 0.6604)
			(end -2.500122 0.229108)
			(stroke
				(width 0.1524)
				(type default)
			)
			(layer "F.SilkS")
		)
		(fp_line
			(start -2.500122 -2.529078)
			(end -2.500122 -2.999994)
			(stroke
				(width 0.1524)
				(type default)
			)
			(layer "F.SilkS")
		)
		(fp_line
			(start -2.500122 -2.999994)
			(end -2.24409 -2.999994)
			(stroke
				(width 0.1524)
				(type default)
			)
			(layer "F.SilkS")
		)
		(fp_poly
			(pts
				(xy -2.708148 -2.422144) (xy -3.381756 -2.64668) (xy -2.932684 -3.095752)
			)
			(stroke
				(width 0)
				(type default)
			)
			(fill yes)
			(layer "F.SilkS")
		)
		(fp_line
			(start 2.500122 2.999994)
			(end -2.500122 2.999994)
			(stroke
				(width 0.1)
				(type default)
			)
			(layer "F.Fab")
		)
		(fp_line
			(start 2.500122 -2.999994)
			(end 2.500122 2.999994)
			(stroke
				(width 0.1)
				(type default)
			)
			(layer "F.Fab")
		)
		(fp_line
			(start -2.500122 2.999994)
			(end -2.500122 -2.999994)
			(stroke
				(width 0.1)
				(type default)
			)
			(layer "F.Fab")
		)
		(fp_line
			(start -2.500122 -2.999994)
			(end 2.500122 -2.999994)
			(stroke
				(width 0.1)
				(type default)
			)
			(layer "F.Fab")
		)
		(fp_poly
			(pts
				(xy -4.218432 -2.783078) (xy -4.218432 -1.767078) (xy -3.202432 -2.275078)
			)
			(stroke
				(width 0)
				(type default)
			)
			(fill yes)
			(layer "F.Fab")
		)
		(pad "1" smd rect
			(at -2.400046 -2.275078 270)
			(size 0.2286 0.6096)
			(layers "F.Cu" "F.Mask" "F.Paste")
			(net "PVDDCR_CPU0_P1_VOS2")
		)
		(pad "2" smd rect
			(at -2.400046 -1.82499 270)
			(size 0.2286 0.6096)
			(layers "F.Cu" "F.Mask" "F.Paste")
			(net "GND")
		)
		(pad "3" smd rect
			(at -2.400046 -1.374902 270)
			(size 0.2286 0.6096)
			(layers "F.Cu" "F.Mask" "F.Paste")
			(net "PVDDCR_CPU0_P1_VCC2")
		)
		(pad "4" smd rect
			(at -2.400046 -0.925068 270)
			(size 0.2286 0.6096)
			(layers "F.Cu" "F.Mask" "F.Paste")
			(net "PVDDCR_CPU0_P1_PVCC")
		)
		(pad "5" smd rect
			(at -2.400046 -0.47498 270)
			(size 0.2286 0.6096)
			(layers "F.Cu" "F.Mask" "F.Paste")
			(net "GND")
		)
		(pad "6" smd rect
			(at -2.400046 -0.024892 270)
			(size 0.2286 0.6096)
			(layers "F.Cu" "F.Mask" "F.Paste")
			(net "NC_PVDDCR_CPU0_P1_GL1_2")
		)
		(pad "7_9-20_24" smd circle
			(at 0 1.150112 270)
			(size 0 0)
			(layers "F.Cu" "F.Mask" "F.Paste")
			(net "GND")
		)
		(pad "10_19" smd rect
			(at 0 2.899918 270)
			(size 0.6096 4.318)
			(layers "F.Cu" "F.Mask" "F.Paste")
			(net "SW_PVDDCR_CPU0_P1_SW2")
		)
		(pad "25_29" smd rect
			(at 1.549908 -1.279906 90)
			(size 2.0574 2.3114)
			(layers "F.Cu" "F.Mask" "F.Paste")
			(net "SW_P12V_AUX_PVDDCR_CPU0_P1_FLT")
		)
		(pad "30" smd rect
			(at 2.05994 -2.899918 180)
			(size 0.2286 0.6096)
			(layers "F.Cu" "F.Mask" "F.Paste")
			(net "SW_P12V_AUX_PVDDCR_CPU0_P1_FLT")
		)
		(pad "31" smd rect
			(at 1.610106 -2.899918 180)
			(size 0.2286 0.6096)
			(layers "F.Cu" "F.Mask" "F.Paste")
			(net "NC_PVDDCR_CPU0_P1_DNC2")
		)
		(pad "32" smd rect
			(at 1.160018 -2.899918 180)
			(size 0.2286 0.6096)
			(layers "F.Cu" "F.Mask" "F.Paste")
			(net "SW_PVDDCR_CPU0_P1_PH2")
		)
		(pad "33" smd rect
			(at 0.70993 -2.899918 180)
			(size 0.2286 0.6096)
			(layers "F.Cu" "F.Mask" "F.Paste")
			(net "SW_PVDDCR_CPU0_P1_BOOT2")
		)
		(pad "34" smd rect
			(at 0.260096 -2.899918 180)
			(size 0.2286 0.6096)
			(layers "F.Cu" "F.Mask" "F.Paste")
			(net "PVDDCR_CPU0_P1_PWM2")
		)
		(pad "35" smd rect
			(at -0.189992 -2.899918 180)
			(size 0.2286 0.6096)
			(layers "F.Cu" "F.Mask" "F.Paste")
			(net "PVDDCR_CPU0_P1_VCC2")
		)
		(pad "36" smd rect
			(at -0.64008 -2.899918 180)
			(size 0.2286 0.6096)
			(layers "F.Cu" "F.Mask" "F.Paste")
			(net "PVDDCR_CPU0_P1_TEMP0")
		)
		(pad "37" smd rect
			(at -1.089914 -2.899918 180)
			(size 0.2286 0.6096)
			(layers "F.Cu" "F.Mask" "F.Paste")
			(net "PVDDCR_CPU0_P1_LSET2")
		)
		(pad "38" smd rect
			(at -1.540002 -2.899918 180)
			(size 0.2286 0.6096)
			(layers "F.Cu" "F.Mask" "F.Paste")
			(net "PVDDCR_CPU0_P1_IMON2")
		)
		(pad "39" smd rect
			(at -1.99009 -2.899918 180)
			(size 0.2286 0.6096)
			(layers "F.Cu" "F.Mask" "F.Paste")
			(net "PVDDCR_CPU0_P1_VCCS")
		)
		(pad "40" smd rect
			(at -0.87503 -1.27508 180)
			(size 1.7526 1.9558)
			(layers "F.Cu" "F.Mask" "F.Paste")
			(net "GND")
		)
		(pad "41" smd rect
			(at -1.525016 0.249936 90)
			(size 0.3048 0.4572)
			(layers "F.Cu" "F.Mask" "F.Paste")
			(net "NC_PVDDCR_CPU0_P1_GL2_2")
		)
		(zone
			(layer "F.Cu")
			(hatch none 0.5)
			(connect_pads
				(clearance 0)
			)
			(min_thickness 0.25)
			(keepout
				(tracks not_allowed)
				(vias allowed)
				(pads allowed)
				(copperpour not_allowed)
				(footprints allowed)
			)
			(placement
				(enabled no)
				(sheetname "")
			)
			(fill
				(thermal_gap 0.5)
				(thermal_bridge_width 0.5)
				(island_removal_mode 0)
			)
			(polygon
				(pts
					(xy 93.181932 -185.220102) (xy 93.181932 -184.926478) (xy 88.181688 -184.926478) (xy 88.181688 -185.220102)
					(xy 88.47201 -185.220102) (xy 92.89161 -185.220102)
				)
			)
		)
		(zone
			(layer "F.Cu")
			(hatch none 0.5)
			(connect_pads
				(clearance 0)
			)
			(min_thickness 0.25)
			(keepout
				(tracks not_allowed)
				(vias allowed)
				(pads allowed)
				(copperpour not_allowed)
				(footprints allowed)
			)
			(placement
				(enabled no)
				(sheetname "")
			)
			(fill
				(thermal_gap 0.5)
				(thermal_bridge_width 0.5)
				(island_removal_mode 0)
			)
			(polygon
				(pts
					(xy 90.62974 -182.429404) (xy 90.62974 -180.372004) (xy 92.48394 -180.372004) (xy 92.48394 -180.61305)
					(xy 92.726256 -180.61305) (xy 92.726256 -180.131466) (xy 88.825578 -180.131466) (xy 88.825578 -180.316378)
					(xy 90.338402 -180.316378) (xy 90.338402 -182.475378) (xy 88.181688 -182.475378) (xy 88.181688 -182.72506)
					(xy 90.334084 -182.72506)
				)
			)
		)
	)
	(footprint ""
		(layer "F.Cu")
		(at 187.127642 -413.64408 90)
		(property "Reference" "R9011"
			(at 0 0 90)
			(layer "F.SilkS")
			(hide yes)
			(effects
				(font
					(size 1.27 1.27)
				)
			)
		)
		(property "Value" ""
			(at 0 0 90)
			(layer "F.Fab")
			(effects
				(font
					(size 1.27 1.27)
				)
			)
		)
		(duplicate_pad_numbers_are_jumpers no)
		(fp_line
			(start 0.7874 -0.4064)
			(end 0.7874 0.4064)
			(stroke
				(width 0.1524)
				(type default)
			)
			(layer "F.SilkS")
		)
		(fp_line
			(start -0.7874 -0.4064)
			(end 0.7874 -0.4064)
			(stroke
				(width 0.1524)
				(type default)
			)
			(layer "F.SilkS")
		)
		(fp_line
			(start 0.7874 0.4064)
			(end -0.7874 0.4064)
			(stroke
				(width 0.1524)
				(type default)
			)
			(layer "F.SilkS")
		)
		(fp_line
			(start -0.7874 0.4064)
			(end -0.7874 -0.4064)
			(stroke
				(width 0.1524)
				(type default)
			)
			(layer "F.SilkS")
		)
		(fp_line
			(start -0.12065 -0.305054)
			(end -0.12065 -0.2794)
			(stroke
				(width 0.1)
				(type default)
			)
			(layer "F.Fab")
		)
		(fp_line
			(start -0.67945 -0.305054)
			(end -0.12065 -0.305054)
			(stroke
				(width 0.1)
				(type default)
			)
			(layer "F.Fab")
		)
		(fp_line
			(start 0.67945 -0.3048)
			(end 0.67945 0.3048)
			(stroke
				(width 0.1)
				(type default)
			)
			(layer "F.Fab")
		)
		(fp_line
			(start 0.12065 -0.3048)
			(end 0.67945 -0.3048)
			(stroke
				(width 0.1)
				(type default)
			)
			(layer "F.Fab")
		)
		(fp_line
			(start 0.12065 -0.2794)
			(end 0.12065 -0.3048)
			(stroke
				(width 0.1)
				(type default)
			)
			(layer "F.Fab")
		)
		(fp_line
			(start -0.12065 -0.2794)
			(end 0.12065 -0.2794)
			(stroke
				(width 0.1)
				(type default)
			)
			(layer "F.Fab")
		)
		(fp_line
			(start 0.120396 0.2794)
			(end -0.12065 0.2794)
			(stroke
				(width 0.1)
				(type default)
			)
			(layer "F.Fab")
		)
		(fp_line
			(start -0.12065 0.2794)
			(end -0.12065 0.3048)
			(stroke
				(width 0.1)
				(type default)
			)
			(layer "F.Fab")
		)
		(fp_line
			(start 0.67945 0.3048)
			(end 0.120396 0.3048)
			(stroke
				(width 0.1)
				(type default)
			)
			(layer "F.Fab")
		)
		(fp_line
			(start 0.120396 0.3048)
			(end 0.120396 0.2794)
			(stroke
				(width 0.1)
				(type default)
			)
			(layer "F.Fab")
		)
		(fp_line
			(start -0.12065 0.3048)
			(end -0.67945 0.3048)
			(stroke
				(width 0.1)
				(type default)
			)
			(layer "F.Fab")
		)
		(fp_line
			(start -0.67945 0.3048)
			(end -0.67945 -0.305054)
			(stroke
				(width 0.1)
				(type default)
			)
			(layer "F.Fab")
		)
		(pad "1" smd circle
			(at -0.40005 0 90)
			(size 0 0)
			(layers "F.Cu" "F.Mask" "F.Paste")
			(net "PRSNT_CABLE_GPU_B3_ISO_N")
		)
		(pad "2" smd circle
			(at 0.40005 0 90)
			(size 0 0)
			(layers "F.Cu" "F.Mask" "F.Paste")
			(net "PRSNT_CABLE_GPU_B3_ISO_R1_N")
		)
	)
	(footprint ""
		(layer "F.Cu")
		(at 265.16838 -419.628828)
		(property "Reference" "R3923"
			(at 0 0 0)
			(layer "F.SilkS")
			(hide yes)
			(effects
				(font
					(size 1.27 1.27)
				)
			)
		)
		(property "Value" ""
			(at 0 0 0)
			(layer "F.Fab")
			(effects
				(font
					(size 1.27 1.27)
				)
			)
		)
		(duplicate_pad_numbers_are_jumpers no)
		(fp_line
			(start -0.7874 -0.4064)
			(end 0.7874 -0.4064)
			(stroke
				(width 0.1524)
				(type default)
			)
			(layer "F.SilkS")
		)
		(fp_line
			(start -0.7874 0.4064)
			(end -0.7874 -0.4064)
			(stroke
				(width 0.1524)
				(type default)
			)
			(layer "F.SilkS")
		)
		(fp_line
			(start 0.7874 -0.4064)
			(end 0.7874 0.4064)
			(stroke
				(width 0.1524)
				(type default)
			)
			(layer "F.SilkS")
		)
		(fp_line
			(start 0.7874 0.4064)
			(end -0.7874 0.4064)
			(stroke
				(width 0.1524)
				(type default)
			)
			(layer "F.SilkS")
		)
		(fp_line
			(start -0.67945 -0.305054)
			(end -0.12065 -0.305054)
			(stroke
				(width 0.1)
				(type default)
			)
			(layer "F.Fab")
		)
		(fp_line
			(start -0.67945 0.3048)
			(end -0.67945 -0.305054)
			(stroke
				(width 0.1)
				(type default)
			)
			(layer "F.Fab")
		)
		(fp_line
			(start -0.12065 -0.305054)
			(end -0.12065 -0.2794)
			(stroke
				(width 0.1)
				(type default)
			)
			(layer "F.Fab")
		)
		(fp_line
			(start -0.12065 -0.2794)
			(end 0.12065 -0.2794)
			(stroke
				(width 0.1)
				(type default)
			)
			(layer "F.Fab")
		)
		(fp_line
			(start -0.12065 0.2794)
			(end -0.12065 0.3048)
			(stroke
				(width 0.1)
				(type default)
			)
			(layer "F.Fab")
		)
		(fp_line
			(start -0.12065 0.3048)
			(end -0.67945 0.3048)
			(stroke
				(width 0.1)
				(type default)
			)
			(layer "F.Fab")
		)
		(fp_line
			(start 0.120396 0.2794)
			(end -0.12065 0.2794)
			(stroke
				(width 0.1)
				(type default)
			)
			(layer "F.Fab")
		)
		(fp_line
			(start 0.120396 0.3048)
			(end 0.120396 0.2794)
			(stroke
				(width 0.1)
				(type default)
			)
			(layer "F.Fab")
		)
		(fp_line
			(start 0.12065 -0.3048)
			(end 0.67945 -0.3048)
			(stroke
				(width 0.1)
				(type default)
			)
			(layer "F.Fab")
		)
		(fp_line
			(start 0.12065 -0.2794)
			(end 0.12065 -0.3048)
			(stroke
				(width 0.1)
				(type default)
			)
			(layer "F.Fab")
		)
		(fp_line
			(start 0.67945 -0.3048)
			(end 0.67945 0.3048)
			(stroke
				(width 0.1)
				(type default)
			)
			(layer "F.Fab")
		)
		(fp_line
			(start 0.67945 0.3048)
			(end 0.120396 0.3048)
			(stroke
				(width 0.1)
				(type default)
			)
			(layer "F.Fab")
		)
		(pad "1" smd circle
			(at -0.40005 0)
			(size 0 0)
			(layers "F.Cu" "F.Mask" "F.Paste")
			(net "P12V_PSU_FUSE")
		)
		(pad "2" smd circle
			(at 0.40005 0)
			(size 0 0)
			(layers "F.Cu" "F.Mask" "F.Paste")
			(net "PDB_PRSNT_R_N")
		)
	)
	(footprint ""
		(layer "F.Cu")
		(at 279.513792 -114.64417 180)
		(property "Reference" "R3527"
			(at 0 0 180)
			(layer "F.SilkS")
			(hide yes)
			(effects
				(font
					(size 1.27 1.27)
				)
			)
		)
		(property "Value" ""
			(at 0 0 180)
			(layer "F.Fab")
			(effects
				(font
					(size 1.27 1.27)
				)
			)
		)
		(duplicate_pad_numbers_are_jumpers no)
		(fp_line
			(start 0.7874 0.4064)
			(end -0.7874 0.4064)
			(stroke
				(width 0.1524)
				(type default)
			)
			(layer "F.SilkS")
		)
		(fp_line
			(start 0.7874 -0.4064)
			(end 0.7874 0.4064)
			(stroke
				(width 0.1524)
				(type default)
			)
			(layer "F.SilkS")
		)
		(fp_line
			(start -0.7874 0.4064)
			(end -0.7874 -0.4064)
			(stroke
				(width 0.1524)
				(type default)
			)
			(layer "F.SilkS")
		)
		(fp_line
			(start -0.7874 -0.4064)
			(end 0.7874 -0.4064)
			(stroke
				(width 0.1524)
				(type default)
			)
			(layer "F.SilkS")
		)
		(fp_line
			(start 0.67945 0.3048)
			(end 0.120396 0.3048)
			(stroke
				(width 0.1)
				(type default)
			)
			(layer "F.Fab")
		)
		(fp_line
			(start 0.67945 -0.3048)
			(end 0.67945 0.3048)
			(stroke
				(width 0.1)
				(type default)
			)
			(layer "F.Fab")
		)
		(fp_line
			(start 0.12065 -0.2794)
			(end 0.12065 -0.3048)
			(stroke
				(width 0.1)
				(type default)
			)
			(layer "F.Fab")
		)
		(fp_line
			(start 0.12065 -0.3048)
			(end 0.67945 -0.3048)
			(stroke
				(width 0.1)
				(type default)
			)
			(layer "F.Fab")
		)
		(fp_line
			(start 0.120396 0.3048)
			(end 0.120396 0.2794)
			(stroke
				(width 0.1)
				(type default)
			)
			(layer "F.Fab")
		)
		(fp_line
			(start 0.120396 0.2794)
			(end -0.12065 0.2794)
			(stroke
				(width 0.1)
				(type default)
			)
			(layer "F.Fab")
		)
		(fp_line
			(start -0.12065 0.3048)
			(end -0.67945 0.3048)
			(stroke
				(width 0.1)
				(type default)
			)
			(layer "F.Fab")
		)
		(fp_line
			(start -0.12065 0.2794)
			(end -0.12065 0.3048)
			(stroke
				(width 0.1)
				(type default)
			)
			(layer "F.Fab")
		)
		(fp_line
			(start -0.12065 -0.2794)
			(end 0.12065 -0.2794)
			(stroke
				(width 0.1)
				(type default)
			)
			(layer "F.Fab")
		)
		(fp_line
			(start -0.12065 -0.305054)
			(end -0.12065 -0.2794)
			(stroke
				(width 0.1)
				(type default)
			)
			(layer "F.Fab")
		)
		(fp_line
			(start -0.67945 0.3048)
			(end -0.67945 -0.305054)
			(stroke
				(width 0.1)
				(type default)
			)
			(layer "F.Fab")
		)
		(fp_line
			(start -0.67945 -0.305054)
			(end -0.12065 -0.305054)
			(stroke
				(width 0.1)
				(type default)
			)
			(layer "F.Fab")
		)
		(pad "1" smd circle
			(at -0.40005 0 180)
			(size 0 0)
			(layers "F.Cu" "F.Mask" "F.Paste")
			(net "SMB_PCIE0_3V3AUX_SDA_R5")
		)
		(pad "2" smd circle
			(at 0.40005 0 180)
			(size 0 0)
			(layers "F.Cu" "F.Mask" "F.Paste")
			(net "SMB_SENSOR_E1S_3V3AUX_SDA")
		)
	)
	(footprint ""
		(layer "F.Cu")
		(at 447.237866 -407.6573 180)
		(property "Reference" "PC6559_1"
			(at 0 0 180)
			(layer "F.SilkS")
			(hide yes)
			(effects
				(font
					(size 1.27 1.27)
				)
			)
		)
		(property "Value" ""
			(at 0 0 180)
			(layer "F.Fab")
			(effects
				(font
					(size 1.27 1.27)
				)
			)
		)
		(duplicate_pad_numbers_are_jumpers no)
		(fp_line
			(start 1.524 0.762)
			(end -1.524 0.762)
			(stroke
				(width 0.1524)
				(type default)
			)
			(layer "F.SilkS")
		)
		(fp_line
			(start 1.524 -0.762)
			(end 1.524 0.762)
			(stroke
				(width 0.1524)
				(type default)
			)
			(layer "F.SilkS")
		)
		(fp_line
			(start -1.524 0.762)
			(end -1.524 -0.762)
			(stroke
				(width 0.1524)
				(type default)
			)
			(layer "F.SilkS")
		)
		(fp_line
			(start -1.524 -0.762)
			(end 1.524 -0.762)
			(stroke
				(width 0.1524)
				(type default)
			)
			(layer "F.SilkS")
		)
		(fp_line
			(start 1.1049 0.724916)
			(end 1.1049 -0.724916)
			(stroke
				(width 0.1)
				(type default)
			)
			(layer "F.Fab")
		)
		(fp_line
			(start 1.1049 -0.724916)
			(end -1.1049 -0.724916)
			(stroke
				(width 0.1)
				(type default)
			)
			(layer "F.Fab")
		)
		(fp_line
			(start -1.1049 0.724916)
			(end 1.1049 0.724916)
			(stroke
				(width 0.1)
				(type default)
			)
			(layer "F.Fab")
		)
		(fp_line
			(start -1.1049 -0.724916)
			(end -1.1049 0.724916)
			(stroke
				(width 0.1)
				(type default)
			)
			(layer "F.Fab")
		)
		(pad "1" smd rect
			(at -0.889 0)
			(size 1.016 1.27)
			(layers "F.Cu" "F.Mask" "F.Paste")
			(net "SW_P12V_AUX_P0V9_RETIMER_CPU0_FLT")
		)
		(pad "2" smd rect
			(at 0.889 0)
			(size 1.016 1.27)
			(layers "F.Cu" "F.Mask" "F.Paste")
			(net "GND")
		)
	)
	(footprint ""
		(layer "F.Cu")
		(at 15.527782 -416.050984 90)
		(property "Reference" "PR6539"
			(at 0 0 90)
			(layer "F.SilkS")
			(hide yes)
			(effects
				(font
					(size 1.27 1.27)
				)
			)
		)
		(property "Value" ""
			(at 0 0 90)
			(layer "F.Fab")
			(effects
				(font
					(size 1.27 1.27)
				)
			)
		)
		(duplicate_pad_numbers_are_jumpers no)
		(fp_line
			(start 0.7874 -0.4064)
			(end 0.7874 0.4064)
			(stroke
				(width 0.1524)
				(type default)
			)
			(layer "F.SilkS")
		)
		(fp_line
			(start -0.7874 -0.4064)
			(end 0.7874 -0.4064)
			(stroke
				(width 0.1524)
				(type default)
			)
			(layer "F.SilkS")
		)
		(fp_line
			(start 0.7874 0.4064)
			(end -0.7874 0.4064)
			(stroke
				(width 0.1524)
				(type default)
			)
			(layer "F.SilkS")
		)
		(fp_line
			(start -0.7874 0.4064)
			(end -0.7874 -0.4064)
			(stroke
				(width 0.1524)
				(type default)
			)
			(layer "F.SilkS")
		)
		(fp_line
			(start -0.12065 -0.305054)
			(end -0.12065 -0.2794)
			(stroke
				(width 0.1)
				(type default)
			)
			(layer "F.Fab")
		)
		(fp_line
			(start -0.67945 -0.305054)
			(end -0.12065 -0.305054)
			(stroke
				(width 0.1)
				(type default)
			)
			(layer "F.Fab")
		)
		(fp_line
			(start 0.67945 -0.3048)
			(end 0.67945 0.3048)
			(stroke
				(width 0.1)
				(type default)
			)
			(layer "F.Fab")
		)
		(fp_line
			(start 0.12065 -0.3048)
			(end 0.67945 -0.3048)
			(stroke
				(width 0.1)
				(type default)
			)
			(layer "F.Fab")
		)
		(fp_line
			(start 0.12065 -0.2794)
			(end 0.12065 -0.3048)
			(stroke
				(width 0.1)
				(type default)
			)
			(layer "F.Fab")
		)
		(fp_line
			(start -0.12065 -0.2794)
			(end 0.12065 -0.2794)
			(stroke
				(width 0.1)
				(type default)
			)
			(layer "F.Fab")
		)
		(fp_line
			(start 0.120396 0.2794)
			(end -0.12065 0.2794)
			(stroke
				(width 0.1)
				(type default)
			)
			(layer "F.Fab")
		)
		(fp_line
			(start -0.12065 0.2794)
			(end -0.12065 0.3048)
			(stroke
				(width 0.1)
				(type default)
			)
			(layer "F.Fab")
		)
		(fp_line
			(start 0.67945 0.3048)
			(end 0.120396 0.3048)
			(stroke
				(width 0.1)
				(type default)
			)
			(layer "F.Fab")
		)
		(fp_line
			(start 0.120396 0.3048)
			(end 0.120396 0.2794)
			(stroke
				(width 0.1)
				(type default)
			)
			(layer "F.Fab")
		)
		(fp_line
			(start -0.12065 0.3048)
			(end -0.67945 0.3048)
			(stroke
				(width 0.1)
				(type default)
			)
			(layer "F.Fab")
		)
		(fp_line
			(start -0.67945 0.3048)
			(end -0.67945 -0.305054)
			(stroke
				(width 0.1)
				(type default)
			)
			(layer "F.Fab")
		)
		(pad "1" smd circle
			(at -0.40005 0 90)
			(size 0 0)
			(layers "F.Cu" "F.Mask" "F.Paste")
			(net "NC_P0V9_RETIMER_CPU1_IMON3")
		)
		(pad "2" smd circle
			(at 0.40005 0 90)
			(size 0 0)
			(layers "F.Cu" "F.Mask" "F.Paste")
			(net "GND")
		)
	)
	(footprint ""
		(layer "F.Cu")
		(at 400.315684 -403.818852 -90)
		(property "Reference" "R1065"
			(at 0 0 270)
			(layer "F.SilkS")
			(hide yes)
			(effects
				(font
					(size 1.27 1.27)
				)
			)
		)
		(property "Value" ""
			(at 0 0 270)
			(layer "F.Fab")
			(effects
				(font
					(size 1.27 1.27)
				)
			)
		)
		(duplicate_pad_numbers_are_jumpers no)
		(fp_line
			(start -0.32512 0.175006)
			(end -0.32512 -0.175006)
			(stroke
				(width 0.1)
				(type default)
			)
			(layer "F.Fab")
		)
		(fp_line
			(start 0.32512 0.175006)
			(end -0.32512 0.175006)
			(stroke
				(width 0.1)
				(type default)
			)
			(layer "F.Fab")
		)
		(fp_line
			(start -0.32512 -0.175006)
			(end 0.32512 -0.175006)
			(stroke
				(width 0.1)
				(type default)
			)
			(layer "F.Fab")
		)
		(fp_line
			(start 0.32512 -0.175006)
			(end 0.32512 0.175006)
			(stroke
				(width 0.1)
				(type default)
			)
			(layer "F.Fab")
		)
		(pad "1" smd rect
			(at -0.2667 0 270)
			(size 0.3048 0.381)
			(layers "F.Cu" "F.Mask" "F.Paste")
			(net "P1V8_CPU0_RT_1D")
		)
		(pad "2" smd rect
			(at 0.2667 0 90)
			(size 0.3048 0.381)
			(layers "F.Cu" "F.Mask" "F.Paste")
			(net "RST_RT_CPU0_P2_RESET_R_N")
		)
	)
	(footprint ""
		(layer "F.Cu")
		(at 314.66282 -337.660488 90)
		(property "Reference" "PC110"
			(at 0 0 90)
			(layer "F.SilkS")
			(hide yes)
			(effects
				(font
					(size 1.27 1.27)
				)
			)
		)
		(property "Value" ""
			(at 0 0 90)
			(layer "F.Fab")
			(effects
				(font
					(size 1.27 1.27)
				)
			)
		)
		(duplicate_pad_numbers_are_jumpers no)
		(fp_line
			(start 0.7874 -0.4064)
			(end 0.7874 0.4064)
			(stroke
				(width 0.1524)
				(type default)
			)
			(layer "F.SilkS")
		)
		(fp_line
			(start -0.7874 -0.4064)
			(end 0.7874 -0.4064)
			(stroke
				(width 0.1524)
				(type default)
			)
			(layer "F.SilkS")
		)
		(fp_line
			(start 0.7874 0.4064)
			(end 0.413512 0.4064)
			(stroke
				(width 0.1524)
				(type default)
			)
			(layer "F.SilkS")
		)
		(fp_line
			(start -0.272288 0.4064)
			(end -0.7874 0.4064)
			(stroke
				(width 0.1524)
				(type default)
			)
			(layer "F.SilkS")
		)
		(fp_line
			(start -0.7874 0.4064)
			(end -0.7874 -0.4064)
			(stroke
				(width 0.1524)
				(type default)
			)
			(layer "F.SilkS")
		)
		(fp_line
			(start -0.12065 -0.305054)
			(end -0.12065 -0.2794)
			(stroke
				(width 0.1)
				(type default)
			)
			(layer "F.Fab")
		)
		(fp_line
			(start -0.67945 -0.305054)
			(end -0.12065 -0.305054)
			(stroke
				(width 0.1)
				(type default)
			)
			(layer "F.Fab")
		)
		(fp_line
			(start 0.67945 -0.3048)
			(end 0.67945 0.3048)
			(stroke
				(width 0.1)
				(type default)
			)
			(layer "F.Fab")
		)
		(fp_line
			(start 0.12065 -0.3048)
			(end 0.67945 -0.3048)
			(stroke
				(width 0.1)
				(type default)
			)
			(layer "F.Fab")
		)
		(fp_line
			(start 0.12065 -0.2794)
			(end 0.12065 -0.3048)
			(stroke
				(width 0.1)
				(type default)
			)
			(layer "F.Fab")
		)
		(fp_line
			(start -0.12065 -0.2794)
			(end 0.12065 -0.2794)
			(stroke
				(width 0.1)
				(type default)
			)
			(layer "F.Fab")
		)
		(fp_line
			(start 0.120396 0.2794)
			(end -0.12065 0.2794)
			(stroke
				(width 0.1)
				(type default)
			)
			(layer "F.Fab")
		)
		(fp_line
			(start -0.12065 0.2794)
			(end -0.12065 0.3048)
			(stroke
				(width 0.1)
				(type default)
			)
			(layer "F.Fab")
		)
		(fp_line
			(start 0.67945 0.3048)
			(end 0.120396 0.3048)
			(stroke
				(width 0.1)
				(type default)
			)
			(layer "F.Fab")
		)
		(fp_line
			(start 0.120396 0.3048)
			(end 0.120396 0.2794)
			(stroke
				(width 0.1)
				(type default)
			)
			(layer "F.Fab")
		)
		(fp_line
			(start -0.12065 0.3048)
			(end -0.67945 0.3048)
			(stroke
				(width 0.1)
				(type default)
			)
			(layer "F.Fab")
		)
		(fp_line
			(start -0.67945 0.3048)
			(end -0.67945 -0.305054)
			(stroke
				(width 0.1)
				(type default)
			)
			(layer "F.Fab")
		)
		(pad "1" smd circle
			(at -0.40005 0 90)
			(size 0 0)
			(layers "F.Cu" "F.Mask" "F.Paste")
			(net "PVDDCR_CPU1_P0_VCC3")
		)
		(pad "2" smd circle
			(at 0.40005 0 90)
			(size 0 0)
			(layers "F.Cu" "F.Mask" "F.Paste")
			(net "GND")
		)
	)
	(footprint ""
		(layer "F.Cu")
		(at 324.516496 -378.95403 -90)
		(property "Reference" "C906"
			(at 0 0 270)
			(layer "F.SilkS")
			(hide yes)
			(effects
				(font
					(size 1.27 1.27)
				)
			)
		)
		(property "Value" ""
			(at 0 0 270)
			(layer "F.Fab")
			(effects
				(font
					(size 1.27 1.27)
				)
			)
		)
		(duplicate_pad_numbers_are_jumpers no)
		(fp_line
			(start -0.299974 0.150114)
			(end -0.299974 -0.150114)
			(stroke
				(width 0.1)
				(type default)
			)
			(layer "F.Fab")
		)
		(fp_line
			(start 0.299974 0.150114)
			(end -0.299974 0.150114)
			(stroke
				(width 0.1)
				(type default)
			)
			(layer "F.Fab")
		)
		(fp_line
			(start -0.299974 -0.150114)
			(end 0.299974 -0.150114)
			(stroke
				(width 0.1)
				(type default)
			)
			(layer "F.Fab")
		)
		(fp_line
			(start 0.299974 -0.150114)
			(end 0.299974 0.150114)
			(stroke
				(width 0.1)
				(type default)
			)
			(layer "F.Fab")
		)
		(pad "1" smd rect
			(at -0.2667 0 270)
			(size 0.3048 0.381)
			(layers "F.Cu" "F.Mask" "F.Paste")
			(net "P5E_CPU0_P0_TX_C_DN<13>")
		)
		(pad "2" smd rect
			(at 0.2667 0 270)
			(size 0.3048 0.381)
			(layers "F.Cu" "F.Mask" "F.Paste")
			(net "P5E_CPU0_P0_TX_DN<13>")
		)
	)
	(footprint ""
		(layer "F.Cu")
		(at 241.403378 -315.82868 90)
		(property "Reference" "PC6513"
			(at -1.75768 9.956292 90)
			(unlocked yes)
			(layer "F.SilkS")
			(effects
				(font
					(size 0.7874 0.5842)
					(thickness 0.1524)
				)
				(justify left)
			)
		)
		(property "Value" ""
			(at 0 0 90)
			(layer "F.Fab")
			(effects
				(font
					(size 1.27 1.27)
				)
			)
		)
		(duplicate_pad_numbers_are_jumpers no)
		(fp_line
			(start 2.750058 -2.750058)
			(end -1.988058 -2.750058)
			(stroke
				(width 0.1524)
				(type default)
			)
			(layer "F.SilkS")
		)
		(fp_line
			(start -1.988058 -2.750058)
			(end -2.750058 -1.988058)
			(stroke
				(width 0.1524)
				(type default)
			)
			(layer "F.SilkS")
		)
		(fp_line
			(start -2.750058 -1.988058)
			(end -2.750058 -0.9398)
			(stroke
				(width 0.1524)
				(type default)
			)
			(layer "F.SilkS")
		)
		(fp_line
			(start 2.750058 -0.9398)
			(end 2.750058 -2.750058)
			(stroke
				(width 0.1524)
				(type default)
			)
			(layer "F.SilkS")
		)
		(fp_line
			(start -2.750058 0.9398)
			(end -2.750058 1.988058)
			(stroke
				(width 0.1524)
				(type default)
			)
			(layer "F.SilkS")
		)
		(fp_line
			(start -2.750058 1.988058)
			(end -1.988058 2.750058)
			(stroke
				(width 0.1524)
				(type default)
			)
			(layer "F.SilkS")
		)
		(fp_line
			(start 2.750058 2.750058)
			(end 2.750058 0.9398)
			(stroke
				(width 0.1524)
				(type default)
			)
			(layer "F.SilkS")
		)
		(fp_line
			(start -1.988058 2.750058)
			(end 2.750058 2.750058)
			(stroke
				(width 0.1524)
				(type default)
			)
			(layer "F.SilkS")
		)
		(fp_line
			(start 2.750058 -2.750058)
			(end -2.750058 -2.750058)
			(stroke
				(width 0.1)
				(type default)
			)
			(layer "F.Fab")
		)
		(fp_line
			(start -2.750058 -2.750058)
			(end -2.750058 2.750058)
			(stroke
				(width 0.1)
				(type default)
			)
			(layer "F.Fab")
		)
		(fp_line
			(start 2.750058 2.750058)
			(end 2.750058 -2.750058)
			(stroke
				(width 0.1)
				(type default)
			)
			(layer "F.Fab")
		)
		(fp_line
			(start -2.750058 2.750058)
			(end 2.750058 2.750058)
			(stroke
				(width 0.1)
				(type default)
			)
			(layer "F.Fab")
		)
		(pad "1" smd rect
			(at -2.199894 0 180)
			(size 1.6002 3.0226)
			(layers "F.Cu" "F.Mask" "F.Paste")
			(net "P1V8_CPU0_RT_1D")
		)
		(pad "2" smd rect
			(at 2.199894 0 180)
			(size 1.6002 3.0226)
			(layers "F.Cu" "F.Mask" "F.Paste")
			(net "GND")
		)
	)
	(footprint ""
		(layer "F.Cu")
		(at 154.690064 -69.665088 -90)
		(property "Reference" "J57"
			(at 2.393696 1.000252 0)
			(unlocked yes)
			(layer "F.SilkS")
			(effects
				(font
					(size 0.7874 0.5842)
					(thickness 0.1524)
				)
				(justify left)
			)
		)
		(property "Value" ""
			(at 0 0 270)
			(layer "F.Fab")
			(effects
				(font
					(size 1.27 1.27)
				)
			)
		)
		(duplicate_pad_numbers_are_jumpers no)
		(fp_line
			(start -1.234948 19.05)
			(end -1.234948 -1.27)
			(stroke
				(width 0.1524)
				(type default)
			)
			(layer "F.SilkS")
		)
		(fp_line
			(start 1.234948 19.05)
			(end -1.234948 19.05)
			(stroke
				(width 0.1524)
				(type default)
			)
			(layer "F.SilkS")
		)
		(fp_line
			(start -1.234948 -1.27)
			(end 1.234948 -1.27)
			(stroke
				(width 0.1524)
				(type default)
			)
			(layer "F.SilkS")
		)
		(fp_line
			(start 1.234948 -1.27)
			(end 1.234948 19.05)
			(stroke
				(width 0.1524)
				(type default)
			)
			(layer "F.SilkS")
		)
		(fp_poly
			(pts
				(xy -2.8194 0.635) (xy -2.8194 -0.5842) (xy -1.4986 0)
			)
			(stroke
				(width 0)
				(type default)
			)
			(fill yes)
			(layer "F.SilkS")
		)
		(fp_line
			(start -1.23698 19.05)
			(end -1.23698 -1.27)
			(stroke
				(width 0.1)
				(type default)
			)
			(layer "F.Fab")
		)
		(fp_line
			(start 1.23698 19.05)
			(end -1.23698 19.05)
			(stroke
				(width 0.1)
				(type default)
			)
			(layer "F.Fab")
		)
		(fp_line
			(start -1.23698 -1.27)
			(end 1.23698 -1.27)
			(stroke
				(width 0.1)
				(type default)
			)
			(layer "F.Fab")
		)
		(fp_line
			(start 1.23698 -1.27)
			(end 1.23698 19.05)
			(stroke
				(width 0.1)
				(type default)
			)
			(layer "F.Fab")
		)
		(fp_poly
			(pts
				(xy -1.4986 0) (xy -2.8194 -0.5842) (xy -2.8194 0.635)
			)
			(stroke
				(width 0)
				(type default)
			)
			(fill yes)
			(layer "F.Fab")
		)
		(fp_text user "8"
			(at -1.886966 18.1737 0)
			(unlocked yes)
			(layer "F.SilkS")
			(effects
				(font
					(size 0.7874 0.5842)
					(thickness 0.1524)
				)
				(justify left)
			)
		)
		(fp_text user "8"
			(at -0.085852 19.3421 180)
			(unlocked yes)
			(layer "B.SilkS")
			(effects
				(font
					(size 0.7874 0.5842)
					(thickness 0.1524)
				)
				(justify left mirror)
			)
		)
		(fp_text user "1"
			(at 0.015748 -0.9271 180)
			(unlocked yes)
			(layer "B.SilkS")
			(effects
				(font
					(size 0.7874 0.5842)
					(thickness 0.1524)
				)
				(justify left mirror)
			)
		)
		(fp_text user "8"
			(at -0.085852 19.3421 180)
			(unlocked yes)
			(layer "B.Fab")
			(effects
				(font
					(size 0.7874 0.5842)
					(thickness 0.1524)
				)
				(justify left mirror)
			)
		)
		(fp_text user "1"
			(at 0.015748 -0.9271 180)
			(unlocked yes)
			(layer "B.Fab")
			(effects
				(font
					(size 0.7874 0.5842)
					(thickness 0.1524)
				)
				(justify left mirror)
			)
		)
		(fp_text user "8"
			(at -1.965706 17.5895 180)
			(unlocked yes)
			(layer "F.Fab")
			(effects
				(font
					(size 0.7874 0.5842)
					(thickness 0.1524)
				)
				(justify left)
			)
		)
		(pad "1" thru_hole rect
			(at 0 0 180)
			(size 1.6764 1.6764)
			(drill 1.1684)
			(layers "*.Cu" "*.Mask")
			(remove_unused_layers no)
			(net "P3V3_AUX")
			(clearance 0)
			(padstack
				(mode front_inner_back)
				(layer "Inner"
					(shape circle)
					(size 1.6764 1.6764)
					(clearance 0)
				)
				(layer "B.Cu"
					(shape rect)
					(size 1.6764 1.6764)
					(clearance 0)
				)
			)
		)
		(pad "2" thru_hole circle
			(at 0 2.54 180)
			(size 1.6764 1.6764)
			(drill 1.1684)
			(layers "*.Cu" "*.Mask")
			(remove_unused_layers no)
			(net "JTAG_PLD_TDI")
			(clearance 0)
		)
		(pad "3" thru_hole circle
			(at 0 5.08 180)
			(size 1.6764 1.6764)
			(drill 1.1684)
			(layers "*.Cu" "*.Mask")
			(remove_unused_layers no)
			(net "JTAG_PLD_TDO")
			(clearance 0)
		)
		(pad "4" thru_hole circle
			(at 0 7.62 180)
			(size 1.6764 1.6764)
			(drill 1.1684)
			(layers "*.Cu" "*.Mask")
			(remove_unused_layers no)
			(net "Net_10747")
			(clearance 0)
		)
		(pad "5" thru_hole circle
			(at 0 10.16 180)
			(size 1.6764 1.6764)
			(drill 1.1684)
			(layers "*.Cu" "*.Mask")
			(remove_unused_layers no)
			(net "Net_10746")
			(clearance 0)
		)
		(pad "6" thru_hole circle
			(at 0 12.7 180)
			(size 1.6764 1.6764)
			(drill 1.1684)
			(layers "*.Cu" "*.Mask")
			(remove_unused_layers no)
			(net "JTAG_PLD_TMS")
			(clearance 0)
		)
		(pad "7" thru_hole circle
			(at 0 15.24 180)
			(size 1.6764 1.6764)
			(drill 1.1684)
			(layers "*.Cu" "*.Mask")
			(remove_unused_layers no)
			(net "GND")
			(clearance 0)
		)
		(pad "8" thru_hole circle
			(at 0 17.78 180)
			(size 1.6764 1.6764)
			(drill 1.1684)
			(layers "*.Cu" "*.Mask")
			(remove_unused_layers no)
			(net "JTAG_PLD_TCK")
			(clearance 0)
		)
	)
	(footprint ""
		(layer "F.Cu")
		(at 16.364458 -418.690298 90)
		(property "Reference" "R6179"
			(at 0 0 90)
			(layer "F.SilkS")
			(hide yes)
			(effects
				(font
					(size 1.27 1.27)
				)
			)
		)
		(property "Value" ""
			(at 0 0 90)
			(layer "F.Fab")
			(effects
				(font
					(size 1.27 1.27)
				)
			)
		)
		(duplicate_pad_numbers_are_jumpers no)
		(fp_line
			(start 0.7874 -0.4064)
			(end 0.7874 0.4064)
			(stroke
				(width 0.1524)
				(type default)
			)
			(layer "F.SilkS")
		)
		(fp_line
			(start -0.7874 -0.4064)
			(end 0.7874 -0.4064)
			(stroke
				(width 0.1524)
				(type default)
			)
			(layer "F.SilkS")
		)
		(fp_line
			(start 0.7874 0.4064)
			(end -0.7874 0.4064)
			(stroke
				(width 0.1524)
				(type default)
			)
			(layer "F.SilkS")
		)
		(fp_line
			(start -0.7874 0.4064)
			(end -0.7874 -0.4064)
			(stroke
				(width 0.1524)
				(type default)
			)
			(layer "F.SilkS")
		)
		(fp_line
			(start -0.12065 -0.305054)
			(end -0.12065 -0.2794)
			(stroke
				(width 0.1)
				(type default)
			)
			(layer "F.Fab")
		)
		(fp_line
			(start -0.67945 -0.305054)
			(end -0.12065 -0.305054)
			(stroke
				(width 0.1)
				(type default)
			)
			(layer "F.Fab")
		)
		(fp_line
			(start 0.67945 -0.3048)
			(end 0.67945 0.3048)
			(stroke
				(width 0.1)
				(type default)
			)
			(layer "F.Fab")
		)
		(fp_line
			(start 0.12065 -0.3048)
			(end 0.67945 -0.3048)
			(stroke
				(width 0.1)
				(type default)
			)
			(layer "F.Fab")
		)
		(fp_line
			(start 0.12065 -0.2794)
			(end 0.12065 -0.3048)
			(stroke
				(width 0.1)
				(type default)
			)
			(layer "F.Fab")
		)
		(fp_line
			(start -0.12065 -0.2794)
			(end 0.12065 -0.2794)
			(stroke
				(width 0.1)
				(type default)
			)
			(layer "F.Fab")
		)
		(fp_line
			(start 0.120396 0.2794)
			(end -0.12065 0.2794)
			(stroke
				(width 0.1)
				(type default)
			)
			(layer "F.Fab")
		)
		(fp_line
			(start -0.12065 0.2794)
			(end -0.12065 0.3048)
			(stroke
				(width 0.1)
				(type default)
			)
			(layer "F.Fab")
		)
		(fp_line
			(start 0.67945 0.3048)
			(end 0.120396 0.3048)
			(stroke
				(width 0.1)
				(type default)
			)
			(layer "F.Fab")
		)
		(fp_line
			(start 0.120396 0.3048)
			(end 0.120396 0.2794)
			(stroke
				(width 0.1)
				(type default)
			)
			(layer "F.Fab")
		)
		(fp_line
			(start -0.12065 0.3048)
			(end -0.67945 0.3048)
			(stroke
				(width 0.1)
				(type default)
			)
			(layer "F.Fab")
		)
		(fp_line
			(start -0.67945 0.3048)
			(end -0.67945 -0.305054)
			(stroke
				(width 0.1)
				(type default)
			)
			(layer "F.Fab")
		)
		(pad "1" smd circle
			(at -0.40005 0 90)
			(size 0 0)
			(layers "F.Cu" "F.Mask" "F.Paste")
			(net "P3V3_AUX")
		)
		(pad "2" smd circle
			(at 0.40005 0 90)
			(size 0 0)
			(layers "F.Cu" "F.Mask" "F.Paste")
			(net "FM_P2E_BUF2_VOD_SEL")
		)
	)
	(footprint ""
		(layer "F.Cu")
		(at 359.416096 -256.012188 90)
		(property "Reference" "C3929"
			(at 0 0 90)
			(layer "F.SilkS")
			(hide yes)
			(effects
				(font
					(size 1.27 1.27)
				)
			)
		)
		(property "Value" ""
			(at 0 0 90)
			(layer "F.Fab")
			(effects
				(font
					(size 1.27 1.27)
				)
			)
		)
		(duplicate_pad_numbers_are_jumpers no)
		(fp_line
			(start 0.7874 -0.4064)
			(end 0.7874 0.4064)
			(stroke
				(width 0.1524)
				(type default)
			)
			(layer "F.SilkS")
		)
		(fp_line
			(start -0.7874 -0.4064)
			(end 0.7874 -0.4064)
			(stroke
				(width 0.1524)
				(type default)
			)
			(layer "F.SilkS")
		)
		(fp_line
			(start 0.7874 0.4064)
			(end -0.7874 0.4064)
			(stroke
				(width 0.1524)
				(type default)
			)
			(layer "F.SilkS")
		)
		(fp_line
			(start -0.7874 0.4064)
			(end -0.7874 -0.4064)
			(stroke
				(width 0.1524)
				(type default)
			)
			(layer "F.SilkS")
		)
		(fp_line
			(start -0.12065 -0.305054)
			(end -0.12065 -0.2794)
			(stroke
				(width 0.1)
				(type default)
			)
			(layer "F.Fab")
		)
		(fp_line
			(start -0.67945 -0.305054)
			(end -0.12065 -0.305054)
			(stroke
				(width 0.1)
				(type default)
			)
			(layer "F.Fab")
		)
		(fp_line
			(start 0.67945 -0.3048)
			(end 0.67945 0.3048)
			(stroke
				(width 0.1)
				(type default)
			)
			(layer "F.Fab")
		)
		(fp_line
			(start 0.12065 -0.3048)
			(end 0.67945 -0.3048)
			(stroke
				(width 0.1)
				(type default)
			)
			(layer "F.Fab")
		)
		(fp_line
			(start 0.12065 -0.2794)
			(end 0.12065 -0.3048)
			(stroke
				(width 0.1)
				(type default)
			)
			(layer "F.Fab")
		)
		(fp_line
			(start -0.12065 -0.2794)
			(end 0.12065 -0.2794)
			(stroke
				(width 0.1)
				(type default)
			)
			(layer "F.Fab")
		)
		(fp_line
			(start 0.120396 0.2794)
			(end -0.12065 0.2794)
			(stroke
				(width 0.1)
				(type default)
			)
			(layer "F.Fab")
		)
		(fp_line
			(start -0.12065 0.2794)
			(end -0.12065 0.3048)
			(stroke
				(width 0.1)
				(type default)
			)
			(layer "F.Fab")
		)
		(fp_line
			(start 0.67945 0.3048)
			(end 0.120396 0.3048)
			(stroke
				(width 0.1)
				(type default)
			)
			(layer "F.Fab")
		)
		(fp_line
			(start 0.120396 0.3048)
			(end 0.120396 0.2794)
			(stroke
				(width 0.1)
				(type default)
			)
			(layer "F.Fab")
		)
		(fp_line
			(start -0.12065 0.3048)
			(end -0.67945 0.3048)
			(stroke
				(width 0.1)
				(type default)
			)
			(layer "F.Fab")
		)
		(fp_line
			(start -0.67945 0.3048)
			(end -0.67945 -0.305054)
			(stroke
				(width 0.1)
				(type default)
			)
			(layer "F.Fab")
		)
		(pad "1" smd circle
			(at -0.40005 0 90)
			(size 0 0)
			(layers "F.Cu" "F.Mask" "F.Paste")
			(net "PVDDCR_SOC_P0")
		)
		(pad "2" smd circle
			(at 0.40005 0 90)
			(size 0 0)
			(layers "F.Cu" "F.Mask" "F.Paste")
			(net "GND")
		)
	)
	(footprint ""
		(layer "F.Cu")
		(at 75.517502 -373.03583 -90)
		(property "Reference" "C737"
			(at 0 0 270)
			(layer "F.SilkS")
			(hide yes)
			(effects
				(font
					(size 1.27 1.27)
				)
			)
		)
		(property "Value" ""
			(at 0 0 270)
			(layer "F.Fab")
			(effects
				(font
					(size 1.27 1.27)
				)
			)
		)
		(duplicate_pad_numbers_are_jumpers no)
		(fp_line
			(start -0.299974 0.150114)
			(end -0.299974 -0.150114)
			(stroke
				(width 0.1)
				(type default)
			)
			(layer "F.Fab")
		)
		(fp_line
			(start 0.299974 0.150114)
			(end -0.299974 0.150114)
			(stroke
				(width 0.1)
				(type default)
			)
			(layer "F.Fab")
		)
		(fp_line
			(start -0.299974 -0.150114)
			(end 0.299974 -0.150114)
			(stroke
				(width 0.1)
				(type default)
			)
			(layer "F.Fab")
		)
		(fp_line
			(start 0.299974 -0.150114)
			(end 0.299974 0.150114)
			(stroke
				(width 0.1)
				(type default)
			)
			(layer "F.Fab")
		)
		(pad "1" smd rect
			(at -0.2667 0 270)
			(size 0.3048 0.381)
			(layers "F.Cu" "F.Mask" "F.Paste")
			(net "P5E_CPU1_P1_TX_C_DP<2>")
		)
		(pad "2" smd rect
			(at 0.2667 0 270)
			(size 0.3048 0.381)
			(layers "F.Cu" "F.Mask" "F.Paste")
			(net "P5E_CPU1_P1_TX_DP<2>")
		)
	)
	(footprint ""
		(layer "F.Cu")
		(at 61.81471 -337.403948)
		(property "Reference" "PL43"
			(at -3.115056 -15.633446 0)
			(unlocked yes)
			(layer "F.SilkS")
			(effects
				(font
					(size 0.7874 0.5842)
					(thickness 0.1524)
				)
				(justify left)
			)
		)
		(property "Value" ""
			(at 0 0 0)
			(layer "F.Fab")
			(effects
				(font
					(size 1.27 1.27)
				)
			)
		)
		(duplicate_pad_numbers_are_jumpers no)
		(fp_line
			(start -3.750056 -5.500116)
			(end -2.393442 -5.500116)
			(stroke
				(width 0.1524)
				(type default)
			)
			(layer "F.SilkS")
		)
		(fp_line
			(start -3.750056 5.500116)
			(end -3.750056 -5.500116)
			(stroke
				(width 0.1524)
				(type default)
			)
			(layer "F.SilkS")
		)
		(fp_line
			(start -2.393442 5.500116)
			(end -3.750056 5.500116)
			(stroke
				(width 0.1524)
				(type default)
			)
			(layer "F.SilkS")
		)
		(fp_line
			(start 2.393442 5.500116)
			(end 3.750056 5.500116)
			(stroke
				(width 0.1524)
				(type default)
			)
			(layer "F.SilkS")
		)
		(fp_line
			(start 3.750056 -5.500116)
			(end 2.393442 -5.500116)
			(stroke
				(width 0.1524)
				(type default)
			)
			(layer "F.SilkS")
		)
		(fp_line
			(start 3.750056 5.500116)
			(end 3.750056 -5.500116)
			(stroke
				(width 0.1524)
				(type default)
			)
			(layer "F.SilkS")
		)
		(fp_poly
			(pts
				(xy -3.9116 -4.249928) (xy -4.3434 -4.034028) (xy -4.3434 -4.465828)
			)
			(stroke
				(width 0)
				(type default)
			)
			(fill yes)
			(layer "F.SilkS")
		)
		(fp_line
			(start -3.750056 -5.500116)
			(end -3.750056 5.500116)
			(stroke
				(width 0.1)
				(type default)
			)
			(layer "F.Fab")
		)
		(fp_line
			(start -3.750056 5.500116)
			(end 3.750056 5.500116)
			(stroke
				(width 0.1)
				(type default)
			)
			(layer "F.Fab")
		)
		(fp_line
			(start 3.750056 -5.500116)
			(end -3.750056 -5.500116)
			(stroke
				(width 0.1)
				(type default)
			)
			(layer "F.Fab")
		)
		(fp_line
			(start 3.750056 5.500116)
			(end 3.750056 -5.500116)
			(stroke
				(width 0.1)
				(type default)
			)
			(layer "F.Fab")
		)
		(fp_poly
			(pts
				(xy -4.9276 -4.757928) (xy -4.9276 -3.741928) (xy -3.9116 -4.249928)
			)
			(stroke
				(width 0)
				(type default)
			)
			(fill yes)
			(layer "F.Fab")
		)
		(pad "1" smd rect
			(at 0 -4.249928 270)
			(size 2.413 4.5212)
			(layers "F.Cu" "F.Mask" "F.Paste")
			(net "SW_PVDDCR_CPU1_P1_SW4")
		)
		(pad "2" smd rect
			(at 0 -1.175004 270)
			(size 1.3716 4.5212)
			(layers "F.Cu" "F.Mask" "F.Paste")
			(net "IND_CPU1_P1_CPL3")
		)
		(pad "3" smd rect
			(at 0 1.175004 270)
			(size 1.3716 4.5212)
			(layers "F.Cu" "F.Mask" "F.Paste")
			(net "GND")
		)
		(pad "4" smd rect
			(at 0 4.249928 270)
			(size 2.413 4.5212)
			(layers "F.Cu" "F.Mask" "F.Paste")
			(net "PVDDCR_CPU1_P1")
		)
	)
	(footprint ""
		(layer "F.Cu")
		(at 204.7621 -408.084782)
		(property "Reference" "PR3917"
			(at 0 0 0)
			(layer "F.SilkS")
			(hide yes)
			(effects
				(font
					(size 1.27 1.27)
				)
			)
		)
		(property "Value" ""
			(at 0 0 0)
			(layer "F.Fab")
			(effects
				(font
					(size 1.27 1.27)
				)
			)
		)
		(duplicate_pad_numbers_are_jumpers no)
		(fp_line
			(start -0.7874 -0.4064)
			(end 0.7874 -0.4064)
			(stroke
				(width 0.1524)
				(type default)
			)
			(layer "F.SilkS")
		)
		(fp_line
			(start -0.7874 0.4064)
			(end -0.7874 -0.4064)
			(stroke
				(width 0.1524)
				(type default)
			)
			(layer "F.SilkS")
		)
		(fp_line
			(start 0.7874 -0.4064)
			(end 0.7874 0.4064)
			(stroke
				(width 0.1524)
				(type default)
			)
			(layer "F.SilkS")
		)
		(fp_line
			(start 0.7874 0.4064)
			(end -0.7874 0.4064)
			(stroke
				(width 0.1524)
				(type default)
			)
			(layer "F.SilkS")
		)
		(fp_line
			(start -0.67945 -0.305054)
			(end -0.12065 -0.305054)
			(stroke
				(width 0.1)
				(type default)
			)
			(layer "F.Fab")
		)
		(fp_line
			(start -0.67945 0.3048)
			(end -0.67945 -0.305054)
			(stroke
				(width 0.1)
				(type default)
			)
			(layer "F.Fab")
		)
		(fp_line
			(start -0.12065 -0.305054)
			(end -0.12065 -0.2794)
			(stroke
				(width 0.1)
				(type default)
			)
			(layer "F.Fab")
		)
		(fp_line
			(start -0.12065 -0.2794)
			(end 0.12065 -0.2794)
			(stroke
				(width 0.1)
				(type default)
			)
			(layer "F.Fab")
		)
		(fp_line
			(start -0.12065 0.2794)
			(end -0.12065 0.3048)
			(stroke
				(width 0.1)
				(type default)
			)
			(layer "F.Fab")
		)
		(fp_line
			(start -0.12065 0.3048)
			(end -0.67945 0.3048)
			(stroke
				(width 0.1)
				(type default)
			)
			(layer "F.Fab")
		)
		(fp_line
			(start 0.120396 0.2794)
			(end -0.12065 0.2794)
			(stroke
				(width 0.1)
				(type default)
			)
			(layer "F.Fab")
		)
		(fp_line
			(start 0.120396 0.3048)
			(end 0.120396 0.2794)
			(stroke
				(width 0.1)
				(type default)
			)
			(layer "F.Fab")
		)
		(fp_line
			(start 0.12065 -0.3048)
			(end 0.67945 -0.3048)
			(stroke
				(width 0.1)
				(type default)
			)
			(layer "F.Fab")
		)
		(fp_line
			(start 0.12065 -0.2794)
			(end 0.12065 -0.3048)
			(stroke
				(width 0.1)
				(type default)
			)
			(layer "F.Fab")
		)
		(fp_line
			(start 0.67945 -0.3048)
			(end 0.67945 0.3048)
			(stroke
				(width 0.1)
				(type default)
			)
			(layer "F.Fab")
		)
		(fp_line
			(start 0.67945 0.3048)
			(end 0.120396 0.3048)
			(stroke
				(width 0.1)
				(type default)
			)
			(layer "F.Fab")
		)
		(pad "1" smd circle
			(at -0.40005 0)
			(size 0 0)
			(layers "F.Cu" "F.Mask" "F.Paste")
			(net "HSC_SCREF")
		)
		(pad "2" smd circle
			(at 0.40005 0)
			(size 0 0)
			(layers "F.Cu" "F.Mask" "F.Paste")
			(net "HSC_SCREF_2")
		)
	)
	(footprint ""
		(layer "F.Cu")
		(at 104.1908 -392.2268)
		(property "Reference" "R1372"
			(at 0 0 0)
			(layer "F.SilkS")
			(hide yes)
			(effects
				(font
					(size 1.27 1.27)
				)
			)
		)
		(property "Value" ""
			(at 0 0 0)
			(layer "F.Fab")
			(effects
				(font
					(size 1.27 1.27)
				)
			)
		)
		(duplicate_pad_numbers_are_jumpers no)
		(fp_line
			(start -0.32512 -0.175006)
			(end 0.32512 -0.175006)
			(stroke
				(width 0.1)
				(type default)
			)
			(layer "F.Fab")
		)
		(fp_line
			(start -0.32512 0.175006)
			(end -0.32512 -0.175006)
			(stroke
				(width 0.1)
				(type default)
			)
			(layer "F.Fab")
		)
		(fp_line
			(start 0.32512 -0.175006)
			(end 0.32512 0.175006)
			(stroke
				(width 0.1)
				(type default)
			)
			(layer "F.Fab")
		)
		(fp_line
			(start 0.32512 0.175006)
			(end -0.32512 0.175006)
			(stroke
				(width 0.1)
				(type default)
			)
			(layer "F.Fab")
		)
		(pad "1" smd rect
			(at -0.2667 0)
			(size 0.3048 0.381)
			(layers "F.Cu" "F.Mask" "F.Paste")
			(net "JTAG_TRST_RT_CPU1_P1_N")
		)
		(pad "2" smd rect
			(at 0.2667 0 180)
			(size 0.3048 0.381)
			(layers "F.Cu" "F.Mask" "F.Paste")
			(net "GND")
		)
	)
	(footprint ""
		(layer "F.Cu")
		(at 331.365098 -331.969364 180)
		(property "Reference" "PC189"
			(at 0 0 180)
			(layer "F.SilkS")
			(hide yes)
			(effects
				(font
					(size 1.27 1.27)
				)
			)
		)
		(property "Value" ""
			(at 0 0 180)
			(layer "F.Fab")
			(effects
				(font
					(size 1.27 1.27)
				)
			)
		)
		(duplicate_pad_numbers_are_jumpers no)
		(fp_line
			(start 0.7874 0.4064)
			(end -0.7874 0.4064)
			(stroke
				(width 0.1524)
				(type default)
			)
			(layer "F.SilkS")
		)
		(fp_line
			(start 0.7874 -0.4064)
			(end 0.7874 0.4064)
			(stroke
				(width 0.1524)
				(type default)
			)
			(layer "F.SilkS")
		)
		(fp_line
			(start -0.7874 0.4064)
			(end -0.7874 -0.4064)
			(stroke
				(width 0.1524)
				(type default)
			)
			(layer "F.SilkS")
		)
		(fp_line
			(start -0.7874 -0.4064)
			(end 0.7874 -0.4064)
			(stroke
				(width 0.1524)
				(type default)
			)
			(layer "F.SilkS")
		)
		(fp_line
			(start 0.67945 0.3048)
			(end 0.120396 0.3048)
			(stroke
				(width 0.1)
				(type default)
			)
			(layer "F.Fab")
		)
		(fp_line
			(start 0.67945 -0.3048)
			(end 0.67945 0.3048)
			(stroke
				(width 0.1)
				(type default)
			)
			(layer "F.Fab")
		)
		(fp_line
			(start 0.12065 -0.2794)
			(end 0.12065 -0.3048)
			(stroke
				(width 0.1)
				(type default)
			)
			(layer "F.Fab")
		)
		(fp_line
			(start 0.12065 -0.3048)
			(end 0.67945 -0.3048)
			(stroke
				(width 0.1)
				(type default)
			)
			(layer "F.Fab")
		)
		(fp_line
			(start 0.120396 0.3048)
			(end 0.120396 0.2794)
			(stroke
				(width 0.1)
				(type default)
			)
			(layer "F.Fab")
		)
		(fp_line
			(start 0.120396 0.2794)
			(end -0.12065 0.2794)
			(stroke
				(width 0.1)
				(type default)
			)
			(layer "F.Fab")
		)
		(fp_line
			(start -0.12065 0.3048)
			(end -0.67945 0.3048)
			(stroke
				(width 0.1)
				(type default)
			)
			(layer "F.Fab")
		)
		(fp_line
			(start -0.12065 0.2794)
			(end -0.12065 0.3048)
			(stroke
				(width 0.1)
				(type default)
			)
			(layer "F.Fab")
		)
		(fp_line
			(start -0.12065 -0.2794)
			(end 0.12065 -0.2794)
			(stroke
				(width 0.1)
				(type default)
			)
			(layer "F.Fab")
		)
		(fp_line
			(start -0.12065 -0.305054)
			(end -0.12065 -0.2794)
			(stroke
				(width 0.1)
				(type default)
			)
			(layer "F.Fab")
		)
		(fp_line
			(start -0.67945 0.3048)
			(end -0.67945 -0.305054)
			(stroke
				(width 0.1)
				(type default)
			)
			(layer "F.Fab")
		)
		(fp_line
			(start -0.67945 -0.305054)
			(end -0.12065 -0.305054)
			(stroke
				(width 0.1)
				(type default)
			)
			(layer "F.Fab")
		)
		(pad "1" smd circle
			(at -0.40005 0 180)
			(size 0 0)
			(layers "F.Cu" "F.Mask" "F.Paste")
			(net "SW_PVDDCR_CPU1_P0_SW1")
		)
		(pad "2" smd circle
			(at 0.40005 0 180)
			(size 0 0)
			(layers "F.Cu" "F.Mask" "F.Paste")
			(net "SW_PVDDCR_CPU1_P0_SW1_RC")
		)
	)
	(footprint ""
		(layer "F.Cu")
		(at 103.886 -426.466 -90)
		(property "Reference" "R3488"
			(at 0 0 270)
			(layer "F.SilkS")
			(hide yes)
			(effects
				(font
					(size 1.27 1.27)
				)
			)
		)
		(property "Value" ""
			(at 0 0 270)
			(layer "F.Fab")
			(effects
				(font
					(size 1.27 1.27)
				)
			)
		)
		(duplicate_pad_numbers_are_jumpers no)
		(fp_line
			(start -0.7874 0.4064)
			(end -0.7874 -0.4064)
			(stroke
				(width 0.1524)
				(type default)
			)
			(layer "F.SilkS")
		)
		(fp_line
			(start 0.7874 0.4064)
			(end -0.7874 0.4064)
			(stroke
				(width 0.1524)
				(type default)
			)
			(layer "F.SilkS")
		)
		(fp_line
			(start -0.7874 -0.4064)
			(end 0.7874 -0.4064)
			(stroke
				(width 0.1524)
				(type default)
			)
			(layer "F.SilkS")
		)
		(fp_line
			(start 0.7874 -0.4064)
			(end 0.7874 0.4064)
			(stroke
				(width 0.1524)
				(type default)
			)
			(layer "F.SilkS")
		)
		(fp_line
			(start -0.67945 0.3048)
			(end -0.67945 -0.305054)
			(stroke
				(width 0.1)
				(type default)
			)
			(layer "F.Fab")
		)
		(fp_line
			(start -0.12065 0.3048)
			(end -0.67945 0.3048)
			(stroke
				(width 0.1)
				(type default)
			)
			(layer "F.Fab")
		)
		(fp_line
			(start 0.120396 0.3048)
			(end 0.120396 0.2794)
			(stroke
				(width 0.1)
				(type default)
			)
			(layer "F.Fab")
		)
		(fp_line
			(start 0.67945 0.3048)
			(end 0.120396 0.3048)
			(stroke
				(width 0.1)
				(type default)
			)
			(layer "F.Fab")
		)
		(fp_line
			(start -0.12065 0.2794)
			(end -0.12065 0.3048)
			(stroke
				(width 0.1)
				(type default)
			)
			(layer "F.Fab")
		)
		(fp_line
			(start 0.120396 0.2794)
			(end -0.12065 0.2794)
			(stroke
				(width 0.1)
				(type default)
			)
			(layer "F.Fab")
		)
		(fp_line
			(start -0.12065 -0.2794)
			(end 0.12065 -0.2794)
			(stroke
				(width 0.1)
				(type default)
			)
			(layer "F.Fab")
		)
		(fp_line
			(start 0.12065 -0.2794)
			(end 0.12065 -0.3048)
			(stroke
				(width 0.1)
				(type default)
			)
			(layer "F.Fab")
		)
		(fp_line
			(start 0.12065 -0.3048)
			(end 0.67945 -0.3048)
			(stroke
				(width 0.1)
				(type default)
			)
			(layer "F.Fab")
		)
		(fp_line
			(start 0.67945 -0.3048)
			(end 0.67945 0.3048)
			(stroke
				(width 0.1)
				(type default)
			)
			(layer "F.Fab")
		)
		(fp_line
			(start -0.67945 -0.305054)
			(end -0.12065 -0.305054)
			(stroke
				(width 0.1)
				(type default)
			)
			(layer "F.Fab")
		)
		(fp_line
			(start -0.12065 -0.305054)
			(end -0.12065 -0.2794)
			(stroke
				(width 0.1)
				(type default)
			)
			(layer "F.Fab")
		)
		(pad "1" smd circle
			(at -0.40005 0 270)
			(size 0 0)
			(layers "F.Cu" "F.Mask" "F.Paste")
			(net "P3V3_AUX")
		)
		(pad "2" smd circle
			(at 0.40005 0 270)
			(size 0 0)
			(layers "F.Cu" "F.Mask" "F.Paste")
			(net "GPU_FPGA_EROT_RST_N")
		)
	)
	(footprint ""
		(layer "F.Cu")
		(at 303.200308 -45.005498 180)
		(property "Reference" "C2051"
			(at 0 0 180)
			(layer "F.SilkS")
			(hide yes)
			(effects
				(font
					(size 1.27 1.27)
				)
			)
		)
		(property "Value" ""
			(at 0 0 180)
			(layer "F.Fab")
			(effects
				(font
					(size 1.27 1.27)
				)
			)
		)
		(duplicate_pad_numbers_are_jumpers no)
		(fp_line
			(start 0.7874 0.4064)
			(end -0.7874 0.4064)
			(stroke
				(width 0.1524)
				(type default)
			)
			(layer "F.SilkS")
		)
		(fp_line
			(start 0.7874 -0.4064)
			(end 0.7874 0.4064)
			(stroke
				(width 0.1524)
				(type default)
			)
			(layer "F.SilkS")
		)
		(fp_line
			(start -0.7874 0.4064)
			(end -0.7874 -0.4064)
			(stroke
				(width 0.1524)
				(type default)
			)
			(layer "F.SilkS")
		)
		(fp_line
			(start -0.7874 -0.4064)
			(end 0.7874 -0.4064)
			(stroke
				(width 0.1524)
				(type default)
			)
			(layer "F.SilkS")
		)
		(fp_line
			(start 0.67945 0.3048)
			(end 0.120396 0.3048)
			(stroke
				(width 0.1)
				(type default)
			)
			(layer "F.Fab")
		)
		(fp_line
			(start 0.67945 -0.3048)
			(end 0.67945 0.3048)
			(stroke
				(width 0.1)
				(type default)
			)
			(layer "F.Fab")
		)
		(fp_line
			(start 0.12065 -0.2794)
			(end 0.12065 -0.3048)
			(stroke
				(width 0.1)
				(type default)
			)
			(layer "F.Fab")
		)
		(fp_line
			(start 0.12065 -0.3048)
			(end 0.67945 -0.3048)
			(stroke
				(width 0.1)
				(type default)
			)
			(layer "F.Fab")
		)
		(fp_line
			(start 0.120396 0.3048)
			(end 0.120396 0.2794)
			(stroke
				(width 0.1)
				(type default)
			)
			(layer "F.Fab")
		)
		(fp_line
			(start 0.120396 0.2794)
			(end -0.12065 0.2794)
			(stroke
				(width 0.1)
				(type default)
			)
			(layer "F.Fab")
		)
		(fp_line
			(start -0.12065 0.3048)
			(end -0.67945 0.3048)
			(stroke
				(width 0.1)
				(type default)
			)
			(layer "F.Fab")
		)
		(fp_line
			(start -0.12065 0.2794)
			(end -0.12065 0.3048)
			(stroke
				(width 0.1)
				(type default)
			)
			(layer "F.Fab")
		)
		(fp_line
			(start -0.12065 -0.2794)
			(end 0.12065 -0.2794)
			(stroke
				(width 0.1)
				(type default)
			)
			(layer "F.Fab")
		)
		(fp_line
			(start -0.12065 -0.305054)
			(end -0.12065 -0.2794)
			(stroke
				(width 0.1)
				(type default)
			)
			(layer "F.Fab")
		)
		(fp_line
			(start -0.67945 0.3048)
			(end -0.67945 -0.305054)
			(stroke
				(width 0.1)
				(type default)
			)
			(layer "F.Fab")
		)
		(fp_line
			(start -0.67945 -0.305054)
			(end -0.12065 -0.305054)
			(stroke
				(width 0.1)
				(type default)
			)
			(layer "F.Fab")
		)
		(pad "1" smd circle
			(at -0.40005 0 180)
			(size 0 0)
			(layers "F.Cu" "F.Mask" "F.Paste")
			(net "P3V3_ADC128_VCC")
		)
		(pad "2" smd circle
			(at 0.40005 0 180)
			(size 0 0)
			(layers "F.Cu" "F.Mask" "F.Paste")
			(net "GND")
		)
	)
	(footprint ""
		(layer "F.Cu")
		(at 37.853112 -368.455448 90)
		(property "Reference" "PR253"
			(at 0 0 90)
			(layer "F.SilkS")
			(hide yes)
			(effects
				(font
					(size 1.27 1.27)
				)
			)
		)
		(property "Value" ""
			(at 0 0 90)
			(layer "F.Fab")
			(effects
				(font
					(size 1.27 1.27)
				)
			)
		)
		(duplicate_pad_numbers_are_jumpers no)
		(fp_line
			(start 0.7874 -0.4064)
			(end 0.7874 0.4064)
			(stroke
				(width 0.1524)
				(type default)
			)
			(layer "F.SilkS")
		)
		(fp_line
			(start -0.7874 -0.4064)
			(end 0.7874 -0.4064)
			(stroke
				(width 0.1524)
				(type default)
			)
			(layer "F.SilkS")
		)
		(fp_line
			(start 0.7874 0.4064)
			(end -0.7874 0.4064)
			(stroke
				(width 0.1524)
				(type default)
			)
			(layer "F.SilkS")
		)
		(fp_line
			(start -0.7874 0.4064)
			(end -0.7874 -0.4064)
			(stroke
				(width 0.1524)
				(type default)
			)
			(layer "F.SilkS")
		)
		(fp_line
			(start -0.12065 -0.305054)
			(end -0.12065 -0.2794)
			(stroke
				(width 0.1)
				(type default)
			)
			(layer "F.Fab")
		)
		(fp_line
			(start -0.67945 -0.305054)
			(end -0.12065 -0.305054)
			(stroke
				(width 0.1)
				(type default)
			)
			(layer "F.Fab")
		)
		(fp_line
			(start 0.67945 -0.3048)
			(end 0.67945 0.3048)
			(stroke
				(width 0.1)
				(type default)
			)
			(layer "F.Fab")
		)
		(fp_line
			(start 0.12065 -0.3048)
			(end 0.67945 -0.3048)
			(stroke
				(width 0.1)
				(type default)
			)
			(layer "F.Fab")
		)
		(fp_line
			(start 0.12065 -0.2794)
			(end 0.12065 -0.3048)
			(stroke
				(width 0.1)
				(type default)
			)
			(layer "F.Fab")
		)
		(fp_line
			(start -0.12065 -0.2794)
			(end 0.12065 -0.2794)
			(stroke
				(width 0.1)
				(type default)
			)
			(layer "F.Fab")
		)
		(fp_line
			(start 0.120396 0.2794)
			(end -0.12065 0.2794)
			(stroke
				(width 0.1)
				(type default)
			)
			(layer "F.Fab")
		)
		(fp_line
			(start -0.12065 0.2794)
			(end -0.12065 0.3048)
			(stroke
				(width 0.1)
				(type default)
			)
			(layer "F.Fab")
		)
		(fp_line
			(start 0.67945 0.3048)
			(end 0.120396 0.3048)
			(stroke
				(width 0.1)
				(type default)
			)
			(layer "F.Fab")
		)
		(fp_line
			(start 0.120396 0.3048)
			(end 0.120396 0.2794)
			(stroke
				(width 0.1)
				(type default)
			)
			(layer "F.Fab")
		)
		(fp_line
			(start -0.12065 0.3048)
			(end -0.67945 0.3048)
			(stroke
				(width 0.1)
				(type default)
			)
			(layer "F.Fab")
		)
		(fp_line
			(start -0.67945 0.3048)
			(end -0.67945 -0.305054)
			(stroke
				(width 0.1)
				(type default)
			)
			(layer "F.Fab")
		)
		(pad "1" smd circle
			(at -0.40005 0 90)
			(size 0 0)
			(layers "F.Cu" "F.Mask" "F.Paste")
			(net "PVDDCR_CPU1_P1_VCC")
		)
		(pad "2" smd circle
			(at 0.40005 0 90)
			(size 0 0)
			(layers "F.Cu" "F.Mask" "F.Paste")
			(net "P3V3_AUX")
		)
	)
	(footprint ""
		(layer "F.Cu")
		(at 303.868328 -404.392892)
		(property "Reference" "C564"
			(at 0 0 0)
			(layer "F.SilkS")
			(hide yes)
			(effects
				(font
					(size 1.27 1.27)
				)
			)
		)
		(property "Value" ""
			(at 0 0 0)
			(layer "F.Fab")
			(effects
				(font
					(size 1.27 1.27)
				)
			)
		)
		(duplicate_pad_numbers_are_jumpers no)
		(fp_line
			(start -1.524 -0.762)
			(end 1.524 -0.762)
			(stroke
				(width 0.1524)
				(type default)
			)
			(layer "F.SilkS")
		)
		(fp_line
			(start -1.524 0.762)
			(end -1.524 -0.762)
			(stroke
				(width 0.1524)
				(type default)
			)
			(layer "F.SilkS")
		)
		(fp_line
			(start 1.524 -0.762)
			(end 1.524 0.762)
			(stroke
				(width 0.1524)
				(type default)
			)
			(layer "F.SilkS")
		)
		(fp_line
			(start 1.524 0.762)
			(end -1.524 0.762)
			(stroke
				(width 0.1524)
				(type default)
			)
			(layer "F.SilkS")
		)
		(fp_line
			(start -1.1049 -0.724916)
			(end -1.1049 0.724916)
			(stroke
				(width 0.1)
				(type default)
			)
			(layer "F.Fab")
		)
		(fp_line
			(start -1.1049 0.724916)
			(end 1.1049 0.724916)
			(stroke
				(width 0.1)
				(type default)
			)
			(layer "F.Fab")
		)
		(fp_line
			(start 1.1049 -0.724916)
			(end -1.1049 -0.724916)
			(stroke
				(width 0.1)
				(type default)
			)
			(layer "F.Fab")
		)
		(fp_line
			(start 1.1049 0.724916)
			(end 1.1049 -0.724916)
			(stroke
				(width 0.1)
				(type default)
			)
			(layer "F.Fab")
		)
		(pad "1" smd rect
			(at -0.889 0 180)
			(size 1.016 1.27)
			(layers "F.Cu" "F.Mask" "F.Paste")
			(net "P0V9_CPU0_RT0_2A")
		)
		(pad "2" smd rect
			(at 0.889 0 180)
			(size 1.016 1.27)
			(layers "F.Cu" "F.Mask" "F.Paste")
			(net "GND")
		)
	)
	(footprint ""
		(layer "F.Cu")
		(at 194.2211 -404.300182)
		(property "Reference" "PR3916"
			(at 0 0 0)
			(layer "F.SilkS")
			(hide yes)
			(effects
				(font
					(size 1.27 1.27)
				)
			)
		)
		(property "Value" ""
			(at 0 0 0)
			(layer "F.Fab")
			(effects
				(font
					(size 1.27 1.27)
				)
			)
		)
		(duplicate_pad_numbers_are_jumpers no)
		(fp_line
			(start -0.7874 -0.4064)
			(end 0.7874 -0.4064)
			(stroke
				(width 0.1524)
				(type default)
			)
			(layer "F.SilkS")
		)
		(fp_line
			(start -0.7874 0.4064)
			(end -0.7874 -0.4064)
			(stroke
				(width 0.1524)
				(type default)
			)
			(layer "F.SilkS")
		)
		(fp_line
			(start 0.7874 -0.4064)
			(end 0.7874 0.4064)
			(stroke
				(width 0.1524)
				(type default)
			)
			(layer "F.SilkS")
		)
		(fp_line
			(start 0.7874 0.4064)
			(end -0.7874 0.4064)
			(stroke
				(width 0.1524)
				(type default)
			)
			(layer "F.SilkS")
		)
		(fp_line
			(start -0.67945 -0.305054)
			(end -0.12065 -0.305054)
			(stroke
				(width 0.1)
				(type default)
			)
			(layer "F.Fab")
		)
		(fp_line
			(start -0.67945 0.3048)
			(end -0.67945 -0.305054)
			(stroke
				(width 0.1)
				(type default)
			)
			(layer "F.Fab")
		)
		(fp_line
			(start -0.12065 -0.305054)
			(end -0.12065 -0.2794)
			(stroke
				(width 0.1)
				(type default)
			)
			(layer "F.Fab")
		)
		(fp_line
			(start -0.12065 -0.2794)
			(end 0.12065 -0.2794)
			(stroke
				(width 0.1)
				(type default)
			)
			(layer "F.Fab")
		)
		(fp_line
			(start -0.12065 0.2794)
			(end -0.12065 0.3048)
			(stroke
				(width 0.1)
				(type default)
			)
			(layer "F.Fab")
		)
		(fp_line
			(start -0.12065 0.3048)
			(end -0.67945 0.3048)
			(stroke
				(width 0.1)
				(type default)
			)
			(layer "F.Fab")
		)
		(fp_line
			(start 0.120396 0.2794)
			(end -0.12065 0.2794)
			(stroke
				(width 0.1)
				(type default)
			)
			(layer "F.Fab")
		)
		(fp_line
			(start 0.120396 0.3048)
			(end 0.120396 0.2794)
			(stroke
				(width 0.1)
				(type default)
			)
			(layer "F.Fab")
		)
		(fp_line
			(start 0.12065 -0.3048)
			(end 0.67945 -0.3048)
			(stroke
				(width 0.1)
				(type default)
			)
			(layer "F.Fab")
		)
		(fp_line
			(start 0.12065 -0.2794)
			(end 0.12065 -0.3048)
			(stroke
				(width 0.1)
				(type default)
			)
			(layer "F.Fab")
		)
		(fp_line
			(start 0.67945 -0.3048)
			(end 0.67945 0.3048)
			(stroke
				(width 0.1)
				(type default)
			)
			(layer "F.Fab")
		)
		(fp_line
			(start 0.67945 0.3048)
			(end 0.120396 0.3048)
			(stroke
				(width 0.1)
				(type default)
			)
			(layer "F.Fab")
		)
		(pad "1" smd circle
			(at -0.40005 0)
			(size 0 0)
			(layers "F.Cu" "F.Mask" "F.Paste")
			(net "HSC_SCREF")
		)
		(pad "2" smd circle
			(at 0.40005 0)
			(size 0 0)
			(layers "F.Cu" "F.Mask" "F.Paste")
			(net "HSC_SCREF_1")
		)
	)
	(footprint ""
		(layer "F.Cu")
		(at 296.52595 -150.538942 180)
		(property "Reference" "R1298"
			(at 0 0 180)
			(layer "F.SilkS")
			(hide yes)
			(effects
				(font
					(size 1.27 1.27)
				)
			)
		)
		(property "Value" ""
			(at 0 0 180)
			(layer "F.Fab")
			(effects
				(font
					(size 1.27 1.27)
				)
			)
		)
		(duplicate_pad_numbers_are_jumpers no)
		(fp_line
			(start 0.7874 0.4064)
			(end -0.7874 0.4064)
			(stroke
				(width 0.1524)
				(type default)
			)
			(layer "F.SilkS")
		)
		(fp_line
			(start 0.7874 -0.4064)
			(end 0.7874 0.4064)
			(stroke
				(width 0.1524)
				(type default)
			)
			(layer "F.SilkS")
		)
		(fp_line
			(start -0.7874 0.4064)
			(end -0.7874 -0.4064)
			(stroke
				(width 0.1524)
				(type default)
			)
			(layer "F.SilkS")
		)
		(fp_line
			(start -0.7874 -0.4064)
			(end 0.7874 -0.4064)
			(stroke
				(width 0.1524)
				(type default)
			)
			(layer "F.SilkS")
		)
		(fp_line
			(start 0.67945 0.3048)
			(end 0.120396 0.3048)
			(stroke
				(width 0.1)
				(type default)
			)
			(layer "F.Fab")
		)
		(fp_line
			(start 0.67945 -0.3048)
			(end 0.67945 0.3048)
			(stroke
				(width 0.1)
				(type default)
			)
			(layer "F.Fab")
		)
		(fp_line
			(start 0.12065 -0.2794)
			(end 0.12065 -0.3048)
			(stroke
				(width 0.1)
				(type default)
			)
			(layer "F.Fab")
		)
		(fp_line
			(start 0.12065 -0.3048)
			(end 0.67945 -0.3048)
			(stroke
				(width 0.1)
				(type default)
			)
			(layer "F.Fab")
		)
		(fp_line
			(start 0.120396 0.3048)
			(end 0.120396 0.2794)
			(stroke
				(width 0.1)
				(type default)
			)
			(layer "F.Fab")
		)
		(fp_line
			(start 0.120396 0.2794)
			(end -0.12065 0.2794)
			(stroke
				(width 0.1)
				(type default)
			)
			(layer "F.Fab")
		)
		(fp_line
			(start -0.12065 0.3048)
			(end -0.67945 0.3048)
			(stroke
				(width 0.1)
				(type default)
			)
			(layer "F.Fab")
		)
		(fp_line
			(start -0.12065 0.2794)
			(end -0.12065 0.3048)
			(stroke
				(width 0.1)
				(type default)
			)
			(layer "F.Fab")
		)
		(fp_line
			(start -0.12065 -0.2794)
			(end 0.12065 -0.2794)
			(stroke
				(width 0.1)
				(type default)
			)
			(layer "F.Fab")
		)
		(fp_line
			(start -0.12065 -0.305054)
			(end -0.12065 -0.2794)
			(stroke
				(width 0.1)
				(type default)
			)
			(layer "F.Fab")
		)
		(fp_line
			(start -0.67945 0.3048)
			(end -0.67945 -0.305054)
			(stroke
				(width 0.1)
				(type default)
			)
			(layer "F.Fab")
		)
		(fp_line
			(start -0.67945 -0.305054)
			(end -0.12065 -0.305054)
			(stroke
				(width 0.1)
				(type default)
			)
			(layer "F.Fab")
		)
		(pad "1" smd rect
			(at -0.40005 0)
			(size 0.4572 0.508)
			(layers "F.Cu" "F.Mask" "F.Paste")
			(net "I3C_SPD_DDRAF_CPU0_SDA")
		)
		(pad "2" smd rect
			(at 0.40005 0)
			(size 0.4572 0.508)
			(layers "F.Cu" "F.Mask" "F.Paste")
			(net "I3C_SPD_DDRAF_CPU0_LVC1_SDA")
		)
	)
	(footprint ""
		(layer "F.Cu")
		(at 392.962384 -393.47648 180)
		(property "Reference" "R1087"
			(at 0 0 180)
			(layer "F.SilkS")
			(hide yes)
			(effects
				(font
					(size 1.27 1.27)
				)
			)
		)
		(property "Value" ""
			(at 0 0 180)
			(layer "F.Fab")
			(effects
				(font
					(size 1.27 1.27)
				)
			)
		)
		(duplicate_pad_numbers_are_jumpers no)
		(fp_line
			(start 0.7874 0.4064)
			(end -0.7874 0.4064)
			(stroke
				(width 0.1524)
				(type default)
			)
			(layer "F.SilkS")
		)
		(fp_line
			(start 0.7874 -0.4064)
			(end 0.7874 0.4064)
			(stroke
				(width 0.1524)
				(type default)
			)
			(layer "F.SilkS")
		)
		(fp_line
			(start -0.7874 0.4064)
			(end -0.7874 -0.4064)
			(stroke
				(width 0.1524)
				(type default)
			)
			(layer "F.SilkS")
		)
		(fp_line
			(start -0.7874 -0.4064)
			(end 0.7874 -0.4064)
			(stroke
				(width 0.1524)
				(type default)
			)
			(layer "F.SilkS")
		)
		(fp_line
			(start 0.67945 0.3048)
			(end 0.120396 0.3048)
			(stroke
				(width 0.1)
				(type default)
			)
			(layer "F.Fab")
		)
		(fp_line
			(start 0.67945 -0.3048)
			(end 0.67945 0.3048)
			(stroke
				(width 0.1)
				(type default)
			)
			(layer "F.Fab")
		)
		(fp_line
			(start 0.12065 -0.2794)
			(end 0.12065 -0.3048)
			(stroke
				(width 0.1)
				(type default)
			)
			(layer "F.Fab")
		)
		(fp_line
			(start 0.12065 -0.3048)
			(end 0.67945 -0.3048)
			(stroke
				(width 0.1)
				(type default)
			)
			(layer "F.Fab")
		)
		(fp_line
			(start 0.120396 0.3048)
			(end 0.120396 0.2794)
			(stroke
				(width 0.1)
				(type default)
			)
			(layer "F.Fab")
		)
		(fp_line
			(start 0.120396 0.2794)
			(end -0.12065 0.2794)
			(stroke
				(width 0.1)
				(type default)
			)
			(layer "F.Fab")
		)
		(fp_line
			(start -0.12065 0.3048)
			(end -0.67945 0.3048)
			(stroke
				(width 0.1)
				(type default)
			)
			(layer "F.Fab")
		)
		(fp_line
			(start -0.12065 0.2794)
			(end -0.12065 0.3048)
			(stroke
				(width 0.1)
				(type default)
			)
			(layer "F.Fab")
		)
		(fp_line
			(start -0.12065 -0.2794)
			(end 0.12065 -0.2794)
			(stroke
				(width 0.1)
				(type default)
			)
			(layer "F.Fab")
		)
		(fp_line
			(start -0.12065 -0.305054)
			(end -0.12065 -0.2794)
			(stroke
				(width 0.1)
				(type default)
			)
			(layer "F.Fab")
		)
		(fp_line
			(start -0.67945 0.3048)
			(end -0.67945 -0.305054)
			(stroke
				(width 0.1)
				(type default)
			)
			(layer "F.Fab")
		)
		(fp_line
			(start -0.67945 -0.305054)
			(end -0.12065 -0.305054)
			(stroke
				(width 0.1)
				(type default)
			)
			(layer "F.Fab")
		)
		(pad "1" smd rect
			(at -0.40005 0)
			(size 0.4572 0.508)
			(layers "F.Cu" "F.Mask" "F.Paste")
			(net "P1V8_CPU0_RT3_1A_1D")
		)
		(pad "2" smd rect
			(at 0.40005 0)
			(size 0.4572 0.508)
			(layers "F.Cu" "F.Mask" "F.Paste")
			(net "P1V8_CPU0_RT3_1A")
		)
	)
	(footprint ""
		(layer "F.Cu")
		(at 415.628582 -333.215996 180)
		(property "Reference" "PR114"
			(at 0 0 180)
			(layer "F.SilkS")
			(hide yes)
			(effects
				(font
					(size 1.27 1.27)
				)
			)
		)
		(property "Value" ""
			(at 0 0 180)
			(layer "F.Fab")
			(effects
				(font
					(size 1.27 1.27)
				)
			)
		)
		(duplicate_pad_numbers_are_jumpers no)
		(fp_line
			(start 0.7874 0.4064)
			(end -0.7874 0.4064)
			(stroke
				(width 0.1524)
				(type default)
			)
			(layer "F.SilkS")
		)
		(fp_line
			(start 0.7874 -0.4064)
			(end 0.7874 0.4064)
			(stroke
				(width 0.1524)
				(type default)
			)
			(layer "F.SilkS")
		)
		(fp_line
			(start -0.7874 0.4064)
			(end -0.7874 -0.4064)
			(stroke
				(width 0.1524)
				(type default)
			)
			(layer "F.SilkS")
		)
		(fp_line
			(start -0.7874 -0.4064)
			(end 0.7874 -0.4064)
			(stroke
				(width 0.1524)
				(type default)
			)
			(layer "F.SilkS")
		)
		(fp_line
			(start 0.67945 0.3048)
			(end 0.120396 0.3048)
			(stroke
				(width 0.1)
				(type default)
			)
			(layer "F.Fab")
		)
		(fp_line
			(start 0.67945 -0.3048)
			(end 0.67945 0.3048)
			(stroke
				(width 0.1)
				(type default)
			)
			(layer "F.Fab")
		)
		(fp_line
			(start 0.12065 -0.2794)
			(end 0.12065 -0.3048)
			(stroke
				(width 0.1)
				(type default)
			)
			(layer "F.Fab")
		)
		(fp_line
			(start 0.12065 -0.3048)
			(end 0.67945 -0.3048)
			(stroke
				(width 0.1)
				(type default)
			)
			(layer "F.Fab")
		)
		(fp_line
			(start 0.120396 0.3048)
			(end 0.120396 0.2794)
			(stroke
				(width 0.1)
				(type default)
			)
			(layer "F.Fab")
		)
		(fp_line
			(start 0.120396 0.2794)
			(end -0.12065 0.2794)
			(stroke
				(width 0.1)
				(type default)
			)
			(layer "F.Fab")
		)
		(fp_line
			(start -0.12065 0.3048)
			(end -0.67945 0.3048)
			(stroke
				(width 0.1)
				(type default)
			)
			(layer "F.Fab")
		)
		(fp_line
			(start -0.12065 0.2794)
			(end -0.12065 0.3048)
			(stroke
				(width 0.1)
				(type default)
			)
			(layer "F.Fab")
		)
		(fp_line
			(start -0.12065 -0.2794)
			(end 0.12065 -0.2794)
			(stroke
				(width 0.1)
				(type default)
			)
			(layer "F.Fab")
		)
		(fp_line
			(start -0.12065 -0.305054)
			(end -0.12065 -0.2794)
			(stroke
				(width 0.1)
				(type default)
			)
			(layer "F.Fab")
		)
		(fp_line
			(start -0.67945 0.3048)
			(end -0.67945 -0.305054)
			(stroke
				(width 0.1)
				(type default)
			)
			(layer "F.Fab")
		)
		(fp_line
			(start -0.67945 -0.305054)
			(end -0.12065 -0.305054)
			(stroke
				(width 0.1)
				(type default)
			)
			(layer "F.Fab")
		)
		(pad "1" smd circle
			(at -0.40005 0 180)
			(size 0 0)
			(layers "F.Cu" "F.Mask" "F.Paste")
			(net "PVDD11_S3_P0")
		)
		(pad "2" smd circle
			(at 0.40005 0 180)
			(size 0 0)
			(layers "F.Cu" "F.Mask" "F.Paste")
			(net "VSENSE_PVDD11_S3_P0_DP")
		)
	)
	(footprint ""
		(layer "F.Cu")
		(at 415.834322 -158.556198)
		(property "Reference" "PR365"
			(at 0 0 0)
			(layer "F.SilkS")
			(hide yes)
			(effects
				(font
					(size 1.27 1.27)
				)
			)
		)
		(property "Value" ""
			(at 0 0 0)
			(layer "F.Fab")
			(effects
				(font
					(size 1.27 1.27)
				)
			)
		)
		(duplicate_pad_numbers_are_jumpers no)
		(fp_line
			(start -0.7874 -0.4064)
			(end 0.7874 -0.4064)
			(stroke
				(width 0.1524)
				(type default)
			)
			(layer "F.SilkS")
		)
		(fp_line
			(start -0.7874 0.4064)
			(end -0.7874 -0.4064)
			(stroke
				(width 0.1524)
				(type default)
			)
			(layer "F.SilkS")
		)
		(fp_line
			(start 0.7874 -0.4064)
			(end 0.7874 0.4064)
			(stroke
				(width 0.1524)
				(type default)
			)
			(layer "F.SilkS")
		)
		(fp_line
			(start 0.7874 0.4064)
			(end -0.7874 0.4064)
			(stroke
				(width 0.1524)
				(type default)
			)
			(layer "F.SilkS")
		)
		(fp_line
			(start -0.67945 -0.305054)
			(end -0.12065 -0.305054)
			(stroke
				(width 0.1)
				(type default)
			)
			(layer "F.Fab")
		)
		(fp_line
			(start -0.67945 0.3048)
			(end -0.67945 -0.305054)
			(stroke
				(width 0.1)
				(type default)
			)
			(layer "F.Fab")
		)
		(fp_line
			(start -0.12065 -0.305054)
			(end -0.12065 -0.2794)
			(stroke
				(width 0.1)
				(type default)
			)
			(layer "F.Fab")
		)
		(fp_line
			(start -0.12065 -0.2794)
			(end 0.12065 -0.2794)
			(stroke
				(width 0.1)
				(type default)
			)
			(layer "F.Fab")
		)
		(fp_line
			(start -0.12065 0.2794)
			(end -0.12065 0.3048)
			(stroke
				(width 0.1)
				(type default)
			)
			(layer "F.Fab")
		)
		(fp_line
			(start -0.12065 0.3048)
			(end -0.67945 0.3048)
			(stroke
				(width 0.1)
				(type default)
			)
			(layer "F.Fab")
		)
		(fp_line
			(start 0.120396 0.2794)
			(end -0.12065 0.2794)
			(stroke
				(width 0.1)
				(type default)
			)
			(layer "F.Fab")
		)
		(fp_line
			(start 0.120396 0.3048)
			(end 0.120396 0.2794)
			(stroke
				(width 0.1)
				(type default)
			)
			(layer "F.Fab")
		)
		(fp_line
			(start 0.12065 -0.3048)
			(end 0.67945 -0.3048)
			(stroke
				(width 0.1)
				(type default)
			)
			(layer "F.Fab")
		)
		(fp_line
			(start 0.12065 -0.2794)
			(end 0.12065 -0.3048)
			(stroke
				(width 0.1)
				(type default)
			)
			(layer "F.Fab")
		)
		(fp_line
			(start 0.67945 -0.3048)
			(end 0.67945 0.3048)
			(stroke
				(width 0.1)
				(type default)
			)
			(layer "F.Fab")
		)
		(fp_line
			(start 0.67945 0.3048)
			(end 0.120396 0.3048)
			(stroke
				(width 0.1)
				(type default)
			)
			(layer "F.Fab")
		)
		(pad "1" smd circle
			(at -0.40005 0)
			(size 0 0)
			(layers "F.Cu" "F.Mask" "F.Paste")
			(net "GND")
		)
		(pad "2" smd circle
			(at 0.40005 0)
			(size 0 0)
			(layers "F.Cu" "F.Mask" "F.Paste")
			(net "PVDDCR_SOC_P0_LSET3")
		)
	)
	(footprint ""
		(layer "F.Cu")
		(at 87.04834 -182.578248 90)
		(property "Reference" "PC263_2"
			(at 0 0 90)
			(layer "F.SilkS")
			(hide yes)
			(effects
				(font
					(size 1.27 1.27)
				)
			)
		)
		(property "Value" ""
			(at 0 0 90)
			(layer "F.Fab")
			(effects
				(font
					(size 1.27 1.27)
				)
			)
		)
		(duplicate_pad_numbers_are_jumpers no)
		(fp_line
			(start 0.7874 -0.4064)
			(end 0.7874 0.4064)
			(stroke
				(width 0.1524)
				(type default)
			)
			(layer "F.SilkS")
		)
		(fp_line
			(start -0.7874 -0.4064)
			(end 0.7874 -0.4064)
			(stroke
				(width 0.1524)
				(type default)
			)
			(layer "F.SilkS")
		)
		(fp_line
			(start 0.7874 0.4064)
			(end -0.7874 0.4064)
			(stroke
				(width 0.1524)
				(type default)
			)
			(layer "F.SilkS")
		)
		(fp_line
			(start -0.7874 0.4064)
			(end -0.7874 -0.4064)
			(stroke
				(width 0.1524)
				(type default)
			)
			(layer "F.SilkS")
		)
		(fp_line
			(start -0.12065 -0.305054)
			(end -0.12065 -0.2794)
			(stroke
				(width 0.1)
				(type default)
			)
			(layer "F.Fab")
		)
		(fp_line
			(start -0.67945 -0.305054)
			(end -0.12065 -0.305054)
			(stroke
				(width 0.1)
				(type default)
			)
			(layer "F.Fab")
		)
		(fp_line
			(start 0.67945 -0.3048)
			(end 0.67945 0.3048)
			(stroke
				(width 0.1)
				(type default)
			)
			(layer "F.Fab")
		)
		(fp_line
			(start 0.12065 -0.3048)
			(end 0.67945 -0.3048)
			(stroke
				(width 0.1)
				(type default)
			)
			(layer "F.Fab")
		)
		(fp_line
			(start 0.12065 -0.2794)
			(end 0.12065 -0.3048)
			(stroke
				(width 0.1)
				(type default)
			)
			(layer "F.Fab")
		)
		(fp_line
			(start -0.12065 -0.2794)
			(end 0.12065 -0.2794)
			(stroke
				(width 0.1)
				(type default)
			)
			(layer "F.Fab")
		)
		(fp_line
			(start 0.120396 0.2794)
			(end -0.12065 0.2794)
			(stroke
				(width 0.1)
				(type default)
			)
			(layer "F.Fab")
		)
		(fp_line
			(start -0.12065 0.2794)
			(end -0.12065 0.3048)
			(stroke
				(width 0.1)
				(type default)
			)
			(layer "F.Fab")
		)
		(fp_line
			(start 0.67945 0.3048)
			(end 0.120396 0.3048)
			(stroke
				(width 0.1)
				(type default)
			)
			(layer "F.Fab")
		)
		(fp_line
			(start 0.120396 0.3048)
			(end 0.120396 0.2794)
			(stroke
				(width 0.1)
				(type default)
			)
			(layer "F.Fab")
		)
		(fp_line
			(start -0.12065 0.3048)
			(end -0.67945 0.3048)
			(stroke
				(width 0.1)
				(type default)
			)
			(layer "F.Fab")
		)
		(fp_line
			(start -0.67945 0.3048)
			(end -0.67945 -0.305054)
			(stroke
				(width 0.1)
				(type default)
			)
			(layer "F.Fab")
		)
		(pad "1" smd circle
			(at -0.40005 0 90)
			(size 0 0)
			(layers "F.Cu" "F.Mask" "F.Paste")
			(net "SW_P12V_AUX_PVDDCR_CPU0_P1_FLT")
		)
		(pad "2" smd circle
			(at 0.40005 0 90)
			(size 0 0)
			(layers "F.Cu" "F.Mask" "F.Paste")
			(net "GND")
		)
	)
	(footprint ""
		(layer "F.Cu")
		(at 366.06734 -384.32486 180)
		(property "Reference" "C899"
			(at 0 0 180)
			(layer "F.SilkS")
			(hide yes)
			(effects
				(font
					(size 1.27 1.27)
				)
			)
		)
		(property "Value" ""
			(at 0 0 180)
			(layer "F.Fab")
			(effects
				(font
					(size 1.27 1.27)
				)
			)
		)
		(duplicate_pad_numbers_are_jumpers no)
		(fp_line
			(start 0.299974 0.150114)
			(end -0.299974 0.150114)
			(stroke
				(width 0.1)
				(type default)
			)
			(layer "F.Fab")
		)
		(fp_line
			(start 0.299974 -0.150114)
			(end 0.299974 0.150114)
			(stroke
				(width 0.1)
				(type default)
			)
			(layer "F.Fab")
		)
		(fp_line
			(start -0.299974 0.150114)
			(end -0.299974 -0.150114)
			(stroke
				(width 0.1)
				(type default)
			)
			(layer "F.Fab")
		)
		(fp_line
			(start -0.299974 -0.150114)
			(end 0.299974 -0.150114)
			(stroke
				(width 0.1)
				(type default)
			)
			(layer "F.Fab")
		)
		(pad "1" smd rect
			(at -0.2667 0 180)
			(size 0.3048 0.381)
			(layers "F.Cu" "F.Mask" "F.Paste")
			(net "P5E_CPU0_P3_TX_C_DP<1>")
		)
		(pad "2" smd rect
			(at 0.2667 0 180)
			(size 0.3048 0.381)
			(layers "F.Cu" "F.Mask" "F.Paste")
			(net "P5E_CPU0_P3_TX_DP<1>")
		)
	)
	(footprint ""
		(layer "F.Cu")
		(at 330.731876 -70.098412 90)
		(property "Reference" "D77"
			(at -3.934714 -0.691642 90)
			(unlocked yes)
			(layer "F.SilkS")
			(effects
				(font
					(size 0.7874 0.5842)
					(thickness 0.1524)
				)
				(justify left)
			)
		)
		(property "Value" ""
			(at 0 0 90)
			(layer "F.Fab")
			(effects
				(font
					(size 1.27 1.27)
				)
			)
		)
		(duplicate_pad_numbers_are_jumpers no)
		(fp_line
			(start 1.16078 -0.4826)
			(end 1.16078 0.4826)
			(stroke
				(width 0.1524)
				(type default)
			)
			(layer "F.SilkS")
		)
		(fp_line
			(start 1.03378 -0.4826)
			(end 1.03378 0.4826)
			(stroke
				(width 0.1524)
				(type default)
			)
			(layer "F.SilkS")
		)
		(fp_line
			(start 0.90678 -0.4826)
			(end 0.90678 0.4826)
			(stroke
				(width 0.1524)
				(type default)
			)
			(layer "F.SilkS")
		)
		(fp_line
			(start -0.64008 -0.4826)
			(end 1.16078 -0.4826)
			(stroke
				(width 0.1524)
				(type default)
			)
			(layer "F.SilkS")
		)
		(fp_line
			(start -0.79248 -0.4826)
			(end 1.03378 -0.4826)
			(stroke
				(width 0.1524)
				(type default)
			)
			(layer "F.SilkS")
		)
		(fp_line
			(start -0.89408 -0.4826)
			(end 0.90678 -0.4826)
			(stroke
				(width 0.1524)
				(type default)
			)
			(layer "F.SilkS")
		)
		(fp_line
			(start 1.16078 0.4826)
			(end -0.64008 0.4826)
			(stroke
				(width 0.1524)
				(type default)
			)
			(layer "F.SilkS")
		)
		(fp_line
			(start 1.03378 0.4826)
			(end -0.79248 0.4826)
			(stroke
				(width 0.1524)
				(type default)
			)
			(layer "F.SilkS")
		)
		(fp_line
			(start 0.90678 0.4826)
			(end -0.90678 0.4826)
			(stroke
				(width 0.1524)
				(type default)
			)
			(layer "F.SilkS")
		)
		(fp_line
			(start -0.90678 0.4826)
			(end -0.90678 -0.4699)
			(stroke
				(width 0.1524)
				(type default)
			)
			(layer "F.SilkS")
		)
		(fp_line
			(start 0.499872 -0.249936)
			(end 0.499872 0.249936)
			(stroke
				(width 0.1)
				(type default)
			)
			(layer "F.Fab")
		)
		(fp_line
			(start -0.499872 -0.249936)
			(end 0.499872 -0.249936)
			(stroke
				(width 0.1)
				(type default)
			)
			(layer "F.Fab")
		)
		(fp_line
			(start 0.499872 0.249936)
			(end -0.499872 0.249936)
			(stroke
				(width 0.1)
				(type default)
			)
			(layer "F.Fab")
		)
		(fp_line
			(start -0.499872 0.249936)
			(end -0.499872 -0.249936)
			(stroke
				(width 0.1)
				(type default)
			)
			(layer "F.Fab")
		)
		(pad "A" smd rect
			(at -0.47498 0 90)
			(size 0.6096 0.7112)
			(layers "F.Cu" "F.Mask" "F.Paste")
			(net "LED_PWRGD_PVDDIO_P0_R")
		)
		(pad "C" smd rect
			(at 0.47498 0 90)
			(size 0.6096 0.7112)
			(layers "F.Cu" "F.Mask" "F.Paste")
			(net "LED_PWRGD_PVDDIO_P0_D")
		)
	)
	(footprint ""
		(layer "F.Cu")
		(at 329.360022 -34.985706 180)
		(property "Reference" "R1793"
			(at 0 0 180)
			(layer "F.SilkS")
			(hide yes)
			(effects
				(font
					(size 1.27 1.27)
				)
			)
		)
		(property "Value" ""
			(at 0 0 180)
			(layer "F.Fab")
			(effects
				(font
					(size 1.27 1.27)
				)
			)
		)
		(duplicate_pad_numbers_are_jumpers no)
		(fp_line
			(start 0.7874 0.4064)
			(end -0.7874 0.4064)
			(stroke
				(width 0.1524)
				(type default)
			)
			(layer "F.SilkS")
		)
		(fp_line
			(start 0.7874 -0.4064)
			(end 0.7874 0.4064)
			(stroke
				(width 0.1524)
				(type default)
			)
			(layer "F.SilkS")
		)
		(fp_line
			(start -0.7874 0.4064)
			(end -0.7874 -0.4064)
			(stroke
				(width 0.1524)
				(type default)
			)
			(layer "F.SilkS")
		)
		(fp_line
			(start -0.7874 -0.4064)
			(end 0.7874 -0.4064)
			(stroke
				(width 0.1524)
				(type default)
			)
			(layer "F.SilkS")
		)
		(fp_line
			(start 0.67945 0.3048)
			(end 0.120396 0.3048)
			(stroke
				(width 0.1)
				(type default)
			)
			(layer "F.Fab")
		)
		(fp_line
			(start 0.67945 -0.3048)
			(end 0.67945 0.3048)
			(stroke
				(width 0.1)
				(type default)
			)
			(layer "F.Fab")
		)
		(fp_line
			(start 0.12065 -0.2794)
			(end 0.12065 -0.3048)
			(stroke
				(width 0.1)
				(type default)
			)
			(layer "F.Fab")
		)
		(fp_line
			(start 0.12065 -0.3048)
			(end 0.67945 -0.3048)
			(stroke
				(width 0.1)
				(type default)
			)
			(layer "F.Fab")
		)
		(fp_line
			(start 0.120396 0.3048)
			(end 0.120396 0.2794)
			(stroke
				(width 0.1)
				(type default)
			)
			(layer "F.Fab")
		)
		(fp_line
			(start 0.120396 0.2794)
			(end -0.12065 0.2794)
			(stroke
				(width 0.1)
				(type default)
			)
			(layer "F.Fab")
		)
		(fp_line
			(start -0.12065 0.3048)
			(end -0.67945 0.3048)
			(stroke
				(width 0.1)
				(type default)
			)
			(layer "F.Fab")
		)
		(fp_line
			(start -0.12065 0.2794)
			(end -0.12065 0.3048)
			(stroke
				(width 0.1)
				(type default)
			)
			(layer "F.Fab")
		)
		(fp_line
			(start -0.12065 -0.2794)
			(end 0.12065 -0.2794)
			(stroke
				(width 0.1)
				(type default)
			)
			(layer "F.Fab")
		)
		(fp_line
			(start -0.12065 -0.305054)
			(end -0.12065 -0.2794)
			(stroke
				(width 0.1)
				(type default)
			)
			(layer "F.Fab")
		)
		(fp_line
			(start -0.67945 0.3048)
			(end -0.67945 -0.305054)
			(stroke
				(width 0.1)
				(type default)
			)
			(layer "F.Fab")
		)
		(fp_line
			(start -0.67945 -0.305054)
			(end -0.12065 -0.305054)
			(stroke
				(width 0.1)
				(type default)
			)
			(layer "F.Fab")
		)
		(pad "1" smd circle
			(at -0.40005 0 180)
			(size 0 0)
			(layers "F.Cu" "F.Mask" "F.Paste")
			(net "SMB_SCM_2_R4_SCL")
		)
		(pad "2" smd circle
			(at 0.40005 0 180)
			(size 0 0)
			(layers "F.Cu" "F.Mask" "F.Paste")
			(net "SMB_SEN_MAM_3V3AUX_SCL")
		)
	)
	(footprint ""
		(layer "F.Cu")
		(at 50.256694 -16.099536 90)
		(property "Reference" "C703"
			(at 0 0 90)
			(layer "F.SilkS")
			(hide yes)
			(effects
				(font
					(size 1.27 1.27)
				)
			)
		)
		(property "Value" ""
			(at 0 0 90)
			(layer "F.Fab")
			(effects
				(font
					(size 1.27 1.27)
				)
			)
		)
		(duplicate_pad_numbers_are_jumpers no)
		(fp_line
			(start 0.299974 -0.150114)
			(end 0.299974 0.150114)
			(stroke
				(width 0.1)
				(type default)
			)
			(layer "F.Fab")
		)
		(fp_line
			(start -0.299974 -0.150114)
			(end 0.299974 -0.150114)
			(stroke
				(width 0.1)
				(type default)
			)
			(layer "F.Fab")
		)
		(fp_line
			(start 0.299974 0.150114)
			(end -0.299974 0.150114)
			(stroke
				(width 0.1)
				(type default)
			)
			(layer "F.Fab")
		)
		(fp_line
			(start -0.299974 0.150114)
			(end -0.299974 -0.150114)
			(stroke
				(width 0.1)
				(type default)
			)
			(layer "F.Fab")
		)
		(pad "1" smd rect
			(at -0.2667 0 90)
			(size 0.3048 0.381)
			(layers "F.Cu" "F.Mask" "F.Paste")
			(net "P5E_CPU1_G1_TX_C_DP<3>")
		)
		(pad "2" smd rect
			(at 0.2667 0 90)
			(size 0.3048 0.381)
			(layers "F.Cu" "F.Mask" "F.Paste")
			(net "P5E_CPU1_G1_TX_DP<3>")
		)
	)
	(footprint ""
		(layer "F.Cu")
		(at 191.41694 -402.341842)
		(property "Reference" "R2588"
			(at 0 0 0)
			(layer "F.SilkS")
			(hide yes)
			(effects
				(font
					(size 1.27 1.27)
				)
			)
		)
		(property "Value" ""
			(at 0 0 0)
			(layer "F.Fab")
			(effects
				(font
					(size 1.27 1.27)
				)
			)
		)
		(duplicate_pad_numbers_are_jumpers no)
		(fp_line
			(start -0.7874 -0.4064)
			(end 0.7874 -0.4064)
			(stroke
				(width 0.1524)
				(type default)
			)
			(layer "F.SilkS")
		)
		(fp_line
			(start -0.7874 0.4064)
			(end -0.7874 -0.4064)
			(stroke
				(width 0.1524)
				(type default)
			)
			(layer "F.SilkS")
		)
		(fp_line
			(start 0.7874 -0.4064)
			(end 0.7874 0.4064)
			(stroke
				(width 0.1524)
				(type default)
			)
			(layer "F.SilkS")
		)
		(fp_line
			(start 0.7874 0.4064)
			(end -0.7874 0.4064)
			(stroke
				(width 0.1524)
				(type default)
			)
			(layer "F.SilkS")
		)
		(fp_line
			(start -0.67945 -0.305054)
			(end -0.12065 -0.305054)
			(stroke
				(width 0.1)
				(type default)
			)
			(layer "F.Fab")
		)
		(fp_line
			(start -0.67945 0.3048)
			(end -0.67945 -0.305054)
			(stroke
				(width 0.1)
				(type default)
			)
			(layer "F.Fab")
		)
		(fp_line
			(start -0.12065 -0.305054)
			(end -0.12065 -0.2794)
			(stroke
				(width 0.1)
				(type default)
			)
			(layer "F.Fab")
		)
		(fp_line
			(start -0.12065 -0.2794)
			(end 0.12065 -0.2794)
			(stroke
				(width 0.1)
				(type default)
			)
			(layer "F.Fab")
		)
		(fp_line
			(start -0.12065 0.2794)
			(end -0.12065 0.3048)
			(stroke
				(width 0.1)
				(type default)
			)
			(layer "F.Fab")
		)
		(fp_line
			(start -0.12065 0.3048)
			(end -0.67945 0.3048)
			(stroke
				(width 0.1)
				(type default)
			)
			(layer "F.Fab")
		)
		(fp_line
			(start 0.120396 0.2794)
			(end -0.12065 0.2794)
			(stroke
				(width 0.1)
				(type default)
			)
			(layer "F.Fab")
		)
		(fp_line
			(start 0.120396 0.3048)
			(end 0.120396 0.2794)
			(stroke
				(width 0.1)
				(type default)
			)
			(layer "F.Fab")
		)
		(fp_line
			(start 0.12065 -0.3048)
			(end 0.67945 -0.3048)
			(stroke
				(width 0.1)
				(type default)
			)
			(layer "F.Fab")
		)
		(fp_line
			(start 0.12065 -0.2794)
			(end 0.12065 -0.3048)
			(stroke
				(width 0.1)
				(type default)
			)
			(layer "F.Fab")
		)
		(fp_line
			(start 0.67945 -0.3048)
			(end 0.67945 0.3048)
			(stroke
				(width 0.1)
				(type default)
			)
			(layer "F.Fab")
		)
		(fp_line
			(start 0.67945 0.3048)
			(end 0.120396 0.3048)
			(stroke
				(width 0.1)
				(type default)
			)
			(layer "F.Fab")
		)
		(pad "1" smd circle
			(at -0.40005 0)
			(size 0 0)
			(layers "F.Cu" "F.Mask" "F.Paste")
			(net "HSC_FAULT")
		)
		(pad "2" smd circle
			(at 0.40005 0)
			(size 0 0)
			(layers "F.Cu" "F.Mask" "F.Paste")
			(net "IRQ_HSC_FAULT_N")
		)
	)
	(footprint ""
		(layer "F.Cu")
		(at 185.039 -129.377948 90)
		(property "Reference" "R933"
			(at 0 0 90)
			(layer "F.SilkS")
			(hide yes)
			(effects
				(font
					(size 1.27 1.27)
				)
			)
		)
		(property "Value" ""
			(at 0 0 90)
			(layer "F.Fab")
			(effects
				(font
					(size 1.27 1.27)
				)
			)
		)
		(duplicate_pad_numbers_are_jumpers no)
		(fp_line
			(start 0.7874 -0.4064)
			(end 0.7874 0.4064)
			(stroke
				(width 0.1524)
				(type default)
			)
			(layer "F.SilkS")
		)
		(fp_line
			(start -0.7874 -0.4064)
			(end 0.7874 -0.4064)
			(stroke
				(width 0.1524)
				(type default)
			)
			(layer "F.SilkS")
		)
		(fp_line
			(start 0.7874 0.4064)
			(end -0.7874 0.4064)
			(stroke
				(width 0.1524)
				(type default)
			)
			(layer "F.SilkS")
		)
		(fp_line
			(start -0.7874 0.4064)
			(end -0.7874 -0.4064)
			(stroke
				(width 0.1524)
				(type default)
			)
			(layer "F.SilkS")
		)
		(fp_line
			(start -0.12065 -0.305054)
			(end -0.12065 -0.2794)
			(stroke
				(width 0.1)
				(type default)
			)
			(layer "F.Fab")
		)
		(fp_line
			(start -0.67945 -0.305054)
			(end -0.12065 -0.305054)
			(stroke
				(width 0.1)
				(type default)
			)
			(layer "F.Fab")
		)
		(fp_line
			(start 0.67945 -0.3048)
			(end 0.67945 0.3048)
			(stroke
				(width 0.1)
				(type default)
			)
			(layer "F.Fab")
		)
		(fp_line
			(start 0.12065 -0.3048)
			(end 0.67945 -0.3048)
			(stroke
				(width 0.1)
				(type default)
			)
			(layer "F.Fab")
		)
		(fp_line
			(start 0.12065 -0.2794)
			(end 0.12065 -0.3048)
			(stroke
				(width 0.1)
				(type default)
			)
			(layer "F.Fab")
		)
		(fp_line
			(start -0.12065 -0.2794)
			(end 0.12065 -0.2794)
			(stroke
				(width 0.1)
				(type default)
			)
			(layer "F.Fab")
		)
		(fp_line
			(start 0.120396 0.2794)
			(end -0.12065 0.2794)
			(stroke
				(width 0.1)
				(type default)
			)
			(layer "F.Fab")
		)
		(fp_line
			(start -0.12065 0.2794)
			(end -0.12065 0.3048)
			(stroke
				(width 0.1)
				(type default)
			)
			(layer "F.Fab")
		)
		(fp_line
			(start 0.67945 0.3048)
			(end 0.120396 0.3048)
			(stroke
				(width 0.1)
				(type default)
			)
			(layer "F.Fab")
		)
		(fp_line
			(start 0.120396 0.3048)
			(end 0.120396 0.2794)
			(stroke
				(width 0.1)
				(type default)
			)
			(layer "F.Fab")
		)
		(fp_line
			(start -0.12065 0.3048)
			(end -0.67945 0.3048)
			(stroke
				(width 0.1)
				(type default)
			)
			(layer "F.Fab")
		)
		(fp_line
			(start -0.67945 0.3048)
			(end -0.67945 -0.305054)
			(stroke
				(width 0.1)
				(type default)
			)
			(layer "F.Fab")
		)
		(pad "1" smd circle
			(at -0.40005 0 90)
			(size 0 0)
			(layers "F.Cu" "F.Mask" "F.Paste")
			(net "FM_SMERR_LED_R_N")
		)
		(pad "2" smd circle
			(at 0.40005 0 90)
			(size 0 0)
			(layers "F.Cu" "F.Mask" "F.Paste")
			(net "FM_SMERR_LED_N")
		)
	)
	(footprint ""
		(layer "F.Cu")
		(at 41.050718 -351.10547)
		(property "Reference" "PC439_2"
			(at 0 0 0)
			(layer "F.SilkS")
			(hide yes)
			(effects
				(font
					(size 1.27 1.27)
				)
			)
		)
		(property "Value" ""
			(at 0 0 0)
			(layer "F.Fab")
			(effects
				(font
					(size 1.27 1.27)
				)
			)
		)
		(duplicate_pad_numbers_are_jumpers no)
		(fp_line
			(start -0.7874 -0.4064)
			(end 0.7874 -0.4064)
			(stroke
				(width 0.1524)
				(type default)
			)
			(layer "F.SilkS")
		)
		(fp_line
			(start -0.7874 0.4064)
			(end -0.7874 -0.4064)
			(stroke
				(width 0.1524)
				(type default)
			)
			(layer "F.SilkS")
		)
		(fp_line
			(start 0.7874 -0.4064)
			(end 0.7874 0.4064)
			(stroke
				(width 0.1524)
				(type default)
			)
			(layer "F.SilkS")
		)
		(fp_line
			(start 0.7874 0.4064)
			(end -0.7874 0.4064)
			(stroke
				(width 0.1524)
				(type default)
			)
			(layer "F.SilkS")
		)
		(fp_line
			(start -0.67945 -0.305054)
			(end -0.12065 -0.305054)
			(stroke
				(width 0.1)
				(type default)
			)
			(layer "F.Fab")
		)
		(fp_line
			(start -0.67945 0.3048)
			(end -0.67945 -0.305054)
			(stroke
				(width 0.1)
				(type default)
			)
			(layer "F.Fab")
		)
		(fp_line
			(start -0.12065 -0.305054)
			(end -0.12065 -0.2794)
			(stroke
				(width 0.1)
				(type default)
			)
			(layer "F.Fab")
		)
		(fp_line
			(start -0.12065 -0.2794)
			(end 0.12065 -0.2794)
			(stroke
				(width 0.1)
				(type default)
			)
			(layer "F.Fab")
		)
		(fp_line
			(start -0.12065 0.2794)
			(end -0.12065 0.3048)
			(stroke
				(width 0.1)
				(type default)
			)
			(layer "F.Fab")
		)
		(fp_line
			(start -0.12065 0.3048)
			(end -0.67945 0.3048)
			(stroke
				(width 0.1)
				(type default)
			)
			(layer "F.Fab")
		)
		(fp_line
			(start 0.120396 0.2794)
			(end -0.12065 0.2794)
			(stroke
				(width 0.1)
				(type default)
			)
			(layer "F.Fab")
		)
		(fp_line
			(start 0.120396 0.3048)
			(end 0.120396 0.2794)
			(stroke
				(width 0.1)
				(type default)
			)
			(layer "F.Fab")
		)
		(fp_line
			(start 0.12065 -0.3048)
			(end 0.67945 -0.3048)
			(stroke
				(width 0.1)
				(type default)
			)
			(layer "F.Fab")
		)
		(fp_line
			(start 0.12065 -0.2794)
			(end 0.12065 -0.3048)
			(stroke
				(width 0.1)
				(type default)
			)
			(layer "F.Fab")
		)
		(fp_line
			(start 0.67945 -0.3048)
			(end 0.67945 0.3048)
			(stroke
				(width 0.1)
				(type default)
			)
			(layer "F.Fab")
		)
		(fp_line
			(start 0.67945 0.3048)
			(end 0.120396 0.3048)
			(stroke
				(width 0.1)
				(type default)
			)
			(layer "F.Fab")
		)
		(pad "1" smd circle
			(at -0.40005 0)
			(size 0 0)
			(layers "F.Cu" "F.Mask" "F.Paste")
			(net "SW_P12V_AUX_PVDDIO_P1_FLT")
		)
		(pad "2" smd circle
			(at 0.40005 0)
			(size 0 0)
			(layers "F.Cu" "F.Mask" "F.Paste")
			(net "GND")
		)
	)
	(footprint ""
		(layer "F.Cu")
		(at 10.066782 -413.231584)
		(property "Reference" "R663"
			(at 0 0 0)
			(layer "F.SilkS")
			(hide yes)
			(effects
				(font
					(size 1.27 1.27)
				)
			)
		)
		(property "Value" ""
			(at 0 0 0)
			(layer "F.Fab")
			(effects
				(font
					(size 1.27 1.27)
				)
			)
		)
		(duplicate_pad_numbers_are_jumpers no)
		(fp_line
			(start -0.7874 -0.4064)
			(end 0.7874 -0.4064)
			(stroke
				(width 0.1524)
				(type default)
			)
			(layer "F.SilkS")
		)
		(fp_line
			(start -0.7874 0.4064)
			(end -0.7874 -0.4064)
			(stroke
				(width 0.1524)
				(type default)
			)
			(layer "F.SilkS")
		)
		(fp_line
			(start 0.7874 -0.4064)
			(end 0.7874 0.4064)
			(stroke
				(width 0.1524)
				(type default)
			)
			(layer "F.SilkS")
		)
		(fp_line
			(start 0.7874 0.4064)
			(end -0.7874 0.4064)
			(stroke
				(width 0.1524)
				(type default)
			)
			(layer "F.SilkS")
		)
		(fp_line
			(start -0.67945 -0.305054)
			(end -0.12065 -0.305054)
			(stroke
				(width 0.1)
				(type default)
			)
			(layer "F.Fab")
		)
		(fp_line
			(start -0.67945 0.3048)
			(end -0.67945 -0.305054)
			(stroke
				(width 0.1)
				(type default)
			)
			(layer "F.Fab")
		)
		(fp_line
			(start -0.12065 -0.305054)
			(end -0.12065 -0.2794)
			(stroke
				(width 0.1)
				(type default)
			)
			(layer "F.Fab")
		)
		(fp_line
			(start -0.12065 -0.2794)
			(end 0.12065 -0.2794)
			(stroke
				(width 0.1)
				(type default)
			)
			(layer "F.Fab")
		)
		(fp_line
			(start -0.12065 0.2794)
			(end -0.12065 0.3048)
			(stroke
				(width 0.1)
				(type default)
			)
			(layer "F.Fab")
		)
		(fp_line
			(start -0.12065 0.3048)
			(end -0.67945 0.3048)
			(stroke
				(width 0.1)
				(type default)
			)
			(layer "F.Fab")
		)
		(fp_line
			(start 0.120396 0.2794)
			(end -0.12065 0.2794)
			(stroke
				(width 0.1)
				(type default)
			)
			(layer "F.Fab")
		)
		(fp_line
			(start 0.120396 0.3048)
			(end 0.120396 0.2794)
			(stroke
				(width 0.1)
				(type default)
			)
			(layer "F.Fab")
		)
		(fp_line
			(start 0.12065 -0.3048)
			(end 0.67945 -0.3048)
			(stroke
				(width 0.1)
				(type default)
			)
			(layer "F.Fab")
		)
		(fp_line
			(start 0.12065 -0.2794)
			(end 0.12065 -0.3048)
			(stroke
				(width 0.1)
				(type default)
			)
			(layer "F.Fab")
		)
		(fp_line
			(start 0.67945 -0.3048)
			(end 0.67945 0.3048)
			(stroke
				(width 0.1)
				(type default)
			)
			(layer "F.Fab")
		)
		(fp_line
			(start 0.67945 0.3048)
			(end 0.120396 0.3048)
			(stroke
				(width 0.1)
				(type default)
			)
			(layer "F.Fab")
		)
		(pad "1" smd circle
			(at -0.40005 0)
			(size 0 0)
			(layers "F.Cu" "F.Mask" "F.Paste")
			(net "P3V3_AUX")
		)
		(pad "2" smd circle
			(at 0.40005 0)
			(size 0 0)
			(layers "F.Cu" "F.Mask" "F.Paste")
			(net "P0V9_RETIMER_CPU1_CFP")
		)
	)
	(footprint ""
		(layer "F.Cu")
		(at 200.952608 -117.689376)
		(property "Reference" "R4148"
			(at 0 0 0)
			(layer "F.SilkS")
			(hide yes)
			(effects
				(font
					(size 1.27 1.27)
				)
			)
		)
		(property "Value" ""
			(at 0 0 0)
			(layer "F.Fab")
			(effects
				(font
					(size 1.27 1.27)
				)
			)
		)
		(duplicate_pad_numbers_are_jumpers no)
		(fp_line
			(start -0.7874 -0.4064)
			(end 0.7874 -0.4064)
			(stroke
				(width 0.1524)
				(type default)
			)
			(layer "F.SilkS")
		)
		(fp_line
			(start -0.7874 0.4064)
			(end -0.7874 -0.4064)
			(stroke
				(width 0.1524)
				(type default)
			)
			(layer "F.SilkS")
		)
		(fp_line
			(start 0.7874 -0.4064)
			(end 0.7874 0.4064)
			(stroke
				(width 0.1524)
				(type default)
			)
			(layer "F.SilkS")
		)
		(fp_line
			(start 0.7874 0.4064)
			(end -0.7874 0.4064)
			(stroke
				(width 0.1524)
				(type default)
			)
			(layer "F.SilkS")
		)
		(fp_line
			(start -0.67945 -0.305054)
			(end -0.12065 -0.305054)
			(stroke
				(width 0.1)
				(type default)
			)
			(layer "F.Fab")
		)
		(fp_line
			(start -0.67945 0.3048)
			(end -0.67945 -0.305054)
			(stroke
				(width 0.1)
				(type default)
			)
			(layer "F.Fab")
		)
		(fp_line
			(start -0.12065 -0.305054)
			(end -0.12065 -0.2794)
			(stroke
				(width 0.1)
				(type default)
			)
			(layer "F.Fab")
		)
		(fp_line
			(start -0.12065 -0.2794)
			(end 0.12065 -0.2794)
			(stroke
				(width 0.1)
				(type default)
			)
			(layer "F.Fab")
		)
		(fp_line
			(start -0.12065 0.2794)
			(end -0.12065 0.3048)
			(stroke
				(width 0.1)
				(type default)
			)
			(layer "F.Fab")
		)
		(fp_line
			(start -0.12065 0.3048)
			(end -0.67945 0.3048)
			(stroke
				(width 0.1)
				(type default)
			)
			(layer "F.Fab")
		)
		(fp_line
			(start 0.120396 0.2794)
			(end -0.12065 0.2794)
			(stroke
				(width 0.1)
				(type default)
			)
			(layer "F.Fab")
		)
		(fp_line
			(start 0.120396 0.3048)
			(end 0.120396 0.2794)
			(stroke
				(width 0.1)
				(type default)
			)
			(layer "F.Fab")
		)
		(fp_line
			(start 0.12065 -0.3048)
			(end 0.67945 -0.3048)
			(stroke
				(width 0.1)
				(type default)
			)
			(layer "F.Fab")
		)
		(fp_line
			(start 0.12065 -0.2794)
			(end 0.12065 -0.3048)
			(stroke
				(width 0.1)
				(type default)
			)
			(layer "F.Fab")
		)
		(fp_line
			(start 0.67945 -0.3048)
			(end 0.67945 0.3048)
			(stroke
				(width 0.1)
				(type default)
			)
			(layer "F.Fab")
		)
		(fp_line
			(start 0.67945 0.3048)
			(end 0.120396 0.3048)
			(stroke
				(width 0.1)
				(type default)
			)
			(layer "F.Fab")
		)
		(pad "1" smd circle
			(at -0.40005 0)
			(size 0 0)
			(layers "F.Cu" "F.Mask" "F.Paste")
			(net "GPU_3V3IO_RSVD5_FFU_ISO_R")
		)
		(pad "2" smd circle
			(at 0.40005 0)
			(size 0 0)
			(layers "F.Cu" "F.Mask" "F.Paste")
			(net "GPU_3V3IO_RSVD5_FFU_ISO")
		)
	)
	(footprint ""
		(layer "F.Cu")
		(at 151.627586 -408.517344 -90)
		(property "Reference" "C6718"
			(at 0 0 270)
			(layer "F.SilkS")
			(hide yes)
			(effects
				(font
					(size 1.27 1.27)
				)
			)
		)
		(property "Value" ""
			(at 0 0 270)
			(layer "F.Fab")
			(effects
				(font
					(size 1.27 1.27)
				)
			)
		)
		(duplicate_pad_numbers_are_jumpers no)
		(fp_line
			(start -0.299974 0.150114)
			(end -0.299974 -0.150114)
			(stroke
				(width 0.1)
				(type default)
			)
			(layer "F.Fab")
		)
		(fp_line
			(start 0.299974 0.150114)
			(end -0.299974 0.150114)
			(stroke
				(width 0.1)
				(type default)
			)
			(layer "F.Fab")
		)
		(fp_line
			(start -0.299974 -0.150114)
			(end 0.299974 -0.150114)
			(stroke
				(width 0.1)
				(type default)
			)
			(layer "F.Fab")
		)
		(fp_line
			(start 0.299974 -0.150114)
			(end 0.299974 0.150114)
			(stroke
				(width 0.1)
				(type default)
			)
			(layer "F.Fab")
		)
		(pad "1" smd rect
			(at -0.2667 0 270)
			(size 0.3048 0.381)
			(layers "F.Cu" "F.Mask" "F.Paste")
			(net "P5E_CPU1_P2_TX_BUF_C_DN<12>")
		)
		(pad "2" smd rect
			(at 0.2667 0 270)
			(size 0.3048 0.381)
			(layers "F.Cu" "F.Mask" "F.Paste")
			(net "P5E_CPU1_P2_TX_BUF_DN<12>")
		)
	)
	(footprint ""
		(layer "F.Cu")
		(at 421.962072 -255.560068 180)
		(property "Reference" "J69"
			(at 3.448304 81.947512 0)
			(unlocked yes)
			(layer "F.SilkS")
			(effects
				(font
					(size 0.7874 0.5842)
					(thickness 0.1524)
				)
			)
		)
		(property "Value" ""
			(at 0 0 180)
			(layer "F.Fab")
			(effects
				(font
					(size 1.27 1.27)
				)
			)
		)
		(duplicate_pad_numbers_are_jumpers no)
		(fp_line
			(start 3.24993 81.000092)
			(end 2.608072 81.000092)
			(stroke
				(width 0.1524)
				(type default)
			)
			(layer "F.SilkS")
		)
		(fp_line
			(start 3.24993 80.608932)
			(end 3.24993 81.000092)
			(stroke
				(width 0.1524)
				(type default)
			)
			(layer "F.SilkS")
		)
		(fp_line
			(start 3.24993 -81.000092)
			(end 3.24993 72.861932)
			(stroke
				(width 0.1524)
				(type default)
			)
			(layer "F.SilkS")
		)
		(fp_line
			(start 0.068072 81.000092)
			(end -3.24993 81.000092)
			(stroke
				(width 0.1524)
				(type default)
			)
			(layer "F.SilkS")
		)
		(fp_line
			(start -3.24993 72.861932)
			(end -3.24993 -80.554068)
			(stroke
				(width 0.1524)
				(type default)
			)
			(layer "F.SilkS")
		)
		(fp_line
			(start -3.24993 72.499982)
			(end 3.24993 72.499982)
			(stroke
				(width 0.1524)
				(type default)
			)
			(layer "F.SilkS")
		)
		(fp_line
			(start -3.24993 -72.499982)
			(end 3.24993 -72.499982)
			(stroke
				(width 0.1524)
				(type default)
			)
			(layer "F.SilkS")
		)
		(fp_poly
			(pts
				(xy -3.845052 -64.55156) (xy -3.3782 -63.912496) (xy -4.169664 -63.92291)
			)
			(stroke
				(width 0)
				(type default)
			)
			(fill yes)
			(layer "F.SilkS")
		)
		(fp_line
			(start 3.24993 81.000092)
			(end -3.24993 81.000092)
			(stroke
				(width 0.1)
				(type default)
			)
			(layer "F.Fab")
		)
		(fp_line
			(start 3.24993 -81.000092)
			(end 3.24993 81.000092)
			(stroke
				(width 0.1)
				(type default)
			)
			(layer "F.Fab")
		)
		(fp_line
			(start -3.24993 81.000092)
			(end -3.24993 -81.000092)
			(stroke
				(width 0.1)
				(type default)
			)
			(layer "F.Fab")
		)
		(fp_line
			(start -3.24993 72.499982)
			(end 3.24993 72.499982)
			(stroke
				(width 0.1)
				(type default)
			)
			(layer "F.Fab")
		)
		(fp_line
			(start -3.24993 71.000112)
			(end 3.24993 71.000112)
			(stroke
				(width 0.1)
				(type default)
			)
			(layer "F.Fab")
		)
		(fp_line
			(start -3.24993 -71.000112)
			(end 3.24993 -71.000112)
			(stroke
				(width 0.1)
				(type default)
			)
			(layer "F.Fab")
		)
		(fp_line
			(start -3.24993 -72.499982)
			(end 3.24993 -72.499982)
			(stroke
				(width 0.1)
				(type default)
			)
			(layer "F.Fab")
		)
		(fp_line
			(start -3.24993 -81.000092)
			(end 3.24993 -81.000092)
			(stroke
				(width 0.1)
				(type default)
			)
			(layer "F.Fab")
		)
		(fp_poly
			(pts
				(xy -3.41503 -63.324994) (xy -4.43103 -62.816994) (xy -4.43103 -63.832994)
			)
			(stroke
				(width 0)
				(type default)
			)
			(fill yes)
			(layer "F.Fab")
		)
		(pad "1" smd rect
			(at -2.050034 -63.324994 90)
			(size 0.519938 1.4986)
			(layers "F.Cu" "F.Mask" "F.Paste")
			(net "P12V_MEM_CPU0")
		)
		(pad "2" smd rect
			(at -2.050034 -62.47511 90)
			(size 0.519938 1.4986)
			(layers "F.Cu" "F.Mask" "F.Paste")
			(net "Net_2347")
		)
		(pad "3" smd rect
			(at -2.050034 -61.624972 90)
			(size 0.519938 1.4986)
			(layers "F.Cu" "F.Mask" "F.Paste")
			(net "P3V3_AUX")
		)
		(pad "4" smd rect
			(at -2.050034 -60.775088 90)
			(size 0.519938 1.4986)
			(layers "F.Cu" "F.Mask" "F.Paste")
			(net "I3C_SPD_DDRH_CPU0_SCL")
		)
		(pad "5" smd rect
			(at -2.050034 -59.92495 90)
			(size 0.519938 1.4986)
			(layers "F.Cu" "F.Mask" "F.Paste")
			(net "I3C_SPD_DDRH_CPU0_SDA")
		)
		(pad "6" smd rect
			(at -2.050034 -59.075066 90)
			(size 0.519938 1.4986)
			(layers "F.Cu" "F.Mask" "F.Paste")
			(net "GND")
		)
		(pad "7" smd rect
			(at -2.050034 -58.224928 90)
			(size 0.519938 1.4986)
			(layers "F.Cu" "F.Mask" "F.Paste")
			(net "M_H_CPU0_SA_DQ<0>")
		)
		(pad "8" smd rect
			(at -2.050034 -57.375044 90)
			(size 0.519938 1.4986)
			(layers "F.Cu" "F.Mask" "F.Paste")
			(net "GND")
		)
		(pad "9" smd rect
			(at -2.050034 -56.524906 90)
			(size 0.519938 1.4986)
			(layers "F.Cu" "F.Mask" "F.Paste")
			(net "M_H_CPU0_SA_DQ<1>")
		)
		(pad "10" smd rect
			(at -2.050034 -55.675022 90)
			(size 0.519938 1.4986)
			(layers "F.Cu" "F.Mask" "F.Paste")
			(net "GND")
		)
		(pad "11" smd rect
			(at -2.050034 -54.824884 90)
			(size 0.519938 1.4986)
			(layers "F.Cu" "F.Mask" "F.Paste")
			(net "M_H_CPU0_SA_DQS_DP<0>")
		)
		(pad "12" smd rect
			(at -2.050034 -53.975 90)
			(size 0.519938 1.4986)
			(layers "F.Cu" "F.Mask" "F.Paste")
			(net "M_H_CPU0_SA_DQS_DN<0>")
		)
		(pad "13" smd rect
			(at -2.050034 -53.125116 90)
			(size 0.519938 1.4986)
			(layers "F.Cu" "F.Mask" "F.Paste")
			(net "GND")
		)
		(pad "14" smd rect
			(at -2.050034 -52.274978 90)
			(size 0.519938 1.4986)
			(layers "F.Cu" "F.Mask" "F.Paste")
			(net "M_H_CPU0_SA_DQ<4>")
		)
		(pad "15" smd rect
			(at -2.050034 -51.425094 90)
			(size 0.519938 1.4986)
			(layers "F.Cu" "F.Mask" "F.Paste")
			(net "GND")
		)
		(pad "16" smd rect
			(at -2.050034 -50.574956 90)
			(size 0.519938 1.4986)
			(layers "F.Cu" "F.Mask" "F.Paste")
			(net "M_H_CPU0_SA_DQ<5>")
		)
		(pad "17" smd rect
			(at -2.050034 -49.725072 90)
			(size 0.519938 1.4986)
			(layers "F.Cu" "F.Mask" "F.Paste")
			(net "GND")
		)
		(pad "18" smd rect
			(at -2.050034 -48.874934 90)
			(size 0.519938 1.4986)
			(layers "F.Cu" "F.Mask" "F.Paste")
			(net "M_H_CPU0_SA_DQ<8>")
		)
		(pad "19" smd rect
			(at -2.050034 -48.02505 90)
			(size 0.519938 1.4986)
			(layers "F.Cu" "F.Mask" "F.Paste")
			(net "GND")
		)
		(pad "20" smd rect
			(at -2.050034 -47.174912 90)
			(size 0.519938 1.4986)
			(layers "F.Cu" "F.Mask" "F.Paste")
			(net "M_H_CPU0_SA_DQ<9>")
		)
		(pad "21" smd rect
			(at -2.050034 -46.325028 90)
			(size 0.519938 1.4986)
			(layers "F.Cu" "F.Mask" "F.Paste")
			(net "GND")
		)
		(pad "22" smd rect
			(at -2.050034 -45.47489 90)
			(size 0.519938 1.4986)
			(layers "F.Cu" "F.Mask" "F.Paste")
			(net "M_H_CPU0_SA_DQS_DP<1>")
		)
		(pad "23" smd rect
			(at -2.050034 -44.625006 90)
			(size 0.519938 1.4986)
			(layers "F.Cu" "F.Mask" "F.Paste")
			(net "M_H_CPU0_SA_DQS_DN<1>")
		)
		(pad "24" smd rect
			(at -2.050034 -43.775122 90)
			(size 0.519938 1.4986)
			(layers "F.Cu" "F.Mask" "F.Paste")
			(net "GND")
		)
		(pad "25" smd rect
			(at -2.050034 -42.924984 90)
			(size 0.519938 1.4986)
			(layers "F.Cu" "F.Mask" "F.Paste")
			(net "M_H_CPU0_SA_DQ<12>")
		)
		(pad "26" smd rect
			(at -2.050034 -42.0751 90)
			(size 0.519938 1.4986)
			(layers "F.Cu" "F.Mask" "F.Paste")
			(net "GND")
		)
		(pad "27" smd rect
			(at -2.050034 -41.224962 90)
			(size 0.519938 1.4986)
			(layers "F.Cu" "F.Mask" "F.Paste")
			(net "M_H_CPU0_SA_DQ<13>")
		)
		(pad "28" smd rect
			(at -2.050034 -40.375078 90)
			(size 0.519938 1.4986)
			(layers "F.Cu" "F.Mask" "F.Paste")
			(net "GND")
		)
		(pad "29" smd rect
			(at -2.050034 -39.52494 90)
			(size 0.519938 1.4986)
			(layers "F.Cu" "F.Mask" "F.Paste")
			(net "M_H_CPU0_SA_DQ<16>")
		)
		(pad "30" smd rect
			(at -2.050034 -38.675056 90)
			(size 0.519938 1.4986)
			(layers "F.Cu" "F.Mask" "F.Paste")
			(net "GND")
		)
		(pad "31" smd rect
			(at -2.050034 -37.824918 90)
			(size 0.519938 1.4986)
			(layers "F.Cu" "F.Mask" "F.Paste")
			(net "M_H_CPU0_SA_DQ<17>")
		)
		(pad "32" smd rect
			(at -2.050034 -36.975034 90)
			(size 0.519938 1.4986)
			(layers "F.Cu" "F.Mask" "F.Paste")
			(net "GND")
		)
		(pad "33" smd rect
			(at -2.050034 -36.124896 90)
			(size 0.519938 1.4986)
			(layers "F.Cu" "F.Mask" "F.Paste")
			(net "M_H_CPU0_SA_DQS_DP<2>")
		)
		(pad "34" smd rect
			(at -2.050034 -35.275012 90)
			(size 0.519938 1.4986)
			(layers "F.Cu" "F.Mask" "F.Paste")
			(net "M_H_CPU0_SA_DQS_DN<2>")
		)
		(pad "35" smd rect
			(at -2.050034 -34.425128 90)
			(size 0.519938 1.4986)
			(layers "F.Cu" "F.Mask" "F.Paste")
			(net "GND")
		)
		(pad "36" smd rect
			(at -2.050034 -33.57499 90)
			(size 0.519938 1.4986)
			(layers "F.Cu" "F.Mask" "F.Paste")
			(net "M_H_CPU0_SA_DQ<20>")
		)
		(pad "37" smd rect
			(at -2.050034 -32.725106 90)
			(size 0.519938 1.4986)
			(layers "F.Cu" "F.Mask" "F.Paste")
			(net "GND")
		)
		(pad "38" smd rect
			(at -2.050034 -31.874968 90)
			(size 0.519938 1.4986)
			(layers "F.Cu" "F.Mask" "F.Paste")
			(net "M_H_CPU0_SA_DQ<21>")
		)
		(pad "39" smd rect
			(at -2.050034 -31.025084 90)
			(size 0.519938 1.4986)
			(layers "F.Cu" "F.Mask" "F.Paste")
			(net "GND")
		)
		(pad "40" smd rect
			(at -2.050034 -30.174946 90)
			(size 0.519938 1.4986)
			(layers "F.Cu" "F.Mask" "F.Paste")
			(net "M_H_CPU0_SA_DQ<24>")
		)
		(pad "41" smd rect
			(at -2.050034 -29.325062 90)
			(size 0.519938 1.4986)
			(layers "F.Cu" "F.Mask" "F.Paste")
			(net "GND")
		)
		(pad "42" smd rect
			(at -2.050034 -28.474924 90)
			(size 0.519938 1.4986)
			(layers "F.Cu" "F.Mask" "F.Paste")
			(net "M_H_CPU0_SA_DQ<25>")
		)
		(pad "43" smd rect
			(at -2.050034 -27.62504 90)
			(size 0.519938 1.4986)
			(layers "F.Cu" "F.Mask" "F.Paste")
			(net "GND")
		)
		(pad "44" smd rect
			(at -2.050034 -26.774902 90)
			(size 0.519938 1.4986)
			(layers "F.Cu" "F.Mask" "F.Paste")
			(net "M_H_CPU0_SA_DQS_DP<3>")
		)
		(pad "45" smd rect
			(at -2.050034 -25.925018 90)
			(size 0.519938 1.4986)
			(layers "F.Cu" "F.Mask" "F.Paste")
			(net "M_H_CPU0_SA_DQS_DN<3>")
		)
		(pad "46" smd rect
			(at -2.050034 -25.07488 90)
			(size 0.519938 1.4986)
			(layers "F.Cu" "F.Mask" "F.Paste")
			(net "GND")
		)
		(pad "47" smd rect
			(at -2.050034 -24.224996 90)
			(size 0.519938 1.4986)
			(layers "F.Cu" "F.Mask" "F.Paste")
			(net "M_H_CPU0_SA_DQ<28>")
		)
		(pad "48" smd rect
			(at -2.050034 -23.375112 90)
			(size 0.519938 1.4986)
			(layers "F.Cu" "F.Mask" "F.Paste")
			(net "GND")
		)
		(pad "49" smd rect
			(at -2.050034 -22.524974 90)
			(size 0.519938 1.4986)
			(layers "F.Cu" "F.Mask" "F.Paste")
			(net "M_H_CPU0_SA_DQ<29>")
		)
		(pad "50" smd rect
			(at -2.050034 -21.67509 90)
			(size 0.519938 1.4986)
			(layers "F.Cu" "F.Mask" "F.Paste")
			(net "GND")
		)
		(pad "51" smd rect
			(at -2.050034 -20.824952 90)
			(size 0.519938 1.4986)
			(layers "F.Cu" "F.Mask" "F.Paste")
			(net "M_H_CPU0_SA_CB<0>")
		)
		(pad "52" smd rect
			(at -2.050034 -19.975068 90)
			(size 0.519938 1.4986)
			(layers "F.Cu" "F.Mask" "F.Paste")
			(net "GND")
		)
		(pad "53" smd rect
			(at -2.050034 -19.12493 90)
			(size 0.519938 1.4986)
			(layers "F.Cu" "F.Mask" "F.Paste")
			(net "M_H_CPU0_SA_CB<1>")
		)
		(pad "54" smd rect
			(at -2.050034 -18.275046 90)
			(size 0.519938 1.4986)
			(layers "F.Cu" "F.Mask" "F.Paste")
			(net "GND")
		)
		(pad "55" smd rect
			(at -2.050034 -17.424908 90)
			(size 0.519938 1.4986)
			(layers "F.Cu" "F.Mask" "F.Paste")
			(net "M_H_CPU0_SA_DQS_DP<4>")
		)
		(pad "56" smd rect
			(at -2.050034 -16.575024 90)
			(size 0.519938 1.4986)
			(layers "F.Cu" "F.Mask" "F.Paste")
			(net "M_H_CPU0_SA_DQS_DN<4>")
		)
		(pad "57" smd rect
			(at -2.050034 -15.724886 90)
			(size 0.519938 1.4986)
			(layers "F.Cu" "F.Mask" "F.Paste")
			(net "GND")
		)
		(pad "58" smd rect
			(at -2.050034 -14.875002 90)
			(size 0.519938 1.4986)
			(layers "F.Cu" "F.Mask" "F.Paste")
			(net "M_H_CPU0_SA_CB<4>")
		)
		(pad "59" smd rect
			(at -2.050034 -14.025118 90)
			(size 0.519938 1.4986)
			(layers "F.Cu" "F.Mask" "F.Paste")
			(net "GND")
		)
		(pad "60" smd rect
			(at -2.050034 -13.17498 90)
			(size 0.519938 1.4986)
			(layers "F.Cu" "F.Mask" "F.Paste")
			(net "M_H_CPU0_SA_CB<5>")
		)
		(pad "61" smd rect
			(at -2.050034 -12.325096 90)
			(size 0.519938 1.4986)
			(layers "F.Cu" "F.Mask" "F.Paste")
			(net "GND")
		)
		(pad "62" smd rect
			(at -2.050034 -11.474958 90)
			(size 0.519938 1.4986)
			(layers "F.Cu" "F.Mask" "F.Paste")
			(net "M_H_CPU0_ALERT_N")
		)
		(pad "63" smd rect
			(at -2.050034 -10.625074 90)
			(size 0.519938 1.4986)
			(layers "F.Cu" "F.Mask" "F.Paste")
			(net "GND")
		)
		(pad "64" smd rect
			(at -2.050034 -9.774936 90)
			(size 0.519938 1.4986)
			(layers "F.Cu" "F.Mask" "F.Paste")
			(net "M_H_CPU0_SA_CS_N<0>")
		)
		(pad "65" smd rect
			(at -2.050034 -8.925052 90)
			(size 0.519938 1.4986)
			(layers "F.Cu" "F.Mask" "F.Paste")
			(net "GND")
		)
		(pad "66" smd rect
			(at -2.050034 -8.074914 90)
			(size 0.519938 1.4986)
			(layers "F.Cu" "F.Mask" "F.Paste")
			(net "M_H_CPU0_SA_CA<0>")
		)
		(pad "67" smd rect
			(at -2.050034 -7.22503 90)
			(size 0.519938 1.4986)
			(layers "F.Cu" "F.Mask" "F.Paste")
			(net "GND")
		)
		(pad "68" smd rect
			(at -2.050034 -6.374892 90)
			(size 0.519938 1.4986)
			(layers "F.Cu" "F.Mask" "F.Paste")
			(net "M_H_CPU0_SA_CA<2>")
		)
		(pad "69" smd rect
			(at -2.050034 -5.525008 90)
			(size 0.519938 1.4986)
			(layers "F.Cu" "F.Mask" "F.Paste")
			(net "GND")
		)
		(pad "70" smd rect
			(at -2.050034 -4.675124 90)
			(size 0.519938 1.4986)
			(layers "F.Cu" "F.Mask" "F.Paste")
			(net "M_H_CPU0_SA_CA<4>")
		)
		(pad "71" smd rect
			(at -2.050034 -3.824986 90)
			(size 0.519938 1.4986)
			(layers "F.Cu" "F.Mask" "F.Paste")
			(net "GND")
		)
		(pad "72" smd rect
			(at -2.050034 -2.975102 90)
			(size 0.519938 1.4986)
			(layers "F.Cu" "F.Mask" "F.Paste")
			(net "M_H_CPU0_SA_CA<6>")
		)
		(pad "73" smd rect
			(at -2.050034 -2.124964 90)
			(size 0.519938 1.4986)
			(layers "F.Cu" "F.Mask" "F.Paste")
			(net "GND")
		)
		(pad "74" smd rect
			(at -2.050034 -1.27508 90)
			(size 0.519938 1.4986)
			(layers "F.Cu" "F.Mask" "F.Paste")
			(net "M_H_CPU0_SA_PAR")
		)
		(pad "75" smd rect
			(at -2.050034 -0.424942 90)
			(size 0.519938 1.4986)
			(layers "F.Cu" "F.Mask" "F.Paste")
			(net "GND")
		)
		(pad "76" smd rect
			(at -2.050034 5.525008 90)
			(size 0.519938 1.4986)
			(layers "F.Cu" "F.Mask" "F.Paste")
			(net "M_H_CPU0_SB_CA<0>")
		)
		(pad "77" smd rect
			(at -2.050034 6.374892 90)
			(size 0.519938 1.4986)
			(layers "F.Cu" "F.Mask" "F.Paste")
			(net "GND")
		)
		(pad "78" smd rect
			(at -2.050034 7.22503 90)
			(size 0.519938 1.4986)
			(layers "F.Cu" "F.Mask" "F.Paste")
			(net "M_H_CPU0_SB_CA<2>")
		)
		(pad "79" smd rect
			(at -2.050034 8.074914 90)
			(size 0.519938 1.4986)
			(layers "F.Cu" "F.Mask" "F.Paste")
			(net "GND")
		)
		(pad "80" smd rect
			(at -2.050034 8.925052 90)
			(size 0.519938 1.4986)
			(layers "F.Cu" "F.Mask" "F.Paste")
			(net "M_H_CPU0_SB_CA<4>")
		)
		(pad "81" smd rect
			(at -2.050034 9.774936 90)
			(size 0.519938 1.4986)
			(layers "F.Cu" "F.Mask" "F.Paste")
			(net "GND")
		)
		(pad "82" smd rect
			(at -2.050034 10.625074 90)
			(size 0.519938 1.4986)
			(layers "F.Cu" "F.Mask" "F.Paste")
			(net "M_H_CPU0_SB_CA<6>")
		)
		(pad "83" smd rect
			(at -2.050034 11.474958 90)
			(size 0.519938 1.4986)
			(layers "F.Cu" "F.Mask" "F.Paste")
			(net "GND")
		)
		(pad "84" smd rect
			(at -2.050034 12.325096 90)
			(size 0.519938 1.4986)
			(layers "F.Cu" "F.Mask" "F.Paste")
			(net "M_H_CPU0_SB_CS_N<0>")
		)
		(pad "85" smd rect
			(at -2.050034 13.17498 90)
			(size 0.519938 1.4986)
			(layers "F.Cu" "F.Mask" "F.Paste")
			(net "GND")
		)
		(pad "86" smd rect
			(at -2.050034 14.025118 90)
			(size 0.519938 1.4986)
			(layers "F.Cu" "F.Mask" "F.Paste")
			(net "M_H_CPU0_SA_RSP<0>")
		)
		(pad "87" smd rect
			(at -2.050034 14.875002 90)
			(size 0.519938 1.4986)
			(layers "F.Cu" "F.Mask" "F.Paste")
			(net "M_H_CPU0_SB_RSP<0>")
		)
		(pad "88" smd rect
			(at -2.050034 15.724886 90)
			(size 0.519938 1.4986)
			(layers "F.Cu" "F.Mask" "F.Paste")
			(net "GND")
		)
		(pad "89" smd rect
			(at -2.050034 16.575024 90)
			(size 0.519938 1.4986)
			(layers "F.Cu" "F.Mask" "F.Paste")
			(net "M_H_CPU0_SB_CB<4>")
		)
		(pad "90" smd rect
			(at -2.050034 17.424908 90)
			(size 0.519938 1.4986)
			(layers "F.Cu" "F.Mask" "F.Paste")
			(net "GND")
		)
		(pad "91" smd rect
			(at -2.050034 18.275046 90)
			(size 0.519938 1.4986)
			(layers "F.Cu" "F.Mask" "F.Paste")
			(net "M_H_CPU0_SB_CB<5>")
		)
		(pad "92" smd rect
			(at -2.050034 19.12493 90)
			(size 0.519938 1.4986)
			(layers "F.Cu" "F.Mask" "F.Paste")
			(net "GND")
		)
		(pad "93" smd rect
			(at -2.050034 19.975068 90)
			(size 0.519938 1.4986)
			(layers "F.Cu" "F.Mask" "F.Paste")
			(net "M_H_CPU0_SB_DQS_DP<9>")
		)
		(pad "94" smd rect
			(at -2.050034 20.824952 90)
			(size 0.519938 1.4986)
			(layers "F.Cu" "F.Mask" "F.Paste")
			(net "M_H_CPU0_SB_DQS_DN<9>")
		)
		(pad "95" smd rect
			(at -2.050034 21.67509 90)
			(size 0.519938 1.4986)
			(layers "F.Cu" "F.Mask" "F.Paste")
			(net "GND")
		)
		(pad "96" smd rect
			(at -2.050034 22.524974 90)
			(size 0.519938 1.4986)
			(layers "F.Cu" "F.Mask" "F.Paste")
			(net "M_H_CPU0_SB_CB<0>")
		)
		(pad "97" smd rect
			(at -2.050034 23.375112 90)
			(size 0.519938 1.4986)
			(layers "F.Cu" "F.Mask" "F.Paste")
			(net "GND")
		)
		(pad "98" smd rect
			(at -2.050034 24.224996 90)
			(size 0.519938 1.4986)
			(layers "F.Cu" "F.Mask" "F.Paste")
			(net "M_H_CPU0_SB_CB<1>")
		)
		(pad "99" smd rect
			(at -2.050034 25.07488 90)
			(size 0.519938 1.4986)
			(layers "F.Cu" "F.Mask" "F.Paste")
			(net "GND")
		)
		(pad "100" smd rect
			(at -2.050034 25.925018 90)
			(size 0.519938 1.4986)
			(layers "F.Cu" "F.Mask" "F.Paste")
			(net "M_H_CPU0_SB_DQ<0>")
		)
		(pad "101" smd rect
			(at -2.050034 26.774902 90)
			(size 0.519938 1.4986)
			(layers "F.Cu" "F.Mask" "F.Paste")
			(net "GND")
		)
		(pad "102" smd rect
			(at -2.050034 27.62504 90)
			(size 0.519938 1.4986)
			(layers "F.Cu" "F.Mask" "F.Paste")
			(net "M_H_CPU0_SB_DQ<1>")
		)
		(pad "103" smd rect
			(at -2.050034 28.474924 90)
			(size 0.519938 1.4986)
			(layers "F.Cu" "F.Mask" "F.Paste")
			(net "GND")
		)
		(pad "104" smd rect
			(at -2.050034 29.325062 90)
			(size 0.519938 1.4986)
			(layers "F.Cu" "F.Mask" "F.Paste")
			(net "M_H_CPU0_SB_DQS_DP<0>")
		)
		(pad "105" smd rect
			(at -2.050034 30.174946 90)
			(size 0.519938 1.4986)
			(layers "F.Cu" "F.Mask" "F.Paste")
			(net "M_H_CPU0_SB_DQS_DN<0>")
		)
		(pad "106" smd rect
			(at -2.050034 31.025084 90)
			(size 0.519938 1.4986)
			(layers "F.Cu" "F.Mask" "F.Paste")
			(net "GND")
		)
		(pad "107" smd rect
			(at -2.050034 31.874968 90)
			(size 0.519938 1.4986)
			(layers "F.Cu" "F.Mask" "F.Paste")
			(net "M_H_CPU0_SB_DQ<4>")
		)
		(pad "108" smd rect
			(at -2.050034 32.725106 90)
			(size 0.519938 1.4986)
			(layers "F.Cu" "F.Mask" "F.Paste")
			(net "GND")
		)
		(pad "109" smd rect
			(at -2.050034 33.57499 90)
			(size 0.519938 1.4986)
			(layers "F.Cu" "F.Mask" "F.Paste")
			(net "M_H_CPU0_SB_DQ<5>")
		)
		(pad "110" smd rect
			(at -2.050034 34.425128 90)
			(size 0.519938 1.4986)
			(layers "F.Cu" "F.Mask" "F.Paste")
			(net "GND")
		)
		(pad "111" smd rect
			(at -2.050034 35.275012 90)
			(size 0.519938 1.4986)
			(layers "F.Cu" "F.Mask" "F.Paste")
			(net "M_H_CPU0_SB_DQ<8>")
		)
		(pad "112" smd rect
			(at -2.050034 36.124896 90)
			(size 0.519938 1.4986)
			(layers "F.Cu" "F.Mask" "F.Paste")
			(net "GND")
		)
		(pad "113" smd rect
			(at -2.050034 36.975034 90)
			(size 0.519938 1.4986)
			(layers "F.Cu" "F.Mask" "F.Paste")
			(net "M_H_CPU0_SB_DQ<9>")
		)
		(pad "114" smd rect
			(at -2.050034 37.824918 90)
			(size 0.519938 1.4986)
			(layers "F.Cu" "F.Mask" "F.Paste")
			(net "GND")
		)
		(pad "115" smd rect
			(at -2.050034 38.675056 90)
			(size 0.519938 1.4986)
			(layers "F.Cu" "F.Mask" "F.Paste")
			(net "M_H_CPU0_SB_DQS_DP<1>")
		)
		(pad "116" smd rect
			(at -2.050034 39.52494 90)
			(size 0.519938 1.4986)
			(layers "F.Cu" "F.Mask" "F.Paste")
			(net "M_H_CPU0_SB_DQS_DN<1>")
		)
		(pad "117" smd rect
			(at -2.050034 40.375078 90)
			(size 0.519938 1.4986)
			(layers "F.Cu" "F.Mask" "F.Paste")
			(net "GND")
		)
		(pad "118" smd rect
			(at -2.050034 41.224962 90)
			(size 0.519938 1.4986)
			(layers "F.Cu" "F.Mask" "F.Paste")
			(net "M_H_CPU0_SB_DQ<12>")
		)
		(pad "119" smd rect
			(at -2.050034 42.0751 90)
			(size 0.519938 1.4986)
			(layers "F.Cu" "F.Mask" "F.Paste")
			(net "GND")
		)
		(pad "120" smd rect
			(at -2.050034 42.924984 90)
			(size 0.519938 1.4986)
			(layers "F.Cu" "F.Mask" "F.Paste")
			(net "M_H_CPU0_SB_DQ<13>")
		)
		(pad "121" smd rect
			(at -2.050034 43.775122 90)
			(size 0.519938 1.4986)
			(layers "F.Cu" "F.Mask" "F.Paste")
			(net "GND")
		)
		(pad "122" smd rect
			(at -2.050034 44.625006 90)
			(size 0.519938 1.4986)
			(layers "F.Cu" "F.Mask" "F.Paste")
			(net "M_H_CPU0_SB_DQ<16>")
		)
		(pad "123" smd rect
			(at -2.050034 45.47489 90)
			(size 0.519938 1.4986)
			(layers "F.Cu" "F.Mask" "F.Paste")
			(net "GND")
		)
		(pad "124" smd rect
			(at -2.050034 46.325028 90)
			(size 0.519938 1.4986)
			(layers "F.Cu" "F.Mask" "F.Paste")
			(net "M_H_CPU0_SB_DQ<17>")
		)
		(pad "125" smd rect
			(at -2.050034 47.174912 90)
			(size 0.519938 1.4986)
			(layers "F.Cu" "F.Mask" "F.Paste")
			(net "GND")
		)
		(pad "126" smd rect
			(at -2.050034 48.02505 90)
			(size 0.519938 1.4986)
			(layers "F.Cu" "F.Mask" "F.Paste")
			(net "M_H_CPU0_SB_DQS_DP<2>")
		)
		(pad "127" smd rect
			(at -2.050034 48.874934 90)
			(size 0.519938 1.4986)
			(layers "F.Cu" "F.Mask" "F.Paste")
			(net "M_H_CPU0_SB_DQS_DN<2>")
		)
		(pad "128" smd rect
			(at -2.050034 49.725072 90)
			(size 0.519938 1.4986)
			(layers "F.Cu" "F.Mask" "F.Paste")
			(net "GND")
		)
		(pad "129" smd rect
			(at -2.050034 50.574956 90)
			(size 0.519938 1.4986)
			(layers "F.Cu" "F.Mask" "F.Paste")
			(net "M_H_CPU0_SB_DQ<20>")
		)
		(pad "130" smd rect
			(at -2.050034 51.425094 90)
			(size 0.519938 1.4986)
			(layers "F.Cu" "F.Mask" "F.Paste")
			(net "GND")
		)
		(pad "131" smd rect
			(at -2.050034 52.274978 90)
			(size 0.519938 1.4986)
			(layers "F.Cu" "F.Mask" "F.Paste")
			(net "M_H_CPU0_SB_DQ<21>")
		)
		(pad "132" smd rect
			(at -2.050034 53.125116 90)
			(size 0.519938 1.4986)
			(layers "F.Cu" "F.Mask" "F.Paste")
			(net "GND")
		)
		(pad "133" smd rect
			(at -2.050034 53.975 90)
			(size 0.519938 1.4986)
			(layers "F.Cu" "F.Mask" "F.Paste")
			(net "M_H_CPU0_SB_DQ<24>")
		)
		(pad "134" smd rect
			(at -2.050034 54.824884 90)
			(size 0.519938 1.4986)
			(layers "F.Cu" "F.Mask" "F.Paste")
			(net "GND")
		)
		(pad "135" smd rect
			(at -2.050034 55.675022 90)
			(size 0.519938 1.4986)
			(layers "F.Cu" "F.Mask" "F.Paste")
			(net "M_H_CPU0_SB_DQ<25>")
		)
		(pad "136" smd rect
			(at -2.050034 56.524906 90)
			(size 0.519938 1.4986)
			(layers "F.Cu" "F.Mask" "F.Paste")
			(net "GND")
		)
		(pad "137" smd rect
			(at -2.050034 57.375044 90)
			(size 0.519938 1.4986)
			(layers "F.Cu" "F.Mask" "F.Paste")
			(net "M_H_CPU0_SB_DQS_DP<3>")
		)
		(pad "138" smd rect
			(at -2.050034 58.224928 90)
			(size 0.519938 1.4986)
			(layers "F.Cu" "F.Mask" "F.Paste")
			(net "M_H_CPU0_SB_DQS_DN<3>")
		)
		(pad "139" smd rect
			(at -2.050034 59.075066 90)
			(size 0.519938 1.4986)
			(layers "F.Cu" "F.Mask" "F.Paste")
			(net "GND")
		)
		(pad "140" smd rect
			(at -2.050034 59.92495 90)
			(size 0.519938 1.4986)
			(layers "F.Cu" "F.Mask" "F.Paste")
			(net "M_H_CPU0_SB_DQ<28>")
		)
		(pad "141" smd rect
			(at -2.050034 60.775088 90)
			(size 0.519938 1.4986)
			(layers "F.Cu" "F.Mask" "F.Paste")
			(net "GND")
		)
		(pad "142" smd rect
			(at -2.050034 61.624972 90)
			(size 0.519938 1.4986)
			(layers "F.Cu" "F.Mask" "F.Paste")
			(net "M_H_CPU0_SB_DQ<29>")
		)
		(pad "143" smd rect
			(at -2.050034 62.47511 90)
			(size 0.519938 1.4986)
			(layers "F.Cu" "F.Mask" "F.Paste")
			(net "GND")
		)
		(pad "144" smd rect
			(at -2.050034 63.324994 90)
			(size 0.519938 1.4986)
			(layers "F.Cu" "F.Mask" "F.Paste")
			(net "Net_2348")
		)
		(pad "145" smd rect
			(at 2.050034 -63.324994 90)
			(size 0.519938 1.4986)
			(layers "F.Cu" "F.Mask" "F.Paste")
			(net "P12V_MEM_CPU0")
		)
		(pad "146" smd rect
			(at 2.050034 -62.47511 90)
			(size 0.519938 1.4986)
			(layers "F.Cu" "F.Mask" "F.Paste")
			(net "P12V_MEM_CPU0")
		)
		(pad "147" smd rect
			(at 2.050034 -61.624972 90)
			(size 0.519938 1.4986)
			(layers "F.Cu" "F.Mask" "F.Paste")
			(net "PWRGD_CHH_CPU0_DIMM")
		)
		(pad "148" smd rect
			(at 2.050034 -60.775088 90)
			(size 0.519938 1.4986)
			(layers "F.Cu" "F.Mask" "F.Paste")
			(net "PD_CHH_CPU0_DIMM_SAA")
		)
		(pad "149" smd rect
			(at 2.050034 -59.92495 90)
			(size 0.519938 1.4986)
			(layers "F.Cu" "F.Mask" "F.Paste")
			(net "Net_2349")
		)
		(pad "150" smd rect
			(at 2.050034 -59.075066 90)
			(size 0.519938 1.4986)
			(layers "F.Cu" "F.Mask" "F.Paste")
			(net "Net_2350")
		)
		(pad "151" smd rect
			(at 2.050034 -58.224928 90)
			(size 0.519938 1.4986)
			(layers "F.Cu" "F.Mask" "F.Paste")
			(net "GND")
		)
		(pad "152" smd rect
			(at 2.050034 -57.375044 90)
			(size 0.519938 1.4986)
			(layers "F.Cu" "F.Mask" "F.Paste")
			(net "M_H_CPU0_SA_DQ<2>")
		)
		(pad "153" smd rect
			(at 2.050034 -56.524906 90)
			(size 0.519938 1.4986)
			(layers "F.Cu" "F.Mask" "F.Paste")
			(net "GND")
		)
		(pad "154" smd rect
			(at 2.050034 -55.675022 90)
			(size 0.519938 1.4986)
			(layers "F.Cu" "F.Mask" "F.Paste")
			(net "M_H_CPU0_SA_DQ<3>")
		)
		(pad "155" smd rect
			(at 2.050034 -54.824884 90)
			(size 0.519938 1.4986)
			(layers "F.Cu" "F.Mask" "F.Paste")
			(net "GND")
		)
		(pad "156" smd rect
			(at 2.050034 -53.975 90)
			(size 0.519938 1.4986)
			(layers "F.Cu" "F.Mask" "F.Paste")
			(net "M_H_CPU0_SA_DQS_DN<5>")
		)
		(pad "157" smd rect
			(at 2.050034 -53.125116 90)
			(size 0.519938 1.4986)
			(layers "F.Cu" "F.Mask" "F.Paste")
			(net "M_H_CPU0_SA_DQS_DP<5>")
		)
		(pad "158" smd rect
			(at 2.050034 -52.274978 90)
			(size 0.519938 1.4986)
			(layers "F.Cu" "F.Mask" "F.Paste")
			(net "GND")
		)
		(pad "159" smd rect
			(at 2.050034 -51.425094 90)
			(size 0.519938 1.4986)
			(layers "F.Cu" "F.Mask" "F.Paste")
			(net "M_H_CPU0_SA_DQ<6>")
		)
		(pad "160" smd rect
			(at 2.050034 -50.574956 90)
			(size 0.519938 1.4986)
			(layers "F.Cu" "F.Mask" "F.Paste")
			(net "GND")
		)
		(pad "161" smd rect
			(at 2.050034 -49.725072 90)
			(size 0.519938 1.4986)
			(layers "F.Cu" "F.Mask" "F.Paste")
			(net "M_H_CPU0_SA_DQ<7>")
		)
		(pad "162" smd rect
			(at 2.050034 -48.874934 90)
			(size 0.519938 1.4986)
			(layers "F.Cu" "F.Mask" "F.Paste")
			(net "GND")
		)
		(pad "163" smd rect
			(at 2.050034 -48.02505 90)
			(size 0.519938 1.4986)
			(layers "F.Cu" "F.Mask" "F.Paste")
			(net "M_H_CPU0_SA_DQ<10>")
		)
		(pad "164" smd rect
			(at 2.050034 -47.174912 90)
			(size 0.519938 1.4986)
			(layers "F.Cu" "F.Mask" "F.Paste")
			(net "GND")
		)
		(pad "165" smd rect
			(at 2.050034 -46.325028 90)
			(size 0.519938 1.4986)
			(layers "F.Cu" "F.Mask" "F.Paste")
			(net "M_H_CPU0_SA_DQ<11>")
		)
		(pad "166" smd rect
			(at 2.050034 -45.47489 90)
			(size 0.519938 1.4986)
			(layers "F.Cu" "F.Mask" "F.Paste")
			(net "GND")
		)
		(pad "167" smd rect
			(at 2.050034 -44.625006 90)
			(size 0.519938 1.4986)
			(layers "F.Cu" "F.Mask" "F.Paste")
			(net "M_H_CPU0_SA_DQS_DN<6>")
		)
		(pad "168" smd rect
			(at 2.050034 -43.775122 90)
			(size 0.519938 1.4986)
			(layers "F.Cu" "F.Mask" "F.Paste")
			(net "M_H_CPU0_SA_DQS_DP<6>")
		)
		(pad "169" smd rect
			(at 2.050034 -42.924984 90)
			(size 0.519938 1.4986)
			(layers "F.Cu" "F.Mask" "F.Paste")
			(net "GND")
		)
		(pad "170" smd rect
			(at 2.050034 -42.0751 90)
			(size 0.519938 1.4986)
			(layers "F.Cu" "F.Mask" "F.Paste")
			(net "M_H_CPU0_SA_DQ<14>")
		)
		(pad "171" smd rect
			(at 2.050034 -41.224962 90)
			(size 0.519938 1.4986)
			(layers "F.Cu" "F.Mask" "F.Paste")
			(net "GND")
		)
		(pad "172" smd rect
			(at 2.050034 -40.375078 90)
			(size 0.519938 1.4986)
			(layers "F.Cu" "F.Mask" "F.Paste")
			(net "M_H_CPU0_SA_DQ<15>")
		)
		(pad "173" smd rect
			(at 2.050034 -39.52494 90)
			(size 0.519938 1.4986)
			(layers "F.Cu" "F.Mask" "F.Paste")
			(net "GND")
		)
		(pad "174" smd rect
			(at 2.050034 -38.675056 90)
			(size 0.519938 1.4986)
			(layers "F.Cu" "F.Mask" "F.Paste")
			(net "M_H_CPU0_SA_DQ<18>")
		)
		(pad "175" smd rect
			(at 2.050034 -37.824918 90)
			(size 0.519938 1.4986)
			(layers "F.Cu" "F.Mask" "F.Paste")
			(net "GND")
		)
		(pad "176" smd rect
			(at 2.050034 -36.975034 90)
			(size 0.519938 1.4986)
			(layers "F.Cu" "F.Mask" "F.Paste")
			(net "M_H_CPU0_SA_DQ<19>")
		)
		(pad "177" smd rect
			(at 2.050034 -36.124896 90)
			(size 0.519938 1.4986)
			(layers "F.Cu" "F.Mask" "F.Paste")
			(net "GND")
		)
		(pad "178" smd rect
			(at 2.050034 -35.275012 90)
			(size 0.519938 1.4986)
			(layers "F.Cu" "F.Mask" "F.Paste")
			(net "M_H_CPU0_SA_DQS_DN<7>")
		)
		(pad "179" smd rect
			(at 2.050034 -34.425128 90)
			(size 0.519938 1.4986)
			(layers "F.Cu" "F.Mask" "F.Paste")
			(net "M_H_CPU0_SA_DQS_DP<7>")
		)
		(pad "180" smd rect
			(at 2.050034 -33.57499 90)
			(size 0.519938 1.4986)
			(layers "F.Cu" "F.Mask" "F.Paste")
			(net "GND")
		)
		(pad "181" smd rect
			(at 2.050034 -32.725106 90)
			(size 0.519938 1.4986)
			(layers "F.Cu" "F.Mask" "F.Paste")
			(net "M_H_CPU0_SA_DQ<22>")
		)
		(pad "182" smd rect
			(at 2.050034 -31.874968 90)
			(size 0.519938 1.4986)
			(layers "F.Cu" "F.Mask" "F.Paste")
			(net "GND")
		)
		(pad "183" smd rect
			(at 2.050034 -31.025084 90)
			(size 0.519938 1.4986)
			(layers "F.Cu" "F.Mask" "F.Paste")
			(net "M_H_CPU0_SA_DQ<23>")
		)
		(pad "184" smd rect
			(at 2.050034 -30.174946 90)
			(size 0.519938 1.4986)
			(layers "F.Cu" "F.Mask" "F.Paste")
			(net "GND")
		)
		(pad "185" smd rect
			(at 2.050034 -29.325062 90)
			(size 0.519938 1.4986)
			(layers "F.Cu" "F.Mask" "F.Paste")
			(net "M_H_CPU0_SA_DQ<26>")
		)
		(pad "186" smd rect
			(at 2.050034 -28.474924 90)
			(size 0.519938 1.4986)
			(layers "F.Cu" "F.Mask" "F.Paste")
			(net "GND")
		)
		(pad "187" smd rect
			(at 2.050034 -27.62504 90)
			(size 0.519938 1.4986)
			(layers "F.Cu" "F.Mask" "F.Paste")
			(net "M_H_CPU0_SA_DQ<27>")
		)
		(pad "188" smd rect
			(at 2.050034 -26.774902 90)
			(size 0.519938 1.4986)
			(layers "F.Cu" "F.Mask" "F.Paste")
			(net "GND")
		)
		(pad "189" smd rect
			(at 2.050034 -25.925018 90)
			(size 0.519938 1.4986)
			(layers "F.Cu" "F.Mask" "F.Paste")
			(net "M_H_CPU0_SA_DQS_DN<8>")
		)
		(pad "190" smd rect
			(at 2.050034 -25.07488 90)
			(size 0.519938 1.4986)
			(layers "F.Cu" "F.Mask" "F.Paste")
			(net "M_H_CPU0_SA_DQS_DP<8>")
		)
		(pad "191" smd rect
			(at 2.050034 -24.224996 90)
			(size 0.519938 1.4986)
			(layers "F.Cu" "F.Mask" "F.Paste")
			(net "GND")
		)
		(pad "192" smd rect
			(at 2.050034 -23.375112 90)
			(size 0.519938 1.4986)
			(layers "F.Cu" "F.Mask" "F.Paste")
			(net "M_H_CPU0_SA_DQ<30>")
		)
		(pad "193" smd rect
			(at 2.050034 -22.524974 90)
			(size 0.519938 1.4986)
			(layers "F.Cu" "F.Mask" "F.Paste")
			(net "GND")
		)
		(pad "194" smd rect
			(at 2.050034 -21.67509 90)
			(size 0.519938 1.4986)
			(layers "F.Cu" "F.Mask" "F.Paste")
			(net "M_H_CPU0_SA_DQ<31>")
		)
		(pad "195" smd rect
			(at 2.050034 -20.824952 90)
			(size 0.519938 1.4986)
			(layers "F.Cu" "F.Mask" "F.Paste")
			(net "GND")
		)
		(pad "196" smd rect
			(at 2.050034 -19.975068 90)
			(size 0.519938 1.4986)
			(layers "F.Cu" "F.Mask" "F.Paste")
			(net "M_H_CPU0_SA_CB<2>")
		)
		(pad "197" smd rect
			(at 2.050034 -19.12493 90)
			(size 0.519938 1.4986)
			(layers "F.Cu" "F.Mask" "F.Paste")
			(net "GND")
		)
		(pad "198" smd rect
			(at 2.050034 -18.275046 90)
			(size 0.519938 1.4986)
			(layers "F.Cu" "F.Mask" "F.Paste")
			(net "M_H_CPU0_SA_CB<3>")
		)
		(pad "199" smd rect
			(at 2.050034 -17.424908 90)
			(size 0.519938 1.4986)
			(layers "F.Cu" "F.Mask" "F.Paste")
			(net "GND")
		)
		(pad "200" smd rect
			(at 2.050034 -16.575024 90)
			(size 0.519938 1.4986)
			(layers "F.Cu" "F.Mask" "F.Paste")
			(net "M_H_CPU0_SA_DQS_DN<9>")
		)
		(pad "201" smd rect
			(at 2.050034 -15.724886 90)
			(size 0.519938 1.4986)
			(layers "F.Cu" "F.Mask" "F.Paste")
			(net "M_H_CPU0_SA_DQS_DP<9>")
		)
		(pad "202" smd rect
			(at 2.050034 -14.875002 90)
			(size 0.519938 1.4986)
			(layers "F.Cu" "F.Mask" "F.Paste")
			(net "GND")
		)
		(pad "203" smd rect
			(at 2.050034 -14.025118 90)
			(size 0.519938 1.4986)
			(layers "F.Cu" "F.Mask" "F.Paste")
			(net "M_H_CPU0_SA_CB<6>")
		)
		(pad "204" smd rect
			(at 2.050034 -13.17498 90)
			(size 0.519938 1.4986)
			(layers "F.Cu" "F.Mask" "F.Paste")
			(net "GND")
		)
		(pad "205" smd rect
			(at 2.050034 -12.325096 90)
			(size 0.519938 1.4986)
			(layers "F.Cu" "F.Mask" "F.Paste")
			(net "M_H_CPU0_SA_CB<7>")
		)
		(pad "206" smd rect
			(at 2.050034 -11.474958 90)
			(size 0.519938 1.4986)
			(layers "F.Cu" "F.Mask" "F.Paste")
			(net "GND")
		)
		(pad "207" smd rect
			(at 2.050034 -10.625074 90)
			(size 0.519938 1.4986)
			(layers "F.Cu" "F.Mask" "F.Paste")
			(net "M_H_CPU0_RESET_N")
		)
		(pad "208" smd rect
			(at 2.050034 -9.774936 90)
			(size 0.519938 1.4986)
			(layers "F.Cu" "F.Mask" "F.Paste")
			(net "GND")
		)
		(pad "209" smd rect
			(at 2.050034 -8.925052 90)
			(size 0.519938 1.4986)
			(layers "F.Cu" "F.Mask" "F.Paste")
			(net "M_H_CPU0_SA_CS_N<1>")
		)
		(pad "210" smd rect
			(at 2.050034 -8.074914 90)
			(size 0.519938 1.4986)
			(layers "F.Cu" "F.Mask" "F.Paste")
			(net "GND")
		)
		(pad "211" smd rect
			(at 2.050034 -7.22503 90)
			(size 0.519938 1.4986)
			(layers "F.Cu" "F.Mask" "F.Paste")
			(net "M_H_CPU0_SA_CA<1>")
		)
		(pad "212" smd rect
			(at 2.050034 -6.374892 90)
			(size 0.519938 1.4986)
			(layers "F.Cu" "F.Mask" "F.Paste")
			(net "GND")
		)
		(pad "213" smd rect
			(at 2.050034 -5.525008 90)
			(size 0.519938 1.4986)
			(layers "F.Cu" "F.Mask" "F.Paste")
			(net "M_H_CPU0_SA_CA<3>")
		)
		(pad "214" smd rect
			(at 2.050034 -4.675124 90)
			(size 0.519938 1.4986)
			(layers "F.Cu" "F.Mask" "F.Paste")
			(net "GND")
		)
		(pad "215" smd rect
			(at 2.050034 -3.824986 90)
			(size 0.519938 1.4986)
			(layers "F.Cu" "F.Mask" "F.Paste")
			(net "M_H_CPU0_SA_CA<5>")
		)
		(pad "216" smd rect
			(at 2.050034 -2.975102 90)
			(size 0.519938 1.4986)
			(layers "F.Cu" "F.Mask" "F.Paste")
			(net "GND")
		)
		(pad "217" smd rect
			(at 2.050034 -2.124964 90)
			(size 0.519938 1.4986)
			(layers "F.Cu" "F.Mask" "F.Paste")
			(net "M_H_CPU0_CLK_DP<0>")
		)
		(pad "218" smd rect
			(at 2.050034 -1.27508 90)
			(size 0.519938 1.4986)
			(layers "F.Cu" "F.Mask" "F.Paste")
			(net "M_H_CPU0_CLK_DN<0>")
		)
		(pad "219" smd rect
			(at 2.050034 -0.424942 90)
			(size 0.519938 1.4986)
			(layers "F.Cu" "F.Mask" "F.Paste")
			(net "GND")
		)
		(pad "220" smd rect
			(at 2.050034 5.525008 90)
			(size 0.519938 1.4986)
			(layers "F.Cu" "F.Mask" "F.Paste")
			(net "Net_2351")
		)
		(pad "221" smd rect
			(at 2.050034 6.374892 90)
			(size 0.519938 1.4986)
			(layers "F.Cu" "F.Mask" "F.Paste")
			(net "M_H_CPU0_SB_CA<1>")
		)
		(pad "222" smd rect
			(at 2.050034 7.22503 90)
			(size 0.519938 1.4986)
			(layers "F.Cu" "F.Mask" "F.Paste")
			(net "GND")
		)
		(pad "223" smd rect
			(at 2.050034 8.074914 90)
			(size 0.519938 1.4986)
			(layers "F.Cu" "F.Mask" "F.Paste")
			(net "M_H_CPU0_SB_CA<3>")
		)
		(pad "224" smd rect
			(at 2.050034 8.925052 90)
			(size 0.519938 1.4986)
			(layers "F.Cu" "F.Mask" "F.Paste")
			(net "GND")
		)
		(pad "225" smd rect
			(at 2.050034 9.774936 90)
			(size 0.519938 1.4986)
			(layers "F.Cu" "F.Mask" "F.Paste")
			(net "M_H_CPU0_SB_CA<5>")
		)
		(pad "226" smd rect
			(at 2.050034 10.625074 90)
			(size 0.519938 1.4986)
			(layers "F.Cu" "F.Mask" "F.Paste")
			(net "GND")
		)
		(pad "227" smd rect
			(at 2.050034 11.474958 90)
			(size 0.519938 1.4986)
			(layers "F.Cu" "F.Mask" "F.Paste")
			(net "M_H_CPU0_SB_PAR")
		)
		(pad "228" smd rect
			(at 2.050034 12.325096 90)
			(size 0.519938 1.4986)
			(layers "F.Cu" "F.Mask" "F.Paste")
			(net "GND")
		)
		(pad "229" smd rect
			(at 2.050034 13.17498 90)
			(size 0.519938 1.4986)
			(layers "F.Cu" "F.Mask" "F.Paste")
			(net "M_H_CPU0_SB_CS_N<1>")
		)
		(pad "230" smd rect
			(at 2.050034 14.025118 90)
			(size 0.519938 1.4986)
			(layers "F.Cu" "F.Mask" "F.Paste")
			(net "GND")
		)
		(pad "231" smd rect
			(at 2.050034 14.875002 90)
			(size 0.519938 1.4986)
			(layers "F.Cu" "F.Mask" "F.Paste")
			(net "Net_2352")
		)
		(pad "232" smd rect
			(at 2.050034 15.724886 90)
			(size 0.519938 1.4986)
			(layers "F.Cu" "F.Mask" "F.Paste")
			(net "Net_2353")
		)
		(pad "233" smd rect
			(at 2.050034 16.575024 90)
			(size 0.519938 1.4986)
			(layers "F.Cu" "F.Mask" "F.Paste")
			(net "GND")
		)
		(pad "234" smd rect
			(at 2.050034 17.424908 90)
			(size 0.519938 1.4986)
			(layers "F.Cu" "F.Mask" "F.Paste")
			(net "M_H_CPU0_SB_CB<6>")
		)
		(pad "235" smd rect
			(at 2.050034 18.275046 90)
			(size 0.519938 1.4986)
			(layers "F.Cu" "F.Mask" "F.Paste")
			(net "GND")
		)
		(pad "236" smd rect
			(at 2.050034 19.12493 90)
			(size 0.519938 1.4986)
			(layers "F.Cu" "F.Mask" "F.Paste")
			(net "M_H_CPU0_SB_CB<7>")
		)
		(pad "237" smd rect
			(at 2.050034 19.975068 90)
			(size 0.519938 1.4986)
			(layers "F.Cu" "F.Mask" "F.Paste")
			(net "GND")
		)
		(pad "238" smd rect
			(at 2.050034 20.824952 90)
			(size 0.519938 1.4986)
			(layers "F.Cu" "F.Mask" "F.Paste")
			(net "M_H_CPU0_SB_DQS_DN<4>")
		)
		(pad "239" smd rect
			(at 2.050034 21.67509 90)
			(size 0.519938 1.4986)
			(layers "F.Cu" "F.Mask" "F.Paste")
			(net "M_H_CPU0_SB_DQS_DP<4>")
		)
		(pad "240" smd rect
			(at 2.050034 22.524974 90)
			(size 0.519938 1.4986)
			(layers "F.Cu" "F.Mask" "F.Paste")
			(net "GND")
		)
		(pad "241" smd rect
			(at 2.050034 23.375112 90)
			(size 0.519938 1.4986)
			(layers "F.Cu" "F.Mask" "F.Paste")
			(net "M_H_CPU0_SB_CB<2>")
		)
		(pad "242" smd rect
			(at 2.050034 24.224996 90)
			(size 0.519938 1.4986)
			(layers "F.Cu" "F.Mask" "F.Paste")
			(net "GND")
		)
		(pad "243" smd rect
			(at 2.050034 25.07488 90)
			(size 0.519938 1.4986)
			(layers "F.Cu" "F.Mask" "F.Paste")
			(net "M_H_CPU0_SB_CB<3>")
		)
		(pad "244" smd rect
			(at 2.050034 25.925018 90)
			(size 0.519938 1.4986)
			(layers "F.Cu" "F.Mask" "F.Paste")
			(net "GND")
		)
		(pad "245" smd rect
			(at 2.050034 26.774902 90)
			(size 0.519938 1.4986)
			(layers "F.Cu" "F.Mask" "F.Paste")
			(net "M_H_CPU0_SB_DQ<2>")
		)
		(pad "246" smd rect
			(at 2.050034 27.62504 90)
			(size 0.519938 1.4986)
			(layers "F.Cu" "F.Mask" "F.Paste")
			(net "GND")
		)
		(pad "247" smd rect
			(at 2.050034 28.474924 90)
			(size 0.519938 1.4986)
			(layers "F.Cu" "F.Mask" "F.Paste")
			(net "M_H_CPU0_SB_DQ<3>")
		)
		(pad "248" smd rect
			(at 2.050034 29.325062 90)
			(size 0.519938 1.4986)
			(layers "F.Cu" "F.Mask" "F.Paste")
			(net "GND")
		)
		(pad "249" smd rect
			(at 2.050034 30.174946 90)
			(size 0.519938 1.4986)
			(layers "F.Cu" "F.Mask" "F.Paste")
			(net "M_H_CPU0_SB_DQS_DN<5>")
		)
		(pad "250" smd rect
			(at 2.050034 31.025084 90)
			(size 0.519938 1.4986)
			(layers "F.Cu" "F.Mask" "F.Paste")
			(net "M_H_CPU0_SB_DQS_DP<5>")
		)
		(pad "251" smd rect
			(at 2.050034 31.874968 90)
			(size 0.519938 1.4986)
			(layers "F.Cu" "F.Mask" "F.Paste")
			(net "GND")
		)
		(pad "252" smd rect
			(at 2.050034 32.725106 90)
			(size 0.519938 1.4986)
			(layers "F.Cu" "F.Mask" "F.Paste")
			(net "M_H_CPU0_SB_DQ<6>")
		)
		(pad "253" smd rect
			(at 2.050034 33.57499 90)
			(size 0.519938 1.4986)
			(layers "F.Cu" "F.Mask" "F.Paste")
			(net "GND")
		)
		(pad "254" smd rect
			(at 2.050034 34.425128 90)
			(size 0.519938 1.4986)
			(layers "F.Cu" "F.Mask" "F.Paste")
			(net "M_H_CPU0_SB_DQ<7>")
		)
		(pad "255" smd rect
			(at 2.050034 35.275012 90)
			(size 0.519938 1.4986)
			(layers "F.Cu" "F.Mask" "F.Paste")
			(net "GND")
		)
		(pad "256" smd rect
			(at 2.050034 36.124896 90)
			(size 0.519938 1.4986)
			(layers "F.Cu" "F.Mask" "F.Paste")
			(net "M_H_CPU0_SB_DQ<10>")
		)
		(pad "257" smd rect
			(at 2.050034 36.975034 90)
			(size 0.519938 1.4986)
			(layers "F.Cu" "F.Mask" "F.Paste")
			(net "GND")
		)
		(pad "258" smd rect
			(at 2.050034 37.824918 90)
			(size 0.519938 1.4986)
			(layers "F.Cu" "F.Mask" "F.Paste")
			(net "M_H_CPU0_SB_DQ<11>")
		)
		(pad "259" smd rect
			(at 2.050034 38.675056 90)
			(size 0.519938 1.4986)
			(layers "F.Cu" "F.Mask" "F.Paste")
			(net "GND")
		)
		(pad "260" smd rect
			(at 2.050034 39.52494 90)
			(size 0.519938 1.4986)
			(layers "F.Cu" "F.Mask" "F.Paste")
			(net "M_H_CPU0_SB_DQS_DN<6>")
		)
		(pad "261" smd rect
			(at 2.050034 40.375078 90)
			(size 0.519938 1.4986)
			(layers "F.Cu" "F.Mask" "F.Paste")
			(net "M_H_CPU0_SB_DQS_DP<6>")
		)
		(pad "262" smd rect
			(at 2.050034 41.224962 90)
			(size 0.519938 1.4986)
			(layers "F.Cu" "F.Mask" "F.Paste")
			(net "GND")
		)
		(pad "263" smd rect
			(at 2.050034 42.0751 90)
			(size 0.519938 1.4986)
			(layers "F.Cu" "F.Mask" "F.Paste")
			(net "M_H_CPU0_SB_DQ<14>")
		)
		(pad "264" smd rect
			(at 2.050034 42.924984 90)
			(size 0.519938 1.4986)
			(layers "F.Cu" "F.Mask" "F.Paste")
			(net "GND")
		)
		(pad "265" smd rect
			(at 2.050034 43.775122 90)
			(size 0.519938 1.4986)
			(layers "F.Cu" "F.Mask" "F.Paste")
			(net "M_H_CPU0_SB_DQ<15>")
		)
		(pad "266" smd rect
			(at 2.050034 44.625006 90)
			(size 0.519938 1.4986)
			(layers "F.Cu" "F.Mask" "F.Paste")
			(net "GND")
		)
		(pad "267" smd rect
			(at 2.050034 45.47489 90)
			(size 0.519938 1.4986)
			(layers "F.Cu" "F.Mask" "F.Paste")
			(net "M_H_CPU0_SB_DQ<18>")
		)
		(pad "268" smd rect
			(at 2.050034 46.325028 90)
			(size 0.519938 1.4986)
			(layers "F.Cu" "F.Mask" "F.Paste")
			(net "GND")
		)
		(pad "269" smd rect
			(at 2.050034 47.174912 90)
			(size 0.519938 1.4986)
			(layers "F.Cu" "F.Mask" "F.Paste")
			(net "M_H_CPU0_SB_DQ<19>")
		)
		(pad "270" smd rect
			(at 2.050034 48.02505 90)
			(size 0.519938 1.4986)
			(layers "F.Cu" "F.Mask" "F.Paste")
			(net "GND")
		)
		(pad "271" smd rect
			(at 2.050034 48.874934 90)
			(size 0.519938 1.4986)
			(layers "F.Cu" "F.Mask" "F.Paste")
			(net "M_H_CPU0_SB_DQS_DN<7>")
		)
		(pad "272" smd rect
			(at 2.050034 49.725072 90)
			(size 0.519938 1.4986)
			(layers "F.Cu" "F.Mask" "F.Paste")
			(net "M_H_CPU0_SB_DQS_DP<7>")
		)
		(pad "273" smd rect
			(at 2.050034 50.574956 90)
			(size 0.519938 1.4986)
			(layers "F.Cu" "F.Mask" "F.Paste")
			(net "GND")
		)
		(pad "274" smd rect
			(at 2.050034 51.425094 90)
			(size 0.519938 1.4986)
			(layers "F.Cu" "F.Mask" "F.Paste")
			(net "M_H_CPU0_SB_DQ<22>")
		)
		(pad "275" smd rect
			(at 2.050034 52.274978 90)
			(size 0.519938 1.4986)
			(layers "F.Cu" "F.Mask" "F.Paste")
			(net "GND")
		)
		(pad "276" smd rect
			(at 2.050034 53.125116 90)
			(size 0.519938 1.4986)
			(layers "F.Cu" "F.Mask" "F.Paste")
			(net "M_H_CPU0_SB_DQ<23>")
		)
		(pad "277" smd rect
			(at 2.050034 53.975 90)
			(size 0.519938 1.4986)
			(layers "F.Cu" "F.Mask" "F.Paste")
			(net "GND")
		)
		(pad "278" smd rect
			(at 2.050034 54.824884 90)
			(size 0.519938 1.4986)
			(layers "F.Cu" "F.Mask" "F.Paste")
			(net "M_H_CPU0_SB_DQ<26>")
		)
		(pad "279" smd rect
			(at 2.050034 55.675022 90)
			(size 0.519938 1.4986)
			(layers "F.Cu" "F.Mask" "F.Paste")
			(net "GND")
		)
		(pad "280" smd rect
			(at 2.050034 56.524906 90)
			(size 0.519938 1.4986)
			(layers "F.Cu" "F.Mask" "F.Paste")
			(net "M_H_CPU0_SB_DQ<27>")
		)
		(pad "281" smd rect
			(at 2.050034 57.375044 90)
			(size 0.519938 1.4986)
			(layers "F.Cu" "F.Mask" "F.Paste")
			(net "GND")
		)
		(pad "282" smd rect
			(at 2.050034 58.224928 90)
			(size 0.519938 1.4986)
			(layers "F.Cu" "F.Mask" "F.Paste")
			(net "M_H_CPU0_SB_DQS_DN<8>")
		)
		(pad "283" smd rect
			(at 2.050034 59.075066 90)
			(size 0.519938 1.4986)
			(layers "F.Cu" "F.Mask" "F.Paste")
			(net "M_H_CPU0_SB_DQS_DP<8>")
		)
		(pad "284" smd rect
			(at 2.050034 59.92495 90)
			(size 0.519938 1.4986)
			(layers "F.Cu" "F.Mask" "F.Paste")
			(net "GND")
		)
		(pad "285" smd rect
			(at 2.050034 60.775088 90)
			(size 0.519938 1.4986)
			(layers "F.Cu" "F.Mask" "F.Paste")
			(net "M_H_CPU0_SB_DQ<30>")
		)
		(pad "286" smd rect
			(at 2.050034 61.624972 90)
			(size 0.519938 1.4986)
			(layers "F.Cu" "F.Mask" "F.Paste")
			(net "GND")
		)
		(pad "287" smd rect
			(at 2.050034 62.47511 90)
			(size 0.519938 1.4986)
			(layers "F.Cu" "F.Mask" "F.Paste")
			(net "M_H_CPU0_SB_DQ<31>")
		)
		(pad "288" smd rect
			(at 2.050034 63.324994 90)
			(size 0.519938 1.4986)
			(layers "F.Cu" "F.Mask" "F.Paste")
			(net "GND")
		)
		(pad "G1" thru_hole oval
			(at 0 -68.97497 90)
			(size 1.7272 3.4798)
			(drill oval 1.2192 2.4638)
			(layers "*.Cu" "*.Mask")
			(remove_unused_layers no)
			(net "GND")
			(clearance 0.127)
			(thermal_gap 0.127)
		)
		(pad "G2" thru_hole oval
			(at 0 3.875024 90)
			(size 1.7272 3.4798)
			(drill oval 1.2192 2.4638)
			(layers "*.Cu" "*.Mask")
			(remove_unused_layers no)
			(net "GND")
			(clearance 0.127)
			(thermal_gap 0.127)
		)
		(pad "G3" thru_hole oval
			(at 0 68.97497 90)
			(size 1.7272 3.4798)
			(drill oval 1.2192 2.4638)
			(layers "*.Cu" "*.Mask")
			(remove_unused_layers no)
			(net "GND")
			(clearance 0.127)
			(thermal_gap 0.127)
		)
	)
	(footprint ""
		(layer "F.Cu")
		(at 163.703 -123.952 180)
		(property "Reference" "R439"
			(at 0 0 180)
			(layer "F.SilkS")
			(hide yes)
			(effects
				(font
					(size 1.27 1.27)
				)
			)
		)
		(property "Value" ""
			(at 0 0 180)
			(layer "F.Fab")
			(effects
				(font
					(size 1.27 1.27)
				)
			)
		)
		(duplicate_pad_numbers_are_jumpers no)
		(fp_line
			(start 0.7874 0.4064)
			(end -0.7874 0.4064)
			(stroke
				(width 0.1524)
				(type default)
			)
			(layer "F.SilkS")
		)
		(fp_line
			(start 0.7874 -0.4064)
			(end 0.7874 0.4064)
			(stroke
				(width 0.1524)
				(type default)
			)
			(layer "F.SilkS")
		)
		(fp_line
			(start -0.7874 0.4064)
			(end -0.7874 -0.4064)
			(stroke
				(width 0.1524)
				(type default)
			)
			(layer "F.SilkS")
		)
		(fp_line
			(start -0.7874 -0.4064)
			(end 0.7874 -0.4064)
			(stroke
				(width 0.1524)
				(type default)
			)
			(layer "F.SilkS")
		)
		(fp_line
			(start 0.67945 0.3048)
			(end 0.120396 0.3048)
			(stroke
				(width 0.1)
				(type default)
			)
			(layer "F.Fab")
		)
		(fp_line
			(start 0.67945 -0.3048)
			(end 0.67945 0.3048)
			(stroke
				(width 0.1)
				(type default)
			)
			(layer "F.Fab")
		)
		(fp_line
			(start 0.12065 -0.2794)
			(end 0.12065 -0.3048)
			(stroke
				(width 0.1)
				(type default)
			)
			(layer "F.Fab")
		)
		(fp_line
			(start 0.12065 -0.3048)
			(end 0.67945 -0.3048)
			(stroke
				(width 0.1)
				(type default)
			)
			(layer "F.Fab")
		)
		(fp_line
			(start 0.120396 0.3048)
			(end 0.120396 0.2794)
			(stroke
				(width 0.1)
				(type default)
			)
			(layer "F.Fab")
		)
		(fp_line
			(start 0.120396 0.2794)
			(end -0.12065 0.2794)
			(stroke
				(width 0.1)
				(type default)
			)
			(layer "F.Fab")
		)
		(fp_line
			(start -0.12065 0.3048)
			(end -0.67945 0.3048)
			(stroke
				(width 0.1)
				(type default)
			)
			(layer "F.Fab")
		)
		(fp_line
			(start -0.12065 0.2794)
			(end -0.12065 0.3048)
			(stroke
				(width 0.1)
				(type default)
			)
			(layer "F.Fab")
		)
		(fp_line
			(start -0.12065 -0.2794)
			(end 0.12065 -0.2794)
			(stroke
				(width 0.1)
				(type default)
			)
			(layer "F.Fab")
		)
		(fp_line
			(start -0.12065 -0.305054)
			(end -0.12065 -0.2794)
			(stroke
				(width 0.1)
				(type default)
			)
			(layer "F.Fab")
		)
		(fp_line
			(start -0.67945 0.3048)
			(end -0.67945 -0.305054)
			(stroke
				(width 0.1)
				(type default)
			)
			(layer "F.Fab")
		)
		(fp_line
			(start -0.67945 -0.305054)
			(end -0.12065 -0.305054)
			(stroke
				(width 0.1)
				(type default)
			)
			(layer "F.Fab")
		)
		(pad "1" smd circle
			(at -0.40005 0 180)
			(size 0 0)
			(layers "F.Cu" "F.Mask" "F.Paste")
			(net "PWRGD_P5V")
		)
		(pad "2" smd circle
			(at 0.40005 0 180)
			(size 0 0)
			(layers "F.Cu" "F.Mask" "F.Paste")
			(net "PWRGD_P5V_R2")
		)
	)
	(footprint ""
		(layer "F.Cu")
		(at 29.954982 -153.765504)
		(property "Reference" "H127"
			(at 5.884164 4.9022 0)
			(unlocked yes)
			(layer "F.SilkS")
			(effects
				(font
					(size 0.7874 0.5842)
					(thickness 0.1524)
				)
				(justify left)
			)
		)
		(property "Value" ""
			(at 0 0 0)
			(layer "F.Fab")
			(effects
				(font
					(size 1.27 1.27)
				)
			)
		)
		(duplicate_pad_numbers_are_jumpers no)
		(fp_circle
			(center 0 0)
			(end 5.8166 0)
			(stroke
				(width 0.1524)
				(type default)
			)
			(fill no)
			(layer "F.SilkS")
		)
		(fp_circle
			(center 0 0)
			(end 5.8166 0)
			(stroke
				(width 0.1524)
				(type default)
			)
			(fill no)
			(layer "B.SilkS")
		)
		(fp_circle
			(center 0 0)
			(end 5.8166 0)
			(stroke
				(width 0.1)
				(type default)
			)
			(fill no)
			(layer "B.Fab")
		)
		(fp_circle
			(center 0 0)
			(end 5.8166 0)
			(stroke
				(width 0.1)
				(type default)
			)
			(fill no)
			(layer "F.Fab")
		)
		(pad "" np_thru_hole circle
			(at 0 0)
			(size 10.0076 10.0076)
			(drill 10.0076)
			(layers "*.Cu" "*.Mask")
			(clearance 0.381)
			(thermal_gap 0.381)
		)
	)
	(footprint ""
		(layer "F.Cu")
		(at 271.085056 -123.86437 180)
		(property "Reference" "R3712"
			(at 0 0 180)
			(layer "F.SilkS")
			(hide yes)
			(effects
				(font
					(size 1.27 1.27)
				)
			)
		)
		(property "Value" ""
			(at 0 0 180)
			(layer "F.Fab")
			(effects
				(font
					(size 1.27 1.27)
				)
			)
		)
		(duplicate_pad_numbers_are_jumpers no)
		(fp_line
			(start 0.7874 0.4064)
			(end -0.7874 0.4064)
			(stroke
				(width 0.1524)
				(type default)
			)
			(layer "F.SilkS")
		)
		(fp_line
			(start 0.7874 -0.4064)
			(end 0.7874 0.4064)
			(stroke
				(width 0.1524)
				(type default)
			)
			(layer "F.SilkS")
		)
		(fp_line
			(start -0.7874 0.4064)
			(end -0.7874 -0.4064)
			(stroke
				(width 0.1524)
				(type default)
			)
			(layer "F.SilkS")
		)
		(fp_line
			(start -0.7874 -0.4064)
			(end 0.7874 -0.4064)
			(stroke
				(width 0.1524)
				(type default)
			)
			(layer "F.SilkS")
		)
		(fp_line
			(start 0.67945 0.3048)
			(end 0.120396 0.3048)
			(stroke
				(width 0.1)
				(type default)
			)
			(layer "F.Fab")
		)
		(fp_line
			(start 0.67945 -0.3048)
			(end 0.67945 0.3048)
			(stroke
				(width 0.1)
				(type default)
			)
			(layer "F.Fab")
		)
		(fp_line
			(start 0.12065 -0.2794)
			(end 0.12065 -0.3048)
			(stroke
				(width 0.1)
				(type default)
			)
			(layer "F.Fab")
		)
		(fp_line
			(start 0.12065 -0.3048)
			(end 0.67945 -0.3048)
			(stroke
				(width 0.1)
				(type default)
			)
			(layer "F.Fab")
		)
		(fp_line
			(start 0.120396 0.3048)
			(end 0.120396 0.2794)
			(stroke
				(width 0.1)
				(type default)
			)
			(layer "F.Fab")
		)
		(fp_line
			(start 0.120396 0.2794)
			(end -0.12065 0.2794)
			(stroke
				(width 0.1)
				(type default)
			)
			(layer "F.Fab")
		)
		(fp_line
			(start -0.12065 0.3048)
			(end -0.67945 0.3048)
			(stroke
				(width 0.1)
				(type default)
			)
			(layer "F.Fab")
		)
		(fp_line
			(start -0.12065 0.2794)
			(end -0.12065 0.3048)
			(stroke
				(width 0.1)
				(type default)
			)
			(layer "F.Fab")
		)
		(fp_line
			(start -0.12065 -0.2794)
			(end 0.12065 -0.2794)
			(stroke
				(width 0.1)
				(type default)
			)
			(layer "F.Fab")
		)
		(fp_line
			(start -0.12065 -0.305054)
			(end -0.12065 -0.2794)
			(stroke
				(width 0.1)
				(type default)
			)
			(layer "F.Fab")
		)
		(fp_line
			(start -0.67945 0.3048)
			(end -0.67945 -0.305054)
			(stroke
				(width 0.1)
				(type default)
			)
			(layer "F.Fab")
		)
		(fp_line
			(start -0.67945 -0.305054)
			(end -0.12065 -0.305054)
			(stroke
				(width 0.1)
				(type default)
			)
			(layer "F.Fab")
		)
		(pad "1" smd circle
			(at -0.40005 0 180)
			(size 0 0)
			(layers "F.Cu" "F.Mask" "F.Paste")
			(net "SMB_VR_SENSOR_3V3AUX_SDA")
		)
		(pad "2" smd circle
			(at 0.40005 0 180)
			(size 0 0)
			(layers "F.Cu" "F.Mask" "F.Paste")
			(net "SMB_VR_SENSOR_3V3AUX_SDA_R")
		)
	)
	(footprint ""
		(layer "F.Cu")
		(at 181.737 -100.294948 90)
		(property "Reference" "R231"
			(at 0 0 90)
			(layer "F.SilkS")
			(hide yes)
			(effects
				(font
					(size 1.27 1.27)
				)
			)
		)
		(property "Value" ""
			(at 0 0 90)
			(layer "F.Fab")
			(effects
				(font
					(size 1.27 1.27)
				)
			)
		)
		(duplicate_pad_numbers_are_jumpers no)
		(fp_line
			(start 0.7874 -0.4064)
			(end 0.7874 0.4064)
			(stroke
				(width 0.1524)
				(type default)
			)
			(layer "F.SilkS")
		)
		(fp_line
			(start -0.7874 -0.4064)
			(end 0.7874 -0.4064)
			(stroke
				(width 0.1524)
				(type default)
			)
			(layer "F.SilkS")
		)
		(fp_line
			(start 0.7874 0.4064)
			(end -0.7874 0.4064)
			(stroke
				(width 0.1524)
				(type default)
			)
			(layer "F.SilkS")
		)
		(fp_line
			(start -0.7874 0.4064)
			(end -0.7874 -0.4064)
			(stroke
				(width 0.1524)
				(type default)
			)
			(layer "F.SilkS")
		)
		(fp_line
			(start -0.12065 -0.305054)
			(end -0.12065 -0.2794)
			(stroke
				(width 0.1)
				(type default)
			)
			(layer "F.Fab")
		)
		(fp_line
			(start -0.67945 -0.305054)
			(end -0.12065 -0.305054)
			(stroke
				(width 0.1)
				(type default)
			)
			(layer "F.Fab")
		)
		(fp_line
			(start 0.67945 -0.3048)
			(end 0.67945 0.3048)
			(stroke
				(width 0.1)
				(type default)
			)
			(layer "F.Fab")
		)
		(fp_line
			(start 0.12065 -0.3048)
			(end 0.67945 -0.3048)
			(stroke
				(width 0.1)
				(type default)
			)
			(layer "F.Fab")
		)
		(fp_line
			(start 0.12065 -0.2794)
			(end 0.12065 -0.3048)
			(stroke
				(width 0.1)
				(type default)
			)
			(layer "F.Fab")
		)
		(fp_line
			(start -0.12065 -0.2794)
			(end 0.12065 -0.2794)
			(stroke
				(width 0.1)
				(type default)
			)
			(layer "F.Fab")
		)
		(fp_line
			(start 0.120396 0.2794)
			(end -0.12065 0.2794)
			(stroke
				(width 0.1)
				(type default)
			)
			(layer "F.Fab")
		)
		(fp_line
			(start -0.12065 0.2794)
			(end -0.12065 0.3048)
			(stroke
				(width 0.1)
				(type default)
			)
			(layer "F.Fab")
		)
		(fp_line
			(start 0.67945 0.3048)
			(end 0.120396 0.3048)
			(stroke
				(width 0.1)
				(type default)
			)
			(layer "F.Fab")
		)
		(fp_line
			(start 0.120396 0.3048)
			(end 0.120396 0.2794)
			(stroke
				(width 0.1)
				(type default)
			)
			(layer "F.Fab")
		)
		(fp_line
			(start -0.12065 0.3048)
			(end -0.67945 0.3048)
			(stroke
				(width 0.1)
				(type default)
			)
			(layer "F.Fab")
		)
		(fp_line
			(start -0.67945 0.3048)
			(end -0.67945 -0.305054)
			(stroke
				(width 0.1)
				(type default)
			)
			(layer "F.Fab")
		)
		(pad "1" smd circle
			(at -0.40005 0 90)
			(size 0 0)
			(layers "F.Cu" "F.Mask" "F.Paste")
			(net "PVDDCR_CPU0_P0_OCP_N")
		)
		(pad "2" smd circle
			(at 0.40005 0 90)
			(size 0 0)
			(layers "F.Cu" "F.Mask" "F.Paste")
			(net "FM_PVDDCR_CPU0_P0_OCP_N")
		)
	)
	(footprint ""
		(layer "F.Cu")
		(at 34.18713 -351.578672 90)
		(property "Reference" "PC620_9"
			(at 0 0 90)
			(layer "F.SilkS")
			(hide yes)
			(effects
				(font
					(size 1.27 1.27)
				)
			)
		)
		(property "Value" ""
			(at 0 0 90)
			(layer "F.Fab")
			(effects
				(font
					(size 1.27 1.27)
				)
			)
		)
		(duplicate_pad_numbers_are_jumpers no)
		(fp_line
			(start 0.7874 -0.4064)
			(end 0.7874 0.4064)
			(stroke
				(width 0.1524)
				(type default)
			)
			(layer "F.SilkS")
		)
		(fp_line
			(start -0.7874 -0.4064)
			(end 0.7874 -0.4064)
			(stroke
				(width 0.1524)
				(type default)
			)
			(layer "F.SilkS")
		)
		(fp_line
			(start 0.7874 0.4064)
			(end -0.7874 0.4064)
			(stroke
				(width 0.1524)
				(type default)
			)
			(layer "F.SilkS")
		)
		(fp_line
			(start -0.7874 0.4064)
			(end -0.7874 -0.4064)
			(stroke
				(width 0.1524)
				(type default)
			)
			(layer "F.SilkS")
		)
		(fp_line
			(start -0.12065 -0.305054)
			(end -0.12065 -0.2794)
			(stroke
				(width 0.1)
				(type default)
			)
			(layer "F.Fab")
		)
		(fp_line
			(start -0.67945 -0.305054)
			(end -0.12065 -0.305054)
			(stroke
				(width 0.1)
				(type default)
			)
			(layer "F.Fab")
		)
		(fp_line
			(start 0.67945 -0.3048)
			(end 0.67945 0.3048)
			(stroke
				(width 0.1)
				(type default)
			)
			(layer "F.Fab")
		)
		(fp_line
			(start 0.12065 -0.3048)
			(end 0.67945 -0.3048)
			(stroke
				(width 0.1)
				(type default)
			)
			(layer "F.Fab")
		)
		(fp_line
			(start 0.12065 -0.2794)
			(end 0.12065 -0.3048)
			(stroke
				(width 0.1)
				(type default)
			)
			(layer "F.Fab")
		)
		(fp_line
			(start -0.12065 -0.2794)
			(end 0.12065 -0.2794)
			(stroke
				(width 0.1)
				(type default)
			)
			(layer "F.Fab")
		)
		(fp_line
			(start 0.120396 0.2794)
			(end -0.12065 0.2794)
			(stroke
				(width 0.1)
				(type default)
			)
			(layer "F.Fab")
		)
		(fp_line
			(start -0.12065 0.2794)
			(end -0.12065 0.3048)
			(stroke
				(width 0.1)
				(type default)
			)
			(layer "F.Fab")
		)
		(fp_line
			(start 0.67945 0.3048)
			(end 0.120396 0.3048)
			(stroke
				(width 0.1)
				(type default)
			)
			(layer "F.Fab")
		)
		(fp_line
			(start 0.120396 0.3048)
			(end 0.120396 0.2794)
			(stroke
				(width 0.1)
				(type default)
			)
			(layer "F.Fab")
		)
		(fp_line
			(start -0.12065 0.3048)
			(end -0.67945 0.3048)
			(stroke
				(width 0.1)
				(type default)
			)
			(layer "F.Fab")
		)
		(fp_line
			(start -0.67945 0.3048)
			(end -0.67945 -0.305054)
			(stroke
				(width 0.1)
				(type default)
			)
			(layer "F.Fab")
		)
		(pad "1" smd circle
			(at -0.40005 0 90)
			(size 0 0)
			(layers "F.Cu" "F.Mask" "F.Paste")
			(net "PVDDCR_CPU1_P1_VCCS")
		)
		(pad "2" smd circle
			(at 0.40005 0 90)
			(size 0 0)
			(layers "F.Cu" "F.Mask" "F.Paste")
			(net "GND")
		)
	)
	(footprint ""
		(layer "F.Cu")
		(at 136.840976 -376.982228)
		(property "Reference" "C51"
			(at 0 0 0)
			(layer "F.SilkS")
			(hide yes)
			(effects
				(font
					(size 1.27 1.27)
				)
			)
		)
		(property "Value" ""
			(at 0 0 0)
			(layer "F.Fab")
			(effects
				(font
					(size 1.27 1.27)
				)
			)
		)
		(duplicate_pad_numbers_are_jumpers no)
		(fp_line
			(start -0.299974 -0.150114)
			(end 0.299974 -0.150114)
			(stroke
				(width 0.1)
				(type default)
			)
			(layer "F.Fab")
		)
		(fp_line
			(start -0.299974 0.150114)
			(end -0.299974 -0.150114)
			(stroke
				(width 0.1)
				(type default)
			)
			(layer "F.Fab")
		)
		(fp_line
			(start 0.299974 -0.150114)
			(end 0.299974 0.150114)
			(stroke
				(width 0.1)
				(type default)
			)
			(layer "F.Fab")
		)
		(fp_line
			(start 0.299974 0.150114)
			(end -0.299974 0.150114)
			(stroke
				(width 0.1)
				(type default)
			)
			(layer "F.Fab")
		)
		(pad "1" smd rect
			(at -0.2667 0)
			(size 0.3048 0.381)
			(layers "F.Cu" "F.Mask" "F.Paste")
			(net "P5E_CPU1_P3_TX_C_DP<14>")
		)
		(pad "2" smd rect
			(at 0.2667 0)
			(size 0.3048 0.381)
			(layers "F.Cu" "F.Mask" "F.Paste")
			(net "P5E_CPU1_P3_TX_DP<14>")
		)
	)
	(footprint ""
		(layer "F.Cu")
		(at 33.722818 -438.084214 -90)
		(property "Reference" "R2986"
			(at 0 0 270)
			(layer "F.SilkS")
			(hide yes)
			(effects
				(font
					(size 1.27 1.27)
				)
			)
		)
		(property "Value" ""
			(at 0 0 270)
			(layer "F.Fab")
			(effects
				(font
					(size 1.27 1.27)
				)
			)
		)
		(duplicate_pad_numbers_are_jumpers no)
		(fp_line
			(start -0.7874 0.4064)
			(end -0.7874 -0.4064)
			(stroke
				(width 0.1524)
				(type default)
			)
			(layer "F.SilkS")
		)
		(fp_line
			(start 0.7874 0.4064)
			(end -0.7874 0.4064)
			(stroke
				(width 0.1524)
				(type default)
			)
			(layer "F.SilkS")
		)
		(fp_line
			(start -0.7874 -0.4064)
			(end 0.7874 -0.4064)
			(stroke
				(width 0.1524)
				(type default)
			)
			(layer "F.SilkS")
		)
		(fp_line
			(start 0.7874 -0.4064)
			(end 0.7874 0.4064)
			(stroke
				(width 0.1524)
				(type default)
			)
			(layer "F.SilkS")
		)
		(fp_line
			(start -0.67945 0.3048)
			(end -0.67945 -0.305054)
			(stroke
				(width 0.1)
				(type default)
			)
			(layer "F.Fab")
		)
		(fp_line
			(start -0.12065 0.3048)
			(end -0.67945 0.3048)
			(stroke
				(width 0.1)
				(type default)
			)
			(layer "F.Fab")
		)
		(fp_line
			(start 0.120396 0.3048)
			(end 0.120396 0.2794)
			(stroke
				(width 0.1)
				(type default)
			)
			(layer "F.Fab")
		)
		(fp_line
			(start 0.67945 0.3048)
			(end 0.120396 0.3048)
			(stroke
				(width 0.1)
				(type default)
			)
			(layer "F.Fab")
		)
		(fp_line
			(start -0.12065 0.2794)
			(end -0.12065 0.3048)
			(stroke
				(width 0.1)
				(type default)
			)
			(layer "F.Fab")
		)
		(fp_line
			(start 0.120396 0.2794)
			(end -0.12065 0.2794)
			(stroke
				(width 0.1)
				(type default)
			)
			(layer "F.Fab")
		)
		(fp_line
			(start -0.12065 -0.2794)
			(end 0.12065 -0.2794)
			(stroke
				(width 0.1)
				(type default)
			)
			(layer "F.Fab")
		)
		(fp_line
			(start 0.12065 -0.2794)
			(end 0.12065 -0.3048)
			(stroke
				(width 0.1)
				(type default)
			)
			(layer "F.Fab")
		)
		(fp_line
			(start 0.12065 -0.3048)
			(end 0.67945 -0.3048)
			(stroke
				(width 0.1)
				(type default)
			)
			(layer "F.Fab")
		)
		(fp_line
			(start 0.67945 -0.3048)
			(end 0.67945 0.3048)
			(stroke
				(width 0.1)
				(type default)
			)
			(layer "F.Fab")
		)
		(fp_line
			(start -0.67945 -0.305054)
			(end -0.12065 -0.305054)
			(stroke
				(width 0.1)
				(type default)
			)
			(layer "F.Fab")
		)
		(fp_line
			(start -0.12065 -0.305054)
			(end -0.12065 -0.2794)
			(stroke
				(width 0.1)
				(type default)
			)
			(layer "F.Fab")
		)
		(pad "1" smd circle
			(at -0.40005 0 270)
			(size 0 0)
			(layers "F.Cu" "F.Mask" "F.Paste")
			(net "SMB_2_BMC_GPU_R_SCL")
		)
		(pad "2" smd circle
			(at 0.40005 0 270)
			(size 0 0)
			(layers "F.Cu" "F.Mask" "F.Paste")
			(net "SMB_2_BMC_GPU_BUF_R_SCL")
		)
	)
	(footprint ""
		(layer "F.Cu")
		(at 130.048 -109.474 90)
		(property "Reference" "R8114"
			(at 0 0 90)
			(layer "F.SilkS")
			(hide yes)
			(effects
				(font
					(size 1.27 1.27)
				)
			)
		)
		(property "Value" ""
			(at 0 0 90)
			(layer "F.Fab")
			(effects
				(font
					(size 1.27 1.27)
				)
			)
		)
		(duplicate_pad_numbers_are_jumpers no)
		(fp_line
			(start 0.7874 -0.4064)
			(end 0.7874 0.4064)
			(stroke
				(width 0.1524)
				(type default)
			)
			(layer "F.SilkS")
		)
		(fp_line
			(start -0.7874 -0.4064)
			(end 0.7874 -0.4064)
			(stroke
				(width 0.1524)
				(type default)
			)
			(layer "F.SilkS")
		)
		(fp_line
			(start 0.7874 0.4064)
			(end -0.7874 0.4064)
			(stroke
				(width 0.1524)
				(type default)
			)
			(layer "F.SilkS")
		)
		(fp_line
			(start -0.7874 0.4064)
			(end -0.7874 -0.4064)
			(stroke
				(width 0.1524)
				(type default)
			)
			(layer "F.SilkS")
		)
		(fp_line
			(start -0.12065 -0.305054)
			(end -0.12065 -0.2794)
			(stroke
				(width 0.1)
				(type default)
			)
			(layer "F.Fab")
		)
		(fp_line
			(start -0.67945 -0.305054)
			(end -0.12065 -0.305054)
			(stroke
				(width 0.1)
				(type default)
			)
			(layer "F.Fab")
		)
		(fp_line
			(start 0.67945 -0.3048)
			(end 0.67945 0.3048)
			(stroke
				(width 0.1)
				(type default)
			)
			(layer "F.Fab")
		)
		(fp_line
			(start 0.12065 -0.3048)
			(end 0.67945 -0.3048)
			(stroke
				(width 0.1)
				(type default)
			)
			(layer "F.Fab")
		)
		(fp_line
			(start 0.12065 -0.2794)
			(end 0.12065 -0.3048)
			(stroke
				(width 0.1)
				(type default)
			)
			(layer "F.Fab")
		)
		(fp_line
			(start -0.12065 -0.2794)
			(end 0.12065 -0.2794)
			(stroke
				(width 0.1)
				(type default)
			)
			(layer "F.Fab")
		)
		(fp_line
			(start 0.120396 0.2794)
			(end -0.12065 0.2794)
			(stroke
				(width 0.1)
				(type default)
			)
			(layer "F.Fab")
		)
		(fp_line
			(start -0.12065 0.2794)
			(end -0.12065 0.3048)
			(stroke
				(width 0.1)
				(type default)
			)
			(layer "F.Fab")
		)
		(fp_line
			(start 0.67945 0.3048)
			(end 0.120396 0.3048)
			(stroke
				(width 0.1)
				(type default)
			)
			(layer "F.Fab")
		)
		(fp_line
			(start 0.120396 0.3048)
			(end 0.120396 0.2794)
			(stroke
				(width 0.1)
				(type default)
			)
			(layer "F.Fab")
		)
		(fp_line
			(start -0.12065 0.3048)
			(end -0.67945 0.3048)
			(stroke
				(width 0.1)
				(type default)
			)
			(layer "F.Fab")
		)
		(fp_line
			(start -0.67945 0.3048)
			(end -0.67945 -0.305054)
			(stroke
				(width 0.1)
				(type default)
			)
			(layer "F.Fab")
		)
		(pad "1" smd circle
			(at -0.40005 0 90)
			(size 0 0)
			(layers "F.Cu" "F.Mask" "F.Paste")
			(net "P12V_AUX")
		)
		(pad "2" smd circle
			(at 0.40005 0 90)
			(size 0 0)
			(layers "F.Cu" "F.Mask" "F.Paste")
			(net "P12V_AUX_UV_ADR_TRIGGER")
		)
	)
	(footprint ""
		(layer "F.Cu")
		(at 184.785 -100.294948 -90)
		(property "Reference" "R1188"
			(at 0 0 270)
			(layer "F.SilkS")
			(hide yes)
			(effects
				(font
					(size 1.27 1.27)
				)
			)
		)
		(property "Value" ""
			(at 0 0 270)
			(layer "F.Fab")
			(effects
				(font
					(size 1.27 1.27)
				)
			)
		)
		(duplicate_pad_numbers_are_jumpers no)
		(fp_line
			(start -0.7874 0.4064)
			(end -0.7874 -0.4064)
			(stroke
				(width 0.1524)
				(type default)
			)
			(layer "F.SilkS")
		)
		(fp_line
			(start 0.7874 0.4064)
			(end -0.7874 0.4064)
			(stroke
				(width 0.1524)
				(type default)
			)
			(layer "F.SilkS")
		)
		(fp_line
			(start -0.7874 -0.4064)
			(end 0.7874 -0.4064)
			(stroke
				(width 0.1524)
				(type default)
			)
			(layer "F.SilkS")
		)
		(fp_line
			(start 0.7874 -0.4064)
			(end 0.7874 0.4064)
			(stroke
				(width 0.1524)
				(type default)
			)
			(layer "F.SilkS")
		)
		(fp_line
			(start -0.67945 0.3048)
			(end -0.67945 -0.305054)
			(stroke
				(width 0.1)
				(type default)
			)
			(layer "F.Fab")
		)
		(fp_line
			(start -0.12065 0.3048)
			(end -0.67945 0.3048)
			(stroke
				(width 0.1)
				(type default)
			)
			(layer "F.Fab")
		)
		(fp_line
			(start 0.120396 0.3048)
			(end 0.120396 0.2794)
			(stroke
				(width 0.1)
				(type default)
			)
			(layer "F.Fab")
		)
		(fp_line
			(start 0.67945 0.3048)
			(end 0.120396 0.3048)
			(stroke
				(width 0.1)
				(type default)
			)
			(layer "F.Fab")
		)
		(fp_line
			(start -0.12065 0.2794)
			(end -0.12065 0.3048)
			(stroke
				(width 0.1)
				(type default)
			)
			(layer "F.Fab")
		)
		(fp_line
			(start 0.120396 0.2794)
			(end -0.12065 0.2794)
			(stroke
				(width 0.1)
				(type default)
			)
			(layer "F.Fab")
		)
		(fp_line
			(start -0.12065 -0.2794)
			(end 0.12065 -0.2794)
			(stroke
				(width 0.1)
				(type default)
			)
			(layer "F.Fab")
		)
		(fp_line
			(start 0.12065 -0.2794)
			(end 0.12065 -0.3048)
			(stroke
				(width 0.1)
				(type default)
			)
			(layer "F.Fab")
		)
		(fp_line
			(start 0.12065 -0.3048)
			(end 0.67945 -0.3048)
			(stroke
				(width 0.1)
				(type default)
			)
			(layer "F.Fab")
		)
		(fp_line
			(start 0.67945 -0.3048)
			(end 0.67945 0.3048)
			(stroke
				(width 0.1)
				(type default)
			)
			(layer "F.Fab")
		)
		(fp_line
			(start -0.67945 -0.305054)
			(end -0.12065 -0.305054)
			(stroke
				(width 0.1)
				(type default)
			)
			(layer "F.Fab")
		)
		(fp_line
			(start -0.12065 -0.305054)
			(end -0.12065 -0.2794)
			(stroke
				(width 0.1)
				(type default)
			)
			(layer "F.Fab")
		)
		(pad "1" smd circle
			(at -0.40005 0 270)
			(size 0 0)
			(layers "F.Cu" "F.Mask" "F.Paste")
			(net "PVDDCR_CPU1_P1_SMB_ALERT")
		)
		(pad "2" smd circle
			(at 0.40005 0 270)
			(size 0 0)
			(layers "F.Cu" "F.Mask" "F.Paste")
			(net "P3V3_AUX")
		)
	)
	(footprint ""
		(layer "F.Cu")
		(at 100.378514 -177.481484)
		(property "Reference" "PR195"
			(at 0 0 0)
			(layer "F.SilkS")
			(hide yes)
			(effects
				(font
					(size 1.27 1.27)
				)
			)
		)
		(property "Value" ""
			(at 0 0 0)
			(layer "F.Fab")
			(effects
				(font
					(size 1.27 1.27)
				)
			)
		)
		(duplicate_pad_numbers_are_jumpers no)
		(fp_line
			(start -0.7874 -0.4064)
			(end 0.7874 -0.4064)
			(stroke
				(width 0.1524)
				(type default)
			)
			(layer "F.SilkS")
		)
		(fp_line
			(start -0.7874 0.4064)
			(end -0.7874 -0.4064)
			(stroke
				(width 0.1524)
				(type default)
			)
			(layer "F.SilkS")
		)
		(fp_line
			(start 0.7874 -0.4064)
			(end 0.7874 0.4064)
			(stroke
				(width 0.1524)
				(type default)
			)
			(layer "F.SilkS")
		)
		(fp_line
			(start 0.7874 0.4064)
			(end -0.7874 0.4064)
			(stroke
				(width 0.1524)
				(type default)
			)
			(layer "F.SilkS")
		)
		(fp_line
			(start -0.67945 -0.305054)
			(end -0.12065 -0.305054)
			(stroke
				(width 0.1)
				(type default)
			)
			(layer "F.Fab")
		)
		(fp_line
			(start -0.67945 0.3048)
			(end -0.67945 -0.305054)
			(stroke
				(width 0.1)
				(type default)
			)
			(layer "F.Fab")
		)
		(fp_line
			(start -0.12065 -0.305054)
			(end -0.12065 -0.2794)
			(stroke
				(width 0.1)
				(type default)
			)
			(layer "F.Fab")
		)
		(fp_line
			(start -0.12065 -0.2794)
			(end 0.12065 -0.2794)
			(stroke
				(width 0.1)
				(type default)
			)
			(layer "F.Fab")
		)
		(fp_line
			(start -0.12065 0.2794)
			(end -0.12065 0.3048)
			(stroke
				(width 0.1)
				(type default)
			)
			(layer "F.Fab")
		)
		(fp_line
			(start -0.12065 0.3048)
			(end -0.67945 0.3048)
			(stroke
				(width 0.1)
				(type default)
			)
			(layer "F.Fab")
		)
		(fp_line
			(start 0.120396 0.2794)
			(end -0.12065 0.2794)
			(stroke
				(width 0.1)
				(type default)
			)
			(layer "F.Fab")
		)
		(fp_line
			(start 0.120396 0.3048)
			(end 0.120396 0.2794)
			(stroke
				(width 0.1)
				(type default)
			)
			(layer "F.Fab")
		)
		(fp_line
			(start 0.12065 -0.3048)
			(end 0.67945 -0.3048)
			(stroke
				(width 0.1)
				(type default)
			)
			(layer "F.Fab")
		)
		(fp_line
			(start 0.12065 -0.2794)
			(end 0.12065 -0.3048)
			(stroke
				(width 0.1)
				(type default)
			)
			(layer "F.Fab")
		)
		(fp_line
			(start 0.67945 -0.3048)
			(end 0.67945 0.3048)
			(stroke
				(width 0.1)
				(type default)
			)
			(layer "F.Fab")
		)
		(fp_line
			(start 0.67945 0.3048)
			(end 0.120396 0.3048)
			(stroke
				(width 0.1)
				(type default)
			)
			(layer "F.Fab")
		)
		(pad "1" smd circle
			(at -0.40005 0)
			(size 0 0)
			(layers "F.Cu" "F.Mask" "F.Paste")
			(net "GND")
		)
		(pad "2" smd circle
			(at 0.40005 0)
			(size 0 0)
			(layers "F.Cu" "F.Mask" "F.Paste")
			(net "PVDDCR_CPU0_P1_LSET3")
		)
	)
	(footprint ""
		(layer "F.Cu")
		(at 50.616866 -437.642 180)
		(property "Reference" "R3467"
			(at 0 0 180)
			(layer "F.SilkS")
			(hide yes)
			(effects
				(font
					(size 1.27 1.27)
				)
			)
		)
		(property "Value" ""
			(at 0 0 180)
			(layer "F.Fab")
			(effects
				(font
					(size 1.27 1.27)
				)
			)
		)
		(duplicate_pad_numbers_are_jumpers no)
		(fp_line
			(start 0.7874 0.4064)
			(end -0.7874 0.4064)
			(stroke
				(width 0.1524)
				(type default)
			)
			(layer "F.SilkS")
		)
		(fp_line
			(start 0.7874 -0.4064)
			(end 0.7874 0.4064)
			(stroke
				(width 0.1524)
				(type default)
			)
			(layer "F.SilkS")
		)
		(fp_line
			(start -0.7874 0.4064)
			(end -0.7874 -0.4064)
			(stroke
				(width 0.1524)
				(type default)
			)
			(layer "F.SilkS")
		)
		(fp_line
			(start -0.7874 -0.4064)
			(end 0.7874 -0.4064)
			(stroke
				(width 0.1524)
				(type default)
			)
			(layer "F.SilkS")
		)
		(fp_line
			(start 0.67945 0.3048)
			(end 0.120396 0.3048)
			(stroke
				(width 0.1)
				(type default)
			)
			(layer "F.Fab")
		)
		(fp_line
			(start 0.67945 -0.3048)
			(end 0.67945 0.3048)
			(stroke
				(width 0.1)
				(type default)
			)
			(layer "F.Fab")
		)
		(fp_line
			(start 0.12065 -0.2794)
			(end 0.12065 -0.3048)
			(stroke
				(width 0.1)
				(type default)
			)
			(layer "F.Fab")
		)
		(fp_line
			(start 0.12065 -0.3048)
			(end 0.67945 -0.3048)
			(stroke
				(width 0.1)
				(type default)
			)
			(layer "F.Fab")
		)
		(fp_line
			(start 0.120396 0.3048)
			(end 0.120396 0.2794)
			(stroke
				(width 0.1)
				(type default)
			)
			(layer "F.Fab")
		)
		(fp_line
			(start 0.120396 0.2794)
			(end -0.12065 0.2794)
			(stroke
				(width 0.1)
				(type default)
			)
			(layer "F.Fab")
		)
		(fp_line
			(start -0.12065 0.3048)
			(end -0.67945 0.3048)
			(stroke
				(width 0.1)
				(type default)
			)
			(layer "F.Fab")
		)
		(fp_line
			(start -0.12065 0.2794)
			(end -0.12065 0.3048)
			(stroke
				(width 0.1)
				(type default)
			)
			(layer "F.Fab")
		)
		(fp_line
			(start -0.12065 -0.2794)
			(end 0.12065 -0.2794)
			(stroke
				(width 0.1)
				(type default)
			)
			(layer "F.Fab")
		)
		(fp_line
			(start -0.12065 -0.305054)
			(end -0.12065 -0.2794)
			(stroke
				(width 0.1)
				(type default)
			)
			(layer "F.Fab")
		)
		(fp_line
			(start -0.67945 0.3048)
			(end -0.67945 -0.305054)
			(stroke
				(width 0.1)
				(type default)
			)
			(layer "F.Fab")
		)
		(fp_line
			(start -0.67945 -0.305054)
			(end -0.12065 -0.305054)
			(stroke
				(width 0.1)
				(type default)
			)
			(layer "F.Fab")
		)
		(pad "1" smd circle
			(at -0.40005 0 180)
			(size 0 0)
			(layers "F.Cu" "F.Mask" "F.Paste")
			(net "RST_PERST_0_SWB_BUF_R_N")
		)
		(pad "2" smd circle
			(at 0.40005 0 180)
			(size 0 0)
			(layers "F.Cu" "F.Mask" "F.Paste")
			(net "GND")
		)
	)
	(footprint ""
		(layer "F.Cu")
		(at 35.649662 -419.249098 -90)
		(property "Reference" "R3290"
			(at 0 0 270)
			(layer "F.SilkS")
			(hide yes)
			(effects
				(font
					(size 1.27 1.27)
				)
			)
		)
		(property "Value" ""
			(at 0 0 270)
			(layer "F.Fab")
			(effects
				(font
					(size 1.27 1.27)
				)
			)
		)
		(duplicate_pad_numbers_are_jumpers no)
		(fp_line
			(start -0.7874 0.4064)
			(end -0.7874 -0.4064)
			(stroke
				(width 0.1524)
				(type default)
			)
			(layer "F.SilkS")
		)
		(fp_line
			(start 0.7874 0.4064)
			(end -0.7874 0.4064)
			(stroke
				(width 0.1524)
				(type default)
			)
			(layer "F.SilkS")
		)
		(fp_line
			(start -0.7874 -0.4064)
			(end 0.7874 -0.4064)
			(stroke
				(width 0.1524)
				(type default)
			)
			(layer "F.SilkS")
		)
		(fp_line
			(start 0.7874 -0.4064)
			(end 0.7874 0.4064)
			(stroke
				(width 0.1524)
				(type default)
			)
			(layer "F.SilkS")
		)
		(fp_line
			(start -0.67945 0.3048)
			(end -0.67945 -0.305054)
			(stroke
				(width 0.1)
				(type default)
			)
			(layer "F.Fab")
		)
		(fp_line
			(start -0.12065 0.3048)
			(end -0.67945 0.3048)
			(stroke
				(width 0.1)
				(type default)
			)
			(layer "F.Fab")
		)
		(fp_line
			(start 0.120396 0.3048)
			(end 0.120396 0.2794)
			(stroke
				(width 0.1)
				(type default)
			)
			(layer "F.Fab")
		)
		(fp_line
			(start 0.67945 0.3048)
			(end 0.120396 0.3048)
			(stroke
				(width 0.1)
				(type default)
			)
			(layer "F.Fab")
		)
		(fp_line
			(start -0.12065 0.2794)
			(end -0.12065 0.3048)
			(stroke
				(width 0.1)
				(type default)
			)
			(layer "F.Fab")
		)
		(fp_line
			(start 0.120396 0.2794)
			(end -0.12065 0.2794)
			(stroke
				(width 0.1)
				(type default)
			)
			(layer "F.Fab")
		)
		(fp_line
			(start -0.12065 -0.2794)
			(end 0.12065 -0.2794)
			(stroke
				(width 0.1)
				(type default)
			)
			(layer "F.Fab")
		)
		(fp_line
			(start 0.12065 -0.2794)
			(end 0.12065 -0.3048)
			(stroke
				(width 0.1)
				(type default)
			)
			(layer "F.Fab")
		)
		(fp_line
			(start 0.12065 -0.3048)
			(end 0.67945 -0.3048)
			(stroke
				(width 0.1)
				(type default)
			)
			(layer "F.Fab")
		)
		(fp_line
			(start 0.67945 -0.3048)
			(end 0.67945 0.3048)
			(stroke
				(width 0.1)
				(type default)
			)
			(layer "F.Fab")
		)
		(fp_line
			(start -0.67945 -0.305054)
			(end -0.12065 -0.305054)
			(stroke
				(width 0.1)
				(type default)
			)
			(layer "F.Fab")
		)
		(fp_line
			(start -0.12065 -0.305054)
			(end -0.12065 -0.2794)
			(stroke
				(width 0.1)
				(type default)
			)
			(layer "F.Fab")
		)
		(pad "1" smd circle
			(at -0.40005 0 270)
			(size 0 0)
			(layers "F.Cu" "F.Mask" "F.Paste")
			(net "FM_P2E_SWA")
		)
		(pad "2" smd circle
			(at 0.40005 0 270)
			(size 0 0)
			(layers "F.Cu" "F.Mask" "F.Paste")
			(net "GND")
		)
	)
	(footprint ""
		(layer "F.Cu")
		(at 424.217338 -365.797846 90)
		(property "Reference" "PR130"
			(at 0 0 90)
			(layer "F.SilkS")
			(hide yes)
			(effects
				(font
					(size 1.27 1.27)
				)
			)
		)
		(property "Value" ""
			(at 0 0 90)
			(layer "F.Fab")
			(effects
				(font
					(size 1.27 1.27)
				)
			)
		)
		(duplicate_pad_numbers_are_jumpers no)
		(fp_line
			(start 0.7874 -0.4064)
			(end 0.7874 0.4064)
			(stroke
				(width 0.1524)
				(type default)
			)
			(layer "F.SilkS")
		)
		(fp_line
			(start -0.7874 -0.4064)
			(end 0.7874 -0.4064)
			(stroke
				(width 0.1524)
				(type default)
			)
			(layer "F.SilkS")
		)
		(fp_line
			(start 0.7874 0.4064)
			(end -0.7874 0.4064)
			(stroke
				(width 0.1524)
				(type default)
			)
			(layer "F.SilkS")
		)
		(fp_line
			(start -0.7874 0.4064)
			(end -0.7874 -0.4064)
			(stroke
				(width 0.1524)
				(type default)
			)
			(layer "F.SilkS")
		)
		(fp_line
			(start -0.12065 -0.305054)
			(end -0.12065 -0.2794)
			(stroke
				(width 0.1)
				(type default)
			)
			(layer "F.Fab")
		)
		(fp_line
			(start -0.67945 -0.305054)
			(end -0.12065 -0.305054)
			(stroke
				(width 0.1)
				(type default)
			)
			(layer "F.Fab")
		)
		(fp_line
			(start 0.67945 -0.3048)
			(end 0.67945 0.3048)
			(stroke
				(width 0.1)
				(type default)
			)
			(layer "F.Fab")
		)
		(fp_line
			(start 0.12065 -0.3048)
			(end 0.67945 -0.3048)
			(stroke
				(width 0.1)
				(type default)
			)
			(layer "F.Fab")
		)
		(fp_line
			(start 0.12065 -0.2794)
			(end 0.12065 -0.3048)
			(stroke
				(width 0.1)
				(type default)
			)
			(layer "F.Fab")
		)
		(fp_line
			(start -0.12065 -0.2794)
			(end 0.12065 -0.2794)
			(stroke
				(width 0.1)
				(type default)
			)
			(layer "F.Fab")
		)
		(fp_line
			(start 0.120396 0.2794)
			(end -0.12065 0.2794)
			(stroke
				(width 0.1)
				(type default)
			)
			(layer "F.Fab")
		)
		(fp_line
			(start -0.12065 0.2794)
			(end -0.12065 0.3048)
			(stroke
				(width 0.1)
				(type default)
			)
			(layer "F.Fab")
		)
		(fp_line
			(start 0.67945 0.3048)
			(end 0.120396 0.3048)
			(stroke
				(width 0.1)
				(type default)
			)
			(layer "F.Fab")
		)
		(fp_line
			(start 0.120396 0.3048)
			(end 0.120396 0.2794)
			(stroke
				(width 0.1)
				(type default)
			)
			(layer "F.Fab")
		)
		(fp_line
			(start -0.12065 0.3048)
			(end -0.67945 0.3048)
			(stroke
				(width 0.1)
				(type default)
			)
			(layer "F.Fab")
		)
		(fp_line
			(start -0.67945 0.3048)
			(end -0.67945 -0.305054)
			(stroke
				(width 0.1)
				(type default)
			)
			(layer "F.Fab")
		)
		(pad "1" smd circle
			(at -0.40005 0 90)
			(size 0 0)
			(layers "F.Cu" "F.Mask" "F.Paste")
			(net "PVDD11_S3_P0_VCC")
		)
		(pad "2" smd circle
			(at 0.40005 0 90)
			(size 0 0)
			(layers "F.Cu" "F.Mask" "F.Paste")
			(net "P3V3_AUX")
		)
	)
	(footprint ""
		(layer "F.Cu")
		(at 106.501946 -52.86248 -90)
		(property "Reference" "R6314"
			(at 0 0 270)
			(layer "F.SilkS")
			(hide yes)
			(effects
				(font
					(size 1.27 1.27)
				)
			)
		)
		(property "Value" ""
			(at 0 0 270)
			(layer "F.Fab")
			(effects
				(font
					(size 1.27 1.27)
				)
			)
		)
		(duplicate_pad_numbers_are_jumpers no)
		(fp_line
			(start -0.7874 0.4064)
			(end -0.7874 -0.4064)
			(stroke
				(width 0.1524)
				(type default)
			)
			(layer "F.SilkS")
		)
		(fp_line
			(start 0.7874 0.4064)
			(end -0.7874 0.4064)
			(stroke
				(width 0.1524)
				(type default)
			)
			(layer "F.SilkS")
		)
		(fp_line
			(start -0.7874 -0.4064)
			(end 0.7874 -0.4064)
			(stroke
				(width 0.1524)
				(type default)
			)
			(layer "F.SilkS")
		)
		(fp_line
			(start 0.7874 -0.4064)
			(end 0.7874 0.4064)
			(stroke
				(width 0.1524)
				(type default)
			)
			(layer "F.SilkS")
		)
		(fp_line
			(start -0.67945 0.3048)
			(end -0.67945 -0.305054)
			(stroke
				(width 0.1)
				(type default)
			)
			(layer "F.Fab")
		)
		(fp_line
			(start -0.12065 0.3048)
			(end -0.67945 0.3048)
			(stroke
				(width 0.1)
				(type default)
			)
			(layer "F.Fab")
		)
		(fp_line
			(start 0.120396 0.3048)
			(end 0.120396 0.2794)
			(stroke
				(width 0.1)
				(type default)
			)
			(layer "F.Fab")
		)
		(fp_line
			(start 0.67945 0.3048)
			(end 0.120396 0.3048)
			(stroke
				(width 0.1)
				(type default)
			)
			(layer "F.Fab")
		)
		(fp_line
			(start -0.12065 0.2794)
			(end -0.12065 0.3048)
			(stroke
				(width 0.1)
				(type default)
			)
			(layer "F.Fab")
		)
		(fp_line
			(start 0.120396 0.2794)
			(end -0.12065 0.2794)
			(stroke
				(width 0.1)
				(type default)
			)
			(layer "F.Fab")
		)
		(fp_line
			(start -0.12065 -0.2794)
			(end 0.12065 -0.2794)
			(stroke
				(width 0.1)
				(type default)
			)
			(layer "F.Fab")
		)
		(fp_line
			(start 0.12065 -0.2794)
			(end 0.12065 -0.3048)
			(stroke
				(width 0.1)
				(type default)
			)
			(layer "F.Fab")
		)
		(fp_line
			(start 0.12065 -0.3048)
			(end 0.67945 -0.3048)
			(stroke
				(width 0.1)
				(type default)
			)
			(layer "F.Fab")
		)
		(fp_line
			(start 0.67945 -0.3048)
			(end 0.67945 0.3048)
			(stroke
				(width 0.1)
				(type default)
			)
			(layer "F.Fab")
		)
		(fp_line
			(start -0.67945 -0.305054)
			(end -0.12065 -0.305054)
			(stroke
				(width 0.1)
				(type default)
			)
			(layer "F.Fab")
		)
		(fp_line
			(start -0.12065 -0.305054)
			(end -0.12065 -0.2794)
			(stroke
				(width 0.1)
				(type default)
			)
			(layer "F.Fab")
		)
		(pad "1" smd circle
			(at -0.40005 0 270)
			(size 0 0)
			(layers "F.Cu" "F.Mask" "F.Paste")
			(net "SMB_USB_CPU0_HUB1_SCL")
		)
		(pad "2" smd circle
			(at 0.40005 0 270)
			(size 0 0)
			(layers "F.Cu" "F.Mask" "F.Paste")
			(net "USB_HUB2_TI_OVERCUR2_MRP_PROG_FUNC5")
		)
	)
	(footprint ""
		(layer "F.Cu")
		(at 282.685998 -255.560068 180)
		(property "Reference" "J19"
			(at -2.2098 -81.984088 0)
			(unlocked yes)
			(layer "F.SilkS")
			(effects
				(font
					(size 0.7874 0.5842)
					(thickness 0.1524)
				)
			)
		)
		(property "Value" ""
			(at 0 0 180)
			(layer "F.Fab")
			(effects
				(font
					(size 1.27 1.27)
				)
			)
		)
		(duplicate_pad_numbers_are_jumpers no)
		(fp_line
			(start 3.24993 -81.000092)
			(end 3.24993 75.630532)
			(stroke
				(width 0.1524)
				(type default)
			)
			(layer "F.SilkS")
		)
		(fp_line
			(start -3.24993 75.666092)
			(end -3.24993 -81.000092)
			(stroke
				(width 0.1524)
				(type default)
			)
			(layer "F.SilkS")
		)
		(fp_line
			(start -3.24993 72.499982)
			(end 3.24993 72.499982)
			(stroke
				(width 0.1524)
				(type default)
			)
			(layer "F.SilkS")
		)
		(fp_line
			(start -3.24993 -72.499982)
			(end 3.24993 -72.499982)
			(stroke
				(width 0.1524)
				(type default)
			)
			(layer "F.SilkS")
		)
		(fp_line
			(start -3.24993 -81.000092)
			(end 3.24993 -81.000092)
			(stroke
				(width 0.1524)
				(type default)
			)
			(layer "F.SilkS")
		)
		(fp_poly
			(pts
				(xy -3.836924 -64.477138) (xy -3.382518 -63.9318) (xy -4.091432 -63.895478)
			)
			(stroke
				(width 0)
				(type default)
			)
			(fill yes)
			(layer "F.SilkS")
		)
		(fp_line
			(start 3.24993 81.000092)
			(end -3.24993 81.000092)
			(stroke
				(width 0.1)
				(type default)
			)
			(layer "F.Fab")
		)
		(fp_line
			(start 3.24993 -81.000092)
			(end 3.24993 81.000092)
			(stroke
				(width 0.1)
				(type default)
			)
			(layer "F.Fab")
		)
		(fp_line
			(start -3.24993 81.000092)
			(end -3.24993 -81.000092)
			(stroke
				(width 0.1)
				(type default)
			)
			(layer "F.Fab")
		)
		(fp_line
			(start -3.24993 72.499982)
			(end 3.24993 72.499982)
			(stroke
				(width 0.1)
				(type default)
			)
			(layer "F.Fab")
		)
		(fp_line
			(start -3.24993 71.000112)
			(end 3.24993 71.000112)
			(stroke
				(width 0.1)
				(type default)
			)
			(layer "F.Fab")
		)
		(fp_line
			(start -3.24993 -71.000112)
			(end 3.24993 -71.000112)
			(stroke
				(width 0.1)
				(type default)
			)
			(layer "F.Fab")
		)
		(fp_line
			(start -3.24993 -72.499982)
			(end 3.24993 -72.499982)
			(stroke
				(width 0.1)
				(type default)
			)
			(layer "F.Fab")
		)
		(fp_line
			(start -3.24993 -81.000092)
			(end 3.24993 -81.000092)
			(stroke
				(width 0.1)
				(type default)
			)
			(layer "F.Fab")
		)
		(fp_poly
			(pts
				(xy -3.41503 -63.324994) (xy -4.43103 -62.816994) (xy -4.43103 -63.832994)
			)
			(stroke
				(width 0)
				(type default)
			)
			(fill yes)
			(layer "F.Fab")
		)
		(pad "1" smd rect
			(at -2.050034 -63.324994 90)
			(size 0.519938 1.4986)
			(layers "F.Cu" "F.Mask" "F.Paste")
			(net "P12V_MEM_CPU0")
		)
		(pad "2" smd rect
			(at -2.050034 -62.47511 90)
			(size 0.519938 1.4986)
			(layers "F.Cu" "F.Mask" "F.Paste")
			(net "Net_2291")
		)
		(pad "3" smd rect
			(at -2.050034 -61.624972 90)
			(size 0.519938 1.4986)
			(layers "F.Cu" "F.Mask" "F.Paste")
			(net "P3V3_AUX")
		)
		(pad "4" smd rect
			(at -2.050034 -60.775088 90)
			(size 0.519938 1.4986)
			(layers "F.Cu" "F.Mask" "F.Paste")
			(net "I3C_SPD_DDRD_CPU0_SCL")
		)
		(pad "5" smd rect
			(at -2.050034 -59.92495 90)
			(size 0.519938 1.4986)
			(layers "F.Cu" "F.Mask" "F.Paste")
			(net "I3C_SPD_DDRD_CPU0_SDA")
		)
		(pad "6" smd rect
			(at -2.050034 -59.075066 90)
			(size 0.519938 1.4986)
			(layers "F.Cu" "F.Mask" "F.Paste")
			(net "GND")
		)
		(pad "7" smd rect
			(at -2.050034 -58.224928 90)
			(size 0.519938 1.4986)
			(layers "F.Cu" "F.Mask" "F.Paste")
			(net "M_D_CPU0_SA_DQ<0>")
		)
		(pad "8" smd rect
			(at -2.050034 -57.375044 90)
			(size 0.519938 1.4986)
			(layers "F.Cu" "F.Mask" "F.Paste")
			(net "GND")
		)
		(pad "9" smd rect
			(at -2.050034 -56.524906 90)
			(size 0.519938 1.4986)
			(layers "F.Cu" "F.Mask" "F.Paste")
			(net "M_D_CPU0_SA_DQ<1>")
		)
		(pad "10" smd rect
			(at -2.050034 -55.675022 90)
			(size 0.519938 1.4986)
			(layers "F.Cu" "F.Mask" "F.Paste")
			(net "GND")
		)
		(pad "11" smd rect
			(at -2.050034 -54.824884 90)
			(size 0.519938 1.4986)
			(layers "F.Cu" "F.Mask" "F.Paste")
			(net "M_D_CPU0_SA_DQS_DP<0>")
		)
		(pad "12" smd rect
			(at -2.050034 -53.975 90)
			(size 0.519938 1.4986)
			(layers "F.Cu" "F.Mask" "F.Paste")
			(net "M_D_CPU0_SA_DQS_DN<0>")
		)
		(pad "13" smd rect
			(at -2.050034 -53.125116 90)
			(size 0.519938 1.4986)
			(layers "F.Cu" "F.Mask" "F.Paste")
			(net "GND")
		)
		(pad "14" smd rect
			(at -2.050034 -52.274978 90)
			(size 0.519938 1.4986)
			(layers "F.Cu" "F.Mask" "F.Paste")
			(net "M_D_CPU0_SA_DQ<4>")
		)
		(pad "15" smd rect
			(at -2.050034 -51.425094 90)
			(size 0.519938 1.4986)
			(layers "F.Cu" "F.Mask" "F.Paste")
			(net "GND")
		)
		(pad "16" smd rect
			(at -2.050034 -50.574956 90)
			(size 0.519938 1.4986)
			(layers "F.Cu" "F.Mask" "F.Paste")
			(net "M_D_CPU0_SA_DQ<5>")
		)
		(pad "17" smd rect
			(at -2.050034 -49.725072 90)
			(size 0.519938 1.4986)
			(layers "F.Cu" "F.Mask" "F.Paste")
			(net "GND")
		)
		(pad "18" smd rect
			(at -2.050034 -48.874934 90)
			(size 0.519938 1.4986)
			(layers "F.Cu" "F.Mask" "F.Paste")
			(net "M_D_CPU0_SA_DQ<8>")
		)
		(pad "19" smd rect
			(at -2.050034 -48.02505 90)
			(size 0.519938 1.4986)
			(layers "F.Cu" "F.Mask" "F.Paste")
			(net "GND")
		)
		(pad "20" smd rect
			(at -2.050034 -47.174912 90)
			(size 0.519938 1.4986)
			(layers "F.Cu" "F.Mask" "F.Paste")
			(net "M_D_CPU0_SA_DQ<9>")
		)
		(pad "21" smd rect
			(at -2.050034 -46.325028 90)
			(size 0.519938 1.4986)
			(layers "F.Cu" "F.Mask" "F.Paste")
			(net "GND")
		)
		(pad "22" smd rect
			(at -2.050034 -45.47489 90)
			(size 0.519938 1.4986)
			(layers "F.Cu" "F.Mask" "F.Paste")
			(net "M_D_CPU0_SA_DQS_DP<1>")
		)
		(pad "23" smd rect
			(at -2.050034 -44.625006 90)
			(size 0.519938 1.4986)
			(layers "F.Cu" "F.Mask" "F.Paste")
			(net "M_D_CPU0_SA_DQS_DN<1>")
		)
		(pad "24" smd rect
			(at -2.050034 -43.775122 90)
			(size 0.519938 1.4986)
			(layers "F.Cu" "F.Mask" "F.Paste")
			(net "GND")
		)
		(pad "25" smd rect
			(at -2.050034 -42.924984 90)
			(size 0.519938 1.4986)
			(layers "F.Cu" "F.Mask" "F.Paste")
			(net "M_D_CPU0_SA_DQ<12>")
		)
		(pad "26" smd rect
			(at -2.050034 -42.0751 90)
			(size 0.519938 1.4986)
			(layers "F.Cu" "F.Mask" "F.Paste")
			(net "GND")
		)
		(pad "27" smd rect
			(at -2.050034 -41.224962 90)
			(size 0.519938 1.4986)
			(layers "F.Cu" "F.Mask" "F.Paste")
			(net "M_D_CPU0_SA_DQ<13>")
		)
		(pad "28" smd rect
			(at -2.050034 -40.375078 90)
			(size 0.519938 1.4986)
			(layers "F.Cu" "F.Mask" "F.Paste")
			(net "GND")
		)
		(pad "29" smd rect
			(at -2.050034 -39.52494 90)
			(size 0.519938 1.4986)
			(layers "F.Cu" "F.Mask" "F.Paste")
			(net "M_D_CPU0_SA_DQ<16>")
		)
		(pad "30" smd rect
			(at -2.050034 -38.675056 90)
			(size 0.519938 1.4986)
			(layers "F.Cu" "F.Mask" "F.Paste")
			(net "GND")
		)
		(pad "31" smd rect
			(at -2.050034 -37.824918 90)
			(size 0.519938 1.4986)
			(layers "F.Cu" "F.Mask" "F.Paste")
			(net "M_D_CPU0_SA_DQ<17>")
		)
		(pad "32" smd rect
			(at -2.050034 -36.975034 90)
			(size 0.519938 1.4986)
			(layers "F.Cu" "F.Mask" "F.Paste")
			(net "GND")
		)
		(pad "33" smd rect
			(at -2.050034 -36.124896 90)
			(size 0.519938 1.4986)
			(layers "F.Cu" "F.Mask" "F.Paste")
			(net "M_D_CPU0_SA_DQS_DP<2>")
		)
		(pad "34" smd rect
			(at -2.050034 -35.275012 90)
			(size 0.519938 1.4986)
			(layers "F.Cu" "F.Mask" "F.Paste")
			(net "M_D_CPU0_SA_DQS_DN<2>")
		)
		(pad "35" smd rect
			(at -2.050034 -34.425128 90)
			(size 0.519938 1.4986)
			(layers "F.Cu" "F.Mask" "F.Paste")
			(net "GND")
		)
		(pad "36" smd rect
			(at -2.050034 -33.57499 90)
			(size 0.519938 1.4986)
			(layers "F.Cu" "F.Mask" "F.Paste")
			(net "M_D_CPU0_SA_DQ<20>")
		)
		(pad "37" smd rect
			(at -2.050034 -32.725106 90)
			(size 0.519938 1.4986)
			(layers "F.Cu" "F.Mask" "F.Paste")
			(net "GND")
		)
		(pad "38" smd rect
			(at -2.050034 -31.874968 90)
			(size 0.519938 1.4986)
			(layers "F.Cu" "F.Mask" "F.Paste")
			(net "M_D_CPU0_SA_DQ<21>")
		)
		(pad "39" smd rect
			(at -2.050034 -31.025084 90)
			(size 0.519938 1.4986)
			(layers "F.Cu" "F.Mask" "F.Paste")
			(net "GND")
		)
		(pad "40" smd rect
			(at -2.050034 -30.174946 90)
			(size 0.519938 1.4986)
			(layers "F.Cu" "F.Mask" "F.Paste")
			(net "M_D_CPU0_SA_DQ<24>")
		)
		(pad "41" smd rect
			(at -2.050034 -29.325062 90)
			(size 0.519938 1.4986)
			(layers "F.Cu" "F.Mask" "F.Paste")
			(net "GND")
		)
		(pad "42" smd rect
			(at -2.050034 -28.474924 90)
			(size 0.519938 1.4986)
			(layers "F.Cu" "F.Mask" "F.Paste")
			(net "M_D_CPU0_SA_DQ<25>")
		)
		(pad "43" smd rect
			(at -2.050034 -27.62504 90)
			(size 0.519938 1.4986)
			(layers "F.Cu" "F.Mask" "F.Paste")
			(net "GND")
		)
		(pad "44" smd rect
			(at -2.050034 -26.774902 90)
			(size 0.519938 1.4986)
			(layers "F.Cu" "F.Mask" "F.Paste")
			(net "M_D_CPU0_SA_DQS_DP<3>")
		)
		(pad "45" smd rect
			(at -2.050034 -25.925018 90)
			(size 0.519938 1.4986)
			(layers "F.Cu" "F.Mask" "F.Paste")
			(net "M_D_CPU0_SA_DQS_DN<3>")
		)
		(pad "46" smd rect
			(at -2.050034 -25.07488 90)
			(size 0.519938 1.4986)
			(layers "F.Cu" "F.Mask" "F.Paste")
			(net "GND")
		)
		(pad "47" smd rect
			(at -2.050034 -24.224996 90)
			(size 0.519938 1.4986)
			(layers "F.Cu" "F.Mask" "F.Paste")
			(net "M_D_CPU0_SA_DQ<28>")
		)
		(pad "48" smd rect
			(at -2.050034 -23.375112 90)
			(size 0.519938 1.4986)
			(layers "F.Cu" "F.Mask" "F.Paste")
			(net "GND")
		)
		(pad "49" smd rect
			(at -2.050034 -22.524974 90)
			(size 0.519938 1.4986)
			(layers "F.Cu" "F.Mask" "F.Paste")
			(net "M_D_CPU0_SA_DQ<29>")
		)
		(pad "50" smd rect
			(at -2.050034 -21.67509 90)
			(size 0.519938 1.4986)
			(layers "F.Cu" "F.Mask" "F.Paste")
			(net "GND")
		)
		(pad "51" smd rect
			(at -2.050034 -20.824952 90)
			(size 0.519938 1.4986)
			(layers "F.Cu" "F.Mask" "F.Paste")
			(net "M_D_CPU0_SA_CB<0>")
		)
		(pad "52" smd rect
			(at -2.050034 -19.975068 90)
			(size 0.519938 1.4986)
			(layers "F.Cu" "F.Mask" "F.Paste")
			(net "GND")
		)
		(pad "53" smd rect
			(at -2.050034 -19.12493 90)
			(size 0.519938 1.4986)
			(layers "F.Cu" "F.Mask" "F.Paste")
			(net "M_D_CPU0_SA_CB<1>")
		)
		(pad "54" smd rect
			(at -2.050034 -18.275046 90)
			(size 0.519938 1.4986)
			(layers "F.Cu" "F.Mask" "F.Paste")
			(net "GND")
		)
		(pad "55" smd rect
			(at -2.050034 -17.424908 90)
			(size 0.519938 1.4986)
			(layers "F.Cu" "F.Mask" "F.Paste")
			(net "M_D_CPU0_SA_DQS_DP<4>")
		)
		(pad "56" smd rect
			(at -2.050034 -16.575024 90)
			(size 0.519938 1.4986)
			(layers "F.Cu" "F.Mask" "F.Paste")
			(net "M_D_CPU0_SA_DQS_DN<4>")
		)
		(pad "57" smd rect
			(at -2.050034 -15.724886 90)
			(size 0.519938 1.4986)
			(layers "F.Cu" "F.Mask" "F.Paste")
			(net "GND")
		)
		(pad "58" smd rect
			(at -2.050034 -14.875002 90)
			(size 0.519938 1.4986)
			(layers "F.Cu" "F.Mask" "F.Paste")
			(net "M_D_CPU0_SA_CB<4>")
		)
		(pad "59" smd rect
			(at -2.050034 -14.025118 90)
			(size 0.519938 1.4986)
			(layers "F.Cu" "F.Mask" "F.Paste")
			(net "GND")
		)
		(pad "60" smd rect
			(at -2.050034 -13.17498 90)
			(size 0.519938 1.4986)
			(layers "F.Cu" "F.Mask" "F.Paste")
			(net "M_D_CPU0_SA_CB<5>")
		)
		(pad "61" smd rect
			(at -2.050034 -12.325096 90)
			(size 0.519938 1.4986)
			(layers "F.Cu" "F.Mask" "F.Paste")
			(net "GND")
		)
		(pad "62" smd rect
			(at -2.050034 -11.474958 90)
			(size 0.519938 1.4986)
			(layers "F.Cu" "F.Mask" "F.Paste")
			(net "M_D_CPU0_ALERT_N")
		)
		(pad "63" smd rect
			(at -2.050034 -10.625074 90)
			(size 0.519938 1.4986)
			(layers "F.Cu" "F.Mask" "F.Paste")
			(net "GND")
		)
		(pad "64" smd rect
			(at -2.050034 -9.774936 90)
			(size 0.519938 1.4986)
			(layers "F.Cu" "F.Mask" "F.Paste")
			(net "M_D_CPU0_SA_CS_N<0>")
		)
		(pad "65" smd rect
			(at -2.050034 -8.925052 90)
			(size 0.519938 1.4986)
			(layers "F.Cu" "F.Mask" "F.Paste")
			(net "GND")
		)
		(pad "66" smd rect
			(at -2.050034 -8.074914 90)
			(size 0.519938 1.4986)
			(layers "F.Cu" "F.Mask" "F.Paste")
			(net "M_D_CPU0_SA_CA<0>")
		)
		(pad "67" smd rect
			(at -2.050034 -7.22503 90)
			(size 0.519938 1.4986)
			(layers "F.Cu" "F.Mask" "F.Paste")
			(net "GND")
		)
		(pad "68" smd rect
			(at -2.050034 -6.374892 90)
			(size 0.519938 1.4986)
			(layers "F.Cu" "F.Mask" "F.Paste")
			(net "M_D_CPU0_SA_CA<2>")
		)
		(pad "69" smd rect
			(at -2.050034 -5.525008 90)
			(size 0.519938 1.4986)
			(layers "F.Cu" "F.Mask" "F.Paste")
			(net "GND")
		)
		(pad "70" smd rect
			(at -2.050034 -4.675124 90)
			(size 0.519938 1.4986)
			(layers "F.Cu" "F.Mask" "F.Paste")
			(net "M_D_CPU0_SA_CA<4>")
		)
		(pad "71" smd rect
			(at -2.050034 -3.824986 90)
			(size 0.519938 1.4986)
			(layers "F.Cu" "F.Mask" "F.Paste")
			(net "GND")
		)
		(pad "72" smd rect
			(at -2.050034 -2.975102 90)
			(size 0.519938 1.4986)
			(layers "F.Cu" "F.Mask" "F.Paste")
			(net "M_D_CPU0_SA_CA<6>")
		)
		(pad "73" smd rect
			(at -2.050034 -2.124964 90)
			(size 0.519938 1.4986)
			(layers "F.Cu" "F.Mask" "F.Paste")
			(net "GND")
		)
		(pad "74" smd rect
			(at -2.050034 -1.27508 90)
			(size 0.519938 1.4986)
			(layers "F.Cu" "F.Mask" "F.Paste")
			(net "M_D_CPU0_SA_PAR")
		)
		(pad "75" smd rect
			(at -2.050034 -0.424942 90)
			(size 0.519938 1.4986)
			(layers "F.Cu" "F.Mask" "F.Paste")
			(net "GND")
		)
		(pad "76" smd rect
			(at -2.050034 5.525008 90)
			(size 0.519938 1.4986)
			(layers "F.Cu" "F.Mask" "F.Paste")
			(net "M_D_CPU0_SB_CA<0>")
		)
		(pad "77" smd rect
			(at -2.050034 6.374892 90)
			(size 0.519938 1.4986)
			(layers "F.Cu" "F.Mask" "F.Paste")
			(net "GND")
		)
		(pad "78" smd rect
			(at -2.050034 7.22503 90)
			(size 0.519938 1.4986)
			(layers "F.Cu" "F.Mask" "F.Paste")
			(net "M_D_CPU0_SB_CA<2>")
		)
		(pad "79" smd rect
			(at -2.050034 8.074914 90)
			(size 0.519938 1.4986)
			(layers "F.Cu" "F.Mask" "F.Paste")
			(net "GND")
		)
		(pad "80" smd rect
			(at -2.050034 8.925052 90)
			(size 0.519938 1.4986)
			(layers "F.Cu" "F.Mask" "F.Paste")
			(net "M_D_CPU0_SB_CA<4>")
		)
		(pad "81" smd rect
			(at -2.050034 9.774936 90)
			(size 0.519938 1.4986)
			(layers "F.Cu" "F.Mask" "F.Paste")
			(net "GND")
		)
		(pad "82" smd rect
			(at -2.050034 10.625074 90)
			(size 0.519938 1.4986)
			(layers "F.Cu" "F.Mask" "F.Paste")
			(net "M_D_CPU0_SB_CA<6>")
		)
		(pad "83" smd rect
			(at -2.050034 11.474958 90)
			(size 0.519938 1.4986)
			(layers "F.Cu" "F.Mask" "F.Paste")
			(net "GND")
		)
		(pad "84" smd rect
			(at -2.050034 12.325096 90)
			(size 0.519938 1.4986)
			(layers "F.Cu" "F.Mask" "F.Paste")
			(net "M_D_CPU0_SB_CS_N<0>")
		)
		(pad "85" smd rect
			(at -2.050034 13.17498 90)
			(size 0.519938 1.4986)
			(layers "F.Cu" "F.Mask" "F.Paste")
			(net "GND")
		)
		(pad "86" smd rect
			(at -2.050034 14.025118 90)
			(size 0.519938 1.4986)
			(layers "F.Cu" "F.Mask" "F.Paste")
			(net "M_D_CPU0_SA_RSP<0>")
		)
		(pad "87" smd rect
			(at -2.050034 14.875002 90)
			(size 0.519938 1.4986)
			(layers "F.Cu" "F.Mask" "F.Paste")
			(net "M_D_CPU0_SB_RSP<0>")
		)
		(pad "88" smd rect
			(at -2.050034 15.724886 90)
			(size 0.519938 1.4986)
			(layers "F.Cu" "F.Mask" "F.Paste")
			(net "GND")
		)
		(pad "89" smd rect
			(at -2.050034 16.575024 90)
			(size 0.519938 1.4986)
			(layers "F.Cu" "F.Mask" "F.Paste")
			(net "M_D_CPU0_SB_CB<4>")
		)
		(pad "90" smd rect
			(at -2.050034 17.424908 90)
			(size 0.519938 1.4986)
			(layers "F.Cu" "F.Mask" "F.Paste")
			(net "GND")
		)
		(pad "91" smd rect
			(at -2.050034 18.275046 90)
			(size 0.519938 1.4986)
			(layers "F.Cu" "F.Mask" "F.Paste")
			(net "M_D_CPU0_SB_CB<5>")
		)
		(pad "92" smd rect
			(at -2.050034 19.12493 90)
			(size 0.519938 1.4986)
			(layers "F.Cu" "F.Mask" "F.Paste")
			(net "GND")
		)
		(pad "93" smd rect
			(at -2.050034 19.975068 90)
			(size 0.519938 1.4986)
			(layers "F.Cu" "F.Mask" "F.Paste")
			(net "M_D_CPU0_SB_DQS_DP<9>")
		)
		(pad "94" smd rect
			(at -2.050034 20.824952 90)
			(size 0.519938 1.4986)
			(layers "F.Cu" "F.Mask" "F.Paste")
			(net "M_D_CPU0_SB_DQS_DN<9>")
		)
		(pad "95" smd rect
			(at -2.050034 21.67509 90)
			(size 0.519938 1.4986)
			(layers "F.Cu" "F.Mask" "F.Paste")
			(net "GND")
		)
		(pad "96" smd rect
			(at -2.050034 22.524974 90)
			(size 0.519938 1.4986)
			(layers "F.Cu" "F.Mask" "F.Paste")
			(net "M_D_CPU0_SB_CB<0>")
		)
		(pad "97" smd rect
			(at -2.050034 23.375112 90)
			(size 0.519938 1.4986)
			(layers "F.Cu" "F.Mask" "F.Paste")
			(net "GND")
		)
		(pad "98" smd rect
			(at -2.050034 24.224996 90)
			(size 0.519938 1.4986)
			(layers "F.Cu" "F.Mask" "F.Paste")
			(net "M_D_CPU0_SB_CB<1>")
		)
		(pad "99" smd rect
			(at -2.050034 25.07488 90)
			(size 0.519938 1.4986)
			(layers "F.Cu" "F.Mask" "F.Paste")
			(net "GND")
		)
		(pad "100" smd rect
			(at -2.050034 25.925018 90)
			(size 0.519938 1.4986)
			(layers "F.Cu" "F.Mask" "F.Paste")
			(net "M_D_CPU0_SB_DQ<0>")
		)
		(pad "101" smd rect
			(at -2.050034 26.774902 90)
			(size 0.519938 1.4986)
			(layers "F.Cu" "F.Mask" "F.Paste")
			(net "GND")
		)
		(pad "102" smd rect
			(at -2.050034 27.62504 90)
			(size 0.519938 1.4986)
			(layers "F.Cu" "F.Mask" "F.Paste")
			(net "M_D_CPU0_SB_DQ<1>")
		)
		(pad "103" smd rect
			(at -2.050034 28.474924 90)
			(size 0.519938 1.4986)
			(layers "F.Cu" "F.Mask" "F.Paste")
			(net "GND")
		)
		(pad "104" smd rect
			(at -2.050034 29.325062 90)
			(size 0.519938 1.4986)
			(layers "F.Cu" "F.Mask" "F.Paste")
			(net "M_D_CPU0_SB_DQS_DP<0>")
		)
		(pad "105" smd rect
			(at -2.050034 30.174946 90)
			(size 0.519938 1.4986)
			(layers "F.Cu" "F.Mask" "F.Paste")
			(net "M_D_CPU0_SB_DQS_DN<0>")
		)
		(pad "106" smd rect
			(at -2.050034 31.025084 90)
			(size 0.519938 1.4986)
			(layers "F.Cu" "F.Mask" "F.Paste")
			(net "GND")
		)
		(pad "107" smd rect
			(at -2.050034 31.874968 90)
			(size 0.519938 1.4986)
			(layers "F.Cu" "F.Mask" "F.Paste")
			(net "M_D_CPU0_SB_DQ<4>")
		)
		(pad "108" smd rect
			(at -2.050034 32.725106 90)
			(size 0.519938 1.4986)
			(layers "F.Cu" "F.Mask" "F.Paste")
			(net "GND")
		)
		(pad "109" smd rect
			(at -2.050034 33.57499 90)
			(size 0.519938 1.4986)
			(layers "F.Cu" "F.Mask" "F.Paste")
			(net "M_D_CPU0_SB_DQ<5>")
		)
		(pad "110" smd rect
			(at -2.050034 34.425128 90)
			(size 0.519938 1.4986)
			(layers "F.Cu" "F.Mask" "F.Paste")
			(net "GND")
		)
		(pad "111" smd rect
			(at -2.050034 35.275012 90)
			(size 0.519938 1.4986)
			(layers "F.Cu" "F.Mask" "F.Paste")
			(net "M_D_CPU0_SB_DQ<8>")
		)
		(pad "112" smd rect
			(at -2.050034 36.124896 90)
			(size 0.519938 1.4986)
			(layers "F.Cu" "F.Mask" "F.Paste")
			(net "GND")
		)
		(pad "113" smd rect
			(at -2.050034 36.975034 90)
			(size 0.519938 1.4986)
			(layers "F.Cu" "F.Mask" "F.Paste")
			(net "M_D_CPU0_SB_DQ<9>")
		)
		(pad "114" smd rect
			(at -2.050034 37.824918 90)
			(size 0.519938 1.4986)
			(layers "F.Cu" "F.Mask" "F.Paste")
			(net "GND")
		)
		(pad "115" smd rect
			(at -2.050034 38.675056 90)
			(size 0.519938 1.4986)
			(layers "F.Cu" "F.Mask" "F.Paste")
			(net "M_D_CPU0_SB_DQS_DP<1>")
		)
		(pad "116" smd rect
			(at -2.050034 39.52494 90)
			(size 0.519938 1.4986)
			(layers "F.Cu" "F.Mask" "F.Paste")
			(net "M_D_CPU0_SB_DQS_DN<1>")
		)
		(pad "117" smd rect
			(at -2.050034 40.375078 90)
			(size 0.519938 1.4986)
			(layers "F.Cu" "F.Mask" "F.Paste")
			(net "GND")
		)
		(pad "118" smd rect
			(at -2.050034 41.224962 90)
			(size 0.519938 1.4986)
			(layers "F.Cu" "F.Mask" "F.Paste")
			(net "M_D_CPU0_SB_DQ<12>")
		)
		(pad "119" smd rect
			(at -2.050034 42.0751 90)
			(size 0.519938 1.4986)
			(layers "F.Cu" "F.Mask" "F.Paste")
			(net "GND")
		)
		(pad "120" smd rect
			(at -2.050034 42.924984 90)
			(size 0.519938 1.4986)
			(layers "F.Cu" "F.Mask" "F.Paste")
			(net "M_D_CPU0_SB_DQ<13>")
		)
		(pad "121" smd rect
			(at -2.050034 43.775122 90)
			(size 0.519938 1.4986)
			(layers "F.Cu" "F.Mask" "F.Paste")
			(net "GND")
		)
		(pad "122" smd rect
			(at -2.050034 44.625006 90)
			(size 0.519938 1.4986)
			(layers "F.Cu" "F.Mask" "F.Paste")
			(net "M_D_CPU0_SB_DQ<16>")
		)
		(pad "123" smd rect
			(at -2.050034 45.47489 90)
			(size 0.519938 1.4986)
			(layers "F.Cu" "F.Mask" "F.Paste")
			(net "GND")
		)
		(pad "124" smd rect
			(at -2.050034 46.325028 90)
			(size 0.519938 1.4986)
			(layers "F.Cu" "F.Mask" "F.Paste")
			(net "M_D_CPU0_SB_DQ<17>")
		)
		(pad "125" smd rect
			(at -2.050034 47.174912 90)
			(size 0.519938 1.4986)
			(layers "F.Cu" "F.Mask" "F.Paste")
			(net "GND")
		)
		(pad "126" smd rect
			(at -2.050034 48.02505 90)
			(size 0.519938 1.4986)
			(layers "F.Cu" "F.Mask" "F.Paste")
			(net "M_D_CPU0_SB_DQS_DP<2>")
		)
		(pad "127" smd rect
			(at -2.050034 48.874934 90)
			(size 0.519938 1.4986)
			(layers "F.Cu" "F.Mask" "F.Paste")
			(net "M_D_CPU0_SB_DQS_DN<2>")
		)
		(pad "128" smd rect
			(at -2.050034 49.725072 90)
			(size 0.519938 1.4986)
			(layers "F.Cu" "F.Mask" "F.Paste")
			(net "GND")
		)
		(pad "129" smd rect
			(at -2.050034 50.574956 90)
			(size 0.519938 1.4986)
			(layers "F.Cu" "F.Mask" "F.Paste")
			(net "M_D_CPU0_SB_DQ<20>")
		)
		(pad "130" smd rect
			(at -2.050034 51.425094 90)
			(size 0.519938 1.4986)
			(layers "F.Cu" "F.Mask" "F.Paste")
			(net "GND")
		)
		(pad "131" smd rect
			(at -2.050034 52.274978 90)
			(size 0.519938 1.4986)
			(layers "F.Cu" "F.Mask" "F.Paste")
			(net "M_D_CPU0_SB_DQ<21>")
		)
		(pad "132" smd rect
			(at -2.050034 53.125116 90)
			(size 0.519938 1.4986)
			(layers "F.Cu" "F.Mask" "F.Paste")
			(net "GND")
		)
		(pad "133" smd rect
			(at -2.050034 53.975 90)
			(size 0.519938 1.4986)
			(layers "F.Cu" "F.Mask" "F.Paste")
			(net "M_D_CPU0_SB_DQ<24>")
		)
		(pad "134" smd rect
			(at -2.050034 54.824884 90)
			(size 0.519938 1.4986)
			(layers "F.Cu" "F.Mask" "F.Paste")
			(net "GND")
		)
		(pad "135" smd rect
			(at -2.050034 55.675022 90)
			(size 0.519938 1.4986)
			(layers "F.Cu" "F.Mask" "F.Paste")
			(net "M_D_CPU0_SB_DQ<25>")
		)
		(pad "136" smd rect
			(at -2.050034 56.524906 90)
			(size 0.519938 1.4986)
			(layers "F.Cu" "F.Mask" "F.Paste")
			(net "GND")
		)
		(pad "137" smd rect
			(at -2.050034 57.375044 90)
			(size 0.519938 1.4986)
			(layers "F.Cu" "F.Mask" "F.Paste")
			(net "M_D_CPU0_SB_DQS_DP<3>")
		)
		(pad "138" smd rect
			(at -2.050034 58.224928 90)
			(size 0.519938 1.4986)
			(layers "F.Cu" "F.Mask" "F.Paste")
			(net "M_D_CPU0_SB_DQS_DN<3>")
		)
		(pad "139" smd rect
			(at -2.050034 59.075066 90)
			(size 0.519938 1.4986)
			(layers "F.Cu" "F.Mask" "F.Paste")
			(net "GND")
		)
		(pad "140" smd rect
			(at -2.050034 59.92495 90)
			(size 0.519938 1.4986)
			(layers "F.Cu" "F.Mask" "F.Paste")
			(net "M_D_CPU0_SB_DQ<28>")
		)
		(pad "141" smd rect
			(at -2.050034 60.775088 90)
			(size 0.519938 1.4986)
			(layers "F.Cu" "F.Mask" "F.Paste")
			(net "GND")
		)
		(pad "142" smd rect
			(at -2.050034 61.624972 90)
			(size 0.519938 1.4986)
			(layers "F.Cu" "F.Mask" "F.Paste")
			(net "M_D_CPU0_SB_DQ<29>")
		)
		(pad "143" smd rect
			(at -2.050034 62.47511 90)
			(size 0.519938 1.4986)
			(layers "F.Cu" "F.Mask" "F.Paste")
			(net "GND")
		)
		(pad "144" smd rect
			(at -2.050034 63.324994 90)
			(size 0.519938 1.4986)
			(layers "F.Cu" "F.Mask" "F.Paste")
			(net "Net_2292")
		)
		(pad "145" smd rect
			(at 2.050034 -63.324994 90)
			(size 0.519938 1.4986)
			(layers "F.Cu" "F.Mask" "F.Paste")
			(net "P12V_MEM_CPU0")
		)
		(pad "146" smd rect
			(at 2.050034 -62.47511 90)
			(size 0.519938 1.4986)
			(layers "F.Cu" "F.Mask" "F.Paste")
			(net "P12V_MEM_CPU0")
		)
		(pad "147" smd rect
			(at 2.050034 -61.624972 90)
			(size 0.519938 1.4986)
			(layers "F.Cu" "F.Mask" "F.Paste")
			(net "PWRGD_CHD_CPU0_DIMM")
		)
		(pad "148" smd rect
			(at 2.050034 -60.775088 90)
			(size 0.519938 1.4986)
			(layers "F.Cu" "F.Mask" "F.Paste")
			(net "PD_CHD_CPU0_DIMM_SAA")
		)
		(pad "149" smd rect
			(at 2.050034 -59.92495 90)
			(size 0.519938 1.4986)
			(layers "F.Cu" "F.Mask" "F.Paste")
			(net "Net_2293")
		)
		(pad "150" smd rect
			(at 2.050034 -59.075066 90)
			(size 0.519938 1.4986)
			(layers "F.Cu" "F.Mask" "F.Paste")
			(net "Net_2294")
		)
		(pad "151" smd rect
			(at 2.050034 -58.224928 90)
			(size 0.519938 1.4986)
			(layers "F.Cu" "F.Mask" "F.Paste")
			(net "GND")
		)
		(pad "152" smd rect
			(at 2.050034 -57.375044 90)
			(size 0.519938 1.4986)
			(layers "F.Cu" "F.Mask" "F.Paste")
			(net "M_D_CPU0_SA_DQ<2>")
		)
		(pad "153" smd rect
			(at 2.050034 -56.524906 90)
			(size 0.519938 1.4986)
			(layers "F.Cu" "F.Mask" "F.Paste")
			(net "GND")
		)
		(pad "154" smd rect
			(at 2.050034 -55.675022 90)
			(size 0.519938 1.4986)
			(layers "F.Cu" "F.Mask" "F.Paste")
			(net "M_D_CPU0_SA_DQ<3>")
		)
		(pad "155" smd rect
			(at 2.050034 -54.824884 90)
			(size 0.519938 1.4986)
			(layers "F.Cu" "F.Mask" "F.Paste")
			(net "GND")
		)
		(pad "156" smd rect
			(at 2.050034 -53.975 90)
			(size 0.519938 1.4986)
			(layers "F.Cu" "F.Mask" "F.Paste")
			(net "M_D_CPU0_SA_DQS_DN<5>")
		)
		(pad "157" smd rect
			(at 2.050034 -53.125116 90)
			(size 0.519938 1.4986)
			(layers "F.Cu" "F.Mask" "F.Paste")
			(net "M_D_CPU0_SA_DQS_DP<5>")
		)
		(pad "158" smd rect
			(at 2.050034 -52.274978 90)
			(size 0.519938 1.4986)
			(layers "F.Cu" "F.Mask" "F.Paste")
			(net "GND")
		)
		(pad "159" smd rect
			(at 2.050034 -51.425094 90)
			(size 0.519938 1.4986)
			(layers "F.Cu" "F.Mask" "F.Paste")
			(net "M_D_CPU0_SA_DQ<6>")
		)
		(pad "160" smd rect
			(at 2.050034 -50.574956 90)
			(size 0.519938 1.4986)
			(layers "F.Cu" "F.Mask" "F.Paste")
			(net "GND")
		)
		(pad "161" smd rect
			(at 2.050034 -49.725072 90)
			(size 0.519938 1.4986)
			(layers "F.Cu" "F.Mask" "F.Paste")
			(net "M_D_CPU0_SA_DQ<7>")
		)
		(pad "162" smd rect
			(at 2.050034 -48.874934 90)
			(size 0.519938 1.4986)
			(layers "F.Cu" "F.Mask" "F.Paste")
			(net "GND")
		)
		(pad "163" smd rect
			(at 2.050034 -48.02505 90)
			(size 0.519938 1.4986)
			(layers "F.Cu" "F.Mask" "F.Paste")
			(net "M_D_CPU0_SA_DQ<10>")
		)
		(pad "164" smd rect
			(at 2.050034 -47.174912 90)
			(size 0.519938 1.4986)
			(layers "F.Cu" "F.Mask" "F.Paste")
			(net "GND")
		)
		(pad "165" smd rect
			(at 2.050034 -46.325028 90)
			(size 0.519938 1.4986)
			(layers "F.Cu" "F.Mask" "F.Paste")
			(net "M_D_CPU0_SA_DQ<11>")
		)
		(pad "166" smd rect
			(at 2.050034 -45.47489 90)
			(size 0.519938 1.4986)
			(layers "F.Cu" "F.Mask" "F.Paste")
			(net "GND")
		)
		(pad "167" smd rect
			(at 2.050034 -44.625006 90)
			(size 0.519938 1.4986)
			(layers "F.Cu" "F.Mask" "F.Paste")
			(net "M_D_CPU0_SA_DQS_DN<6>")
		)
		(pad "168" smd rect
			(at 2.050034 -43.775122 90)
			(size 0.519938 1.4986)
			(layers "F.Cu" "F.Mask" "F.Paste")
			(net "M_D_CPU0_SA_DQS_DP<6>")
		)
		(pad "169" smd rect
			(at 2.050034 -42.924984 90)
			(size 0.519938 1.4986)
			(layers "F.Cu" "F.Mask" "F.Paste")
			(net "GND")
		)
		(pad "170" smd rect
			(at 2.050034 -42.0751 90)
			(size 0.519938 1.4986)
			(layers "F.Cu" "F.Mask" "F.Paste")
			(net "M_D_CPU0_SA_DQ<14>")
		)
		(pad "171" smd rect
			(at 2.050034 -41.224962 90)
			(size 0.519938 1.4986)
			(layers "F.Cu" "F.Mask" "F.Paste")
			(net "GND")
		)
		(pad "172" smd rect
			(at 2.050034 -40.375078 90)
			(size 0.519938 1.4986)
			(layers "F.Cu" "F.Mask" "F.Paste")
			(net "M_D_CPU0_SA_DQ<15>")
		)
		(pad "173" smd rect
			(at 2.050034 -39.52494 90)
			(size 0.519938 1.4986)
			(layers "F.Cu" "F.Mask" "F.Paste")
			(net "GND")
		)
		(pad "174" smd rect
			(at 2.050034 -38.675056 90)
			(size 0.519938 1.4986)
			(layers "F.Cu" "F.Mask" "F.Paste")
			(net "M_D_CPU0_SA_DQ<18>")
		)
		(pad "175" smd rect
			(at 2.050034 -37.824918 90)
			(size 0.519938 1.4986)
			(layers "F.Cu" "F.Mask" "F.Paste")
			(net "GND")
		)
		(pad "176" smd rect
			(at 2.050034 -36.975034 90)
			(size 0.519938 1.4986)
			(layers "F.Cu" "F.Mask" "F.Paste")
			(net "M_D_CPU0_SA_DQ<19>")
		)
		(pad "177" smd rect
			(at 2.050034 -36.124896 90)
			(size 0.519938 1.4986)
			(layers "F.Cu" "F.Mask" "F.Paste")
			(net "GND")
		)
		(pad "178" smd rect
			(at 2.050034 -35.275012 90)
			(size 0.519938 1.4986)
			(layers "F.Cu" "F.Mask" "F.Paste")
			(net "M_D_CPU0_SA_DQS_DN<7>")
		)
		(pad "179" smd rect
			(at 2.050034 -34.425128 90)
			(size 0.519938 1.4986)
			(layers "F.Cu" "F.Mask" "F.Paste")
			(net "M_D_CPU0_SA_DQS_DP<7>")
		)
		(pad "180" smd rect
			(at 2.050034 -33.57499 90)
			(size 0.519938 1.4986)
			(layers "F.Cu" "F.Mask" "F.Paste")
			(net "GND")
		)
		(pad "181" smd rect
			(at 2.050034 -32.725106 90)
			(size 0.519938 1.4986)
			(layers "F.Cu" "F.Mask" "F.Paste")
			(net "M_D_CPU0_SA_DQ<22>")
		)
		(pad "182" smd rect
			(at 2.050034 -31.874968 90)
			(size 0.519938 1.4986)
			(layers "F.Cu" "F.Mask" "F.Paste")
			(net "GND")
		)
		(pad "183" smd rect
			(at 2.050034 -31.025084 90)
			(size 0.519938 1.4986)
			(layers "F.Cu" "F.Mask" "F.Paste")
			(net "M_D_CPU0_SA_DQ<23>")
		)
		(pad "184" smd rect
			(at 2.050034 -30.174946 90)
			(size 0.519938 1.4986)
			(layers "F.Cu" "F.Mask" "F.Paste")
			(net "GND")
		)
		(pad "185" smd rect
			(at 2.050034 -29.325062 90)
			(size 0.519938 1.4986)
			(layers "F.Cu" "F.Mask" "F.Paste")
			(net "M_D_CPU0_SA_DQ<26>")
		)
		(pad "186" smd rect
			(at 2.050034 -28.474924 90)
			(size 0.519938 1.4986)
			(layers "F.Cu" "F.Mask" "F.Paste")
			(net "GND")
		)
		(pad "187" smd rect
			(at 2.050034 -27.62504 90)
			(size 0.519938 1.4986)
			(layers "F.Cu" "F.Mask" "F.Paste")
			(net "M_D_CPU0_SA_DQ<27>")
		)
		(pad "188" smd rect
			(at 2.050034 -26.774902 90)
			(size 0.519938 1.4986)
			(layers "F.Cu" "F.Mask" "F.Paste")
			(net "GND")
		)
		(pad "189" smd rect
			(at 2.050034 -25.925018 90)
			(size 0.519938 1.4986)
			(layers "F.Cu" "F.Mask" "F.Paste")
			(net "M_D_CPU0_SA_DQS_DN<8>")
		)
		(pad "190" smd rect
			(at 2.050034 -25.07488 90)
			(size 0.519938 1.4986)
			(layers "F.Cu" "F.Mask" "F.Paste")
			(net "M_D_CPU0_SA_DQS_DP<8>")
		)
		(pad "191" smd rect
			(at 2.050034 -24.224996 90)
			(size 0.519938 1.4986)
			(layers "F.Cu" "F.Mask" "F.Paste")
			(net "GND")
		)
		(pad "192" smd rect
			(at 2.050034 -23.375112 90)
			(size 0.519938 1.4986)
			(layers "F.Cu" "F.Mask" "F.Paste")
			(net "M_D_CPU0_SA_DQ<30>")
		)
		(pad "193" smd rect
			(at 2.050034 -22.524974 90)
			(size 0.519938 1.4986)
			(layers "F.Cu" "F.Mask" "F.Paste")
			(net "GND")
		)
		(pad "194" smd rect
			(at 2.050034 -21.67509 90)
			(size 0.519938 1.4986)
			(layers "F.Cu" "F.Mask" "F.Paste")
			(net "M_D_CPU0_SA_DQ<31>")
		)
		(pad "195" smd rect
			(at 2.050034 -20.824952 90)
			(size 0.519938 1.4986)
			(layers "F.Cu" "F.Mask" "F.Paste")
			(net "GND")
		)
		(pad "196" smd rect
			(at 2.050034 -19.975068 90)
			(size 0.519938 1.4986)
			(layers "F.Cu" "F.Mask" "F.Paste")
			(net "M_D_CPU0_SA_CB<2>")
		)
		(pad "197" smd rect
			(at 2.050034 -19.12493 90)
			(size 0.519938 1.4986)
			(layers "F.Cu" "F.Mask" "F.Paste")
			(net "GND")
		)
		(pad "198" smd rect
			(at 2.050034 -18.275046 90)
			(size 0.519938 1.4986)
			(layers "F.Cu" "F.Mask" "F.Paste")
			(net "M_D_CPU0_SA_CB<3>")
		)
		(pad "199" smd rect
			(at 2.050034 -17.424908 90)
			(size 0.519938 1.4986)
			(layers "F.Cu" "F.Mask" "F.Paste")
			(net "GND")
		)
		(pad "200" smd rect
			(at 2.050034 -16.575024 90)
			(size 0.519938 1.4986)
			(layers "F.Cu" "F.Mask" "F.Paste")
			(net "M_D_CPU0_SA_DQS_DN<9>")
		)
		(pad "201" smd rect
			(at 2.050034 -15.724886 90)
			(size 0.519938 1.4986)
			(layers "F.Cu" "F.Mask" "F.Paste")
			(net "M_D_CPU0_SA_DQS_DP<9>")
		)
		(pad "202" smd rect
			(at 2.050034 -14.875002 90)
			(size 0.519938 1.4986)
			(layers "F.Cu" "F.Mask" "F.Paste")
			(net "GND")
		)
		(pad "203" smd rect
			(at 2.050034 -14.025118 90)
			(size 0.519938 1.4986)
			(layers "F.Cu" "F.Mask" "F.Paste")
			(net "M_D_CPU0_SA_CB<6>")
		)
		(pad "204" smd rect
			(at 2.050034 -13.17498 90)
			(size 0.519938 1.4986)
			(layers "F.Cu" "F.Mask" "F.Paste")
			(net "GND")
		)
		(pad "205" smd rect
			(at 2.050034 -12.325096 90)
			(size 0.519938 1.4986)
			(layers "F.Cu" "F.Mask" "F.Paste")
			(net "M_D_CPU0_SA_CB<7>")
		)
		(pad "206" smd rect
			(at 2.050034 -11.474958 90)
			(size 0.519938 1.4986)
			(layers "F.Cu" "F.Mask" "F.Paste")
			(net "GND")
		)
		(pad "207" smd rect
			(at 2.050034 -10.625074 90)
			(size 0.519938 1.4986)
			(layers "F.Cu" "F.Mask" "F.Paste")
			(net "M_D_CPU0_RESET_N")
		)
		(pad "208" smd rect
			(at 2.050034 -9.774936 90)
			(size 0.519938 1.4986)
			(layers "F.Cu" "F.Mask" "F.Paste")
			(net "GND")
		)
		(pad "209" smd rect
			(at 2.050034 -8.925052 90)
			(size 0.519938 1.4986)
			(layers "F.Cu" "F.Mask" "F.Paste")
			(net "M_D_CPU0_SA_CS_N<1>")
		)
		(pad "210" smd rect
			(at 2.050034 -8.074914 90)
			(size 0.519938 1.4986)
			(layers "F.Cu" "F.Mask" "F.Paste")
			(net "GND")
		)
		(pad "211" smd rect
			(at 2.050034 -7.22503 90)
			(size 0.519938 1.4986)
			(layers "F.Cu" "F.Mask" "F.Paste")
			(net "M_D_CPU0_SA_CA<1>")
		)
		(pad "212" smd rect
			(at 2.050034 -6.374892 90)
			(size 0.519938 1.4986)
			(layers "F.Cu" "F.Mask" "F.Paste")
			(net "GND")
		)
		(pad "213" smd rect
			(at 2.050034 -5.525008 90)
			(size 0.519938 1.4986)
			(layers "F.Cu" "F.Mask" "F.Paste")
			(net "M_D_CPU0_SA_CA<3>")
		)
		(pad "214" smd rect
			(at 2.050034 -4.675124 90)
			(size 0.519938 1.4986)
			(layers "F.Cu" "F.Mask" "F.Paste")
			(net "GND")
		)
		(pad "215" smd rect
			(at 2.050034 -3.824986 90)
			(size 0.519938 1.4986)
			(layers "F.Cu" "F.Mask" "F.Paste")
			(net "M_D_CPU0_SA_CA<5>")
		)
		(pad "216" smd rect
			(at 2.050034 -2.975102 90)
			(size 0.519938 1.4986)
			(layers "F.Cu" "F.Mask" "F.Paste")
			(net "GND")
		)
		(pad "217" smd rect
			(at 2.050034 -2.124964 90)
			(size 0.519938 1.4986)
			(layers "F.Cu" "F.Mask" "F.Paste")
			(net "M_D_CPU0_CLK_DP<0>")
		)
		(pad "218" smd rect
			(at 2.050034 -1.27508 90)
			(size 0.519938 1.4986)
			(layers "F.Cu" "F.Mask" "F.Paste")
			(net "M_D_CPU0_CLK_DN<0>")
		)
		(pad "219" smd rect
			(at 2.050034 -0.424942 90)
			(size 0.519938 1.4986)
			(layers "F.Cu" "F.Mask" "F.Paste")
			(net "GND")
		)
		(pad "220" smd rect
			(at 2.050034 5.525008 90)
			(size 0.519938 1.4986)
			(layers "F.Cu" "F.Mask" "F.Paste")
			(net "Net_2295")
		)
		(pad "221" smd rect
			(at 2.050034 6.374892 90)
			(size 0.519938 1.4986)
			(layers "F.Cu" "F.Mask" "F.Paste")
			(net "M_D_CPU0_SB_CA<1>")
		)
		(pad "222" smd rect
			(at 2.050034 7.22503 90)
			(size 0.519938 1.4986)
			(layers "F.Cu" "F.Mask" "F.Paste")
			(net "GND")
		)
		(pad "223" smd rect
			(at 2.050034 8.074914 90)
			(size 0.519938 1.4986)
			(layers "F.Cu" "F.Mask" "F.Paste")
			(net "M_D_CPU0_SB_CA<3>")
		)
		(pad "224" smd rect
			(at 2.050034 8.925052 90)
			(size 0.519938 1.4986)
			(layers "F.Cu" "F.Mask" "F.Paste")
			(net "GND")
		)
		(pad "225" smd rect
			(at 2.050034 9.774936 90)
			(size 0.519938 1.4986)
			(layers "F.Cu" "F.Mask" "F.Paste")
			(net "M_D_CPU0_SB_CA<5>")
		)
		(pad "226" smd rect
			(at 2.050034 10.625074 90)
			(size 0.519938 1.4986)
			(layers "F.Cu" "F.Mask" "F.Paste")
			(net "GND")
		)
		(pad "227" smd rect
			(at 2.050034 11.474958 90)
			(size 0.519938 1.4986)
			(layers "F.Cu" "F.Mask" "F.Paste")
			(net "M_D_CPU0_SB_PAR")
		)
		(pad "228" smd rect
			(at 2.050034 12.325096 90)
			(size 0.519938 1.4986)
			(layers "F.Cu" "F.Mask" "F.Paste")
			(net "GND")
		)
		(pad "229" smd rect
			(at 2.050034 13.17498 90)
			(size 0.519938 1.4986)
			(layers "F.Cu" "F.Mask" "F.Paste")
			(net "M_D_CPU0_SB_CS_N<1>")
		)
		(pad "230" smd rect
			(at 2.050034 14.025118 90)
			(size 0.519938 1.4986)
			(layers "F.Cu" "F.Mask" "F.Paste")
			(net "GND")
		)
		(pad "231" smd rect
			(at 2.050034 14.875002 90)
			(size 0.519938 1.4986)
			(layers "F.Cu" "F.Mask" "F.Paste")
			(net "Net_2296")
		)
		(pad "232" smd rect
			(at 2.050034 15.724886 90)
			(size 0.519938 1.4986)
			(layers "F.Cu" "F.Mask" "F.Paste")
			(net "Net_2297")
		)
		(pad "233" smd rect
			(at 2.050034 16.575024 90)
			(size 0.519938 1.4986)
			(layers "F.Cu" "F.Mask" "F.Paste")
			(net "GND")
		)
		(pad "234" smd rect
			(at 2.050034 17.424908 90)
			(size 0.519938 1.4986)
			(layers "F.Cu" "F.Mask" "F.Paste")
			(net "M_D_CPU0_SB_CB<6>")
		)
		(pad "235" smd rect
			(at 2.050034 18.275046 90)
			(size 0.519938 1.4986)
			(layers "F.Cu" "F.Mask" "F.Paste")
			(net "GND")
		)
		(pad "236" smd rect
			(at 2.050034 19.12493 90)
			(size 0.519938 1.4986)
			(layers "F.Cu" "F.Mask" "F.Paste")
			(net "M_D_CPU0_SB_CB<7>")
		)
		(pad "237" smd rect
			(at 2.050034 19.975068 90)
			(size 0.519938 1.4986)
			(layers "F.Cu" "F.Mask" "F.Paste")
			(net "GND")
		)
		(pad "238" smd rect
			(at 2.050034 20.824952 90)
			(size 0.519938 1.4986)
			(layers "F.Cu" "F.Mask" "F.Paste")
			(net "M_D_CPU0_SB_DQS_DN<4>")
		)
		(pad "239" smd rect
			(at 2.050034 21.67509 90)
			(size 0.519938 1.4986)
			(layers "F.Cu" "F.Mask" "F.Paste")
			(net "M_D_CPU0_SB_DQS_DP<4>")
		)
		(pad "240" smd rect
			(at 2.050034 22.524974 90)
			(size 0.519938 1.4986)
			(layers "F.Cu" "F.Mask" "F.Paste")
			(net "GND")
		)
		(pad "241" smd rect
			(at 2.050034 23.375112 90)
			(size 0.519938 1.4986)
			(layers "F.Cu" "F.Mask" "F.Paste")
			(net "M_D_CPU0_SB_CB<2>")
		)
		(pad "242" smd rect
			(at 2.050034 24.224996 90)
			(size 0.519938 1.4986)
			(layers "F.Cu" "F.Mask" "F.Paste")
			(net "GND")
		)
		(pad "243" smd rect
			(at 2.050034 25.07488 90)
			(size 0.519938 1.4986)
			(layers "F.Cu" "F.Mask" "F.Paste")
			(net "M_D_CPU0_SB_CB<3>")
		)
		(pad "244" smd rect
			(at 2.050034 25.925018 90)
			(size 0.519938 1.4986)
			(layers "F.Cu" "F.Mask" "F.Paste")
			(net "GND")
		)
		(pad "245" smd rect
			(at 2.050034 26.774902 90)
			(size 0.519938 1.4986)
			(layers "F.Cu" "F.Mask" "F.Paste")
			(net "M_D_CPU0_SB_DQ<2>")
		)
		(pad "246" smd rect
			(at 2.050034 27.62504 90)
			(size 0.519938 1.4986)
			(layers "F.Cu" "F.Mask" "F.Paste")
			(net "GND")
		)
		(pad "247" smd rect
			(at 2.050034 28.474924 90)
			(size 0.519938 1.4986)
			(layers "F.Cu" "F.Mask" "F.Paste")
			(net "M_D_CPU0_SB_DQ<3>")
		)
		(pad "248" smd rect
			(at 2.050034 29.325062 90)
			(size 0.519938 1.4986)
			(layers "F.Cu" "F.Mask" "F.Paste")
			(net "GND")
		)
		(pad "249" smd rect
			(at 2.050034 30.174946 90)
			(size 0.519938 1.4986)
			(layers "F.Cu" "F.Mask" "F.Paste")
			(net "M_D_CPU0_SB_DQS_DN<5>")
		)
		(pad "250" smd rect
			(at 2.050034 31.025084 90)
			(size 0.519938 1.4986)
			(layers "F.Cu" "F.Mask" "F.Paste")
			(net "M_D_CPU0_SB_DQS_DP<5>")
		)
		(pad "251" smd rect
			(at 2.050034 31.874968 90)
			(size 0.519938 1.4986)
			(layers "F.Cu" "F.Mask" "F.Paste")
			(net "GND")
		)
		(pad "252" smd rect
			(at 2.050034 32.725106 90)
			(size 0.519938 1.4986)
			(layers "F.Cu" "F.Mask" "F.Paste")
			(net "M_D_CPU0_SB_DQ<6>")
		)
		(pad "253" smd rect
			(at 2.050034 33.57499 90)
			(size 0.519938 1.4986)
			(layers "F.Cu" "F.Mask" "F.Paste")
			(net "GND")
		)
		(pad "254" smd rect
			(at 2.050034 34.425128 90)
			(size 0.519938 1.4986)
			(layers "F.Cu" "F.Mask" "F.Paste")
			(net "M_D_CPU0_SB_DQ<7>")
		)
		(pad "255" smd rect
			(at 2.050034 35.275012 90)
			(size 0.519938 1.4986)
			(layers "F.Cu" "F.Mask" "F.Paste")
			(net "GND")
		)
		(pad "256" smd rect
			(at 2.050034 36.124896 90)
			(size 0.519938 1.4986)
			(layers "F.Cu" "F.Mask" "F.Paste")
			(net "M_D_CPU0_SB_DQ<10>")
		)
		(pad "257" smd rect
			(at 2.050034 36.975034 90)
			(size 0.519938 1.4986)
			(layers "F.Cu" "F.Mask" "F.Paste")
			(net "GND")
		)
		(pad "258" smd rect
			(at 2.050034 37.824918 90)
			(size 0.519938 1.4986)
			(layers "F.Cu" "F.Mask" "F.Paste")
			(net "M_D_CPU0_SB_DQ<11>")
		)
		(pad "259" smd rect
			(at 2.050034 38.675056 90)
			(size 0.519938 1.4986)
			(layers "F.Cu" "F.Mask" "F.Paste")
			(net "GND")
		)
		(pad "260" smd rect
			(at 2.050034 39.52494 90)
			(size 0.519938 1.4986)
			(layers "F.Cu" "F.Mask" "F.Paste")
			(net "M_D_CPU0_SB_DQS_DN<6>")
		)
		(pad "261" smd rect
			(at 2.050034 40.375078 90)
			(size 0.519938 1.4986)
			(layers "F.Cu" "F.Mask" "F.Paste")
			(net "M_D_CPU0_SB_DQS_DP<6>")
		)
		(pad "262" smd rect
			(at 2.050034 41.224962 90)
			(size 0.519938 1.4986)
			(layers "F.Cu" "F.Mask" "F.Paste")
			(net "GND")
		)
		(pad "263" smd rect
			(at 2.050034 42.0751 90)
			(size 0.519938 1.4986)
			(layers "F.Cu" "F.Mask" "F.Paste")
			(net "M_D_CPU0_SB_DQ<14>")
		)
		(pad "264" smd rect
			(at 2.050034 42.924984 90)
			(size 0.519938 1.4986)
			(layers "F.Cu" "F.Mask" "F.Paste")
			(net "GND")
		)
		(pad "265" smd rect
			(at 2.050034 43.775122 90)
			(size 0.519938 1.4986)
			(layers "F.Cu" "F.Mask" "F.Paste")
			(net "M_D_CPU0_SB_DQ<15>")
		)
		(pad "266" smd rect
			(at 2.050034 44.625006 90)
			(size 0.519938 1.4986)
			(layers "F.Cu" "F.Mask" "F.Paste")
			(net "GND")
		)
		(pad "267" smd rect
			(at 2.050034 45.47489 90)
			(size 0.519938 1.4986)
			(layers "F.Cu" "F.Mask" "F.Paste")
			(net "M_D_CPU0_SB_DQ<18>")
		)
		(pad "268" smd rect
			(at 2.050034 46.325028 90)
			(size 0.519938 1.4986)
			(layers "F.Cu" "F.Mask" "F.Paste")
			(net "GND")
		)
		(pad "269" smd rect
			(at 2.050034 47.174912 90)
			(size 0.519938 1.4986)
			(layers "F.Cu" "F.Mask" "F.Paste")
			(net "M_D_CPU0_SB_DQ<19>")
		)
		(pad "270" smd rect
			(at 2.050034 48.02505 90)
			(size 0.519938 1.4986)
			(layers "F.Cu" "F.Mask" "F.Paste")
			(net "GND")
		)
		(pad "271" smd rect
			(at 2.050034 48.874934 90)
			(size 0.519938 1.4986)
			(layers "F.Cu" "F.Mask" "F.Paste")
			(net "M_D_CPU0_SB_DQS_DN<7>")
		)
		(pad "272" smd rect
			(at 2.050034 49.725072 90)
			(size 0.519938 1.4986)
			(layers "F.Cu" "F.Mask" "F.Paste")
			(net "M_D_CPU0_SB_DQS_DP<7>")
		)
		(pad "273" smd rect
			(at 2.050034 50.574956 90)
			(size 0.519938 1.4986)
			(layers "F.Cu" "F.Mask" "F.Paste")
			(net "GND")
		)
		(pad "274" smd rect
			(at 2.050034 51.425094 90)
			(size 0.519938 1.4986)
			(layers "F.Cu" "F.Mask" "F.Paste")
			(net "M_D_CPU0_SB_DQ<22>")
		)
		(pad "275" smd rect
			(at 2.050034 52.274978 90)
			(size 0.519938 1.4986)
			(layers "F.Cu" "F.Mask" "F.Paste")
			(net "GND")
		)
		(pad "276" smd rect
			(at 2.050034 53.125116 90)
			(size 0.519938 1.4986)
			(layers "F.Cu" "F.Mask" "F.Paste")
			(net "M_D_CPU0_SB_DQ<23>")
		)
		(pad "277" smd rect
			(at 2.050034 53.975 90)
			(size 0.519938 1.4986)
			(layers "F.Cu" "F.Mask" "F.Paste")
			(net "GND")
		)
		(pad "278" smd rect
			(at 2.050034 54.824884 90)
			(size 0.519938 1.4986)
			(layers "F.Cu" "F.Mask" "F.Paste")
			(net "M_D_CPU0_SB_DQ<26>")
		)
		(pad "279" smd rect
			(at 2.050034 55.675022 90)
			(size 0.519938 1.4986)
			(layers "F.Cu" "F.Mask" "F.Paste")
			(net "GND")
		)
		(pad "280" smd rect
			(at 2.050034 56.524906 90)
			(size 0.519938 1.4986)
			(layers "F.Cu" "F.Mask" "F.Paste")
			(net "M_D_CPU0_SB_DQ<27>")
		)
		(pad "281" smd rect
			(at 2.050034 57.375044 90)
			(size 0.519938 1.4986)
			(layers "F.Cu" "F.Mask" "F.Paste")
			(net "GND")
		)
		(pad "282" smd rect
			(at 2.050034 58.224928 90)
			(size 0.519938 1.4986)
			(layers "F.Cu" "F.Mask" "F.Paste")
			(net "M_D_CPU0_SB_DQS_DN<8>")
		)
		(pad "283" smd rect
			(at 2.050034 59.075066 90)
			(size 0.519938 1.4986)
			(layers "F.Cu" "F.Mask" "F.Paste")
			(net "M_D_CPU0_SB_DQS_DP<8>")
		)
		(pad "284" smd rect
			(at 2.050034 59.92495 90)
			(size 0.519938 1.4986)
			(layers "F.Cu" "F.Mask" "F.Paste")
			(net "GND")
		)
		(pad "285" smd rect
			(at 2.050034 60.775088 90)
			(size 0.519938 1.4986)
			(layers "F.Cu" "F.Mask" "F.Paste")
			(net "M_D_CPU0_SB_DQ<30>")
		)
		(pad "286" smd rect
			(at 2.050034 61.624972 90)
			(size 0.519938 1.4986)
			(layers "F.Cu" "F.Mask" "F.Paste")
			(net "GND")
		)
		(pad "287" smd rect
			(at 2.050034 62.47511 90)
			(size 0.519938 1.4986)
			(layers "F.Cu" "F.Mask" "F.Paste")
			(net "M_D_CPU0_SB_DQ<31>")
		)
		(pad "288" smd rect
			(at 2.050034 63.324994 90)
			(size 0.519938 1.4986)
			(layers "F.Cu" "F.Mask" "F.Paste")
			(net "GND")
		)
		(pad "G1" thru_hole oval
			(at 0 -68.97497 90)
			(size 1.7272 3.4798)
			(drill oval 1.2192 2.4638)
			(layers "*.Cu" "*.Mask")
			(remove_unused_layers no)
			(net "GND")
			(clearance 0.127)
			(thermal_gap 0.127)
		)
		(pad "G2" thru_hole oval
			(at 0 3.875024 90)
			(size 1.7272 3.4798)
			(drill oval 1.2192 2.4638)
			(layers "*.Cu" "*.Mask")
			(remove_unused_layers no)
			(net "GND")
			(clearance 0.127)
			(thermal_gap 0.127)
		)
		(pad "G3" thru_hole oval
			(at 0 68.97497 90)
			(size 1.7272 3.4798)
			(drill oval 1.2192 2.4638)
			(layers "*.Cu" "*.Mask")
			(remove_unused_layers no)
			(net "GND")
			(clearance 0.127)
			(thermal_gap 0.127)
		)
	)
	(footprint ""
		(layer "F.Cu")
		(at 40.494458 -429.790098 -90)
		(property "Reference" "R3265"
			(at 0 0 270)
			(layer "F.SilkS")
			(hide yes)
			(effects
				(font
					(size 1.27 1.27)
				)
			)
		)
		(property "Value" ""
			(at 0 0 270)
			(layer "F.Fab")
			(effects
				(font
					(size 1.27 1.27)
				)
			)
		)
		(duplicate_pad_numbers_are_jumpers no)
		(fp_line
			(start -0.7874 0.4064)
			(end -0.7874 -0.4064)
			(stroke
				(width 0.1524)
				(type default)
			)
			(layer "F.SilkS")
		)
		(fp_line
			(start 0.7874 0.4064)
			(end -0.7874 0.4064)
			(stroke
				(width 0.1524)
				(type default)
			)
			(layer "F.SilkS")
		)
		(fp_line
			(start -0.7874 -0.4064)
			(end 0.7874 -0.4064)
			(stroke
				(width 0.1524)
				(type default)
			)
			(layer "F.SilkS")
		)
		(fp_line
			(start 0.7874 -0.4064)
			(end 0.7874 0.4064)
			(stroke
				(width 0.1524)
				(type default)
			)
			(layer "F.SilkS")
		)
		(fp_line
			(start -0.67945 0.3048)
			(end -0.67945 -0.305054)
			(stroke
				(width 0.1)
				(type default)
			)
			(layer "F.Fab")
		)
		(fp_line
			(start -0.12065 0.3048)
			(end -0.67945 0.3048)
			(stroke
				(width 0.1)
				(type default)
			)
			(layer "F.Fab")
		)
		(fp_line
			(start 0.120396 0.3048)
			(end 0.120396 0.2794)
			(stroke
				(width 0.1)
				(type default)
			)
			(layer "F.Fab")
		)
		(fp_line
			(start 0.67945 0.3048)
			(end 0.120396 0.3048)
			(stroke
				(width 0.1)
				(type default)
			)
			(layer "F.Fab")
		)
		(fp_line
			(start -0.12065 0.2794)
			(end -0.12065 0.3048)
			(stroke
				(width 0.1)
				(type default)
			)
			(layer "F.Fab")
		)
		(fp_line
			(start 0.120396 0.2794)
			(end -0.12065 0.2794)
			(stroke
				(width 0.1)
				(type default)
			)
			(layer "F.Fab")
		)
		(fp_line
			(start -0.12065 -0.2794)
			(end 0.12065 -0.2794)
			(stroke
				(width 0.1)
				(type default)
			)
			(layer "F.Fab")
		)
		(fp_line
			(start 0.12065 -0.2794)
			(end 0.12065 -0.3048)
			(stroke
				(width 0.1)
				(type default)
			)
			(layer "F.Fab")
		)
		(fp_line
			(start 0.12065 -0.3048)
			(end 0.67945 -0.3048)
			(stroke
				(width 0.1)
				(type default)
			)
			(layer "F.Fab")
		)
		(fp_line
			(start 0.67945 -0.3048)
			(end 0.67945 0.3048)
			(stroke
				(width 0.1)
				(type default)
			)
			(layer "F.Fab")
		)
		(fp_line
			(start -0.67945 -0.305054)
			(end -0.12065 -0.305054)
			(stroke
				(width 0.1)
				(type default)
			)
			(layer "F.Fab")
		)
		(fp_line
			(start -0.12065 -0.305054)
			(end -0.12065 -0.2794)
			(stroke
				(width 0.1)
				(type default)
			)
			(layer "F.Fab")
		)
		(pad "1" smd circle
			(at -0.40005 0 270)
			(size 0 0)
			(layers "F.Cu" "F.Mask" "F.Paste")
			(net "CLK_GEN2_GPU_FPGA_OE_OR_N")
		)
		(pad "2" smd circle
			(at 0.40005 0 270)
			(size 0 0)
			(layers "F.Cu" "F.Mask" "F.Paste")
			(net "GND")
		)
	)
	(footprint ""
		(layer "F.Cu")
		(at 305.31816 -255.560068 180)
		(property "Reference" "J1"
			(at -2.2098 -81.984088 0)
			(unlocked yes)
			(layer "F.SilkS")
			(effects
				(font
					(size 0.7874 0.5842)
					(thickness 0.1524)
				)
			)
		)
		(property "Value" ""
			(at 0 0 180)
			(layer "F.Fab")
			(effects
				(font
					(size 1.27 1.27)
				)
			)
		)
		(duplicate_pad_numbers_are_jumpers no)
		(fp_line
			(start 3.24993 -81.000092)
			(end 3.24993 75.617832)
			(stroke
				(width 0.1524)
				(type default)
			)
			(layer "F.SilkS")
		)
		(fp_line
			(start -3.24993 75.617832)
			(end -3.24993 62.447932)
			(stroke
				(width 0.1524)
				(type default)
			)
			(layer "F.SilkS")
		)
		(fp_line
			(start -3.24993 72.499982)
			(end 3.24993 72.499982)
			(stroke
				(width 0.1524)
				(type default)
			)
			(layer "F.SilkS")
		)
		(fp_line
			(start -3.24993 4.916932)
			(end -3.24993 1.233932)
			(stroke
				(width 0.1524)
				(type default)
			)
			(layer "F.SilkS")
		)
		(fp_line
			(start -3.24993 -58.329068)
			(end -3.24993 -81.000092)
			(stroke
				(width 0.1524)
				(type default)
			)
			(layer "F.SilkS")
		)
		(fp_line
			(start -3.24993 -72.499982)
			(end 3.24993 -72.499982)
			(stroke
				(width 0.1524)
				(type default)
			)
			(layer "F.SilkS")
		)
		(fp_line
			(start -3.24993 -81.000092)
			(end 3.24993 -81.000092)
			(stroke
				(width 0.1524)
				(type default)
			)
			(layer "F.SilkS")
		)
		(fp_poly
			(pts
				(xy -4.652518 -63.893446) (xy -3.623056 -63.41364) (xy -4.624578 -62.877954)
			)
			(stroke
				(width 0)
				(type default)
			)
			(fill yes)
			(layer "F.SilkS")
		)
		(fp_line
			(start 3.24993 81.000092)
			(end -3.24993 81.000092)
			(stroke
				(width 0.1)
				(type default)
			)
			(layer "F.Fab")
		)
		(fp_line
			(start 3.24993 -81.000092)
			(end 3.24993 81.000092)
			(stroke
				(width 0.1)
				(type default)
			)
			(layer "F.Fab")
		)
		(fp_line
			(start -3.24993 81.000092)
			(end -3.24993 -81.000092)
			(stroke
				(width 0.1)
				(type default)
			)
			(layer "F.Fab")
		)
		(fp_line
			(start -3.24993 72.499982)
			(end 3.24993 72.499982)
			(stroke
				(width 0.1)
				(type default)
			)
			(layer "F.Fab")
		)
		(fp_line
			(start -3.24993 71.000112)
			(end 3.24993 71.000112)
			(stroke
				(width 0.1)
				(type default)
			)
			(layer "F.Fab")
		)
		(fp_line
			(start -3.24993 -71.000112)
			(end 3.24993 -71.000112)
			(stroke
				(width 0.1)
				(type default)
			)
			(layer "F.Fab")
		)
		(fp_line
			(start -3.24993 -72.499982)
			(end 3.24993 -72.499982)
			(stroke
				(width 0.1)
				(type default)
			)
			(layer "F.Fab")
		)
		(fp_line
			(start -3.24993 -81.000092)
			(end 3.24993 -81.000092)
			(stroke
				(width 0.1)
				(type default)
			)
			(layer "F.Fab")
		)
		(fp_poly
			(pts
				(xy -3.41503 -63.324994) (xy -4.43103 -62.816994) (xy -4.43103 -63.832994)
			)
			(stroke
				(width 0)
				(type default)
			)
			(fill yes)
			(layer "F.Fab")
		)
		(pad "1" smd rect
			(at -2.050034 -63.324994 90)
			(size 0.519938 1.4986)
			(layers "F.Cu" "F.Mask" "F.Paste")
			(net "P12V_MEM_CPU0")
		)
		(pad "2" smd rect
			(at -2.050034 -62.47511 90)
			(size 0.519938 1.4986)
			(layers "F.Cu" "F.Mask" "F.Paste")
			(net "Net_2249")
		)
		(pad "3" smd rect
			(at -2.050034 -61.624972 90)
			(size 0.519938 1.4986)
			(layers "F.Cu" "F.Mask" "F.Paste")
			(net "P3V3_AUX")
		)
		(pad "4" smd rect
			(at -2.050034 -60.775088 90)
			(size 0.519938 1.4986)
			(layers "F.Cu" "F.Mask" "F.Paste")
			(net "I3C_SPD_DDRA_CPU0_SCL")
		)
		(pad "5" smd rect
			(at -2.050034 -59.92495 90)
			(size 0.519938 1.4986)
			(layers "F.Cu" "F.Mask" "F.Paste")
			(net "I3C_SPD_DDRA_CPU0_SDA")
		)
		(pad "6" smd rect
			(at -2.050034 -59.075066 90)
			(size 0.519938 1.4986)
			(layers "F.Cu" "F.Mask" "F.Paste")
			(net "GND")
		)
		(pad "7" smd rect
			(at -2.050034 -58.224928 90)
			(size 0.519938 1.4986)
			(layers "F.Cu" "F.Mask" "F.Paste")
			(net "M_A_CPU0_SA_DQ<0>")
		)
		(pad "8" smd rect
			(at -2.050034 -57.375044 90)
			(size 0.519938 1.4986)
			(layers "F.Cu" "F.Mask" "F.Paste")
			(net "GND")
		)
		(pad "9" smd rect
			(at -2.050034 -56.524906 90)
			(size 0.519938 1.4986)
			(layers "F.Cu" "F.Mask" "F.Paste")
			(net "M_A_CPU0_SA_DQ<1>")
		)
		(pad "10" smd rect
			(at -2.050034 -55.675022 90)
			(size 0.519938 1.4986)
			(layers "F.Cu" "F.Mask" "F.Paste")
			(net "GND")
		)
		(pad "11" smd rect
			(at -2.050034 -54.824884 90)
			(size 0.519938 1.4986)
			(layers "F.Cu" "F.Mask" "F.Paste")
			(net "M_A_CPU0_SA_DQS_DP<0>")
		)
		(pad "12" smd rect
			(at -2.050034 -53.975 90)
			(size 0.519938 1.4986)
			(layers "F.Cu" "F.Mask" "F.Paste")
			(net "M_A_CPU0_SA_DQS_DN<0>")
		)
		(pad "13" smd rect
			(at -2.050034 -53.125116 90)
			(size 0.519938 1.4986)
			(layers "F.Cu" "F.Mask" "F.Paste")
			(net "GND")
		)
		(pad "14" smd rect
			(at -2.050034 -52.274978 90)
			(size 0.519938 1.4986)
			(layers "F.Cu" "F.Mask" "F.Paste")
			(net "M_A_CPU0_SA_DQ<4>")
		)
		(pad "15" smd rect
			(at -2.050034 -51.425094 90)
			(size 0.519938 1.4986)
			(layers "F.Cu" "F.Mask" "F.Paste")
			(net "GND")
		)
		(pad "16" smd rect
			(at -2.050034 -50.574956 90)
			(size 0.519938 1.4986)
			(layers "F.Cu" "F.Mask" "F.Paste")
			(net "M_A_CPU0_SA_DQ<5>")
		)
		(pad "17" smd rect
			(at -2.050034 -49.725072 90)
			(size 0.519938 1.4986)
			(layers "F.Cu" "F.Mask" "F.Paste")
			(net "GND")
		)
		(pad "18" smd rect
			(at -2.050034 -48.874934 90)
			(size 0.519938 1.4986)
			(layers "F.Cu" "F.Mask" "F.Paste")
			(net "M_A_CPU0_SA_DQ<8>")
		)
		(pad "19" smd rect
			(at -2.050034 -48.02505 90)
			(size 0.519938 1.4986)
			(layers "F.Cu" "F.Mask" "F.Paste")
			(net "GND")
		)
		(pad "20" smd rect
			(at -2.050034 -47.174912 90)
			(size 0.519938 1.4986)
			(layers "F.Cu" "F.Mask" "F.Paste")
			(net "M_A_CPU0_SA_DQ<9>")
		)
		(pad "21" smd rect
			(at -2.050034 -46.325028 90)
			(size 0.519938 1.4986)
			(layers "F.Cu" "F.Mask" "F.Paste")
			(net "GND")
		)
		(pad "22" smd rect
			(at -2.050034 -45.47489 90)
			(size 0.519938 1.4986)
			(layers "F.Cu" "F.Mask" "F.Paste")
			(net "M_A_CPU0_SA_DQS_DP<1>")
		)
		(pad "23" smd rect
			(at -2.050034 -44.625006 90)
			(size 0.519938 1.4986)
			(layers "F.Cu" "F.Mask" "F.Paste")
			(net "M_A_CPU0_SA_DQS_DN<1>")
		)
		(pad "24" smd rect
			(at -2.050034 -43.775122 90)
			(size 0.519938 1.4986)
			(layers "F.Cu" "F.Mask" "F.Paste")
			(net "GND")
		)
		(pad "25" smd rect
			(at -2.050034 -42.924984 90)
			(size 0.519938 1.4986)
			(layers "F.Cu" "F.Mask" "F.Paste")
			(net "M_A_CPU0_SA_DQ<12>")
		)
		(pad "26" smd rect
			(at -2.050034 -42.0751 90)
			(size 0.519938 1.4986)
			(layers "F.Cu" "F.Mask" "F.Paste")
			(net "GND")
		)
		(pad "27" smd rect
			(at -2.050034 -41.224962 90)
			(size 0.519938 1.4986)
			(layers "F.Cu" "F.Mask" "F.Paste")
			(net "M_A_CPU0_SA_DQ<13>")
		)
		(pad "28" smd rect
			(at -2.050034 -40.375078 90)
			(size 0.519938 1.4986)
			(layers "F.Cu" "F.Mask" "F.Paste")
			(net "GND")
		)
		(pad "29" smd rect
			(at -2.050034 -39.52494 90)
			(size 0.519938 1.4986)
			(layers "F.Cu" "F.Mask" "F.Paste")
			(net "M_A_CPU0_SA_DQ<16>")
		)
		(pad "30" smd rect
			(at -2.050034 -38.675056 90)
			(size 0.519938 1.4986)
			(layers "F.Cu" "F.Mask" "F.Paste")
			(net "GND")
		)
		(pad "31" smd rect
			(at -2.050034 -37.824918 90)
			(size 0.519938 1.4986)
			(layers "F.Cu" "F.Mask" "F.Paste")
			(net "M_A_CPU0_SA_DQ<17>")
		)
		(pad "32" smd rect
			(at -2.050034 -36.975034 90)
			(size 0.519938 1.4986)
			(layers "F.Cu" "F.Mask" "F.Paste")
			(net "GND")
		)
		(pad "33" smd rect
			(at -2.050034 -36.124896 90)
			(size 0.519938 1.4986)
			(layers "F.Cu" "F.Mask" "F.Paste")
			(net "M_A_CPU0_SA_DQS_DP<2>")
		)
		(pad "34" smd rect
			(at -2.050034 -35.275012 90)
			(size 0.519938 1.4986)
			(layers "F.Cu" "F.Mask" "F.Paste")
			(net "M_A_CPU0_SA_DQS_DN<2>")
		)
		(pad "35" smd rect
			(at -2.050034 -34.425128 90)
			(size 0.519938 1.4986)
			(layers "F.Cu" "F.Mask" "F.Paste")
			(net "GND")
		)
		(pad "36" smd rect
			(at -2.050034 -33.57499 90)
			(size 0.519938 1.4986)
			(layers "F.Cu" "F.Mask" "F.Paste")
			(net "M_A_CPU0_SA_DQ<20>")
		)
		(pad "37" smd rect
			(at -2.050034 -32.725106 90)
			(size 0.519938 1.4986)
			(layers "F.Cu" "F.Mask" "F.Paste")
			(net "GND")
		)
		(pad "38" smd rect
			(at -2.050034 -31.874968 90)
			(size 0.519938 1.4986)
			(layers "F.Cu" "F.Mask" "F.Paste")
			(net "M_A_CPU0_SA_DQ<21>")
		)
		(pad "39" smd rect
			(at -2.050034 -31.025084 90)
			(size 0.519938 1.4986)
			(layers "F.Cu" "F.Mask" "F.Paste")
			(net "GND")
		)
		(pad "40" smd rect
			(at -2.050034 -30.174946 90)
			(size 0.519938 1.4986)
			(layers "F.Cu" "F.Mask" "F.Paste")
			(net "M_A_CPU0_SA_DQ<24>")
		)
		(pad "41" smd rect
			(at -2.050034 -29.325062 90)
			(size 0.519938 1.4986)
			(layers "F.Cu" "F.Mask" "F.Paste")
			(net "GND")
		)
		(pad "42" smd rect
			(at -2.050034 -28.474924 90)
			(size 0.519938 1.4986)
			(layers "F.Cu" "F.Mask" "F.Paste")
			(net "M_A_CPU0_SA_DQ<25>")
		)
		(pad "43" smd rect
			(at -2.050034 -27.62504 90)
			(size 0.519938 1.4986)
			(layers "F.Cu" "F.Mask" "F.Paste")
			(net "GND")
		)
		(pad "44" smd rect
			(at -2.050034 -26.774902 90)
			(size 0.519938 1.4986)
			(layers "F.Cu" "F.Mask" "F.Paste")
			(net "M_A_CPU0_SA_DQS_DP<3>")
		)
		(pad "45" smd rect
			(at -2.050034 -25.925018 90)
			(size 0.519938 1.4986)
			(layers "F.Cu" "F.Mask" "F.Paste")
			(net "M_A_CPU0_SA_DQS_DN<3>")
		)
		(pad "46" smd rect
			(at -2.050034 -25.07488 90)
			(size 0.519938 1.4986)
			(layers "F.Cu" "F.Mask" "F.Paste")
			(net "GND")
		)
		(pad "47" smd rect
			(at -2.050034 -24.224996 90)
			(size 0.519938 1.4986)
			(layers "F.Cu" "F.Mask" "F.Paste")
			(net "M_A_CPU0_SA_DQ<28>")
		)
		(pad "48" smd rect
			(at -2.050034 -23.375112 90)
			(size 0.519938 1.4986)
			(layers "F.Cu" "F.Mask" "F.Paste")
			(net "GND")
		)
		(pad "49" smd rect
			(at -2.050034 -22.524974 90)
			(size 0.519938 1.4986)
			(layers "F.Cu" "F.Mask" "F.Paste")
			(net "M_A_CPU0_SA_DQ<29>")
		)
		(pad "50" smd rect
			(at -2.050034 -21.67509 90)
			(size 0.519938 1.4986)
			(layers "F.Cu" "F.Mask" "F.Paste")
			(net "GND")
		)
		(pad "51" smd rect
			(at -2.050034 -20.824952 90)
			(size 0.519938 1.4986)
			(layers "F.Cu" "F.Mask" "F.Paste")
			(net "M_A_CPU0_SA_CB<0>")
		)
		(pad "52" smd rect
			(at -2.050034 -19.975068 90)
			(size 0.519938 1.4986)
			(layers "F.Cu" "F.Mask" "F.Paste")
			(net "GND")
		)
		(pad "53" smd rect
			(at -2.050034 -19.12493 90)
			(size 0.519938 1.4986)
			(layers "F.Cu" "F.Mask" "F.Paste")
			(net "M_A_CPU0_SA_CB<1>")
		)
		(pad "54" smd rect
			(at -2.050034 -18.275046 90)
			(size 0.519938 1.4986)
			(layers "F.Cu" "F.Mask" "F.Paste")
			(net "GND")
		)
		(pad "55" smd rect
			(at -2.050034 -17.424908 90)
			(size 0.519938 1.4986)
			(layers "F.Cu" "F.Mask" "F.Paste")
			(net "M_A_CPU0_SA_DQS_DP<4>")
		)
		(pad "56" smd rect
			(at -2.050034 -16.575024 90)
			(size 0.519938 1.4986)
			(layers "F.Cu" "F.Mask" "F.Paste")
			(net "M_A_CPU0_SA_DQS_DN<4>")
		)
		(pad "57" smd rect
			(at -2.050034 -15.724886 90)
			(size 0.519938 1.4986)
			(layers "F.Cu" "F.Mask" "F.Paste")
			(net "GND")
		)
		(pad "58" smd rect
			(at -2.050034 -14.875002 90)
			(size 0.519938 1.4986)
			(layers "F.Cu" "F.Mask" "F.Paste")
			(net "M_A_CPU0_SA_CB<4>")
		)
		(pad "59" smd rect
			(at -2.050034 -14.025118 90)
			(size 0.519938 1.4986)
			(layers "F.Cu" "F.Mask" "F.Paste")
			(net "GND")
		)
		(pad "60" smd rect
			(at -2.050034 -13.17498 90)
			(size 0.519938 1.4986)
			(layers "F.Cu" "F.Mask" "F.Paste")
			(net "M_A_CPU0_SA_CB<5>")
		)
		(pad "61" smd rect
			(at -2.050034 -12.325096 90)
			(size 0.519938 1.4986)
			(layers "F.Cu" "F.Mask" "F.Paste")
			(net "GND")
		)
		(pad "62" smd rect
			(at -2.050034 -11.474958 90)
			(size 0.519938 1.4986)
			(layers "F.Cu" "F.Mask" "F.Paste")
			(net "M_A_CPU0_ALERT_N")
		)
		(pad "63" smd rect
			(at -2.050034 -10.625074 90)
			(size 0.519938 1.4986)
			(layers "F.Cu" "F.Mask" "F.Paste")
			(net "GND")
		)
		(pad "64" smd rect
			(at -2.050034 -9.774936 90)
			(size 0.519938 1.4986)
			(layers "F.Cu" "F.Mask" "F.Paste")
			(net "M_A_CPU0_SA_CS_N<0>")
		)
		(pad "65" smd rect
			(at -2.050034 -8.925052 90)
			(size 0.519938 1.4986)
			(layers "F.Cu" "F.Mask" "F.Paste")
			(net "GND")
		)
		(pad "66" smd rect
			(at -2.050034 -8.074914 90)
			(size 0.519938 1.4986)
			(layers "F.Cu" "F.Mask" "F.Paste")
			(net "M_A_CPU0_SA_CA<0>")
		)
		(pad "67" smd rect
			(at -2.050034 -7.22503 90)
			(size 0.519938 1.4986)
			(layers "F.Cu" "F.Mask" "F.Paste")
			(net "GND")
		)
		(pad "68" smd rect
			(at -2.050034 -6.374892 90)
			(size 0.519938 1.4986)
			(layers "F.Cu" "F.Mask" "F.Paste")
			(net "M_A_CPU0_SA_CA<2>")
		)
		(pad "69" smd rect
			(at -2.050034 -5.525008 90)
			(size 0.519938 1.4986)
			(layers "F.Cu" "F.Mask" "F.Paste")
			(net "GND")
		)
		(pad "70" smd rect
			(at -2.050034 -4.675124 90)
			(size 0.519938 1.4986)
			(layers "F.Cu" "F.Mask" "F.Paste")
			(net "M_A_CPU0_SA_CA<4>")
		)
		(pad "71" smd rect
			(at -2.050034 -3.824986 90)
			(size 0.519938 1.4986)
			(layers "F.Cu" "F.Mask" "F.Paste")
			(net "GND")
		)
		(pad "72" smd rect
			(at -2.050034 -2.975102 90)
			(size 0.519938 1.4986)
			(layers "F.Cu" "F.Mask" "F.Paste")
			(net "M_A_CPU0_SA_CA<6>")
		)
		(pad "73" smd rect
			(at -2.050034 -2.124964 90)
			(size 0.519938 1.4986)
			(layers "F.Cu" "F.Mask" "F.Paste")
			(net "GND")
		)
		(pad "74" smd rect
			(at -2.050034 -1.27508 90)
			(size 0.519938 1.4986)
			(layers "F.Cu" "F.Mask" "F.Paste")
			(net "M_A_CPU0_SA_PAR")
		)
		(pad "75" smd rect
			(at -2.050034 -0.424942 90)
			(size 0.519938 1.4986)
			(layers "F.Cu" "F.Mask" "F.Paste")
			(net "GND")
		)
		(pad "76" smd rect
			(at -2.050034 5.525008 90)
			(size 0.519938 1.4986)
			(layers "F.Cu" "F.Mask" "F.Paste")
			(net "M_A_CPU0_SB_CA<0>")
		)
		(pad "77" smd rect
			(at -2.050034 6.374892 90)
			(size 0.519938 1.4986)
			(layers "F.Cu" "F.Mask" "F.Paste")
			(net "GND")
		)
		(pad "78" smd rect
			(at -2.050034 7.22503 90)
			(size 0.519938 1.4986)
			(layers "F.Cu" "F.Mask" "F.Paste")
			(net "M_A_CPU0_SB_CA<2>")
		)
		(pad "79" smd rect
			(at -2.050034 8.074914 90)
			(size 0.519938 1.4986)
			(layers "F.Cu" "F.Mask" "F.Paste")
			(net "GND")
		)
		(pad "80" smd rect
			(at -2.050034 8.925052 90)
			(size 0.519938 1.4986)
			(layers "F.Cu" "F.Mask" "F.Paste")
			(net "M_A_CPU0_SB_CA<4>")
		)
		(pad "81" smd rect
			(at -2.050034 9.774936 90)
			(size 0.519938 1.4986)
			(layers "F.Cu" "F.Mask" "F.Paste")
			(net "GND")
		)
		(pad "82" smd rect
			(at -2.050034 10.625074 90)
			(size 0.519938 1.4986)
			(layers "F.Cu" "F.Mask" "F.Paste")
			(net "M_A_CPU0_SB_CA<6>")
		)
		(pad "83" smd rect
			(at -2.050034 11.474958 90)
			(size 0.519938 1.4986)
			(layers "F.Cu" "F.Mask" "F.Paste")
			(net "GND")
		)
		(pad "84" smd rect
			(at -2.050034 12.325096 90)
			(size 0.519938 1.4986)
			(layers "F.Cu" "F.Mask" "F.Paste")
			(net "M_A_CPU0_SB_CS_N<0>")
		)
		(pad "85" smd rect
			(at -2.050034 13.17498 90)
			(size 0.519938 1.4986)
			(layers "F.Cu" "F.Mask" "F.Paste")
			(net "GND")
		)
		(pad "86" smd rect
			(at -2.050034 14.025118 90)
			(size 0.519938 1.4986)
			(layers "F.Cu" "F.Mask" "F.Paste")
			(net "M_A_CPU0_SA_RSP<0>")
		)
		(pad "87" smd rect
			(at -2.050034 14.875002 90)
			(size 0.519938 1.4986)
			(layers "F.Cu" "F.Mask" "F.Paste")
			(net "M_A_CPU0_SB_RSP<0>")
		)
		(pad "88" smd rect
			(at -2.050034 15.724886 90)
			(size 0.519938 1.4986)
			(layers "F.Cu" "F.Mask" "F.Paste")
			(net "GND")
		)
		(pad "89" smd rect
			(at -2.050034 16.575024 90)
			(size 0.519938 1.4986)
			(layers "F.Cu" "F.Mask" "F.Paste")
			(net "M_A_CPU0_SB_CB<4>")
		)
		(pad "90" smd rect
			(at -2.050034 17.424908 90)
			(size 0.519938 1.4986)
			(layers "F.Cu" "F.Mask" "F.Paste")
			(net "GND")
		)
		(pad "91" smd rect
			(at -2.050034 18.275046 90)
			(size 0.519938 1.4986)
			(layers "F.Cu" "F.Mask" "F.Paste")
			(net "M_A_CPU0_SB_CB<5>")
		)
		(pad "92" smd rect
			(at -2.050034 19.12493 90)
			(size 0.519938 1.4986)
			(layers "F.Cu" "F.Mask" "F.Paste")
			(net "GND")
		)
		(pad "93" smd rect
			(at -2.050034 19.975068 90)
			(size 0.519938 1.4986)
			(layers "F.Cu" "F.Mask" "F.Paste")
			(net "M_A_CPU0_SB_DQS_DP<9>")
		)
		(pad "94" smd rect
			(at -2.050034 20.824952 90)
			(size 0.519938 1.4986)
			(layers "F.Cu" "F.Mask" "F.Paste")
			(net "M_A_CPU0_SB_DQS_DN<9>")
		)
		(pad "95" smd rect
			(at -2.050034 21.67509 90)
			(size 0.519938 1.4986)
			(layers "F.Cu" "F.Mask" "F.Paste")
			(net "GND")
		)
		(pad "96" smd rect
			(at -2.050034 22.524974 90)
			(size 0.519938 1.4986)
			(layers "F.Cu" "F.Mask" "F.Paste")
			(net "M_A_CPU0_SB_CB<0>")
		)
		(pad "97" smd rect
			(at -2.050034 23.375112 90)
			(size 0.519938 1.4986)
			(layers "F.Cu" "F.Mask" "F.Paste")
			(net "GND")
		)
		(pad "98" smd rect
			(at -2.050034 24.224996 90)
			(size 0.519938 1.4986)
			(layers "F.Cu" "F.Mask" "F.Paste")
			(net "M_A_CPU0_SB_CB<1>")
		)
		(pad "99" smd rect
			(at -2.050034 25.07488 90)
			(size 0.519938 1.4986)
			(layers "F.Cu" "F.Mask" "F.Paste")
			(net "GND")
		)
		(pad "100" smd rect
			(at -2.050034 25.925018 90)
			(size 0.519938 1.4986)
			(layers "F.Cu" "F.Mask" "F.Paste")
			(net "M_A_CPU0_SB_DQ<0>")
		)
		(pad "101" smd rect
			(at -2.050034 26.774902 90)
			(size 0.519938 1.4986)
			(layers "F.Cu" "F.Mask" "F.Paste")
			(net "GND")
		)
		(pad "102" smd rect
			(at -2.050034 27.62504 90)
			(size 0.519938 1.4986)
			(layers "F.Cu" "F.Mask" "F.Paste")
			(net "M_A_CPU0_SB_DQ<1>")
		)
		(pad "103" smd rect
			(at -2.050034 28.474924 90)
			(size 0.519938 1.4986)
			(layers "F.Cu" "F.Mask" "F.Paste")
			(net "GND")
		)
		(pad "104" smd rect
			(at -2.050034 29.325062 90)
			(size 0.519938 1.4986)
			(layers "F.Cu" "F.Mask" "F.Paste")
			(net "M_A_CPU0_SB_DQS_DP<0>")
		)
		(pad "105" smd rect
			(at -2.050034 30.174946 90)
			(size 0.519938 1.4986)
			(layers "F.Cu" "F.Mask" "F.Paste")
			(net "M_A_CPU0_SB_DQS_DN<0>")
		)
		(pad "106" smd rect
			(at -2.050034 31.025084 90)
			(size 0.519938 1.4986)
			(layers "F.Cu" "F.Mask" "F.Paste")
			(net "GND")
		)
		(pad "107" smd rect
			(at -2.050034 31.874968 90)
			(size 0.519938 1.4986)
			(layers "F.Cu" "F.Mask" "F.Paste")
			(net "M_A_CPU0_SB_DQ<4>")
		)
		(pad "108" smd rect
			(at -2.050034 32.725106 90)
			(size 0.519938 1.4986)
			(layers "F.Cu" "F.Mask" "F.Paste")
			(net "GND")
		)
		(pad "109" smd rect
			(at -2.050034 33.57499 90)
			(size 0.519938 1.4986)
			(layers "F.Cu" "F.Mask" "F.Paste")
			(net "M_A_CPU0_SB_DQ<5>")
		)
		(pad "110" smd rect
			(at -2.050034 34.425128 90)
			(size 0.519938 1.4986)
			(layers "F.Cu" "F.Mask" "F.Paste")
			(net "GND")
		)
		(pad "111" smd rect
			(at -2.050034 35.275012 90)
			(size 0.519938 1.4986)
			(layers "F.Cu" "F.Mask" "F.Paste")
			(net "M_A_CPU0_SB_DQ<8>")
		)
		(pad "112" smd rect
			(at -2.050034 36.124896 90)
			(size 0.519938 1.4986)
			(layers "F.Cu" "F.Mask" "F.Paste")
			(net "GND")
		)
		(pad "113" smd rect
			(at -2.050034 36.975034 90)
			(size 0.519938 1.4986)
			(layers "F.Cu" "F.Mask" "F.Paste")
			(net "M_A_CPU0_SB_DQ<9>")
		)
		(pad "114" smd rect
			(at -2.050034 37.824918 90)
			(size 0.519938 1.4986)
			(layers "F.Cu" "F.Mask" "F.Paste")
			(net "GND")
		)
		(pad "115" smd rect
			(at -2.050034 38.675056 90)
			(size 0.519938 1.4986)
			(layers "F.Cu" "F.Mask" "F.Paste")
			(net "M_A_CPU0_SB_DQS_DP<1>")
		)
		(pad "116" smd rect
			(at -2.050034 39.52494 90)
			(size 0.519938 1.4986)
			(layers "F.Cu" "F.Mask" "F.Paste")
			(net "M_A_CPU0_SB_DQS_DN<1>")
		)
		(pad "117" smd rect
			(at -2.050034 40.375078 90)
			(size 0.519938 1.4986)
			(layers "F.Cu" "F.Mask" "F.Paste")
			(net "GND")
		)
		(pad "118" smd rect
			(at -2.050034 41.224962 90)
			(size 0.519938 1.4986)
			(layers "F.Cu" "F.Mask" "F.Paste")
			(net "M_A_CPU0_SB_DQ<12>")
		)
		(pad "119" smd rect
			(at -2.050034 42.0751 90)
			(size 0.519938 1.4986)
			(layers "F.Cu" "F.Mask" "F.Paste")
			(net "GND")
		)
		(pad "120" smd rect
			(at -2.050034 42.924984 90)
			(size 0.519938 1.4986)
			(layers "F.Cu" "F.Mask" "F.Paste")
			(net "M_A_CPU0_SB_DQ<13>")
		)
		(pad "121" smd rect
			(at -2.050034 43.775122 90)
			(size 0.519938 1.4986)
			(layers "F.Cu" "F.Mask" "F.Paste")
			(net "GND")
		)
		(pad "122" smd rect
			(at -2.050034 44.625006 90)
			(size 0.519938 1.4986)
			(layers "F.Cu" "F.Mask" "F.Paste")
			(net "M_A_CPU0_SB_DQ<16>")
		)
		(pad "123" smd rect
			(at -2.050034 45.47489 90)
			(size 0.519938 1.4986)
			(layers "F.Cu" "F.Mask" "F.Paste")
			(net "GND")
		)
		(pad "124" smd rect
			(at -2.050034 46.325028 90)
			(size 0.519938 1.4986)
			(layers "F.Cu" "F.Mask" "F.Paste")
			(net "M_A_CPU0_SB_DQ<17>")
		)
		(pad "125" smd rect
			(at -2.050034 47.174912 90)
			(size 0.519938 1.4986)
			(layers "F.Cu" "F.Mask" "F.Paste")
			(net "GND")
		)
		(pad "126" smd rect
			(at -2.050034 48.02505 90)
			(size 0.519938 1.4986)
			(layers "F.Cu" "F.Mask" "F.Paste")
			(net "M_A_CPU0_SB_DQS_DP<2>")
		)
		(pad "127" smd rect
			(at -2.050034 48.874934 90)
			(size 0.519938 1.4986)
			(layers "F.Cu" "F.Mask" "F.Paste")
			(net "M_A_CPU0_SB_DQS_DN<2>")
		)
		(pad "128" smd rect
			(at -2.050034 49.725072 90)
			(size 0.519938 1.4986)
			(layers "F.Cu" "F.Mask" "F.Paste")
			(net "GND")
		)
		(pad "129" smd rect
			(at -2.050034 50.574956 90)
			(size 0.519938 1.4986)
			(layers "F.Cu" "F.Mask" "F.Paste")
			(net "M_A_CPU0_SB_DQ<20>")
		)
		(pad "130" smd rect
			(at -2.050034 51.425094 90)
			(size 0.519938 1.4986)
			(layers "F.Cu" "F.Mask" "F.Paste")
			(net "GND")
		)
		(pad "131" smd rect
			(at -2.050034 52.274978 90)
			(size 0.519938 1.4986)
			(layers "F.Cu" "F.Mask" "F.Paste")
			(net "M_A_CPU0_SB_DQ<21>")
		)
		(pad "132" smd rect
			(at -2.050034 53.125116 90)
			(size 0.519938 1.4986)
			(layers "F.Cu" "F.Mask" "F.Paste")
			(net "GND")
		)
		(pad "133" smd rect
			(at -2.050034 53.975 90)
			(size 0.519938 1.4986)
			(layers "F.Cu" "F.Mask" "F.Paste")
			(net "M_A_CPU0_SB_DQ<24>")
		)
		(pad "134" smd rect
			(at -2.050034 54.824884 90)
			(size 0.519938 1.4986)
			(layers "F.Cu" "F.Mask" "F.Paste")
			(net "GND")
		)
		(pad "135" smd rect
			(at -2.050034 55.675022 90)
			(size 0.519938 1.4986)
			(layers "F.Cu" "F.Mask" "F.Paste")
			(net "M_A_CPU0_SB_DQ<25>")
		)
		(pad "136" smd rect
			(at -2.050034 56.524906 90)
			(size 0.519938 1.4986)
			(layers "F.Cu" "F.Mask" "F.Paste")
			(net "GND")
		)
		(pad "137" smd rect
			(at -2.050034 57.375044 90)
			(size 0.519938 1.4986)
			(layers "F.Cu" "F.Mask" "F.Paste")
			(net "M_A_CPU0_SB_DQS_DP<3>")
		)
		(pad "138" smd rect
			(at -2.050034 58.224928 90)
			(size 0.519938 1.4986)
			(layers "F.Cu" "F.Mask" "F.Paste")
			(net "M_A_CPU0_SB_DQS_DN<3>")
		)
		(pad "139" smd rect
			(at -2.050034 59.075066 90)
			(size 0.519938 1.4986)
			(layers "F.Cu" "F.Mask" "F.Paste")
			(net "GND")
		)
		(pad "140" smd rect
			(at -2.050034 59.92495 90)
			(size 0.519938 1.4986)
			(layers "F.Cu" "F.Mask" "F.Paste")
			(net "M_A_CPU0_SB_DQ<28>")
		)
		(pad "141" smd rect
			(at -2.050034 60.775088 90)
			(size 0.519938 1.4986)
			(layers "F.Cu" "F.Mask" "F.Paste")
			(net "GND")
		)
		(pad "142" smd rect
			(at -2.050034 61.624972 90)
			(size 0.519938 1.4986)
			(layers "F.Cu" "F.Mask" "F.Paste")
			(net "M_A_CPU0_SB_DQ<29>")
		)
		(pad "143" smd rect
			(at -2.050034 62.47511 90)
			(size 0.519938 1.4986)
			(layers "F.Cu" "F.Mask" "F.Paste")
			(net "GND")
		)
		(pad "144" smd rect
			(at -2.050034 63.324994 90)
			(size 0.519938 1.4986)
			(layers "F.Cu" "F.Mask" "F.Paste")
			(net "Net_2250")
		)
		(pad "145" smd rect
			(at 2.050034 -63.324994 90)
			(size 0.519938 1.4986)
			(layers "F.Cu" "F.Mask" "F.Paste")
			(net "P12V_MEM_CPU0")
		)
		(pad "146" smd rect
			(at 2.050034 -62.47511 90)
			(size 0.519938 1.4986)
			(layers "F.Cu" "F.Mask" "F.Paste")
			(net "P12V_MEM_CPU0")
		)
		(pad "147" smd rect
			(at 2.050034 -61.624972 90)
			(size 0.519938 1.4986)
			(layers "F.Cu" "F.Mask" "F.Paste")
			(net "PWRGD_CHA_CPU0_DIMM0")
		)
		(pad "148" smd rect
			(at 2.050034 -60.775088 90)
			(size 0.519938 1.4986)
			(layers "F.Cu" "F.Mask" "F.Paste")
			(net "PD_CHA_CPU0_DIMM0_SAA")
		)
		(pad "149" smd rect
			(at 2.050034 -59.92495 90)
			(size 0.519938 1.4986)
			(layers "F.Cu" "F.Mask" "F.Paste")
			(net "Net_2251")
		)
		(pad "150" smd rect
			(at 2.050034 -59.075066 90)
			(size 0.519938 1.4986)
			(layers "F.Cu" "F.Mask" "F.Paste")
			(net "Net_2252")
		)
		(pad "151" smd rect
			(at 2.050034 -58.224928 90)
			(size 0.519938 1.4986)
			(layers "F.Cu" "F.Mask" "F.Paste")
			(net "GND")
		)
		(pad "152" smd rect
			(at 2.050034 -57.375044 90)
			(size 0.519938 1.4986)
			(layers "F.Cu" "F.Mask" "F.Paste")
			(net "M_A_CPU0_SA_DQ<2>")
		)
		(pad "153" smd rect
			(at 2.050034 -56.524906 90)
			(size 0.519938 1.4986)
			(layers "F.Cu" "F.Mask" "F.Paste")
			(net "GND")
		)
		(pad "154" smd rect
			(at 2.050034 -55.675022 90)
			(size 0.519938 1.4986)
			(layers "F.Cu" "F.Mask" "F.Paste")
			(net "M_A_CPU0_SA_DQ<3>")
		)
		(pad "155" smd rect
			(at 2.050034 -54.824884 90)
			(size 0.519938 1.4986)
			(layers "F.Cu" "F.Mask" "F.Paste")
			(net "GND")
		)
		(pad "156" smd rect
			(at 2.050034 -53.975 90)
			(size 0.519938 1.4986)
			(layers "F.Cu" "F.Mask" "F.Paste")
			(net "M_A_CPU0_SA_DQS_DN<5>")
		)
		(pad "157" smd rect
			(at 2.050034 -53.125116 90)
			(size 0.519938 1.4986)
			(layers "F.Cu" "F.Mask" "F.Paste")
			(net "M_A_CPU0_SA_DQS_DP<5>")
		)
		(pad "158" smd rect
			(at 2.050034 -52.274978 90)
			(size 0.519938 1.4986)
			(layers "F.Cu" "F.Mask" "F.Paste")
			(net "GND")
		)
		(pad "159" smd rect
			(at 2.050034 -51.425094 90)
			(size 0.519938 1.4986)
			(layers "F.Cu" "F.Mask" "F.Paste")
			(net "M_A_CPU0_SA_DQ<6>")
		)
		(pad "160" smd rect
			(at 2.050034 -50.574956 90)
			(size 0.519938 1.4986)
			(layers "F.Cu" "F.Mask" "F.Paste")
			(net "GND")
		)
		(pad "161" smd rect
			(at 2.050034 -49.725072 90)
			(size 0.519938 1.4986)
			(layers "F.Cu" "F.Mask" "F.Paste")
			(net "M_A_CPU0_SA_DQ<7>")
		)
		(pad "162" smd rect
			(at 2.050034 -48.874934 90)
			(size 0.519938 1.4986)
			(layers "F.Cu" "F.Mask" "F.Paste")
			(net "GND")
		)
		(pad "163" smd rect
			(at 2.050034 -48.02505 90)
			(size 0.519938 1.4986)
			(layers "F.Cu" "F.Mask" "F.Paste")
			(net "M_A_CPU0_SA_DQ<10>")
		)
		(pad "164" smd rect
			(at 2.050034 -47.174912 90)
			(size 0.519938 1.4986)
			(layers "F.Cu" "F.Mask" "F.Paste")
			(net "GND")
		)
		(pad "165" smd rect
			(at 2.050034 -46.325028 90)
			(size 0.519938 1.4986)
			(layers "F.Cu" "F.Mask" "F.Paste")
			(net "M_A_CPU0_SA_DQ<11>")
		)
		(pad "166" smd rect
			(at 2.050034 -45.47489 90)
			(size 0.519938 1.4986)
			(layers "F.Cu" "F.Mask" "F.Paste")
			(net "GND")
		)
		(pad "167" smd rect
			(at 2.050034 -44.625006 90)
			(size 0.519938 1.4986)
			(layers "F.Cu" "F.Mask" "F.Paste")
			(net "M_A_CPU0_SA_DQS_DN<6>")
		)
		(pad "168" smd rect
			(at 2.050034 -43.775122 90)
			(size 0.519938 1.4986)
			(layers "F.Cu" "F.Mask" "F.Paste")
			(net "M_A_CPU0_SA_DQS_DP<6>")
		)
		(pad "169" smd rect
			(at 2.050034 -42.924984 90)
			(size 0.519938 1.4986)
			(layers "F.Cu" "F.Mask" "F.Paste")
			(net "GND")
		)
		(pad "170" smd rect
			(at 2.050034 -42.0751 90)
			(size 0.519938 1.4986)
			(layers "F.Cu" "F.Mask" "F.Paste")
			(net "M_A_CPU0_SA_DQ<14>")
		)
		(pad "171" smd rect
			(at 2.050034 -41.224962 90)
			(size 0.519938 1.4986)
			(layers "F.Cu" "F.Mask" "F.Paste")
			(net "GND")
		)
		(pad "172" smd rect
			(at 2.050034 -40.375078 90)
			(size 0.519938 1.4986)
			(layers "F.Cu" "F.Mask" "F.Paste")
			(net "M_A_CPU0_SA_DQ<15>")
		)
		(pad "173" smd rect
			(at 2.050034 -39.52494 90)
			(size 0.519938 1.4986)
			(layers "F.Cu" "F.Mask" "F.Paste")
			(net "GND")
		)
		(pad "174" smd rect
			(at 2.050034 -38.675056 90)
			(size 0.519938 1.4986)
			(layers "F.Cu" "F.Mask" "F.Paste")
			(net "M_A_CPU0_SA_DQ<18>")
		)
		(pad "175" smd rect
			(at 2.050034 -37.824918 90)
			(size 0.519938 1.4986)
			(layers "F.Cu" "F.Mask" "F.Paste")
			(net "GND")
		)
		(pad "176" smd rect
			(at 2.050034 -36.975034 90)
			(size 0.519938 1.4986)
			(layers "F.Cu" "F.Mask" "F.Paste")
			(net "M_A_CPU0_SA_DQ<19>")
		)
		(pad "177" smd rect
			(at 2.050034 -36.124896 90)
			(size 0.519938 1.4986)
			(layers "F.Cu" "F.Mask" "F.Paste")
			(net "GND")
		)
		(pad "178" smd rect
			(at 2.050034 -35.275012 90)
			(size 0.519938 1.4986)
			(layers "F.Cu" "F.Mask" "F.Paste")
			(net "M_A_CPU0_SA_DQS_DN<7>")
		)
		(pad "179" smd rect
			(at 2.050034 -34.425128 90)
			(size 0.519938 1.4986)
			(layers "F.Cu" "F.Mask" "F.Paste")
			(net "M_A_CPU0_SA_DQS_DP<7>")
		)
		(pad "180" smd rect
			(at 2.050034 -33.57499 90)
			(size 0.519938 1.4986)
			(layers "F.Cu" "F.Mask" "F.Paste")
			(net "GND")
		)
		(pad "181" smd rect
			(at 2.050034 -32.725106 90)
			(size 0.519938 1.4986)
			(layers "F.Cu" "F.Mask" "F.Paste")
			(net "M_A_CPU0_SA_DQ<22>")
		)
		(pad "182" smd rect
			(at 2.050034 -31.874968 90)
			(size 0.519938 1.4986)
			(layers "F.Cu" "F.Mask" "F.Paste")
			(net "GND")
		)
		(pad "183" smd rect
			(at 2.050034 -31.025084 90)
			(size 0.519938 1.4986)
			(layers "F.Cu" "F.Mask" "F.Paste")
			(net "M_A_CPU0_SA_DQ<23>")
		)
		(pad "184" smd rect
			(at 2.050034 -30.174946 90)
			(size 0.519938 1.4986)
			(layers "F.Cu" "F.Mask" "F.Paste")
			(net "GND")
		)
		(pad "185" smd rect
			(at 2.050034 -29.325062 90)
			(size 0.519938 1.4986)
			(layers "F.Cu" "F.Mask" "F.Paste")
			(net "M_A_CPU0_SA_DQ<26>")
		)
		(pad "186" smd rect
			(at 2.050034 -28.474924 90)
			(size 0.519938 1.4986)
			(layers "F.Cu" "F.Mask" "F.Paste")
			(net "GND")
		)
		(pad "187" smd rect
			(at 2.050034 -27.62504 90)
			(size 0.519938 1.4986)
			(layers "F.Cu" "F.Mask" "F.Paste")
			(net "M_A_CPU0_SA_DQ<27>")
		)
		(pad "188" smd rect
			(at 2.050034 -26.774902 90)
			(size 0.519938 1.4986)
			(layers "F.Cu" "F.Mask" "F.Paste")
			(net "GND")
		)
		(pad "189" smd rect
			(at 2.050034 -25.925018 90)
			(size 0.519938 1.4986)
			(layers "F.Cu" "F.Mask" "F.Paste")
			(net "M_A_CPU0_SA_DQS_DN<8>")
		)
		(pad "190" smd rect
			(at 2.050034 -25.07488 90)
			(size 0.519938 1.4986)
			(layers "F.Cu" "F.Mask" "F.Paste")
			(net "M_A_CPU0_SA_DQS_DP<8>")
		)
		(pad "191" smd rect
			(at 2.050034 -24.224996 90)
			(size 0.519938 1.4986)
			(layers "F.Cu" "F.Mask" "F.Paste")
			(net "GND")
		)
		(pad "192" smd rect
			(at 2.050034 -23.375112 90)
			(size 0.519938 1.4986)
			(layers "F.Cu" "F.Mask" "F.Paste")
			(net "M_A_CPU0_SA_DQ<30>")
		)
		(pad "193" smd rect
			(at 2.050034 -22.524974 90)
			(size 0.519938 1.4986)
			(layers "F.Cu" "F.Mask" "F.Paste")
			(net "GND")
		)
		(pad "194" smd rect
			(at 2.050034 -21.67509 90)
			(size 0.519938 1.4986)
			(layers "F.Cu" "F.Mask" "F.Paste")
			(net "M_A_CPU0_SA_DQ<31>")
		)
		(pad "195" smd rect
			(at 2.050034 -20.824952 90)
			(size 0.519938 1.4986)
			(layers "F.Cu" "F.Mask" "F.Paste")
			(net "GND")
		)
		(pad "196" smd rect
			(at 2.050034 -19.975068 90)
			(size 0.519938 1.4986)
			(layers "F.Cu" "F.Mask" "F.Paste")
			(net "M_A_CPU0_SA_CB<2>")
		)
		(pad "197" smd rect
			(at 2.050034 -19.12493 90)
			(size 0.519938 1.4986)
			(layers "F.Cu" "F.Mask" "F.Paste")
			(net "GND")
		)
		(pad "198" smd rect
			(at 2.050034 -18.275046 90)
			(size 0.519938 1.4986)
			(layers "F.Cu" "F.Mask" "F.Paste")
			(net "M_A_CPU0_SA_CB<3>")
		)
		(pad "199" smd rect
			(at 2.050034 -17.424908 90)
			(size 0.519938 1.4986)
			(layers "F.Cu" "F.Mask" "F.Paste")
			(net "GND")
		)
		(pad "200" smd rect
			(at 2.050034 -16.575024 90)
			(size 0.519938 1.4986)
			(layers "F.Cu" "F.Mask" "F.Paste")
			(net "M_A_CPU0_SA_DQS_DN<9>")
		)
		(pad "201" smd rect
			(at 2.050034 -15.724886 90)
			(size 0.519938 1.4986)
			(layers "F.Cu" "F.Mask" "F.Paste")
			(net "M_A_CPU0_SA_DQS_DP<9>")
		)
		(pad "202" smd rect
			(at 2.050034 -14.875002 90)
			(size 0.519938 1.4986)
			(layers "F.Cu" "F.Mask" "F.Paste")
			(net "GND")
		)
		(pad "203" smd rect
			(at 2.050034 -14.025118 90)
			(size 0.519938 1.4986)
			(layers "F.Cu" "F.Mask" "F.Paste")
			(net "M_A_CPU0_SA_CB<6>")
		)
		(pad "204" smd rect
			(at 2.050034 -13.17498 90)
			(size 0.519938 1.4986)
			(layers "F.Cu" "F.Mask" "F.Paste")
			(net "GND")
		)
		(pad "205" smd rect
			(at 2.050034 -12.325096 90)
			(size 0.519938 1.4986)
			(layers "F.Cu" "F.Mask" "F.Paste")
			(net "M_A_CPU0_SA_CB<7>")
		)
		(pad "206" smd rect
			(at 2.050034 -11.474958 90)
			(size 0.519938 1.4986)
			(layers "F.Cu" "F.Mask" "F.Paste")
			(net "GND")
		)
		(pad "207" smd rect
			(at 2.050034 -10.625074 90)
			(size 0.519938 1.4986)
			(layers "F.Cu" "F.Mask" "F.Paste")
			(net "M_A_CPU0_RESET_N")
		)
		(pad "208" smd rect
			(at 2.050034 -9.774936 90)
			(size 0.519938 1.4986)
			(layers "F.Cu" "F.Mask" "F.Paste")
			(net "GND")
		)
		(pad "209" smd rect
			(at 2.050034 -8.925052 90)
			(size 0.519938 1.4986)
			(layers "F.Cu" "F.Mask" "F.Paste")
			(net "M_A_CPU0_SA_CS_N<1>")
		)
		(pad "210" smd rect
			(at 2.050034 -8.074914 90)
			(size 0.519938 1.4986)
			(layers "F.Cu" "F.Mask" "F.Paste")
			(net "GND")
		)
		(pad "211" smd rect
			(at 2.050034 -7.22503 90)
			(size 0.519938 1.4986)
			(layers "F.Cu" "F.Mask" "F.Paste")
			(net "M_A_CPU0_SA_CA<1>")
		)
		(pad "212" smd rect
			(at 2.050034 -6.374892 90)
			(size 0.519938 1.4986)
			(layers "F.Cu" "F.Mask" "F.Paste")
			(net "GND")
		)
		(pad "213" smd rect
			(at 2.050034 -5.525008 90)
			(size 0.519938 1.4986)
			(layers "F.Cu" "F.Mask" "F.Paste")
			(net "M_A_CPU0_SA_CA<3>")
		)
		(pad "214" smd rect
			(at 2.050034 -4.675124 90)
			(size 0.519938 1.4986)
			(layers "F.Cu" "F.Mask" "F.Paste")
			(net "GND")
		)
		(pad "215" smd rect
			(at 2.050034 -3.824986 90)
			(size 0.519938 1.4986)
			(layers "F.Cu" "F.Mask" "F.Paste")
			(net "M_A_CPU0_SA_CA<5>")
		)
		(pad "216" smd rect
			(at 2.050034 -2.975102 90)
			(size 0.519938 1.4986)
			(layers "F.Cu" "F.Mask" "F.Paste")
			(net "GND")
		)
		(pad "217" smd rect
			(at 2.050034 -2.124964 90)
			(size 0.519938 1.4986)
			(layers "F.Cu" "F.Mask" "F.Paste")
			(net "M_A_CPU0_CLK_DP<0>")
		)
		(pad "218" smd rect
			(at 2.050034 -1.27508 90)
			(size 0.519938 1.4986)
			(layers "F.Cu" "F.Mask" "F.Paste")
			(net "M_A_CPU0_CLK_DN<0>")
		)
		(pad "219" smd rect
			(at 2.050034 -0.424942 90)
			(size 0.519938 1.4986)
			(layers "F.Cu" "F.Mask" "F.Paste")
			(net "GND")
		)
		(pad "220" smd rect
			(at 2.050034 5.525008 90)
			(size 0.519938 1.4986)
			(layers "F.Cu" "F.Mask" "F.Paste")
			(net "Net_2253")
		)
		(pad "221" smd rect
			(at 2.050034 6.374892 90)
			(size 0.519938 1.4986)
			(layers "F.Cu" "F.Mask" "F.Paste")
			(net "M_A_CPU0_SB_CA<1>")
		)
		(pad "222" smd rect
			(at 2.050034 7.22503 90)
			(size 0.519938 1.4986)
			(layers "F.Cu" "F.Mask" "F.Paste")
			(net "GND")
		)
		(pad "223" smd rect
			(at 2.050034 8.074914 90)
			(size 0.519938 1.4986)
			(layers "F.Cu" "F.Mask" "F.Paste")
			(net "M_A_CPU0_SB_CA<3>")
		)
		(pad "224" smd rect
			(at 2.050034 8.925052 90)
			(size 0.519938 1.4986)
			(layers "F.Cu" "F.Mask" "F.Paste")
			(net "GND")
		)
		(pad "225" smd rect
			(at 2.050034 9.774936 90)
			(size 0.519938 1.4986)
			(layers "F.Cu" "F.Mask" "F.Paste")
			(net "M_A_CPU0_SB_CA<5>")
		)
		(pad "226" smd rect
			(at 2.050034 10.625074 90)
			(size 0.519938 1.4986)
			(layers "F.Cu" "F.Mask" "F.Paste")
			(net "GND")
		)
		(pad "227" smd rect
			(at 2.050034 11.474958 90)
			(size 0.519938 1.4986)
			(layers "F.Cu" "F.Mask" "F.Paste")
			(net "M_A_CPU0_SB_PAR")
		)
		(pad "228" smd rect
			(at 2.050034 12.325096 90)
			(size 0.519938 1.4986)
			(layers "F.Cu" "F.Mask" "F.Paste")
			(net "GND")
		)
		(pad "229" smd rect
			(at 2.050034 13.17498 90)
			(size 0.519938 1.4986)
			(layers "F.Cu" "F.Mask" "F.Paste")
			(net "M_A_CPU0_SB_CS_N<1>")
		)
		(pad "230" smd rect
			(at 2.050034 14.025118 90)
			(size 0.519938 1.4986)
			(layers "F.Cu" "F.Mask" "F.Paste")
			(net "GND")
		)
		(pad "231" smd rect
			(at 2.050034 14.875002 90)
			(size 0.519938 1.4986)
			(layers "F.Cu" "F.Mask" "F.Paste")
			(net "Net_2254")
		)
		(pad "232" smd rect
			(at 2.050034 15.724886 90)
			(size 0.519938 1.4986)
			(layers "F.Cu" "F.Mask" "F.Paste")
			(net "Net_2255")
		)
		(pad "233" smd rect
			(at 2.050034 16.575024 90)
			(size 0.519938 1.4986)
			(layers "F.Cu" "F.Mask" "F.Paste")
			(net "GND")
		)
		(pad "234" smd rect
			(at 2.050034 17.424908 90)
			(size 0.519938 1.4986)
			(layers "F.Cu" "F.Mask" "F.Paste")
			(net "M_A_CPU0_SB_CB<6>")
		)
		(pad "235" smd rect
			(at 2.050034 18.275046 90)
			(size 0.519938 1.4986)
			(layers "F.Cu" "F.Mask" "F.Paste")
			(net "GND")
		)
		(pad "236" smd rect
			(at 2.050034 19.12493 90)
			(size 0.519938 1.4986)
			(layers "F.Cu" "F.Mask" "F.Paste")
			(net "M_A_CPU0_SB_CB<7>")
		)
		(pad "237" smd rect
			(at 2.050034 19.975068 90)
			(size 0.519938 1.4986)
			(layers "F.Cu" "F.Mask" "F.Paste")
			(net "GND")
		)
		(pad "238" smd rect
			(at 2.050034 20.824952 90)
			(size 0.519938 1.4986)
			(layers "F.Cu" "F.Mask" "F.Paste")
			(net "M_A_CPU0_SB_DQS_DN<4>")
		)
		(pad "239" smd rect
			(at 2.050034 21.67509 90)
			(size 0.519938 1.4986)
			(layers "F.Cu" "F.Mask" "F.Paste")
			(net "M_A_CPU0_SB_DQS_DP<4>")
		)
		(pad "240" smd rect
			(at 2.050034 22.524974 90)
			(size 0.519938 1.4986)
			(layers "F.Cu" "F.Mask" "F.Paste")
			(net "GND")
		)
		(pad "241" smd rect
			(at 2.050034 23.375112 90)
			(size 0.519938 1.4986)
			(layers "F.Cu" "F.Mask" "F.Paste")
			(net "M_A_CPU0_SB_CB<2>")
		)
		(pad "242" smd rect
			(at 2.050034 24.224996 90)
			(size 0.519938 1.4986)
			(layers "F.Cu" "F.Mask" "F.Paste")
			(net "GND")
		)
		(pad "243" smd rect
			(at 2.050034 25.07488 90)
			(size 0.519938 1.4986)
			(layers "F.Cu" "F.Mask" "F.Paste")
			(net "M_A_CPU0_SB_CB<3>")
		)
		(pad "244" smd rect
			(at 2.050034 25.925018 90)
			(size 0.519938 1.4986)
			(layers "F.Cu" "F.Mask" "F.Paste")
			(net "GND")
		)
		(pad "245" smd rect
			(at 2.050034 26.774902 90)
			(size 0.519938 1.4986)
			(layers "F.Cu" "F.Mask" "F.Paste")
			(net "M_A_CPU0_SB_DQ<2>")
		)
		(pad "246" smd rect
			(at 2.050034 27.62504 90)
			(size 0.519938 1.4986)
			(layers "F.Cu" "F.Mask" "F.Paste")
			(net "GND")
		)
		(pad "247" smd rect
			(at 2.050034 28.474924 90)
			(size 0.519938 1.4986)
			(layers "F.Cu" "F.Mask" "F.Paste")
			(net "M_A_CPU0_SB_DQ<3>")
		)
		(pad "248" smd rect
			(at 2.050034 29.325062 90)
			(size 0.519938 1.4986)
			(layers "F.Cu" "F.Mask" "F.Paste")
			(net "GND")
		)
		(pad "249" smd rect
			(at 2.050034 30.174946 90)
			(size 0.519938 1.4986)
			(layers "F.Cu" "F.Mask" "F.Paste")
			(net "M_A_CPU0_SB_DQS_DN<5>")
		)
		(pad "250" smd rect
			(at 2.050034 31.025084 90)
			(size 0.519938 1.4986)
			(layers "F.Cu" "F.Mask" "F.Paste")
			(net "M_A_CPU0_SB_DQS_DP<5>")
		)
		(pad "251" smd rect
			(at 2.050034 31.874968 90)
			(size 0.519938 1.4986)
			(layers "F.Cu" "F.Mask" "F.Paste")
			(net "GND")
		)
		(pad "252" smd rect
			(at 2.050034 32.725106 90)
			(size 0.519938 1.4986)
			(layers "F.Cu" "F.Mask" "F.Paste")
			(net "M_A_CPU0_SB_DQ<6>")
		)
		(pad "253" smd rect
			(at 2.050034 33.57499 90)
			(size 0.519938 1.4986)
			(layers "F.Cu" "F.Mask" "F.Paste")
			(net "GND")
		)
		(pad "254" smd rect
			(at 2.050034 34.425128 90)
			(size 0.519938 1.4986)
			(layers "F.Cu" "F.Mask" "F.Paste")
			(net "M_A_CPU0_SB_DQ<7>")
		)
		(pad "255" smd rect
			(at 2.050034 35.275012 90)
			(size 0.519938 1.4986)
			(layers "F.Cu" "F.Mask" "F.Paste")
			(net "GND")
		)
		(pad "256" smd rect
			(at 2.050034 36.124896 90)
			(size 0.519938 1.4986)
			(layers "F.Cu" "F.Mask" "F.Paste")
			(net "M_A_CPU0_SB_DQ<10>")
		)
		(pad "257" smd rect
			(at 2.050034 36.975034 90)
			(size 0.519938 1.4986)
			(layers "F.Cu" "F.Mask" "F.Paste")
			(net "GND")
		)
		(pad "258" smd rect
			(at 2.050034 37.824918 90)
			(size 0.519938 1.4986)
			(layers "F.Cu" "F.Mask" "F.Paste")
			(net "M_A_CPU0_SB_DQ<11>")
		)
		(pad "259" smd rect
			(at 2.050034 38.675056 90)
			(size 0.519938 1.4986)
			(layers "F.Cu" "F.Mask" "F.Paste")
			(net "GND")
		)
		(pad "260" smd rect
			(at 2.050034 39.52494 90)
			(size 0.519938 1.4986)
			(layers "F.Cu" "F.Mask" "F.Paste")
			(net "M_A_CPU0_SB_DQS_DN<6>")
		)
		(pad "261" smd rect
			(at 2.050034 40.375078 90)
			(size 0.519938 1.4986)
			(layers "F.Cu" "F.Mask" "F.Paste")
			(net "M_A_CPU0_SB_DQS_DP<6>")
		)
		(pad "262" smd rect
			(at 2.050034 41.224962 90)
			(size 0.519938 1.4986)
			(layers "F.Cu" "F.Mask" "F.Paste")
			(net "GND")
		)
		(pad "263" smd rect
			(at 2.050034 42.0751 90)
			(size 0.519938 1.4986)
			(layers "F.Cu" "F.Mask" "F.Paste")
			(net "M_A_CPU0_SB_DQ<14>")
		)
		(pad "264" smd rect
			(at 2.050034 42.924984 90)
			(size 0.519938 1.4986)
			(layers "F.Cu" "F.Mask" "F.Paste")
			(net "GND")
		)
		(pad "265" smd rect
			(at 2.050034 43.775122 90)
			(size 0.519938 1.4986)
			(layers "F.Cu" "F.Mask" "F.Paste")
			(net "M_A_CPU0_SB_DQ<15>")
		)
		(pad "266" smd rect
			(at 2.050034 44.625006 90)
			(size 0.519938 1.4986)
			(layers "F.Cu" "F.Mask" "F.Paste")
			(net "GND")
		)
		(pad "267" smd rect
			(at 2.050034 45.47489 90)
			(size 0.519938 1.4986)
			(layers "F.Cu" "F.Mask" "F.Paste")
			(net "M_A_CPU0_SB_DQ<18>")
		)
		(pad "268" smd rect
			(at 2.050034 46.325028 90)
			(size 0.519938 1.4986)
			(layers "F.Cu" "F.Mask" "F.Paste")
			(net "GND")
		)
		(pad "269" smd rect
			(at 2.050034 47.174912 90)
			(size 0.519938 1.4986)
			(layers "F.Cu" "F.Mask" "F.Paste")
			(net "M_A_CPU0_SB_DQ<19>")
		)
		(pad "270" smd rect
			(at 2.050034 48.02505 90)
			(size 0.519938 1.4986)
			(layers "F.Cu" "F.Mask" "F.Paste")
			(net "GND")
		)
		(pad "271" smd rect
			(at 2.050034 48.874934 90)
			(size 0.519938 1.4986)
			(layers "F.Cu" "F.Mask" "F.Paste")
			(net "M_A_CPU0_SB_DQS_DN<7>")
		)
		(pad "272" smd rect
			(at 2.050034 49.725072 90)
			(size 0.519938 1.4986)
			(layers "F.Cu" "F.Mask" "F.Paste")
			(net "M_A_CPU0_SB_DQS_DP<7>")
		)
		(pad "273" smd rect
			(at 2.050034 50.574956 90)
			(size 0.519938 1.4986)
			(layers "F.Cu" "F.Mask" "F.Paste")
			(net "GND")
		)
		(pad "274" smd rect
			(at 2.050034 51.425094 90)
			(size 0.519938 1.4986)
			(layers "F.Cu" "F.Mask" "F.Paste")
			(net "M_A_CPU0_SB_DQ<22>")
		)
		(pad "275" smd rect
			(at 2.050034 52.274978 90)
			(size 0.519938 1.4986)
			(layers "F.Cu" "F.Mask" "F.Paste")
			(net "GND")
		)
		(pad "276" smd rect
			(at 2.050034 53.125116 90)
			(size 0.519938 1.4986)
			(layers "F.Cu" "F.Mask" "F.Paste")
			(net "M_A_CPU0_SB_DQ<23>")
		)
		(pad "277" smd rect
			(at 2.050034 53.975 90)
			(size 0.519938 1.4986)
			(layers "F.Cu" "F.Mask" "F.Paste")
			(net "GND")
		)
		(pad "278" smd rect
			(at 2.050034 54.824884 90)
			(size 0.519938 1.4986)
			(layers "F.Cu" "F.Mask" "F.Paste")
			(net "M_A_CPU0_SB_DQ<26>")
		)
		(pad "279" smd rect
			(at 2.050034 55.675022 90)
			(size 0.519938 1.4986)
			(layers "F.Cu" "F.Mask" "F.Paste")
			(net "GND")
		)
		(pad "280" smd rect
			(at 2.050034 56.524906 90)
			(size 0.519938 1.4986)
			(layers "F.Cu" "F.Mask" "F.Paste")
			(net "M_A_CPU0_SB_DQ<27>")
		)
		(pad "281" smd rect
			(at 2.050034 57.375044 90)
			(size 0.519938 1.4986)
			(layers "F.Cu" "F.Mask" "F.Paste")
			(net "GND")
		)
		(pad "282" smd rect
			(at 2.050034 58.224928 90)
			(size 0.519938 1.4986)
			(layers "F.Cu" "F.Mask" "F.Paste")
			(net "M_A_CPU0_SB_DQS_DN<8>")
		)
		(pad "283" smd rect
			(at 2.050034 59.075066 90)
			(size 0.519938 1.4986)
			(layers "F.Cu" "F.Mask" "F.Paste")
			(net "M_A_CPU0_SB_DQS_DP<8>")
		)
		(pad "284" smd rect
			(at 2.050034 59.92495 90)
			(size 0.519938 1.4986)
			(layers "F.Cu" "F.Mask" "F.Paste")
			(net "GND")
		)
		(pad "285" smd rect
			(at 2.050034 60.775088 90)
			(size 0.519938 1.4986)
			(layers "F.Cu" "F.Mask" "F.Paste")
			(net "M_A_CPU0_SB_DQ<30>")
		)
		(pad "286" smd rect
			(at 2.050034 61.624972 90)
			(size 0.519938 1.4986)
			(layers "F.Cu" "F.Mask" "F.Paste")
			(net "GND")
		)
		(pad "287" smd rect
			(at 2.050034 62.47511 90)
			(size 0.519938 1.4986)
			(layers "F.Cu" "F.Mask" "F.Paste")
			(net "M_A_CPU0_SB_DQ<31>")
		)
		(pad "288" smd rect
			(at 2.050034 63.324994 90)
			(size 0.519938 1.4986)
			(layers "F.Cu" "F.Mask" "F.Paste")
			(net "GND")
		)
		(pad "G1" thru_hole oval
			(at 0 -68.97497 90)
			(size 1.7272 3.4798)
			(drill oval 1.2192 2.4638)
			(layers "*.Cu" "*.Mask")
			(remove_unused_layers no)
			(net "GND")
			(clearance 0.127)
			(thermal_gap 0.127)
		)
		(pad "G2" thru_hole oval
			(at 0 3.875024 90)
			(size 1.7272 3.4798)
			(drill oval 1.2192 2.4638)
			(layers "*.Cu" "*.Mask")
			(remove_unused_layers no)
			(net "GND")
			(clearance 0.127)
			(thermal_gap 0.127)
		)
		(pad "G3" thru_hole oval
			(at 0 68.97497 90)
			(size 1.7272 3.4798)
			(drill oval 1.2192 2.4638)
			(layers "*.Cu" "*.Mask")
			(remove_unused_layers no)
			(net "GND")
			(clearance 0.127)
			(thermal_gap 0.127)
		)
	)
	(footprint ""
		(layer "F.Cu")
		(at 511.924808 7.571994 -90)
		(property "Reference" "X8002"
			(at -1.835658 4.818888 0)
			(unlocked yes)
			(layer "F.SilkS")
			(effects
				(font
					(size 0.7874 0.5842)
					(thickness 0.1524)
				)
				(justify left)
			)
		)
		(property "Value" ""
			(at 0 0 270)
			(layer "F.Fab")
			(effects
				(font
					(size 1.27 1.27)
				)
			)
		)
		(property "Device Type" "TP_TDR_4P_FTS_TH-TP_TDR_4P_DIP,EMPTY,TP15"
			(at 1.30175 1.27 0)
			(unlocked yes)
			(layer "F.Fab")
			(hide yes)
			(effects
				(font
					(size 0.635 0.4064)
					(thickness 0.1524)
				)
			)
		)
		(property "User Part Number" "N_A"
			(at 1.30175 1.27 0)
			(unlocked yes)
			(layer "Cmts.User")
			(hide yes)
			(effects
				(font
					(size 0.635 0.4064)
					(thickness 0.1524)
				)
			)
		)
		(duplicate_pad_numbers_are_jumpers no)
		(fp_line
			(start 0 3.81)
			(end 2.54 3.81)
			(stroke
				(width 0.1524)
				(type default)
			)
			(layer "F.SilkS")
		)
		(fp_line
			(start 2.54 3.81)
			(end 2.54 3.6703)
			(stroke
				(width 0.1524)
				(type default)
			)
			(layer "F.SilkS")
		)
		(fp_line
			(start 0 3.175)
			(end 0 3.81)
			(stroke
				(width 0.1524)
				(type default)
			)
			(layer "F.SilkS")
		)
		(fp_line
			(start 2.54 1.4097)
			(end 2.54 1.1303)
			(stroke
				(width 0.1524)
				(type default)
			)
			(layer "F.SilkS")
		)
		(fp_line
			(start 0 0.635)
			(end 0 1.905)
			(stroke
				(width 0.1524)
				(type default)
			)
			(layer "F.SilkS")
		)
		(fp_line
			(start 2.54 -1.1303)
			(end 2.54 -1.27)
			(stroke
				(width 0.1524)
				(type default)
			)
			(layer "F.SilkS")
		)
		(fp_line
			(start 0 -1.27)
			(end 0 -0.635)
			(stroke
				(width 0.1524)
				(type default)
			)
			(layer "F.SilkS")
		)
		(fp_line
			(start 2.54 -1.27)
			(end 0 -1.27)
			(stroke
				(width 0.1524)
				(type default)
			)
			(layer "F.SilkS")
		)
		(fp_poly
			(pts
				(xy -2.285746 -0.762) (xy -0.761746 0) (xy -2.285746 0.762)
			)
			(stroke
				(width 0)
				(type default)
			)
			(fill yes)
			(layer "F.SilkS")
		)
		(fp_line
			(start 0 3.81)
			(end 2.54 3.81)
			(stroke
				(width 0.1)
				(type default)
			)
			(layer "F.Fab")
		)
		(fp_line
			(start 2.54 3.81)
			(end 2.54 -1.27)
			(stroke
				(width 0.1)
				(type default)
			)
			(layer "F.Fab")
		)
		(fp_line
			(start 0 -1.27)
			(end 0 3.81)
			(stroke
				(width 0.1)
				(type default)
			)
			(layer "F.Fab")
		)
		(fp_line
			(start 2.54 -1.27)
			(end 0 -1.27)
			(stroke
				(width 0.1)
				(type default)
			)
			(layer "F.Fab")
		)
		(fp_poly
			(pts
				(xy -0.761746 0) (xy -2.285746 -0.762) (xy -2.285746 0.762)
			)
			(stroke
				(width 0)
				(type default)
			)
			(fill yes)
			(layer "F.Fab")
		)
		(pad "1" thru_hole circle
			(at 0 0 270)
			(size 1.0033 1.0033)
			(drill 0.249936)
			(layers "*.Cu" "*.Mask")
			(remove_unused_layers no)
			(net "TDR_DIFF_85_IN1_DP")
			(clearance 0.10795)
			(thermal_gap 0.10795)
			(padstack
				(mode front_inner_back)
				(layer "Inner"
					(shape circle)
					(size 0.8001 0.8001)
					(clearance 0.1524)
				)
				(layer "B.Cu"
					(shape circle)
					(size 1.0033 1.0033)
					(clearance 0.10795)
				)
			)
		)
		(pad "2" thru_hole circle
			(at 2.54 0 270)
			(size 1.9939 1.9939)
			(drill 0.249936)
			(layers "*.Cu" "*.Mask")
			(remove_unused_layers no)
			(net "T1_GND")
			(clearance 0.10795)
			(thermal_gap 0.10795)
			(padstack
				(mode front_inner_back)
				(layer "Inner"
					(shape circle)
					(size 0.8001 0.8001)
					(clearance 0.1524)
				)
				(layer "B.Cu"
					(shape circle)
					(size 1.9939 1.9939)
					(clearance 0.10795)
				)
			)
		)
		(pad "3" thru_hole circle
			(at 2.54 2.54 270)
			(size 1.9939 1.9939)
			(drill 0.249936)
			(layers "*.Cu" "*.Mask")
			(remove_unused_layers no)
			(net "T1_GND")
			(clearance 0.10795)
			(thermal_gap 0.10795)
			(padstack
				(mode front_inner_back)
				(layer "Inner"
					(shape circle)
					(size 0.8001 0.8001)
					(clearance 0.1524)
				)
				(layer "B.Cu"
					(shape circle)
					(size 1.9939 1.9939)
					(clearance 0.10795)
				)
			)
		)
		(pad "4" thru_hole circle
			(at 0 2.54 270)
			(size 1.0033 1.0033)
			(drill 0.249936)
			(layers "*.Cu" "*.Mask")
			(remove_unused_layers no)
			(net "TDR_DIFF_85_IN1_DN")
			(clearance 0.10795)
			(thermal_gap 0.10795)
			(padstack
				(mode front_inner_back)
				(layer "Inner"
					(shape circle)
					(size 0.8001 0.8001)
					(clearance 0.1524)
				)
				(layer "B.Cu"
					(shape circle)
					(size 1.0033 1.0033)
					(clearance 0.10795)
				)
			)
		)
	)
	(footprint ""
		(layer "F.Cu")
		(at 398.012412 -410.175456 90)
		(property "Reference" "C7036"
			(at 0 0 90)
			(layer "F.SilkS")
			(hide yes)
			(effects
				(font
					(size 1.27 1.27)
				)
			)
		)
		(property "Value" ""
			(at 0 0 90)
			(layer "F.Fab")
			(effects
				(font
					(size 1.27 1.27)
				)
			)
		)
		(duplicate_pad_numbers_are_jumpers no)
		(fp_line
			(start 1.524 -0.762)
			(end 1.524 0.762)
			(stroke
				(width 0.1524)
				(type default)
			)
			(layer "F.SilkS")
		)
		(fp_line
			(start -1.524 -0.762)
			(end 1.524 -0.762)
			(stroke
				(width 0.1524)
				(type default)
			)
			(layer "F.SilkS")
		)
		(fp_line
			(start 1.524 0.762)
			(end -1.524 0.762)
			(stroke
				(width 0.1524)
				(type default)
			)
			(layer "F.SilkS")
		)
		(fp_line
			(start -1.524 0.762)
			(end -1.524 -0.762)
			(stroke
				(width 0.1524)
				(type default)
			)
			(layer "F.SilkS")
		)
		(fp_line
			(start 1.1049 -0.724916)
			(end -1.1049 -0.724916)
			(stroke
				(width 0.1)
				(type default)
			)
			(layer "F.Fab")
		)
		(fp_line
			(start -1.1049 -0.724916)
			(end -1.1049 0.724916)
			(stroke
				(width 0.1)
				(type default)
			)
			(layer "F.Fab")
		)
		(fp_line
			(start 1.1049 0.724916)
			(end 1.1049 -0.724916)
			(stroke
				(width 0.1)
				(type default)
			)
			(layer "F.Fab")
		)
		(fp_line
			(start -1.1049 0.724916)
			(end 1.1049 0.724916)
			(stroke
				(width 0.1)
				(type default)
			)
			(layer "F.Fab")
		)
		(pad "1" smd rect
			(at -0.889 0 270)
			(size 1.016 1.27)
			(layers "F.Cu" "F.Mask" "F.Paste")
			(net "P0V9_CPU0_RT_2D")
		)
		(pad "2" smd rect
			(at 0.889 0 270)
			(size 1.016 1.27)
			(layers "F.Cu" "F.Mask" "F.Paste")
			(net "GND")
		)
	)
	(footprint ""
		(layer "F.Cu")
		(at 95.939102 -373.03583 -90)
		(property "Reference" "C719"
			(at 0 0 270)
			(layer "F.SilkS")
			(hide yes)
			(effects
				(font
					(size 1.27 1.27)
				)
			)
		)
		(property "Value" ""
			(at 0 0 270)
			(layer "F.Fab")
			(effects
				(font
					(size 1.27 1.27)
				)
			)
		)
		(duplicate_pad_numbers_are_jumpers no)
		(fp_line
			(start -0.299974 0.150114)
			(end -0.299974 -0.150114)
			(stroke
				(width 0.1)
				(type default)
			)
			(layer "F.Fab")
		)
		(fp_line
			(start 0.299974 0.150114)
			(end -0.299974 0.150114)
			(stroke
				(width 0.1)
				(type default)
			)
			(layer "F.Fab")
		)
		(fp_line
			(start -0.299974 -0.150114)
			(end 0.299974 -0.150114)
			(stroke
				(width 0.1)
				(type default)
			)
			(layer "F.Fab")
		)
		(fp_line
			(start 0.299974 -0.150114)
			(end 0.299974 0.150114)
			(stroke
				(width 0.1)
				(type default)
			)
			(layer "F.Fab")
		)
		(pad "1" smd rect
			(at -0.2667 0 270)
			(size 0.3048 0.381)
			(layers "F.Cu" "F.Mask" "F.Paste")
			(net "P5E_CPU1_P1_TX_C_DP<11>")
		)
		(pad "2" smd rect
			(at 0.2667 0 270)
			(size 0.3048 0.381)
			(layers "F.Cu" "F.Mask" "F.Paste")
			(net "P5E_CPU1_P1_TX_DP<11>")
		)
	)
	(footprint ""
		(layer "F.Cu")
		(at 369.146836 -323.466968 90)
		(property "Reference" "R1205"
			(at 0 0 90)
			(layer "F.SilkS")
			(hide yes)
			(effects
				(font
					(size 1.27 1.27)
				)
			)
		)
		(property "Value" ""
			(at 0 0 90)
			(layer "F.Fab")
			(effects
				(font
					(size 1.27 1.27)
				)
			)
		)
		(duplicate_pad_numbers_are_jumpers no)
		(fp_line
			(start 0.7874 -0.4064)
			(end 0.7874 0.4064)
			(stroke
				(width 0.1524)
				(type default)
			)
			(layer "F.SilkS")
		)
		(fp_line
			(start -0.7874 -0.4064)
			(end 0.7874 -0.4064)
			(stroke
				(width 0.1524)
				(type default)
			)
			(layer "F.SilkS")
		)
		(fp_line
			(start 0.7874 0.4064)
			(end -0.7874 0.4064)
			(stroke
				(width 0.1524)
				(type default)
			)
			(layer "F.SilkS")
		)
		(fp_line
			(start -0.7874 0.4064)
			(end -0.7874 -0.4064)
			(stroke
				(width 0.1524)
				(type default)
			)
			(layer "F.SilkS")
		)
		(fp_line
			(start -0.12065 -0.305054)
			(end -0.12065 -0.2794)
			(stroke
				(width 0.1)
				(type default)
			)
			(layer "F.Fab")
		)
		(fp_line
			(start -0.67945 -0.305054)
			(end -0.12065 -0.305054)
			(stroke
				(width 0.1)
				(type default)
			)
			(layer "F.Fab")
		)
		(fp_line
			(start 0.67945 -0.3048)
			(end 0.67945 0.3048)
			(stroke
				(width 0.1)
				(type default)
			)
			(layer "F.Fab")
		)
		(fp_line
			(start 0.12065 -0.3048)
			(end 0.67945 -0.3048)
			(stroke
				(width 0.1)
				(type default)
			)
			(layer "F.Fab")
		)
		(fp_line
			(start 0.12065 -0.2794)
			(end 0.12065 -0.3048)
			(stroke
				(width 0.1)
				(type default)
			)
			(layer "F.Fab")
		)
		(fp_line
			(start -0.12065 -0.2794)
			(end 0.12065 -0.2794)
			(stroke
				(width 0.1)
				(type default)
			)
			(layer "F.Fab")
		)
		(fp_line
			(start 0.120396 0.2794)
			(end -0.12065 0.2794)
			(stroke
				(width 0.1)
				(type default)
			)
			(layer "F.Fab")
		)
		(fp_line
			(start -0.12065 0.2794)
			(end -0.12065 0.3048)
			(stroke
				(width 0.1)
				(type default)
			)
			(layer "F.Fab")
		)
		(fp_line
			(start 0.67945 0.3048)
			(end 0.120396 0.3048)
			(stroke
				(width 0.1)
				(type default)
			)
			(layer "F.Fab")
		)
		(fp_line
			(start 0.120396 0.3048)
			(end 0.120396 0.2794)
			(stroke
				(width 0.1)
				(type default)
			)
			(layer "F.Fab")
		)
		(fp_line
			(start -0.12065 0.3048)
			(end -0.67945 0.3048)
			(stroke
				(width 0.1)
				(type default)
			)
			(layer "F.Fab")
		)
		(fp_line
			(start -0.67945 0.3048)
			(end -0.67945 -0.305054)
			(stroke
				(width 0.1)
				(type default)
			)
			(layer "F.Fab")
		)
		(pad "1" smd circle
			(at -0.40005 0 90)
			(size 0 0)
			(layers "F.Cu" "F.Mask" "F.Paste")
			(net "FM_PASSWORD_CLEAR_R_N")
		)
		(pad "2" smd circle
			(at 0.40005 0 90)
			(size 0 0)
			(layers "F.Cu" "F.Mask" "F.Paste")
			(net "FM_PASSWORD_CLEAR_N")
		)
	)
	(footprint ""
		(layer "F.Cu")
		(at 449.551806 -424.310556)
		(property "Reference" "PR6605"
			(at 0 0 0)
			(layer "F.SilkS")
			(hide yes)
			(effects
				(font
					(size 1.27 1.27)
				)
			)
		)
		(property "Value" ""
			(at 0 0 0)
			(layer "F.Fab")
			(effects
				(font
					(size 1.27 1.27)
				)
			)
		)
		(duplicate_pad_numbers_are_jumpers no)
		(fp_line
			(start -0.7874 -0.4064)
			(end 0.7874 -0.4064)
			(stroke
				(width 0.1524)
				(type default)
			)
			(layer "F.SilkS")
		)
		(fp_line
			(start -0.7874 0.4064)
			(end -0.7874 -0.4064)
			(stroke
				(width 0.1524)
				(type default)
			)
			(layer "F.SilkS")
		)
		(fp_line
			(start 0.7874 -0.4064)
			(end 0.7874 0.4064)
			(stroke
				(width 0.1524)
				(type default)
			)
			(layer "F.SilkS")
		)
		(fp_line
			(start 0.7874 0.4064)
			(end -0.7874 0.4064)
			(stroke
				(width 0.1524)
				(type default)
			)
			(layer "F.SilkS")
		)
		(fp_line
			(start -0.67945 -0.305054)
			(end -0.12065 -0.305054)
			(stroke
				(width 0.1)
				(type default)
			)
			(layer "F.Fab")
		)
		(fp_line
			(start -0.67945 0.3048)
			(end -0.67945 -0.305054)
			(stroke
				(width 0.1)
				(type default)
			)
			(layer "F.Fab")
		)
		(fp_line
			(start -0.12065 -0.305054)
			(end -0.12065 -0.2794)
			(stroke
				(width 0.1)
				(type default)
			)
			(layer "F.Fab")
		)
		(fp_line
			(start -0.12065 -0.2794)
			(end 0.12065 -0.2794)
			(stroke
				(width 0.1)
				(type default)
			)
			(layer "F.Fab")
		)
		(fp_line
			(start -0.12065 0.2794)
			(end -0.12065 0.3048)
			(stroke
				(width 0.1)
				(type default)
			)
			(layer "F.Fab")
		)
		(fp_line
			(start -0.12065 0.3048)
			(end -0.67945 0.3048)
			(stroke
				(width 0.1)
				(type default)
			)
			(layer "F.Fab")
		)
		(fp_line
			(start 0.120396 0.2794)
			(end -0.12065 0.2794)
			(stroke
				(width 0.1)
				(type default)
			)
			(layer "F.Fab")
		)
		(fp_line
			(start 0.120396 0.3048)
			(end 0.120396 0.2794)
			(stroke
				(width 0.1)
				(type default)
			)
			(layer "F.Fab")
		)
		(fp_line
			(start 0.12065 -0.3048)
			(end 0.67945 -0.3048)
			(stroke
				(width 0.1)
				(type default)
			)
			(layer "F.Fab")
		)
		(fp_line
			(start 0.12065 -0.2794)
			(end 0.12065 -0.3048)
			(stroke
				(width 0.1)
				(type default)
			)
			(layer "F.Fab")
		)
		(fp_line
			(start 0.67945 -0.3048)
			(end 0.67945 0.3048)
			(stroke
				(width 0.1)
				(type default)
			)
			(layer "F.Fab")
		)
		(fp_line
			(start 0.67945 0.3048)
			(end 0.120396 0.3048)
			(stroke
				(width 0.1)
				(type default)
			)
			(layer "F.Fab")
		)
		(pad "1" smd circle
			(at -0.40005 0)
			(size 0 0)
			(layers "F.Cu" "F.Mask" "F.Paste")
			(net "P0V9_RETIMER_CPU0_VMON")
		)
		(pad "2" smd circle
			(at 0.40005 0)
			(size 0 0)
			(layers "F.Cu" "F.Mask" "F.Paste")
			(net "GND")
		)
	)
	(footprint ""
		(layer "F.Cu")
		(at 91.313 -78.105)
		(property "Reference" "R1163"
			(at 0 0 0)
			(layer "F.SilkS")
			(hide yes)
			(effects
				(font
					(size 1.27 1.27)
				)
			)
		)
		(property "Value" ""
			(at 0 0 0)
			(layer "F.Fab")
			(effects
				(font
					(size 1.27 1.27)
				)
			)
		)
		(duplicate_pad_numbers_are_jumpers no)
		(fp_line
			(start -0.7874 -0.4064)
			(end 0.7874 -0.4064)
			(stroke
				(width 0.1524)
				(type default)
			)
			(layer "F.SilkS")
		)
		(fp_line
			(start -0.7874 0.4064)
			(end -0.7874 -0.4064)
			(stroke
				(width 0.1524)
				(type default)
			)
			(layer "F.SilkS")
		)
		(fp_line
			(start 0.7874 -0.4064)
			(end 0.7874 0.4064)
			(stroke
				(width 0.1524)
				(type default)
			)
			(layer "F.SilkS")
		)
		(fp_line
			(start 0.7874 0.4064)
			(end -0.7874 0.4064)
			(stroke
				(width 0.1524)
				(type default)
			)
			(layer "F.SilkS")
		)
		(fp_line
			(start -0.67945 -0.305054)
			(end -0.12065 -0.305054)
			(stroke
				(width 0.1)
				(type default)
			)
			(layer "F.Fab")
		)
		(fp_line
			(start -0.67945 0.3048)
			(end -0.67945 -0.305054)
			(stroke
				(width 0.1)
				(type default)
			)
			(layer "F.Fab")
		)
		(fp_line
			(start -0.12065 -0.305054)
			(end -0.12065 -0.2794)
			(stroke
				(width 0.1)
				(type default)
			)
			(layer "F.Fab")
		)
		(fp_line
			(start -0.12065 -0.2794)
			(end 0.12065 -0.2794)
			(stroke
				(width 0.1)
				(type default)
			)
			(layer "F.Fab")
		)
		(fp_line
			(start -0.12065 0.2794)
			(end -0.12065 0.3048)
			(stroke
				(width 0.1)
				(type default)
			)
			(layer "F.Fab")
		)
		(fp_line
			(start -0.12065 0.3048)
			(end -0.67945 0.3048)
			(stroke
				(width 0.1)
				(type default)
			)
			(layer "F.Fab")
		)
		(fp_line
			(start 0.120396 0.2794)
			(end -0.12065 0.2794)
			(stroke
				(width 0.1)
				(type default)
			)
			(layer "F.Fab")
		)
		(fp_line
			(start 0.120396 0.3048)
			(end 0.120396 0.2794)
			(stroke
				(width 0.1)
				(type default)
			)
			(layer "F.Fab")
		)
		(fp_line
			(start 0.12065 -0.3048)
			(end 0.67945 -0.3048)
			(stroke
				(width 0.1)
				(type default)
			)
			(layer "F.Fab")
		)
		(fp_line
			(start 0.12065 -0.2794)
			(end 0.12065 -0.3048)
			(stroke
				(width 0.1)
				(type default)
			)
			(layer "F.Fab")
		)
		(fp_line
			(start 0.67945 -0.3048)
			(end 0.67945 0.3048)
			(stroke
				(width 0.1)
				(type default)
			)
			(layer "F.Fab")
		)
		(fp_line
			(start 0.67945 0.3048)
			(end 0.120396 0.3048)
			(stroke
				(width 0.1)
				(type default)
			)
			(layer "F.Fab")
		)
		(pad "1" smd circle
			(at -0.40005 0)
			(size 0 0)
			(layers "F.Cu" "F.Mask" "F.Paste")
			(net "HP_LVC3_OCP_V3_2_P12V_PWRGD")
		)
		(pad "2" smd circle
			(at 0.40005 0)
			(size 0 0)
			(layers "F.Cu" "F.Mask" "F.Paste")
			(net "HP_LVC3_OCP_V3_2_P12V_R_PWRGD")
		)
	)
	(footprint ""
		(layer "F.Cu")
		(at 362.025438 -408.915616 180)
		(property "Reference" "R9015"
			(at 0 0 180)
			(layer "F.SilkS")
			(hide yes)
			(effects
				(font
					(size 1.27 1.27)
				)
			)
		)
		(property "Value" ""
			(at 0 0 180)
			(layer "F.Fab")
			(effects
				(font
					(size 1.27 1.27)
				)
			)
		)
		(duplicate_pad_numbers_are_jumpers no)
		(fp_line
			(start 0.7874 0.4064)
			(end -0.7874 0.4064)
			(stroke
				(width 0.1524)
				(type default)
			)
			(layer "F.SilkS")
		)
		(fp_line
			(start 0.7874 -0.4064)
			(end 0.7874 0.4064)
			(stroke
				(width 0.1524)
				(type default)
			)
			(layer "F.SilkS")
		)
		(fp_line
			(start -0.7874 0.4064)
			(end -0.7874 -0.4064)
			(stroke
				(width 0.1524)
				(type default)
			)
			(layer "F.SilkS")
		)
		(fp_line
			(start -0.7874 -0.4064)
			(end 0.7874 -0.4064)
			(stroke
				(width 0.1524)
				(type default)
			)
			(layer "F.SilkS")
		)
		(fp_line
			(start 0.67945 0.3048)
			(end 0.120396 0.3048)
			(stroke
				(width 0.1)
				(type default)
			)
			(layer "F.Fab")
		)
		(fp_line
			(start 0.67945 -0.3048)
			(end 0.67945 0.3048)
			(stroke
				(width 0.1)
				(type default)
			)
			(layer "F.Fab")
		)
		(fp_line
			(start 0.12065 -0.2794)
			(end 0.12065 -0.3048)
			(stroke
				(width 0.1)
				(type default)
			)
			(layer "F.Fab")
		)
		(fp_line
			(start 0.12065 -0.3048)
			(end 0.67945 -0.3048)
			(stroke
				(width 0.1)
				(type default)
			)
			(layer "F.Fab")
		)
		(fp_line
			(start 0.120396 0.3048)
			(end 0.120396 0.2794)
			(stroke
				(width 0.1)
				(type default)
			)
			(layer "F.Fab")
		)
		(fp_line
			(start 0.120396 0.2794)
			(end -0.12065 0.2794)
			(stroke
				(width 0.1)
				(type default)
			)
			(layer "F.Fab")
		)
		(fp_line
			(start -0.12065 0.3048)
			(end -0.67945 0.3048)
			(stroke
				(width 0.1)
				(type default)
			)
			(layer "F.Fab")
		)
		(fp_line
			(start -0.12065 0.2794)
			(end -0.12065 0.3048)
			(stroke
				(width 0.1)
				(type default)
			)
			(layer "F.Fab")
		)
		(fp_line
			(start -0.12065 -0.2794)
			(end 0.12065 -0.2794)
			(stroke
				(width 0.1)
				(type default)
			)
			(layer "F.Fab")
		)
		(fp_line
			(start -0.12065 -0.305054)
			(end -0.12065 -0.2794)
			(stroke
				(width 0.1)
				(type default)
			)
			(layer "F.Fab")
		)
		(fp_line
			(start -0.67945 0.3048)
			(end -0.67945 -0.305054)
			(stroke
				(width 0.1)
				(type default)
			)
			(layer "F.Fab")
		)
		(fp_line
			(start -0.67945 -0.305054)
			(end -0.12065 -0.305054)
			(stroke
				(width 0.1)
				(type default)
			)
			(layer "F.Fab")
		)
		(pad "1" smd circle
			(at -0.40005 0 180)
			(size 0 0)
			(layers "F.Cu" "F.Mask" "F.Paste")
			(net "PRSNT_CABLE_GPU_A3_N")
		)
		(pad "2" smd circle
			(at 0.40005 0 180)
			(size 0 0)
			(layers "F.Cu" "F.Mask" "F.Paste")
			(net "GND")
		)
	)
	(footprint ""
		(layer "F.Cu")
		(at 299.772578 -13.41501 180)
		(property "Reference" "R4188"
			(at 0 0 180)
			(layer "F.SilkS")
			(hide yes)
			(effects
				(font
					(size 1.27 1.27)
				)
			)
		)
		(property "Value" ""
			(at 0 0 180)
			(layer "F.Fab")
			(effects
				(font
					(size 1.27 1.27)
				)
			)
		)
		(duplicate_pad_numbers_are_jumpers no)
		(fp_line
			(start 0.7874 0.4064)
			(end -0.7874 0.4064)
			(stroke
				(width 0.1524)
				(type default)
			)
			(layer "F.SilkS")
		)
		(fp_line
			(start 0.7874 -0.4064)
			(end 0.7874 0.4064)
			(stroke
				(width 0.1524)
				(type default)
			)
			(layer "F.SilkS")
		)
		(fp_line
			(start -0.7874 0.4064)
			(end -0.7874 -0.4064)
			(stroke
				(width 0.1524)
				(type default)
			)
			(layer "F.SilkS")
		)
		(fp_line
			(start -0.7874 -0.4064)
			(end 0.7874 -0.4064)
			(stroke
				(width 0.1524)
				(type default)
			)
			(layer "F.SilkS")
		)
		(fp_line
			(start 0.67945 0.3048)
			(end 0.120396 0.3048)
			(stroke
				(width 0.1)
				(type default)
			)
			(layer "F.Fab")
		)
		(fp_line
			(start 0.67945 -0.3048)
			(end 0.67945 0.3048)
			(stroke
				(width 0.1)
				(type default)
			)
			(layer "F.Fab")
		)
		(fp_line
			(start 0.12065 -0.2794)
			(end 0.12065 -0.3048)
			(stroke
				(width 0.1)
				(type default)
			)
			(layer "F.Fab")
		)
		(fp_line
			(start 0.12065 -0.3048)
			(end 0.67945 -0.3048)
			(stroke
				(width 0.1)
				(type default)
			)
			(layer "F.Fab")
		)
		(fp_line
			(start 0.120396 0.3048)
			(end 0.120396 0.2794)
			(stroke
				(width 0.1)
				(type default)
			)
			(layer "F.Fab")
		)
		(fp_line
			(start 0.120396 0.2794)
			(end -0.12065 0.2794)
			(stroke
				(width 0.1)
				(type default)
			)
			(layer "F.Fab")
		)
		(fp_line
			(start -0.12065 0.3048)
			(end -0.67945 0.3048)
			(stroke
				(width 0.1)
				(type default)
			)
			(layer "F.Fab")
		)
		(fp_line
			(start -0.12065 0.2794)
			(end -0.12065 0.3048)
			(stroke
				(width 0.1)
				(type default)
			)
			(layer "F.Fab")
		)
		(fp_line
			(start -0.12065 -0.2794)
			(end 0.12065 -0.2794)
			(stroke
				(width 0.1)
				(type default)
			)
			(layer "F.Fab")
		)
		(fp_line
			(start -0.12065 -0.305054)
			(end -0.12065 -0.2794)
			(stroke
				(width 0.1)
				(type default)
			)
			(layer "F.Fab")
		)
		(fp_line
			(start -0.67945 0.3048)
			(end -0.67945 -0.305054)
			(stroke
				(width 0.1)
				(type default)
			)
			(layer "F.Fab")
		)
		(fp_line
			(start -0.67945 -0.305054)
			(end -0.12065 -0.305054)
			(stroke
				(width 0.1)
				(type default)
			)
			(layer "F.Fab")
		)
		(pad "1" smd circle
			(at -0.40005 0 180)
			(size 0 0)
			(layers "F.Cu" "F.Mask" "F.Paste")
			(net "P3V3_AUX")
		)
		(pad "2" smd circle
			(at 0.40005 0 180)
			(size 0 0)
			(layers "F.Cu" "F.Mask" "F.Paste")
			(net "U271_1_ADD2")
		)
	)
	(footprint ""
		(layer "F.Cu")
		(at 444.329566 -423.914824 -90)
		(property "Reference" "PU6502"
			(at -6.632956 -0.115824 0)
			(unlocked yes)
			(layer "F.SilkS")
			(effects
				(font
					(size 0.7874 0.5842)
					(thickness 0.1524)
				)
				(justify left)
			)
		)
		(property "Value" ""
			(at 0 0 270)
			(layer "F.Fab")
			(effects
				(font
					(size 1.27 1.27)
				)
			)
		)
		(duplicate_pad_numbers_are_jumpers no)
		(fp_line
			(start 1.778 3.6322)
			(end 1.778 2.8702)
			(stroke
				(width 0.1524)
				(type default)
			)
			(layer "F.SilkS")
		)
		(fp_line
			(start -0.2032 2.8829)
			(end -0.2032 3.2639)
			(stroke
				(width 0.1524)
				(type default)
			)
			(layer "F.SilkS")
		)
		(fp_line
			(start -2.500122 2.500122)
			(end -2.500122 2.018538)
			(stroke
				(width 0.1524)
				(type default)
			)
			(layer "F.SilkS")
		)
		(fp_line
			(start -2.015998 2.500122)
			(end -2.500122 2.500122)
			(stroke
				(width 0.1524)
				(type default)
			)
			(layer "F.SilkS")
		)
		(fp_line
			(start 2.500122 2.500122)
			(end 2.015998 2.500122)
			(stroke
				(width 0.1524)
				(type default)
			)
			(layer "F.SilkS")
		)
		(fp_line
			(start 2.500122 2.015998)
			(end 2.500122 2.500122)
			(stroke
				(width 0.1524)
				(type default)
			)
			(layer "F.SilkS")
		)
		(fp_line
			(start -3.6576 1.8034)
			(end -2.8956 1.8034)
			(stroke
				(width 0.1524)
				(type default)
			)
			(layer "F.SilkS")
		)
		(fp_line
			(start 2.8829 0.2032)
			(end 3.2639 0.2032)
			(stroke
				(width 0.1524)
				(type default)
			)
			(layer "F.SilkS")
		)
		(fp_line
			(start -3.2639 -0.1778)
			(end -2.8829 -0.1778)
			(stroke
				(width 0.1524)
				(type default)
			)
			(layer "F.SilkS")
		)
		(fp_line
			(start 2.8702 -1.778)
			(end 3.6322 -1.778)
			(stroke
				(width 0.1524)
				(type default)
			)
			(layer "F.SilkS")
		)
		(fp_line
			(start -2.500122 -2.015998)
			(end -2.500122 -2.500122)
			(stroke
				(width 0.1524)
				(type default)
			)
			(layer "F.SilkS")
		)
		(fp_line
			(start -2.500122 -2.500122)
			(end -2.015998 -2.500122)
			(stroke
				(width 0.1524)
				(type default)
			)
			(layer "F.SilkS")
		)
		(fp_line
			(start 2.015998 -2.500122)
			(end 2.500122 -2.500122)
			(stroke
				(width 0.1524)
				(type default)
			)
			(layer "F.SilkS")
		)
		(fp_line
			(start 2.500122 -2.500122)
			(end 2.500122 -2.015998)
			(stroke
				(width 0.1524)
				(type default)
			)
			(layer "F.SilkS")
		)
		(fp_line
			(start -1.8034 -2.8702)
			(end -1.8034 -3.6322)
			(stroke
				(width 0.1524)
				(type default)
			)
			(layer "F.SilkS")
		)
		(fp_line
			(start 0.1778 -3.2385)
			(end 0.1778 -2.8575)
			(stroke
				(width 0.1524)
				(type default)
			)
			(layer "F.SilkS")
		)
		(fp_poly
			(pts
				(xy -2.921 -1.800098) (xy -3.504184 -1.508506) (xy -3.504184 -2.09169)
			)
			(stroke
				(width 0)
				(type default)
			)
			(fill yes)
			(layer "F.SilkS")
		)
		(fp_line
			(start 1.778 3.6322)
			(end 1.778 2.8702)
			(stroke
				(width 0.1)
				(type default)
			)
			(layer "F.Fab")
		)
		(fp_line
			(start -0.2032 2.8829)
			(end -0.2032 3.2639)
			(stroke
				(width 0.1)
				(type default)
			)
			(layer "F.Fab")
		)
		(fp_line
			(start -2.500122 2.500122)
			(end -2.500122 -2.500122)
			(stroke
				(width 0.1)
				(type default)
			)
			(layer "F.Fab")
		)
		(fp_line
			(start 2.500122 2.500122)
			(end -2.500122 2.500122)
			(stroke
				(width 0.1)
				(type default)
			)
			(layer "F.Fab")
		)
		(fp_line
			(start -3.6576 1.8034)
			(end -2.8956 1.8034)
			(stroke
				(width 0.1)
				(type default)
			)
			(layer "F.Fab")
		)
		(fp_line
			(start 2.8829 0.2032)
			(end 3.2639 0.2032)
			(stroke
				(width 0.1)
				(type default)
			)
			(layer "F.Fab")
		)
		(fp_line
			(start -3.2639 -0.1778)
			(end -2.8829 -0.1778)
			(stroke
				(width 0.1)
				(type default)
			)
			(layer "F.Fab")
		)
		(fp_line
			(start 2.8702 -1.778)
			(end 3.6322 -1.778)
			(stroke
				(width 0.1)
				(type default)
			)
			(layer "F.Fab")
		)
		(fp_line
			(start -2.500122 -2.500122)
			(end 2.500122 -2.500122)
			(stroke
				(width 0.1)
				(type default)
			)
			(layer "F.Fab")
		)
		(fp_line
			(start 2.500122 -2.500122)
			(end 2.500122 2.500122)
			(stroke
				(width 0.1)
				(type default)
			)
			(layer "F.Fab")
		)
		(fp_line
			(start -1.8034 -2.8702)
			(end -1.8034 -3.6322)
			(stroke
				(width 0.1)
				(type default)
			)
			(layer "F.Fab")
		)
		(fp_line
			(start 0.1778 -3.2385)
			(end 0.1778 -2.8575)
			(stroke
				(width 0.1)
				(type default)
			)
			(layer "F.Fab")
		)
		(fp_poly
			(pts
				(xy -2.921 -1.800098) (xy -3.504184 -1.508506) (xy -3.504184 -2.09169)
			)
			(stroke
				(width 0)
				(type default)
			)
			(fill yes)
			(layer "F.Fab")
		)
		(fp_text user "20"
			(at 1.840484 4.009898 270)
			(unlocked yes)
			(layer "F.SilkS")
			(effects
				(font
					(size 0.635 0.4064)
					(thickness 0.1524)
				)
				(justify left)
			)
		)
		(fp_text user "11"
			(at -3.331972 3.750056 270)
			(unlocked yes)
			(layer "F.SilkS")
			(effects
				(font
					(size 0.635 0.4064)
					(thickness 0.1524)
				)
				(justify left)
			)
		)
		(fp_text user "10"
			(at -2.990342 2.17678 180)
			(unlocked yes)
			(layer "F.SilkS")
			(effects
				(font
					(size 0.635 0.4064)
					(thickness 0.1524)
				)
				(justify left)
			)
		)
		(fp_text user "21"
			(at 2.97053 2.045716 180)
			(unlocked yes)
			(layer "F.SilkS")
			(effects
				(font
					(size 0.635 0.4064)
					(thickness 0.1524)
				)
				(justify left)
			)
		)
		(fp_text user "40"
			(at -3.61569 -2.603754 270)
			(unlocked yes)
			(layer "F.SilkS")
			(effects
				(font
					(size 0.635 0.4064)
					(thickness 0.1524)
				)
				(justify left)
			)
		)
		(fp_text user "30"
			(at 3.223768 -3.0988 180)
			(unlocked yes)
			(layer "F.SilkS")
			(effects
				(font
					(size 0.635 0.4064)
					(thickness 0.1524)
				)
				(justify left)
			)
		)
		(fp_text user "31"
			(at 1.42494 -3.682746 270)
			(unlocked yes)
			(layer "F.SilkS")
			(effects
				(font
					(size 0.635 0.4064)
					(thickness 0.1524)
				)
				(justify left)
			)
		)
		(fp_text user "11"
			(at -2.8702 3.278632 270)
			(unlocked yes)
			(layer "F.Fab")
			(effects
				(font
					(size 0.635 0.4064)
					(thickness 0.1524)
				)
				(justify left)
			)
		)
		(fp_text user "20"
			(at 2.0828 3.253232 270)
			(unlocked yes)
			(layer "F.Fab")
			(effects
				(font
					(size 0.635 0.4064)
					(thickness 0.1524)
				)
				(justify left)
			)
		)
		(fp_text user "10"
			(at -3.253232 2.1336 180)
			(unlocked yes)
			(layer "F.Fab")
			(effects
				(font
					(size 0.635 0.4064)
					(thickness 0.1524)
				)
				(justify left)
			)
		)
		(fp_text user "21"
			(at 3.274568 1.8796 180)
			(unlocked yes)
			(layer "F.Fab")
			(effects
				(font
					(size 0.635 0.4064)
					(thickness 0.1524)
				)
				(justify left)
			)
		)
		(fp_text user "40"
			(at -3.2004 -3.096768 270)
			(unlocked yes)
			(layer "F.Fab")
			(effects
				(font
					(size 0.635 0.4064)
					(thickness 0.1524)
				)
				(justify left)
			)
		)
		(fp_text user "30"
			(at 3.223768 -3.0988 180)
			(unlocked yes)
			(layer "F.Fab")
			(effects
				(font
					(size 0.635 0.4064)
					(thickness 0.1524)
				)
				(justify left)
			)
		)
		(fp_text user "31"
			(at 1.8542 -3.172968 270)
			(unlocked yes)
			(layer "F.Fab")
			(effects
				(font
					(size 0.635 0.4064)
					(thickness 0.1524)
				)
				(justify left)
			)
		)
		(pad "1" smd rect
			(at -2.400046 -1.800098 180)
			(size 0.1778 0.6096)
			(layers "F.Cu" "F.Mask" "F.Paste")
			(net "NC_P0V9_RETIMER_CPU0_PWM8")
		)
		(pad "2" smd rect
			(at -2.400046 -1.400048 180)
			(size 0.1778 0.6096)
			(layers "F.Cu" "F.Mask" "F.Paste")
			(net "NC_P0V9_RETIMER_CPU0_PWM7")
		)
		(pad "3" smd rect
			(at -2.400046 -0.999998 180)
			(size 0.1778 0.6096)
			(layers "F.Cu" "F.Mask" "F.Paste")
			(net "NC_P0V9_RETIMER_CPU0_PWM6")
		)
		(pad "4" smd rect
			(at -2.400046 -0.599948 180)
			(size 0.1778 0.6096)
			(layers "F.Cu" "F.Mask" "F.Paste")
			(net "NC_P0V9_RETIMER_CPU0_PWM5")
		)
		(pad "5" smd rect
			(at -2.400046 -0.199898 180)
			(size 0.1778 0.6096)
			(layers "F.Cu" "F.Mask" "F.Paste")
			(net "NC_P0V9_RETIMER_CPU0_PWM4")
		)
		(pad "6" smd rect
			(at -2.400046 0.199898 180)
			(size 0.1778 0.6096)
			(layers "F.Cu" "F.Mask" "F.Paste")
			(net "NC_P0V9_RETIMER_CPU0_PWM3")
		)
		(pad "7" smd rect
			(at -2.400046 0.599948 180)
			(size 0.1778 0.6096)
			(layers "F.Cu" "F.Mask" "F.Paste")
			(net "P0V9_RETIMER_CPU0_PWM2")
		)
		(pad "8" smd rect
			(at -2.400046 0.999998 180)
			(size 0.1778 0.6096)
			(layers "F.Cu" "F.Mask" "F.Paste")
			(net "P0V9_RETIMER_CPU0_PWM1")
		)
		(pad "9" smd rect
			(at -2.400046 1.400048 180)
			(size 0.1778 0.6096)
			(layers "F.Cu" "F.Mask" "F.Paste")
			(net "P0V9_RETIMER_CPU0_PMSDA_R")
		)
		(pad "10" smd rect
			(at -2.400046 1.800098 180)
			(size 0.1778 0.6096)
			(layers "F.Cu" "F.Mask" "F.Paste")
			(net "P0V9_RETIMER_CPU0_PMSCL_R")
		)
		(pad "11" smd rect
			(at -1.800098 2.400046 270)
			(size 0.1778 0.6096)
			(layers "F.Cu" "F.Mask" "F.Paste")
			(net "TP_P0V9_RETIMER_CPU0_PMALERT")
		)
		(pad "12" smd rect
			(at -1.400048 2.400046 270)
			(size 0.1778 0.6096)
			(layers "F.Cu" "F.Mask" "F.Paste")
			(net "PWRGD_P0V9_RETIMER_CPU0_R")
		)
		(pad "13" smd rect
			(at -0.999998 2.400046 270)
			(size 0.1778 0.6096)
			(layers "F.Cu" "F.Mask" "F.Paste")
			(net "P0V9_RETIMER_CPU0_EN0_R")
		)
		(pad "14" smd rect
			(at -0.599948 2.400046 270)
			(size 0.1778 0.6096)
			(layers "F.Cu" "F.Mask" "F.Paste")
			(net "P0V9_RETIMER_CPU0_VRHOT")
		)
		(pad "15" smd rect
			(at -0.199898 2.400046 270)
			(size 0.1778 0.6096)
			(layers "F.Cu" "F.Mask" "F.Paste")
			(net "P0V9_RETIMER_CPU0_INALERT")
		)
		(pad "16" smd rect
			(at 0.199898 2.400046 270)
			(size 0.1778 0.6096)
			(layers "F.Cu" "F.Mask" "F.Paste")
			(net "NC_P0V9_RETIMER_CPU0_PG1")
		)
		(pad "17" smd rect
			(at 0.599948 2.400046 270)
			(size 0.1778 0.6096)
			(layers "F.Cu" "F.Mask" "F.Paste")
			(net "P0V9_RETIMER_CPU0_SVID_CLK")
		)
		(pad "18" smd rect
			(at 0.999998 2.400046 270)
			(size 0.1778 0.6096)
			(layers "F.Cu" "F.Mask" "F.Paste")
			(net "P0V9_RETIMER_CPU0_SVID_SDA")
		)
		(pad "19" smd rect
			(at 1.400048 2.400046 270)
			(size 0.1778 0.6096)
			(layers "F.Cu" "F.Mask" "F.Paste")
			(net "TP_P0V9_RETIMER_CPU0_SVID_ALERT_N")
		)
		(pad "20" smd rect
			(at 1.800098 2.400046 270)
			(size 0.1778 0.6096)
			(layers "F.Cu" "F.Mask" "F.Paste")
			(net "P0V9_RETIMER_CPU0_EN1_R")
		)
		(pad "21" smd rect
			(at 2.400046 1.800098 180)
			(size 0.1778 0.6096)
			(layers "F.Cu" "F.Mask" "F.Paste")
			(net "P0V9_RETIMER_CPU0_SENSE_R_P")
		)
		(pad "22" smd rect
			(at 2.400046 1.400048 180)
			(size 0.1778 0.6096)
			(layers "F.Cu" "F.Mask" "F.Paste")
			(net "P0V9_RETIMER_CPU0_SENSE_SH_N")
		)
		(pad "23" smd rect
			(at 2.400046 0.999998 180)
			(size 0.1778 0.6096)
			(layers "F.Cu" "F.Mask" "F.Paste")
			(net "P0V9_RETIMER_CPU0_IMON1")
		)
		(pad "24" smd rect
			(at 2.400046 0.599948 180)
			(size 0.1778 0.6096)
			(layers "F.Cu" "F.Mask" "F.Paste")
			(net "P0V9_RETIMER_CPU0_IMON2")
		)
		(pad "25" smd rect
			(at 2.400046 0.199898 180)
			(size 0.1778 0.6096)
			(layers "F.Cu" "F.Mask" "F.Paste")
			(net "NC_P0V9_RETIMER_CPU0_IMON3")
		)
		(pad "26" smd rect
			(at 2.400046 -0.199898 180)
			(size 0.1778 0.6096)
			(layers "F.Cu" "F.Mask" "F.Paste")
			(net "NC_P0V9_RETIMER_CPU0_IMON4")
		)
		(pad "27" smd rect
			(at 2.400046 -0.599948 180)
			(size 0.1778 0.6096)
			(layers "F.Cu" "F.Mask" "F.Paste")
			(net "NC_P0V9_RETIMER_CPU0_IMON5")
		)
		(pad "28" smd rect
			(at 2.400046 -0.999998 180)
			(size 0.1778 0.6096)
			(layers "F.Cu" "F.Mask" "F.Paste")
			(net "NC_P0V9_RETIMER_CPU0_IMON6")
		)
		(pad "29" smd rect
			(at 2.400046 -1.400048 180)
			(size 0.1778 0.6096)
			(layers "F.Cu" "F.Mask" "F.Paste")
			(net "NC_P0V9_RETIMER_CPU0_IMON7")
		)
		(pad "30" smd rect
			(at 2.400046 -1.800098 180)
			(size 0.1778 0.6096)
			(layers "F.Cu" "F.Mask" "F.Paste")
			(net "NC_P0V9_RETIMER_CPU0_IMON8")
		)
		(pad "31" smd rect
			(at 1.800098 -2.400046 270)
			(size 0.1778 0.6096)
			(layers "F.Cu" "F.Mask" "F.Paste")
			(net "GND")
		)
		(pad "32" smd rect
			(at 1.400048 -2.400046 270)
			(size 0.1778 0.6096)
			(layers "F.Cu" "F.Mask" "F.Paste")
			(net "GND")
		)
		(pad "33" smd rect
			(at 0.999998 -2.400046 270)
			(size 0.1778 0.6096)
			(layers "F.Cu" "F.Mask" "F.Paste")
			(net "P0V9_RETIMER_CPU0_CFP")
		)
		(pad "34" smd rect
			(at 0.599948 -2.400046 270)
			(size 0.1778 0.6096)
			(layers "F.Cu" "F.Mask" "F.Paste")
			(net "P0V9_RETIMER_CPU0_ADDR")
		)
		(pad "35" smd rect
			(at 0.199898 -2.400046 270)
			(size 0.1778 0.6096)
			(layers "F.Cu" "F.Mask" "F.Paste")
			(net "P0V9_RETIMER_CPU0_TEMP0")
		)
		(pad "36" smd rect
			(at -0.199898 -2.400046 270)
			(size 0.1778 0.6096)
			(layers "F.Cu" "F.Mask" "F.Paste")
			(net "P0V9_RETIMER_CPU0_TEMP1_R")
		)
		(pad "37" smd rect
			(at -0.599948 -2.400046 270)
			(size 0.1778 0.6096)
			(layers "F.Cu" "F.Mask" "F.Paste")
			(net "P0V9_RETIMER_CPU0_VMON")
		)
		(pad "38" smd rect
			(at -0.999998 -2.400046 270)
			(size 0.1778 0.6096)
			(layers "F.Cu" "F.Mask" "F.Paste")
			(net "P0V9_RETIMER_CPU0_VINSEN")
		)
		(pad "39" smd rect
			(at -1.400048 -2.400046 270)
			(size 0.1778 0.6096)
			(layers "F.Cu" "F.Mask" "F.Paste")
			(net "P0V9_RETIMER_CPU0_VCC")
		)
		(pad "40" smd rect
			(at -1.800098 -2.400046 270)
			(size 0.1778 0.6096)
			(layers "F.Cu" "F.Mask" "F.Paste")
			(net "PV09_RETIMER_CPU0_VCCS")
		)
		(pad "TH" smd rect
			(at 0 0 270)
			(size 3.6576 3.6576)
			(layers "F.Cu" "F.Mask" "F.Paste")
			(net "GND")
		)
		(zone
			(layer "F.Cu")
			(hatch none 0.5)
			(connect_pads
				(clearance 0)
			)
			(min_thickness 0.25)
			(keepout
				(tracks not_allowed)
				(vias allowed)
				(pads allowed)
				(copperpour not_allowed)
				(footprints allowed)
			)
			(placement
				(enabled no)
				(sheetname "")
			)
			(fill
				(thermal_gap 0.5)
				(thermal_bridge_width 0.5)
				(island_removal_mode 0)
			)
			(polygon
				(pts
					(xy 446.361566 -425.946824) (xy 446.361566 -421.882824) (xy 442.297566 -421.882824) (xy 442.297566 -425.946824)
					(xy 446.183766 -425.946824) (xy 446.183766 -425.794424) (xy 442.449966 -425.794424) (xy 442.449966 -422.035224)
					(xy 446.209166 -422.035224) (xy 446.209166 -425.946824)
				)
			)
		)
	)
	(footprint ""
		(layer "F.Cu")
		(at 42.989754 -373.03583 -90)
		(property "Reference" "C833"
			(at 0 0 270)
			(layer "F.SilkS")
			(hide yes)
			(effects
				(font
					(size 1.27 1.27)
				)
			)
		)
		(property "Value" ""
			(at 0 0 270)
			(layer "F.Fab")
			(effects
				(font
					(size 1.27 1.27)
				)
			)
		)
		(duplicate_pad_numbers_are_jumpers no)
		(fp_line
			(start -0.299974 0.150114)
			(end -0.299974 -0.150114)
			(stroke
				(width 0.1)
				(type default)
			)
			(layer "F.Fab")
		)
		(fp_line
			(start 0.299974 0.150114)
			(end -0.299974 0.150114)
			(stroke
				(width 0.1)
				(type default)
			)
			(layer "F.Fab")
		)
		(fp_line
			(start -0.299974 -0.150114)
			(end 0.299974 -0.150114)
			(stroke
				(width 0.1)
				(type default)
			)
			(layer "F.Fab")
		)
		(fp_line
			(start 0.299974 -0.150114)
			(end 0.299974 0.150114)
			(stroke
				(width 0.1)
				(type default)
			)
			(layer "F.Fab")
		)
		(pad "1" smd rect
			(at -0.2667 0 270)
			(size 0.3048 0.381)
			(layers "F.Cu" "F.Mask" "F.Paste")
			(net "P5E_CPU1_P0_TX_C_DP<2>")
		)
		(pad "2" smd rect
			(at 0.2667 0 270)
			(size 0.3048 0.381)
			(layers "F.Cu" "F.Mask" "F.Paste")
			(net "P5E_CPU1_P0_TX_DP<2>")
		)
	)
	(footprint ""
		(layer "F.Cu")
		(at 239.152684 -57.41289)
		(property "Reference" "C1990"
			(at 0 0 0)
			(layer "F.SilkS")
			(hide yes)
			(effects
				(font
					(size 1.27 1.27)
				)
			)
		)
		(property "Value" ""
			(at 0 0 0)
			(layer "F.Fab")
			(effects
				(font
					(size 1.27 1.27)
				)
			)
		)
		(duplicate_pad_numbers_are_jumpers no)
		(fp_line
			(start -0.299974 -0.150114)
			(end 0.299974 -0.150114)
			(stroke
				(width 0.1)
				(type default)
			)
			(layer "F.Fab")
		)
		(fp_line
			(start -0.299974 0.150114)
			(end -0.299974 -0.150114)
			(stroke
				(width 0.1)
				(type default)
			)
			(layer "F.Fab")
		)
		(fp_line
			(start 0.299974 -0.150114)
			(end 0.299974 0.150114)
			(stroke
				(width 0.1)
				(type default)
			)
			(layer "F.Fab")
		)
		(fp_line
			(start 0.299974 0.150114)
			(end -0.299974 0.150114)
			(stroke
				(width 0.1)
				(type default)
			)
			(layer "F.Fab")
		)
		(pad "1" smd rect
			(at -0.2667 0)
			(size 0.3048 0.381)
			(layers "F.Cu" "F.Mask" "F.Paste")
			(net "P3E_CPU0_P4_TX_C_DN<3>")
		)
		(pad "2" smd rect
			(at 0.2667 0)
			(size 0.3048 0.381)
			(layers "F.Cu" "F.Mask" "F.Paste")
			(net "P3E_CPU0_P4_TX_DN<3>")
		)
	)
	(footprint ""
		(layer "F.Cu")
		(at 455.01306 -41.105836 180)
		(property "Reference" "R4069"
			(at 0 0 180)
			(layer "F.SilkS")
			(hide yes)
			(effects
				(font
					(size 1.27 1.27)
				)
			)
		)
		(property "Value" ""
			(at 0 0 180)
			(layer "F.Fab")
			(effects
				(font
					(size 1.27 1.27)
				)
			)
		)
		(duplicate_pad_numbers_are_jumpers no)
		(fp_line
			(start 0.7874 0.4064)
			(end -0.7874 0.4064)
			(stroke
				(width 0.1524)
				(type default)
			)
			(layer "F.SilkS")
		)
		(fp_line
			(start 0.7874 -0.4064)
			(end 0.7874 0.4064)
			(stroke
				(width 0.1524)
				(type default)
			)
			(layer "F.SilkS")
		)
		(fp_line
			(start -0.7874 0.4064)
			(end -0.7874 -0.4064)
			(stroke
				(width 0.1524)
				(type default)
			)
			(layer "F.SilkS")
		)
		(fp_line
			(start -0.7874 -0.4064)
			(end 0.7874 -0.4064)
			(stroke
				(width 0.1524)
				(type default)
			)
			(layer "F.SilkS")
		)
		(fp_line
			(start 0.67945 0.3048)
			(end 0.120396 0.3048)
			(stroke
				(width 0.1)
				(type default)
			)
			(layer "F.Fab")
		)
		(fp_line
			(start 0.67945 -0.3048)
			(end 0.67945 0.3048)
			(stroke
				(width 0.1)
				(type default)
			)
			(layer "F.Fab")
		)
		(fp_line
			(start 0.12065 -0.2794)
			(end 0.12065 -0.3048)
			(stroke
				(width 0.1)
				(type default)
			)
			(layer "F.Fab")
		)
		(fp_line
			(start 0.12065 -0.3048)
			(end 0.67945 -0.3048)
			(stroke
				(width 0.1)
				(type default)
			)
			(layer "F.Fab")
		)
		(fp_line
			(start 0.120396 0.3048)
			(end 0.120396 0.2794)
			(stroke
				(width 0.1)
				(type default)
			)
			(layer "F.Fab")
		)
		(fp_line
			(start 0.120396 0.2794)
			(end -0.12065 0.2794)
			(stroke
				(width 0.1)
				(type default)
			)
			(layer "F.Fab")
		)
		(fp_line
			(start -0.12065 0.3048)
			(end -0.67945 0.3048)
			(stroke
				(width 0.1)
				(type default)
			)
			(layer "F.Fab")
		)
		(fp_line
			(start -0.12065 0.2794)
			(end -0.12065 0.3048)
			(stroke
				(width 0.1)
				(type default)
			)
			(layer "F.Fab")
		)
		(fp_line
			(start -0.12065 -0.2794)
			(end 0.12065 -0.2794)
			(stroke
				(width 0.1)
				(type default)
			)
			(layer "F.Fab")
		)
		(fp_line
			(start -0.12065 -0.305054)
			(end -0.12065 -0.2794)
			(stroke
				(width 0.1)
				(type default)
			)
			(layer "F.Fab")
		)
		(fp_line
			(start -0.67945 0.3048)
			(end -0.67945 -0.305054)
			(stroke
				(width 0.1)
				(type default)
			)
			(layer "F.Fab")
		)
		(fp_line
			(start -0.67945 -0.305054)
			(end -0.12065 -0.305054)
			(stroke
				(width 0.1)
				(type default)
			)
			(layer "F.Fab")
		)
		(pad "1" smd circle
			(at -0.40005 0 180)
			(size 0 0)
			(layers "F.Cu" "F.Mask" "F.Paste")
			(net "P3V3_OCP_EN_1_R")
		)
		(pad "2" smd circle
			(at 0.40005 0 180)
			(size 0 0)
			(layers "F.Cu" "F.Mask" "F.Paste")
			(net "GND")
		)
	)
	(footprint ""
		(layer "F.Cu")
		(at 447.44005 -40.420036)
		(property "Reference" "H6000"
			(at -2.5146 -3.58013 0)
			(unlocked yes)
			(layer "F.SilkS")
			(effects
				(font
					(size 0.7874 0.5842)
					(thickness 0.1524)
				)
				(justify left)
			)
		)
		(property "Value" ""
			(at 0 0 0)
			(layer "F.Fab")
			(effects
				(font
					(size 1.27 1.27)
				)
			)
		)
		(duplicate_pad_numbers_are_jumpers no)
		(pad "1" thru_hole circle
			(at 0 0)
			(size 6.1976 6.1976)
			(drill 3.7338)
			(layers "*.Cu" "*.Mask")
			(remove_unused_layers no)
			(net "GND")
			(clearance -0.9779)
			(padstack
				(mode front_inner_back)
				(layer "Inner"
					(shape circle)
					(size 5.5372 5.5372)
					(clearance -0.6477)
				)
				(layer "B.Cu"
					(shape circle)
					(size 6.1976 6.1976)
					(clearance -0.9779)
				)
			)
		)
	)
	(footprint ""
		(layer "F.Cu")
		(at 189.103 -129.377948 90)
		(property "Reference" "R258"
			(at 0 0 90)
			(layer "F.SilkS")
			(hide yes)
			(effects
				(font
					(size 1.27 1.27)
				)
			)
		)
		(property "Value" ""
			(at 0 0 90)
			(layer "F.Fab")
			(effects
				(font
					(size 1.27 1.27)
				)
			)
		)
		(duplicate_pad_numbers_are_jumpers no)
		(fp_line
			(start 0.7874 -0.4064)
			(end 0.7874 0.4064)
			(stroke
				(width 0.1524)
				(type default)
			)
			(layer "F.SilkS")
		)
		(fp_line
			(start -0.7874 -0.4064)
			(end 0.7874 -0.4064)
			(stroke
				(width 0.1524)
				(type default)
			)
			(layer "F.SilkS")
		)
		(fp_line
			(start 0.7874 0.4064)
			(end -0.7874 0.4064)
			(stroke
				(width 0.1524)
				(type default)
			)
			(layer "F.SilkS")
		)
		(fp_line
			(start -0.7874 0.4064)
			(end -0.7874 -0.4064)
			(stroke
				(width 0.1524)
				(type default)
			)
			(layer "F.SilkS")
		)
		(fp_line
			(start -0.12065 -0.305054)
			(end -0.12065 -0.2794)
			(stroke
				(width 0.1)
				(type default)
			)
			(layer "F.Fab")
		)
		(fp_line
			(start -0.67945 -0.305054)
			(end -0.12065 -0.305054)
			(stroke
				(width 0.1)
				(type default)
			)
			(layer "F.Fab")
		)
		(fp_line
			(start 0.67945 -0.3048)
			(end 0.67945 0.3048)
			(stroke
				(width 0.1)
				(type default)
			)
			(layer "F.Fab")
		)
		(fp_line
			(start 0.12065 -0.3048)
			(end 0.67945 -0.3048)
			(stroke
				(width 0.1)
				(type default)
			)
			(layer "F.Fab")
		)
		(fp_line
			(start 0.12065 -0.2794)
			(end 0.12065 -0.3048)
			(stroke
				(width 0.1)
				(type default)
			)
			(layer "F.Fab")
		)
		(fp_line
			(start -0.12065 -0.2794)
			(end 0.12065 -0.2794)
			(stroke
				(width 0.1)
				(type default)
			)
			(layer "F.Fab")
		)
		(fp_line
			(start 0.120396 0.2794)
			(end -0.12065 0.2794)
			(stroke
				(width 0.1)
				(type default)
			)
			(layer "F.Fab")
		)
		(fp_line
			(start -0.12065 0.2794)
			(end -0.12065 0.3048)
			(stroke
				(width 0.1)
				(type default)
			)
			(layer "F.Fab")
		)
		(fp_line
			(start 0.67945 0.3048)
			(end 0.120396 0.3048)
			(stroke
				(width 0.1)
				(type default)
			)
			(layer "F.Fab")
		)
		(fp_line
			(start 0.120396 0.3048)
			(end 0.120396 0.2794)
			(stroke
				(width 0.1)
				(type default)
			)
			(layer "F.Fab")
		)
		(fp_line
			(start -0.12065 0.3048)
			(end -0.67945 0.3048)
			(stroke
				(width 0.1)
				(type default)
			)
			(layer "F.Fab")
		)
		(fp_line
			(start -0.67945 0.3048)
			(end -0.67945 -0.305054)
			(stroke
				(width 0.1)
				(type default)
			)
			(layer "F.Fab")
		)
		(pad "1" smd circle
			(at -0.40005 0 90)
			(size 0 0)
			(layers "F.Cu" "F.Mask" "F.Paste")
			(net "FM_CPU0_HDT_CONN_TESTEN")
		)
		(pad "2" smd circle
			(at 0.40005 0 90)
			(size 0 0)
			(layers "F.Cu" "F.Mask" "F.Paste")
			(net "CPU0_HDT_CONN_TESTEN")
		)
	)
	(footprint ""
		(layer "F.Cu")
		(at 460.292196 -47.929546 -90)
		(property "Reference" "PC8008"
			(at 0 0 270)
			(layer "F.SilkS")
			(hide yes)
			(effects
				(font
					(size 1.27 1.27)
				)
			)
		)
		(property "Value" ""
			(at 0 0 270)
			(layer "F.Fab")
			(effects
				(font
					(size 1.27 1.27)
				)
			)
		)
		(duplicate_pad_numbers_are_jumpers no)
		(fp_line
			(start -1.2954 0.5842)
			(end -1.2954 -0.5842)
			(stroke
				(width 0.1524)
				(type default)
			)
			(layer "F.SilkS")
		)
		(fp_line
			(start 1.2954 0.5842)
			(end -1.2954 0.5842)
			(stroke
				(width 0.1524)
				(type default)
			)
			(layer "F.SilkS")
		)
		(fp_line
			(start -1.2954 -0.5842)
			(end 1.2954 -0.5842)
			(stroke
				(width 0.1524)
				(type default)
			)
			(layer "F.SilkS")
		)
		(fp_line
			(start 1.2954 -0.5842)
			(end 1.2954 0.5842)
			(stroke
				(width 0.1524)
				(type default)
			)
			(layer "F.SilkS")
		)
		(fp_line
			(start -0.8636 0.4572)
			(end -0.8636 0.4064)
			(stroke
				(width 0.1)
				(type default)
			)
			(layer "F.Fab")
		)
		(fp_line
			(start 0.8636 0.4572)
			(end -0.8636 0.4572)
			(stroke
				(width 0.1)
				(type default)
			)
			(layer "F.Fab")
		)
		(fp_line
			(start -1.1938 0.4064)
			(end -1.1938 -0.4064)
			(stroke
				(width 0.1)
				(type default)
			)
			(layer "F.Fab")
		)
		(fp_line
			(start -0.8636 0.4064)
			(end -1.1938 0.4064)
			(stroke
				(width 0.1)
				(type default)
			)
			(layer "F.Fab")
		)
		(fp_line
			(start 0.8636 0.4064)
			(end 0.8636 0.4572)
			(stroke
				(width 0.1)
				(type default)
			)
			(layer "F.Fab")
		)
		(fp_line
			(start 1.1938 0.4064)
			(end 0.8636 0.4064)
			(stroke
				(width 0.1)
				(type default)
			)
			(layer "F.Fab")
		)
		(fp_line
			(start -1.1938 -0.4064)
			(end -0.8636 -0.4064)
			(stroke
				(width 0.1)
				(type default)
			)
			(layer "F.Fab")
		)
		(fp_line
			(start -0.8636 -0.4064)
			(end -0.8636 -0.4572)
			(stroke
				(width 0.1)
				(type default)
			)
			(layer "F.Fab")
		)
		(fp_line
			(start 0.8636 -0.4064)
			(end 1.1938 -0.4064)
			(stroke
				(width 0.1)
				(type default)
			)
			(layer "F.Fab")
		)
		(fp_line
			(start 1.1938 -0.4064)
			(end 1.1938 0.4064)
			(stroke
				(width 0.1)
				(type default)
			)
			(layer "F.Fab")
		)
		(fp_line
			(start -0.8636 -0.4572)
			(end 0.8636 -0.4572)
			(stroke
				(width 0.1)
				(type default)
			)
			(layer "F.Fab")
		)
		(fp_line
			(start 0.8636 -0.4572)
			(end 0.8636 -0.4064)
			(stroke
				(width 0.1)
				(type default)
			)
			(layer "F.Fab")
		)
		(pad "1" smd rect
			(at -0.7366 0 180)
			(size 0.7112 0.8128)
			(layers "F.Cu" "F.Mask" "F.Paste")
			(net "P12V_AUX")
		)
		(pad "2" smd rect
			(at 0.7366 0 180)
			(size 0.7112 0.8128)
			(layers "F.Cu" "F.Mask" "F.Paste")
			(net "GND")
		)
	)
	(footprint ""
		(layer "F.Cu")
		(at 182.026306 -332.744572 -90)
		(property "Reference" "PC531"
			(at -4.13512 9.547352 90)
			(unlocked yes)
			(layer "F.SilkS")
			(effects
				(font
					(size 0.7874 0.5842)
					(thickness 0.1524)
				)
				(justify left)
			)
		)
		(property "Value" ""
			(at 0 0 270)
			(layer "F.Fab")
			(effects
				(font
					(size 1.27 1.27)
				)
			)
		)
		(duplicate_pad_numbers_are_jumpers no)
		(fp_line
			(start -1.988058 2.750058)
			(end 2.750058 2.750058)
			(stroke
				(width 0.1524)
				(type default)
			)
			(layer "F.SilkS")
		)
		(fp_line
			(start 2.750058 2.750058)
			(end 2.750058 0.9398)
			(stroke
				(width 0.1524)
				(type default)
			)
			(layer "F.SilkS")
		)
		(fp_line
			(start -2.750058 1.988058)
			(end -1.988058 2.750058)
			(stroke
				(width 0.1524)
				(type default)
			)
			(layer "F.SilkS")
		)
		(fp_line
			(start -2.750058 0.9398)
			(end -2.750058 1.988058)
			(stroke
				(width 0.1524)
				(type default)
			)
			(layer "F.SilkS")
		)
		(fp_line
			(start 2.750058 -0.9398)
			(end 2.750058 -2.750058)
			(stroke
				(width 0.1524)
				(type default)
			)
			(layer "F.SilkS")
		)
		(fp_line
			(start -2.750058 -1.988058)
			(end -2.750058 -0.9398)
			(stroke
				(width 0.1524)
				(type default)
			)
			(layer "F.SilkS")
		)
		(fp_line
			(start -1.988058 -2.750058)
			(end -2.750058 -1.988058)
			(stroke
				(width 0.1524)
				(type default)
			)
			(layer "F.SilkS")
		)
		(fp_line
			(start 2.750058 -2.750058)
			(end -1.988058 -2.750058)
			(stroke
				(width 0.1524)
				(type default)
			)
			(layer "F.SilkS")
		)
		(fp_line
			(start -2.750058 2.750058)
			(end 2.750058 2.750058)
			(stroke
				(width 0.1)
				(type default)
			)
			(layer "F.Fab")
		)
		(fp_line
			(start 2.750058 2.750058)
			(end 2.750058 -2.750058)
			(stroke
				(width 0.1)
				(type default)
			)
			(layer "F.Fab")
		)
		(fp_line
			(start -2.750058 -2.750058)
			(end -2.750058 2.750058)
			(stroke
				(width 0.1)
				(type default)
			)
			(layer "F.Fab")
		)
		(fp_line
			(start 2.750058 -2.750058)
			(end -2.750058 -2.750058)
			(stroke
				(width 0.1)
				(type default)
			)
			(layer "F.Fab")
		)
		(pad "1" smd rect
			(at -2.199894 0)
			(size 1.6002 3.0226)
			(layers "F.Cu" "F.Mask" "F.Paste")
			(net "PVDD11_S3_P1")
		)
		(pad "2" smd rect
			(at 2.199894 0)
			(size 1.6002 3.0226)
			(layers "F.Cu" "F.Mask" "F.Paste")
			(net "GND")
		)
	)
	(footprint ""
		(layer "F.Cu")
		(at 384.465576 -56.81345 -90)
		(property "Reference" "C605"
			(at 0 0 270)
			(layer "F.SilkS")
			(hide yes)
			(effects
				(font
					(size 1.27 1.27)
				)
			)
		)
		(property "Value" ""
			(at 0 0 270)
			(layer "F.Fab")
			(effects
				(font
					(size 1.27 1.27)
				)
			)
		)
		(duplicate_pad_numbers_are_jumpers no)
		(fp_line
			(start -0.7874 0.4064)
			(end -0.7874 -0.4064)
			(stroke
				(width 0.1524)
				(type default)
			)
			(layer "F.SilkS")
		)
		(fp_line
			(start 0.7874 0.4064)
			(end -0.7874 0.4064)
			(stroke
				(width 0.1524)
				(type default)
			)
			(layer "F.SilkS")
		)
		(fp_line
			(start -0.7874 -0.4064)
			(end 0.7874 -0.4064)
			(stroke
				(width 0.1524)
				(type default)
			)
			(layer "F.SilkS")
		)
		(fp_line
			(start 0.7874 -0.4064)
			(end 0.7874 0.4064)
			(stroke
				(width 0.1524)
				(type default)
			)
			(layer "F.SilkS")
		)
		(fp_line
			(start -0.67945 0.3048)
			(end -0.67945 -0.305054)
			(stroke
				(width 0.1)
				(type default)
			)
			(layer "F.Fab")
		)
		(fp_line
			(start -0.12065 0.3048)
			(end -0.67945 0.3048)
			(stroke
				(width 0.1)
				(type default)
			)
			(layer "F.Fab")
		)
		(fp_line
			(start 0.120396 0.3048)
			(end 0.120396 0.2794)
			(stroke
				(width 0.1)
				(type default)
			)
			(layer "F.Fab")
		)
		(fp_line
			(start 0.67945 0.3048)
			(end 0.120396 0.3048)
			(stroke
				(width 0.1)
				(type default)
			)
			(layer "F.Fab")
		)
		(fp_line
			(start -0.12065 0.2794)
			(end -0.12065 0.3048)
			(stroke
				(width 0.1)
				(type default)
			)
			(layer "F.Fab")
		)
		(fp_line
			(start 0.120396 0.2794)
			(end -0.12065 0.2794)
			(stroke
				(width 0.1)
				(type default)
			)
			(layer "F.Fab")
		)
		(fp_line
			(start -0.12065 -0.2794)
			(end 0.12065 -0.2794)
			(stroke
				(width 0.1)
				(type default)
			)
			(layer "F.Fab")
		)
		(fp_line
			(start 0.12065 -0.2794)
			(end 0.12065 -0.3048)
			(stroke
				(width 0.1)
				(type default)
			)
			(layer "F.Fab")
		)
		(fp_line
			(start 0.12065 -0.3048)
			(end 0.67945 -0.3048)
			(stroke
				(width 0.1)
				(type default)
			)
			(layer "F.Fab")
		)
		(fp_line
			(start 0.67945 -0.3048)
			(end 0.67945 0.3048)
			(stroke
				(width 0.1)
				(type default)
			)
			(layer "F.Fab")
		)
		(fp_line
			(start -0.67945 -0.305054)
			(end -0.12065 -0.305054)
			(stroke
				(width 0.1)
				(type default)
			)
			(layer "F.Fab")
		)
		(fp_line
			(start -0.12065 -0.305054)
			(end -0.12065 -0.2794)
			(stroke
				(width 0.1)
				(type default)
			)
			(layer "F.Fab")
		)
		(pad "1" smd circle
			(at -0.40005 0 270)
			(size 0 0)
			(layers "F.Cu" "F.Mask" "F.Paste")
			(net "HDT_HDR_TDI")
		)
		(pad "2" smd circle
			(at 0.40005 0 270)
			(size 0 0)
			(layers "F.Cu" "F.Mask" "F.Paste")
			(net "GND")
		)
	)
	(footprint ""
		(layer "F.Cu")
		(at 56.50992 -31.664148)
		(property "Reference" "R3235"
			(at 0 0 0)
			(layer "F.SilkS")
			(hide yes)
			(effects
				(font
					(size 1.27 1.27)
				)
			)
		)
		(property "Value" ""
			(at 0 0 0)
			(layer "F.Fab")
			(effects
				(font
					(size 1.27 1.27)
				)
			)
		)
		(duplicate_pad_numbers_are_jumpers no)
		(fp_line
			(start -0.7874 -0.4064)
			(end 0.7874 -0.4064)
			(stroke
				(width 0.1524)
				(type default)
			)
			(layer "F.SilkS")
		)
		(fp_line
			(start -0.7874 0.4064)
			(end -0.7874 -0.4064)
			(stroke
				(width 0.1524)
				(type default)
			)
			(layer "F.SilkS")
		)
		(fp_line
			(start 0.7874 -0.4064)
			(end 0.7874 0.4064)
			(stroke
				(width 0.1524)
				(type default)
			)
			(layer "F.SilkS")
		)
		(fp_line
			(start 0.7874 0.4064)
			(end -0.7874 0.4064)
			(stroke
				(width 0.1524)
				(type default)
			)
			(layer "F.SilkS")
		)
		(fp_line
			(start -0.67945 -0.305054)
			(end -0.12065 -0.305054)
			(stroke
				(width 0.1)
				(type default)
			)
			(layer "F.Fab")
		)
		(fp_line
			(start -0.67945 0.3048)
			(end -0.67945 -0.305054)
			(stroke
				(width 0.1)
				(type default)
			)
			(layer "F.Fab")
		)
		(fp_line
			(start -0.12065 -0.305054)
			(end -0.12065 -0.2794)
			(stroke
				(width 0.1)
				(type default)
			)
			(layer "F.Fab")
		)
		(fp_line
			(start -0.12065 -0.2794)
			(end 0.12065 -0.2794)
			(stroke
				(width 0.1)
				(type default)
			)
			(layer "F.Fab")
		)
		(fp_line
			(start -0.12065 0.2794)
			(end -0.12065 0.3048)
			(stroke
				(width 0.1)
				(type default)
			)
			(layer "F.Fab")
		)
		(fp_line
			(start -0.12065 0.3048)
			(end -0.67945 0.3048)
			(stroke
				(width 0.1)
				(type default)
			)
			(layer "F.Fab")
		)
		(fp_line
			(start 0.120396 0.2794)
			(end -0.12065 0.2794)
			(stroke
				(width 0.1)
				(type default)
			)
			(layer "F.Fab")
		)
		(fp_line
			(start 0.120396 0.3048)
			(end 0.120396 0.2794)
			(stroke
				(width 0.1)
				(type default)
			)
			(layer "F.Fab")
		)
		(fp_line
			(start 0.12065 -0.3048)
			(end 0.67945 -0.3048)
			(stroke
				(width 0.1)
				(type default)
			)
			(layer "F.Fab")
		)
		(fp_line
			(start 0.12065 -0.2794)
			(end 0.12065 -0.3048)
			(stroke
				(width 0.1)
				(type default)
			)
			(layer "F.Fab")
		)
		(fp_line
			(start 0.67945 -0.3048)
			(end 0.67945 0.3048)
			(stroke
				(width 0.1)
				(type default)
			)
			(layer "F.Fab")
		)
		(fp_line
			(start 0.67945 0.3048)
			(end 0.120396 0.3048)
			(stroke
				(width 0.1)
				(type default)
			)
			(layer "F.Fab")
		)
		(pad "1" smd circle
			(at -0.40005 0)
			(size 0 0)
			(layers "F.Cu" "F.Mask" "F.Paste")
			(net "RST_HP_OCP_V3_2_R_N")
		)
		(pad "2" smd circle
			(at 0.40005 0)
			(size 0 0)
			(layers "F.Cu" "F.Mask" "F.Paste")
			(net "GND")
		)
	)
	(footprint ""
		(layer "F.Cu")
		(at 418.852096 -357.688134 -90)
		(property "Reference" "PR37"
			(at 0 0 270)
			(layer "F.SilkS")
			(hide yes)
			(effects
				(font
					(size 1.27 1.27)
				)
			)
		)
		(property "Value" ""
			(at 0 0 270)
			(layer "F.Fab")
			(effects
				(font
					(size 1.27 1.27)
				)
			)
		)
		(duplicate_pad_numbers_are_jumpers no)
		(fp_line
			(start -0.7874 0.4064)
			(end -0.7874 -0.4064)
			(stroke
				(width 0.1524)
				(type default)
			)
			(layer "F.SilkS")
		)
		(fp_line
			(start 0.7874 0.4064)
			(end -0.7874 0.4064)
			(stroke
				(width 0.1524)
				(type default)
			)
			(layer "F.SilkS")
		)
		(fp_line
			(start -0.7874 -0.4064)
			(end 0.7874 -0.4064)
			(stroke
				(width 0.1524)
				(type default)
			)
			(layer "F.SilkS")
		)
		(fp_line
			(start 0.7874 -0.4064)
			(end 0.7874 0.4064)
			(stroke
				(width 0.1524)
				(type default)
			)
			(layer "F.SilkS")
		)
		(fp_line
			(start -0.67945 0.3048)
			(end -0.67945 -0.305054)
			(stroke
				(width 0.1)
				(type default)
			)
			(layer "F.Fab")
		)
		(fp_line
			(start -0.12065 0.3048)
			(end -0.67945 0.3048)
			(stroke
				(width 0.1)
				(type default)
			)
			(layer "F.Fab")
		)
		(fp_line
			(start 0.120396 0.3048)
			(end 0.120396 0.2794)
			(stroke
				(width 0.1)
				(type default)
			)
			(layer "F.Fab")
		)
		(fp_line
			(start 0.67945 0.3048)
			(end 0.120396 0.3048)
			(stroke
				(width 0.1)
				(type default)
			)
			(layer "F.Fab")
		)
		(fp_line
			(start -0.12065 0.2794)
			(end -0.12065 0.3048)
			(stroke
				(width 0.1)
				(type default)
			)
			(layer "F.Fab")
		)
		(fp_line
			(start 0.120396 0.2794)
			(end -0.12065 0.2794)
			(stroke
				(width 0.1)
				(type default)
			)
			(layer "F.Fab")
		)
		(fp_line
			(start -0.12065 -0.2794)
			(end 0.12065 -0.2794)
			(stroke
				(width 0.1)
				(type default)
			)
			(layer "F.Fab")
		)
		(fp_line
			(start 0.12065 -0.2794)
			(end 0.12065 -0.3048)
			(stroke
				(width 0.1)
				(type default)
			)
			(layer "F.Fab")
		)
		(fp_line
			(start 0.12065 -0.3048)
			(end 0.67945 -0.3048)
			(stroke
				(width 0.1)
				(type default)
			)
			(layer "F.Fab")
		)
		(fp_line
			(start 0.67945 -0.3048)
			(end 0.67945 0.3048)
			(stroke
				(width 0.1)
				(type default)
			)
			(layer "F.Fab")
		)
		(fp_line
			(start -0.67945 -0.305054)
			(end -0.12065 -0.305054)
			(stroke
				(width 0.1)
				(type default)
			)
			(layer "F.Fab")
		)
		(fp_line
			(start -0.12065 -0.305054)
			(end -0.12065 -0.2794)
			(stroke
				(width 0.1)
				(type default)
			)
			(layer "F.Fab")
		)
		(pad "1" smd circle
			(at -0.40005 0 270)
			(size 0 0)
			(layers "F.Cu" "F.Mask" "F.Paste")
			(net "NC_PVDD11_S3_P0_IMON3")
		)
		(pad "2" smd circle
			(at 0.40005 0 270)
			(size 0 0)
			(layers "F.Cu" "F.Mask" "F.Paste")
			(net "GND")
		)
	)
	(footprint ""
		(layer "F.Cu")
		(at 183.007 -137.632948 90)
		(property "Reference" "R1286"
			(at 0 0 90)
			(layer "F.SilkS")
			(hide yes)
			(effects
				(font
					(size 1.27 1.27)
				)
			)
		)
		(property "Value" ""
			(at 0 0 90)
			(layer "F.Fab")
			(effects
				(font
					(size 1.27 1.27)
				)
			)
		)
		(duplicate_pad_numbers_are_jumpers no)
		(fp_line
			(start 0.7874 -0.4064)
			(end 0.7874 0.4064)
			(stroke
				(width 0.1524)
				(type default)
			)
			(layer "F.SilkS")
		)
		(fp_line
			(start -0.7874 -0.4064)
			(end 0.7874 -0.4064)
			(stroke
				(width 0.1524)
				(type default)
			)
			(layer "F.SilkS")
		)
		(fp_line
			(start 0.7874 0.4064)
			(end -0.7874 0.4064)
			(stroke
				(width 0.1524)
				(type default)
			)
			(layer "F.SilkS")
		)
		(fp_line
			(start -0.7874 0.4064)
			(end -0.7874 -0.4064)
			(stroke
				(width 0.1524)
				(type default)
			)
			(layer "F.SilkS")
		)
		(fp_line
			(start -0.12065 -0.305054)
			(end -0.12065 -0.2794)
			(stroke
				(width 0.1)
				(type default)
			)
			(layer "F.Fab")
		)
		(fp_line
			(start -0.67945 -0.305054)
			(end -0.12065 -0.305054)
			(stroke
				(width 0.1)
				(type default)
			)
			(layer "F.Fab")
		)
		(fp_line
			(start 0.67945 -0.3048)
			(end 0.67945 0.3048)
			(stroke
				(width 0.1)
				(type default)
			)
			(layer "F.Fab")
		)
		(fp_line
			(start 0.12065 -0.3048)
			(end 0.67945 -0.3048)
			(stroke
				(width 0.1)
				(type default)
			)
			(layer "F.Fab")
		)
		(fp_line
			(start 0.12065 -0.2794)
			(end 0.12065 -0.3048)
			(stroke
				(width 0.1)
				(type default)
			)
			(layer "F.Fab")
		)
		(fp_line
			(start -0.12065 -0.2794)
			(end 0.12065 -0.2794)
			(stroke
				(width 0.1)
				(type default)
			)
			(layer "F.Fab")
		)
		(fp_line
			(start 0.120396 0.2794)
			(end -0.12065 0.2794)
			(stroke
				(width 0.1)
				(type default)
			)
			(layer "F.Fab")
		)
		(fp_line
			(start -0.12065 0.2794)
			(end -0.12065 0.3048)
			(stroke
				(width 0.1)
				(type default)
			)
			(layer "F.Fab")
		)
		(fp_line
			(start 0.67945 0.3048)
			(end 0.120396 0.3048)
			(stroke
				(width 0.1)
				(type default)
			)
			(layer "F.Fab")
		)
		(fp_line
			(start 0.120396 0.3048)
			(end 0.120396 0.2794)
			(stroke
				(width 0.1)
				(type default)
			)
			(layer "F.Fab")
		)
		(fp_line
			(start -0.12065 0.3048)
			(end -0.67945 0.3048)
			(stroke
				(width 0.1)
				(type default)
			)
			(layer "F.Fab")
		)
		(fp_line
			(start -0.67945 0.3048)
			(end -0.67945 -0.305054)
			(stroke
				(width 0.1)
				(type default)
			)
			(layer "F.Fab")
		)
		(pad "1" smd circle
			(at -0.40005 0 90)
			(size 0 0)
			(layers "F.Cu" "F.Mask" "F.Paste")
			(net "FM_P1_PCC1_N")
		)
		(pad "2" smd circle
			(at 0.40005 0 90)
			(size 0 0)
			(layers "F.Cu" "F.Mask" "F.Paste")
			(net "PVDD18_S5_P1")
		)
	)
	(footprint ""
		(layer "F.Cu")
		(at 421.047164 -17.624298 90)
		(property "Reference" "C1570"
			(at 0 0 90)
			(layer "F.SilkS")
			(hide yes)
			(effects
				(font
					(size 1.27 1.27)
				)
			)
		)
		(property "Value" ""
			(at 0 0 90)
			(layer "F.Fab")
			(effects
				(font
					(size 1.27 1.27)
				)
			)
		)
		(duplicate_pad_numbers_are_jumpers no)
		(fp_line
			(start 0.299974 -0.150114)
			(end 0.299974 0.150114)
			(stroke
				(width 0.1)
				(type default)
			)
			(layer "F.Fab")
		)
		(fp_line
			(start -0.299974 -0.150114)
			(end 0.299974 -0.150114)
			(stroke
				(width 0.1)
				(type default)
			)
			(layer "F.Fab")
		)
		(fp_line
			(start 0.299974 0.150114)
			(end -0.299974 0.150114)
			(stroke
				(width 0.1)
				(type default)
			)
			(layer "F.Fab")
		)
		(fp_line
			(start -0.299974 0.150114)
			(end -0.299974 -0.150114)
			(stroke
				(width 0.1)
				(type default)
			)
			(layer "F.Fab")
		)
		(pad "1" smd rect
			(at -0.2667 0 90)
			(size 0.3048 0.381)
			(layers "F.Cu" "F.Mask" "F.Paste")
			(net "P5E_CPU0_G3_TX_C_DN<4>")
		)
		(pad "2" smd rect
			(at 0.2667 0 90)
			(size 0.3048 0.381)
			(layers "F.Cu" "F.Mask" "F.Paste")
			(net "P5E_CPU0_G3_TX_DN<4>")
		)
	)
	(footprint ""
		(layer "F.Cu")
		(at 58.191654 -349.386398 90)
		(property "Reference" "PC399"
			(at 0 0 90)
			(layer "F.SilkS")
			(hide yes)
			(effects
				(font
					(size 1.27 1.27)
				)
			)
		)
		(property "Value" ""
			(at 0 0 90)
			(layer "F.Fab")
			(effects
				(font
					(size 1.27 1.27)
				)
			)
		)
		(duplicate_pad_numbers_are_jumpers no)
		(fp_line
			(start 0.7874 -0.4064)
			(end 0.7874 0.4064)
			(stroke
				(width 0.1524)
				(type default)
			)
			(layer "F.SilkS")
		)
		(fp_line
			(start -0.7874 -0.4064)
			(end 0.7874 -0.4064)
			(stroke
				(width 0.1524)
				(type default)
			)
			(layer "F.SilkS")
		)
		(fp_line
			(start 0.7874 0.4064)
			(end 0.397002 0.4064)
			(stroke
				(width 0.1524)
				(type default)
			)
			(layer "F.SilkS")
		)
		(fp_line
			(start -0.212598 0.4064)
			(end -0.7874 0.4064)
			(stroke
				(width 0.1524)
				(type default)
			)
			(layer "F.SilkS")
		)
		(fp_line
			(start -0.7874 0.4064)
			(end -0.7874 -0.4064)
			(stroke
				(width 0.1524)
				(type default)
			)
			(layer "F.SilkS")
		)
		(fp_line
			(start -0.12065 -0.305054)
			(end -0.12065 -0.2794)
			(stroke
				(width 0.1)
				(type default)
			)
			(layer "F.Fab")
		)
		(fp_line
			(start -0.67945 -0.305054)
			(end -0.12065 -0.305054)
			(stroke
				(width 0.1)
				(type default)
			)
			(layer "F.Fab")
		)
		(fp_line
			(start 0.67945 -0.3048)
			(end 0.67945 0.3048)
			(stroke
				(width 0.1)
				(type default)
			)
			(layer "F.Fab")
		)
		(fp_line
			(start 0.12065 -0.3048)
			(end 0.67945 -0.3048)
			(stroke
				(width 0.1)
				(type default)
			)
			(layer "F.Fab")
		)
		(fp_line
			(start 0.12065 -0.2794)
			(end 0.12065 -0.3048)
			(stroke
				(width 0.1)
				(type default)
			)
			(layer "F.Fab")
		)
		(fp_line
			(start -0.12065 -0.2794)
			(end 0.12065 -0.2794)
			(stroke
				(width 0.1)
				(type default)
			)
			(layer "F.Fab")
		)
		(fp_line
			(start 0.120396 0.2794)
			(end -0.12065 0.2794)
			(stroke
				(width 0.1)
				(type default)
			)
			(layer "F.Fab")
		)
		(fp_line
			(start -0.12065 0.2794)
			(end -0.12065 0.3048)
			(stroke
				(width 0.1)
				(type default)
			)
			(layer "F.Fab")
		)
		(fp_line
			(start 0.67945 0.3048)
			(end 0.120396 0.3048)
			(stroke
				(width 0.1)
				(type default)
			)
			(layer "F.Fab")
		)
		(fp_line
			(start 0.120396 0.3048)
			(end 0.120396 0.2794)
			(stroke
				(width 0.1)
				(type default)
			)
			(layer "F.Fab")
		)
		(fp_line
			(start -0.12065 0.3048)
			(end -0.67945 0.3048)
			(stroke
				(width 0.1)
				(type default)
			)
			(layer "F.Fab")
		)
		(fp_line
			(start -0.67945 0.3048)
			(end -0.67945 -0.305054)
			(stroke
				(width 0.1)
				(type default)
			)
			(layer "F.Fab")
		)
		(pad "1" smd circle
			(at -0.40005 0 90)
			(size 0 0)
			(layers "F.Cu" "F.Mask" "F.Paste")
			(net "PVDDCR_CPU1_P1_VCC4")
		)
		(pad "2" smd circle
			(at 0.40005 0 90)
			(size 0 0)
			(layers "F.Cu" "F.Mask" "F.Paste")
			(net "GND")
		)
	)
	(footprint ""
		(layer "F.Cu")
		(at 443.347602 -429.37811 -90)
		(property "Reference" "R647"
			(at 0 0 270)
			(layer "F.SilkS")
			(hide yes)
			(effects
				(font
					(size 1.27 1.27)
				)
			)
		)
		(property "Value" ""
			(at 0 0 270)
			(layer "F.Fab")
			(effects
				(font
					(size 1.27 1.27)
				)
			)
		)
		(duplicate_pad_numbers_are_jumpers no)
		(fp_line
			(start -0.7874 0.4064)
			(end -0.7874 -0.4064)
			(stroke
				(width 0.1524)
				(type default)
			)
			(layer "F.SilkS")
		)
		(fp_line
			(start 0.7874 0.4064)
			(end -0.7874 0.4064)
			(stroke
				(width 0.1524)
				(type default)
			)
			(layer "F.SilkS")
		)
		(fp_line
			(start -0.7874 -0.4064)
			(end 0.7874 -0.4064)
			(stroke
				(width 0.1524)
				(type default)
			)
			(layer "F.SilkS")
		)
		(fp_line
			(start 0.7874 -0.4064)
			(end 0.7874 0.4064)
			(stroke
				(width 0.1524)
				(type default)
			)
			(layer "F.SilkS")
		)
		(fp_line
			(start -0.67945 0.3048)
			(end -0.67945 -0.305054)
			(stroke
				(width 0.1)
				(type default)
			)
			(layer "F.Fab")
		)
		(fp_line
			(start -0.12065 0.3048)
			(end -0.67945 0.3048)
			(stroke
				(width 0.1)
				(type default)
			)
			(layer "F.Fab")
		)
		(fp_line
			(start 0.120396 0.3048)
			(end 0.120396 0.2794)
			(stroke
				(width 0.1)
				(type default)
			)
			(layer "F.Fab")
		)
		(fp_line
			(start 0.67945 0.3048)
			(end 0.120396 0.3048)
			(stroke
				(width 0.1)
				(type default)
			)
			(layer "F.Fab")
		)
		(fp_line
			(start -0.12065 0.2794)
			(end -0.12065 0.3048)
			(stroke
				(width 0.1)
				(type default)
			)
			(layer "F.Fab")
		)
		(fp_line
			(start 0.120396 0.2794)
			(end -0.12065 0.2794)
			(stroke
				(width 0.1)
				(type default)
			)
			(layer "F.Fab")
		)
		(fp_line
			(start -0.12065 -0.2794)
			(end 0.12065 -0.2794)
			(stroke
				(width 0.1)
				(type default)
			)
			(layer "F.Fab")
		)
		(fp_line
			(start 0.12065 -0.2794)
			(end 0.12065 -0.3048)
			(stroke
				(width 0.1)
				(type default)
			)
			(layer "F.Fab")
		)
		(fp_line
			(start 0.12065 -0.3048)
			(end 0.67945 -0.3048)
			(stroke
				(width 0.1)
				(type default)
			)
			(layer "F.Fab")
		)
		(fp_line
			(start 0.67945 -0.3048)
			(end 0.67945 0.3048)
			(stroke
				(width 0.1)
				(type default)
			)
			(layer "F.Fab")
		)
		(fp_line
			(start -0.67945 -0.305054)
			(end -0.12065 -0.305054)
			(stroke
				(width 0.1)
				(type default)
			)
			(layer "F.Fab")
		)
		(fp_line
			(start -0.12065 -0.305054)
			(end -0.12065 -0.2794)
			(stroke
				(width 0.1)
				(type default)
			)
			(layer "F.Fab")
		)
		(pad "1" smd circle
			(at -0.40005 0 270)
			(size 0 0)
			(layers "F.Cu" "F.Mask" "F.Paste")
			(net "P0V9_RETIMER_CPU0_PMSDA")
		)
		(pad "2" smd circle
			(at 0.40005 0 270)
			(size 0 0)
			(layers "F.Cu" "F.Mask" "F.Paste")
			(net "P0V9_RETIMER_CPU0_PMSDA_R")
		)
	)
	(footprint ""
		(layer "F.Cu")
		(at 464.799934 -22.29993)
		(property "Reference" "H96"
			(at -5.137658 -5.653532 0)
			(unlocked yes)
			(layer "F.SilkS")
			(effects
				(font
					(size 0.7874 0.5842)
					(thickness 0.1524)
				)
				(justify left)
			)
		)
		(property "Value" ""
			(at 0 0 0)
			(layer "F.Fab")
			(effects
				(font
					(size 1.27 1.27)
				)
			)
		)
		(duplicate_pad_numbers_are_jumpers no)
		(pad "1" thru_hole circle
			(at 0 0)
			(size 10.0076 10.0076)
			(drill 5.6134)
			(layers "*.Cu" "*.Mask")
			(remove_unused_layers no)
			(net "GND")
			(clearance -1.9431)
		)
	)
	(footprint ""
		(layer "F.Cu")
		(at 142.367 -121.285)
		(property "Reference" "R8124"
			(at 0 0 0)
			(layer "F.SilkS")
			(hide yes)
			(effects
				(font
					(size 1.27 1.27)
				)
			)
		)
		(property "Value" ""
			(at 0 0 0)
			(layer "F.Fab")
			(effects
				(font
					(size 1.27 1.27)
				)
			)
		)
		(duplicate_pad_numbers_are_jumpers no)
		(fp_line
			(start -0.7874 -0.4064)
			(end 0.7874 -0.4064)
			(stroke
				(width 0.1524)
				(type default)
			)
			(layer "F.SilkS")
		)
		(fp_line
			(start -0.7874 0.4064)
			(end -0.7874 -0.4064)
			(stroke
				(width 0.1524)
				(type default)
			)
			(layer "F.SilkS")
		)
		(fp_line
			(start 0.7874 -0.4064)
			(end 0.7874 0.4064)
			(stroke
				(width 0.1524)
				(type default)
			)
			(layer "F.SilkS")
		)
		(fp_line
			(start 0.7874 0.4064)
			(end -0.7874 0.4064)
			(stroke
				(width 0.1524)
				(type default)
			)
			(layer "F.SilkS")
		)
		(fp_line
			(start -0.67945 -0.305054)
			(end -0.12065 -0.305054)
			(stroke
				(width 0.1)
				(type default)
			)
			(layer "F.Fab")
		)
		(fp_line
			(start -0.67945 0.3048)
			(end -0.67945 -0.305054)
			(stroke
				(width 0.1)
				(type default)
			)
			(layer "F.Fab")
		)
		(fp_line
			(start -0.12065 -0.305054)
			(end -0.12065 -0.2794)
			(stroke
				(width 0.1)
				(type default)
			)
			(layer "F.Fab")
		)
		(fp_line
			(start -0.12065 -0.2794)
			(end 0.12065 -0.2794)
			(stroke
				(width 0.1)
				(type default)
			)
			(layer "F.Fab")
		)
		(fp_line
			(start -0.12065 0.2794)
			(end -0.12065 0.3048)
			(stroke
				(width 0.1)
				(type default)
			)
			(layer "F.Fab")
		)
		(fp_line
			(start -0.12065 0.3048)
			(end -0.67945 0.3048)
			(stroke
				(width 0.1)
				(type default)
			)
			(layer "F.Fab")
		)
		(fp_line
			(start 0.120396 0.2794)
			(end -0.12065 0.2794)
			(stroke
				(width 0.1)
				(type default)
			)
			(layer "F.Fab")
		)
		(fp_line
			(start 0.120396 0.3048)
			(end 0.120396 0.2794)
			(stroke
				(width 0.1)
				(type default)
			)
			(layer "F.Fab")
		)
		(fp_line
			(start 0.12065 -0.3048)
			(end 0.67945 -0.3048)
			(stroke
				(width 0.1)
				(type default)
			)
			(layer "F.Fab")
		)
		(fp_line
			(start 0.12065 -0.2794)
			(end 0.12065 -0.3048)
			(stroke
				(width 0.1)
				(type default)
			)
			(layer "F.Fab")
		)
		(fp_line
			(start 0.67945 -0.3048)
			(end 0.67945 0.3048)
			(stroke
				(width 0.1)
				(type default)
			)
			(layer "F.Fab")
		)
		(fp_line
			(start 0.67945 0.3048)
			(end 0.120396 0.3048)
			(stroke
				(width 0.1)
				(type default)
			)
			(layer "F.Fab")
		)
		(pad "1" smd circle
			(at -0.40005 0)
			(size 0 0)
			(layers "F.Cu" "F.Mask" "F.Paste")
			(net "IRQ_UV_DETECT_R2_N")
		)
		(pad "2" smd circle
			(at 0.40005 0)
			(size 0 0)
			(layers "F.Cu" "F.Mask" "F.Paste")
			(net "IRQ_UV_DETECT_N")
		)
	)
	(footprint ""
		(layer "F.Cu")
		(at 62.339728 -53.693314)
		(property "Reference" "U9051"
			(at -4.14782 2.455672 0)
			(unlocked yes)
			(layer "F.SilkS")
			(effects
				(font
					(size 0.7874 0.5842)
					(thickness 0.1524)
				)
				(justify left)
			)
		)
		(property "Value" ""
			(at 0 0 0)
			(layer "F.Fab")
			(effects
				(font
					(size 1.27 1.27)
				)
			)
		)
		(duplicate_pad_numbers_are_jumpers no)
		(fp_line
			(start -1.733296 -1.549908)
			(end -1.733296 1.549908)
			(stroke
				(width 0.1524)
				(type default)
			)
			(layer "F.SilkS")
		)
		(fp_line
			(start -1.733296 1.549908)
			(end 1.733296 1.549908)
			(stroke
				(width 0.1524)
				(type default)
			)
			(layer "F.SilkS")
		)
		(fp_line
			(start -0.660908 -1.549908)
			(end -1.733296 -1.549908)
			(stroke
				(width 0.1524)
				(type default)
			)
			(layer "F.SilkS")
		)
		(fp_line
			(start 0 -0.889)
			(end -0.660908 -1.549908)
			(stroke
				(width 0.1524)
				(type default)
			)
			(layer "F.SilkS")
		)
		(fp_line
			(start 0.660908 -1.549908)
			(end 0 -0.889)
			(stroke
				(width 0.1524)
				(type default)
			)
			(layer "F.SilkS")
		)
		(fp_line
			(start 1.733296 -1.549908)
			(end 0.660908 -1.549908)
			(stroke
				(width 0.1524)
				(type default)
			)
			(layer "F.SilkS")
		)
		(fp_line
			(start 1.733296 1.549908)
			(end 1.733296 -1.549908)
			(stroke
				(width 0.1524)
				(type default)
			)
			(layer "F.SilkS")
		)
		(fp_poly
			(pts
				(xy -2.4384 -1.20396) (xy -2.4384 -0.69596) (xy -1.9304 -0.94996)
			)
			(stroke
				(width 0)
				(type default)
			)
			(fill yes)
			(layer "F.SilkS")
		)
		(fp_line
			(start -0.849884 -1.549908)
			(end -0.849884 1.549908)
			(stroke
				(width 0.1)
				(type default)
			)
			(layer "F.Fab")
		)
		(fp_line
			(start -0.849884 1.549908)
			(end 0.849884 1.549908)
			(stroke
				(width 0.1)
				(type default)
			)
			(layer "F.Fab")
		)
		(fp_line
			(start 0.849884 -1.549908)
			(end -0.849884 -1.549908)
			(stroke
				(width 0.1)
				(type default)
			)
			(layer "F.Fab")
		)
		(fp_line
			(start 0.849884 1.549908)
			(end 0.849884 -1.549908)
			(stroke
				(width 0.1)
				(type default)
			)
			(layer "F.Fab")
		)
		(fp_poly
			(pts
				(xy -2.4384 -1.20396) (xy -2.4384 -0.69596) (xy -1.9304 -0.94996)
			)
			(stroke
				(width 0)
				(type default)
			)
			(fill yes)
			(layer "F.Fab")
		)
		(pad "1" smd rect
			(at -1.199896 -0.94996 270)
			(size 0.5588 0.8128)
			(layers "F.Cu" "F.Mask" "F.Paste")
			(net "OCP_V3_2_P3V3_PWRGD")
		)
		(pad "2" smd rect
			(at -1.199896 0 270)
			(size 0.5588 0.8128)
			(layers "F.Cu" "F.Mask" "F.Paste")
			(net "HP_LVC3_OCP_V3_2_P12V_PWRGD_R2")
		)
		(pad "3" smd rect
			(at -1.199896 0.94996 270)
			(size 0.5588 0.8128)
			(layers "F.Cu" "F.Mask" "F.Paste")
			(net "GND")
		)
		(pad "4" smd rect
			(at 1.199896 0.94996 270)
			(size 0.5588 0.8128)
			(layers "F.Cu" "F.Mask" "F.Paste")
			(net "HP_LVC3_OCP_V3_2_PWRGD_R2")
		)
		(pad "5" smd rect
			(at 1.199896 -0.94996 270)
			(size 0.5588 0.8128)
			(layers "F.Cu" "F.Mask" "F.Paste")
			(net "P3V3_AUX")
		)
	)
	(footprint ""
		(layer "F.Cu")
		(at 304.419 -356.997)
		(property "Reference" "PR8007"
			(at 0 0 0)
			(layer "F.SilkS")
			(hide yes)
			(effects
				(font
					(size 1.27 1.27)
				)
			)
		)
		(property "Value" ""
			(at 0 0 0)
			(layer "F.Fab")
			(effects
				(font
					(size 1.27 1.27)
				)
			)
		)
		(duplicate_pad_numbers_are_jumpers no)
		(fp_line
			(start -0.7874 -0.4064)
			(end 0.7874 -0.4064)
			(stroke
				(width 0.1524)
				(type default)
			)
			(layer "F.SilkS")
		)
		(fp_line
			(start -0.7874 0.4064)
			(end -0.7874 -0.4064)
			(stroke
				(width 0.1524)
				(type default)
			)
			(layer "F.SilkS")
		)
		(fp_line
			(start 0.7874 -0.4064)
			(end 0.7874 0.4064)
			(stroke
				(width 0.1524)
				(type default)
			)
			(layer "F.SilkS")
		)
		(fp_line
			(start 0.7874 0.4064)
			(end -0.7874 0.4064)
			(stroke
				(width 0.1524)
				(type default)
			)
			(layer "F.SilkS")
		)
		(fp_line
			(start -0.67945 -0.305054)
			(end -0.12065 -0.305054)
			(stroke
				(width 0.1)
				(type default)
			)
			(layer "F.Fab")
		)
		(fp_line
			(start -0.67945 0.3048)
			(end -0.67945 -0.305054)
			(stroke
				(width 0.1)
				(type default)
			)
			(layer "F.Fab")
		)
		(fp_line
			(start -0.12065 -0.305054)
			(end -0.12065 -0.2794)
			(stroke
				(width 0.1)
				(type default)
			)
			(layer "F.Fab")
		)
		(fp_line
			(start -0.12065 -0.2794)
			(end 0.12065 -0.2794)
			(stroke
				(width 0.1)
				(type default)
			)
			(layer "F.Fab")
		)
		(fp_line
			(start -0.12065 0.2794)
			(end -0.12065 0.3048)
			(stroke
				(width 0.1)
				(type default)
			)
			(layer "F.Fab")
		)
		(fp_line
			(start -0.12065 0.3048)
			(end -0.67945 0.3048)
			(stroke
				(width 0.1)
				(type default)
			)
			(layer "F.Fab")
		)
		(fp_line
			(start 0.120396 0.2794)
			(end -0.12065 0.2794)
			(stroke
				(width 0.1)
				(type default)
			)
			(layer "F.Fab")
		)
		(fp_line
			(start 0.120396 0.3048)
			(end 0.120396 0.2794)
			(stroke
				(width 0.1)
				(type default)
			)
			(layer "F.Fab")
		)
		(fp_line
			(start 0.12065 -0.3048)
			(end 0.67945 -0.3048)
			(stroke
				(width 0.1)
				(type default)
			)
			(layer "F.Fab")
		)
		(fp_line
			(start 0.12065 -0.2794)
			(end 0.12065 -0.3048)
			(stroke
				(width 0.1)
				(type default)
			)
			(layer "F.Fab")
		)
		(fp_line
			(start 0.67945 -0.3048)
			(end 0.67945 0.3048)
			(stroke
				(width 0.1)
				(type default)
			)
			(layer "F.Fab")
		)
		(fp_line
			(start 0.67945 0.3048)
			(end 0.120396 0.3048)
			(stroke
				(width 0.1)
				(type default)
			)
			(layer "F.Fab")
		)
		(pad "1" smd circle
			(at -0.40005 0)
			(size 0 0)
			(layers "F.Cu" "F.Mask" "F.Paste")
			(net "SVID_PVDDCR_CPU1_P0_SVC_R")
		)
		(pad "2" smd circle
			(at 0.40005 0)
			(size 0 0)
			(layers "F.Cu" "F.Mask" "F.Paste")
			(net "SVID_PVDDCR_CPU1_P0_SVC_R1")
		)
	)
	(footprint ""
		(layer "F.Cu")
		(at 169.404792 -101.520498 -90)
		(property "Reference" "R6187"
			(at 0 0 270)
			(layer "F.SilkS")
			(hide yes)
			(effects
				(font
					(size 1.27 1.27)
				)
			)
		)
		(property "Value" ""
			(at 0 0 270)
			(layer "F.Fab")
			(effects
				(font
					(size 1.27 1.27)
				)
			)
		)
		(duplicate_pad_numbers_are_jumpers no)
		(fp_line
			(start -0.7874 0.4064)
			(end -0.7874 -0.4064)
			(stroke
				(width 0.1524)
				(type default)
			)
			(layer "F.SilkS")
		)
		(fp_line
			(start 0.7874 0.4064)
			(end -0.7874 0.4064)
			(stroke
				(width 0.1524)
				(type default)
			)
			(layer "F.SilkS")
		)
		(fp_line
			(start -0.7874 -0.4064)
			(end 0.7874 -0.4064)
			(stroke
				(width 0.1524)
				(type default)
			)
			(layer "F.SilkS")
		)
		(fp_line
			(start 0.7874 -0.4064)
			(end 0.7874 0.4064)
			(stroke
				(width 0.1524)
				(type default)
			)
			(layer "F.SilkS")
		)
		(fp_line
			(start -0.67945 0.3048)
			(end -0.67945 -0.305054)
			(stroke
				(width 0.1)
				(type default)
			)
			(layer "F.Fab")
		)
		(fp_line
			(start -0.12065 0.3048)
			(end -0.67945 0.3048)
			(stroke
				(width 0.1)
				(type default)
			)
			(layer "F.Fab")
		)
		(fp_line
			(start 0.120396 0.3048)
			(end 0.120396 0.2794)
			(stroke
				(width 0.1)
				(type default)
			)
			(layer "F.Fab")
		)
		(fp_line
			(start 0.67945 0.3048)
			(end 0.120396 0.3048)
			(stroke
				(width 0.1)
				(type default)
			)
			(layer "F.Fab")
		)
		(fp_line
			(start -0.12065 0.2794)
			(end -0.12065 0.3048)
			(stroke
				(width 0.1)
				(type default)
			)
			(layer "F.Fab")
		)
		(fp_line
			(start 0.120396 0.2794)
			(end -0.12065 0.2794)
			(stroke
				(width 0.1)
				(type default)
			)
			(layer "F.Fab")
		)
		(fp_line
			(start -0.12065 -0.2794)
			(end 0.12065 -0.2794)
			(stroke
				(width 0.1)
				(type default)
			)
			(layer "F.Fab")
		)
		(fp_line
			(start 0.12065 -0.2794)
			(end 0.12065 -0.3048)
			(stroke
				(width 0.1)
				(type default)
			)
			(layer "F.Fab")
		)
		(fp_line
			(start 0.12065 -0.3048)
			(end 0.67945 -0.3048)
			(stroke
				(width 0.1)
				(type default)
			)
			(layer "F.Fab")
		)
		(fp_line
			(start 0.67945 -0.3048)
			(end 0.67945 0.3048)
			(stroke
				(width 0.1)
				(type default)
			)
			(layer "F.Fab")
		)
		(fp_line
			(start -0.67945 -0.305054)
			(end -0.12065 -0.305054)
			(stroke
				(width 0.1)
				(type default)
			)
			(layer "F.Fab")
		)
		(fp_line
			(start -0.12065 -0.305054)
			(end -0.12065 -0.2794)
			(stroke
				(width 0.1)
				(type default)
			)
			(layer "F.Fab")
		)
		(pad "1" smd circle
			(at -0.40005 0 270)
			(size 0 0)
			(layers "F.Cu" "F.Mask" "F.Paste")
			(net "FM_SEC_MUX_SEL")
		)
		(pad "2" smd circle
			(at 0.40005 0 270)
			(size 0 0)
			(layers "F.Cu" "F.Mask" "F.Paste")
			(net "GND")
		)
	)
	(footprint ""
		(layer "F.Cu")
		(at 58.180732 -343.716864 180)
		(property "Reference" "PC205"
			(at 0 0 180)
			(layer "F.SilkS")
			(hide yes)
			(effects
				(font
					(size 1.27 1.27)
				)
			)
		)
		(property "Value" ""
			(at 0 0 180)
			(layer "F.Fab")
			(effects
				(font
					(size 1.27 1.27)
				)
			)
		)
		(duplicate_pad_numbers_are_jumpers no)
		(fp_line
			(start 0.7874 0.4064)
			(end -0.7874 0.4064)
			(stroke
				(width 0.1524)
				(type default)
			)
			(layer "F.SilkS")
		)
		(fp_line
			(start 0.7874 -0.4064)
			(end 0.7874 0.4064)
			(stroke
				(width 0.1524)
				(type default)
			)
			(layer "F.SilkS")
		)
		(fp_line
			(start -0.7874 0.4064)
			(end -0.7874 -0.4064)
			(stroke
				(width 0.1524)
				(type default)
			)
			(layer "F.SilkS")
		)
		(fp_line
			(start -0.7874 -0.4064)
			(end 0.7874 -0.4064)
			(stroke
				(width 0.1524)
				(type default)
			)
			(layer "F.SilkS")
		)
		(fp_line
			(start 0.67945 0.3048)
			(end 0.120396 0.3048)
			(stroke
				(width 0.1)
				(type default)
			)
			(layer "F.Fab")
		)
		(fp_line
			(start 0.67945 -0.3048)
			(end 0.67945 0.3048)
			(stroke
				(width 0.1)
				(type default)
			)
			(layer "F.Fab")
		)
		(fp_line
			(start 0.12065 -0.2794)
			(end 0.12065 -0.3048)
			(stroke
				(width 0.1)
				(type default)
			)
			(layer "F.Fab")
		)
		(fp_line
			(start 0.12065 -0.3048)
			(end 0.67945 -0.3048)
			(stroke
				(width 0.1)
				(type default)
			)
			(layer "F.Fab")
		)
		(fp_line
			(start 0.120396 0.3048)
			(end 0.120396 0.2794)
			(stroke
				(width 0.1)
				(type default)
			)
			(layer "F.Fab")
		)
		(fp_line
			(start 0.120396 0.2794)
			(end -0.12065 0.2794)
			(stroke
				(width 0.1)
				(type default)
			)
			(layer "F.Fab")
		)
		(fp_line
			(start -0.12065 0.3048)
			(end -0.67945 0.3048)
			(stroke
				(width 0.1)
				(type default)
			)
			(layer "F.Fab")
		)
		(fp_line
			(start -0.12065 0.2794)
			(end -0.12065 0.3048)
			(stroke
				(width 0.1)
				(type default)
			)
			(layer "F.Fab")
		)
		(fp_line
			(start -0.12065 -0.2794)
			(end 0.12065 -0.2794)
			(stroke
				(width 0.1)
				(type default)
			)
			(layer "F.Fab")
		)
		(fp_line
			(start -0.12065 -0.305054)
			(end -0.12065 -0.2794)
			(stroke
				(width 0.1)
				(type default)
			)
			(layer "F.Fab")
		)
		(fp_line
			(start -0.67945 0.3048)
			(end -0.67945 -0.305054)
			(stroke
				(width 0.1)
				(type default)
			)
			(layer "F.Fab")
		)
		(fp_line
			(start -0.67945 -0.305054)
			(end -0.12065 -0.305054)
			(stroke
				(width 0.1)
				(type default)
			)
			(layer "F.Fab")
		)
		(pad "1" smd circle
			(at -0.40005 0 180)
			(size 0 0)
			(layers "F.Cu" "F.Mask" "F.Paste")
			(net "SW_PVDDCR_CPU1_P1_SW4")
		)
		(pad "2" smd circle
			(at 0.40005 0 180)
			(size 0 0)
			(layers "F.Cu" "F.Mask" "F.Paste")
			(net "SW_PVDDCR_CPU1_P1_SW4_RC")
		)
	)
	(footprint ""
		(layer "F.Cu")
		(at 110.856014 -259.845302)
		(property "Reference" "C2266"
			(at 0 0 0)
			(layer "F.SilkS")
			(hide yes)
			(effects
				(font
					(size 1.27 1.27)
				)
			)
		)
		(property "Value" ""
			(at 0 0 0)
			(layer "F.Fab")
			(effects
				(font
					(size 1.27 1.27)
				)
			)
		)
		(duplicate_pad_numbers_are_jumpers no)
		(fp_line
			(start -0.7874 -0.4064)
			(end 0.7874 -0.4064)
			(stroke
				(width 0.1524)
				(type default)
			)
			(layer "F.SilkS")
		)
		(fp_line
			(start -0.7874 0.4064)
			(end -0.7874 -0.4064)
			(stroke
				(width 0.1524)
				(type default)
			)
			(layer "F.SilkS")
		)
		(fp_line
			(start 0.7874 -0.4064)
			(end 0.7874 0.4064)
			(stroke
				(width 0.1524)
				(type default)
			)
			(layer "F.SilkS")
		)
		(fp_line
			(start 0.7874 0.4064)
			(end -0.7874 0.4064)
			(stroke
				(width 0.1524)
				(type default)
			)
			(layer "F.SilkS")
		)
		(fp_line
			(start -0.67945 -0.305054)
			(end -0.12065 -0.305054)
			(stroke
				(width 0.1)
				(type default)
			)
			(layer "F.Fab")
		)
		(fp_line
			(start -0.67945 0.3048)
			(end -0.67945 -0.305054)
			(stroke
				(width 0.1)
				(type default)
			)
			(layer "F.Fab")
		)
		(fp_line
			(start -0.12065 -0.305054)
			(end -0.12065 -0.2794)
			(stroke
				(width 0.1)
				(type default)
			)
			(layer "F.Fab")
		)
		(fp_line
			(start -0.12065 -0.2794)
			(end 0.12065 -0.2794)
			(stroke
				(width 0.1)
				(type default)
			)
			(layer "F.Fab")
		)
		(fp_line
			(start -0.12065 0.2794)
			(end -0.12065 0.3048)
			(stroke
				(width 0.1)
				(type default)
			)
			(layer "F.Fab")
		)
		(fp_line
			(start -0.12065 0.3048)
			(end -0.67945 0.3048)
			(stroke
				(width 0.1)
				(type default)
			)
			(layer "F.Fab")
		)
		(fp_line
			(start 0.120396 0.2794)
			(end -0.12065 0.2794)
			(stroke
				(width 0.1)
				(type default)
			)
			(layer "F.Fab")
		)
		(fp_line
			(start 0.120396 0.3048)
			(end 0.120396 0.2794)
			(stroke
				(width 0.1)
				(type default)
			)
			(layer "F.Fab")
		)
		(fp_line
			(start 0.12065 -0.3048)
			(end 0.67945 -0.3048)
			(stroke
				(width 0.1)
				(type default)
			)
			(layer "F.Fab")
		)
		(fp_line
			(start 0.12065 -0.2794)
			(end 0.12065 -0.3048)
			(stroke
				(width 0.1)
				(type default)
			)
			(layer "F.Fab")
		)
		(fp_line
			(start 0.67945 -0.3048)
			(end 0.67945 0.3048)
			(stroke
				(width 0.1)
				(type default)
			)
			(layer "F.Fab")
		)
		(fp_line
			(start 0.67945 0.3048)
			(end 0.120396 0.3048)
			(stroke
				(width 0.1)
				(type default)
			)
			(layer "F.Fab")
		)
		(pad "1" smd circle
			(at -0.40005 0)
			(size 0 0)
			(layers "F.Cu" "F.Mask" "F.Paste")
			(net "PVDD11_S3_P1")
		)
		(pad "2" smd circle
			(at 0.40005 0)
			(size 0 0)
			(layers "F.Cu" "F.Mask" "F.Paste")
			(net "GND")
		)
	)
	(footprint ""
		(layer "F.Cu")
		(at 318.623696 -383.88163 -90)
		(property "Reference" "C912"
			(at 0 0 270)
			(layer "F.SilkS")
			(hide yes)
			(effects
				(font
					(size 1.27 1.27)
				)
			)
		)
		(property "Value" ""
			(at 0 0 270)
			(layer "F.Fab")
			(effects
				(font
					(size 1.27 1.27)
				)
			)
		)
		(duplicate_pad_numbers_are_jumpers no)
		(fp_line
			(start -0.299974 0.150114)
			(end -0.299974 -0.150114)
			(stroke
				(width 0.1)
				(type default)
			)
			(layer "F.Fab")
		)
		(fp_line
			(start 0.299974 0.150114)
			(end -0.299974 0.150114)
			(stroke
				(width 0.1)
				(type default)
			)
			(layer "F.Fab")
		)
		(fp_line
			(start -0.299974 -0.150114)
			(end 0.299974 -0.150114)
			(stroke
				(width 0.1)
				(type default)
			)
			(layer "F.Fab")
		)
		(fp_line
			(start 0.299974 -0.150114)
			(end 0.299974 0.150114)
			(stroke
				(width 0.1)
				(type default)
			)
			(layer "F.Fab")
		)
		(pad "1" smd rect
			(at -0.2667 0 270)
			(size 0.3048 0.381)
			(layers "F.Cu" "F.Mask" "F.Paste")
			(net "P5E_CPU0_P0_TX_C_DN<10>")
		)
		(pad "2" smd rect
			(at 0.2667 0 270)
			(size 0.3048 0.381)
			(layers "F.Cu" "F.Mask" "F.Paste")
			(net "P5E_CPU0_P0_TX_DN<10>")
		)
	)
	(footprint ""
		(layer "F.Cu")
		(at 193.954908 -153.774902)
		(property "Reference" "H126"
			(at 6.2738 -0.68453 0)
			(unlocked yes)
			(layer "F.SilkS")
			(effects
				(font
					(size 0.7874 0.5842)
					(thickness 0.1524)
				)
				(justify left)
			)
		)
		(property "Value" ""
			(at 0 0 0)
			(layer "F.Fab")
			(effects
				(font
					(size 1.27 1.27)
				)
			)
		)
		(duplicate_pad_numbers_are_jumpers no)
		(fp_circle
			(center 0 0)
			(end 5.8166 0)
			(stroke
				(width 0.1524)
				(type default)
			)
			(fill no)
			(layer "F.SilkS")
		)
		(fp_circle
			(center 0 0)
			(end 5.8166 0)
			(stroke
				(width 0.1524)
				(type default)
			)
			(fill no)
			(layer "B.SilkS")
		)
		(fp_circle
			(center 0 0)
			(end 5.8166 0)
			(stroke
				(width 0.1)
				(type default)
			)
			(fill no)
			(layer "B.Fab")
		)
		(fp_circle
			(center 0 0)
			(end 5.8166 0)
			(stroke
				(width 0.1)
				(type default)
			)
			(fill no)
			(layer "F.Fab")
		)
		(pad "" np_thru_hole circle
			(at 0 0)
			(size 10.0076 10.0076)
			(drill 10.0076)
			(layers "*.Cu" "*.Mask")
			(clearance 0.381)
			(thermal_gap 0.381)
		)
	)
	(footprint ""
		(layer "F.Cu")
		(at 101.760528 -36.25215 90)
		(property "Reference" "R6325"
			(at 0 0 90)
			(layer "F.SilkS")
			(hide yes)
			(effects
				(font
					(size 1.27 1.27)
				)
			)
		)
		(property "Value" ""
			(at 0 0 90)
			(layer "F.Fab")
			(effects
				(font
					(size 1.27 1.27)
				)
			)
		)
		(duplicate_pad_numbers_are_jumpers no)
		(fp_line
			(start 0.7874 -0.4064)
			(end 0.7874 0.4064)
			(stroke
				(width 0.1524)
				(type default)
			)
			(layer "F.SilkS")
		)
		(fp_line
			(start -0.7874 -0.4064)
			(end 0.7874 -0.4064)
			(stroke
				(width 0.1524)
				(type default)
			)
			(layer "F.SilkS")
		)
		(fp_line
			(start 0.7874 0.4064)
			(end -0.7874 0.4064)
			(stroke
				(width 0.1524)
				(type default)
			)
			(layer "F.SilkS")
		)
		(fp_line
			(start -0.7874 0.4064)
			(end -0.7874 -0.4064)
			(stroke
				(width 0.1524)
				(type default)
			)
			(layer "F.SilkS")
		)
		(fp_line
			(start -0.12065 -0.305054)
			(end -0.12065 -0.2794)
			(stroke
				(width 0.1)
				(type default)
			)
			(layer "F.Fab")
		)
		(fp_line
			(start -0.67945 -0.305054)
			(end -0.12065 -0.305054)
			(stroke
				(width 0.1)
				(type default)
			)
			(layer "F.Fab")
		)
		(fp_line
			(start 0.67945 -0.3048)
			(end 0.67945 0.3048)
			(stroke
				(width 0.1)
				(type default)
			)
			(layer "F.Fab")
		)
		(fp_line
			(start 0.12065 -0.3048)
			(end 0.67945 -0.3048)
			(stroke
				(width 0.1)
				(type default)
			)
			(layer "F.Fab")
		)
		(fp_line
			(start 0.12065 -0.2794)
			(end 0.12065 -0.3048)
			(stroke
				(width 0.1)
				(type default)
			)
			(layer "F.Fab")
		)
		(fp_line
			(start -0.12065 -0.2794)
			(end 0.12065 -0.2794)
			(stroke
				(width 0.1)
				(type default)
			)
			(layer "F.Fab")
		)
		(fp_line
			(start 0.120396 0.2794)
			(end -0.12065 0.2794)
			(stroke
				(width 0.1)
				(type default)
			)
			(layer "F.Fab")
		)
		(fp_line
			(start -0.12065 0.2794)
			(end -0.12065 0.3048)
			(stroke
				(width 0.1)
				(type default)
			)
			(layer "F.Fab")
		)
		(fp_line
			(start 0.67945 0.3048)
			(end 0.120396 0.3048)
			(stroke
				(width 0.1)
				(type default)
			)
			(layer "F.Fab")
		)
		(fp_line
			(start 0.120396 0.3048)
			(end 0.120396 0.2794)
			(stroke
				(width 0.1)
				(type default)
			)
			(layer "F.Fab")
		)
		(fp_line
			(start -0.12065 0.3048)
			(end -0.67945 0.3048)
			(stroke
				(width 0.1)
				(type default)
			)
			(layer "F.Fab")
		)
		(fp_line
			(start -0.67945 0.3048)
			(end -0.67945 -0.305054)
			(stroke
				(width 0.1)
				(type default)
			)
			(layer "F.Fab")
		)
		(pad "1" smd circle
			(at -0.40005 0 90)
			(size 0 0)
			(layers "F.Cu" "F.Mask" "F.Paste")
			(net "USB_HUB2_TI_TEST")
		)
		(pad "2" smd circle
			(at 0.40005 0 90)
			(size 0 0)
			(layers "F.Cu" "F.Mask" "F.Paste")
			(net "GND")
		)
	)
	(footprint ""
		(layer "F.Cu")
		(at 368.241326 -45.267118 -90)
		(property "Reference" "R816"
			(at 0 0 270)
			(layer "F.SilkS")
			(hide yes)
			(effects
				(font
					(size 1.27 1.27)
				)
			)
		)
		(property "Value" ""
			(at 0 0 270)
			(layer "F.Fab")
			(effects
				(font
					(size 1.27 1.27)
				)
			)
		)
		(duplicate_pad_numbers_are_jumpers no)
		(fp_line
			(start -0.7874 0.4064)
			(end -0.7874 -0.4064)
			(stroke
				(width 0.1524)
				(type default)
			)
			(layer "F.SilkS")
		)
		(fp_line
			(start 0.7874 0.4064)
			(end -0.7874 0.4064)
			(stroke
				(width 0.1524)
				(type default)
			)
			(layer "F.SilkS")
		)
		(fp_line
			(start -0.7874 -0.4064)
			(end 0.7874 -0.4064)
			(stroke
				(width 0.1524)
				(type default)
			)
			(layer "F.SilkS")
		)
		(fp_line
			(start 0.7874 -0.4064)
			(end 0.7874 0.4064)
			(stroke
				(width 0.1524)
				(type default)
			)
			(layer "F.SilkS")
		)
		(fp_line
			(start -0.67945 0.3048)
			(end -0.67945 -0.305054)
			(stroke
				(width 0.1)
				(type default)
			)
			(layer "F.Fab")
		)
		(fp_line
			(start -0.12065 0.3048)
			(end -0.67945 0.3048)
			(stroke
				(width 0.1)
				(type default)
			)
			(layer "F.Fab")
		)
		(fp_line
			(start 0.120396 0.3048)
			(end 0.120396 0.2794)
			(stroke
				(width 0.1)
				(type default)
			)
			(layer "F.Fab")
		)
		(fp_line
			(start 0.67945 0.3048)
			(end 0.120396 0.3048)
			(stroke
				(width 0.1)
				(type default)
			)
			(layer "F.Fab")
		)
		(fp_line
			(start -0.12065 0.2794)
			(end -0.12065 0.3048)
			(stroke
				(width 0.1)
				(type default)
			)
			(layer "F.Fab")
		)
		(fp_line
			(start 0.120396 0.2794)
			(end -0.12065 0.2794)
			(stroke
				(width 0.1)
				(type default)
			)
			(layer "F.Fab")
		)
		(fp_line
			(start -0.12065 -0.2794)
			(end 0.12065 -0.2794)
			(stroke
				(width 0.1)
				(type default)
			)
			(layer "F.Fab")
		)
		(fp_line
			(start 0.12065 -0.2794)
			(end 0.12065 -0.3048)
			(stroke
				(width 0.1)
				(type default)
			)
			(layer "F.Fab")
		)
		(fp_line
			(start 0.12065 -0.3048)
			(end 0.67945 -0.3048)
			(stroke
				(width 0.1)
				(type default)
			)
			(layer "F.Fab")
		)
		(fp_line
			(start 0.67945 -0.3048)
			(end 0.67945 0.3048)
			(stroke
				(width 0.1)
				(type default)
			)
			(layer "F.Fab")
		)
		(fp_line
			(start -0.67945 -0.305054)
			(end -0.12065 -0.305054)
			(stroke
				(width 0.1)
				(type default)
			)
			(layer "F.Fab")
		)
		(fp_line
			(start -0.12065 -0.305054)
			(end -0.12065 -0.2794)
			(stroke
				(width 0.1)
				(type default)
			)
			(layer "F.Fab")
		)
		(pad "1" smd circle
			(at -0.40005 0 270)
			(size 0 0)
			(layers "F.Cu" "F.Mask" "F.Paste")
			(net "PVDD18_S5_P0")
		)
		(pad "2" smd circle
			(at 0.40005 0 270)
			(size 0 0)
			(layers "F.Cu" "F.Mask" "F.Paste")
			(net "UART_CPU0_SCM_UART1_RX")
		)
	)
	(footprint ""
		(layer "F.Cu")
		(at 6.673088 -373.44985 -90)
		(property "Reference" "PC6632"
			(at 4.41452 2.228088 0)
			(unlocked yes)
			(layer "F.SilkS")
			(effects
				(font
					(size 0.7874 0.5842)
					(thickness 0.1524)
				)
				(justify left)
			)
		)
		(property "Value" ""
			(at 0 0 270)
			(layer "F.Fab")
			(effects
				(font
					(size 1.27 1.27)
				)
			)
		)
		(duplicate_pad_numbers_are_jumpers no)
		(fp_line
			(start -1.988058 2.750058)
			(end 2.750058 2.750058)
			(stroke
				(width 0.1524)
				(type default)
			)
			(layer "F.SilkS")
		)
		(fp_line
			(start 2.750058 2.750058)
			(end 2.750058 0.9398)
			(stroke
				(width 0.1524)
				(type default)
			)
			(layer "F.SilkS")
		)
		(fp_line
			(start -2.750058 1.988058)
			(end -1.988058 2.750058)
			(stroke
				(width 0.1524)
				(type default)
			)
			(layer "F.SilkS")
		)
		(fp_line
			(start -2.750058 0.9398)
			(end -2.750058 1.988058)
			(stroke
				(width 0.1524)
				(type default)
			)
			(layer "F.SilkS")
		)
		(fp_line
			(start 2.750058 -0.9398)
			(end 2.750058 -2.750058)
			(stroke
				(width 0.1524)
				(type default)
			)
			(layer "F.SilkS")
		)
		(fp_line
			(start -2.750058 -1.988058)
			(end -2.750058 -0.9398)
			(stroke
				(width 0.1524)
				(type default)
			)
			(layer "F.SilkS")
		)
		(fp_line
			(start -1.988058 -2.750058)
			(end -2.750058 -1.988058)
			(stroke
				(width 0.1524)
				(type default)
			)
			(layer "F.SilkS")
		)
		(fp_line
			(start 2.750058 -2.750058)
			(end -1.988058 -2.750058)
			(stroke
				(width 0.1524)
				(type default)
			)
			(layer "F.SilkS")
		)
		(fp_line
			(start -2.750058 2.750058)
			(end 2.750058 2.750058)
			(stroke
				(width 0.1)
				(type default)
			)
			(layer "F.Fab")
		)
		(fp_line
			(start 2.750058 2.750058)
			(end 2.750058 -2.750058)
			(stroke
				(width 0.1)
				(type default)
			)
			(layer "F.Fab")
		)
		(fp_line
			(start -2.750058 -2.750058)
			(end -2.750058 2.750058)
			(stroke
				(width 0.1)
				(type default)
			)
			(layer "F.Fab")
		)
		(fp_line
			(start 2.750058 -2.750058)
			(end -2.750058 -2.750058)
			(stroke
				(width 0.1)
				(type default)
			)
			(layer "F.Fab")
		)
		(pad "1" smd rect
			(at -2.199894 0)
			(size 1.6002 3.0226)
			(layers "F.Cu" "F.Mask" "F.Paste")
			(net "P0V9_CPU1_RT_2D")
		)
		(pad "2" smd rect
			(at 2.199894 0)
			(size 1.6002 3.0226)
			(layers "F.Cu" "F.Mask" "F.Paste")
			(net "GND")
		)
	)
	(footprint ""
		(layer "F.Cu")
		(at 353.900232 -260.305042)
		(property "Reference" "C2141"
			(at 0 0 0)
			(layer "F.SilkS")
			(hide yes)
			(effects
				(font
					(size 1.27 1.27)
				)
			)
		)
		(property "Value" ""
			(at 0 0 0)
			(layer "F.Fab")
			(effects
				(font
					(size 1.27 1.27)
				)
			)
		)
		(duplicate_pad_numbers_are_jumpers no)
		(fp_line
			(start -0.7874 -0.4064)
			(end 0.7874 -0.4064)
			(stroke
				(width 0.1524)
				(type default)
			)
			(layer "F.SilkS")
		)
		(fp_line
			(start -0.7874 0.4064)
			(end -0.7874 -0.4064)
			(stroke
				(width 0.1524)
				(type default)
			)
			(layer "F.SilkS")
		)
		(fp_line
			(start 0.7874 -0.4064)
			(end 0.7874 0.4064)
			(stroke
				(width 0.1524)
				(type default)
			)
			(layer "F.SilkS")
		)
		(fp_line
			(start 0.7874 0.4064)
			(end -0.7874 0.4064)
			(stroke
				(width 0.1524)
				(type default)
			)
			(layer "F.SilkS")
		)
		(fp_line
			(start -0.67945 -0.305054)
			(end -0.12065 -0.305054)
			(stroke
				(width 0.1)
				(type default)
			)
			(layer "F.Fab")
		)
		(fp_line
			(start -0.67945 0.3048)
			(end -0.67945 -0.305054)
			(stroke
				(width 0.1)
				(type default)
			)
			(layer "F.Fab")
		)
		(fp_line
			(start -0.12065 -0.305054)
			(end -0.12065 -0.2794)
			(stroke
				(width 0.1)
				(type default)
			)
			(layer "F.Fab")
		)
		(fp_line
			(start -0.12065 -0.2794)
			(end 0.12065 -0.2794)
			(stroke
				(width 0.1)
				(type default)
			)
			(layer "F.Fab")
		)
		(fp_line
			(start -0.12065 0.2794)
			(end -0.12065 0.3048)
			(stroke
				(width 0.1)
				(type default)
			)
			(layer "F.Fab")
		)
		(fp_line
			(start -0.12065 0.3048)
			(end -0.67945 0.3048)
			(stroke
				(width 0.1)
				(type default)
			)
			(layer "F.Fab")
		)
		(fp_line
			(start 0.120396 0.2794)
			(end -0.12065 0.2794)
			(stroke
				(width 0.1)
				(type default)
			)
			(layer "F.Fab")
		)
		(fp_line
			(start 0.120396 0.3048)
			(end 0.120396 0.2794)
			(stroke
				(width 0.1)
				(type default)
			)
			(layer "F.Fab")
		)
		(fp_line
			(start 0.12065 -0.3048)
			(end 0.67945 -0.3048)
			(stroke
				(width 0.1)
				(type default)
			)
			(layer "F.Fab")
		)
		(fp_line
			(start 0.12065 -0.2794)
			(end 0.12065 -0.3048)
			(stroke
				(width 0.1)
				(type default)
			)
			(layer "F.Fab")
		)
		(fp_line
			(start 0.67945 -0.3048)
			(end 0.67945 0.3048)
			(stroke
				(width 0.1)
				(type default)
			)
			(layer "F.Fab")
		)
		(fp_line
			(start 0.67945 0.3048)
			(end 0.120396 0.3048)
			(stroke
				(width 0.1)
				(type default)
			)
			(layer "F.Fab")
		)
		(pad "1" smd circle
			(at -0.40005 0)
			(size 0 0)
			(layers "F.Cu" "F.Mask" "F.Paste")
			(net "PVDDIO_P0")
		)
		(pad "2" smd circle
			(at 0.40005 0)
			(size 0 0)
			(layers "F.Cu" "F.Mask" "F.Paste")
			(net "GND")
		)
	)
	(footprint ""
		(layer "F.Cu")
		(at 146.27479 -57.275984 -90)
		(property "Reference" "U147"
			(at 1.504188 2.769108 90)
			(unlocked yes)
			(layer "F.SilkS")
			(effects
				(font
					(size 0.7874 0.5842)
					(thickness 0.1524)
				)
				(justify left)
			)
		)
		(property "Value" ""
			(at 0 0 270)
			(layer "F.Fab")
			(effects
				(font
					(size 1.27 1.27)
				)
			)
		)
		(duplicate_pad_numbers_are_jumpers no)
		(fp_line
			(start -1.245616 1.445768)
			(end -1.245616 -1.445768)
			(stroke
				(width 0.1524)
				(type default)
			)
			(layer "F.SilkS")
		)
		(fp_line
			(start 1.245616 1.445768)
			(end -1.245616 1.445768)
			(stroke
				(width 0.1524)
				(type default)
			)
			(layer "F.SilkS")
		)
		(fp_line
			(start -1.245616 -1.445768)
			(end 1.245616 -1.445768)
			(stroke
				(width 0.1524)
				(type default)
			)
			(layer "F.SilkS")
		)
		(fp_line
			(start 1.245616 -1.445768)
			(end 1.245616 1.445768)
			(stroke
				(width 0.1524)
				(type default)
			)
			(layer "F.SilkS")
		)
		(fp_poly
			(pts
				(xy -1.386586 -0.199898) (xy -1.894586 0.054102) (xy -1.894586 -0.453898)
			)
			(stroke
				(width 0)
				(type default)
			)
			(fill yes)
			(layer "F.SilkS")
		)
		(fp_line
			(start -0.724916 0.925068)
			(end -0.724916 -0.925068)
			(stroke
				(width 0.1)
				(type default)
			)
			(layer "F.Fab")
		)
		(fp_line
			(start 0.724916 0.925068)
			(end -0.724916 0.925068)
			(stroke
				(width 0.1)
				(type default)
			)
			(layer "F.Fab")
		)
		(fp_line
			(start -0.724916 -0.925068)
			(end 0.724916 -0.925068)
			(stroke
				(width 0.1)
				(type default)
			)
			(layer "F.Fab")
		)
		(fp_line
			(start 0.724916 -0.925068)
			(end 0.724916 0.925068)
			(stroke
				(width 0.1)
				(type default)
			)
			(layer "F.Fab")
		)
		(fp_poly
			(pts
				(xy -1.894586 -0.453898) (xy -1.894586 0.054102) (xy -1.386586 -0.199898)
			)
			(stroke
				(width 0)
				(type default)
			)
			(fill yes)
			(layer "F.Fab")
		)
		(pad "1" smd circle
			(at -0.649986 -0.199898 180)
			(size 0 0)
			(layers "F.Cu" "F.Mask" "F.Paste")
			(net "GND")
		)
		(pad "2" smd rect
			(at -0.700024 0.199898)
			(size 0.1778 0.8128)
			(layers "F.Cu" "F.Mask" "F.Paste")
			(net "JTAG_BMC_OE_N")
		)
		(pad "3" smd rect
			(at -0.40005 0.899922 270)
			(size 0.1778 0.8128)
			(layers "F.Cu" "F.Mask" "F.Paste")
			(net "GND")
		)
		(pad "4" smd rect
			(at 0 0.899922 270)
			(size 0.1778 0.8128)
			(layers "F.Cu" "F.Mask" "F.Paste")
			(net "JTAG_TDO_R1")
		)
		(pad "5" smd rect
			(at 0.40005 0.899922 270)
			(size 0.1778 0.8128)
			(layers "F.Cu" "F.Mask" "F.Paste")
			(net "JTAG_TDI_R")
		)
		(pad "6" smd rect
			(at 0.700024 0.199898 180)
			(size 0.1778 0.8128)
			(layers "F.Cu" "F.Mask" "F.Paste")
			(net "PVDD18_S5_P0")
		)
		(pad "7" smd rect
			(at 0.700024 -0.199898 180)
			(size 0.1778 0.8128)
			(layers "F.Cu" "F.Mask" "F.Paste")
			(net "P3V3_AUX")
		)
		(pad "8" smd rect
			(at 0.40005 -0.899922 270)
			(size 0.1778 0.8128)
			(layers "F.Cu" "F.Mask" "F.Paste")
			(net "JTAG_SCM_MUX_TDO")
		)
		(pad "9" smd rect
			(at 0 -0.899922 270)
			(size 0.1778 0.8128)
			(layers "F.Cu" "F.Mask" "F.Paste")
			(net "JTAG_SCM_MUX_TDI")
		)
		(pad "10" smd rect
			(at -0.40005 -0.912622 270)
			(size 0.1778 0.7874)
			(layers "F.Cu" "F.Mask" "F.Paste")
			(net "P3V3_AUX")
		)
	)
	(footprint ""
		(layer "F.Cu")
		(at 392.962384 -392.48588 180)
		(property "Reference" "R1086"
			(at 0 0 180)
			(layer "F.SilkS")
			(hide yes)
			(effects
				(font
					(size 1.27 1.27)
				)
			)
		)
		(property "Value" ""
			(at 0 0 180)
			(layer "F.Fab")
			(effects
				(font
					(size 1.27 1.27)
				)
			)
		)
		(duplicate_pad_numbers_are_jumpers no)
		(fp_line
			(start 0.7874 0.4064)
			(end -0.7874 0.4064)
			(stroke
				(width 0.1524)
				(type default)
			)
			(layer "F.SilkS")
		)
		(fp_line
			(start 0.7874 -0.4064)
			(end 0.7874 0.4064)
			(stroke
				(width 0.1524)
				(type default)
			)
			(layer "F.SilkS")
		)
		(fp_line
			(start -0.7874 0.4064)
			(end -0.7874 -0.4064)
			(stroke
				(width 0.1524)
				(type default)
			)
			(layer "F.SilkS")
		)
		(fp_line
			(start -0.7874 -0.4064)
			(end 0.7874 -0.4064)
			(stroke
				(width 0.1524)
				(type default)
			)
			(layer "F.SilkS")
		)
		(fp_line
			(start 0.67945 0.3048)
			(end 0.120396 0.3048)
			(stroke
				(width 0.1)
				(type default)
			)
			(layer "F.Fab")
		)
		(fp_line
			(start 0.67945 -0.3048)
			(end 0.67945 0.3048)
			(stroke
				(width 0.1)
				(type default)
			)
			(layer "F.Fab")
		)
		(fp_line
			(start 0.12065 -0.2794)
			(end 0.12065 -0.3048)
			(stroke
				(width 0.1)
				(type default)
			)
			(layer "F.Fab")
		)
		(fp_line
			(start 0.12065 -0.3048)
			(end 0.67945 -0.3048)
			(stroke
				(width 0.1)
				(type default)
			)
			(layer "F.Fab")
		)
		(fp_line
			(start 0.120396 0.3048)
			(end 0.120396 0.2794)
			(stroke
				(width 0.1)
				(type default)
			)
			(layer "F.Fab")
		)
		(fp_line
			(start 0.120396 0.2794)
			(end -0.12065 0.2794)
			(stroke
				(width 0.1)
				(type default)
			)
			(layer "F.Fab")
		)
		(fp_line
			(start -0.12065 0.3048)
			(end -0.67945 0.3048)
			(stroke
				(width 0.1)
				(type default)
			)
			(layer "F.Fab")
		)
		(fp_line
			(start -0.12065 0.2794)
			(end -0.12065 0.3048)
			(stroke
				(width 0.1)
				(type default)
			)
			(layer "F.Fab")
		)
		(fp_line
			(start -0.12065 -0.2794)
			(end 0.12065 -0.2794)
			(stroke
				(width 0.1)
				(type default)
			)
			(layer "F.Fab")
		)
		(fp_line
			(start -0.12065 -0.305054)
			(end -0.12065 -0.2794)
			(stroke
				(width 0.1)
				(type default)
			)
			(layer "F.Fab")
		)
		(fp_line
			(start -0.67945 0.3048)
			(end -0.67945 -0.305054)
			(stroke
				(width 0.1)
				(type default)
			)
			(layer "F.Fab")
		)
		(fp_line
			(start -0.67945 -0.305054)
			(end -0.12065 -0.305054)
			(stroke
				(width 0.1)
				(type default)
			)
			(layer "F.Fab")
		)
		(pad "1" smd rect
			(at -0.40005 0)
			(size 0.4572 0.508)
			(layers "F.Cu" "F.Mask" "F.Paste")
			(net "P1V8_CPU0_RT3_1A_1D")
		)
		(pad "2" smd rect
			(at 0.40005 0)
			(size 0.4572 0.508)
			(layers "F.Cu" "F.Mask" "F.Paste")
			(net "P1V8_CPU0_RT3_1A")
		)
	)
	(footprint ""
		(layer "F.Cu")
		(at 103.185722 -28.422854 -90)
		(property "Reference" "R346"
			(at 0 0 270)
			(layer "F.SilkS")
			(hide yes)
			(effects
				(font
					(size 1.27 1.27)
				)
			)
		)
		(property "Value" ""
			(at 0 0 270)
			(layer "F.Fab")
			(effects
				(font
					(size 1.27 1.27)
				)
			)
		)
		(duplicate_pad_numbers_are_jumpers no)
		(fp_line
			(start -0.32512 0.175006)
			(end -0.32512 -0.175006)
			(stroke
				(width 0.1)
				(type default)
			)
			(layer "F.Fab")
		)
		(fp_line
			(start 0.32512 0.175006)
			(end -0.32512 0.175006)
			(stroke
				(width 0.1)
				(type default)
			)
			(layer "F.Fab")
		)
		(fp_line
			(start -0.32512 -0.175006)
			(end 0.32512 -0.175006)
			(stroke
				(width 0.1)
				(type default)
			)
			(layer "F.Fab")
		)
		(fp_line
			(start 0.32512 -0.175006)
			(end 0.32512 0.175006)
			(stroke
				(width 0.1)
				(type default)
			)
			(layer "F.Fab")
		)
		(pad "1" smd rect
			(at -0.2667 0 270)
			(size 0.3048 0.381)
			(layers "F.Cu" "F.Mask" "F.Paste")
			(net "USB3_CPU0_BMC_TX_C2_DN")
		)
		(pad "2" smd rect
			(at 0.2667 0 90)
			(size 0.3048 0.381)
			(layers "F.Cu" "F.Mask" "F.Paste")
			(net "GND")
		)
	)
	(footprint ""
		(layer "F.Cu")
		(at 432.2572 -17.624298 90)
		(property "Reference" "C1578"
			(at 0 0 90)
			(layer "F.SilkS")
			(hide yes)
			(effects
				(font
					(size 1.27 1.27)
				)
			)
		)
		(property "Value" ""
			(at 0 0 90)
			(layer "F.Fab")
			(effects
				(font
					(size 1.27 1.27)
				)
			)
		)
		(duplicate_pad_numbers_are_jumpers no)
		(fp_line
			(start 0.299974 -0.150114)
			(end 0.299974 0.150114)
			(stroke
				(width 0.1)
				(type default)
			)
			(layer "F.Fab")
		)
		(fp_line
			(start -0.299974 -0.150114)
			(end 0.299974 -0.150114)
			(stroke
				(width 0.1)
				(type default)
			)
			(layer "F.Fab")
		)
		(fp_line
			(start 0.299974 0.150114)
			(end -0.299974 0.150114)
			(stroke
				(width 0.1)
				(type default)
			)
			(layer "F.Fab")
		)
		(fp_line
			(start -0.299974 0.150114)
			(end -0.299974 -0.150114)
			(stroke
				(width 0.1)
				(type default)
			)
			(layer "F.Fab")
		)
		(pad "1" smd rect
			(at -0.2667 0 90)
			(size 0.3048 0.381)
			(layers "F.Cu" "F.Mask" "F.Paste")
			(net "P5E_CPU0_G3_TX_C_DN<0>")
		)
		(pad "2" smd rect
			(at 0.2667 0 90)
			(size 0.3048 0.381)
			(layers "F.Cu" "F.Mask" "F.Paste")
			(net "P5E_CPU0_G3_TX_DN<0>")
		)
	)
	(footprint ""
		(layer "F.Cu")
		(at 417.33724 -383.88163 -90)
		(property "Reference" "C849"
			(at 0 0 270)
			(layer "F.SilkS")
			(hide yes)
			(effects
				(font
					(size 1.27 1.27)
				)
			)
		)
		(property "Value" ""
			(at 0 0 270)
			(layer "F.Fab")
			(effects
				(font
					(size 1.27 1.27)
				)
			)
		)
		(duplicate_pad_numbers_are_jumpers no)
		(fp_line
			(start -0.299974 0.150114)
			(end -0.299974 -0.150114)
			(stroke
				(width 0.1)
				(type default)
			)
			(layer "F.Fab")
		)
		(fp_line
			(start 0.299974 0.150114)
			(end -0.299974 0.150114)
			(stroke
				(width 0.1)
				(type default)
			)
			(layer "F.Fab")
		)
		(fp_line
			(start -0.299974 -0.150114)
			(end 0.299974 -0.150114)
			(stroke
				(width 0.1)
				(type default)
			)
			(layer "F.Fab")
		)
		(fp_line
			(start 0.299974 -0.150114)
			(end 0.299974 0.150114)
			(stroke
				(width 0.1)
				(type default)
			)
			(layer "F.Fab")
		)
		(pad "1" smd rect
			(at -0.2667 0 270)
			(size 0.3048 0.381)
			(layers "F.Cu" "F.Mask" "F.Paste")
			(net "P5E_CPU0_P2_TX_C_DP<10>")
		)
		(pad "2" smd rect
			(at 0.2667 0 270)
			(size 0.3048 0.381)
			(layers "F.Cu" "F.Mask" "F.Paste")
			(net "P5E_CPU0_P2_TX_DP<10>")
		)
	)
	(footprint ""
		(layer "F.Cu")
		(at 8.406384 -381.562356)
		(property "Reference" "PR6602"
			(at 0 0 0)
			(layer "F.SilkS")
			(hide yes)
			(effects
				(font
					(size 1.27 1.27)
				)
			)
		)
		(property "Value" ""
			(at 0 0 0)
			(layer "F.Fab")
			(effects
				(font
					(size 1.27 1.27)
				)
			)
		)
		(duplicate_pad_numbers_are_jumpers no)
		(fp_line
			(start -0.7874 -0.4064)
			(end 0.7874 -0.4064)
			(stroke
				(width 0.1524)
				(type default)
			)
			(layer "F.SilkS")
		)
		(fp_line
			(start -0.7874 0.4064)
			(end -0.7874 -0.4064)
			(stroke
				(width 0.1524)
				(type default)
			)
			(layer "F.SilkS")
		)
		(fp_line
			(start 0.7874 -0.4064)
			(end 0.7874 0.4064)
			(stroke
				(width 0.1524)
				(type default)
			)
			(layer "F.SilkS")
		)
		(fp_line
			(start 0.7874 0.4064)
			(end -0.7874 0.4064)
			(stroke
				(width 0.1524)
				(type default)
			)
			(layer "F.SilkS")
		)
		(fp_line
			(start -0.67945 -0.305054)
			(end -0.12065 -0.305054)
			(stroke
				(width 0.1)
				(type default)
			)
			(layer "F.Fab")
		)
		(fp_line
			(start -0.67945 0.3048)
			(end -0.67945 -0.305054)
			(stroke
				(width 0.1)
				(type default)
			)
			(layer "F.Fab")
		)
		(fp_line
			(start -0.12065 -0.305054)
			(end -0.12065 -0.2794)
			(stroke
				(width 0.1)
				(type default)
			)
			(layer "F.Fab")
		)
		(fp_line
			(start -0.12065 -0.2794)
			(end 0.12065 -0.2794)
			(stroke
				(width 0.1)
				(type default)
			)
			(layer "F.Fab")
		)
		(fp_line
			(start -0.12065 0.2794)
			(end -0.12065 0.3048)
			(stroke
				(width 0.1)
				(type default)
			)
			(layer "F.Fab")
		)
		(fp_line
			(start -0.12065 0.3048)
			(end -0.67945 0.3048)
			(stroke
				(width 0.1)
				(type default)
			)
			(layer "F.Fab")
		)
		(fp_line
			(start 0.120396 0.2794)
			(end -0.12065 0.2794)
			(stroke
				(width 0.1)
				(type default)
			)
			(layer "F.Fab")
		)
		(fp_line
			(start 0.120396 0.3048)
			(end 0.120396 0.2794)
			(stroke
				(width 0.1)
				(type default)
			)
			(layer "F.Fab")
		)
		(fp_line
			(start 0.12065 -0.3048)
			(end 0.67945 -0.3048)
			(stroke
				(width 0.1)
				(type default)
			)
			(layer "F.Fab")
		)
		(fp_line
			(start 0.12065 -0.2794)
			(end 0.12065 -0.3048)
			(stroke
				(width 0.1)
				(type default)
			)
			(layer "F.Fab")
		)
		(fp_line
			(start 0.67945 -0.3048)
			(end 0.67945 0.3048)
			(stroke
				(width 0.1)
				(type default)
			)
			(layer "F.Fab")
		)
		(fp_line
			(start 0.67945 0.3048)
			(end 0.120396 0.3048)
			(stroke
				(width 0.1)
				(type default)
			)
			(layer "F.Fab")
		)
		(pad "1" smd circle
			(at -0.40005 0)
			(size 0 0)
			(layers "F.Cu" "F.Mask" "F.Paste")
			(net "P0V9_RETIMER_CPU1_SENSE_SH_N")
		)
		(pad "2" smd circle
			(at 0.40005 0)
			(size 0 0)
			(layers "F.Cu" "F.Mask" "F.Paste")
			(net "GND")
		)
	)
	(footprint ""
		(layer "F.Cu")
		(at 386.211826 -63.3095 180)
		(property "Reference" "R1629"
			(at 0 0 180)
			(layer "F.SilkS")
			(hide yes)
			(effects
				(font
					(size 1.27 1.27)
				)
			)
		)
		(property "Value" ""
			(at 0 0 180)
			(layer "F.Fab")
			(effects
				(font
					(size 1.27 1.27)
				)
			)
		)
		(duplicate_pad_numbers_are_jumpers no)
		(fp_line
			(start 0.7874 0.4064)
			(end -0.7874 0.4064)
			(stroke
				(width 0.1524)
				(type default)
			)
			(layer "F.SilkS")
		)
		(fp_line
			(start 0.7874 -0.4064)
			(end 0.7874 0.4064)
			(stroke
				(width 0.1524)
				(type default)
			)
			(layer "F.SilkS")
		)
		(fp_line
			(start -0.7874 0.4064)
			(end -0.7874 -0.4064)
			(stroke
				(width 0.1524)
				(type default)
			)
			(layer "F.SilkS")
		)
		(fp_line
			(start -0.7874 -0.4064)
			(end 0.7874 -0.4064)
			(stroke
				(width 0.1524)
				(type default)
			)
			(layer "F.SilkS")
		)
		(fp_line
			(start 0.67945 0.3048)
			(end 0.120396 0.3048)
			(stroke
				(width 0.1)
				(type default)
			)
			(layer "F.Fab")
		)
		(fp_line
			(start 0.67945 -0.3048)
			(end 0.67945 0.3048)
			(stroke
				(width 0.1)
				(type default)
			)
			(layer "F.Fab")
		)
		(fp_line
			(start 0.12065 -0.2794)
			(end 0.12065 -0.3048)
			(stroke
				(width 0.1)
				(type default)
			)
			(layer "F.Fab")
		)
		(fp_line
			(start 0.12065 -0.3048)
			(end 0.67945 -0.3048)
			(stroke
				(width 0.1)
				(type default)
			)
			(layer "F.Fab")
		)
		(fp_line
			(start 0.120396 0.3048)
			(end 0.120396 0.2794)
			(stroke
				(width 0.1)
				(type default)
			)
			(layer "F.Fab")
		)
		(fp_line
			(start 0.120396 0.2794)
			(end -0.12065 0.2794)
			(stroke
				(width 0.1)
				(type default)
			)
			(layer "F.Fab")
		)
		(fp_line
			(start -0.12065 0.3048)
			(end -0.67945 0.3048)
			(stroke
				(width 0.1)
				(type default)
			)
			(layer "F.Fab")
		)
		(fp_line
			(start -0.12065 0.2794)
			(end -0.12065 0.3048)
			(stroke
				(width 0.1)
				(type default)
			)
			(layer "F.Fab")
		)
		(fp_line
			(start -0.12065 -0.2794)
			(end 0.12065 -0.2794)
			(stroke
				(width 0.1)
				(type default)
			)
			(layer "F.Fab")
		)
		(fp_line
			(start -0.12065 -0.305054)
			(end -0.12065 -0.2794)
			(stroke
				(width 0.1)
				(type default)
			)
			(layer "F.Fab")
		)
		(fp_line
			(start -0.67945 0.3048)
			(end -0.67945 -0.305054)
			(stroke
				(width 0.1)
				(type default)
			)
			(layer "F.Fab")
		)
		(fp_line
			(start -0.67945 -0.305054)
			(end -0.12065 -0.305054)
			(stroke
				(width 0.1)
				(type default)
			)
			(layer "F.Fab")
		)
		(pad "1" smd circle
			(at -0.40005 0 180)
			(size 0 0)
			(layers "F.Cu" "F.Mask" "F.Paste")
			(net "HDT_CPU0_HDT_CONN_TESTEN")
		)
		(pad "2" smd circle
			(at 0.40005 0 180)
			(size 0 0)
			(layers "F.Cu" "F.Mask" "F.Paste")
			(net "GND")
		)
	)
	(footprint ""
		(layer "F.Cu")
		(at 103.998522 -33.185354 90)
		(property "Reference" "R343"
			(at 0 0 90)
			(layer "F.SilkS")
			(hide yes)
			(effects
				(font
					(size 1.27 1.27)
				)
			)
		)
		(property "Value" ""
			(at 0 0 90)
			(layer "F.Fab")
			(effects
				(font
					(size 1.27 1.27)
				)
			)
		)
		(duplicate_pad_numbers_are_jumpers no)
		(fp_line
			(start 0.32512 -0.175006)
			(end 0.32512 0.175006)
			(stroke
				(width 0.1)
				(type default)
			)
			(layer "F.Fab")
		)
		(fp_line
			(start -0.32512 -0.175006)
			(end 0.32512 -0.175006)
			(stroke
				(width 0.1)
				(type default)
			)
			(layer "F.Fab")
		)
		(fp_line
			(start 0.32512 0.175006)
			(end -0.32512 0.175006)
			(stroke
				(width 0.1)
				(type default)
			)
			(layer "F.Fab")
		)
		(fp_line
			(start -0.32512 0.175006)
			(end -0.32512 -0.175006)
			(stroke
				(width 0.1)
				(type default)
			)
			(layer "F.Fab")
		)
		(pad "1" smd rect
			(at -0.2667 0 90)
			(size 0.3048 0.381)
			(layers "F.Cu" "F.Mask" "F.Paste")
			(net "USB2_CPU0_P0_R2_DP")
		)
		(pad "2" smd rect
			(at 0.2667 0 270)
			(size 0.3048 0.381)
			(layers "F.Cu" "F.Mask" "F.Paste")
			(net "GND")
		)
	)
	(footprint ""
		(layer "F.Cu")
		(at 130.511296 -373.03583 -90)
		(property "Reference" "C1525"
			(at 0 0 270)
			(layer "F.SilkS")
			(hide yes)
			(effects
				(font
					(size 1.27 1.27)
				)
			)
		)
		(property "Value" ""
			(at 0 0 270)
			(layer "F.Fab")
			(effects
				(font
					(size 1.27 1.27)
				)
			)
		)
		(duplicate_pad_numbers_are_jumpers no)
		(fp_line
			(start -0.299974 0.150114)
			(end -0.299974 -0.150114)
			(stroke
				(width 0.1)
				(type default)
			)
			(layer "F.Fab")
		)
		(fp_line
			(start 0.299974 0.150114)
			(end -0.299974 0.150114)
			(stroke
				(width 0.1)
				(type default)
			)
			(layer "F.Fab")
		)
		(fp_line
			(start -0.299974 -0.150114)
			(end 0.299974 -0.150114)
			(stroke
				(width 0.1)
				(type default)
			)
			(layer "F.Fab")
		)
		(fp_line
			(start 0.299974 -0.150114)
			(end 0.299974 0.150114)
			(stroke
				(width 0.1)
				(type default)
			)
			(layer "F.Fab")
		)
		(pad "1" smd rect
			(at -0.2667 0 270)
			(size 0.3048 0.381)
			(layers "F.Cu" "F.Mask" "F.Paste")
			(net "P5E_CPU1_P3_TX_C_DP<11>")
		)
		(pad "2" smd rect
			(at 0.2667 0 270)
			(size 0.3048 0.381)
			(layers "F.Cu" "F.Mask" "F.Paste")
			(net "P5E_CPU1_P3_TX_DP<11>")
		)
	)
	(footprint ""
		(layer "F.Cu")
		(at 49.860454 -349.386398 90)
		(property "Reference" "PC433"
			(at 0 0 90)
			(layer "F.SilkS")
			(hide yes)
			(effects
				(font
					(size 1.27 1.27)
				)
			)
		)
		(property "Value" ""
			(at 0 0 90)
			(layer "F.Fab")
			(effects
				(font
					(size 1.27 1.27)
				)
			)
		)
		(duplicate_pad_numbers_are_jumpers no)
		(fp_line
			(start 0.7874 -0.4064)
			(end 0.7874 0.4064)
			(stroke
				(width 0.1524)
				(type default)
			)
			(layer "F.SilkS")
		)
		(fp_line
			(start -0.7874 -0.4064)
			(end 0.7874 -0.4064)
			(stroke
				(width 0.1524)
				(type default)
			)
			(layer "F.SilkS")
		)
		(fp_line
			(start 0.7874 0.4064)
			(end 0.447802 0.4064)
			(stroke
				(width 0.1524)
				(type default)
			)
			(layer "F.SilkS")
		)
		(fp_line
			(start -0.263398 0.4064)
			(end -0.7874 0.4064)
			(stroke
				(width 0.1524)
				(type default)
			)
			(layer "F.SilkS")
		)
		(fp_line
			(start -0.7874 0.4064)
			(end -0.7874 -0.4064)
			(stroke
				(width 0.1524)
				(type default)
			)
			(layer "F.SilkS")
		)
		(fp_line
			(start -0.12065 -0.305054)
			(end -0.12065 -0.2794)
			(stroke
				(width 0.1)
				(type default)
			)
			(layer "F.Fab")
		)
		(fp_line
			(start -0.67945 -0.305054)
			(end -0.12065 -0.305054)
			(stroke
				(width 0.1)
				(type default)
			)
			(layer "F.Fab")
		)
		(fp_line
			(start 0.67945 -0.3048)
			(end 0.67945 0.3048)
			(stroke
				(width 0.1)
				(type default)
			)
			(layer "F.Fab")
		)
		(fp_line
			(start 0.12065 -0.3048)
			(end 0.67945 -0.3048)
			(stroke
				(width 0.1)
				(type default)
			)
			(layer "F.Fab")
		)
		(fp_line
			(start 0.12065 -0.2794)
			(end 0.12065 -0.3048)
			(stroke
				(width 0.1)
				(type default)
			)
			(layer "F.Fab")
		)
		(fp_line
			(start -0.12065 -0.2794)
			(end 0.12065 -0.2794)
			(stroke
				(width 0.1)
				(type default)
			)
			(layer "F.Fab")
		)
		(fp_line
			(start 0.120396 0.2794)
			(end -0.12065 0.2794)
			(stroke
				(width 0.1)
				(type default)
			)
			(layer "F.Fab")
		)
		(fp_line
			(start -0.12065 0.2794)
			(end -0.12065 0.3048)
			(stroke
				(width 0.1)
				(type default)
			)
			(layer "F.Fab")
		)
		(fp_line
			(start 0.67945 0.3048)
			(end 0.120396 0.3048)
			(stroke
				(width 0.1)
				(type default)
			)
			(layer "F.Fab")
		)
		(fp_line
			(start 0.120396 0.3048)
			(end 0.120396 0.2794)
			(stroke
				(width 0.1)
				(type default)
			)
			(layer "F.Fab")
		)
		(fp_line
			(start -0.12065 0.3048)
			(end -0.67945 0.3048)
			(stroke
				(width 0.1)
				(type default)
			)
			(layer "F.Fab")
		)
		(fp_line
			(start -0.67945 0.3048)
			(end -0.67945 -0.305054)
			(stroke
				(width 0.1)
				(type default)
			)
			(layer "F.Fab")
		)
		(pad "1" smd circle
			(at -0.40005 0 90)
			(size 0 0)
			(layers "F.Cu" "F.Mask" "F.Paste")
			(net "PVDDIO_P1_VCC1")
		)
		(pad "2" smd circle
			(at 0.40005 0 90)
			(size 0 0)
			(layers "F.Cu" "F.Mask" "F.Paste")
			(net "GND")
		)
	)
	(footprint ""
		(layer "F.Cu")
		(at 145.233644 -370.57203 -90)
		(property "Reference" "C766"
			(at 0 0 270)
			(layer "F.SilkS")
			(hide yes)
			(effects
				(font
					(size 1.27 1.27)
				)
			)
		)
		(property "Value" ""
			(at 0 0 270)
			(layer "F.Fab")
			(effects
				(font
					(size 1.27 1.27)
				)
			)
		)
		(duplicate_pad_numbers_are_jumpers no)
		(fp_line
			(start -0.299974 0.150114)
			(end -0.299974 -0.150114)
			(stroke
				(width 0.1)
				(type default)
			)
			(layer "F.Fab")
		)
		(fp_line
			(start 0.299974 0.150114)
			(end -0.299974 0.150114)
			(stroke
				(width 0.1)
				(type default)
			)
			(layer "F.Fab")
		)
		(fp_line
			(start -0.299974 -0.150114)
			(end 0.299974 -0.150114)
			(stroke
				(width 0.1)
				(type default)
			)
			(layer "F.Fab")
		)
		(fp_line
			(start 0.299974 -0.150114)
			(end 0.299974 0.150114)
			(stroke
				(width 0.1)
				(type default)
			)
			(layer "F.Fab")
		)
		(pad "1" smd rect
			(at -0.2667 0 270)
			(size 0.3048 0.381)
			(layers "F.Cu" "F.Mask" "F.Paste")
			(net "P5E_CPU1_P2_TX_C_DN<3>")
		)
		(pad "2" smd rect
			(at 0.2667 0 270)
			(size 0.3048 0.381)
			(layers "F.Cu" "F.Mask" "F.Paste")
			(net "P5E_CPU1_P2_TX_DN<3>")
		)
	)
	(footprint ""
		(layer "F.Cu")
		(at 29.045662 -424.259502)
		(property "Reference" "R3277"
			(at 0 0 0)
			(layer "F.SilkS")
			(hide yes)
			(effects
				(font
					(size 1.27 1.27)
				)
			)
		)
		(property "Value" ""
			(at 0 0 0)
			(layer "F.Fab")
			(effects
				(font
					(size 1.27 1.27)
				)
			)
		)
		(duplicate_pad_numbers_are_jumpers no)
		(fp_line
			(start -0.7874 -0.4064)
			(end 0.7874 -0.4064)
			(stroke
				(width 0.1524)
				(type default)
			)
			(layer "F.SilkS")
		)
		(fp_line
			(start -0.7874 0.4064)
			(end -0.7874 -0.4064)
			(stroke
				(width 0.1524)
				(type default)
			)
			(layer "F.SilkS")
		)
		(fp_line
			(start 0.7874 -0.4064)
			(end 0.7874 0.4064)
			(stroke
				(width 0.1524)
				(type default)
			)
			(layer "F.SilkS")
		)
		(fp_line
			(start 0.7874 0.4064)
			(end -0.7874 0.4064)
			(stroke
				(width 0.1524)
				(type default)
			)
			(layer "F.SilkS")
		)
		(fp_line
			(start -0.67945 -0.305054)
			(end -0.12065 -0.305054)
			(stroke
				(width 0.1)
				(type default)
			)
			(layer "F.Fab")
		)
		(fp_line
			(start -0.67945 0.3048)
			(end -0.67945 -0.305054)
			(stroke
				(width 0.1)
				(type default)
			)
			(layer "F.Fab")
		)
		(fp_line
			(start -0.12065 -0.305054)
			(end -0.12065 -0.2794)
			(stroke
				(width 0.1)
				(type default)
			)
			(layer "F.Fab")
		)
		(fp_line
			(start -0.12065 -0.2794)
			(end 0.12065 -0.2794)
			(stroke
				(width 0.1)
				(type default)
			)
			(layer "F.Fab")
		)
		(fp_line
			(start -0.12065 0.2794)
			(end -0.12065 0.3048)
			(stroke
				(width 0.1)
				(type default)
			)
			(layer "F.Fab")
		)
		(fp_line
			(start -0.12065 0.3048)
			(end -0.67945 0.3048)
			(stroke
				(width 0.1)
				(type default)
			)
			(layer "F.Fab")
		)
		(fp_line
			(start 0.120396 0.2794)
			(end -0.12065 0.2794)
			(stroke
				(width 0.1)
				(type default)
			)
			(layer "F.Fab")
		)
		(fp_line
			(start 0.120396 0.3048)
			(end 0.120396 0.2794)
			(stroke
				(width 0.1)
				(type default)
			)
			(layer "F.Fab")
		)
		(fp_line
			(start 0.12065 -0.3048)
			(end 0.67945 -0.3048)
			(stroke
				(width 0.1)
				(type default)
			)
			(layer "F.Fab")
		)
		(fp_line
			(start 0.12065 -0.2794)
			(end 0.12065 -0.3048)
			(stroke
				(width 0.1)
				(type default)
			)
			(layer "F.Fab")
		)
		(fp_line
			(start 0.67945 -0.3048)
			(end 0.67945 0.3048)
			(stroke
				(width 0.1)
				(type default)
			)
			(layer "F.Fab")
		)
		(fp_line
			(start 0.67945 0.3048)
			(end 0.120396 0.3048)
			(stroke
				(width 0.1)
				(type default)
			)
			(layer "F.Fab")
		)
		(pad "1" smd circle
			(at -0.40005 0)
			(size 0 0)
			(layers "F.Cu" "F.Mask" "F.Paste")
			(net "P3V3_AUX")
		)
		(pad "2" smd circle
			(at 0.40005 0)
			(size 0 0)
			(layers "F.Cu" "F.Mask" "F.Paste")
			(net "FM_P2E_EQA0")
		)
	)
	(footprint ""
		(layer "F.Cu")
		(at 33.63468 -432.564794 90)
		(property "Reference" "R2894"
			(at 0 0 90)
			(layer "F.SilkS")
			(hide yes)
			(effects
				(font
					(size 1.27 1.27)
				)
			)
		)
		(property "Value" ""
			(at 0 0 90)
			(layer "F.Fab")
			(effects
				(font
					(size 1.27 1.27)
				)
			)
		)
		(duplicate_pad_numbers_are_jumpers no)
		(fp_line
			(start 0.7874 -0.4064)
			(end 0.7874 0.4064)
			(stroke
				(width 0.1524)
				(type default)
			)
			(layer "F.SilkS")
		)
		(fp_line
			(start -0.7874 -0.4064)
			(end 0.7874 -0.4064)
			(stroke
				(width 0.1524)
				(type default)
			)
			(layer "F.SilkS")
		)
		(fp_line
			(start 0.7874 0.4064)
			(end -0.7874 0.4064)
			(stroke
				(width 0.1524)
				(type default)
			)
			(layer "F.SilkS")
		)
		(fp_line
			(start -0.7874 0.4064)
			(end -0.7874 -0.4064)
			(stroke
				(width 0.1524)
				(type default)
			)
			(layer "F.SilkS")
		)
		(fp_line
			(start -0.12065 -0.305054)
			(end -0.12065 -0.2794)
			(stroke
				(width 0.1)
				(type default)
			)
			(layer "F.Fab")
		)
		(fp_line
			(start -0.67945 -0.305054)
			(end -0.12065 -0.305054)
			(stroke
				(width 0.1)
				(type default)
			)
			(layer "F.Fab")
		)
		(fp_line
			(start 0.67945 -0.3048)
			(end 0.67945 0.3048)
			(stroke
				(width 0.1)
				(type default)
			)
			(layer "F.Fab")
		)
		(fp_line
			(start 0.12065 -0.3048)
			(end 0.67945 -0.3048)
			(stroke
				(width 0.1)
				(type default)
			)
			(layer "F.Fab")
		)
		(fp_line
			(start 0.12065 -0.2794)
			(end 0.12065 -0.3048)
			(stroke
				(width 0.1)
				(type default)
			)
			(layer "F.Fab")
		)
		(fp_line
			(start -0.12065 -0.2794)
			(end 0.12065 -0.2794)
			(stroke
				(width 0.1)
				(type default)
			)
			(layer "F.Fab")
		)
		(fp_line
			(start 0.120396 0.2794)
			(end -0.12065 0.2794)
			(stroke
				(width 0.1)
				(type default)
			)
			(layer "F.Fab")
		)
		(fp_line
			(start -0.12065 0.2794)
			(end -0.12065 0.3048)
			(stroke
				(width 0.1)
				(type default)
			)
			(layer "F.Fab")
		)
		(fp_line
			(start 0.67945 0.3048)
			(end 0.120396 0.3048)
			(stroke
				(width 0.1)
				(type default)
			)
			(layer "F.Fab")
		)
		(fp_line
			(start 0.120396 0.3048)
			(end 0.120396 0.2794)
			(stroke
				(width 0.1)
				(type default)
			)
			(layer "F.Fab")
		)
		(fp_line
			(start -0.12065 0.3048)
			(end -0.67945 0.3048)
			(stroke
				(width 0.1)
				(type default)
			)
			(layer "F.Fab")
		)
		(fp_line
			(start -0.67945 0.3048)
			(end -0.67945 -0.305054)
			(stroke
				(width 0.1)
				(type default)
			)
			(layer "F.Fab")
		)
		(pad "1" smd circle
			(at -0.40005 0 90)
			(size 0 0)
			(layers "F.Cu" "F.Mask" "F.Paste")
			(net "SMB_1_BMC_GPU_R_SDA")
		)
		(pad "2" smd circle
			(at 0.40005 0 90)
			(size 0 0)
			(layers "F.Cu" "F.Mask" "F.Paste")
			(net "SMB_1_BMC_GPU_BUF_R_SDA")
		)
	)
	(footprint ""
		(layer "F.Cu")
		(at 303.69383 -152.875742 180)
		(property "Reference" "TP4"
			(at 2.89814 -0.282194 0)
			(unlocked yes)
			(layer "F.SilkS")
			(effects
				(font
					(size 0.7874 0.5842)
					(thickness 0.1524)
				)
				(justify left)
			)
		)
		(property "Value" ""
			(at 0 0 180)
			(layer "F.Fab")
			(effects
				(font
					(size 1.27 1.27)
				)
			)
		)
		(duplicate_pad_numbers_are_jumpers no)
		(pad "1" smd circle
			(at 0 0 180)
			(size 0.762 0.762)
			(layers "F.Cu" "F.Mask" "F.Paste")
			(net "VSENSE_PVDD18_S5_P0_DN")
		)
	)
	(footprint ""
		(layer "F.Cu")
		(at 98.795078 -145.06321 180)
		(property "Reference" "PR159"
			(at 0 0 180)
			(layer "F.SilkS")
			(hide yes)
			(effects
				(font
					(size 1.27 1.27)
				)
			)
		)
		(property "Value" ""
			(at 0 0 180)
			(layer "F.Fab")
			(effects
				(font
					(size 1.27 1.27)
				)
			)
		)
		(duplicate_pad_numbers_are_jumpers no)
		(fp_line
			(start 0.7874 0.4064)
			(end -0.7874 0.4064)
			(stroke
				(width 0.1524)
				(type default)
			)
			(layer "F.SilkS")
		)
		(fp_line
			(start 0.7874 -0.4064)
			(end 0.7874 0.4064)
			(stroke
				(width 0.1524)
				(type default)
			)
			(layer "F.SilkS")
		)
		(fp_line
			(start -0.7874 0.4064)
			(end -0.7874 -0.4064)
			(stroke
				(width 0.1524)
				(type default)
			)
			(layer "F.SilkS")
		)
		(fp_line
			(start -0.7874 -0.4064)
			(end 0.7874 -0.4064)
			(stroke
				(width 0.1524)
				(type default)
			)
			(layer "F.SilkS")
		)
		(fp_line
			(start 0.67945 0.3048)
			(end 0.120396 0.3048)
			(stroke
				(width 0.1)
				(type default)
			)
			(layer "F.Fab")
		)
		(fp_line
			(start 0.67945 -0.3048)
			(end 0.67945 0.3048)
			(stroke
				(width 0.1)
				(type default)
			)
			(layer "F.Fab")
		)
		(fp_line
			(start 0.12065 -0.2794)
			(end 0.12065 -0.3048)
			(stroke
				(width 0.1)
				(type default)
			)
			(layer "F.Fab")
		)
		(fp_line
			(start 0.12065 -0.3048)
			(end 0.67945 -0.3048)
			(stroke
				(width 0.1)
				(type default)
			)
			(layer "F.Fab")
		)
		(fp_line
			(start 0.120396 0.3048)
			(end 0.120396 0.2794)
			(stroke
				(width 0.1)
				(type default)
			)
			(layer "F.Fab")
		)
		(fp_line
			(start 0.120396 0.2794)
			(end -0.12065 0.2794)
			(stroke
				(width 0.1)
				(type default)
			)
			(layer "F.Fab")
		)
		(fp_line
			(start -0.12065 0.3048)
			(end -0.67945 0.3048)
			(stroke
				(width 0.1)
				(type default)
			)
			(layer "F.Fab")
		)
		(fp_line
			(start -0.12065 0.2794)
			(end -0.12065 0.3048)
			(stroke
				(width 0.1)
				(type default)
			)
			(layer "F.Fab")
		)
		(fp_line
			(start -0.12065 -0.2794)
			(end 0.12065 -0.2794)
			(stroke
				(width 0.1)
				(type default)
			)
			(layer "F.Fab")
		)
		(fp_line
			(start -0.12065 -0.305054)
			(end -0.12065 -0.2794)
			(stroke
				(width 0.1)
				(type default)
			)
			(layer "F.Fab")
		)
		(fp_line
			(start -0.67945 0.3048)
			(end -0.67945 -0.305054)
			(stroke
				(width 0.1)
				(type default)
			)
			(layer "F.Fab")
		)
		(fp_line
			(start -0.67945 -0.305054)
			(end -0.12065 -0.305054)
			(stroke
				(width 0.1)
				(type default)
			)
			(layer "F.Fab")
		)
		(pad "1" smd circle
			(at -0.40005 0 180)
			(size 0 0)
			(layers "F.Cu" "F.Mask" "F.Paste")
			(net "PVDDCR_SOC_P1_EN//ADDR_CFG")
		)
		(pad "2" smd circle
			(at 0.40005 0 180)
			(size 0 0)
			(layers "F.Cu" "F.Mask" "F.Paste")
			(net "GND")
		)
	)
	(footprint ""
		(layer "F.Cu")
		(at 368.427 -411.226 90)
		(property "Reference" "R4211"
			(at 0 0 90)
			(layer "F.SilkS")
			(hide yes)
			(effects
				(font
					(size 1.27 1.27)
				)
			)
		)
		(property "Value" ""
			(at 0 0 90)
			(layer "F.Fab")
			(effects
				(font
					(size 1.27 1.27)
				)
			)
		)
		(duplicate_pad_numbers_are_jumpers no)
		(fp_line
			(start 0.7874 -0.4064)
			(end 0.7874 0.4064)
			(stroke
				(width 0.1524)
				(type default)
			)
			(layer "F.SilkS")
		)
		(fp_line
			(start -0.7874 -0.4064)
			(end 0.7874 -0.4064)
			(stroke
				(width 0.1524)
				(type default)
			)
			(layer "F.SilkS")
		)
		(fp_line
			(start 0.7874 0.4064)
			(end -0.7874 0.4064)
			(stroke
				(width 0.1524)
				(type default)
			)
			(layer "F.SilkS")
		)
		(fp_line
			(start -0.7874 0.4064)
			(end -0.7874 -0.4064)
			(stroke
				(width 0.1524)
				(type default)
			)
			(layer "F.SilkS")
		)
		(fp_line
			(start -0.12065 -0.305054)
			(end -0.12065 -0.2794)
			(stroke
				(width 0.1)
				(type default)
			)
			(layer "F.Fab")
		)
		(fp_line
			(start -0.67945 -0.305054)
			(end -0.12065 -0.305054)
			(stroke
				(width 0.1)
				(type default)
			)
			(layer "F.Fab")
		)
		(fp_line
			(start 0.67945 -0.3048)
			(end 0.67945 0.3048)
			(stroke
				(width 0.1)
				(type default)
			)
			(layer "F.Fab")
		)
		(fp_line
			(start 0.12065 -0.3048)
			(end 0.67945 -0.3048)
			(stroke
				(width 0.1)
				(type default)
			)
			(layer "F.Fab")
		)
		(fp_line
			(start 0.12065 -0.2794)
			(end 0.12065 -0.3048)
			(stroke
				(width 0.1)
				(type default)
			)
			(layer "F.Fab")
		)
		(fp_line
			(start -0.12065 -0.2794)
			(end 0.12065 -0.2794)
			(stroke
				(width 0.1)
				(type default)
			)
			(layer "F.Fab")
		)
		(fp_line
			(start 0.120396 0.2794)
			(end -0.12065 0.2794)
			(stroke
				(width 0.1)
				(type default)
			)
			(layer "F.Fab")
		)
		(fp_line
			(start -0.12065 0.2794)
			(end -0.12065 0.3048)
			(stroke
				(width 0.1)
				(type default)
			)
			(layer "F.Fab")
		)
		(fp_line
			(start 0.67945 0.3048)
			(end 0.120396 0.3048)
			(stroke
				(width 0.1)
				(type default)
			)
			(layer "F.Fab")
		)
		(fp_line
			(start 0.120396 0.3048)
			(end 0.120396 0.2794)
			(stroke
				(width 0.1)
				(type default)
			)
			(layer "F.Fab")
		)
		(fp_line
			(start -0.12065 0.3048)
			(end -0.67945 0.3048)
			(stroke
				(width 0.1)
				(type default)
			)
			(layer "F.Fab")
		)
		(fp_line
			(start -0.67945 0.3048)
			(end -0.67945 -0.305054)
			(stroke
				(width 0.1)
				(type default)
			)
			(layer "F.Fab")
		)
		(pad "1" smd circle
			(at -0.40005 0 90)
			(size 0 0)
			(layers "F.Cu" "F.Mask" "F.Paste")
			(net "P3V3_AUX")
		)
		(pad "2" smd circle
			(at 0.40005 0 90)
			(size 0 0)
			(layers "F.Cu" "F.Mask" "F.Paste")
			(net "FM_THERMAL_ALERT_N")
		)
	)
	(footprint ""
		(layer "F.Cu")
		(at 111.4298 -332.733142 90)
		(property "Reference" "PL39"
			(at -3.302 4.022852 90)
			(unlocked yes)
			(layer "F.SilkS")
			(effects
				(font
					(size 0.7874 0.5842)
					(thickness 0.1524)
				)
				(justify left)
			)
		)
		(property "Value" ""
			(at 0 0 90)
			(layer "F.Fab")
			(effects
				(font
					(size 1.27 1.27)
				)
			)
		)
		(duplicate_pad_numbers_are_jumpers no)
		(fp_line
			(start 3.24993 -3.24993)
			(end 3.24993 -2.2352)
			(stroke
				(width 0.1524)
				(type default)
			)
			(layer "F.SilkS")
		)
		(fp_line
			(start -3.24993 -3.24993)
			(end 3.24993 -3.24993)
			(stroke
				(width 0.1524)
				(type default)
			)
			(layer "F.SilkS")
		)
		(fp_line
			(start -3.24993 -2.2352)
			(end -3.24993 -3.24993)
			(stroke
				(width 0.1524)
				(type default)
			)
			(layer "F.SilkS")
		)
		(fp_line
			(start 3.24993 2.2352)
			(end 3.24993 3.24993)
			(stroke
				(width 0.1524)
				(type default)
			)
			(layer "F.SilkS")
		)
		(fp_line
			(start 3.24993 3.24993)
			(end -3.24993 3.24993)
			(stroke
				(width 0.1524)
				(type default)
			)
			(layer "F.SilkS")
		)
		(fp_line
			(start -3.24993 3.24993)
			(end -3.24993 2.2352)
			(stroke
				(width 0.1524)
				(type default)
			)
			(layer "F.SilkS")
		)
		(fp_line
			(start 3.24993 -3.24993)
			(end 3.24993 3.24993)
			(stroke
				(width 0.1)
				(type default)
			)
			(layer "F.Fab")
		)
		(fp_line
			(start -3.24993 -3.24993)
			(end 3.24993 -3.24993)
			(stroke
				(width 0.1)
				(type default)
			)
			(layer "F.Fab")
		)
		(fp_line
			(start 3.24993 3.24993)
			(end -3.24993 3.24993)
			(stroke
				(width 0.1)
				(type default)
			)
			(layer "F.Fab")
		)
		(fp_line
			(start -3.24993 3.24993)
			(end -3.24993 -3.24993)
			(stroke
				(width 0.1)
				(type default)
			)
			(layer "F.Fab")
		)
		(pad "1" smd rect
			(at -2.29997 0 90)
			(size 2.0066 4.2164)
			(layers "F.Cu" "F.Mask" "F.Paste")
			(net "IND_CPU1_P1_CPL0")
		)
		(pad "2" smd rect
			(at 2.29997 0 90)
			(size 2.0066 4.2164)
			(layers "F.Cu" "F.Mask" "F.Paste")
			(net "GND")
		)
	)
	(footprint ""
		(layer "F.Cu")
		(at 243.446808 -42.063162 -90)
		(property "Reference" "C1276"
			(at 0 0 270)
			(layer "F.SilkS")
			(hide yes)
			(effects
				(font
					(size 1.27 1.27)
				)
			)
		)
		(property "Value" ""
			(at 0 0 270)
			(layer "F.Fab")
			(effects
				(font
					(size 1.27 1.27)
				)
			)
		)
		(duplicate_pad_numbers_are_jumpers no)
		(fp_line
			(start -1.524 0.762)
			(end -1.524 -0.762)
			(stroke
				(width 0.1524)
				(type default)
			)
			(layer "F.SilkS")
		)
		(fp_line
			(start 1.524 0.762)
			(end -1.524 0.762)
			(stroke
				(width 0.1524)
				(type default)
			)
			(layer "F.SilkS")
		)
		(fp_line
			(start -1.524 -0.762)
			(end 1.524 -0.762)
			(stroke
				(width 0.1524)
				(type default)
			)
			(layer "F.SilkS")
		)
		(fp_line
			(start 1.524 -0.762)
			(end 1.524 0.762)
			(stroke
				(width 0.1524)
				(type default)
			)
			(layer "F.SilkS")
		)
		(fp_line
			(start -1.1049 0.724916)
			(end 1.1049 0.724916)
			(stroke
				(width 0.1)
				(type default)
			)
			(layer "F.Fab")
		)
		(fp_line
			(start 1.1049 0.724916)
			(end 1.1049 -0.724916)
			(stroke
				(width 0.1)
				(type default)
			)
			(layer "F.Fab")
		)
		(fp_line
			(start -1.1049 -0.724916)
			(end -1.1049 0.724916)
			(stroke
				(width 0.1)
				(type default)
			)
			(layer "F.Fab")
		)
		(fp_line
			(start 1.1049 -0.724916)
			(end -1.1049 -0.724916)
			(stroke
				(width 0.1)
				(type default)
			)
			(layer "F.Fab")
		)
		(pad "1" smd rect
			(at -0.889 0 90)
			(size 1.016 1.27)
			(layers "F.Cu" "F.Mask" "F.Paste")
			(net "P12V_E1S_0_R")
		)
		(pad "2" smd rect
			(at 0.889 0 90)
			(size 1.016 1.27)
			(layers "F.Cu" "F.Mask" "F.Paste")
			(net "GND")
		)
	)
	(footprint ""
		(layer "F.Cu")
		(at 41.33596 -434.086 -90)
		(property "Reference" "R3515"
			(at 0 0 270)
			(layer "F.SilkS")
			(hide yes)
			(effects
				(font
					(size 1.27 1.27)
				)
			)
		)
		(property "Value" ""
			(at 0 0 270)
			(layer "F.Fab")
			(effects
				(font
					(size 1.27 1.27)
				)
			)
		)
		(duplicate_pad_numbers_are_jumpers no)
		(fp_line
			(start -0.7874 0.4064)
			(end -0.7874 -0.4064)
			(stroke
				(width 0.1524)
				(type default)
			)
			(layer "F.SilkS")
		)
		(fp_line
			(start 0.7874 0.4064)
			(end -0.7874 0.4064)
			(stroke
				(width 0.1524)
				(type default)
			)
			(layer "F.SilkS")
		)
		(fp_line
			(start -0.7874 -0.4064)
			(end 0.7874 -0.4064)
			(stroke
				(width 0.1524)
				(type default)
			)
			(layer "F.SilkS")
		)
		(fp_line
			(start 0.7874 -0.4064)
			(end 0.7874 0.4064)
			(stroke
				(width 0.1524)
				(type default)
			)
			(layer "F.SilkS")
		)
		(fp_line
			(start -0.67945 0.3048)
			(end -0.67945 -0.305054)
			(stroke
				(width 0.1)
				(type default)
			)
			(layer "F.Fab")
		)
		(fp_line
			(start -0.12065 0.3048)
			(end -0.67945 0.3048)
			(stroke
				(width 0.1)
				(type default)
			)
			(layer "F.Fab")
		)
		(fp_line
			(start 0.120396 0.3048)
			(end 0.120396 0.2794)
			(stroke
				(width 0.1)
				(type default)
			)
			(layer "F.Fab")
		)
		(fp_line
			(start 0.67945 0.3048)
			(end 0.120396 0.3048)
			(stroke
				(width 0.1)
				(type default)
			)
			(layer "F.Fab")
		)
		(fp_line
			(start -0.12065 0.2794)
			(end -0.12065 0.3048)
			(stroke
				(width 0.1)
				(type default)
			)
			(layer "F.Fab")
		)
		(fp_line
			(start 0.120396 0.2794)
			(end -0.12065 0.2794)
			(stroke
				(width 0.1)
				(type default)
			)
			(layer "F.Fab")
		)
		(fp_line
			(start -0.12065 -0.2794)
			(end 0.12065 -0.2794)
			(stroke
				(width 0.1)
				(type default)
			)
			(layer "F.Fab")
		)
		(fp_line
			(start 0.12065 -0.2794)
			(end 0.12065 -0.3048)
			(stroke
				(width 0.1)
				(type default)
			)
			(layer "F.Fab")
		)
		(fp_line
			(start 0.12065 -0.3048)
			(end 0.67945 -0.3048)
			(stroke
				(width 0.1)
				(type default)
			)
			(layer "F.Fab")
		)
		(fp_line
			(start 0.67945 -0.3048)
			(end 0.67945 0.3048)
			(stroke
				(width 0.1)
				(type default)
			)
			(layer "F.Fab")
		)
		(fp_line
			(start -0.67945 -0.305054)
			(end -0.12065 -0.305054)
			(stroke
				(width 0.1)
				(type default)
			)
			(layer "F.Fab")
		)
		(fp_line
			(start -0.12065 -0.305054)
			(end -0.12065 -0.2794)
			(stroke
				(width 0.1)
				(type default)
			)
			(layer "F.Fab")
		)
		(pad "1" smd circle
			(at -0.40005 0 270)
			(size 0 0)
			(layers "F.Cu" "F.Mask" "F.Paste")
			(net "FM_SWB_PWR_EN_R1_BUF")
		)
		(pad "2" smd circle
			(at 0.40005 0 270)
			(size 0 0)
			(layers "F.Cu" "F.Mask" "F.Paste")
			(net "FM_SWB_PWR_EN_R_BUF")
		)
	)
	(footprint ""
		(layer "F.Cu")
		(at 418.212778 -161.102548 -90)
		(property "Reference" "PC606"
			(at 0 0 270)
			(layer "F.SilkS")
			(hide yes)
			(effects
				(font
					(size 1.27 1.27)
				)
			)
		)
		(property "Value" ""
			(at 0 0 270)
			(layer "F.Fab")
			(effects
				(font
					(size 1.27 1.27)
				)
			)
		)
		(duplicate_pad_numbers_are_jumpers no)
		(fp_line
			(start -0.7874 0.4064)
			(end -0.7874 -0.4064)
			(stroke
				(width 0.1524)
				(type default)
			)
			(layer "F.SilkS")
		)
		(fp_line
			(start -0.085852 0.4064)
			(end -0.7874 0.4064)
			(stroke
				(width 0.1524)
				(type default)
			)
			(layer "F.SilkS")
		)
		(fp_line
			(start 0.7874 0.4064)
			(end 0.396748 0.4064)
			(stroke
				(width 0.1524)
				(type default)
			)
			(layer "F.SilkS")
		)
		(fp_line
			(start -0.7874 -0.4064)
			(end 0.7874 -0.4064)
			(stroke
				(width 0.1524)
				(type default)
			)
			(layer "F.SilkS")
		)
		(fp_line
			(start 0.7874 -0.4064)
			(end 0.7874 0.4064)
			(stroke
				(width 0.1524)
				(type default)
			)
			(layer "F.SilkS")
		)
		(fp_line
			(start -0.67945 0.3048)
			(end -0.67945 -0.305054)
			(stroke
				(width 0.1)
				(type default)
			)
			(layer "F.Fab")
		)
		(fp_line
			(start -0.12065 0.3048)
			(end -0.67945 0.3048)
			(stroke
				(width 0.1)
				(type default)
			)
			(layer "F.Fab")
		)
		(fp_line
			(start 0.120396 0.3048)
			(end 0.120396 0.2794)
			(stroke
				(width 0.1)
				(type default)
			)
			(layer "F.Fab")
		)
		(fp_line
			(start 0.67945 0.3048)
			(end 0.120396 0.3048)
			(stroke
				(width 0.1)
				(type default)
			)
			(layer "F.Fab")
		)
		(fp_line
			(start -0.12065 0.2794)
			(end -0.12065 0.3048)
			(stroke
				(width 0.1)
				(type default)
			)
			(layer "F.Fab")
		)
		(fp_line
			(start 0.120396 0.2794)
			(end -0.12065 0.2794)
			(stroke
				(width 0.1)
				(type default)
			)
			(layer "F.Fab")
		)
		(fp_line
			(start -0.12065 -0.2794)
			(end 0.12065 -0.2794)
			(stroke
				(width 0.1)
				(type default)
			)
			(layer "F.Fab")
		)
		(fp_line
			(start 0.12065 -0.2794)
			(end 0.12065 -0.3048)
			(stroke
				(width 0.1)
				(type default)
			)
			(layer "F.Fab")
		)
		(fp_line
			(start 0.12065 -0.3048)
			(end 0.67945 -0.3048)
			(stroke
				(width 0.1)
				(type default)
			)
			(layer "F.Fab")
		)
		(fp_line
			(start 0.67945 -0.3048)
			(end 0.67945 0.3048)
			(stroke
				(width 0.1)
				(type default)
			)
			(layer "F.Fab")
		)
		(fp_line
			(start -0.67945 -0.305054)
			(end -0.12065 -0.305054)
			(stroke
				(width 0.1)
				(type default)
			)
			(layer "F.Fab")
		)
		(fp_line
			(start -0.12065 -0.305054)
			(end -0.12065 -0.2794)
			(stroke
				(width 0.1)
				(type default)
			)
			(layer "F.Fab")
		)
		(pad "1" smd circle
			(at -0.40005 0 270)
			(size 0 0)
			(layers "F.Cu" "F.Mask" "F.Paste")
			(net "PVDDCR_SOC_P0_VCC3")
		)
		(pad "2" smd circle
			(at 0.40005 0 270)
			(size 0 0)
			(layers "F.Cu" "F.Mask" "F.Paste")
			(net "GND")
		)
	)
	(footprint ""
		(layer "F.Cu")
		(at 162.218116 -33.723834 90)
		(property "Reference" "U157"
			(at -0.75946 -2.367788 90)
			(unlocked yes)
			(layer "F.SilkS")
			(effects
				(font
					(size 0.7874 0.5842)
					(thickness 0.1524)
				)
				(justify left)
			)
		)
		(property "Value" ""
			(at 0 0 90)
			(layer "F.Fab")
			(effects
				(font
					(size 1.27 1.27)
				)
			)
		)
		(duplicate_pad_numbers_are_jumpers no)
		(fp_line
			(start 1.733296 -1.549908)
			(end 0.660908 -1.549908)
			(stroke
				(width 0.1524)
				(type default)
			)
			(layer "F.SilkS")
		)
		(fp_line
			(start 0.660908 -1.549908)
			(end 0 -0.889)
			(stroke
				(width 0.1524)
				(type default)
			)
			(layer "F.SilkS")
		)
		(fp_line
			(start -0.660908 -1.549908)
			(end -1.733296 -1.549908)
			(stroke
				(width 0.1524)
				(type default)
			)
			(layer "F.SilkS")
		)
		(fp_line
			(start -1.733296 -1.549908)
			(end -1.733296 1.549908)
			(stroke
				(width 0.1524)
				(type default)
			)
			(layer "F.SilkS")
		)
		(fp_line
			(start 0 -0.889)
			(end -0.660908 -1.549908)
			(stroke
				(width 0.1524)
				(type default)
			)
			(layer "F.SilkS")
		)
		(fp_line
			(start 1.733296 1.549908)
			(end 1.733296 -1.549908)
			(stroke
				(width 0.1524)
				(type default)
			)
			(layer "F.SilkS")
		)
		(fp_line
			(start -1.733296 1.549908)
			(end 1.733296 1.549908)
			(stroke
				(width 0.1524)
				(type default)
			)
			(layer "F.SilkS")
		)
		(fp_poly
			(pts
				(xy -1.9304 -0.94996) (xy -2.4384 -0.69596) (xy -2.4384 -1.20396)
			)
			(stroke
				(width 0)
				(type default)
			)
			(fill yes)
			(layer "F.SilkS")
		)
		(fp_line
			(start 0.849884 -1.549908)
			(end -0.849884 -1.549908)
			(stroke
				(width 0.1)
				(type default)
			)
			(layer "F.Fab")
		)
		(fp_line
			(start -0.849884 -1.549908)
			(end -0.849884 1.549908)
			(stroke
				(width 0.1)
				(type default)
			)
			(layer "F.Fab")
		)
		(fp_line
			(start 0.849884 1.549908)
			(end 0.849884 -1.549908)
			(stroke
				(width 0.1)
				(type default)
			)
			(layer "F.Fab")
		)
		(fp_line
			(start -0.849884 1.549908)
			(end 0.849884 1.549908)
			(stroke
				(width 0.1)
				(type default)
			)
			(layer "F.Fab")
		)
		(fp_poly
			(pts
				(xy -2.4384 -1.20396) (xy -2.4384 -0.69596) (xy -1.9304 -0.94996)
			)
			(stroke
				(width 0)
				(type default)
			)
			(fill yes)
			(layer "F.Fab")
		)
		(pad "1" smd rect
			(at -1.199896 -0.94996)
			(size 0.5588 0.8128)
			(layers "F.Cu" "F.Mask" "F.Paste")
			(net "NC_U157_NC1")
		)
		(pad "2" smd rect
			(at -1.199896 0)
			(size 0.5588 0.8128)
			(layers "F.Cu" "F.Mask" "F.Paste")
			(net "OCP_SFF_WAKE_BUFF_R_N")
		)
		(pad "3" smd rect
			(at -1.199896 0.94996)
			(size 0.5588 0.8128)
			(layers "F.Cu" "F.Mask" "F.Paste")
			(net "GND")
		)
		(pad "4" smd rect
			(at 1.199896 0.94996)
			(size 0.5588 0.8128)
			(layers "F.Cu" "F.Mask" "F.Paste")
			(net "IRQ_LVC3_WAKE_BUF_N")
		)
		(pad "5" smd rect
			(at 1.199896 -0.94996)
			(size 0.5588 0.8128)
			(layers "F.Cu" "F.Mask" "F.Paste")
			(net "P3V3_AUX")
		)
	)
	(footprint ""
		(layer "F.Cu")
		(at 184.605422 -133.565646 -90)
		(property "Reference" "R6806"
			(at 0 0 270)
			(layer "F.SilkS")
			(hide yes)
			(effects
				(font
					(size 1.27 1.27)
				)
			)
		)
		(property "Value" ""
			(at 0 0 270)
			(layer "F.Fab")
			(effects
				(font
					(size 1.27 1.27)
				)
			)
		)
		(duplicate_pad_numbers_are_jumpers no)
		(fp_line
			(start -0.7874 0.4064)
			(end -0.7874 -0.4064)
			(stroke
				(width 0.1524)
				(type default)
			)
			(layer "F.SilkS")
		)
		(fp_line
			(start 0.7874 0.4064)
			(end -0.7874 0.4064)
			(stroke
				(width 0.1524)
				(type default)
			)
			(layer "F.SilkS")
		)
		(fp_line
			(start -0.7874 -0.4064)
			(end 0.7874 -0.4064)
			(stroke
				(width 0.1524)
				(type default)
			)
			(layer "F.SilkS")
		)
		(fp_line
			(start 0.7874 -0.4064)
			(end 0.7874 0.4064)
			(stroke
				(width 0.1524)
				(type default)
			)
			(layer "F.SilkS")
		)
		(fp_line
			(start -0.67945 0.3048)
			(end -0.67945 -0.305054)
			(stroke
				(width 0.1)
				(type default)
			)
			(layer "F.Fab")
		)
		(fp_line
			(start -0.12065 0.3048)
			(end -0.67945 0.3048)
			(stroke
				(width 0.1)
				(type default)
			)
			(layer "F.Fab")
		)
		(fp_line
			(start 0.120396 0.3048)
			(end 0.120396 0.2794)
			(stroke
				(width 0.1)
				(type default)
			)
			(layer "F.Fab")
		)
		(fp_line
			(start 0.67945 0.3048)
			(end 0.120396 0.3048)
			(stroke
				(width 0.1)
				(type default)
			)
			(layer "F.Fab")
		)
		(fp_line
			(start -0.12065 0.2794)
			(end -0.12065 0.3048)
			(stroke
				(width 0.1)
				(type default)
			)
			(layer "F.Fab")
		)
		(fp_line
			(start 0.120396 0.2794)
			(end -0.12065 0.2794)
			(stroke
				(width 0.1)
				(type default)
			)
			(layer "F.Fab")
		)
		(fp_line
			(start -0.12065 -0.2794)
			(end 0.12065 -0.2794)
			(stroke
				(width 0.1)
				(type default)
			)
			(layer "F.Fab")
		)
		(fp_line
			(start 0.12065 -0.2794)
			(end 0.12065 -0.3048)
			(stroke
				(width 0.1)
				(type default)
			)
			(layer "F.Fab")
		)
		(fp_line
			(start 0.12065 -0.3048)
			(end 0.67945 -0.3048)
			(stroke
				(width 0.1)
				(type default)
			)
			(layer "F.Fab")
		)
		(fp_line
			(start 0.67945 -0.3048)
			(end 0.67945 0.3048)
			(stroke
				(width 0.1)
				(type default)
			)
			(layer "F.Fab")
		)
		(fp_line
			(start -0.67945 -0.305054)
			(end -0.12065 -0.305054)
			(stroke
				(width 0.1)
				(type default)
			)
			(layer "F.Fab")
		)
		(fp_line
			(start -0.12065 -0.305054)
			(end -0.12065 -0.2794)
			(stroke
				(width 0.1)
				(type default)
			)
			(layer "F.Fab")
		)
		(pad "1" smd circle
			(at -0.40005 0 270)
			(size 0 0)
			(layers "F.Cu" "F.Mask" "F.Paste")
			(net "RST_RT_CPU0_P1_PERST_R_N")
		)
		(pad "2" smd circle
			(at 0.40005 0 270)
			(size 0 0)
			(layers "F.Cu" "F.Mask" "F.Paste")
			(net "RST_RT_CPU0_P1_PERST_R2_N")
		)
	)
	(footprint ""
		(layer "F.Cu")
		(at 82.166714 -192.061084 180)
		(property "Reference" "PL28"
			(at -21.355304 3.337306 90)
			(unlocked yes)
			(layer "F.SilkS")
			(effects
				(font
					(size 0.7874 0.5842)
					(thickness 0.1524)
				)
				(justify left)
			)
		)
		(property "Value" ""
			(at 0 0 180)
			(layer "F.Fab")
			(effects
				(font
					(size 1.27 1.27)
				)
			)
		)
		(duplicate_pad_numbers_are_jumpers no)
		(fp_line
			(start 3.750056 5.500116)
			(end 3.750056 -5.500116)
			(stroke
				(width 0.1524)
				(type default)
			)
			(layer "F.SilkS")
		)
		(fp_line
			(start 3.750056 -5.500116)
			(end 2.393442 -5.500116)
			(stroke
				(width 0.1524)
				(type default)
			)
			(layer "F.SilkS")
		)
		(fp_line
			(start 2.393442 5.500116)
			(end 3.750056 5.500116)
			(stroke
				(width 0.1524)
				(type default)
			)
			(layer "F.SilkS")
		)
		(fp_line
			(start -2.393442 5.500116)
			(end -3.750056 5.500116)
			(stroke
				(width 0.1524)
				(type default)
			)
			(layer "F.SilkS")
		)
		(fp_line
			(start -3.750056 5.500116)
			(end -3.750056 -5.500116)
			(stroke
				(width 0.1524)
				(type default)
			)
			(layer "F.SilkS")
		)
		(fp_line
			(start -3.750056 -5.500116)
			(end -2.393442 -5.500116)
			(stroke
				(width 0.1524)
				(type default)
			)
			(layer "F.SilkS")
		)
		(fp_poly
			(pts
				(xy -3.9116 -4.249928) (xy -4.445 -3.983228) (xy -4.445 -4.516628)
			)
			(stroke
				(width 0)
				(type default)
			)
			(fill yes)
			(layer "F.SilkS")
		)
		(fp_line
			(start 3.750056 5.500116)
			(end 3.750056 -5.500116)
			(stroke
				(width 0.1)
				(type default)
			)
			(layer "F.Fab")
		)
		(fp_line
			(start 3.750056 -5.500116)
			(end -3.750056 -5.500116)
			(stroke
				(width 0.1)
				(type default)
			)
			(layer "F.Fab")
		)
		(fp_line
			(start -3.750056 5.500116)
			(end 3.750056 5.500116)
			(stroke
				(width 0.1)
				(type default)
			)
			(layer "F.Fab")
		)
		(fp_line
			(start -3.750056 -5.500116)
			(end -3.750056 5.500116)
			(stroke
				(width 0.1)
				(type default)
			)
			(layer "F.Fab")
		)
		(fp_poly
			(pts
				(xy -4.9276 -4.757928) (xy -4.9276 -3.741928) (xy -3.9116 -4.249928)
			)
			(stroke
				(width 0)
				(type default)
			)
			(fill yes)
			(layer "F.Fab")
		)
		(pad "1" smd rect
			(at 0 -4.249928 90)
			(size 2.413 4.5212)
			(layers "F.Cu" "F.Mask" "F.Paste")
			(net "SW_PVDDCR_CPU0_P1_SW1")
		)
		(pad "2" smd rect
			(at 0 -1.175004 90)
			(size 1.3716 4.5212)
			(layers "F.Cu" "F.Mask" "F.Paste")
			(net "IND_CPU0_P1_CPL5")
		)
		(pad "3" smd rect
			(at 0 1.175004 90)
			(size 1.3716 4.5212)
			(layers "F.Cu" "F.Mask" "F.Paste")
			(net "IND_CPU0_P1_CPL1")
		)
		(pad "4" smd rect
			(at 0 4.249928 90)
			(size 2.413 4.5212)
			(layers "F.Cu" "F.Mask" "F.Paste")
			(net "PVDDCR_CPU0_P1")
		)
	)
	(footprint ""
		(layer "F.Cu")
		(at 40.386 -391.7696 -90)
		(property "Reference" "R6725"
			(at 0 0 270)
			(layer "F.SilkS")
			(hide yes)
			(effects
				(font
					(size 1.27 1.27)
				)
			)
		)
		(property "Value" ""
			(at 0 0 270)
			(layer "F.Fab")
			(effects
				(font
					(size 1.27 1.27)
				)
			)
		)
		(duplicate_pad_numbers_are_jumpers no)
		(fp_line
			(start -0.32512 0.175006)
			(end -0.32512 -0.175006)
			(stroke
				(width 0.1)
				(type default)
			)
			(layer "F.Fab")
		)
		(fp_line
			(start 0.32512 0.175006)
			(end -0.32512 0.175006)
			(stroke
				(width 0.1)
				(type default)
			)
			(layer "F.Fab")
		)
		(fp_line
			(start -0.32512 -0.175006)
			(end 0.32512 -0.175006)
			(stroke
				(width 0.1)
				(type default)
			)
			(layer "F.Fab")
		)
		(fp_line
			(start 0.32512 -0.175006)
			(end 0.32512 0.175006)
			(stroke
				(width 0.1)
				(type default)
			)
			(layer "F.Fab")
		)
		(pad "1" smd rect
			(at -0.2667 0 270)
			(size 0.3048 0.381)
			(layers "F.Cu" "F.Mask" "F.Paste")
			(net "P1V8_CPU1_RT_1D")
		)
		(pad "2" smd rect
			(at 0.2667 0 90)
			(size 0.3048 0.381)
			(layers "F.Cu" "F.Mask" "F.Paste")
			(net "JTAG_TEST_MODE_RT_CPU1_P0")
		)
	)
	(footprint ""
		(layer "F.Cu")
		(at 54.809644 -408.517344 -90)
		(property "Reference" "C6633"
			(at 0 0 270)
			(layer "F.SilkS")
			(hide yes)
			(effects
				(font
					(size 1.27 1.27)
				)
			)
		)
		(property "Value" ""
			(at 0 0 270)
			(layer "F.Fab")
			(effects
				(font
					(size 1.27 1.27)
				)
			)
		)
		(duplicate_pad_numbers_are_jumpers no)
		(fp_line
			(start -0.299974 0.150114)
			(end -0.299974 -0.150114)
			(stroke
				(width 0.1)
				(type default)
			)
			(layer "F.Fab")
		)
		(fp_line
			(start 0.299974 0.150114)
			(end -0.299974 0.150114)
			(stroke
				(width 0.1)
				(type default)
			)
			(layer "F.Fab")
		)
		(fp_line
			(start -0.299974 -0.150114)
			(end 0.299974 -0.150114)
			(stroke
				(width 0.1)
				(type default)
			)
			(layer "F.Fab")
		)
		(fp_line
			(start 0.299974 -0.150114)
			(end 0.299974 0.150114)
			(stroke
				(width 0.1)
				(type default)
			)
			(layer "F.Fab")
		)
		(pad "1" smd rect
			(at -0.2667 0 270)
			(size 0.3048 0.381)
			(layers "F.Cu" "F.Mask" "F.Paste")
			(net "P5E_CPU1_P0_TX_BUF_C_DP<2>")
		)
		(pad "2" smd rect
			(at 0.2667 0 270)
			(size 0.3048 0.381)
			(layers "F.Cu" "F.Mask" "F.Paste")
			(net "P5E_CPU1_P0_TX_BUF_DP<2>")
		)
	)
	(footprint ""
		(layer "F.Cu")
		(at 99.080828 -395.6304 -90)
		(property "Reference" "R6730"
			(at 0 0 270)
			(layer "F.SilkS")
			(hide yes)
			(effects
				(font
					(size 1.27 1.27)
				)
			)
		)
		(property "Value" ""
			(at 0 0 270)
			(layer "F.Fab")
			(effects
				(font
					(size 1.27 1.27)
				)
			)
		)
		(duplicate_pad_numbers_are_jumpers no)
		(fp_line
			(start -0.32512 0.175006)
			(end -0.32512 -0.175006)
			(stroke
				(width 0.1)
				(type default)
			)
			(layer "F.Fab")
		)
		(fp_line
			(start 0.32512 0.175006)
			(end -0.32512 0.175006)
			(stroke
				(width 0.1)
				(type default)
			)
			(layer "F.Fab")
		)
		(fp_line
			(start -0.32512 -0.175006)
			(end 0.32512 -0.175006)
			(stroke
				(width 0.1)
				(type default)
			)
			(layer "F.Fab")
		)
		(fp_line
			(start 0.32512 -0.175006)
			(end 0.32512 0.175006)
			(stroke
				(width 0.1)
				(type default)
			)
			(layer "F.Fab")
		)
		(pad "1" smd rect
			(at -0.2667 0 270)
			(size 0.3048 0.381)
			(layers "F.Cu" "F.Mask" "F.Paste")
			(net "P1V8_CPU1_RT_1D")
		)
		(pad "2" smd rect
			(at 0.2667 0 90)
			(size 0.3048 0.381)
			(layers "F.Cu" "F.Mask" "F.Paste")
			(net "RT_CPU1_P1_VQPS")
		)
	)
	(footprint ""
		(layer "F.Cu")
		(at 360.098594 -320.132964 90)
		(property "Reference" "R8306"
			(at 0 0 90)
			(layer "F.SilkS")
			(hide yes)
			(effects
				(font
					(size 1.27 1.27)
				)
			)
		)
		(property "Value" ""
			(at 0 0 90)
			(layer "F.Fab")
			(effects
				(font
					(size 1.27 1.27)
				)
			)
		)
		(duplicate_pad_numbers_are_jumpers no)
		(fp_line
			(start 0.7874 -0.4064)
			(end 0.7874 -0.053594)
			(stroke
				(width 0.1524)
				(type default)
			)
			(layer "F.SilkS")
		)
		(fp_line
			(start -0.7874 -0.4064)
			(end 0.7874 -0.4064)
			(stroke
				(width 0.1524)
				(type default)
			)
			(layer "F.SilkS")
		)
		(fp_line
			(start -0.7874 0.022606)
			(end -0.7874 -0.4064)
			(stroke
				(width 0.1524)
				(type default)
			)
			(layer "F.SilkS")
		)
		(fp_line
			(start 0.364236 0.4064)
			(end -0.372364 0.4064)
			(stroke
				(width 0.1524)
				(type default)
			)
			(layer "F.SilkS")
		)
		(fp_line
			(start -0.12065 -0.305054)
			(end -0.12065 -0.2794)
			(stroke
				(width 0.1)
				(type default)
			)
			(layer "F.Fab")
		)
		(fp_line
			(start -0.67945 -0.305054)
			(end -0.12065 -0.305054)
			(stroke
				(width 0.1)
				(type default)
			)
			(layer "F.Fab")
		)
		(fp_line
			(start 0.67945 -0.3048)
			(end 0.67945 0.3048)
			(stroke
				(width 0.1)
				(type default)
			)
			(layer "F.Fab")
		)
		(fp_line
			(start 0.12065 -0.3048)
			(end 0.67945 -0.3048)
			(stroke
				(width 0.1)
				(type default)
			)
			(layer "F.Fab")
		)
		(fp_line
			(start 0.12065 -0.2794)
			(end 0.12065 -0.3048)
			(stroke
				(width 0.1)
				(type default)
			)
			(layer "F.Fab")
		)
		(fp_line
			(start -0.12065 -0.2794)
			(end 0.12065 -0.2794)
			(stroke
				(width 0.1)
				(type default)
			)
			(layer "F.Fab")
		)
		(fp_line
			(start 0.120396 0.2794)
			(end -0.12065 0.2794)
			(stroke
				(width 0.1)
				(type default)
			)
			(layer "F.Fab")
		)
		(fp_line
			(start -0.12065 0.2794)
			(end -0.12065 0.3048)
			(stroke
				(width 0.1)
				(type default)
			)
			(layer "F.Fab")
		)
		(fp_line
			(start 0.67945 0.3048)
			(end 0.120396 0.3048)
			(stroke
				(width 0.1)
				(type default)
			)
			(layer "F.Fab")
		)
		(fp_line
			(start 0.120396 0.3048)
			(end 0.120396 0.2794)
			(stroke
				(width 0.1)
				(type default)
			)
			(layer "F.Fab")
		)
		(fp_line
			(start -0.12065 0.3048)
			(end -0.67945 0.3048)
			(stroke
				(width 0.1)
				(type default)
			)
			(layer "F.Fab")
		)
		(fp_line
			(start -0.67945 0.3048)
			(end -0.67945 -0.305054)
			(stroke
				(width 0.1)
				(type default)
			)
			(layer "F.Fab")
		)
		(pad "1" smd circle
			(at -0.40005 0 90)
			(size 0 0)
			(layers "F.Cu" "F.Mask" "F.Paste")
			(net "CLK_100M_CPU0_CLK13_R_DN")
		)
		(pad "2" smd circle
			(at 0.40005 0 90)
			(size 0 0)
			(layers "F.Cu" "F.Mask" "F.Paste")
			(net "CLK_100M_CPU0_CLK13_DN")
		)
	)
	(footprint ""
		(layer "F.Cu")
		(at 177.397918 -424.283632)
		(property "Reference" "R2983"
			(at 0 0 0)
			(layer "F.SilkS")
			(hide yes)
			(effects
				(font
					(size 1.27 1.27)
				)
			)
		)
		(property "Value" ""
			(at 0 0 0)
			(layer "F.Fab")
			(effects
				(font
					(size 1.27 1.27)
				)
			)
		)
		(duplicate_pad_numbers_are_jumpers no)
		(fp_line
			(start -0.7874 -0.4064)
			(end 0.7874 -0.4064)
			(stroke
				(width 0.1524)
				(type default)
			)
			(layer "F.SilkS")
		)
		(fp_line
			(start -0.7874 0.4064)
			(end -0.7874 -0.4064)
			(stroke
				(width 0.1524)
				(type default)
			)
			(layer "F.SilkS")
		)
		(fp_line
			(start 0.7874 -0.4064)
			(end 0.7874 0.4064)
			(stroke
				(width 0.1524)
				(type default)
			)
			(layer "F.SilkS")
		)
		(fp_line
			(start 0.7874 0.4064)
			(end -0.7874 0.4064)
			(stroke
				(width 0.1524)
				(type default)
			)
			(layer "F.SilkS")
		)
		(fp_line
			(start -0.67945 -0.305054)
			(end -0.12065 -0.305054)
			(stroke
				(width 0.1)
				(type default)
			)
			(layer "F.Fab")
		)
		(fp_line
			(start -0.67945 0.3048)
			(end -0.67945 -0.305054)
			(stroke
				(width 0.1)
				(type default)
			)
			(layer "F.Fab")
		)
		(fp_line
			(start -0.12065 -0.305054)
			(end -0.12065 -0.2794)
			(stroke
				(width 0.1)
				(type default)
			)
			(layer "F.Fab")
		)
		(fp_line
			(start -0.12065 -0.2794)
			(end 0.12065 -0.2794)
			(stroke
				(width 0.1)
				(type default)
			)
			(layer "F.Fab")
		)
		(fp_line
			(start -0.12065 0.2794)
			(end -0.12065 0.3048)
			(stroke
				(width 0.1)
				(type default)
			)
			(layer "F.Fab")
		)
		(fp_line
			(start -0.12065 0.3048)
			(end -0.67945 0.3048)
			(stroke
				(width 0.1)
				(type default)
			)
			(layer "F.Fab")
		)
		(fp_line
			(start 0.120396 0.2794)
			(end -0.12065 0.2794)
			(stroke
				(width 0.1)
				(type default)
			)
			(layer "F.Fab")
		)
		(fp_line
			(start 0.120396 0.3048)
			(end 0.120396 0.2794)
			(stroke
				(width 0.1)
				(type default)
			)
			(layer "F.Fab")
		)
		(fp_line
			(start 0.12065 -0.3048)
			(end 0.67945 -0.3048)
			(stroke
				(width 0.1)
				(type default)
			)
			(layer "F.Fab")
		)
		(fp_line
			(start 0.12065 -0.2794)
			(end 0.12065 -0.3048)
			(stroke
				(width 0.1)
				(type default)
			)
			(layer "F.Fab")
		)
		(fp_line
			(start 0.67945 -0.3048)
			(end 0.67945 0.3048)
			(stroke
				(width 0.1)
				(type default)
			)
			(layer "F.Fab")
		)
		(fp_line
			(start 0.67945 0.3048)
			(end 0.120396 0.3048)
			(stroke
				(width 0.1)
				(type default)
			)
			(layer "F.Fab")
		)
		(pad "1" smd circle
			(at -0.40005 0)
			(size 0 0)
			(layers "F.Cu" "F.Mask" "F.Paste")
			(net "SMB_IOEXP_3V3AUX_SDA")
		)
		(pad "2" smd circle
			(at 0.40005 0)
			(size 0 0)
			(layers "F.Cu" "F.Mask" "F.Paste")
			(net "SMB_IOEXP_3V3AUX_SDA_R1")
		)
	)
	(footprint ""
		(layer "F.Cu")
		(at 88.995758 -387.342634)
		(property "Reference" "U6015"
			(at -7.723124 -7.528052 0)
			(unlocked yes)
			(layer "F.SilkS")
			(effects
				(font
					(size 0.7874 0.5842)
					(thickness 0.1524)
				)
				(justify left)
			)
		)
		(property "Value" ""
			(at 0 0 0)
			(layer "F.Fab")
			(effects
				(font
					(size 1.27 1.27)
				)
			)
		)
		(duplicate_pad_numbers_are_jumpers no)
		(fp_line
			(start -11.400028 -4.45008)
			(end -9.773158 -4.45008)
			(stroke
				(width 0.1524)
				(type default)
			)
			(layer "F.SilkS")
		)
		(fp_line
			(start -11.400028 -0.896366)
			(end -11.400028 -4.45008)
			(stroke
				(width 0.1524)
				(type default)
			)
			(layer "F.SilkS")
		)
		(fp_line
			(start -11.400028 4.45008)
			(end -11.400028 0.195834)
			(stroke
				(width 0.1524)
				(type default)
			)
			(layer "F.SilkS")
		)
		(fp_line
			(start -9.823958 4.45008)
			(end -11.400028 4.45008)
			(stroke
				(width 0.1524)
				(type default)
			)
			(layer "F.SilkS")
		)
		(fp_line
			(start 9.581642 -4.45008)
			(end 11.400028 -4.45008)
			(stroke
				(width 0.1524)
				(type default)
			)
			(layer "F.SilkS")
		)
		(fp_line
			(start 11.400028 -4.45008)
			(end 11.400028 4.45008)
			(stroke
				(width 0.1524)
				(type default)
			)
			(layer "F.SilkS")
		)
		(fp_line
			(start 11.400028 4.45008)
			(end 9.632442 4.45008)
			(stroke
				(width 0.1524)
				(type default)
			)
			(layer "F.SilkS")
		)
		(fp_poly
			(pts
				(xy 10.450068 -4.45008) (xy 10.450068 -5.21208) (xy 12.162028 -5.21208) (xy 12.162028 -3.41884)
				(xy 11.400028 -3.41884) (xy 11.400028 -4.45008)
			)
			(stroke
				(width 0)
				(type default)
			)
			(fill yes)
			(layer "F.SilkS")
		)
		(fp_line
			(start -11.400028 -4.45008)
			(end -11.400028 4.45008)
			(stroke
				(width 0.1)
				(type default)
			)
			(layer "F.Fab")
		)
		(fp_line
			(start -11.400028 4.45008)
			(end 11.400028 4.45008)
			(stroke
				(width 0.1)
				(type default)
			)
			(layer "F.Fab")
		)
		(fp_line
			(start 11.400028 -4.45008)
			(end -11.400028 -4.45008)
			(stroke
				(width 0.1)
				(type default)
			)
			(layer "F.Fab")
		)
		(fp_line
			(start 11.400028 4.45008)
			(end 11.400028 -4.45008)
			(stroke
				(width 0.1)
				(type default)
			)
			(layer "F.Fab")
		)
		(fp_poly
			(pts
				(xy 10.450068 -4.45008) (xy 10.450068 -5.21208) (xy 12.162028 -5.21208) (xy 12.162028 -3.41884)
				(xy 11.400028 -3.41884) (xy 11.400028 -4.45008)
			)
			(stroke
				(width 0)
				(type default)
			)
			(fill yes)
			(layer "F.Fab")
		)
		(pad "A1" smd oval
			(at 11.050016 -3.938524)
			(size 0.254 0.3302)
			(layers "F.Cu" "F.Mask" "F.Paste")
			(net "NCF_A1_CPU1_P1_GND")
		)
		(pad "A35" smd oval
			(at 11.050016 3.940048)
			(size 0.254 0.3302)
			(layers "F.Cu" "F.Mask" "F.Paste")
			(net "NCF_CPU1_P1_GND")
		)
		(pad "AA10" smd circle
			(at 7.602728 -1.431798)
			(size 0.381 0.381)
			(layers "F.Cu" "F.Mask" "F.Paste")
			(net "P5E_CPU1_P1_TX_BUF_DN<14>")
		)
		(pad "AA29" smd circle
			(at 7.602728 2.032254)
			(size 0.381 0.381)
			(layers "F.Cu" "F.Mask" "F.Paste")
			(net "P5E_CPU1_P1_RX_DN<14>")
		)
		(pad "AB1" smd oval
			(at 7.450074 -3.938524)
			(size 0.254 0.3302)
			(layers "F.Cu" "F.Mask" "F.Paste")
			(net "P5E_CPU1_P1_RX_BUF_DP<14>")
		)
		(pad "AB35" smd oval
			(at 7.450074 3.940048)
			(size 0.254 0.3302)
			(layers "F.Cu" "F.Mask" "F.Paste")
			(net "P5E_CPU1_P1_TX_C_DN<14>")
		)
		(pad "AC4" smd circle
			(at 7.202678 -2.817368)
			(size 0.381 0.381)
			(layers "F.Cu" "F.Mask" "F.Paste")
			(net "GND")
		)
		(pad "AC13" smd circle
			(at 7.202678 -0.79629)
			(size 0.3048 0.3048)
			(layers "F.Cu" "F.Mask" "F.Paste")
			(net "GND")
		)
		(pad "AC17" smd circle
			(at 7.202678 -0.296164)
			(size 0.3048 0.3048)
			(layers "F.Cu" "F.Mask" "F.Paste")
			(net "P0V9_CPU1_RT1_2A")
		)
		(pad "AC20" smd circle
			(at 7.202678 0.203708)
			(size 0.3048 0.3048)
			(layers "F.Cu" "F.Mask" "F.Paste")
			(net "P0V9_CPU1_RT1_2A")
		)
		(pad "AC22" smd circle
			(at 7.202678 0.703834)
			(size 0.3048 0.3048)
			(layers "F.Cu" "F.Mask" "F.Paste")
			(net "GND")
		)
		(pad "AC32" smd circle
			(at 7.202678 2.724912)
			(size 0.381 0.381)
			(layers "F.Cu" "F.Mask" "F.Paste")
			(net "GND")
		)
		(pad "AD2" smd circle
			(at 7.1501 -3.41884)
			(size 0.3048 0.3048)
			(layers "F.Cu" "F.Mask" "F.Paste")
			(net "GND")
		)
		(pad "AD34" smd circle
			(at 7.1501 3.420364)
			(size 0.3048 0.3048)
			(layers "F.Cu" "F.Mask" "F.Paste")
			(net "GND")
		)
		(pad "AE1" smd oval
			(at 6.849872 -3.938524)
			(size 0.254 0.3302)
			(layers "F.Cu" "F.Mask" "F.Paste")
			(net "GND")
		)
		(pad "AE35" smd oval
			(at 6.849872 3.940048)
			(size 0.254 0.3302)
			(layers "F.Cu" "F.Mask" "F.Paste")
			(net "GND")
		)
		(pad "AF7" smd circle
			(at 6.802628 -2.12471)
			(size 0.381 0.381)
			(layers "F.Cu" "F.Mask" "F.Paste")
			(net "P5E_CPU1_P1_TX_BUF_DP<13>")
		)
		(pad "AF26" smd circle
			(at 6.802628 1.339342)
			(size 0.381 0.381)
			(layers "F.Cu" "F.Mask" "F.Paste")
			(net "P5E_CPU1_P1_RX_DP<13>")
		)
		(pad "AG2" smd circle
			(at 6.549898 -3.41884)
			(size 0.3048 0.3048)
			(layers "F.Cu" "F.Mask" "F.Paste")
			(net "P5E_CPU1_P1_RX_BUF_DN<13>")
		)
		(pad "AG34" smd circle
			(at 6.549898 3.420364)
			(size 0.3048 0.3048)
			(layers "F.Cu" "F.Mask" "F.Paste")
			(net "P5E_CPU1_P1_TX_C_DN<13>")
		)
		(pad "AH10" smd circle
			(at 6.402578 -1.431798)
			(size 0.381 0.381)
			(layers "F.Cu" "F.Mask" "F.Paste")
			(net "P5E_CPU1_P1_TX_BUF_DN<13>")
		)
		(pad "AH29" smd circle
			(at 6.402578 2.032254)
			(size 0.381 0.381)
			(layers "F.Cu" "F.Mask" "F.Paste")
			(net "P5E_CPU1_P1_RX_DN<13>")
		)
		(pad "AJ1" smd oval
			(at 6.249924 -3.938524)
			(size 0.254 0.3302)
			(layers "F.Cu" "F.Mask" "F.Paste")
			(net "P5E_CPU1_P1_RX_BUF_DP<13>")
		)
		(pad "AJ35" smd oval
			(at 6.249924 3.940048)
			(size 0.254 0.3302)
			(layers "F.Cu" "F.Mask" "F.Paste")
			(net "P5E_CPU1_P1_TX_C_DP<13>")
		)
		(pad "AK4" smd circle
			(at 6.002528 -2.817368)
			(size 0.381 0.381)
			(layers "F.Cu" "F.Mask" "F.Paste")
			(net "GND")
		)
		(pad "AK13" smd circle
			(at 6.002528 -0.79629)
			(size 0.3048 0.3048)
			(layers "F.Cu" "F.Mask" "F.Paste")
			(net "GND")
		)
		(pad "AK17" smd circle
			(at 6.002528 -0.296164)
			(size 0.3048 0.3048)
			(layers "F.Cu" "F.Mask" "F.Paste")
			(net "P0V9_CPU1_RT1_2A")
		)
		(pad "AK20" smd circle
			(at 6.002528 0.203708)
			(size 0.3048 0.3048)
			(layers "F.Cu" "F.Mask" "F.Paste")
			(net "P0V9_CPU1_RT1_2A")
		)
		(pad "AK22" smd circle
			(at 6.002528 0.703834)
			(size 0.3048 0.3048)
			(layers "F.Cu" "F.Mask" "F.Paste")
			(net "GND")
		)
		(pad "AK32" smd circle
			(at 6.002528 2.724912)
			(size 0.381 0.381)
			(layers "F.Cu" "F.Mask" "F.Paste")
			(net "GND")
		)
		(pad "AL2" smd circle
			(at 5.94995 -3.41884)
			(size 0.3048 0.3048)
			(layers "F.Cu" "F.Mask" "F.Paste")
			(net "GND")
		)
		(pad "AL34" smd circle
			(at 5.94995 3.420364)
			(size 0.3048 0.3048)
			(layers "F.Cu" "F.Mask" "F.Paste")
			(net "GND")
		)
		(pad "AM1" smd oval
			(at 5.649976 -3.938524)
			(size 0.254 0.3302)
			(layers "F.Cu" "F.Mask" "F.Paste")
			(net "GND")
		)
		(pad "AM35" smd oval
			(at 5.649976 3.940048)
			(size 0.254 0.3302)
			(layers "F.Cu" "F.Mask" "F.Paste")
			(net "GND")
		)
		(pad "AN7" smd circle
			(at 5.602478 -2.12471)
			(size 0.381 0.381)
			(layers "F.Cu" "F.Mask" "F.Paste")
			(net "P5E_CPU1_P1_TX_BUF_DP<12>")
		)
		(pad "AN26" smd circle
			(at 5.602478 1.339342)
			(size 0.381 0.381)
			(layers "F.Cu" "F.Mask" "F.Paste")
			(net "P5E_CPU1_P1_RX_DP<12>")
		)
		(pad "AP2" smd circle
			(at 5.350002 -3.41884)
			(size 0.3048 0.3048)
			(layers "F.Cu" "F.Mask" "F.Paste")
			(net "P5E_CPU1_P1_RX_BUF_DN<12>")
		)
		(pad "AP34" smd circle
			(at 5.350002 3.420364)
			(size 0.3048 0.3048)
			(layers "F.Cu" "F.Mask" "F.Paste")
			(net "P5E_CPU1_P1_TX_C_DN<12>")
		)
		(pad "AR10" smd circle
			(at 5.202682 -1.431798)
			(size 0.381 0.381)
			(layers "F.Cu" "F.Mask" "F.Paste")
			(net "P5E_CPU1_P1_TX_BUF_DN<12>")
		)
		(pad "AR29" smd circle
			(at 5.202682 2.032254)
			(size 0.381 0.381)
			(layers "F.Cu" "F.Mask" "F.Paste")
			(net "P5E_CPU1_P1_RX_DN<12>")
		)
		(pad "AT1" smd oval
			(at 5.050028 -3.938524)
			(size 0.254 0.3302)
			(layers "F.Cu" "F.Mask" "F.Paste")
			(net "P5E_CPU1_P1_RX_BUF_DP<12>")
		)
		(pad "AT35" smd oval
			(at 5.050028 3.940048)
			(size 0.254 0.3302)
			(layers "F.Cu" "F.Mask" "F.Paste")
			(net "P5E_CPU1_P1_TX_C_DP<12>")
		)
		(pad "AU4" smd circle
			(at 4.802632 -2.817368)
			(size 0.381 0.381)
			(layers "F.Cu" "F.Mask" "F.Paste")
			(net "GND")
		)
		(pad "AU13" smd circle
			(at 4.802632 -0.79629)
			(size 0.3048 0.3048)
			(layers "F.Cu" "F.Mask" "F.Paste")
			(net "GND")
		)
		(pad "AU17" smd circle
			(at 4.802632 -0.296164)
			(size 0.3048 0.3048)
			(layers "F.Cu" "F.Mask" "F.Paste")
			(net "P0V9_CPU1_RT1_2A")
		)
		(pad "AU20" smd circle
			(at 4.802632 0.203708)
			(size 0.3048 0.3048)
			(layers "F.Cu" "F.Mask" "F.Paste")
			(net "P0V9_CPU1_RT1_2A")
		)
		(pad "AU22" smd circle
			(at 4.802632 0.703834)
			(size 0.3048 0.3048)
			(layers "F.Cu" "F.Mask" "F.Paste")
			(net "GND")
		)
		(pad "AU32" smd circle
			(at 4.802632 2.724912)
			(size 0.381 0.381)
			(layers "F.Cu" "F.Mask" "F.Paste")
			(net "GND")
		)
		(pad "AV2" smd circle
			(at 4.750054 -3.41884)
			(size 0.3048 0.3048)
			(layers "F.Cu" "F.Mask" "F.Paste")
			(net "GND")
		)
		(pad "AV34" smd circle
			(at 4.750054 3.420364)
			(size 0.3048 0.3048)
			(layers "F.Cu" "F.Mask" "F.Paste")
			(net "GND")
		)
		(pad "AW1" smd oval
			(at 4.45008 -3.938524)
			(size 0.254 0.3302)
			(layers "F.Cu" "F.Mask" "F.Paste")
			(net "GND")
		)
		(pad "AW35" smd oval
			(at 4.45008 3.940048)
			(size 0.254 0.3302)
			(layers "F.Cu" "F.Mask" "F.Paste")
			(net "GND")
		)
		(pad "AY7" smd circle
			(at 4.402582 -2.12471)
			(size 0.381 0.381)
			(layers "F.Cu" "F.Mask" "F.Paste")
			(net "P5E_CPU1_P1_TX_BUF_DP<11>")
		)
		(pad "AY26" smd circle
			(at 4.402582 1.339342)
			(size 0.381 0.381)
			(layers "F.Cu" "F.Mask" "F.Paste")
			(net "P5E_CPU1_P1_RX_DP<11>")
		)
		(pad "B3" smd oval
			(at 10.885932 -2.888488 90)
			(size 0.254 0.3302)
			(layers "F.Cu" "F.Mask" "F.Paste")
			(net "JTAG_TCK_RT_CPU1_P1")
		)
		(pad "B6" smd oval
			(at 10.885932 -2.288286 90)
			(size 0.254 0.3302)
			(layers "F.Cu" "F.Mask" "F.Paste")
			(net "JTAG_TDI_RT_CPU1_P1")
		)
		(pad "B9" smd oval
			(at 10.885932 -1.688338 90)
			(size 0.254 0.3302)
			(layers "F.Cu" "F.Mask" "F.Paste")
			(net "JTAG_TDO_RT_CPU1_P1")
		)
		(pad "B12" smd oval
			(at 10.885932 -1.08839 90)
			(size 0.254 0.3302)
			(layers "F.Cu" "F.Mask" "F.Paste")
			(net "JTAG_TMS_RT_CPU1_P1")
		)
		(pad "B16" smd oval
			(at 10.885932 -0.488442 90)
			(size 0.254 0.3302)
			(layers "F.Cu" "F.Mask" "F.Paste")
			(net "Net_2221")
		)
		(pad "B19" smd oval
			(at 10.885932 0.111506 90)
			(size 0.254 0.3302)
			(layers "F.Cu" "F.Mask" "F.Paste")
			(net "GND")
		)
		(pad "B23" smd oval
			(at 10.885932 0.711708 90)
			(size 0.254 0.3302)
			(layers "F.Cu" "F.Mask" "F.Paste")
			(net "RT_CPU1_P1_ADDR2")
		)
		(pad "B25" smd oval
			(at 10.885932 1.311656 90)
			(size 0.254 0.3302)
			(layers "F.Cu" "F.Mask" "F.Paste")
			(net "RT_CPU1_P1_ADDR3")
		)
		(pad "B28" smd oval
			(at 10.885932 1.911604 90)
			(size 0.254 0.3302)
			(layers "F.Cu" "F.Mask" "F.Paste")
			(net "SMB_RT_CPU1_P1_R2_SDA")
		)
		(pad "B31" smd oval
			(at 10.885932 2.511552 90)
			(size 0.254 0.3302)
			(layers "F.Cu" "F.Mask" "F.Paste")
			(net "SMB_RT_CPU1_P1_R2_SCL")
		)
		(pad "BA2" smd circle
			(at 4.150106 -3.41884)
			(size 0.3048 0.3048)
			(layers "F.Cu" "F.Mask" "F.Paste")
			(net "P5E_CPU1_P1_RX_BUF_DN<11>")
		)
		(pad "BA34" smd circle
			(at 4.150106 3.420364)
			(size 0.3048 0.3048)
			(layers "F.Cu" "F.Mask" "F.Paste")
			(net "P5E_CPU1_P1_TX_C_DN<11>")
		)
		(pad "BB10" smd circle
			(at 4.002532 -1.431798)
			(size 0.381 0.381)
			(layers "F.Cu" "F.Mask" "F.Paste")
			(net "P5E_CPU1_P1_TX_BUF_DN<11>")
		)
		(pad "BB29" smd circle
			(at 4.002532 2.032254)
			(size 0.381 0.381)
			(layers "F.Cu" "F.Mask" "F.Paste")
			(net "P5E_CPU1_P1_RX_DN<11>")
		)
		(pad "BC1" smd oval
			(at 3.849878 -3.938524)
			(size 0.254 0.3302)
			(layers "F.Cu" "F.Mask" "F.Paste")
			(net "P5E_CPU1_P1_RX_BUF_DP<11>")
		)
		(pad "BC35" smd oval
			(at 3.849878 3.940048)
			(size 0.254 0.3302)
			(layers "F.Cu" "F.Mask" "F.Paste")
			(net "P5E_CPU1_P1_TX_C_DP<11>")
		)
		(pad "BD4" smd circle
			(at 3.602482 -2.817368)
			(size 0.381 0.381)
			(layers "F.Cu" "F.Mask" "F.Paste")
			(net "GND")
		)
		(pad "BD13" smd circle
			(at 3.602482 -0.79629)
			(size 0.3048 0.3048)
			(layers "F.Cu" "F.Mask" "F.Paste")
			(net "GND")
		)
		(pad "BD17" smd circle
			(at 3.602482 -0.296164)
			(size 0.3048 0.3048)
			(layers "F.Cu" "F.Mask" "F.Paste")
			(net "P0V9_CPU1_RT1_2A_2D")
		)
		(pad "BD20" smd circle
			(at 3.602482 0.203708)
			(size 0.3048 0.3048)
			(layers "F.Cu" "F.Mask" "F.Paste")
			(net "P0V9_CPU1_RT1_2A_2D")
		)
		(pad "BD22" smd circle
			(at 3.602482 0.703834)
			(size 0.3048 0.3048)
			(layers "F.Cu" "F.Mask" "F.Paste")
			(net "GND")
		)
		(pad "BD32" smd circle
			(at 3.602482 2.724912)
			(size 0.381 0.381)
			(layers "F.Cu" "F.Mask" "F.Paste")
			(net "GND")
		)
		(pad "BE2" smd circle
			(at 3.549904 -3.41884)
			(size 0.3048 0.3048)
			(layers "F.Cu" "F.Mask" "F.Paste")
			(net "GND")
		)
		(pad "BE34" smd circle
			(at 3.549904 3.420364)
			(size 0.3048 0.3048)
			(layers "F.Cu" "F.Mask" "F.Paste")
			(net "GND")
		)
		(pad "BF1" smd oval
			(at 3.24993 -3.938524)
			(size 0.254 0.3302)
			(layers "F.Cu" "F.Mask" "F.Paste")
			(net "GND")
		)
		(pad "BF35" smd oval
			(at 3.24993 3.940048)
			(size 0.254 0.3302)
			(layers "F.Cu" "F.Mask" "F.Paste")
			(net "GND")
		)
		(pad "BG7" smd circle
			(at 3.202686 -2.12471)
			(size 0.381 0.381)
			(layers "F.Cu" "F.Mask" "F.Paste")
			(net "P5E_CPU1_P1_TX_BUF_DP<10>")
		)
		(pad "BG26" smd circle
			(at 3.202686 1.339342)
			(size 0.381 0.381)
			(layers "F.Cu" "F.Mask" "F.Paste")
			(net "P5E_CPU1_P1_RX_DP<10>")
		)
		(pad "BH2" smd circle
			(at 2.949956 -3.41884)
			(size 0.3048 0.3048)
			(layers "F.Cu" "F.Mask" "F.Paste")
			(net "P5E_CPU1_P1_RX_BUF_DN<10>")
		)
		(pad "BH34" smd circle
			(at 2.949956 3.420364)
			(size 0.3048 0.3048)
			(layers "F.Cu" "F.Mask" "F.Paste")
			(net "P5E_CPU1_P1_TX_C_DN<10>")
		)
		(pad "BJ10" smd circle
			(at 2.802636 -1.431798)
			(size 0.381 0.381)
			(layers "F.Cu" "F.Mask" "F.Paste")
			(net "P5E_CPU1_P1_TX_BUF_DN<10>")
		)
		(pad "BJ29" smd circle
			(at 2.802636 2.032254)
			(size 0.381 0.381)
			(layers "F.Cu" "F.Mask" "F.Paste")
			(net "P5E_CPU1_P1_RX_DN<10>")
		)
		(pad "BK1" smd oval
			(at 2.649982 -3.938524)
			(size 0.254 0.3302)
			(layers "F.Cu" "F.Mask" "F.Paste")
			(net "P5E_CPU1_P1_RX_BUF_DP<10>")
		)
		(pad "BK35" smd oval
			(at 2.649982 3.940048)
			(size 0.254 0.3302)
			(layers "F.Cu" "F.Mask" "F.Paste")
			(net "P5E_CPU1_P1_TX_C_DP<10>")
		)
		(pad "BL4" smd circle
			(at 2.402586 -2.817368)
			(size 0.381 0.381)
			(layers "F.Cu" "F.Mask" "F.Paste")
			(net "GND")
		)
		(pad "BL13" smd circle
			(at 2.402586 -0.79629)
			(size 0.3048 0.3048)
			(layers "F.Cu" "F.Mask" "F.Paste")
			(net "GND")
		)
		(pad "BL17" smd circle
			(at 2.402586 -0.296164)
			(size 0.3048 0.3048)
			(layers "F.Cu" "F.Mask" "F.Paste")
			(net "P0V9_CPU1_RT_2D")
		)
		(pad "BL20" smd circle
			(at 2.402586 0.203708)
			(size 0.3048 0.3048)
			(layers "F.Cu" "F.Mask" "F.Paste")
			(net "P0V9_CPU1_RT_2D")
		)
		(pad "BL22" smd circle
			(at 2.402586 0.703834)
			(size 0.3048 0.3048)
			(layers "F.Cu" "F.Mask" "F.Paste")
			(net "GND")
		)
		(pad "BL32" smd circle
			(at 2.402586 2.724912)
			(size 0.381 0.381)
			(layers "F.Cu" "F.Mask" "F.Paste")
			(net "GND")
		)
		(pad "BM2" smd circle
			(at 2.350008 -3.41884)
			(size 0.3048 0.3048)
			(layers "F.Cu" "F.Mask" "F.Paste")
			(net "GND")
		)
		(pad "BM34" smd circle
			(at 2.350008 3.420364)
			(size 0.3048 0.3048)
			(layers "F.Cu" "F.Mask" "F.Paste")
			(net "GND")
		)
		(pad "BN1" smd oval
			(at 2.050034 -3.938524)
			(size 0.254 0.3302)
			(layers "F.Cu" "F.Mask" "F.Paste")
			(net "GND")
		)
		(pad "BN35" smd oval
			(at 2.050034 3.940048)
			(size 0.254 0.3302)
			(layers "F.Cu" "F.Mask" "F.Paste")
			(net "GND")
		)
		(pad "BP7" smd circle
			(at 2.002536 -2.12471)
			(size 0.381 0.381)
			(layers "F.Cu" "F.Mask" "F.Paste")
			(net "P5E_CPU1_P1_TX_BUF_DP<9>")
		)
		(pad "BP26" smd circle
			(at 2.002536 1.339342)
			(size 0.381 0.381)
			(layers "F.Cu" "F.Mask" "F.Paste")
			(net "P5E_CPU1_P1_RX_DP<9>")
		)
		(pad "BR2" smd circle
			(at 1.75006 -3.41884)
			(size 0.3048 0.3048)
			(layers "F.Cu" "F.Mask" "F.Paste")
			(net "P5E_CPU1_P1_RX_BUF_DN<9>")
		)
		(pad "BR34" smd circle
			(at 1.75006 3.420364)
			(size 0.3048 0.3048)
			(layers "F.Cu" "F.Mask" "F.Paste")
			(net "P5E_CPU1_P1_TX_C_DN<9>")
		)
		(pad "BT10" smd circle
			(at 1.602486 -1.431798)
			(size 0.381 0.381)
			(layers "F.Cu" "F.Mask" "F.Paste")
			(net "P5E_CPU1_P1_TX_BUF_DN<9>")
		)
		(pad "BT29" smd circle
			(at 1.602486 2.032254)
			(size 0.381 0.381)
			(layers "F.Cu" "F.Mask" "F.Paste")
			(net "P5E_CPU1_P1_RX_DN<9>")
		)
		(pad "BU1" smd oval
			(at 1.450086 -3.938524)
			(size 0.254 0.3302)
			(layers "F.Cu" "F.Mask" "F.Paste")
			(net "P5E_CPU1_P1_RX_BUF_DP<9>")
		)
		(pad "BU35" smd oval
			(at 1.450086 3.940048)
			(size 0.254 0.3302)
			(layers "F.Cu" "F.Mask" "F.Paste")
			(net "P5E_CPU1_P1_TX_C_DP<9>")
		)
		(pad "BV4" smd circle
			(at 1.20269 -2.817368)
			(size 0.381 0.381)
			(layers "F.Cu" "F.Mask" "F.Paste")
			(net "GND")
		)
		(pad "BV13" smd circle
			(at 1.20269 -0.79629)
			(size 0.3048 0.3048)
			(layers "F.Cu" "F.Mask" "F.Paste")
			(net "GND")
		)
		(pad "BV17" smd circle
			(at 1.20269 -0.296164)
			(size 0.3048 0.3048)
			(layers "F.Cu" "F.Mask" "F.Paste")
			(net "P1V8_CPU1_RT1_1A_1D")
		)
		(pad "BV20" smd circle
			(at 1.20269 0.203708)
			(size 0.3048 0.3048)
			(layers "F.Cu" "F.Mask" "F.Paste")
			(net "P1V8_CPU1_RT1_1A")
		)
		(pad "BV22" smd circle
			(at 1.20269 0.703834)
			(size 0.3048 0.3048)
			(layers "F.Cu" "F.Mask" "F.Paste")
			(net "GND")
		)
		(pad "BV32" smd circle
			(at 1.20269 2.724912)
			(size 0.381 0.381)
			(layers "F.Cu" "F.Mask" "F.Paste")
			(net "GND")
		)
		(pad "BW2" smd circle
			(at 1.150112 -3.41884)
			(size 0.3048 0.3048)
			(layers "F.Cu" "F.Mask" "F.Paste")
			(net "GND")
		)
		(pad "BW34" smd circle
			(at 1.150112 3.420364)
			(size 0.3048 0.3048)
			(layers "F.Cu" "F.Mask" "F.Paste")
			(net "GND")
		)
		(pad "BY1" smd oval
			(at 0.849884 -3.938524)
			(size 0.254 0.3302)
			(layers "F.Cu" "F.Mask" "F.Paste")
			(net "GND")
		)
		(pad "BY35" smd oval
			(at 0.849884 3.940048)
			(size 0.254 0.3302)
			(layers "F.Cu" "F.Mask" "F.Paste")
			(net "GND")
		)
		(pad "C2" smd circle
			(at 10.750042 -3.41884)
			(size 0.3048 0.3048)
			(layers "F.Cu" "F.Mask" "F.Paste")
			(net "NCF_CPU1_P1_GND")
		)
		(pad "C34" smd circle
			(at 10.750042 3.420364)
			(size 0.3048 0.3048)
			(layers "F.Cu" "F.Mask" "F.Paste")
			(net "NCF_CPU1_P1_GND")
		)
		(pad "CA7" smd circle
			(at 0.80264 -2.12471)
			(size 0.381 0.381)
			(layers "F.Cu" "F.Mask" "F.Paste")
			(net "P5E_CPU1_P1_TX_BUF_DP<8>")
		)
		(pad "CA26" smd circle
			(at 0.80264 1.339342)
			(size 0.381 0.381)
			(layers "F.Cu" "F.Mask" "F.Paste")
			(net "P5E_CPU1_P1_RX_DP<8>")
		)
		(pad "CB2" smd circle
			(at 0.54991 -3.41884)
			(size 0.3048 0.3048)
			(layers "F.Cu" "F.Mask" "F.Paste")
			(net "P5E_CPU1_P1_RX_BUF_DN<8>")
		)
		(pad "CB34" smd circle
			(at 0.54991 3.420364)
			(size 0.3048 0.3048)
			(layers "F.Cu" "F.Mask" "F.Paste")
			(net "P5E_CPU1_P1_TX_C_DN<8>")
		)
		(pad "CC10" smd circle
			(at 0.40259 -1.431798)
			(size 0.381 0.381)
			(layers "F.Cu" "F.Mask" "F.Paste")
			(net "P5E_CPU1_P1_TX_BUF_DN<8>")
		)
		(pad "CC29" smd circle
			(at 0.40259 2.032254)
			(size 0.381 0.381)
			(layers "F.Cu" "F.Mask" "F.Paste")
			(net "P5E_CPU1_P1_RX_DN<8>")
		)
		(pad "CD1" smd oval
			(at 0.249936 -3.938524)
			(size 0.254 0.3302)
			(layers "F.Cu" "F.Mask" "F.Paste")
			(net "P5E_CPU1_P1_RX_BUF_DP<8>")
		)
		(pad "CD35" smd oval
			(at 0.249936 3.940048)
			(size 0.254 0.3302)
			(layers "F.Cu" "F.Mask" "F.Paste")
			(net "P5E_CPU1_P1_TX_C_DP<8>")
		)
		(pad "CE4" smd circle
			(at 0.00254 -2.817368)
			(size 0.381 0.381)
			(layers "F.Cu" "F.Mask" "F.Paste")
			(net "GND")
		)
		(pad "CE13" smd circle
			(at 0.00254 -0.79629)
			(size 0.3048 0.3048)
			(layers "F.Cu" "F.Mask" "F.Paste")
			(net "GND")
		)
		(pad "CE17" smd circle
			(at 0.00254 -0.296164)
			(size 0.3048 0.3048)
			(layers "F.Cu" "F.Mask" "F.Paste")
			(net "P1V8_CPU1_RT1_1A")
		)
		(pad "CE20" smd circle
			(at 0.00254 0.203708)
			(size 0.3048 0.3048)
			(layers "F.Cu" "F.Mask" "F.Paste")
			(net "P1V8_CPU1_RT1_1A")
		)
		(pad "CE22" smd circle
			(at 0.00254 0.703834)
			(size 0.3048 0.3048)
			(layers "F.Cu" "F.Mask" "F.Paste")
			(net "GND")
		)
		(pad "CE32" smd circle
			(at 0.00254 2.724912)
			(size 0.381 0.381)
			(layers "F.Cu" "F.Mask" "F.Paste")
			(net "GND")
		)
		(pad "CF2" smd circle
			(at -0.050038 -3.41884)
			(size 0.3048 0.3048)
			(layers "F.Cu" "F.Mask" "F.Paste")
			(net "GND")
		)
		(pad "CF34" smd circle
			(at -0.050038 3.420364)
			(size 0.3048 0.3048)
			(layers "F.Cu" "F.Mask" "F.Paste")
			(net "GND")
		)
		(pad "CG1" smd oval
			(at -0.350012 -3.938524)
			(size 0.254 0.3302)
			(layers "F.Cu" "F.Mask" "F.Paste")
			(net "GND")
		)
		(pad "CG35" smd oval
			(at -0.350012 3.940048)
			(size 0.254 0.3302)
			(layers "F.Cu" "F.Mask" "F.Paste")
			(net "GND")
		)
		(pad "CH7" smd circle
			(at -0.39751 -2.12471)
			(size 0.381 0.381)
			(layers "F.Cu" "F.Mask" "F.Paste")
			(net "P5E_CPU1_P1_TX_BUF_DP<7>")
		)
		(pad "CH26" smd circle
			(at -0.39751 1.339342)
			(size 0.381 0.381)
			(layers "F.Cu" "F.Mask" "F.Paste")
			(net "P5E_CPU1_P1_RX_DP<7>")
		)
		(pad "CJ2" smd circle
			(at -0.649986 -3.41884)
			(size 0.3048 0.3048)
			(layers "F.Cu" "F.Mask" "F.Paste")
			(net "P5E_CPU1_P1_RX_BUF_DN<7>")
		)
		(pad "CJ34" smd circle
			(at -0.649986 3.420364)
			(size 0.3048 0.3048)
			(layers "F.Cu" "F.Mask" "F.Paste")
			(net "P5E_CPU1_P1_TX_C_DN<7>")
		)
		(pad "CK10" smd circle
			(at -0.797306 -1.431798)
			(size 0.381 0.381)
			(layers "F.Cu" "F.Mask" "F.Paste")
			(net "P5E_CPU1_P1_TX_BUF_DN<7>")
		)
		(pad "CK29" smd circle
			(at -0.797306 2.032254)
			(size 0.381 0.381)
			(layers "F.Cu" "F.Mask" "F.Paste")
			(net "P5E_CPU1_P1_RX_DN<7>")
		)
		(pad "CL1" smd oval
			(at -0.94996 -3.938524)
			(size 0.254 0.3302)
			(layers "F.Cu" "F.Mask" "F.Paste")
			(net "P5E_CPU1_P1_RX_BUF_DP<7>")
		)
		(pad "CL35" smd oval
			(at -0.94996 3.940048)
			(size 0.254 0.3302)
			(layers "F.Cu" "F.Mask" "F.Paste")
			(net "P5E_CPU1_P1_TX_C_DP<7>")
		)
		(pad "CM4" smd circle
			(at -1.197356 -2.817368)
			(size 0.381 0.381)
			(layers "F.Cu" "F.Mask" "F.Paste")
			(net "GND")
		)
		(pad "CM13" smd circle
			(at -1.197356 -0.79629)
			(size 0.3048 0.3048)
			(layers "F.Cu" "F.Mask" "F.Paste")
			(net "GND")
		)
		(pad "CM17" smd circle
			(at -1.197356 -0.296164)
			(size 0.3048 0.3048)
			(layers "F.Cu" "F.Mask" "F.Paste")
			(net "P1V8_CPU1_RT1_1A")
		)
		(pad "CM20" smd circle
			(at -1.197356 0.203708)
			(size 0.3048 0.3048)
			(layers "F.Cu" "F.Mask" "F.Paste")
			(net "P1V8_CPU1_RT1_1A")
		)
		(pad "CM22" smd circle
			(at -1.197356 0.703834)
			(size 0.3048 0.3048)
			(layers "F.Cu" "F.Mask" "F.Paste")
			(net "GND")
		)
		(pad "CM32" smd circle
			(at -1.197356 2.724912)
			(size 0.381 0.381)
			(layers "F.Cu" "F.Mask" "F.Paste")
			(net "GND")
		)
		(pad "CN2" smd circle
			(at -1.249934 -3.41884)
			(size 0.3048 0.3048)
			(layers "F.Cu" "F.Mask" "F.Paste")
			(net "GND")
		)
		(pad "CN34" smd circle
			(at -1.249934 3.420364)
			(size 0.3048 0.3048)
			(layers "F.Cu" "F.Mask" "F.Paste")
			(net "GND")
		)
		(pad "CP1" smd oval
			(at -1.549908 -3.938524)
			(size 0.254 0.3302)
			(layers "F.Cu" "F.Mask" "F.Paste")
			(net "GND")
		)
		(pad "CP35" smd oval
			(at -1.549908 3.940048)
			(size 0.254 0.3302)
			(layers "F.Cu" "F.Mask" "F.Paste")
			(net "GND")
		)
		(pad "CR7" smd circle
			(at -1.597406 -2.12471)
			(size 0.381 0.381)
			(layers "F.Cu" "F.Mask" "F.Paste")
			(net "P5E_CPU1_P1_TX_BUF_DP<6>")
		)
		(pad "CR26" smd circle
			(at -1.597406 1.339342)
			(size 0.381 0.381)
			(layers "F.Cu" "F.Mask" "F.Paste")
			(net "P5E_CPU1_P1_RX_DP<6>")
		)
		(pad "CT2" smd circle
			(at -1.849882 -3.41884)
			(size 0.3048 0.3048)
			(layers "F.Cu" "F.Mask" "F.Paste")
			(net "P5E_CPU1_P1_RX_BUF_DN<6>")
		)
		(pad "CT34" smd circle
			(at -1.849882 3.420364)
			(size 0.3048 0.3048)
			(layers "F.Cu" "F.Mask" "F.Paste")
			(net "P5E_CPU1_P1_TX_C_DN<6>")
		)
		(pad "CU10" smd circle
			(at -1.997456 -1.431798)
			(size 0.381 0.381)
			(layers "F.Cu" "F.Mask" "F.Paste")
			(net "P5E_CPU1_P1_TX_BUF_DN<6>")
		)
		(pad "CU29" smd circle
			(at -1.997456 2.032254)
			(size 0.381 0.381)
			(layers "F.Cu" "F.Mask" "F.Paste")
			(net "P5E_CPU1_P1_RX_DN<6>")
		)
		(pad "CV1" smd oval
			(at -2.15011 -3.938524)
			(size 0.254 0.3302)
			(layers "F.Cu" "F.Mask" "F.Paste")
			(net "P5E_CPU1_P1_RX_BUF_DP<6>")
		)
		(pad "CV35" smd oval
			(at -2.15011 3.940048)
			(size 0.254 0.3302)
			(layers "F.Cu" "F.Mask" "F.Paste")
			(net "P5E_CPU1_P1_TX_C_DP<6>")
		)
		(pad "CW4" smd circle
			(at -2.397506 -2.817368)
			(size 0.381 0.381)
			(layers "F.Cu" "F.Mask" "F.Paste")
			(net "GND")
		)
		(pad "CW13" smd circle
			(at -2.397506 -0.79629)
			(size 0.3048 0.3048)
			(layers "F.Cu" "F.Mask" "F.Paste")
			(net "GND")
		)
		(pad "CW17" smd circle
			(at -2.397506 -0.296164)
			(size 0.3048 0.3048)
			(layers "F.Cu" "F.Mask" "F.Paste")
			(net "P0V9_CPU1_RT_2D")
		)
		(pad "CW20" smd circle
			(at -2.397506 0.203708)
			(size 0.3048 0.3048)
			(layers "F.Cu" "F.Mask" "F.Paste")
			(net "P0V9_CPU1_RT_2D")
		)
		(pad "CW22" smd circle
			(at -2.397506 0.703834)
			(size 0.3048 0.3048)
			(layers "F.Cu" "F.Mask" "F.Paste")
			(net "GND")
		)
		(pad "CW32" smd circle
			(at -2.397506 2.724912)
			(size 0.381 0.381)
			(layers "F.Cu" "F.Mask" "F.Paste")
			(net "GND")
		)
		(pad "CY2" smd circle
			(at -2.450084 -3.41884)
			(size 0.3048 0.3048)
			(layers "F.Cu" "F.Mask" "F.Paste")
			(net "GND")
		)
		(pad "CY34" smd circle
			(at -2.450084 3.420364)
			(size 0.3048 0.3048)
			(layers "F.Cu" "F.Mask" "F.Paste")
			(net "GND")
		)
		(pad "D1" smd oval
			(at 10.450068 -3.938524)
			(size 0.254 0.3302)
			(layers "F.Cu" "F.Mask" "F.Paste")
			(net "NCF_CPU1_P1_GND")
		)
		(pad "D35" smd oval
			(at 10.450068 3.940048)
			(size 0.254 0.3302)
			(layers "F.Cu" "F.Mask" "F.Paste")
			(net "NCF_CPU1_P1_GND")
		)
		(pad "DA1" smd oval
			(at -2.750058 -3.938524)
			(size 0.254 0.3302)
			(layers "F.Cu" "F.Mask" "F.Paste")
			(net "GND")
		)
		(pad "DA35" smd oval
			(at -2.750058 3.940048)
			(size 0.254 0.3302)
			(layers "F.Cu" "F.Mask" "F.Paste")
			(net "GND")
		)
		(pad "DB7" smd circle
			(at -2.797302 -2.12471)
			(size 0.381 0.381)
			(layers "F.Cu" "F.Mask" "F.Paste")
			(net "P5E_CPU1_P1_TX_BUF_DP<5>")
		)
		(pad "DB26" smd circle
			(at -2.797302 1.339342)
			(size 0.381 0.381)
			(layers "F.Cu" "F.Mask" "F.Paste")
			(net "P5E_CPU1_P1_RX_DP<5>")
		)
		(pad "DC2" smd circle
			(at -3.050032 -3.41884)
			(size 0.3048 0.3048)
			(layers "F.Cu" "F.Mask" "F.Paste")
			(net "P5E_CPU1_P1_RX_BUF_DN<5>")
		)
		(pad "DC34" smd circle
			(at -3.050032 3.420364)
			(size 0.3048 0.3048)
			(layers "F.Cu" "F.Mask" "F.Paste")
			(net "P5E_CPU1_P1_TX_C_DN<5>")
		)
		(pad "DD10" smd circle
			(at -3.197352 -1.431798)
			(size 0.381 0.381)
			(layers "F.Cu" "F.Mask" "F.Paste")
			(net "P5E_CPU1_P1_TX_BUF_DN<5>")
		)
		(pad "DD29" smd circle
			(at -3.197352 2.032254)
			(size 0.381 0.381)
			(layers "F.Cu" "F.Mask" "F.Paste")
			(net "P5E_CPU1_P1_RX_DN<5>")
		)
		(pad "DE1" smd oval
			(at -3.350006 -3.938524)
			(size 0.254 0.3302)
			(layers "F.Cu" "F.Mask" "F.Paste")
			(net "P5E_CPU1_P1_RX_BUF_DP<5>")
		)
		(pad "DE35" smd oval
			(at -3.350006 3.940048)
			(size 0.254 0.3302)
			(layers "F.Cu" "F.Mask" "F.Paste")
			(net "P5E_CPU1_P1_TX_C_DP<5>")
		)
		(pad "DF4" smd circle
			(at -3.597402 -2.817368)
			(size 0.381 0.381)
			(layers "F.Cu" "F.Mask" "F.Paste")
			(net "GND")
		)
		(pad "DF13" smd circle
			(at -3.597402 -0.79629)
			(size 0.3048 0.3048)
			(layers "F.Cu" "F.Mask" "F.Paste")
			(net "GND")
		)
		(pad "DF17" smd circle
			(at -3.597402 -0.296164)
			(size 0.3048 0.3048)
			(layers "F.Cu" "F.Mask" "F.Paste")
			(net "P0V9_CPU1_RT1_2A_2D")
		)
		(pad "DF20" smd circle
			(at -3.597402 0.203708)
			(size 0.3048 0.3048)
			(layers "F.Cu" "F.Mask" "F.Paste")
			(net "P0V9_CPU1_RT1_2A_2D")
		)
		(pad "DF22" smd circle
			(at -3.597402 0.703834)
			(size 0.3048 0.3048)
			(layers "F.Cu" "F.Mask" "F.Paste")
			(net "GND")
		)
		(pad "DF32" smd circle
			(at -3.597402 2.724912)
			(size 0.381 0.381)
			(layers "F.Cu" "F.Mask" "F.Paste")
			(net "GND")
		)
		(pad "DG2" smd circle
			(at -3.64998 -3.41884)
			(size 0.3048 0.3048)
			(layers "F.Cu" "F.Mask" "F.Paste")
			(net "GND")
		)
		(pad "DG34" smd circle
			(at -3.64998 3.420364)
			(size 0.3048 0.3048)
			(layers "F.Cu" "F.Mask" "F.Paste")
			(net "GND")
		)
		(pad "DH1" smd oval
			(at -3.949954 -3.938524)
			(size 0.254 0.3302)
			(layers "F.Cu" "F.Mask" "F.Paste")
			(net "GND")
		)
		(pad "DH35" smd oval
			(at -3.949954 3.940048)
			(size 0.254 0.3302)
			(layers "F.Cu" "F.Mask" "F.Paste")
			(net "GND")
		)
		(pad "DJ7" smd circle
			(at -3.997452 -2.12471)
			(size 0.381 0.381)
			(layers "F.Cu" "F.Mask" "F.Paste")
			(net "P5E_CPU1_P1_TX_BUF_DP<4>")
		)
		(pad "DJ26" smd circle
			(at -3.997452 1.339342)
			(size 0.381 0.381)
			(layers "F.Cu" "F.Mask" "F.Paste")
			(net "P5E_CPU1_P1_RX_DP<4>")
		)
		(pad "DK2" smd circle
			(at -4.249928 -3.41884)
			(size 0.3048 0.3048)
			(layers "F.Cu" "F.Mask" "F.Paste")
			(net "P5E_CPU1_P1_RX_BUF_DN<4>")
		)
		(pad "DK34" smd circle
			(at -4.249928 3.420364)
			(size 0.3048 0.3048)
			(layers "F.Cu" "F.Mask" "F.Paste")
			(net "P5E_CPU1_P1_TX_C_DN<4>")
		)
		(pad "DL10" smd circle
			(at -4.397502 -1.431798)
			(size 0.381 0.381)
			(layers "F.Cu" "F.Mask" "F.Paste")
			(net "P5E_CPU1_P1_TX_BUF_DN<4>")
		)
		(pad "DL29" smd circle
			(at -4.397502 2.032254)
			(size 0.381 0.381)
			(layers "F.Cu" "F.Mask" "F.Paste")
			(net "P5E_CPU1_P1_RX_DN<4>")
		)
		(pad "DM1" smd oval
			(at -4.549902 -3.938524)
			(size 0.254 0.3302)
			(layers "F.Cu" "F.Mask" "F.Paste")
			(net "P5E_CPU1_P1_RX_BUF_DP<4>")
		)
		(pad "DM35" smd oval
			(at -4.549902 3.940048)
			(size 0.254 0.3302)
			(layers "F.Cu" "F.Mask" "F.Paste")
			(net "P5E_CPU1_P1_TX_C_DP<4>")
		)
		(pad "DN4" smd circle
			(at -4.797298 -2.817368)
			(size 0.381 0.381)
			(layers "F.Cu" "F.Mask" "F.Paste")
			(net "GND")
		)
		(pad "DN13" smd circle
			(at -4.797298 -0.79629)
			(size 0.3048 0.3048)
			(layers "F.Cu" "F.Mask" "F.Paste")
			(net "GND")
		)
		(pad "DN17" smd circle
			(at -4.797298 -0.296164)
			(size 0.3048 0.3048)
			(layers "F.Cu" "F.Mask" "F.Paste")
			(net "P0V9_CPU1_RT1_2A")
		)
		(pad "DN20" smd circle
			(at -4.797298 0.203708)
			(size 0.3048 0.3048)
			(layers "F.Cu" "F.Mask" "F.Paste")
			(net "P0V9_CPU1_RT1_2A")
		)
		(pad "DN22" smd circle
			(at -4.797298 0.703834)
			(size 0.3048 0.3048)
			(layers "F.Cu" "F.Mask" "F.Paste")
			(net "GND")
		)
		(pad "DN32" smd circle
			(at -4.797298 2.724912)
			(size 0.381 0.381)
			(layers "F.Cu" "F.Mask" "F.Paste")
			(net "GND")
		)
		(pad "DP2" smd circle
			(at -4.849876 -3.41884)
			(size 0.3048 0.3048)
			(layers "F.Cu" "F.Mask" "F.Paste")
			(net "GND")
		)
		(pad "DP34" smd circle
			(at -4.849876 3.420364)
			(size 0.3048 0.3048)
			(layers "F.Cu" "F.Mask" "F.Paste")
			(net "GND")
		)
		(pad "DR1" smd oval
			(at -5.150104 -3.938524)
			(size 0.254 0.3302)
			(layers "F.Cu" "F.Mask" "F.Paste")
			(net "GND")
		)
		(pad "DR35" smd oval
			(at -5.150104 3.940048)
			(size 0.254 0.3302)
			(layers "F.Cu" "F.Mask" "F.Paste")
			(net "GND")
		)
		(pad "DT7" smd circle
			(at -5.197348 -2.12471)
			(size 0.381 0.381)
			(layers "F.Cu" "F.Mask" "F.Paste")
			(net "P5E_CPU1_P1_TX_BUF_DP<3>")
		)
		(pad "DT26" smd circle
			(at -5.197348 1.339342)
			(size 0.381 0.381)
			(layers "F.Cu" "F.Mask" "F.Paste")
			(net "P5E_CPU1_P1_RX_DP<3>")
		)
		(pad "DU2" smd circle
			(at -5.450078 -3.41884)
			(size 0.3048 0.3048)
			(layers "F.Cu" "F.Mask" "F.Paste")
			(net "P5E_CPU1_P1_RX_BUF_DN<3>")
		)
		(pad "DU34" smd circle
			(at -5.450078 3.420364)
			(size 0.3048 0.3048)
			(layers "F.Cu" "F.Mask" "F.Paste")
			(net "P5E_CPU1_P1_TX_C_DN<3>")
		)
		(pad "DV10" smd circle
			(at -5.597398 -1.431798)
			(size 0.381 0.381)
			(layers "F.Cu" "F.Mask" "F.Paste")
			(net "P5E_CPU1_P1_TX_BUF_DN<3>")
		)
		(pad "DV29" smd circle
			(at -5.597398 2.032254)
			(size 0.381 0.381)
			(layers "F.Cu" "F.Mask" "F.Paste")
			(net "P5E_CPU1_P1_RX_DN<3>")
		)
		(pad "DW1" smd oval
			(at -5.750052 -3.938524)
			(size 0.254 0.3302)
			(layers "F.Cu" "F.Mask" "F.Paste")
			(net "P5E_CPU1_P1_RX_BUF_DP<3>")
		)
		(pad "DW35" smd oval
			(at -5.750052 3.940048)
			(size 0.254 0.3302)
			(layers "F.Cu" "F.Mask" "F.Paste")
			(net "P5E_CPU1_P1_TX_C_DP<3>")
		)
		(pad "DY4" smd circle
			(at -5.997448 -2.817368)
			(size 0.381 0.381)
			(layers "F.Cu" "F.Mask" "F.Paste")
			(net "GND")
		)
		(pad "DY13" smd circle
			(at -5.997448 -0.79629)
			(size 0.3048 0.3048)
			(layers "F.Cu" "F.Mask" "F.Paste")
			(net "GND")
		)
		(pad "DY17" smd circle
			(at -5.997448 -0.296164)
			(size 0.3048 0.3048)
			(layers "F.Cu" "F.Mask" "F.Paste")
			(net "P0V9_CPU1_RT1_2A")
		)
		(pad "DY20" smd circle
			(at -5.997448 0.203708)
			(size 0.3048 0.3048)
			(layers "F.Cu" "F.Mask" "F.Paste")
			(net "P0V9_CPU1_RT1_2A")
		)
		(pad "DY22" smd circle
			(at -5.997448 0.703834)
			(size 0.3048 0.3048)
			(layers "F.Cu" "F.Mask" "F.Paste")
			(net "GND")
		)
		(pad "DY32" smd circle
			(at -5.997448 2.724912)
			(size 0.381 0.381)
			(layers "F.Cu" "F.Mask" "F.Paste")
			(net "GND")
		)
		(pad "E8" smd circle
			(at 10.366502 -1.988312)
			(size 0.3048 0.3048)
			(layers "F.Cu" "F.Mask" "F.Paste")
			(net "JTAG_TRST_RT_CPU1_P1_N")
		)
		(pad "E11" smd circle
			(at 10.366502 -1.388364)
			(size 0.3048 0.3048)
			(layers "F.Cu" "F.Mask" "F.Paste")
			(net "RXDET_BYP_RT_CPU1_P1")
		)
		(pad "E14" smd circle
			(at 10.366502 -0.788416)
			(size 0.3048 0.3048)
			(layers "F.Cu" "F.Mask" "F.Paste")
			(net "GND")
		)
		(pad "E18" smd circle
			(at 10.366502 -0.188468)
			(size 0.3048 0.3048)
			(layers "F.Cu" "F.Mask" "F.Paste")
			(net "Net_2220")
		)
		(pad "E27" smd circle
			(at 10.366502 1.61163)
			(size 0.3048 0.3048)
			(layers "F.Cu" "F.Mask" "F.Paste")
			(net "GND")
		)
		(pad "E30" smd circle
			(at 10.366502 2.211578)
			(size 0.3048 0.3048)
			(layers "F.Cu" "F.Mask" "F.Paste")
			(net "GND")
		)
		(pad "E33" smd circle
			(at 10.366502 2.811526)
			(size 0.3048 0.3048)
			(layers "F.Cu" "F.Mask" "F.Paste")
			(net "GND")
		)
		(pad "EA2" smd circle
			(at -6.050026 -3.41884)
			(size 0.3048 0.3048)
			(layers "F.Cu" "F.Mask" "F.Paste")
			(net "GND")
		)
		(pad "EA34" smd circle
			(at -6.050026 3.420364)
			(size 0.3048 0.3048)
			(layers "F.Cu" "F.Mask" "F.Paste")
			(net "GND")
		)
		(pad "EB1" smd oval
			(at -6.35 -3.938524)
			(size 0.254 0.3302)
			(layers "F.Cu" "F.Mask" "F.Paste")
			(net "GND")
		)
		(pad "EB35" smd oval
			(at -6.35 3.940048)
			(size 0.254 0.3302)
			(layers "F.Cu" "F.Mask" "F.Paste")
			(net "GND")
		)
		(pad "EC7" smd circle
			(at -6.397498 -2.12471)
			(size 0.381 0.381)
			(layers "F.Cu" "F.Mask" "F.Paste")
			(net "P5E_CPU1_P1_TX_BUF_DP<2>")
		)
		(pad "EC26" smd circle
			(at -6.397498 1.339342)
			(size 0.381 0.381)
			(layers "F.Cu" "F.Mask" "F.Paste")
			(net "P5E_CPU1_P1_RX_DP<2>")
		)
		(pad "ED2" smd circle
			(at -6.649974 -3.41884)
			(size 0.3048 0.3048)
			(layers "F.Cu" "F.Mask" "F.Paste")
			(net "P5E_CPU1_P1_RX_BUF_DN<2>")
		)
		(pad "ED34" smd circle
			(at -6.649974 3.420364)
			(size 0.3048 0.3048)
			(layers "F.Cu" "F.Mask" "F.Paste")
			(net "P5E_CPU1_P1_TX_C_DN<2>")
		)
		(pad "EE10" smd circle
			(at -6.797294 -1.431798)
			(size 0.381 0.381)
			(layers "F.Cu" "F.Mask" "F.Paste")
			(net "P5E_CPU1_P1_TX_BUF_DN<2>")
		)
		(pad "EE29" smd circle
			(at -6.797294 2.032254)
			(size 0.381 0.381)
			(layers "F.Cu" "F.Mask" "F.Paste")
			(net "P5E_CPU1_P1_RX_DN<2>")
		)
		(pad "EF1" smd oval
			(at -6.949948 -3.938524)
			(size 0.254 0.3302)
			(layers "F.Cu" "F.Mask" "F.Paste")
			(net "P5E_CPU1_P1_RX_BUF_DP<2>")
		)
		(pad "EF35" smd oval
			(at -6.949948 3.940048)
			(size 0.254 0.3302)
			(layers "F.Cu" "F.Mask" "F.Paste")
			(net "P5E_CPU1_P1_TX_C_DP<2>")
		)
		(pad "EG4" smd circle
			(at -7.197344 -2.817368)
			(size 0.381 0.381)
			(layers "F.Cu" "F.Mask" "F.Paste")
			(net "GND")
		)
		(pad "EG13" smd circle
			(at -7.197344 -0.79629)
			(size 0.3048 0.3048)
			(layers "F.Cu" "F.Mask" "F.Paste")
			(net "GND")
		)
		(pad "EG17" smd circle
			(at -7.197344 -0.296164)
			(size 0.3048 0.3048)
			(layers "F.Cu" "F.Mask" "F.Paste")
			(net "P0V9_CPU1_RT1_2A")
		)
		(pad "EG20" smd circle
			(at -7.197344 0.203708)
			(size 0.3048 0.3048)
			(layers "F.Cu" "F.Mask" "F.Paste")
			(net "P0V9_CPU1_RT1_2A")
		)
		(pad "EG22" smd circle
			(at -7.197344 0.703834)
			(size 0.3048 0.3048)
			(layers "F.Cu" "F.Mask" "F.Paste")
			(net "GND")
		)
		(pad "EG32" smd circle
			(at -7.197344 2.724912)
			(size 0.381 0.381)
			(layers "F.Cu" "F.Mask" "F.Paste")
			(net "GND")
		)
		(pad "EH2" smd circle
			(at -7.249922 -3.41884)
			(size 0.3048 0.3048)
			(layers "F.Cu" "F.Mask" "F.Paste")
			(net "GND")
		)
		(pad "EH34" smd circle
			(at -7.249922 3.420364)
			(size 0.3048 0.3048)
			(layers "F.Cu" "F.Mask" "F.Paste")
			(net "GND")
		)
		(pad "EJ1" smd oval
			(at -7.549896 -3.938524)
			(size 0.254 0.3302)
			(layers "F.Cu" "F.Mask" "F.Paste")
			(net "GND")
		)
		(pad "EJ35" smd oval
			(at -7.549896 3.940048)
			(size 0.254 0.3302)
			(layers "F.Cu" "F.Mask" "F.Paste")
			(net "GND")
		)
		(pad "EK7" smd circle
			(at -7.597394 -2.12471)
			(size 0.381 0.381)
			(layers "F.Cu" "F.Mask" "F.Paste")
			(net "P5E_CPU1_P1_TX_BUF_DP<1>")
		)
		(pad "EK26" smd circle
			(at -7.597394 1.339342)
			(size 0.381 0.381)
			(layers "F.Cu" "F.Mask" "F.Paste")
			(net "P5E_CPU1_P1_RX_DP<1>")
		)
		(pad "EL2" smd circle
			(at -7.850124 -3.41884)
			(size 0.3048 0.3048)
			(layers "F.Cu" "F.Mask" "F.Paste")
			(net "P5E_CPU1_P1_RX_BUF_DN<1>")
		)
		(pad "EL34" smd circle
			(at -7.850124 3.420364)
			(size 0.3048 0.3048)
			(layers "F.Cu" "F.Mask" "F.Paste")
			(net "P5E_CPU1_P1_TX_C_DP<1>")
		)
		(pad "EM10" smd circle
			(at -7.997444 -1.431798)
			(size 0.381 0.381)
			(layers "F.Cu" "F.Mask" "F.Paste")
			(net "P5E_CPU1_P1_TX_BUF_DN<1>")
		)
		(pad "EM29" smd circle
			(at -7.997444 2.032254)
			(size 0.381 0.381)
			(layers "F.Cu" "F.Mask" "F.Paste")
			(net "P5E_CPU1_P1_RX_DN<1>")
		)
		(pad "EN1" smd oval
			(at -8.150098 -3.938524)
			(size 0.254 0.3302)
			(layers "F.Cu" "F.Mask" "F.Paste")
			(net "P5E_CPU1_P1_RX_BUF_DP<1>")
		)
		(pad "EN35" smd oval
			(at -8.150098 3.940048)
			(size 0.254 0.3302)
			(layers "F.Cu" "F.Mask" "F.Paste")
			(net "P5E_CPU1_P1_TX_C_DN<1>")
		)
		(pad "EP4" smd circle
			(at -8.397494 -2.817368)
			(size 0.381 0.381)
			(layers "F.Cu" "F.Mask" "F.Paste")
			(net "GND")
		)
		(pad "EP13" smd circle
			(at -8.397494 -0.79629)
			(size 0.3048 0.3048)
			(layers "F.Cu" "F.Mask" "F.Paste")
			(net "GND")
		)
		(pad "EP17" smd circle
			(at -8.397494 -0.296164)
			(size 0.3048 0.3048)
			(layers "F.Cu" "F.Mask" "F.Paste")
			(net "P0V9_CPU1_RT1_2A")
		)
		(pad "EP20" smd circle
			(at -8.397494 0.203708)
			(size 0.3048 0.3048)
			(layers "F.Cu" "F.Mask" "F.Paste")
			(net "P0V9_CPU1_RT1_2A")
		)
		(pad "EP22" smd circle
			(at -8.397494 0.703834)
			(size 0.3048 0.3048)
			(layers "F.Cu" "F.Mask" "F.Paste")
			(net "GND")
		)
		(pad "EP32" smd circle
			(at -8.397494 2.724912)
			(size 0.381 0.381)
			(layers "F.Cu" "F.Mask" "F.Paste")
			(net "GND")
		)
		(pad "ER2" smd circle
			(at -8.450072 -3.41884)
			(size 0.3048 0.3048)
			(layers "F.Cu" "F.Mask" "F.Paste")
			(net "GND")
		)
		(pad "ER34" smd circle
			(at -8.450072 3.420364)
			(size 0.3048 0.3048)
			(layers "F.Cu" "F.Mask" "F.Paste")
			(net "GND")
		)
		(pad "ET1" smd oval
			(at -8.750046 -3.938524)
			(size 0.254 0.3302)
			(layers "F.Cu" "F.Mask" "F.Paste")
			(net "GND")
		)
		(pad "ET35" smd oval
			(at -8.750046 3.940048)
			(size 0.254 0.3302)
			(layers "F.Cu" "F.Mask" "F.Paste")
			(net "GND")
		)
		(pad "EU7" smd circle
			(at -8.79729 -2.12471)
			(size 0.381 0.381)
			(layers "F.Cu" "F.Mask" "F.Paste")
			(net "P5E_CPU1_P1_TX_BUF_DP<0>")
		)
		(pad "EU26" smd circle
			(at -8.79729 1.339342)
			(size 0.381 0.381)
			(layers "F.Cu" "F.Mask" "F.Paste")
			(net "P5E_CPU1_P1_RX_DP<0>")
		)
		(pad "EV2" smd circle
			(at -9.05002 -3.41884)
			(size 0.3048 0.3048)
			(layers "F.Cu" "F.Mask" "F.Paste")
			(net "P5E_CPU1_P1_RX_BUF_DN<0>")
		)
		(pad "EV34" smd circle
			(at -9.05002 3.420364)
			(size 0.3048 0.3048)
			(layers "F.Cu" "F.Mask" "F.Paste")
			(net "P5E_CPU1_P1_TX_C_DN<0>")
		)
		(pad "EW10" smd circle
			(at -9.19734 -1.431798)
			(size 0.381 0.381)
			(layers "F.Cu" "F.Mask" "F.Paste")
			(net "P5E_CPU1_P1_TX_BUF_DN<0>")
		)
		(pad "EW29" smd circle
			(at -9.19734 2.032254)
			(size 0.381 0.381)
			(layers "F.Cu" "F.Mask" "F.Paste")
			(net "P5E_CPU1_P1_RX_DN<0>")
		)
		(pad "EY1" smd oval
			(at -9.349994 -3.938524)
			(size 0.254 0.3302)
			(layers "F.Cu" "F.Mask" "F.Paste")
			(net "P5E_CPU1_P1_RX_BUF_DP<0>")
		)
		(pad "EY35" smd oval
			(at -9.349994 3.940048)
			(size 0.254 0.3302)
			(layers "F.Cu" "F.Mask" "F.Paste")
			(net "P5E_CPU1_P1_TX_C_DP<0>")
		)
		(pad "F2" smd circle
			(at 10.150094 -3.41884)
			(size 0.3048 0.3048)
			(layers "F.Cu" "F.Mask" "F.Paste")
			(net "RST_RT_CPU1_P1_PERST_N")
		)
		(pad "F34" smd circle
			(at 10.150094 3.420364)
			(size 0.3048 0.3048)
			(layers "F.Cu" "F.Mask" "F.Paste")
			(net "RT_CPU1_P1_ADDR1")
		)
		(pad "FA15" smd circle
			(at -9.59739 -0.738886)
			(size 0.381 0.381)
			(layers "F.Cu" "F.Mask" "F.Paste")
			(net "GND")
		)
		(pad "FA32" smd circle
			(at -9.59739 2.724912)
			(size 0.381 0.381)
			(layers "F.Cu" "F.Mask" "F.Paste")
			(net "GND")
		)
		(pad "FB2" smd circle
			(at -9.649968 -3.41884)
			(size 0.3048 0.3048)
			(layers "F.Cu" "F.Mask" "F.Paste")
			(net "GND")
		)
		(pad "FB34" smd circle
			(at -9.649968 3.420364)
			(size 0.3048 0.3048)
			(layers "F.Cu" "F.Mask" "F.Paste")
			(net "GND")
		)
		(pad "FC3" smd circle
			(at -9.846818 -2.888488)
			(size 0.3048 0.3048)
			(layers "F.Cu" "F.Mask" "F.Paste")
			(net "GND")
		)
		(pad "FC6" smd circle
			(at -9.846818 -2.288286)
			(size 0.3048 0.3048)
			(layers "F.Cu" "F.Mask" "F.Paste")
			(net "GND")
		)
		(pad "FC9" smd circle
			(at -9.846818 -1.688338)
			(size 0.3048 0.3048)
			(layers "F.Cu" "F.Mask" "F.Paste")
			(net "GND")
		)
		(pad "FC19" smd circle
			(at -9.846818 0.111506)
			(size 0.3048 0.3048)
			(layers "F.Cu" "F.Mask" "F.Paste")
			(net "GND")
		)
		(pad "FC23" smd circle
			(at -9.846818 0.711708)
			(size 0.3048 0.3048)
			(layers "F.Cu" "F.Mask" "F.Paste")
			(net "GND")
		)
		(pad "FC25" smd circle
			(at -9.846818 1.311656)
			(size 0.3048 0.3048)
			(layers "F.Cu" "F.Mask" "F.Paste")
			(net "GND")
		)
		(pad "FC28" smd circle
			(at -9.846818 1.911604)
			(size 0.3048 0.3048)
			(layers "F.Cu" "F.Mask" "F.Paste")
			(net "GND")
		)
		(pad "FD1" smd oval
			(at -9.949942 -3.938524)
			(size 0.254 0.3302)
			(layers "F.Cu" "F.Mask" "F.Paste")
			(net "GND")
		)
		(pad "FD35" smd oval
			(at -9.949942 3.940048)
			(size 0.254 0.3302)
			(layers "F.Cu" "F.Mask" "F.Paste")
			(net "GND")
		)
		(pad "FE2" smd circle
			(at -10.249916 -3.41884)
			(size 0.3048 0.3048)
			(layers "F.Cu" "F.Mask" "F.Paste")
			(net "NCF_CPU1_P1_GND")
		)
		(pad "FE34" smd circle
			(at -10.249916 3.420364)
			(size 0.3048 0.3048)
			(layers "F.Cu" "F.Mask" "F.Paste")
			(net "NCF_CPU1_P1_GND")
		)
		(pad "FF5" smd circle
			(at -10.366248 -2.588514)
			(size 0.3048 0.3048)
			(layers "F.Cu" "F.Mask" "F.Paste")
			(net "SMB_RT_CPU1_P1_ROM_MUX_1D_R_SCL")
		)
		(pad "FF8" smd circle
			(at -10.366248 -1.988312)
			(size 0.3048 0.3048)
			(layers "F.Cu" "F.Mask" "F.Paste")
			(net "JTAG_TEST_MODE_RT_CPU1_P1")
		)
		(pad "FF11" smd circle
			(at -10.366248 -1.388364)
			(size 0.3048 0.3048)
			(layers "F.Cu" "F.Mask" "F.Paste")
			(net "RST_RT_CPU1_P1_RESET_N")
		)
		(pad "FF14" smd circle
			(at -10.366248 -0.788416)
			(size 0.3048 0.3048)
			(layers "F.Cu" "F.Mask" "F.Paste")
			(net "GND")
		)
		(pad "FF18" smd circle
			(at -10.366248 -0.188468)
			(size 0.3048 0.3048)
			(layers "F.Cu" "F.Mask" "F.Paste")
			(net "CLK_100M_RETIMER_CPU1_P1_DN")
		)
		(pad "FF21" smd circle
			(at -10.366248 0.41148)
			(size 0.3048 0.3048)
			(layers "F.Cu" "F.Mask" "F.Paste")
			(net "GND")
		)
		(pad "FF24" smd circle
			(at -10.366248 1.011682)
			(size 0.3048 0.3048)
			(layers "F.Cu" "F.Mask" "F.Paste")
			(net "TEST0_RT_CPU1_P1")
		)
		(pad "FF27" smd circle
			(at -10.366248 1.61163)
			(size 0.3048 0.3048)
			(layers "F.Cu" "F.Mask" "F.Paste")
			(net "TEST1_RT_CPU1_P1")
		)
		(pad "FF30" smd circle
			(at -10.366248 2.211578)
			(size 0.3048 0.3048)
			(layers "F.Cu" "F.Mask" "F.Paste")
			(net "TEST2_RT_CPU1_P1")
		)
		(pad "FF33" smd circle
			(at -10.366248 2.811526)
			(size 0.3048 0.3048)
			(layers "F.Cu" "F.Mask" "F.Paste")
			(net "RT_CPU1_P1_SCAN_MODE")
		)
		(pad "FG1" smd oval
			(at -10.54989 -3.938524)
			(size 0.254 0.3302)
			(layers "F.Cu" "F.Mask" "F.Paste")
			(net "NCF_CPU1_P1_GND")
		)
		(pad "FG35" smd oval
			(at -10.54989 3.940048)
			(size 0.254 0.3302)
			(layers "F.Cu" "F.Mask" "F.Paste")
			(net "NCF_CPU1_P1_GND")
		)
		(pad "FH2" smd circle
			(at -10.850118 -3.41884)
			(size 0.3048 0.3048)
			(layers "F.Cu" "F.Mask" "F.Paste")
			(net "NCF_CPU1_P1_GND")
		)
		(pad "FH34" smd circle
			(at -10.850118 3.420364)
			(size 0.3048 0.3048)
			(layers "F.Cu" "F.Mask" "F.Paste")
			(net "NCF_CPU1_P1_GND")
		)
		(pad "FJ3" smd oval
			(at -10.885932 -2.888488 90)
			(size 0.254 0.3302)
			(layers "F.Cu" "F.Mask" "F.Paste")
			(net "SMB_RT_CPU1_P1_ROM_MUX_1D_R_SDA")
		)
		(pad "FJ6" smd oval
			(at -10.885932 -2.288286 90)
			(size 0.254 0.3302)
			(layers "F.Cu" "F.Mask" "F.Paste")
			(net "Net_2218")
		)
		(pad "FJ9" smd oval
			(at -10.885932 -1.688338 90)
			(size 0.254 0.3302)
			(layers "F.Cu" "F.Mask" "F.Paste")
			(net "MODE_RT_CPU1_P1")
		)
		(pad "FJ12" smd oval
			(at -10.885932 -1.08839 90)
			(size 0.254 0.3302)
			(layers "F.Cu" "F.Mask" "F.Paste")
			(net "GND")
		)
		(pad "FJ16" smd oval
			(at -10.885932 -0.488442 90)
			(size 0.254 0.3302)
			(layers "F.Cu" "F.Mask" "F.Paste")
			(net "CLK_100M_RETIMER_CPU1_P1_DP")
		)
		(pad "FJ19" smd oval
			(at -10.885932 0.111506 90)
			(size 0.254 0.3302)
			(layers "F.Cu" "F.Mask" "F.Paste")
			(net "GND")
		)
		(pad "FJ23" smd oval
			(at -10.885932 0.711708 90)
			(size 0.254 0.3302)
			(layers "F.Cu" "F.Mask" "F.Paste")
			(net "Net_2219")
		)
		(pad "FJ25" smd oval
			(at -10.885932 1.311656 90)
			(size 0.254 0.3302)
			(layers "F.Cu" "F.Mask" "F.Paste")
			(net "GPIO2_RT_CPU1_P1")
		)
		(pad "FJ28" smd oval
			(at -10.885932 1.911604 90)
			(size 0.254 0.3302)
			(layers "F.Cu" "F.Mask" "F.Paste")
			(net "GPIO3_RT_CPU1_P1")
		)
		(pad "FJ31" smd oval
			(at -10.885932 2.511552 90)
			(size 0.254 0.3302)
			(layers "F.Cu" "F.Mask" "F.Paste")
			(net "Net_55")
		)
		(pad "G1" smd oval
			(at 9.85012 -3.938524)
			(size 0.254 0.3302)
			(layers "F.Cu" "F.Mask" "F.Paste")
			(net "RT_CPU1_P1_VQPS")
		)
		(pad "G35" smd oval
			(at 9.85012 3.940048)
			(size 0.254 0.3302)
			(layers "F.Cu" "F.Mask" "F.Paste")
			(net "CLKREQ_RT_CPU1_P1_N")
		)
		(pad "H12" smd circle
			(at 9.846818 -1.08839)
			(size 0.3048 0.3048)
			(layers "F.Cu" "F.Mask" "F.Paste")
			(net "GND")
		)
		(pad "H16" smd circle
			(at 9.846818 -0.488442)
			(size 0.3048 0.3048)
			(layers "F.Cu" "F.Mask" "F.Paste")
			(net "GND")
		)
		(pad "H19" smd circle
			(at 9.846818 0.111506)
			(size 0.3048 0.3048)
			(layers "F.Cu" "F.Mask" "F.Paste")
			(net "GND")
		)
		(pad "H31" smd circle
			(at 9.846818 2.511552)
			(size 0.3048 0.3048)
			(layers "F.Cu" "F.Mask" "F.Paste")
			(net "GND")
		)
		(pad "J4" smd circle
			(at 9.602724 -2.817368)
			(size 0.381 0.381)
			(layers "F.Cu" "F.Mask" "F.Paste")
			(net "GND")
		)
		(pad "J22" smd circle
			(at 9.602724 0.703834)
			(size 0.3048 0.3048)
			(layers "F.Cu" "F.Mask" "F.Paste")
			(net "GND")
		)
		(pad "K2" smd circle
			(at 9.549892 -3.41884)
			(size 0.3048 0.3048)
			(layers "F.Cu" "F.Mask" "F.Paste")
			(net "GND")
		)
		(pad "K34" smd circle
			(at 9.549892 3.420364)
			(size 0.3048 0.3048)
			(layers "F.Cu" "F.Mask" "F.Paste")
			(net "GND")
		)
		(pad "L1" smd oval
			(at 9.249918 -3.938524)
			(size 0.254 0.3302)
			(layers "F.Cu" "F.Mask" "F.Paste")
			(net "GND")
		)
		(pad "L35" smd oval
			(at 9.249918 3.940048)
			(size 0.254 0.3302)
			(layers "F.Cu" "F.Mask" "F.Paste")
			(net "GND")
		)
		(pad "M7" smd circle
			(at 9.202674 -2.12471)
			(size 0.381 0.381)
			(layers "F.Cu" "F.Mask" "F.Paste")
			(net "P5E_CPU1_P1_TX_BUF_DP<15>")
		)
		(pad "M26" smd circle
			(at 9.202674 1.339342)
			(size 0.381 0.381)
			(layers "F.Cu" "F.Mask" "F.Paste")
			(net "P5E_CPU1_P1_RX_DP<15>")
		)
		(pad "N2" smd circle
			(at 8.949944 -3.41884)
			(size 0.3048 0.3048)
			(layers "F.Cu" "F.Mask" "F.Paste")
			(net "P5E_CPU1_P1_RX_BUF_DN<15>")
		)
		(pad "N34" smd circle
			(at 8.949944 3.420364)
			(size 0.3048 0.3048)
			(layers "F.Cu" "F.Mask" "F.Paste")
			(net "P5E_CPU1_P1_TX_C_DN<15>")
		)
		(pad "P10" smd circle
			(at 8.802624 -1.431798)
			(size 0.381 0.381)
			(layers "F.Cu" "F.Mask" "F.Paste")
			(net "P5E_CPU1_P1_TX_BUF_DN<15>")
		)
		(pad "P29" smd circle
			(at 8.802624 2.032254)
			(size 0.381 0.381)
			(layers "F.Cu" "F.Mask" "F.Paste")
			(net "P5E_CPU1_P1_RX_DN<15>")
		)
		(pad "R1" smd oval
			(at 8.64997 -3.938524)
			(size 0.254 0.3302)
			(layers "F.Cu" "F.Mask" "F.Paste")
			(net "P5E_CPU1_P1_RX_BUF_DP<15>")
		)
		(pad "R35" smd oval
			(at 8.64997 3.940048)
			(size 0.254 0.3302)
			(layers "F.Cu" "F.Mask" "F.Paste")
			(net "P5E_CPU1_P1_TX_C_DP<15>")
		)
		(pad "T4" smd circle
			(at 8.402574 -2.817368)
			(size 0.381 0.381)
			(layers "F.Cu" "F.Mask" "F.Paste")
			(net "GND")
		)
		(pad "T13" smd circle
			(at 8.402574 -0.79629)
			(size 0.3048 0.3048)
			(layers "F.Cu" "F.Mask" "F.Paste")
			(net "GND")
		)
		(pad "T17" smd circle
			(at 8.402574 -0.296164)
			(size 0.3048 0.3048)
			(layers "F.Cu" "F.Mask" "F.Paste")
			(net "P0V9_CPU1_RT1_2A")
		)
		(pad "T20" smd circle
			(at 8.402574 0.203708)
			(size 0.3048 0.3048)
			(layers "F.Cu" "F.Mask" "F.Paste")
			(net "P0V9_CPU1_RT1_2A")
		)
		(pad "T22" smd circle
			(at 8.402574 0.703834)
			(size 0.3048 0.3048)
			(layers "F.Cu" "F.Mask" "F.Paste")
			(net "GND")
		)
		(pad "T32" smd circle
			(at 8.402574 2.724912)
			(size 0.381 0.381)
			(layers "F.Cu" "F.Mask" "F.Paste")
			(net "GND")
		)
		(pad "U2" smd circle
			(at 8.349996 -3.41884)
			(size 0.3048 0.3048)
			(layers "F.Cu" "F.Mask" "F.Paste")
			(net "GND")
		)
		(pad "U34" smd circle
			(at 8.349996 3.420364)
			(size 0.3048 0.3048)
			(layers "F.Cu" "F.Mask" "F.Paste")
			(net "GND")
		)
		(pad "V1" smd oval
			(at 8.050022 -3.938524)
			(size 0.254 0.3302)
			(layers "F.Cu" "F.Mask" "F.Paste")
			(net "GND")
		)
		(pad "V35" smd oval
			(at 8.050022 3.940048)
			(size 0.254 0.3302)
			(layers "F.Cu" "F.Mask" "F.Paste")
			(net "GND")
		)
		(pad "W7" smd circle
			(at 8.002524 -2.12471)
			(size 0.381 0.381)
			(layers "F.Cu" "F.Mask" "F.Paste")
			(net "P5E_CPU1_P1_TX_BUF_DP<14>")
		)
		(pad "W26" smd circle
			(at 8.002524 1.339342)
			(size 0.381 0.381)
			(layers "F.Cu" "F.Mask" "F.Paste")
			(net "P5E_CPU1_P1_RX_DP<14>")
		)
		(pad "Y2" smd circle
			(at 7.750048 -3.41884)
			(size 0.3048 0.3048)
			(layers "F.Cu" "F.Mask" "F.Paste")
			(net "P5E_CPU1_P1_RX_BUF_DN<14>")
		)
		(pad "Y34" smd circle
			(at 7.750048 3.420364)
			(size 0.3048 0.3048)
			(layers "F.Cu" "F.Mask" "F.Paste")
			(net "P5E_CPU1_P1_TX_C_DP<14>")
		)
	)
	(footprint ""
		(layer "F.Cu")
		(at 178.71694 -404.500842 180)
		(property "Reference" "PR3935"
			(at 0 0 180)
			(layer "F.SilkS")
			(hide yes)
			(effects
				(font
					(size 1.27 1.27)
				)
			)
		)
		(property "Value" ""
			(at 0 0 180)
			(layer "F.Fab")
			(effects
				(font
					(size 1.27 1.27)
				)
			)
		)
		(duplicate_pad_numbers_are_jumpers no)
		(fp_line
			(start 0.7874 0.4064)
			(end -0.7874 0.4064)
			(stroke
				(width 0.1524)
				(type default)
			)
			(layer "F.SilkS")
		)
		(fp_line
			(start 0.7874 -0.4064)
			(end 0.7874 0.4064)
			(stroke
				(width 0.1524)
				(type default)
			)
			(layer "F.SilkS")
		)
		(fp_line
			(start -0.7874 0.4064)
			(end -0.7874 -0.4064)
			(stroke
				(width 0.1524)
				(type default)
			)
			(layer "F.SilkS")
		)
		(fp_line
			(start -0.7874 -0.4064)
			(end 0.7874 -0.4064)
			(stroke
				(width 0.1524)
				(type default)
			)
			(layer "F.SilkS")
		)
		(fp_line
			(start 0.67945 0.3048)
			(end 0.120396 0.3048)
			(stroke
				(width 0.1)
				(type default)
			)
			(layer "F.Fab")
		)
		(fp_line
			(start 0.67945 -0.3048)
			(end 0.67945 0.3048)
			(stroke
				(width 0.1)
				(type default)
			)
			(layer "F.Fab")
		)
		(fp_line
			(start 0.12065 -0.2794)
			(end 0.12065 -0.3048)
			(stroke
				(width 0.1)
				(type default)
			)
			(layer "F.Fab")
		)
		(fp_line
			(start 0.12065 -0.3048)
			(end 0.67945 -0.3048)
			(stroke
				(width 0.1)
				(type default)
			)
			(layer "F.Fab")
		)
		(fp_line
			(start 0.120396 0.3048)
			(end 0.120396 0.2794)
			(stroke
				(width 0.1)
				(type default)
			)
			(layer "F.Fab")
		)
		(fp_line
			(start 0.120396 0.2794)
			(end -0.12065 0.2794)
			(stroke
				(width 0.1)
				(type default)
			)
			(layer "F.Fab")
		)
		(fp_line
			(start -0.12065 0.3048)
			(end -0.67945 0.3048)
			(stroke
				(width 0.1)
				(type default)
			)
			(layer "F.Fab")
		)
		(fp_line
			(start -0.12065 0.2794)
			(end -0.12065 0.3048)
			(stroke
				(width 0.1)
				(type default)
			)
			(layer "F.Fab")
		)
		(fp_line
			(start -0.12065 -0.2794)
			(end 0.12065 -0.2794)
			(stroke
				(width 0.1)
				(type default)
			)
			(layer "F.Fab")
		)
		(fp_line
			(start -0.12065 -0.305054)
			(end -0.12065 -0.2794)
			(stroke
				(width 0.1)
				(type default)
			)
			(layer "F.Fab")
		)
		(fp_line
			(start -0.67945 0.3048)
			(end -0.67945 -0.305054)
			(stroke
				(width 0.1)
				(type default)
			)
			(layer "F.Fab")
		)
		(fp_line
			(start -0.67945 -0.305054)
			(end -0.12065 -0.305054)
			(stroke
				(width 0.1)
				(type default)
			)
			(layer "F.Fab")
		)
		(pad "1" smd circle
			(at -0.40005 0 180)
			(size 0 0)
			(layers "F.Cu" "F.Mask" "F.Paste")
			(net "HSC_VTEMP")
		)
		(pad "2" smd circle
			(at 0.40005 0 180)
			(size 0 0)
			(layers "F.Cu" "F.Mask" "F.Paste")
			(net "AGND_HSC")
		)
	)
	(footprint ""
		(layer "F.Cu")
		(at 167.79621 -394.3604 -90)
		(property "Reference" "R866"
			(at 0 0 270)
			(layer "F.SilkS")
			(hide yes)
			(effects
				(font
					(size 1.27 1.27)
				)
			)
		)
		(property "Value" ""
			(at 0 0 270)
			(layer "F.Fab")
			(effects
				(font
					(size 1.27 1.27)
				)
			)
		)
		(duplicate_pad_numbers_are_jumpers no)
		(fp_line
			(start -0.32512 0.175006)
			(end -0.32512 -0.175006)
			(stroke
				(width 0.1)
				(type default)
			)
			(layer "F.Fab")
		)
		(fp_line
			(start 0.32512 0.175006)
			(end -0.32512 0.175006)
			(stroke
				(width 0.1)
				(type default)
			)
			(layer "F.Fab")
		)
		(fp_line
			(start -0.32512 -0.175006)
			(end 0.32512 -0.175006)
			(stroke
				(width 0.1)
				(type default)
			)
			(layer "F.Fab")
		)
		(fp_line
			(start 0.32512 -0.175006)
			(end 0.32512 0.175006)
			(stroke
				(width 0.1)
				(type default)
			)
			(layer "F.Fab")
		)
		(pad "1" smd rect
			(at -0.2667 0 270)
			(size 0.3048 0.381)
			(layers "F.Cu" "F.Mask" "F.Paste")
			(net "RST_RT_CPU1_P2_PERST_R_N")
		)
		(pad "2" smd rect
			(at 0.2667 0 90)
			(size 0.3048 0.381)
			(layers "F.Cu" "F.Mask" "F.Paste")
			(net "GND")
		)
	)
	(footprint ""
		(layer "F.Cu")
		(at 13.437108 -128.54559 90)
		(property "Reference" "R3341"
			(at 0 0 90)
			(layer "F.SilkS")
			(hide yes)
			(effects
				(font
					(size 1.27 1.27)
				)
			)
		)
		(property "Value" ""
			(at 0 0 90)
			(layer "F.Fab")
			(effects
				(font
					(size 1.27 1.27)
				)
			)
		)
		(duplicate_pad_numbers_are_jumpers no)
		(fp_line
			(start 0.7874 -0.4064)
			(end 0.7874 0.4064)
			(stroke
				(width 0.1524)
				(type default)
			)
			(layer "F.SilkS")
		)
		(fp_line
			(start -0.7874 -0.4064)
			(end 0.7874 -0.4064)
			(stroke
				(width 0.1524)
				(type default)
			)
			(layer "F.SilkS")
		)
		(fp_line
			(start 0.7874 0.4064)
			(end -0.7874 0.4064)
			(stroke
				(width 0.1524)
				(type default)
			)
			(layer "F.SilkS")
		)
		(fp_line
			(start -0.7874 0.4064)
			(end -0.7874 -0.4064)
			(stroke
				(width 0.1524)
				(type default)
			)
			(layer "F.SilkS")
		)
		(fp_line
			(start -0.12065 -0.305054)
			(end -0.12065 -0.2794)
			(stroke
				(width 0.1)
				(type default)
			)
			(layer "F.Fab")
		)
		(fp_line
			(start -0.67945 -0.305054)
			(end -0.12065 -0.305054)
			(stroke
				(width 0.1)
				(type default)
			)
			(layer "F.Fab")
		)
		(fp_line
			(start 0.67945 -0.3048)
			(end 0.67945 0.3048)
			(stroke
				(width 0.1)
				(type default)
			)
			(layer "F.Fab")
		)
		(fp_line
			(start 0.12065 -0.3048)
			(end 0.67945 -0.3048)
			(stroke
				(width 0.1)
				(type default)
			)
			(layer "F.Fab")
		)
		(fp_line
			(start 0.12065 -0.2794)
			(end 0.12065 -0.3048)
			(stroke
				(width 0.1)
				(type default)
			)
			(layer "F.Fab")
		)
		(fp_line
			(start -0.12065 -0.2794)
			(end 0.12065 -0.2794)
			(stroke
				(width 0.1)
				(type default)
			)
			(layer "F.Fab")
		)
		(fp_line
			(start 0.120396 0.2794)
			(end -0.12065 0.2794)
			(stroke
				(width 0.1)
				(type default)
			)
			(layer "F.Fab")
		)
		(fp_line
			(start -0.12065 0.2794)
			(end -0.12065 0.3048)
			(stroke
				(width 0.1)
				(type default)
			)
			(layer "F.Fab")
		)
		(fp_line
			(start 0.67945 0.3048)
			(end 0.120396 0.3048)
			(stroke
				(width 0.1)
				(type default)
			)
			(layer "F.Fab")
		)
		(fp_line
			(start 0.120396 0.3048)
			(end 0.120396 0.2794)
			(stroke
				(width 0.1)
				(type default)
			)
			(layer "F.Fab")
		)
		(fp_line
			(start -0.12065 0.3048)
			(end -0.67945 0.3048)
			(stroke
				(width 0.1)
				(type default)
			)
			(layer "F.Fab")
		)
		(fp_line
			(start -0.67945 0.3048)
			(end -0.67945 -0.305054)
			(stroke
				(width 0.1)
				(type default)
			)
			(layer "F.Fab")
		)
		(pad "1" smd circle
			(at -0.40005 0 90)
			(size 0 0)
			(layers "F.Cu" "F.Mask" "F.Paste")
			(net "SMB_HOST_CLK_3V3AUX_SDA")
		)
		(pad "2" smd circle
			(at 0.40005 0 90)
			(size 0 0)
			(layers "F.Cu" "F.Mask" "F.Paste")
			(net "SMB_HOST_CLK_GEN2_3V3AUX_SDA")
		)
	)
	(footprint ""
		(layer "F.Cu")
		(at 228.827076 -294.597074 180)
		(property "Reference" "PR6801"
			(at 0 0 180)
			(layer "F.SilkS")
			(hide yes)
			(effects
				(font
					(size 1.27 1.27)
				)
			)
		)
		(property "Value" ""
			(at 0 0 180)
			(layer "F.Fab")
			(effects
				(font
					(size 1.27 1.27)
				)
			)
		)
		(duplicate_pad_numbers_are_jumpers no)
		(fp_line
			(start 0.7874 0.4064)
			(end -0.7874 0.4064)
			(stroke
				(width 0.1524)
				(type default)
			)
			(layer "F.SilkS")
		)
		(fp_line
			(start 0.7874 -0.4064)
			(end 0.7874 0.4064)
			(stroke
				(width 0.1524)
				(type default)
			)
			(layer "F.SilkS")
		)
		(fp_line
			(start -0.7874 0.4064)
			(end -0.7874 -0.4064)
			(stroke
				(width 0.1524)
				(type default)
			)
			(layer "F.SilkS")
		)
		(fp_line
			(start -0.7874 -0.4064)
			(end 0.7874 -0.4064)
			(stroke
				(width 0.1524)
				(type default)
			)
			(layer "F.SilkS")
		)
		(fp_line
			(start 0.67945 0.3048)
			(end 0.120396 0.3048)
			(stroke
				(width 0.1)
				(type default)
			)
			(layer "F.Fab")
		)
		(fp_line
			(start 0.67945 -0.3048)
			(end 0.67945 0.3048)
			(stroke
				(width 0.1)
				(type default)
			)
			(layer "F.Fab")
		)
		(fp_line
			(start 0.12065 -0.2794)
			(end 0.12065 -0.3048)
			(stroke
				(width 0.1)
				(type default)
			)
			(layer "F.Fab")
		)
		(fp_line
			(start 0.12065 -0.3048)
			(end 0.67945 -0.3048)
			(stroke
				(width 0.1)
				(type default)
			)
			(layer "F.Fab")
		)
		(fp_line
			(start 0.120396 0.3048)
			(end 0.120396 0.2794)
			(stroke
				(width 0.1)
				(type default)
			)
			(layer "F.Fab")
		)
		(fp_line
			(start 0.120396 0.2794)
			(end -0.12065 0.2794)
			(stroke
				(width 0.1)
				(type default)
			)
			(layer "F.Fab")
		)
		(fp_line
			(start -0.12065 0.3048)
			(end -0.67945 0.3048)
			(stroke
				(width 0.1)
				(type default)
			)
			(layer "F.Fab")
		)
		(fp_line
			(start -0.12065 0.2794)
			(end -0.12065 0.3048)
			(stroke
				(width 0.1)
				(type default)
			)
			(layer "F.Fab")
		)
		(fp_line
			(start -0.12065 -0.2794)
			(end 0.12065 -0.2794)
			(stroke
				(width 0.1)
				(type default)
			)
			(layer "F.Fab")
		)
		(fp_line
			(start -0.12065 -0.305054)
			(end -0.12065 -0.2794)
			(stroke
				(width 0.1)
				(type default)
			)
			(layer "F.Fab")
		)
		(fp_line
			(start -0.67945 0.3048)
			(end -0.67945 -0.305054)
			(stroke
				(width 0.1)
				(type default)
			)
			(layer "F.Fab")
		)
		(fp_line
			(start -0.67945 -0.305054)
			(end -0.12065 -0.305054)
			(stroke
				(width 0.1)
				(type default)
			)
			(layer "F.Fab")
		)
		(pad "1" smd circle
			(at -0.40005 0 180)
			(size 0 0)
			(layers "F.Cu" "F.Mask" "F.Paste")
			(net "SW_P1V8_RETIMER_CPU1_BST")
		)
		(pad "2" smd circle
			(at 0.40005 0 180)
			(size 0 0)
			(layers "F.Cu" "F.Mask" "F.Paste")
			(net "SW_P1V8_RETIMER_CPU1_BST_R")
		)
	)
	(footprint ""
		(layer "F.Cu")
		(at 397.824198 -177.171096 180)
		(property "Reference" "PU49"
			(at 4.331716 -6.338062 0)
			(unlocked yes)
			(layer "F.SilkS")
			(effects
				(font
					(size 0.7874 0.5842)
					(thickness 0.1524)
				)
				(justify left)
			)
		)
		(property "Value" ""
			(at 0 0 180)
			(layer "F.Fab")
			(effects
				(font
					(size 1.27 1.27)
				)
			)
		)
		(duplicate_pad_numbers_are_jumpers no)
		(fp_line
			(start 2.500122 2.999994)
			(end 2.2987 2.999994)
			(stroke
				(width 0.1524)
				(type default)
			)
			(layer "F.SilkS")
		)
		(fp_line
			(start 2.500122 2.339594)
			(end 2.500122 2.999994)
			(stroke
				(width 0.1524)
				(type default)
			)
			(layer "F.SilkS")
		)
		(fp_line
			(start 2.500122 -2.999994)
			(end 2.500122 -2.44348)
			(stroke
				(width 0.1524)
				(type default)
			)
			(layer "F.SilkS")
		)
		(fp_line
			(start 2.31394 -2.999994)
			(end 2.500122 -2.999994)
			(stroke
				(width 0.1524)
				(type default)
			)
			(layer "F.SilkS")
		)
		(fp_line
			(start -2.2987 2.999994)
			(end -2.500122 2.999994)
			(stroke
				(width 0.1524)
				(type default)
			)
			(layer "F.SilkS")
		)
		(fp_line
			(start -2.500122 2.999994)
			(end -2.500122 2.339594)
			(stroke
				(width 0.1524)
				(type default)
			)
			(layer "F.SilkS")
		)
		(fp_line
			(start -2.500122 0.6604)
			(end -2.500122 0.229108)
			(stroke
				(width 0.1524)
				(type default)
			)
			(layer "F.SilkS")
		)
		(fp_line
			(start -2.500122 -2.529078)
			(end -2.500122 -2.999994)
			(stroke
				(width 0.1524)
				(type default)
			)
			(layer "F.SilkS")
		)
		(fp_line
			(start -2.500122 -2.999994)
			(end -2.24409 -2.999994)
			(stroke
				(width 0.1524)
				(type default)
			)
			(layer "F.SilkS")
		)
		(fp_poly
			(pts
				(xy -2.695448 -2.471928) (xy -3.476244 -2.732278) (xy -2.955798 -3.252978)
			)
			(stroke
				(width 0)
				(type default)
			)
			(fill yes)
			(layer "F.SilkS")
		)
		(fp_line
			(start 2.500122 2.999994)
			(end -2.500122 2.999994)
			(stroke
				(width 0.1)
				(type default)
			)
			(layer "F.Fab")
		)
		(fp_line
			(start 2.500122 -2.999994)
			(end 2.500122 2.999994)
			(stroke
				(width 0.1)
				(type default)
			)
			(layer "F.Fab")
		)
		(fp_line
			(start -2.500122 2.999994)
			(end -2.500122 -2.999994)
			(stroke
				(width 0.1)
				(type default)
			)
			(layer "F.Fab")
		)
		(fp_line
			(start -2.500122 -2.999994)
			(end 2.500122 -2.999994)
			(stroke
				(width 0.1)
				(type default)
			)
			(layer "F.Fab")
		)
		(fp_poly
			(pts
				(xy -4.218432 -2.783078) (xy -4.218432 -1.767078) (xy -3.202432 -2.275078)
			)
			(stroke
				(width 0)
				(type default)
			)
			(fill yes)
			(layer "F.Fab")
		)
		(pad "1" smd rect
			(at -2.400046 -2.275078 270)
			(size 0.2286 0.6096)
			(layers "F.Cu" "F.Mask" "F.Paste")
			(net "PVDDCR_SOC_P0_VOS1")
		)
		(pad "2" smd rect
			(at -2.400046 -1.82499 270)
			(size 0.2286 0.6096)
			(layers "F.Cu" "F.Mask" "F.Paste")
			(net "GND")
		)
		(pad "3" smd rect
			(at -2.400046 -1.374902 270)
			(size 0.2286 0.6096)
			(layers "F.Cu" "F.Mask" "F.Paste")
			(net "PVDDCR_SOC_P0_VCC1")
		)
		(pad "4" smd rect
			(at -2.400046 -0.925068 270)
			(size 0.2286 0.6096)
			(layers "F.Cu" "F.Mask" "F.Paste")
			(net "PVDDCR_CPU0_P0_PVCC")
		)
		(pad "5" smd rect
			(at -2.400046 -0.47498 270)
			(size 0.2286 0.6096)
			(layers "F.Cu" "F.Mask" "F.Paste")
			(net "GND")
		)
		(pad "6" smd rect
			(at -2.400046 -0.024892 270)
			(size 0.2286 0.6096)
			(layers "F.Cu" "F.Mask" "F.Paste")
			(net "NC_PVDDCR_SOC_P0_GL1_1")
		)
		(pad "7_9-20_24" smd circle
			(at 0 1.150112 270)
			(size 0 0)
			(layers "F.Cu" "F.Mask" "F.Paste")
			(net "GND")
		)
		(pad "10_19" smd rect
			(at 0 2.899918 270)
			(size 0.6096 4.318)
			(layers "F.Cu" "F.Mask" "F.Paste")
			(net "SW_PVDDCR_SOC_P0_SW1")
		)
		(pad "25_29" smd rect
			(at 1.549908 -1.279906 90)
			(size 2.0574 2.3114)
			(layers "F.Cu" "F.Mask" "F.Paste")
			(net "SW_P12V_AUX_PVDDCR_SOC_P0_FLT")
		)
		(pad "30" smd rect
			(at 2.05994 -2.899918 180)
			(size 0.2286 0.6096)
			(layers "F.Cu" "F.Mask" "F.Paste")
			(net "SW_P12V_AUX_PVDDCR_SOC_P0_FLT")
		)
		(pad "31" smd rect
			(at 1.610106 -2.899918 180)
			(size 0.2286 0.6096)
			(layers "F.Cu" "F.Mask" "F.Paste")
			(net "NC_PVDDCR_SOC_P0_DNC1")
		)
		(pad "32" smd rect
			(at 1.160018 -2.899918 180)
			(size 0.2286 0.6096)
			(layers "F.Cu" "F.Mask" "F.Paste")
			(net "SW_PVDDCR_SOC_P0_PH1")
		)
		(pad "33" smd rect
			(at 0.70993 -2.899918 180)
			(size 0.2286 0.6096)
			(layers "F.Cu" "F.Mask" "F.Paste")
			(net "SW_PVDDCR_SOC_P0_BOOT1")
		)
		(pad "34" smd rect
			(at 0.260096 -2.899918 180)
			(size 0.2286 0.6096)
			(layers "F.Cu" "F.Mask" "F.Paste")
			(net "PVDDCR_SOC_P0_PWM1")
		)
		(pad "35" smd rect
			(at -0.189992 -2.899918 180)
			(size 0.2286 0.6096)
			(layers "F.Cu" "F.Mask" "F.Paste")
			(net "PVDDCR_SOC_P0_VCC1")
		)
		(pad "36" smd rect
			(at -0.64008 -2.899918 180)
			(size 0.2286 0.6096)
			(layers "F.Cu" "F.Mask" "F.Paste")
			(net "PVDDCR_SOC_P0_TEMP1")
		)
		(pad "37" smd rect
			(at -1.089914 -2.899918 180)
			(size 0.2286 0.6096)
			(layers "F.Cu" "F.Mask" "F.Paste")
			(net "PVDDCR_SOC_P0_LSET1")
		)
		(pad "38" smd rect
			(at -1.540002 -2.899918 180)
			(size 0.2286 0.6096)
			(layers "F.Cu" "F.Mask" "F.Paste")
			(net "PVDDCR_SOC_P0_IMON1")
		)
		(pad "39" smd rect
			(at -1.99009 -2.899918 180)
			(size 0.2286 0.6096)
			(layers "F.Cu" "F.Mask" "F.Paste")
			(net "PVDDCR_CPU0_P0_VCCS")
		)
		(pad "40" smd rect
			(at -0.87503 -1.27508 180)
			(size 1.7526 1.9558)
			(layers "F.Cu" "F.Mask" "F.Paste")
			(net "GND")
		)
		(pad "41" smd rect
			(at -1.525016 0.249936 90)
			(size 0.3048 0.4572)
			(layers "F.Cu" "F.Mask" "F.Paste")
			(net "NC_PVDDCR_SOC_P0_GL2_1")
		)
		(zone
			(layer "F.Cu")
			(hatch none 0.5)
			(connect_pads
				(clearance 0)
			)
			(min_thickness 0.25)
			(keepout
				(tracks not_allowed)
				(vias allowed)
				(pads allowed)
				(copperpour not_allowed)
				(footprints allowed)
			)
			(placement
				(enabled no)
				(sheetname "")
			)
			(fill
				(thermal_gap 0.5)
				(thermal_bridge_width 0.5)
				(island_removal_mode 0)
			)
			(polygon
				(pts
					(xy 400.32432 -179.75453) (xy 400.32432 -179.42179) (xy 395.324076 -179.42179) (xy 395.324076 -179.747418)
					(xy 395.614398 -179.747418) (xy 395.614398 -179.715414) (xy 400.033998 -179.715414) (xy 400.033998 -179.75453)
				)
			)
		)
		(zone
			(layer "F.Cu")
			(hatch none 0.5)
			(connect_pads
				(clearance 0)
			)
			(min_thickness 0.25)
			(keepout
				(tracks not_allowed)
				(vias allowed)
				(pads allowed)
				(copperpour not_allowed)
				(footprints allowed)
			)
			(placement
				(enabled no)
				(sheetname "")
			)
			(fill
				(thermal_gap 0.5)
				(thermal_bridge_width 0.5)
				(island_removal_mode 0)
			)
			(polygon
				(pts
					(xy 397.772128 -176.924716) (xy 397.772128 -174.867316) (xy 399.626328 -174.867316) (xy 399.626328 -175.108362)
					(xy 399.868644 -175.108362) (xy 399.868644 -174.626778) (xy 395.960346 -174.626778) (xy 395.960346 -174.81169)
					(xy 397.48079 -174.81169) (xy 397.48079 -176.97069) (xy 395.324076 -176.97069) (xy 395.324076 -177.220372)
					(xy 397.472408 -177.220372) (xy 397.74876 -176.94402) (xy 397.752824 -176.94402)
				)
			)
		)
	)
	(footprint ""
		(layer "F.Cu")
		(at 54.594506 19.444716 -90)
		(property "Reference" "J90_CON"
			(at 0 0 270)
			(layer "F.SilkS")
			(hide yes)
			(effects
				(font
					(size 1.27 1.27)
				)
			)
		)
		(property "Value" ""
			(at 0 0 270)
			(layer "F.Fab")
			(effects
				(font
					(size 1.27 1.27)
				)
			)
		)
		(duplicate_pad_numbers_are_jumpers no)
		(pad "1" smd circle
			(at 0 0 270)
			(size 0.762 0.762)
			(layers "F.Cu" "F.Mask" "F.Paste")
			(net "Net_2617")
		)
	)
	(footprint ""
		(layer "F.Cu")
		(at 157.692852 -350.256856 180)
		(property "Reference" "C642"
			(at 0 0 180)
			(layer "F.SilkS")
			(hide yes)
			(effects
				(font
					(size 1.27 1.27)
				)
			)
		)
		(property "Value" ""
			(at 0 0 180)
			(layer "F.Fab")
			(effects
				(font
					(size 1.27 1.27)
				)
			)
		)
		(duplicate_pad_numbers_are_jumpers no)
		(fp_line
			(start 0.7874 0.4064)
			(end -0.7874 0.4064)
			(stroke
				(width 0.1524)
				(type default)
			)
			(layer "F.SilkS")
		)
		(fp_line
			(start 0.7874 -0.4064)
			(end 0.7874 0.4064)
			(stroke
				(width 0.1524)
				(type default)
			)
			(layer "F.SilkS")
		)
		(fp_line
			(start -0.7874 0.4064)
			(end -0.7874 -0.4064)
			(stroke
				(width 0.1524)
				(type default)
			)
			(layer "F.SilkS")
		)
		(fp_line
			(start -0.7874 -0.4064)
			(end 0.7874 -0.4064)
			(stroke
				(width 0.1524)
				(type default)
			)
			(layer "F.SilkS")
		)
		(fp_line
			(start 0.67945 0.3048)
			(end 0.120396 0.3048)
			(stroke
				(width 0.1)
				(type default)
			)
			(layer "F.Fab")
		)
		(fp_line
			(start 0.67945 -0.3048)
			(end 0.67945 0.3048)
			(stroke
				(width 0.1)
				(type default)
			)
			(layer "F.Fab")
		)
		(fp_line
			(start 0.12065 -0.2794)
			(end 0.12065 -0.3048)
			(stroke
				(width 0.1)
				(type default)
			)
			(layer "F.Fab")
		)
		(fp_line
			(start 0.12065 -0.3048)
			(end 0.67945 -0.3048)
			(stroke
				(width 0.1)
				(type default)
			)
			(layer "F.Fab")
		)
		(fp_line
			(start 0.120396 0.3048)
			(end 0.120396 0.2794)
			(stroke
				(width 0.1)
				(type default)
			)
			(layer "F.Fab")
		)
		(fp_line
			(start 0.120396 0.2794)
			(end -0.12065 0.2794)
			(stroke
				(width 0.1)
				(type default)
			)
			(layer "F.Fab")
		)
		(fp_line
			(start -0.12065 0.3048)
			(end -0.67945 0.3048)
			(stroke
				(width 0.1)
				(type default)
			)
			(layer "F.Fab")
		)
		(fp_line
			(start -0.12065 0.2794)
			(end -0.12065 0.3048)
			(stroke
				(width 0.1)
				(type default)
			)
			(layer "F.Fab")
		)
		(fp_line
			(start -0.12065 -0.2794)
			(end 0.12065 -0.2794)
			(stroke
				(width 0.1)
				(type default)
			)
			(layer "F.Fab")
		)
		(fp_line
			(start -0.12065 -0.305054)
			(end -0.12065 -0.2794)
			(stroke
				(width 0.1)
				(type default)
			)
			(layer "F.Fab")
		)
		(fp_line
			(start -0.67945 0.3048)
			(end -0.67945 -0.305054)
			(stroke
				(width 0.1)
				(type default)
			)
			(layer "F.Fab")
		)
		(fp_line
			(start -0.67945 -0.305054)
			(end -0.12065 -0.305054)
			(stroke
				(width 0.1)
				(type default)
			)
			(layer "F.Fab")
		)
		(pad "1" smd circle
			(at -0.40005 0 180)
			(size 0 0)
			(layers "F.Cu" "F.Mask" "F.Paste")
			(net "PVDD11_S3_P1_EN_R")
		)
		(pad "2" smd circle
			(at 0.40005 0 180)
			(size 0 0)
			(layers "F.Cu" "F.Mask" "F.Paste")
			(net "GND")
		)
	)
	(footprint ""
		(layer "F.Cu")
		(at 366.971326 -43.235118 -90)
		(property "Reference" "R814"
			(at 0 0 270)
			(layer "F.SilkS")
			(hide yes)
			(effects
				(font
					(size 1.27 1.27)
				)
			)
		)
		(property "Value" ""
			(at 0 0 270)
			(layer "F.Fab")
			(effects
				(font
					(size 1.27 1.27)
				)
			)
		)
		(duplicate_pad_numbers_are_jumpers no)
		(fp_line
			(start -0.7874 0.4064)
			(end -0.7874 -0.4064)
			(stroke
				(width 0.1524)
				(type default)
			)
			(layer "F.SilkS")
		)
		(fp_line
			(start 0.7874 0.4064)
			(end -0.7874 0.4064)
			(stroke
				(width 0.1524)
				(type default)
			)
			(layer "F.SilkS")
		)
		(fp_line
			(start -0.7874 -0.4064)
			(end 0.7874 -0.4064)
			(stroke
				(width 0.1524)
				(type default)
			)
			(layer "F.SilkS")
		)
		(fp_line
			(start 0.7874 -0.4064)
			(end 0.7874 0.4064)
			(stroke
				(width 0.1524)
				(type default)
			)
			(layer "F.SilkS")
		)
		(fp_line
			(start -0.67945 0.3048)
			(end -0.67945 -0.305054)
			(stroke
				(width 0.1)
				(type default)
			)
			(layer "F.Fab")
		)
		(fp_line
			(start -0.12065 0.3048)
			(end -0.67945 0.3048)
			(stroke
				(width 0.1)
				(type default)
			)
			(layer "F.Fab")
		)
		(fp_line
			(start 0.120396 0.3048)
			(end 0.120396 0.2794)
			(stroke
				(width 0.1)
				(type default)
			)
			(layer "F.Fab")
		)
		(fp_line
			(start 0.67945 0.3048)
			(end 0.120396 0.3048)
			(stroke
				(width 0.1)
				(type default)
			)
			(layer "F.Fab")
		)
		(fp_line
			(start -0.12065 0.2794)
			(end -0.12065 0.3048)
			(stroke
				(width 0.1)
				(type default)
			)
			(layer "F.Fab")
		)
		(fp_line
			(start 0.120396 0.2794)
			(end -0.12065 0.2794)
			(stroke
				(width 0.1)
				(type default)
			)
			(layer "F.Fab")
		)
		(fp_line
			(start -0.12065 -0.2794)
			(end 0.12065 -0.2794)
			(stroke
				(width 0.1)
				(type default)
			)
			(layer "F.Fab")
		)
		(fp_line
			(start 0.12065 -0.2794)
			(end 0.12065 -0.3048)
			(stroke
				(width 0.1)
				(type default)
			)
			(layer "F.Fab")
		)
		(fp_line
			(start 0.12065 -0.3048)
			(end 0.67945 -0.3048)
			(stroke
				(width 0.1)
				(type default)
			)
			(layer "F.Fab")
		)
		(fp_line
			(start 0.67945 -0.3048)
			(end 0.67945 0.3048)
			(stroke
				(width 0.1)
				(type default)
			)
			(layer "F.Fab")
		)
		(fp_line
			(start -0.67945 -0.305054)
			(end -0.12065 -0.305054)
			(stroke
				(width 0.1)
				(type default)
			)
			(layer "F.Fab")
		)
		(fp_line
			(start -0.12065 -0.305054)
			(end -0.12065 -0.2794)
			(stroke
				(width 0.1)
				(type default)
			)
			(layer "F.Fab")
		)
		(pad "1" smd circle
			(at -0.40005 0 270)
			(size 0 0)
			(layers "F.Cu" "F.Mask" "F.Paste")
			(net "PVDD18_S5_P0")
		)
		(pad "2" smd circle
			(at 0.40005 0 270)
			(size 0 0)
			(layers "F.Cu" "F.Mask" "F.Paste")
			(net "UART_CPU0_UART0_TX")
		)
	)
	(footprint ""
		(layer "F.Cu")
		(at 36.411662 -429.790098 90)
		(property "Reference" "R3285"
			(at 0 0 90)
			(layer "F.SilkS")
			(hide yes)
			(effects
				(font
					(size 1.27 1.27)
				)
			)
		)
		(property "Value" ""
			(at 0 0 90)
			(layer "F.Fab")
			(effects
				(font
					(size 1.27 1.27)
				)
			)
		)
		(duplicate_pad_numbers_are_jumpers no)
		(fp_line
			(start 0.7874 -0.4064)
			(end 0.7874 0.4064)
			(stroke
				(width 0.1524)
				(type default)
			)
			(layer "F.SilkS")
		)
		(fp_line
			(start -0.7874 -0.4064)
			(end 0.7874 -0.4064)
			(stroke
				(width 0.1524)
				(type default)
			)
			(layer "F.SilkS")
		)
		(fp_line
			(start 0.7874 0.4064)
			(end -0.7874 0.4064)
			(stroke
				(width 0.1524)
				(type default)
			)
			(layer "F.SilkS")
		)
		(fp_line
			(start -0.7874 0.4064)
			(end -0.7874 -0.4064)
			(stroke
				(width 0.1524)
				(type default)
			)
			(layer "F.SilkS")
		)
		(fp_line
			(start -0.12065 -0.305054)
			(end -0.12065 -0.2794)
			(stroke
				(width 0.1)
				(type default)
			)
			(layer "F.Fab")
		)
		(fp_line
			(start -0.67945 -0.305054)
			(end -0.12065 -0.305054)
			(stroke
				(width 0.1)
				(type default)
			)
			(layer "F.Fab")
		)
		(fp_line
			(start 0.67945 -0.3048)
			(end 0.67945 0.3048)
			(stroke
				(width 0.1)
				(type default)
			)
			(layer "F.Fab")
		)
		(fp_line
			(start 0.12065 -0.3048)
			(end 0.67945 -0.3048)
			(stroke
				(width 0.1)
				(type default)
			)
			(layer "F.Fab")
		)
		(fp_line
			(start 0.12065 -0.2794)
			(end 0.12065 -0.3048)
			(stroke
				(width 0.1)
				(type default)
			)
			(layer "F.Fab")
		)
		(fp_line
			(start -0.12065 -0.2794)
			(end 0.12065 -0.2794)
			(stroke
				(width 0.1)
				(type default)
			)
			(layer "F.Fab")
		)
		(fp_line
			(start 0.120396 0.2794)
			(end -0.12065 0.2794)
			(stroke
				(width 0.1)
				(type default)
			)
			(layer "F.Fab")
		)
		(fp_line
			(start -0.12065 0.2794)
			(end -0.12065 0.3048)
			(stroke
				(width 0.1)
				(type default)
			)
			(layer "F.Fab")
		)
		(fp_line
			(start 0.67945 0.3048)
			(end 0.120396 0.3048)
			(stroke
				(width 0.1)
				(type default)
			)
			(layer "F.Fab")
		)
		(fp_line
			(start 0.120396 0.3048)
			(end 0.120396 0.2794)
			(stroke
				(width 0.1)
				(type default)
			)
			(layer "F.Fab")
		)
		(fp_line
			(start -0.12065 0.3048)
			(end -0.67945 0.3048)
			(stroke
				(width 0.1)
				(type default)
			)
			(layer "F.Fab")
		)
		(fp_line
			(start -0.67945 0.3048)
			(end -0.67945 -0.305054)
			(stroke
				(width 0.1)
				(type default)
			)
			(layer "F.Fab")
		)
		(pad "1" smd circle
			(at -0.40005 0 90)
			(size 0 0)
			(layers "F.Cu" "F.Mask" "F.Paste")
			(net "FM_P2E_SWB")
		)
		(pad "2" smd circle
			(at 0.40005 0 90)
			(size 0 0)
			(layers "F.Cu" "F.Mask" "F.Paste")
			(net "GND")
		)
	)
	(footprint ""
		(layer "F.Cu")
		(at 43.14444 -101.74224)
		(property "Reference" "R855"
			(at 0 0 0)
			(layer "F.SilkS")
			(hide yes)
			(effects
				(font
					(size 1.27 1.27)
				)
			)
		)
		(property "Value" ""
			(at 0 0 0)
			(layer "F.Fab")
			(effects
				(font
					(size 1.27 1.27)
				)
			)
		)
		(duplicate_pad_numbers_are_jumpers no)
		(fp_line
			(start -0.7874 -0.4064)
			(end 0.7874 -0.4064)
			(stroke
				(width 0.1524)
				(type default)
			)
			(layer "F.SilkS")
		)
		(fp_line
			(start -0.7874 0.4064)
			(end -0.7874 -0.4064)
			(stroke
				(width 0.1524)
				(type default)
			)
			(layer "F.SilkS")
		)
		(fp_line
			(start 0.7874 -0.4064)
			(end 0.7874 0.4064)
			(stroke
				(width 0.1524)
				(type default)
			)
			(layer "F.SilkS")
		)
		(fp_line
			(start 0.7874 0.4064)
			(end -0.7874 0.4064)
			(stroke
				(width 0.1524)
				(type default)
			)
			(layer "F.SilkS")
		)
		(fp_line
			(start -0.67945 -0.305054)
			(end -0.12065 -0.305054)
			(stroke
				(width 0.1)
				(type default)
			)
			(layer "F.Fab")
		)
		(fp_line
			(start -0.67945 0.3048)
			(end -0.67945 -0.305054)
			(stroke
				(width 0.1)
				(type default)
			)
			(layer "F.Fab")
		)
		(fp_line
			(start -0.12065 -0.305054)
			(end -0.12065 -0.2794)
			(stroke
				(width 0.1)
				(type default)
			)
			(layer "F.Fab")
		)
		(fp_line
			(start -0.12065 -0.2794)
			(end 0.12065 -0.2794)
			(stroke
				(width 0.1)
				(type default)
			)
			(layer "F.Fab")
		)
		(fp_line
			(start -0.12065 0.2794)
			(end -0.12065 0.3048)
			(stroke
				(width 0.1)
				(type default)
			)
			(layer "F.Fab")
		)
		(fp_line
			(start -0.12065 0.3048)
			(end -0.67945 0.3048)
			(stroke
				(width 0.1)
				(type default)
			)
			(layer "F.Fab")
		)
		(fp_line
			(start 0.120396 0.2794)
			(end -0.12065 0.2794)
			(stroke
				(width 0.1)
				(type default)
			)
			(layer "F.Fab")
		)
		(fp_line
			(start 0.120396 0.3048)
			(end 0.120396 0.2794)
			(stroke
				(width 0.1)
				(type default)
			)
			(layer "F.Fab")
		)
		(fp_line
			(start 0.12065 -0.3048)
			(end 0.67945 -0.3048)
			(stroke
				(width 0.1)
				(type default)
			)
			(layer "F.Fab")
		)
		(fp_line
			(start 0.12065 -0.2794)
			(end 0.12065 -0.3048)
			(stroke
				(width 0.1)
				(type default)
			)
			(layer "F.Fab")
		)
		(fp_line
			(start 0.67945 -0.3048)
			(end 0.67945 0.3048)
			(stroke
				(width 0.1)
				(type default)
			)
			(layer "F.Fab")
		)
		(fp_line
			(start 0.67945 0.3048)
			(end 0.120396 0.3048)
			(stroke
				(width 0.1)
				(type default)
			)
			(layer "F.Fab")
		)
		(pad "1" smd circle
			(at -0.40005 0)
			(size 0 0)
			(layers "F.Cu" "F.Mask" "F.Paste")
			(net "P12V_AUX_DSC_VOL")
		)
		(pad "2" smd circle
			(at 0.40005 0)
			(size 0 0)
			(layers "F.Cu" "F.Mask" "F.Paste")
			(net "GND")
		)
	)
	(footprint ""
		(layer "F.Cu")
		(at 303.200308 -43.989498 180)
		(property "Reference" "C2052"
			(at 0 0 180)
			(layer "F.SilkS")
			(hide yes)
			(effects
				(font
					(size 1.27 1.27)
				)
			)
		)
		(property "Value" ""
			(at 0 0 180)
			(layer "F.Fab")
			(effects
				(font
					(size 1.27 1.27)
				)
			)
		)
		(duplicate_pad_numbers_are_jumpers no)
		(fp_line
			(start 0.7874 0.4064)
			(end -0.7874 0.4064)
			(stroke
				(width 0.1524)
				(type default)
			)
			(layer "F.SilkS")
		)
		(fp_line
			(start 0.7874 -0.4064)
			(end 0.7874 0.4064)
			(stroke
				(width 0.1524)
				(type default)
			)
			(layer "F.SilkS")
		)
		(fp_line
			(start -0.7874 0.4064)
			(end -0.7874 -0.4064)
			(stroke
				(width 0.1524)
				(type default)
			)
			(layer "F.SilkS")
		)
		(fp_line
			(start -0.7874 -0.4064)
			(end 0.7874 -0.4064)
			(stroke
				(width 0.1524)
				(type default)
			)
			(layer "F.SilkS")
		)
		(fp_line
			(start 0.67945 0.3048)
			(end 0.120396 0.3048)
			(stroke
				(width 0.1)
				(type default)
			)
			(layer "F.Fab")
		)
		(fp_line
			(start 0.67945 -0.3048)
			(end 0.67945 0.3048)
			(stroke
				(width 0.1)
				(type default)
			)
			(layer "F.Fab")
		)
		(fp_line
			(start 0.12065 -0.2794)
			(end 0.12065 -0.3048)
			(stroke
				(width 0.1)
				(type default)
			)
			(layer "F.Fab")
		)
		(fp_line
			(start 0.12065 -0.3048)
			(end 0.67945 -0.3048)
			(stroke
				(width 0.1)
				(type default)
			)
			(layer "F.Fab")
		)
		(fp_line
			(start 0.120396 0.3048)
			(end 0.120396 0.2794)
			(stroke
				(width 0.1)
				(type default)
			)
			(layer "F.Fab")
		)
		(fp_line
			(start 0.120396 0.2794)
			(end -0.12065 0.2794)
			(stroke
				(width 0.1)
				(type default)
			)
			(layer "F.Fab")
		)
		(fp_line
			(start -0.12065 0.3048)
			(end -0.67945 0.3048)
			(stroke
				(width 0.1)
				(type default)
			)
			(layer "F.Fab")
		)
		(fp_line
			(start -0.12065 0.2794)
			(end -0.12065 0.3048)
			(stroke
				(width 0.1)
				(type default)
			)
			(layer "F.Fab")
		)
		(fp_line
			(start -0.12065 -0.2794)
			(end 0.12065 -0.2794)
			(stroke
				(width 0.1)
				(type default)
			)
			(layer "F.Fab")
		)
		(fp_line
			(start -0.12065 -0.305054)
			(end -0.12065 -0.2794)
			(stroke
				(width 0.1)
				(type default)
			)
			(layer "F.Fab")
		)
		(fp_line
			(start -0.67945 0.3048)
			(end -0.67945 -0.305054)
			(stroke
				(width 0.1)
				(type default)
			)
			(layer "F.Fab")
		)
		(fp_line
			(start -0.67945 -0.305054)
			(end -0.12065 -0.305054)
			(stroke
				(width 0.1)
				(type default)
			)
			(layer "F.Fab")
		)
		(pad "1" smd circle
			(at -0.40005 0 180)
			(size 0 0)
			(layers "F.Cu" "F.Mask" "F.Paste")
			(net "P3V3_ADC128_VCC")
		)
		(pad "2" smd circle
			(at 0.40005 0 180)
			(size 0 0)
			(layers "F.Cu" "F.Mask" "F.Paste")
			(net "GND")
		)
	)
	(footprint ""
		(layer "F.Cu")
		(at 340.891876 -70.098412 90)
		(property "Reference" "D82"
			(at -3.934714 -0.691642 90)
			(unlocked yes)
			(layer "F.SilkS")
			(effects
				(font
					(size 0.7874 0.5842)
					(thickness 0.1524)
				)
				(justify left)
			)
		)
		(property "Value" ""
			(at 0 0 90)
			(layer "F.Fab")
			(effects
				(font
					(size 1.27 1.27)
				)
			)
		)
		(duplicate_pad_numbers_are_jumpers no)
		(fp_line
			(start 1.16078 -0.4826)
			(end 1.16078 0.4826)
			(stroke
				(width 0.1524)
				(type default)
			)
			(layer "F.SilkS")
		)
		(fp_line
			(start 1.03378 -0.4826)
			(end 1.03378 0.4826)
			(stroke
				(width 0.1524)
				(type default)
			)
			(layer "F.SilkS")
		)
		(fp_line
			(start 0.90678 -0.4826)
			(end 0.90678 0.4826)
			(stroke
				(width 0.1524)
				(type default)
			)
			(layer "F.SilkS")
		)
		(fp_line
			(start -0.64008 -0.4826)
			(end 1.16078 -0.4826)
			(stroke
				(width 0.1524)
				(type default)
			)
			(layer "F.SilkS")
		)
		(fp_line
			(start -0.79248 -0.4826)
			(end 1.03378 -0.4826)
			(stroke
				(width 0.1524)
				(type default)
			)
			(layer "F.SilkS")
		)
		(fp_line
			(start -0.89408 -0.4826)
			(end 0.90678 -0.4826)
			(stroke
				(width 0.1524)
				(type default)
			)
			(layer "F.SilkS")
		)
		(fp_line
			(start 1.16078 0.4826)
			(end -0.64008 0.4826)
			(stroke
				(width 0.1524)
				(type default)
			)
			(layer "F.SilkS")
		)
		(fp_line
			(start 1.03378 0.4826)
			(end -0.79248 0.4826)
			(stroke
				(width 0.1524)
				(type default)
			)
			(layer "F.SilkS")
		)
		(fp_line
			(start 0.90678 0.4826)
			(end -0.90678 0.4826)
			(stroke
				(width 0.1524)
				(type default)
			)
			(layer "F.SilkS")
		)
		(fp_line
			(start -0.90678 0.4826)
			(end -0.90678 -0.4699)
			(stroke
				(width 0.1524)
				(type default)
			)
			(layer "F.SilkS")
		)
		(fp_line
			(start 0.499872 -0.249936)
			(end 0.499872 0.249936)
			(stroke
				(width 0.1)
				(type default)
			)
			(layer "F.Fab")
		)
		(fp_line
			(start -0.499872 -0.249936)
			(end 0.499872 -0.249936)
			(stroke
				(width 0.1)
				(type default)
			)
			(layer "F.Fab")
		)
		(fp_line
			(start 0.499872 0.249936)
			(end -0.499872 0.249936)
			(stroke
				(width 0.1)
				(type default)
			)
			(layer "F.Fab")
		)
		(fp_line
			(start -0.499872 0.249936)
			(end -0.499872 -0.249936)
			(stroke
				(width 0.1)
				(type default)
			)
			(layer "F.Fab")
		)
		(pad "A" smd rect
			(at -0.47498 0 90)
			(size 0.6096 0.7112)
			(layers "F.Cu" "F.Mask" "F.Paste")
			(net "LED_PWRGD_PVDDCR_CPU1_P1_R")
		)
		(pad "C" smd rect
			(at 0.47498 0 90)
			(size 0.6096 0.7112)
			(layers "F.Cu" "F.Mask" "F.Paste")
			(net "LED_PWRGD_PVDDCR_CPU1_P1_D")
		)
	)
	(footprint ""
		(layer "F.Cu")
		(at 73.466706 -152.990804 90)
		(property "Reference" "PC61"
			(at 0 0 90)
			(layer "F.SilkS")
			(hide yes)
			(effects
				(font
					(size 1.27 1.27)
				)
			)
		)
		(property "Value" ""
			(at 0 0 90)
			(layer "F.Fab")
			(effects
				(font
					(size 1.27 1.27)
				)
			)
		)
		(duplicate_pad_numbers_are_jumpers no)
		(fp_line
			(start 1.524 -0.762)
			(end 1.524 0.762)
			(stroke
				(width 0.1524)
				(type default)
			)
			(layer "F.SilkS")
		)
		(fp_line
			(start -1.524 -0.762)
			(end 1.524 -0.762)
			(stroke
				(width 0.1524)
				(type default)
			)
			(layer "F.SilkS")
		)
		(fp_line
			(start 1.524 0.762)
			(end -1.524 0.762)
			(stroke
				(width 0.1524)
				(type default)
			)
			(layer "F.SilkS")
		)
		(fp_line
			(start -1.524 0.762)
			(end -1.524 -0.762)
			(stroke
				(width 0.1524)
				(type default)
			)
			(layer "F.SilkS")
		)
		(fp_line
			(start 1.1049 -0.724916)
			(end -1.1049 -0.724916)
			(stroke
				(width 0.1)
				(type default)
			)
			(layer "F.Fab")
		)
		(fp_line
			(start -1.1049 -0.724916)
			(end -1.1049 0.724916)
			(stroke
				(width 0.1)
				(type default)
			)
			(layer "F.Fab")
		)
		(fp_line
			(start 1.1049 0.724916)
			(end 1.1049 -0.724916)
			(stroke
				(width 0.1)
				(type default)
			)
			(layer "F.Fab")
		)
		(fp_line
			(start -1.1049 0.724916)
			(end 1.1049 0.724916)
			(stroke
				(width 0.1)
				(type default)
			)
			(layer "F.Fab")
		)
		(pad "1" smd rect
			(at -0.889 0 270)
			(size 1.016 1.27)
			(layers "F.Cu" "F.Mask" "F.Paste")
			(net "SW_P12V_AUX_PVDD18_S5_P1_FLT")
		)
		(pad "2" smd rect
			(at 0.889 0 270)
			(size 1.016 1.27)
			(layers "F.Cu" "F.Mask" "F.Paste")
			(net "GND")
		)
	)
	(footprint ""
		(layer "F.Cu")
		(at 208.878932 -119.721376)
		(property "Reference" "R2664"
			(at 0 0 0)
			(layer "F.SilkS")
			(hide yes)
			(effects
				(font
					(size 1.27 1.27)
				)
			)
		)
		(property "Value" ""
			(at 0 0 0)
			(layer "F.Fab")
			(effects
				(font
					(size 1.27 1.27)
				)
			)
		)
		(duplicate_pad_numbers_are_jumpers no)
		(fp_line
			(start -0.7874 -0.4064)
			(end 0.7874 -0.4064)
			(stroke
				(width 0.1524)
				(type default)
			)
			(layer "F.SilkS")
		)
		(fp_line
			(start -0.7874 0.4064)
			(end -0.7874 -0.4064)
			(stroke
				(width 0.1524)
				(type default)
			)
			(layer "F.SilkS")
		)
		(fp_line
			(start 0.7874 -0.4064)
			(end 0.7874 0.4064)
			(stroke
				(width 0.1524)
				(type default)
			)
			(layer "F.SilkS")
		)
		(fp_line
			(start 0.7874 0.4064)
			(end -0.7874 0.4064)
			(stroke
				(width 0.1524)
				(type default)
			)
			(layer "F.SilkS")
		)
		(fp_line
			(start -0.67945 -0.305054)
			(end -0.12065 -0.305054)
			(stroke
				(width 0.1)
				(type default)
			)
			(layer "F.Fab")
		)
		(fp_line
			(start -0.67945 0.3048)
			(end -0.67945 -0.305054)
			(stroke
				(width 0.1)
				(type default)
			)
			(layer "F.Fab")
		)
		(fp_line
			(start -0.12065 -0.305054)
			(end -0.12065 -0.2794)
			(stroke
				(width 0.1)
				(type default)
			)
			(layer "F.Fab")
		)
		(fp_line
			(start -0.12065 -0.2794)
			(end 0.12065 -0.2794)
			(stroke
				(width 0.1)
				(type default)
			)
			(layer "F.Fab")
		)
		(fp_line
			(start -0.12065 0.2794)
			(end -0.12065 0.3048)
			(stroke
				(width 0.1)
				(type default)
			)
			(layer "F.Fab")
		)
		(fp_line
			(start -0.12065 0.3048)
			(end -0.67945 0.3048)
			(stroke
				(width 0.1)
				(type default)
			)
			(layer "F.Fab")
		)
		(fp_line
			(start 0.120396 0.2794)
			(end -0.12065 0.2794)
			(stroke
				(width 0.1)
				(type default)
			)
			(layer "F.Fab")
		)
		(fp_line
			(start 0.120396 0.3048)
			(end 0.120396 0.2794)
			(stroke
				(width 0.1)
				(type default)
			)
			(layer "F.Fab")
		)
		(fp_line
			(start 0.12065 -0.3048)
			(end 0.67945 -0.3048)
			(stroke
				(width 0.1)
				(type default)
			)
			(layer "F.Fab")
		)
		(fp_line
			(start 0.12065 -0.2794)
			(end 0.12065 -0.3048)
			(stroke
				(width 0.1)
				(type default)
			)
			(layer "F.Fab")
		)
		(fp_line
			(start 0.67945 -0.3048)
			(end 0.67945 0.3048)
			(stroke
				(width 0.1)
				(type default)
			)
			(layer "F.Fab")
		)
		(fp_line
			(start 0.67945 0.3048)
			(end 0.120396 0.3048)
			(stroke
				(width 0.1)
				(type default)
			)
			(layer "F.Fab")
		)
		(pad "1" smd circle
			(at -0.40005 0)
			(size 0 0)
			(layers "F.Cu" "F.Mask" "F.Paste")
			(net "FM_GPU_PWRGD_ISO_R")
		)
		(pad "2" smd circle
			(at 0.40005 0)
			(size 0 0)
			(layers "F.Cu" "F.Mask" "F.Paste")
			(net "FM_GPU_PWRGD_ISO")
		)
	)
	(footprint ""
		(layer "F.Cu")
		(at 279.513792 -115.66017 180)
		(property "Reference" "R2967"
			(at 0 0 180)
			(layer "F.SilkS")
			(hide yes)
			(effects
				(font
					(size 1.27 1.27)
				)
			)
		)
		(property "Value" ""
			(at 0 0 180)
			(layer "F.Fab")
			(effects
				(font
					(size 1.27 1.27)
				)
			)
		)
		(duplicate_pad_numbers_are_jumpers no)
		(fp_line
			(start 0.7874 0.4064)
			(end -0.7874 0.4064)
			(stroke
				(width 0.1524)
				(type default)
			)
			(layer "F.SilkS")
		)
		(fp_line
			(start 0.7874 -0.4064)
			(end 0.7874 0.4064)
			(stroke
				(width 0.1524)
				(type default)
			)
			(layer "F.SilkS")
		)
		(fp_line
			(start -0.7874 0.4064)
			(end -0.7874 -0.4064)
			(stroke
				(width 0.1524)
				(type default)
			)
			(layer "F.SilkS")
		)
		(fp_line
			(start -0.7874 -0.4064)
			(end 0.7874 -0.4064)
			(stroke
				(width 0.1524)
				(type default)
			)
			(layer "F.SilkS")
		)
		(fp_line
			(start 0.67945 0.3048)
			(end 0.120396 0.3048)
			(stroke
				(width 0.1)
				(type default)
			)
			(layer "F.Fab")
		)
		(fp_line
			(start 0.67945 -0.3048)
			(end 0.67945 0.3048)
			(stroke
				(width 0.1)
				(type default)
			)
			(layer "F.Fab")
		)
		(fp_line
			(start 0.12065 -0.2794)
			(end 0.12065 -0.3048)
			(stroke
				(width 0.1)
				(type default)
			)
			(layer "F.Fab")
		)
		(fp_line
			(start 0.12065 -0.3048)
			(end 0.67945 -0.3048)
			(stroke
				(width 0.1)
				(type default)
			)
			(layer "F.Fab")
		)
		(fp_line
			(start 0.120396 0.3048)
			(end 0.120396 0.2794)
			(stroke
				(width 0.1)
				(type default)
			)
			(layer "F.Fab")
		)
		(fp_line
			(start 0.120396 0.2794)
			(end -0.12065 0.2794)
			(stroke
				(width 0.1)
				(type default)
			)
			(layer "F.Fab")
		)
		(fp_line
			(start -0.12065 0.3048)
			(end -0.67945 0.3048)
			(stroke
				(width 0.1)
				(type default)
			)
			(layer "F.Fab")
		)
		(fp_line
			(start -0.12065 0.2794)
			(end -0.12065 0.3048)
			(stroke
				(width 0.1)
				(type default)
			)
			(layer "F.Fab")
		)
		(fp_line
			(start -0.12065 -0.2794)
			(end 0.12065 -0.2794)
			(stroke
				(width 0.1)
				(type default)
			)
			(layer "F.Fab")
		)
		(fp_line
			(start -0.12065 -0.305054)
			(end -0.12065 -0.2794)
			(stroke
				(width 0.1)
				(type default)
			)
			(layer "F.Fab")
		)
		(fp_line
			(start -0.67945 0.3048)
			(end -0.67945 -0.305054)
			(stroke
				(width 0.1)
				(type default)
			)
			(layer "F.Fab")
		)
		(fp_line
			(start -0.67945 -0.305054)
			(end -0.12065 -0.305054)
			(stroke
				(width 0.1)
				(type default)
			)
			(layer "F.Fab")
		)
		(pad "1" smd circle
			(at -0.40005 0 180)
			(size 0 0)
			(layers "F.Cu" "F.Mask" "F.Paste")
			(net "SMB_PCIE0_3V3AUX_SCL_R3")
		)
		(pad "2" smd circle
			(at 0.40005 0 180)
			(size 0 0)
			(layers "F.Cu" "F.Mask" "F.Paste")
			(net "SMB_SENSOR_M2_P1_3V3AUX_SCL")
		)
	)
	(footprint ""
		(layer "F.Cu")
		(at 142.729712 -73.623932)
		(property "Reference" "PR6007"
			(at 0 0 0)
			(layer "F.SilkS")
			(hide yes)
			(effects
				(font
					(size 1.27 1.27)
				)
			)
		)
		(property "Value" ""
			(at 0 0 0)
			(layer "F.Fab")
			(effects
				(font
					(size 1.27 1.27)
				)
			)
		)
		(duplicate_pad_numbers_are_jumpers no)
		(fp_line
			(start -0.7874 -0.4064)
			(end 0.7874 -0.4064)
			(stroke
				(width 0.1524)
				(type default)
			)
			(layer "F.SilkS")
		)
		(fp_line
			(start -0.7874 0.4064)
			(end -0.7874 -0.4064)
			(stroke
				(width 0.1524)
				(type default)
			)
			(layer "F.SilkS")
		)
		(fp_line
			(start 0.7874 -0.4064)
			(end 0.7874 0.4064)
			(stroke
				(width 0.1524)
				(type default)
			)
			(layer "F.SilkS")
		)
		(fp_line
			(start 0.7874 0.4064)
			(end -0.7874 0.4064)
			(stroke
				(width 0.1524)
				(type default)
			)
			(layer "F.SilkS")
		)
		(fp_line
			(start -0.67945 -0.305054)
			(end -0.12065 -0.305054)
			(stroke
				(width 0.1)
				(type default)
			)
			(layer "F.Fab")
		)
		(fp_line
			(start -0.67945 0.3048)
			(end -0.67945 -0.305054)
			(stroke
				(width 0.1)
				(type default)
			)
			(layer "F.Fab")
		)
		(fp_line
			(start -0.12065 -0.305054)
			(end -0.12065 -0.2794)
			(stroke
				(width 0.1)
				(type default)
			)
			(layer "F.Fab")
		)
		(fp_line
			(start -0.12065 -0.2794)
			(end 0.12065 -0.2794)
			(stroke
				(width 0.1)
				(type default)
			)
			(layer "F.Fab")
		)
		(fp_line
			(start -0.12065 0.2794)
			(end -0.12065 0.3048)
			(stroke
				(width 0.1)
				(type default)
			)
			(layer "F.Fab")
		)
		(fp_line
			(start -0.12065 0.3048)
			(end -0.67945 0.3048)
			(stroke
				(width 0.1)
				(type default)
			)
			(layer "F.Fab")
		)
		(fp_line
			(start 0.120396 0.2794)
			(end -0.12065 0.2794)
			(stroke
				(width 0.1)
				(type default)
			)
			(layer "F.Fab")
		)
		(fp_line
			(start 0.120396 0.3048)
			(end 0.120396 0.2794)
			(stroke
				(width 0.1)
				(type default)
			)
			(layer "F.Fab")
		)
		(fp_line
			(start 0.12065 -0.3048)
			(end 0.67945 -0.3048)
			(stroke
				(width 0.1)
				(type default)
			)
			(layer "F.Fab")
		)
		(fp_line
			(start 0.12065 -0.2794)
			(end 0.12065 -0.3048)
			(stroke
				(width 0.1)
				(type default)
			)
			(layer "F.Fab")
		)
		(fp_line
			(start 0.67945 -0.3048)
			(end 0.67945 0.3048)
			(stroke
				(width 0.1)
				(type default)
			)
			(layer "F.Fab")
		)
		(fp_line
			(start 0.67945 0.3048)
			(end 0.120396 0.3048)
			(stroke
				(width 0.1)
				(type default)
			)
			(layer "F.Fab")
		)
		(pad "1" smd circle
			(at -0.40005 0)
			(size 0 0)
			(layers "F.Cu" "F.Mask" "F.Paste")
			(net "P1V8_AUX_FB")
		)
		(pad "2" smd circle
			(at 0.40005 0)
			(size 0 0)
			(layers "F.Cu" "F.Mask" "F.Paste")
			(net "P1V8_AUX")
		)
	)
	(footprint ""
		(layer "F.Cu")
		(at 430.664366 -392.879072 -90)
		(property "Reference" "C667"
			(at 0 0 270)
			(layer "F.SilkS")
			(hide yes)
			(effects
				(font
					(size 1.27 1.27)
				)
			)
		)
		(property "Value" ""
			(at 0 0 270)
			(layer "F.Fab")
			(effects
				(font
					(size 1.27 1.27)
				)
			)
		)
		(duplicate_pad_numbers_are_jumpers no)
		(fp_line
			(start -0.7874 0.4064)
			(end -0.7874 -0.4064)
			(stroke
				(width 0.1524)
				(type default)
			)
			(layer "F.SilkS")
		)
		(fp_line
			(start 0.7874 0.4064)
			(end -0.7874 0.4064)
			(stroke
				(width 0.1524)
				(type default)
			)
			(layer "F.SilkS")
		)
		(fp_line
			(start -0.7874 -0.4064)
			(end 0.7874 -0.4064)
			(stroke
				(width 0.1524)
				(type default)
			)
			(layer "F.SilkS")
		)
		(fp_line
			(start 0.7874 -0.4064)
			(end 0.7874 0.4064)
			(stroke
				(width 0.1524)
				(type default)
			)
			(layer "F.SilkS")
		)
		(fp_line
			(start -0.67945 0.3048)
			(end -0.67945 -0.305054)
			(stroke
				(width 0.1)
				(type default)
			)
			(layer "F.Fab")
		)
		(fp_line
			(start -0.12065 0.3048)
			(end -0.67945 0.3048)
			(stroke
				(width 0.1)
				(type default)
			)
			(layer "F.Fab")
		)
		(fp_line
			(start 0.120396 0.3048)
			(end 0.120396 0.2794)
			(stroke
				(width 0.1)
				(type default)
			)
			(layer "F.Fab")
		)
		(fp_line
			(start 0.67945 0.3048)
			(end 0.120396 0.3048)
			(stroke
				(width 0.1)
				(type default)
			)
			(layer "F.Fab")
		)
		(fp_line
			(start -0.12065 0.2794)
			(end -0.12065 0.3048)
			(stroke
				(width 0.1)
				(type default)
			)
			(layer "F.Fab")
		)
		(fp_line
			(start 0.120396 0.2794)
			(end -0.12065 0.2794)
			(stroke
				(width 0.1)
				(type default)
			)
			(layer "F.Fab")
		)
		(fp_line
			(start -0.12065 -0.2794)
			(end 0.12065 -0.2794)
			(stroke
				(width 0.1)
				(type default)
			)
			(layer "F.Fab")
		)
		(fp_line
			(start 0.12065 -0.2794)
			(end 0.12065 -0.3048)
			(stroke
				(width 0.1)
				(type default)
			)
			(layer "F.Fab")
		)
		(fp_line
			(start 0.12065 -0.3048)
			(end 0.67945 -0.3048)
			(stroke
				(width 0.1)
				(type default)
			)
			(layer "F.Fab")
		)
		(fp_line
			(start 0.67945 -0.3048)
			(end 0.67945 0.3048)
			(stroke
				(width 0.1)
				(type default)
			)
			(layer "F.Fab")
		)
		(fp_line
			(start -0.67945 -0.305054)
			(end -0.12065 -0.305054)
			(stroke
				(width 0.1)
				(type default)
			)
			(layer "F.Fab")
		)
		(fp_line
			(start -0.12065 -0.305054)
			(end -0.12065 -0.2794)
			(stroke
				(width 0.1)
				(type default)
			)
			(layer "F.Fab")
		)
		(pad "1" smd circle
			(at -0.40005 0 270)
			(size 0 0)
			(layers "F.Cu" "F.Mask" "F.Paste")
			(net "P1V8_CPU0_RT_1D")
		)
		(pad "2" smd circle
			(at 0.40005 0 270)
			(size 0 0)
			(layers "F.Cu" "F.Mask" "F.Paste")
			(net "GND")
		)
	)
	(footprint ""
		(layer "F.Cu")
		(at 103.847138 -330.622148)
		(property "Reference" "PL69"
			(at -3.115056 -15.887446 0)
			(unlocked yes)
			(layer "F.SilkS")
			(effects
				(font
					(size 0.7874 0.5842)
					(thickness 0.1524)
				)
				(justify left)
			)
		)
		(property "Value" ""
			(at 0 0 0)
			(layer "F.Fab")
			(effects
				(font
					(size 1.27 1.27)
				)
			)
		)
		(duplicate_pad_numbers_are_jumpers no)
		(fp_line
			(start -3.750056 -5.500116)
			(end -2.393442 -5.500116)
			(stroke
				(width 0.1524)
				(type default)
			)
			(layer "F.SilkS")
		)
		(fp_line
			(start -3.750056 5.500116)
			(end -3.750056 -5.500116)
			(stroke
				(width 0.1524)
				(type default)
			)
			(layer "F.SilkS")
		)
		(fp_line
			(start -2.393442 5.500116)
			(end -3.750056 5.500116)
			(stroke
				(width 0.1524)
				(type default)
			)
			(layer "F.SilkS")
		)
		(fp_line
			(start 2.393442 5.500116)
			(end 3.750056 5.500116)
			(stroke
				(width 0.1524)
				(type default)
			)
			(layer "F.SilkS")
		)
		(fp_line
			(start 3.750056 -5.500116)
			(end 2.393442 -5.500116)
			(stroke
				(width 0.1524)
				(type default)
			)
			(layer "F.SilkS")
		)
		(fp_line
			(start 3.750056 5.500116)
			(end 3.750056 -5.500116)
			(stroke
				(width 0.1524)
				(type default)
			)
			(layer "F.SilkS")
		)
		(fp_poly
			(pts
				(xy -3.847084 -5.385308) (xy -4.305046 -5.537962) (xy -3.999738 -5.84327)
			)
			(stroke
				(width 0)
				(type default)
			)
			(fill yes)
			(layer "F.SilkS")
		)
		(fp_line
			(start -3.750056 -5.500116)
			(end -3.750056 5.500116)
			(stroke
				(width 0.1)
				(type default)
			)
			(layer "F.Fab")
		)
		(fp_line
			(start -3.750056 5.500116)
			(end 3.750056 5.500116)
			(stroke
				(width 0.1)
				(type default)
			)
			(layer "F.Fab")
		)
		(fp_line
			(start 3.750056 -5.500116)
			(end -3.750056 -5.500116)
			(stroke
				(width 0.1)
				(type default)
			)
			(layer "F.Fab")
		)
		(fp_line
			(start 3.750056 5.500116)
			(end 3.750056 -5.500116)
			(stroke
				(width 0.1)
				(type default)
			)
			(layer "F.Fab")
		)
		(fp_poly
			(pts
				(xy -4.9276 -4.757928) (xy -4.9276 -3.741928) (xy -3.9116 -4.249928)
			)
			(stroke
				(width 0)
				(type default)
			)
			(fill yes)
			(layer "F.Fab")
		)
		(pad "1" smd rect
			(at 0 -4.249928 270)
			(size 2.413 4.5212)
			(layers "F.Cu" "F.Mask" "F.Paste")
			(net "SW_PVDDCR_CPU1_P1_SW6")
		)
		(pad "2" smd rect
			(at 0 -1.175004 270)
			(size 1.3716 4.5212)
			(layers "F.Cu" "F.Mask" "F.Paste")
			(net "IND_CPU1_P1_CPL0")
		)
		(pad "3" smd rect
			(at 0 1.175004 270)
			(size 1.3716 4.5212)
			(layers "F.Cu" "F.Mask" "F.Paste")
			(net "IND_CPU1_P1_CPL6")
		)
		(pad "4" smd rect
			(at 0 4.249928 270)
			(size 2.413 4.5212)
			(layers "F.Cu" "F.Mask" "F.Paste")
			(net "PVDDCR_CPU1_P1")
		)
	)
	(footprint ""
		(layer "F.Cu")
		(at 297.741594 -392.1252)
		(property "Reference" "R985"
			(at 0 0 0)
			(layer "F.SilkS")
			(hide yes)
			(effects
				(font
					(size 1.27 1.27)
				)
			)
		)
		(property "Value" ""
			(at 0 0 0)
			(layer "F.Fab")
			(effects
				(font
					(size 1.27 1.27)
				)
			)
		)
		(duplicate_pad_numbers_are_jumpers no)
		(fp_line
			(start -0.32512 -0.175006)
			(end 0.32512 -0.175006)
			(stroke
				(width 0.1)
				(type default)
			)
			(layer "F.Fab")
		)
		(fp_line
			(start -0.32512 0.175006)
			(end -0.32512 -0.175006)
			(stroke
				(width 0.1)
				(type default)
			)
			(layer "F.Fab")
		)
		(fp_line
			(start 0.32512 -0.175006)
			(end 0.32512 0.175006)
			(stroke
				(width 0.1)
				(type default)
			)
			(layer "F.Fab")
		)
		(fp_line
			(start 0.32512 0.175006)
			(end -0.32512 0.175006)
			(stroke
				(width 0.1)
				(type default)
			)
			(layer "F.Fab")
		)
		(pad "1" smd rect
			(at -0.2667 0)
			(size 0.3048 0.381)
			(layers "F.Cu" "F.Mask" "F.Paste")
			(net "P1V8_CPU0_RT_1D")
		)
		(pad "2" smd rect
			(at 0.2667 0 180)
			(size 0.3048 0.381)
			(layers "F.Cu" "F.Mask" "F.Paste")
			(net "TEST2_RT_CPU0_P0")
		)
	)
	(footprint ""
		(layer "F.Cu")
		(at 60.920122 -181.291992 -90)
		(property "Reference" "PC278"
			(at 0 0 270)
			(layer "F.SilkS")
			(hide yes)
			(effects
				(font
					(size 1.27 1.27)
				)
			)
		)
		(property "Value" ""
			(at 0 0 270)
			(layer "F.Fab")
			(effects
				(font
					(size 1.27 1.27)
				)
			)
		)
		(duplicate_pad_numbers_are_jumpers no)
		(fp_line
			(start -0.7874 0.4064)
			(end -0.7874 -0.4064)
			(stroke
				(width 0.1524)
				(type default)
			)
			(layer "F.SilkS")
		)
		(fp_line
			(start 0.7874 0.4064)
			(end -0.7874 0.4064)
			(stroke
				(width 0.1524)
				(type default)
			)
			(layer "F.SilkS")
		)
		(fp_line
			(start -0.7874 -0.4064)
			(end 0.7874 -0.4064)
			(stroke
				(width 0.1524)
				(type default)
			)
			(layer "F.SilkS")
		)
		(fp_line
			(start 0.7874 -0.4064)
			(end 0.7874 0.4064)
			(stroke
				(width 0.1524)
				(type default)
			)
			(layer "F.SilkS")
		)
		(fp_line
			(start -0.67945 0.3048)
			(end -0.67945 -0.305054)
			(stroke
				(width 0.1)
				(type default)
			)
			(layer "F.Fab")
		)
		(fp_line
			(start -0.12065 0.3048)
			(end -0.67945 0.3048)
			(stroke
				(width 0.1)
				(type default)
			)
			(layer "F.Fab")
		)
		(fp_line
			(start 0.120396 0.3048)
			(end 0.120396 0.2794)
			(stroke
				(width 0.1)
				(type default)
			)
			(layer "F.Fab")
		)
		(fp_line
			(start 0.67945 0.3048)
			(end 0.120396 0.3048)
			(stroke
				(width 0.1)
				(type default)
			)
			(layer "F.Fab")
		)
		(fp_line
			(start -0.12065 0.2794)
			(end -0.12065 0.3048)
			(stroke
				(width 0.1)
				(type default)
			)
			(layer "F.Fab")
		)
		(fp_line
			(start 0.120396 0.2794)
			(end -0.12065 0.2794)
			(stroke
				(width 0.1)
				(type default)
			)
			(layer "F.Fab")
		)
		(fp_line
			(start -0.12065 -0.2794)
			(end 0.12065 -0.2794)
			(stroke
				(width 0.1)
				(type default)
			)
			(layer "F.Fab")
		)
		(fp_line
			(start 0.12065 -0.2794)
			(end 0.12065 -0.3048)
			(stroke
				(width 0.1)
				(type default)
			)
			(layer "F.Fab")
		)
		(fp_line
			(start 0.12065 -0.3048)
			(end 0.67945 -0.3048)
			(stroke
				(width 0.1)
				(type default)
			)
			(layer "F.Fab")
		)
		(fp_line
			(start 0.67945 -0.3048)
			(end 0.67945 0.3048)
			(stroke
				(width 0.1)
				(type default)
			)
			(layer "F.Fab")
		)
		(fp_line
			(start -0.67945 -0.305054)
			(end -0.12065 -0.305054)
			(stroke
				(width 0.1)
				(type default)
			)
			(layer "F.Fab")
		)
		(fp_line
			(start -0.12065 -0.305054)
			(end -0.12065 -0.2794)
			(stroke
				(width 0.1)
				(type default)
			)
			(layer "F.Fab")
		)
		(pad "1" smd circle
			(at -0.40005 0 270)
			(size 0 0)
			(layers "F.Cu" "F.Mask" "F.Paste")
			(net "PVDDCR_CPU0_P1")
		)
		(pad "2" smd circle
			(at 0.40005 0 270)
			(size 0 0)
			(layers "F.Cu" "F.Mask" "F.Paste")
			(net "GND")
		)
	)
	(footprint ""
		(layer "F.Cu")
		(at 140.208 -111.633 -90)
		(property "Reference" "U8009"
			(at 1.7018 -2.253488 90)
			(unlocked yes)
			(layer "F.SilkS")
			(effects
				(font
					(size 0.7874 0.5842)
					(thickness 0.1524)
				)
				(justify left)
			)
		)
		(property "Value" ""
			(at 0 0 270)
			(layer "F.Fab")
			(effects
				(font
					(size 1.27 1.27)
				)
			)
		)
		(duplicate_pad_numbers_are_jumpers no)
		(fp_line
			(start -1.868424 1.519936)
			(end 1.868424 1.519936)
			(stroke
				(width 0.1524)
				(type default)
			)
			(layer "F.SilkS")
		)
		(fp_line
			(start 1.868424 1.519936)
			(end 1.868424 -1.519936)
			(stroke
				(width 0.1524)
				(type default)
			)
			(layer "F.SilkS")
		)
		(fp_line
			(start -1.868424 -1.519936)
			(end -1.868424 1.519936)
			(stroke
				(width 0.1524)
				(type default)
			)
			(layer "F.SilkS")
		)
		(fp_line
			(start 1.868424 -1.519936)
			(end -1.868424 -1.519936)
			(stroke
				(width 0.1524)
				(type default)
			)
			(layer "F.SilkS")
		)
		(fp_line
			(start -0.700024 1.519936)
			(end 0.700024 1.519936)
			(stroke
				(width 0.1)
				(type default)
			)
			(layer "F.Fab")
		)
		(fp_line
			(start 0.700024 1.519936)
			(end 0.700024 -1.519936)
			(stroke
				(width 0.1)
				(type default)
			)
			(layer "F.Fab")
		)
		(fp_line
			(start -0.700024 -1.519936)
			(end -0.700024 1.519936)
			(stroke
				(width 0.1)
				(type default)
			)
			(layer "F.Fab")
		)
		(fp_line
			(start 0.700024 -1.519936)
			(end -0.700024 -1.519936)
			(stroke
				(width 0.1)
				(type default)
			)
			(layer "F.Fab")
		)
		(pad "1" smd rect
			(at -1.18491 -0.94996 180)
			(size 0.6096 1.0668)
			(layers "F.Cu" "F.Mask" "F.Paste")
			(net "UV_P2V5_COMP")
		)
		(pad "2" smd rect
			(at -1.18491 0.94996 180)
			(size 0.6096 1.0668)
			(layers "F.Cu" "F.Mask" "F.Paste")
			(net "GND")
		)
		(pad "3" smd rect
			(at 1.18491 0 180)
			(size 0.6096 1.0668)
			(layers "F.Cu" "F.Mask" "F.Paste")
			(net "Net_10849")
		)
	)
	(footprint ""
		(layer "F.Cu")
		(at 321.107308 -103.40975)
		(property "Reference" "R1308"
			(at 0 0 0)
			(layer "F.SilkS")
			(hide yes)
			(effects
				(font
					(size 1.27 1.27)
				)
			)
		)
		(property "Value" ""
			(at 0 0 0)
			(layer "F.Fab")
			(effects
				(font
					(size 1.27 1.27)
				)
			)
		)
		(duplicate_pad_numbers_are_jumpers no)
		(fp_line
			(start -0.7874 -0.4064)
			(end 0.7874 -0.4064)
			(stroke
				(width 0.1524)
				(type default)
			)
			(layer "F.SilkS")
		)
		(fp_line
			(start -0.7874 0.4064)
			(end -0.7874 -0.4064)
			(stroke
				(width 0.1524)
				(type default)
			)
			(layer "F.SilkS")
		)
		(fp_line
			(start 0.7874 -0.4064)
			(end 0.7874 0.4064)
			(stroke
				(width 0.1524)
				(type default)
			)
			(layer "F.SilkS")
		)
		(fp_line
			(start 0.7874 0.4064)
			(end -0.7874 0.4064)
			(stroke
				(width 0.1524)
				(type default)
			)
			(layer "F.SilkS")
		)
		(fp_line
			(start -0.67945 -0.305054)
			(end -0.12065 -0.305054)
			(stroke
				(width 0.1)
				(type default)
			)
			(layer "F.Fab")
		)
		(fp_line
			(start -0.67945 0.3048)
			(end -0.67945 -0.305054)
			(stroke
				(width 0.1)
				(type default)
			)
			(layer "F.Fab")
		)
		(fp_line
			(start -0.12065 -0.305054)
			(end -0.12065 -0.2794)
			(stroke
				(width 0.1)
				(type default)
			)
			(layer "F.Fab")
		)
		(fp_line
			(start -0.12065 -0.2794)
			(end 0.12065 -0.2794)
			(stroke
				(width 0.1)
				(type default)
			)
			(layer "F.Fab")
		)
		(fp_line
			(start -0.12065 0.2794)
			(end -0.12065 0.3048)
			(stroke
				(width 0.1)
				(type default)
			)
			(layer "F.Fab")
		)
		(fp_line
			(start -0.12065 0.3048)
			(end -0.67945 0.3048)
			(stroke
				(width 0.1)
				(type default)
			)
			(layer "F.Fab")
		)
		(fp_line
			(start 0.120396 0.2794)
			(end -0.12065 0.2794)
			(stroke
				(width 0.1)
				(type default)
			)
			(layer "F.Fab")
		)
		(fp_line
			(start 0.120396 0.3048)
			(end 0.120396 0.2794)
			(stroke
				(width 0.1)
				(type default)
			)
			(layer "F.Fab")
		)
		(fp_line
			(start 0.12065 -0.3048)
			(end 0.67945 -0.3048)
			(stroke
				(width 0.1)
				(type default)
			)
			(layer "F.Fab")
		)
		(fp_line
			(start 0.12065 -0.2794)
			(end 0.12065 -0.3048)
			(stroke
				(width 0.1)
				(type default)
			)
			(layer "F.Fab")
		)
		(fp_line
			(start 0.67945 -0.3048)
			(end 0.67945 0.3048)
			(stroke
				(width 0.1)
				(type default)
			)
			(layer "F.Fab")
		)
		(fp_line
			(start 0.67945 0.3048)
			(end 0.120396 0.3048)
			(stroke
				(width 0.1)
				(type default)
			)
			(layer "F.Fab")
		)
		(pad "1" smd circle
			(at -0.40005 0)
			(size 0 0)
			(layers "F.Cu" "F.Mask" "F.Paste")
			(net "GND")
		)
		(pad "2" smd circle
			(at 0.40005 0)
			(size 0 0)
			(layers "F.Cu" "F.Mask" "F.Paste")
			(net "INA230_8_A0")
		)
	)
	(footprint ""
		(layer "F.Cu")
		(at 430.155858 -430.891188)
		(property "Reference" "C6087"
			(at 0 0 0)
			(layer "F.SilkS")
			(hide yes)
			(effects
				(font
					(size 1.27 1.27)
				)
			)
		)
		(property "Value" ""
			(at 0 0 0)
			(layer "F.Fab")
			(effects
				(font
					(size 1.27 1.27)
				)
			)
		)
		(duplicate_pad_numbers_are_jumpers no)
		(fp_line
			(start -0.7874 -0.4064)
			(end 0.7874 -0.4064)
			(stroke
				(width 0.1524)
				(type default)
			)
			(layer "F.SilkS")
		)
		(fp_line
			(start -0.7874 0.4064)
			(end -0.7874 -0.4064)
			(stroke
				(width 0.1524)
				(type default)
			)
			(layer "F.SilkS")
		)
		(fp_line
			(start 0.7874 -0.4064)
			(end 0.7874 0.4064)
			(stroke
				(width 0.1524)
				(type default)
			)
			(layer "F.SilkS")
		)
		(fp_line
			(start 0.7874 0.4064)
			(end -0.7874 0.4064)
			(stroke
				(width 0.1524)
				(type default)
			)
			(layer "F.SilkS")
		)
		(fp_line
			(start -0.67945 -0.305054)
			(end -0.12065 -0.305054)
			(stroke
				(width 0.1)
				(type default)
			)
			(layer "F.Fab")
		)
		(fp_line
			(start -0.67945 0.3048)
			(end -0.67945 -0.305054)
			(stroke
				(width 0.1)
				(type default)
			)
			(layer "F.Fab")
		)
		(fp_line
			(start -0.12065 -0.305054)
			(end -0.12065 -0.2794)
			(stroke
				(width 0.1)
				(type default)
			)
			(layer "F.Fab")
		)
		(fp_line
			(start -0.12065 -0.2794)
			(end 0.12065 -0.2794)
			(stroke
				(width 0.1)
				(type default)
			)
			(layer "F.Fab")
		)
		(fp_line
			(start -0.12065 0.2794)
			(end -0.12065 0.3048)
			(stroke
				(width 0.1)
				(type default)
			)
			(layer "F.Fab")
		)
		(fp_line
			(start -0.12065 0.3048)
			(end -0.67945 0.3048)
			(stroke
				(width 0.1)
				(type default)
			)
			(layer "F.Fab")
		)
		(fp_line
			(start 0.120396 0.2794)
			(end -0.12065 0.2794)
			(stroke
				(width 0.1)
				(type default)
			)
			(layer "F.Fab")
		)
		(fp_line
			(start 0.120396 0.3048)
			(end 0.120396 0.2794)
			(stroke
				(width 0.1)
				(type default)
			)
			(layer "F.Fab")
		)
		(fp_line
			(start 0.12065 -0.3048)
			(end 0.67945 -0.3048)
			(stroke
				(width 0.1)
				(type default)
			)
			(layer "F.Fab")
		)
		(fp_line
			(start 0.12065 -0.2794)
			(end 0.12065 -0.3048)
			(stroke
				(width 0.1)
				(type default)
			)
			(layer "F.Fab")
		)
		(fp_line
			(start 0.67945 -0.3048)
			(end 0.67945 0.3048)
			(stroke
				(width 0.1)
				(type default)
			)
			(layer "F.Fab")
		)
		(fp_line
			(start 0.67945 0.3048)
			(end 0.120396 0.3048)
			(stroke
				(width 0.1)
				(type default)
			)
			(layer "F.Fab")
		)
		(pad "1" smd circle
			(at -0.40005 0)
			(size 0 0)
			(layers "F.Cu" "F.Mask" "F.Paste")
			(net "P3V3_AUX")
		)
		(pad "2" smd circle
			(at 0.40005 0)
			(size 0 0)
			(layers "F.Cu" "F.Mask" "F.Paste")
			(net "GND")
		)
	)
	(footprint ""
		(layer "F.Cu")
		(at 187.316618 -427.255178 -90)
		(property "Reference" "R3499"
			(at 0 0 270)
			(layer "F.SilkS")
			(hide yes)
			(effects
				(font
					(size 1.27 1.27)
				)
			)
		)
		(property "Value" ""
			(at 0 0 270)
			(layer "F.Fab")
			(effects
				(font
					(size 1.27 1.27)
				)
			)
		)
		(duplicate_pad_numbers_are_jumpers no)
		(fp_line
			(start -0.7874 0.4064)
			(end -0.7874 -0.4064)
			(stroke
				(width 0.1524)
				(type default)
			)
			(layer "F.SilkS")
		)
		(fp_line
			(start 0.7874 0.4064)
			(end -0.7874 0.4064)
			(stroke
				(width 0.1524)
				(type default)
			)
			(layer "F.SilkS")
		)
		(fp_line
			(start -0.7874 -0.4064)
			(end 0.7874 -0.4064)
			(stroke
				(width 0.1524)
				(type default)
			)
			(layer "F.SilkS")
		)
		(fp_line
			(start 0.7874 -0.4064)
			(end 0.7874 0.4064)
			(stroke
				(width 0.1524)
				(type default)
			)
			(layer "F.SilkS")
		)
		(fp_line
			(start -0.67945 0.3048)
			(end -0.67945 -0.305054)
			(stroke
				(width 0.1)
				(type default)
			)
			(layer "F.Fab")
		)
		(fp_line
			(start -0.12065 0.3048)
			(end -0.67945 0.3048)
			(stroke
				(width 0.1)
				(type default)
			)
			(layer "F.Fab")
		)
		(fp_line
			(start 0.120396 0.3048)
			(end 0.120396 0.2794)
			(stroke
				(width 0.1)
				(type default)
			)
			(layer "F.Fab")
		)
		(fp_line
			(start 0.67945 0.3048)
			(end 0.120396 0.3048)
			(stroke
				(width 0.1)
				(type default)
			)
			(layer "F.Fab")
		)
		(fp_line
			(start -0.12065 0.2794)
			(end -0.12065 0.3048)
			(stroke
				(width 0.1)
				(type default)
			)
			(layer "F.Fab")
		)
		(fp_line
			(start 0.120396 0.2794)
			(end -0.12065 0.2794)
			(stroke
				(width 0.1)
				(type default)
			)
			(layer "F.Fab")
		)
		(fp_line
			(start -0.12065 -0.2794)
			(end 0.12065 -0.2794)
			(stroke
				(width 0.1)
				(type default)
			)
			(layer "F.Fab")
		)
		(fp_line
			(start 0.12065 -0.2794)
			(end 0.12065 -0.3048)
			(stroke
				(width 0.1)
				(type default)
			)
			(layer "F.Fab")
		)
		(fp_line
			(start 0.12065 -0.3048)
			(end 0.67945 -0.3048)
			(stroke
				(width 0.1)
				(type default)
			)
			(layer "F.Fab")
		)
		(fp_line
			(start 0.67945 -0.3048)
			(end 0.67945 0.3048)
			(stroke
				(width 0.1)
				(type default)
			)
			(layer "F.Fab")
		)
		(fp_line
			(start -0.67945 -0.305054)
			(end -0.12065 -0.305054)
			(stroke
				(width 0.1)
				(type default)
			)
			(layer "F.Fab")
		)
		(fp_line
			(start -0.12065 -0.305054)
			(end -0.12065 -0.2794)
			(stroke
				(width 0.1)
				(type default)
			)
			(layer "F.Fab")
		)
		(pad "1" smd circle
			(at -0.40005 0 270)
			(size 0 0)
			(layers "F.Cu" "F.Mask" "F.Paste")
			(net "GPU_BASE_ID1")
		)
		(pad "2" smd circle
			(at 0.40005 0 270)
			(size 0 0)
			(layers "F.Cu" "F.Mask" "F.Paste")
			(net "GPU_BASE_ID1_R")
		)
	)
	(footprint ""
		(layer "F.Cu")
		(at 322.565268 -339.372448)
		(property "Reference" "PC86_2"
			(at 0 0 0)
			(layer "F.SilkS")
			(hide yes)
			(effects
				(font
					(size 1.27 1.27)
				)
			)
		)
		(property "Value" ""
			(at 0 0 0)
			(layer "F.Fab")
			(effects
				(font
					(size 1.27 1.27)
				)
			)
		)
		(duplicate_pad_numbers_are_jumpers no)
		(fp_line
			(start -0.7874 -0.4064)
			(end 0.7874 -0.4064)
			(stroke
				(width 0.1524)
				(type default)
			)
			(layer "F.SilkS")
		)
		(fp_line
			(start -0.7874 0.4064)
			(end -0.7874 -0.4064)
			(stroke
				(width 0.1524)
				(type default)
			)
			(layer "F.SilkS")
		)
		(fp_line
			(start 0.7874 -0.4064)
			(end 0.7874 0.4064)
			(stroke
				(width 0.1524)
				(type default)
			)
			(layer "F.SilkS")
		)
		(fp_line
			(start 0.7874 0.4064)
			(end -0.7874 0.4064)
			(stroke
				(width 0.1524)
				(type default)
			)
			(layer "F.SilkS")
		)
		(fp_line
			(start -0.67945 -0.305054)
			(end -0.12065 -0.305054)
			(stroke
				(width 0.1)
				(type default)
			)
			(layer "F.Fab")
		)
		(fp_line
			(start -0.67945 0.3048)
			(end -0.67945 -0.305054)
			(stroke
				(width 0.1)
				(type default)
			)
			(layer "F.Fab")
		)
		(fp_line
			(start -0.12065 -0.305054)
			(end -0.12065 -0.2794)
			(stroke
				(width 0.1)
				(type default)
			)
			(layer "F.Fab")
		)
		(fp_line
			(start -0.12065 -0.2794)
			(end 0.12065 -0.2794)
			(stroke
				(width 0.1)
				(type default)
			)
			(layer "F.Fab")
		)
		(fp_line
			(start -0.12065 0.2794)
			(end -0.12065 0.3048)
			(stroke
				(width 0.1)
				(type default)
			)
			(layer "F.Fab")
		)
		(fp_line
			(start -0.12065 0.3048)
			(end -0.67945 0.3048)
			(stroke
				(width 0.1)
				(type default)
			)
			(layer "F.Fab")
		)
		(fp_line
			(start 0.120396 0.2794)
			(end -0.12065 0.2794)
			(stroke
				(width 0.1)
				(type default)
			)
			(layer "F.Fab")
		)
		(fp_line
			(start 0.120396 0.3048)
			(end 0.120396 0.2794)
			(stroke
				(width 0.1)
				(type default)
			)
			(layer "F.Fab")
		)
		(fp_line
			(start 0.12065 -0.3048)
			(end 0.67945 -0.3048)
			(stroke
				(width 0.1)
				(type default)
			)
			(layer "F.Fab")
		)
		(fp_line
			(start 0.12065 -0.2794)
			(end 0.12065 -0.3048)
			(stroke
				(width 0.1)
				(type default)
			)
			(layer "F.Fab")
		)
		(fp_line
			(start 0.67945 -0.3048)
			(end 0.67945 0.3048)
			(stroke
				(width 0.1)
				(type default)
			)
			(layer "F.Fab")
		)
		(fp_line
			(start 0.67945 0.3048)
			(end 0.120396 0.3048)
			(stroke
				(width 0.1)
				(type default)
			)
			(layer "F.Fab")
		)
		(pad "1" smd circle
			(at -0.40005 0)
			(size 0 0)
			(layers "F.Cu" "F.Mask" "F.Paste")
			(net "SW_P12V_AUX_PVDDCR_CPU1_P0_FLT")
		)
		(pad "2" smd circle
			(at 0.40005 0)
			(size 0 0)
			(layers "F.Cu" "F.Mask" "F.Paste")
			(net "GND")
		)
	)
	(footprint ""
		(layer "F.Cu")
		(at 342.442546 -23.897336 -90)
		(property "Reference" "R946"
			(at 0 0 270)
			(layer "F.SilkS")
			(hide yes)
			(effects
				(font
					(size 1.27 1.27)
				)
			)
		)
		(property "Value" ""
			(at 0 0 270)
			(layer "F.Fab")
			(effects
				(font
					(size 1.27 1.27)
				)
			)
		)
		(duplicate_pad_numbers_are_jumpers no)
		(fp_line
			(start -0.7874 0.4064)
			(end -0.7874 -0.4064)
			(stroke
				(width 0.1524)
				(type default)
			)
			(layer "F.SilkS")
		)
		(fp_line
			(start 0.7874 0.4064)
			(end -0.7874 0.4064)
			(stroke
				(width 0.1524)
				(type default)
			)
			(layer "F.SilkS")
		)
		(fp_line
			(start -0.7874 -0.4064)
			(end 0.7874 -0.4064)
			(stroke
				(width 0.1524)
				(type default)
			)
			(layer "F.SilkS")
		)
		(fp_line
			(start 0.7874 -0.4064)
			(end 0.7874 0.4064)
			(stroke
				(width 0.1524)
				(type default)
			)
			(layer "F.SilkS")
		)
		(fp_line
			(start -0.67945 0.3048)
			(end -0.67945 -0.305054)
			(stroke
				(width 0.1)
				(type default)
			)
			(layer "F.Fab")
		)
		(fp_line
			(start -0.12065 0.3048)
			(end -0.67945 0.3048)
			(stroke
				(width 0.1)
				(type default)
			)
			(layer "F.Fab")
		)
		(fp_line
			(start 0.120396 0.3048)
			(end 0.120396 0.2794)
			(stroke
				(width 0.1)
				(type default)
			)
			(layer "F.Fab")
		)
		(fp_line
			(start 0.67945 0.3048)
			(end 0.120396 0.3048)
			(stroke
				(width 0.1)
				(type default)
			)
			(layer "F.Fab")
		)
		(fp_line
			(start -0.12065 0.2794)
			(end -0.12065 0.3048)
			(stroke
				(width 0.1)
				(type default)
			)
			(layer "F.Fab")
		)
		(fp_line
			(start 0.120396 0.2794)
			(end -0.12065 0.2794)
			(stroke
				(width 0.1)
				(type default)
			)
			(layer "F.Fab")
		)
		(fp_line
			(start -0.12065 -0.2794)
			(end 0.12065 -0.2794)
			(stroke
				(width 0.1)
				(type default)
			)
			(layer "F.Fab")
		)
		(fp_line
			(start 0.12065 -0.2794)
			(end 0.12065 -0.3048)
			(stroke
				(width 0.1)
				(type default)
			)
			(layer "F.Fab")
		)
		(fp_line
			(start 0.12065 -0.3048)
			(end 0.67945 -0.3048)
			(stroke
				(width 0.1)
				(type default)
			)
			(layer "F.Fab")
		)
		(fp_line
			(start 0.67945 -0.3048)
			(end 0.67945 0.3048)
			(stroke
				(width 0.1)
				(type default)
			)
			(layer "F.Fab")
		)
		(fp_line
			(start -0.67945 -0.305054)
			(end -0.12065 -0.305054)
			(stroke
				(width 0.1)
				(type default)
			)
			(layer "F.Fab")
		)
		(fp_line
			(start -0.12065 -0.305054)
			(end -0.12065 -0.2794)
			(stroke
				(width 0.1)
				(type default)
			)
			(layer "F.Fab")
		)
		(pad "1" smd circle
			(at -0.40005 0 270)
			(size 0 0)
			(layers "F.Cu" "F.Mask" "F.Paste")
			(net "P3V3_AUX")
		)
		(pad "2" smd circle
			(at 0.40005 0 270)
			(size 0 0)
			(layers "F.Cu" "F.Mask" "F.Paste")
			(net "BOOT_RDY_LED")
		)
	)
	(footprint ""
		(layer "F.Cu")
		(at 166.8272 -429.9712 90)
		(property "Reference" "R2667"
			(at 0 0 90)
			(layer "F.SilkS")
			(hide yes)
			(effects
				(font
					(size 1.27 1.27)
				)
			)
		)
		(property "Value" ""
			(at 0 0 90)
			(layer "F.Fab")
			(effects
				(font
					(size 1.27 1.27)
				)
			)
		)
		(duplicate_pad_numbers_are_jumpers no)
		(fp_line
			(start 0.7874 -0.4064)
			(end 0.7874 0.4064)
			(stroke
				(width 0.1524)
				(type default)
			)
			(layer "F.SilkS")
		)
		(fp_line
			(start -0.7874 -0.4064)
			(end 0.7874 -0.4064)
			(stroke
				(width 0.1524)
				(type default)
			)
			(layer "F.SilkS")
		)
		(fp_line
			(start 0.7874 0.4064)
			(end -0.7874 0.4064)
			(stroke
				(width 0.1524)
				(type default)
			)
			(layer "F.SilkS")
		)
		(fp_line
			(start -0.7874 0.4064)
			(end -0.7874 -0.4064)
			(stroke
				(width 0.1524)
				(type default)
			)
			(layer "F.SilkS")
		)
		(fp_line
			(start -0.12065 -0.305054)
			(end -0.12065 -0.2794)
			(stroke
				(width 0.1)
				(type default)
			)
			(layer "F.Fab")
		)
		(fp_line
			(start -0.67945 -0.305054)
			(end -0.12065 -0.305054)
			(stroke
				(width 0.1)
				(type default)
			)
			(layer "F.Fab")
		)
		(fp_line
			(start 0.67945 -0.3048)
			(end 0.67945 0.3048)
			(stroke
				(width 0.1)
				(type default)
			)
			(layer "F.Fab")
		)
		(fp_line
			(start 0.12065 -0.3048)
			(end 0.67945 -0.3048)
			(stroke
				(width 0.1)
				(type default)
			)
			(layer "F.Fab")
		)
		(fp_line
			(start 0.12065 -0.2794)
			(end 0.12065 -0.3048)
			(stroke
				(width 0.1)
				(type default)
			)
			(layer "F.Fab")
		)
		(fp_line
			(start -0.12065 -0.2794)
			(end 0.12065 -0.2794)
			(stroke
				(width 0.1)
				(type default)
			)
			(layer "F.Fab")
		)
		(fp_line
			(start 0.120396 0.2794)
			(end -0.12065 0.2794)
			(stroke
				(width 0.1)
				(type default)
			)
			(layer "F.Fab")
		)
		(fp_line
			(start -0.12065 0.2794)
			(end -0.12065 0.3048)
			(stroke
				(width 0.1)
				(type default)
			)
			(layer "F.Fab")
		)
		(fp_line
			(start 0.67945 0.3048)
			(end 0.120396 0.3048)
			(stroke
				(width 0.1)
				(type default)
			)
			(layer "F.Fab")
		)
		(fp_line
			(start 0.120396 0.3048)
			(end 0.120396 0.2794)
			(stroke
				(width 0.1)
				(type default)
			)
			(layer "F.Fab")
		)
		(fp_line
			(start -0.12065 0.3048)
			(end -0.67945 0.3048)
			(stroke
				(width 0.1)
				(type default)
			)
			(layer "F.Fab")
		)
		(fp_line
			(start -0.67945 0.3048)
			(end -0.67945 -0.305054)
			(stroke
				(width 0.1)
				(type default)
			)
			(layer "F.Fab")
		)
		(pad "1" smd circle
			(at -0.40005 0 90)
			(size 0 0)
			(layers "F.Cu" "F.Mask" "F.Paste")
			(net "P3V3_AUX")
		)
		(pad "2" smd circle
			(at 0.40005 0 90)
			(size 0 0)
			(layers "F.Cu" "F.Mask" "F.Paste")
			(net "SMB_BMC_SWB_BUF_R_SCL")
		)
	)
	(footprint ""
		(layer "F.Cu")
		(at 169.1894 -332.244192 180)
		(property "Reference" "TP13"
			(at 2.356612 5.244846 0)
			(unlocked yes)
			(layer "F.SilkS")
			(effects
				(font
					(size 0.7874 0.5842)
					(thickness 0.1524)
				)
				(justify left)
			)
		)
		(property "Value" ""
			(at 0 0 180)
			(layer "F.Fab")
			(effects
				(font
					(size 1.27 1.27)
				)
			)
		)
		(duplicate_pad_numbers_are_jumpers no)
		(pad "1" smd circle
			(at 0 0 180)
			(size 0.762 0.762)
			(layers "F.Cu" "F.Mask" "F.Paste")
			(net "VSENSE_VSS_SENSE_C_P1")
		)
	)
	(footprint ""
		(layer "F.Cu")
		(at 444.733172 -32.173418 -90)
		(property "Reference" "R3834"
			(at 0 0 270)
			(layer "F.SilkS")
			(hide yes)
			(effects
				(font
					(size 1.27 1.27)
				)
			)
		)
		(property "Value" ""
			(at 0 0 270)
			(layer "F.Fab")
			(effects
				(font
					(size 1.27 1.27)
				)
			)
		)
		(duplicate_pad_numbers_are_jumpers no)
		(fp_line
			(start -0.7874 0.4064)
			(end -0.7874 -0.4064)
			(stroke
				(width 0.1524)
				(type default)
			)
			(layer "F.SilkS")
		)
		(fp_line
			(start 0.7874 0.4064)
			(end -0.7874 0.4064)
			(stroke
				(width 0.1524)
				(type default)
			)
			(layer "F.SilkS")
		)
		(fp_line
			(start -0.7874 -0.4064)
			(end 0.7874 -0.4064)
			(stroke
				(width 0.1524)
				(type default)
			)
			(layer "F.SilkS")
		)
		(fp_line
			(start 0.7874 -0.4064)
			(end 0.7874 0.4064)
			(stroke
				(width 0.1524)
				(type default)
			)
			(layer "F.SilkS")
		)
		(fp_line
			(start -0.67945 0.3048)
			(end -0.67945 -0.305054)
			(stroke
				(width 0.1)
				(type default)
			)
			(layer "F.Fab")
		)
		(fp_line
			(start -0.12065 0.3048)
			(end -0.67945 0.3048)
			(stroke
				(width 0.1)
				(type default)
			)
			(layer "F.Fab")
		)
		(fp_line
			(start 0.120396 0.3048)
			(end 0.120396 0.2794)
			(stroke
				(width 0.1)
				(type default)
			)
			(layer "F.Fab")
		)
		(fp_line
			(start 0.67945 0.3048)
			(end 0.120396 0.3048)
			(stroke
				(width 0.1)
				(type default)
			)
			(layer "F.Fab")
		)
		(fp_line
			(start -0.12065 0.2794)
			(end -0.12065 0.3048)
			(stroke
				(width 0.1)
				(type default)
			)
			(layer "F.Fab")
		)
		(fp_line
			(start 0.120396 0.2794)
			(end -0.12065 0.2794)
			(stroke
				(width 0.1)
				(type default)
			)
			(layer "F.Fab")
		)
		(fp_line
			(start -0.12065 -0.2794)
			(end 0.12065 -0.2794)
			(stroke
				(width 0.1)
				(type default)
			)
			(layer "F.Fab")
		)
		(fp_line
			(start 0.12065 -0.2794)
			(end 0.12065 -0.3048)
			(stroke
				(width 0.1)
				(type default)
			)
			(layer "F.Fab")
		)
		(fp_line
			(start 0.12065 -0.3048)
			(end 0.67945 -0.3048)
			(stroke
				(width 0.1)
				(type default)
			)
			(layer "F.Fab")
		)
		(fp_line
			(start 0.67945 -0.3048)
			(end 0.67945 0.3048)
			(stroke
				(width 0.1)
				(type default)
			)
			(layer "F.Fab")
		)
		(fp_line
			(start -0.67945 -0.305054)
			(end -0.12065 -0.305054)
			(stroke
				(width 0.1)
				(type default)
			)
			(layer "F.Fab")
		)
		(fp_line
			(start -0.12065 -0.305054)
			(end -0.12065 -0.2794)
			(stroke
				(width 0.1)
				(type default)
			)
			(layer "F.Fab")
		)
		(pad "1" smd circle
			(at -0.40005 0 270)
			(size 0 0)
			(layers "F.Cu" "F.Mask" "F.Paste")
			(net "P12V_OCP_SFF_EN_R")
		)
		(pad "2" smd circle
			(at 0.40005 0 270)
			(size 0 0)
			(layers "F.Cu" "F.Mask" "F.Paste")
			(net "P12V_OCP_EN_1_R2")
		)
	)
	(footprint ""
		(layer "F.Cu")
		(at 119.362728 -173.657768 -90)
		(property "Reference" "PR525"
			(at 0 0 270)
			(layer "F.SilkS")
			(hide yes)
			(effects
				(font
					(size 1.27 1.27)
				)
			)
		)
		(property "Value" ""
			(at 0 0 270)
			(layer "F.Fab")
			(effects
				(font
					(size 1.27 1.27)
				)
			)
		)
		(duplicate_pad_numbers_are_jumpers no)
		(fp_line
			(start -0.7874 0.4064)
			(end -0.7874 -0.4064)
			(stroke
				(width 0.1524)
				(type default)
			)
			(layer "F.SilkS")
		)
		(fp_line
			(start 0.7874 0.4064)
			(end -0.7874 0.4064)
			(stroke
				(width 0.1524)
				(type default)
			)
			(layer "F.SilkS")
		)
		(fp_line
			(start -0.7874 -0.4064)
			(end 0.7874 -0.4064)
			(stroke
				(width 0.1524)
				(type default)
			)
			(layer "F.SilkS")
		)
		(fp_line
			(start 0.7874 -0.4064)
			(end 0.7874 0.4064)
			(stroke
				(width 0.1524)
				(type default)
			)
			(layer "F.SilkS")
		)
		(fp_line
			(start -0.67945 0.3048)
			(end -0.67945 -0.305054)
			(stroke
				(width 0.1)
				(type default)
			)
			(layer "F.Fab")
		)
		(fp_line
			(start -0.12065 0.3048)
			(end -0.67945 0.3048)
			(stroke
				(width 0.1)
				(type default)
			)
			(layer "F.Fab")
		)
		(fp_line
			(start 0.120396 0.3048)
			(end 0.120396 0.2794)
			(stroke
				(width 0.1)
				(type default)
			)
			(layer "F.Fab")
		)
		(fp_line
			(start 0.67945 0.3048)
			(end 0.120396 0.3048)
			(stroke
				(width 0.1)
				(type default)
			)
			(layer "F.Fab")
		)
		(fp_line
			(start -0.12065 0.2794)
			(end -0.12065 0.3048)
			(stroke
				(width 0.1)
				(type default)
			)
			(layer "F.Fab")
		)
		(fp_line
			(start 0.120396 0.2794)
			(end -0.12065 0.2794)
			(stroke
				(width 0.1)
				(type default)
			)
			(layer "F.Fab")
		)
		(fp_line
			(start -0.12065 -0.2794)
			(end 0.12065 -0.2794)
			(stroke
				(width 0.1)
				(type default)
			)
			(layer "F.Fab")
		)
		(fp_line
			(start 0.12065 -0.2794)
			(end 0.12065 -0.3048)
			(stroke
				(width 0.1)
				(type default)
			)
			(layer "F.Fab")
		)
		(fp_line
			(start 0.12065 -0.3048)
			(end 0.67945 -0.3048)
			(stroke
				(width 0.1)
				(type default)
			)
			(layer "F.Fab")
		)
		(fp_line
			(start 0.67945 -0.3048)
			(end 0.67945 0.3048)
			(stroke
				(width 0.1)
				(type default)
			)
			(layer "F.Fab")
		)
		(fp_line
			(start -0.67945 -0.305054)
			(end -0.12065 -0.305054)
			(stroke
				(width 0.1)
				(type default)
			)
			(layer "F.Fab")
		)
		(fp_line
			(start -0.12065 -0.305054)
			(end -0.12065 -0.2794)
			(stroke
				(width 0.1)
				(type default)
			)
			(layer "F.Fab")
		)
		(pad "1" smd circle
			(at -0.40005 0 270)
			(size 0 0)
			(layers "F.Cu" "F.Mask" "F.Paste")
			(net "SW_PVDDCR_SOC_P1_SW1_RC")
		)
		(pad "2" smd circle
			(at 0.40005 0 270)
			(size 0 0)
			(layers "F.Cu" "F.Mask" "F.Paste")
			(net "GND")
		)
	)
	(footprint ""
		(layer "F.Cu")
		(at 173.899322 -28.03779 -90)
		(property "Reference" "PR4011"
			(at 0 0 270)
			(layer "F.SilkS")
			(hide yes)
			(effects
				(font
					(size 1.27 1.27)
				)
			)
		)
		(property "Value" ""
			(at 0 0 270)
			(layer "F.Fab")
			(effects
				(font
					(size 1.27 1.27)
				)
			)
		)
		(duplicate_pad_numbers_are_jumpers no)
		(fp_line
			(start -0.7874 0.4064)
			(end -0.7874 -0.4064)
			(stroke
				(width 0.1524)
				(type default)
			)
			(layer "F.SilkS")
		)
		(fp_line
			(start 0.7874 0.4064)
			(end -0.7874 0.4064)
			(stroke
				(width 0.1524)
				(type default)
			)
			(layer "F.SilkS")
		)
		(fp_line
			(start -0.7874 -0.4064)
			(end 0.7874 -0.4064)
			(stroke
				(width 0.1524)
				(type default)
			)
			(layer "F.SilkS")
		)
		(fp_line
			(start 0.7874 -0.4064)
			(end 0.7874 0.4064)
			(stroke
				(width 0.1524)
				(type default)
			)
			(layer "F.SilkS")
		)
		(fp_line
			(start -0.67945 0.3048)
			(end -0.67945 -0.305054)
			(stroke
				(width 0.1)
				(type default)
			)
			(layer "F.Fab")
		)
		(fp_line
			(start -0.12065 0.3048)
			(end -0.67945 0.3048)
			(stroke
				(width 0.1)
				(type default)
			)
			(layer "F.Fab")
		)
		(fp_line
			(start 0.120396 0.3048)
			(end 0.120396 0.2794)
			(stroke
				(width 0.1)
				(type default)
			)
			(layer "F.Fab")
		)
		(fp_line
			(start 0.67945 0.3048)
			(end 0.120396 0.3048)
			(stroke
				(width 0.1)
				(type default)
			)
			(layer "F.Fab")
		)
		(fp_line
			(start -0.12065 0.2794)
			(end -0.12065 0.3048)
			(stroke
				(width 0.1)
				(type default)
			)
			(layer "F.Fab")
		)
		(fp_line
			(start 0.120396 0.2794)
			(end -0.12065 0.2794)
			(stroke
				(width 0.1)
				(type default)
			)
			(layer "F.Fab")
		)
		(fp_line
			(start -0.12065 -0.2794)
			(end 0.12065 -0.2794)
			(stroke
				(width 0.1)
				(type default)
			)
			(layer "F.Fab")
		)
		(fp_line
			(start 0.12065 -0.2794)
			(end 0.12065 -0.3048)
			(stroke
				(width 0.1)
				(type default)
			)
			(layer "F.Fab")
		)
		(fp_line
			(start 0.12065 -0.3048)
			(end 0.67945 -0.3048)
			(stroke
				(width 0.1)
				(type default)
			)
			(layer "F.Fab")
		)
		(fp_line
			(start 0.67945 -0.3048)
			(end 0.67945 0.3048)
			(stroke
				(width 0.1)
				(type default)
			)
			(layer "F.Fab")
		)
		(fp_line
			(start -0.67945 -0.305054)
			(end -0.12065 -0.305054)
			(stroke
				(width 0.1)
				(type default)
			)
			(layer "F.Fab")
		)
		(fp_line
			(start -0.12065 -0.305054)
			(end -0.12065 -0.2794)
			(stroke
				(width 0.1)
				(type default)
			)
			(layer "F.Fab")
		)
		(pad "1" smd circle
			(at -0.40005 0 270)
			(size 0 0)
			(layers "F.Cu" "F.Mask" "F.Paste")
			(net "P12V_SCM_OV_FB")
		)
		(pad "2" smd circle
			(at 0.40005 0 270)
			(size 0 0)
			(layers "F.Cu" "F.Mask" "F.Paste")
			(net "GND")
		)
	)
	(footprint ""
		(layer "F.Cu")
		(at 267.598144 -255.560068 180)
		(property "Reference" "J23"
			(at -2.2098 -81.984088 0)
			(unlocked yes)
			(layer "F.SilkS")
			(effects
				(font
					(size 0.7874 0.5842)
					(thickness 0.1524)
				)
			)
		)
		(property "Value" ""
			(at 0 0 180)
			(layer "F.Fab")
			(effects
				(font
					(size 1.27 1.27)
				)
			)
		)
		(duplicate_pad_numbers_are_jumpers no)
		(fp_line
			(start 3.24993 -81.000092)
			(end 3.24993 81.000092)
			(stroke
				(width 0.1524)
				(type default)
			)
			(layer "F.SilkS")
		)
		(fp_line
			(start -3.24993 79.979012)
			(end -3.24993 78.175612)
			(stroke
				(width 0.1524)
				(type default)
			)
			(layer "F.SilkS")
		)
		(fp_line
			(start -3.24993 75.841352)
			(end -3.24993 -81.000092)
			(stroke
				(width 0.1524)
				(type default)
			)
			(layer "F.SilkS")
		)
		(fp_line
			(start -3.24993 72.499982)
			(end 3.24993 72.499982)
			(stroke
				(width 0.1524)
				(type default)
			)
			(layer "F.SilkS")
		)
		(fp_line
			(start -3.24993 -72.499982)
			(end 3.24993 -72.499982)
			(stroke
				(width 0.1524)
				(type default)
			)
			(layer "F.SilkS")
		)
		(fp_line
			(start -3.24993 -81.000092)
			(end 3.24993 -81.000092)
			(stroke
				(width 0.1524)
				(type default)
			)
			(layer "F.SilkS")
		)
		(fp_poly
			(pts
				(xy -3.80365 -64.173354) (xy -3.349244 -63.628016) (xy -4.058158 -63.591694)
			)
			(stroke
				(width 0)
				(type default)
			)
			(fill yes)
			(layer "F.SilkS")
		)
		(fp_line
			(start 3.24993 81.000092)
			(end -3.24993 81.000092)
			(stroke
				(width 0.1)
				(type default)
			)
			(layer "F.Fab")
		)
		(fp_line
			(start 3.24993 -81.000092)
			(end 3.24993 81.000092)
			(stroke
				(width 0.1)
				(type default)
			)
			(layer "F.Fab")
		)
		(fp_line
			(start -3.24993 81.000092)
			(end -3.24993 -81.000092)
			(stroke
				(width 0.1)
				(type default)
			)
			(layer "F.Fab")
		)
		(fp_line
			(start -3.24993 72.499982)
			(end 3.24993 72.499982)
			(stroke
				(width 0.1)
				(type default)
			)
			(layer "F.Fab")
		)
		(fp_line
			(start -3.24993 71.000112)
			(end 3.24993 71.000112)
			(stroke
				(width 0.1)
				(type default)
			)
			(layer "F.Fab")
		)
		(fp_line
			(start -3.24993 -71.000112)
			(end 3.24993 -71.000112)
			(stroke
				(width 0.1)
				(type default)
			)
			(layer "F.Fab")
		)
		(fp_line
			(start -3.24993 -72.499982)
			(end 3.24993 -72.499982)
			(stroke
				(width 0.1)
				(type default)
			)
			(layer "F.Fab")
		)
		(fp_line
			(start -3.24993 -81.000092)
			(end 3.24993 -81.000092)
			(stroke
				(width 0.1)
				(type default)
			)
			(layer "F.Fab")
		)
		(fp_poly
			(pts
				(xy -3.41503 -63.324994) (xy -4.43103 -62.816994) (xy -4.43103 -63.832994)
			)
			(stroke
				(width 0)
				(type default)
			)
			(fill yes)
			(layer "F.Fab")
		)
		(pad "1" smd rect
			(at -2.050034 -63.324994 90)
			(size 0.519938 1.4986)
			(layers "F.Cu" "F.Mask" "F.Paste")
			(net "P12V_MEM_CPU0")
		)
		(pad "2" smd rect
			(at -2.050034 -62.47511 90)
			(size 0.519938 1.4986)
			(layers "F.Cu" "F.Mask" "F.Paste")
			(net "Net_2319")
		)
		(pad "3" smd rect
			(at -2.050034 -61.624972 90)
			(size 0.519938 1.4986)
			(layers "F.Cu" "F.Mask" "F.Paste")
			(net "P3V3_AUX")
		)
		(pad "4" smd rect
			(at -2.050034 -60.775088 90)
			(size 0.519938 1.4986)
			(layers "F.Cu" "F.Mask" "F.Paste")
			(net "I3C_SPD_DDRF_CPU0_SCL")
		)
		(pad "5" smd rect
			(at -2.050034 -59.92495 90)
			(size 0.519938 1.4986)
			(layers "F.Cu" "F.Mask" "F.Paste")
			(net "I3C_SPD_DDRF_CPU0_SDA")
		)
		(pad "6" smd rect
			(at -2.050034 -59.075066 90)
			(size 0.519938 1.4986)
			(layers "F.Cu" "F.Mask" "F.Paste")
			(net "GND")
		)
		(pad "7" smd rect
			(at -2.050034 -58.224928 90)
			(size 0.519938 1.4986)
			(layers "F.Cu" "F.Mask" "F.Paste")
			(net "M_F_CPU0_SA_DQ<0>")
		)
		(pad "8" smd rect
			(at -2.050034 -57.375044 90)
			(size 0.519938 1.4986)
			(layers "F.Cu" "F.Mask" "F.Paste")
			(net "GND")
		)
		(pad "9" smd rect
			(at -2.050034 -56.524906 90)
			(size 0.519938 1.4986)
			(layers "F.Cu" "F.Mask" "F.Paste")
			(net "M_F_CPU0_SA_DQ<1>")
		)
		(pad "10" smd rect
			(at -2.050034 -55.675022 90)
			(size 0.519938 1.4986)
			(layers "F.Cu" "F.Mask" "F.Paste")
			(net "GND")
		)
		(pad "11" smd rect
			(at -2.050034 -54.824884 90)
			(size 0.519938 1.4986)
			(layers "F.Cu" "F.Mask" "F.Paste")
			(net "M_F_CPU0_SA_DQS_DP<0>")
		)
		(pad "12" smd rect
			(at -2.050034 -53.975 90)
			(size 0.519938 1.4986)
			(layers "F.Cu" "F.Mask" "F.Paste")
			(net "M_F_CPU0_SA_DQS_DN<0>")
		)
		(pad "13" smd rect
			(at -2.050034 -53.125116 90)
			(size 0.519938 1.4986)
			(layers "F.Cu" "F.Mask" "F.Paste")
			(net "GND")
		)
		(pad "14" smd rect
			(at -2.050034 -52.274978 90)
			(size 0.519938 1.4986)
			(layers "F.Cu" "F.Mask" "F.Paste")
			(net "M_F_CPU0_SA_DQ<4>")
		)
		(pad "15" smd rect
			(at -2.050034 -51.425094 90)
			(size 0.519938 1.4986)
			(layers "F.Cu" "F.Mask" "F.Paste")
			(net "GND")
		)
		(pad "16" smd rect
			(at -2.050034 -50.574956 90)
			(size 0.519938 1.4986)
			(layers "F.Cu" "F.Mask" "F.Paste")
			(net "M_F_CPU0_SA_DQ<5>")
		)
		(pad "17" smd rect
			(at -2.050034 -49.725072 90)
			(size 0.519938 1.4986)
			(layers "F.Cu" "F.Mask" "F.Paste")
			(net "GND")
		)
		(pad "18" smd rect
			(at -2.050034 -48.874934 90)
			(size 0.519938 1.4986)
			(layers "F.Cu" "F.Mask" "F.Paste")
			(net "M_F_CPU0_SA_DQ<8>")
		)
		(pad "19" smd rect
			(at -2.050034 -48.02505 90)
			(size 0.519938 1.4986)
			(layers "F.Cu" "F.Mask" "F.Paste")
			(net "GND")
		)
		(pad "20" smd rect
			(at -2.050034 -47.174912 90)
			(size 0.519938 1.4986)
			(layers "F.Cu" "F.Mask" "F.Paste")
			(net "M_F_CPU0_SA_DQ<9>")
		)
		(pad "21" smd rect
			(at -2.050034 -46.325028 90)
			(size 0.519938 1.4986)
			(layers "F.Cu" "F.Mask" "F.Paste")
			(net "GND")
		)
		(pad "22" smd rect
			(at -2.050034 -45.47489 90)
			(size 0.519938 1.4986)
			(layers "F.Cu" "F.Mask" "F.Paste")
			(net "M_F_CPU0_SA_DQS_DP<1>")
		)
		(pad "23" smd rect
			(at -2.050034 -44.625006 90)
			(size 0.519938 1.4986)
			(layers "F.Cu" "F.Mask" "F.Paste")
			(net "M_F_CPU0_SA_DQS_DN<1>")
		)
		(pad "24" smd rect
			(at -2.050034 -43.775122 90)
			(size 0.519938 1.4986)
			(layers "F.Cu" "F.Mask" "F.Paste")
			(net "GND")
		)
		(pad "25" smd rect
			(at -2.050034 -42.924984 90)
			(size 0.519938 1.4986)
			(layers "F.Cu" "F.Mask" "F.Paste")
			(net "M_F_CPU0_SA_DQ<12>")
		)
		(pad "26" smd rect
			(at -2.050034 -42.0751 90)
			(size 0.519938 1.4986)
			(layers "F.Cu" "F.Mask" "F.Paste")
			(net "GND")
		)
		(pad "27" smd rect
			(at -2.050034 -41.224962 90)
			(size 0.519938 1.4986)
			(layers "F.Cu" "F.Mask" "F.Paste")
			(net "M_F_CPU0_SA_DQ<13>")
		)
		(pad "28" smd rect
			(at -2.050034 -40.375078 90)
			(size 0.519938 1.4986)
			(layers "F.Cu" "F.Mask" "F.Paste")
			(net "GND")
		)
		(pad "29" smd rect
			(at -2.050034 -39.52494 90)
			(size 0.519938 1.4986)
			(layers "F.Cu" "F.Mask" "F.Paste")
			(net "M_F_CPU0_SA_DQ<16>")
		)
		(pad "30" smd rect
			(at -2.050034 -38.675056 90)
			(size 0.519938 1.4986)
			(layers "F.Cu" "F.Mask" "F.Paste")
			(net "GND")
		)
		(pad "31" smd rect
			(at -2.050034 -37.824918 90)
			(size 0.519938 1.4986)
			(layers "F.Cu" "F.Mask" "F.Paste")
			(net "M_F_CPU0_SA_DQ<17>")
		)
		(pad "32" smd rect
			(at -2.050034 -36.975034 90)
			(size 0.519938 1.4986)
			(layers "F.Cu" "F.Mask" "F.Paste")
			(net "GND")
		)
		(pad "33" smd rect
			(at -2.050034 -36.124896 90)
			(size 0.519938 1.4986)
			(layers "F.Cu" "F.Mask" "F.Paste")
			(net "M_F_CPU0_SA_DQS_DP<2>")
		)
		(pad "34" smd rect
			(at -2.050034 -35.275012 90)
			(size 0.519938 1.4986)
			(layers "F.Cu" "F.Mask" "F.Paste")
			(net "M_F_CPU0_SA_DQS_DN<2>")
		)
		(pad "35" smd rect
			(at -2.050034 -34.425128 90)
			(size 0.519938 1.4986)
			(layers "F.Cu" "F.Mask" "F.Paste")
			(net "GND")
		)
		(pad "36" smd rect
			(at -2.050034 -33.57499 90)
			(size 0.519938 1.4986)
			(layers "F.Cu" "F.Mask" "F.Paste")
			(net "M_F_CPU0_SA_DQ<20>")
		)
		(pad "37" smd rect
			(at -2.050034 -32.725106 90)
			(size 0.519938 1.4986)
			(layers "F.Cu" "F.Mask" "F.Paste")
			(net "GND")
		)
		(pad "38" smd rect
			(at -2.050034 -31.874968 90)
			(size 0.519938 1.4986)
			(layers "F.Cu" "F.Mask" "F.Paste")
			(net "M_F_CPU0_SA_DQ<21>")
		)
		(pad "39" smd rect
			(at -2.050034 -31.025084 90)
			(size 0.519938 1.4986)
			(layers "F.Cu" "F.Mask" "F.Paste")
			(net "GND")
		)
		(pad "40" smd rect
			(at -2.050034 -30.174946 90)
			(size 0.519938 1.4986)
			(layers "F.Cu" "F.Mask" "F.Paste")
			(net "M_F_CPU0_SA_DQ<24>")
		)
		(pad "41" smd rect
			(at -2.050034 -29.325062 90)
			(size 0.519938 1.4986)
			(layers "F.Cu" "F.Mask" "F.Paste")
			(net "GND")
		)
		(pad "42" smd rect
			(at -2.050034 -28.474924 90)
			(size 0.519938 1.4986)
			(layers "F.Cu" "F.Mask" "F.Paste")
			(net "M_F_CPU0_SA_DQ<25>")
		)
		(pad "43" smd rect
			(at -2.050034 -27.62504 90)
			(size 0.519938 1.4986)
			(layers "F.Cu" "F.Mask" "F.Paste")
			(net "GND")
		)
		(pad "44" smd rect
			(at -2.050034 -26.774902 90)
			(size 0.519938 1.4986)
			(layers "F.Cu" "F.Mask" "F.Paste")
			(net "M_F_CPU0_SA_DQS_DP<3>")
		)
		(pad "45" smd rect
			(at -2.050034 -25.925018 90)
			(size 0.519938 1.4986)
			(layers "F.Cu" "F.Mask" "F.Paste")
			(net "M_F_CPU0_SA_DQS_DN<3>")
		)
		(pad "46" smd rect
			(at -2.050034 -25.07488 90)
			(size 0.519938 1.4986)
			(layers "F.Cu" "F.Mask" "F.Paste")
			(net "GND")
		)
		(pad "47" smd rect
			(at -2.050034 -24.224996 90)
			(size 0.519938 1.4986)
			(layers "F.Cu" "F.Mask" "F.Paste")
			(net "M_F_CPU0_SA_DQ<28>")
		)
		(pad "48" smd rect
			(at -2.050034 -23.375112 90)
			(size 0.519938 1.4986)
			(layers "F.Cu" "F.Mask" "F.Paste")
			(net "GND")
		)
		(pad "49" smd rect
			(at -2.050034 -22.524974 90)
			(size 0.519938 1.4986)
			(layers "F.Cu" "F.Mask" "F.Paste")
			(net "M_F_CPU0_SA_DQ<29>")
		)
		(pad "50" smd rect
			(at -2.050034 -21.67509 90)
			(size 0.519938 1.4986)
			(layers "F.Cu" "F.Mask" "F.Paste")
			(net "GND")
		)
		(pad "51" smd rect
			(at -2.050034 -20.824952 90)
			(size 0.519938 1.4986)
			(layers "F.Cu" "F.Mask" "F.Paste")
			(net "M_F_CPU0_SA_CB<0>")
		)
		(pad "52" smd rect
			(at -2.050034 -19.975068 90)
			(size 0.519938 1.4986)
			(layers "F.Cu" "F.Mask" "F.Paste")
			(net "GND")
		)
		(pad "53" smd rect
			(at -2.050034 -19.12493 90)
			(size 0.519938 1.4986)
			(layers "F.Cu" "F.Mask" "F.Paste")
			(net "M_F_CPU0_SA_CB<1>")
		)
		(pad "54" smd rect
			(at -2.050034 -18.275046 90)
			(size 0.519938 1.4986)
			(layers "F.Cu" "F.Mask" "F.Paste")
			(net "GND")
		)
		(pad "55" smd rect
			(at -2.050034 -17.424908 90)
			(size 0.519938 1.4986)
			(layers "F.Cu" "F.Mask" "F.Paste")
			(net "M_F_CPU0_SA_DQS_DP<4>")
		)
		(pad "56" smd rect
			(at -2.050034 -16.575024 90)
			(size 0.519938 1.4986)
			(layers "F.Cu" "F.Mask" "F.Paste")
			(net "M_F_CPU0_SA_DQS_DN<4>")
		)
		(pad "57" smd rect
			(at -2.050034 -15.724886 90)
			(size 0.519938 1.4986)
			(layers "F.Cu" "F.Mask" "F.Paste")
			(net "GND")
		)
		(pad "58" smd rect
			(at -2.050034 -14.875002 90)
			(size 0.519938 1.4986)
			(layers "F.Cu" "F.Mask" "F.Paste")
			(net "M_F_CPU0_SA_CB<4>")
		)
		(pad "59" smd rect
			(at -2.050034 -14.025118 90)
			(size 0.519938 1.4986)
			(layers "F.Cu" "F.Mask" "F.Paste")
			(net "GND")
		)
		(pad "60" smd rect
			(at -2.050034 -13.17498 90)
			(size 0.519938 1.4986)
			(layers "F.Cu" "F.Mask" "F.Paste")
			(net "M_F_CPU0_SA_CB<5>")
		)
		(pad "61" smd rect
			(at -2.050034 -12.325096 90)
			(size 0.519938 1.4986)
			(layers "F.Cu" "F.Mask" "F.Paste")
			(net "GND")
		)
		(pad "62" smd rect
			(at -2.050034 -11.474958 90)
			(size 0.519938 1.4986)
			(layers "F.Cu" "F.Mask" "F.Paste")
			(net "M_F_CPU0_ALERT_N")
		)
		(pad "63" smd rect
			(at -2.050034 -10.625074 90)
			(size 0.519938 1.4986)
			(layers "F.Cu" "F.Mask" "F.Paste")
			(net "GND")
		)
		(pad "64" smd rect
			(at -2.050034 -9.774936 90)
			(size 0.519938 1.4986)
			(layers "F.Cu" "F.Mask" "F.Paste")
			(net "M_F_CPU0_SA_CS_N<0>")
		)
		(pad "65" smd rect
			(at -2.050034 -8.925052 90)
			(size 0.519938 1.4986)
			(layers "F.Cu" "F.Mask" "F.Paste")
			(net "GND")
		)
		(pad "66" smd rect
			(at -2.050034 -8.074914 90)
			(size 0.519938 1.4986)
			(layers "F.Cu" "F.Mask" "F.Paste")
			(net "M_F_CPU0_SA_CA<0>")
		)
		(pad "67" smd rect
			(at -2.050034 -7.22503 90)
			(size 0.519938 1.4986)
			(layers "F.Cu" "F.Mask" "F.Paste")
			(net "GND")
		)
		(pad "68" smd rect
			(at -2.050034 -6.374892 90)
			(size 0.519938 1.4986)
			(layers "F.Cu" "F.Mask" "F.Paste")
			(net "M_F_CPU0_SA_CA<2>")
		)
		(pad "69" smd rect
			(at -2.050034 -5.525008 90)
			(size 0.519938 1.4986)
			(layers "F.Cu" "F.Mask" "F.Paste")
			(net "GND")
		)
		(pad "70" smd rect
			(at -2.050034 -4.675124 90)
			(size 0.519938 1.4986)
			(layers "F.Cu" "F.Mask" "F.Paste")
			(net "M_F_CPU0_SA_CA<4>")
		)
		(pad "71" smd rect
			(at -2.050034 -3.824986 90)
			(size 0.519938 1.4986)
			(layers "F.Cu" "F.Mask" "F.Paste")
			(net "GND")
		)
		(pad "72" smd rect
			(at -2.050034 -2.975102 90)
			(size 0.519938 1.4986)
			(layers "F.Cu" "F.Mask" "F.Paste")
			(net "M_F_CPU0_SA_CA<6>")
		)
		(pad "73" smd rect
			(at -2.050034 -2.124964 90)
			(size 0.519938 1.4986)
			(layers "F.Cu" "F.Mask" "F.Paste")
			(net "GND")
		)
		(pad "74" smd rect
			(at -2.050034 -1.27508 90)
			(size 0.519938 1.4986)
			(layers "F.Cu" "F.Mask" "F.Paste")
			(net "M_F_CPU0_SA_PAR")
		)
		(pad "75" smd rect
			(at -2.050034 -0.424942 90)
			(size 0.519938 1.4986)
			(layers "F.Cu" "F.Mask" "F.Paste")
			(net "GND")
		)
		(pad "76" smd rect
			(at -2.050034 5.525008 90)
			(size 0.519938 1.4986)
			(layers "F.Cu" "F.Mask" "F.Paste")
			(net "M_F_CPU0_SB_CA<0>")
		)
		(pad "77" smd rect
			(at -2.050034 6.374892 90)
			(size 0.519938 1.4986)
			(layers "F.Cu" "F.Mask" "F.Paste")
			(net "GND")
		)
		(pad "78" smd rect
			(at -2.050034 7.22503 90)
			(size 0.519938 1.4986)
			(layers "F.Cu" "F.Mask" "F.Paste")
			(net "M_F_CPU0_SB_CA<2>")
		)
		(pad "79" smd rect
			(at -2.050034 8.074914 90)
			(size 0.519938 1.4986)
			(layers "F.Cu" "F.Mask" "F.Paste")
			(net "GND")
		)
		(pad "80" smd rect
			(at -2.050034 8.925052 90)
			(size 0.519938 1.4986)
			(layers "F.Cu" "F.Mask" "F.Paste")
			(net "M_F_CPU0_SB_CA<4>")
		)
		(pad "81" smd rect
			(at -2.050034 9.774936 90)
			(size 0.519938 1.4986)
			(layers "F.Cu" "F.Mask" "F.Paste")
			(net "GND")
		)
		(pad "82" smd rect
			(at -2.050034 10.625074 90)
			(size 0.519938 1.4986)
			(layers "F.Cu" "F.Mask" "F.Paste")
			(net "M_F_CPU0_SB_CA<6>")
		)
		(pad "83" smd rect
			(at -2.050034 11.474958 90)
			(size 0.519938 1.4986)
			(layers "F.Cu" "F.Mask" "F.Paste")
			(net "GND")
		)
		(pad "84" smd rect
			(at -2.050034 12.325096 90)
			(size 0.519938 1.4986)
			(layers "F.Cu" "F.Mask" "F.Paste")
			(net "M_F_CPU0_SB_CS_N<0>")
		)
		(pad "85" smd rect
			(at -2.050034 13.17498 90)
			(size 0.519938 1.4986)
			(layers "F.Cu" "F.Mask" "F.Paste")
			(net "GND")
		)
		(pad "86" smd rect
			(at -2.050034 14.025118 90)
			(size 0.519938 1.4986)
			(layers "F.Cu" "F.Mask" "F.Paste")
			(net "M_F_CPU0_SA_RSP<0>")
		)
		(pad "87" smd rect
			(at -2.050034 14.875002 90)
			(size 0.519938 1.4986)
			(layers "F.Cu" "F.Mask" "F.Paste")
			(net "M_F_CPU0_SB_RSP<0>")
		)
		(pad "88" smd rect
			(at -2.050034 15.724886 90)
			(size 0.519938 1.4986)
			(layers "F.Cu" "F.Mask" "F.Paste")
			(net "GND")
		)
		(pad "89" smd rect
			(at -2.050034 16.575024 90)
			(size 0.519938 1.4986)
			(layers "F.Cu" "F.Mask" "F.Paste")
			(net "M_F_CPU0_SB_CB<4>")
		)
		(pad "90" smd rect
			(at -2.050034 17.424908 90)
			(size 0.519938 1.4986)
			(layers "F.Cu" "F.Mask" "F.Paste")
			(net "GND")
		)
		(pad "91" smd rect
			(at -2.050034 18.275046 90)
			(size 0.519938 1.4986)
			(layers "F.Cu" "F.Mask" "F.Paste")
			(net "M_F_CPU0_SB_CB<5>")
		)
		(pad "92" smd rect
			(at -2.050034 19.12493 90)
			(size 0.519938 1.4986)
			(layers "F.Cu" "F.Mask" "F.Paste")
			(net "GND")
		)
		(pad "93" smd rect
			(at -2.050034 19.975068 90)
			(size 0.519938 1.4986)
			(layers "F.Cu" "F.Mask" "F.Paste")
			(net "M_F_CPU0_SB_DQS_DP<9>")
		)
		(pad "94" smd rect
			(at -2.050034 20.824952 90)
			(size 0.519938 1.4986)
			(layers "F.Cu" "F.Mask" "F.Paste")
			(net "M_F_CPU0_SB_DQS_DN<9>")
		)
		(pad "95" smd rect
			(at -2.050034 21.67509 90)
			(size 0.519938 1.4986)
			(layers "F.Cu" "F.Mask" "F.Paste")
			(net "GND")
		)
		(pad "96" smd rect
			(at -2.050034 22.524974 90)
			(size 0.519938 1.4986)
			(layers "F.Cu" "F.Mask" "F.Paste")
			(net "M_F_CPU0_SB_CB<0>")
		)
		(pad "97" smd rect
			(at -2.050034 23.375112 90)
			(size 0.519938 1.4986)
			(layers "F.Cu" "F.Mask" "F.Paste")
			(net "GND")
		)
		(pad "98" smd rect
			(at -2.050034 24.224996 90)
			(size 0.519938 1.4986)
			(layers "F.Cu" "F.Mask" "F.Paste")
			(net "M_F_CPU0_SB_CB<1>")
		)
		(pad "99" smd rect
			(at -2.050034 25.07488 90)
			(size 0.519938 1.4986)
			(layers "F.Cu" "F.Mask" "F.Paste")
			(net "GND")
		)
		(pad "100" smd rect
			(at -2.050034 25.925018 90)
			(size 0.519938 1.4986)
			(layers "F.Cu" "F.Mask" "F.Paste")
			(net "M_F_CPU0_SB_DQ<0>")
		)
		(pad "101" smd rect
			(at -2.050034 26.774902 90)
			(size 0.519938 1.4986)
			(layers "F.Cu" "F.Mask" "F.Paste")
			(net "GND")
		)
		(pad "102" smd rect
			(at -2.050034 27.62504 90)
			(size 0.519938 1.4986)
			(layers "F.Cu" "F.Mask" "F.Paste")
			(net "M_F_CPU0_SB_DQ<1>")
		)
		(pad "103" smd rect
			(at -2.050034 28.474924 90)
			(size 0.519938 1.4986)
			(layers "F.Cu" "F.Mask" "F.Paste")
			(net "GND")
		)
		(pad "104" smd rect
			(at -2.050034 29.325062 90)
			(size 0.519938 1.4986)
			(layers "F.Cu" "F.Mask" "F.Paste")
			(net "M_F_CPU0_SB_DQS_DP<0>")
		)
		(pad "105" smd rect
			(at -2.050034 30.174946 90)
			(size 0.519938 1.4986)
			(layers "F.Cu" "F.Mask" "F.Paste")
			(net "M_F_CPU0_SB_DQS_DN<0>")
		)
		(pad "106" smd rect
			(at -2.050034 31.025084 90)
			(size 0.519938 1.4986)
			(layers "F.Cu" "F.Mask" "F.Paste")
			(net "GND")
		)
		(pad "107" smd rect
			(at -2.050034 31.874968 90)
			(size 0.519938 1.4986)
			(layers "F.Cu" "F.Mask" "F.Paste")
			(net "M_F_CPU0_SB_DQ<4>")
		)
		(pad "108" smd rect
			(at -2.050034 32.725106 90)
			(size 0.519938 1.4986)
			(layers "F.Cu" "F.Mask" "F.Paste")
			(net "GND")
		)
		(pad "109" smd rect
			(at -2.050034 33.57499 90)
			(size 0.519938 1.4986)
			(layers "F.Cu" "F.Mask" "F.Paste")
			(net "M_F_CPU0_SB_DQ<5>")
		)
		(pad "110" smd rect
			(at -2.050034 34.425128 90)
			(size 0.519938 1.4986)
			(layers "F.Cu" "F.Mask" "F.Paste")
			(net "GND")
		)
		(pad "111" smd rect
			(at -2.050034 35.275012 90)
			(size 0.519938 1.4986)
			(layers "F.Cu" "F.Mask" "F.Paste")
			(net "M_F_CPU0_SB_DQ<8>")
		)
		(pad "112" smd rect
			(at -2.050034 36.124896 90)
			(size 0.519938 1.4986)
			(layers "F.Cu" "F.Mask" "F.Paste")
			(net "GND")
		)
		(pad "113" smd rect
			(at -2.050034 36.975034 90)
			(size 0.519938 1.4986)
			(layers "F.Cu" "F.Mask" "F.Paste")
			(net "M_F_CPU0_SB_DQ<9>")
		)
		(pad "114" smd rect
			(at -2.050034 37.824918 90)
			(size 0.519938 1.4986)
			(layers "F.Cu" "F.Mask" "F.Paste")
			(net "GND")
		)
		(pad "115" smd rect
			(at -2.050034 38.675056 90)
			(size 0.519938 1.4986)
			(layers "F.Cu" "F.Mask" "F.Paste")
			(net "M_F_CPU0_SB_DQS_DP<1>")
		)
		(pad "116" smd rect
			(at -2.050034 39.52494 90)
			(size 0.519938 1.4986)
			(layers "F.Cu" "F.Mask" "F.Paste")
			(net "M_F_CPU0_SB_DQS_DN<1>")
		)
		(pad "117" smd rect
			(at -2.050034 40.375078 90)
			(size 0.519938 1.4986)
			(layers "F.Cu" "F.Mask" "F.Paste")
			(net "GND")
		)
		(pad "118" smd rect
			(at -2.050034 41.224962 90)
			(size 0.519938 1.4986)
			(layers "F.Cu" "F.Mask" "F.Paste")
			(net "M_F_CPU0_SB_DQ<12>")
		)
		(pad "119" smd rect
			(at -2.050034 42.0751 90)
			(size 0.519938 1.4986)
			(layers "F.Cu" "F.Mask" "F.Paste")
			(net "GND")
		)
		(pad "120" smd rect
			(at -2.050034 42.924984 90)
			(size 0.519938 1.4986)
			(layers "F.Cu" "F.Mask" "F.Paste")
			(net "M_F_CPU0_SB_DQ<13>")
		)
		(pad "121" smd rect
			(at -2.050034 43.775122 90)
			(size 0.519938 1.4986)
			(layers "F.Cu" "F.Mask" "F.Paste")
			(net "GND")
		)
		(pad "122" smd rect
			(at -2.050034 44.625006 90)
			(size 0.519938 1.4986)
			(layers "F.Cu" "F.Mask" "F.Paste")
			(net "M_F_CPU0_SB_DQ<16>")
		)
		(pad "123" smd rect
			(at -2.050034 45.47489 90)
			(size 0.519938 1.4986)
			(layers "F.Cu" "F.Mask" "F.Paste")
			(net "GND")
		)
		(pad "124" smd rect
			(at -2.050034 46.325028 90)
			(size 0.519938 1.4986)
			(layers "F.Cu" "F.Mask" "F.Paste")
			(net "M_F_CPU0_SB_DQ<17>")
		)
		(pad "125" smd rect
			(at -2.050034 47.174912 90)
			(size 0.519938 1.4986)
			(layers "F.Cu" "F.Mask" "F.Paste")
			(net "GND")
		)
		(pad "126" smd rect
			(at -2.050034 48.02505 90)
			(size 0.519938 1.4986)
			(layers "F.Cu" "F.Mask" "F.Paste")
			(net "M_F_CPU0_SB_DQS_DP<2>")
		)
		(pad "127" smd rect
			(at -2.050034 48.874934 90)
			(size 0.519938 1.4986)
			(layers "F.Cu" "F.Mask" "F.Paste")
			(net "M_F_CPU0_SB_DQS_DN<2>")
		)
		(pad "128" smd rect
			(at -2.050034 49.725072 90)
			(size 0.519938 1.4986)
			(layers "F.Cu" "F.Mask" "F.Paste")
			(net "GND")
		)
		(pad "129" smd rect
			(at -2.050034 50.574956 90)
			(size 0.519938 1.4986)
			(layers "F.Cu" "F.Mask" "F.Paste")
			(net "M_F_CPU0_SB_DQ<20>")
		)
		(pad "130" smd rect
			(at -2.050034 51.425094 90)
			(size 0.519938 1.4986)
			(layers "F.Cu" "F.Mask" "F.Paste")
			(net "GND")
		)
		(pad "131" smd rect
			(at -2.050034 52.274978 90)
			(size 0.519938 1.4986)
			(layers "F.Cu" "F.Mask" "F.Paste")
			(net "M_F_CPU0_SB_DQ<21>")
		)
		(pad "132" smd rect
			(at -2.050034 53.125116 90)
			(size 0.519938 1.4986)
			(layers "F.Cu" "F.Mask" "F.Paste")
			(net "GND")
		)
		(pad "133" smd rect
			(at -2.050034 53.975 90)
			(size 0.519938 1.4986)
			(layers "F.Cu" "F.Mask" "F.Paste")
			(net "M_F_CPU0_SB_DQ<24>")
		)
		(pad "134" smd rect
			(at -2.050034 54.824884 90)
			(size 0.519938 1.4986)
			(layers "F.Cu" "F.Mask" "F.Paste")
			(net "GND")
		)
		(pad "135" smd rect
			(at -2.050034 55.675022 90)
			(size 0.519938 1.4986)
			(layers "F.Cu" "F.Mask" "F.Paste")
			(net "M_F_CPU0_SB_DQ<25>")
		)
		(pad "136" smd rect
			(at -2.050034 56.524906 90)
			(size 0.519938 1.4986)
			(layers "F.Cu" "F.Mask" "F.Paste")
			(net "GND")
		)
		(pad "137" smd rect
			(at -2.050034 57.375044 90)
			(size 0.519938 1.4986)
			(layers "F.Cu" "F.Mask" "F.Paste")
			(net "M_F_CPU0_SB_DQS_DP<3>")
		)
		(pad "138" smd rect
			(at -2.050034 58.224928 90)
			(size 0.519938 1.4986)
			(layers "F.Cu" "F.Mask" "F.Paste")
			(net "M_F_CPU0_SB_DQS_DN<3>")
		)
		(pad "139" smd rect
			(at -2.050034 59.075066 90)
			(size 0.519938 1.4986)
			(layers "F.Cu" "F.Mask" "F.Paste")
			(net "GND")
		)
		(pad "140" smd rect
			(at -2.050034 59.92495 90)
			(size 0.519938 1.4986)
			(layers "F.Cu" "F.Mask" "F.Paste")
			(net "M_F_CPU0_SB_DQ<28>")
		)
		(pad "141" smd rect
			(at -2.050034 60.775088 90)
			(size 0.519938 1.4986)
			(layers "F.Cu" "F.Mask" "F.Paste")
			(net "GND")
		)
		(pad "142" smd rect
			(at -2.050034 61.624972 90)
			(size 0.519938 1.4986)
			(layers "F.Cu" "F.Mask" "F.Paste")
			(net "M_F_CPU0_SB_DQ<29>")
		)
		(pad "143" smd rect
			(at -2.050034 62.47511 90)
			(size 0.519938 1.4986)
			(layers "F.Cu" "F.Mask" "F.Paste")
			(net "GND")
		)
		(pad "144" smd rect
			(at -2.050034 63.324994 90)
			(size 0.519938 1.4986)
			(layers "F.Cu" "F.Mask" "F.Paste")
			(net "Net_2320")
		)
		(pad "145" smd rect
			(at 2.050034 -63.324994 90)
			(size 0.519938 1.4986)
			(layers "F.Cu" "F.Mask" "F.Paste")
			(net "P12V_MEM_CPU0")
		)
		(pad "146" smd rect
			(at 2.050034 -62.47511 90)
			(size 0.519938 1.4986)
			(layers "F.Cu" "F.Mask" "F.Paste")
			(net "P12V_MEM_CPU0")
		)
		(pad "147" smd rect
			(at 2.050034 -61.624972 90)
			(size 0.519938 1.4986)
			(layers "F.Cu" "F.Mask" "F.Paste")
			(net "PWRGD_CHF_CPU0_DIMM")
		)
		(pad "148" smd rect
			(at 2.050034 -60.775088 90)
			(size 0.519938 1.4986)
			(layers "F.Cu" "F.Mask" "F.Paste")
			(net "PD_CHF_CPU0_DIMM_SAA")
		)
		(pad "149" smd rect
			(at 2.050034 -59.92495 90)
			(size 0.519938 1.4986)
			(layers "F.Cu" "F.Mask" "F.Paste")
			(net "Net_2321")
		)
		(pad "150" smd rect
			(at 2.050034 -59.075066 90)
			(size 0.519938 1.4986)
			(layers "F.Cu" "F.Mask" "F.Paste")
			(net "Net_2322")
		)
		(pad "151" smd rect
			(at 2.050034 -58.224928 90)
			(size 0.519938 1.4986)
			(layers "F.Cu" "F.Mask" "F.Paste")
			(net "GND")
		)
		(pad "152" smd rect
			(at 2.050034 -57.375044 90)
			(size 0.519938 1.4986)
			(layers "F.Cu" "F.Mask" "F.Paste")
			(net "M_F_CPU0_SA_DQ<2>")
		)
		(pad "153" smd rect
			(at 2.050034 -56.524906 90)
			(size 0.519938 1.4986)
			(layers "F.Cu" "F.Mask" "F.Paste")
			(net "GND")
		)
		(pad "154" smd rect
			(at 2.050034 -55.675022 90)
			(size 0.519938 1.4986)
			(layers "F.Cu" "F.Mask" "F.Paste")
			(net "M_F_CPU0_SA_DQ<3>")
		)
		(pad "155" smd rect
			(at 2.050034 -54.824884 90)
			(size 0.519938 1.4986)
			(layers "F.Cu" "F.Mask" "F.Paste")
			(net "GND")
		)
		(pad "156" smd rect
			(at 2.050034 -53.975 90)
			(size 0.519938 1.4986)
			(layers "F.Cu" "F.Mask" "F.Paste")
			(net "M_F_CPU0_SA_DQS_DN<5>")
		)
		(pad "157" smd rect
			(at 2.050034 -53.125116 90)
			(size 0.519938 1.4986)
			(layers "F.Cu" "F.Mask" "F.Paste")
			(net "M_F_CPU0_SA_DQS_DP<5>")
		)
		(pad "158" smd rect
			(at 2.050034 -52.274978 90)
			(size 0.519938 1.4986)
			(layers "F.Cu" "F.Mask" "F.Paste")
			(net "GND")
		)
		(pad "159" smd rect
			(at 2.050034 -51.425094 90)
			(size 0.519938 1.4986)
			(layers "F.Cu" "F.Mask" "F.Paste")
			(net "M_F_CPU0_SA_DQ<6>")
		)
		(pad "160" smd rect
			(at 2.050034 -50.574956 90)
			(size 0.519938 1.4986)
			(layers "F.Cu" "F.Mask" "F.Paste")
			(net "GND")
		)
		(pad "161" smd rect
			(at 2.050034 -49.725072 90)
			(size 0.519938 1.4986)
			(layers "F.Cu" "F.Mask" "F.Paste")
			(net "M_F_CPU0_SA_DQ<7>")
		)
		(pad "162" smd rect
			(at 2.050034 -48.874934 90)
			(size 0.519938 1.4986)
			(layers "F.Cu" "F.Mask" "F.Paste")
			(net "GND")
		)
		(pad "163" smd rect
			(at 2.050034 -48.02505 90)
			(size 0.519938 1.4986)
			(layers "F.Cu" "F.Mask" "F.Paste")
			(net "M_F_CPU0_SA_DQ<10>")
		)
		(pad "164" smd rect
			(at 2.050034 -47.174912 90)
			(size 0.519938 1.4986)
			(layers "F.Cu" "F.Mask" "F.Paste")
			(net "GND")
		)
		(pad "165" smd rect
			(at 2.050034 -46.325028 90)
			(size 0.519938 1.4986)
			(layers "F.Cu" "F.Mask" "F.Paste")
			(net "M_F_CPU0_SA_DQ<11>")
		)
		(pad "166" smd rect
			(at 2.050034 -45.47489 90)
			(size 0.519938 1.4986)
			(layers "F.Cu" "F.Mask" "F.Paste")
			(net "GND")
		)
		(pad "167" smd rect
			(at 2.050034 -44.625006 90)
			(size 0.519938 1.4986)
			(layers "F.Cu" "F.Mask" "F.Paste")
			(net "M_F_CPU0_SA_DQS_DN<6>")
		)
		(pad "168" smd rect
			(at 2.050034 -43.775122 90)
			(size 0.519938 1.4986)
			(layers "F.Cu" "F.Mask" "F.Paste")
			(net "M_F_CPU0_SA_DQS_DP<6>")
		)
		(pad "169" smd rect
			(at 2.050034 -42.924984 90)
			(size 0.519938 1.4986)
			(layers "F.Cu" "F.Mask" "F.Paste")
			(net "GND")
		)
		(pad "170" smd rect
			(at 2.050034 -42.0751 90)
			(size 0.519938 1.4986)
			(layers "F.Cu" "F.Mask" "F.Paste")
			(net "M_F_CPU0_SA_DQ<14>")
		)
		(pad "171" smd rect
			(at 2.050034 -41.224962 90)
			(size 0.519938 1.4986)
			(layers "F.Cu" "F.Mask" "F.Paste")
			(net "GND")
		)
		(pad "172" smd rect
			(at 2.050034 -40.375078 90)
			(size 0.519938 1.4986)
			(layers "F.Cu" "F.Mask" "F.Paste")
			(net "M_F_CPU0_SA_DQ<15>")
		)
		(pad "173" smd rect
			(at 2.050034 -39.52494 90)
			(size 0.519938 1.4986)
			(layers "F.Cu" "F.Mask" "F.Paste")
			(net "GND")
		)
		(pad "174" smd rect
			(at 2.050034 -38.675056 90)
			(size 0.519938 1.4986)
			(layers "F.Cu" "F.Mask" "F.Paste")
			(net "M_F_CPU0_SA_DQ<18>")
		)
		(pad "175" smd rect
			(at 2.050034 -37.824918 90)
			(size 0.519938 1.4986)
			(layers "F.Cu" "F.Mask" "F.Paste")
			(net "GND")
		)
		(pad "176" smd rect
			(at 2.050034 -36.975034 90)
			(size 0.519938 1.4986)
			(layers "F.Cu" "F.Mask" "F.Paste")
			(net "M_F_CPU0_SA_DQ<19>")
		)
		(pad "177" smd rect
			(at 2.050034 -36.124896 90)
			(size 0.519938 1.4986)
			(layers "F.Cu" "F.Mask" "F.Paste")
			(net "GND")
		)
		(pad "178" smd rect
			(at 2.050034 -35.275012 90)
			(size 0.519938 1.4986)
			(layers "F.Cu" "F.Mask" "F.Paste")
			(net "M_F_CPU0_SA_DQS_DN<7>")
		)
		(pad "179" smd rect
			(at 2.050034 -34.425128 90)
			(size 0.519938 1.4986)
			(layers "F.Cu" "F.Mask" "F.Paste")
			(net "M_F_CPU0_SA_DQS_DP<7>")
		)
		(pad "180" smd rect
			(at 2.050034 -33.57499 90)
			(size 0.519938 1.4986)
			(layers "F.Cu" "F.Mask" "F.Paste")
			(net "GND")
		)
		(pad "181" smd rect
			(at 2.050034 -32.725106 90)
			(size 0.519938 1.4986)
			(layers "F.Cu" "F.Mask" "F.Paste")
			(net "M_F_CPU0_SA_DQ<22>")
		)
		(pad "182" smd rect
			(at 2.050034 -31.874968 90)
			(size 0.519938 1.4986)
			(layers "F.Cu" "F.Mask" "F.Paste")
			(net "GND")
		)
		(pad "183" smd rect
			(at 2.050034 -31.025084 90)
			(size 0.519938 1.4986)
			(layers "F.Cu" "F.Mask" "F.Paste")
			(net "M_F_CPU0_SA_DQ<23>")
		)
		(pad "184" smd rect
			(at 2.050034 -30.174946 90)
			(size 0.519938 1.4986)
			(layers "F.Cu" "F.Mask" "F.Paste")
			(net "GND")
		)
		(pad "185" smd rect
			(at 2.050034 -29.325062 90)
			(size 0.519938 1.4986)
			(layers "F.Cu" "F.Mask" "F.Paste")
			(net "M_F_CPU0_SA_DQ<26>")
		)
		(pad "186" smd rect
			(at 2.050034 -28.474924 90)
			(size 0.519938 1.4986)
			(layers "F.Cu" "F.Mask" "F.Paste")
			(net "GND")
		)
		(pad "187" smd rect
			(at 2.050034 -27.62504 90)
			(size 0.519938 1.4986)
			(layers "F.Cu" "F.Mask" "F.Paste")
			(net "M_F_CPU0_SA_DQ<27>")
		)
		(pad "188" smd rect
			(at 2.050034 -26.774902 90)
			(size 0.519938 1.4986)
			(layers "F.Cu" "F.Mask" "F.Paste")
			(net "GND")
		)
		(pad "189" smd rect
			(at 2.050034 -25.925018 90)
			(size 0.519938 1.4986)
			(layers "F.Cu" "F.Mask" "F.Paste")
			(net "M_F_CPU0_SA_DQS_DN<8>")
		)
		(pad "190" smd rect
			(at 2.050034 -25.07488 90)
			(size 0.519938 1.4986)
			(layers "F.Cu" "F.Mask" "F.Paste")
			(net "M_F_CPU0_SA_DQS_DP<8>")
		)
		(pad "191" smd rect
			(at 2.050034 -24.224996 90)
			(size 0.519938 1.4986)
			(layers "F.Cu" "F.Mask" "F.Paste")
			(net "GND")
		)
		(pad "192" smd rect
			(at 2.050034 -23.375112 90)
			(size 0.519938 1.4986)
			(layers "F.Cu" "F.Mask" "F.Paste")
			(net "M_F_CPU0_SA_DQ<30>")
		)
		(pad "193" smd rect
			(at 2.050034 -22.524974 90)
			(size 0.519938 1.4986)
			(layers "F.Cu" "F.Mask" "F.Paste")
			(net "GND")
		)
		(pad "194" smd rect
			(at 2.050034 -21.67509 90)
			(size 0.519938 1.4986)
			(layers "F.Cu" "F.Mask" "F.Paste")
			(net "M_F_CPU0_SA_DQ<31>")
		)
		(pad "195" smd rect
			(at 2.050034 -20.824952 90)
			(size 0.519938 1.4986)
			(layers "F.Cu" "F.Mask" "F.Paste")
			(net "GND")
		)
		(pad "196" smd rect
			(at 2.050034 -19.975068 90)
			(size 0.519938 1.4986)
			(layers "F.Cu" "F.Mask" "F.Paste")
			(net "M_F_CPU0_SA_CB<2>")
		)
		(pad "197" smd rect
			(at 2.050034 -19.12493 90)
			(size 0.519938 1.4986)
			(layers "F.Cu" "F.Mask" "F.Paste")
			(net "GND")
		)
		(pad "198" smd rect
			(at 2.050034 -18.275046 90)
			(size 0.519938 1.4986)
			(layers "F.Cu" "F.Mask" "F.Paste")
			(net "M_F_CPU0_SA_CB<3>")
		)
		(pad "199" smd rect
			(at 2.050034 -17.424908 90)
			(size 0.519938 1.4986)
			(layers "F.Cu" "F.Mask" "F.Paste")
			(net "GND")
		)
		(pad "200" smd rect
			(at 2.050034 -16.575024 90)
			(size 0.519938 1.4986)
			(layers "F.Cu" "F.Mask" "F.Paste")
			(net "M_F_CPU0_SA_DQS_DN<9>")
		)
		(pad "201" smd rect
			(at 2.050034 -15.724886 90)
			(size 0.519938 1.4986)
			(layers "F.Cu" "F.Mask" "F.Paste")
			(net "M_F_CPU0_SA_DQS_DP<9>")
		)
		(pad "202" smd rect
			(at 2.050034 -14.875002 90)
			(size 0.519938 1.4986)
			(layers "F.Cu" "F.Mask" "F.Paste")
			(net "GND")
		)
		(pad "203" smd rect
			(at 2.050034 -14.025118 90)
			(size 0.519938 1.4986)
			(layers "F.Cu" "F.Mask" "F.Paste")
			(net "M_F_CPU0_SA_CB<6>")
		)
		(pad "204" smd rect
			(at 2.050034 -13.17498 90)
			(size 0.519938 1.4986)
			(layers "F.Cu" "F.Mask" "F.Paste")
			(net "GND")
		)
		(pad "205" smd rect
			(at 2.050034 -12.325096 90)
			(size 0.519938 1.4986)
			(layers "F.Cu" "F.Mask" "F.Paste")
			(net "M_F_CPU0_SA_CB<7>")
		)
		(pad "206" smd rect
			(at 2.050034 -11.474958 90)
			(size 0.519938 1.4986)
			(layers "F.Cu" "F.Mask" "F.Paste")
			(net "GND")
		)
		(pad "207" smd rect
			(at 2.050034 -10.625074 90)
			(size 0.519938 1.4986)
			(layers "F.Cu" "F.Mask" "F.Paste")
			(net "M_F_CPU0_RESET_N")
		)
		(pad "208" smd rect
			(at 2.050034 -9.774936 90)
			(size 0.519938 1.4986)
			(layers "F.Cu" "F.Mask" "F.Paste")
			(net "GND")
		)
		(pad "209" smd rect
			(at 2.050034 -8.925052 90)
			(size 0.519938 1.4986)
			(layers "F.Cu" "F.Mask" "F.Paste")
			(net "M_F_CPU0_SA_CS_N<1>")
		)
		(pad "210" smd rect
			(at 2.050034 -8.074914 90)
			(size 0.519938 1.4986)
			(layers "F.Cu" "F.Mask" "F.Paste")
			(net "GND")
		)
		(pad "211" smd rect
			(at 2.050034 -7.22503 90)
			(size 0.519938 1.4986)
			(layers "F.Cu" "F.Mask" "F.Paste")
			(net "M_F_CPU0_SA_CA<1>")
		)
		(pad "212" smd rect
			(at 2.050034 -6.374892 90)
			(size 0.519938 1.4986)
			(layers "F.Cu" "F.Mask" "F.Paste")
			(net "GND")
		)
		(pad "213" smd rect
			(at 2.050034 -5.525008 90)
			(size 0.519938 1.4986)
			(layers "F.Cu" "F.Mask" "F.Paste")
			(net "M_F_CPU0_SA_CA<3>")
		)
		(pad "214" smd rect
			(at 2.050034 -4.675124 90)
			(size 0.519938 1.4986)
			(layers "F.Cu" "F.Mask" "F.Paste")
			(net "GND")
		)
		(pad "215" smd rect
			(at 2.050034 -3.824986 90)
			(size 0.519938 1.4986)
			(layers "F.Cu" "F.Mask" "F.Paste")
			(net "M_F_CPU0_SA_CA<5>")
		)
		(pad "216" smd rect
			(at 2.050034 -2.975102 90)
			(size 0.519938 1.4986)
			(layers "F.Cu" "F.Mask" "F.Paste")
			(net "GND")
		)
		(pad "217" smd rect
			(at 2.050034 -2.124964 90)
			(size 0.519938 1.4986)
			(layers "F.Cu" "F.Mask" "F.Paste")
			(net "M_F_CPU0_CLK_DP<0>")
		)
		(pad "218" smd rect
			(at 2.050034 -1.27508 90)
			(size 0.519938 1.4986)
			(layers "F.Cu" "F.Mask" "F.Paste")
			(net "M_F_CPU0_CLK_DN<0>")
		)
		(pad "219" smd rect
			(at 2.050034 -0.424942 90)
			(size 0.519938 1.4986)
			(layers "F.Cu" "F.Mask" "F.Paste")
			(net "GND")
		)
		(pad "220" smd rect
			(at 2.050034 5.525008 90)
			(size 0.519938 1.4986)
			(layers "F.Cu" "F.Mask" "F.Paste")
			(net "Net_2323")
		)
		(pad "221" smd rect
			(at 2.050034 6.374892 90)
			(size 0.519938 1.4986)
			(layers "F.Cu" "F.Mask" "F.Paste")
			(net "M_F_CPU0_SB_CA<1>")
		)
		(pad "222" smd rect
			(at 2.050034 7.22503 90)
			(size 0.519938 1.4986)
			(layers "F.Cu" "F.Mask" "F.Paste")
			(net "GND")
		)
		(pad "223" smd rect
			(at 2.050034 8.074914 90)
			(size 0.519938 1.4986)
			(layers "F.Cu" "F.Mask" "F.Paste")
			(net "M_F_CPU0_SB_CA<3>")
		)
		(pad "224" smd rect
			(at 2.050034 8.925052 90)
			(size 0.519938 1.4986)
			(layers "F.Cu" "F.Mask" "F.Paste")
			(net "GND")
		)
		(pad "225" smd rect
			(at 2.050034 9.774936 90)
			(size 0.519938 1.4986)
			(layers "F.Cu" "F.Mask" "F.Paste")
			(net "M_F_CPU0_SB_CA<5>")
		)
		(pad "226" smd rect
			(at 2.050034 10.625074 90)
			(size 0.519938 1.4986)
			(layers "F.Cu" "F.Mask" "F.Paste")
			(net "GND")
		)
		(pad "227" smd rect
			(at 2.050034 11.474958 90)
			(size 0.519938 1.4986)
			(layers "F.Cu" "F.Mask" "F.Paste")
			(net "M_F_CPU0_SB_PAR")
		)
		(pad "228" smd rect
			(at 2.050034 12.325096 90)
			(size 0.519938 1.4986)
			(layers "F.Cu" "F.Mask" "F.Paste")
			(net "GND")
		)
		(pad "229" smd rect
			(at 2.050034 13.17498 90)
			(size 0.519938 1.4986)
			(layers "F.Cu" "F.Mask" "F.Paste")
			(net "M_F_CPU0_SB_CS_N<1>")
		)
		(pad "230" smd rect
			(at 2.050034 14.025118 90)
			(size 0.519938 1.4986)
			(layers "F.Cu" "F.Mask" "F.Paste")
			(net "GND")
		)
		(pad "231" smd rect
			(at 2.050034 14.875002 90)
			(size 0.519938 1.4986)
			(layers "F.Cu" "F.Mask" "F.Paste")
			(net "Net_2324")
		)
		(pad "232" smd rect
			(at 2.050034 15.724886 90)
			(size 0.519938 1.4986)
			(layers "F.Cu" "F.Mask" "F.Paste")
			(net "Net_2325")
		)
		(pad "233" smd rect
			(at 2.050034 16.575024 90)
			(size 0.519938 1.4986)
			(layers "F.Cu" "F.Mask" "F.Paste")
			(net "GND")
		)
		(pad "234" smd rect
			(at 2.050034 17.424908 90)
			(size 0.519938 1.4986)
			(layers "F.Cu" "F.Mask" "F.Paste")
			(net "M_F_CPU0_SB_CB<6>")
		)
		(pad "235" smd rect
			(at 2.050034 18.275046 90)
			(size 0.519938 1.4986)
			(layers "F.Cu" "F.Mask" "F.Paste")
			(net "GND")
		)
		(pad "236" smd rect
			(at 2.050034 19.12493 90)
			(size 0.519938 1.4986)
			(layers "F.Cu" "F.Mask" "F.Paste")
			(net "M_F_CPU0_SB_CB<7>")
		)
		(pad "237" smd rect
			(at 2.050034 19.975068 90)
			(size 0.519938 1.4986)
			(layers "F.Cu" "F.Mask" "F.Paste")
			(net "GND")
		)
		(pad "238" smd rect
			(at 2.050034 20.824952 90)
			(size 0.519938 1.4986)
			(layers "F.Cu" "F.Mask" "F.Paste")
			(net "M_F_CPU0_SB_DQS_DN<4>")
		)
		(pad "239" smd rect
			(at 2.050034 21.67509 90)
			(size 0.519938 1.4986)
			(layers "F.Cu" "F.Mask" "F.Paste")
			(net "M_F_CPU0_SB_DQS_DP<4>")
		)
		(pad "240" smd rect
			(at 2.050034 22.524974 90)
			(size 0.519938 1.4986)
			(layers "F.Cu" "F.Mask" "F.Paste")
			(net "GND")
		)
		(pad "241" smd rect
			(at 2.050034 23.375112 90)
			(size 0.519938 1.4986)
			(layers "F.Cu" "F.Mask" "F.Paste")
			(net "M_F_CPU0_SB_CB<2>")
		)
		(pad "242" smd rect
			(at 2.050034 24.224996 90)
			(size 0.519938 1.4986)
			(layers "F.Cu" "F.Mask" "F.Paste")
			(net "GND")
		)
		(pad "243" smd rect
			(at 2.050034 25.07488 90)
			(size 0.519938 1.4986)
			(layers "F.Cu" "F.Mask" "F.Paste")
			(net "M_F_CPU0_SB_CB<3>")
		)
		(pad "244" smd rect
			(at 2.050034 25.925018 90)
			(size 0.519938 1.4986)
			(layers "F.Cu" "F.Mask" "F.Paste")
			(net "GND")
		)
		(pad "245" smd rect
			(at 2.050034 26.774902 90)
			(size 0.519938 1.4986)
			(layers "F.Cu" "F.Mask" "F.Paste")
			(net "M_F_CPU0_SB_DQ<2>")
		)
		(pad "246" smd rect
			(at 2.050034 27.62504 90)
			(size 0.519938 1.4986)
			(layers "F.Cu" "F.Mask" "F.Paste")
			(net "GND")
		)
		(pad "247" smd rect
			(at 2.050034 28.474924 90)
			(size 0.519938 1.4986)
			(layers "F.Cu" "F.Mask" "F.Paste")
			(net "M_F_CPU0_SB_DQ<3>")
		)
		(pad "248" smd rect
			(at 2.050034 29.325062 90)
			(size 0.519938 1.4986)
			(layers "F.Cu" "F.Mask" "F.Paste")
			(net "GND")
		)
		(pad "249" smd rect
			(at 2.050034 30.174946 90)
			(size 0.519938 1.4986)
			(layers "F.Cu" "F.Mask" "F.Paste")
			(net "M_F_CPU0_SB_DQS_DN<5>")
		)
		(pad "250" smd rect
			(at 2.050034 31.025084 90)
			(size 0.519938 1.4986)
			(layers "F.Cu" "F.Mask" "F.Paste")
			(net "M_F_CPU0_SB_DQS_DP<5>")
		)
		(pad "251" smd rect
			(at 2.050034 31.874968 90)
			(size 0.519938 1.4986)
			(layers "F.Cu" "F.Mask" "F.Paste")
			(net "GND")
		)
		(pad "252" smd rect
			(at 2.050034 32.725106 90)
			(size 0.519938 1.4986)
			(layers "F.Cu" "F.Mask" "F.Paste")
			(net "M_F_CPU0_SB_DQ<6>")
		)
		(pad "253" smd rect
			(at 2.050034 33.57499 90)
			(size 0.519938 1.4986)
			(layers "F.Cu" "F.Mask" "F.Paste")
			(net "GND")
		)
		(pad "254" smd rect
			(at 2.050034 34.425128 90)
			(size 0.519938 1.4986)
			(layers "F.Cu" "F.Mask" "F.Paste")
			(net "M_F_CPU0_SB_DQ<7>")
		)
		(pad "255" smd rect
			(at 2.050034 35.275012 90)
			(size 0.519938 1.4986)
			(layers "F.Cu" "F.Mask" "F.Paste")
			(net "GND")
		)
		(pad "256" smd rect
			(at 2.050034 36.124896 90)
			(size 0.519938 1.4986)
			(layers "F.Cu" "F.Mask" "F.Paste")
			(net "M_F_CPU0_SB_DQ<10>")
		)
		(pad "257" smd rect
			(at 2.050034 36.975034 90)
			(size 0.519938 1.4986)
			(layers "F.Cu" "F.Mask" "F.Paste")
			(net "GND")
		)
		(pad "258" smd rect
			(at 2.050034 37.824918 90)
			(size 0.519938 1.4986)
			(layers "F.Cu" "F.Mask" "F.Paste")
			(net "M_F_CPU0_SB_DQ<11>")
		)
		(pad "259" smd rect
			(at 2.050034 38.675056 90)
			(size 0.519938 1.4986)
			(layers "F.Cu" "F.Mask" "F.Paste")
			(net "GND")
		)
		(pad "260" smd rect
			(at 2.050034 39.52494 90)
			(size 0.519938 1.4986)
			(layers "F.Cu" "F.Mask" "F.Paste")
			(net "M_F_CPU0_SB_DQS_DN<6>")
		)
		(pad "261" smd rect
			(at 2.050034 40.375078 90)
			(size 0.519938 1.4986)
			(layers "F.Cu" "F.Mask" "F.Paste")
			(net "M_F_CPU0_SB_DQS_DP<6>")
		)
		(pad "262" smd rect
			(at 2.050034 41.224962 90)
			(size 0.519938 1.4986)
			(layers "F.Cu" "F.Mask" "F.Paste")
			(net "GND")
		)
		(pad "263" smd rect
			(at 2.050034 42.0751 90)
			(size 0.519938 1.4986)
			(layers "F.Cu" "F.Mask" "F.Paste")
			(net "M_F_CPU0_SB_DQ<14>")
		)
		(pad "264" smd rect
			(at 2.050034 42.924984 90)
			(size 0.519938 1.4986)
			(layers "F.Cu" "F.Mask" "F.Paste")
			(net "GND")
		)
		(pad "265" smd rect
			(at 2.050034 43.775122 90)
			(size 0.519938 1.4986)
			(layers "F.Cu" "F.Mask" "F.Paste")
			(net "M_F_CPU0_SB_DQ<15>")
		)
		(pad "266" smd rect
			(at 2.050034 44.625006 90)
			(size 0.519938 1.4986)
			(layers "F.Cu" "F.Mask" "F.Paste")
			(net "GND")
		)
		(pad "267" smd rect
			(at 2.050034 45.47489 90)
			(size 0.519938 1.4986)
			(layers "F.Cu" "F.Mask" "F.Paste")
			(net "M_F_CPU0_SB_DQ<18>")
		)
		(pad "268" smd rect
			(at 2.050034 46.325028 90)
			(size 0.519938 1.4986)
			(layers "F.Cu" "F.Mask" "F.Paste")
			(net "GND")
		)
		(pad "269" smd rect
			(at 2.050034 47.174912 90)
			(size 0.519938 1.4986)
			(layers "F.Cu" "F.Mask" "F.Paste")
			(net "M_F_CPU0_SB_DQ<19>")
		)
		(pad "270" smd rect
			(at 2.050034 48.02505 90)
			(size 0.519938 1.4986)
			(layers "F.Cu" "F.Mask" "F.Paste")
			(net "GND")
		)
		(pad "271" smd rect
			(at 2.050034 48.874934 90)
			(size 0.519938 1.4986)
			(layers "F.Cu" "F.Mask" "F.Paste")
			(net "M_F_CPU0_SB_DQS_DN<7>")
		)
		(pad "272" smd rect
			(at 2.050034 49.725072 90)
			(size 0.519938 1.4986)
			(layers "F.Cu" "F.Mask" "F.Paste")
			(net "M_F_CPU0_SB_DQS_DP<7>")
		)
		(pad "273" smd rect
			(at 2.050034 50.574956 90)
			(size 0.519938 1.4986)
			(layers "F.Cu" "F.Mask" "F.Paste")
			(net "GND")
		)
		(pad "274" smd rect
			(at 2.050034 51.425094 90)
			(size 0.519938 1.4986)
			(layers "F.Cu" "F.Mask" "F.Paste")
			(net "M_F_CPU0_SB_DQ<22>")
		)
		(pad "275" smd rect
			(at 2.050034 52.274978 90)
			(size 0.519938 1.4986)
			(layers "F.Cu" "F.Mask" "F.Paste")
			(net "GND")
		)
		(pad "276" smd rect
			(at 2.050034 53.125116 90)
			(size 0.519938 1.4986)
			(layers "F.Cu" "F.Mask" "F.Paste")
			(net "M_F_CPU0_SB_DQ<23>")
		)
		(pad "277" smd rect
			(at 2.050034 53.975 90)
			(size 0.519938 1.4986)
			(layers "F.Cu" "F.Mask" "F.Paste")
			(net "GND")
		)
		(pad "278" smd rect
			(at 2.050034 54.824884 90)
			(size 0.519938 1.4986)
			(layers "F.Cu" "F.Mask" "F.Paste")
			(net "M_F_CPU0_SB_DQ<26>")
		)
		(pad "279" smd rect
			(at 2.050034 55.675022 90)
			(size 0.519938 1.4986)
			(layers "F.Cu" "F.Mask" "F.Paste")
			(net "GND")
		)
		(pad "280" smd rect
			(at 2.050034 56.524906 90)
			(size 0.519938 1.4986)
			(layers "F.Cu" "F.Mask" "F.Paste")
			(net "M_F_CPU0_SB_DQ<27>")
		)
		(pad "281" smd rect
			(at 2.050034 57.375044 90)
			(size 0.519938 1.4986)
			(layers "F.Cu" "F.Mask" "F.Paste")
			(net "GND")
		)
		(pad "282" smd rect
			(at 2.050034 58.224928 90)
			(size 0.519938 1.4986)
			(layers "F.Cu" "F.Mask" "F.Paste")
			(net "M_F_CPU0_SB_DQS_DN<8>")
		)
		(pad "283" smd rect
			(at 2.050034 59.075066 90)
			(size 0.519938 1.4986)
			(layers "F.Cu" "F.Mask" "F.Paste")
			(net "M_F_CPU0_SB_DQS_DP<8>")
		)
		(pad "284" smd rect
			(at 2.050034 59.92495 90)
			(size 0.519938 1.4986)
			(layers "F.Cu" "F.Mask" "F.Paste")
			(net "GND")
		)
		(pad "285" smd rect
			(at 2.050034 60.775088 90)
			(size 0.519938 1.4986)
			(layers "F.Cu" "F.Mask" "F.Paste")
			(net "M_F_CPU0_SB_DQ<30>")
		)
		(pad "286" smd rect
			(at 2.050034 61.624972 90)
			(size 0.519938 1.4986)
			(layers "F.Cu" "F.Mask" "F.Paste")
			(net "GND")
		)
		(pad "287" smd rect
			(at 2.050034 62.47511 90)
			(size 0.519938 1.4986)
			(layers "F.Cu" "F.Mask" "F.Paste")
			(net "M_F_CPU0_SB_DQ<31>")
		)
		(pad "288" smd rect
			(at 2.050034 63.324994 90)
			(size 0.519938 1.4986)
			(layers "F.Cu" "F.Mask" "F.Paste")
			(net "GND")
		)
		(pad "G1" thru_hole oval
			(at 0 -68.97497 90)
			(size 1.7272 3.4798)
			(drill oval 1.2192 2.4638)
			(layers "*.Cu" "*.Mask")
			(remove_unused_layers no)
			(net "GND")
			(clearance 0.127)
			(thermal_gap 0.127)
		)
		(pad "G2" thru_hole oval
			(at 0 3.875024 90)
			(size 1.7272 3.4798)
			(drill oval 1.2192 2.4638)
			(layers "*.Cu" "*.Mask")
			(remove_unused_layers no)
			(net "GND")
			(clearance 0.127)
			(thermal_gap 0.127)
		)
		(pad "G3" thru_hole oval
			(at 0 68.97497 90)
			(size 1.7272 3.4798)
			(drill oval 1.2192 2.4638)
			(layers "*.Cu" "*.Mask")
			(remove_unused_layers no)
			(net "GND")
			(clearance 0.127)
			(thermal_gap 0.127)
		)
	)
	(footprint ""
		(layer "F.Cu")
		(at 74.969878 -389.344154 180)
		(property "Reference" "R1388"
			(at 0 0 180)
			(layer "F.SilkS")
			(hide yes)
			(effects
				(font
					(size 1.27 1.27)
				)
			)
		)
		(property "Value" ""
			(at 0 0 180)
			(layer "F.Fab")
			(effects
				(font
					(size 1.27 1.27)
				)
			)
		)
		(duplicate_pad_numbers_are_jumpers no)
		(fp_line
			(start 0.32512 0.175006)
			(end -0.32512 0.175006)
			(stroke
				(width 0.1)
				(type default)
			)
			(layer "F.Fab")
		)
		(fp_line
			(start 0.32512 -0.175006)
			(end 0.32512 0.175006)
			(stroke
				(width 0.1)
				(type default)
			)
			(layer "F.Fab")
		)
		(fp_line
			(start -0.32512 0.175006)
			(end -0.32512 -0.175006)
			(stroke
				(width 0.1)
				(type default)
			)
			(layer "F.Fab")
		)
		(fp_line
			(start -0.32512 -0.175006)
			(end 0.32512 -0.175006)
			(stroke
				(width 0.1)
				(type default)
			)
			(layer "F.Fab")
		)
		(pad "1" smd rect
			(at -0.2667 0 180)
			(size 0.3048 0.381)
			(layers "F.Cu" "F.Mask" "F.Paste")
			(net "P1V8_CPU1_RT_1D")
		)
		(pad "2" smd rect
			(at 0.2667 0)
			(size 0.3048 0.381)
			(layers "F.Cu" "F.Mask" "F.Paste")
			(net "RXDET_BYP_RT_CPU1_P0")
		)
	)
	(footprint ""
		(layer "F.Cu")
		(at 252.573536 -121.71045 180)
		(property "Reference" "R1498"
			(at 0 0 180)
			(layer "F.SilkS")
			(hide yes)
			(effects
				(font
					(size 1.27 1.27)
				)
			)
		)
		(property "Value" ""
			(at 0 0 180)
			(layer "F.Fab")
			(effects
				(font
					(size 1.27 1.27)
				)
			)
		)
		(duplicate_pad_numbers_are_jumpers no)
		(fp_line
			(start 0.7874 0.4064)
			(end -0.7874 0.4064)
			(stroke
				(width 0.1524)
				(type default)
			)
			(layer "F.SilkS")
		)
		(fp_line
			(start 0.7874 -0.4064)
			(end 0.7874 0.4064)
			(stroke
				(width 0.1524)
				(type default)
			)
			(layer "F.SilkS")
		)
		(fp_line
			(start -0.7874 0.4064)
			(end -0.7874 -0.4064)
			(stroke
				(width 0.1524)
				(type default)
			)
			(layer "F.SilkS")
		)
		(fp_line
			(start -0.7874 -0.4064)
			(end 0.7874 -0.4064)
			(stroke
				(width 0.1524)
				(type default)
			)
			(layer "F.SilkS")
		)
		(fp_line
			(start 0.67945 0.3048)
			(end 0.120396 0.3048)
			(stroke
				(width 0.1)
				(type default)
			)
			(layer "F.Fab")
		)
		(fp_line
			(start 0.67945 -0.3048)
			(end 0.67945 0.3048)
			(stroke
				(width 0.1)
				(type default)
			)
			(layer "F.Fab")
		)
		(fp_line
			(start 0.12065 -0.2794)
			(end 0.12065 -0.3048)
			(stroke
				(width 0.1)
				(type default)
			)
			(layer "F.Fab")
		)
		(fp_line
			(start 0.12065 -0.3048)
			(end 0.67945 -0.3048)
			(stroke
				(width 0.1)
				(type default)
			)
			(layer "F.Fab")
		)
		(fp_line
			(start 0.120396 0.3048)
			(end 0.120396 0.2794)
			(stroke
				(width 0.1)
				(type default)
			)
			(layer "F.Fab")
		)
		(fp_line
			(start 0.120396 0.2794)
			(end -0.12065 0.2794)
			(stroke
				(width 0.1)
				(type default)
			)
			(layer "F.Fab")
		)
		(fp_line
			(start -0.12065 0.3048)
			(end -0.67945 0.3048)
			(stroke
				(width 0.1)
				(type default)
			)
			(layer "F.Fab")
		)
		(fp_line
			(start -0.12065 0.2794)
			(end -0.12065 0.3048)
			(stroke
				(width 0.1)
				(type default)
			)
			(layer "F.Fab")
		)
		(fp_line
			(start -0.12065 -0.2794)
			(end 0.12065 -0.2794)
			(stroke
				(width 0.1)
				(type default)
			)
			(layer "F.Fab")
		)
		(fp_line
			(start -0.12065 -0.305054)
			(end -0.12065 -0.2794)
			(stroke
				(width 0.1)
				(type default)
			)
			(layer "F.Fab")
		)
		(fp_line
			(start -0.67945 0.3048)
			(end -0.67945 -0.305054)
			(stroke
				(width 0.1)
				(type default)
			)
			(layer "F.Fab")
		)
		(fp_line
			(start -0.67945 -0.305054)
			(end -0.12065 -0.305054)
			(stroke
				(width 0.1)
				(type default)
			)
			(layer "F.Fab")
		)
		(pad "1" smd circle
			(at -0.40005 0 180)
			(size 0 0)
			(layers "F.Cu" "F.Mask" "F.Paste")
			(net "SMB_VR_3V3AUX_SDA")
		)
		(pad "2" smd circle
			(at 0.40005 0 180)
			(size 0 0)
			(layers "F.Cu" "F.Mask" "F.Paste")
			(net "SMB_SCM_2_R3_SDA")
		)
	)
	(footprint ""
		(layer "F.Cu")
		(at 297.315128 -147.472908)
		(property "Reference" "R5006"
			(at 0 0 0)
			(layer "F.SilkS")
			(hide yes)
			(effects
				(font
					(size 1.27 1.27)
				)
			)
		)
		(property "Value" ""
			(at 0 0 0)
			(layer "F.Fab")
			(effects
				(font
					(size 1.27 1.27)
				)
			)
		)
		(duplicate_pad_numbers_are_jumpers no)
		(fp_line
			(start -0.7874 -0.4064)
			(end 0.7874 -0.4064)
			(stroke
				(width 0.1524)
				(type default)
			)
			(layer "F.SilkS")
		)
		(fp_line
			(start -0.7874 0.4064)
			(end -0.7874 -0.4064)
			(stroke
				(width 0.1524)
				(type default)
			)
			(layer "F.SilkS")
		)
		(fp_line
			(start 0.7874 -0.4064)
			(end 0.7874 0.4064)
			(stroke
				(width 0.1524)
				(type default)
			)
			(layer "F.SilkS")
		)
		(fp_line
			(start 0.7874 0.4064)
			(end -0.7874 0.4064)
			(stroke
				(width 0.1524)
				(type default)
			)
			(layer "F.SilkS")
		)
		(fp_line
			(start -0.67945 -0.305054)
			(end -0.12065 -0.305054)
			(stroke
				(width 0.1)
				(type default)
			)
			(layer "F.Fab")
		)
		(fp_line
			(start -0.67945 0.3048)
			(end -0.67945 -0.305054)
			(stroke
				(width 0.1)
				(type default)
			)
			(layer "F.Fab")
		)
		(fp_line
			(start -0.12065 -0.305054)
			(end -0.12065 -0.2794)
			(stroke
				(width 0.1)
				(type default)
			)
			(layer "F.Fab")
		)
		(fp_line
			(start -0.12065 -0.2794)
			(end 0.12065 -0.2794)
			(stroke
				(width 0.1)
				(type default)
			)
			(layer "F.Fab")
		)
		(fp_line
			(start -0.12065 0.2794)
			(end -0.12065 0.3048)
			(stroke
				(width 0.1)
				(type default)
			)
			(layer "F.Fab")
		)
		(fp_line
			(start -0.12065 0.3048)
			(end -0.67945 0.3048)
			(stroke
				(width 0.1)
				(type default)
			)
			(layer "F.Fab")
		)
		(fp_line
			(start 0.120396 0.2794)
			(end -0.12065 0.2794)
			(stroke
				(width 0.1)
				(type default)
			)
			(layer "F.Fab")
		)
		(fp_line
			(start 0.120396 0.3048)
			(end 0.120396 0.2794)
			(stroke
				(width 0.1)
				(type default)
			)
			(layer "F.Fab")
		)
		(fp_line
			(start 0.12065 -0.3048)
			(end 0.67945 -0.3048)
			(stroke
				(width 0.1)
				(type default)
			)
			(layer "F.Fab")
		)
		(fp_line
			(start 0.12065 -0.2794)
			(end 0.12065 -0.3048)
			(stroke
				(width 0.1)
				(type default)
			)
			(layer "F.Fab")
		)
		(fp_line
			(start 0.67945 -0.3048)
			(end 0.67945 0.3048)
			(stroke
				(width 0.1)
				(type default)
			)
			(layer "F.Fab")
		)
		(fp_line
			(start 0.67945 0.3048)
			(end 0.120396 0.3048)
			(stroke
				(width 0.1)
				(type default)
			)
			(layer "F.Fab")
		)
		(pad "1" smd circle
			(at -0.40005 0)
			(size 0 0)
			(layers "F.Cu" "F.Mask" "F.Paste")
			(net "PVDD11_S3_P0")
		)
		(pad "2" smd circle
			(at 0.40005 0)
			(size 0 0)
			(layers "F.Cu" "F.Mask" "F.Paste")
			(net "I3C_SPD_DDRAF_CPU0_LVC1_SCL")
		)
	)
	(footprint ""
		(layer "F.Cu")
		(at 463.465926 -97.523808)
		(property "Reference" "R2473"
			(at 0 0 0)
			(layer "F.SilkS")
			(hide yes)
			(effects
				(font
					(size 1.27 1.27)
				)
			)
		)
		(property "Value" ""
			(at 0 0 0)
			(layer "F.Fab")
			(effects
				(font
					(size 1.27 1.27)
				)
			)
		)
		(duplicate_pad_numbers_are_jumpers no)
		(fp_line
			(start -0.7874 -0.4064)
			(end 0.7874 -0.4064)
			(stroke
				(width 0.1524)
				(type default)
			)
			(layer "F.SilkS")
		)
		(fp_line
			(start -0.7874 0.4064)
			(end -0.7874 -0.4064)
			(stroke
				(width 0.1524)
				(type default)
			)
			(layer "F.SilkS")
		)
		(fp_line
			(start 0.7874 -0.4064)
			(end 0.7874 0.4064)
			(stroke
				(width 0.1524)
				(type default)
			)
			(layer "F.SilkS")
		)
		(fp_line
			(start 0.7874 0.4064)
			(end -0.7874 0.4064)
			(stroke
				(width 0.1524)
				(type default)
			)
			(layer "F.SilkS")
		)
		(fp_line
			(start -0.67945 -0.305054)
			(end -0.12065 -0.305054)
			(stroke
				(width 0.1)
				(type default)
			)
			(layer "F.Fab")
		)
		(fp_line
			(start -0.67945 0.3048)
			(end -0.67945 -0.305054)
			(stroke
				(width 0.1)
				(type default)
			)
			(layer "F.Fab")
		)
		(fp_line
			(start -0.12065 -0.305054)
			(end -0.12065 -0.2794)
			(stroke
				(width 0.1)
				(type default)
			)
			(layer "F.Fab")
		)
		(fp_line
			(start -0.12065 -0.2794)
			(end 0.12065 -0.2794)
			(stroke
				(width 0.1)
				(type default)
			)
			(layer "F.Fab")
		)
		(fp_line
			(start -0.12065 0.2794)
			(end -0.12065 0.3048)
			(stroke
				(width 0.1)
				(type default)
			)
			(layer "F.Fab")
		)
		(fp_line
			(start -0.12065 0.3048)
			(end -0.67945 0.3048)
			(stroke
				(width 0.1)
				(type default)
			)
			(layer "F.Fab")
		)
		(fp_line
			(start 0.120396 0.2794)
			(end -0.12065 0.2794)
			(stroke
				(width 0.1)
				(type default)
			)
			(layer "F.Fab")
		)
		(fp_line
			(start 0.120396 0.3048)
			(end 0.120396 0.2794)
			(stroke
				(width 0.1)
				(type default)
			)
			(layer "F.Fab")
		)
		(fp_line
			(start 0.12065 -0.3048)
			(end 0.67945 -0.3048)
			(stroke
				(width 0.1)
				(type default)
			)
			(layer "F.Fab")
		)
		(fp_line
			(start 0.12065 -0.2794)
			(end 0.12065 -0.3048)
			(stroke
				(width 0.1)
				(type default)
			)
			(layer "F.Fab")
		)
		(fp_line
			(start 0.67945 -0.3048)
			(end 0.67945 0.3048)
			(stroke
				(width 0.1)
				(type default)
			)
			(layer "F.Fab")
		)
		(fp_line
			(start 0.67945 0.3048)
			(end 0.120396 0.3048)
			(stroke
				(width 0.1)
				(type default)
			)
			(layer "F.Fab")
		)
		(pad "1" smd circle
			(at -0.40005 0)
			(size 0 0)
			(layers "F.Cu" "F.Mask" "F.Paste")
			(net "FB_BMC_ISOLATE_R1")
		)
		(pad "2" smd circle
			(at 0.40005 0)
			(size 0 0)
			(layers "F.Cu" "F.Mask" "F.Paste")
			(net "FB_BMC_ISOLATE")
		)
	)
	(footprint ""
		(layer "F.Cu")
		(at 114.926364 -167.2717 -90)
		(property "Reference" "PR209"
			(at 0 0 270)
			(layer "F.SilkS")
			(hide yes)
			(effects
				(font
					(size 1.27 1.27)
				)
			)
		)
		(property "Value" ""
			(at 0 0 270)
			(layer "F.Fab")
			(effects
				(font
					(size 1.27 1.27)
				)
			)
		)
		(duplicate_pad_numbers_are_jumpers no)
		(fp_line
			(start -0.7874 0.4064)
			(end -0.7874 -0.4064)
			(stroke
				(width 0.1524)
				(type default)
			)
			(layer "F.SilkS")
		)
		(fp_line
			(start 0.7874 0.4064)
			(end -0.7874 0.4064)
			(stroke
				(width 0.1524)
				(type default)
			)
			(layer "F.SilkS")
		)
		(fp_line
			(start -0.7874 -0.4064)
			(end 0.7874 -0.4064)
			(stroke
				(width 0.1524)
				(type default)
			)
			(layer "F.SilkS")
		)
		(fp_line
			(start 0.7874 -0.4064)
			(end 0.7874 0.4064)
			(stroke
				(width 0.1524)
				(type default)
			)
			(layer "F.SilkS")
		)
		(fp_line
			(start -0.67945 0.3048)
			(end -0.67945 -0.305054)
			(stroke
				(width 0.1)
				(type default)
			)
			(layer "F.Fab")
		)
		(fp_line
			(start -0.12065 0.3048)
			(end -0.67945 0.3048)
			(stroke
				(width 0.1)
				(type default)
			)
			(layer "F.Fab")
		)
		(fp_line
			(start 0.120396 0.3048)
			(end 0.120396 0.2794)
			(stroke
				(width 0.1)
				(type default)
			)
			(layer "F.Fab")
		)
		(fp_line
			(start 0.67945 0.3048)
			(end 0.120396 0.3048)
			(stroke
				(width 0.1)
				(type default)
			)
			(layer "F.Fab")
		)
		(fp_line
			(start -0.12065 0.2794)
			(end -0.12065 0.3048)
			(stroke
				(width 0.1)
				(type default)
			)
			(layer "F.Fab")
		)
		(fp_line
			(start 0.120396 0.2794)
			(end -0.12065 0.2794)
			(stroke
				(width 0.1)
				(type default)
			)
			(layer "F.Fab")
		)
		(fp_line
			(start -0.12065 -0.2794)
			(end 0.12065 -0.2794)
			(stroke
				(width 0.1)
				(type default)
			)
			(layer "F.Fab")
		)
		(fp_line
			(start 0.12065 -0.2794)
			(end 0.12065 -0.3048)
			(stroke
				(width 0.1)
				(type default)
			)
			(layer "F.Fab")
		)
		(fp_line
			(start 0.12065 -0.3048)
			(end 0.67945 -0.3048)
			(stroke
				(width 0.1)
				(type default)
			)
			(layer "F.Fab")
		)
		(fp_line
			(start 0.67945 -0.3048)
			(end 0.67945 0.3048)
			(stroke
				(width 0.1)
				(type default)
			)
			(layer "F.Fab")
		)
		(fp_line
			(start -0.67945 -0.305054)
			(end -0.12065 -0.305054)
			(stroke
				(width 0.1)
				(type default)
			)
			(layer "F.Fab")
		)
		(fp_line
			(start -0.12065 -0.305054)
			(end -0.12065 -0.2794)
			(stroke
				(width 0.1)
				(type default)
			)
			(layer "F.Fab")
		)
		(pad "1" smd circle
			(at -0.40005 0 270)
			(size 0 0)
			(layers "F.Cu" "F.Mask" "F.Paste")
			(net "SW_PVDDCR_SOC_P1_BOOT1")
		)
		(pad "2" smd circle
			(at 0.40005 0 270)
			(size 0 0)
			(layers "F.Cu" "F.Mask" "F.Paste")
			(net "SW_PVDDCR_SOC_P1_BOOT1_RC")
		)
	)
	(footprint ""
		(layer "F.Cu")
		(at 408.841702 -163.736274 -90)
		(property "Reference" "PC578_8"
			(at 0 0 270)
			(layer "F.SilkS")
			(hide yes)
			(effects
				(font
					(size 1.27 1.27)
				)
			)
		)
		(property "Value" ""
			(at 0 0 270)
			(layer "F.Fab")
			(effects
				(font
					(size 1.27 1.27)
				)
			)
		)
		(duplicate_pad_numbers_are_jumpers no)
		(fp_line
			(start -0.7874 0.4064)
			(end -0.7874 -0.4064)
			(stroke
				(width 0.1524)
				(type default)
			)
			(layer "F.SilkS")
		)
		(fp_line
			(start 0.7874 0.4064)
			(end -0.7874 0.4064)
			(stroke
				(width 0.1524)
				(type default)
			)
			(layer "F.SilkS")
		)
		(fp_line
			(start -0.7874 -0.4064)
			(end 0.7874 -0.4064)
			(stroke
				(width 0.1524)
				(type default)
			)
			(layer "F.SilkS")
		)
		(fp_line
			(start 0.7874 -0.4064)
			(end 0.7874 0.4064)
			(stroke
				(width 0.1524)
				(type default)
			)
			(layer "F.SilkS")
		)
		(fp_line
			(start -0.67945 0.3048)
			(end -0.67945 -0.305054)
			(stroke
				(width 0.1)
				(type default)
			)
			(layer "F.Fab")
		)
		(fp_line
			(start -0.12065 0.3048)
			(end -0.67945 0.3048)
			(stroke
				(width 0.1)
				(type default)
			)
			(layer "F.Fab")
		)
		(fp_line
			(start 0.120396 0.3048)
			(end 0.120396 0.2794)
			(stroke
				(width 0.1)
				(type default)
			)
			(layer "F.Fab")
		)
		(fp_line
			(start 0.67945 0.3048)
			(end 0.120396 0.3048)
			(stroke
				(width 0.1)
				(type default)
			)
			(layer "F.Fab")
		)
		(fp_line
			(start -0.12065 0.2794)
			(end -0.12065 0.3048)
			(stroke
				(width 0.1)
				(type default)
			)
			(layer "F.Fab")
		)
		(fp_line
			(start 0.120396 0.2794)
			(end -0.12065 0.2794)
			(stroke
				(width 0.1)
				(type default)
			)
			(layer "F.Fab")
		)
		(fp_line
			(start -0.12065 -0.2794)
			(end 0.12065 -0.2794)
			(stroke
				(width 0.1)
				(type default)
			)
			(layer "F.Fab")
		)
		(fp_line
			(start 0.12065 -0.2794)
			(end 0.12065 -0.3048)
			(stroke
				(width 0.1)
				(type default)
			)
			(layer "F.Fab")
		)
		(fp_line
			(start 0.12065 -0.3048)
			(end 0.67945 -0.3048)
			(stroke
				(width 0.1)
				(type default)
			)
			(layer "F.Fab")
		)
		(fp_line
			(start 0.67945 -0.3048)
			(end 0.67945 0.3048)
			(stroke
				(width 0.1)
				(type default)
			)
			(layer "F.Fab")
		)
		(fp_line
			(start -0.67945 -0.305054)
			(end -0.12065 -0.305054)
			(stroke
				(width 0.1)
				(type default)
			)
			(layer "F.Fab")
		)
		(fp_line
			(start -0.12065 -0.305054)
			(end -0.12065 -0.2794)
			(stroke
				(width 0.1)
				(type default)
			)
			(layer "F.Fab")
		)
		(pad "1" smd circle
			(at -0.40005 0 270)
			(size 0 0)
			(layers "F.Cu" "F.Mask" "F.Paste")
			(net "PVDDCR_CPU0_P0_VCCS")
		)
		(pad "2" smd circle
			(at 0.40005 0 270)
			(size 0 0)
			(layers "F.Cu" "F.Mask" "F.Paste")
			(net "GND")
		)
	)
	(footprint ""
		(layer "F.Cu")
		(at 437.515 -94.071948 90)
		(property "Reference" "C2024"
			(at 0 0 90)
			(layer "F.SilkS")
			(hide yes)
			(effects
				(font
					(size 1.27 1.27)
				)
			)
		)
		(property "Value" ""
			(at 0 0 90)
			(layer "F.Fab")
			(effects
				(font
					(size 1.27 1.27)
				)
			)
		)
		(duplicate_pad_numbers_are_jumpers no)
		(fp_line
			(start 0.7874 -0.4064)
			(end 0.7874 0.4064)
			(stroke
				(width 0.1524)
				(type default)
			)
			(layer "F.SilkS")
		)
		(fp_line
			(start -0.7874 -0.4064)
			(end 0.7874 -0.4064)
			(stroke
				(width 0.1524)
				(type default)
			)
			(layer "F.SilkS")
		)
		(fp_line
			(start 0.7874 0.4064)
			(end -0.7874 0.4064)
			(stroke
				(width 0.1524)
				(type default)
			)
			(layer "F.SilkS")
		)
		(fp_line
			(start -0.7874 0.4064)
			(end -0.7874 -0.4064)
			(stroke
				(width 0.1524)
				(type default)
			)
			(layer "F.SilkS")
		)
		(fp_line
			(start -0.12065 -0.305054)
			(end -0.12065 -0.2794)
			(stroke
				(width 0.1)
				(type default)
			)
			(layer "F.Fab")
		)
		(fp_line
			(start -0.67945 -0.305054)
			(end -0.12065 -0.305054)
			(stroke
				(width 0.1)
				(type default)
			)
			(layer "F.Fab")
		)
		(fp_line
			(start 0.67945 -0.3048)
			(end 0.67945 0.3048)
			(stroke
				(width 0.1)
				(type default)
			)
			(layer "F.Fab")
		)
		(fp_line
			(start 0.12065 -0.3048)
			(end 0.67945 -0.3048)
			(stroke
				(width 0.1)
				(type default)
			)
			(layer "F.Fab")
		)
		(fp_line
			(start 0.12065 -0.2794)
			(end 0.12065 -0.3048)
			(stroke
				(width 0.1)
				(type default)
			)
			(layer "F.Fab")
		)
		(fp_line
			(start -0.12065 -0.2794)
			(end 0.12065 -0.2794)
			(stroke
				(width 0.1)
				(type default)
			)
			(layer "F.Fab")
		)
		(fp_line
			(start 0.120396 0.2794)
			(end -0.12065 0.2794)
			(stroke
				(width 0.1)
				(type default)
			)
			(layer "F.Fab")
		)
		(fp_line
			(start -0.12065 0.2794)
			(end -0.12065 0.3048)
			(stroke
				(width 0.1)
				(type default)
			)
			(layer "F.Fab")
		)
		(fp_line
			(start 0.67945 0.3048)
			(end 0.120396 0.3048)
			(stroke
				(width 0.1)
				(type default)
			)
			(layer "F.Fab")
		)
		(fp_line
			(start 0.120396 0.3048)
			(end 0.120396 0.2794)
			(stroke
				(width 0.1)
				(type default)
			)
			(layer "F.Fab")
		)
		(fp_line
			(start -0.12065 0.3048)
			(end -0.67945 0.3048)
			(stroke
				(width 0.1)
				(type default)
			)
			(layer "F.Fab")
		)
		(fp_line
			(start -0.67945 0.3048)
			(end -0.67945 -0.305054)
			(stroke
				(width 0.1)
				(type default)
			)
			(layer "F.Fab")
		)
		(pad "1" smd circle
			(at -0.40005 0 90)
			(size 0 0)
			(layers "F.Cu" "F.Mask" "F.Paste")
			(net "P3V3_OCP_SFF_R")
		)
		(pad "2" smd circle
			(at 0.40005 0 90)
			(size 0 0)
			(layers "F.Cu" "F.Mask" "F.Paste")
			(net "GND")
		)
	)
	(footprint ""
		(layer "F.Cu")
		(at 218.011502 -71.126858 180)
		(property "Reference" "PR3969"
			(at 0 0 180)
			(layer "F.SilkS")
			(hide yes)
			(effects
				(font
					(size 1.27 1.27)
				)
			)
		)
		(property "Value" ""
			(at 0 0 180)
			(layer "F.Fab")
			(effects
				(font
					(size 1.27 1.27)
				)
			)
		)
		(duplicate_pad_numbers_are_jumpers no)
		(fp_line
			(start 0.7874 0.4064)
			(end -0.7874 0.4064)
			(stroke
				(width 0.1524)
				(type default)
			)
			(layer "F.SilkS")
		)
		(fp_line
			(start 0.7874 -0.4064)
			(end 0.7874 0.4064)
			(stroke
				(width 0.1524)
				(type default)
			)
			(layer "F.SilkS")
		)
		(fp_line
			(start -0.7874 0.4064)
			(end -0.7874 -0.4064)
			(stroke
				(width 0.1524)
				(type default)
			)
			(layer "F.SilkS")
		)
		(fp_line
			(start -0.7874 -0.4064)
			(end 0.7874 -0.4064)
			(stroke
				(width 0.1524)
				(type default)
			)
			(layer "F.SilkS")
		)
		(fp_line
			(start 0.67945 0.3048)
			(end 0.120396 0.3048)
			(stroke
				(width 0.1)
				(type default)
			)
			(layer "F.Fab")
		)
		(fp_line
			(start 0.67945 -0.3048)
			(end 0.67945 0.3048)
			(stroke
				(width 0.1)
				(type default)
			)
			(layer "F.Fab")
		)
		(fp_line
			(start 0.12065 -0.2794)
			(end 0.12065 -0.3048)
			(stroke
				(width 0.1)
				(type default)
			)
			(layer "F.Fab")
		)
		(fp_line
			(start 0.12065 -0.3048)
			(end 0.67945 -0.3048)
			(stroke
				(width 0.1)
				(type default)
			)
			(layer "F.Fab")
		)
		(fp_line
			(start 0.120396 0.3048)
			(end 0.120396 0.2794)
			(stroke
				(width 0.1)
				(type default)
			)
			(layer "F.Fab")
		)
		(fp_line
			(start 0.120396 0.2794)
			(end -0.12065 0.2794)
			(stroke
				(width 0.1)
				(type default)
			)
			(layer "F.Fab")
		)
		(fp_line
			(start -0.12065 0.3048)
			(end -0.67945 0.3048)
			(stroke
				(width 0.1)
				(type default)
			)
			(layer "F.Fab")
		)
		(fp_line
			(start -0.12065 0.2794)
			(end -0.12065 0.3048)
			(stroke
				(width 0.1)
				(type default)
			)
			(layer "F.Fab")
		)
		(fp_line
			(start -0.12065 -0.2794)
			(end 0.12065 -0.2794)
			(stroke
				(width 0.1)
				(type default)
			)
			(layer "F.Fab")
		)
		(fp_line
			(start -0.12065 -0.305054)
			(end -0.12065 -0.2794)
			(stroke
				(width 0.1)
				(type default)
			)
			(layer "F.Fab")
		)
		(fp_line
			(start -0.67945 0.3048)
			(end -0.67945 -0.305054)
			(stroke
				(width 0.1)
				(type default)
			)
			(layer "F.Fab")
		)
		(fp_line
			(start -0.67945 -0.305054)
			(end -0.12065 -0.305054)
			(stroke
				(width 0.1)
				(type default)
			)
			(layer "F.Fab")
		)
		(pad "1" smd circle
			(at -0.40005 0 180)
			(size 0 0)
			(layers "F.Cu" "F.Mask" "F.Paste")
			(net "P3V3_E1S_CB_0")
		)
		(pad "2" smd circle
			(at 0.40005 0 180)
			(size 0 0)
			(layers "F.Cu" "F.Mask" "F.Paste")
			(net "GND")
		)
	)
	(footprint ""
		(layer "F.Cu")
		(at 18.330418 -415.26587 180)
		(property "Reference" "PR6601"
			(at 0 0 180)
			(layer "F.SilkS")
			(hide yes)
			(effects
				(font
					(size 1.27 1.27)
				)
			)
		)
		(property "Value" ""
			(at 0 0 180)
			(layer "F.Fab")
			(effects
				(font
					(size 1.27 1.27)
				)
			)
		)
		(duplicate_pad_numbers_are_jumpers no)
		(fp_line
			(start 0.7874 0.4064)
			(end -0.7874 0.4064)
			(stroke
				(width 0.1524)
				(type default)
			)
			(layer "F.SilkS")
		)
		(fp_line
			(start 0.7874 -0.4064)
			(end 0.7874 0.4064)
			(stroke
				(width 0.1524)
				(type default)
			)
			(layer "F.SilkS")
		)
		(fp_line
			(start -0.7874 0.4064)
			(end -0.7874 -0.4064)
			(stroke
				(width 0.1524)
				(type default)
			)
			(layer "F.SilkS")
		)
		(fp_line
			(start -0.7874 -0.4064)
			(end 0.7874 -0.4064)
			(stroke
				(width 0.1524)
				(type default)
			)
			(layer "F.SilkS")
		)
		(fp_line
			(start 0.67945 0.3048)
			(end 0.120396 0.3048)
			(stroke
				(width 0.1)
				(type default)
			)
			(layer "F.Fab")
		)
		(fp_line
			(start 0.67945 -0.3048)
			(end 0.67945 0.3048)
			(stroke
				(width 0.1)
				(type default)
			)
			(layer "F.Fab")
		)
		(fp_line
			(start 0.12065 -0.2794)
			(end 0.12065 -0.3048)
			(stroke
				(width 0.1)
				(type default)
			)
			(layer "F.Fab")
		)
		(fp_line
			(start 0.12065 -0.3048)
			(end 0.67945 -0.3048)
			(stroke
				(width 0.1)
				(type default)
			)
			(layer "F.Fab")
		)
		(fp_line
			(start 0.120396 0.3048)
			(end 0.120396 0.2794)
			(stroke
				(width 0.1)
				(type default)
			)
			(layer "F.Fab")
		)
		(fp_line
			(start 0.120396 0.2794)
			(end -0.12065 0.2794)
			(stroke
				(width 0.1)
				(type default)
			)
			(layer "F.Fab")
		)
		(fp_line
			(start -0.12065 0.3048)
			(end -0.67945 0.3048)
			(stroke
				(width 0.1)
				(type default)
			)
			(layer "F.Fab")
		)
		(fp_line
			(start -0.12065 0.2794)
			(end -0.12065 0.3048)
			(stroke
				(width 0.1)
				(type default)
			)
			(layer "F.Fab")
		)
		(fp_line
			(start -0.12065 -0.2794)
			(end 0.12065 -0.2794)
			(stroke
				(width 0.1)
				(type default)
			)
			(layer "F.Fab")
		)
		(fp_line
			(start -0.12065 -0.305054)
			(end -0.12065 -0.2794)
			(stroke
				(width 0.1)
				(type default)
			)
			(layer "F.Fab")
		)
		(fp_line
			(start -0.67945 0.3048)
			(end -0.67945 -0.305054)
			(stroke
				(width 0.1)
				(type default)
			)
			(layer "F.Fab")
		)
		(fp_line
			(start -0.67945 -0.305054)
			(end -0.12065 -0.305054)
			(stroke
				(width 0.1)
				(type default)
			)
			(layer "F.Fab")
		)
		(pad "1" smd circle
			(at -0.40005 0 180)
			(size 0 0)
			(layers "F.Cu" "F.Mask" "F.Paste")
			(net "P0V9_RETIMER_CPU1_SENSE_SH_P")
		)
		(pad "2" smd circle
			(at 0.40005 0 180)
			(size 0 0)
			(layers "F.Cu" "F.Mask" "F.Paste")
			(net "P0V9_RETIMER_CPU1_SENSE_R_P")
		)
	)
	(footprint ""
		(layer "F.Cu")
		(at 38.354 -366.776 90)
		(property "Reference" "PR251"
			(at 0 0 90)
			(layer "F.SilkS")
			(hide yes)
			(effects
				(font
					(size 1.27 1.27)
				)
			)
		)
		(property "Value" ""
			(at 0 0 90)
			(layer "F.Fab")
			(effects
				(font
					(size 1.27 1.27)
				)
			)
		)
		(duplicate_pad_numbers_are_jumpers no)
		(fp_line
			(start 0.7874 -0.4064)
			(end 0.7874 0.4064)
			(stroke
				(width 0.1524)
				(type default)
			)
			(layer "F.SilkS")
		)
		(fp_line
			(start -0.7874 -0.4064)
			(end 0.7874 -0.4064)
			(stroke
				(width 0.1524)
				(type default)
			)
			(layer "F.SilkS")
		)
		(fp_line
			(start 0.7874 0.4064)
			(end -0.7874 0.4064)
			(stroke
				(width 0.1524)
				(type default)
			)
			(layer "F.SilkS")
		)
		(fp_line
			(start -0.7874 0.4064)
			(end -0.7874 -0.4064)
			(stroke
				(width 0.1524)
				(type default)
			)
			(layer "F.SilkS")
		)
		(fp_line
			(start -0.12065 -0.305054)
			(end -0.12065 -0.2794)
			(stroke
				(width 0.1)
				(type default)
			)
			(layer "F.Fab")
		)
		(fp_line
			(start -0.67945 -0.305054)
			(end -0.12065 -0.305054)
			(stroke
				(width 0.1)
				(type default)
			)
			(layer "F.Fab")
		)
		(fp_line
			(start 0.67945 -0.3048)
			(end 0.67945 0.3048)
			(stroke
				(width 0.1)
				(type default)
			)
			(layer "F.Fab")
		)
		(fp_line
			(start 0.12065 -0.3048)
			(end 0.67945 -0.3048)
			(stroke
				(width 0.1)
				(type default)
			)
			(layer "F.Fab")
		)
		(fp_line
			(start 0.12065 -0.2794)
			(end 0.12065 -0.3048)
			(stroke
				(width 0.1)
				(type default)
			)
			(layer "F.Fab")
		)
		(fp_line
			(start -0.12065 -0.2794)
			(end 0.12065 -0.2794)
			(stroke
				(width 0.1)
				(type default)
			)
			(layer "F.Fab")
		)
		(fp_line
			(start 0.120396 0.2794)
			(end -0.12065 0.2794)
			(stroke
				(width 0.1)
				(type default)
			)
			(layer "F.Fab")
		)
		(fp_line
			(start -0.12065 0.2794)
			(end -0.12065 0.3048)
			(stroke
				(width 0.1)
				(type default)
			)
			(layer "F.Fab")
		)
		(fp_line
			(start 0.67945 0.3048)
			(end 0.120396 0.3048)
			(stroke
				(width 0.1)
				(type default)
			)
			(layer "F.Fab")
		)
		(fp_line
			(start 0.120396 0.3048)
			(end 0.120396 0.2794)
			(stroke
				(width 0.1)
				(type default)
			)
			(layer "F.Fab")
		)
		(fp_line
			(start -0.12065 0.3048)
			(end -0.67945 0.3048)
			(stroke
				(width 0.1)
				(type default)
			)
			(layer "F.Fab")
		)
		(fp_line
			(start -0.67945 0.3048)
			(end -0.67945 -0.305054)
			(stroke
				(width 0.1)
				(type default)
			)
			(layer "F.Fab")
		)
		(pad "1" smd circle
			(at -0.40005 0 90)
			(size 0 0)
			(layers "F.Cu" "F.Mask" "F.Paste")
			(net "P12V_AUX")
		)
		(pad "2" smd circle
			(at 0.40005 0 90)
			(size 0 0)
			(layers "F.Cu" "F.Mask" "F.Paste")
			(net "PVDDCR_CPU1_P1_VINSEN")
		)
	)
	(footprint ""
		(layer "F.Cu")
		(at 213.41588 -50.637948 90)
		(property "Reference" "R3756"
			(at 0 0 90)
			(layer "F.SilkS")
			(hide yes)
			(effects
				(font
					(size 1.27 1.27)
				)
			)
		)
		(property "Value" ""
			(at 0 0 90)
			(layer "F.Fab")
			(effects
				(font
					(size 1.27 1.27)
				)
			)
		)
		(duplicate_pad_numbers_are_jumpers no)
		(fp_line
			(start 0.7874 -0.4064)
			(end 0.7874 0.4064)
			(stroke
				(width 0.1524)
				(type default)
			)
			(layer "F.SilkS")
		)
		(fp_line
			(start -0.7874 -0.4064)
			(end 0.7874 -0.4064)
			(stroke
				(width 0.1524)
				(type default)
			)
			(layer "F.SilkS")
		)
		(fp_line
			(start 0.7874 0.4064)
			(end -0.7874 0.4064)
			(stroke
				(width 0.1524)
				(type default)
			)
			(layer "F.SilkS")
		)
		(fp_line
			(start -0.7874 0.4064)
			(end -0.7874 -0.4064)
			(stroke
				(width 0.1524)
				(type default)
			)
			(layer "F.SilkS")
		)
		(fp_line
			(start -0.12065 -0.305054)
			(end -0.12065 -0.2794)
			(stroke
				(width 0.1)
				(type default)
			)
			(layer "F.Fab")
		)
		(fp_line
			(start -0.67945 -0.305054)
			(end -0.12065 -0.305054)
			(stroke
				(width 0.1)
				(type default)
			)
			(layer "F.Fab")
		)
		(fp_line
			(start 0.67945 -0.3048)
			(end 0.67945 0.3048)
			(stroke
				(width 0.1)
				(type default)
			)
			(layer "F.Fab")
		)
		(fp_line
			(start 0.12065 -0.3048)
			(end 0.67945 -0.3048)
			(stroke
				(width 0.1)
				(type default)
			)
			(layer "F.Fab")
		)
		(fp_line
			(start 0.12065 -0.2794)
			(end 0.12065 -0.3048)
			(stroke
				(width 0.1)
				(type default)
			)
			(layer "F.Fab")
		)
		(fp_line
			(start -0.12065 -0.2794)
			(end 0.12065 -0.2794)
			(stroke
				(width 0.1)
				(type default)
			)
			(layer "F.Fab")
		)
		(fp_line
			(start 0.120396 0.2794)
			(end -0.12065 0.2794)
			(stroke
				(width 0.1)
				(type default)
			)
			(layer "F.Fab")
		)
		(fp_line
			(start -0.12065 0.2794)
			(end -0.12065 0.3048)
			(stroke
				(width 0.1)
				(type default)
			)
			(layer "F.Fab")
		)
		(fp_line
			(start 0.67945 0.3048)
			(end 0.120396 0.3048)
			(stroke
				(width 0.1)
				(type default)
			)
			(layer "F.Fab")
		)
		(fp_line
			(start 0.120396 0.3048)
			(end 0.120396 0.2794)
			(stroke
				(width 0.1)
				(type default)
			)
			(layer "F.Fab")
		)
		(fp_line
			(start -0.12065 0.3048)
			(end -0.67945 0.3048)
			(stroke
				(width 0.1)
				(type default)
			)
			(layer "F.Fab")
		)
		(fp_line
			(start -0.67945 0.3048)
			(end -0.67945 -0.305054)
			(stroke
				(width 0.1)
				(type default)
			)
			(layer "F.Fab")
		)
		(pad "1" smd circle
			(at -0.40005 0 90)
			(size 0 0)
			(layers "F.Cu" "F.Mask" "F.Paste")
			(net "SMB_INA230_2_3V3AUX_SDA_R")
		)
		(pad "2" smd circle
			(at 0.40005 0 90)
			(size 0 0)
			(layers "F.Cu" "F.Mask" "F.Paste")
			(net "SMB_INA230_2_3V3AUX_SDA_R1")
		)
	)
	(footprint ""
		(layer "F.Cu")
		(at 419.230302 -438.234836 90)
		(property "Reference" "R2919"
			(at 0 0 90)
			(layer "F.SilkS")
			(hide yes)
			(effects
				(font
					(size 1.27 1.27)
				)
			)
		)
		(property "Value" ""
			(at 0 0 90)
			(layer "F.Fab")
			(effects
				(font
					(size 1.27 1.27)
				)
			)
		)
		(duplicate_pad_numbers_are_jumpers no)
		(fp_line
			(start 0.7874 -0.4064)
			(end 0.7874 0.4064)
			(stroke
				(width 0.1524)
				(type default)
			)
			(layer "F.SilkS")
		)
		(fp_line
			(start -0.7874 -0.4064)
			(end 0.7874 -0.4064)
			(stroke
				(width 0.1524)
				(type default)
			)
			(layer "F.SilkS")
		)
		(fp_line
			(start 0.7874 0.4064)
			(end -0.7874 0.4064)
			(stroke
				(width 0.1524)
				(type default)
			)
			(layer "F.SilkS")
		)
		(fp_line
			(start -0.7874 0.4064)
			(end -0.7874 -0.4064)
			(stroke
				(width 0.1524)
				(type default)
			)
			(layer "F.SilkS")
		)
		(fp_line
			(start -0.12065 -0.305054)
			(end -0.12065 -0.2794)
			(stroke
				(width 0.1)
				(type default)
			)
			(layer "F.Fab")
		)
		(fp_line
			(start -0.67945 -0.305054)
			(end -0.12065 -0.305054)
			(stroke
				(width 0.1)
				(type default)
			)
			(layer "F.Fab")
		)
		(fp_line
			(start 0.67945 -0.3048)
			(end 0.67945 0.3048)
			(stroke
				(width 0.1)
				(type default)
			)
			(layer "F.Fab")
		)
		(fp_line
			(start 0.12065 -0.3048)
			(end 0.67945 -0.3048)
			(stroke
				(width 0.1)
				(type default)
			)
			(layer "F.Fab")
		)
		(fp_line
			(start 0.12065 -0.2794)
			(end 0.12065 -0.3048)
			(stroke
				(width 0.1)
				(type default)
			)
			(layer "F.Fab")
		)
		(fp_line
			(start -0.12065 -0.2794)
			(end 0.12065 -0.2794)
			(stroke
				(width 0.1)
				(type default)
			)
			(layer "F.Fab")
		)
		(fp_line
			(start 0.120396 0.2794)
			(end -0.12065 0.2794)
			(stroke
				(width 0.1)
				(type default)
			)
			(layer "F.Fab")
		)
		(fp_line
			(start -0.12065 0.2794)
			(end -0.12065 0.3048)
			(stroke
				(width 0.1)
				(type default)
			)
			(layer "F.Fab")
		)
		(fp_line
			(start 0.67945 0.3048)
			(end 0.120396 0.3048)
			(stroke
				(width 0.1)
				(type default)
			)
			(layer "F.Fab")
		)
		(fp_line
			(start 0.120396 0.3048)
			(end 0.120396 0.2794)
			(stroke
				(width 0.1)
				(type default)
			)
			(layer "F.Fab")
		)
		(fp_line
			(start -0.12065 0.3048)
			(end -0.67945 0.3048)
			(stroke
				(width 0.1)
				(type default)
			)
			(layer "F.Fab")
		)
		(fp_line
			(start -0.67945 0.3048)
			(end -0.67945 -0.305054)
			(stroke
				(width 0.1)
				(type default)
			)
			(layer "F.Fab")
		)
		(pad "1" smd circle
			(at -0.40005 0 90)
			(size 0 0)
			(layers "F.Cu" "F.Mask" "F.Paste")
			(net "P3V3_AUX")
		)
		(pad "2" smd circle
			(at 0.40005 0 90)
			(size 0 0)
			(layers "F.Cu" "F.Mask" "F.Paste")
			(net "RST_BMC_FROM_SWB_ISO_N")
		)
	)
	(footprint ""
		(layer "F.Cu")
		(at 170.46956 -388.753604 180)
		(property "Reference" "R853"
			(at 0 0 180)
			(layer "F.SilkS")
			(hide yes)
			(effects
				(font
					(size 1.27 1.27)
				)
			)
		)
		(property "Value" ""
			(at 0 0 180)
			(layer "F.Fab")
			(effects
				(font
					(size 1.27 1.27)
				)
			)
		)
		(duplicate_pad_numbers_are_jumpers no)
		(fp_line
			(start 0.7874 0.4064)
			(end -0.7874 0.4064)
			(stroke
				(width 0.1524)
				(type default)
			)
			(layer "F.SilkS")
		)
		(fp_line
			(start 0.7874 -0.4064)
			(end 0.7874 0.4064)
			(stroke
				(width 0.1524)
				(type default)
			)
			(layer "F.SilkS")
		)
		(fp_line
			(start -0.7874 0.4064)
			(end -0.7874 -0.4064)
			(stroke
				(width 0.1524)
				(type default)
			)
			(layer "F.SilkS")
		)
		(fp_line
			(start -0.7874 -0.4064)
			(end 0.7874 -0.4064)
			(stroke
				(width 0.1524)
				(type default)
			)
			(layer "F.SilkS")
		)
		(fp_line
			(start 0.67945 0.3048)
			(end 0.120396 0.3048)
			(stroke
				(width 0.1)
				(type default)
			)
			(layer "F.Fab")
		)
		(fp_line
			(start 0.67945 -0.3048)
			(end 0.67945 0.3048)
			(stroke
				(width 0.1)
				(type default)
			)
			(layer "F.Fab")
		)
		(fp_line
			(start 0.12065 -0.2794)
			(end 0.12065 -0.3048)
			(stroke
				(width 0.1)
				(type default)
			)
			(layer "F.Fab")
		)
		(fp_line
			(start 0.12065 -0.3048)
			(end 0.67945 -0.3048)
			(stroke
				(width 0.1)
				(type default)
			)
			(layer "F.Fab")
		)
		(fp_line
			(start 0.120396 0.3048)
			(end 0.120396 0.2794)
			(stroke
				(width 0.1)
				(type default)
			)
			(layer "F.Fab")
		)
		(fp_line
			(start 0.120396 0.2794)
			(end -0.12065 0.2794)
			(stroke
				(width 0.1)
				(type default)
			)
			(layer "F.Fab")
		)
		(fp_line
			(start -0.12065 0.3048)
			(end -0.67945 0.3048)
			(stroke
				(width 0.1)
				(type default)
			)
			(layer "F.Fab")
		)
		(fp_line
			(start -0.12065 0.2794)
			(end -0.12065 0.3048)
			(stroke
				(width 0.1)
				(type default)
			)
			(layer "F.Fab")
		)
		(fp_line
			(start -0.12065 -0.2794)
			(end 0.12065 -0.2794)
			(stroke
				(width 0.1)
				(type default)
			)
			(layer "F.Fab")
		)
		(fp_line
			(start -0.12065 -0.305054)
			(end -0.12065 -0.2794)
			(stroke
				(width 0.1)
				(type default)
			)
			(layer "F.Fab")
		)
		(fp_line
			(start -0.67945 0.3048)
			(end -0.67945 -0.305054)
			(stroke
				(width 0.1)
				(type default)
			)
			(layer "F.Fab")
		)
		(fp_line
			(start -0.67945 -0.305054)
			(end -0.12065 -0.305054)
			(stroke
				(width 0.1)
				(type default)
			)
			(layer "F.Fab")
		)
		(pad "1" smd rect
			(at -0.40005 0)
			(size 0.4572 0.508)
			(layers "F.Cu" "F.Mask" "F.Paste")
			(net "P1V8_CPU1_RT2_1A_1D")
		)
		(pad "2" smd rect
			(at 0.40005 0)
			(size 0.4572 0.508)
			(layers "F.Cu" "F.Mask" "F.Paste")
			(net "P1V8_CPU1_RT2_1A")
		)
	)
	(footprint ""
		(layer "F.Cu")
		(at 116.045234 -77.002894 90)
		(property "Reference" "PC6015"
			(at 0 0 90)
			(layer "F.SilkS")
			(hide yes)
			(effects
				(font
					(size 1.27 1.27)
				)
			)
		)
		(property "Value" ""
			(at 0 0 90)
			(layer "F.Fab")
			(effects
				(font
					(size 1.27 1.27)
				)
			)
		)
		(duplicate_pad_numbers_are_jumpers no)
		(fp_line
			(start 1.524 -0.762)
			(end 1.524 0.762)
			(stroke
				(width 0.1524)
				(type default)
			)
			(layer "F.SilkS")
		)
		(fp_line
			(start -1.524 -0.762)
			(end 1.524 -0.762)
			(stroke
				(width 0.1524)
				(type default)
			)
			(layer "F.SilkS")
		)
		(fp_line
			(start 1.524 0.762)
			(end -1.524 0.762)
			(stroke
				(width 0.1524)
				(type default)
			)
			(layer "F.SilkS")
		)
		(fp_line
			(start -1.524 0.762)
			(end -1.524 -0.762)
			(stroke
				(width 0.1524)
				(type default)
			)
			(layer "F.SilkS")
		)
		(fp_line
			(start 1.1049 -0.724916)
			(end -1.1049 -0.724916)
			(stroke
				(width 0.1)
				(type default)
			)
			(layer "F.Fab")
		)
		(fp_line
			(start -1.1049 -0.724916)
			(end -1.1049 0.724916)
			(stroke
				(width 0.1)
				(type default)
			)
			(layer "F.Fab")
		)
		(fp_line
			(start 1.1049 0.724916)
			(end 1.1049 -0.724916)
			(stroke
				(width 0.1)
				(type default)
			)
			(layer "F.Fab")
		)
		(fp_line
			(start -1.1049 0.724916)
			(end 1.1049 0.724916)
			(stroke
				(width 0.1)
				(type default)
			)
			(layer "F.Fab")
		)
		(pad "1" smd rect
			(at -0.889 0 270)
			(size 1.016 1.27)
			(layers "F.Cu" "F.Mask" "F.Paste")
			(net "SW_P12V_AUX_P1V2_AUX_FLT")
		)
		(pad "2" smd rect
			(at 0.889 0 270)
			(size 1.016 1.27)
			(layers "F.Cu" "F.Mask" "F.Paste")
			(net "GND")
		)
	)
	(footprint ""
		(layer "F.Cu")
		(at 99.650296 -425.82973 -90)
		(property "Reference" "R4194"
			(at 0 0 270)
			(layer "F.SilkS")
			(hide yes)
			(effects
				(font
					(size 1.27 1.27)
				)
			)
		)
		(property "Value" ""
			(at 0 0 270)
			(layer "F.Fab")
			(effects
				(font
					(size 1.27 1.27)
				)
			)
		)
		(duplicate_pad_numbers_are_jumpers no)
		(fp_line
			(start -0.7874 0.4064)
			(end -0.7874 -0.4064)
			(stroke
				(width 0.1524)
				(type default)
			)
			(layer "F.SilkS")
		)
		(fp_line
			(start 0.7874 0.4064)
			(end -0.7874 0.4064)
			(stroke
				(width 0.1524)
				(type default)
			)
			(layer "F.SilkS")
		)
		(fp_line
			(start -0.7874 -0.4064)
			(end 0.7874 -0.4064)
			(stroke
				(width 0.1524)
				(type default)
			)
			(layer "F.SilkS")
		)
		(fp_line
			(start 0.7874 -0.4064)
			(end 0.7874 0.4064)
			(stroke
				(width 0.1524)
				(type default)
			)
			(layer "F.SilkS")
		)
		(fp_line
			(start -0.67945 0.3048)
			(end -0.67945 -0.305054)
			(stroke
				(width 0.1)
				(type default)
			)
			(layer "F.Fab")
		)
		(fp_line
			(start -0.12065 0.3048)
			(end -0.67945 0.3048)
			(stroke
				(width 0.1)
				(type default)
			)
			(layer "F.Fab")
		)
		(fp_line
			(start 0.120396 0.3048)
			(end 0.120396 0.2794)
			(stroke
				(width 0.1)
				(type default)
			)
			(layer "F.Fab")
		)
		(fp_line
			(start 0.67945 0.3048)
			(end 0.120396 0.3048)
			(stroke
				(width 0.1)
				(type default)
			)
			(layer "F.Fab")
		)
		(fp_line
			(start -0.12065 0.2794)
			(end -0.12065 0.3048)
			(stroke
				(width 0.1)
				(type default)
			)
			(layer "F.Fab")
		)
		(fp_line
			(start 0.120396 0.2794)
			(end -0.12065 0.2794)
			(stroke
				(width 0.1)
				(type default)
			)
			(layer "F.Fab")
		)
		(fp_line
			(start -0.12065 -0.2794)
			(end 0.12065 -0.2794)
			(stroke
				(width 0.1)
				(type default)
			)
			(layer "F.Fab")
		)
		(fp_line
			(start 0.12065 -0.2794)
			(end 0.12065 -0.3048)
			(stroke
				(width 0.1)
				(type default)
			)
			(layer "F.Fab")
		)
		(fp_line
			(start 0.12065 -0.3048)
			(end 0.67945 -0.3048)
			(stroke
				(width 0.1)
				(type default)
			)
			(layer "F.Fab")
		)
		(fp_line
			(start 0.67945 -0.3048)
			(end 0.67945 0.3048)
			(stroke
				(width 0.1)
				(type default)
			)
			(layer "F.Fab")
		)
		(fp_line
			(start -0.67945 -0.305054)
			(end -0.12065 -0.305054)
			(stroke
				(width 0.1)
				(type default)
			)
			(layer "F.Fab")
		)
		(fp_line
			(start -0.12065 -0.305054)
			(end -0.12065 -0.2794)
			(stroke
				(width 0.1)
				(type default)
			)
			(layer "F.Fab")
		)
		(pad "1" smd circle
			(at -0.40005 0 270)
			(size 0 0)
			(layers "F.Cu" "F.Mask" "F.Paste")
			(net "P3V3_AUX")
		)
		(pad "2" smd circle
			(at 0.40005 0 270)
			(size 0 0)
			(layers "F.Cu" "F.Mask" "F.Paste")
			(net "U272_2_ADD1")
		)
	)
	(footprint ""
		(layer "F.Cu")
		(at 371.195092 -383.88163 -90)
		(property "Reference" "C893"
			(at 0 0 270)
			(layer "F.SilkS")
			(hide yes)
			(effects
				(font
					(size 1.27 1.27)
				)
			)
		)
		(property "Value" ""
			(at 0 0 270)
			(layer "F.Fab")
			(effects
				(font
					(size 1.27 1.27)
				)
			)
		)
		(duplicate_pad_numbers_are_jumpers no)
		(fp_line
			(start -0.299974 0.150114)
			(end -0.299974 -0.150114)
			(stroke
				(width 0.1)
				(type default)
			)
			(layer "F.Fab")
		)
		(fp_line
			(start 0.299974 0.150114)
			(end -0.299974 0.150114)
			(stroke
				(width 0.1)
				(type default)
			)
			(layer "F.Fab")
		)
		(fp_line
			(start -0.299974 -0.150114)
			(end 0.299974 -0.150114)
			(stroke
				(width 0.1)
				(type default)
			)
			(layer "F.Fab")
		)
		(fp_line
			(start 0.299974 -0.150114)
			(end 0.299974 0.150114)
			(stroke
				(width 0.1)
				(type default)
			)
			(layer "F.Fab")
		)
		(pad "1" smd rect
			(at -0.2667 0 270)
			(size 0.3048 0.381)
			(layers "F.Cu" "F.Mask" "F.Paste")
			(net "P5E_CPU0_P3_TX_C_DP<4>")
		)
		(pad "2" smd rect
			(at 0.2667 0 270)
			(size 0.3048 0.381)
			(layers "F.Cu" "F.Mask" "F.Paste")
			(net "P5E_CPU0_P3_TX_DP<4>")
		)
	)
	(footprint ""
		(layer "F.Cu")
		(at 90.832178 -139.80541)
		(property "Reference" "C5003"
			(at 0 0 0)
			(layer "F.SilkS")
			(hide yes)
			(effects
				(font
					(size 1.27 1.27)
				)
			)
		)
		(property "Value" ""
			(at 0 0 0)
			(layer "F.Fab")
			(effects
				(font
					(size 1.27 1.27)
				)
			)
		)
		(duplicate_pad_numbers_are_jumpers no)
		(fp_line
			(start -0.7874 -0.4064)
			(end 0.7874 -0.4064)
			(stroke
				(width 0.1524)
				(type default)
			)
			(layer "F.SilkS")
		)
		(fp_line
			(start -0.7874 0.4064)
			(end -0.7874 -0.4064)
			(stroke
				(width 0.1524)
				(type default)
			)
			(layer "F.SilkS")
		)
		(fp_line
			(start 0.7874 -0.4064)
			(end 0.7874 0.4064)
			(stroke
				(width 0.1524)
				(type default)
			)
			(layer "F.SilkS")
		)
		(fp_line
			(start 0.7874 0.4064)
			(end -0.7874 0.4064)
			(stroke
				(width 0.1524)
				(type default)
			)
			(layer "F.SilkS")
		)
		(fp_line
			(start -0.67945 -0.305054)
			(end -0.12065 -0.305054)
			(stroke
				(width 0.1)
				(type default)
			)
			(layer "F.Fab")
		)
		(fp_line
			(start -0.67945 0.3048)
			(end -0.67945 -0.305054)
			(stroke
				(width 0.1)
				(type default)
			)
			(layer "F.Fab")
		)
		(fp_line
			(start -0.12065 -0.305054)
			(end -0.12065 -0.2794)
			(stroke
				(width 0.1)
				(type default)
			)
			(layer "F.Fab")
		)
		(fp_line
			(start -0.12065 -0.2794)
			(end 0.12065 -0.2794)
			(stroke
				(width 0.1)
				(type default)
			)
			(layer "F.Fab")
		)
		(fp_line
			(start -0.12065 0.2794)
			(end -0.12065 0.3048)
			(stroke
				(width 0.1)
				(type default)
			)
			(layer "F.Fab")
		)
		(fp_line
			(start -0.12065 0.3048)
			(end -0.67945 0.3048)
			(stroke
				(width 0.1)
				(type default)
			)
			(layer "F.Fab")
		)
		(fp_line
			(start 0.120396 0.2794)
			(end -0.12065 0.2794)
			(stroke
				(width 0.1)
				(type default)
			)
			(layer "F.Fab")
		)
		(fp_line
			(start 0.120396 0.3048)
			(end 0.120396 0.2794)
			(stroke
				(width 0.1)
				(type default)
			)
			(layer "F.Fab")
		)
		(fp_line
			(start 0.12065 -0.3048)
			(end 0.67945 -0.3048)
			(stroke
				(width 0.1)
				(type default)
			)
			(layer "F.Fab")
		)
		(fp_line
			(start 0.12065 -0.2794)
			(end 0.12065 -0.3048)
			(stroke
				(width 0.1)
				(type default)
			)
			(layer "F.Fab")
		)
		(fp_line
			(start 0.67945 -0.3048)
			(end 0.67945 0.3048)
			(stroke
				(width 0.1)
				(type default)
			)
			(layer "F.Fab")
		)
		(fp_line
			(start 0.67945 0.3048)
			(end 0.120396 0.3048)
			(stroke
				(width 0.1)
				(type default)
			)
			(layer "F.Fab")
		)
		(pad "1" smd circle
			(at -0.40005 0)
			(size 0 0)
			(layers "F.Cu" "F.Mask" "F.Paste")
			(net "GND")
		)
		(pad "2" smd circle
			(at 0.40005 0)
			(size 0 0)
			(layers "F.Cu" "F.Mask" "F.Paste")
			(net "PWRGD_PVDDCR_CPU0_P1")
		)
	)
	(footprint ""
		(layer "F.Cu")
		(at 187.892182 -28.258008 180)
		(property "Reference" "PC2233"
			(at 0 0 180)
			(layer "F.SilkS")
			(hide yes)
			(effects
				(font
					(size 1.27 1.27)
				)
			)
		)
		(property "Value" ""
			(at 0 0 180)
			(layer "F.Fab")
			(effects
				(font
					(size 1.27 1.27)
				)
			)
		)
		(duplicate_pad_numbers_are_jumpers no)
		(fp_line
			(start 0.7874 0.4064)
			(end -0.7874 0.4064)
			(stroke
				(width 0.1524)
				(type default)
			)
			(layer "F.SilkS")
		)
		(fp_line
			(start 0.7874 -0.4064)
			(end 0.7874 0.4064)
			(stroke
				(width 0.1524)
				(type default)
			)
			(layer "F.SilkS")
		)
		(fp_line
			(start -0.7874 0.4064)
			(end -0.7874 -0.4064)
			(stroke
				(width 0.1524)
				(type default)
			)
			(layer "F.SilkS")
		)
		(fp_line
			(start -0.7874 -0.4064)
			(end 0.7874 -0.4064)
			(stroke
				(width 0.1524)
				(type default)
			)
			(layer "F.SilkS")
		)
		(fp_line
			(start 0.67945 0.3048)
			(end 0.120396 0.3048)
			(stroke
				(width 0.1)
				(type default)
			)
			(layer "F.Fab")
		)
		(fp_line
			(start 0.67945 -0.3048)
			(end 0.67945 0.3048)
			(stroke
				(width 0.1)
				(type default)
			)
			(layer "F.Fab")
		)
		(fp_line
			(start 0.12065 -0.2794)
			(end 0.12065 -0.3048)
			(stroke
				(width 0.1)
				(type default)
			)
			(layer "F.Fab")
		)
		(fp_line
			(start 0.12065 -0.3048)
			(end 0.67945 -0.3048)
			(stroke
				(width 0.1)
				(type default)
			)
			(layer "F.Fab")
		)
		(fp_line
			(start 0.120396 0.3048)
			(end 0.120396 0.2794)
			(stroke
				(width 0.1)
				(type default)
			)
			(layer "F.Fab")
		)
		(fp_line
			(start 0.120396 0.2794)
			(end -0.12065 0.2794)
			(stroke
				(width 0.1)
				(type default)
			)
			(layer "F.Fab")
		)
		(fp_line
			(start -0.12065 0.3048)
			(end -0.67945 0.3048)
			(stroke
				(width 0.1)
				(type default)
			)
			(layer "F.Fab")
		)
		(fp_line
			(start -0.12065 0.2794)
			(end -0.12065 0.3048)
			(stroke
				(width 0.1)
				(type default)
			)
			(layer "F.Fab")
		)
		(fp_line
			(start -0.12065 -0.2794)
			(end 0.12065 -0.2794)
			(stroke
				(width 0.1)
				(type default)
			)
			(layer "F.Fab")
		)
		(fp_line
			(start -0.12065 -0.305054)
			(end -0.12065 -0.2794)
			(stroke
				(width 0.1)
				(type default)
			)
			(layer "F.Fab")
		)
		(fp_line
			(start -0.67945 0.3048)
			(end -0.67945 -0.305054)
			(stroke
				(width 0.1)
				(type default)
			)
			(layer "F.Fab")
		)
		(fp_line
			(start -0.67945 -0.305054)
			(end -0.12065 -0.305054)
			(stroke
				(width 0.1)
				(type default)
			)
			(layer "F.Fab")
		)
		(pad "1" smd circle
			(at -0.40005 0 180)
			(size 0 0)
			(layers "F.Cu" "F.Mask" "F.Paste")
			(net "P12V_SCM_VCC")
		)
		(pad "2" smd circle
			(at 0.40005 0 180)
			(size 0 0)
			(layers "F.Cu" "F.Mask" "F.Paste")
			(net "GND")
		)
	)
	(footprint ""
		(layer "F.Cu")
		(at 412.481268 -70.74408)
		(property "Reference" "R1500"
			(at 0 0 0)
			(layer "F.SilkS")
			(hide yes)
			(effects
				(font
					(size 1.27 1.27)
				)
			)
		)
		(property "Value" ""
			(at 0 0 0)
			(layer "F.Fab")
			(effects
				(font
					(size 1.27 1.27)
				)
			)
		)
		(duplicate_pad_numbers_are_jumpers no)
		(fp_line
			(start -0.7874 -0.4064)
			(end 0.7874 -0.4064)
			(stroke
				(width 0.1524)
				(type default)
			)
			(layer "F.SilkS")
		)
		(fp_line
			(start -0.7874 0.4064)
			(end -0.7874 -0.4064)
			(stroke
				(width 0.1524)
				(type default)
			)
			(layer "F.SilkS")
		)
		(fp_line
			(start 0.7874 -0.4064)
			(end 0.7874 0.4064)
			(stroke
				(width 0.1524)
				(type default)
			)
			(layer "F.SilkS")
		)
		(fp_line
			(start 0.7874 0.4064)
			(end -0.7874 0.4064)
			(stroke
				(width 0.1524)
				(type default)
			)
			(layer "F.SilkS")
		)
		(fp_line
			(start -0.67945 -0.305054)
			(end -0.12065 -0.305054)
			(stroke
				(width 0.1)
				(type default)
			)
			(layer "F.Fab")
		)
		(fp_line
			(start -0.67945 0.3048)
			(end -0.67945 -0.305054)
			(stroke
				(width 0.1)
				(type default)
			)
			(layer "F.Fab")
		)
		(fp_line
			(start -0.12065 -0.305054)
			(end -0.12065 -0.2794)
			(stroke
				(width 0.1)
				(type default)
			)
			(layer "F.Fab")
		)
		(fp_line
			(start -0.12065 -0.2794)
			(end 0.12065 -0.2794)
			(stroke
				(width 0.1)
				(type default)
			)
			(layer "F.Fab")
		)
		(fp_line
			(start -0.12065 0.2794)
			(end -0.12065 0.3048)
			(stroke
				(width 0.1)
				(type default)
			)
			(layer "F.Fab")
		)
		(fp_line
			(start -0.12065 0.3048)
			(end -0.67945 0.3048)
			(stroke
				(width 0.1)
				(type default)
			)
			(layer "F.Fab")
		)
		(fp_line
			(start 0.120396 0.2794)
			(end -0.12065 0.2794)
			(stroke
				(width 0.1)
				(type default)
			)
			(layer "F.Fab")
		)
		(fp_line
			(start 0.120396 0.3048)
			(end 0.120396 0.2794)
			(stroke
				(width 0.1)
				(type default)
			)
			(layer "F.Fab")
		)
		(fp_line
			(start 0.12065 -0.3048)
			(end 0.67945 -0.3048)
			(stroke
				(width 0.1)
				(type default)
			)
			(layer "F.Fab")
		)
		(fp_line
			(start 0.12065 -0.2794)
			(end 0.12065 -0.3048)
			(stroke
				(width 0.1)
				(type default)
			)
			(layer "F.Fab")
		)
		(fp_line
			(start 0.67945 -0.3048)
			(end 0.67945 0.3048)
			(stroke
				(width 0.1)
				(type default)
			)
			(layer "F.Fab")
		)
		(fp_line
			(start 0.67945 0.3048)
			(end 0.120396 0.3048)
			(stroke
				(width 0.1)
				(type default)
			)
			(layer "F.Fab")
		)
		(pad "1" smd circle
			(at -0.40005 0)
			(size 0 0)
			(layers "F.Cu" "F.Mask" "F.Paste")
			(net "HP_LVC3_OCP_V3_1_R_EN")
		)
		(pad "2" smd circle
			(at 0.40005 0)
			(size 0 0)
			(layers "F.Cu" "F.Mask" "F.Paste")
			(net "P12V_OCP_SFF_BUF_EN_R")
		)
	)
	(footprint ""
		(layer "F.Cu")
		(at 169.368724 -379.471428)
		(property "Reference" "C743"
			(at 0 0 0)
			(layer "F.SilkS")
			(hide yes)
			(effects
				(font
					(size 1.27 1.27)
				)
			)
		)
		(property "Value" ""
			(at 0 0 0)
			(layer "F.Fab")
			(effects
				(font
					(size 1.27 1.27)
				)
			)
		)
		(duplicate_pad_numbers_are_jumpers no)
		(fp_line
			(start -0.299974 -0.150114)
			(end 0.299974 -0.150114)
			(stroke
				(width 0.1)
				(type default)
			)
			(layer "F.Fab")
		)
		(fp_line
			(start -0.299974 0.150114)
			(end -0.299974 -0.150114)
			(stroke
				(width 0.1)
				(type default)
			)
			(layer "F.Fab")
		)
		(fp_line
			(start 0.299974 -0.150114)
			(end 0.299974 0.150114)
			(stroke
				(width 0.1)
				(type default)
			)
			(layer "F.Fab")
		)
		(fp_line
			(start 0.299974 0.150114)
			(end -0.299974 0.150114)
			(stroke
				(width 0.1)
				(type default)
			)
			(layer "F.Fab")
		)
		(pad "1" smd rect
			(at -0.2667 0)
			(size 0.3048 0.381)
			(layers "F.Cu" "F.Mask" "F.Paste")
			(net "P5E_CPU1_P2_TX_C_DP<15>")
		)
		(pad "2" smd rect
			(at 0.2667 0)
			(size 0.3048 0.381)
			(layers "F.Cu" "F.Mask" "F.Paste")
			(net "P5E_CPU1_P2_TX_DP<15>")
		)
	)
	(footprint ""
		(layer "F.Cu")
		(at 105.92816 -395.55674 180)
		(property "Reference" "R670"
			(at 0 0 180)
			(layer "F.SilkS")
			(hide yes)
			(effects
				(font
					(size 1.27 1.27)
				)
			)
		)
		(property "Value" ""
			(at 0 0 180)
			(layer "F.Fab")
			(effects
				(font
					(size 1.27 1.27)
				)
			)
		)
		(duplicate_pad_numbers_are_jumpers no)
		(fp_line
			(start 0.32512 0.175006)
			(end -0.32512 0.175006)
			(stroke
				(width 0.1)
				(type default)
			)
			(layer "F.Fab")
		)
		(fp_line
			(start 0.32512 -0.175006)
			(end 0.32512 0.175006)
			(stroke
				(width 0.1)
				(type default)
			)
			(layer "F.Fab")
		)
		(fp_line
			(start -0.32512 0.175006)
			(end -0.32512 -0.175006)
			(stroke
				(width 0.1)
				(type default)
			)
			(layer "F.Fab")
		)
		(fp_line
			(start -0.32512 -0.175006)
			(end 0.32512 -0.175006)
			(stroke
				(width 0.1)
				(type default)
			)
			(layer "F.Fab")
		)
		(pad "1" smd rect
			(at -0.2667 0 180)
			(size 0.3048 0.381)
			(layers "F.Cu" "F.Mask" "F.Paste")
			(net "SMB_RT_CPU1_P1_ROM_MUX_1D_SCL")
		)
		(pad "2" smd rect
			(at 0.2667 0)
			(size 0.3048 0.381)
			(layers "F.Cu" "F.Mask" "F.Paste")
			(net "SMB_RT_CPU1_P1_ROM_MUX_1D_R_SCL")
		)
	)
	(footprint ""
		(layer "F.Cu")
		(at 401.471638 -168.510966 90)
		(property "Reference" "PC586_2"
			(at 0 0 90)
			(layer "F.SilkS")
			(hide yes)
			(effects
				(font
					(size 1.27 1.27)
				)
			)
		)
		(property "Value" ""
			(at 0 0 90)
			(layer "F.Fab")
			(effects
				(font
					(size 1.27 1.27)
				)
			)
		)
		(duplicate_pad_numbers_are_jumpers no)
		(fp_line
			(start 0.7874 -0.4064)
			(end 0.7874 0.4064)
			(stroke
				(width 0.1524)
				(type default)
			)
			(layer "F.SilkS")
		)
		(fp_line
			(start -0.7874 -0.4064)
			(end 0.7874 -0.4064)
			(stroke
				(width 0.1524)
				(type default)
			)
			(layer "F.SilkS")
		)
		(fp_line
			(start 0.7874 0.4064)
			(end -0.7874 0.4064)
			(stroke
				(width 0.1524)
				(type default)
			)
			(layer "F.SilkS")
		)
		(fp_line
			(start -0.7874 0.4064)
			(end -0.7874 -0.4064)
			(stroke
				(width 0.1524)
				(type default)
			)
			(layer "F.SilkS")
		)
		(fp_line
			(start -0.12065 -0.305054)
			(end -0.12065 -0.2794)
			(stroke
				(width 0.1)
				(type default)
			)
			(layer "F.Fab")
		)
		(fp_line
			(start -0.67945 -0.305054)
			(end -0.12065 -0.305054)
			(stroke
				(width 0.1)
				(type default)
			)
			(layer "F.Fab")
		)
		(fp_line
			(start 0.67945 -0.3048)
			(end 0.67945 0.3048)
			(stroke
				(width 0.1)
				(type default)
			)
			(layer "F.Fab")
		)
		(fp_line
			(start 0.12065 -0.3048)
			(end 0.67945 -0.3048)
			(stroke
				(width 0.1)
				(type default)
			)
			(layer "F.Fab")
		)
		(fp_line
			(start 0.12065 -0.2794)
			(end 0.12065 -0.3048)
			(stroke
				(width 0.1)
				(type default)
			)
			(layer "F.Fab")
		)
		(fp_line
			(start -0.12065 -0.2794)
			(end 0.12065 -0.2794)
			(stroke
				(width 0.1)
				(type default)
			)
			(layer "F.Fab")
		)
		(fp_line
			(start 0.120396 0.2794)
			(end -0.12065 0.2794)
			(stroke
				(width 0.1)
				(type default)
			)
			(layer "F.Fab")
		)
		(fp_line
			(start -0.12065 0.2794)
			(end -0.12065 0.3048)
			(stroke
				(width 0.1)
				(type default)
			)
			(layer "F.Fab")
		)
		(fp_line
			(start 0.67945 0.3048)
			(end 0.120396 0.3048)
			(stroke
				(width 0.1)
				(type default)
			)
			(layer "F.Fab")
		)
		(fp_line
			(start 0.120396 0.3048)
			(end 0.120396 0.2794)
			(stroke
				(width 0.1)
				(type default)
			)
			(layer "F.Fab")
		)
		(fp_line
			(start -0.12065 0.3048)
			(end -0.67945 0.3048)
			(stroke
				(width 0.1)
				(type default)
			)
			(layer "F.Fab")
		)
		(fp_line
			(start -0.67945 0.3048)
			(end -0.67945 -0.305054)
			(stroke
				(width 0.1)
				(type default)
			)
			(layer "F.Fab")
		)
		(pad "1" smd circle
			(at -0.40005 0 90)
			(size 0 0)
			(layers "F.Cu" "F.Mask" "F.Paste")
			(net "SW_P12V_AUX_PVDDCR_SOC_P0_FLT")
		)
		(pad "2" smd circle
			(at 0.40005 0 90)
			(size 0 0)
			(layers "F.Cu" "F.Mask" "F.Paste")
			(net "GND")
		)
	)
	(footprint ""
		(layer "F.Cu")
		(at 414.668462 -416.899344 -90)
		(property "Reference" "C6593"
			(at 0 0 270)
			(layer "F.SilkS")
			(hide yes)
			(effects
				(font
					(size 1.27 1.27)
				)
			)
		)
		(property "Value" ""
			(at 0 0 270)
			(layer "F.Fab")
			(effects
				(font
					(size 1.27 1.27)
				)
			)
		)
		(duplicate_pad_numbers_are_jumpers no)
		(fp_line
			(start -0.299974 0.150114)
			(end -0.299974 -0.150114)
			(stroke
				(width 0.1)
				(type default)
			)
			(layer "F.Fab")
		)
		(fp_line
			(start 0.299974 0.150114)
			(end -0.299974 0.150114)
			(stroke
				(width 0.1)
				(type default)
			)
			(layer "F.Fab")
		)
		(fp_line
			(start -0.299974 -0.150114)
			(end 0.299974 -0.150114)
			(stroke
				(width 0.1)
				(type default)
			)
			(layer "F.Fab")
		)
		(fp_line
			(start 0.299974 -0.150114)
			(end 0.299974 0.150114)
			(stroke
				(width 0.1)
				(type default)
			)
			(layer "F.Fab")
		)
		(pad "1" smd rect
			(at -0.2667 0 270)
			(size 0.3048 0.381)
			(layers "F.Cu" "F.Mask" "F.Paste")
			(net "P5E_CPU0_P2_TX_BUF_C_DP<14>")
		)
		(pad "2" smd rect
			(at 0.2667 0 270)
			(size 0.3048 0.381)
			(layers "F.Cu" "F.Mask" "F.Paste")
			(net "P5E_CPU0_P2_TX_BUF_DP<14>")
		)
	)
	(footprint ""
		(layer "F.Cu")
		(at 305.013106 -349.381572 90)
		(property "Reference" "PC109"
			(at 0 0 90)
			(layer "F.SilkS")
			(hide yes)
			(effects
				(font
					(size 1.27 1.27)
				)
			)
		)
		(property "Value" ""
			(at 0 0 90)
			(layer "F.Fab")
			(effects
				(font
					(size 1.27 1.27)
				)
			)
		)
		(duplicate_pad_numbers_are_jumpers no)
		(fp_line
			(start 0.7874 -0.4064)
			(end 0.7874 0.4064)
			(stroke
				(width 0.1524)
				(type default)
			)
			(layer "F.SilkS")
		)
		(fp_line
			(start -0.7874 -0.4064)
			(end 0.7874 -0.4064)
			(stroke
				(width 0.1524)
				(type default)
			)
			(layer "F.SilkS")
		)
		(fp_line
			(start 0.7874 0.4064)
			(end 0.376428 0.4064)
			(stroke
				(width 0.1524)
				(type default)
			)
			(layer "F.SilkS")
		)
		(fp_line
			(start -0.156972 0.4064)
			(end -0.7874 0.4064)
			(stroke
				(width 0.1524)
				(type default)
			)
			(layer "F.SilkS")
		)
		(fp_line
			(start -0.7874 0.4064)
			(end -0.7874 -0.4064)
			(stroke
				(width 0.1524)
				(type default)
			)
			(layer "F.SilkS")
		)
		(fp_line
			(start -0.12065 -0.305054)
			(end -0.12065 -0.2794)
			(stroke
				(width 0.1)
				(type default)
			)
			(layer "F.Fab")
		)
		(fp_line
			(start -0.67945 -0.305054)
			(end -0.12065 -0.305054)
			(stroke
				(width 0.1)
				(type default)
			)
			(layer "F.Fab")
		)
		(fp_line
			(start 0.67945 -0.3048)
			(end 0.67945 0.3048)
			(stroke
				(width 0.1)
				(type default)
			)
			(layer "F.Fab")
		)
		(fp_line
			(start 0.12065 -0.3048)
			(end 0.67945 -0.3048)
			(stroke
				(width 0.1)
				(type default)
			)
			(layer "F.Fab")
		)
		(fp_line
			(start 0.12065 -0.2794)
			(end 0.12065 -0.3048)
			(stroke
				(width 0.1)
				(type default)
			)
			(layer "F.Fab")
		)
		(fp_line
			(start -0.12065 -0.2794)
			(end 0.12065 -0.2794)
			(stroke
				(width 0.1)
				(type default)
			)
			(layer "F.Fab")
		)
		(fp_line
			(start 0.120396 0.2794)
			(end -0.12065 0.2794)
			(stroke
				(width 0.1)
				(type default)
			)
			(layer "F.Fab")
		)
		(fp_line
			(start -0.12065 0.2794)
			(end -0.12065 0.3048)
			(stroke
				(width 0.1)
				(type default)
			)
			(layer "F.Fab")
		)
		(fp_line
			(start 0.67945 0.3048)
			(end 0.120396 0.3048)
			(stroke
				(width 0.1)
				(type default)
			)
			(layer "F.Fab")
		)
		(fp_line
			(start 0.120396 0.3048)
			(end 0.120396 0.2794)
			(stroke
				(width 0.1)
				(type default)
			)
			(layer "F.Fab")
		)
		(fp_line
			(start -0.12065 0.3048)
			(end -0.67945 0.3048)
			(stroke
				(width 0.1)
				(type default)
			)
			(layer "F.Fab")
		)
		(fp_line
			(start -0.67945 0.3048)
			(end -0.67945 -0.305054)
			(stroke
				(width 0.1)
				(type default)
			)
			(layer "F.Fab")
		)
		(pad "1" smd circle
			(at -0.40005 0 90)
			(size 0 0)
			(layers "F.Cu" "F.Mask" "F.Paste")
			(net "PVDDCR_CPU1_P0_VCC4")
		)
		(pad "2" smd circle
			(at 0.40005 0 90)
			(size 0 0)
			(layers "F.Cu" "F.Mask" "F.Paste")
			(net "GND")
		)
	)
	(footprint ""
		(layer "F.Cu")
		(at 277.352252 -118.89867)
		(property "Reference" "R3583"
			(at 0 0 0)
			(layer "F.SilkS")
			(hide yes)
			(effects
				(font
					(size 1.27 1.27)
				)
			)
		)
		(property "Value" ""
			(at 0 0 0)
			(layer "F.Fab")
			(effects
				(font
					(size 1.27 1.27)
				)
			)
		)
		(duplicate_pad_numbers_are_jumpers no)
		(fp_line
			(start -0.7874 -0.4064)
			(end 0.7874 -0.4064)
			(stroke
				(width 0.1524)
				(type default)
			)
			(layer "F.SilkS")
		)
		(fp_line
			(start -0.7874 0.4064)
			(end -0.7874 -0.4064)
			(stroke
				(width 0.1524)
				(type default)
			)
			(layer "F.SilkS")
		)
		(fp_line
			(start 0.7874 -0.4064)
			(end 0.7874 0.4064)
			(stroke
				(width 0.1524)
				(type default)
			)
			(layer "F.SilkS")
		)
		(fp_line
			(start 0.7874 0.4064)
			(end -0.7874 0.4064)
			(stroke
				(width 0.1524)
				(type default)
			)
			(layer "F.SilkS")
		)
		(fp_line
			(start -0.67945 -0.305054)
			(end -0.12065 -0.305054)
			(stroke
				(width 0.1)
				(type default)
			)
			(layer "F.Fab")
		)
		(fp_line
			(start -0.67945 0.3048)
			(end -0.67945 -0.305054)
			(stroke
				(width 0.1)
				(type default)
			)
			(layer "F.Fab")
		)
		(fp_line
			(start -0.12065 -0.305054)
			(end -0.12065 -0.2794)
			(stroke
				(width 0.1)
				(type default)
			)
			(layer "F.Fab")
		)
		(fp_line
			(start -0.12065 -0.2794)
			(end 0.12065 -0.2794)
			(stroke
				(width 0.1)
				(type default)
			)
			(layer "F.Fab")
		)
		(fp_line
			(start -0.12065 0.2794)
			(end -0.12065 0.3048)
			(stroke
				(width 0.1)
				(type default)
			)
			(layer "F.Fab")
		)
		(fp_line
			(start -0.12065 0.3048)
			(end -0.67945 0.3048)
			(stroke
				(width 0.1)
				(type default)
			)
			(layer "F.Fab")
		)
		(fp_line
			(start 0.120396 0.2794)
			(end -0.12065 0.2794)
			(stroke
				(width 0.1)
				(type default)
			)
			(layer "F.Fab")
		)
		(fp_line
			(start 0.120396 0.3048)
			(end 0.120396 0.2794)
			(stroke
				(width 0.1)
				(type default)
			)
			(layer "F.Fab")
		)
		(fp_line
			(start 0.12065 -0.3048)
			(end 0.67945 -0.3048)
			(stroke
				(width 0.1)
				(type default)
			)
			(layer "F.Fab")
		)
		(fp_line
			(start 0.12065 -0.2794)
			(end 0.12065 -0.3048)
			(stroke
				(width 0.1)
				(type default)
			)
			(layer "F.Fab")
		)
		(fp_line
			(start 0.67945 -0.3048)
			(end 0.67945 0.3048)
			(stroke
				(width 0.1)
				(type default)
			)
			(layer "F.Fab")
		)
		(fp_line
			(start 0.67945 0.3048)
			(end 0.120396 0.3048)
			(stroke
				(width 0.1)
				(type default)
			)
			(layer "F.Fab")
		)
		(pad "1" smd circle
			(at -0.40005 0)
			(size 0 0)
			(layers "F.Cu" "F.Mask" "F.Paste")
			(net "P3V3_AUX")
		)
		(pad "2" smd circle
			(at 0.40005 0)
			(size 0 0)
			(layers "F.Cu" "F.Mask" "F.Paste")
			(net "SMB_IOEXP_3V3AUX_SDA")
		)
	)
	(footprint ""
		(layer "F.Cu")
		(at 123.725178 -72.829166 90)
		(property "Reference" "R6244"
			(at 0 0 90)
			(layer "F.SilkS")
			(hide yes)
			(effects
				(font
					(size 1.27 1.27)
				)
			)
		)
		(property "Value" ""
			(at 0 0 90)
			(layer "F.Fab")
			(effects
				(font
					(size 1.27 1.27)
				)
			)
		)
		(duplicate_pad_numbers_are_jumpers no)
		(fp_line
			(start 0.7874 -0.4064)
			(end 0.7874 0.4064)
			(stroke
				(width 0.1524)
				(type default)
			)
			(layer "F.SilkS")
		)
		(fp_line
			(start -0.7874 -0.4064)
			(end 0.7874 -0.4064)
			(stroke
				(width 0.1524)
				(type default)
			)
			(layer "F.SilkS")
		)
		(fp_line
			(start 0.7874 0.4064)
			(end -0.7874 0.4064)
			(stroke
				(width 0.1524)
				(type default)
			)
			(layer "F.SilkS")
		)
		(fp_line
			(start -0.7874 0.4064)
			(end -0.7874 -0.4064)
			(stroke
				(width 0.1524)
				(type default)
			)
			(layer "F.SilkS")
		)
		(fp_line
			(start -0.12065 -0.305054)
			(end -0.12065 -0.2794)
			(stroke
				(width 0.1)
				(type default)
			)
			(layer "F.Fab")
		)
		(fp_line
			(start -0.67945 -0.305054)
			(end -0.12065 -0.305054)
			(stroke
				(width 0.1)
				(type default)
			)
			(layer "F.Fab")
		)
		(fp_line
			(start 0.67945 -0.3048)
			(end 0.67945 0.3048)
			(stroke
				(width 0.1)
				(type default)
			)
			(layer "F.Fab")
		)
		(fp_line
			(start 0.12065 -0.3048)
			(end 0.67945 -0.3048)
			(stroke
				(width 0.1)
				(type default)
			)
			(layer "F.Fab")
		)
		(fp_line
			(start 0.12065 -0.2794)
			(end 0.12065 -0.3048)
			(stroke
				(width 0.1)
				(type default)
			)
			(layer "F.Fab")
		)
		(fp_line
			(start -0.12065 -0.2794)
			(end 0.12065 -0.2794)
			(stroke
				(width 0.1)
				(type default)
			)
			(layer "F.Fab")
		)
		(fp_line
			(start 0.120396 0.2794)
			(end -0.12065 0.2794)
			(stroke
				(width 0.1)
				(type default)
			)
			(layer "F.Fab")
		)
		(fp_line
			(start -0.12065 0.2794)
			(end -0.12065 0.3048)
			(stroke
				(width 0.1)
				(type default)
			)
			(layer "F.Fab")
		)
		(fp_line
			(start 0.67945 0.3048)
			(end 0.120396 0.3048)
			(stroke
				(width 0.1)
				(type default)
			)
			(layer "F.Fab")
		)
		(fp_line
			(start 0.120396 0.3048)
			(end 0.120396 0.2794)
			(stroke
				(width 0.1)
				(type default)
			)
			(layer "F.Fab")
		)
		(fp_line
			(start -0.12065 0.3048)
			(end -0.67945 0.3048)
			(stroke
				(width 0.1)
				(type default)
			)
			(layer "F.Fab")
		)
		(fp_line
			(start -0.67945 0.3048)
			(end -0.67945 -0.305054)
			(stroke
				(width 0.1)
				(type default)
			)
			(layer "F.Fab")
		)
		(pad "1" smd circle
			(at -0.40005 0 90)
			(size 0 0)
			(layers "F.Cu" "F.Mask" "F.Paste")
			(net "P3V3_AUX")
		)
		(pad "2" smd circle
			(at 0.40005 0 90)
			(size 0 0)
			(layers "F.Cu" "F.Mask" "F.Paste")
			(net "PWRGD_P1V2_AUX")
		)
	)
	(footprint ""
		(layer "F.Cu")
		(at 439.272172 -32.173418 90)
		(property "Reference" "PC2156"
			(at 0 0 90)
			(layer "F.SilkS")
			(hide yes)
			(effects
				(font
					(size 1.27 1.27)
				)
			)
		)
		(property "Value" ""
			(at 0 0 90)
			(layer "F.Fab")
			(effects
				(font
					(size 1.27 1.27)
				)
			)
		)
		(duplicate_pad_numbers_are_jumpers no)
		(fp_line
			(start 0.7874 -0.4064)
			(end 0.7874 0.4064)
			(stroke
				(width 0.1524)
				(type default)
			)
			(layer "F.SilkS")
		)
		(fp_line
			(start -0.7874 -0.4064)
			(end 0.7874 -0.4064)
			(stroke
				(width 0.1524)
				(type default)
			)
			(layer "F.SilkS")
		)
		(fp_line
			(start 0.7874 0.4064)
			(end -0.7874 0.4064)
			(stroke
				(width 0.1524)
				(type default)
			)
			(layer "F.SilkS")
		)
		(fp_line
			(start -0.7874 0.4064)
			(end -0.7874 -0.4064)
			(stroke
				(width 0.1524)
				(type default)
			)
			(layer "F.SilkS")
		)
		(fp_line
			(start -0.12065 -0.305054)
			(end -0.12065 -0.2794)
			(stroke
				(width 0.1)
				(type default)
			)
			(layer "F.Fab")
		)
		(fp_line
			(start -0.67945 -0.305054)
			(end -0.12065 -0.305054)
			(stroke
				(width 0.1)
				(type default)
			)
			(layer "F.Fab")
		)
		(fp_line
			(start 0.67945 -0.3048)
			(end 0.67945 0.3048)
			(stroke
				(width 0.1)
				(type default)
			)
			(layer "F.Fab")
		)
		(fp_line
			(start 0.12065 -0.3048)
			(end 0.67945 -0.3048)
			(stroke
				(width 0.1)
				(type default)
			)
			(layer "F.Fab")
		)
		(fp_line
			(start 0.12065 -0.2794)
			(end 0.12065 -0.3048)
			(stroke
				(width 0.1)
				(type default)
			)
			(layer "F.Fab")
		)
		(fp_line
			(start -0.12065 -0.2794)
			(end 0.12065 -0.2794)
			(stroke
				(width 0.1)
				(type default)
			)
			(layer "F.Fab")
		)
		(fp_line
			(start 0.120396 0.2794)
			(end -0.12065 0.2794)
			(stroke
				(width 0.1)
				(type default)
			)
			(layer "F.Fab")
		)
		(fp_line
			(start -0.12065 0.2794)
			(end -0.12065 0.3048)
			(stroke
				(width 0.1)
				(type default)
			)
			(layer "F.Fab")
		)
		(fp_line
			(start 0.67945 0.3048)
			(end 0.120396 0.3048)
			(stroke
				(width 0.1)
				(type default)
			)
			(layer "F.Fab")
		)
		(fp_line
			(start 0.120396 0.3048)
			(end 0.120396 0.2794)
			(stroke
				(width 0.1)
				(type default)
			)
			(layer "F.Fab")
		)
		(fp_line
			(start -0.12065 0.3048)
			(end -0.67945 0.3048)
			(stroke
				(width 0.1)
				(type default)
			)
			(layer "F.Fab")
		)
		(fp_line
			(start -0.67945 0.3048)
			(end -0.67945 -0.305054)
			(stroke
				(width 0.1)
				(type default)
			)
			(layer "F.Fab")
		)
		(pad "1" smd circle
			(at -0.40005 0 90)
			(size 0 0)
			(layers "F.Cu" "F.Mask" "F.Paste")
			(net "P12V_OCP_IMON_1")
		)
		(pad "2" smd circle
			(at 0.40005 0 90)
			(size 0 0)
			(layers "F.Cu" "F.Mask" "F.Paste")
			(net "GND")
		)
	)
	(footprint ""
		(layer "F.Cu")
		(at 298.967144 -390.77646 180)
		(property "Reference" "C933"
			(at 0 0 180)
			(layer "F.SilkS")
			(hide yes)
			(effects
				(font
					(size 1.27 1.27)
				)
			)
		)
		(property "Value" ""
			(at 0 0 180)
			(layer "F.Fab")
			(effects
				(font
					(size 1.27 1.27)
				)
			)
		)
		(duplicate_pad_numbers_are_jumpers no)
		(fp_line
			(start 0.299974 0.150114)
			(end -0.299974 0.150114)
			(stroke
				(width 0.1)
				(type default)
			)
			(layer "F.Fab")
		)
		(fp_line
			(start 0.299974 -0.150114)
			(end 0.299974 0.150114)
			(stroke
				(width 0.1)
				(type default)
			)
			(layer "F.Fab")
		)
		(fp_line
			(start -0.299974 0.150114)
			(end -0.299974 -0.150114)
			(stroke
				(width 0.1)
				(type default)
			)
			(layer "F.Fab")
		)
		(fp_line
			(start -0.299974 -0.150114)
			(end 0.299974 -0.150114)
			(stroke
				(width 0.1)
				(type default)
			)
			(layer "F.Fab")
		)
		(pad "1" smd rect
			(at -0.2667 0 180)
			(size 0.3048 0.381)
			(layers "F.Cu" "F.Mask" "F.Paste")
			(net "P5E_CPU0_P0_TX_C_DP<0>")
		)
		(pad "2" smd rect
			(at 0.2667 0 180)
			(size 0.3048 0.381)
			(layers "F.Cu" "F.Mask" "F.Paste")
			(net "P5E_CPU0_P0_TX_DP<0>")
		)
	)
	(footprint ""
		(layer "F.Cu")
		(at 196.342 -137.632948 90)
		(property "Reference" "R1556"
			(at 0 0 90)
			(layer "F.SilkS")
			(hide yes)
			(effects
				(font
					(size 1.27 1.27)
				)
			)
		)
		(property "Value" ""
			(at 0 0 90)
			(layer "F.Fab")
			(effects
				(font
					(size 1.27 1.27)
				)
			)
		)
		(duplicate_pad_numbers_are_jumpers no)
		(fp_line
			(start 0.7874 -0.4064)
			(end 0.7874 0.4064)
			(stroke
				(width 0.1524)
				(type default)
			)
			(layer "F.SilkS")
		)
		(fp_line
			(start -0.7874 -0.4064)
			(end 0.7874 -0.4064)
			(stroke
				(width 0.1524)
				(type default)
			)
			(layer "F.SilkS")
		)
		(fp_line
			(start 0.7874 0.4064)
			(end -0.7874 0.4064)
			(stroke
				(width 0.1524)
				(type default)
			)
			(layer "F.SilkS")
		)
		(fp_line
			(start -0.7874 0.4064)
			(end -0.7874 -0.4064)
			(stroke
				(width 0.1524)
				(type default)
			)
			(layer "F.SilkS")
		)
		(fp_line
			(start -0.12065 -0.305054)
			(end -0.12065 -0.2794)
			(stroke
				(width 0.1)
				(type default)
			)
			(layer "F.Fab")
		)
		(fp_line
			(start -0.67945 -0.305054)
			(end -0.12065 -0.305054)
			(stroke
				(width 0.1)
				(type default)
			)
			(layer "F.Fab")
		)
		(fp_line
			(start 0.67945 -0.3048)
			(end 0.67945 0.3048)
			(stroke
				(width 0.1)
				(type default)
			)
			(layer "F.Fab")
		)
		(fp_line
			(start 0.12065 -0.3048)
			(end 0.67945 -0.3048)
			(stroke
				(width 0.1)
				(type default)
			)
			(layer "F.Fab")
		)
		(fp_line
			(start 0.12065 -0.2794)
			(end 0.12065 -0.3048)
			(stroke
				(width 0.1)
				(type default)
			)
			(layer "F.Fab")
		)
		(fp_line
			(start -0.12065 -0.2794)
			(end 0.12065 -0.2794)
			(stroke
				(width 0.1)
				(type default)
			)
			(layer "F.Fab")
		)
		(fp_line
			(start 0.120396 0.2794)
			(end -0.12065 0.2794)
			(stroke
				(width 0.1)
				(type default)
			)
			(layer "F.Fab")
		)
		(fp_line
			(start -0.12065 0.2794)
			(end -0.12065 0.3048)
			(stroke
				(width 0.1)
				(type default)
			)
			(layer "F.Fab")
		)
		(fp_line
			(start 0.67945 0.3048)
			(end 0.120396 0.3048)
			(stroke
				(width 0.1)
				(type default)
			)
			(layer "F.Fab")
		)
		(fp_line
			(start 0.120396 0.3048)
			(end 0.120396 0.2794)
			(stroke
				(width 0.1)
				(type default)
			)
			(layer "F.Fab")
		)
		(fp_line
			(start -0.12065 0.3048)
			(end -0.67945 0.3048)
			(stroke
				(width 0.1)
				(type default)
			)
			(layer "F.Fab")
		)
		(fp_line
			(start -0.67945 0.3048)
			(end -0.67945 -0.305054)
			(stroke
				(width 0.1)
				(type default)
			)
			(layer "F.Fab")
		)
		(pad "1" smd circle
			(at -0.40005 0 90)
			(size 0 0)
			(layers "F.Cu" "F.Mask" "F.Paste")
			(net "CLK_ESPI_CPU0_R1_CLK1")
		)
		(pad "2" smd circle
			(at 0.40005 0 90)
			(size 0 0)
			(layers "F.Cu" "F.Mask" "F.Paste")
			(net "CLK_ESPI_CPU0_CLK1")
		)
	)
	(footprint ""
		(layer "F.Cu")
		(at 435.102 -166.751 90)
		(property "Reference" "R1299"
			(at 0 0 90)
			(layer "F.SilkS")
			(hide yes)
			(effects
				(font
					(size 1.27 1.27)
				)
			)
		)
		(property "Value" ""
			(at 0 0 90)
			(layer "F.Fab")
			(effects
				(font
					(size 1.27 1.27)
				)
			)
		)
		(duplicate_pad_numbers_are_jumpers no)
		(fp_line
			(start 0.7874 -0.4064)
			(end 0.7874 0.4064)
			(stroke
				(width 0.1524)
				(type default)
			)
			(layer "F.SilkS")
		)
		(fp_line
			(start -0.7874 -0.4064)
			(end 0.7874 -0.4064)
			(stroke
				(width 0.1524)
				(type default)
			)
			(layer "F.SilkS")
		)
		(fp_line
			(start 0.7874 0.4064)
			(end -0.7874 0.4064)
			(stroke
				(width 0.1524)
				(type default)
			)
			(layer "F.SilkS")
		)
		(fp_line
			(start -0.7874 0.4064)
			(end -0.7874 -0.4064)
			(stroke
				(width 0.1524)
				(type default)
			)
			(layer "F.SilkS")
		)
		(fp_line
			(start -0.12065 -0.305054)
			(end -0.12065 -0.2794)
			(stroke
				(width 0.1)
				(type default)
			)
			(layer "F.Fab")
		)
		(fp_line
			(start -0.67945 -0.305054)
			(end -0.12065 -0.305054)
			(stroke
				(width 0.1)
				(type default)
			)
			(layer "F.Fab")
		)
		(fp_line
			(start 0.67945 -0.3048)
			(end 0.67945 0.3048)
			(stroke
				(width 0.1)
				(type default)
			)
			(layer "F.Fab")
		)
		(fp_line
			(start 0.12065 -0.3048)
			(end 0.67945 -0.3048)
			(stroke
				(width 0.1)
				(type default)
			)
			(layer "F.Fab")
		)
		(fp_line
			(start 0.12065 -0.2794)
			(end 0.12065 -0.3048)
			(stroke
				(width 0.1)
				(type default)
			)
			(layer "F.Fab")
		)
		(fp_line
			(start -0.12065 -0.2794)
			(end 0.12065 -0.2794)
			(stroke
				(width 0.1)
				(type default)
			)
			(layer "F.Fab")
		)
		(fp_line
			(start 0.120396 0.2794)
			(end -0.12065 0.2794)
			(stroke
				(width 0.1)
				(type default)
			)
			(layer "F.Fab")
		)
		(fp_line
			(start -0.12065 0.2794)
			(end -0.12065 0.3048)
			(stroke
				(width 0.1)
				(type default)
			)
			(layer "F.Fab")
		)
		(fp_line
			(start 0.67945 0.3048)
			(end 0.120396 0.3048)
			(stroke
				(width 0.1)
				(type default)
			)
			(layer "F.Fab")
		)
		(fp_line
			(start 0.120396 0.3048)
			(end 0.120396 0.2794)
			(stroke
				(width 0.1)
				(type default)
			)
			(layer "F.Fab")
		)
		(fp_line
			(start -0.12065 0.3048)
			(end -0.67945 0.3048)
			(stroke
				(width 0.1)
				(type default)
			)
			(layer "F.Fab")
		)
		(fp_line
			(start -0.67945 0.3048)
			(end -0.67945 -0.305054)
			(stroke
				(width 0.1)
				(type default)
			)
			(layer "F.Fab")
		)
		(pad "1" smd rect
			(at -0.40005 0 270)
			(size 0.4572 0.508)
			(layers "F.Cu" "F.Mask" "F.Paste")
			(net "I3C_SPD_DDRGL_CPU0_SCL")
		)
		(pad "2" smd rect
			(at 0.40005 0 270)
			(size 0.4572 0.508)
			(layers "F.Cu" "F.Mask" "F.Paste")
			(net "I3C_SPD_DDRGL_CPU0_LVC1_SCL")
		)
	)
	(footprint ""
		(layer "F.Cu")
		(at 93.113352 -72.61098 -90)
		(property "Reference" "PU207"
			(at -3.701542 2.497328 0)
			(unlocked yes)
			(layer "F.SilkS")
			(effects
				(font
					(size 0.7874 0.5842)
					(thickness 0.1524)
				)
			)
		)
		(property "Value" ""
			(at 0 0 270)
			(layer "F.Fab")
			(effects
				(font
					(size 1.27 1.27)
				)
			)
		)
		(duplicate_pad_numbers_are_jumpers no)
		(fp_line
			(start -1.239774 1.495298)
			(end -1.239774 -1.495298)
			(stroke
				(width 0.1524)
				(type default)
			)
			(layer "F.SilkS")
		)
		(fp_line
			(start 1.239774 1.495298)
			(end -1.239774 1.495298)
			(stroke
				(width 0.1524)
				(type default)
			)
			(layer "F.SilkS")
		)
		(fp_line
			(start -1.239774 -1.495298)
			(end 1.239774 -1.495298)
			(stroke
				(width 0.1524)
				(type default)
			)
			(layer "F.SilkS")
		)
		(fp_line
			(start 1.239774 -1.495298)
			(end 1.239774 1.495298)
			(stroke
				(width 0.1524)
				(type default)
			)
			(layer "F.SilkS")
		)
		(fp_poly
			(pts
				(xy -1.843532 -0.966724) (xy -2.921 -1.32588) (xy -2.202688 -2.044446)
			)
			(stroke
				(width 0)
				(type default)
			)
			(fill yes)
			(layer "F.SilkS")
		)
		(fp_line
			(start -0.8001 1.050036)
			(end -0.8001 -1.050036)
			(stroke
				(width 0.1)
				(type default)
			)
			(layer "F.Fab")
		)
		(fp_line
			(start 0.8001 1.050036)
			(end -0.8001 1.050036)
			(stroke
				(width 0.1)
				(type default)
			)
			(layer "F.Fab")
		)
		(fp_line
			(start -0.8001 -1.050036)
			(end 0.8001 -1.050036)
			(stroke
				(width 0.1)
				(type default)
			)
			(layer "F.Fab")
		)
		(fp_line
			(start 0.8001 -1.050036)
			(end 0.8001 1.050036)
			(stroke
				(width 0.1)
				(type default)
			)
			(layer "F.Fab")
		)
		(fp_poly
			(pts
				(xy -2.458974 -0.508) (xy -2.458974 0.508) (xy -1.442974 0)
			)
			(stroke
				(width 0)
				(type default)
			)
			(fill yes)
			(layer "F.Fab")
		)
		(pad "1_2" smd circle
			(at -0.374904 0)
			(size 0 0)
			(layers "F.Cu" "F.Mask" "F.Paste")
			(net "P3V3_AUX")
		)
		(pad "3" smd rect
			(at -0.499872 0.999998 270)
			(size 0.254 0.7112)
			(layers "F.Cu" "F.Mask" "F.Paste")
			(net "GND")
		)
		(pad "4" smd rect
			(at 0 0.999998 270)
			(size 0.254 0.7112)
			(layers "F.Cu" "F.Mask" "F.Paste")
			(net "P3V3_OCP_ILIMIT_2")
		)
		(pad "5" smd rect
			(at 0.499872 0.999998 270)
			(size 0.254 0.7112)
			(layers "F.Cu" "F.Mask" "F.Paste")
			(net "P3V3_OCP_MODE_2")
		)
		(pad "6_7" smd circle
			(at 0.374904 0 180)
			(size 0 0)
			(layers "F.Cu" "F.Mask" "F.Paste")
			(net "P3V3_OCP_V3_2_R")
		)
		(pad "8" smd rect
			(at 0.499872 -0.999998 270)
			(size 0.254 0.7112)
			(layers "F.Cu" "F.Mask" "F.Paste")
			(net "P3V3_OCP_GATE_PU207_2")
		)
		(pad "9" smd rect
			(at 0 -0.999998 270)
			(size 0.254 0.7112)
			(layers "F.Cu" "F.Mask" "F.Paste")
			(net "P3V3_OCP_EN_2")
		)
		(pad "10" smd rect
			(at -0.499872 -0.999998 270)
			(size 0.254 0.7112)
			(layers "F.Cu" "F.Mask" "F.Paste")
			(net "P3V3_OCP_DVDT_2")
		)
	)
	(footprint ""
		(layer "F.Cu")
		(at 254.592836 -125.52045)
		(property "Reference" "R3706"
			(at 0 0 0)
			(layer "F.SilkS")
			(hide yes)
			(effects
				(font
					(size 1.27 1.27)
				)
			)
		)
		(property "Value" ""
			(at 0 0 0)
			(layer "F.Fab")
			(effects
				(font
					(size 1.27 1.27)
				)
			)
		)
		(duplicate_pad_numbers_are_jumpers no)
		(fp_line
			(start -0.7874 -0.4064)
			(end 0.7874 -0.4064)
			(stroke
				(width 0.1524)
				(type default)
			)
			(layer "F.SilkS")
		)
		(fp_line
			(start -0.7874 0.4064)
			(end -0.7874 -0.4064)
			(stroke
				(width 0.1524)
				(type default)
			)
			(layer "F.SilkS")
		)
		(fp_line
			(start 0.7874 -0.4064)
			(end 0.7874 0.4064)
			(stroke
				(width 0.1524)
				(type default)
			)
			(layer "F.SilkS")
		)
		(fp_line
			(start 0.7874 0.4064)
			(end -0.7874 0.4064)
			(stroke
				(width 0.1524)
				(type default)
			)
			(layer "F.SilkS")
		)
		(fp_line
			(start -0.67945 -0.305054)
			(end -0.12065 -0.305054)
			(stroke
				(width 0.1)
				(type default)
			)
			(layer "F.Fab")
		)
		(fp_line
			(start -0.67945 0.3048)
			(end -0.67945 -0.305054)
			(stroke
				(width 0.1)
				(type default)
			)
			(layer "F.Fab")
		)
		(fp_line
			(start -0.12065 -0.305054)
			(end -0.12065 -0.2794)
			(stroke
				(width 0.1)
				(type default)
			)
			(layer "F.Fab")
		)
		(fp_line
			(start -0.12065 -0.2794)
			(end 0.12065 -0.2794)
			(stroke
				(width 0.1)
				(type default)
			)
			(layer "F.Fab")
		)
		(fp_line
			(start -0.12065 0.2794)
			(end -0.12065 0.3048)
			(stroke
				(width 0.1)
				(type default)
			)
			(layer "F.Fab")
		)
		(fp_line
			(start -0.12065 0.3048)
			(end -0.67945 0.3048)
			(stroke
				(width 0.1)
				(type default)
			)
			(layer "F.Fab")
		)
		(fp_line
			(start 0.120396 0.2794)
			(end -0.12065 0.2794)
			(stroke
				(width 0.1)
				(type default)
			)
			(layer "F.Fab")
		)
		(fp_line
			(start 0.120396 0.3048)
			(end 0.120396 0.2794)
			(stroke
				(width 0.1)
				(type default)
			)
			(layer "F.Fab")
		)
		(fp_line
			(start 0.12065 -0.3048)
			(end 0.67945 -0.3048)
			(stroke
				(width 0.1)
				(type default)
			)
			(layer "F.Fab")
		)
		(fp_line
			(start 0.12065 -0.2794)
			(end 0.12065 -0.3048)
			(stroke
				(width 0.1)
				(type default)
			)
			(layer "F.Fab")
		)
		(fp_line
			(start 0.67945 -0.3048)
			(end 0.67945 0.3048)
			(stroke
				(width 0.1)
				(type default)
			)
			(layer "F.Fab")
		)
		(fp_line
			(start 0.67945 0.3048)
			(end 0.120396 0.3048)
			(stroke
				(width 0.1)
				(type default)
			)
			(layer "F.Fab")
		)
		(pad "1" smd circle
			(at -0.40005 0)
			(size 0 0)
			(layers "F.Cu" "F.Mask" "F.Paste")
			(net "P3V3_AUX")
		)
		(pad "2" smd circle
			(at 0.40005 0)
			(size 0 0)
			(layers "F.Cu" "F.Mask" "F.Paste")
			(net "PCA9548_PCIE0_ADDR1")
		)
	)
	(footprint ""
		(layer "F.Cu")
		(at 450.049392 -47.506382 -90)
		(property "Reference" "PC2343"
			(at 0 0 270)
			(layer "F.SilkS")
			(hide yes)
			(effects
				(font
					(size 1.27 1.27)
				)
			)
		)
		(property "Value" ""
			(at 0 0 270)
			(layer "F.Fab")
			(effects
				(font
					(size 1.27 1.27)
				)
			)
		)
		(duplicate_pad_numbers_are_jumpers no)
		(fp_line
			(start -1.524 0.762)
			(end -1.524 -0.762)
			(stroke
				(width 0.1524)
				(type default)
			)
			(layer "F.SilkS")
		)
		(fp_line
			(start 1.524 0.762)
			(end -1.524 0.762)
			(stroke
				(width 0.1524)
				(type default)
			)
			(layer "F.SilkS")
		)
		(fp_line
			(start -1.524 -0.762)
			(end 1.524 -0.762)
			(stroke
				(width 0.1524)
				(type default)
			)
			(layer "F.SilkS")
		)
		(fp_line
			(start 1.524 -0.762)
			(end 1.524 0.762)
			(stroke
				(width 0.1524)
				(type default)
			)
			(layer "F.SilkS")
		)
		(fp_line
			(start -1.1049 0.724916)
			(end 1.1049 0.724916)
			(stroke
				(width 0.1)
				(type default)
			)
			(layer "F.Fab")
		)
		(fp_line
			(start 1.1049 0.724916)
			(end 1.1049 -0.724916)
			(stroke
				(width 0.1)
				(type default)
			)
			(layer "F.Fab")
		)
		(fp_line
			(start -1.1049 -0.724916)
			(end -1.1049 0.724916)
			(stroke
				(width 0.1)
				(type default)
			)
			(layer "F.Fab")
		)
		(fp_line
			(start 1.1049 -0.724916)
			(end -1.1049 -0.724916)
			(stroke
				(width 0.1)
				(type default)
			)
			(layer "F.Fab")
		)
		(pad "1" smd rect
			(at -0.889 0 90)
			(size 1.016 1.27)
			(layers "F.Cu" "F.Mask" "F.Paste")
			(net "SW_P3V3_AUX_FLT")
		)
		(pad "2" smd rect
			(at 0.889 0 90)
			(size 1.016 1.27)
			(layers "F.Cu" "F.Mask" "F.Paste")
			(net "GND")
		)
	)
	(footprint ""
		(layer "F.Cu")
		(at 440.40171 -13.627354 180)
		(property "Reference" "C27"
			(at 0 0 180)
			(layer "F.SilkS")
			(hide yes)
			(effects
				(font
					(size 1.27 1.27)
				)
			)
		)
		(property "Value" ""
			(at 0 0 180)
			(layer "F.Fab")
			(effects
				(font
					(size 1.27 1.27)
				)
			)
		)
		(duplicate_pad_numbers_are_jumpers no)
		(fp_line
			(start 0.7874 0.4064)
			(end -0.7874 0.4064)
			(stroke
				(width 0.1524)
				(type default)
			)
			(layer "F.SilkS")
		)
		(fp_line
			(start 0.7874 -0.4064)
			(end 0.7874 0.4064)
			(stroke
				(width 0.1524)
				(type default)
			)
			(layer "F.SilkS")
		)
		(fp_line
			(start -0.7874 0.4064)
			(end -0.7874 -0.4064)
			(stroke
				(width 0.1524)
				(type default)
			)
			(layer "F.SilkS")
		)
		(fp_line
			(start -0.7874 -0.4064)
			(end 0.7874 -0.4064)
			(stroke
				(width 0.1524)
				(type default)
			)
			(layer "F.SilkS")
		)
		(fp_line
			(start 0.67945 0.3048)
			(end 0.120396 0.3048)
			(stroke
				(width 0.1)
				(type default)
			)
			(layer "F.Fab")
		)
		(fp_line
			(start 0.67945 -0.3048)
			(end 0.67945 0.3048)
			(stroke
				(width 0.1)
				(type default)
			)
			(layer "F.Fab")
		)
		(fp_line
			(start 0.12065 -0.2794)
			(end 0.12065 -0.3048)
			(stroke
				(width 0.1)
				(type default)
			)
			(layer "F.Fab")
		)
		(fp_line
			(start 0.12065 -0.3048)
			(end 0.67945 -0.3048)
			(stroke
				(width 0.1)
				(type default)
			)
			(layer "F.Fab")
		)
		(fp_line
			(start 0.120396 0.3048)
			(end 0.120396 0.2794)
			(stroke
				(width 0.1)
				(type default)
			)
			(layer "F.Fab")
		)
		(fp_line
			(start 0.120396 0.2794)
			(end -0.12065 0.2794)
			(stroke
				(width 0.1)
				(type default)
			)
			(layer "F.Fab")
		)
		(fp_line
			(start -0.12065 0.3048)
			(end -0.67945 0.3048)
			(stroke
				(width 0.1)
				(type default)
			)
			(layer "F.Fab")
		)
		(fp_line
			(start -0.12065 0.2794)
			(end -0.12065 0.3048)
			(stroke
				(width 0.1)
				(type default)
			)
			(layer "F.Fab")
		)
		(fp_line
			(start -0.12065 -0.2794)
			(end 0.12065 -0.2794)
			(stroke
				(width 0.1)
				(type default)
			)
			(layer "F.Fab")
		)
		(fp_line
			(start -0.12065 -0.305054)
			(end -0.12065 -0.2794)
			(stroke
				(width 0.1)
				(type default)
			)
			(layer "F.Fab")
		)
		(fp_line
			(start -0.67945 0.3048)
			(end -0.67945 -0.305054)
			(stroke
				(width 0.1)
				(type default)
			)
			(layer "F.Fab")
		)
		(fp_line
			(start -0.67945 -0.305054)
			(end -0.12065 -0.305054)
			(stroke
				(width 0.1)
				(type default)
			)
			(layer "F.Fab")
		)
		(pad "1" smd circle
			(at -0.40005 0 180)
			(size 0 0)
			(layers "F.Cu" "F.Mask" "F.Paste")
			(net "P12V_OCP_SFF_R")
		)
		(pad "2" smd circle
			(at 0.40005 0 180)
			(size 0 0)
			(layers "F.Cu" "F.Mask" "F.Paste")
			(net "GND")
		)
	)
	(footprint ""
		(layer "F.Cu")
		(at 360.190542 -400.6088)
		(property "Reference" "R1391"
			(at 0 0 0)
			(layer "F.SilkS")
			(hide yes)
			(effects
				(font
					(size 1.27 1.27)
				)
			)
		)
		(property "Value" ""
			(at 0 0 0)
			(layer "F.Fab")
			(effects
				(font
					(size 1.27 1.27)
				)
			)
		)
		(duplicate_pad_numbers_are_jumpers no)
		(fp_line
			(start -0.32512 -0.175006)
			(end 0.32512 -0.175006)
			(stroke
				(width 0.1)
				(type default)
			)
			(layer "F.Fab")
		)
		(fp_line
			(start -0.32512 0.175006)
			(end -0.32512 -0.175006)
			(stroke
				(width 0.1)
				(type default)
			)
			(layer "F.Fab")
		)
		(fp_line
			(start 0.32512 -0.175006)
			(end 0.32512 0.175006)
			(stroke
				(width 0.1)
				(type default)
			)
			(layer "F.Fab")
		)
		(fp_line
			(start 0.32512 0.175006)
			(end -0.32512 0.175006)
			(stroke
				(width 0.1)
				(type default)
			)
			(layer "F.Fab")
		)
		(pad "1" smd rect
			(at -0.2667 0)
			(size 0.3048 0.381)
			(layers "F.Cu" "F.Mask" "F.Paste")
			(net "JTAG_TRST_RT_CPU0_P1_N")
		)
		(pad "2" smd rect
			(at 0.2667 0 180)
			(size 0.3048 0.381)
			(layers "F.Cu" "F.Mask" "F.Paste")
			(net "GND")
		)
	)
	(footprint ""
		(layer "F.Cu")
		(at 49.61763 -360.025696 90)
		(property "Reference" "PL49"
			(at 4.310634 -1.48463 0)
			(unlocked yes)
			(layer "F.SilkS")
			(effects
				(font
					(size 0.7874 0.5842)
					(thickness 0.1524)
				)
				(justify left)
			)
		)
		(property "Value" ""
			(at 0 0 90)
			(layer "F.Fab")
			(effects
				(font
					(size 1.27 1.27)
				)
			)
		)
		(duplicate_pad_numbers_are_jumpers no)
		(fp_line
			(start 3.050032 -2.999994)
			(end -3.050032 -2.999994)
			(stroke
				(width 0.1524)
				(type default)
			)
			(layer "F.SilkS")
		)
		(fp_line
			(start -3.050032 -2.999994)
			(end -3.050032 -1.4478)
			(stroke
				(width 0.1524)
				(type default)
			)
			(layer "F.SilkS")
		)
		(fp_line
			(start 3.050032 -1.4478)
			(end 3.050032 -2.999994)
			(stroke
				(width 0.1524)
				(type default)
			)
			(layer "F.SilkS")
		)
		(fp_line
			(start -3.050032 1.4478)
			(end -3.050032 2.999994)
			(stroke
				(width 0.1524)
				(type default)
			)
			(layer "F.SilkS")
		)
		(fp_line
			(start 3.050032 2.999994)
			(end 3.050032 1.4478)
			(stroke
				(width 0.1524)
				(type default)
			)
			(layer "F.SilkS")
		)
		(fp_line
			(start -3.050032 2.999994)
			(end 3.050032 2.999994)
			(stroke
				(width 0.1524)
				(type default)
			)
			(layer "F.SilkS")
		)
		(fp_line
			(start 3.050032 -2.999994)
			(end -3.050032 -2.999994)
			(stroke
				(width 0.1)
				(type default)
			)
			(layer "F.Fab")
		)
		(fp_line
			(start -3.050032 -2.999994)
			(end -3.050032 2.999994)
			(stroke
				(width 0.1)
				(type default)
			)
			(layer "F.Fab")
		)
		(fp_line
			(start 3.050032 2.999994)
			(end 3.050032 -2.999994)
			(stroke
				(width 0.1)
				(type default)
			)
			(layer "F.Fab")
		)
		(fp_line
			(start -3.050032 2.999994)
			(end 3.050032 2.999994)
			(stroke
				(width 0.1)
				(type default)
			)
			(layer "F.Fab")
		)
		(pad "1" smd rect
			(at -2.525014 0 90)
			(size 1.651 2.6162)
			(layers "F.Cu" "F.Mask" "F.Paste")
			(net "SW_P12V_AUX_PVDDIO_P1_FLT")
		)
		(pad "2" smd rect
			(at 2.525014 0 90)
			(size 1.651 2.6162)
			(layers "F.Cu" "F.Mask" "F.Paste")
			(net "P12V_AUX")
		)
	)
	(footprint ""
		(layer "F.Cu")
		(at 425.36872 -387.853428)
		(property "Reference" "C839"
			(at 0 0 0)
			(layer "F.SilkS")
			(hide yes)
			(effects
				(font
					(size 1.27 1.27)
				)
			)
		)
		(property "Value" ""
			(at 0 0 0)
			(layer "F.Fab")
			(effects
				(font
					(size 1.27 1.27)
				)
			)
		)
		(duplicate_pad_numbers_are_jumpers no)
		(fp_line
			(start -0.299974 -0.150114)
			(end 0.299974 -0.150114)
			(stroke
				(width 0.1)
				(type default)
			)
			(layer "F.Fab")
		)
		(fp_line
			(start -0.299974 0.150114)
			(end -0.299974 -0.150114)
			(stroke
				(width 0.1)
				(type default)
			)
			(layer "F.Fab")
		)
		(fp_line
			(start 0.299974 -0.150114)
			(end 0.299974 0.150114)
			(stroke
				(width 0.1)
				(type default)
			)
			(layer "F.Fab")
		)
		(fp_line
			(start 0.299974 0.150114)
			(end -0.299974 0.150114)
			(stroke
				(width 0.1)
				(type default)
			)
			(layer "F.Fab")
		)
		(pad "1" smd rect
			(at -0.2667 0)
			(size 0.3048 0.381)
			(layers "F.Cu" "F.Mask" "F.Paste")
			(net "P5E_CPU0_P2_TX_C_DP<15>")
		)
		(pad "2" smd rect
			(at 0.2667 0)
			(size 0.3048 0.381)
			(layers "F.Cu" "F.Mask" "F.Paste")
			(net "P5E_CPU0_P2_TX_DP<15>")
		)
	)
	(footprint ""
		(layer "F.Cu")
		(at 61.88075 -193.594228)
		(property "Reference" "TP19"
			(at 0 0 0)
			(layer "F.SilkS")
			(hide yes)
			(effects
				(font
					(size 1.27 1.27)
				)
			)
		)
		(property "Value" ""
			(at 0 0 0)
			(layer "F.Fab")
			(effects
				(font
					(size 1.27 1.27)
				)
			)
		)
		(duplicate_pad_numbers_are_jumpers no)
		(pad "1" smd circle
			(at 0 0)
			(size 0.762 0.762)
			(layers "F.Cu" "F.Mask" "F.Paste")
			(net "VSENSE_PVDD18_S5_P1_DP")
		)
	)
	(footprint ""
		(layer "F.Cu")
		(at 296.515028 -146.202908 180)
		(property "Reference" "R1297"
			(at 0 0 180)
			(layer "F.SilkS")
			(hide yes)
			(effects
				(font
					(size 1.27 1.27)
				)
			)
		)
		(property "Value" ""
			(at 0 0 180)
			(layer "F.Fab")
			(effects
				(font
					(size 1.27 1.27)
				)
			)
		)
		(duplicate_pad_numbers_are_jumpers no)
		(fp_line
			(start 0.7874 0.4064)
			(end -0.7874 0.4064)
			(stroke
				(width 0.1524)
				(type default)
			)
			(layer "F.SilkS")
		)
		(fp_line
			(start 0.7874 -0.4064)
			(end 0.7874 0.4064)
			(stroke
				(width 0.1524)
				(type default)
			)
			(layer "F.SilkS")
		)
		(fp_line
			(start -0.7874 0.4064)
			(end -0.7874 -0.4064)
			(stroke
				(width 0.1524)
				(type default)
			)
			(layer "F.SilkS")
		)
		(fp_line
			(start -0.7874 -0.4064)
			(end 0.7874 -0.4064)
			(stroke
				(width 0.1524)
				(type default)
			)
			(layer "F.SilkS")
		)
		(fp_line
			(start 0.67945 0.3048)
			(end 0.120396 0.3048)
			(stroke
				(width 0.1)
				(type default)
			)
			(layer "F.Fab")
		)
		(fp_line
			(start 0.67945 -0.3048)
			(end 0.67945 0.3048)
			(stroke
				(width 0.1)
				(type default)
			)
			(layer "F.Fab")
		)
		(fp_line
			(start 0.12065 -0.2794)
			(end 0.12065 -0.3048)
			(stroke
				(width 0.1)
				(type default)
			)
			(layer "F.Fab")
		)
		(fp_line
			(start 0.12065 -0.3048)
			(end 0.67945 -0.3048)
			(stroke
				(width 0.1)
				(type default)
			)
			(layer "F.Fab")
		)
		(fp_line
			(start 0.120396 0.3048)
			(end 0.120396 0.2794)
			(stroke
				(width 0.1)
				(type default)
			)
			(layer "F.Fab")
		)
		(fp_line
			(start 0.120396 0.2794)
			(end -0.12065 0.2794)
			(stroke
				(width 0.1)
				(type default)
			)
			(layer "F.Fab")
		)
		(fp_line
			(start -0.12065 0.3048)
			(end -0.67945 0.3048)
			(stroke
				(width 0.1)
				(type default)
			)
			(layer "F.Fab")
		)
		(fp_line
			(start -0.12065 0.2794)
			(end -0.12065 0.3048)
			(stroke
				(width 0.1)
				(type default)
			)
			(layer "F.Fab")
		)
		(fp_line
			(start -0.12065 -0.2794)
			(end 0.12065 -0.2794)
			(stroke
				(width 0.1)
				(type default)
			)
			(layer "F.Fab")
		)
		(fp_line
			(start -0.12065 -0.305054)
			(end -0.12065 -0.2794)
			(stroke
				(width 0.1)
				(type default)
			)
			(layer "F.Fab")
		)
		(fp_line
			(start -0.67945 0.3048)
			(end -0.67945 -0.305054)
			(stroke
				(width 0.1)
				(type default)
			)
			(layer "F.Fab")
		)
		(fp_line
			(start -0.67945 -0.305054)
			(end -0.12065 -0.305054)
			(stroke
				(width 0.1)
				(type default)
			)
			(layer "F.Fab")
		)
		(pad "1" smd rect
			(at -0.40005 0)
			(size 0.4572 0.508)
			(layers "F.Cu" "F.Mask" "F.Paste")
			(net "I3C_SPD_DDRAF_CPU0_SCL")
		)
		(pad "2" smd rect
			(at 0.40005 0)
			(size 0.4572 0.508)
			(layers "F.Cu" "F.Mask" "F.Paste")
			(net "I3C_SPD_DDRAF_CPU0_LVC1_SCL")
		)
	)
	(footprint ""
		(layer "F.Cu")
		(at 386.211826 -56.1975 180)
		(property "Reference" "R1354"
			(at 0 0 180)
			(layer "F.SilkS")
			(hide yes)
			(effects
				(font
					(size 1.27 1.27)
				)
			)
		)
		(property "Value" ""
			(at 0 0 180)
			(layer "F.Fab")
			(effects
				(font
					(size 1.27 1.27)
				)
			)
		)
		(duplicate_pad_numbers_are_jumpers no)
		(fp_line
			(start 0.7874 0.4064)
			(end -0.7874 0.4064)
			(stroke
				(width 0.1524)
				(type default)
			)
			(layer "F.SilkS")
		)
		(fp_line
			(start 0.7874 -0.4064)
			(end 0.7874 0.4064)
			(stroke
				(width 0.1524)
				(type default)
			)
			(layer "F.SilkS")
		)
		(fp_line
			(start -0.7874 0.4064)
			(end -0.7874 -0.4064)
			(stroke
				(width 0.1524)
				(type default)
			)
			(layer "F.SilkS")
		)
		(fp_line
			(start -0.7874 -0.4064)
			(end 0.7874 -0.4064)
			(stroke
				(width 0.1524)
				(type default)
			)
			(layer "F.SilkS")
		)
		(fp_line
			(start 0.67945 0.3048)
			(end 0.120396 0.3048)
			(stroke
				(width 0.1)
				(type default)
			)
			(layer "F.Fab")
		)
		(fp_line
			(start 0.67945 -0.3048)
			(end 0.67945 0.3048)
			(stroke
				(width 0.1)
				(type default)
			)
			(layer "F.Fab")
		)
		(fp_line
			(start 0.12065 -0.2794)
			(end 0.12065 -0.3048)
			(stroke
				(width 0.1)
				(type default)
			)
			(layer "F.Fab")
		)
		(fp_line
			(start 0.12065 -0.3048)
			(end 0.67945 -0.3048)
			(stroke
				(width 0.1)
				(type default)
			)
			(layer "F.Fab")
		)
		(fp_line
			(start 0.120396 0.3048)
			(end 0.120396 0.2794)
			(stroke
				(width 0.1)
				(type default)
			)
			(layer "F.Fab")
		)
		(fp_line
			(start 0.120396 0.2794)
			(end -0.12065 0.2794)
			(stroke
				(width 0.1)
				(type default)
			)
			(layer "F.Fab")
		)
		(fp_line
			(start -0.12065 0.3048)
			(end -0.67945 0.3048)
			(stroke
				(width 0.1)
				(type default)
			)
			(layer "F.Fab")
		)
		(fp_line
			(start -0.12065 0.2794)
			(end -0.12065 0.3048)
			(stroke
				(width 0.1)
				(type default)
			)
			(layer "F.Fab")
		)
		(fp_line
			(start -0.12065 -0.2794)
			(end 0.12065 -0.2794)
			(stroke
				(width 0.1)
				(type default)
			)
			(layer "F.Fab")
		)
		(fp_line
			(start -0.12065 -0.305054)
			(end -0.12065 -0.2794)
			(stroke
				(width 0.1)
				(type default)
			)
			(layer "F.Fab")
		)
		(fp_line
			(start -0.67945 0.3048)
			(end -0.67945 -0.305054)
			(stroke
				(width 0.1)
				(type default)
			)
			(layer "F.Fab")
		)
		(fp_line
			(start -0.67945 -0.305054)
			(end -0.12065 -0.305054)
			(stroke
				(width 0.1)
				(type default)
			)
			(layer "F.Fab")
		)
		(pad "1" smd circle
			(at -0.40005 0 180)
			(size 0 0)
			(layers "F.Cu" "F.Mask" "F.Paste")
			(net "HDT_HDR_R_TDI")
		)
		(pad "2" smd circle
			(at 0.40005 0 180)
			(size 0 0)
			(layers "F.Cu" "F.Mask" "F.Paste")
			(net "HDT_HDR_TDI")
		)
	)
	(footprint ""
		(layer "F.Cu")
		(at 302.109378 -435.233572 -90)
		(property "Reference" "R3435"
			(at 0 0 270)
			(layer "F.SilkS")
			(hide yes)
			(effects
				(font
					(size 1.27 1.27)
				)
			)
		)
		(property "Value" ""
			(at 0 0 270)
			(layer "F.Fab")
			(effects
				(font
					(size 1.27 1.27)
				)
			)
		)
		(duplicate_pad_numbers_are_jumpers no)
		(fp_line
			(start -0.7874 0.4064)
			(end -0.7874 -0.4064)
			(stroke
				(width 0.1524)
				(type default)
			)
			(layer "F.SilkS")
		)
		(fp_line
			(start 0.7874 0.4064)
			(end -0.7874 0.4064)
			(stroke
				(width 0.1524)
				(type default)
			)
			(layer "F.SilkS")
		)
		(fp_line
			(start -0.7874 -0.4064)
			(end 0.7874 -0.4064)
			(stroke
				(width 0.1524)
				(type default)
			)
			(layer "F.SilkS")
		)
		(fp_line
			(start 0.7874 -0.4064)
			(end 0.7874 0.4064)
			(stroke
				(width 0.1524)
				(type default)
			)
			(layer "F.SilkS")
		)
		(fp_line
			(start -0.67945 0.3048)
			(end -0.67945 -0.305054)
			(stroke
				(width 0.1)
				(type default)
			)
			(layer "F.Fab")
		)
		(fp_line
			(start -0.12065 0.3048)
			(end -0.67945 0.3048)
			(stroke
				(width 0.1)
				(type default)
			)
			(layer "F.Fab")
		)
		(fp_line
			(start 0.120396 0.3048)
			(end 0.120396 0.2794)
			(stroke
				(width 0.1)
				(type default)
			)
			(layer "F.Fab")
		)
		(fp_line
			(start 0.67945 0.3048)
			(end 0.120396 0.3048)
			(stroke
				(width 0.1)
				(type default)
			)
			(layer "F.Fab")
		)
		(fp_line
			(start -0.12065 0.2794)
			(end -0.12065 0.3048)
			(stroke
				(width 0.1)
				(type default)
			)
			(layer "F.Fab")
		)
		(fp_line
			(start 0.120396 0.2794)
			(end -0.12065 0.2794)
			(stroke
				(width 0.1)
				(type default)
			)
			(layer "F.Fab")
		)
		(fp_line
			(start -0.12065 -0.2794)
			(end 0.12065 -0.2794)
			(stroke
				(width 0.1)
				(type default)
			)
			(layer "F.Fab")
		)
		(fp_line
			(start 0.12065 -0.2794)
			(end 0.12065 -0.3048)
			(stroke
				(width 0.1)
				(type default)
			)
			(layer "F.Fab")
		)
		(fp_line
			(start 0.12065 -0.3048)
			(end 0.67945 -0.3048)
			(stroke
				(width 0.1)
				(type default)
			)
			(layer "F.Fab")
		)
		(fp_line
			(start 0.67945 -0.3048)
			(end 0.67945 0.3048)
			(stroke
				(width 0.1)
				(type default)
			)
			(layer "F.Fab")
		)
		(fp_line
			(start -0.67945 -0.305054)
			(end -0.12065 -0.305054)
			(stroke
				(width 0.1)
				(type default)
			)
			(layer "F.Fab")
		)
		(fp_line
			(start -0.12065 -0.305054)
			(end -0.12065 -0.2794)
			(stroke
				(width 0.1)
				(type default)
			)
			(layer "F.Fab")
		)
		(pad "1" smd circle
			(at -0.40005 0 270)
			(size 0 0)
			(layers "F.Cu" "F.Mask" "F.Paste")
			(net "P3V3_AUX")
		)
		(pad "2" smd circle
			(at 0.40005 0 270)
			(size 0 0)
			(layers "F.Cu" "F.Mask" "F.Paste")
			(net "GPU_FPGA_OVERT")
		)
	)
	(footprint ""
		(layer "F.Cu")
		(at 406.33904 -381.41783 -90)
		(property "Reference" "C858"
			(at 0 0 270)
			(layer "F.SilkS")
			(hide yes)
			(effects
				(font
					(size 1.27 1.27)
				)
			)
		)
		(property "Value" ""
			(at 0 0 270)
			(layer "F.Fab")
			(effects
				(font
					(size 1.27 1.27)
				)
			)
		)
		(duplicate_pad_numbers_are_jumpers no)
		(fp_line
			(start -0.299974 0.150114)
			(end -0.299974 -0.150114)
			(stroke
				(width 0.1)
				(type default)
			)
			(layer "F.Fab")
		)
		(fp_line
			(start 0.299974 0.150114)
			(end -0.299974 0.150114)
			(stroke
				(width 0.1)
				(type default)
			)
			(layer "F.Fab")
		)
		(fp_line
			(start -0.299974 -0.150114)
			(end 0.299974 -0.150114)
			(stroke
				(width 0.1)
				(type default)
			)
			(layer "F.Fab")
		)
		(fp_line
			(start 0.299974 -0.150114)
			(end 0.299974 0.150114)
			(stroke
				(width 0.1)
				(type default)
			)
			(layer "F.Fab")
		)
		(pad "1" smd rect
			(at -0.2667 0 270)
			(size 0.3048 0.381)
			(layers "F.Cu" "F.Mask" "F.Paste")
			(net "P5E_CPU0_P2_TX_C_DN<5>")
		)
		(pad "2" smd rect
			(at 0.2667 0 270)
			(size 0.3048 0.381)
			(layers "F.Cu" "F.Mask" "F.Paste")
			(net "P5E_CPU0_P2_TX_DN<5>")
		)
	)
	(footprint ""
		(layer "F.Cu")
		(at 110.365794 -384.66268)
		(property "Reference" "R917"
			(at 0 0 0)
			(layer "F.SilkS")
			(hide yes)
			(effects
				(font
					(size 1.27 1.27)
				)
			)
		)
		(property "Value" ""
			(at 0 0 0)
			(layer "F.Fab")
			(effects
				(font
					(size 1.27 1.27)
				)
			)
		)
		(duplicate_pad_numbers_are_jumpers no)
		(fp_line
			(start -0.32512 -0.175006)
			(end 0.32512 -0.175006)
			(stroke
				(width 0.1)
				(type default)
			)
			(layer "F.Fab")
		)
		(fp_line
			(start -0.32512 0.175006)
			(end -0.32512 -0.175006)
			(stroke
				(width 0.1)
				(type default)
			)
			(layer "F.Fab")
		)
		(fp_line
			(start 0.32512 -0.175006)
			(end 0.32512 0.175006)
			(stroke
				(width 0.1)
				(type default)
			)
			(layer "F.Fab")
		)
		(fp_line
			(start 0.32512 0.175006)
			(end -0.32512 0.175006)
			(stroke
				(width 0.1)
				(type default)
			)
			(layer "F.Fab")
		)
		(pad "1" smd rect
			(at -0.2667 0)
			(size 0.3048 0.381)
			(layers "F.Cu" "F.Mask" "F.Paste")
			(net "GPIO3_RT_CPU1_P3")
		)
		(pad "2" smd rect
			(at 0.2667 0 180)
			(size 0.3048 0.381)
			(layers "F.Cu" "F.Mask" "F.Paste")
			(net "GND")
		)
	)
	(footprint ""
		(layer "F.Cu")
		(at 248.20753 -53.193442 90)
		(property "Reference" "PR3950"
			(at 0 0 90)
			(layer "F.SilkS")
			(hide yes)
			(effects
				(font
					(size 1.27 1.27)
				)
			)
		)
		(property "Value" ""
			(at 0 0 90)
			(layer "F.Fab")
			(effects
				(font
					(size 1.27 1.27)
				)
			)
		)
		(duplicate_pad_numbers_are_jumpers no)
		(fp_line
			(start 0.7874 -0.4064)
			(end 0.7874 0.4064)
			(stroke
				(width 0.1524)
				(type default)
			)
			(layer "F.SilkS")
		)
		(fp_line
			(start -0.7874 -0.4064)
			(end 0.7874 -0.4064)
			(stroke
				(width 0.1524)
				(type default)
			)
			(layer "F.SilkS")
		)
		(fp_line
			(start 0.7874 0.4064)
			(end -0.7874 0.4064)
			(stroke
				(width 0.1524)
				(type default)
			)
			(layer "F.SilkS")
		)
		(fp_line
			(start -0.7874 0.4064)
			(end -0.7874 -0.4064)
			(stroke
				(width 0.1524)
				(type default)
			)
			(layer "F.SilkS")
		)
		(fp_line
			(start -0.12065 -0.305054)
			(end -0.12065 -0.2794)
			(stroke
				(width 0.1)
				(type default)
			)
			(layer "F.Fab")
		)
		(fp_line
			(start -0.67945 -0.305054)
			(end -0.12065 -0.305054)
			(stroke
				(width 0.1)
				(type default)
			)
			(layer "F.Fab")
		)
		(fp_line
			(start 0.67945 -0.3048)
			(end 0.67945 0.3048)
			(stroke
				(width 0.1)
				(type default)
			)
			(layer "F.Fab")
		)
		(fp_line
			(start 0.12065 -0.3048)
			(end 0.67945 -0.3048)
			(stroke
				(width 0.1)
				(type default)
			)
			(layer "F.Fab")
		)
		(fp_line
			(start 0.12065 -0.2794)
			(end 0.12065 -0.3048)
			(stroke
				(width 0.1)
				(type default)
			)
			(layer "F.Fab")
		)
		(fp_line
			(start -0.12065 -0.2794)
			(end 0.12065 -0.2794)
			(stroke
				(width 0.1)
				(type default)
			)
			(layer "F.Fab")
		)
		(fp_line
			(start 0.120396 0.2794)
			(end -0.12065 0.2794)
			(stroke
				(width 0.1)
				(type default)
			)
			(layer "F.Fab")
		)
		(fp_line
			(start -0.12065 0.2794)
			(end -0.12065 0.3048)
			(stroke
				(width 0.1)
				(type default)
			)
			(layer "F.Fab")
		)
		(fp_line
			(start 0.67945 0.3048)
			(end 0.120396 0.3048)
			(stroke
				(width 0.1)
				(type default)
			)
			(layer "F.Fab")
		)
		(fp_line
			(start 0.120396 0.3048)
			(end 0.120396 0.2794)
			(stroke
				(width 0.1)
				(type default)
			)
			(layer "F.Fab")
		)
		(fp_line
			(start -0.12065 0.3048)
			(end -0.67945 0.3048)
			(stroke
				(width 0.1)
				(type default)
			)
			(layer "F.Fab")
		)
		(fp_line
			(start -0.67945 0.3048)
			(end -0.67945 -0.305054)
			(stroke
				(width 0.1)
				(type default)
			)
			(layer "F.Fab")
		)
		(pad "1" smd circle
			(at -0.40005 0 90)
			(size 0 0)
			(layers "F.Cu" "F.Mask" "F.Paste")
			(net "P12V_E1S_0")
		)
		(pad "2" smd circle
			(at 0.40005 0 90)
			(size 0 0)
			(layers "F.Cu" "F.Mask" "F.Paste")
			(net "P12V_E1S_AVIN_PD_0")
		)
	)
	(footprint ""
		(layer "F.Cu")
		(at 36.319968 -132.587238 180)
		(property "Reference" "R3326"
			(at 0 0 180)
			(layer "F.SilkS")
			(hide yes)
			(effects
				(font
					(size 1.27 1.27)
				)
			)
		)
		(property "Value" ""
			(at 0 0 180)
			(layer "F.Fab")
			(effects
				(font
					(size 1.27 1.27)
				)
			)
		)
		(duplicate_pad_numbers_are_jumpers no)
		(fp_line
			(start 0.7874 0.4064)
			(end -0.7874 0.4064)
			(stroke
				(width 0.1524)
				(type default)
			)
			(layer "F.SilkS")
		)
		(fp_line
			(start 0.7874 -0.4064)
			(end 0.7874 0.4064)
			(stroke
				(width 0.1524)
				(type default)
			)
			(layer "F.SilkS")
		)
		(fp_line
			(start -0.7874 0.4064)
			(end -0.7874 -0.4064)
			(stroke
				(width 0.1524)
				(type default)
			)
			(layer "F.SilkS")
		)
		(fp_line
			(start -0.7874 -0.4064)
			(end 0.7874 -0.4064)
			(stroke
				(width 0.1524)
				(type default)
			)
			(layer "F.SilkS")
		)
		(fp_line
			(start 0.67945 0.3048)
			(end 0.120396 0.3048)
			(stroke
				(width 0.1)
				(type default)
			)
			(layer "F.Fab")
		)
		(fp_line
			(start 0.67945 -0.3048)
			(end 0.67945 0.3048)
			(stroke
				(width 0.1)
				(type default)
			)
			(layer "F.Fab")
		)
		(fp_line
			(start 0.12065 -0.2794)
			(end 0.12065 -0.3048)
			(stroke
				(width 0.1)
				(type default)
			)
			(layer "F.Fab")
		)
		(fp_line
			(start 0.12065 -0.3048)
			(end 0.67945 -0.3048)
			(stroke
				(width 0.1)
				(type default)
			)
			(layer "F.Fab")
		)
		(fp_line
			(start 0.120396 0.3048)
			(end 0.120396 0.2794)
			(stroke
				(width 0.1)
				(type default)
			)
			(layer "F.Fab")
		)
		(fp_line
			(start 0.120396 0.2794)
			(end -0.12065 0.2794)
			(stroke
				(width 0.1)
				(type default)
			)
			(layer "F.Fab")
		)
		(fp_line
			(start -0.12065 0.3048)
			(end -0.67945 0.3048)
			(stroke
				(width 0.1)
				(type default)
			)
			(layer "F.Fab")
		)
		(fp_line
			(start -0.12065 0.2794)
			(end -0.12065 0.3048)
			(stroke
				(width 0.1)
				(type default)
			)
			(layer "F.Fab")
		)
		(fp_line
			(start -0.12065 -0.2794)
			(end 0.12065 -0.2794)
			(stroke
				(width 0.1)
				(type default)
			)
			(layer "F.Fab")
		)
		(fp_line
			(start -0.12065 -0.305054)
			(end -0.12065 -0.2794)
			(stroke
				(width 0.1)
				(type default)
			)
			(layer "F.Fab")
		)
		(fp_line
			(start -0.67945 0.3048)
			(end -0.67945 -0.305054)
			(stroke
				(width 0.1)
				(type default)
			)
			(layer "F.Fab")
		)
		(fp_line
			(start -0.67945 -0.305054)
			(end -0.12065 -0.305054)
			(stroke
				(width 0.1)
				(type default)
			)
			(layer "F.Fab")
		)
		(pad "1" smd circle
			(at -0.40005 0 180)
			(size 0 0)
			(layers "F.Cu" "F.Mask" "F.Paste")
			(net "GPU_FPGA_READY_N")
		)
		(pad "2" smd circle
			(at 0.40005 0 180)
			(size 0 0)
			(layers "F.Cu" "F.Mask" "F.Paste")
			(net "GPU_FPGA_READY_R_N")
		)
	)
	(footprint ""
		(layer "F.Cu")
		(at 193.167 -137.632948 -90)
		(property "Reference" "R1453"
			(at 0 0 270)
			(layer "F.SilkS")
			(hide yes)
			(effects
				(font
					(size 1.27 1.27)
				)
			)
		)
		(property "Value" ""
			(at 0 0 270)
			(layer "F.Fab")
			(effects
				(font
					(size 1.27 1.27)
				)
			)
		)
		(duplicate_pad_numbers_are_jumpers no)
		(fp_line
			(start -0.7874 0.4064)
			(end -0.7874 -0.4064)
			(stroke
				(width 0.1524)
				(type default)
			)
			(layer "F.SilkS")
		)
		(fp_line
			(start 0.7874 0.4064)
			(end -0.7874 0.4064)
			(stroke
				(width 0.1524)
				(type default)
			)
			(layer "F.SilkS")
		)
		(fp_line
			(start -0.7874 -0.4064)
			(end 0.7874 -0.4064)
			(stroke
				(width 0.1524)
				(type default)
			)
			(layer "F.SilkS")
		)
		(fp_line
			(start 0.7874 -0.4064)
			(end 0.7874 0.4064)
			(stroke
				(width 0.1524)
				(type default)
			)
			(layer "F.SilkS")
		)
		(fp_line
			(start -0.67945 0.3048)
			(end -0.67945 -0.305054)
			(stroke
				(width 0.1)
				(type default)
			)
			(layer "F.Fab")
		)
		(fp_line
			(start -0.12065 0.3048)
			(end -0.67945 0.3048)
			(stroke
				(width 0.1)
				(type default)
			)
			(layer "F.Fab")
		)
		(fp_line
			(start 0.120396 0.3048)
			(end 0.120396 0.2794)
			(stroke
				(width 0.1)
				(type default)
			)
			(layer "F.Fab")
		)
		(fp_line
			(start 0.67945 0.3048)
			(end 0.120396 0.3048)
			(stroke
				(width 0.1)
				(type default)
			)
			(layer "F.Fab")
		)
		(fp_line
			(start -0.12065 0.2794)
			(end -0.12065 0.3048)
			(stroke
				(width 0.1)
				(type default)
			)
			(layer "F.Fab")
		)
		(fp_line
			(start 0.120396 0.2794)
			(end -0.12065 0.2794)
			(stroke
				(width 0.1)
				(type default)
			)
			(layer "F.Fab")
		)
		(fp_line
			(start -0.12065 -0.2794)
			(end 0.12065 -0.2794)
			(stroke
				(width 0.1)
				(type default)
			)
			(layer "F.Fab")
		)
		(fp_line
			(start 0.12065 -0.2794)
			(end 0.12065 -0.3048)
			(stroke
				(width 0.1)
				(type default)
			)
			(layer "F.Fab")
		)
		(fp_line
			(start 0.12065 -0.3048)
			(end 0.67945 -0.3048)
			(stroke
				(width 0.1)
				(type default)
			)
			(layer "F.Fab")
		)
		(fp_line
			(start 0.67945 -0.3048)
			(end 0.67945 0.3048)
			(stroke
				(width 0.1)
				(type default)
			)
			(layer "F.Fab")
		)
		(fp_line
			(start -0.67945 -0.305054)
			(end -0.12065 -0.305054)
			(stroke
				(width 0.1)
				(type default)
			)
			(layer "F.Fab")
		)
		(fp_line
			(start -0.12065 -0.305054)
			(end -0.12065 -0.2794)
			(stroke
				(width 0.1)
				(type default)
			)
			(layer "F.Fab")
		)
		(pad "1" smd circle
			(at -0.40005 0 270)
			(size 0 0)
			(layers "F.Cu" "F.Mask" "F.Paste")
			(net "SMB_CPU_5_SDA")
		)
		(pad "2" smd circle
			(at 0.40005 0 270)
			(size 0 0)
			(layers "F.Cu" "F.Mask" "F.Paste")
			(net "SMB_CPU_5_R1_SDA")
		)
	)
	(footprint ""
		(layer "F.Cu")
		(at 164.521134 -46.954948 180)
		(property "Reference" "R1605"
			(at 0 0 180)
			(layer "F.SilkS")
			(hide yes)
			(effects
				(font
					(size 1.27 1.27)
				)
			)
		)
		(property "Value" ""
			(at 0 0 180)
			(layer "F.Fab")
			(effects
				(font
					(size 1.27 1.27)
				)
			)
		)
		(duplicate_pad_numbers_are_jumpers no)
		(fp_line
			(start 0.7874 0.4064)
			(end -0.7874 0.4064)
			(stroke
				(width 0.1524)
				(type default)
			)
			(layer "F.SilkS")
		)
		(fp_line
			(start 0.7874 -0.4064)
			(end 0.7874 0.4064)
			(stroke
				(width 0.1524)
				(type default)
			)
			(layer "F.SilkS")
		)
		(fp_line
			(start -0.7874 0.4064)
			(end -0.7874 -0.4064)
			(stroke
				(width 0.1524)
				(type default)
			)
			(layer "F.SilkS")
		)
		(fp_line
			(start -0.7874 -0.4064)
			(end 0.7874 -0.4064)
			(stroke
				(width 0.1524)
				(type default)
			)
			(layer "F.SilkS")
		)
		(fp_line
			(start 0.67945 0.3048)
			(end 0.120396 0.3048)
			(stroke
				(width 0.1)
				(type default)
			)
			(layer "F.Fab")
		)
		(fp_line
			(start 0.67945 -0.3048)
			(end 0.67945 0.3048)
			(stroke
				(width 0.1)
				(type default)
			)
			(layer "F.Fab")
		)
		(fp_line
			(start 0.12065 -0.2794)
			(end 0.12065 -0.3048)
			(stroke
				(width 0.1)
				(type default)
			)
			(layer "F.Fab")
		)
		(fp_line
			(start 0.12065 -0.3048)
			(end 0.67945 -0.3048)
			(stroke
				(width 0.1)
				(type default)
			)
			(layer "F.Fab")
		)
		(fp_line
			(start 0.120396 0.3048)
			(end 0.120396 0.2794)
			(stroke
				(width 0.1)
				(type default)
			)
			(layer "F.Fab")
		)
		(fp_line
			(start 0.120396 0.2794)
			(end -0.12065 0.2794)
			(stroke
				(width 0.1)
				(type default)
			)
			(layer "F.Fab")
		)
		(fp_line
			(start -0.12065 0.3048)
			(end -0.67945 0.3048)
			(stroke
				(width 0.1)
				(type default)
			)
			(layer "F.Fab")
		)
		(fp_line
			(start -0.12065 0.2794)
			(end -0.12065 0.3048)
			(stroke
				(width 0.1)
				(type default)
			)
			(layer "F.Fab")
		)
		(fp_line
			(start -0.12065 -0.2794)
			(end 0.12065 -0.2794)
			(stroke
				(width 0.1)
				(type default)
			)
			(layer "F.Fab")
		)
		(fp_line
			(start -0.12065 -0.305054)
			(end -0.12065 -0.2794)
			(stroke
				(width 0.1)
				(type default)
			)
			(layer "F.Fab")
		)
		(fp_line
			(start -0.67945 0.3048)
			(end -0.67945 -0.305054)
			(stroke
				(width 0.1)
				(type default)
			)
			(layer "F.Fab")
		)
		(fp_line
			(start -0.67945 -0.305054)
			(end -0.12065 -0.305054)
			(stroke
				(width 0.1)
				(type default)
			)
			(layer "F.Fab")
		)
		(pad "1" smd circle
			(at -0.40005 0 180)
			(size 0 0)
			(layers "F.Cu" "F.Mask" "F.Paste")
			(net "PD_M2_0_DEVSLP")
		)
		(pad "2" smd circle
			(at 0.40005 0 180)
			(size 0 0)
			(layers "F.Cu" "F.Mask" "F.Paste")
			(net "GND")
		)
	)
	(footprint ""
		(layer "F.Cu")
		(at 454.447402 -18.030698)
		(property "Reference" "R3144"
			(at 0 0 0)
			(layer "F.SilkS")
			(hide yes)
			(effects
				(font
					(size 1.27 1.27)
				)
			)
		)
		(property "Value" ""
			(at 0 0 0)
			(layer "F.Fab")
			(effects
				(font
					(size 1.27 1.27)
				)
			)
		)
		(duplicate_pad_numbers_are_jumpers no)
		(fp_line
			(start -0.7874 -0.4064)
			(end 0.7874 -0.4064)
			(stroke
				(width 0.1524)
				(type default)
			)
			(layer "F.SilkS")
		)
		(fp_line
			(start -0.7874 0.4064)
			(end -0.7874 -0.4064)
			(stroke
				(width 0.1524)
				(type default)
			)
			(layer "F.SilkS")
		)
		(fp_line
			(start 0.7874 -0.4064)
			(end 0.7874 0.4064)
			(stroke
				(width 0.1524)
				(type default)
			)
			(layer "F.SilkS")
		)
		(fp_line
			(start 0.7874 0.4064)
			(end -0.7874 0.4064)
			(stroke
				(width 0.1524)
				(type default)
			)
			(layer "F.SilkS")
		)
		(fp_line
			(start -0.67945 -0.305054)
			(end -0.12065 -0.305054)
			(stroke
				(width 0.1)
				(type default)
			)
			(layer "F.Fab")
		)
		(fp_line
			(start -0.67945 0.3048)
			(end -0.67945 -0.305054)
			(stroke
				(width 0.1)
				(type default)
			)
			(layer "F.Fab")
		)
		(fp_line
			(start -0.12065 -0.305054)
			(end -0.12065 -0.2794)
			(stroke
				(width 0.1)
				(type default)
			)
			(layer "F.Fab")
		)
		(fp_line
			(start -0.12065 -0.2794)
			(end 0.12065 -0.2794)
			(stroke
				(width 0.1)
				(type default)
			)
			(layer "F.Fab")
		)
		(fp_line
			(start -0.12065 0.2794)
			(end -0.12065 0.3048)
			(stroke
				(width 0.1)
				(type default)
			)
			(layer "F.Fab")
		)
		(fp_line
			(start -0.12065 0.3048)
			(end -0.67945 0.3048)
			(stroke
				(width 0.1)
				(type default)
			)
			(layer "F.Fab")
		)
		(fp_line
			(start 0.120396 0.2794)
			(end -0.12065 0.2794)
			(stroke
				(width 0.1)
				(type default)
			)
			(layer "F.Fab")
		)
		(fp_line
			(start 0.120396 0.3048)
			(end 0.120396 0.2794)
			(stroke
				(width 0.1)
				(type default)
			)
			(layer "F.Fab")
		)
		(fp_line
			(start 0.12065 -0.3048)
			(end 0.67945 -0.3048)
			(stroke
				(width 0.1)
				(type default)
			)
			(layer "F.Fab")
		)
		(fp_line
			(start 0.12065 -0.2794)
			(end 0.12065 -0.3048)
			(stroke
				(width 0.1)
				(type default)
			)
			(layer "F.Fab")
		)
		(fp_line
			(start 0.67945 -0.3048)
			(end 0.67945 0.3048)
			(stroke
				(width 0.1)
				(type default)
			)
			(layer "F.Fab")
		)
		(fp_line
			(start 0.67945 0.3048)
			(end 0.120396 0.3048)
			(stroke
				(width 0.1)
				(type default)
			)
			(layer "F.Fab")
		)
		(pad "1" smd circle
			(at -0.40005 0)
			(size 0 0)
			(layers "F.Cu" "F.Mask" "F.Paste")
			(net "P12V_OCP_PWRGD_1")
		)
		(pad "2" smd circle
			(at 0.40005 0)
			(size 0 0)
			(layers "F.Cu" "F.Mask" "F.Paste")
			(net "HP_LVC3_OCP_V3_1_P12V_PWRGD")
		)
	)
	(footprint ""
		(layer "F.Cu")
		(at 52.143406 -150.15083 180)
		(property "Reference" "PC88"
			(at 0 0 180)
			(layer "F.SilkS")
			(hide yes)
			(effects
				(font
					(size 1.27 1.27)
				)
			)
		)
		(property "Value" ""
			(at 0 0 180)
			(layer "F.Fab")
			(effects
				(font
					(size 1.27 1.27)
				)
			)
		)
		(duplicate_pad_numbers_are_jumpers no)
		(fp_line
			(start 1.524 0.762)
			(end -1.524 0.762)
			(stroke
				(width 0.1524)
				(type default)
			)
			(layer "F.SilkS")
		)
		(fp_line
			(start 1.524 -0.762)
			(end 1.524 0.762)
			(stroke
				(width 0.1524)
				(type default)
			)
			(layer "F.SilkS")
		)
		(fp_line
			(start -1.524 0.762)
			(end -1.524 -0.762)
			(stroke
				(width 0.1524)
				(type default)
			)
			(layer "F.SilkS")
		)
		(fp_line
			(start -1.524 -0.762)
			(end 1.524 -0.762)
			(stroke
				(width 0.1524)
				(type default)
			)
			(layer "F.SilkS")
		)
		(fp_line
			(start 1.1049 0.724916)
			(end 1.1049 -0.724916)
			(stroke
				(width 0.1)
				(type default)
			)
			(layer "F.Fab")
		)
		(fp_line
			(start 1.1049 -0.724916)
			(end -1.1049 -0.724916)
			(stroke
				(width 0.1)
				(type default)
			)
			(layer "F.Fab")
		)
		(fp_line
			(start -1.1049 0.724916)
			(end 1.1049 0.724916)
			(stroke
				(width 0.1)
				(type default)
			)
			(layer "F.Fab")
		)
		(fp_line
			(start -1.1049 -0.724916)
			(end -1.1049 0.724916)
			(stroke
				(width 0.1)
				(type default)
			)
			(layer "F.Fab")
		)
		(pad "1" smd rect
			(at -0.889 0)
			(size 1.016 1.27)
			(layers "F.Cu" "F.Mask" "F.Paste")
			(net "PVDD18_S5_P1")
		)
		(pad "2" smd rect
			(at 0.889 0)
			(size 1.016 1.27)
			(layers "F.Cu" "F.Mask" "F.Paste")
			(net "GND")
		)
	)
	(footprint ""
		(layer "F.Cu")
		(at 176.115218 -92.685616 -90)
		(property "Reference" "R6745"
			(at 0 0 270)
			(layer "F.SilkS")
			(hide yes)
			(effects
				(font
					(size 1.27 1.27)
				)
			)
		)
		(property "Value" ""
			(at 0 0 270)
			(layer "F.Fab")
			(effects
				(font
					(size 1.27 1.27)
				)
			)
		)
		(duplicate_pad_numbers_are_jumpers no)
		(fp_line
			(start -0.7874 0.4064)
			(end -0.7874 -0.4064)
			(stroke
				(width 0.1524)
				(type default)
			)
			(layer "F.SilkS")
		)
		(fp_line
			(start 0.7874 0.4064)
			(end -0.7874 0.4064)
			(stroke
				(width 0.1524)
				(type default)
			)
			(layer "F.SilkS")
		)
		(fp_line
			(start -0.7874 -0.4064)
			(end 0.7874 -0.4064)
			(stroke
				(width 0.1524)
				(type default)
			)
			(layer "F.SilkS")
		)
		(fp_line
			(start 0.7874 -0.4064)
			(end 0.7874 0.4064)
			(stroke
				(width 0.1524)
				(type default)
			)
			(layer "F.SilkS")
		)
		(fp_line
			(start -0.67945 0.3048)
			(end -0.67945 -0.305054)
			(stroke
				(width 0.1)
				(type default)
			)
			(layer "F.Fab")
		)
		(fp_line
			(start -0.12065 0.3048)
			(end -0.67945 0.3048)
			(stroke
				(width 0.1)
				(type default)
			)
			(layer "F.Fab")
		)
		(fp_line
			(start 0.120396 0.3048)
			(end 0.120396 0.2794)
			(stroke
				(width 0.1)
				(type default)
			)
			(layer "F.Fab")
		)
		(fp_line
			(start 0.67945 0.3048)
			(end 0.120396 0.3048)
			(stroke
				(width 0.1)
				(type default)
			)
			(layer "F.Fab")
		)
		(fp_line
			(start -0.12065 0.2794)
			(end -0.12065 0.3048)
			(stroke
				(width 0.1)
				(type default)
			)
			(layer "F.Fab")
		)
		(fp_line
			(start 0.120396 0.2794)
			(end -0.12065 0.2794)
			(stroke
				(width 0.1)
				(type default)
			)
			(layer "F.Fab")
		)
		(fp_line
			(start -0.12065 -0.2794)
			(end 0.12065 -0.2794)
			(stroke
				(width 0.1)
				(type default)
			)
			(layer "F.Fab")
		)
		(fp_line
			(start 0.12065 -0.2794)
			(end 0.12065 -0.3048)
			(stroke
				(width 0.1)
				(type default)
			)
			(layer "F.Fab")
		)
		(fp_line
			(start 0.12065 -0.3048)
			(end 0.67945 -0.3048)
			(stroke
				(width 0.1)
				(type default)
			)
			(layer "F.Fab")
		)
		(fp_line
			(start 0.67945 -0.3048)
			(end 0.67945 0.3048)
			(stroke
				(width 0.1)
				(type default)
			)
			(layer "F.Fab")
		)
		(fp_line
			(start -0.67945 -0.305054)
			(end -0.12065 -0.305054)
			(stroke
				(width 0.1)
				(type default)
			)
			(layer "F.Fab")
		)
		(fp_line
			(start -0.12065 -0.305054)
			(end -0.12065 -0.2794)
			(stroke
				(width 0.1)
				(type default)
			)
			(layer "F.Fab")
		)
		(pad "1" smd circle
			(at -0.40005 0 270)
			(size 0 0)
			(layers "F.Cu" "F.Mask" "F.Paste")
			(net "RT_BOARD_ID_ID0")
		)
		(pad "2" smd circle
			(at 0.40005 0 270)
			(size 0 0)
			(layers "F.Cu" "F.Mask" "F.Paste")
			(net "GND")
		)
	)
	(footprint ""
		(layer "F.Cu")
		(at 279.708864 -414.051242)
		(property "Reference" "R6864"
			(at 0 0 0)
			(layer "F.SilkS")
			(hide yes)
			(effects
				(font
					(size 1.27 1.27)
				)
			)
		)
		(property "Value" ""
			(at 0 0 0)
			(layer "F.Fab")
			(effects
				(font
					(size 1.27 1.27)
				)
			)
		)
		(duplicate_pad_numbers_are_jumpers no)
		(fp_line
			(start -0.7874 -0.4064)
			(end 0.7874 -0.4064)
			(stroke
				(width 0.1524)
				(type default)
			)
			(layer "F.SilkS")
		)
		(fp_line
			(start -0.7874 0.4064)
			(end -0.7874 -0.4064)
			(stroke
				(width 0.1524)
				(type default)
			)
			(layer "F.SilkS")
		)
		(fp_line
			(start 0.7874 -0.4064)
			(end 0.7874 0.4064)
			(stroke
				(width 0.1524)
				(type default)
			)
			(layer "F.SilkS")
		)
		(fp_line
			(start 0.7874 0.4064)
			(end -0.7874 0.4064)
			(stroke
				(width 0.1524)
				(type default)
			)
			(layer "F.SilkS")
		)
		(fp_line
			(start -0.67945 -0.305054)
			(end -0.12065 -0.305054)
			(stroke
				(width 0.1)
				(type default)
			)
			(layer "F.Fab")
		)
		(fp_line
			(start -0.67945 0.3048)
			(end -0.67945 -0.305054)
			(stroke
				(width 0.1)
				(type default)
			)
			(layer "F.Fab")
		)
		(fp_line
			(start -0.12065 -0.305054)
			(end -0.12065 -0.2794)
			(stroke
				(width 0.1)
				(type default)
			)
			(layer "F.Fab")
		)
		(fp_line
			(start -0.12065 -0.2794)
			(end 0.12065 -0.2794)
			(stroke
				(width 0.1)
				(type default)
			)
			(layer "F.Fab")
		)
		(fp_line
			(start -0.12065 0.2794)
			(end -0.12065 0.3048)
			(stroke
				(width 0.1)
				(type default)
			)
			(layer "F.Fab")
		)
		(fp_line
			(start -0.12065 0.3048)
			(end -0.67945 0.3048)
			(stroke
				(width 0.1)
				(type default)
			)
			(layer "F.Fab")
		)
		(fp_line
			(start 0.120396 0.2794)
			(end -0.12065 0.2794)
			(stroke
				(width 0.1)
				(type default)
			)
			(layer "F.Fab")
		)
		(fp_line
			(start 0.120396 0.3048)
			(end 0.120396 0.2794)
			(stroke
				(width 0.1)
				(type default)
			)
			(layer "F.Fab")
		)
		(fp_line
			(start 0.12065 -0.3048)
			(end 0.67945 -0.3048)
			(stroke
				(width 0.1)
				(type default)
			)
			(layer "F.Fab")
		)
		(fp_line
			(start 0.12065 -0.2794)
			(end 0.12065 -0.3048)
			(stroke
				(width 0.1)
				(type default)
			)
			(layer "F.Fab")
		)
		(fp_line
			(start 0.67945 -0.3048)
			(end 0.67945 0.3048)
			(stroke
				(width 0.1)
				(type default)
			)
			(layer "F.Fab")
		)
		(fp_line
			(start 0.67945 0.3048)
			(end 0.120396 0.3048)
			(stroke
				(width 0.1)
				(type default)
			)
			(layer "F.Fab")
		)
		(pad "1" smd circle
			(at -0.40005 0)
			(size 0 0)
			(layers "F.Cu" "F.Mask" "F.Paste")
			(net "SMB_HOST_CLK_3V3AUX_SCL_R1")
		)
		(pad "2" smd circle
			(at 0.40005 0)
			(size 0 0)
			(layers "F.Cu" "F.Mask" "F.Paste")
			(net "SMB_9ZXL045_P0_SCL")
		)
	)
	(footprint ""
		(layer "F.Cu")
		(at 126.804928 -48.137064)
		(property "Reference" "R6202"
			(at 0 0 0)
			(layer "F.SilkS")
			(hide yes)
			(effects
				(font
					(size 1.27 1.27)
				)
			)
		)
		(property "Value" ""
			(at 0 0 0)
			(layer "F.Fab")
			(effects
				(font
					(size 1.27 1.27)
				)
			)
		)
		(duplicate_pad_numbers_are_jumpers no)
		(fp_line
			(start -0.7874 -0.4064)
			(end 0.7874 -0.4064)
			(stroke
				(width 0.1524)
				(type default)
			)
			(layer "F.SilkS")
		)
		(fp_line
			(start -0.7874 0.4064)
			(end -0.7874 -0.4064)
			(stroke
				(width 0.1524)
				(type default)
			)
			(layer "F.SilkS")
		)
		(fp_line
			(start 0.7874 -0.4064)
			(end 0.7874 0.4064)
			(stroke
				(width 0.1524)
				(type default)
			)
			(layer "F.SilkS")
		)
		(fp_line
			(start 0.7874 0.4064)
			(end -0.7874 0.4064)
			(stroke
				(width 0.1524)
				(type default)
			)
			(layer "F.SilkS")
		)
		(fp_line
			(start -0.67945 -0.305054)
			(end -0.12065 -0.305054)
			(stroke
				(width 0.1)
				(type default)
			)
			(layer "F.Fab")
		)
		(fp_line
			(start -0.67945 0.3048)
			(end -0.67945 -0.305054)
			(stroke
				(width 0.1)
				(type default)
			)
			(layer "F.Fab")
		)
		(fp_line
			(start -0.12065 -0.305054)
			(end -0.12065 -0.2794)
			(stroke
				(width 0.1)
				(type default)
			)
			(layer "F.Fab")
		)
		(fp_line
			(start -0.12065 -0.2794)
			(end 0.12065 -0.2794)
			(stroke
				(width 0.1)
				(type default)
			)
			(layer "F.Fab")
		)
		(fp_line
			(start -0.12065 0.2794)
			(end -0.12065 0.3048)
			(stroke
				(width 0.1)
				(type default)
			)
			(layer "F.Fab")
		)
		(fp_line
			(start -0.12065 0.3048)
			(end -0.67945 0.3048)
			(stroke
				(width 0.1)
				(type default)
			)
			(layer "F.Fab")
		)
		(fp_line
			(start 0.120396 0.2794)
			(end -0.12065 0.2794)
			(stroke
				(width 0.1)
				(type default)
			)
			(layer "F.Fab")
		)
		(fp_line
			(start 0.120396 0.3048)
			(end 0.120396 0.2794)
			(stroke
				(width 0.1)
				(type default)
			)
			(layer "F.Fab")
		)
		(fp_line
			(start 0.12065 -0.3048)
			(end 0.67945 -0.3048)
			(stroke
				(width 0.1)
				(type default)
			)
			(layer "F.Fab")
		)
		(fp_line
			(start 0.12065 -0.2794)
			(end 0.12065 -0.3048)
			(stroke
				(width 0.1)
				(type default)
			)
			(layer "F.Fab")
		)
		(fp_line
			(start 0.67945 -0.3048)
			(end 0.67945 0.3048)
			(stroke
				(width 0.1)
				(type default)
			)
			(layer "F.Fab")
		)
		(fp_line
			(start 0.67945 0.3048)
			(end 0.120396 0.3048)
			(stroke
				(width 0.1)
				(type default)
			)
			(layer "F.Fab")
		)
		(pad "1" smd circle
			(at -0.40005 0)
			(size 0 0)
			(layers "F.Cu" "F.Mask" "F.Paste")
			(net "GND")
		)
		(pad "2" smd circle
			(at 0.40005 0)
			(size 0 0)
			(layers "F.Cu" "F.Mask" "F.Paste")
			(net "USB_CPU0_HUB1_RREF_SS")
		)
	)
	(footprint ""
		(layer "F.Cu")
		(at 313.518296 -381.41783 -90)
		(property "Reference" "C916"
			(at 0 0 270)
			(layer "F.SilkS")
			(hide yes)
			(effects
				(font
					(size 1.27 1.27)
				)
			)
		)
		(property "Value" ""
			(at 0 0 270)
			(layer "F.Fab")
			(effects
				(font
					(size 1.27 1.27)
				)
			)
		)
		(duplicate_pad_numbers_are_jumpers no)
		(fp_line
			(start -0.299974 0.150114)
			(end -0.299974 -0.150114)
			(stroke
				(width 0.1)
				(type default)
			)
			(layer "F.Fab")
		)
		(fp_line
			(start 0.299974 0.150114)
			(end -0.299974 0.150114)
			(stroke
				(width 0.1)
				(type default)
			)
			(layer "F.Fab")
		)
		(fp_line
			(start -0.299974 -0.150114)
			(end 0.299974 -0.150114)
			(stroke
				(width 0.1)
				(type default)
			)
			(layer "F.Fab")
		)
		(fp_line
			(start 0.299974 -0.150114)
			(end 0.299974 0.150114)
			(stroke
				(width 0.1)
				(type default)
			)
			(layer "F.Fab")
		)
		(pad "1" smd rect
			(at -0.2667 0 270)
			(size 0.3048 0.381)
			(layers "F.Cu" "F.Mask" "F.Paste")
			(net "P5E_CPU0_P0_TX_C_DN<8>")
		)
		(pad "2" smd rect
			(at 0.2667 0 270)
			(size 0.3048 0.381)
			(layers "F.Cu" "F.Mask" "F.Paste")
			(net "P5E_CPU0_P0_TX_DN<8>")
		)
	)
	(footprint ""
		(layer "F.Cu")
		(at 361.317032 -261.747762 -90)
		(property "Reference" "C2635"
			(at 0 0 270)
			(layer "F.SilkS")
			(hide yes)
			(effects
				(font
					(size 1.27 1.27)
				)
			)
		)
		(property "Value" ""
			(at 0 0 270)
			(layer "F.Fab")
			(effects
				(font
					(size 1.27 1.27)
				)
			)
		)
		(duplicate_pad_numbers_are_jumpers no)
		(fp_line
			(start -0.7874 0.4064)
			(end -0.7874 -0.4064)
			(stroke
				(width 0.1524)
				(type default)
			)
			(layer "F.SilkS")
		)
		(fp_line
			(start 0.7874 0.4064)
			(end -0.7874 0.4064)
			(stroke
				(width 0.1524)
				(type default)
			)
			(layer "F.SilkS")
		)
		(fp_line
			(start -0.7874 -0.4064)
			(end 0.7874 -0.4064)
			(stroke
				(width 0.1524)
				(type default)
			)
			(layer "F.SilkS")
		)
		(fp_line
			(start 0.7874 -0.4064)
			(end 0.7874 0.4064)
			(stroke
				(width 0.1524)
				(type default)
			)
			(layer "F.SilkS")
		)
		(fp_line
			(start -0.67945 0.3048)
			(end -0.67945 -0.305054)
			(stroke
				(width 0.1)
				(type default)
			)
			(layer "F.Fab")
		)
		(fp_line
			(start -0.12065 0.3048)
			(end -0.67945 0.3048)
			(stroke
				(width 0.1)
				(type default)
			)
			(layer "F.Fab")
		)
		(fp_line
			(start 0.120396 0.3048)
			(end 0.120396 0.2794)
			(stroke
				(width 0.1)
				(type default)
			)
			(layer "F.Fab")
		)
		(fp_line
			(start 0.67945 0.3048)
			(end 0.120396 0.3048)
			(stroke
				(width 0.1)
				(type default)
			)
			(layer "F.Fab")
		)
		(fp_line
			(start -0.12065 0.2794)
			(end -0.12065 0.3048)
			(stroke
				(width 0.1)
				(type default)
			)
			(layer "F.Fab")
		)
		(fp_line
			(start 0.120396 0.2794)
			(end -0.12065 0.2794)
			(stroke
				(width 0.1)
				(type default)
			)
			(layer "F.Fab")
		)
		(fp_line
			(start -0.12065 -0.2794)
			(end 0.12065 -0.2794)
			(stroke
				(width 0.1)
				(type default)
			)
			(layer "F.Fab")
		)
		(fp_line
			(start 0.12065 -0.2794)
			(end 0.12065 -0.3048)
			(stroke
				(width 0.1)
				(type default)
			)
			(layer "F.Fab")
		)
		(fp_line
			(start 0.12065 -0.3048)
			(end 0.67945 -0.3048)
			(stroke
				(width 0.1)
				(type default)
			)
			(layer "F.Fab")
		)
		(fp_line
			(start 0.67945 -0.3048)
			(end 0.67945 0.3048)
			(stroke
				(width 0.1)
				(type default)
			)
			(layer "F.Fab")
		)
		(fp_line
			(start -0.67945 -0.305054)
			(end -0.12065 -0.305054)
			(stroke
				(width 0.1)
				(type default)
			)
			(layer "F.Fab")
		)
		(fp_line
			(start -0.12065 -0.305054)
			(end -0.12065 -0.2794)
			(stroke
				(width 0.1)
				(type default)
			)
			(layer "F.Fab")
		)
		(pad "1" smd circle
			(at -0.40005 0 270)
			(size 0 0)
			(layers "F.Cu" "F.Mask" "F.Paste")
			(net "PVDD11_S3_P0")
		)
		(pad "2" smd circle
			(at 0.40005 0 270)
			(size 0 0)
			(layers "F.Cu" "F.Mask" "F.Paste")
			(net "GND")
		)
	)
	(footprint ""
		(layer "F.Cu")
		(at 138.2014 -389.27786 90)
		(property "Reference" "R1435"
			(at 0 0 90)
			(layer "F.SilkS")
			(hide yes)
			(effects
				(font
					(size 1.27 1.27)
				)
			)
		)
		(property "Value" ""
			(at 0 0 90)
			(layer "F.Fab")
			(effects
				(font
					(size 1.27 1.27)
				)
			)
		)
		(duplicate_pad_numbers_are_jumpers no)
		(fp_line
			(start 0.32512 -0.175006)
			(end 0.32512 0.175006)
			(stroke
				(width 0.1)
				(type default)
			)
			(layer "F.Fab")
		)
		(fp_line
			(start -0.32512 -0.175006)
			(end 0.32512 -0.175006)
			(stroke
				(width 0.1)
				(type default)
			)
			(layer "F.Fab")
		)
		(fp_line
			(start 0.32512 0.175006)
			(end -0.32512 0.175006)
			(stroke
				(width 0.1)
				(type default)
			)
			(layer "F.Fab")
		)
		(fp_line
			(start -0.32512 0.175006)
			(end -0.32512 -0.175006)
			(stroke
				(width 0.1)
				(type default)
			)
			(layer "F.Fab")
		)
		(pad "1" smd rect
			(at -0.2667 0 90)
			(size 0.3048 0.381)
			(layers "F.Cu" "F.Mask" "F.Paste")
			(net "RXDET_BYP_RT_CPU1_P3")
		)
		(pad "2" smd rect
			(at 0.2667 0 270)
			(size 0.3048 0.381)
			(layers "F.Cu" "F.Mask" "F.Paste")
			(net "GND")
		)
	)
	(footprint ""
		(layer "F.Cu")
		(at 358.959404 -28.695396)
		(property "Reference" "Q61"
			(at -0.26924 -2.352548 0)
			(unlocked yes)
			(layer "F.SilkS")
			(effects
				(font
					(size 0.7874 0.5842)
					(thickness 0.1524)
				)
			)
		)
		(property "Value" ""
			(at 0 0 0)
			(layer "F.Fab")
			(effects
				(font
					(size 1.27 1.27)
				)
			)
		)
		(duplicate_pad_numbers_are_jumpers no)
		(fp_line
			(start -1.8796 -1.651)
			(end 1.8796 -1.651)
			(stroke
				(width 0.1524)
				(type default)
			)
			(layer "F.SilkS")
		)
		(fp_line
			(start -1.8796 1.651)
			(end -1.8796 -1.651)
			(stroke
				(width 0.1524)
				(type default)
			)
			(layer "F.SilkS")
		)
		(fp_line
			(start 1.8796 -1.651)
			(end 1.8796 1.651)
			(stroke
				(width 0.1524)
				(type default)
			)
			(layer "F.SilkS")
		)
		(fp_line
			(start 1.8796 1.651)
			(end -1.8796 1.651)
			(stroke
				(width 0.1524)
				(type default)
			)
			(layer "F.SilkS")
		)
		(fp_line
			(start -0.700024 -1.500124)
			(end 0.700024 -1.500124)
			(stroke
				(width 0.1)
				(type default)
			)
			(layer "F.Fab")
		)
		(fp_line
			(start -0.700024 1.500124)
			(end -0.700024 -1.500124)
			(stroke
				(width 0.1)
				(type default)
			)
			(layer "F.Fab")
		)
		(fp_line
			(start 0.700024 -1.500124)
			(end 0.700024 1.500124)
			(stroke
				(width 0.1)
				(type default)
			)
			(layer "F.Fab")
		)
		(fp_line
			(start 0.700024 1.500124)
			(end -0.700024 1.500124)
			(stroke
				(width 0.1)
				(type default)
			)
			(layer "F.Fab")
		)
		(pad "D" smd rect
			(at 1.119886 0 270)
			(size 1.016 1.2192)
			(layers "F.Cu" "F.Mask" "F.Paste")
			(net "UART_LS_EN_R_N")
		)
		(pad "G" smd rect
			(at -1.119886 -0.999998 270)
			(size 1.016 1.2192)
			(layers "F.Cu" "F.Mask" "F.Paste")
			(net "UART_LS_EN")
		)
		(pad "S" smd rect
			(at -1.119886 0.999998 270)
			(size 1.016 1.2192)
			(layers "F.Cu" "F.Mask" "F.Paste")
			(net "GND")
		)
	)
	(footprint ""
		(layer "F.Cu")
		(at 136.840976 -376.067828)
		(property "Reference" "C50"
			(at 0 0 0)
			(layer "F.SilkS")
			(hide yes)
			(effects
				(font
					(size 1.27 1.27)
				)
			)
		)
		(property "Value" ""
			(at 0 0 0)
			(layer "F.Fab")
			(effects
				(font
					(size 1.27 1.27)
				)
			)
		)
		(duplicate_pad_numbers_are_jumpers no)
		(fp_line
			(start -0.299974 -0.150114)
			(end 0.299974 -0.150114)
			(stroke
				(width 0.1)
				(type default)
			)
			(layer "F.Fab")
		)
		(fp_line
			(start -0.299974 0.150114)
			(end -0.299974 -0.150114)
			(stroke
				(width 0.1)
				(type default)
			)
			(layer "F.Fab")
		)
		(fp_line
			(start 0.299974 -0.150114)
			(end 0.299974 0.150114)
			(stroke
				(width 0.1)
				(type default)
			)
			(layer "F.Fab")
		)
		(fp_line
			(start 0.299974 0.150114)
			(end -0.299974 0.150114)
			(stroke
				(width 0.1)
				(type default)
			)
			(layer "F.Fab")
		)
		(pad "1" smd rect
			(at -0.2667 0)
			(size 0.3048 0.381)
			(layers "F.Cu" "F.Mask" "F.Paste")
			(net "P5E_CPU1_P3_TX_C_DN<14>")
		)
		(pad "2" smd rect
			(at 0.2667 0)
			(size 0.3048 0.381)
			(layers "F.Cu" "F.Mask" "F.Paste")
			(net "P5E_CPU1_P3_TX_DN<14>")
		)
	)
	(footprint ""
		(layer "F.Cu")
		(at 271.728184 -343.712038 180)
		(property "Reference" "PC163"
			(at 0 0 180)
			(layer "F.SilkS")
			(hide yes)
			(effects
				(font
					(size 1.27 1.27)
				)
			)
		)
		(property "Value" ""
			(at 0 0 180)
			(layer "F.Fab")
			(effects
				(font
					(size 1.27 1.27)
				)
			)
		)
		(duplicate_pad_numbers_are_jumpers no)
		(fp_line
			(start 0.7874 0.4064)
			(end -0.7874 0.4064)
			(stroke
				(width 0.1524)
				(type default)
			)
			(layer "F.SilkS")
		)
		(fp_line
			(start 0.7874 -0.4064)
			(end 0.7874 0.4064)
			(stroke
				(width 0.1524)
				(type default)
			)
			(layer "F.SilkS")
		)
		(fp_line
			(start -0.7874 0.4064)
			(end -0.7874 -0.4064)
			(stroke
				(width 0.1524)
				(type default)
			)
			(layer "F.SilkS")
		)
		(fp_line
			(start -0.7874 -0.4064)
			(end 0.7874 -0.4064)
			(stroke
				(width 0.1524)
				(type default)
			)
			(layer "F.SilkS")
		)
		(fp_line
			(start 0.67945 0.3048)
			(end 0.120396 0.3048)
			(stroke
				(width 0.1)
				(type default)
			)
			(layer "F.Fab")
		)
		(fp_line
			(start 0.67945 -0.3048)
			(end 0.67945 0.3048)
			(stroke
				(width 0.1)
				(type default)
			)
			(layer "F.Fab")
		)
		(fp_line
			(start 0.12065 -0.2794)
			(end 0.12065 -0.3048)
			(stroke
				(width 0.1)
				(type default)
			)
			(layer "F.Fab")
		)
		(fp_line
			(start 0.12065 -0.3048)
			(end 0.67945 -0.3048)
			(stroke
				(width 0.1)
				(type default)
			)
			(layer "F.Fab")
		)
		(fp_line
			(start 0.120396 0.3048)
			(end 0.120396 0.2794)
			(stroke
				(width 0.1)
				(type default)
			)
			(layer "F.Fab")
		)
		(fp_line
			(start 0.120396 0.2794)
			(end -0.12065 0.2794)
			(stroke
				(width 0.1)
				(type default)
			)
			(layer "F.Fab")
		)
		(fp_line
			(start -0.12065 0.3048)
			(end -0.67945 0.3048)
			(stroke
				(width 0.1)
				(type default)
			)
			(layer "F.Fab")
		)
		(fp_line
			(start -0.12065 0.2794)
			(end -0.12065 0.3048)
			(stroke
				(width 0.1)
				(type default)
			)
			(layer "F.Fab")
		)
		(fp_line
			(start -0.12065 -0.2794)
			(end 0.12065 -0.2794)
			(stroke
				(width 0.1)
				(type default)
			)
			(layer "F.Fab")
		)
		(fp_line
			(start -0.12065 -0.305054)
			(end -0.12065 -0.2794)
			(stroke
				(width 0.1)
				(type default)
			)
			(layer "F.Fab")
		)
		(fp_line
			(start -0.67945 0.3048)
			(end -0.67945 -0.305054)
			(stroke
				(width 0.1)
				(type default)
			)
			(layer "F.Fab")
		)
		(fp_line
			(start -0.67945 -0.305054)
			(end -0.12065 -0.305054)
			(stroke
				(width 0.1)
				(type default)
			)
			(layer "F.Fab")
		)
		(pad "1" smd circle
			(at -0.40005 0 180)
			(size 0 0)
			(layers "F.Cu" "F.Mask" "F.Paste")
			(net "SW_PVDDIO_P0_SW4")
		)
		(pad "2" smd circle
			(at 0.40005 0 180)
			(size 0 0)
			(layers "F.Cu" "F.Mask" "F.Paste")
			(net "SW_PVDDIO_P0_SW4_RC")
		)
	)
	(footprint ""
		(layer "F.Cu")
		(at 312.603896 -381.41783 -90)
		(property "Reference" "C917"
			(at 0 0 270)
			(layer "F.SilkS")
			(hide yes)
			(effects
				(font
					(size 1.27 1.27)
				)
			)
		)
		(property "Value" ""
			(at 0 0 270)
			(layer "F.Fab")
			(effects
				(font
					(size 1.27 1.27)
				)
			)
		)
		(duplicate_pad_numbers_are_jumpers no)
		(fp_line
			(start -0.299974 0.150114)
			(end -0.299974 -0.150114)
			(stroke
				(width 0.1)
				(type default)
			)
			(layer "F.Fab")
		)
		(fp_line
			(start 0.299974 0.150114)
			(end -0.299974 0.150114)
			(stroke
				(width 0.1)
				(type default)
			)
			(layer "F.Fab")
		)
		(fp_line
			(start -0.299974 -0.150114)
			(end 0.299974 -0.150114)
			(stroke
				(width 0.1)
				(type default)
			)
			(layer "F.Fab")
		)
		(fp_line
			(start 0.299974 -0.150114)
			(end 0.299974 0.150114)
			(stroke
				(width 0.1)
				(type default)
			)
			(layer "F.Fab")
		)
		(pad "1" smd rect
			(at -0.2667 0 270)
			(size 0.3048 0.381)
			(layers "F.Cu" "F.Mask" "F.Paste")
			(net "P5E_CPU0_P0_TX_C_DP<8>")
		)
		(pad "2" smd rect
			(at 0.2667 0 270)
			(size 0.3048 0.381)
			(layers "F.Cu" "F.Mask" "F.Paste")
			(net "P5E_CPU0_P0_TX_DP<8>")
		)
	)
	(footprint ""
		(layer "F.Cu")
		(at 63.575438 -31.887922 90)
		(property "Reference" "PR3849"
			(at 0 0 90)
			(layer "F.SilkS")
			(hide yes)
			(effects
				(font
					(size 1.27 1.27)
				)
			)
		)
		(property "Value" ""
			(at 0 0 90)
			(layer "F.Fab")
			(effects
				(font
					(size 1.27 1.27)
				)
			)
		)
		(duplicate_pad_numbers_are_jumpers no)
		(fp_line
			(start 0.7874 -0.4064)
			(end 0.7874 0.4064)
			(stroke
				(width 0.1524)
				(type default)
			)
			(layer "F.SilkS")
		)
		(fp_line
			(start -0.7874 -0.4064)
			(end 0.7874 -0.4064)
			(stroke
				(width 0.1524)
				(type default)
			)
			(layer "F.SilkS")
		)
		(fp_line
			(start 0.7874 0.4064)
			(end -0.7874 0.4064)
			(stroke
				(width 0.1524)
				(type default)
			)
			(layer "F.SilkS")
		)
		(fp_line
			(start -0.7874 0.4064)
			(end -0.7874 -0.4064)
			(stroke
				(width 0.1524)
				(type default)
			)
			(layer "F.SilkS")
		)
		(fp_line
			(start -0.12065 -0.305054)
			(end -0.12065 -0.2794)
			(stroke
				(width 0.1)
				(type default)
			)
			(layer "F.Fab")
		)
		(fp_line
			(start -0.67945 -0.305054)
			(end -0.12065 -0.305054)
			(stroke
				(width 0.1)
				(type default)
			)
			(layer "F.Fab")
		)
		(fp_line
			(start 0.67945 -0.3048)
			(end 0.67945 0.3048)
			(stroke
				(width 0.1)
				(type default)
			)
			(layer "F.Fab")
		)
		(fp_line
			(start 0.12065 -0.3048)
			(end 0.67945 -0.3048)
			(stroke
				(width 0.1)
				(type default)
			)
			(layer "F.Fab")
		)
		(fp_line
			(start 0.12065 -0.2794)
			(end 0.12065 -0.3048)
			(stroke
				(width 0.1)
				(type default)
			)
			(layer "F.Fab")
		)
		(fp_line
			(start -0.12065 -0.2794)
			(end 0.12065 -0.2794)
			(stroke
				(width 0.1)
				(type default)
			)
			(layer "F.Fab")
		)
		(fp_line
			(start 0.120396 0.2794)
			(end -0.12065 0.2794)
			(stroke
				(width 0.1)
				(type default)
			)
			(layer "F.Fab")
		)
		(fp_line
			(start -0.12065 0.2794)
			(end -0.12065 0.3048)
			(stroke
				(width 0.1)
				(type default)
			)
			(layer "F.Fab")
		)
		(fp_line
			(start 0.67945 0.3048)
			(end 0.120396 0.3048)
			(stroke
				(width 0.1)
				(type default)
			)
			(layer "F.Fab")
		)
		(fp_line
			(start 0.120396 0.3048)
			(end 0.120396 0.2794)
			(stroke
				(width 0.1)
				(type default)
			)
			(layer "F.Fab")
		)
		(fp_line
			(start -0.12065 0.3048)
			(end -0.67945 0.3048)
			(stroke
				(width 0.1)
				(type default)
			)
			(layer "F.Fab")
		)
		(fp_line
			(start -0.67945 0.3048)
			(end -0.67945 -0.305054)
			(stroke
				(width 0.1)
				(type default)
			)
			(layer "F.Fab")
		)
		(pad "1" smd circle
			(at -0.40005 0 90)
			(size 0 0)
			(layers "F.Cu" "F.Mask" "F.Paste")
			(net "P12V_OCP_IMON_2")
		)
		(pad "2" smd circle
			(at 0.40005 0 90)
			(size 0 0)
			(layers "F.Cu" "F.Mask" "F.Paste")
			(net "GND")
		)
	)
	(footprint ""
		(layer "F.Cu")
		(at 364.167166 -261.747762 -90)
		(property "Reference" "C2633"
			(at 0 0 270)
			(layer "F.SilkS")
			(hide yes)
			(effects
				(font
					(size 1.27 1.27)
				)
			)
		)
		(property "Value" ""
			(at 0 0 270)
			(layer "F.Fab")
			(effects
				(font
					(size 1.27 1.27)
				)
			)
		)
		(duplicate_pad_numbers_are_jumpers no)
		(fp_line
			(start -0.7874 0.4064)
			(end -0.7874 -0.4064)
			(stroke
				(width 0.1524)
				(type default)
			)
			(layer "F.SilkS")
		)
		(fp_line
			(start 0.7874 0.4064)
			(end -0.7874 0.4064)
			(stroke
				(width 0.1524)
				(type default)
			)
			(layer "F.SilkS")
		)
		(fp_line
			(start -0.7874 -0.4064)
			(end 0.7874 -0.4064)
			(stroke
				(width 0.1524)
				(type default)
			)
			(layer "F.SilkS")
		)
		(fp_line
			(start 0.7874 -0.4064)
			(end 0.7874 0.4064)
			(stroke
				(width 0.1524)
				(type default)
			)
			(layer "F.SilkS")
		)
		(fp_line
			(start -0.67945 0.3048)
			(end -0.67945 -0.305054)
			(stroke
				(width 0.1)
				(type default)
			)
			(layer "F.Fab")
		)
		(fp_line
			(start -0.12065 0.3048)
			(end -0.67945 0.3048)
			(stroke
				(width 0.1)
				(type default)
			)
			(layer "F.Fab")
		)
		(fp_line
			(start 0.120396 0.3048)
			(end 0.120396 0.2794)
			(stroke
				(width 0.1)
				(type default)
			)
			(layer "F.Fab")
		)
		(fp_line
			(start 0.67945 0.3048)
			(end 0.120396 0.3048)
			(stroke
				(width 0.1)
				(type default)
			)
			(layer "F.Fab")
		)
		(fp_line
			(start -0.12065 0.2794)
			(end -0.12065 0.3048)
			(stroke
				(width 0.1)
				(type default)
			)
			(layer "F.Fab")
		)
		(fp_line
			(start 0.120396 0.2794)
			(end -0.12065 0.2794)
			(stroke
				(width 0.1)
				(type default)
			)
			(layer "F.Fab")
		)
		(fp_line
			(start -0.12065 -0.2794)
			(end 0.12065 -0.2794)
			(stroke
				(width 0.1)
				(type default)
			)
			(layer "F.Fab")
		)
		(fp_line
			(start 0.12065 -0.2794)
			(end 0.12065 -0.3048)
			(stroke
				(width 0.1)
				(type default)
			)
			(layer "F.Fab")
		)
		(fp_line
			(start 0.12065 -0.3048)
			(end 0.67945 -0.3048)
			(stroke
				(width 0.1)
				(type default)
			)
			(layer "F.Fab")
		)
		(fp_line
			(start 0.67945 -0.3048)
			(end 0.67945 0.3048)
			(stroke
				(width 0.1)
				(type default)
			)
			(layer "F.Fab")
		)
		(fp_line
			(start -0.67945 -0.305054)
			(end -0.12065 -0.305054)
			(stroke
				(width 0.1)
				(type default)
			)
			(layer "F.Fab")
		)
		(fp_line
			(start -0.12065 -0.305054)
			(end -0.12065 -0.2794)
			(stroke
				(width 0.1)
				(type default)
			)
			(layer "F.Fab")
		)
		(pad "1" smd circle
			(at -0.40005 0 270)
			(size 0 0)
			(layers "F.Cu" "F.Mask" "F.Paste")
			(net "PVDD11_S3_P0")
		)
		(pad "2" smd circle
			(at 0.40005 0 270)
			(size 0 0)
			(layers "F.Cu" "F.Mask" "F.Paste")
			(net "GND")
		)
	)
	(footprint ""
		(layer "F.Cu")
		(at 392.531092 -378.95403 -90)
		(property "Reference" "C874"
			(at 0 0 270)
			(layer "F.SilkS")
			(hide yes)
			(effects
				(font
					(size 1.27 1.27)
				)
			)
		)
		(property "Value" ""
			(at 0 0 270)
			(layer "F.Fab")
			(effects
				(font
					(size 1.27 1.27)
				)
			)
		)
		(duplicate_pad_numbers_are_jumpers no)
		(fp_line
			(start -0.299974 0.150114)
			(end -0.299974 -0.150114)
			(stroke
				(width 0.1)
				(type default)
			)
			(layer "F.Fab")
		)
		(fp_line
			(start 0.299974 0.150114)
			(end -0.299974 0.150114)
			(stroke
				(width 0.1)
				(type default)
			)
			(layer "F.Fab")
		)
		(fp_line
			(start -0.299974 -0.150114)
			(end 0.299974 -0.150114)
			(stroke
				(width 0.1)
				(type default)
			)
			(layer "F.Fab")
		)
		(fp_line
			(start 0.299974 -0.150114)
			(end 0.299974 0.150114)
			(stroke
				(width 0.1)
				(type default)
			)
			(layer "F.Fab")
		)
		(pad "1" smd rect
			(at -0.2667 0 270)
			(size 0.3048 0.381)
			(layers "F.Cu" "F.Mask" "F.Paste")
			(net "P5E_CPU0_P3_TX_C_DN<13>")
		)
		(pad "2" smd rect
			(at 0.2667 0 270)
			(size 0.3048 0.381)
			(layers "F.Cu" "F.Mask" "F.Paste")
			(net "P5E_CPU0_P3_TX_DN<13>")
		)
	)
	(footprint ""
		(layer "F.Cu")
		(at 11.717782 -415.263584 90)
		(property "Reference" "PR6544"
			(at 0 0 90)
			(layer "F.SilkS")
			(hide yes)
			(effects
				(font
					(size 1.27 1.27)
				)
			)
		)
		(property "Value" ""
			(at 0 0 90)
			(layer "F.Fab")
			(effects
				(font
					(size 1.27 1.27)
				)
			)
		)
		(duplicate_pad_numbers_are_jumpers no)
		(fp_line
			(start 0.7874 -0.4064)
			(end 0.7874 0.4064)
			(stroke
				(width 0.1524)
				(type default)
			)
			(layer "F.SilkS")
		)
		(fp_line
			(start -0.7874 -0.4064)
			(end 0.7874 -0.4064)
			(stroke
				(width 0.1524)
				(type default)
			)
			(layer "F.SilkS")
		)
		(fp_line
			(start 0.7874 0.4064)
			(end -0.7874 0.4064)
			(stroke
				(width 0.1524)
				(type default)
			)
			(layer "F.SilkS")
		)
		(fp_line
			(start -0.7874 0.4064)
			(end -0.7874 -0.4064)
			(stroke
				(width 0.1524)
				(type default)
			)
			(layer "F.SilkS")
		)
		(fp_line
			(start -0.12065 -0.305054)
			(end -0.12065 -0.2794)
			(stroke
				(width 0.1)
				(type default)
			)
			(layer "F.Fab")
		)
		(fp_line
			(start -0.67945 -0.305054)
			(end -0.12065 -0.305054)
			(stroke
				(width 0.1)
				(type default)
			)
			(layer "F.Fab")
		)
		(fp_line
			(start 0.67945 -0.3048)
			(end 0.67945 0.3048)
			(stroke
				(width 0.1)
				(type default)
			)
			(layer "F.Fab")
		)
		(fp_line
			(start 0.12065 -0.3048)
			(end 0.67945 -0.3048)
			(stroke
				(width 0.1)
				(type default)
			)
			(layer "F.Fab")
		)
		(fp_line
			(start 0.12065 -0.2794)
			(end 0.12065 -0.3048)
			(stroke
				(width 0.1)
				(type default)
			)
			(layer "F.Fab")
		)
		(fp_line
			(start -0.12065 -0.2794)
			(end 0.12065 -0.2794)
			(stroke
				(width 0.1)
				(type default)
			)
			(layer "F.Fab")
		)
		(fp_line
			(start 0.120396 0.2794)
			(end -0.12065 0.2794)
			(stroke
				(width 0.1)
				(type default)
			)
			(layer "F.Fab")
		)
		(fp_line
			(start -0.12065 0.2794)
			(end -0.12065 0.3048)
			(stroke
				(width 0.1)
				(type default)
			)
			(layer "F.Fab")
		)
		(fp_line
			(start 0.67945 0.3048)
			(end 0.120396 0.3048)
			(stroke
				(width 0.1)
				(type default)
			)
			(layer "F.Fab")
		)
		(fp_line
			(start 0.120396 0.3048)
			(end 0.120396 0.2794)
			(stroke
				(width 0.1)
				(type default)
			)
			(layer "F.Fab")
		)
		(fp_line
			(start -0.12065 0.3048)
			(end -0.67945 0.3048)
			(stroke
				(width 0.1)
				(type default)
			)
			(layer "F.Fab")
		)
		(fp_line
			(start -0.67945 0.3048)
			(end -0.67945 -0.305054)
			(stroke
				(width 0.1)
				(type default)
			)
			(layer "F.Fab")
		)
		(pad "1" smd circle
			(at -0.40005 0 90)
			(size 0 0)
			(layers "F.Cu" "F.Mask" "F.Paste")
			(net "NC_P0V9_RETIMER_CPU1_IMON8")
		)
		(pad "2" smd circle
			(at 0.40005 0 90)
			(size 0 0)
			(layers "F.Cu" "F.Mask" "F.Paste")
			(net "GND")
		)
	)
	(footprint ""
		(layer "F.Cu")
		(at 145.128488 -394.166852 -90)
		(property "Reference" "R886"
			(at 0 0 270)
			(layer "F.SilkS")
			(hide yes)
			(effects
				(font
					(size 1.27 1.27)
				)
			)
		)
		(property "Value" ""
			(at 0 0 270)
			(layer "F.Fab")
			(effects
				(font
					(size 1.27 1.27)
				)
			)
		)
		(duplicate_pad_numbers_are_jumpers no)
		(fp_line
			(start -0.32512 0.175006)
			(end -0.32512 -0.175006)
			(stroke
				(width 0.1)
				(type default)
			)
			(layer "F.Fab")
		)
		(fp_line
			(start 0.32512 0.175006)
			(end -0.32512 0.175006)
			(stroke
				(width 0.1)
				(type default)
			)
			(layer "F.Fab")
		)
		(fp_line
			(start -0.32512 -0.175006)
			(end 0.32512 -0.175006)
			(stroke
				(width 0.1)
				(type default)
			)
			(layer "F.Fab")
		)
		(fp_line
			(start 0.32512 -0.175006)
			(end 0.32512 0.175006)
			(stroke
				(width 0.1)
				(type default)
			)
			(layer "F.Fab")
		)
		(pad "1" smd rect
			(at -0.2667 0 270)
			(size 0.3048 0.381)
			(layers "F.Cu" "F.Mask" "F.Paste")
			(net "MODE_RT_CPU1_P2")
		)
		(pad "2" smd rect
			(at 0.2667 0 90)
			(size 0.3048 0.381)
			(layers "F.Cu" "F.Mask" "F.Paste")
			(net "GND")
		)
	)
	(footprint ""
		(layer "F.Cu")
		(at 286.928052 -119.207026)
		(property "Reference" "U36"
			(at -2.1844 -4.587748 0)
			(unlocked yes)
			(layer "F.SilkS")
			(effects
				(font
					(size 0.7874 0.5842)
					(thickness 0.1524)
				)
				(justify left)
			)
		)
		(property "Value" ""
			(at 0 0 0)
			(layer "F.Fab")
			(effects
				(font
					(size 1.27 1.27)
				)
			)
		)
		(duplicate_pad_numbers_are_jumpers no)
		(fp_line
			(start -1.8542 -3.949954)
			(end -1.8542 3.949954)
			(stroke
				(width 0.1524)
				(type default)
			)
			(layer "F.SilkS")
		)
		(fp_line
			(start -1.8542 3.949954)
			(end 1.8542 3.949954)
			(stroke
				(width 0.1524)
				(type default)
			)
			(layer "F.SilkS")
		)
		(fp_line
			(start -1.282954 -3.949954)
			(end -1.8542 -3.949954)
			(stroke
				(width 0.1524)
				(type default)
			)
			(layer "F.SilkS")
		)
		(fp_line
			(start 0 -2.667)
			(end -1.282954 -3.949954)
			(stroke
				(width 0.1524)
				(type default)
			)
			(layer "F.SilkS")
		)
		(fp_line
			(start 1.282954 -3.949954)
			(end 0 -2.667)
			(stroke
				(width 0.1524)
				(type default)
			)
			(layer "F.SilkS")
		)
		(fp_line
			(start 1.8542 -3.949954)
			(end 1.282954 -3.949954)
			(stroke
				(width 0.1524)
				(type default)
			)
			(layer "F.SilkS")
		)
		(fp_line
			(start 1.8542 3.949954)
			(end 1.8542 -3.949954)
			(stroke
				(width 0.1524)
				(type default)
			)
			(layer "F.SilkS")
		)
		(fp_poly
			(pts
				(xy -3.074416 -3.996182) (xy -3.582416 -5.012182) (xy -2.566416 -5.012182)
			)
			(stroke
				(width 0)
				(type default)
			)
			(fill yes)
			(layer "F.SilkS")
		)
		(fp_line
			(start -2.249932 -3.949954)
			(end -2.249932 3.949954)
			(stroke
				(width 0.1)
				(type default)
			)
			(layer "F.Fab")
		)
		(fp_line
			(start -2.249932 3.949954)
			(end 2.249932 3.949954)
			(stroke
				(width 0.1)
				(type default)
			)
			(layer "F.Fab")
		)
		(fp_line
			(start 2.249932 -3.949954)
			(end -2.249932 -3.949954)
			(stroke
				(width 0.1)
				(type default)
			)
			(layer "F.Fab")
		)
		(fp_line
			(start 2.249932 3.949954)
			(end 2.249932 -3.949954)
			(stroke
				(width 0.1)
				(type default)
			)
			(layer "F.Fab")
		)
		(fp_poly
			(pts
				(xy -4.8006 -4.08305) (xy -4.8006 -3.06705) (xy -3.7846 -3.57505)
			)
			(stroke
				(width 0)
				(type default)
			)
			(fill yes)
			(layer "F.Fab")
		)
		(pad "1" smd rect
			(at -2.800096 -3.57505 270)
			(size 0.3048 1.6002)
			(layers "F.Cu" "F.Mask" "F.Paste")
			(net "PCA9548_PCIE3_ADDR0")
		)
		(pad "2" smd rect
			(at -2.800096 -2.925064 270)
			(size 0.3048 1.6002)
			(layers "F.Cu" "F.Mask" "F.Paste")
			(net "PCA9548_PCIE3_ADDR1")
		)
		(pad "3" smd rect
			(at -2.800096 -2.275078 270)
			(size 0.3048 1.6002)
			(layers "F.Cu" "F.Mask" "F.Paste")
			(net "PU_RST_SMB_PCIE0_N")
		)
		(pad "4" smd rect
			(at -2.800096 -1.625092 270)
			(size 0.3048 1.6002)
			(layers "F.Cu" "F.Mask" "F.Paste")
			(net "SMB_USB_CPU0_HUB1_SDA_R")
		)
		(pad "5" smd rect
			(at -2.800096 -0.975106 270)
			(size 0.3048 1.6002)
			(layers "F.Cu" "F.Mask" "F.Paste")
			(net "SMB_USB_CPU0_HUB1_SCL_R")
		)
		(pad "6" smd rect
			(at -2.800096 -0.32512 270)
			(size 0.3048 1.6002)
			(layers "F.Cu" "F.Mask" "F.Paste")
			(net "SMB_IOEXP_3V3AUX_SDA_R")
		)
		(pad "7" smd rect
			(at -2.800096 0.32512 270)
			(size 0.3048 1.6002)
			(layers "F.Cu" "F.Mask" "F.Paste")
			(net "SMB_IOEXP_3V3AUX_SCL_R")
		)
		(pad "8" smd rect
			(at -2.800096 0.975106 270)
			(size 0.3048 1.6002)
			(layers "F.Cu" "F.Mask" "F.Paste")
			(net "SMB_PCIE0_3V3AUX_SDA_R3")
		)
		(pad "9" smd rect
			(at -2.800096 1.625092 270)
			(size 0.3048 1.6002)
			(layers "F.Cu" "F.Mask" "F.Paste")
			(net "SMB_PCIE0_3V3AUX_SCL_R3")
		)
		(pad "10" smd rect
			(at -2.800096 2.275078 270)
			(size 0.3048 1.6002)
			(layers "F.Cu" "F.Mask" "F.Paste")
			(net "SMB_PCIE0_3V3AUX_SDA_R5")
		)
		(pad "11" smd rect
			(at -2.800096 2.925064 270)
			(size 0.3048 1.6002)
			(layers "F.Cu" "F.Mask" "F.Paste")
			(net "SMB_PCIE0_3V3AUX_SCL_R5")
		)
		(pad "12" smd rect
			(at -2.800096 3.57505 270)
			(size 0.3048 1.6002)
			(layers "F.Cu" "F.Mask" "F.Paste")
			(net "GND")
		)
		(pad "13" smd rect
			(at 2.800096 3.57505 270)
			(size 0.3048 1.6002)
			(layers "F.Cu" "F.Mask" "F.Paste")
			(net "SMB_BMC_SWB_SDA_R4")
		)
		(pad "14" smd rect
			(at 2.800096 2.925064 270)
			(size 0.3048 1.6002)
			(layers "F.Cu" "F.Mask" "F.Paste")
			(net "SMB_BMC_SWB_SCL_R4")
		)
		(pad "15" smd rect
			(at 2.800096 2.275078 270)
			(size 0.3048 1.6002)
			(layers "F.Cu" "F.Mask" "F.Paste")
			(net "SMB_FRU_3V3AUX_SDA_R")
		)
		(pad "16" smd rect
			(at 2.800096 1.625092 270)
			(size 0.3048 1.6002)
			(layers "F.Cu" "F.Mask" "F.Paste")
			(net "SMB_FRU_3V3AUX_SCL_R")
		)
		(pad "17" smd rect
			(at 2.800096 0.975106 270)
			(size 0.3048 1.6002)
			(layers "F.Cu" "F.Mask" "F.Paste")
			(net "SMB_INA230_3V3AUX_SDA_R")
		)
		(pad "18" smd rect
			(at 2.800096 0.32512 270)
			(size 0.3048 1.6002)
			(layers "F.Cu" "F.Mask" "F.Paste")
			(net "SMB_INA230_3V3AUX_SCL_R")
		)
		(pad "19" smd rect
			(at 2.800096 -0.32512 270)
			(size 0.3048 1.6002)
			(layers "F.Cu" "F.Mask" "F.Paste")
			(net "Net_10757")
		)
		(pad "20" smd rect
			(at 2.800096 -0.975106 270)
			(size 0.3048 1.6002)
			(layers "F.Cu" "F.Mask" "F.Paste")
			(net "Net_10758")
		)
		(pad "21" smd rect
			(at 2.800096 -1.625092 270)
			(size 0.3048 1.6002)
			(layers "F.Cu" "F.Mask" "F.Paste")
			(net "PCA9548_PCIE3_ADDR2")
		)
		(pad "22" smd rect
			(at 2.800096 -2.275078 270)
			(size 0.3048 1.6002)
			(layers "F.Cu" "F.Mask" "F.Paste")
			(net "SMB_PCIE0_3V3AUX_SCL_R")
		)
		(pad "23" smd rect
			(at 2.800096 -2.925064 270)
			(size 0.3048 1.6002)
			(layers "F.Cu" "F.Mask" "F.Paste")
			(net "SMB_PCIE0_3V3AUX_SDA_R")
		)
		(pad "24" smd rect
			(at 2.800096 -3.57505 270)
			(size 0.3048 1.6002)
			(layers "F.Cu" "F.Mask" "F.Paste")
			(net "P3V3_AUX")
		)
	)
	(footprint ""
		(layer "F.Cu")
		(at 194.183 -129.377948 90)
		(property "Reference" "R1202"
			(at 0 0 90)
			(layer "F.SilkS")
			(hide yes)
			(effects
				(font
					(size 1.27 1.27)
				)
			)
		)
		(property "Value" ""
			(at 0 0 90)
			(layer "F.Fab")
			(effects
				(font
					(size 1.27 1.27)
				)
			)
		)
		(duplicate_pad_numbers_are_jumpers no)
		(fp_line
			(start 0.7874 -0.4064)
			(end 0.7874 0.4064)
			(stroke
				(width 0.1524)
				(type default)
			)
			(layer "F.SilkS")
		)
		(fp_line
			(start -0.7874 -0.4064)
			(end 0.7874 -0.4064)
			(stroke
				(width 0.1524)
				(type default)
			)
			(layer "F.SilkS")
		)
		(fp_line
			(start 0.7874 0.4064)
			(end -0.7874 0.4064)
			(stroke
				(width 0.1524)
				(type default)
			)
			(layer "F.SilkS")
		)
		(fp_line
			(start -0.7874 0.4064)
			(end -0.7874 -0.4064)
			(stroke
				(width 0.1524)
				(type default)
			)
			(layer "F.SilkS")
		)
		(fp_line
			(start -0.12065 -0.305054)
			(end -0.12065 -0.2794)
			(stroke
				(width 0.1)
				(type default)
			)
			(layer "F.Fab")
		)
		(fp_line
			(start -0.67945 -0.305054)
			(end -0.12065 -0.305054)
			(stroke
				(width 0.1)
				(type default)
			)
			(layer "F.Fab")
		)
		(fp_line
			(start 0.67945 -0.3048)
			(end 0.67945 0.3048)
			(stroke
				(width 0.1)
				(type default)
			)
			(layer "F.Fab")
		)
		(fp_line
			(start 0.12065 -0.3048)
			(end 0.67945 -0.3048)
			(stroke
				(width 0.1)
				(type default)
			)
			(layer "F.Fab")
		)
		(fp_line
			(start 0.12065 -0.2794)
			(end 0.12065 -0.3048)
			(stroke
				(width 0.1)
				(type default)
			)
			(layer "F.Fab")
		)
		(fp_line
			(start -0.12065 -0.2794)
			(end 0.12065 -0.2794)
			(stroke
				(width 0.1)
				(type default)
			)
			(layer "F.Fab")
		)
		(fp_line
			(start 0.120396 0.2794)
			(end -0.12065 0.2794)
			(stroke
				(width 0.1)
				(type default)
			)
			(layer "F.Fab")
		)
		(fp_line
			(start -0.12065 0.2794)
			(end -0.12065 0.3048)
			(stroke
				(width 0.1)
				(type default)
			)
			(layer "F.Fab")
		)
		(fp_line
			(start 0.67945 0.3048)
			(end 0.120396 0.3048)
			(stroke
				(width 0.1)
				(type default)
			)
			(layer "F.Fab")
		)
		(fp_line
			(start 0.120396 0.3048)
			(end 0.120396 0.2794)
			(stroke
				(width 0.1)
				(type default)
			)
			(layer "F.Fab")
		)
		(fp_line
			(start -0.12065 0.3048)
			(end -0.67945 0.3048)
			(stroke
				(width 0.1)
				(type default)
			)
			(layer "F.Fab")
		)
		(fp_line
			(start -0.67945 0.3048)
			(end -0.67945 -0.305054)
			(stroke
				(width 0.1)
				(type default)
			)
			(layer "F.Fab")
		)
		(pad "1" smd circle
			(at -0.40005 0 90)
			(size 0 0)
			(layers "F.Cu" "F.Mask" "F.Paste")
			(net "FM_FORCE_ALL_PWRON_R")
		)
		(pad "2" smd circle
			(at 0.40005 0 90)
			(size 0 0)
			(layers "F.Cu" "F.Mask" "F.Paste")
			(net "FM_FORCE_ALL_PWRON")
		)
	)
	(footprint ""
		(layer "F.Cu")
		(at 99.015296 -422.43248 90)
		(property "Reference" "R4203"
			(at 0 0 90)
			(layer "F.SilkS")
			(hide yes)
			(effects
				(font
					(size 1.27 1.27)
				)
			)
		)
		(property "Value" ""
			(at 0 0 90)
			(layer "F.Fab")
			(effects
				(font
					(size 1.27 1.27)
				)
			)
		)
		(duplicate_pad_numbers_are_jumpers no)
		(fp_line
			(start 0.7874 -0.4064)
			(end 0.7874 0.4064)
			(stroke
				(width 0.1524)
				(type default)
			)
			(layer "F.SilkS")
		)
		(fp_line
			(start -0.7874 -0.4064)
			(end 0.7874 -0.4064)
			(stroke
				(width 0.1524)
				(type default)
			)
			(layer "F.SilkS")
		)
		(fp_line
			(start 0.7874 0.4064)
			(end -0.7874 0.4064)
			(stroke
				(width 0.1524)
				(type default)
			)
			(layer "F.SilkS")
		)
		(fp_line
			(start -0.7874 0.4064)
			(end -0.7874 -0.4064)
			(stroke
				(width 0.1524)
				(type default)
			)
			(layer "F.SilkS")
		)
		(fp_line
			(start -0.12065 -0.305054)
			(end -0.12065 -0.2794)
			(stroke
				(width 0.1)
				(type default)
			)
			(layer "F.Fab")
		)
		(fp_line
			(start -0.67945 -0.305054)
			(end -0.12065 -0.305054)
			(stroke
				(width 0.1)
				(type default)
			)
			(layer "F.Fab")
		)
		(fp_line
			(start 0.67945 -0.3048)
			(end 0.67945 0.3048)
			(stroke
				(width 0.1)
				(type default)
			)
			(layer "F.Fab")
		)
		(fp_line
			(start 0.12065 -0.3048)
			(end 0.67945 -0.3048)
			(stroke
				(width 0.1)
				(type default)
			)
			(layer "F.Fab")
		)
		(fp_line
			(start 0.12065 -0.2794)
			(end 0.12065 -0.3048)
			(stroke
				(width 0.1)
				(type default)
			)
			(layer "F.Fab")
		)
		(fp_line
			(start -0.12065 -0.2794)
			(end 0.12065 -0.2794)
			(stroke
				(width 0.1)
				(type default)
			)
			(layer "F.Fab")
		)
		(fp_line
			(start 0.120396 0.2794)
			(end -0.12065 0.2794)
			(stroke
				(width 0.1)
				(type default)
			)
			(layer "F.Fab")
		)
		(fp_line
			(start -0.12065 0.2794)
			(end -0.12065 0.3048)
			(stroke
				(width 0.1)
				(type default)
			)
			(layer "F.Fab")
		)
		(fp_line
			(start 0.67945 0.3048)
			(end 0.120396 0.3048)
			(stroke
				(width 0.1)
				(type default)
			)
			(layer "F.Fab")
		)
		(fp_line
			(start 0.120396 0.3048)
			(end 0.120396 0.2794)
			(stroke
				(width 0.1)
				(type default)
			)
			(layer "F.Fab")
		)
		(fp_line
			(start -0.12065 0.3048)
			(end -0.67945 0.3048)
			(stroke
				(width 0.1)
				(type default)
			)
			(layer "F.Fab")
		)
		(fp_line
			(start -0.67945 0.3048)
			(end -0.67945 -0.305054)
			(stroke
				(width 0.1)
				(type default)
			)
			(layer "F.Fab")
		)
		(pad "1" smd circle
			(at -0.40005 0 90)
			(size 0 0)
			(layers "F.Cu" "F.Mask" "F.Paste")
			(net "U272_2_ADD0")
		)
		(pad "2" smd circle
			(at 0.40005 0 90)
			(size 0 0)
			(layers "F.Cu" "F.Mask" "F.Paste")
			(net "GND")
		)
	)
	(footprint ""
		(layer "F.Cu")
		(at 438.056782 -435.27726 90)
		(property "Reference" "R3471"
			(at 0 0 90)
			(layer "F.SilkS")
			(hide yes)
			(effects
				(font
					(size 1.27 1.27)
				)
			)
		)
		(property "Value" ""
			(at 0 0 90)
			(layer "F.Fab")
			(effects
				(font
					(size 1.27 1.27)
				)
			)
		)
		(duplicate_pad_numbers_are_jumpers no)
		(fp_line
			(start 0.7874 -0.4064)
			(end 0.7874 0.4064)
			(stroke
				(width 0.1524)
				(type default)
			)
			(layer "F.SilkS")
		)
		(fp_line
			(start -0.7874 -0.4064)
			(end 0.7874 -0.4064)
			(stroke
				(width 0.1524)
				(type default)
			)
			(layer "F.SilkS")
		)
		(fp_line
			(start 0.7874 0.4064)
			(end -0.7874 0.4064)
			(stroke
				(width 0.1524)
				(type default)
			)
			(layer "F.SilkS")
		)
		(fp_line
			(start -0.7874 0.4064)
			(end -0.7874 -0.4064)
			(stroke
				(width 0.1524)
				(type default)
			)
			(layer "F.SilkS")
		)
		(fp_line
			(start -0.12065 -0.305054)
			(end -0.12065 -0.2794)
			(stroke
				(width 0.1)
				(type default)
			)
			(layer "F.Fab")
		)
		(fp_line
			(start -0.67945 -0.305054)
			(end -0.12065 -0.305054)
			(stroke
				(width 0.1)
				(type default)
			)
			(layer "F.Fab")
		)
		(fp_line
			(start 0.67945 -0.3048)
			(end 0.67945 0.3048)
			(stroke
				(width 0.1)
				(type default)
			)
			(layer "F.Fab")
		)
		(fp_line
			(start 0.12065 -0.3048)
			(end 0.67945 -0.3048)
			(stroke
				(width 0.1)
				(type default)
			)
			(layer "F.Fab")
		)
		(fp_line
			(start 0.12065 -0.2794)
			(end 0.12065 -0.3048)
			(stroke
				(width 0.1)
				(type default)
			)
			(layer "F.Fab")
		)
		(fp_line
			(start -0.12065 -0.2794)
			(end 0.12065 -0.2794)
			(stroke
				(width 0.1)
				(type default)
			)
			(layer "F.Fab")
		)
		(fp_line
			(start 0.120396 0.2794)
			(end -0.12065 0.2794)
			(stroke
				(width 0.1)
				(type default)
			)
			(layer "F.Fab")
		)
		(fp_line
			(start -0.12065 0.2794)
			(end -0.12065 0.3048)
			(stroke
				(width 0.1)
				(type default)
			)
			(layer "F.Fab")
		)
		(fp_line
			(start 0.67945 0.3048)
			(end 0.120396 0.3048)
			(stroke
				(width 0.1)
				(type default)
			)
			(layer "F.Fab")
		)
		(fp_line
			(start 0.120396 0.3048)
			(end 0.120396 0.2794)
			(stroke
				(width 0.1)
				(type default)
			)
			(layer "F.Fab")
		)
		(fp_line
			(start -0.12065 0.3048)
			(end -0.67945 0.3048)
			(stroke
				(width 0.1)
				(type default)
			)
			(layer "F.Fab")
		)
		(fp_line
			(start -0.67945 0.3048)
			(end -0.67945 -0.305054)
			(stroke
				(width 0.1)
				(type default)
			)
			(layer "F.Fab")
		)
		(pad "1" smd circle
			(at -0.40005 0 90)
			(size 0 0)
			(layers "F.Cu" "F.Mask" "F.Paste")
			(net "GPU_WP_HW_CTRL_N")
		)
		(pad "2" smd circle
			(at 0.40005 0 90)
			(size 0 0)
			(layers "F.Cu" "F.Mask" "F.Paste")
			(net "GND")
		)
	)
	(footprint ""
		(layer "F.Cu")
		(at 139.420092 -355.91242)
		(property "Reference" "ME6"
			(at 0.1143 -8.208518 0)
			(unlocked yes)
			(layer "F.SilkS")
			(effects
				(font
					(size 0.254 0.127)
					(thickness 0.000001)
				)
				(justify left)
			)
		)
		(property "Value" ""
			(at 0 0 0)
			(layer "F.Fab")
			(effects
				(font
					(size 1.27 1.27)
				)
			)
		)
		(duplicate_pad_numbers_are_jumpers no)
		(fp_poly
			(pts
				(xy 0 0) (xy 14.99997 0) (xy 14.99997 -7.999984) (xy 0 -7.999984)
			)
			(stroke
				(width 0)
				(type default)
			)
			(fill no)
			(layer "F.CrtYd")
		)
	)
	(footprint ""
		(layer "F.Cu")
		(at 401.128484 -402.548852 -90)
		(property "Reference" "R1048"
			(at 0 0 270)
			(layer "F.SilkS")
			(hide yes)
			(effects
				(font
					(size 1.27 1.27)
				)
			)
		)
		(property "Value" ""
			(at 0 0 270)
			(layer "F.Fab")
			(effects
				(font
					(size 1.27 1.27)
				)
			)
		)
		(duplicate_pad_numbers_are_jumpers no)
		(fp_line
			(start -0.32512 0.175006)
			(end -0.32512 -0.175006)
			(stroke
				(width 0.1)
				(type default)
			)
			(layer "F.Fab")
		)
		(fp_line
			(start 0.32512 0.175006)
			(end -0.32512 0.175006)
			(stroke
				(width 0.1)
				(type default)
			)
			(layer "F.Fab")
		)
		(fp_line
			(start -0.32512 -0.175006)
			(end 0.32512 -0.175006)
			(stroke
				(width 0.1)
				(type default)
			)
			(layer "F.Fab")
		)
		(fp_line
			(start 0.32512 -0.175006)
			(end 0.32512 0.175006)
			(stroke
				(width 0.1)
				(type default)
			)
			(layer "F.Fab")
		)
		(pad "1" smd rect
			(at -0.2667 0 270)
			(size 0.3048 0.381)
			(layers "F.Cu" "F.Mask" "F.Paste")
			(net "MODE_RT_CPU0_P2")
		)
		(pad "2" smd rect
			(at 0.2667 0 90)
			(size 0.3048 0.381)
			(layers "F.Cu" "F.Mask" "F.Paste")
			(net "GND")
		)
	)
	(footprint ""
		(layer "F.Cu")
		(at 58.580782 -145.066766)
		(property "Reference" "PC21"
			(at 0 0 0)
			(layer "F.SilkS")
			(hide yes)
			(effects
				(font
					(size 1.27 1.27)
				)
			)
		)
		(property "Value" ""
			(at 0 0 0)
			(layer "F.Fab")
			(effects
				(font
					(size 1.27 1.27)
				)
			)
		)
		(duplicate_pad_numbers_are_jumpers no)
		(fp_line
			(start -0.7874 -0.4064)
			(end 0.7874 -0.4064)
			(stroke
				(width 0.1524)
				(type default)
			)
			(layer "F.SilkS")
		)
		(fp_line
			(start -0.7874 0.4064)
			(end -0.7874 -0.4064)
			(stroke
				(width 0.1524)
				(type default)
			)
			(layer "F.SilkS")
		)
		(fp_line
			(start 0.7874 -0.4064)
			(end 0.7874 0.4064)
			(stroke
				(width 0.1524)
				(type default)
			)
			(layer "F.SilkS")
		)
		(fp_line
			(start 0.7874 0.4064)
			(end -0.7874 0.4064)
			(stroke
				(width 0.1524)
				(type default)
			)
			(layer "F.SilkS")
		)
		(fp_line
			(start -0.67945 -0.305054)
			(end -0.12065 -0.305054)
			(stroke
				(width 0.1)
				(type default)
			)
			(layer "F.Fab")
		)
		(fp_line
			(start -0.67945 0.3048)
			(end -0.67945 -0.305054)
			(stroke
				(width 0.1)
				(type default)
			)
			(layer "F.Fab")
		)
		(fp_line
			(start -0.12065 -0.305054)
			(end -0.12065 -0.2794)
			(stroke
				(width 0.1)
				(type default)
			)
			(layer "F.Fab")
		)
		(fp_line
			(start -0.12065 -0.2794)
			(end 0.12065 -0.2794)
			(stroke
				(width 0.1)
				(type default)
			)
			(layer "F.Fab")
		)
		(fp_line
			(start -0.12065 0.2794)
			(end -0.12065 0.3048)
			(stroke
				(width 0.1)
				(type default)
			)
			(layer "F.Fab")
		)
		(fp_line
			(start -0.12065 0.3048)
			(end -0.67945 0.3048)
			(stroke
				(width 0.1)
				(type default)
			)
			(layer "F.Fab")
		)
		(fp_line
			(start 0.120396 0.2794)
			(end -0.12065 0.2794)
			(stroke
				(width 0.1)
				(type default)
			)
			(layer "F.Fab")
		)
		(fp_line
			(start 0.120396 0.3048)
			(end 0.120396 0.2794)
			(stroke
				(width 0.1)
				(type default)
			)
			(layer "F.Fab")
		)
		(fp_line
			(start 0.12065 -0.3048)
			(end 0.67945 -0.3048)
			(stroke
				(width 0.1)
				(type default)
			)
			(layer "F.Fab")
		)
		(fp_line
			(start 0.12065 -0.2794)
			(end 0.12065 -0.3048)
			(stroke
				(width 0.1)
				(type default)
			)
			(layer "F.Fab")
		)
		(fp_line
			(start 0.67945 -0.3048)
			(end 0.67945 0.3048)
			(stroke
				(width 0.1)
				(type default)
			)
			(layer "F.Fab")
		)
		(fp_line
			(start 0.67945 0.3048)
			(end 0.120396 0.3048)
			(stroke
				(width 0.1)
				(type default)
			)
			(layer "F.Fab")
		)
		(pad "1" smd circle
			(at -0.40005 0)
			(size 0 0)
			(layers "F.Cu" "F.Mask" "F.Paste")
			(net "PVDD18_S5_P1")
		)
		(pad "2" smd circle
			(at 0.40005 0)
			(size 0 0)
			(layers "F.Cu" "F.Mask" "F.Paste")
			(net "GND")
		)
	)
	(footprint ""
		(layer "F.Cu")
		(at 144.386554 -321.695572 -90)
		(property "Reference" "R551"
			(at 0 0 270)
			(layer "F.SilkS")
			(hide yes)
			(effects
				(font
					(size 1.27 1.27)
				)
			)
		)
		(property "Value" ""
			(at 0 0 270)
			(layer "F.Fab")
			(effects
				(font
					(size 1.27 1.27)
				)
			)
		)
		(duplicate_pad_numbers_are_jumpers no)
		(fp_line
			(start -0.7874 0.4064)
			(end -0.7874 -0.4064)
			(stroke
				(width 0.1524)
				(type default)
			)
			(layer "F.SilkS")
		)
		(fp_line
			(start 0.7874 0.4064)
			(end -0.7874 0.4064)
			(stroke
				(width 0.1524)
				(type default)
			)
			(layer "F.SilkS")
		)
		(fp_line
			(start -0.7874 -0.4064)
			(end 0.7874 -0.4064)
			(stroke
				(width 0.1524)
				(type default)
			)
			(layer "F.SilkS")
		)
		(fp_line
			(start 0.7874 -0.4064)
			(end 0.7874 0.4064)
			(stroke
				(width 0.1524)
				(type default)
			)
			(layer "F.SilkS")
		)
		(fp_line
			(start -0.67945 0.3048)
			(end -0.67945 -0.305054)
			(stroke
				(width 0.1)
				(type default)
			)
			(layer "F.Fab")
		)
		(fp_line
			(start -0.12065 0.3048)
			(end -0.67945 0.3048)
			(stroke
				(width 0.1)
				(type default)
			)
			(layer "F.Fab")
		)
		(fp_line
			(start 0.120396 0.3048)
			(end 0.120396 0.2794)
			(stroke
				(width 0.1)
				(type default)
			)
			(layer "F.Fab")
		)
		(fp_line
			(start 0.67945 0.3048)
			(end 0.120396 0.3048)
			(stroke
				(width 0.1)
				(type default)
			)
			(layer "F.Fab")
		)
		(fp_line
			(start -0.12065 0.2794)
			(end -0.12065 0.3048)
			(stroke
				(width 0.1)
				(type default)
			)
			(layer "F.Fab")
		)
		(fp_line
			(start 0.120396 0.2794)
			(end -0.12065 0.2794)
			(stroke
				(width 0.1)
				(type default)
			)
			(layer "F.Fab")
		)
		(fp_line
			(start -0.12065 -0.2794)
			(end 0.12065 -0.2794)
			(stroke
				(width 0.1)
				(type default)
			)
			(layer "F.Fab")
		)
		(fp_line
			(start 0.12065 -0.2794)
			(end 0.12065 -0.3048)
			(stroke
				(width 0.1)
				(type default)
			)
			(layer "F.Fab")
		)
		(fp_line
			(start 0.12065 -0.3048)
			(end 0.67945 -0.3048)
			(stroke
				(width 0.1)
				(type default)
			)
			(layer "F.Fab")
		)
		(fp_line
			(start 0.67945 -0.3048)
			(end 0.67945 0.3048)
			(stroke
				(width 0.1)
				(type default)
			)
			(layer "F.Fab")
		)
		(fp_line
			(start -0.67945 -0.305054)
			(end -0.12065 -0.305054)
			(stroke
				(width 0.1)
				(type default)
			)
			(layer "F.Fab")
		)
		(fp_line
			(start -0.12065 -0.305054)
			(end -0.12065 -0.2794)
			(stroke
				(width 0.1)
				(type default)
			)
			(layer "F.Fab")
		)
		(pad "1" smd circle
			(at -0.40005 0 270)
			(size 0 0)
			(layers "F.Cu" "F.Mask" "F.Paste")
			(net "CPU1_SPD_HOST_CTRL_N")
		)
		(pad "2" smd circle
			(at 0.40005 0 270)
			(size 0 0)
			(layers "F.Cu" "F.Mask" "F.Paste")
			(net "PVDD18_S5_P1")
		)
	)
	(footprint ""
		(layer "F.Cu")
		(at 52.17033 -17.623536 90)
		(property "Reference" "C704"
			(at 0 0 90)
			(layer "F.SilkS")
			(hide yes)
			(effects
				(font
					(size 1.27 1.27)
				)
			)
		)
		(property "Value" ""
			(at 0 0 90)
			(layer "F.Fab")
			(effects
				(font
					(size 1.27 1.27)
				)
			)
		)
		(duplicate_pad_numbers_are_jumpers no)
		(fp_line
			(start 0.299974 -0.150114)
			(end 0.299974 0.150114)
			(stroke
				(width 0.1)
				(type default)
			)
			(layer "F.Fab")
		)
		(fp_line
			(start -0.299974 -0.150114)
			(end 0.299974 -0.150114)
			(stroke
				(width 0.1)
				(type default)
			)
			(layer "F.Fab")
		)
		(fp_line
			(start 0.299974 0.150114)
			(end -0.299974 0.150114)
			(stroke
				(width 0.1)
				(type default)
			)
			(layer "F.Fab")
		)
		(fp_line
			(start -0.299974 0.150114)
			(end -0.299974 -0.150114)
			(stroke
				(width 0.1)
				(type default)
			)
			(layer "F.Fab")
		)
		(pad "1" smd rect
			(at -0.2667 0 90)
			(size 0.3048 0.381)
			(layers "F.Cu" "F.Mask" "F.Paste")
			(net "P5E_CPU1_G1_TX_C_DN<2>")
		)
		(pad "2" smd rect
			(at 0.2667 0 90)
			(size 0.3048 0.381)
			(layers "F.Cu" "F.Mask" "F.Paste")
			(net "P5E_CPU1_G1_TX_DN<2>")
		)
	)
	(footprint ""
		(layer "F.Cu")
		(at 171.196 -104.993948 180)
		(property "Reference" "R169"
			(at 0 0 180)
			(layer "F.SilkS")
			(hide yes)
			(effects
				(font
					(size 1.27 1.27)
				)
			)
		)
		(property "Value" ""
			(at 0 0 180)
			(layer "F.Fab")
			(effects
				(font
					(size 1.27 1.27)
				)
			)
		)
		(duplicate_pad_numbers_are_jumpers no)
		(fp_line
			(start 0.7874 0.4064)
			(end -0.7874 0.4064)
			(stroke
				(width 0.1524)
				(type default)
			)
			(layer "F.SilkS")
		)
		(fp_line
			(start 0.7874 -0.4064)
			(end 0.7874 0.4064)
			(stroke
				(width 0.1524)
				(type default)
			)
			(layer "F.SilkS")
		)
		(fp_line
			(start -0.7874 0.4064)
			(end -0.7874 -0.4064)
			(stroke
				(width 0.1524)
				(type default)
			)
			(layer "F.SilkS")
		)
		(fp_line
			(start -0.7874 -0.4064)
			(end 0.7874 -0.4064)
			(stroke
				(width 0.1524)
				(type default)
			)
			(layer "F.SilkS")
		)
		(fp_line
			(start 0.67945 0.3048)
			(end 0.120396 0.3048)
			(stroke
				(width 0.1)
				(type default)
			)
			(layer "F.Fab")
		)
		(fp_line
			(start 0.67945 -0.3048)
			(end 0.67945 0.3048)
			(stroke
				(width 0.1)
				(type default)
			)
			(layer "F.Fab")
		)
		(fp_line
			(start 0.12065 -0.2794)
			(end 0.12065 -0.3048)
			(stroke
				(width 0.1)
				(type default)
			)
			(layer "F.Fab")
		)
		(fp_line
			(start 0.12065 -0.3048)
			(end 0.67945 -0.3048)
			(stroke
				(width 0.1)
				(type default)
			)
			(layer "F.Fab")
		)
		(fp_line
			(start 0.120396 0.3048)
			(end 0.120396 0.2794)
			(stroke
				(width 0.1)
				(type default)
			)
			(layer "F.Fab")
		)
		(fp_line
			(start 0.120396 0.2794)
			(end -0.12065 0.2794)
			(stroke
				(width 0.1)
				(type default)
			)
			(layer "F.Fab")
		)
		(fp_line
			(start -0.12065 0.3048)
			(end -0.67945 0.3048)
			(stroke
				(width 0.1)
				(type default)
			)
			(layer "F.Fab")
		)
		(fp_line
			(start -0.12065 0.2794)
			(end -0.12065 0.3048)
			(stroke
				(width 0.1)
				(type default)
			)
			(layer "F.Fab")
		)
		(fp_line
			(start -0.12065 -0.2794)
			(end 0.12065 -0.2794)
			(stroke
				(width 0.1)
				(type default)
			)
			(layer "F.Fab")
		)
		(fp_line
			(start -0.12065 -0.305054)
			(end -0.12065 -0.2794)
			(stroke
				(width 0.1)
				(type default)
			)
			(layer "F.Fab")
		)
		(fp_line
			(start -0.67945 0.3048)
			(end -0.67945 -0.305054)
			(stroke
				(width 0.1)
				(type default)
			)
			(layer "F.Fab")
		)
		(fp_line
			(start -0.67945 -0.305054)
			(end -0.12065 -0.305054)
			(stroke
				(width 0.1)
				(type default)
			)
			(layer "F.Fab")
		)
		(pad "1" smd circle
			(at -0.40005 0 180)
			(size 0 0)
			(layers "F.Cu" "F.Mask" "F.Paste")
			(net "FM_I3C_CPU1_MUX0_OE_R_N")
		)
		(pad "2" smd circle
			(at 0.40005 0 180)
			(size 0 0)
			(layers "F.Cu" "F.Mask" "F.Paste")
			(net "FM_I3C_CPU1_MUX0_OE_N")
		)
	)
	(footprint ""
		(layer "F.Cu")
		(at 120.396 -433.451)
		(property "Reference" "R3497"
			(at 0 0 0)
			(layer "F.SilkS")
			(hide yes)
			(effects
				(font
					(size 1.27 1.27)
				)
			)
		)
		(property "Value" ""
			(at 0 0 0)
			(layer "F.Fab")
			(effects
				(font
					(size 1.27 1.27)
				)
			)
		)
		(duplicate_pad_numbers_are_jumpers no)
		(fp_line
			(start -0.7874 -0.4064)
			(end 0.7874 -0.4064)
			(stroke
				(width 0.1524)
				(type default)
			)
			(layer "F.SilkS")
		)
		(fp_line
			(start -0.7874 0.4064)
			(end -0.7874 -0.4064)
			(stroke
				(width 0.1524)
				(type default)
			)
			(layer "F.SilkS")
		)
		(fp_line
			(start 0.7874 -0.4064)
			(end 0.7874 0.4064)
			(stroke
				(width 0.1524)
				(type default)
			)
			(layer "F.SilkS")
		)
		(fp_line
			(start 0.7874 0.4064)
			(end -0.7874 0.4064)
			(stroke
				(width 0.1524)
				(type default)
			)
			(layer "F.SilkS")
		)
		(fp_line
			(start -0.67945 -0.305054)
			(end -0.12065 -0.305054)
			(stroke
				(width 0.1)
				(type default)
			)
			(layer "F.Fab")
		)
		(fp_line
			(start -0.67945 0.3048)
			(end -0.67945 -0.305054)
			(stroke
				(width 0.1)
				(type default)
			)
			(layer "F.Fab")
		)
		(fp_line
			(start -0.12065 -0.305054)
			(end -0.12065 -0.2794)
			(stroke
				(width 0.1)
				(type default)
			)
			(layer "F.Fab")
		)
		(fp_line
			(start -0.12065 -0.2794)
			(end 0.12065 -0.2794)
			(stroke
				(width 0.1)
				(type default)
			)
			(layer "F.Fab")
		)
		(fp_line
			(start -0.12065 0.2794)
			(end -0.12065 0.3048)
			(stroke
				(width 0.1)
				(type default)
			)
			(layer "F.Fab")
		)
		(fp_line
			(start -0.12065 0.3048)
			(end -0.67945 0.3048)
			(stroke
				(width 0.1)
				(type default)
			)
			(layer "F.Fab")
		)
		(fp_line
			(start 0.120396 0.2794)
			(end -0.12065 0.2794)
			(stroke
				(width 0.1)
				(type default)
			)
			(layer "F.Fab")
		)
		(fp_line
			(start 0.120396 0.3048)
			(end 0.120396 0.2794)
			(stroke
				(width 0.1)
				(type default)
			)
			(layer "F.Fab")
		)
		(fp_line
			(start 0.12065 -0.3048)
			(end 0.67945 -0.3048)
			(stroke
				(width 0.1)
				(type default)
			)
			(layer "F.Fab")
		)
		(fp_line
			(start 0.12065 -0.2794)
			(end 0.12065 -0.3048)
			(stroke
				(width 0.1)
				(type default)
			)
			(layer "F.Fab")
		)
		(fp_line
			(start 0.67945 -0.3048)
			(end 0.67945 0.3048)
			(stroke
				(width 0.1)
				(type default)
			)
			(layer "F.Fab")
		)
		(fp_line
			(start 0.67945 0.3048)
			(end 0.120396 0.3048)
			(stroke
				(width 0.1)
				(type default)
			)
			(layer "F.Fab")
		)
		(pad "1" smd circle
			(at -0.40005 0)
			(size 0 0)
			(layers "F.Cu" "F.Mask" "F.Paste")
			(net "GPU_FPGA_EROT_RECOV_BUF_R_N")
		)
		(pad "2" smd circle
			(at 0.40005 0)
			(size 0 0)
			(layers "F.Cu" "F.Mask" "F.Paste")
			(net "GPU_FPGA_EROT_RECOV_BUF_N")
		)
	)
	(footprint ""
		(layer "F.Cu")
		(at 148.73859 -98.755708 90)
		(property "Reference" "R3308"
			(at 0 0 90)
			(layer "F.SilkS")
			(hide yes)
			(effects
				(font
					(size 1.27 1.27)
				)
			)
		)
		(property "Value" ""
			(at 0 0 90)
			(layer "F.Fab")
			(effects
				(font
					(size 1.27 1.27)
				)
			)
		)
		(duplicate_pad_numbers_are_jumpers no)
		(fp_line
			(start 0.7874 -0.4064)
			(end 0.7874 0.4064)
			(stroke
				(width 0.1524)
				(type default)
			)
			(layer "F.SilkS")
		)
		(fp_line
			(start -0.7874 -0.4064)
			(end 0.7874 -0.4064)
			(stroke
				(width 0.1524)
				(type default)
			)
			(layer "F.SilkS")
		)
		(fp_line
			(start 0.7874 0.4064)
			(end -0.7874 0.4064)
			(stroke
				(width 0.1524)
				(type default)
			)
			(layer "F.SilkS")
		)
		(fp_line
			(start -0.7874 0.4064)
			(end -0.7874 -0.4064)
			(stroke
				(width 0.1524)
				(type default)
			)
			(layer "F.SilkS")
		)
		(fp_line
			(start -0.12065 -0.305054)
			(end -0.12065 -0.2794)
			(stroke
				(width 0.1)
				(type default)
			)
			(layer "F.Fab")
		)
		(fp_line
			(start -0.67945 -0.305054)
			(end -0.12065 -0.305054)
			(stroke
				(width 0.1)
				(type default)
			)
			(layer "F.Fab")
		)
		(fp_line
			(start 0.67945 -0.3048)
			(end 0.67945 0.3048)
			(stroke
				(width 0.1)
				(type default)
			)
			(layer "F.Fab")
		)
		(fp_line
			(start 0.12065 -0.3048)
			(end 0.67945 -0.3048)
			(stroke
				(width 0.1)
				(type default)
			)
			(layer "F.Fab")
		)
		(fp_line
			(start 0.12065 -0.2794)
			(end 0.12065 -0.3048)
			(stroke
				(width 0.1)
				(type default)
			)
			(layer "F.Fab")
		)
		(fp_line
			(start -0.12065 -0.2794)
			(end 0.12065 -0.2794)
			(stroke
				(width 0.1)
				(type default)
			)
			(layer "F.Fab")
		)
		(fp_line
			(start 0.120396 0.2794)
			(end -0.12065 0.2794)
			(stroke
				(width 0.1)
				(type default)
			)
			(layer "F.Fab")
		)
		(fp_line
			(start -0.12065 0.2794)
			(end -0.12065 0.3048)
			(stroke
				(width 0.1)
				(type default)
			)
			(layer "F.Fab")
		)
		(fp_line
			(start 0.67945 0.3048)
			(end 0.120396 0.3048)
			(stroke
				(width 0.1)
				(type default)
			)
			(layer "F.Fab")
		)
		(fp_line
			(start 0.120396 0.3048)
			(end 0.120396 0.2794)
			(stroke
				(width 0.1)
				(type default)
			)
			(layer "F.Fab")
		)
		(fp_line
			(start -0.12065 0.3048)
			(end -0.67945 0.3048)
			(stroke
				(width 0.1)
				(type default)
			)
			(layer "F.Fab")
		)
		(fp_line
			(start -0.67945 0.3048)
			(end -0.67945 -0.305054)
			(stroke
				(width 0.1)
				(type default)
			)
			(layer "F.Fab")
		)
		(pad "1" smd circle
			(at -0.40005 0 90)
			(size 0 0)
			(layers "F.Cu" "F.Mask" "F.Paste")
			(net "OCP_V3_2_PRSNT_ALL_R_N")
		)
		(pad "2" smd circle
			(at 0.40005 0 90)
			(size 0 0)
			(layers "F.Cu" "F.Mask" "F.Paste")
			(net "OCP_V3_2_PRSNT_ALL_R1_N")
		)
	)
	(footprint ""
		(layer "F.Cu")
		(at 191.246506 -342.487758 -90)
		(property "Reference" "PL55"
			(at -15.522956 3.048254 0)
			(unlocked yes)
			(layer "F.SilkS")
			(effects
				(font
					(size 0.7874 0.5842)
					(thickness 0.1524)
				)
				(justify left)
			)
		)
		(property "Value" ""
			(at 0 0 270)
			(layer "F.Fab")
			(effects
				(font
					(size 1.27 1.27)
				)
			)
		)
		(duplicate_pad_numbers_are_jumpers no)
		(fp_line
			(start -4.99999 3.849878)
			(end -4.99999 2.23901)
			(stroke
				(width 0.1524)
				(type default)
			)
			(layer "F.SilkS")
		)
		(fp_line
			(start 4.99999 3.849878)
			(end -4.99999 3.849878)
			(stroke
				(width 0.1524)
				(type default)
			)
			(layer "F.SilkS")
		)
		(fp_line
			(start 4.99999 2.23901)
			(end 4.99999 3.849878)
			(stroke
				(width 0.1524)
				(type default)
			)
			(layer "F.SilkS")
		)
		(fp_line
			(start -4.99999 -2.23901)
			(end -4.99999 -3.849878)
			(stroke
				(width 0.1524)
				(type default)
			)
			(layer "F.SilkS")
		)
		(fp_line
			(start -4.99999 -3.849878)
			(end 4.99999 -3.849878)
			(stroke
				(width 0.1524)
				(type default)
			)
			(layer "F.SilkS")
		)
		(fp_line
			(start 4.99999 -3.849878)
			(end 4.99999 -2.23901)
			(stroke
				(width 0.1524)
				(type default)
			)
			(layer "F.SilkS")
		)
		(fp_line
			(start -4.99999 3.849878)
			(end -4.99999 -3.849878)
			(stroke
				(width 0.1)
				(type default)
			)
			(layer "F.Fab")
		)
		(fp_line
			(start 4.99999 3.849878)
			(end -4.99999 3.849878)
			(stroke
				(width 0.1)
				(type default)
			)
			(layer "F.Fab")
		)
		(fp_line
			(start -4.99999 -3.849878)
			(end 4.99999 -3.849878)
			(stroke
				(width 0.1)
				(type default)
			)
			(layer "F.Fab")
		)
		(fp_line
			(start 4.99999 -3.849878)
			(end 4.99999 3.849878)
			(stroke
				(width 0.1)
				(type default)
			)
			(layer "F.Fab")
		)
		(pad "1" smd rect
			(at -3.299968 0 270)
			(size 3.302 4.2164)
			(layers "F.Cu" "F.Mask" "F.Paste")
			(net "SW_PVDD11_S3_P1_SW2")
		)
		(pad "2" smd rect
			(at 3.299968 0 270)
			(size 3.302 4.2164)
			(layers "F.Cu" "F.Mask" "F.Paste")
			(net "PVDD11_S3_P1")
		)
	)
	(footprint ""
		(layer "F.Cu")
		(at 316.738 -359.283 180)
		(property "Reference" "R8075"
			(at 0 0 180)
			(layer "F.SilkS")
			(hide yes)
			(effects
				(font
					(size 1.27 1.27)
				)
			)
		)
		(property "Value" ""
			(at 0 0 180)
			(layer "F.Fab")
			(effects
				(font
					(size 1.27 1.27)
				)
			)
		)
		(duplicate_pad_numbers_are_jumpers no)
		(fp_line
			(start 0.7874 0.4064)
			(end -0.7874 0.4064)
			(stroke
				(width 0.1524)
				(type default)
			)
			(layer "F.SilkS")
		)
		(fp_line
			(start 0.7874 -0.4064)
			(end 0.7874 0.4064)
			(stroke
				(width 0.1524)
				(type default)
			)
			(layer "F.SilkS")
		)
		(fp_line
			(start -0.7874 0.4064)
			(end -0.7874 -0.4064)
			(stroke
				(width 0.1524)
				(type default)
			)
			(layer "F.SilkS")
		)
		(fp_line
			(start -0.7874 -0.4064)
			(end 0.7874 -0.4064)
			(stroke
				(width 0.1524)
				(type default)
			)
			(layer "F.SilkS")
		)
		(fp_line
			(start 0.67945 0.3048)
			(end 0.120396 0.3048)
			(stroke
				(width 0.1)
				(type default)
			)
			(layer "F.Fab")
		)
		(fp_line
			(start 0.67945 -0.3048)
			(end 0.67945 0.3048)
			(stroke
				(width 0.1)
				(type default)
			)
			(layer "F.Fab")
		)
		(fp_line
			(start 0.12065 -0.2794)
			(end 0.12065 -0.3048)
			(stroke
				(width 0.1)
				(type default)
			)
			(layer "F.Fab")
		)
		(fp_line
			(start 0.12065 -0.3048)
			(end 0.67945 -0.3048)
			(stroke
				(width 0.1)
				(type default)
			)
			(layer "F.Fab")
		)
		(fp_line
			(start 0.120396 0.3048)
			(end 0.120396 0.2794)
			(stroke
				(width 0.1)
				(type default)
			)
			(layer "F.Fab")
		)
		(fp_line
			(start 0.120396 0.2794)
			(end -0.12065 0.2794)
			(stroke
				(width 0.1)
				(type default)
			)
			(layer "F.Fab")
		)
		(fp_line
			(start -0.12065 0.3048)
			(end -0.67945 0.3048)
			(stroke
				(width 0.1)
				(type default)
			)
			(layer "F.Fab")
		)
		(fp_line
			(start -0.12065 0.2794)
			(end -0.12065 0.3048)
			(stroke
				(width 0.1)
				(type default)
			)
			(layer "F.Fab")
		)
		(fp_line
			(start -0.12065 -0.2794)
			(end 0.12065 -0.2794)
			(stroke
				(width 0.1)
				(type default)
			)
			(layer "F.Fab")
		)
		(fp_line
			(start -0.12065 -0.305054)
			(end -0.12065 -0.2794)
			(stroke
				(width 0.1)
				(type default)
			)
			(layer "F.Fab")
		)
		(fp_line
			(start -0.67945 0.3048)
			(end -0.67945 -0.305054)
			(stroke
				(width 0.1)
				(type default)
			)
			(layer "F.Fab")
		)
		(fp_line
			(start -0.67945 -0.305054)
			(end -0.12065 -0.305054)
			(stroke
				(width 0.1)
				(type default)
			)
			(layer "F.Fab")
		)
		(pad "1" smd circle
			(at -0.40005 0 180)
			(size 0 0)
			(layers "F.Cu" "F.Mask" "F.Paste")
			(net "PVDD18_S5_P0")
		)
		(pad "2" smd circle
			(at 0.40005 0 180)
			(size 0 0)
			(layers "F.Cu" "F.Mask" "F.Paste")
			(net "PVDDCR_CPU1_P0_OCP_N_R")
		)
	)
	(footprint ""
		(layer "F.Cu")
		(at 119.379238 -41.17975 -90)
		(property "Reference" "R6280"
			(at 0 0 270)
			(layer "F.SilkS")
			(hide yes)
			(effects
				(font
					(size 1.27 1.27)
				)
			)
		)
		(property "Value" ""
			(at 0 0 270)
			(layer "F.Fab")
			(effects
				(font
					(size 1.27 1.27)
				)
			)
		)
		(duplicate_pad_numbers_are_jumpers no)
		(fp_line
			(start -0.7874 0.4064)
			(end -0.7874 -0.4064)
			(stroke
				(width 0.1524)
				(type default)
			)
			(layer "F.SilkS")
		)
		(fp_line
			(start 0.7874 0.4064)
			(end -0.7874 0.4064)
			(stroke
				(width 0.1524)
				(type default)
			)
			(layer "F.SilkS")
		)
		(fp_line
			(start -0.7874 -0.4064)
			(end 0.7874 -0.4064)
			(stroke
				(width 0.1524)
				(type default)
			)
			(layer "F.SilkS")
		)
		(fp_line
			(start 0.7874 -0.4064)
			(end 0.7874 0.4064)
			(stroke
				(width 0.1524)
				(type default)
			)
			(layer "F.SilkS")
		)
		(fp_line
			(start -0.67945 0.3048)
			(end -0.67945 -0.305054)
			(stroke
				(width 0.1)
				(type default)
			)
			(layer "F.Fab")
		)
		(fp_line
			(start -0.12065 0.3048)
			(end -0.67945 0.3048)
			(stroke
				(width 0.1)
				(type default)
			)
			(layer "F.Fab")
		)
		(fp_line
			(start 0.120396 0.3048)
			(end 0.120396 0.2794)
			(stroke
				(width 0.1)
				(type default)
			)
			(layer "F.Fab")
		)
		(fp_line
			(start 0.67945 0.3048)
			(end 0.120396 0.3048)
			(stroke
				(width 0.1)
				(type default)
			)
			(layer "F.Fab")
		)
		(fp_line
			(start -0.12065 0.2794)
			(end -0.12065 0.3048)
			(stroke
				(width 0.1)
				(type default)
			)
			(layer "F.Fab")
		)
		(fp_line
			(start 0.120396 0.2794)
			(end -0.12065 0.2794)
			(stroke
				(width 0.1)
				(type default)
			)
			(layer "F.Fab")
		)
		(fp_line
			(start -0.12065 -0.2794)
			(end 0.12065 -0.2794)
			(stroke
				(width 0.1)
				(type default)
			)
			(layer "F.Fab")
		)
		(fp_line
			(start 0.12065 -0.2794)
			(end 0.12065 -0.3048)
			(stroke
				(width 0.1)
				(type default)
			)
			(layer "F.Fab")
		)
		(fp_line
			(start 0.12065 -0.3048)
			(end 0.67945 -0.3048)
			(stroke
				(width 0.1)
				(type default)
			)
			(layer "F.Fab")
		)
		(fp_line
			(start 0.67945 -0.3048)
			(end 0.67945 0.3048)
			(stroke
				(width 0.1)
				(type default)
			)
			(layer "F.Fab")
		)
		(fp_line
			(start -0.67945 -0.305054)
			(end -0.12065 -0.305054)
			(stroke
				(width 0.1)
				(type default)
			)
			(layer "F.Fab")
		)
		(fp_line
			(start -0.12065 -0.305054)
			(end -0.12065 -0.2794)
			(stroke
				(width 0.1)
				(type default)
			)
			(layer "F.Fab")
		)
		(pad "1" smd circle
			(at -0.40005 0 270)
			(size 0 0)
			(layers "F.Cu" "F.Mask" "F.Paste")
			(net "SMB_USB_CPU0_HUB1_SCL")
		)
		(pad "2" smd circle
			(at 0.40005 0 270)
			(size 0 0)
			(layers "F.Cu" "F.Mask" "F.Paste")
			(net "SMB_USB_HUB2_TI_SCL_MRP_PRT_CTL1")
		)
	)
	(footprint ""
		(layer "F.Cu")
		(at 143.46174 -78.287626)
		(property "Reference" "PU6000"
			(at -5.757672 -4.30784 0)
			(unlocked yes)
			(layer "F.SilkS")
			(effects
				(font
					(size 0.7874 0.5842)
					(thickness 0.1524)
				)
				(justify left)
			)
		)
		(property "Value" ""
			(at 0 0 0)
			(layer "F.Fab")
			(effects
				(font
					(size 1.27 1.27)
				)
			)
		)
		(duplicate_pad_numbers_are_jumpers no)
		(fp_line
			(start -1.050036 -1.549908)
			(end -0.503936 -1.549908)
			(stroke
				(width 0.1524)
				(type default)
			)
			(layer "F.SilkS")
		)
		(fp_line
			(start -1.050036 -1.253998)
			(end -1.050036 -1.549908)
			(stroke
				(width 0.1524)
				(type default)
			)
			(layer "F.SilkS")
		)
		(fp_line
			(start -1.050036 1.549908)
			(end -1.050036 1.253998)
			(stroke
				(width 0.1524)
				(type default)
			)
			(layer "F.SilkS")
		)
		(fp_line
			(start -0.503936 1.549908)
			(end -1.050036 1.549908)
			(stroke
				(width 0.1524)
				(type default)
			)
			(layer "F.SilkS")
		)
		(fp_line
			(start 0.503936 -1.549908)
			(end 1.050036 -1.549908)
			(stroke
				(width 0.1524)
				(type default)
			)
			(layer "F.SilkS")
		)
		(fp_line
			(start 1.050036 -1.549908)
			(end 1.050036 -1.253998)
			(stroke
				(width 0.1524)
				(type default)
			)
			(layer "F.SilkS")
		)
		(fp_line
			(start 1.050036 1.253998)
			(end 1.050036 1.549908)
			(stroke
				(width 0.1524)
				(type default)
			)
			(layer "F.SilkS")
		)
		(fp_line
			(start 1.050036 1.549908)
			(end 0.503936 1.549908)
			(stroke
				(width 0.1524)
				(type default)
			)
			(layer "F.SilkS")
		)
		(fp_poly
			(pts
				(xy -1.499616 -1.491488) (xy -2.307844 -1.760982) (xy -1.76911 -2.299716)
			)
			(stroke
				(width 0)
				(type default)
			)
			(fill yes)
			(layer "F.SilkS")
		)
		(fp_line
			(start -1.050036 -1.549908)
			(end 1.050036 -1.549908)
			(stroke
				(width 0.1)
				(type default)
			)
			(layer "F.Fab")
		)
		(fp_line
			(start -1.050036 1.549908)
			(end -1.050036 -1.549908)
			(stroke
				(width 0.1)
				(type default)
			)
			(layer "F.Fab")
		)
		(fp_line
			(start 1.050036 -1.549908)
			(end 1.050036 1.549908)
			(stroke
				(width 0.1)
				(type default)
			)
			(layer "F.Fab")
		)
		(fp_line
			(start 1.050036 1.549908)
			(end -1.050036 1.549908)
			(stroke
				(width 0.1)
				(type default)
			)
			(layer "F.Fab")
		)
		(fp_poly
			(pts
				(xy -2.2352 -0.618998) (xy -2.2352 -1.380998) (xy -1.4732 -0.999998)
			)
			(stroke
				(width 0)
				(type default)
			)
			(fill yes)
			(layer "F.Fab")
		)
		(pad "1" smd circle
			(at -0.94996 -0.999998 270)
			(size 0 0)
			(layers "F.Cu" "F.Mask" "F.Paste")
			(net "GND")
		)
		(pad "2" smd rect
			(at -0.849884 -0.499872 90)
			(size 0.254 0.9144)
			(layers "F.Cu" "F.Mask" "F.Paste")
			(net "SW_P1V8_AUX_PH")
		)
		(pad "3" smd rect
			(at -0.649986 0 90)
			(size 0.254 1.3208)
			(layers "F.Cu" "F.Mask" "F.Paste")
			(net "SW_P12V_AUX_P1V8_AUX_FLT")
		)
		(pad "4" smd rect
			(at -0.849884 0.499872 90)
			(size 0.254 0.9144)
			(layers "F.Cu" "F.Mask" "F.Paste")
			(net "P1V8_AUX_CS")
		)
		(pad "5" smd circle
			(at -0.94996 0.999998 270)
			(size 0 0)
			(layers "F.Cu" "F.Mask" "F.Paste")
			(net "P1V8_AUX_ENABLE")
		)
		(pad "6" smd circle
			(at -0.249936 1.450086)
			(size 0 0)
			(layers "F.Cu" "F.Mask" "F.Paste")
			(net "P1V8_AUX_FB")
		)
		(pad "7" smd circle
			(at 0.249936 1.450086)
			(size 0 0)
			(layers "F.Cu" "F.Mask" "F.Paste")
			(net "GND")
		)
		(pad "8" smd circle
			(at 0.94996 0.999998 90)
			(size 0 0)
			(layers "F.Cu" "F.Mask" "F.Paste")
			(net "P1V8_AUX_REF")
		)
		(pad "9" smd rect
			(at 0.849884 0.499872 90)
			(size 0.254 0.9144)
			(layers "F.Cu" "F.Mask" "F.Paste")
			(net "PWRGD_P1V8_AUX")
		)
		(pad "10" smd rect
			(at 0.849884 0 90)
			(size 0.254 0.9144)
			(layers "F.Cu" "F.Mask" "F.Paste")
			(net "SW_P1V8_AUX_BT")
		)
		(pad "11" smd rect
			(at 0.849884 -0.499872 90)
			(size 0.254 0.9144)
			(layers "F.Cu" "F.Mask" "F.Paste")
			(net "SW_P1V8_AUX_PH")
		)
		(pad "12" smd circle
			(at 0.94996 -0.999998 90)
			(size 0 0)
			(layers "F.Cu" "F.Mask" "F.Paste")
			(net "P1V8_AUX_MODE")
		)
		(pad "13" smd circle
			(at 0.249936 -1.450086 180)
			(size 0 0)
			(layers "F.Cu" "F.Mask" "F.Paste")
			(net "P1V8_AUX_VCC")
		)
		(pad "14" smd circle
			(at -0.249936 -1.450086 180)
			(size 0 0)
			(layers "F.Cu" "F.Mask" "F.Paste")
			(net "GND")
		)
	)
	(footprint ""
		(layer "F.Cu")
		(at 121.36247 -78.691486 180)
		(property "Reference" "PC6009"
			(at 0 0 180)
			(layer "F.SilkS")
			(hide yes)
			(effects
				(font
					(size 1.27 1.27)
				)
			)
		)
		(property "Value" ""
			(at 0 0 180)
			(layer "F.Fab")
			(effects
				(font
					(size 1.27 1.27)
				)
			)
		)
		(duplicate_pad_numbers_are_jumpers no)
		(fp_line
			(start 0.7874 0.4064)
			(end -0.7874 0.4064)
			(stroke
				(width 0.1524)
				(type default)
			)
			(layer "F.SilkS")
		)
		(fp_line
			(start 0.7874 -0.4064)
			(end 0.7874 0.4064)
			(stroke
				(width 0.1524)
				(type default)
			)
			(layer "F.SilkS")
		)
		(fp_line
			(start -0.7874 0.4064)
			(end -0.7874 -0.4064)
			(stroke
				(width 0.1524)
				(type default)
			)
			(layer "F.SilkS")
		)
		(fp_line
			(start -0.7874 -0.4064)
			(end 0.7874 -0.4064)
			(stroke
				(width 0.1524)
				(type default)
			)
			(layer "F.SilkS")
		)
		(fp_line
			(start 0.67945 0.3048)
			(end 0.120396 0.3048)
			(stroke
				(width 0.1)
				(type default)
			)
			(layer "F.Fab")
		)
		(fp_line
			(start 0.67945 -0.3048)
			(end 0.67945 0.3048)
			(stroke
				(width 0.1)
				(type default)
			)
			(layer "F.Fab")
		)
		(fp_line
			(start 0.12065 -0.2794)
			(end 0.12065 -0.3048)
			(stroke
				(width 0.1)
				(type default)
			)
			(layer "F.Fab")
		)
		(fp_line
			(start 0.12065 -0.3048)
			(end 0.67945 -0.3048)
			(stroke
				(width 0.1)
				(type default)
			)
			(layer "F.Fab")
		)
		(fp_line
			(start 0.120396 0.3048)
			(end 0.120396 0.2794)
			(stroke
				(width 0.1)
				(type default)
			)
			(layer "F.Fab")
		)
		(fp_line
			(start 0.120396 0.2794)
			(end -0.12065 0.2794)
			(stroke
				(width 0.1)
				(type default)
			)
			(layer "F.Fab")
		)
		(fp_line
			(start -0.12065 0.3048)
			(end -0.67945 0.3048)
			(stroke
				(width 0.1)
				(type default)
			)
			(layer "F.Fab")
		)
		(fp_line
			(start -0.12065 0.2794)
			(end -0.12065 0.3048)
			(stroke
				(width 0.1)
				(type default)
			)
			(layer "F.Fab")
		)
		(fp_line
			(start -0.12065 -0.2794)
			(end 0.12065 -0.2794)
			(stroke
				(width 0.1)
				(type default)
			)
			(layer "F.Fab")
		)
		(fp_line
			(start -0.12065 -0.305054)
			(end -0.12065 -0.2794)
			(stroke
				(width 0.1)
				(type default)
			)
			(layer "F.Fab")
		)
		(fp_line
			(start -0.67945 0.3048)
			(end -0.67945 -0.305054)
			(stroke
				(width 0.1)
				(type default)
			)
			(layer "F.Fab")
		)
		(fp_line
			(start -0.67945 -0.305054)
			(end -0.12065 -0.305054)
			(stroke
				(width 0.1)
				(type default)
			)
			(layer "F.Fab")
		)
		(pad "1" smd circle
			(at -0.40005 0 180)
			(size 0 0)
			(layers "F.Cu" "F.Mask" "F.Paste")
			(net "P1V2_AUX_VCC")
		)
		(pad "2" smd circle
			(at 0.40005 0 180)
			(size 0 0)
			(layers "F.Cu" "F.Mask" "F.Paste")
			(net "GND")
		)
	)
	(footprint ""
		(layer "F.Cu")
		(at 106.696764 -173.5201 -90)
		(property "Reference" "PR198"
			(at 0 0 270)
			(layer "F.SilkS")
			(hide yes)
			(effects
				(font
					(size 1.27 1.27)
				)
			)
		)
		(property "Value" ""
			(at 0 0 270)
			(layer "F.Fab")
			(effects
				(font
					(size 1.27 1.27)
				)
			)
		)
		(duplicate_pad_numbers_are_jumpers no)
		(fp_line
			(start -0.7874 0.4064)
			(end -0.7874 -0.4064)
			(stroke
				(width 0.1524)
				(type default)
			)
			(layer "F.SilkS")
		)
		(fp_line
			(start 0.7874 0.4064)
			(end -0.7874 0.4064)
			(stroke
				(width 0.1524)
				(type default)
			)
			(layer "F.SilkS")
		)
		(fp_line
			(start -0.7874 -0.4064)
			(end 0.7874 -0.4064)
			(stroke
				(width 0.1524)
				(type default)
			)
			(layer "F.SilkS")
		)
		(fp_line
			(start 0.7874 -0.4064)
			(end 0.7874 0.4064)
			(stroke
				(width 0.1524)
				(type default)
			)
			(layer "F.SilkS")
		)
		(fp_line
			(start -0.67945 0.3048)
			(end -0.67945 -0.305054)
			(stroke
				(width 0.1)
				(type default)
			)
			(layer "F.Fab")
		)
		(fp_line
			(start -0.12065 0.3048)
			(end -0.67945 0.3048)
			(stroke
				(width 0.1)
				(type default)
			)
			(layer "F.Fab")
		)
		(fp_line
			(start 0.120396 0.3048)
			(end 0.120396 0.2794)
			(stroke
				(width 0.1)
				(type default)
			)
			(layer "F.Fab")
		)
		(fp_line
			(start 0.67945 0.3048)
			(end 0.120396 0.3048)
			(stroke
				(width 0.1)
				(type default)
			)
			(layer "F.Fab")
		)
		(fp_line
			(start -0.12065 0.2794)
			(end -0.12065 0.3048)
			(stroke
				(width 0.1)
				(type default)
			)
			(layer "F.Fab")
		)
		(fp_line
			(start 0.120396 0.2794)
			(end -0.12065 0.2794)
			(stroke
				(width 0.1)
				(type default)
			)
			(layer "F.Fab")
		)
		(fp_line
			(start -0.12065 -0.2794)
			(end 0.12065 -0.2794)
			(stroke
				(width 0.1)
				(type default)
			)
			(layer "F.Fab")
		)
		(fp_line
			(start 0.12065 -0.2794)
			(end 0.12065 -0.3048)
			(stroke
				(width 0.1)
				(type default)
			)
			(layer "F.Fab")
		)
		(fp_line
			(start 0.12065 -0.3048)
			(end 0.67945 -0.3048)
			(stroke
				(width 0.1)
				(type default)
			)
			(layer "F.Fab")
		)
		(fp_line
			(start 0.67945 -0.3048)
			(end 0.67945 0.3048)
			(stroke
				(width 0.1)
				(type default)
			)
			(layer "F.Fab")
		)
		(fp_line
			(start -0.67945 -0.305054)
			(end -0.12065 -0.305054)
			(stroke
				(width 0.1)
				(type default)
			)
			(layer "F.Fab")
		)
		(fp_line
			(start -0.12065 -0.305054)
			(end -0.12065 -0.2794)
			(stroke
				(width 0.1)
				(type default)
			)
			(layer "F.Fab")
		)
		(pad "1" smd circle
			(at -0.40005 0 270)
			(size 0 0)
			(layers "F.Cu" "F.Mask" "F.Paste")
			(net "SW_PVDDCR_CPU0_P1_BOOT4")
		)
		(pad "2" smd circle
			(at 0.40005 0 270)
			(size 0 0)
			(layers "F.Cu" "F.Mask" "F.Paste")
			(net "SW_PVDDCR_CPU0_P1_BOOT4_RC")
		)
	)
	(footprint ""
		(layer "F.Cu")
		(at 34.379662 -429.790098 90)
		(property "Reference" "R3267"
			(at 0 0 90)
			(layer "F.SilkS")
			(hide yes)
			(effects
				(font
					(size 1.27 1.27)
				)
			)
		)
		(property "Value" ""
			(at 0 0 90)
			(layer "F.Fab")
			(effects
				(font
					(size 1.27 1.27)
				)
			)
		)
		(duplicate_pad_numbers_are_jumpers no)
		(fp_line
			(start 0.7874 -0.4064)
			(end 0.7874 0.4064)
			(stroke
				(width 0.1524)
				(type default)
			)
			(layer "F.SilkS")
		)
		(fp_line
			(start -0.7874 -0.4064)
			(end 0.7874 -0.4064)
			(stroke
				(width 0.1524)
				(type default)
			)
			(layer "F.SilkS")
		)
		(fp_line
			(start 0.7874 0.4064)
			(end -0.7874 0.4064)
			(stroke
				(width 0.1524)
				(type default)
			)
			(layer "F.SilkS")
		)
		(fp_line
			(start -0.7874 0.4064)
			(end -0.7874 -0.4064)
			(stroke
				(width 0.1524)
				(type default)
			)
			(layer "F.SilkS")
		)
		(fp_line
			(start -0.12065 -0.305054)
			(end -0.12065 -0.2794)
			(stroke
				(width 0.1)
				(type default)
			)
			(layer "F.Fab")
		)
		(fp_line
			(start -0.67945 -0.305054)
			(end -0.12065 -0.305054)
			(stroke
				(width 0.1)
				(type default)
			)
			(layer "F.Fab")
		)
		(fp_line
			(start 0.67945 -0.3048)
			(end 0.67945 0.3048)
			(stroke
				(width 0.1)
				(type default)
			)
			(layer "F.Fab")
		)
		(fp_line
			(start 0.12065 -0.3048)
			(end 0.67945 -0.3048)
			(stroke
				(width 0.1)
				(type default)
			)
			(layer "F.Fab")
		)
		(fp_line
			(start 0.12065 -0.2794)
			(end 0.12065 -0.3048)
			(stroke
				(width 0.1)
				(type default)
			)
			(layer "F.Fab")
		)
		(fp_line
			(start -0.12065 -0.2794)
			(end 0.12065 -0.2794)
			(stroke
				(width 0.1)
				(type default)
			)
			(layer "F.Fab")
		)
		(fp_line
			(start 0.120396 0.2794)
			(end -0.12065 0.2794)
			(stroke
				(width 0.1)
				(type default)
			)
			(layer "F.Fab")
		)
		(fp_line
			(start -0.12065 0.2794)
			(end -0.12065 0.3048)
			(stroke
				(width 0.1)
				(type default)
			)
			(layer "F.Fab")
		)
		(fp_line
			(start 0.67945 0.3048)
			(end 0.120396 0.3048)
			(stroke
				(width 0.1)
				(type default)
			)
			(layer "F.Fab")
		)
		(fp_line
			(start 0.120396 0.3048)
			(end 0.120396 0.2794)
			(stroke
				(width 0.1)
				(type default)
			)
			(layer "F.Fab")
		)
		(fp_line
			(start -0.12065 0.3048)
			(end -0.67945 0.3048)
			(stroke
				(width 0.1)
				(type default)
			)
			(layer "F.Fab")
		)
		(fp_line
			(start -0.67945 0.3048)
			(end -0.67945 -0.305054)
			(stroke
				(width 0.1)
				(type default)
			)
			(layer "F.Fab")
		)
		(pad "1" smd circle
			(at -0.40005 0 90)
			(size 0 0)
			(layers "F.Cu" "F.Mask" "F.Paste")
			(net "FM_P2E_FGB")
		)
		(pad "2" smd circle
			(at 0.40005 0 90)
			(size 0 0)
			(layers "F.Cu" "F.Mask" "F.Paste")
			(net "GND")
		)
	)
	(footprint ""
		(layer "F.Cu")
		(at 446.258442 -53.188108 90)
		(property "Reference" "PC2261"
			(at 0 0 90)
			(layer "F.SilkS")
			(hide yes)
			(effects
				(font
					(size 1.27 1.27)
				)
			)
		)
		(property "Value" ""
			(at 0 0 90)
			(layer "F.Fab")
			(effects
				(font
					(size 1.27 1.27)
				)
			)
		)
		(duplicate_pad_numbers_are_jumpers no)
		(fp_line
			(start 1.524 -0.762)
			(end 1.524 0.762)
			(stroke
				(width 0.1524)
				(type default)
			)
			(layer "F.SilkS")
		)
		(fp_line
			(start -1.524 -0.762)
			(end 1.524 -0.762)
			(stroke
				(width 0.1524)
				(type default)
			)
			(layer "F.SilkS")
		)
		(fp_line
			(start 1.524 0.762)
			(end -1.524 0.762)
			(stroke
				(width 0.1524)
				(type default)
			)
			(layer "F.SilkS")
		)
		(fp_line
			(start -1.524 0.762)
			(end -1.524 -0.762)
			(stroke
				(width 0.1524)
				(type default)
			)
			(layer "F.SilkS")
		)
		(fp_line
			(start 1.1049 -0.724916)
			(end -1.1049 -0.724916)
			(stroke
				(width 0.1)
				(type default)
			)
			(layer "F.Fab")
		)
		(fp_line
			(start -1.1049 -0.724916)
			(end -1.1049 0.724916)
			(stroke
				(width 0.1)
				(type default)
			)
			(layer "F.Fab")
		)
		(fp_line
			(start 1.1049 0.724916)
			(end 1.1049 -0.724916)
			(stroke
				(width 0.1)
				(type default)
			)
			(layer "F.Fab")
		)
		(fp_line
			(start -1.1049 0.724916)
			(end 1.1049 0.724916)
			(stroke
				(width 0.1)
				(type default)
			)
			(layer "F.Fab")
		)
		(pad "1" smd rect
			(at -0.889 0 270)
			(size 1.016 1.27)
			(layers "F.Cu" "F.Mask" "F.Paste")
			(net "SW_P3V3_AUX_FLT")
		)
		(pad "2" smd rect
			(at 0.889 0 270)
			(size 1.016 1.27)
			(layers "F.Cu" "F.Mask" "F.Paste")
			(net "GND")
		)
	)
	(footprint ""
		(layer "F.Cu")
		(at 20.480782 -410.564584 180)
		(property "Reference" "PR6806"
			(at 0 0 180)
			(layer "F.SilkS")
			(hide yes)
			(effects
				(font
					(size 1.27 1.27)
				)
			)
		)
		(property "Value" ""
			(at 0 0 180)
			(layer "F.Fab")
			(effects
				(font
					(size 1.27 1.27)
				)
			)
		)
		(duplicate_pad_numbers_are_jumpers no)
		(fp_line
			(start 0.7874 0.4064)
			(end -0.7874 0.4064)
			(stroke
				(width 0.1524)
				(type default)
			)
			(layer "F.SilkS")
		)
		(fp_line
			(start 0.7874 -0.4064)
			(end 0.7874 0.4064)
			(stroke
				(width 0.1524)
				(type default)
			)
			(layer "F.SilkS")
		)
		(fp_line
			(start -0.7874 0.4064)
			(end -0.7874 -0.4064)
			(stroke
				(width 0.1524)
				(type default)
			)
			(layer "F.SilkS")
		)
		(fp_line
			(start -0.7874 -0.4064)
			(end 0.7874 -0.4064)
			(stroke
				(width 0.1524)
				(type default)
			)
			(layer "F.SilkS")
		)
		(fp_line
			(start 0.67945 0.3048)
			(end 0.120396 0.3048)
			(stroke
				(width 0.1)
				(type default)
			)
			(layer "F.Fab")
		)
		(fp_line
			(start 0.67945 -0.3048)
			(end 0.67945 0.3048)
			(stroke
				(width 0.1)
				(type default)
			)
			(layer "F.Fab")
		)
		(fp_line
			(start 0.12065 -0.2794)
			(end 0.12065 -0.3048)
			(stroke
				(width 0.1)
				(type default)
			)
			(layer "F.Fab")
		)
		(fp_line
			(start 0.12065 -0.3048)
			(end 0.67945 -0.3048)
			(stroke
				(width 0.1)
				(type default)
			)
			(layer "F.Fab")
		)
		(fp_line
			(start 0.120396 0.3048)
			(end 0.120396 0.2794)
			(stroke
				(width 0.1)
				(type default)
			)
			(layer "F.Fab")
		)
		(fp_line
			(start 0.120396 0.2794)
			(end -0.12065 0.2794)
			(stroke
				(width 0.1)
				(type default)
			)
			(layer "F.Fab")
		)
		(fp_line
			(start -0.12065 0.3048)
			(end -0.67945 0.3048)
			(stroke
				(width 0.1)
				(type default)
			)
			(layer "F.Fab")
		)
		(fp_line
			(start -0.12065 0.2794)
			(end -0.12065 0.3048)
			(stroke
				(width 0.1)
				(type default)
			)
			(layer "F.Fab")
		)
		(fp_line
			(start -0.12065 -0.2794)
			(end 0.12065 -0.2794)
			(stroke
				(width 0.1)
				(type default)
			)
			(layer "F.Fab")
		)
		(fp_line
			(start -0.12065 -0.305054)
			(end -0.12065 -0.2794)
			(stroke
				(width 0.1)
				(type default)
			)
			(layer "F.Fab")
		)
		(fp_line
			(start -0.67945 0.3048)
			(end -0.67945 -0.305054)
			(stroke
				(width 0.1)
				(type default)
			)
			(layer "F.Fab")
		)
		(fp_line
			(start -0.67945 -0.305054)
			(end -0.12065 -0.305054)
			(stroke
				(width 0.1)
				(type default)
			)
			(layer "F.Fab")
		)
		(pad "1" smd circle
			(at -0.40005 0 180)
			(size 0 0)
			(layers "F.Cu" "F.Mask" "F.Paste")
			(net "P3V3_AUX")
		)
		(pad "2" smd circle
			(at 0.40005 0 180)
			(size 0 0)
			(layers "F.Cu" "F.Mask" "F.Paste")
			(net "P0V9_RETIMER_CPU1_SVID_CLK")
		)
	)
	(footprint ""
		(layer "F.Cu")
		(at 419.10889 -109.231176 -90)
		(property "Reference" "R1487"
			(at 0 0 270)
			(layer "F.SilkS")
			(hide yes)
			(effects
				(font
					(size 1.27 1.27)
				)
			)
		)
		(property "Value" ""
			(at 0 0 270)
			(layer "F.Fab")
			(effects
				(font
					(size 1.27 1.27)
				)
			)
		)
		(duplicate_pad_numbers_are_jumpers no)
		(fp_line
			(start -0.7874 0.4064)
			(end -0.7874 -0.4064)
			(stroke
				(width 0.1524)
				(type default)
			)
			(layer "F.SilkS")
		)
		(fp_line
			(start 0.7874 0.4064)
			(end -0.7874 0.4064)
			(stroke
				(width 0.1524)
				(type default)
			)
			(layer "F.SilkS")
		)
		(fp_line
			(start -0.7874 -0.4064)
			(end 0.7874 -0.4064)
			(stroke
				(width 0.1524)
				(type default)
			)
			(layer "F.SilkS")
		)
		(fp_line
			(start 0.7874 -0.4064)
			(end 0.7874 0.4064)
			(stroke
				(width 0.1524)
				(type default)
			)
			(layer "F.SilkS")
		)
		(fp_line
			(start -0.67945 0.3048)
			(end -0.67945 -0.305054)
			(stroke
				(width 0.1)
				(type default)
			)
			(layer "F.Fab")
		)
		(fp_line
			(start -0.12065 0.3048)
			(end -0.67945 0.3048)
			(stroke
				(width 0.1)
				(type default)
			)
			(layer "F.Fab")
		)
		(fp_line
			(start 0.120396 0.3048)
			(end 0.120396 0.2794)
			(stroke
				(width 0.1)
				(type default)
			)
			(layer "F.Fab")
		)
		(fp_line
			(start 0.67945 0.3048)
			(end 0.120396 0.3048)
			(stroke
				(width 0.1)
				(type default)
			)
			(layer "F.Fab")
		)
		(fp_line
			(start -0.12065 0.2794)
			(end -0.12065 0.3048)
			(stroke
				(width 0.1)
				(type default)
			)
			(layer "F.Fab")
		)
		(fp_line
			(start 0.120396 0.2794)
			(end -0.12065 0.2794)
			(stroke
				(width 0.1)
				(type default)
			)
			(layer "F.Fab")
		)
		(fp_line
			(start -0.12065 -0.2794)
			(end 0.12065 -0.2794)
			(stroke
				(width 0.1)
				(type default)
			)
			(layer "F.Fab")
		)
		(fp_line
			(start 0.12065 -0.2794)
			(end 0.12065 -0.3048)
			(stroke
				(width 0.1)
				(type default)
			)
			(layer "F.Fab")
		)
		(fp_line
			(start 0.12065 -0.3048)
			(end 0.67945 -0.3048)
			(stroke
				(width 0.1)
				(type default)
			)
			(layer "F.Fab")
		)
		(fp_line
			(start 0.67945 -0.3048)
			(end 0.67945 0.3048)
			(stroke
				(width 0.1)
				(type default)
			)
			(layer "F.Fab")
		)
		(fp_line
			(start -0.67945 -0.305054)
			(end -0.12065 -0.305054)
			(stroke
				(width 0.1)
				(type default)
			)
			(layer "F.Fab")
		)
		(fp_line
			(start -0.12065 -0.305054)
			(end -0.12065 -0.2794)
			(stroke
				(width 0.1)
				(type default)
			)
			(layer "F.Fab")
		)
		(pad "1" smd circle
			(at -0.40005 0 270)
			(size 0 0)
			(layers "F.Cu" "F.Mask" "F.Paste")
			(net "P12V_OCP_SFF_BUF_EN_R")
		)
		(pad "2" smd circle
			(at 0.40005 0 270)
			(size 0 0)
			(layers "F.Cu" "F.Mask" "F.Paste")
			(net "P3V3_OCP_EN_1_R2")
		)
	)
	(footprint ""
		(layer "F.Cu")
		(at 186.038236 -428.414942 90)
		(property "Reference" "R3442"
			(at 0 0 90)
			(layer "F.SilkS")
			(hide yes)
			(effects
				(font
					(size 1.27 1.27)
				)
			)
		)
		(property "Value" ""
			(at 0 0 90)
			(layer "F.Fab")
			(effects
				(font
					(size 1.27 1.27)
				)
			)
		)
		(duplicate_pad_numbers_are_jumpers no)
		(fp_line
			(start 0.7874 -0.4064)
			(end 0.7874 0.4064)
			(stroke
				(width 0.1524)
				(type default)
			)
			(layer "F.SilkS")
		)
		(fp_line
			(start -0.7874 -0.4064)
			(end 0.7874 -0.4064)
			(stroke
				(width 0.1524)
				(type default)
			)
			(layer "F.SilkS")
		)
		(fp_line
			(start 0.7874 0.4064)
			(end -0.7874 0.4064)
			(stroke
				(width 0.1524)
				(type default)
			)
			(layer "F.SilkS")
		)
		(fp_line
			(start -0.7874 0.4064)
			(end -0.7874 -0.4064)
			(stroke
				(width 0.1524)
				(type default)
			)
			(layer "F.SilkS")
		)
		(fp_line
			(start -0.12065 -0.305054)
			(end -0.12065 -0.2794)
			(stroke
				(width 0.1)
				(type default)
			)
			(layer "F.Fab")
		)
		(fp_line
			(start -0.67945 -0.305054)
			(end -0.12065 -0.305054)
			(stroke
				(width 0.1)
				(type default)
			)
			(layer "F.Fab")
		)
		(fp_line
			(start 0.67945 -0.3048)
			(end 0.67945 0.3048)
			(stroke
				(width 0.1)
				(type default)
			)
			(layer "F.Fab")
		)
		(fp_line
			(start 0.12065 -0.3048)
			(end 0.67945 -0.3048)
			(stroke
				(width 0.1)
				(type default)
			)
			(layer "F.Fab")
		)
		(fp_line
			(start 0.12065 -0.2794)
			(end 0.12065 -0.3048)
			(stroke
				(width 0.1)
				(type default)
			)
			(layer "F.Fab")
		)
		(fp_line
			(start -0.12065 -0.2794)
			(end 0.12065 -0.2794)
			(stroke
				(width 0.1)
				(type default)
			)
			(layer "F.Fab")
		)
		(fp_line
			(start 0.120396 0.2794)
			(end -0.12065 0.2794)
			(stroke
				(width 0.1)
				(type default)
			)
			(layer "F.Fab")
		)
		(fp_line
			(start -0.12065 0.2794)
			(end -0.12065 0.3048)
			(stroke
				(width 0.1)
				(type default)
			)
			(layer "F.Fab")
		)
		(fp_line
			(start 0.67945 0.3048)
			(end 0.120396 0.3048)
			(stroke
				(width 0.1)
				(type default)
			)
			(layer "F.Fab")
		)
		(fp_line
			(start 0.120396 0.3048)
			(end 0.120396 0.2794)
			(stroke
				(width 0.1)
				(type default)
			)
			(layer "F.Fab")
		)
		(fp_line
			(start -0.12065 0.3048)
			(end -0.67945 0.3048)
			(stroke
				(width 0.1)
				(type default)
			)
			(layer "F.Fab")
		)
		(fp_line
			(start -0.67945 0.3048)
			(end -0.67945 -0.305054)
			(stroke
				(width 0.1)
				(type default)
			)
			(layer "F.Fab")
		)
		(pad "1" smd circle
			(at -0.40005 0 90)
			(size 0 0)
			(layers "F.Cu" "F.Mask" "F.Paste")
			(net "GPU_PEX_STRAP0")
		)
		(pad "2" smd circle
			(at 0.40005 0 90)
			(size 0 0)
			(layers "F.Cu" "F.Mask" "F.Paste")
			(net "GND")
		)
	)
	(footprint ""
		(layer "F.Cu")
		(at 307.404516 -435.720744 90)
		(property "Reference" "C1976"
			(at 0 0 90)
			(layer "F.SilkS")
			(hide yes)
			(effects
				(font
					(size 1.27 1.27)
				)
			)
		)
		(property "Value" ""
			(at 0 0 90)
			(layer "F.Fab")
			(effects
				(font
					(size 1.27 1.27)
				)
			)
		)
		(duplicate_pad_numbers_are_jumpers no)
		(fp_line
			(start 0.7874 -0.4064)
			(end 0.7874 0.4064)
			(stroke
				(width 0.1524)
				(type default)
			)
			(layer "F.SilkS")
		)
		(fp_line
			(start -0.7874 -0.4064)
			(end 0.7874 -0.4064)
			(stroke
				(width 0.1524)
				(type default)
			)
			(layer "F.SilkS")
		)
		(fp_line
			(start 0.7874 0.4064)
			(end -0.7874 0.4064)
			(stroke
				(width 0.1524)
				(type default)
			)
			(layer "F.SilkS")
		)
		(fp_line
			(start -0.7874 0.4064)
			(end -0.7874 -0.4064)
			(stroke
				(width 0.1524)
				(type default)
			)
			(layer "F.SilkS")
		)
		(fp_line
			(start -0.12065 -0.305054)
			(end -0.12065 -0.2794)
			(stroke
				(width 0.1)
				(type default)
			)
			(layer "F.Fab")
		)
		(fp_line
			(start -0.67945 -0.305054)
			(end -0.12065 -0.305054)
			(stroke
				(width 0.1)
				(type default)
			)
			(layer "F.Fab")
		)
		(fp_line
			(start 0.67945 -0.3048)
			(end 0.67945 0.3048)
			(stroke
				(width 0.1)
				(type default)
			)
			(layer "F.Fab")
		)
		(fp_line
			(start 0.12065 -0.3048)
			(end 0.67945 -0.3048)
			(stroke
				(width 0.1)
				(type default)
			)
			(layer "F.Fab")
		)
		(fp_line
			(start 0.12065 -0.2794)
			(end 0.12065 -0.3048)
			(stroke
				(width 0.1)
				(type default)
			)
			(layer "F.Fab")
		)
		(fp_line
			(start -0.12065 -0.2794)
			(end 0.12065 -0.2794)
			(stroke
				(width 0.1)
				(type default)
			)
			(layer "F.Fab")
		)
		(fp_line
			(start 0.120396 0.2794)
			(end -0.12065 0.2794)
			(stroke
				(width 0.1)
				(type default)
			)
			(layer "F.Fab")
		)
		(fp_line
			(start -0.12065 0.2794)
			(end -0.12065 0.3048)
			(stroke
				(width 0.1)
				(type default)
			)
			(layer "F.Fab")
		)
		(fp_line
			(start 0.67945 0.3048)
			(end 0.120396 0.3048)
			(stroke
				(width 0.1)
				(type default)
			)
			(layer "F.Fab")
		)
		(fp_line
			(start 0.120396 0.3048)
			(end 0.120396 0.2794)
			(stroke
				(width 0.1)
				(type default)
			)
			(layer "F.Fab")
		)
		(fp_line
			(start -0.12065 0.3048)
			(end -0.67945 0.3048)
			(stroke
				(width 0.1)
				(type default)
			)
			(layer "F.Fab")
		)
		(fp_line
			(start -0.67945 0.3048)
			(end -0.67945 -0.305054)
			(stroke
				(width 0.1)
				(type default)
			)
			(layer "F.Fab")
		)
		(pad "1" smd circle
			(at -0.40005 0 90)
			(size 0 0)
			(layers "F.Cu" "F.Mask" "F.Paste")
			(net "GPU_FPGA_OVERT_ISO_N")
		)
		(pad "2" smd circle
			(at 0.40005 0 90)
			(size 0 0)
			(layers "F.Cu" "F.Mask" "F.Paste")
			(net "GND")
		)
	)
	(footprint ""
		(layer "F.Cu")
		(at 138.617198 -167.510206 180)
		(property "Reference" "PR164"
			(at 0 0 180)
			(layer "F.SilkS")
			(hide yes)
			(effects
				(font
					(size 1.27 1.27)
				)
			)
		)
		(property "Value" ""
			(at 0 0 180)
			(layer "F.Fab")
			(effects
				(font
					(size 1.27 1.27)
				)
			)
		)
		(duplicate_pad_numbers_are_jumpers no)
		(fp_line
			(start 0.7874 0.4064)
			(end -0.7874 0.4064)
			(stroke
				(width 0.1524)
				(type default)
			)
			(layer "F.SilkS")
		)
		(fp_line
			(start 0.7874 -0.4064)
			(end 0.7874 0.4064)
			(stroke
				(width 0.1524)
				(type default)
			)
			(layer "F.SilkS")
		)
		(fp_line
			(start -0.7874 0.4064)
			(end -0.7874 -0.4064)
			(stroke
				(width 0.1524)
				(type default)
			)
			(layer "F.SilkS")
		)
		(fp_line
			(start -0.7874 -0.4064)
			(end 0.7874 -0.4064)
			(stroke
				(width 0.1524)
				(type default)
			)
			(layer "F.SilkS")
		)
		(fp_line
			(start 0.67945 0.3048)
			(end 0.120396 0.3048)
			(stroke
				(width 0.1)
				(type default)
			)
			(layer "F.Fab")
		)
		(fp_line
			(start 0.67945 -0.3048)
			(end 0.67945 0.3048)
			(stroke
				(width 0.1)
				(type default)
			)
			(layer "F.Fab")
		)
		(fp_line
			(start 0.12065 -0.2794)
			(end 0.12065 -0.3048)
			(stroke
				(width 0.1)
				(type default)
			)
			(layer "F.Fab")
		)
		(fp_line
			(start 0.12065 -0.3048)
			(end 0.67945 -0.3048)
			(stroke
				(width 0.1)
				(type default)
			)
			(layer "F.Fab")
		)
		(fp_line
			(start 0.120396 0.3048)
			(end 0.120396 0.2794)
			(stroke
				(width 0.1)
				(type default)
			)
			(layer "F.Fab")
		)
		(fp_line
			(start 0.120396 0.2794)
			(end -0.12065 0.2794)
			(stroke
				(width 0.1)
				(type default)
			)
			(layer "F.Fab")
		)
		(fp_line
			(start -0.12065 0.3048)
			(end -0.67945 0.3048)
			(stroke
				(width 0.1)
				(type default)
			)
			(layer "F.Fab")
		)
		(fp_line
			(start -0.12065 0.2794)
			(end -0.12065 0.3048)
			(stroke
				(width 0.1)
				(type default)
			)
			(layer "F.Fab")
		)
		(fp_line
			(start -0.12065 -0.2794)
			(end 0.12065 -0.2794)
			(stroke
				(width 0.1)
				(type default)
			)
			(layer "F.Fab")
		)
		(fp_line
			(start -0.12065 -0.305054)
			(end -0.12065 -0.2794)
			(stroke
				(width 0.1)
				(type default)
			)
			(layer "F.Fab")
		)
		(fp_line
			(start -0.67945 0.3048)
			(end -0.67945 -0.305054)
			(stroke
				(width 0.1)
				(type default)
			)
			(layer "F.Fab")
		)
		(fp_line
			(start -0.67945 -0.305054)
			(end -0.12065 -0.305054)
			(stroke
				(width 0.1)
				(type default)
			)
			(layer "F.Fab")
		)
		(pad "1" smd circle
			(at -0.40005 0 180)
			(size 0 0)
			(layers "F.Cu" "F.Mask" "F.Paste")
			(net "VSENSE_VSS_SENSE_A_P1")
		)
		(pad "2" smd circle
			(at 0.40005 0 180)
			(size 0 0)
			(layers "F.Cu" "F.Mask" "F.Paste")
			(net "GND")
		)
	)
	(footprint ""
		(layer "F.Cu")
		(at 167.871902 -439.490358)
		(property "Reference" "Q67"
			(at 3.377184 1.185672 0)
			(unlocked yes)
			(layer "F.SilkS")
			(effects
				(font
					(size 0.7874 0.5842)
					(thickness 0.1524)
				)
				(justify left)
			)
		)
		(property "Value" ""
			(at 0 0 0)
			(layer "F.Fab")
			(effects
				(font
					(size 1.27 1.27)
				)
			)
		)
		(duplicate_pad_numbers_are_jumpers no)
		(fp_line
			(start -1.332738 -1.100074)
			(end -0.4826 -1.100074)
			(stroke
				(width 0.1524)
				(type default)
			)
			(layer "F.SilkS")
		)
		(fp_line
			(start -1.332738 1.100074)
			(end -1.332738 -1.100074)
			(stroke
				(width 0.1524)
				(type default)
			)
			(layer "F.SilkS")
		)
		(fp_line
			(start -0.4826 -1.100074)
			(end 0 -0.541274)
			(stroke
				(width 0.1524)
				(type default)
			)
			(layer "F.SilkS")
		)
		(fp_line
			(start 0 -0.541274)
			(end 0.4826 -1.100074)
			(stroke
				(width 0.1524)
				(type default)
			)
			(layer "F.SilkS")
		)
		(fp_line
			(start 0.4826 -1.100074)
			(end 1.332738 -1.100074)
			(stroke
				(width 0.1524)
				(type default)
			)
			(layer "F.SilkS")
		)
		(fp_line
			(start 1.332738 -1.100074)
			(end 1.332738 1.100074)
			(stroke
				(width 0.1524)
				(type default)
			)
			(layer "F.SilkS")
		)
		(fp_line
			(start 1.332738 1.100074)
			(end -1.332738 1.100074)
			(stroke
				(width 0.1524)
				(type default)
			)
			(layer "F.SilkS")
		)
		(fp_poly
			(pts
				(xy -1.561592 -1.409192) (xy -2.337308 -1.52908) (xy -1.930908 -2.101596)
			)
			(stroke
				(width 0)
				(type default)
			)
			(fill yes)
			(layer "F.SilkS")
		)
		(fp_line
			(start -0.674878 -1.100074)
			(end 0.674878 -1.100074)
			(stroke
				(width 0.1)
				(type default)
			)
			(layer "F.Fab")
		)
		(fp_line
			(start -0.674878 1.100074)
			(end -0.674878 -1.100074)
			(stroke
				(width 0.1)
				(type default)
			)
			(layer "F.Fab")
		)
		(fp_line
			(start 0.674878 -1.100074)
			(end 0.674878 1.100074)
			(stroke
				(width 0.1)
				(type default)
			)
			(layer "F.Fab")
		)
		(fp_line
			(start 0.674878 1.100074)
			(end -0.674878 1.100074)
			(stroke
				(width 0.1)
				(type default)
			)
			(layer "F.Fab")
		)
		(fp_poly
			(pts
				(xy -2.2352 -0.298958) (xy -2.2352 -1.001014) (xy -1.533144 -0.649986)
			)
			(stroke
				(width 0)
				(type default)
			)
			(fill yes)
			(layer "F.Fab")
		)
		(pad "1" smd rect
			(at -0.94996 -0.649986 90)
			(size 0.4318 0.508)
			(layers "F.Cu" "F.Mask" "F.Paste")
			(net "GND")
		)
		(pad "2" smd rect
			(at -0.94996 0 90)
			(size 0.4318 0.508)
			(layers "F.Cu" "F.Mask" "F.Paste")
			(net "BIC_MONITER")
		)
		(pad "3" smd rect
			(at -0.94996 0.649986 90)
			(size 0.4318 0.508)
			(layers "F.Cu" "F.Mask" "F.Paste")
			(net "BIC_MONITER_ISO")
		)
		(pad "4" smd rect
			(at 0.94996 0.649986 90)
			(size 0.4318 0.508)
			(layers "F.Cu" "F.Mask" "F.Paste")
			(net "GND")
		)
		(pad "5" smd rect
			(at 0.94996 0 90)
			(size 0.4318 0.508)
			(layers "F.Cu" "F.Mask" "F.Paste")
			(net "BIC_MONITER_N")
		)
		(pad "6" smd rect
			(at 0.94996 -0.649986 90)
			(size 0.4318 0.508)
			(layers "F.Cu" "F.Mask" "F.Paste")
			(net "BIC_MONITER_N")
		)
	)
	(footprint ""
		(layer "F.Cu")
		(at 407.1874 -76.063348)
		(property "Reference" "U236"
			(at -3.0988 -2.885948 0)
			(unlocked yes)
			(layer "F.SilkS")
			(effects
				(font
					(size 0.7874 0.5842)
					(thickness 0.1524)
				)
				(justify left)
			)
		)
		(property "Value" ""
			(at 0 0 0)
			(layer "F.Fab")
			(effects
				(font
					(size 1.27 1.27)
				)
			)
		)
		(duplicate_pad_numbers_are_jumpers no)
		(fp_line
			(start -1.463548 -1.549908)
			(end -0.787908 -1.549908)
			(stroke
				(width 0.1524)
				(type default)
			)
			(layer "F.SilkS")
		)
		(fp_line
			(start -1.463548 1.549908)
			(end -1.463548 -1.549908)
			(stroke
				(width 0.1524)
				(type default)
			)
			(layer "F.SilkS")
		)
		(fp_line
			(start -0.787908 -1.549908)
			(end -0.0254 -0.7874)
			(stroke
				(width 0.1524)
				(type default)
			)
			(layer "F.SilkS")
		)
		(fp_line
			(start -0.0254 1.549908)
			(end -1.463548 1.549908)
			(stroke
				(width 0.1524)
				(type default)
			)
			(layer "F.SilkS")
		)
		(fp_line
			(start 1.0922 -1.549908)
			(end 1.463548 -1.549908)
			(stroke
				(width 0.1524)
				(type default)
			)
			(layer "F.SilkS")
		)
		(fp_line
			(start 1.463548 -1.549908)
			(end 1.463548 1.549908)
			(stroke
				(width 0.1524)
				(type default)
			)
			(layer "F.SilkS")
		)
		(fp_line
			(start 1.463548 1.549908)
			(end 1.0922 1.549908)
			(stroke
				(width 0.1524)
				(type default)
			)
			(layer "F.SilkS")
		)
		(fp_poly
			(pts
				(xy -2.623566 -2.194306) (xy -2.00406 -2.205482) (xy -2.30251 -1.580134)
			)
			(stroke
				(width 0)
				(type default)
			)
			(fill yes)
			(layer "F.SilkS")
		)
		(fp_line
			(start -1.549908 -1.549908)
			(end 1.549908 -1.549908)
			(stroke
				(width 0.1)
				(type default)
			)
			(layer "F.Fab")
		)
		(fp_line
			(start -1.549908 1.549908)
			(end -1.549908 -1.549908)
			(stroke
				(width 0.1)
				(type default)
			)
			(layer "F.Fab")
		)
		(fp_line
			(start 1.549908 -1.549908)
			(end 1.549908 1.549908)
			(stroke
				(width 0.1)
				(type default)
			)
			(layer "F.Fab")
		)
		(fp_line
			(start 1.549908 1.549908)
			(end -1.549908 1.549908)
			(stroke
				(width 0.1)
				(type default)
			)
			(layer "F.Fab")
		)
		(fp_poly
			(pts
				(xy -3.4798 -1.359916) (xy -2.86004 -1.050036) (xy -3.4798 -0.740156)
			)
			(stroke
				(width 0)
				(type default)
			)
			(fill yes)
			(layer "F.Fab")
		)
		(pad "1" smd rect
			(at -2.175002 -1.050036 90)
			(size 0.6096 1.1684)
			(layers "F.Cu" "F.Mask" "F.Paste")
			(net "P3V3_AUX")
		)
		(pad "2" smd rect
			(at -2.175002 -0.32512 90)
			(size 0.4318 1.1684)
			(layers "F.Cu" "F.Mask" "F.Paste")
			(net "SMB_OCP_SFF_3V3AUX_SCL")
		)
		(pad "3" smd rect
			(at -2.175002 0.32512 90)
			(size 0.4318 1.1684)
			(layers "F.Cu" "F.Mask" "F.Paste")
			(net "SMB_OCP_SFF_3V3AUX_SDA")
		)
		(pad "4" smd rect
			(at -2.175002 1.050036 90)
			(size 0.6096 1.1684)
			(layers "F.Cu" "F.Mask" "F.Paste")
			(net "GND")
		)
		(pad "5" smd rect
			(at 2.175002 1.050036 90)
			(size 0.6096 1.1684)
			(layers "F.Cu" "F.Mask" "F.Paste")
			(net "HP_LVC3_OCP_V3_1_R_EN")
		)
		(pad "6" smd rect
			(at 2.175002 0.32512 90)
			(size 0.4318 1.1684)
			(layers "F.Cu" "F.Mask" "F.Paste")
			(net "SMB_OCP_SFF_3V3AUX_BUF_SDA")
		)
		(pad "7" smd rect
			(at 2.175002 -0.32512 90)
			(size 0.4318 1.1684)
			(layers "F.Cu" "F.Mask" "F.Paste")
			(net "SMB_OCP_SFF_3V3AUX_BUF_SCL")
		)
		(pad "8" smd rect
			(at 2.175002 -1.050036 90)
			(size 0.6096 1.1684)
			(layers "F.Cu" "F.Mask" "F.Paste")
			(net "P3V3_OCP_SFF")
		)
	)
	(footprint ""
		(layer "F.Cu")
		(at 79.114904 -395.221206 -90)
		(property "Reference" "R792"
			(at 0 0 270)
			(layer "F.SilkS")
			(hide yes)
			(effects
				(font
					(size 1.27 1.27)
				)
			)
		)
		(property "Value" ""
			(at 0 0 270)
			(layer "F.Fab")
			(effects
				(font
					(size 1.27 1.27)
				)
			)
		)
		(duplicate_pad_numbers_are_jumpers no)
		(fp_line
			(start -0.32512 0.175006)
			(end -0.32512 -0.175006)
			(stroke
				(width 0.1)
				(type default)
			)
			(layer "F.Fab")
		)
		(fp_line
			(start 0.32512 0.175006)
			(end -0.32512 0.175006)
			(stroke
				(width 0.1)
				(type default)
			)
			(layer "F.Fab")
		)
		(fp_line
			(start -0.32512 -0.175006)
			(end 0.32512 -0.175006)
			(stroke
				(width 0.1)
				(type default)
			)
			(layer "F.Fab")
		)
		(fp_line
			(start 0.32512 -0.175006)
			(end 0.32512 0.175006)
			(stroke
				(width 0.1)
				(type default)
			)
			(layer "F.Fab")
		)
		(pad "1" smd rect
			(at -0.2667 0 270)
			(size 0.3048 0.381)
			(layers "F.Cu" "F.Mask" "F.Paste")
			(net "JTAG_TEST_MODE_RT_CPU1_P1")
		)
		(pad "2" smd rect
			(at 0.2667 0 90)
			(size 0.3048 0.381)
			(layers "F.Cu" "F.Mask" "F.Paste")
			(net "GND")
		)
	)
	(footprint ""
		(layer "F.Cu")
		(at 459.158594 -46.264576 -90)
		(property "Reference" "PR834"
			(at 0 0 270)
			(layer "F.SilkS")
			(hide yes)
			(effects
				(font
					(size 1.27 1.27)
				)
			)
		)
		(property "Value" ""
			(at 0 0 270)
			(layer "F.Fab")
			(effects
				(font
					(size 1.27 1.27)
				)
			)
		)
		(duplicate_pad_numbers_are_jumpers no)
		(fp_line
			(start -0.7874 0.4064)
			(end -0.7874 -0.4064)
			(stroke
				(width 0.1524)
				(type default)
			)
			(layer "F.SilkS")
		)
		(fp_line
			(start 0.7874 0.4064)
			(end -0.7874 0.4064)
			(stroke
				(width 0.1524)
				(type default)
			)
			(layer "F.SilkS")
		)
		(fp_line
			(start -0.7874 -0.4064)
			(end 0.7874 -0.4064)
			(stroke
				(width 0.1524)
				(type default)
			)
			(layer "F.SilkS")
		)
		(fp_line
			(start 0.7874 -0.4064)
			(end 0.7874 0.4064)
			(stroke
				(width 0.1524)
				(type default)
			)
			(layer "F.SilkS")
		)
		(fp_line
			(start -0.67945 0.3048)
			(end -0.67945 -0.305054)
			(stroke
				(width 0.1)
				(type default)
			)
			(layer "F.Fab")
		)
		(fp_line
			(start -0.12065 0.3048)
			(end -0.67945 0.3048)
			(stroke
				(width 0.1)
				(type default)
			)
			(layer "F.Fab")
		)
		(fp_line
			(start 0.120396 0.3048)
			(end 0.120396 0.2794)
			(stroke
				(width 0.1)
				(type default)
			)
			(layer "F.Fab")
		)
		(fp_line
			(start 0.67945 0.3048)
			(end 0.120396 0.3048)
			(stroke
				(width 0.1)
				(type default)
			)
			(layer "F.Fab")
		)
		(fp_line
			(start -0.12065 0.2794)
			(end -0.12065 0.3048)
			(stroke
				(width 0.1)
				(type default)
			)
			(layer "F.Fab")
		)
		(fp_line
			(start 0.120396 0.2794)
			(end -0.12065 0.2794)
			(stroke
				(width 0.1)
				(type default)
			)
			(layer "F.Fab")
		)
		(fp_line
			(start -0.12065 -0.2794)
			(end 0.12065 -0.2794)
			(stroke
				(width 0.1)
				(type default)
			)
			(layer "F.Fab")
		)
		(fp_line
			(start 0.12065 -0.2794)
			(end 0.12065 -0.3048)
			(stroke
				(width 0.1)
				(type default)
			)
			(layer "F.Fab")
		)
		(fp_line
			(start 0.12065 -0.3048)
			(end 0.67945 -0.3048)
			(stroke
				(width 0.1)
				(type default)
			)
			(layer "F.Fab")
		)
		(fp_line
			(start 0.67945 -0.3048)
			(end 0.67945 0.3048)
			(stroke
				(width 0.1)
				(type default)
			)
			(layer "F.Fab")
		)
		(fp_line
			(start -0.67945 -0.305054)
			(end -0.12065 -0.305054)
			(stroke
				(width 0.1)
				(type default)
			)
			(layer "F.Fab")
		)
		(fp_line
			(start -0.12065 -0.305054)
			(end -0.12065 -0.2794)
			(stroke
				(width 0.1)
				(type default)
			)
			(layer "F.Fab")
		)
		(pad "1" smd circle
			(at -0.40005 0 270)
			(size 0 0)
			(layers "F.Cu" "F.Mask" "F.Paste")
			(net "P3V3_AUX_ILIM")
		)
		(pad "2" smd circle
			(at 0.40005 0 270)
			(size 0 0)
			(layers "F.Cu" "F.Mask" "F.Paste")
			(net "GND")
		)
	)
	(footprint ""
		(layer "F.Cu")
		(at 233.2228 -281.7368)
		(property "Reference" "PC6803"
			(at 0 0 0)
			(layer "F.SilkS")
			(hide yes)
			(effects
				(font
					(size 1.27 1.27)
				)
			)
		)
		(property "Value" ""
			(at 0 0 0)
			(layer "F.Fab")
			(effects
				(font
					(size 1.27 1.27)
				)
			)
		)
		(duplicate_pad_numbers_are_jumpers no)
		(fp_line
			(start -1.524 -0.762)
			(end 1.524 -0.762)
			(stroke
				(width 0.1524)
				(type default)
			)
			(layer "F.SilkS")
		)
		(fp_line
			(start -1.524 0.762)
			(end -1.524 -0.762)
			(stroke
				(width 0.1524)
				(type default)
			)
			(layer "F.SilkS")
		)
		(fp_line
			(start 1.524 -0.762)
			(end 1.524 0.762)
			(stroke
				(width 0.1524)
				(type default)
			)
			(layer "F.SilkS")
		)
		(fp_line
			(start 1.524 0.762)
			(end -1.524 0.762)
			(stroke
				(width 0.1524)
				(type default)
			)
			(layer "F.SilkS")
		)
		(fp_line
			(start -1.1049 -0.724916)
			(end -1.1049 0.724916)
			(stroke
				(width 0.1)
				(type default)
			)
			(layer "F.Fab")
		)
		(fp_line
			(start -1.1049 0.724916)
			(end 1.1049 0.724916)
			(stroke
				(width 0.1)
				(type default)
			)
			(layer "F.Fab")
		)
		(fp_line
			(start 1.1049 -0.724916)
			(end -1.1049 -0.724916)
			(stroke
				(width 0.1)
				(type default)
			)
			(layer "F.Fab")
		)
		(fp_line
			(start 1.1049 0.724916)
			(end 1.1049 -0.724916)
			(stroke
				(width 0.1)
				(type default)
			)
			(layer "F.Fab")
		)
		(pad "1" smd rect
			(at -0.889 0 180)
			(size 1.016 1.27)
			(layers "F.Cu" "F.Mask" "F.Paste")
			(net "SW_P12V_AUX_P1V8_RETIMER_CPU1_FLT")
		)
		(pad "2" smd rect
			(at 0.889 0 180)
			(size 1.016 1.27)
			(layers "F.Cu" "F.Mask" "F.Paste")
			(net "GND")
		)
	)
	(footprint ""
		(layer "F.Cu")
		(at 421.104568 -369.28044 90)
		(property "Reference" "R6857"
			(at 0 0 90)
			(layer "F.SilkS")
			(hide yes)
			(effects
				(font
					(size 1.27 1.27)
				)
			)
		)
		(property "Value" ""
			(at 0 0 90)
			(layer "F.Fab")
			(effects
				(font
					(size 1.27 1.27)
				)
			)
		)
		(duplicate_pad_numbers_are_jumpers no)
		(fp_line
			(start 0.7874 -0.4064)
			(end 0.7874 0.4064)
			(stroke
				(width 0.1524)
				(type default)
			)
			(layer "F.SilkS")
		)
		(fp_line
			(start -0.7874 -0.4064)
			(end 0.7874 -0.4064)
			(stroke
				(width 0.1524)
				(type default)
			)
			(layer "F.SilkS")
		)
		(fp_line
			(start 0.7874 0.4064)
			(end -0.7874 0.4064)
			(stroke
				(width 0.1524)
				(type default)
			)
			(layer "F.SilkS")
		)
		(fp_line
			(start -0.7874 0.4064)
			(end -0.7874 -0.4064)
			(stroke
				(width 0.1524)
				(type default)
			)
			(layer "F.SilkS")
		)
		(fp_line
			(start -0.12065 -0.305054)
			(end -0.12065 -0.2794)
			(stroke
				(width 0.1)
				(type default)
			)
			(layer "F.Fab")
		)
		(fp_line
			(start -0.67945 -0.305054)
			(end -0.12065 -0.305054)
			(stroke
				(width 0.1)
				(type default)
			)
			(layer "F.Fab")
		)
		(fp_line
			(start 0.67945 -0.3048)
			(end 0.67945 0.3048)
			(stroke
				(width 0.1)
				(type default)
			)
			(layer "F.Fab")
		)
		(fp_line
			(start 0.12065 -0.3048)
			(end 0.67945 -0.3048)
			(stroke
				(width 0.1)
				(type default)
			)
			(layer "F.Fab")
		)
		(fp_line
			(start 0.12065 -0.2794)
			(end 0.12065 -0.3048)
			(stroke
				(width 0.1)
				(type default)
			)
			(layer "F.Fab")
		)
		(fp_line
			(start -0.12065 -0.2794)
			(end 0.12065 -0.2794)
			(stroke
				(width 0.1)
				(type default)
			)
			(layer "F.Fab")
		)
		(fp_line
			(start 0.120396 0.2794)
			(end -0.12065 0.2794)
			(stroke
				(width 0.1)
				(type default)
			)
			(layer "F.Fab")
		)
		(fp_line
			(start -0.12065 0.2794)
			(end -0.12065 0.3048)
			(stroke
				(width 0.1)
				(type default)
			)
			(layer "F.Fab")
		)
		(fp_line
			(start 0.67945 0.3048)
			(end 0.120396 0.3048)
			(stroke
				(width 0.1)
				(type default)
			)
			(layer "F.Fab")
		)
		(fp_line
			(start 0.120396 0.3048)
			(end 0.120396 0.2794)
			(stroke
				(width 0.1)
				(type default)
			)
			(layer "F.Fab")
		)
		(fp_line
			(start -0.12065 0.3048)
			(end -0.67945 0.3048)
			(stroke
				(width 0.1)
				(type default)
			)
			(layer "F.Fab")
		)
		(fp_line
			(start -0.67945 0.3048)
			(end -0.67945 -0.305054)
			(stroke
				(width 0.1)
				(type default)
			)
			(layer "F.Fab")
		)
		(pad "1" smd circle
			(at -0.40005 0 90)
			(size 0 0)
			(layers "F.Cu" "F.Mask" "F.Paste")
			(net "SMB_SCM_2_R6_SDA")
		)
		(pad "2" smd circle
			(at 0.40005 0 90)
			(size 0 0)
			(layers "F.Cu" "F.Mask" "F.Paste")
			(net "P0V9_RETIMER_CPU0_PMSDA")
		)
	)
	(footprint ""
		(layer "F.Cu")
		(at 302.241458 -110.795308)
		(property "Reference" "R52"
			(at 0 0 0)
			(layer "F.SilkS")
			(hide yes)
			(effects
				(font
					(size 1.27 1.27)
				)
			)
		)
		(property "Value" ""
			(at 0 0 0)
			(layer "F.Fab")
			(effects
				(font
					(size 1.27 1.27)
				)
			)
		)
		(duplicate_pad_numbers_are_jumpers no)
		(fp_line
			(start -0.7874 -0.4064)
			(end 0.7874 -0.4064)
			(stroke
				(width 0.1524)
				(type default)
			)
			(layer "F.SilkS")
		)
		(fp_line
			(start -0.7874 0.4064)
			(end -0.7874 -0.4064)
			(stroke
				(width 0.1524)
				(type default)
			)
			(layer "F.SilkS")
		)
		(fp_line
			(start 0.7874 -0.4064)
			(end 0.7874 0.4064)
			(stroke
				(width 0.1524)
				(type default)
			)
			(layer "F.SilkS")
		)
		(fp_line
			(start 0.7874 0.4064)
			(end -0.7874 0.4064)
			(stroke
				(width 0.1524)
				(type default)
			)
			(layer "F.SilkS")
		)
		(fp_line
			(start -0.67945 -0.305054)
			(end -0.12065 -0.305054)
			(stroke
				(width 0.1)
				(type default)
			)
			(layer "F.Fab")
		)
		(fp_line
			(start -0.67945 0.3048)
			(end -0.67945 -0.305054)
			(stroke
				(width 0.1)
				(type default)
			)
			(layer "F.Fab")
		)
		(fp_line
			(start -0.12065 -0.305054)
			(end -0.12065 -0.2794)
			(stroke
				(width 0.1)
				(type default)
			)
			(layer "F.Fab")
		)
		(fp_line
			(start -0.12065 -0.2794)
			(end 0.12065 -0.2794)
			(stroke
				(width 0.1)
				(type default)
			)
			(layer "F.Fab")
		)
		(fp_line
			(start -0.12065 0.2794)
			(end -0.12065 0.3048)
			(stroke
				(width 0.1)
				(type default)
			)
			(layer "F.Fab")
		)
		(fp_line
			(start -0.12065 0.3048)
			(end -0.67945 0.3048)
			(stroke
				(width 0.1)
				(type default)
			)
			(layer "F.Fab")
		)
		(fp_line
			(start 0.120396 0.2794)
			(end -0.12065 0.2794)
			(stroke
				(width 0.1)
				(type default)
			)
			(layer "F.Fab")
		)
		(fp_line
			(start 0.120396 0.3048)
			(end 0.120396 0.2794)
			(stroke
				(width 0.1)
				(type default)
			)
			(layer "F.Fab")
		)
		(fp_line
			(start 0.12065 -0.3048)
			(end 0.67945 -0.3048)
			(stroke
				(width 0.1)
				(type default)
			)
			(layer "F.Fab")
		)
		(fp_line
			(start 0.12065 -0.2794)
			(end 0.12065 -0.3048)
			(stroke
				(width 0.1)
				(type default)
			)
			(layer "F.Fab")
		)
		(fp_line
			(start 0.67945 -0.3048)
			(end 0.67945 0.3048)
			(stroke
				(width 0.1)
				(type default)
			)
			(layer "F.Fab")
		)
		(fp_line
			(start 0.67945 0.3048)
			(end 0.120396 0.3048)
			(stroke
				(width 0.1)
				(type default)
			)
			(layer "F.Fab")
		)
		(pad "1" smd circle
			(at -0.40005 0)
			(size 0 0)
			(layers "F.Cu" "F.Mask" "F.Paste")
			(net "P3V3_AUX")
		)
		(pad "2" smd circle
			(at 0.40005 0)
			(size 0 0)
			(layers "F.Cu" "F.Mask" "F.Paste")
			(net "CPU_FRU_ADDR2")
		)
	)
	(footprint ""
		(layer "F.Cu")
		(at 105.64876 -61.087254 180)
		(property "Reference" "R1741"
			(at 0 0 180)
			(layer "F.SilkS")
			(hide yes)
			(effects
				(font
					(size 1.27 1.27)
				)
			)
		)
		(property "Value" ""
			(at 0 0 180)
			(layer "F.Fab")
			(effects
				(font
					(size 1.27 1.27)
				)
			)
		)
		(duplicate_pad_numbers_are_jumpers no)
		(fp_line
			(start 0.7874 0.4064)
			(end -0.7874 0.4064)
			(stroke
				(width 0.1524)
				(type default)
			)
			(layer "F.SilkS")
		)
		(fp_line
			(start 0.7874 -0.4064)
			(end 0.7874 0.4064)
			(stroke
				(width 0.1524)
				(type default)
			)
			(layer "F.SilkS")
		)
		(fp_line
			(start -0.7874 0.4064)
			(end -0.7874 -0.4064)
			(stroke
				(width 0.1524)
				(type default)
			)
			(layer "F.SilkS")
		)
		(fp_line
			(start -0.7874 -0.4064)
			(end 0.7874 -0.4064)
			(stroke
				(width 0.1524)
				(type default)
			)
			(layer "F.SilkS")
		)
		(fp_line
			(start 0.67945 0.3048)
			(end 0.120396 0.3048)
			(stroke
				(width 0.1)
				(type default)
			)
			(layer "F.Fab")
		)
		(fp_line
			(start 0.67945 -0.3048)
			(end 0.67945 0.3048)
			(stroke
				(width 0.1)
				(type default)
			)
			(layer "F.Fab")
		)
		(fp_line
			(start 0.12065 -0.2794)
			(end 0.12065 -0.3048)
			(stroke
				(width 0.1)
				(type default)
			)
			(layer "F.Fab")
		)
		(fp_line
			(start 0.12065 -0.3048)
			(end 0.67945 -0.3048)
			(stroke
				(width 0.1)
				(type default)
			)
			(layer "F.Fab")
		)
		(fp_line
			(start 0.120396 0.3048)
			(end 0.120396 0.2794)
			(stroke
				(width 0.1)
				(type default)
			)
			(layer "F.Fab")
		)
		(fp_line
			(start 0.120396 0.2794)
			(end -0.12065 0.2794)
			(stroke
				(width 0.1)
				(type default)
			)
			(layer "F.Fab")
		)
		(fp_line
			(start -0.12065 0.3048)
			(end -0.67945 0.3048)
			(stroke
				(width 0.1)
				(type default)
			)
			(layer "F.Fab")
		)
		(fp_line
			(start -0.12065 0.2794)
			(end -0.12065 0.3048)
			(stroke
				(width 0.1)
				(type default)
			)
			(layer "F.Fab")
		)
		(fp_line
			(start -0.12065 -0.2794)
			(end 0.12065 -0.2794)
			(stroke
				(width 0.1)
				(type default)
			)
			(layer "F.Fab")
		)
		(fp_line
			(start -0.12065 -0.305054)
			(end -0.12065 -0.2794)
			(stroke
				(width 0.1)
				(type default)
			)
			(layer "F.Fab")
		)
		(fp_line
			(start -0.67945 0.3048)
			(end -0.67945 -0.305054)
			(stroke
				(width 0.1)
				(type default)
			)
			(layer "F.Fab")
		)
		(fp_line
			(start -0.67945 -0.305054)
			(end -0.12065 -0.305054)
			(stroke
				(width 0.1)
				(type default)
			)
			(layer "F.Fab")
		)
		(pad "1" smd circle
			(at -0.40005 0 180)
			(size 0 0)
			(layers "F.Cu" "F.Mask" "F.Paste")
			(net "JTAG_SCM_PLD_R_TMS")
		)
		(pad "2" smd circle
			(at 0.40005 0 180)
			(size 0 0)
			(layers "F.Cu" "F.Mask" "F.Paste")
			(net "JTAG_SCM_PLD_TMS")
		)
	)
	(footprint ""
		(layer "F.Cu")
		(at 328.092308 -103.66375)
		(property "Reference" "C1107"
			(at 0 0 0)
			(layer "F.SilkS")
			(hide yes)
			(effects
				(font
					(size 1.27 1.27)
				)
			)
		)
		(property "Value" ""
			(at 0 0 0)
			(layer "F.Fab")
			(effects
				(font
					(size 1.27 1.27)
				)
			)
		)
		(duplicate_pad_numbers_are_jumpers no)
		(fp_line
			(start -0.7874 -0.4064)
			(end 0.7874 -0.4064)
			(stroke
				(width 0.1524)
				(type default)
			)
			(layer "F.SilkS")
		)
		(fp_line
			(start -0.7874 0.4064)
			(end -0.7874 -0.4064)
			(stroke
				(width 0.1524)
				(type default)
			)
			(layer "F.SilkS")
		)
		(fp_line
			(start 0.7874 -0.4064)
			(end 0.7874 0.4064)
			(stroke
				(width 0.1524)
				(type default)
			)
			(layer "F.SilkS")
		)
		(fp_line
			(start 0.7874 0.4064)
			(end -0.7874 0.4064)
			(stroke
				(width 0.1524)
				(type default)
			)
			(layer "F.SilkS")
		)
		(fp_line
			(start -0.67945 -0.305054)
			(end -0.12065 -0.305054)
			(stroke
				(width 0.1)
				(type default)
			)
			(layer "F.Fab")
		)
		(fp_line
			(start -0.67945 0.3048)
			(end -0.67945 -0.305054)
			(stroke
				(width 0.1)
				(type default)
			)
			(layer "F.Fab")
		)
		(fp_line
			(start -0.12065 -0.305054)
			(end -0.12065 -0.2794)
			(stroke
				(width 0.1)
				(type default)
			)
			(layer "F.Fab")
		)
		(fp_line
			(start -0.12065 -0.2794)
			(end 0.12065 -0.2794)
			(stroke
				(width 0.1)
				(type default)
			)
			(layer "F.Fab")
		)
		(fp_line
			(start -0.12065 0.2794)
			(end -0.12065 0.3048)
			(stroke
				(width 0.1)
				(type default)
			)
			(layer "F.Fab")
		)
		(fp_line
			(start -0.12065 0.3048)
			(end -0.67945 0.3048)
			(stroke
				(width 0.1)
				(type default)
			)
			(layer "F.Fab")
		)
		(fp_line
			(start 0.120396 0.2794)
			(end -0.12065 0.2794)
			(stroke
				(width 0.1)
				(type default)
			)
			(layer "F.Fab")
		)
		(fp_line
			(start 0.120396 0.3048)
			(end 0.120396 0.2794)
			(stroke
				(width 0.1)
				(type default)
			)
			(layer "F.Fab")
		)
		(fp_line
			(start 0.12065 -0.3048)
			(end 0.67945 -0.3048)
			(stroke
				(width 0.1)
				(type default)
			)
			(layer "F.Fab")
		)
		(fp_line
			(start 0.12065 -0.2794)
			(end 0.12065 -0.3048)
			(stroke
				(width 0.1)
				(type default)
			)
			(layer "F.Fab")
		)
		(fp_line
			(start 0.67945 -0.3048)
			(end 0.67945 0.3048)
			(stroke
				(width 0.1)
				(type default)
			)
			(layer "F.Fab")
		)
		(fp_line
			(start 0.67945 0.3048)
			(end 0.120396 0.3048)
			(stroke
				(width 0.1)
				(type default)
			)
			(layer "F.Fab")
		)
		(pad "1" smd circle
			(at -0.40005 0)
			(size 0 0)
			(layers "F.Cu" "F.Mask" "F.Paste")
			(net "P12V_E1S_0")
		)
		(pad "2" smd circle
			(at 0.40005 0)
			(size 0 0)
			(layers "F.Cu" "F.Mask" "F.Paste")
			(net "GND")
		)
	)
	(footprint ""
		(layer "F.Cu")
		(at 367.787936 -402.548852 -90)
		(property "Reference" "R1104"
			(at 0 0 270)
			(layer "F.SilkS")
			(hide yes)
			(effects
				(font
					(size 1.27 1.27)
				)
			)
		)
		(property "Value" ""
			(at 0 0 270)
			(layer "F.Fab")
			(effects
				(font
					(size 1.27 1.27)
				)
			)
		)
		(duplicate_pad_numbers_are_jumpers no)
		(fp_line
			(start -0.32512 0.175006)
			(end -0.32512 -0.175006)
			(stroke
				(width 0.1)
				(type default)
			)
			(layer "F.Fab")
		)
		(fp_line
			(start 0.32512 0.175006)
			(end -0.32512 0.175006)
			(stroke
				(width 0.1)
				(type default)
			)
			(layer "F.Fab")
		)
		(fp_line
			(start -0.32512 -0.175006)
			(end 0.32512 -0.175006)
			(stroke
				(width 0.1)
				(type default)
			)
			(layer "F.Fab")
		)
		(fp_line
			(start 0.32512 -0.175006)
			(end 0.32512 0.175006)
			(stroke
				(width 0.1)
				(type default)
			)
			(layer "F.Fab")
		)
		(pad "1" smd rect
			(at -0.2667 0 270)
			(size 0.3048 0.381)
			(layers "F.Cu" "F.Mask" "F.Paste")
			(net "RST_RT_CPU0_P3_RESET_R_N")
		)
		(pad "2" smd rect
			(at 0.2667 0 90)
			(size 0.3048 0.381)
			(layers "F.Cu" "F.Mask" "F.Paste")
			(net "GND")
		)
	)
	(footprint ""
		(layer "F.Cu")
		(at 448.672458 -92.493592 180)
		(property "Reference" "R3616"
			(at 0 0 180)
			(layer "F.SilkS")
			(hide yes)
			(effects
				(font
					(size 1.27 1.27)
				)
			)
		)
		(property "Value" ""
			(at 0 0 180)
			(layer "F.Fab")
			(effects
				(font
					(size 1.27 1.27)
				)
			)
		)
		(duplicate_pad_numbers_are_jumpers no)
		(fp_line
			(start 0.7874 0.4064)
			(end -0.7874 0.4064)
			(stroke
				(width 0.1524)
				(type default)
			)
			(layer "F.SilkS")
		)
		(fp_line
			(start 0.7874 -0.4064)
			(end 0.7874 0.4064)
			(stroke
				(width 0.1524)
				(type default)
			)
			(layer "F.SilkS")
		)
		(fp_line
			(start -0.7874 0.4064)
			(end -0.7874 -0.4064)
			(stroke
				(width 0.1524)
				(type default)
			)
			(layer "F.SilkS")
		)
		(fp_line
			(start -0.7874 -0.4064)
			(end 0.7874 -0.4064)
			(stroke
				(width 0.1524)
				(type default)
			)
			(layer "F.SilkS")
		)
		(fp_line
			(start 0.67945 0.3048)
			(end 0.120396 0.3048)
			(stroke
				(width 0.1)
				(type default)
			)
			(layer "F.Fab")
		)
		(fp_line
			(start 0.67945 -0.3048)
			(end 0.67945 0.3048)
			(stroke
				(width 0.1)
				(type default)
			)
			(layer "F.Fab")
		)
		(fp_line
			(start 0.12065 -0.2794)
			(end 0.12065 -0.3048)
			(stroke
				(width 0.1)
				(type default)
			)
			(layer "F.Fab")
		)
		(fp_line
			(start 0.12065 -0.3048)
			(end 0.67945 -0.3048)
			(stroke
				(width 0.1)
				(type default)
			)
			(layer "F.Fab")
		)
		(fp_line
			(start 0.120396 0.3048)
			(end 0.120396 0.2794)
			(stroke
				(width 0.1)
				(type default)
			)
			(layer "F.Fab")
		)
		(fp_line
			(start 0.120396 0.2794)
			(end -0.12065 0.2794)
			(stroke
				(width 0.1)
				(type default)
			)
			(layer "F.Fab")
		)
		(fp_line
			(start -0.12065 0.3048)
			(end -0.67945 0.3048)
			(stroke
				(width 0.1)
				(type default)
			)
			(layer "F.Fab")
		)
		(fp_line
			(start -0.12065 0.2794)
			(end -0.12065 0.3048)
			(stroke
				(width 0.1)
				(type default)
			)
			(layer "F.Fab")
		)
		(fp_line
			(start -0.12065 -0.2794)
			(end 0.12065 -0.2794)
			(stroke
				(width 0.1)
				(type default)
			)
			(layer "F.Fab")
		)
		(fp_line
			(start -0.12065 -0.305054)
			(end -0.12065 -0.2794)
			(stroke
				(width 0.1)
				(type default)
			)
			(layer "F.Fab")
		)
		(fp_line
			(start -0.67945 0.3048)
			(end -0.67945 -0.305054)
			(stroke
				(width 0.1)
				(type default)
			)
			(layer "F.Fab")
		)
		(fp_line
			(start -0.67945 -0.305054)
			(end -0.12065 -0.305054)
			(stroke
				(width 0.1)
				(type default)
			)
			(layer "F.Fab")
		)
		(pad "1" smd circle
			(at -0.40005 0 180)
			(size 0 0)
			(layers "F.Cu" "F.Mask" "F.Paste")
			(net "GND")
		)
		(pad "2" smd circle
			(at 0.40005 0 180)
			(size 0 0)
			(layers "F.Cu" "F.Mask" "F.Paste")
			(net "INA230_1_A1")
		)
	)
	(footprint ""
		(layer "F.Cu")
		(at 52.877466 -25.309068 90)
		(property "Reference" "R3234"
			(at 0 0 90)
			(layer "F.SilkS")
			(hide yes)
			(effects
				(font
					(size 1.27 1.27)
				)
			)
		)
		(property "Value" ""
			(at 0 0 90)
			(layer "F.Fab")
			(effects
				(font
					(size 1.27 1.27)
				)
			)
		)
		(duplicate_pad_numbers_are_jumpers no)
		(fp_line
			(start 0.7874 -0.4064)
			(end 0.7874 0.4064)
			(stroke
				(width 0.1524)
				(type default)
			)
			(layer "F.SilkS")
		)
		(fp_line
			(start -0.7874 -0.4064)
			(end 0.7874 -0.4064)
			(stroke
				(width 0.1524)
				(type default)
			)
			(layer "F.SilkS")
		)
		(fp_line
			(start 0.7874 0.4064)
			(end -0.7874 0.4064)
			(stroke
				(width 0.1524)
				(type default)
			)
			(layer "F.SilkS")
		)
		(fp_line
			(start -0.7874 0.4064)
			(end -0.7874 -0.4064)
			(stroke
				(width 0.1524)
				(type default)
			)
			(layer "F.SilkS")
		)
		(fp_line
			(start -0.12065 -0.305054)
			(end -0.12065 -0.2794)
			(stroke
				(width 0.1)
				(type default)
			)
			(layer "F.Fab")
		)
		(fp_line
			(start -0.67945 -0.305054)
			(end -0.12065 -0.305054)
			(stroke
				(width 0.1)
				(type default)
			)
			(layer "F.Fab")
		)
		(fp_line
			(start 0.67945 -0.3048)
			(end 0.67945 0.3048)
			(stroke
				(width 0.1)
				(type default)
			)
			(layer "F.Fab")
		)
		(fp_line
			(start 0.12065 -0.3048)
			(end 0.67945 -0.3048)
			(stroke
				(width 0.1)
				(type default)
			)
			(layer "F.Fab")
		)
		(fp_line
			(start 0.12065 -0.2794)
			(end 0.12065 -0.3048)
			(stroke
				(width 0.1)
				(type default)
			)
			(layer "F.Fab")
		)
		(fp_line
			(start -0.12065 -0.2794)
			(end 0.12065 -0.2794)
			(stroke
				(width 0.1)
				(type default)
			)
			(layer "F.Fab")
		)
		(fp_line
			(start 0.120396 0.2794)
			(end -0.12065 0.2794)
			(stroke
				(width 0.1)
				(type default)
			)
			(layer "F.Fab")
		)
		(fp_line
			(start -0.12065 0.2794)
			(end -0.12065 0.3048)
			(stroke
				(width 0.1)
				(type default)
			)
			(layer "F.Fab")
		)
		(fp_line
			(start 0.67945 0.3048)
			(end 0.120396 0.3048)
			(stroke
				(width 0.1)
				(type default)
			)
			(layer "F.Fab")
		)
		(fp_line
			(start 0.120396 0.3048)
			(end 0.120396 0.2794)
			(stroke
				(width 0.1)
				(type default)
			)
			(layer "F.Fab")
		)
		(fp_line
			(start -0.12065 0.3048)
			(end -0.67945 0.3048)
			(stroke
				(width 0.1)
				(type default)
			)
			(layer "F.Fab")
		)
		(fp_line
			(start -0.67945 0.3048)
			(end -0.67945 -0.305054)
			(stroke
				(width 0.1)
				(type default)
			)
			(layer "F.Fab")
		)
		(pad "1" smd circle
			(at -0.40005 0 90)
			(size 0 0)
			(layers "F.Cu" "F.Mask" "F.Paste")
			(net "OCP_V3_2_AUX_PWR_EN")
		)
		(pad "2" smd circle
			(at 0.40005 0 90)
			(size 0 0)
			(layers "F.Cu" "F.Mask" "F.Paste")
			(net "OCP_V3_2_AUX_PWR_EN_R3")
		)
	)
	(footprint ""
		(layer "F.Cu")
		(at 271.800574 -93.927168 180)
		(property "Reference" "R1624"
			(at 0 0 180)
			(layer "F.SilkS")
			(hide yes)
			(effects
				(font
					(size 1.27 1.27)
				)
			)
		)
		(property "Value" ""
			(at 0 0 180)
			(layer "F.Fab")
			(effects
				(font
					(size 1.27 1.27)
				)
			)
		)
		(duplicate_pad_numbers_are_jumpers no)
		(fp_line
			(start 0.7874 0.4064)
			(end -0.7874 0.4064)
			(stroke
				(width 0.1524)
				(type default)
			)
			(layer "F.SilkS")
		)
		(fp_line
			(start 0.7874 -0.4064)
			(end 0.7874 0.4064)
			(stroke
				(width 0.1524)
				(type default)
			)
			(layer "F.SilkS")
		)
		(fp_line
			(start -0.7874 0.4064)
			(end -0.7874 -0.4064)
			(stroke
				(width 0.1524)
				(type default)
			)
			(layer "F.SilkS")
		)
		(fp_line
			(start -0.7874 -0.4064)
			(end 0.7874 -0.4064)
			(stroke
				(width 0.1524)
				(type default)
			)
			(layer "F.SilkS")
		)
		(fp_line
			(start 0.67945 0.3048)
			(end 0.120396 0.3048)
			(stroke
				(width 0.1)
				(type default)
			)
			(layer "F.Fab")
		)
		(fp_line
			(start 0.67945 -0.3048)
			(end 0.67945 0.3048)
			(stroke
				(width 0.1)
				(type default)
			)
			(layer "F.Fab")
		)
		(fp_line
			(start 0.12065 -0.2794)
			(end 0.12065 -0.3048)
			(stroke
				(width 0.1)
				(type default)
			)
			(layer "F.Fab")
		)
		(fp_line
			(start 0.12065 -0.3048)
			(end 0.67945 -0.3048)
			(stroke
				(width 0.1)
				(type default)
			)
			(layer "F.Fab")
		)
		(fp_line
			(start 0.120396 0.3048)
			(end 0.120396 0.2794)
			(stroke
				(width 0.1)
				(type default)
			)
			(layer "F.Fab")
		)
		(fp_line
			(start 0.120396 0.2794)
			(end -0.12065 0.2794)
			(stroke
				(width 0.1)
				(type default)
			)
			(layer "F.Fab")
		)
		(fp_line
			(start -0.12065 0.3048)
			(end -0.67945 0.3048)
			(stroke
				(width 0.1)
				(type default)
			)
			(layer "F.Fab")
		)
		(fp_line
			(start -0.12065 0.2794)
			(end -0.12065 0.3048)
			(stroke
				(width 0.1)
				(type default)
			)
			(layer "F.Fab")
		)
		(fp_line
			(start -0.12065 -0.2794)
			(end 0.12065 -0.2794)
			(stroke
				(width 0.1)
				(type default)
			)
			(layer "F.Fab")
		)
		(fp_line
			(start -0.12065 -0.305054)
			(end -0.12065 -0.2794)
			(stroke
				(width 0.1)
				(type default)
			)
			(layer "F.Fab")
		)
		(fp_line
			(start -0.67945 0.3048)
			(end -0.67945 -0.305054)
			(stroke
				(width 0.1)
				(type default)
			)
			(layer "F.Fab")
		)
		(fp_line
			(start -0.67945 -0.305054)
			(end -0.12065 -0.305054)
			(stroke
				(width 0.1)
				(type default)
			)
			(layer "F.Fab")
		)
		(pad "1" smd circle
			(at -0.40005 0 180)
			(size 0 0)
			(layers "F.Cu" "F.Mask" "F.Paste")
			(net "PVDD18_S5_P0")
		)
		(pad "2" smd circle
			(at 0.40005 0 180)
			(size 0 0)
			(layers "F.Cu" "F.Mask" "F.Paste")
			(net "HDT_HDR_TCK")
		)
	)
	(footprint ""
		(layer "F.Cu")
		(at 110.140496 -150.941786 90)
		(property "Reference" "PC336"
			(at 4.185666 -0.65151 0)
			(unlocked yes)
			(layer "F.SilkS")
			(effects
				(font
					(size 0.7874 0.5842)
					(thickness 0.1524)
				)
				(justify left)
			)
		)
		(property "Value" ""
			(at 0 0 90)
			(layer "F.Fab")
			(effects
				(font
					(size 1.27 1.27)
				)
			)
		)
		(duplicate_pad_numbers_are_jumpers no)
		(fp_line
			(start -3.400044 1.249934)
			(end 3.400044 1.249934)
			(stroke
				(width 0.1524)
				(type default)
			)
			(layer "F.SilkS")
		)
		(fp_circle
			(center 0 1.249934)
			(end 0 4.649978)
			(stroke
				(width 0.1524)
				(type default)
			)
			(fill no)
			(layer "F.SilkS")
		)
		(fp_poly
			(pts
				(arc
					(start 3.400044 1.249934)
					(mid 0 4.649978)
					(end -3.400044 1.249934)
				)
			)
			(stroke
				(width 0)
				(type default)
			)
			(fill yes)
			(layer "F.SilkS")
		)
		(fp_circle
			(center 0 1.249934)
			(end 0 4.649978)
			(stroke
				(width 0.1)
				(type default)
			)
			(fill no)
			(layer "F.Fab")
		)
		(pad "1" thru_hole rect
			(at 0 0 90)
			(size 1.524 1.524)
			(drill 1.016)
			(layers "*.Cu" "*.Mask")
			(remove_unused_layers no)
			(net "SW_P12V_AUX_PVDDCR_SOC_P1_FLT")
			(clearance 0)
			(padstack
				(mode front_inner_back)
				(layer "Inner"
					(shape circle)
					(size 1.524 1.524)
					(clearance 0)
				)
				(layer "B.Cu"
					(shape rect)
					(size 1.524 1.524)
					(clearance 0)
				)
			)
		)
		(pad "2" thru_hole circle
			(at 0 2.500122 90)
			(size 1.524 1.524)
			(drill 1.016)
			(layers "*.Cu" "*.Mask")
			(remove_unused_layers no)
			(net "GND")
			(clearance 0)
		)
	)
	(footprint ""
		(layer "F.Cu")
		(at 425.163488 -109.12983 90)
		(property "Reference" "PC2091"
			(at 0 0 90)
			(layer "F.SilkS")
			(hide yes)
			(effects
				(font
					(size 1.27 1.27)
				)
			)
		)
		(property "Value" ""
			(at 0 0 90)
			(layer "F.Fab")
			(effects
				(font
					(size 1.27 1.27)
				)
			)
		)
		(duplicate_pad_numbers_are_jumpers no)
		(fp_line
			(start 0.7874 -0.4064)
			(end 0.7874 0.4064)
			(stroke
				(width 0.1524)
				(type default)
			)
			(layer "F.SilkS")
		)
		(fp_line
			(start -0.7874 -0.4064)
			(end 0.7874 -0.4064)
			(stroke
				(width 0.1524)
				(type default)
			)
			(layer "F.SilkS")
		)
		(fp_line
			(start 0.7874 0.4064)
			(end -0.7874 0.4064)
			(stroke
				(width 0.1524)
				(type default)
			)
			(layer "F.SilkS")
		)
		(fp_line
			(start -0.7874 0.4064)
			(end -0.7874 -0.4064)
			(stroke
				(width 0.1524)
				(type default)
			)
			(layer "F.SilkS")
		)
		(fp_line
			(start -0.12065 -0.305054)
			(end -0.12065 -0.2794)
			(stroke
				(width 0.1)
				(type default)
			)
			(layer "F.Fab")
		)
		(fp_line
			(start -0.67945 -0.305054)
			(end -0.12065 -0.305054)
			(stroke
				(width 0.1)
				(type default)
			)
			(layer "F.Fab")
		)
		(fp_line
			(start 0.67945 -0.3048)
			(end 0.67945 0.3048)
			(stroke
				(width 0.1)
				(type default)
			)
			(layer "F.Fab")
		)
		(fp_line
			(start 0.12065 -0.3048)
			(end 0.67945 -0.3048)
			(stroke
				(width 0.1)
				(type default)
			)
			(layer "F.Fab")
		)
		(fp_line
			(start 0.12065 -0.2794)
			(end 0.12065 -0.3048)
			(stroke
				(width 0.1)
				(type default)
			)
			(layer "F.Fab")
		)
		(fp_line
			(start -0.12065 -0.2794)
			(end 0.12065 -0.2794)
			(stroke
				(width 0.1)
				(type default)
			)
			(layer "F.Fab")
		)
		(fp_line
			(start 0.120396 0.2794)
			(end -0.12065 0.2794)
			(stroke
				(width 0.1)
				(type default)
			)
			(layer "F.Fab")
		)
		(fp_line
			(start -0.12065 0.2794)
			(end -0.12065 0.3048)
			(stroke
				(width 0.1)
				(type default)
			)
			(layer "F.Fab")
		)
		(fp_line
			(start 0.67945 0.3048)
			(end 0.120396 0.3048)
			(stroke
				(width 0.1)
				(type default)
			)
			(layer "F.Fab")
		)
		(fp_line
			(start 0.120396 0.3048)
			(end 0.120396 0.2794)
			(stroke
				(width 0.1)
				(type default)
			)
			(layer "F.Fab")
		)
		(fp_line
			(start -0.12065 0.3048)
			(end -0.67945 0.3048)
			(stroke
				(width 0.1)
				(type default)
			)
			(layer "F.Fab")
		)
		(fp_line
			(start -0.67945 0.3048)
			(end -0.67945 -0.305054)
			(stroke
				(width 0.1)
				(type default)
			)
			(layer "F.Fab")
		)
		(pad "1" smd circle
			(at -0.40005 0 90)
			(size 0 0)
			(layers "F.Cu" "F.Mask" "F.Paste")
			(net "P3V3_OCP_SFF_R")
		)
		(pad "2" smd circle
			(at 0.40005 0 90)
			(size 0 0)
			(layers "F.Cu" "F.Mask" "F.Paste")
			(net "GND")
		)
	)
	(footprint ""
		(layer "F.Cu")
		(at 79.356458 -20.694142)
		(property "Reference" "PU201"
			(at 2.898394 -1.895856 0)
			(unlocked yes)
			(layer "F.SilkS")
			(effects
				(font
					(size 0.7874 0.5842)
					(thickness 0.1524)
				)
				(justify left)
			)
		)
		(property "Value" ""
			(at 0 0 0)
			(layer "F.Fab")
			(effects
				(font
					(size 1.27 1.27)
				)
			)
		)
		(duplicate_pad_numbers_are_jumpers no)
		(fp_line
			(start -1.774952 -1.039876)
			(end -1.774952 1.039876)
			(stroke
				(width 0.1524)
				(type default)
			)
			(layer "F.SilkS")
		)
		(fp_line
			(start -1.774952 1.039876)
			(end 1.774952 1.039876)
			(stroke
				(width 0.1524)
				(type default)
			)
			(layer "F.SilkS")
		)
		(fp_line
			(start 1.774952 -1.039876)
			(end -1.774952 -1.039876)
			(stroke
				(width 0.1524)
				(type default)
			)
			(layer "F.SilkS")
		)
		(fp_line
			(start 1.774952 1.039876)
			(end 1.774952 -1.039876)
			(stroke
				(width 0.1524)
				(type default)
			)
			(layer "F.SilkS")
		)
		(fp_poly
			(pts
				(xy -0.999998 -1.801876) (xy -0.999998 -1.039876) (xy -1.769872 -1.039876) (xy -1.769872 -0.249936)
				(xy -2.531872 -0.249936) (xy -2.531872 -1.801876)
			)
			(stroke
				(width 0)
				(type default)
			)
			(fill yes)
			(layer "F.SilkS")
		)
		(fp_line
			(start -1.769872 -1.039876)
			(end -1.769872 1.039876)
			(stroke
				(width 0.1)
				(type default)
			)
			(layer "F.Fab")
		)
		(fp_line
			(start -1.769872 1.039876)
			(end 1.769872 1.039876)
			(stroke
				(width 0.1)
				(type default)
			)
			(layer "F.Fab")
		)
		(fp_line
			(start 1.769872 -1.039876)
			(end -1.769872 -1.039876)
			(stroke
				(width 0.1)
				(type default)
			)
			(layer "F.Fab")
		)
		(fp_line
			(start 1.769872 1.039876)
			(end 1.769872 -1.039876)
			(stroke
				(width 0.1)
				(type default)
			)
			(layer "F.Fab")
		)
		(fp_poly
			(pts
				(xy -1.769872 -1.039876) (xy -0.999998 -1.039876) (xy -0.999998 -1.801876) (xy -2.531872 -1.801876)
				(xy -2.531872 -0.249936) (xy -1.769872 -0.249936)
			)
			(stroke
				(width 0)
				(type default)
			)
			(fill yes)
			(layer "F.Fab")
		)
		(pad "A1" smd circle
			(at -1.500124 -0.750062)
			(size 0.2286 0.2286)
			(layers "F.Cu" "F.Mask" "F.Paste")
			(net "P12V_OCP_SENSE_2")
		)
		(pad "A2" smd circle
			(at -0.999998 -0.750062)
			(size 0.2286 0.2286)
			(layers "F.Cu" "F.Mask" "F.Paste")
			(net "P12V_OCP_VCC_2")
		)
		(pad "A3" smd circle
			(at -0.499872 -0.750062)
			(size 0.2286 0.2286)
			(layers "F.Cu" "F.Mask" "F.Paste")
			(net "P12V_AUX")
		)
		(pad "A4" smd circle
			(at 0 -0.750062)
			(size 0.2286 0.2286)
			(layers "F.Cu" "F.Mask" "F.Paste")
			(net "P12V_OCP_V3_2")
		)
		(pad "A5" smd circle
			(at 0.499872 -0.750062)
			(size 0.2286 0.2286)
			(layers "F.Cu" "F.Mask" "F.Paste")
			(net "P12V_AUX")
		)
		(pad "A6" smd circle
			(at 0.999998 -0.750062)
			(size 0.2286 0.2286)
			(layers "F.Cu" "F.Mask" "F.Paste")
			(net "P12V_OCP_GATE_2")
		)
		(pad "A7" smd circle
			(at 1.500124 -0.750062)
			(size 0.2286 0.2286)
			(layers "F.Cu" "F.Mask" "F.Paste")
			(net "GND")
		)
		(pad "B1" smd circle
			(at -1.500124 -0.249936)
			(size 0.2286 0.2286)
			(layers "F.Cu" "F.Mask" "F.Paste")
			(net "P12V_OCP_CB_2")
		)
		(pad "B2" smd circle
			(at -0.999998 -0.249936)
			(size 0.2286 0.2286)
			(layers "F.Cu" "F.Mask" "F.Paste")
			(net "GND")
		)
		(pad "B3" smd circle
			(at -0.499872 -0.249936)
			(size 0.2286 0.2286)
			(layers "F.Cu" "F.Mask" "F.Paste")
			(net "P12V_AUX")
		)
		(pad "B4" smd circle
			(at 0 -0.249936)
			(size 0.2286 0.2286)
			(layers "F.Cu" "F.Mask" "F.Paste")
			(net "P12V_OCP_V3_2")
		)
		(pad "B5" smd circle
			(at 0.499872 -0.249936)
			(size 0.2286 0.2286)
			(layers "F.Cu" "F.Mask" "F.Paste")
			(net "P12V_AUX")
		)
		(pad "B6" smd circle
			(at 0.999998 -0.249936)
			(size 0.2286 0.2286)
			(layers "F.Cu" "F.Mask" "F.Paste")
			(net "P12V_OCP_V3_2")
		)
		(pad "B7" smd circle
			(at 1.500124 -0.249936)
			(size 0.2286 0.2286)
			(layers "F.Cu" "F.Mask" "F.Paste")
			(net "GND")
		)
		(pad "C1" smd circle
			(at -1.500124 0.249936)
			(size 0.2286 0.2286)
			(layers "F.Cu" "F.Mask" "F.Paste")
			(net "GND")
		)
		(pad "C2" smd circle
			(at -0.999998 0.249936)
			(size 0.2286 0.2286)
			(layers "F.Cu" "F.Mask" "F.Paste")
			(net "GND")
		)
		(pad "C3" smd circle
			(at -0.499872 0.249936)
			(size 0.2286 0.2286)
			(layers "F.Cu" "F.Mask" "F.Paste")
			(net "P12V_AUX")
		)
		(pad "C4" smd circle
			(at 0 0.249936)
			(size 0.2286 0.2286)
			(layers "F.Cu" "F.Mask" "F.Paste")
			(net "P12V_OCP_V3_2")
		)
		(pad "C5" smd circle
			(at 0.499872 0.249936)
			(size 0.2286 0.2286)
			(layers "F.Cu" "F.Mask" "F.Paste")
			(net "P12V_AUX")
		)
		(pad "C6" smd circle
			(at 0.999998 0.249936)
			(size 0.2286 0.2286)
			(layers "F.Cu" "F.Mask" "F.Paste")
			(net "P12V_OCP_V3_2")
		)
		(pad "C7" smd circle
			(at 1.500124 0.249936)
			(size 0.2286 0.2286)
			(layers "F.Cu" "F.Mask" "F.Paste")
			(net "P12V_OCP_FAULT_2")
		)
		(pad "D1" smd circle
			(at -1.500124 0.750062)
			(size 0.2286 0.2286)
			(layers "F.Cu" "F.Mask" "F.Paste")
			(net "P12V_OCP_REG_2")
		)
		(pad "D2" smd circle
			(at -0.999998 0.750062)
			(size 0.2286 0.2286)
			(layers "F.Cu" "F.Mask" "F.Paste")
			(net "P12V_OCP_UV_2")
		)
		(pad "D3" smd circle
			(at -0.499872 0.750062)
			(size 0.2286 0.2286)
			(layers "F.Cu" "F.Mask" "F.Paste")
			(net "P12V_OCP_OV_2")
		)
		(pad "D4" smd circle
			(at 0 0.750062)
			(size 0.2286 0.2286)
			(layers "F.Cu" "F.Mask" "F.Paste")
			(net "P12V_OCP_V3_2")
		)
		(pad "D5" smd circle
			(at 0.499872 0.750062)
			(size 0.2286 0.2286)
			(layers "F.Cu" "F.Mask" "F.Paste")
			(net "P12V_AUX")
		)
		(pad "D6" smd circle
			(at 0.999998 0.750062)
			(size 0.2286 0.2286)
			(layers "F.Cu" "F.Mask" "F.Paste")
			(net "P12V_OCP_V3_2")
		)
		(pad "D7" smd circle
			(at 1.500124 0.750062)
			(size 0.2286 0.2286)
			(layers "F.Cu" "F.Mask" "F.Paste")
			(net "P12V_OCP_PWRGD_2")
		)
	)
	(footprint ""
		(layer "F.Cu")
		(at 175.82388 -19.548348 180)
		(property "Reference" "PC2238"
			(at 0 0 180)
			(layer "F.SilkS")
			(hide yes)
			(effects
				(font
					(size 1.27 1.27)
				)
			)
		)
		(property "Value" ""
			(at 0 0 180)
			(layer "F.Fab")
			(effects
				(font
					(size 1.27 1.27)
				)
			)
		)
		(duplicate_pad_numbers_are_jumpers no)
		(fp_line
			(start 0.7874 0.4064)
			(end -0.7874 0.4064)
			(stroke
				(width 0.1524)
				(type default)
			)
			(layer "F.SilkS")
		)
		(fp_line
			(start 0.7874 -0.4064)
			(end 0.7874 0.4064)
			(stroke
				(width 0.1524)
				(type default)
			)
			(layer "F.SilkS")
		)
		(fp_line
			(start -0.7874 0.4064)
			(end -0.7874 -0.4064)
			(stroke
				(width 0.1524)
				(type default)
			)
			(layer "F.SilkS")
		)
		(fp_line
			(start -0.7874 -0.4064)
			(end 0.7874 -0.4064)
			(stroke
				(width 0.1524)
				(type default)
			)
			(layer "F.SilkS")
		)
		(fp_line
			(start 0.67945 0.3048)
			(end 0.120396 0.3048)
			(stroke
				(width 0.1)
				(type default)
			)
			(layer "F.Fab")
		)
		(fp_line
			(start 0.67945 -0.3048)
			(end 0.67945 0.3048)
			(stroke
				(width 0.1)
				(type default)
			)
			(layer "F.Fab")
		)
		(fp_line
			(start 0.12065 -0.2794)
			(end 0.12065 -0.3048)
			(stroke
				(width 0.1)
				(type default)
			)
			(layer "F.Fab")
		)
		(fp_line
			(start 0.12065 -0.3048)
			(end 0.67945 -0.3048)
			(stroke
				(width 0.1)
				(type default)
			)
			(layer "F.Fab")
		)
		(fp_line
			(start 0.120396 0.3048)
			(end 0.120396 0.2794)
			(stroke
				(width 0.1)
				(type default)
			)
			(layer "F.Fab")
		)
		(fp_line
			(start 0.120396 0.2794)
			(end -0.12065 0.2794)
			(stroke
				(width 0.1)
				(type default)
			)
			(layer "F.Fab")
		)
		(fp_line
			(start -0.12065 0.3048)
			(end -0.67945 0.3048)
			(stroke
				(width 0.1)
				(type default)
			)
			(layer "F.Fab")
		)
		(fp_line
			(start -0.12065 0.2794)
			(end -0.12065 0.3048)
			(stroke
				(width 0.1)
				(type default)
			)
			(layer "F.Fab")
		)
		(fp_line
			(start -0.12065 -0.2794)
			(end 0.12065 -0.2794)
			(stroke
				(width 0.1)
				(type default)
			)
			(layer "F.Fab")
		)
		(fp_line
			(start -0.12065 -0.305054)
			(end -0.12065 -0.2794)
			(stroke
				(width 0.1)
				(type default)
			)
			(layer "F.Fab")
		)
		(fp_line
			(start -0.67945 0.3048)
			(end -0.67945 -0.305054)
			(stroke
				(width 0.1)
				(type default)
			)
			(layer "F.Fab")
		)
		(fp_line
			(start -0.67945 -0.305054)
			(end -0.12065 -0.305054)
			(stroke
				(width 0.1)
				(type default)
			)
			(layer "F.Fab")
		)
		(pad "1" smd circle
			(at -0.40005 0 180)
			(size 0 0)
			(layers "F.Cu" "F.Mask" "F.Paste")
			(net "P12V_SCM_R")
		)
		(pad "2" smd circle
			(at 0.40005 0 180)
			(size 0 0)
			(layers "F.Cu" "F.Mask" "F.Paste")
			(net "GND")
		)
	)
	(footprint ""
		(layer "F.Cu")
		(at 412.359348 -16.100298 90)
		(property "Reference" "C46"
			(at 0 0 90)
			(layer "F.SilkS")
			(hide yes)
			(effects
				(font
					(size 1.27 1.27)
				)
			)
		)
		(property "Value" ""
			(at 0 0 90)
			(layer "F.Fab")
			(effects
				(font
					(size 1.27 1.27)
				)
			)
		)
		(duplicate_pad_numbers_are_jumpers no)
		(fp_line
			(start 0.299974 -0.150114)
			(end 0.299974 0.150114)
			(stroke
				(width 0.1)
				(type default)
			)
			(layer "F.Fab")
		)
		(fp_line
			(start -0.299974 -0.150114)
			(end 0.299974 -0.150114)
			(stroke
				(width 0.1)
				(type default)
			)
			(layer "F.Fab")
		)
		(fp_line
			(start 0.299974 0.150114)
			(end -0.299974 0.150114)
			(stroke
				(width 0.1)
				(type default)
			)
			(layer "F.Fab")
		)
		(fp_line
			(start -0.299974 0.150114)
			(end -0.299974 -0.150114)
			(stroke
				(width 0.1)
				(type default)
			)
			(layer "F.Fab")
		)
		(pad "1" smd rect
			(at -0.2667 0 90)
			(size 0.3048 0.381)
			(layers "F.Cu" "F.Mask" "F.Paste")
			(net "P5E_CPU0_G3_TX_C_DN<7>")
		)
		(pad "2" smd rect
			(at 0.2667 0 90)
			(size 0.3048 0.381)
			(layers "F.Cu" "F.Mask" "F.Paste")
			(net "P5E_CPU0_G3_TX_DN<7>")
		)
	)
	(footprint ""
		(layer "F.Cu")
		(at 316.507876 -70.098412 90)
		(property "Reference" "D99"
			(at -3.934714 -0.691642 90)
			(unlocked yes)
			(layer "F.SilkS")
			(effects
				(font
					(size 0.7874 0.5842)
					(thickness 0.1524)
				)
				(justify left)
			)
		)
		(property "Value" ""
			(at 0 0 90)
			(layer "F.Fab")
			(effects
				(font
					(size 1.27 1.27)
				)
			)
		)
		(duplicate_pad_numbers_are_jumpers no)
		(fp_line
			(start 1.16078 -0.4826)
			(end 1.16078 0.4826)
			(stroke
				(width 0.1524)
				(type default)
			)
			(layer "F.SilkS")
		)
		(fp_line
			(start 1.03378 -0.4826)
			(end 1.03378 0.4826)
			(stroke
				(width 0.1524)
				(type default)
			)
			(layer "F.SilkS")
		)
		(fp_line
			(start 0.90678 -0.4826)
			(end 0.90678 0.4826)
			(stroke
				(width 0.1524)
				(type default)
			)
			(layer "F.SilkS")
		)
		(fp_line
			(start -0.64008 -0.4826)
			(end 1.16078 -0.4826)
			(stroke
				(width 0.1524)
				(type default)
			)
			(layer "F.SilkS")
		)
		(fp_line
			(start -0.79248 -0.4826)
			(end 1.03378 -0.4826)
			(stroke
				(width 0.1524)
				(type default)
			)
			(layer "F.SilkS")
		)
		(fp_line
			(start -0.89408 -0.4826)
			(end 0.90678 -0.4826)
			(stroke
				(width 0.1524)
				(type default)
			)
			(layer "F.SilkS")
		)
		(fp_line
			(start 1.16078 0.4826)
			(end -0.64008 0.4826)
			(stroke
				(width 0.1524)
				(type default)
			)
			(layer "F.SilkS")
		)
		(fp_line
			(start 1.03378 0.4826)
			(end -0.79248 0.4826)
			(stroke
				(width 0.1524)
				(type default)
			)
			(layer "F.SilkS")
		)
		(fp_line
			(start 0.90678 0.4826)
			(end -0.90678 0.4826)
			(stroke
				(width 0.1524)
				(type default)
			)
			(layer "F.SilkS")
		)
		(fp_line
			(start -0.90678 0.4826)
			(end -0.90678 -0.4699)
			(stroke
				(width 0.1524)
				(type default)
			)
			(layer "F.SilkS")
		)
		(fp_line
			(start 0.499872 -0.249936)
			(end 0.499872 0.249936)
			(stroke
				(width 0.1)
				(type default)
			)
			(layer "F.Fab")
		)
		(fp_line
			(start -0.499872 -0.249936)
			(end 0.499872 -0.249936)
			(stroke
				(width 0.1)
				(type default)
			)
			(layer "F.Fab")
		)
		(fp_line
			(start 0.499872 0.249936)
			(end -0.499872 0.249936)
			(stroke
				(width 0.1)
				(type default)
			)
			(layer "F.Fab")
		)
		(fp_line
			(start -0.499872 0.249936)
			(end -0.499872 -0.249936)
			(stroke
				(width 0.1)
				(type default)
			)
			(layer "F.Fab")
		)
		(pad "A" smd rect
			(at -0.47498 0 90)
			(size 0.6096 0.7112)
			(layers "F.Cu" "F.Mask" "F.Paste")
			(net "LED_P3V3")
		)
		(pad "C" smd rect
			(at 0.47498 0 90)
			(size 0.6096 0.7112)
			(layers "F.Cu" "F.Mask" "F.Paste")
			(net "GND")
		)
	)
	(footprint ""
		(layer "F.Cu")
		(at 96.0628 -416.4076 180)
		(property "Reference" "R1461"
			(at 0 0 180)
			(layer "F.SilkS")
			(hide yes)
			(effects
				(font
					(size 1.27 1.27)
				)
			)
		)
		(property "Value" ""
			(at 0 0 180)
			(layer "F.Fab")
			(effects
				(font
					(size 1.27 1.27)
				)
			)
		)
		(duplicate_pad_numbers_are_jumpers no)
		(fp_line
			(start 0.32512 0.175006)
			(end -0.32512 0.175006)
			(stroke
				(width 0.1)
				(type default)
			)
			(layer "F.Fab")
		)
		(fp_line
			(start 0.32512 -0.175006)
			(end 0.32512 0.175006)
			(stroke
				(width 0.1)
				(type default)
			)
			(layer "F.Fab")
		)
		(fp_line
			(start -0.32512 0.175006)
			(end -0.32512 -0.175006)
			(stroke
				(width 0.1)
				(type default)
			)
			(layer "F.Fab")
		)
		(fp_line
			(start -0.32512 -0.175006)
			(end 0.32512 -0.175006)
			(stroke
				(width 0.1)
				(type default)
			)
			(layer "F.Fab")
		)
		(pad "1" smd rect
			(at -0.2667 0 180)
			(size 0.3048 0.381)
			(layers "F.Cu" "F.Mask" "F.Paste")
			(net "P1V8_CPU1_RT_1D")
		)
		(pad "2" smd rect
			(at 0.2667 0)
			(size 0.3048 0.381)
			(layers "F.Cu" "F.Mask" "F.Paste")
			(net "JTAG_TCK_RT_CPU1_P1")
		)
	)
	(footprint ""
		(layer "F.Cu")
		(at 381.573278 -141.345158 180)
		(property "Reference" "PR5"
			(at 0 0 180)
			(layer "F.SilkS")
			(hide yes)
			(effects
				(font
					(size 1.27 1.27)
				)
			)
		)
		(property "Value" ""
			(at 0 0 180)
			(layer "F.Fab")
			(effects
				(font
					(size 1.27 1.27)
				)
			)
		)
		(duplicate_pad_numbers_are_jumpers no)
		(fp_line
			(start 0.7874 0.4064)
			(end -0.7874 0.4064)
			(stroke
				(width 0.1524)
				(type default)
			)
			(layer "F.SilkS")
		)
		(fp_line
			(start 0.7874 -0.4064)
			(end 0.7874 0.4064)
			(stroke
				(width 0.1524)
				(type default)
			)
			(layer "F.SilkS")
		)
		(fp_line
			(start -0.7874 0.4064)
			(end -0.7874 -0.4064)
			(stroke
				(width 0.1524)
				(type default)
			)
			(layer "F.SilkS")
		)
		(fp_line
			(start -0.7874 -0.4064)
			(end 0.7874 -0.4064)
			(stroke
				(width 0.1524)
				(type default)
			)
			(layer "F.SilkS")
		)
		(fp_line
			(start 0.67945 0.3048)
			(end 0.120396 0.3048)
			(stroke
				(width 0.1)
				(type default)
			)
			(layer "F.Fab")
		)
		(fp_line
			(start 0.67945 -0.3048)
			(end 0.67945 0.3048)
			(stroke
				(width 0.1)
				(type default)
			)
			(layer "F.Fab")
		)
		(fp_line
			(start 0.12065 -0.2794)
			(end 0.12065 -0.3048)
			(stroke
				(width 0.1)
				(type default)
			)
			(layer "F.Fab")
		)
		(fp_line
			(start 0.12065 -0.3048)
			(end 0.67945 -0.3048)
			(stroke
				(width 0.1)
				(type default)
			)
			(layer "F.Fab")
		)
		(fp_line
			(start 0.120396 0.3048)
			(end 0.120396 0.2794)
			(stroke
				(width 0.1)
				(type default)
			)
			(layer "F.Fab")
		)
		(fp_line
			(start 0.120396 0.2794)
			(end -0.12065 0.2794)
			(stroke
				(width 0.1)
				(type default)
			)
			(layer "F.Fab")
		)
		(fp_line
			(start -0.12065 0.3048)
			(end -0.67945 0.3048)
			(stroke
				(width 0.1)
				(type default)
			)
			(layer "F.Fab")
		)
		(fp_line
			(start -0.12065 0.2794)
			(end -0.12065 0.3048)
			(stroke
				(width 0.1)
				(type default)
			)
			(layer "F.Fab")
		)
		(fp_line
			(start -0.12065 -0.2794)
			(end 0.12065 -0.2794)
			(stroke
				(width 0.1)
				(type default)
			)
			(layer "F.Fab")
		)
		(fp_line
			(start -0.12065 -0.305054)
			(end -0.12065 -0.2794)
			(stroke
				(width 0.1)
				(type default)
			)
			(layer "F.Fab")
		)
		(fp_line
			(start -0.67945 0.3048)
			(end -0.67945 -0.305054)
			(stroke
				(width 0.1)
				(type default)
			)
			(layer "F.Fab")
		)
		(fp_line
			(start -0.67945 -0.305054)
			(end -0.12065 -0.305054)
			(stroke
				(width 0.1)
				(type default)
			)
			(layer "F.Fab")
		)
		(pad "1" smd circle
			(at -0.40005 0 180)
			(size 0 0)
			(layers "F.Cu" "F.Mask" "F.Paste")
			(net "PVDDCR_CPU0_P0_VMON")
		)
		(pad "2" smd circle
			(at 0.40005 0 180)
			(size 0 0)
			(layers "F.Cu" "F.Mask" "F.Paste")
			(net "GND")
		)
	)
	(footprint ""
		(layer "F.Cu")
		(at 391.290556 -73.359264 180)
		(property "Reference" "R1327"
			(at 0 0 180)
			(layer "F.SilkS")
			(hide yes)
			(effects
				(font
					(size 1.27 1.27)
				)
			)
		)
		(property "Value" ""
			(at 0 0 180)
			(layer "F.Fab")
			(effects
				(font
					(size 1.27 1.27)
				)
			)
		)
		(duplicate_pad_numbers_are_jumpers no)
		(fp_line
			(start 0.7874 0.4064)
			(end -0.7874 0.4064)
			(stroke
				(width 0.1524)
				(type default)
			)
			(layer "F.SilkS")
		)
		(fp_line
			(start 0.7874 -0.4064)
			(end 0.7874 0.4064)
			(stroke
				(width 0.1524)
				(type default)
			)
			(layer "F.SilkS")
		)
		(fp_line
			(start -0.7874 0.4064)
			(end -0.7874 -0.4064)
			(stroke
				(width 0.1524)
				(type default)
			)
			(layer "F.SilkS")
		)
		(fp_line
			(start -0.7874 -0.4064)
			(end 0.7874 -0.4064)
			(stroke
				(width 0.1524)
				(type default)
			)
			(layer "F.SilkS")
		)
		(fp_line
			(start 0.67945 0.3048)
			(end 0.120396 0.3048)
			(stroke
				(width 0.1)
				(type default)
			)
			(layer "F.Fab")
		)
		(fp_line
			(start 0.67945 -0.3048)
			(end 0.67945 0.3048)
			(stroke
				(width 0.1)
				(type default)
			)
			(layer "F.Fab")
		)
		(fp_line
			(start 0.12065 -0.2794)
			(end 0.12065 -0.3048)
			(stroke
				(width 0.1)
				(type default)
			)
			(layer "F.Fab")
		)
		(fp_line
			(start 0.12065 -0.3048)
			(end 0.67945 -0.3048)
			(stroke
				(width 0.1)
				(type default)
			)
			(layer "F.Fab")
		)
		(fp_line
			(start 0.120396 0.3048)
			(end 0.120396 0.2794)
			(stroke
				(width 0.1)
				(type default)
			)
			(layer "F.Fab")
		)
		(fp_line
			(start 0.120396 0.2794)
			(end -0.12065 0.2794)
			(stroke
				(width 0.1)
				(type default)
			)
			(layer "F.Fab")
		)
		(fp_line
			(start -0.12065 0.3048)
			(end -0.67945 0.3048)
			(stroke
				(width 0.1)
				(type default)
			)
			(layer "F.Fab")
		)
		(fp_line
			(start -0.12065 0.2794)
			(end -0.12065 0.3048)
			(stroke
				(width 0.1)
				(type default)
			)
			(layer "F.Fab")
		)
		(fp_line
			(start -0.12065 -0.2794)
			(end 0.12065 -0.2794)
			(stroke
				(width 0.1)
				(type default)
			)
			(layer "F.Fab")
		)
		(fp_line
			(start -0.12065 -0.305054)
			(end -0.12065 -0.2794)
			(stroke
				(width 0.1)
				(type default)
			)
			(layer "F.Fab")
		)
		(fp_line
			(start -0.67945 0.3048)
			(end -0.67945 -0.305054)
			(stroke
				(width 0.1)
				(type default)
			)
			(layer "F.Fab")
		)
		(fp_line
			(start -0.67945 -0.305054)
			(end -0.12065 -0.305054)
			(stroke
				(width 0.1)
				(type default)
			)
			(layer "F.Fab")
		)
		(pad "1" smd circle
			(at -0.40005 0 180)
			(size 0 0)
			(layers "F.Cu" "F.Mask" "F.Paste")
			(net "P3V3_AUX")
		)
		(pad "2" smd circle
			(at 0.40005 0 180)
			(size 0 0)
			(layers "F.Cu" "F.Mask" "F.Paste")
			(net "OCP_SFF_P3V3_P12V_ADC_R_ALERT")
		)
	)
	(footprint ""
		(layer "F.Cu")
		(at 298.050966 -22.747224)
		(property "Reference" "C193"
			(at 0 0 0)
			(layer "F.SilkS")
			(hide yes)
			(effects
				(font
					(size 1.27 1.27)
				)
			)
		)
		(property "Value" ""
			(at 0 0 0)
			(layer "F.Fab")
			(effects
				(font
					(size 1.27 1.27)
				)
			)
		)
		(duplicate_pad_numbers_are_jumpers no)
		(fp_line
			(start -0.7874 -0.4064)
			(end 0.7874 -0.4064)
			(stroke
				(width 0.1524)
				(type default)
			)
			(layer "F.SilkS")
		)
		(fp_line
			(start -0.7874 0.4064)
			(end -0.7874 -0.4064)
			(stroke
				(width 0.1524)
				(type default)
			)
			(layer "F.SilkS")
		)
		(fp_line
			(start 0.7874 -0.4064)
			(end 0.7874 0.4064)
			(stroke
				(width 0.1524)
				(type default)
			)
			(layer "F.SilkS")
		)
		(fp_line
			(start 0.7874 0.4064)
			(end -0.7874 0.4064)
			(stroke
				(width 0.1524)
				(type default)
			)
			(layer "F.SilkS")
		)
		(fp_line
			(start -0.67945 -0.305054)
			(end -0.12065 -0.305054)
			(stroke
				(width 0.1)
				(type default)
			)
			(layer "F.Fab")
		)
		(fp_line
			(start -0.67945 0.3048)
			(end -0.67945 -0.305054)
			(stroke
				(width 0.1)
				(type default)
			)
			(layer "F.Fab")
		)
		(fp_line
			(start -0.12065 -0.305054)
			(end -0.12065 -0.2794)
			(stroke
				(width 0.1)
				(type default)
			)
			(layer "F.Fab")
		)
		(fp_line
			(start -0.12065 -0.2794)
			(end 0.12065 -0.2794)
			(stroke
				(width 0.1)
				(type default)
			)
			(layer "F.Fab")
		)
		(fp_line
			(start -0.12065 0.2794)
			(end -0.12065 0.3048)
			(stroke
				(width 0.1)
				(type default)
			)
			(layer "F.Fab")
		)
		(fp_line
			(start -0.12065 0.3048)
			(end -0.67945 0.3048)
			(stroke
				(width 0.1)
				(type default)
			)
			(layer "F.Fab")
		)
		(fp_line
			(start 0.120396 0.2794)
			(end -0.12065 0.2794)
			(stroke
				(width 0.1)
				(type default)
			)
			(layer "F.Fab")
		)
		(fp_line
			(start 0.120396 0.3048)
			(end 0.120396 0.2794)
			(stroke
				(width 0.1)
				(type default)
			)
			(layer "F.Fab")
		)
		(fp_line
			(start 0.12065 -0.3048)
			(end 0.67945 -0.3048)
			(stroke
				(width 0.1)
				(type default)
			)
			(layer "F.Fab")
		)
		(fp_line
			(start 0.12065 -0.2794)
			(end 0.12065 -0.3048)
			(stroke
				(width 0.1)
				(type default)
			)
			(layer "F.Fab")
		)
		(fp_line
			(start 0.67945 -0.3048)
			(end 0.67945 0.3048)
			(stroke
				(width 0.1)
				(type default)
			)
			(layer "F.Fab")
		)
		(fp_line
			(start 0.67945 0.3048)
			(end 0.120396 0.3048)
			(stroke
				(width 0.1)
				(type default)
			)
			(layer "F.Fab")
		)
		(pad "1" smd circle
			(at -0.40005 0)
			(size 0 0)
			(layers "F.Cu" "F.Mask" "F.Paste")
			(net "P1V5_BAT_IN")
		)
		(pad "2" smd circle
			(at 0.40005 0)
			(size 0 0)
			(layers "F.Cu" "F.Mask" "F.Paste")
			(net "GND")
		)
	)
	(footprint ""
		(layer "F.Cu")
		(at 284.73654 -403.961092 -90)
		(property "Reference" "R2624"
			(at 0 0 270)
			(layer "F.SilkS")
			(hide yes)
			(effects
				(font
					(size 1.27 1.27)
				)
			)
		)
		(property "Value" ""
			(at 0 0 270)
			(layer "F.Fab")
			(effects
				(font
					(size 1.27 1.27)
				)
			)
		)
		(duplicate_pad_numbers_are_jumpers no)
		(fp_line
			(start -0.7874 0.4064)
			(end -0.7874 -0.4064)
			(stroke
				(width 0.1524)
				(type default)
			)
			(layer "F.SilkS")
		)
		(fp_line
			(start 0.7874 0.4064)
			(end -0.7874 0.4064)
			(stroke
				(width 0.1524)
				(type default)
			)
			(layer "F.SilkS")
		)
		(fp_line
			(start -0.7874 -0.4064)
			(end 0.7874 -0.4064)
			(stroke
				(width 0.1524)
				(type default)
			)
			(layer "F.SilkS")
		)
		(fp_line
			(start 0.7874 -0.4064)
			(end 0.7874 0.4064)
			(stroke
				(width 0.1524)
				(type default)
			)
			(layer "F.SilkS")
		)
		(fp_line
			(start -0.67945 0.3048)
			(end -0.67945 -0.305054)
			(stroke
				(width 0.1)
				(type default)
			)
			(layer "F.Fab")
		)
		(fp_line
			(start -0.12065 0.3048)
			(end -0.67945 0.3048)
			(stroke
				(width 0.1)
				(type default)
			)
			(layer "F.Fab")
		)
		(fp_line
			(start 0.120396 0.3048)
			(end 0.120396 0.2794)
			(stroke
				(width 0.1)
				(type default)
			)
			(layer "F.Fab")
		)
		(fp_line
			(start 0.67945 0.3048)
			(end 0.120396 0.3048)
			(stroke
				(width 0.1)
				(type default)
			)
			(layer "F.Fab")
		)
		(fp_line
			(start -0.12065 0.2794)
			(end -0.12065 0.3048)
			(stroke
				(width 0.1)
				(type default)
			)
			(layer "F.Fab")
		)
		(fp_line
			(start 0.120396 0.2794)
			(end -0.12065 0.2794)
			(stroke
				(width 0.1)
				(type default)
			)
			(layer "F.Fab")
		)
		(fp_line
			(start -0.12065 -0.2794)
			(end 0.12065 -0.2794)
			(stroke
				(width 0.1)
				(type default)
			)
			(layer "F.Fab")
		)
		(fp_line
			(start 0.12065 -0.2794)
			(end 0.12065 -0.3048)
			(stroke
				(width 0.1)
				(type default)
			)
			(layer "F.Fab")
		)
		(fp_line
			(start 0.12065 -0.3048)
			(end 0.67945 -0.3048)
			(stroke
				(width 0.1)
				(type default)
			)
			(layer "F.Fab")
		)
		(fp_line
			(start 0.67945 -0.3048)
			(end 0.67945 0.3048)
			(stroke
				(width 0.1)
				(type default)
			)
			(layer "F.Fab")
		)
		(fp_line
			(start -0.67945 -0.305054)
			(end -0.12065 -0.305054)
			(stroke
				(width 0.1)
				(type default)
			)
			(layer "F.Fab")
		)
		(fp_line
			(start -0.12065 -0.305054)
			(end -0.12065 -0.2794)
			(stroke
				(width 0.1)
				(type default)
			)
			(layer "F.Fab")
		)
		(pad "1" smd circle
			(at -0.40005 0 270)
			(size 0 0)
			(layers "F.Cu" "F.Mask" "F.Paste")
			(net "P12V_HSC_TEMP_E")
		)
		(pad "2" smd circle
			(at 0.40005 0 270)
			(size 0 0)
			(layers "F.Cu" "F.Mask" "F.Paste")
			(net "P12V_HSC_TEMP_D-")
		)
	)
	(footprint ""
		(layer "F.Cu")
		(at 22.479 -364.617 180)
		(property "Reference" "C5020"
			(at 0 0 180)
			(layer "F.SilkS")
			(hide yes)
			(effects
				(font
					(size 1.27 1.27)
				)
			)
		)
		(property "Value" ""
			(at 0 0 180)
			(layer "F.Fab")
			(effects
				(font
					(size 1.27 1.27)
				)
			)
		)
		(duplicate_pad_numbers_are_jumpers no)
		(fp_line
			(start 0.7874 0.4064)
			(end -0.7874 0.4064)
			(stroke
				(width 0.1524)
				(type default)
			)
			(layer "F.SilkS")
		)
		(fp_line
			(start 0.7874 -0.4064)
			(end 0.7874 0.4064)
			(stroke
				(width 0.1524)
				(type default)
			)
			(layer "F.SilkS")
		)
		(fp_line
			(start -0.7874 0.4064)
			(end -0.7874 -0.4064)
			(stroke
				(width 0.1524)
				(type default)
			)
			(layer "F.SilkS")
		)
		(fp_line
			(start -0.7874 -0.4064)
			(end 0.7874 -0.4064)
			(stroke
				(width 0.1524)
				(type default)
			)
			(layer "F.SilkS")
		)
		(fp_line
			(start 0.67945 0.3048)
			(end 0.120396 0.3048)
			(stroke
				(width 0.1)
				(type default)
			)
			(layer "F.Fab")
		)
		(fp_line
			(start 0.67945 -0.3048)
			(end 0.67945 0.3048)
			(stroke
				(width 0.1)
				(type default)
			)
			(layer "F.Fab")
		)
		(fp_line
			(start 0.12065 -0.2794)
			(end 0.12065 -0.3048)
			(stroke
				(width 0.1)
				(type default)
			)
			(layer "F.Fab")
		)
		(fp_line
			(start 0.12065 -0.3048)
			(end 0.67945 -0.3048)
			(stroke
				(width 0.1)
				(type default)
			)
			(layer "F.Fab")
		)
		(fp_line
			(start 0.120396 0.3048)
			(end 0.120396 0.2794)
			(stroke
				(width 0.1)
				(type default)
			)
			(layer "F.Fab")
		)
		(fp_line
			(start 0.120396 0.2794)
			(end -0.12065 0.2794)
			(stroke
				(width 0.1)
				(type default)
			)
			(layer "F.Fab")
		)
		(fp_line
			(start -0.12065 0.3048)
			(end -0.67945 0.3048)
			(stroke
				(width 0.1)
				(type default)
			)
			(layer "F.Fab")
		)
		(fp_line
			(start -0.12065 0.2794)
			(end -0.12065 0.3048)
			(stroke
				(width 0.1)
				(type default)
			)
			(layer "F.Fab")
		)
		(fp_line
			(start -0.12065 -0.2794)
			(end 0.12065 -0.2794)
			(stroke
				(width 0.1)
				(type default)
			)
			(layer "F.Fab")
		)
		(fp_line
			(start -0.12065 -0.305054)
			(end -0.12065 -0.2794)
			(stroke
				(width 0.1)
				(type default)
			)
			(layer "F.Fab")
		)
		(fp_line
			(start -0.67945 0.3048)
			(end -0.67945 -0.305054)
			(stroke
				(width 0.1)
				(type default)
			)
			(layer "F.Fab")
		)
		(fp_line
			(start -0.67945 -0.305054)
			(end -0.12065 -0.305054)
			(stroke
				(width 0.1)
				(type default)
			)
			(layer "F.Fab")
		)
		(pad "1" smd circle
			(at -0.40005 0 180)
			(size 0 0)
			(layers "F.Cu" "F.Mask" "F.Paste")
			(net "GND")
		)
		(pad "2" smd circle
			(at 0.40005 0 180)
			(size 0 0)
			(layers "F.Cu" "F.Mask" "F.Paste")
			(net "PVDDCR_CPU1_P1_SMB_ALERT")
		)
	)
	(footprint ""
		(layer "F.Cu")
		(at 180.970936 -133.235954 -90)
		(property "Reference" "R217"
			(at 0 0 270)
			(layer "F.SilkS")
			(hide yes)
			(effects
				(font
					(size 1.27 1.27)
				)
			)
		)
		(property "Value" ""
			(at 0 0 270)
			(layer "F.Fab")
			(effects
				(font
					(size 1.27 1.27)
				)
			)
		)
		(duplicate_pad_numbers_are_jumpers no)
		(fp_line
			(start -0.7874 0.4064)
			(end -0.7874 -0.4064)
			(stroke
				(width 0.1524)
				(type default)
			)
			(layer "F.SilkS")
		)
		(fp_line
			(start 0.7874 0.4064)
			(end -0.7874 0.4064)
			(stroke
				(width 0.1524)
				(type default)
			)
			(layer "F.SilkS")
		)
		(fp_line
			(start -0.7874 -0.4064)
			(end 0.7874 -0.4064)
			(stroke
				(width 0.1524)
				(type default)
			)
			(layer "F.SilkS")
		)
		(fp_line
			(start 0.7874 -0.4064)
			(end 0.7874 0.4064)
			(stroke
				(width 0.1524)
				(type default)
			)
			(layer "F.SilkS")
		)
		(fp_line
			(start -0.67945 0.3048)
			(end -0.67945 -0.305054)
			(stroke
				(width 0.1)
				(type default)
			)
			(layer "F.Fab")
		)
		(fp_line
			(start -0.12065 0.3048)
			(end -0.67945 0.3048)
			(stroke
				(width 0.1)
				(type default)
			)
			(layer "F.Fab")
		)
		(fp_line
			(start 0.120396 0.3048)
			(end 0.120396 0.2794)
			(stroke
				(width 0.1)
				(type default)
			)
			(layer "F.Fab")
		)
		(fp_line
			(start 0.67945 0.3048)
			(end 0.120396 0.3048)
			(stroke
				(width 0.1)
				(type default)
			)
			(layer "F.Fab")
		)
		(fp_line
			(start -0.12065 0.2794)
			(end -0.12065 0.3048)
			(stroke
				(width 0.1)
				(type default)
			)
			(layer "F.Fab")
		)
		(fp_line
			(start 0.120396 0.2794)
			(end -0.12065 0.2794)
			(stroke
				(width 0.1)
				(type default)
			)
			(layer "F.Fab")
		)
		(fp_line
			(start -0.12065 -0.2794)
			(end 0.12065 -0.2794)
			(stroke
				(width 0.1)
				(type default)
			)
			(layer "F.Fab")
		)
		(fp_line
			(start 0.12065 -0.2794)
			(end 0.12065 -0.3048)
			(stroke
				(width 0.1)
				(type default)
			)
			(layer "F.Fab")
		)
		(fp_line
			(start 0.12065 -0.3048)
			(end 0.67945 -0.3048)
			(stroke
				(width 0.1)
				(type default)
			)
			(layer "F.Fab")
		)
		(fp_line
			(start 0.67945 -0.3048)
			(end 0.67945 0.3048)
			(stroke
				(width 0.1)
				(type default)
			)
			(layer "F.Fab")
		)
		(fp_line
			(start -0.67945 -0.305054)
			(end -0.12065 -0.305054)
			(stroke
				(width 0.1)
				(type default)
			)
			(layer "F.Fab")
		)
		(fp_line
			(start -0.12065 -0.305054)
			(end -0.12065 -0.2794)
			(stroke
				(width 0.1)
				(type default)
			)
			(layer "F.Fab")
		)
		(pad "1" smd circle
			(at -0.40005 0 270)
			(size 0 0)
			(layers "F.Cu" "F.Mask" "F.Paste")
			(net "RST_CPU0_RSMRST_N")
		)
		(pad "2" smd circle
			(at 0.40005 0 270)
			(size 0 0)
			(layers "F.Cu" "F.Mask" "F.Paste")
			(net "FM_CPU0_RSMRST_N")
		)
	)
	(footprint ""
		(layer "F.Cu")
		(at 77.55001 -24.713946 -90)
		(property "Reference" "PR3830"
			(at 0 0 270)
			(layer "F.SilkS")
			(hide yes)
			(effects
				(font
					(size 1.27 1.27)
				)
			)
		)
		(property "Value" ""
			(at 0 0 270)
			(layer "F.Fab")
			(effects
				(font
					(size 1.27 1.27)
				)
			)
		)
		(duplicate_pad_numbers_are_jumpers no)
		(fp_line
			(start -0.7874 0.4064)
			(end -0.7874 -0.4064)
			(stroke
				(width 0.1524)
				(type default)
			)
			(layer "F.SilkS")
		)
		(fp_line
			(start 0.7874 0.4064)
			(end -0.7874 0.4064)
			(stroke
				(width 0.1524)
				(type default)
			)
			(layer "F.SilkS")
		)
		(fp_line
			(start -0.7874 -0.4064)
			(end 0.7874 -0.4064)
			(stroke
				(width 0.1524)
				(type default)
			)
			(layer "F.SilkS")
		)
		(fp_line
			(start 0.7874 -0.4064)
			(end 0.7874 0.4064)
			(stroke
				(width 0.1524)
				(type default)
			)
			(layer "F.SilkS")
		)
		(fp_line
			(start -0.67945 0.3048)
			(end -0.67945 -0.305054)
			(stroke
				(width 0.1)
				(type default)
			)
			(layer "F.Fab")
		)
		(fp_line
			(start -0.12065 0.3048)
			(end -0.67945 0.3048)
			(stroke
				(width 0.1)
				(type default)
			)
			(layer "F.Fab")
		)
		(fp_line
			(start 0.120396 0.3048)
			(end 0.120396 0.2794)
			(stroke
				(width 0.1)
				(type default)
			)
			(layer "F.Fab")
		)
		(fp_line
			(start 0.67945 0.3048)
			(end 0.120396 0.3048)
			(stroke
				(width 0.1)
				(type default)
			)
			(layer "F.Fab")
		)
		(fp_line
			(start -0.12065 0.2794)
			(end -0.12065 0.3048)
			(stroke
				(width 0.1)
				(type default)
			)
			(layer "F.Fab")
		)
		(fp_line
			(start 0.120396 0.2794)
			(end -0.12065 0.2794)
			(stroke
				(width 0.1)
				(type default)
			)
			(layer "F.Fab")
		)
		(fp_line
			(start -0.12065 -0.2794)
			(end 0.12065 -0.2794)
			(stroke
				(width 0.1)
				(type default)
			)
			(layer "F.Fab")
		)
		(fp_line
			(start 0.12065 -0.2794)
			(end 0.12065 -0.3048)
			(stroke
				(width 0.1)
				(type default)
			)
			(layer "F.Fab")
		)
		(fp_line
			(start 0.12065 -0.3048)
			(end 0.67945 -0.3048)
			(stroke
				(width 0.1)
				(type default)
			)
			(layer "F.Fab")
		)
		(fp_line
			(start 0.67945 -0.3048)
			(end 0.67945 0.3048)
			(stroke
				(width 0.1)
				(type default)
			)
			(layer "F.Fab")
		)
		(fp_line
			(start -0.67945 -0.305054)
			(end -0.12065 -0.305054)
			(stroke
				(width 0.1)
				(type default)
			)
			(layer "F.Fab")
		)
		(fp_line
			(start -0.12065 -0.305054)
			(end -0.12065 -0.2794)
			(stroke
				(width 0.1)
				(type default)
			)
			(layer "F.Fab")
		)
		(pad "1" smd circle
			(at -0.40005 0 270)
			(size 0 0)
			(layers "F.Cu" "F.Mask" "F.Paste")
			(net "P12V_AUX")
		)
		(pad "2" smd circle
			(at 0.40005 0 270)
			(size 0 0)
			(layers "F.Cu" "F.Mask" "F.Paste")
			(net "P12V_OCP_VCC_2")
		)
	)
	(footprint ""
		(layer "F.Cu")
		(at 19.241516 -37.894514 180)
		(property "Reference" "R1271"
			(at 0 0 180)
			(layer "F.SilkS")
			(hide yes)
			(effects
				(font
					(size 1.27 1.27)
				)
			)
		)
		(property "Value" ""
			(at 0 0 180)
			(layer "F.Fab")
			(effects
				(font
					(size 1.27 1.27)
				)
			)
		)
		(duplicate_pad_numbers_are_jumpers no)
		(fp_line
			(start 0.7874 0.4064)
			(end -0.7874 0.4064)
			(stroke
				(width 0.1524)
				(type default)
			)
			(layer "F.SilkS")
		)
		(fp_line
			(start 0.7874 -0.4064)
			(end 0.7874 0.4064)
			(stroke
				(width 0.1524)
				(type default)
			)
			(layer "F.SilkS")
		)
		(fp_line
			(start -0.7874 0.4064)
			(end -0.7874 -0.4064)
			(stroke
				(width 0.1524)
				(type default)
			)
			(layer "F.SilkS")
		)
		(fp_line
			(start -0.7874 -0.4064)
			(end 0.7874 -0.4064)
			(stroke
				(width 0.1524)
				(type default)
			)
			(layer "F.SilkS")
		)
		(fp_line
			(start 0.67945 0.3048)
			(end 0.120396 0.3048)
			(stroke
				(width 0.1)
				(type default)
			)
			(layer "F.Fab")
		)
		(fp_line
			(start 0.67945 -0.3048)
			(end 0.67945 0.3048)
			(stroke
				(width 0.1)
				(type default)
			)
			(layer "F.Fab")
		)
		(fp_line
			(start 0.12065 -0.2794)
			(end 0.12065 -0.3048)
			(stroke
				(width 0.1)
				(type default)
			)
			(layer "F.Fab")
		)
		(fp_line
			(start 0.12065 -0.3048)
			(end 0.67945 -0.3048)
			(stroke
				(width 0.1)
				(type default)
			)
			(layer "F.Fab")
		)
		(fp_line
			(start 0.120396 0.3048)
			(end 0.120396 0.2794)
			(stroke
				(width 0.1)
				(type default)
			)
			(layer "F.Fab")
		)
		(fp_line
			(start 0.120396 0.2794)
			(end -0.12065 0.2794)
			(stroke
				(width 0.1)
				(type default)
			)
			(layer "F.Fab")
		)
		(fp_line
			(start -0.12065 0.3048)
			(end -0.67945 0.3048)
			(stroke
				(width 0.1)
				(type default)
			)
			(layer "F.Fab")
		)
		(fp_line
			(start -0.12065 0.2794)
			(end -0.12065 0.3048)
			(stroke
				(width 0.1)
				(type default)
			)
			(layer "F.Fab")
		)
		(fp_line
			(start -0.12065 -0.2794)
			(end 0.12065 -0.2794)
			(stroke
				(width 0.1)
				(type default)
			)
			(layer "F.Fab")
		)
		(fp_line
			(start -0.12065 -0.305054)
			(end -0.12065 -0.2794)
			(stroke
				(width 0.1)
				(type default)
			)
			(layer "F.Fab")
		)
		(fp_line
			(start -0.67945 0.3048)
			(end -0.67945 -0.305054)
			(stroke
				(width 0.1)
				(type default)
			)
			(layer "F.Fab")
		)
		(fp_line
			(start -0.67945 -0.305054)
			(end -0.12065 -0.305054)
			(stroke
				(width 0.1)
				(type default)
			)
			(layer "F.Fab")
		)
		(pad "1" smd circle
			(at -0.40005 0 180)
			(size 0 0)
			(layers "F.Cu" "F.Mask" "F.Paste")
			(net "P12V_OCP_V3_2_ADC_ALERT_R")
		)
		(pad "2" smd circle
			(at 0.40005 0 180)
			(size 0 0)
			(layers "F.Cu" "F.Mask" "F.Paste")
			(net "OCP_V3_2_P3V3_P12V_ADC_R_ALERT")
		)
	)
	(footprint ""
		(layer "F.Cu")
		(at 403.476714 -147.706588)
		(property "Reference" "Q57"
			(at -2.2225 -3.470402 0)
			(unlocked yes)
			(layer "F.SilkS")
			(effects
				(font
					(size 0.7874 0.5842)
					(thickness 0.1524)
				)
				(justify left)
			)
		)
		(property "Value" ""
			(at 0 0 0)
			(layer "F.Fab")
			(effects
				(font
					(size 1.27 1.27)
				)
			)
		)
		(duplicate_pad_numbers_are_jumpers no)
		(fp_line
			(start -2.350008 -2.649982)
			(end 2.350008 -2.649982)
			(stroke
				(width 0.1524)
				(type default)
			)
			(layer "F.SilkS")
		)
		(fp_line
			(start -2.350008 -2.4384)
			(end -2.350008 -2.649982)
			(stroke
				(width 0.1524)
				(type default)
			)
			(layer "F.SilkS")
		)
		(fp_line
			(start -2.350008 2.649982)
			(end -2.350008 2.413)
			(stroke
				(width 0.1524)
				(type default)
			)
			(layer "F.SilkS")
		)
		(fp_line
			(start 2.350008 -2.649982)
			(end 2.350008 -2.4892)
			(stroke
				(width 0.1524)
				(type default)
			)
			(layer "F.SilkS")
		)
		(fp_line
			(start 2.350008 2.4892)
			(end 2.350008 2.649982)
			(stroke
				(width 0.1524)
				(type default)
			)
			(layer "F.SilkS")
		)
		(fp_line
			(start 2.350008 2.649982)
			(end -2.350008 2.649982)
			(stroke
				(width 0.1524)
				(type default)
			)
			(layer "F.SilkS")
		)
		(fp_poly
			(pts
				(xy -5.142992 -3.626866) (xy -4.444238 -2.74828) (xy -5.537962 -2.930906)
			)
			(stroke
				(width 0)
				(type default)
			)
			(fill yes)
			(layer "F.SilkS")
		)
		(fp_line
			(start -2.350008 -2.649982)
			(end 2.350008 -2.649982)
			(stroke
				(width 0.1)
				(type default)
			)
			(layer "F.Fab")
		)
		(fp_line
			(start -2.350008 2.649982)
			(end -2.350008 -2.649982)
			(stroke
				(width 0.1)
				(type default)
			)
			(layer "F.Fab")
		)
		(fp_line
			(start 2.350008 -2.649982)
			(end 2.350008 2.649982)
			(stroke
				(width 0.1)
				(type default)
			)
			(layer "F.Fab")
		)
		(fp_line
			(start 2.350008 2.649982)
			(end -2.350008 2.649982)
			(stroke
				(width 0.1)
				(type default)
			)
			(layer "F.Fab")
		)
		(fp_poly
			(pts
				(xy -3.717544 -1.905) (xy -4.758944 -2.3241) (xy -4.758944 -1.524)
			)
			(stroke
				(width 0)
				(type default)
			)
			(fill yes)
			(layer "F.Fab")
		)
		(pad "1" smd rect
			(at -2.999994 -1.905 270)
			(size 0.7112 1.1684)
			(layers "F.Cu" "F.Mask" "F.Paste")
			(net "P5V")
		)
		(pad "2" smd rect
			(at -2.999994 -0.635 270)
			(size 0.7112 1.1684)
			(layers "F.Cu" "F.Mask" "F.Paste")
			(net "P5V")
		)
		(pad "3" smd rect
			(at -2.999994 0.635 270)
			(size 0.7112 1.1684)
			(layers "F.Cu" "F.Mask" "F.Paste")
			(net "P5V")
		)
		(pad "4" smd rect
			(at -2.999994 1.905 270)
			(size 0.7112 1.1684)
			(layers "F.Cu" "F.Mask" "F.Paste")
			(net "VR_P5V_EN_D_R")
		)
		(pad "5" smd circle
			(at 0.925068 0 270)
			(size 0 0)
			(layers "F.Cu" "F.Mask" "F.Paste")
			(net "P5V_AUX")
		)
		(zone
			(layer "F.Cu")
			(hatch none 0.5)
			(connect_pads
				(clearance 0)
			)
			(min_thickness 0.25)
			(keepout
				(tracks not_allowed)
				(vias allowed)
				(pads allowed)
				(copperpour not_allowed)
				(footprints allowed)
			)
			(placement
				(enabled no)
				(sheetname "")
			)
			(fill
				(thermal_gap 0.5)
				(thermal_bridge_width 0.5)
				(island_removal_mode 0)
			)
			(polygon
				(pts
					(xy 402.086064 -149.865588) (xy 402.028914 -149.865588) (xy 402.028914 -145.547588) (xy 402.091144 -145.547588)
					(xy 402.091144 -145.064988) (xy 401.127214 -145.064988) (xy 401.127214 -150.348188) (xy 402.086064 -150.348188)
				)
			)
		)
	)
	(footprint ""
		(layer "F.Cu")
		(at 399.128742 -171.959524)
		(property "Reference" "PR358"
			(at 0 0 0)
			(layer "F.SilkS")
			(hide yes)
			(effects
				(font
					(size 1.27 1.27)
				)
			)
		)
		(property "Value" ""
			(at 0 0 0)
			(layer "F.Fab")
			(effects
				(font
					(size 1.27 1.27)
				)
			)
		)
		(duplicate_pad_numbers_are_jumpers no)
		(fp_line
			(start -0.7874 -0.4064)
			(end 0.7874 -0.4064)
			(stroke
				(width 0.1524)
				(type default)
			)
			(layer "F.SilkS")
		)
		(fp_line
			(start -0.7874 0.4064)
			(end -0.7874 -0.4064)
			(stroke
				(width 0.1524)
				(type default)
			)
			(layer "F.SilkS")
		)
		(fp_line
			(start 0.7874 -0.4064)
			(end 0.7874 0.4064)
			(stroke
				(width 0.1524)
				(type default)
			)
			(layer "F.SilkS")
		)
		(fp_line
			(start 0.7874 0.4064)
			(end -0.7874 0.4064)
			(stroke
				(width 0.1524)
				(type default)
			)
			(layer "F.SilkS")
		)
		(fp_line
			(start -0.67945 -0.305054)
			(end -0.12065 -0.305054)
			(stroke
				(width 0.1)
				(type default)
			)
			(layer "F.Fab")
		)
		(fp_line
			(start -0.67945 0.3048)
			(end -0.67945 -0.305054)
			(stroke
				(width 0.1)
				(type default)
			)
			(layer "F.Fab")
		)
		(fp_line
			(start -0.12065 -0.305054)
			(end -0.12065 -0.2794)
			(stroke
				(width 0.1)
				(type default)
			)
			(layer "F.Fab")
		)
		(fp_line
			(start -0.12065 -0.2794)
			(end 0.12065 -0.2794)
			(stroke
				(width 0.1)
				(type default)
			)
			(layer "F.Fab")
		)
		(fp_line
			(start -0.12065 0.2794)
			(end -0.12065 0.3048)
			(stroke
				(width 0.1)
				(type default)
			)
			(layer "F.Fab")
		)
		(fp_line
			(start -0.12065 0.3048)
			(end -0.67945 0.3048)
			(stroke
				(width 0.1)
				(type default)
			)
			(layer "F.Fab")
		)
		(fp_line
			(start 0.120396 0.2794)
			(end -0.12065 0.2794)
			(stroke
				(width 0.1)
				(type default)
			)
			(layer "F.Fab")
		)
		(fp_line
			(start 0.120396 0.3048)
			(end 0.120396 0.2794)
			(stroke
				(width 0.1)
				(type default)
			)
			(layer "F.Fab")
		)
		(fp_line
			(start 0.12065 -0.3048)
			(end 0.67945 -0.3048)
			(stroke
				(width 0.1)
				(type default)
			)
			(layer "F.Fab")
		)
		(fp_line
			(start 0.12065 -0.2794)
			(end 0.12065 -0.3048)
			(stroke
				(width 0.1)
				(type default)
			)
			(layer "F.Fab")
		)
		(fp_line
			(start 0.67945 -0.3048)
			(end 0.67945 0.3048)
			(stroke
				(width 0.1)
				(type default)
			)
			(layer "F.Fab")
		)
		(fp_line
			(start 0.67945 0.3048)
			(end 0.120396 0.3048)
			(stroke
				(width 0.1)
				(type default)
			)
			(layer "F.Fab")
		)
		(pad "1" smd circle
			(at -0.40005 0)
			(size 0 0)
			(layers "F.Cu" "F.Mask" "F.Paste")
			(net "GND")
		)
		(pad "2" smd circle
			(at 0.40005 0)
			(size 0 0)
			(layers "F.Cu" "F.Mask" "F.Paste")
			(net "PVDDCR_SOC_P0_LSET1")
		)
	)
	(footprint ""
		(layer "F.Cu")
		(at 116.990114 -166.711884)
		(property "Reference" "PR207"
			(at 0 0 0)
			(layer "F.SilkS")
			(hide yes)
			(effects
				(font
					(size 1.27 1.27)
				)
			)
		)
		(property "Value" ""
			(at 0 0 0)
			(layer "F.Fab")
			(effects
				(font
					(size 1.27 1.27)
				)
			)
		)
		(duplicate_pad_numbers_are_jumpers no)
		(fp_line
			(start -0.7874 -0.4064)
			(end 0.7874 -0.4064)
			(stroke
				(width 0.1524)
				(type default)
			)
			(layer "F.SilkS")
		)
		(fp_line
			(start -0.7874 0.4064)
			(end -0.7874 -0.4064)
			(stroke
				(width 0.1524)
				(type default)
			)
			(layer "F.SilkS")
		)
		(fp_line
			(start 0.7874 -0.4064)
			(end 0.7874 0.4064)
			(stroke
				(width 0.1524)
				(type default)
			)
			(layer "F.SilkS")
		)
		(fp_line
			(start 0.7874 0.4064)
			(end -0.7874 0.4064)
			(stroke
				(width 0.1524)
				(type default)
			)
			(layer "F.SilkS")
		)
		(fp_line
			(start -0.67945 -0.305054)
			(end -0.12065 -0.305054)
			(stroke
				(width 0.1)
				(type default)
			)
			(layer "F.Fab")
		)
		(fp_line
			(start -0.67945 0.3048)
			(end -0.67945 -0.305054)
			(stroke
				(width 0.1)
				(type default)
			)
			(layer "F.Fab")
		)
		(fp_line
			(start -0.12065 -0.305054)
			(end -0.12065 -0.2794)
			(stroke
				(width 0.1)
				(type default)
			)
			(layer "F.Fab")
		)
		(fp_line
			(start -0.12065 -0.2794)
			(end 0.12065 -0.2794)
			(stroke
				(width 0.1)
				(type default)
			)
			(layer "F.Fab")
		)
		(fp_line
			(start -0.12065 0.2794)
			(end -0.12065 0.3048)
			(stroke
				(width 0.1)
				(type default)
			)
			(layer "F.Fab")
		)
		(fp_line
			(start -0.12065 0.3048)
			(end -0.67945 0.3048)
			(stroke
				(width 0.1)
				(type default)
			)
			(layer "F.Fab")
		)
		(fp_line
			(start 0.120396 0.2794)
			(end -0.12065 0.2794)
			(stroke
				(width 0.1)
				(type default)
			)
			(layer "F.Fab")
		)
		(fp_line
			(start 0.120396 0.3048)
			(end 0.120396 0.2794)
			(stroke
				(width 0.1)
				(type default)
			)
			(layer "F.Fab")
		)
		(fp_line
			(start 0.12065 -0.3048)
			(end 0.67945 -0.3048)
			(stroke
				(width 0.1)
				(type default)
			)
			(layer "F.Fab")
		)
		(fp_line
			(start 0.12065 -0.2794)
			(end 0.12065 -0.3048)
			(stroke
				(width 0.1)
				(type default)
			)
			(layer "F.Fab")
		)
		(fp_line
			(start 0.67945 -0.3048)
			(end 0.67945 0.3048)
			(stroke
				(width 0.1)
				(type default)
			)
			(layer "F.Fab")
		)
		(fp_line
			(start 0.67945 0.3048)
			(end 0.120396 0.3048)
			(stroke
				(width 0.1)
				(type default)
			)
			(layer "F.Fab")
		)
		(pad "1" smd circle
			(at -0.40005 0)
			(size 0 0)
			(layers "F.Cu" "F.Mask" "F.Paste")
			(net "GND")
		)
		(pad "2" smd circle
			(at 0.40005 0)
			(size 0 0)
			(layers "F.Cu" "F.Mask" "F.Paste")
			(net "PVDDCR_SOC_P1_LSET1")
		)
	)
	(footprint ""
		(layer "F.Cu")
		(at 106.235754 -26.453592)
		(property "Reference" "R6257"
			(at 0 0 0)
			(layer "F.SilkS")
			(hide yes)
			(effects
				(font
					(size 1.27 1.27)
				)
			)
		)
		(property "Value" ""
			(at 0 0 0)
			(layer "F.Fab")
			(effects
				(font
					(size 1.27 1.27)
				)
			)
		)
		(duplicate_pad_numbers_are_jumpers no)
		(fp_line
			(start -0.7874 -0.4064)
			(end 0.7874 -0.4064)
			(stroke
				(width 0.1524)
				(type default)
			)
			(layer "F.SilkS")
		)
		(fp_line
			(start -0.7874 0.4064)
			(end -0.7874 -0.4064)
			(stroke
				(width 0.1524)
				(type default)
			)
			(layer "F.SilkS")
		)
		(fp_line
			(start 0.7874 -0.4064)
			(end 0.7874 0.4064)
			(stroke
				(width 0.1524)
				(type default)
			)
			(layer "F.SilkS")
		)
		(fp_line
			(start 0.7874 0.4064)
			(end -0.7874 0.4064)
			(stroke
				(width 0.1524)
				(type default)
			)
			(layer "F.SilkS")
		)
		(fp_line
			(start -0.67945 -0.305054)
			(end -0.12065 -0.305054)
			(stroke
				(width 0.1)
				(type default)
			)
			(layer "F.Fab")
		)
		(fp_line
			(start -0.67945 0.3048)
			(end -0.67945 -0.305054)
			(stroke
				(width 0.1)
				(type default)
			)
			(layer "F.Fab")
		)
		(fp_line
			(start -0.12065 -0.305054)
			(end -0.12065 -0.2794)
			(stroke
				(width 0.1)
				(type default)
			)
			(layer "F.Fab")
		)
		(fp_line
			(start -0.12065 -0.2794)
			(end 0.12065 -0.2794)
			(stroke
				(width 0.1)
				(type default)
			)
			(layer "F.Fab")
		)
		(fp_line
			(start -0.12065 0.2794)
			(end -0.12065 0.3048)
			(stroke
				(width 0.1)
				(type default)
			)
			(layer "F.Fab")
		)
		(fp_line
			(start -0.12065 0.3048)
			(end -0.67945 0.3048)
			(stroke
				(width 0.1)
				(type default)
			)
			(layer "F.Fab")
		)
		(fp_line
			(start 0.120396 0.2794)
			(end -0.12065 0.2794)
			(stroke
				(width 0.1)
				(type default)
			)
			(layer "F.Fab")
		)
		(fp_line
			(start 0.120396 0.3048)
			(end 0.120396 0.2794)
			(stroke
				(width 0.1)
				(type default)
			)
			(layer "F.Fab")
		)
		(fp_line
			(start 0.12065 -0.3048)
			(end 0.67945 -0.3048)
			(stroke
				(width 0.1)
				(type default)
			)
			(layer "F.Fab")
		)
		(fp_line
			(start 0.12065 -0.2794)
			(end 0.12065 -0.3048)
			(stroke
				(width 0.1)
				(type default)
			)
			(layer "F.Fab")
		)
		(fp_line
			(start 0.67945 -0.3048)
			(end 0.67945 0.3048)
			(stroke
				(width 0.1)
				(type default)
			)
			(layer "F.Fab")
		)
		(fp_line
			(start 0.67945 0.3048)
			(end 0.120396 0.3048)
			(stroke
				(width 0.1)
				(type default)
			)
			(layer "F.Fab")
		)
		(pad "1" smd circle
			(at -0.40005 0)
			(size 0 0)
			(layers "F.Cu" "F.Mask" "F.Paste")
			(net "XTAL_USB_CPU0_HUB2_XOUT")
		)
		(pad "2" smd circle
			(at 0.40005 0)
			(size 0 0)
			(layers "F.Cu" "F.Mask" "F.Paste")
			(net "XTAL_USB_CPU0_HUB2_XIN")
		)
	)
	(footprint ""
		(layer "F.Cu")
		(at 140.886942 -101.494844)
		(property "Reference" "R2121"
			(at 0 0 0)
			(layer "F.SilkS")
			(hide yes)
			(effects
				(font
					(size 1.27 1.27)
				)
			)
		)
		(property "Value" ""
			(at 0 0 0)
			(layer "F.Fab")
			(effects
				(font
					(size 1.27 1.27)
				)
			)
		)
		(duplicate_pad_numbers_are_jumpers no)
		(fp_line
			(start -0.7874 -0.4064)
			(end 0.7874 -0.4064)
			(stroke
				(width 0.1524)
				(type default)
			)
			(layer "F.SilkS")
		)
		(fp_line
			(start -0.7874 0.4064)
			(end -0.7874 -0.4064)
			(stroke
				(width 0.1524)
				(type default)
			)
			(layer "F.SilkS")
		)
		(fp_line
			(start 0.7874 -0.4064)
			(end 0.7874 0.4064)
			(stroke
				(width 0.1524)
				(type default)
			)
			(layer "F.SilkS")
		)
		(fp_line
			(start 0.7874 0.4064)
			(end -0.7874 0.4064)
			(stroke
				(width 0.1524)
				(type default)
			)
			(layer "F.SilkS")
		)
		(fp_line
			(start -0.67945 -0.305054)
			(end -0.12065 -0.305054)
			(stroke
				(width 0.1)
				(type default)
			)
			(layer "F.Fab")
		)
		(fp_line
			(start -0.67945 0.3048)
			(end -0.67945 -0.305054)
			(stroke
				(width 0.1)
				(type default)
			)
			(layer "F.Fab")
		)
		(fp_line
			(start -0.12065 -0.305054)
			(end -0.12065 -0.2794)
			(stroke
				(width 0.1)
				(type default)
			)
			(layer "F.Fab")
		)
		(fp_line
			(start -0.12065 -0.2794)
			(end 0.12065 -0.2794)
			(stroke
				(width 0.1)
				(type default)
			)
			(layer "F.Fab")
		)
		(fp_line
			(start -0.12065 0.2794)
			(end -0.12065 0.3048)
			(stroke
				(width 0.1)
				(type default)
			)
			(layer "F.Fab")
		)
		(fp_line
			(start -0.12065 0.3048)
			(end -0.67945 0.3048)
			(stroke
				(width 0.1)
				(type default)
			)
			(layer "F.Fab")
		)
		(fp_line
			(start 0.120396 0.2794)
			(end -0.12065 0.2794)
			(stroke
				(width 0.1)
				(type default)
			)
			(layer "F.Fab")
		)
		(fp_line
			(start 0.120396 0.3048)
			(end 0.120396 0.2794)
			(stroke
				(width 0.1)
				(type default)
			)
			(layer "F.Fab")
		)
		(fp_line
			(start 0.12065 -0.3048)
			(end 0.67945 -0.3048)
			(stroke
				(width 0.1)
				(type default)
			)
			(layer "F.Fab")
		)
		(fp_line
			(start 0.12065 -0.2794)
			(end 0.12065 -0.3048)
			(stroke
				(width 0.1)
				(type default)
			)
			(layer "F.Fab")
		)
		(fp_line
			(start 0.67945 -0.3048)
			(end 0.67945 0.3048)
			(stroke
				(width 0.1)
				(type default)
			)
			(layer "F.Fab")
		)
		(fp_line
			(start 0.67945 0.3048)
			(end 0.120396 0.3048)
			(stroke
				(width 0.1)
				(type default)
			)
			(layer "F.Fab")
		)
		(pad "1" smd circle
			(at -0.40005 0)
			(size 0 0)
			(layers "F.Cu" "F.Mask" "F.Paste")
			(net "P3V3_AUX")
		)
		(pad "2" smd circle
			(at 0.40005 0)
			(size 0 0)
			(layers "F.Cu" "F.Mask" "F.Paste")
			(net "RST_PERST_BUF_M2_0_N")
		)
	)
	(footprint ""
		(layer "F.Cu")
		(at 366.202214 -151.857964 -90)
		(property "Reference" "PC479"
			(at 0 0 270)
			(layer "F.SilkS")
			(hide yes)
			(effects
				(font
					(size 1.27 1.27)
				)
			)
		)
		(property "Value" ""
			(at 0 0 270)
			(layer "F.Fab")
			(effects
				(font
					(size 1.27 1.27)
				)
			)
		)
		(duplicate_pad_numbers_are_jumpers no)
		(fp_line
			(start -0.7874 0.4064)
			(end -0.7874 -0.4064)
			(stroke
				(width 0.1524)
				(type default)
			)
			(layer "F.SilkS")
		)
		(fp_line
			(start 0.7874 0.4064)
			(end -0.7874 0.4064)
			(stroke
				(width 0.1524)
				(type default)
			)
			(layer "F.SilkS")
		)
		(fp_line
			(start -0.7874 -0.4064)
			(end 0.7874 -0.4064)
			(stroke
				(width 0.1524)
				(type default)
			)
			(layer "F.SilkS")
		)
		(fp_line
			(start 0.7874 -0.4064)
			(end 0.7874 0.4064)
			(stroke
				(width 0.1524)
				(type default)
			)
			(layer "F.SilkS")
		)
		(fp_line
			(start -0.67945 0.3048)
			(end -0.67945 -0.305054)
			(stroke
				(width 0.1)
				(type default)
			)
			(layer "F.Fab")
		)
		(fp_line
			(start -0.12065 0.3048)
			(end -0.67945 0.3048)
			(stroke
				(width 0.1)
				(type default)
			)
			(layer "F.Fab")
		)
		(fp_line
			(start 0.120396 0.3048)
			(end 0.120396 0.2794)
			(stroke
				(width 0.1)
				(type default)
			)
			(layer "F.Fab")
		)
		(fp_line
			(start 0.67945 0.3048)
			(end 0.120396 0.3048)
			(stroke
				(width 0.1)
				(type default)
			)
			(layer "F.Fab")
		)
		(fp_line
			(start -0.12065 0.2794)
			(end -0.12065 0.3048)
			(stroke
				(width 0.1)
				(type default)
			)
			(layer "F.Fab")
		)
		(fp_line
			(start 0.120396 0.2794)
			(end -0.12065 0.2794)
			(stroke
				(width 0.1)
				(type default)
			)
			(layer "F.Fab")
		)
		(fp_line
			(start -0.12065 -0.2794)
			(end 0.12065 -0.2794)
			(stroke
				(width 0.1)
				(type default)
			)
			(layer "F.Fab")
		)
		(fp_line
			(start 0.12065 -0.2794)
			(end 0.12065 -0.3048)
			(stroke
				(width 0.1)
				(type default)
			)
			(layer "F.Fab")
		)
		(fp_line
			(start 0.12065 -0.3048)
			(end 0.67945 -0.3048)
			(stroke
				(width 0.1)
				(type default)
			)
			(layer "F.Fab")
		)
		(fp_line
			(start 0.67945 -0.3048)
			(end 0.67945 0.3048)
			(stroke
				(width 0.1)
				(type default)
			)
			(layer "F.Fab")
		)
		(fp_line
			(start -0.67945 -0.305054)
			(end -0.12065 -0.305054)
			(stroke
				(width 0.1)
				(type default)
			)
			(layer "F.Fab")
		)
		(fp_line
			(start -0.12065 -0.305054)
			(end -0.12065 -0.2794)
			(stroke
				(width 0.1)
				(type default)
			)
			(layer "F.Fab")
		)
		(pad "1" smd circle
			(at -0.40005 0 270)
			(size 0 0)
			(layers "F.Cu" "F.Mask" "F.Paste")
			(net "P12V_AUX")
		)
		(pad "2" smd circle
			(at 0.40005 0 270)
			(size 0 0)
			(layers "F.Cu" "F.Mask" "F.Paste")
			(net "GND")
		)
	)
	(footprint ""
		(layer "F.Cu")
		(at 362.984288 -415.729166 90)
		(property "Reference" "Q9000"
			(at -1.462278 1.708658 90)
			(unlocked yes)
			(layer "F.SilkS")
			(effects
				(font
					(size 0.7874 0.5842)
					(thickness 0.1524)
				)
				(justify left)
			)
		)
		(property "Value" ""
			(at 0 0 90)
			(layer "F.Fab")
			(effects
				(font
					(size 1.27 1.27)
				)
			)
		)
		(duplicate_pad_numbers_are_jumpers no)
		(fp_line
			(start 1.332738 -1.100074)
			(end 1.332738 1.100074)
			(stroke
				(width 0.1524)
				(type default)
			)
			(layer "F.SilkS")
		)
		(fp_line
			(start 0.4826 -1.100074)
			(end 1.332738 -1.100074)
			(stroke
				(width 0.1524)
				(type default)
			)
			(layer "F.SilkS")
		)
		(fp_line
			(start -0.4826 -1.100074)
			(end 0 -0.541274)
			(stroke
				(width 0.1524)
				(type default)
			)
			(layer "F.SilkS")
		)
		(fp_line
			(start -1.332738 -1.100074)
			(end -0.4826 -1.100074)
			(stroke
				(width 0.1524)
				(type default)
			)
			(layer "F.SilkS")
		)
		(fp_line
			(start 0 -0.541274)
			(end 0.4826 -1.100074)
			(stroke
				(width 0.1524)
				(type default)
			)
			(layer "F.SilkS")
		)
		(fp_line
			(start 1.332738 1.100074)
			(end -1.332738 1.100074)
			(stroke
				(width 0.1524)
				(type default)
			)
			(layer "F.SilkS")
		)
		(fp_line
			(start -1.332738 1.100074)
			(end -1.332738 -1.100074)
			(stroke
				(width 0.1524)
				(type default)
			)
			(layer "F.SilkS")
		)
		(fp_poly
			(pts
				(xy -2.2352 -0.298958) (xy -2.2352 -1.001014) (xy -1.533144 -0.649986)
			)
			(stroke
				(width 0)
				(type default)
			)
			(fill yes)
			(layer "F.SilkS")
		)
		(fp_line
			(start 0.674878 -1.100074)
			(end 0.674878 1.100074)
			(stroke
				(width 0.1)
				(type default)
			)
			(layer "F.Fab")
		)
		(fp_line
			(start -0.674878 -1.100074)
			(end 0.674878 -1.100074)
			(stroke
				(width 0.1)
				(type default)
			)
			(layer "F.Fab")
		)
		(fp_line
			(start 0.674878 1.100074)
			(end -0.674878 1.100074)
			(stroke
				(width 0.1)
				(type default)
			)
			(layer "F.Fab")
		)
		(fp_line
			(start -0.674878 1.100074)
			(end -0.674878 -1.100074)
			(stroke
				(width 0.1)
				(type default)
			)
			(layer "F.Fab")
		)
		(fp_poly
			(pts
				(xy -2.2352 -0.298958) (xy -2.2352 -1.001014) (xy -1.533144 -0.649986)
			)
			(stroke
				(width 0)
				(type default)
			)
			(fill yes)
			(layer "F.Fab")
		)
		(pad "1" smd rect
			(at -0.94996 -0.649986 180)
			(size 0.4318 0.508)
			(layers "F.Cu" "F.Mask" "F.Paste")
			(net "GND")
		)
		(pad "2" smd rect
			(at -0.94996 0 180)
			(size 0.4318 0.508)
			(layers "F.Cu" "F.Mask" "F.Paste")
			(net "PRSNT_CABLE_SWB_B1_N")
		)
		(pad "3" smd rect
			(at -0.94996 0.649986 180)
			(size 0.4318 0.508)
			(layers "F.Cu" "F.Mask" "F.Paste")
			(net "PRSNT_CABLE_SWB_B1_ISO_N")
		)
		(pad "4" smd rect
			(at 0.94996 0.649986 180)
			(size 0.4318 0.508)
			(layers "F.Cu" "F.Mask" "F.Paste")
			(net "GND")
		)
		(pad "5" smd rect
			(at 0.94996 0 180)
			(size 0.4318 0.508)
			(layers "F.Cu" "F.Mask" "F.Paste")
			(net "PRSNT_CABLE_SWB_B1")
		)
		(pad "6" smd rect
			(at 0.94996 -0.649986 180)
			(size 0.4318 0.508)
			(layers "F.Cu" "F.Mask" "F.Paste")
			(net "PRSNT_CABLE_SWB_B1")
		)
	)
	(footprint ""
		(layer "F.Cu")
		(at 421.54094 -101.270308 -90)
		(property "Reference" "PC2157"
			(at 0 0 270)
			(layer "F.SilkS")
			(hide yes)
			(effects
				(font
					(size 1.27 1.27)
				)
			)
		)
		(property "Value" ""
			(at 0 0 270)
			(layer "F.Fab")
			(effects
				(font
					(size 1.27 1.27)
				)
			)
		)
		(duplicate_pad_numbers_are_jumpers no)
		(fp_line
			(start -0.7874 0.4064)
			(end -0.7874 -0.4064)
			(stroke
				(width 0.1524)
				(type default)
			)
			(layer "F.SilkS")
		)
		(fp_line
			(start 0.7874 0.4064)
			(end -0.7874 0.4064)
			(stroke
				(width 0.1524)
				(type default)
			)
			(layer "F.SilkS")
		)
		(fp_line
			(start -0.7874 -0.4064)
			(end 0.7874 -0.4064)
			(stroke
				(width 0.1524)
				(type default)
			)
			(layer "F.SilkS")
		)
		(fp_line
			(start 0.7874 -0.4064)
			(end 0.7874 0.4064)
			(stroke
				(width 0.1524)
				(type default)
			)
			(layer "F.SilkS")
		)
		(fp_line
			(start -0.67945 0.3048)
			(end -0.67945 -0.305054)
			(stroke
				(width 0.1)
				(type default)
			)
			(layer "F.Fab")
		)
		(fp_line
			(start -0.12065 0.3048)
			(end -0.67945 0.3048)
			(stroke
				(width 0.1)
				(type default)
			)
			(layer "F.Fab")
		)
		(fp_line
			(start 0.120396 0.3048)
			(end 0.120396 0.2794)
			(stroke
				(width 0.1)
				(type default)
			)
			(layer "F.Fab")
		)
		(fp_line
			(start 0.67945 0.3048)
			(end 0.120396 0.3048)
			(stroke
				(width 0.1)
				(type default)
			)
			(layer "F.Fab")
		)
		(fp_line
			(start -0.12065 0.2794)
			(end -0.12065 0.3048)
			(stroke
				(width 0.1)
				(type default)
			)
			(layer "F.Fab")
		)
		(fp_line
			(start 0.120396 0.2794)
			(end -0.12065 0.2794)
			(stroke
				(width 0.1)
				(type default)
			)
			(layer "F.Fab")
		)
		(fp_line
			(start -0.12065 -0.2794)
			(end 0.12065 -0.2794)
			(stroke
				(width 0.1)
				(type default)
			)
			(layer "F.Fab")
		)
		(fp_line
			(start 0.12065 -0.2794)
			(end 0.12065 -0.3048)
			(stroke
				(width 0.1)
				(type default)
			)
			(layer "F.Fab")
		)
		(fp_line
			(start 0.12065 -0.3048)
			(end 0.67945 -0.3048)
			(stroke
				(width 0.1)
				(type default)
			)
			(layer "F.Fab")
		)
		(fp_line
			(start 0.67945 -0.3048)
			(end 0.67945 0.3048)
			(stroke
				(width 0.1)
				(type default)
			)
			(layer "F.Fab")
		)
		(fp_line
			(start -0.67945 -0.305054)
			(end -0.12065 -0.305054)
			(stroke
				(width 0.1)
				(type default)
			)
			(layer "F.Fab")
		)
		(fp_line
			(start -0.12065 -0.305054)
			(end -0.12065 -0.2794)
			(stroke
				(width 0.1)
				(type default)
			)
			(layer "F.Fab")
		)
		(pad "1" smd circle
			(at -0.40005 0 270)
			(size 0 0)
			(layers "F.Cu" "F.Mask" "F.Paste")
			(net "P3V3_OCP_MODE_1")
		)
		(pad "2" smd circle
			(at 0.40005 0 270)
			(size 0 0)
			(layers "F.Cu" "F.Mask" "F.Paste")
			(net "GND")
		)
	)
	(footprint ""
		(layer "F.Cu")
		(at 35.395662 -429.790098 90)
		(property "Reference" "R3287"
			(at 0 0 90)
			(layer "F.SilkS")
			(hide yes)
			(effects
				(font
					(size 1.27 1.27)
				)
			)
		)
		(property "Value" ""
			(at 0 0 90)
			(layer "F.Fab")
			(effects
				(font
					(size 1.27 1.27)
				)
			)
		)
		(duplicate_pad_numbers_are_jumpers no)
		(fp_line
			(start 0.7874 -0.4064)
			(end 0.7874 0.4064)
			(stroke
				(width 0.1524)
				(type default)
			)
			(layer "F.SilkS")
		)
		(fp_line
			(start -0.7874 -0.4064)
			(end 0.7874 -0.4064)
			(stroke
				(width 0.1524)
				(type default)
			)
			(layer "F.SilkS")
		)
		(fp_line
			(start 0.7874 0.4064)
			(end -0.7874 0.4064)
			(stroke
				(width 0.1524)
				(type default)
			)
			(layer "F.SilkS")
		)
		(fp_line
			(start -0.7874 0.4064)
			(end -0.7874 -0.4064)
			(stroke
				(width 0.1524)
				(type default)
			)
			(layer "F.SilkS")
		)
		(fp_line
			(start -0.12065 -0.305054)
			(end -0.12065 -0.2794)
			(stroke
				(width 0.1)
				(type default)
			)
			(layer "F.Fab")
		)
		(fp_line
			(start -0.67945 -0.305054)
			(end -0.12065 -0.305054)
			(stroke
				(width 0.1)
				(type default)
			)
			(layer "F.Fab")
		)
		(fp_line
			(start 0.67945 -0.3048)
			(end 0.67945 0.3048)
			(stroke
				(width 0.1)
				(type default)
			)
			(layer "F.Fab")
		)
		(fp_line
			(start 0.12065 -0.3048)
			(end 0.67945 -0.3048)
			(stroke
				(width 0.1)
				(type default)
			)
			(layer "F.Fab")
		)
		(fp_line
			(start 0.12065 -0.2794)
			(end 0.12065 -0.3048)
			(stroke
				(width 0.1)
				(type default)
			)
			(layer "F.Fab")
		)
		(fp_line
			(start -0.12065 -0.2794)
			(end 0.12065 -0.2794)
			(stroke
				(width 0.1)
				(type default)
			)
			(layer "F.Fab")
		)
		(fp_line
			(start 0.120396 0.2794)
			(end -0.12065 0.2794)
			(stroke
				(width 0.1)
				(type default)
			)
			(layer "F.Fab")
		)
		(fp_line
			(start -0.12065 0.2794)
			(end -0.12065 0.3048)
			(stroke
				(width 0.1)
				(type default)
			)
			(layer "F.Fab")
		)
		(fp_line
			(start 0.67945 0.3048)
			(end 0.120396 0.3048)
			(stroke
				(width 0.1)
				(type default)
			)
			(layer "F.Fab")
		)
		(fp_line
			(start 0.120396 0.3048)
			(end 0.120396 0.2794)
			(stroke
				(width 0.1)
				(type default)
			)
			(layer "F.Fab")
		)
		(fp_line
			(start -0.12065 0.3048)
			(end -0.67945 0.3048)
			(stroke
				(width 0.1)
				(type default)
			)
			(layer "F.Fab")
		)
		(fp_line
			(start -0.67945 0.3048)
			(end -0.67945 -0.305054)
			(stroke
				(width 0.1)
				(type default)
			)
			(layer "F.Fab")
		)
		(pad "1" smd circle
			(at -0.40005 0 90)
			(size 0 0)
			(layers "F.Cu" "F.Mask" "F.Paste")
			(net "FM_P2E_SWB")
		)
		(pad "2" smd circle
			(at 0.40005 0 90)
			(size 0 0)
			(layers "F.Cu" "F.Mask" "F.Paste")
			(net "GND")
		)
	)
	(footprint ""
		(layer "F.Cu")
		(at 154.633676 -48.961294 -90)
		(property "Reference" "R3590"
			(at 0 0 270)
			(layer "F.SilkS")
			(hide yes)
			(effects
				(font
					(size 1.27 1.27)
				)
			)
		)
		(property "Value" ""
			(at 0 0 270)
			(layer "F.Fab")
			(effects
				(font
					(size 1.27 1.27)
				)
			)
		)
		(duplicate_pad_numbers_are_jumpers no)
		(fp_line
			(start -0.7874 0.4064)
			(end -0.7874 -0.4064)
			(stroke
				(width 0.1524)
				(type default)
			)
			(layer "F.SilkS")
		)
		(fp_line
			(start 0.7874 0.4064)
			(end -0.7874 0.4064)
			(stroke
				(width 0.1524)
				(type default)
			)
			(layer "F.SilkS")
		)
		(fp_line
			(start -0.7874 -0.4064)
			(end 0.7874 -0.4064)
			(stroke
				(width 0.1524)
				(type default)
			)
			(layer "F.SilkS")
		)
		(fp_line
			(start 0.7874 -0.4064)
			(end 0.7874 0.4064)
			(stroke
				(width 0.1524)
				(type default)
			)
			(layer "F.SilkS")
		)
		(fp_line
			(start -0.67945 0.3048)
			(end -0.67945 -0.305054)
			(stroke
				(width 0.1)
				(type default)
			)
			(layer "F.Fab")
		)
		(fp_line
			(start -0.12065 0.3048)
			(end -0.67945 0.3048)
			(stroke
				(width 0.1)
				(type default)
			)
			(layer "F.Fab")
		)
		(fp_line
			(start 0.120396 0.3048)
			(end 0.120396 0.2794)
			(stroke
				(width 0.1)
				(type default)
			)
			(layer "F.Fab")
		)
		(fp_line
			(start 0.67945 0.3048)
			(end 0.120396 0.3048)
			(stroke
				(width 0.1)
				(type default)
			)
			(layer "F.Fab")
		)
		(fp_line
			(start -0.12065 0.2794)
			(end -0.12065 0.3048)
			(stroke
				(width 0.1)
				(type default)
			)
			(layer "F.Fab")
		)
		(fp_line
			(start 0.120396 0.2794)
			(end -0.12065 0.2794)
			(stroke
				(width 0.1)
				(type default)
			)
			(layer "F.Fab")
		)
		(fp_line
			(start -0.12065 -0.2794)
			(end 0.12065 -0.2794)
			(stroke
				(width 0.1)
				(type default)
			)
			(layer "F.Fab")
		)
		(fp_line
			(start 0.12065 -0.2794)
			(end 0.12065 -0.3048)
			(stroke
				(width 0.1)
				(type default)
			)
			(layer "F.Fab")
		)
		(fp_line
			(start 0.12065 -0.3048)
			(end 0.67945 -0.3048)
			(stroke
				(width 0.1)
				(type default)
			)
			(layer "F.Fab")
		)
		(fp_line
			(start 0.67945 -0.3048)
			(end 0.67945 0.3048)
			(stroke
				(width 0.1)
				(type default)
			)
			(layer "F.Fab")
		)
		(fp_line
			(start -0.67945 -0.305054)
			(end -0.12065 -0.305054)
			(stroke
				(width 0.1)
				(type default)
			)
			(layer "F.Fab")
		)
		(fp_line
			(start -0.12065 -0.305054)
			(end -0.12065 -0.2794)
			(stroke
				(width 0.1)
				(type default)
			)
			(layer "F.Fab")
		)
		(pad "1" smd circle
			(at -0.40005 0 270)
			(size 0 0)
			(layers "F.Cu" "F.Mask" "F.Paste")
			(net "SMB_INA230_3V3AUX_SCL")
		)
		(pad "2" smd circle
			(at 0.40005 0 270)
			(size 0 0)
			(layers "F.Cu" "F.Mask" "F.Paste")
			(net "SMB_INA230_3_3V3AUX_SCL_R")
		)
	)
	(footprint ""
		(layer "F.Cu")
		(at 18.076672 -396.076678 180)
		(property "Reference" "PC6638_2"
			(at 0 0 180)
			(layer "F.SilkS")
			(hide yes)
			(effects
				(font
					(size 1.27 1.27)
				)
			)
		)
		(property "Value" ""
			(at 0 0 180)
			(layer "F.Fab")
			(effects
				(font
					(size 1.27 1.27)
				)
			)
		)
		(duplicate_pad_numbers_are_jumpers no)
		(fp_line
			(start 1.524 0.762)
			(end -1.524 0.762)
			(stroke
				(width 0.1524)
				(type default)
			)
			(layer "F.SilkS")
		)
		(fp_line
			(start 1.524 -0.762)
			(end 1.524 0.762)
			(stroke
				(width 0.1524)
				(type default)
			)
			(layer "F.SilkS")
		)
		(fp_line
			(start -1.524 0.762)
			(end -1.524 -0.762)
			(stroke
				(width 0.1524)
				(type default)
			)
			(layer "F.SilkS")
		)
		(fp_line
			(start -1.524 -0.762)
			(end 1.524 -0.762)
			(stroke
				(width 0.1524)
				(type default)
			)
			(layer "F.SilkS")
		)
		(fp_line
			(start 1.1049 0.724916)
			(end 1.1049 -0.724916)
			(stroke
				(width 0.1)
				(type default)
			)
			(layer "F.Fab")
		)
		(fp_line
			(start 1.1049 -0.724916)
			(end -1.1049 -0.724916)
			(stroke
				(width 0.1)
				(type default)
			)
			(layer "F.Fab")
		)
		(fp_line
			(start -1.1049 0.724916)
			(end 1.1049 0.724916)
			(stroke
				(width 0.1)
				(type default)
			)
			(layer "F.Fab")
		)
		(fp_line
			(start -1.1049 -0.724916)
			(end -1.1049 0.724916)
			(stroke
				(width 0.1)
				(type default)
			)
			(layer "F.Fab")
		)
		(pad "1" smd rect
			(at -0.889 0)
			(size 1.016 1.27)
			(layers "F.Cu" "F.Mask" "F.Paste")
			(net "SW_P12V_AUX_P0V9_RETIMER_CPU1_FLT")
		)
		(pad "2" smd rect
			(at 0.889 0)
			(size 1.016 1.27)
			(layers "F.Cu" "F.Mask" "F.Paste")
			(net "GND")
		)
	)
	(footprint ""
		(layer "F.Cu")
		(at 381.077978 -182.786528 180)
		(property "Reference" "PU46"
			(at 1.867916 -7.072122 0)
			(unlocked yes)
			(layer "F.SilkS")
			(effects
				(font
					(size 0.7874 0.5842)
					(thickness 0.1524)
				)
				(justify left)
			)
		)
		(property "Value" ""
			(at 0 0 180)
			(layer "F.Fab")
			(effects
				(font
					(size 1.27 1.27)
				)
			)
		)
		(duplicate_pad_numbers_are_jumpers no)
		(fp_line
			(start 2.500122 2.999994)
			(end 2.2987 2.999994)
			(stroke
				(width 0.1524)
				(type default)
			)
			(layer "F.SilkS")
		)
		(fp_line
			(start 2.500122 2.339594)
			(end 2.500122 2.999994)
			(stroke
				(width 0.1524)
				(type default)
			)
			(layer "F.SilkS")
		)
		(fp_line
			(start 2.500122 -2.999994)
			(end 2.500122 -2.44348)
			(stroke
				(width 0.1524)
				(type default)
			)
			(layer "F.SilkS")
		)
		(fp_line
			(start 2.31394 -2.999994)
			(end 2.500122 -2.999994)
			(stroke
				(width 0.1524)
				(type default)
			)
			(layer "F.SilkS")
		)
		(fp_line
			(start -2.2987 2.999994)
			(end -2.500122 2.999994)
			(stroke
				(width 0.1524)
				(type default)
			)
			(layer "F.SilkS")
		)
		(fp_line
			(start -2.500122 2.999994)
			(end -2.500122 2.339594)
			(stroke
				(width 0.1524)
				(type default)
			)
			(layer "F.SilkS")
		)
		(fp_line
			(start -2.500122 0.6604)
			(end -2.500122 0.229108)
			(stroke
				(width 0.1524)
				(type default)
			)
			(layer "F.SilkS")
		)
		(fp_line
			(start -2.500122 -2.529078)
			(end -2.500122 -2.999994)
			(stroke
				(width 0.1524)
				(type default)
			)
			(layer "F.SilkS")
		)
		(fp_line
			(start -2.500122 -2.999994)
			(end -2.24409 -2.999994)
			(stroke
				(width 0.1524)
				(type default)
			)
			(layer "F.SilkS")
		)
		(fp_poly
			(pts
				(xy -2.788666 -2.483612) (xy -3.45948 -2.707386) (xy -3.01244 -3.154426)
			)
			(stroke
				(width 0)
				(type default)
			)
			(fill yes)
			(layer "F.SilkS")
		)
		(fp_line
			(start 2.500122 2.999994)
			(end -2.500122 2.999994)
			(stroke
				(width 0.1)
				(type default)
			)
			(layer "F.Fab")
		)
		(fp_line
			(start 2.500122 -2.999994)
			(end 2.500122 2.999994)
			(stroke
				(width 0.1)
				(type default)
			)
			(layer "F.Fab")
		)
		(fp_line
			(start -2.500122 2.999994)
			(end -2.500122 -2.999994)
			(stroke
				(width 0.1)
				(type default)
			)
			(layer "F.Fab")
		)
		(fp_line
			(start -2.500122 -2.999994)
			(end 2.500122 -2.999994)
			(stroke
				(width 0.1)
				(type default)
			)
			(layer "F.Fab")
		)
		(fp_poly
			(pts
				(xy -4.218432 -2.783078) (xy -4.218432 -1.767078) (xy -3.202432 -2.275078)
			)
			(stroke
				(width 0)
				(type default)
			)
			(fill yes)
			(layer "F.Fab")
		)
		(pad "1" smd rect
			(at -2.400046 -2.275078 270)
			(size 0.2286 0.6096)
			(layers "F.Cu" "F.Mask" "F.Paste")
			(net "PVDDCR_CPU0_P0_VOS3")
		)
		(pad "2" smd rect
			(at -2.400046 -1.82499 270)
			(size 0.2286 0.6096)
			(layers "F.Cu" "F.Mask" "F.Paste")
			(net "GND")
		)
		(pad "3" smd rect
			(at -2.400046 -1.374902 270)
			(size 0.2286 0.6096)
			(layers "F.Cu" "F.Mask" "F.Paste")
			(net "PVDDCR_CPU0_P0_VCC3")
		)
		(pad "4" smd rect
			(at -2.400046 -0.925068 270)
			(size 0.2286 0.6096)
			(layers "F.Cu" "F.Mask" "F.Paste")
			(net "PVDDCR_CPU0_P0_PVCC")
		)
		(pad "5" smd rect
			(at -2.400046 -0.47498 270)
			(size 0.2286 0.6096)
			(layers "F.Cu" "F.Mask" "F.Paste")
			(net "GND")
		)
		(pad "6" smd rect
			(at -2.400046 -0.024892 270)
			(size 0.2286 0.6096)
			(layers "F.Cu" "F.Mask" "F.Paste")
			(net "NC_PVDDCR_CPU0_P0_GL1_3")
		)
		(pad "7_9-20_24" smd circle
			(at 0 1.150112 270)
			(size 0 0)
			(layers "F.Cu" "F.Mask" "F.Paste")
			(net "GND")
		)
		(pad "10_19" smd rect
			(at 0 2.899918 270)
			(size 0.6096 4.318)
			(layers "F.Cu" "F.Mask" "F.Paste")
			(net "SW_PVDDCR_CPU0_P0_SW3")
		)
		(pad "25_29" smd rect
			(at 1.549908 -1.279906 90)
			(size 2.0574 2.3114)
			(layers "F.Cu" "F.Mask" "F.Paste")
			(net "SW_P12V_AUX_PVDDCR_CPU0_P0_FLT")
		)
		(pad "30" smd rect
			(at 2.05994 -2.899918 180)
			(size 0.2286 0.6096)
			(layers "F.Cu" "F.Mask" "F.Paste")
			(net "SW_P12V_AUX_PVDDCR_CPU0_P0_FLT")
		)
		(pad "31" smd rect
			(at 1.610106 -2.899918 180)
			(size 0.2286 0.6096)
			(layers "F.Cu" "F.Mask" "F.Paste")
			(net "NC_PVDDCR_CPU0_P0_DNC3")
		)
		(pad "32" smd rect
			(at 1.160018 -2.899918 180)
			(size 0.2286 0.6096)
			(layers "F.Cu" "F.Mask" "F.Paste")
			(net "SW_PVDDCR_CPU0_P0_PH3")
		)
		(pad "33" smd rect
			(at 0.70993 -2.899918 180)
			(size 0.2286 0.6096)
			(layers "F.Cu" "F.Mask" "F.Paste")
			(net "SW_PVDDCR_CPU0_P0_BOOT3")
		)
		(pad "34" smd rect
			(at 0.260096 -2.899918 180)
			(size 0.2286 0.6096)
			(layers "F.Cu" "F.Mask" "F.Paste")
			(net "PVDDCR_CPU0_P0_PWM3")
		)
		(pad "35" smd rect
			(at -0.189992 -2.899918 180)
			(size 0.2286 0.6096)
			(layers "F.Cu" "F.Mask" "F.Paste")
			(net "PVDDCR_CPU0_P0_VCC3")
		)
		(pad "36" smd rect
			(at -0.64008 -2.899918 180)
			(size 0.2286 0.6096)
			(layers "F.Cu" "F.Mask" "F.Paste")
			(net "PVDDCR_CPU0_P0_TEMP0")
		)
		(pad "37" smd rect
			(at -1.089914 -2.899918 180)
			(size 0.2286 0.6096)
			(layers "F.Cu" "F.Mask" "F.Paste")
			(net "PVDDCR_CPU0_P0_LSET3")
		)
		(pad "38" smd rect
			(at -1.540002 -2.899918 180)
			(size 0.2286 0.6096)
			(layers "F.Cu" "F.Mask" "F.Paste")
			(net "PVDDCR_CPU0_P0_IMON3")
		)
		(pad "39" smd rect
			(at -1.99009 -2.899918 180)
			(size 0.2286 0.6096)
			(layers "F.Cu" "F.Mask" "F.Paste")
			(net "PVDDCR_CPU0_P0_VCCS")
		)
		(pad "40" smd rect
			(at -0.87503 -1.27508 180)
			(size 1.7526 1.9558)
			(layers "F.Cu" "F.Mask" "F.Paste")
			(net "GND")
		)
		(pad "41" smd rect
			(at -1.525016 0.249936 90)
			(size 0.3048 0.4572)
			(layers "F.Cu" "F.Mask" "F.Paste")
			(net "NC_PVDDCR_CPU0_P0_GL2_3")
		)
		(zone
			(layer "F.Cu")
			(hatch none 0.5)
			(connect_pads
				(clearance 0)
			)
			(min_thickness 0.25)
			(keepout
				(tracks not_allowed)
				(vias allowed)
				(pads allowed)
				(copperpour not_allowed)
				(footprints allowed)
			)
			(placement
				(enabled no)
				(sheetname "")
			)
			(fill
				(thermal_gap 0.5)
				(thermal_bridge_width 0.5)
				(island_removal_mode 0)
			)
			(polygon
				(pts
					(xy 383.5781 -185.334402) (xy 383.5781 -185.037222) (xy 378.577856 -185.037222) (xy 378.577856 -185.33491)
					(xy 378.868178 -185.33491) (xy 378.868178 -185.330846) (xy 383.287778 -185.330846) (xy 383.287778 -185.334402)
				)
			)
		)
		(zone
			(layer "F.Cu")
			(hatch none 0.5)
			(connect_pads
				(clearance 0)
			)
			(min_thickness 0.25)
			(keepout
				(tracks not_allowed)
				(vias allowed)
				(pads allowed)
				(copperpour not_allowed)
				(footprints allowed)
			)
			(placement
				(enabled no)
				(sheetname "")
			)
			(fill
				(thermal_gap 0.5)
				(thermal_bridge_width 0.5)
				(island_removal_mode 0)
			)
			(polygon
				(pts
					(xy 381.025908 -182.53456) (xy 381.025908 -180.482748) (xy 382.880108 -180.482748) (xy 382.880108 -180.723794)
					(xy 383.122424 -180.723794) (xy 383.122424 -180.24221) (xy 379.244098 -180.24221) (xy 379.244098 -180.427122)
					(xy 380.73457 -180.427122) (xy 380.73457 -182.586122) (xy 378.577856 -182.586122) (xy 378.577856 -182.835804)
					(xy 380.724664 -182.835804)
				)
			)
		)
	)
	(footprint ""
		(layer "F.Cu")
		(at 253.86157 -51.382422 180)
		(property "Reference" "PU292"
			(at -1.008634 -4.773422 0)
			(unlocked yes)
			(layer "F.SilkS")
			(effects
				(font
					(size 0.7874 0.5842)
					(thickness 0.1524)
				)
				(justify left)
			)
		)
		(property "Value" ""
			(at 0 0 180)
			(layer "F.Fab")
			(effects
				(font
					(size 1.27 1.27)
				)
			)
		)
		(duplicate_pad_numbers_are_jumpers no)
		(fp_line
			(start 1.549908 2.549906)
			(end 1.549908 2.253996)
			(stroke
				(width 0.1524)
				(type default)
			)
			(layer "F.SilkS")
		)
		(fp_line
			(start 1.549908 -2.253996)
			(end 1.549908 -2.549906)
			(stroke
				(width 0.1524)
				(type default)
			)
			(layer "F.SilkS")
		)
		(fp_line
			(start 1.549908 -2.549906)
			(end 0.752094 -2.549906)
			(stroke
				(width 0.1524)
				(type default)
			)
			(layer "F.SilkS")
		)
		(fp_line
			(start 0.753872 2.549906)
			(end 1.549908 2.549906)
			(stroke
				(width 0.1524)
				(type default)
			)
			(layer "F.SilkS")
		)
		(fp_line
			(start 0.2413 -2.549906)
			(end -0.2413 -2.549906)
			(stroke
				(width 0.1524)
				(type default)
			)
			(layer "F.SilkS")
		)
		(fp_line
			(start -0.245872 2.549906)
			(end 0.245872 2.549906)
			(stroke
				(width 0.1524)
				(type default)
			)
			(layer "F.SilkS")
		)
		(fp_line
			(start -0.752094 -2.549906)
			(end -1.549908 -2.549906)
			(stroke
				(width 0.1524)
				(type default)
			)
			(layer "F.SilkS")
		)
		(fp_line
			(start -1.549908 2.549906)
			(end -0.753872 2.549906)
			(stroke
				(width 0.1524)
				(type default)
			)
			(layer "F.SilkS")
		)
		(fp_line
			(start -1.549908 2.253996)
			(end -1.549908 2.549906)
			(stroke
				(width 0.1524)
				(type default)
			)
			(layer "F.SilkS")
		)
		(fp_line
			(start -1.549908 -2.549906)
			(end -1.549908 -2.251964)
			(stroke
				(width 0.1524)
				(type default)
			)
			(layer "F.SilkS")
		)
		(fp_poly
			(pts
				(xy -2.18694 -3.538982) (xy -2.02057 -2.601722) (xy -2.8702 -3.031236)
			)
			(stroke
				(width 0)
				(type default)
			)
			(fill yes)
			(layer "F.SilkS")
		)
		(fp_line
			(start 1.549908 2.549906)
			(end 1.549908 -2.549906)
			(stroke
				(width 0.1)
				(type default)
			)
			(layer "F.Fab")
		)
		(fp_line
			(start 1.549908 -2.549906)
			(end -1.549908 -2.549906)
			(stroke
				(width 0.1)
				(type default)
			)
			(layer "F.Fab")
		)
		(fp_line
			(start -1.549908 2.549906)
			(end 1.549908 2.549906)
			(stroke
				(width 0.1)
				(type default)
			)
			(layer "F.Fab")
		)
		(fp_line
			(start -1.549908 -2.549906)
			(end -1.549908 2.549906)
			(stroke
				(width 0.1)
				(type default)
			)
			(layer "F.Fab")
		)
		(fp_poly
			(pts
				(xy -1.891538 -1.999996) (xy -2.7432 -1.574292) (xy -2.7432 -2.4257)
			)
			(stroke
				(width 0)
				(type default)
			)
			(fill yes)
			(layer "F.Fab")
		)
		(fp_text user "12"
			(at 3.551428 5.08762 90)
			(unlocked yes)
			(layer "F.SilkS")
			(effects
				(font
					(size 0.635 0.4064)
					(thickness 0.1524)
				)
			)
		)
		(fp_text user "11"
			(at 2.3241 5.249672 180)
			(unlocked yes)
			(layer "F.SilkS")
			(effects
				(font
					(size 0.635 0.4064)
					(thickness 0.1524)
				)
			)
		)
		(fp_text user "20"
			(at 2.141728 -3.6449 90)
			(unlocked yes)
			(layer "F.SilkS")
			(effects
				(font
					(size 0.635 0.4064)
					(thickness 0.1524)
				)
			)
		)
		(fp_text user "21_22"
			(at -0.0762 -3.401568 180)
			(unlocked yes)
			(layer "F.SilkS")
			(effects
				(font
					(size 0.635 0.4064)
					(thickness 0.1524)
				)
			)
		)
		(fp_text user "10"
			(at -1.46558 5.945632 180)
			(unlocked yes)
			(layer "F.SilkS")
			(effects
				(font
					(size 0.635 0.4064)
					(thickness 0.1524)
				)
			)
		)
		(fp_text user "9"
			(at -2.51587 2.156206 90)
			(unlocked yes)
			(layer "F.SilkS")
			(effects
				(font
					(size 0.635 0.4064)
					(thickness 0.1524)
				)
			)
		)
		(fp_text user "12"
			(at 2.207768 2.7178 90)
			(unlocked yes)
			(layer "F.Fab")
			(effects
				(font
					(size 0.635 0.4064)
					(thickness 0.1524)
				)
			)
		)
		(fp_text user "20"
			(at 2.055368 -2.7686 90)
			(unlocked yes)
			(layer "F.Fab")
			(effects
				(font
					(size 0.635 0.4064)
					(thickness 0.1524)
				)
			)
		)
		(fp_text user "11"
			(at 1.1938 3.329432 180)
			(unlocked yes)
			(layer "F.Fab")
			(effects
				(font
					(size 0.635 0.4064)
					(thickness 0.1524)
				)
			)
		)
		(fp_text user "21_22"
			(at -0.0762 -3.401568 180)
			(unlocked yes)
			(layer "F.Fab")
			(effects
				(font
					(size 0.635 0.4064)
					(thickness 0.1524)
				)
			)
		)
		(fp_text user "10"
			(at -1.4224 3.253232 180)
			(unlocked yes)
			(layer "F.Fab")
			(effects
				(font
					(size 0.635 0.4064)
					(thickness 0.1524)
				)
			)
		)
		(fp_text user "9"
			(at -2.338832 2.5908 90)
			(unlocked yes)
			(layer "F.Fab")
			(effects
				(font
					(size 0.635 0.4064)
					(thickness 0.1524)
				)
			)
		)
		(pad "1" smd circle
			(at -1.374902 -1.999996 90)
			(size 0 0)
			(layers "F.Cu" "F.Mask" "F.Paste")
			(net "P12V_E1S_EN_0_R2")
		)
		(pad "2" smd rect
			(at -1.400048 -1.500124 90)
			(size 0.254 0.8128)
			(layers "F.Cu" "F.Mask" "F.Paste")
			(net "GND")
		)
		(pad "3" smd rect
			(at -1.400048 -0.999998 90)
			(size 0.254 0.8128)
			(layers "F.Cu" "F.Mask" "F.Paste")
			(net "GND")
		)
		(pad "4" smd rect
			(at -1.400048 -0.499872 90)
			(size 0.254 0.8128)
			(layers "F.Cu" "F.Mask" "F.Paste")
			(net "P12V_E1S_TIMER_0")
		)
		(pad "5" smd rect
			(at -1.400048 0 90)
			(size 0.254 0.8128)
			(layers "F.Cu" "F.Mask" "F.Paste")
			(net "P12V_E1S_ISET_0")
		)
		(pad "6" smd rect
			(at -1.400048 0.499872 90)
			(size 0.254 0.8128)
			(layers "F.Cu" "F.Mask" "F.Paste")
			(net "P12V_E1S_SS_0")
		)
		(pad "7" smd rect
			(at -1.400048 0.999998 90)
			(size 0.254 0.8128)
			(layers "F.Cu" "F.Mask" "F.Paste")
			(net "GND")
		)
		(pad "8" smd rect
			(at -1.400048 1.500124 90)
			(size 0.254 0.8128)
			(layers "F.Cu" "F.Mask" "F.Paste")
			(net "P12V_E1S_IMON_0")
		)
		(pad "9" smd rect
			(at -1.400048 1.999996 90)
			(size 0.254 0.8128)
			(layers "F.Cu" "F.Mask" "F.Paste")
			(net "P12V_E1S_FLTB_0")
		)
		(pad "10" smd rect
			(at -0.499872 2.400046 180)
			(size 0.254 0.8128)
			(layers "F.Cu" "F.Mask" "F.Paste")
			(net "HP_LVC3_E1S_0_HSC_PWRGD")
		)
		(pad "11" smd rect
			(at 0.499872 2.400046 180)
			(size 0.254 0.8128)
			(layers "F.Cu" "F.Mask" "F.Paste")
			(net "P12V_E1S_OV_FB_0")
		)
		(pad "12" smd rect
			(at 1.400048 1.999996 90)
			(size 0.254 0.8128)
			(layers "F.Cu" "F.Mask" "F.Paste")
			(net "P12V_E1S_AVIN_PD_0")
		)
		(pad "13" smd rect
			(at 1.400048 1.500124 90)
			(size 0.254 0.8128)
			(layers "F.Cu" "F.Mask" "F.Paste")
			(net "P12V_E1S_0")
		)
		(pad "14" smd rect
			(at 1.400048 0.999998 90)
			(size 0.254 0.8128)
			(layers "F.Cu" "F.Mask" "F.Paste")
			(net "P12V_E1S_0")
		)
		(pad "15" smd rect
			(at 1.400048 0.499872 90)
			(size 0.254 0.8128)
			(layers "F.Cu" "F.Mask" "F.Paste")
			(net "P12V_E1S_0")
		)
		(pad "16" smd rect
			(at 1.400048 0 90)
			(size 0.254 0.8128)
			(layers "F.Cu" "F.Mask" "F.Paste")
			(net "P12V_E1S_0")
		)
		(pad "17" smd rect
			(at 1.400048 -0.499872 90)
			(size 0.254 0.8128)
			(layers "F.Cu" "F.Mask" "F.Paste")
			(net "P12V_E1S_0")
		)
		(pad "18" smd rect
			(at 1.400048 -0.999998 90)
			(size 0.254 0.8128)
			(layers "F.Cu" "F.Mask" "F.Paste")
			(net "P12V_E1S_0")
		)
		(pad "19" smd rect
			(at 1.400048 -1.500124 90)
			(size 0.254 0.8128)
			(layers "F.Cu" "F.Mask" "F.Paste")
			(net "P12V_E1S_0")
		)
		(pad "20" smd rect
			(at 1.400048 -1.999996 90)
			(size 0.254 0.8128)
			(layers "F.Cu" "F.Mask" "F.Paste")
			(net "P12V_E1S_0")
		)
		(pad "21_22" smd circle
			(at 0.499872 -2.337562 90)
			(size 0 0)
			(layers "F.Cu" "F.Mask" "F.Paste")
			(net "P12V_AUX")
		)
		(pad "23" smd rect
			(at 0 -1.100074 90)
			(size 0.254 1.27)
			(layers "F.Cu" "F.Mask" "F.Paste")
			(net "P12V_AUX")
		)
		(pad "24" smd rect
			(at 0 -0.199898 90)
			(size 0.254 1.27)
			(layers "F.Cu" "F.Mask" "F.Paste")
			(net "P12V_AUX")
		)
		(pad "25" smd rect
			(at 0 0.700024 90)
			(size 0.254 1.27)
			(layers "F.Cu" "F.Mask" "F.Paste")
			(net "P12V_AUX")
		)
		(pad "26" smd rect
			(at 0 1.599946 90)
			(size 0.254 1.27)
			(layers "F.Cu" "F.Mask" "F.Paste")
			(net "P12V_AUX")
		)
	)
	(footprint ""
		(layer "F.Cu")
		(at 442.828172 -33.062418 90)
		(property "Reference" "PR3835"
			(at 0 0 90)
			(layer "F.SilkS")
			(hide yes)
			(effects
				(font
					(size 1.27 1.27)
				)
			)
		)
		(property "Value" ""
			(at 0 0 90)
			(layer "F.Fab")
			(effects
				(font
					(size 1.27 1.27)
				)
			)
		)
		(duplicate_pad_numbers_are_jumpers no)
		(fp_line
			(start 0.7874 -0.4064)
			(end 0.7874 0.4064)
			(stroke
				(width 0.1524)
				(type default)
			)
			(layer "F.SilkS")
		)
		(fp_line
			(start -0.7874 -0.4064)
			(end 0.7874 -0.4064)
			(stroke
				(width 0.1524)
				(type default)
			)
			(layer "F.SilkS")
		)
		(fp_line
			(start 0.7874 0.4064)
			(end -0.7874 0.4064)
			(stroke
				(width 0.1524)
				(type default)
			)
			(layer "F.SilkS")
		)
		(fp_line
			(start -0.7874 0.4064)
			(end -0.7874 -0.4064)
			(stroke
				(width 0.1524)
				(type default)
			)
			(layer "F.SilkS")
		)
		(fp_line
			(start -0.12065 -0.305054)
			(end -0.12065 -0.2794)
			(stroke
				(width 0.1)
				(type default)
			)
			(layer "F.Fab")
		)
		(fp_line
			(start -0.67945 -0.305054)
			(end -0.12065 -0.305054)
			(stroke
				(width 0.1)
				(type default)
			)
			(layer "F.Fab")
		)
		(fp_line
			(start 0.67945 -0.3048)
			(end 0.67945 0.3048)
			(stroke
				(width 0.1)
				(type default)
			)
			(layer "F.Fab")
		)
		(fp_line
			(start 0.12065 -0.3048)
			(end 0.67945 -0.3048)
			(stroke
				(width 0.1)
				(type default)
			)
			(layer "F.Fab")
		)
		(fp_line
			(start 0.12065 -0.2794)
			(end 0.12065 -0.3048)
			(stroke
				(width 0.1)
				(type default)
			)
			(layer "F.Fab")
		)
		(fp_line
			(start -0.12065 -0.2794)
			(end 0.12065 -0.2794)
			(stroke
				(width 0.1)
				(type default)
			)
			(layer "F.Fab")
		)
		(fp_line
			(start 0.120396 0.2794)
			(end -0.12065 0.2794)
			(stroke
				(width 0.1)
				(type default)
			)
			(layer "F.Fab")
		)
		(fp_line
			(start -0.12065 0.2794)
			(end -0.12065 0.3048)
			(stroke
				(width 0.1)
				(type default)
			)
			(layer "F.Fab")
		)
		(fp_line
			(start 0.67945 0.3048)
			(end 0.120396 0.3048)
			(stroke
				(width 0.1)
				(type default)
			)
			(layer "F.Fab")
		)
		(fp_line
			(start 0.120396 0.3048)
			(end 0.120396 0.2794)
			(stroke
				(width 0.1)
				(type default)
			)
			(layer "F.Fab")
		)
		(fp_line
			(start -0.12065 0.3048)
			(end -0.67945 0.3048)
			(stroke
				(width 0.1)
				(type default)
			)
			(layer "F.Fab")
		)
		(fp_line
			(start -0.67945 0.3048)
			(end -0.67945 -0.305054)
			(stroke
				(width 0.1)
				(type default)
			)
			(layer "F.Fab")
		)
		(pad "1" smd circle
			(at -0.40005 0 90)
			(size 0 0)
			(layers "F.Cu" "F.Mask" "F.Paste")
			(net "P12V_OCP_ISET_1")
		)
		(pad "2" smd circle
			(at 0.40005 0 90)
			(size 0 0)
			(layers "F.Cu" "F.Mask" "F.Paste")
			(net "GND")
		)
	)
	(footprint ""
		(layer "F.Cu")
		(at 105.537 -421.005)
		(property "Reference" "R3461"
			(at 0 0 0)
			(layer "F.SilkS")
			(hide yes)
			(effects
				(font
					(size 1.27 1.27)
				)
			)
		)
		(property "Value" ""
			(at 0 0 0)
			(layer "F.Fab")
			(effects
				(font
					(size 1.27 1.27)
				)
			)
		)
		(duplicate_pad_numbers_are_jumpers no)
		(fp_line
			(start -0.7874 -0.4064)
			(end 0.7874 -0.4064)
			(stroke
				(width 0.1524)
				(type default)
			)
			(layer "F.SilkS")
		)
		(fp_line
			(start -0.7874 0.4064)
			(end -0.7874 -0.4064)
			(stroke
				(width 0.1524)
				(type default)
			)
			(layer "F.SilkS")
		)
		(fp_line
			(start 0.7874 -0.4064)
			(end 0.7874 0.4064)
			(stroke
				(width 0.1524)
				(type default)
			)
			(layer "F.SilkS")
		)
		(fp_line
			(start 0.7874 0.4064)
			(end -0.7874 0.4064)
			(stroke
				(width 0.1524)
				(type default)
			)
			(layer "F.SilkS")
		)
		(fp_line
			(start -0.67945 -0.305054)
			(end -0.12065 -0.305054)
			(stroke
				(width 0.1)
				(type default)
			)
			(layer "F.Fab")
		)
		(fp_line
			(start -0.67945 0.3048)
			(end -0.67945 -0.305054)
			(stroke
				(width 0.1)
				(type default)
			)
			(layer "F.Fab")
		)
		(fp_line
			(start -0.12065 -0.305054)
			(end -0.12065 -0.2794)
			(stroke
				(width 0.1)
				(type default)
			)
			(layer "F.Fab")
		)
		(fp_line
			(start -0.12065 -0.2794)
			(end 0.12065 -0.2794)
			(stroke
				(width 0.1)
				(type default)
			)
			(layer "F.Fab")
		)
		(fp_line
			(start -0.12065 0.2794)
			(end -0.12065 0.3048)
			(stroke
				(width 0.1)
				(type default)
			)
			(layer "F.Fab")
		)
		(fp_line
			(start -0.12065 0.3048)
			(end -0.67945 0.3048)
			(stroke
				(width 0.1)
				(type default)
			)
			(layer "F.Fab")
		)
		(fp_line
			(start 0.120396 0.2794)
			(end -0.12065 0.2794)
			(stroke
				(width 0.1)
				(type default)
			)
			(layer "F.Fab")
		)
		(fp_line
			(start 0.120396 0.3048)
			(end 0.120396 0.2794)
			(stroke
				(width 0.1)
				(type default)
			)
			(layer "F.Fab")
		)
		(fp_line
			(start 0.12065 -0.3048)
			(end 0.67945 -0.3048)
			(stroke
				(width 0.1)
				(type default)
			)
			(layer "F.Fab")
		)
		(fp_line
			(start 0.12065 -0.2794)
			(end 0.12065 -0.3048)
			(stroke
				(width 0.1)
				(type default)
			)
			(layer "F.Fab")
		)
		(fp_line
			(start 0.67945 -0.3048)
			(end 0.67945 0.3048)
			(stroke
				(width 0.1)
				(type default)
			)
			(layer "F.Fab")
		)
		(fp_line
			(start 0.67945 0.3048)
			(end 0.120396 0.3048)
			(stroke
				(width 0.1)
				(type default)
			)
			(layer "F.Fab")
		)
		(pad "1" smd circle
			(at -0.40005 0)
			(size 0 0)
			(layers "F.Cu" "F.Mask" "F.Paste")
			(net "P3V3_AUX")
		)
		(pad "2" smd circle
			(at 0.40005 0)
			(size 0 0)
			(layers "F.Cu" "F.Mask" "F.Paste")
			(net "GPU_NVS_PWR_BRAKE_N_R")
		)
	)
	(footprint ""
		(layer "F.Cu")
		(at 305.018948 -344.982038 90)
		(property "Reference" "PR509"
			(at 0 0 90)
			(layer "F.SilkS")
			(hide yes)
			(effects
				(font
					(size 1.27 1.27)
				)
			)
		)
		(property "Value" ""
			(at 0 0 90)
			(layer "F.Fab")
			(effects
				(font
					(size 1.27 1.27)
				)
			)
		)
		(duplicate_pad_numbers_are_jumpers no)
		(fp_line
			(start 0.7874 -0.4064)
			(end 0.7874 0.4064)
			(stroke
				(width 0.1524)
				(type default)
			)
			(layer "F.SilkS")
		)
		(fp_line
			(start -0.7874 -0.4064)
			(end 0.7874 -0.4064)
			(stroke
				(width 0.1524)
				(type default)
			)
			(layer "F.SilkS")
		)
		(fp_line
			(start 0.7874 0.4064)
			(end -0.7874 0.4064)
			(stroke
				(width 0.1524)
				(type default)
			)
			(layer "F.SilkS")
		)
		(fp_line
			(start -0.7874 0.4064)
			(end -0.7874 -0.4064)
			(stroke
				(width 0.1524)
				(type default)
			)
			(layer "F.SilkS")
		)
		(fp_line
			(start -0.12065 -0.305054)
			(end -0.12065 -0.2794)
			(stroke
				(width 0.1)
				(type default)
			)
			(layer "F.Fab")
		)
		(fp_line
			(start -0.67945 -0.305054)
			(end -0.12065 -0.305054)
			(stroke
				(width 0.1)
				(type default)
			)
			(layer "F.Fab")
		)
		(fp_line
			(start 0.67945 -0.3048)
			(end 0.67945 0.3048)
			(stroke
				(width 0.1)
				(type default)
			)
			(layer "F.Fab")
		)
		(fp_line
			(start 0.12065 -0.3048)
			(end 0.67945 -0.3048)
			(stroke
				(width 0.1)
				(type default)
			)
			(layer "F.Fab")
		)
		(fp_line
			(start 0.12065 -0.2794)
			(end 0.12065 -0.3048)
			(stroke
				(width 0.1)
				(type default)
			)
			(layer "F.Fab")
		)
		(fp_line
			(start -0.12065 -0.2794)
			(end 0.12065 -0.2794)
			(stroke
				(width 0.1)
				(type default)
			)
			(layer "F.Fab")
		)
		(fp_line
			(start 0.120396 0.2794)
			(end -0.12065 0.2794)
			(stroke
				(width 0.1)
				(type default)
			)
			(layer "F.Fab")
		)
		(fp_line
			(start -0.12065 0.2794)
			(end -0.12065 0.3048)
			(stroke
				(width 0.1)
				(type default)
			)
			(layer "F.Fab")
		)
		(fp_line
			(start 0.67945 0.3048)
			(end 0.120396 0.3048)
			(stroke
				(width 0.1)
				(type default)
			)
			(layer "F.Fab")
		)
		(fp_line
			(start 0.120396 0.3048)
			(end 0.120396 0.2794)
			(stroke
				(width 0.1)
				(type default)
			)
			(layer "F.Fab")
		)
		(fp_line
			(start -0.12065 0.3048)
			(end -0.67945 0.3048)
			(stroke
				(width 0.1)
				(type default)
			)
			(layer "F.Fab")
		)
		(fp_line
			(start -0.67945 0.3048)
			(end -0.67945 -0.305054)
			(stroke
				(width 0.1)
				(type default)
			)
			(layer "F.Fab")
		)
		(pad "1" smd circle
			(at -0.40005 0 90)
			(size 0 0)
			(layers "F.Cu" "F.Mask" "F.Paste")
			(net "SW_PVDDCR_CPU1_P0_SW4_RC")
		)
		(pad "2" smd circle
			(at 0.40005 0 90)
			(size 0 0)
			(layers "F.Cu" "F.Mask" "F.Paste")
			(net "GND")
		)
	)
	(footprint ""
		(layer "F.Cu")
		(at 197.180962 -39.046912)
		(property "Reference" "R1857"
			(at 0 0 0)
			(layer "F.SilkS")
			(hide yes)
			(effects
				(font
					(size 1.27 1.27)
				)
			)
		)
		(property "Value" ""
			(at 0 0 0)
			(layer "F.Fab")
			(effects
				(font
					(size 1.27 1.27)
				)
			)
		)
		(duplicate_pad_numbers_are_jumpers no)
		(fp_line
			(start -0.7874 -0.4064)
			(end 0.7874 -0.4064)
			(stroke
				(width 0.1524)
				(type default)
			)
			(layer "F.SilkS")
		)
		(fp_line
			(start -0.7874 0.4064)
			(end -0.7874 -0.4064)
			(stroke
				(width 0.1524)
				(type default)
			)
			(layer "F.SilkS")
		)
		(fp_line
			(start 0.7874 -0.4064)
			(end 0.7874 0.4064)
			(stroke
				(width 0.1524)
				(type default)
			)
			(layer "F.SilkS")
		)
		(fp_line
			(start 0.7874 0.4064)
			(end -0.7874 0.4064)
			(stroke
				(width 0.1524)
				(type default)
			)
			(layer "F.SilkS")
		)
		(fp_line
			(start -0.67945 -0.305054)
			(end -0.12065 -0.305054)
			(stroke
				(width 0.1)
				(type default)
			)
			(layer "F.Fab")
		)
		(fp_line
			(start -0.67945 0.3048)
			(end -0.67945 -0.305054)
			(stroke
				(width 0.1)
				(type default)
			)
			(layer "F.Fab")
		)
		(fp_line
			(start -0.12065 -0.305054)
			(end -0.12065 -0.2794)
			(stroke
				(width 0.1)
				(type default)
			)
			(layer "F.Fab")
		)
		(fp_line
			(start -0.12065 -0.2794)
			(end 0.12065 -0.2794)
			(stroke
				(width 0.1)
				(type default)
			)
			(layer "F.Fab")
		)
		(fp_line
			(start -0.12065 0.2794)
			(end -0.12065 0.3048)
			(stroke
				(width 0.1)
				(type default)
			)
			(layer "F.Fab")
		)
		(fp_line
			(start -0.12065 0.3048)
			(end -0.67945 0.3048)
			(stroke
				(width 0.1)
				(type default)
			)
			(layer "F.Fab")
		)
		(fp_line
			(start 0.120396 0.2794)
			(end -0.12065 0.2794)
			(stroke
				(width 0.1)
				(type default)
			)
			(layer "F.Fab")
		)
		(fp_line
			(start 0.120396 0.3048)
			(end 0.120396 0.2794)
			(stroke
				(width 0.1)
				(type default)
			)
			(layer "F.Fab")
		)
		(fp_line
			(start 0.12065 -0.3048)
			(end 0.67945 -0.3048)
			(stroke
				(width 0.1)
				(type default)
			)
			(layer "F.Fab")
		)
		(fp_line
			(start 0.12065 -0.2794)
			(end 0.12065 -0.3048)
			(stroke
				(width 0.1)
				(type default)
			)
			(layer "F.Fab")
		)
		(fp_line
			(start 0.67945 -0.3048)
			(end 0.67945 0.3048)
			(stroke
				(width 0.1)
				(type default)
			)
			(layer "F.Fab")
		)
		(fp_line
			(start 0.67945 0.3048)
			(end 0.120396 0.3048)
			(stroke
				(width 0.1)
				(type default)
			)
			(layer "F.Fab")
		)
		(pad "1" smd circle
			(at -0.40005 0)
			(size 0 0)
			(layers "F.Cu" "F.Mask" "F.Paste")
			(net "P3V3_AUX")
		)
		(pad "2" smd circle
			(at 0.40005 0)
			(size 0 0)
			(layers "F.Cu" "F.Mask" "F.Paste")
			(net "P12V_SCM_EN")
		)
	)
	(footprint ""
		(layer "F.Cu")
		(at 403.682962 -60.7695 180)
		(property "Reference" "R477"
			(at 0 0 180)
			(layer "F.SilkS")
			(hide yes)
			(effects
				(font
					(size 1.27 1.27)
				)
			)
		)
		(property "Value" ""
			(at 0 0 180)
			(layer "F.Fab")
			(effects
				(font
					(size 1.27 1.27)
				)
			)
		)
		(duplicate_pad_numbers_are_jumpers no)
		(fp_line
			(start 0.7874 0.4064)
			(end -0.7874 0.4064)
			(stroke
				(width 0.1524)
				(type default)
			)
			(layer "F.SilkS")
		)
		(fp_line
			(start 0.7874 -0.4064)
			(end 0.7874 0.4064)
			(stroke
				(width 0.1524)
				(type default)
			)
			(layer "F.SilkS")
		)
		(fp_line
			(start -0.7874 0.4064)
			(end -0.7874 -0.4064)
			(stroke
				(width 0.1524)
				(type default)
			)
			(layer "F.SilkS")
		)
		(fp_line
			(start -0.7874 -0.4064)
			(end 0.7874 -0.4064)
			(stroke
				(width 0.1524)
				(type default)
			)
			(layer "F.SilkS")
		)
		(fp_line
			(start 0.67945 0.3048)
			(end 0.120396 0.3048)
			(stroke
				(width 0.1)
				(type default)
			)
			(layer "F.Fab")
		)
		(fp_line
			(start 0.67945 -0.3048)
			(end 0.67945 0.3048)
			(stroke
				(width 0.1)
				(type default)
			)
			(layer "F.Fab")
		)
		(fp_line
			(start 0.12065 -0.2794)
			(end 0.12065 -0.3048)
			(stroke
				(width 0.1)
				(type default)
			)
			(layer "F.Fab")
		)
		(fp_line
			(start 0.12065 -0.3048)
			(end 0.67945 -0.3048)
			(stroke
				(width 0.1)
				(type default)
			)
			(layer "F.Fab")
		)
		(fp_line
			(start 0.120396 0.3048)
			(end 0.120396 0.2794)
			(stroke
				(width 0.1)
				(type default)
			)
			(layer "F.Fab")
		)
		(fp_line
			(start 0.120396 0.2794)
			(end -0.12065 0.2794)
			(stroke
				(width 0.1)
				(type default)
			)
			(layer "F.Fab")
		)
		(fp_line
			(start -0.12065 0.3048)
			(end -0.67945 0.3048)
			(stroke
				(width 0.1)
				(type default)
			)
			(layer "F.Fab")
		)
		(fp_line
			(start -0.12065 0.2794)
			(end -0.12065 0.3048)
			(stroke
				(width 0.1)
				(type default)
			)
			(layer "F.Fab")
		)
		(fp_line
			(start -0.12065 -0.2794)
			(end 0.12065 -0.2794)
			(stroke
				(width 0.1)
				(type default)
			)
			(layer "F.Fab")
		)
		(fp_line
			(start -0.12065 -0.305054)
			(end -0.12065 -0.2794)
			(stroke
				(width 0.1)
				(type default)
			)
			(layer "F.Fab")
		)
		(fp_line
			(start -0.67945 0.3048)
			(end -0.67945 -0.305054)
			(stroke
				(width 0.1)
				(type default)
			)
			(layer "F.Fab")
		)
		(fp_line
			(start -0.67945 -0.305054)
			(end -0.12065 -0.305054)
			(stroke
				(width 0.1)
				(type default)
			)
			(layer "F.Fab")
		)
		(pad "1" smd circle
			(at -0.40005 0 180)
			(size 0 0)
			(layers "F.Cu" "F.Mask" "F.Paste")
			(net "CPU0_XTRIG_L7")
		)
		(pad "2" smd circle
			(at 0.40005 0 180)
			(size 0 0)
			(layers "F.Cu" "F.Mask" "F.Paste")
			(net "HDT_CPU0_XTRIG_L7")
		)
	)
	(footprint ""
		(layer "F.Cu")
		(at 39.842694 -422.06037)
		(property "Reference" "R6154"
			(at 0 0 0)
			(layer "F.SilkS")
			(hide yes)
			(effects
				(font
					(size 1.27 1.27)
				)
			)
		)
		(property "Value" ""
			(at 0 0 0)
			(layer "F.Fab")
			(effects
				(font
					(size 1.27 1.27)
				)
			)
		)
		(duplicate_pad_numbers_are_jumpers no)
		(fp_line
			(start -0.32512 -0.175006)
			(end 0.32512 -0.175006)
			(stroke
				(width 0.1)
				(type default)
			)
			(layer "F.Fab")
		)
		(fp_line
			(start -0.32512 0.175006)
			(end -0.32512 -0.175006)
			(stroke
				(width 0.1)
				(type default)
			)
			(layer "F.Fab")
		)
		(fp_line
			(start 0.32512 -0.175006)
			(end 0.32512 0.175006)
			(stroke
				(width 0.1)
				(type default)
			)
			(layer "F.Fab")
		)
		(fp_line
			(start 0.32512 0.175006)
			(end -0.32512 0.175006)
			(stroke
				(width 0.1)
				(type default)
			)
			(layer "F.Fab")
		)
		(pad "1" smd rect
			(at -0.2667 0)
			(size 0.3048 0.381)
			(layers "F.Cu" "F.Mask" "F.Paste")
			(net "P2E_MB_BMC_TX_C_DP<0>")
		)
		(pad "2" smd rect
			(at 0.2667 0 180)
			(size 0.3048 0.381)
			(layers "F.Cu" "F.Mask" "F.Paste")
			(net "P2E_MB_BMC_TX_C_R2_DP<0>")
		)
	)
	(footprint ""
		(layer "F.Cu")
		(at 87.54618 -58.21172 180)
		(property "Reference" "R3826"
			(at 0 0 180)
			(layer "F.SilkS")
			(hide yes)
			(effects
				(font
					(size 1.27 1.27)
				)
			)
		)
		(property "Value" ""
			(at 0 0 180)
			(layer "F.Fab")
			(effects
				(font
					(size 1.27 1.27)
				)
			)
		)
		(duplicate_pad_numbers_are_jumpers no)
		(fp_line
			(start 0.7874 0.4064)
			(end -0.7874 0.4064)
			(stroke
				(width 0.1524)
				(type default)
			)
			(layer "F.SilkS")
		)
		(fp_line
			(start 0.7874 -0.4064)
			(end 0.7874 0.4064)
			(stroke
				(width 0.1524)
				(type default)
			)
			(layer "F.SilkS")
		)
		(fp_line
			(start -0.7874 0.4064)
			(end -0.7874 -0.4064)
			(stroke
				(width 0.1524)
				(type default)
			)
			(layer "F.SilkS")
		)
		(fp_line
			(start -0.7874 -0.4064)
			(end 0.7874 -0.4064)
			(stroke
				(width 0.1524)
				(type default)
			)
			(layer "F.SilkS")
		)
		(fp_line
			(start 0.67945 0.3048)
			(end 0.120396 0.3048)
			(stroke
				(width 0.1)
				(type default)
			)
			(layer "F.Fab")
		)
		(fp_line
			(start 0.67945 -0.3048)
			(end 0.67945 0.3048)
			(stroke
				(width 0.1)
				(type default)
			)
			(layer "F.Fab")
		)
		(fp_line
			(start 0.12065 -0.2794)
			(end 0.12065 -0.3048)
			(stroke
				(width 0.1)
				(type default)
			)
			(layer "F.Fab")
		)
		(fp_line
			(start 0.12065 -0.3048)
			(end 0.67945 -0.3048)
			(stroke
				(width 0.1)
				(type default)
			)
			(layer "F.Fab")
		)
		(fp_line
			(start 0.120396 0.3048)
			(end 0.120396 0.2794)
			(stroke
				(width 0.1)
				(type default)
			)
			(layer "F.Fab")
		)
		(fp_line
			(start 0.120396 0.2794)
			(end -0.12065 0.2794)
			(stroke
				(width 0.1)
				(type default)
			)
			(layer "F.Fab")
		)
		(fp_line
			(start -0.12065 0.3048)
			(end -0.67945 0.3048)
			(stroke
				(width 0.1)
				(type default)
			)
			(layer "F.Fab")
		)
		(fp_line
			(start -0.12065 0.2794)
			(end -0.12065 0.3048)
			(stroke
				(width 0.1)
				(type default)
			)
			(layer "F.Fab")
		)
		(fp_line
			(start -0.12065 -0.2794)
			(end 0.12065 -0.2794)
			(stroke
				(width 0.1)
				(type default)
			)
			(layer "F.Fab")
		)
		(fp_line
			(start -0.12065 -0.305054)
			(end -0.12065 -0.2794)
			(stroke
				(width 0.1)
				(type default)
			)
			(layer "F.Fab")
		)
		(fp_line
			(start -0.67945 0.3048)
			(end -0.67945 -0.305054)
			(stroke
				(width 0.1)
				(type default)
			)
			(layer "F.Fab")
		)
		(fp_line
			(start -0.67945 -0.305054)
			(end -0.12065 -0.305054)
			(stroke
				(width 0.1)
				(type default)
			)
			(layer "F.Fab")
		)
		(pad "1" smd circle
			(at -0.40005 0 180)
			(size 0 0)
			(layers "F.Cu" "F.Mask" "F.Paste")
			(net "P3V3_AUX")
		)
		(pad "2" smd circle
			(at 0.40005 0 180)
			(size 0 0)
			(layers "F.Cu" "F.Mask" "F.Paste")
			(net "OCP_V3_2_P3V3_PWRGD")
		)
	)
	(footprint ""
		(layer "F.Cu")
		(at 463.439764 -399.030952)
		(property "Reference" "H2"
			(at -2.5146 -3.58013 0)
			(unlocked yes)
			(layer "F.SilkS")
			(effects
				(font
					(size 0.7874 0.5842)
					(thickness 0.1524)
				)
				(justify left)
			)
		)
		(property "Value" ""
			(at 0 0 0)
			(layer "F.Fab")
			(effects
				(font
					(size 1.27 1.27)
				)
			)
		)
		(duplicate_pad_numbers_are_jumpers no)
		(pad "1" thru_hole circle
			(at 0 0)
			(size 6.1976 6.1976)
			(drill 3.7338)
			(layers "*.Cu" "*.Mask")
			(remove_unused_layers no)
			(net "GND")
			(clearance -0.9779)
			(padstack
				(mode front_inner_back)
				(layer "Inner"
					(shape circle)
					(size 5.5372 5.5372)
					(clearance -0.6477)
				)
				(layer "B.Cu"
					(shape circle)
					(size 6.1976 6.1976)
					(clearance -0.9779)
				)
			)
		)
	)
	(footprint ""
		(layer "F.Cu")
		(at 112.649 -412.1658)
		(property "Reference" "C82"
			(at 0 0 0)
			(layer "F.SilkS")
			(hide yes)
			(effects
				(font
					(size 1.27 1.27)
				)
			)
		)
		(property "Value" ""
			(at 0 0 0)
			(layer "F.Fab")
			(effects
				(font
					(size 1.27 1.27)
				)
			)
		)
		(duplicate_pad_numbers_are_jumpers no)
		(fp_line
			(start -0.7874 -0.4064)
			(end 0.7874 -0.4064)
			(stroke
				(width 0.1524)
				(type default)
			)
			(layer "F.SilkS")
		)
		(fp_line
			(start -0.7874 0.4064)
			(end -0.7874 -0.4064)
			(stroke
				(width 0.1524)
				(type default)
			)
			(layer "F.SilkS")
		)
		(fp_line
			(start 0.7874 -0.4064)
			(end 0.7874 0.4064)
			(stroke
				(width 0.1524)
				(type default)
			)
			(layer "F.SilkS")
		)
		(fp_line
			(start 0.7874 0.4064)
			(end -0.7874 0.4064)
			(stroke
				(width 0.1524)
				(type default)
			)
			(layer "F.SilkS")
		)
		(fp_line
			(start -0.67945 -0.305054)
			(end -0.12065 -0.305054)
			(stroke
				(width 0.1)
				(type default)
			)
			(layer "F.Fab")
		)
		(fp_line
			(start -0.67945 0.3048)
			(end -0.67945 -0.305054)
			(stroke
				(width 0.1)
				(type default)
			)
			(layer "F.Fab")
		)
		(fp_line
			(start -0.12065 -0.305054)
			(end -0.12065 -0.2794)
			(stroke
				(width 0.1)
				(type default)
			)
			(layer "F.Fab")
		)
		(fp_line
			(start -0.12065 -0.2794)
			(end 0.12065 -0.2794)
			(stroke
				(width 0.1)
				(type default)
			)
			(layer "F.Fab")
		)
		(fp_line
			(start -0.12065 0.2794)
			(end -0.12065 0.3048)
			(stroke
				(width 0.1)
				(type default)
			)
			(layer "F.Fab")
		)
		(fp_line
			(start -0.12065 0.3048)
			(end -0.67945 0.3048)
			(stroke
				(width 0.1)
				(type default)
			)
			(layer "F.Fab")
		)
		(fp_line
			(start 0.120396 0.2794)
			(end -0.12065 0.2794)
			(stroke
				(width 0.1)
				(type default)
			)
			(layer "F.Fab")
		)
		(fp_line
			(start 0.120396 0.3048)
			(end 0.120396 0.2794)
			(stroke
				(width 0.1)
				(type default)
			)
			(layer "F.Fab")
		)
		(fp_line
			(start 0.12065 -0.3048)
			(end 0.67945 -0.3048)
			(stroke
				(width 0.1)
				(type default)
			)
			(layer "F.Fab")
		)
		(fp_line
			(start 0.12065 -0.2794)
			(end 0.12065 -0.3048)
			(stroke
				(width 0.1)
				(type default)
			)
			(layer "F.Fab")
		)
		(fp_line
			(start 0.67945 -0.3048)
			(end 0.67945 0.3048)
			(stroke
				(width 0.1)
				(type default)
			)
			(layer "F.Fab")
		)
		(fp_line
			(start 0.67945 0.3048)
			(end 0.120396 0.3048)
			(stroke
				(width 0.1)
				(type default)
			)
			(layer "F.Fab")
		)
		(pad "1" smd circle
			(at -0.40005 0)
			(size 0 0)
			(layers "F.Cu" "F.Mask" "F.Paste")
			(net "P3V3_9ZXL045_P1_VDDA")
		)
		(pad "2" smd circle
			(at 0.40005 0)
			(size 0 0)
			(layers "F.Cu" "F.Mask" "F.Paste")
			(net "GND")
		)
	)
	(footprint ""
		(layer "F.Cu")
		(at 436.608474 -103.768398 90)
		(property "Reference" "PR4525"
			(at 0 0 90)
			(layer "F.SilkS")
			(hide yes)
			(effects
				(font
					(size 1.27 1.27)
				)
			)
		)
		(property "Value" ""
			(at 0 0 90)
			(layer "F.Fab")
			(effects
				(font
					(size 1.27 1.27)
				)
			)
		)
		(duplicate_pad_numbers_are_jumpers no)
		(fp_line
			(start 0.7874 -0.4064)
			(end 0.7874 0.4064)
			(stroke
				(width 0.1524)
				(type default)
			)
			(layer "F.SilkS")
		)
		(fp_line
			(start -0.7874 -0.4064)
			(end 0.7874 -0.4064)
			(stroke
				(width 0.1524)
				(type default)
			)
			(layer "F.SilkS")
		)
		(fp_line
			(start 0.7874 0.4064)
			(end -0.7874 0.4064)
			(stroke
				(width 0.1524)
				(type default)
			)
			(layer "F.SilkS")
		)
		(fp_line
			(start -0.7874 0.4064)
			(end -0.7874 -0.4064)
			(stroke
				(width 0.1524)
				(type default)
			)
			(layer "F.SilkS")
		)
		(fp_line
			(start -0.12065 -0.305054)
			(end -0.12065 -0.2794)
			(stroke
				(width 0.1)
				(type default)
			)
			(layer "F.Fab")
		)
		(fp_line
			(start -0.67945 -0.305054)
			(end -0.12065 -0.305054)
			(stroke
				(width 0.1)
				(type default)
			)
			(layer "F.Fab")
		)
		(fp_line
			(start 0.67945 -0.3048)
			(end 0.67945 0.3048)
			(stroke
				(width 0.1)
				(type default)
			)
			(layer "F.Fab")
		)
		(fp_line
			(start 0.12065 -0.3048)
			(end 0.67945 -0.3048)
			(stroke
				(width 0.1)
				(type default)
			)
			(layer "F.Fab")
		)
		(fp_line
			(start 0.12065 -0.2794)
			(end 0.12065 -0.3048)
			(stroke
				(width 0.1)
				(type default)
			)
			(layer "F.Fab")
		)
		(fp_line
			(start -0.12065 -0.2794)
			(end 0.12065 -0.2794)
			(stroke
				(width 0.1)
				(type default)
			)
			(layer "F.Fab")
		)
		(fp_line
			(start 0.120396 0.2794)
			(end -0.12065 0.2794)
			(stroke
				(width 0.1)
				(type default)
			)
			(layer "F.Fab")
		)
		(fp_line
			(start -0.12065 0.2794)
			(end -0.12065 0.3048)
			(stroke
				(width 0.1)
				(type default)
			)
			(layer "F.Fab")
		)
		(fp_line
			(start 0.67945 0.3048)
			(end 0.120396 0.3048)
			(stroke
				(width 0.1)
				(type default)
			)
			(layer "F.Fab")
		)
		(fp_line
			(start 0.120396 0.3048)
			(end 0.120396 0.2794)
			(stroke
				(width 0.1)
				(type default)
			)
			(layer "F.Fab")
		)
		(fp_line
			(start -0.12065 0.3048)
			(end -0.67945 0.3048)
			(stroke
				(width 0.1)
				(type default)
			)
			(layer "F.Fab")
		)
		(fp_line
			(start -0.67945 0.3048)
			(end -0.67945 -0.305054)
			(stroke
				(width 0.1)
				(type default)
			)
			(layer "F.Fab")
		)
		(pad "1" smd circle
			(at -0.40005 0 90)
			(size 0 0)
			(layers "F.Cu" "F.Mask" "F.Paste")
			(net "P3V3_OCP_SFF_R")
		)
		(pad "2" smd circle
			(at 0.40005 0 90)
			(size 0 0)
			(layers "F.Cu" "F.Mask" "F.Paste")
			(net "P3V3_OCP_GATE_PU202_1")
		)
	)
	(footprint ""
		(layer "F.Cu")
		(at 339.699346 -23.897336 -90)
		(property "Reference" "R935"
			(at 0 0 270)
			(layer "F.SilkS")
			(hide yes)
			(effects
				(font
					(size 1.27 1.27)
				)
			)
		)
		(property "Value" ""
			(at 0 0 270)
			(layer "F.Fab")
			(effects
				(font
					(size 1.27 1.27)
				)
			)
		)
		(duplicate_pad_numbers_are_jumpers no)
		(fp_line
			(start -0.7874 0.4064)
			(end -0.7874 -0.4064)
			(stroke
				(width 0.1524)
				(type default)
			)
			(layer "F.SilkS")
		)
		(fp_line
			(start 0.7874 0.4064)
			(end -0.7874 0.4064)
			(stroke
				(width 0.1524)
				(type default)
			)
			(layer "F.SilkS")
		)
		(fp_line
			(start -0.7874 -0.4064)
			(end 0.7874 -0.4064)
			(stroke
				(width 0.1524)
				(type default)
			)
			(layer "F.SilkS")
		)
		(fp_line
			(start 0.7874 -0.4064)
			(end 0.7874 0.4064)
			(stroke
				(width 0.1524)
				(type default)
			)
			(layer "F.SilkS")
		)
		(fp_line
			(start -0.67945 0.3048)
			(end -0.67945 -0.305054)
			(stroke
				(width 0.1)
				(type default)
			)
			(layer "F.Fab")
		)
		(fp_line
			(start -0.12065 0.3048)
			(end -0.67945 0.3048)
			(stroke
				(width 0.1)
				(type default)
			)
			(layer "F.Fab")
		)
		(fp_line
			(start 0.120396 0.3048)
			(end 0.120396 0.2794)
			(stroke
				(width 0.1)
				(type default)
			)
			(layer "F.Fab")
		)
		(fp_line
			(start 0.67945 0.3048)
			(end 0.120396 0.3048)
			(stroke
				(width 0.1)
				(type default)
			)
			(layer "F.Fab")
		)
		(fp_line
			(start -0.12065 0.2794)
			(end -0.12065 0.3048)
			(stroke
				(width 0.1)
				(type default)
			)
			(layer "F.Fab")
		)
		(fp_line
			(start 0.120396 0.2794)
			(end -0.12065 0.2794)
			(stroke
				(width 0.1)
				(type default)
			)
			(layer "F.Fab")
		)
		(fp_line
			(start -0.12065 -0.2794)
			(end 0.12065 -0.2794)
			(stroke
				(width 0.1)
				(type default)
			)
			(layer "F.Fab")
		)
		(fp_line
			(start 0.12065 -0.2794)
			(end 0.12065 -0.3048)
			(stroke
				(width 0.1)
				(type default)
			)
			(layer "F.Fab")
		)
		(fp_line
			(start 0.12065 -0.3048)
			(end 0.67945 -0.3048)
			(stroke
				(width 0.1)
				(type default)
			)
			(layer "F.Fab")
		)
		(fp_line
			(start 0.67945 -0.3048)
			(end 0.67945 0.3048)
			(stroke
				(width 0.1)
				(type default)
			)
			(layer "F.Fab")
		)
		(fp_line
			(start -0.67945 -0.305054)
			(end -0.12065 -0.305054)
			(stroke
				(width 0.1)
				(type default)
			)
			(layer "F.Fab")
		)
		(fp_line
			(start -0.12065 -0.305054)
			(end -0.12065 -0.2794)
			(stroke
				(width 0.1)
				(type default)
			)
			(layer "F.Fab")
		)
		(pad "1" smd circle
			(at -0.40005 0 270)
			(size 0 0)
			(layers "F.Cu" "F.Mask" "F.Paste")
			(net "BOOT_RDY_BUF_R_LED")
		)
		(pad "2" smd circle
			(at 0.40005 0 270)
			(size 0 0)
			(layers "F.Cu" "F.Mask" "F.Paste")
			(net "BOOT_RDY_BUF_LED")
		)
	)
	(footprint ""
		(layer "F.Cu")
		(at 350.44761 -62.634876 180)
		(property "Reference" "R484"
			(at 0 0 180)
			(layer "F.SilkS")
			(hide yes)
			(effects
				(font
					(size 1.27 1.27)
				)
			)
		)
		(property "Value" ""
			(at 0 0 180)
			(layer "F.Fab")
			(effects
				(font
					(size 1.27 1.27)
				)
			)
		)
		(duplicate_pad_numbers_are_jumpers no)
		(fp_line
			(start 0.7874 0.4064)
			(end -0.7874 0.4064)
			(stroke
				(width 0.1524)
				(type default)
			)
			(layer "F.SilkS")
		)
		(fp_line
			(start 0.7874 -0.4064)
			(end 0.7874 0.4064)
			(stroke
				(width 0.1524)
				(type default)
			)
			(layer "F.SilkS")
		)
		(fp_line
			(start -0.7874 0.4064)
			(end -0.7874 -0.4064)
			(stroke
				(width 0.1524)
				(type default)
			)
			(layer "F.SilkS")
		)
		(fp_line
			(start -0.7874 -0.4064)
			(end 0.7874 -0.4064)
			(stroke
				(width 0.1524)
				(type default)
			)
			(layer "F.SilkS")
		)
		(fp_line
			(start 0.67945 0.3048)
			(end 0.120396 0.3048)
			(stroke
				(width 0.1)
				(type default)
			)
			(layer "F.Fab")
		)
		(fp_line
			(start 0.67945 -0.3048)
			(end 0.67945 0.3048)
			(stroke
				(width 0.1)
				(type default)
			)
			(layer "F.Fab")
		)
		(fp_line
			(start 0.12065 -0.2794)
			(end 0.12065 -0.3048)
			(stroke
				(width 0.1)
				(type default)
			)
			(layer "F.Fab")
		)
		(fp_line
			(start 0.12065 -0.3048)
			(end 0.67945 -0.3048)
			(stroke
				(width 0.1)
				(type default)
			)
			(layer "F.Fab")
		)
		(fp_line
			(start 0.120396 0.3048)
			(end 0.120396 0.2794)
			(stroke
				(width 0.1)
				(type default)
			)
			(layer "F.Fab")
		)
		(fp_line
			(start 0.120396 0.2794)
			(end -0.12065 0.2794)
			(stroke
				(width 0.1)
				(type default)
			)
			(layer "F.Fab")
		)
		(fp_line
			(start -0.12065 0.3048)
			(end -0.67945 0.3048)
			(stroke
				(width 0.1)
				(type default)
			)
			(layer "F.Fab")
		)
		(fp_line
			(start -0.12065 0.2794)
			(end -0.12065 0.3048)
			(stroke
				(width 0.1)
				(type default)
			)
			(layer "F.Fab")
		)
		(fp_line
			(start -0.12065 -0.2794)
			(end 0.12065 -0.2794)
			(stroke
				(width 0.1)
				(type default)
			)
			(layer "F.Fab")
		)
		(fp_line
			(start -0.12065 -0.305054)
			(end -0.12065 -0.2794)
			(stroke
				(width 0.1)
				(type default)
			)
			(layer "F.Fab")
		)
		(fp_line
			(start -0.67945 0.3048)
			(end -0.67945 -0.305054)
			(stroke
				(width 0.1)
				(type default)
			)
			(layer "F.Fab")
		)
		(fp_line
			(start -0.67945 -0.305054)
			(end -0.12065 -0.305054)
			(stroke
				(width 0.1)
				(type default)
			)
			(layer "F.Fab")
		)
		(pad "1" smd circle
			(at -0.40005 0 180)
			(size 0 0)
			(layers "F.Cu" "F.Mask" "F.Paste")
			(net "CPU0_XTRIG_L6")
		)
		(pad "2" smd circle
			(at 0.40005 0 180)
			(size 0 0)
			(layers "F.Cu" "F.Mask" "F.Paste")
			(net "CPU0_XTRIG_R1_L6")
		)
	)
	(footprint ""
		(layer "F.Cu")
		(at 181.688486 -426.349922 -90)
		(property "Reference" "R9018"
			(at 0 0 270)
			(layer "F.SilkS")
			(hide yes)
			(effects
				(font
					(size 1.27 1.27)
				)
			)
		)
		(property "Value" ""
			(at 0 0 270)
			(layer "F.Fab")
			(effects
				(font
					(size 1.27 1.27)
				)
			)
		)
		(duplicate_pad_numbers_are_jumpers no)
		(fp_line
			(start -0.7874 0.4064)
			(end -0.7874 -0.4064)
			(stroke
				(width 0.1524)
				(type default)
			)
			(layer "F.SilkS")
		)
		(fp_line
			(start 0.7874 0.4064)
			(end -0.7874 0.4064)
			(stroke
				(width 0.1524)
				(type default)
			)
			(layer "F.SilkS")
		)
		(fp_line
			(start -0.7874 -0.4064)
			(end 0.7874 -0.4064)
			(stroke
				(width 0.1524)
				(type default)
			)
			(layer "F.SilkS")
		)
		(fp_line
			(start 0.7874 -0.4064)
			(end 0.7874 0.4064)
			(stroke
				(width 0.1524)
				(type default)
			)
			(layer "F.SilkS")
		)
		(fp_line
			(start -0.67945 0.3048)
			(end -0.67945 -0.305054)
			(stroke
				(width 0.1)
				(type default)
			)
			(layer "F.Fab")
		)
		(fp_line
			(start -0.12065 0.3048)
			(end -0.67945 0.3048)
			(stroke
				(width 0.1)
				(type default)
			)
			(layer "F.Fab")
		)
		(fp_line
			(start 0.120396 0.3048)
			(end 0.120396 0.2794)
			(stroke
				(width 0.1)
				(type default)
			)
			(layer "F.Fab")
		)
		(fp_line
			(start 0.67945 0.3048)
			(end 0.120396 0.3048)
			(stroke
				(width 0.1)
				(type default)
			)
			(layer "F.Fab")
		)
		(fp_line
			(start -0.12065 0.2794)
			(end -0.12065 0.3048)
			(stroke
				(width 0.1)
				(type default)
			)
			(layer "F.Fab")
		)
		(fp_line
			(start 0.120396 0.2794)
			(end -0.12065 0.2794)
			(stroke
				(width 0.1)
				(type default)
			)
			(layer "F.Fab")
		)
		(fp_line
			(start -0.12065 -0.2794)
			(end 0.12065 -0.2794)
			(stroke
				(width 0.1)
				(type default)
			)
			(layer "F.Fab")
		)
		(fp_line
			(start 0.12065 -0.2794)
			(end 0.12065 -0.3048)
			(stroke
				(width 0.1)
				(type default)
			)
			(layer "F.Fab")
		)
		(fp_line
			(start 0.12065 -0.3048)
			(end 0.67945 -0.3048)
			(stroke
				(width 0.1)
				(type default)
			)
			(layer "F.Fab")
		)
		(fp_line
			(start 0.67945 -0.3048)
			(end 0.67945 0.3048)
			(stroke
				(width 0.1)
				(type default)
			)
			(layer "F.Fab")
		)
		(fp_line
			(start -0.67945 -0.305054)
			(end -0.12065 -0.305054)
			(stroke
				(width 0.1)
				(type default)
			)
			(layer "F.Fab")
		)
		(fp_line
			(start -0.12065 -0.305054)
			(end -0.12065 -0.2794)
			(stroke
				(width 0.1)
				(type default)
			)
			(layer "F.Fab")
		)
		(pad "1" smd circle
			(at -0.40005 0 270)
			(size 0 0)
			(layers "F.Cu" "F.Mask" "F.Paste")
			(net "PRSNT_CABLE_GPU_A3_ISO_N")
		)
		(pad "2" smd circle
			(at 0.40005 0 270)
			(size 0 0)
			(layers "F.Cu" "F.Mask" "F.Paste")
			(net "PRSNT_CABLE_GPU_A3_ISO_R_N")
		)
	)
	(footprint ""
		(layer "F.Cu")
		(at 82.706718 -19.142202 -90)
		(property "Reference" "R3825"
			(at 0 0 270)
			(layer "F.SilkS")
			(hide yes)
			(effects
				(font
					(size 1.27 1.27)
				)
			)
		)
		(property "Value" ""
			(at 0 0 270)
			(layer "F.Fab")
			(effects
				(font
					(size 1.27 1.27)
				)
			)
		)
		(duplicate_pad_numbers_are_jumpers no)
		(fp_line
			(start -0.7874 0.4064)
			(end -0.7874 -0.4064)
			(stroke
				(width 0.1524)
				(type default)
			)
			(layer "F.SilkS")
		)
		(fp_line
			(start 0.7874 0.4064)
			(end -0.7874 0.4064)
			(stroke
				(width 0.1524)
				(type default)
			)
			(layer "F.SilkS")
		)
		(fp_line
			(start -0.7874 -0.4064)
			(end 0.7874 -0.4064)
			(stroke
				(width 0.1524)
				(type default)
			)
			(layer "F.SilkS")
		)
		(fp_line
			(start 0.7874 -0.4064)
			(end 0.7874 0.4064)
			(stroke
				(width 0.1524)
				(type default)
			)
			(layer "F.SilkS")
		)
		(fp_line
			(start -0.67945 0.3048)
			(end -0.67945 -0.305054)
			(stroke
				(width 0.1)
				(type default)
			)
			(layer "F.Fab")
		)
		(fp_line
			(start -0.12065 0.3048)
			(end -0.67945 0.3048)
			(stroke
				(width 0.1)
				(type default)
			)
			(layer "F.Fab")
		)
		(fp_line
			(start 0.120396 0.3048)
			(end 0.120396 0.2794)
			(stroke
				(width 0.1)
				(type default)
			)
			(layer "F.Fab")
		)
		(fp_line
			(start 0.67945 0.3048)
			(end 0.120396 0.3048)
			(stroke
				(width 0.1)
				(type default)
			)
			(layer "F.Fab")
		)
		(fp_line
			(start -0.12065 0.2794)
			(end -0.12065 0.3048)
			(stroke
				(width 0.1)
				(type default)
			)
			(layer "F.Fab")
		)
		(fp_line
			(start 0.120396 0.2794)
			(end -0.12065 0.2794)
			(stroke
				(width 0.1)
				(type default)
			)
			(layer "F.Fab")
		)
		(fp_line
			(start -0.12065 -0.2794)
			(end 0.12065 -0.2794)
			(stroke
				(width 0.1)
				(type default)
			)
			(layer "F.Fab")
		)
		(fp_line
			(start 0.12065 -0.2794)
			(end 0.12065 -0.3048)
			(stroke
				(width 0.1)
				(type default)
			)
			(layer "F.Fab")
		)
		(fp_line
			(start 0.12065 -0.3048)
			(end 0.67945 -0.3048)
			(stroke
				(width 0.1)
				(type default)
			)
			(layer "F.Fab")
		)
		(fp_line
			(start 0.67945 -0.3048)
			(end 0.67945 0.3048)
			(stroke
				(width 0.1)
				(type default)
			)
			(layer "F.Fab")
		)
		(fp_line
			(start -0.67945 -0.305054)
			(end -0.12065 -0.305054)
			(stroke
				(width 0.1)
				(type default)
			)
			(layer "F.Fab")
		)
		(fp_line
			(start -0.12065 -0.305054)
			(end -0.12065 -0.2794)
			(stroke
				(width 0.1)
				(type default)
			)
			(layer "F.Fab")
		)
		(pad "1" smd circle
			(at -0.40005 0 270)
			(size 0 0)
			(layers "F.Cu" "F.Mask" "F.Paste")
			(net "P3V3_AUX")
		)
		(pad "2" smd circle
			(at 0.40005 0 270)
			(size 0 0)
			(layers "F.Cu" "F.Mask" "F.Paste")
			(net "HP_LVC3_OCP_V3_2_P12V_PWRGD")
		)
	)
	(footprint ""
		(layer "F.Cu")
		(at 43.4721 -170.307)
		(property "Reference" "R988"
			(at 0 0 0)
			(layer "F.SilkS")
			(hide yes)
			(effects
				(font
					(size 1.27 1.27)
				)
			)
		)
		(property "Value" ""
			(at 0 0 0)
			(layer "F.Fab")
			(effects
				(font
					(size 1.27 1.27)
				)
			)
		)
		(duplicate_pad_numbers_are_jumpers no)
		(fp_line
			(start -0.7874 -0.4064)
			(end 0.7874 -0.4064)
			(stroke
				(width 0.1524)
				(type default)
			)
			(layer "F.SilkS")
		)
		(fp_line
			(start -0.7874 0.4064)
			(end -0.7874 -0.4064)
			(stroke
				(width 0.1524)
				(type default)
			)
			(layer "F.SilkS")
		)
		(fp_line
			(start 0.7874 -0.4064)
			(end 0.7874 0.4064)
			(stroke
				(width 0.1524)
				(type default)
			)
			(layer "F.SilkS")
		)
		(fp_line
			(start 0.7874 0.4064)
			(end -0.7874 0.4064)
			(stroke
				(width 0.1524)
				(type default)
			)
			(layer "F.SilkS")
		)
		(fp_line
			(start -0.67945 -0.305054)
			(end -0.12065 -0.305054)
			(stroke
				(width 0.1)
				(type default)
			)
			(layer "F.Fab")
		)
		(fp_line
			(start -0.67945 0.3048)
			(end -0.67945 -0.305054)
			(stroke
				(width 0.1)
				(type default)
			)
			(layer "F.Fab")
		)
		(fp_line
			(start -0.12065 -0.305054)
			(end -0.12065 -0.2794)
			(stroke
				(width 0.1)
				(type default)
			)
			(layer "F.Fab")
		)
		(fp_line
			(start -0.12065 -0.2794)
			(end 0.12065 -0.2794)
			(stroke
				(width 0.1)
				(type default)
			)
			(layer "F.Fab")
		)
		(fp_line
			(start -0.12065 0.2794)
			(end -0.12065 0.3048)
			(stroke
				(width 0.1)
				(type default)
			)
			(layer "F.Fab")
		)
		(fp_line
			(start -0.12065 0.3048)
			(end -0.67945 0.3048)
			(stroke
				(width 0.1)
				(type default)
			)
			(layer "F.Fab")
		)
		(fp_line
			(start 0.120396 0.2794)
			(end -0.12065 0.2794)
			(stroke
				(width 0.1)
				(type default)
			)
			(layer "F.Fab")
		)
		(fp_line
			(start 0.120396 0.3048)
			(end 0.120396 0.2794)
			(stroke
				(width 0.1)
				(type default)
			)
			(layer "F.Fab")
		)
		(fp_line
			(start 0.12065 -0.3048)
			(end 0.67945 -0.3048)
			(stroke
				(width 0.1)
				(type default)
			)
			(layer "F.Fab")
		)
		(fp_line
			(start 0.12065 -0.2794)
			(end 0.12065 -0.3048)
			(stroke
				(width 0.1)
				(type default)
			)
			(layer "F.Fab")
		)
		(fp_line
			(start 0.67945 -0.3048)
			(end 0.67945 0.3048)
			(stroke
				(width 0.1)
				(type default)
			)
			(layer "F.Fab")
		)
		(fp_line
			(start 0.67945 0.3048)
			(end 0.120396 0.3048)
			(stroke
				(width 0.1)
				(type default)
			)
			(layer "F.Fab")
		)
		(pad "1" smd rect
			(at -0.40005 0 180)
			(size 0.4572 0.508)
			(layers "F.Cu" "F.Mask" "F.Paste")
			(net "I3C_0_SPD_DDRAF_CPU1_R_SCL")
		)
		(pad "2" smd rect
			(at 0.40005 0 180)
			(size 0.4572 0.508)
			(layers "F.Cu" "F.Mask" "F.Paste")
			(net "I3C_SPD_DDRAF_CPU1_BYPASS_SCL")
		)
	)
	(footprint ""
		(layer "F.Cu")
		(at 304.305716 -437.820308 180)
		(property "Reference" "Q129"
			(at 1.52908 -1.79832 0)
			(unlocked yes)
			(layer "F.SilkS")
			(effects
				(font
					(size 0.7874 0.5842)
					(thickness 0.1524)
				)
				(justify left)
			)
		)
		(property "Value" ""
			(at 0 0 180)
			(layer "F.Fab")
			(effects
				(font
					(size 1.27 1.27)
				)
			)
		)
		(duplicate_pad_numbers_are_jumpers no)
		(fp_line
			(start 1.332738 1.100074)
			(end -1.332738 1.100074)
			(stroke
				(width 0.1524)
				(type default)
			)
			(layer "F.SilkS")
		)
		(fp_line
			(start 1.332738 -1.100074)
			(end 1.332738 1.100074)
			(stroke
				(width 0.1524)
				(type default)
			)
			(layer "F.SilkS")
		)
		(fp_line
			(start 0.4826 -1.100074)
			(end 1.332738 -1.100074)
			(stroke
				(width 0.1524)
				(type default)
			)
			(layer "F.SilkS")
		)
		(fp_line
			(start 0 -0.541274)
			(end 0.4826 -1.100074)
			(stroke
				(width 0.1524)
				(type default)
			)
			(layer "F.SilkS")
		)
		(fp_line
			(start -0.4826 -1.100074)
			(end 0 -0.541274)
			(stroke
				(width 0.1524)
				(type default)
			)
			(layer "F.SilkS")
		)
		(fp_line
			(start -1.332738 1.100074)
			(end -1.332738 -1.100074)
			(stroke
				(width 0.1524)
				(type default)
			)
			(layer "F.SilkS")
		)
		(fp_line
			(start -1.332738 -1.100074)
			(end -0.4826 -1.100074)
			(stroke
				(width 0.1524)
				(type default)
			)
			(layer "F.SilkS")
		)
		(fp_poly
			(pts
				(xy -1.489456 -1.189482) (xy -2.23393 -1.43764) (xy -1.737614 -1.933956)
			)
			(stroke
				(width 0)
				(type default)
			)
			(fill yes)
			(layer "F.SilkS")
		)
		(fp_line
			(start 0.674878 1.100074)
			(end -0.674878 1.100074)
			(stroke
				(width 0.1)
				(type default)
			)
			(layer "F.Fab")
		)
		(fp_line
			(start 0.674878 -1.100074)
			(end 0.674878 1.100074)
			(stroke
				(width 0.1)
				(type default)
			)
			(layer "F.Fab")
		)
		(fp_line
			(start -0.674878 1.100074)
			(end -0.674878 -1.100074)
			(stroke
				(width 0.1)
				(type default)
			)
			(layer "F.Fab")
		)
		(fp_line
			(start -0.674878 -1.100074)
			(end 0.674878 -1.100074)
			(stroke
				(width 0.1)
				(type default)
			)
			(layer "F.Fab")
		)
		(fp_poly
			(pts
				(xy -2.2352 -0.298958) (xy -2.2352 -1.001014) (xy -1.533144 -0.649986)
			)
			(stroke
				(width 0)
				(type default)
			)
			(fill yes)
			(layer "F.Fab")
		)
		(pad "1" smd rect
			(at -0.94996 -0.649986 270)
			(size 0.4318 0.508)
			(layers "F.Cu" "F.Mask" "F.Paste")
			(net "GND")
		)
		(pad "2" smd rect
			(at -0.94996 0 270)
			(size 0.4318 0.508)
			(layers "F.Cu" "F.Mask" "F.Paste")
			(net "GPU_3V3IO_RSVD5_FFU")
		)
		(pad "3" smd rect
			(at -0.94996 0.649986 270)
			(size 0.4318 0.508)
			(layers "F.Cu" "F.Mask" "F.Paste")
			(net "GPU_3V3IO_RSVD5_FFU_ISO")
		)
		(pad "4" smd rect
			(at 0.94996 0.649986 270)
			(size 0.4318 0.508)
			(layers "F.Cu" "F.Mask" "F.Paste")
			(net "GND")
		)
		(pad "5" smd rect
			(at 0.94996 0 270)
			(size 0.4318 0.508)
			(layers "F.Cu" "F.Mask" "F.Paste")
			(net "GPU_3V3IO_RSVD5_FFU_N")
		)
		(pad "6" smd rect
			(at 0.94996 -0.649986 270)
			(size 0.4318 0.508)
			(layers "F.Cu" "F.Mask" "F.Paste")
			(net "GPU_3V3IO_RSVD5_FFU_N")
		)
	)
	(footprint ""
		(layer "F.Cu")
		(at 364.165896 -256.012188 90)
		(property "Reference" "C2528"
			(at 0 0 90)
			(layer "F.SilkS")
			(hide yes)
			(effects
				(font
					(size 1.27 1.27)
				)
			)
		)
		(property "Value" ""
			(at 0 0 90)
			(layer "F.Fab")
			(effects
				(font
					(size 1.27 1.27)
				)
			)
		)
		(duplicate_pad_numbers_are_jumpers no)
		(fp_line
			(start 0.7874 -0.4064)
			(end 0.7874 0.4064)
			(stroke
				(width 0.1524)
				(type default)
			)
			(layer "F.SilkS")
		)
		(fp_line
			(start -0.7874 -0.4064)
			(end 0.7874 -0.4064)
			(stroke
				(width 0.1524)
				(type default)
			)
			(layer "F.SilkS")
		)
		(fp_line
			(start 0.7874 0.4064)
			(end -0.7874 0.4064)
			(stroke
				(width 0.1524)
				(type default)
			)
			(layer "F.SilkS")
		)
		(fp_line
			(start -0.7874 0.4064)
			(end -0.7874 -0.4064)
			(stroke
				(width 0.1524)
				(type default)
			)
			(layer "F.SilkS")
		)
		(fp_line
			(start -0.12065 -0.305054)
			(end -0.12065 -0.2794)
			(stroke
				(width 0.1)
				(type default)
			)
			(layer "F.Fab")
		)
		(fp_line
			(start -0.67945 -0.305054)
			(end -0.12065 -0.305054)
			(stroke
				(width 0.1)
				(type default)
			)
			(layer "F.Fab")
		)
		(fp_line
			(start 0.67945 -0.3048)
			(end 0.67945 0.3048)
			(stroke
				(width 0.1)
				(type default)
			)
			(layer "F.Fab")
		)
		(fp_line
			(start 0.12065 -0.3048)
			(end 0.67945 -0.3048)
			(stroke
				(width 0.1)
				(type default)
			)
			(layer "F.Fab")
		)
		(fp_line
			(start 0.12065 -0.2794)
			(end 0.12065 -0.3048)
			(stroke
				(width 0.1)
				(type default)
			)
			(layer "F.Fab")
		)
		(fp_line
			(start -0.12065 -0.2794)
			(end 0.12065 -0.2794)
			(stroke
				(width 0.1)
				(type default)
			)
			(layer "F.Fab")
		)
		(fp_line
			(start 0.120396 0.2794)
			(end -0.12065 0.2794)
			(stroke
				(width 0.1)
				(type default)
			)
			(layer "F.Fab")
		)
		(fp_line
			(start -0.12065 0.2794)
			(end -0.12065 0.3048)
			(stroke
				(width 0.1)
				(type default)
			)
			(layer "F.Fab")
		)
		(fp_line
			(start 0.67945 0.3048)
			(end 0.120396 0.3048)
			(stroke
				(width 0.1)
				(type default)
			)
			(layer "F.Fab")
		)
		(fp_line
			(start 0.120396 0.3048)
			(end 0.120396 0.2794)
			(stroke
				(width 0.1)
				(type default)
			)
			(layer "F.Fab")
		)
		(fp_line
			(start -0.12065 0.3048)
			(end -0.67945 0.3048)
			(stroke
				(width 0.1)
				(type default)
			)
			(layer "F.Fab")
		)
		(fp_line
			(start -0.67945 0.3048)
			(end -0.67945 -0.305054)
			(stroke
				(width 0.1)
				(type default)
			)
			(layer "F.Fab")
		)
		(pad "1" smd circle
			(at -0.40005 0 90)
			(size 0 0)
			(layers "F.Cu" "F.Mask" "F.Paste")
			(net "PVDDCR_SOC_P0")
		)
		(pad "2" smd circle
			(at 0.40005 0 90)
			(size 0 0)
			(layers "F.Cu" "F.Mask" "F.Paste")
			(net "GND")
		)
	)
	(footprint ""
		(layer "F.Cu")
		(at 301.621952 -22.12975)
		(property "Reference" "C1563"
			(at 0 0 0)
			(layer "F.SilkS")
			(hide yes)
			(effects
				(font
					(size 1.27 1.27)
				)
			)
		)
		(property "Value" ""
			(at 0 0 0)
			(layer "F.Fab")
			(effects
				(font
					(size 1.27 1.27)
				)
			)
		)
		(duplicate_pad_numbers_are_jumpers no)
		(fp_line
			(start -0.7874 -0.4064)
			(end 0.7874 -0.4064)
			(stroke
				(width 0.1524)
				(type default)
			)
			(layer "F.SilkS")
		)
		(fp_line
			(start -0.7874 0.4064)
			(end -0.7874 -0.4064)
			(stroke
				(width 0.1524)
				(type default)
			)
			(layer "F.SilkS")
		)
		(fp_line
			(start 0.7874 -0.4064)
			(end 0.7874 0.4064)
			(stroke
				(width 0.1524)
				(type default)
			)
			(layer "F.SilkS")
		)
		(fp_line
			(start 0.7874 0.4064)
			(end -0.7874 0.4064)
			(stroke
				(width 0.1524)
				(type default)
			)
			(layer "F.SilkS")
		)
		(fp_line
			(start -0.67945 -0.305054)
			(end -0.12065 -0.305054)
			(stroke
				(width 0.1)
				(type default)
			)
			(layer "F.Fab")
		)
		(fp_line
			(start -0.67945 0.3048)
			(end -0.67945 -0.305054)
			(stroke
				(width 0.1)
				(type default)
			)
			(layer "F.Fab")
		)
		(fp_line
			(start -0.12065 -0.305054)
			(end -0.12065 -0.2794)
			(stroke
				(width 0.1)
				(type default)
			)
			(layer "F.Fab")
		)
		(fp_line
			(start -0.12065 -0.2794)
			(end 0.12065 -0.2794)
			(stroke
				(width 0.1)
				(type default)
			)
			(layer "F.Fab")
		)
		(fp_line
			(start -0.12065 0.2794)
			(end -0.12065 0.3048)
			(stroke
				(width 0.1)
				(type default)
			)
			(layer "F.Fab")
		)
		(fp_line
			(start -0.12065 0.3048)
			(end -0.67945 0.3048)
			(stroke
				(width 0.1)
				(type default)
			)
			(layer "F.Fab")
		)
		(fp_line
			(start 0.120396 0.2794)
			(end -0.12065 0.2794)
			(stroke
				(width 0.1)
				(type default)
			)
			(layer "F.Fab")
		)
		(fp_line
			(start 0.120396 0.3048)
			(end 0.120396 0.2794)
			(stroke
				(width 0.1)
				(type default)
			)
			(layer "F.Fab")
		)
		(fp_line
			(start 0.12065 -0.3048)
			(end 0.67945 -0.3048)
			(stroke
				(width 0.1)
				(type default)
			)
			(layer "F.Fab")
		)
		(fp_line
			(start 0.12065 -0.2794)
			(end 0.12065 -0.3048)
			(stroke
				(width 0.1)
				(type default)
			)
			(layer "F.Fab")
		)
		(fp_line
			(start 0.67945 -0.3048)
			(end 0.67945 0.3048)
			(stroke
				(width 0.1)
				(type default)
			)
			(layer "F.Fab")
		)
		(fp_line
			(start 0.67945 0.3048)
			(end 0.120396 0.3048)
			(stroke
				(width 0.1)
				(type default)
			)
			(layer "F.Fab")
		)
		(pad "1" smd circle
			(at -0.40005 0)
			(size 0 0)
			(layers "F.Cu" "F.Mask" "F.Paste")
			(net "CLR_CMOS")
		)
		(pad "2" smd circle
			(at 0.40005 0)
			(size 0 0)
			(layers "F.Cu" "F.Mask" "F.Paste")
			(net "GND")
		)
	)
	(footprint ""
		(layer "F.Cu")
		(at 200.939908 -109.561376 180)
		(property "Reference" "R6047"
			(at 0 0 180)
			(layer "F.SilkS")
			(hide yes)
			(effects
				(font
					(size 1.27 1.27)
				)
			)
		)
		(property "Value" ""
			(at 0 0 180)
			(layer "F.Fab")
			(effects
				(font
					(size 1.27 1.27)
				)
			)
		)
		(duplicate_pad_numbers_are_jumpers no)
		(fp_line
			(start 0.7874 0.4064)
			(end -0.7874 0.4064)
			(stroke
				(width 0.1524)
				(type default)
			)
			(layer "F.SilkS")
		)
		(fp_line
			(start 0.7874 -0.4064)
			(end 0.7874 0.4064)
			(stroke
				(width 0.1524)
				(type default)
			)
			(layer "F.SilkS")
		)
		(fp_line
			(start -0.7874 0.4064)
			(end -0.7874 -0.4064)
			(stroke
				(width 0.1524)
				(type default)
			)
			(layer "F.SilkS")
		)
		(fp_line
			(start -0.7874 -0.4064)
			(end 0.7874 -0.4064)
			(stroke
				(width 0.1524)
				(type default)
			)
			(layer "F.SilkS")
		)
		(fp_line
			(start 0.67945 0.3048)
			(end 0.120396 0.3048)
			(stroke
				(width 0.1)
				(type default)
			)
			(layer "F.Fab")
		)
		(fp_line
			(start 0.67945 -0.3048)
			(end 0.67945 0.3048)
			(stroke
				(width 0.1)
				(type default)
			)
			(layer "F.Fab")
		)
		(fp_line
			(start 0.12065 -0.2794)
			(end 0.12065 -0.3048)
			(stroke
				(width 0.1)
				(type default)
			)
			(layer "F.Fab")
		)
		(fp_line
			(start 0.12065 -0.3048)
			(end 0.67945 -0.3048)
			(stroke
				(width 0.1)
				(type default)
			)
			(layer "F.Fab")
		)
		(fp_line
			(start 0.120396 0.3048)
			(end 0.120396 0.2794)
			(stroke
				(width 0.1)
				(type default)
			)
			(layer "F.Fab")
		)
		(fp_line
			(start 0.120396 0.2794)
			(end -0.12065 0.2794)
			(stroke
				(width 0.1)
				(type default)
			)
			(layer "F.Fab")
		)
		(fp_line
			(start -0.12065 0.3048)
			(end -0.67945 0.3048)
			(stroke
				(width 0.1)
				(type default)
			)
			(layer "F.Fab")
		)
		(fp_line
			(start -0.12065 0.2794)
			(end -0.12065 0.3048)
			(stroke
				(width 0.1)
				(type default)
			)
			(layer "F.Fab")
		)
		(fp_line
			(start -0.12065 -0.2794)
			(end 0.12065 -0.2794)
			(stroke
				(width 0.1)
				(type default)
			)
			(layer "F.Fab")
		)
		(fp_line
			(start -0.12065 -0.305054)
			(end -0.12065 -0.2794)
			(stroke
				(width 0.1)
				(type default)
			)
			(layer "F.Fab")
		)
		(fp_line
			(start -0.67945 0.3048)
			(end -0.67945 -0.305054)
			(stroke
				(width 0.1)
				(type default)
			)
			(layer "F.Fab")
		)
		(fp_line
			(start -0.67945 -0.305054)
			(end -0.12065 -0.305054)
			(stroke
				(width 0.1)
				(type default)
			)
			(layer "F.Fab")
		)
		(pad "1" smd circle
			(at -0.40005 0 180)
			(size 0 0)
			(layers "F.Cu" "F.Mask" "F.Paste")
			(net "PWRGD_P3V3_AUX")
		)
		(pad "2" smd circle
			(at 0.40005 0 180)
			(size 0 0)
			(layers "F.Cu" "F.Mask" "F.Paste")
			(net "PWRGD_P3V3_AUX_R")
		)
	)
	(footprint ""
		(layer "F.Cu")
		(at 201.086212 -351.825052)
		(property "Reference" "H49"
			(at -3.0226 -3.96113 0)
			(unlocked yes)
			(layer "F.SilkS")
			(effects
				(font
					(size 0.7874 0.5842)
					(thickness 0.1524)
				)
				(justify left)
			)
		)
		(property "Value" ""
			(at 0 0 0)
			(layer "F.Fab")
			(effects
				(font
					(size 1.27 1.27)
				)
			)
		)
		(duplicate_pad_numbers_are_jumpers no)
		(pad "1" thru_hole circle
			(at 0 0)
			(size 6.1976 6.1976)
			(drill 3.7338)
			(layers "*.Cu" "*.Mask")
			(remove_unused_layers no)
			(net "GND")
			(clearance -0.9779)
			(padstack
				(mode front_inner_back)
				(layer "Inner"
					(shape circle)
					(size 5.5372 5.5372)
					(clearance -0.6477)
				)
				(layer "B.Cu"
					(shape circle)
					(size 6.1976 6.1976)
					(clearance -0.9779)
				)
			)
		)
	)
	(footprint ""
		(layer "F.Cu")
		(at 147.69084 -93.174058 180)
		(property "Reference" "R3307"
			(at 0 0 180)
			(layer "F.SilkS")
			(hide yes)
			(effects
				(font
					(size 1.27 1.27)
				)
			)
		)
		(property "Value" ""
			(at 0 0 180)
			(layer "F.Fab")
			(effects
				(font
					(size 1.27 1.27)
				)
			)
		)
		(duplicate_pad_numbers_are_jumpers no)
		(fp_line
			(start 0.7874 0.4064)
			(end -0.7874 0.4064)
			(stroke
				(width 0.1524)
				(type default)
			)
			(layer "F.SilkS")
		)
		(fp_line
			(start 0.7874 -0.4064)
			(end 0.7874 0.4064)
			(stroke
				(width 0.1524)
				(type default)
			)
			(layer "F.SilkS")
		)
		(fp_line
			(start -0.7874 0.4064)
			(end -0.7874 -0.4064)
			(stroke
				(width 0.1524)
				(type default)
			)
			(layer "F.SilkS")
		)
		(fp_line
			(start -0.7874 -0.4064)
			(end 0.7874 -0.4064)
			(stroke
				(width 0.1524)
				(type default)
			)
			(layer "F.SilkS")
		)
		(fp_line
			(start 0.67945 0.3048)
			(end 0.120396 0.3048)
			(stroke
				(width 0.1)
				(type default)
			)
			(layer "F.Fab")
		)
		(fp_line
			(start 0.67945 -0.3048)
			(end 0.67945 0.3048)
			(stroke
				(width 0.1)
				(type default)
			)
			(layer "F.Fab")
		)
		(fp_line
			(start 0.12065 -0.2794)
			(end 0.12065 -0.3048)
			(stroke
				(width 0.1)
				(type default)
			)
			(layer "F.Fab")
		)
		(fp_line
			(start 0.12065 -0.3048)
			(end 0.67945 -0.3048)
			(stroke
				(width 0.1)
				(type default)
			)
			(layer "F.Fab")
		)
		(fp_line
			(start 0.120396 0.3048)
			(end 0.120396 0.2794)
			(stroke
				(width 0.1)
				(type default)
			)
			(layer "F.Fab")
		)
		(fp_line
			(start 0.120396 0.2794)
			(end -0.12065 0.2794)
			(stroke
				(width 0.1)
				(type default)
			)
			(layer "F.Fab")
		)
		(fp_line
			(start -0.12065 0.3048)
			(end -0.67945 0.3048)
			(stroke
				(width 0.1)
				(type default)
			)
			(layer "F.Fab")
		)
		(fp_line
			(start -0.12065 0.2794)
			(end -0.12065 0.3048)
			(stroke
				(width 0.1)
				(type default)
			)
			(layer "F.Fab")
		)
		(fp_line
			(start -0.12065 -0.2794)
			(end 0.12065 -0.2794)
			(stroke
				(width 0.1)
				(type default)
			)
			(layer "F.Fab")
		)
		(fp_line
			(start -0.12065 -0.305054)
			(end -0.12065 -0.2794)
			(stroke
				(width 0.1)
				(type default)
			)
			(layer "F.Fab")
		)
		(fp_line
			(start -0.67945 0.3048)
			(end -0.67945 -0.305054)
			(stroke
				(width 0.1)
				(type default)
			)
			(layer "F.Fab")
		)
		(fp_line
			(start -0.67945 -0.305054)
			(end -0.12065 -0.305054)
			(stroke
				(width 0.1)
				(type default)
			)
			(layer "F.Fab")
		)
		(pad "1" smd circle
			(at -0.40005 0 180)
			(size 0 0)
			(layers "F.Cu" "F.Mask" "F.Paste")
			(net "OCP_SFF_RBT_ARB_IN_MUX2")
		)
		(pad "2" smd circle
			(at 0.40005 0 180)
			(size 0 0)
			(layers "F.Cu" "F.Mask" "F.Paste")
			(net "OCP_SFF_RBT_ARB_IN_MUX2_R")
		)
	)
	(footprint ""
		(layer "F.Cu")
		(at 232.732072 -69.560186 90)
		(property "Reference" "R1000"
			(at 0 0 90)
			(layer "F.SilkS")
			(hide yes)
			(effects
				(font
					(size 1.27 1.27)
				)
			)
		)
		(property "Value" ""
			(at 0 0 90)
			(layer "F.Fab")
			(effects
				(font
					(size 1.27 1.27)
				)
			)
		)
		(duplicate_pad_numbers_are_jumpers no)
		(fp_line
			(start 0.7874 -0.4064)
			(end 0.7874 0.4064)
			(stroke
				(width 0.1524)
				(type default)
			)
			(layer "F.SilkS")
		)
		(fp_line
			(start -0.7874 -0.4064)
			(end 0.7874 -0.4064)
			(stroke
				(width 0.1524)
				(type default)
			)
			(layer "F.SilkS")
		)
		(fp_line
			(start 0.7874 0.4064)
			(end -0.7874 0.4064)
			(stroke
				(width 0.1524)
				(type default)
			)
			(layer "F.SilkS")
		)
		(fp_line
			(start -0.7874 0.4064)
			(end -0.7874 -0.4064)
			(stroke
				(width 0.1524)
				(type default)
			)
			(layer "F.SilkS")
		)
		(fp_line
			(start -0.12065 -0.305054)
			(end -0.12065 -0.2794)
			(stroke
				(width 0.1)
				(type default)
			)
			(layer "F.Fab")
		)
		(fp_line
			(start -0.67945 -0.305054)
			(end -0.12065 -0.305054)
			(stroke
				(width 0.1)
				(type default)
			)
			(layer "F.Fab")
		)
		(fp_line
			(start 0.67945 -0.3048)
			(end 0.67945 0.3048)
			(stroke
				(width 0.1)
				(type default)
			)
			(layer "F.Fab")
		)
		(fp_line
			(start 0.12065 -0.3048)
			(end 0.67945 -0.3048)
			(stroke
				(width 0.1)
				(type default)
			)
			(layer "F.Fab")
		)
		(fp_line
			(start 0.12065 -0.2794)
			(end 0.12065 -0.3048)
			(stroke
				(width 0.1)
				(type default)
			)
			(layer "F.Fab")
		)
		(fp_line
			(start -0.12065 -0.2794)
			(end 0.12065 -0.2794)
			(stroke
				(width 0.1)
				(type default)
			)
			(layer "F.Fab")
		)
		(fp_line
			(start 0.120396 0.2794)
			(end -0.12065 0.2794)
			(stroke
				(width 0.1)
				(type default)
			)
			(layer "F.Fab")
		)
		(fp_line
			(start -0.12065 0.2794)
			(end -0.12065 0.3048)
			(stroke
				(width 0.1)
				(type default)
			)
			(layer "F.Fab")
		)
		(fp_line
			(start 0.67945 0.3048)
			(end 0.120396 0.3048)
			(stroke
				(width 0.1)
				(type default)
			)
			(layer "F.Fab")
		)
		(fp_line
			(start 0.120396 0.3048)
			(end 0.120396 0.2794)
			(stroke
				(width 0.1)
				(type default)
			)
			(layer "F.Fab")
		)
		(fp_line
			(start -0.12065 0.3048)
			(end -0.67945 0.3048)
			(stroke
				(width 0.1)
				(type default)
			)
			(layer "F.Fab")
		)
		(fp_line
			(start -0.67945 0.3048)
			(end -0.67945 -0.305054)
			(stroke
				(width 0.1)
				(type default)
			)
			(layer "F.Fab")
		)
		(pad "1" smd circle
			(at -0.40005 0 90)
			(size 0 0)
			(layers "F.Cu" "F.Mask" "F.Paste")
			(net "FM_LED_ACTIVE_E1S_0_BUF")
		)
		(pad "2" smd circle
			(at 0.40005 0 90)
			(size 0 0)
			(layers "F.Cu" "F.Mask" "F.Paste")
			(net "GND")
		)
	)
	(footprint ""
		(layer "F.Cu")
		(at 426.974 -364.49 -90)
		(property "Reference" "PR601"
			(at 0 0 270)
			(layer "F.SilkS")
			(hide yes)
			(effects
				(font
					(size 1.27 1.27)
				)
			)
		)
		(property "Value" ""
			(at 0 0 270)
			(layer "F.Fab")
			(effects
				(font
					(size 1.27 1.27)
				)
			)
		)
		(duplicate_pad_numbers_are_jumpers no)
		(fp_line
			(start -0.7874 0.4064)
			(end -0.7874 -0.4064)
			(stroke
				(width 0.1524)
				(type default)
			)
			(layer "F.SilkS")
		)
		(fp_line
			(start 0.7874 0.4064)
			(end -0.7874 0.4064)
			(stroke
				(width 0.1524)
				(type default)
			)
			(layer "F.SilkS")
		)
		(fp_line
			(start -0.7874 -0.4064)
			(end 0.7874 -0.4064)
			(stroke
				(width 0.1524)
				(type default)
			)
			(layer "F.SilkS")
		)
		(fp_line
			(start 0.7874 -0.4064)
			(end 0.7874 0.4064)
			(stroke
				(width 0.1524)
				(type default)
			)
			(layer "F.SilkS")
		)
		(fp_line
			(start -0.67945 0.3048)
			(end -0.67945 -0.305054)
			(stroke
				(width 0.1)
				(type default)
			)
			(layer "F.Fab")
		)
		(fp_line
			(start -0.12065 0.3048)
			(end -0.67945 0.3048)
			(stroke
				(width 0.1)
				(type default)
			)
			(layer "F.Fab")
		)
		(fp_line
			(start 0.120396 0.3048)
			(end 0.120396 0.2794)
			(stroke
				(width 0.1)
				(type default)
			)
			(layer "F.Fab")
		)
		(fp_line
			(start 0.67945 0.3048)
			(end 0.120396 0.3048)
			(stroke
				(width 0.1)
				(type default)
			)
			(layer "F.Fab")
		)
		(fp_line
			(start -0.12065 0.2794)
			(end -0.12065 0.3048)
			(stroke
				(width 0.1)
				(type default)
			)
			(layer "F.Fab")
		)
		(fp_line
			(start 0.120396 0.2794)
			(end -0.12065 0.2794)
			(stroke
				(width 0.1)
				(type default)
			)
			(layer "F.Fab")
		)
		(fp_line
			(start -0.12065 -0.2794)
			(end 0.12065 -0.2794)
			(stroke
				(width 0.1)
				(type default)
			)
			(layer "F.Fab")
		)
		(fp_line
			(start 0.12065 -0.2794)
			(end 0.12065 -0.3048)
			(stroke
				(width 0.1)
				(type default)
			)
			(layer "F.Fab")
		)
		(fp_line
			(start 0.12065 -0.3048)
			(end 0.67945 -0.3048)
			(stroke
				(width 0.1)
				(type default)
			)
			(layer "F.Fab")
		)
		(fp_line
			(start 0.67945 -0.3048)
			(end 0.67945 0.3048)
			(stroke
				(width 0.1)
				(type default)
			)
			(layer "F.Fab")
		)
		(fp_line
			(start -0.67945 -0.305054)
			(end -0.12065 -0.305054)
			(stroke
				(width 0.1)
				(type default)
			)
			(layer "F.Fab")
		)
		(fp_line
			(start -0.12065 -0.305054)
			(end -0.12065 -0.2794)
			(stroke
				(width 0.1)
				(type default)
			)
			(layer "F.Fab")
		)
		(pad "1" smd circle
			(at -0.40005 0 270)
			(size 0 0)
			(layers "F.Cu" "F.Mask" "F.Paste")
			(net "PVDD11_S3_P0_VINSEN")
		)
		(pad "2" smd circle
			(at 0.40005 0 270)
			(size 0 0)
			(layers "F.Cu" "F.Mask" "F.Paste")
			(net "GND")
		)
	)
	(footprint ""
		(layer "F.Cu")
		(at 26.793444 -426.609256 180)
		(property "Reference" "R3282"
			(at 0 0 180)
			(layer "F.SilkS")
			(hide yes)
			(effects
				(font
					(size 1.27 1.27)
				)
			)
		)
		(property "Value" ""
			(at 0 0 180)
			(layer "F.Fab")
			(effects
				(font
					(size 1.27 1.27)
				)
			)
		)
		(duplicate_pad_numbers_are_jumpers no)
		(fp_line
			(start 0.7874 0.4064)
			(end -0.7874 0.4064)
			(stroke
				(width 0.1524)
				(type default)
			)
			(layer "F.SilkS")
		)
		(fp_line
			(start 0.7874 -0.4064)
			(end 0.7874 0.4064)
			(stroke
				(width 0.1524)
				(type default)
			)
			(layer "F.SilkS")
		)
		(fp_line
			(start -0.7874 0.4064)
			(end -0.7874 -0.4064)
			(stroke
				(width 0.1524)
				(type default)
			)
			(layer "F.SilkS")
		)
		(fp_line
			(start -0.7874 -0.4064)
			(end 0.7874 -0.4064)
			(stroke
				(width 0.1524)
				(type default)
			)
			(layer "F.SilkS")
		)
		(fp_line
			(start 0.67945 0.3048)
			(end 0.120396 0.3048)
			(stroke
				(width 0.1)
				(type default)
			)
			(layer "F.Fab")
		)
		(fp_line
			(start 0.67945 -0.3048)
			(end 0.67945 0.3048)
			(stroke
				(width 0.1)
				(type default)
			)
			(layer "F.Fab")
		)
		(fp_line
			(start 0.12065 -0.2794)
			(end 0.12065 -0.3048)
			(stroke
				(width 0.1)
				(type default)
			)
			(layer "F.Fab")
		)
		(fp_line
			(start 0.12065 -0.3048)
			(end 0.67945 -0.3048)
			(stroke
				(width 0.1)
				(type default)
			)
			(layer "F.Fab")
		)
		(fp_line
			(start 0.120396 0.3048)
			(end 0.120396 0.2794)
			(stroke
				(width 0.1)
				(type default)
			)
			(layer "F.Fab")
		)
		(fp_line
			(start 0.120396 0.2794)
			(end -0.12065 0.2794)
			(stroke
				(width 0.1)
				(type default)
			)
			(layer "F.Fab")
		)
		(fp_line
			(start -0.12065 0.3048)
			(end -0.67945 0.3048)
			(stroke
				(width 0.1)
				(type default)
			)
			(layer "F.Fab")
		)
		(fp_line
			(start -0.12065 0.2794)
			(end -0.12065 0.3048)
			(stroke
				(width 0.1)
				(type default)
			)
			(layer "F.Fab")
		)
		(fp_line
			(start -0.12065 -0.2794)
			(end 0.12065 -0.2794)
			(stroke
				(width 0.1)
				(type default)
			)
			(layer "F.Fab")
		)
		(fp_line
			(start -0.12065 -0.305054)
			(end -0.12065 -0.2794)
			(stroke
				(width 0.1)
				(type default)
			)
			(layer "F.Fab")
		)
		(fp_line
			(start -0.67945 0.3048)
			(end -0.67945 -0.305054)
			(stroke
				(width 0.1)
				(type default)
			)
			(layer "F.Fab")
		)
		(fp_line
			(start -0.67945 -0.305054)
			(end -0.12065 -0.305054)
			(stroke
				(width 0.1)
				(type default)
			)
			(layer "F.Fab")
		)
		(pad "1" smd circle
			(at -0.40005 0 180)
			(size 0 0)
			(layers "F.Cu" "F.Mask" "F.Paste")
			(net "FM_P2E_EQB0")
		)
		(pad "2" smd circle
			(at 0.40005 0 180)
			(size 0 0)
			(layers "F.Cu" "F.Mask" "F.Paste")
			(net "GND")
		)
	)
	(footprint ""
		(layer "F.Cu")
		(at 119.36857 -171.925234 90)
		(property "Reference" "PC321_SOP1_1"
			(at 0 0 90)
			(layer "F.SilkS")
			(hide yes)
			(effects
				(font
					(size 1.27 1.27)
				)
			)
		)
		(property "Value" ""
			(at 0 0 90)
			(layer "F.Fab")
			(effects
				(font
					(size 1.27 1.27)
				)
			)
		)
		(duplicate_pad_numbers_are_jumpers no)
		(fp_line
			(start 0.7874 -0.4064)
			(end 0.7874 0.4064)
			(stroke
				(width 0.1524)
				(type default)
			)
			(layer "F.SilkS")
		)
		(fp_line
			(start -0.7874 -0.4064)
			(end 0.7874 -0.4064)
			(stroke
				(width 0.1524)
				(type default)
			)
			(layer "F.SilkS")
		)
		(fp_line
			(start 0.7874 0.4064)
			(end -0.7874 0.4064)
			(stroke
				(width 0.1524)
				(type default)
			)
			(layer "F.SilkS")
		)
		(fp_line
			(start -0.7874 0.4064)
			(end -0.7874 -0.4064)
			(stroke
				(width 0.1524)
				(type default)
			)
			(layer "F.SilkS")
		)
		(fp_line
			(start -0.12065 -0.305054)
			(end -0.12065 -0.2794)
			(stroke
				(width 0.1)
				(type default)
			)
			(layer "F.Fab")
		)
		(fp_line
			(start -0.67945 -0.305054)
			(end -0.12065 -0.305054)
			(stroke
				(width 0.1)
				(type default)
			)
			(layer "F.Fab")
		)
		(fp_line
			(start 0.67945 -0.3048)
			(end 0.67945 0.3048)
			(stroke
				(width 0.1)
				(type default)
			)
			(layer "F.Fab")
		)
		(fp_line
			(start 0.12065 -0.3048)
			(end 0.67945 -0.3048)
			(stroke
				(width 0.1)
				(type default)
			)
			(layer "F.Fab")
		)
		(fp_line
			(start 0.12065 -0.2794)
			(end 0.12065 -0.3048)
			(stroke
				(width 0.1)
				(type default)
			)
			(layer "F.Fab")
		)
		(fp_line
			(start -0.12065 -0.2794)
			(end 0.12065 -0.2794)
			(stroke
				(width 0.1)
				(type default)
			)
			(layer "F.Fab")
		)
		(fp_line
			(start 0.120396 0.2794)
			(end -0.12065 0.2794)
			(stroke
				(width 0.1)
				(type default)
			)
			(layer "F.Fab")
		)
		(fp_line
			(start -0.12065 0.2794)
			(end -0.12065 0.3048)
			(stroke
				(width 0.1)
				(type default)
			)
			(layer "F.Fab")
		)
		(fp_line
			(start 0.67945 0.3048)
			(end 0.120396 0.3048)
			(stroke
				(width 0.1)
				(type default)
			)
			(layer "F.Fab")
		)
		(fp_line
			(start 0.120396 0.3048)
			(end 0.120396 0.2794)
			(stroke
				(width 0.1)
				(type default)
			)
			(layer "F.Fab")
		)
		(fp_line
			(start -0.12065 0.3048)
			(end -0.67945 0.3048)
			(stroke
				(width 0.1)
				(type default)
			)
			(layer "F.Fab")
		)
		(fp_line
			(start -0.67945 0.3048)
			(end -0.67945 -0.305054)
			(stroke
				(width 0.1)
				(type default)
			)
			(layer "F.Fab")
		)
		(pad "1" smd circle
			(at -0.40005 0 90)
			(size 0 0)
			(layers "F.Cu" "F.Mask" "F.Paste")
			(net "PVDDCR_CPU0_P1_PVCC")
		)
		(pad "2" smd circle
			(at 0.40005 0 90)
			(size 0 0)
			(layers "F.Cu" "F.Mask" "F.Paste")
			(net "GND")
		)
	)
	(footprint ""
		(layer "F.Cu")
		(at 61.0235 -111.940848)
		(property "Reference" "ME12"
			(at 0 0 0)
			(layer "F.SilkS")
			(hide yes)
			(effects
				(font
					(size 1.27 1.27)
				)
			)
		)
		(property "Value" ""
			(at 0 0 0)
			(layer "F.Fab")
			(effects
				(font
					(size 1.27 1.27)
				)
			)
		)
		(duplicate_pad_numbers_are_jumpers no)
		(zone
			(layer "F.Cu")
			(hatch none 0.5)
			(connect_pads
				(clearance 0)
			)
			(min_thickness 0.25)
			(keepout
				(tracks allowed)
				(vias allowed)
				(pads allowed)
				(copperpour allowed)
				(footprints not_allowed)
			)
			(placement
				(enabled no)
				(sheetname "")
			)
			(fill
				(thermal_gap 0.5)
				(thermal_bridge_width 0.5)
				(island_removal_mode 0)
			)
			(polygon
				(pts
					(arc
						(start 71.02348 -111.940848)
						(mid 51.02352 -111.940848)
						(end 71.02348 -111.940848)
					)
				)
			)
		)
	)
	(footprint ""
		(layer "F.Cu")
		(at 95.453454 -335.029302)
		(property "Reference" "PU38"
			(at -2.616454 -8.479028 0)
			(unlocked yes)
			(layer "F.SilkS")
			(effects
				(font
					(size 0.7874 0.5842)
					(thickness 0.1524)
				)
				(justify left)
			)
		)
		(property "Value" ""
			(at 0 0 0)
			(layer "F.Fab")
			(effects
				(font
					(size 1.27 1.27)
				)
			)
		)
		(duplicate_pad_numbers_are_jumpers no)
		(fp_line
			(start -2.500122 -2.999994)
			(end -2.24409 -2.999994)
			(stroke
				(width 0.1524)
				(type default)
			)
			(layer "F.SilkS")
		)
		(fp_line
			(start -2.500122 -2.529078)
			(end -2.500122 -2.999994)
			(stroke
				(width 0.1524)
				(type default)
			)
			(layer "F.SilkS")
		)
		(fp_line
			(start -2.500122 0.6604)
			(end -2.500122 0.229108)
			(stroke
				(width 0.1524)
				(type default)
			)
			(layer "F.SilkS")
		)
		(fp_line
			(start -2.500122 2.999994)
			(end -2.500122 2.339594)
			(stroke
				(width 0.1524)
				(type default)
			)
			(layer "F.SilkS")
		)
		(fp_line
			(start -2.2987 2.999994)
			(end -2.500122 2.999994)
			(stroke
				(width 0.1524)
				(type default)
			)
			(layer "F.SilkS")
		)
		(fp_line
			(start 2.31394 -2.999994)
			(end 2.500122 -2.999994)
			(stroke
				(width 0.1524)
				(type default)
			)
			(layer "F.SilkS")
		)
		(fp_line
			(start 2.500122 -2.999994)
			(end 2.500122 -2.44348)
			(stroke
				(width 0.1524)
				(type default)
			)
			(layer "F.SilkS")
		)
		(fp_line
			(start 2.500122 2.339594)
			(end 2.500122 2.999994)
			(stroke
				(width 0.1524)
				(type default)
			)
			(layer "F.SilkS")
		)
		(fp_line
			(start 2.500122 2.999994)
			(end 2.2987 2.999994)
			(stroke
				(width 0.1524)
				(type default)
			)
			(layer "F.SilkS")
		)
		(fp_poly
			(pts
				(xy -2.742184 -2.419096) (xy -3.415538 -2.643632) (xy -2.966466 -3.092704)
			)
			(stroke
				(width 0)
				(type default)
			)
			(fill yes)
			(layer "F.SilkS")
		)
		(fp_line
			(start -2.500122 -2.999994)
			(end 2.500122 -2.999994)
			(stroke
				(width 0.1)
				(type default)
			)
			(layer "F.Fab")
		)
		(fp_line
			(start -2.500122 2.999994)
			(end -2.500122 -2.999994)
			(stroke
				(width 0.1)
				(type default)
			)
			(layer "F.Fab")
		)
		(fp_line
			(start 2.500122 -2.999994)
			(end 2.500122 2.999994)
			(stroke
				(width 0.1)
				(type default)
			)
			(layer "F.Fab")
		)
		(fp_line
			(start 2.500122 2.999994)
			(end -2.500122 2.999994)
			(stroke
				(width 0.1)
				(type default)
			)
			(layer "F.Fab")
		)
		(fp_poly
			(pts
				(xy -4.218432 -2.783078) (xy -4.218432 -1.767078) (xy -3.202432 -2.275078)
			)
			(stroke
				(width 0)
				(type default)
			)
			(fill yes)
			(layer "F.Fab")
		)
		(pad "1" smd rect
			(at -2.400046 -2.275078 90)
			(size 0.2286 0.6096)
			(layers "F.Cu" "F.Mask" "F.Paste")
			(net "PVDDCR_CPU1_P1_VOS5")
		)
		(pad "2" smd rect
			(at -2.400046 -1.82499 90)
			(size 0.2286 0.6096)
			(layers "F.Cu" "F.Mask" "F.Paste")
			(net "GND")
		)
		(pad "3" smd rect
			(at -2.400046 -1.374902 90)
			(size 0.2286 0.6096)
			(layers "F.Cu" "F.Mask" "F.Paste")
			(net "PVDDCR_CPU1_P1_VCC5")
		)
		(pad "4" smd rect
			(at -2.400046 -0.925068 90)
			(size 0.2286 0.6096)
			(layers "F.Cu" "F.Mask" "F.Paste")
			(net "PVDDCR_CPU1_P1_PVCC")
		)
		(pad "5" smd rect
			(at -2.400046 -0.47498 90)
			(size 0.2286 0.6096)
			(layers "F.Cu" "F.Mask" "F.Paste")
			(net "GND")
		)
		(pad "6" smd rect
			(at -2.400046 -0.024892 90)
			(size 0.2286 0.6096)
			(layers "F.Cu" "F.Mask" "F.Paste")
			(net "NC_PVDDCR_CPU1_P1_GL1_5")
		)
		(pad "7_9-20_24" smd circle
			(at 0 1.150112 90)
			(size 0 0)
			(layers "F.Cu" "F.Mask" "F.Paste")
			(net "GND")
		)
		(pad "10_19" smd rect
			(at 0 2.899918 90)
			(size 0.6096 4.318)
			(layers "F.Cu" "F.Mask" "F.Paste")
			(net "SW_PVDDCR_CPU1_P1_SW5")
		)
		(pad "25_29" smd rect
			(at 1.549908 -1.279906 270)
			(size 2.0574 2.3114)
			(layers "F.Cu" "F.Mask" "F.Paste")
			(net "SW_P12V_AUX_PVDDCR_CPU1_P1_FLT")
		)
		(pad "30" smd rect
			(at 2.05994 -2.899918)
			(size 0.2286 0.6096)
			(layers "F.Cu" "F.Mask" "F.Paste")
			(net "SW_P12V_AUX_PVDDCR_CPU1_P1_FLT")
		)
		(pad "31" smd rect
			(at 1.610106 -2.899918)
			(size 0.2286 0.6096)
			(layers "F.Cu" "F.Mask" "F.Paste")
			(net "NC_PVDDCR_CPU1_P1_DNC5")
		)
		(pad "32" smd rect
			(at 1.160018 -2.899918)
			(size 0.2286 0.6096)
			(layers "F.Cu" "F.Mask" "F.Paste")
			(net "SW_PVDDCR_CPU1_P1_BOOTR5")
		)
		(pad "33" smd rect
			(at 0.70993 -2.899918)
			(size 0.2286 0.6096)
			(layers "F.Cu" "F.Mask" "F.Paste")
			(net "SW_PVDDCR_CPU1_P1_BOOT5")
		)
		(pad "34" smd rect
			(at 0.260096 -2.899918)
			(size 0.2286 0.6096)
			(layers "F.Cu" "F.Mask" "F.Paste")
			(net "PVDDCR_CPU1_P1_PWM5")
		)
		(pad "35" smd rect
			(at -0.189992 -2.899918)
			(size 0.2286 0.6096)
			(layers "F.Cu" "F.Mask" "F.Paste")
			(net "PVDDCR_CPU1_P1_VCC5")
		)
		(pad "36" smd rect
			(at -0.64008 -2.899918)
			(size 0.2286 0.6096)
			(layers "F.Cu" "F.Mask" "F.Paste")
			(net "PVDDCR_CPU1_P1_TEMP0")
		)
		(pad "37" smd rect
			(at -1.089914 -2.899918)
			(size 0.2286 0.6096)
			(layers "F.Cu" "F.Mask" "F.Paste")
			(net "PVDDCR_CPU1_P1_LSET5")
		)
		(pad "38" smd rect
			(at -1.540002 -2.899918)
			(size 0.2286 0.6096)
			(layers "F.Cu" "F.Mask" "F.Paste")
			(net "PVDDCR_CPU1_P1_IMON5")
		)
		(pad "39" smd rect
			(at -1.99009 -2.899918)
			(size 0.2286 0.6096)
			(layers "F.Cu" "F.Mask" "F.Paste")
			(net "PVDDCR_CPU1_P1_VCCS")
		)
		(pad "40" smd rect
			(at -0.87503 -1.27508)
			(size 1.7526 1.9558)
			(layers "F.Cu" "F.Mask" "F.Paste")
			(net "GND")
		)
		(pad "41" smd rect
			(at -1.525016 0.249936 270)
			(size 0.3048 0.4572)
			(layers "F.Cu" "F.Mask" "F.Paste")
			(net "NC_PVDDCR_CPU1_P1_GL2_5")
		)
		(zone
			(layer "F.Cu")
			(hatch none 0.5)
			(connect_pads
				(clearance 0)
			)
			(min_thickness 0.25)
			(keepout
				(tracks not_allowed)
				(vias allowed)
				(pads allowed)
				(copperpour not_allowed)
				(footprints allowed)
			)
			(placement
				(enabled no)
				(sheetname "")
			)
			(fill
				(thermal_gap 0.5)
				(thermal_bridge_width 0.5)
				(island_removal_mode 0)
			)
			(polygon
				(pts
					(xy 92.953332 -332.450694) (xy 92.953332 -332.778608) (xy 97.953576 -332.778608) (xy 97.953576 -332.455774)
					(xy 97.663254 -332.455774) (xy 97.663254 -332.484984) (xy 93.243654 -332.484984) (xy 93.243654 -332.450694)
				)
			)
		)
		(zone
			(layer "F.Cu")
			(hatch none 0.5)
			(connect_pads
				(clearance 0)
			)
			(min_thickness 0.25)
			(keepout
				(tracks not_allowed)
				(vias allowed)
				(pads allowed)
				(copperpour not_allowed)
				(footprints allowed)
			)
			(placement
				(enabled no)
				(sheetname "")
			)
			(fill
				(thermal_gap 0.5)
				(thermal_bridge_width 0.5)
				(island_removal_mode 0)
			)
			(polygon
				(pts
					(xy 95.505524 -335.275682) (xy 95.505524 -337.333082) (xy 93.651324 -337.333082) (xy 93.651324 -337.092036)
					(xy 93.409008 -337.092036) (xy 93.409008 -337.57362) (xy 97.152714 -337.57362) (xy 97.152714 -337.388708)
					(xy 95.796862 -337.388708) (xy 95.796862 -335.229708) (xy 97.953576 -335.229708) (xy 97.953576 -334.980026)
					(xy 95.80118 -334.980026)
				)
			)
		)
	)
	(footprint ""
		(layer "F.Cu")
		(at 94.4626 -416.4076 180)
		(property "Reference" "R1373"
			(at 0 0 180)
			(layer "F.SilkS")
			(hide yes)
			(effects
				(font
					(size 1.27 1.27)
				)
			)
		)
		(property "Value" ""
			(at 0 0 180)
			(layer "F.Fab")
			(effects
				(font
					(size 1.27 1.27)
				)
			)
		)
		(duplicate_pad_numbers_are_jumpers no)
		(fp_line
			(start 0.32512 0.175006)
			(end -0.32512 0.175006)
			(stroke
				(width 0.1)
				(type default)
			)
			(layer "F.Fab")
		)
		(fp_line
			(start 0.32512 -0.175006)
			(end 0.32512 0.175006)
			(stroke
				(width 0.1)
				(type default)
			)
			(layer "F.Fab")
		)
		(fp_line
			(start -0.32512 0.175006)
			(end -0.32512 -0.175006)
			(stroke
				(width 0.1)
				(type default)
			)
			(layer "F.Fab")
		)
		(fp_line
			(start -0.32512 -0.175006)
			(end 0.32512 -0.175006)
			(stroke
				(width 0.1)
				(type default)
			)
			(layer "F.Fab")
		)
		(pad "1" smd rect
			(at -0.2667 0 180)
			(size 0.3048 0.381)
			(layers "F.Cu" "F.Mask" "F.Paste")
			(net "JTAG_TCK_RT_CPU1_P1")
		)
		(pad "2" smd rect
			(at 0.2667 0)
			(size 0.3048 0.381)
			(layers "F.Cu" "F.Mask" "F.Paste")
			(net "GND")
		)
	)
	(footprint ""
		(layer "F.Cu")
		(at 314.567316 -108.52277 180)
		(property "Reference" "R125"
			(at 0 0 180)
			(layer "F.SilkS")
			(hide yes)
			(effects
				(font
					(size 1.27 1.27)
				)
			)
		)
		(property "Value" ""
			(at 0 0 180)
			(layer "F.Fab")
			(effects
				(font
					(size 1.27 1.27)
				)
			)
		)
		(duplicate_pad_numbers_are_jumpers no)
		(fp_line
			(start 0.7874 0.4064)
			(end -0.7874 0.4064)
			(stroke
				(width 0.1524)
				(type default)
			)
			(layer "F.SilkS")
		)
		(fp_line
			(start 0.7874 -0.4064)
			(end 0.7874 0.4064)
			(stroke
				(width 0.1524)
				(type default)
			)
			(layer "F.SilkS")
		)
		(fp_line
			(start -0.7874 0.4064)
			(end -0.7874 -0.4064)
			(stroke
				(width 0.1524)
				(type default)
			)
			(layer "F.SilkS")
		)
		(fp_line
			(start -0.7874 -0.4064)
			(end 0.7874 -0.4064)
			(stroke
				(width 0.1524)
				(type default)
			)
			(layer "F.SilkS")
		)
		(fp_line
			(start 0.67945 0.3048)
			(end 0.120396 0.3048)
			(stroke
				(width 0.1)
				(type default)
			)
			(layer "F.Fab")
		)
		(fp_line
			(start 0.67945 -0.3048)
			(end 0.67945 0.3048)
			(stroke
				(width 0.1)
				(type default)
			)
			(layer "F.Fab")
		)
		(fp_line
			(start 0.12065 -0.2794)
			(end 0.12065 -0.3048)
			(stroke
				(width 0.1)
				(type default)
			)
			(layer "F.Fab")
		)
		(fp_line
			(start 0.12065 -0.3048)
			(end 0.67945 -0.3048)
			(stroke
				(width 0.1)
				(type default)
			)
			(layer "F.Fab")
		)
		(fp_line
			(start 0.120396 0.3048)
			(end 0.120396 0.2794)
			(stroke
				(width 0.1)
				(type default)
			)
			(layer "F.Fab")
		)
		(fp_line
			(start 0.120396 0.2794)
			(end -0.12065 0.2794)
			(stroke
				(width 0.1)
				(type default)
			)
			(layer "F.Fab")
		)
		(fp_line
			(start -0.12065 0.3048)
			(end -0.67945 0.3048)
			(stroke
				(width 0.1)
				(type default)
			)
			(layer "F.Fab")
		)
		(fp_line
			(start -0.12065 0.2794)
			(end -0.12065 0.3048)
			(stroke
				(width 0.1)
				(type default)
			)
			(layer "F.Fab")
		)
		(fp_line
			(start -0.12065 -0.2794)
			(end 0.12065 -0.2794)
			(stroke
				(width 0.1)
				(type default)
			)
			(layer "F.Fab")
		)
		(fp_line
			(start -0.12065 -0.305054)
			(end -0.12065 -0.2794)
			(stroke
				(width 0.1)
				(type default)
			)
			(layer "F.Fab")
		)
		(fp_line
			(start -0.67945 0.3048)
			(end -0.67945 -0.305054)
			(stroke
				(width 0.1)
				(type default)
			)
			(layer "F.Fab")
		)
		(fp_line
			(start -0.67945 -0.305054)
			(end -0.12065 -0.305054)
			(stroke
				(width 0.1)
				(type default)
			)
			(layer "F.Fab")
		)
		(pad "1" smd circle
			(at -0.40005 0 180)
			(size 0 0)
			(layers "F.Cu" "F.Mask" "F.Paste")
			(net "SMB_FRU_3V3AUX_SDA")
		)
		(pad "2" smd circle
			(at 0.40005 0 180)
			(size 0 0)
			(layers "F.Cu" "F.Mask" "F.Paste")
			(net "SMB_CPU_FRU_3V3AUX_SDA")
		)
	)
	(footprint ""
		(layer "F.Cu")
		(at 74.422 -56.134 -90)
		(property "Reference" "C1064"
			(at 0 0 270)
			(layer "F.SilkS")
			(hide yes)
			(effects
				(font
					(size 1.27 1.27)
				)
			)
		)
		(property "Value" ""
			(at 0 0 270)
			(layer "F.Fab")
			(effects
				(font
					(size 1.27 1.27)
				)
			)
		)
		(duplicate_pad_numbers_are_jumpers no)
		(fp_line
			(start -0.7874 0.4064)
			(end -0.7874 -0.4064)
			(stroke
				(width 0.1524)
				(type default)
			)
			(layer "F.SilkS")
		)
		(fp_line
			(start 0.7874 0.4064)
			(end -0.7874 0.4064)
			(stroke
				(width 0.1524)
				(type default)
			)
			(layer "F.SilkS")
		)
		(fp_line
			(start -0.7874 -0.4064)
			(end 0.7874 -0.4064)
			(stroke
				(width 0.1524)
				(type default)
			)
			(layer "F.SilkS")
		)
		(fp_line
			(start 0.7874 -0.4064)
			(end 0.7874 0.4064)
			(stroke
				(width 0.1524)
				(type default)
			)
			(layer "F.SilkS")
		)
		(fp_line
			(start -0.67945 0.3048)
			(end -0.67945 -0.305054)
			(stroke
				(width 0.1)
				(type default)
			)
			(layer "F.Fab")
		)
		(fp_line
			(start -0.12065 0.3048)
			(end -0.67945 0.3048)
			(stroke
				(width 0.1)
				(type default)
			)
			(layer "F.Fab")
		)
		(fp_line
			(start 0.120396 0.3048)
			(end 0.120396 0.2794)
			(stroke
				(width 0.1)
				(type default)
			)
			(layer "F.Fab")
		)
		(fp_line
			(start 0.67945 0.3048)
			(end 0.120396 0.3048)
			(stroke
				(width 0.1)
				(type default)
			)
			(layer "F.Fab")
		)
		(fp_line
			(start -0.12065 0.2794)
			(end -0.12065 0.3048)
			(stroke
				(width 0.1)
				(type default)
			)
			(layer "F.Fab")
		)
		(fp_line
			(start 0.120396 0.2794)
			(end -0.12065 0.2794)
			(stroke
				(width 0.1)
				(type default)
			)
			(layer "F.Fab")
		)
		(fp_line
			(start -0.12065 -0.2794)
			(end 0.12065 -0.2794)
			(stroke
				(width 0.1)
				(type default)
			)
			(layer "F.Fab")
		)
		(fp_line
			(start 0.12065 -0.2794)
			(end 0.12065 -0.3048)
			(stroke
				(width 0.1)
				(type default)
			)
			(layer "F.Fab")
		)
		(fp_line
			(start 0.12065 -0.3048)
			(end 0.67945 -0.3048)
			(stroke
				(width 0.1)
				(type default)
			)
			(layer "F.Fab")
		)
		(fp_line
			(start 0.67945 -0.3048)
			(end 0.67945 0.3048)
			(stroke
				(width 0.1)
				(type default)
			)
			(layer "F.Fab")
		)
		(fp_line
			(start -0.67945 -0.305054)
			(end -0.12065 -0.305054)
			(stroke
				(width 0.1)
				(type default)
			)
			(layer "F.Fab")
		)
		(fp_line
			(start -0.12065 -0.305054)
			(end -0.12065 -0.2794)
			(stroke
				(width 0.1)
				(type default)
			)
			(layer "F.Fab")
		)
		(pad "1" smd circle
			(at -0.40005 0 270)
			(size 0 0)
			(layers "F.Cu" "F.Mask" "F.Paste")
			(net "P3V3_AUX")
		)
		(pad "2" smd circle
			(at 0.40005 0 270)
			(size 0 0)
			(layers "F.Cu" "F.Mask" "F.Paste")
			(net "GND")
		)
	)
	(footprint ""
		(layer "F.Cu")
		(at 79.908908 -69.238114 90)
		(property "Reference" "R1169"
			(at 0 0 90)
			(layer "F.SilkS")
			(hide yes)
			(effects
				(font
					(size 1.27 1.27)
				)
			)
		)
		(property "Value" ""
			(at 0 0 90)
			(layer "F.Fab")
			(effects
				(font
					(size 1.27 1.27)
				)
			)
		)
		(duplicate_pad_numbers_are_jumpers no)
		(fp_line
			(start 0.7874 -0.4064)
			(end 0.7874 0.4064)
			(stroke
				(width 0.1524)
				(type default)
			)
			(layer "F.SilkS")
		)
		(fp_line
			(start -0.7874 -0.4064)
			(end 0.7874 -0.4064)
			(stroke
				(width 0.1524)
				(type default)
			)
			(layer "F.SilkS")
		)
		(fp_line
			(start 0.7874 0.4064)
			(end -0.7874 0.4064)
			(stroke
				(width 0.1524)
				(type default)
			)
			(layer "F.SilkS")
		)
		(fp_line
			(start -0.7874 0.4064)
			(end -0.7874 -0.4064)
			(stroke
				(width 0.1524)
				(type default)
			)
			(layer "F.SilkS")
		)
		(fp_line
			(start -0.12065 -0.305054)
			(end -0.12065 -0.2794)
			(stroke
				(width 0.1)
				(type default)
			)
			(layer "F.Fab")
		)
		(fp_line
			(start -0.67945 -0.305054)
			(end -0.12065 -0.305054)
			(stroke
				(width 0.1)
				(type default)
			)
			(layer "F.Fab")
		)
		(fp_line
			(start 0.67945 -0.3048)
			(end 0.67945 0.3048)
			(stroke
				(width 0.1)
				(type default)
			)
			(layer "F.Fab")
		)
		(fp_line
			(start 0.12065 -0.3048)
			(end 0.67945 -0.3048)
			(stroke
				(width 0.1)
				(type default)
			)
			(layer "F.Fab")
		)
		(fp_line
			(start 0.12065 -0.2794)
			(end 0.12065 -0.3048)
			(stroke
				(width 0.1)
				(type default)
			)
			(layer "F.Fab")
		)
		(fp_line
			(start -0.12065 -0.2794)
			(end 0.12065 -0.2794)
			(stroke
				(width 0.1)
				(type default)
			)
			(layer "F.Fab")
		)
		(fp_line
			(start 0.120396 0.2794)
			(end -0.12065 0.2794)
			(stroke
				(width 0.1)
				(type default)
			)
			(layer "F.Fab")
		)
		(fp_line
			(start -0.12065 0.2794)
			(end -0.12065 0.3048)
			(stroke
				(width 0.1)
				(type default)
			)
			(layer "F.Fab")
		)
		(fp_line
			(start 0.67945 0.3048)
			(end 0.120396 0.3048)
			(stroke
				(width 0.1)
				(type default)
			)
			(layer "F.Fab")
		)
		(fp_line
			(start 0.120396 0.3048)
			(end 0.120396 0.2794)
			(stroke
				(width 0.1)
				(type default)
			)
			(layer "F.Fab")
		)
		(fp_line
			(start -0.12065 0.3048)
			(end -0.67945 0.3048)
			(stroke
				(width 0.1)
				(type default)
			)
			(layer "F.Fab")
		)
		(fp_line
			(start -0.67945 0.3048)
			(end -0.67945 -0.305054)
			(stroke
				(width 0.1)
				(type default)
			)
			(layer "F.Fab")
		)
		(pad "1" smd circle
			(at -0.40005 0 90)
			(size 0 0)
			(layers "F.Cu" "F.Mask" "F.Paste")
			(net "OCP_V3_2_P3V3_PWRGD")
		)
		(pad "2" smd circle
			(at 0.40005 0 90)
			(size 0 0)
			(layers "F.Cu" "F.Mask" "F.Paste")
			(net "OCP_V3_2_P3V3_R2_PWRGD")
		)
	)
	(footprint ""
		(layer "F.Cu")
		(at 194.914774 -424.622214 90)
		(property "Reference" "C8011"
			(at 0 0 90)
			(layer "F.SilkS")
			(hide yes)
			(effects
				(font
					(size 1.27 1.27)
				)
			)
		)
		(property "Value" ""
			(at 0 0 90)
			(layer "F.Fab")
			(effects
				(font
					(size 1.27 1.27)
				)
			)
		)
		(duplicate_pad_numbers_are_jumpers no)
		(fp_line
			(start 0.7874 -0.4064)
			(end 0.7874 0.4064)
			(stroke
				(width 0.1524)
				(type default)
			)
			(layer "F.SilkS")
		)
		(fp_line
			(start -0.7874 -0.4064)
			(end 0.7874 -0.4064)
			(stroke
				(width 0.1524)
				(type default)
			)
			(layer "F.SilkS")
		)
		(fp_line
			(start 0.7874 0.4064)
			(end -0.7874 0.4064)
			(stroke
				(width 0.1524)
				(type default)
			)
			(layer "F.SilkS")
		)
		(fp_line
			(start -0.7874 0.4064)
			(end -0.7874 -0.4064)
			(stroke
				(width 0.1524)
				(type default)
			)
			(layer "F.SilkS")
		)
		(fp_line
			(start -0.12065 -0.305054)
			(end -0.12065 -0.2794)
			(stroke
				(width 0.1)
				(type default)
			)
			(layer "F.Fab")
		)
		(fp_line
			(start -0.67945 -0.305054)
			(end -0.12065 -0.305054)
			(stroke
				(width 0.1)
				(type default)
			)
			(layer "F.Fab")
		)
		(fp_line
			(start 0.67945 -0.3048)
			(end 0.67945 0.3048)
			(stroke
				(width 0.1)
				(type default)
			)
			(layer "F.Fab")
		)
		(fp_line
			(start 0.12065 -0.3048)
			(end 0.67945 -0.3048)
			(stroke
				(width 0.1)
				(type default)
			)
			(layer "F.Fab")
		)
		(fp_line
			(start 0.12065 -0.2794)
			(end 0.12065 -0.3048)
			(stroke
				(width 0.1)
				(type default)
			)
			(layer "F.Fab")
		)
		(fp_line
			(start -0.12065 -0.2794)
			(end 0.12065 -0.2794)
			(stroke
				(width 0.1)
				(type default)
			)
			(layer "F.Fab")
		)
		(fp_line
			(start 0.120396 0.2794)
			(end -0.12065 0.2794)
			(stroke
				(width 0.1)
				(type default)
			)
			(layer "F.Fab")
		)
		(fp_line
			(start -0.12065 0.2794)
			(end -0.12065 0.3048)
			(stroke
				(width 0.1)
				(type default)
			)
			(layer "F.Fab")
		)
		(fp_line
			(start 0.67945 0.3048)
			(end 0.120396 0.3048)
			(stroke
				(width 0.1)
				(type default)
			)
			(layer "F.Fab")
		)
		(fp_line
			(start 0.120396 0.3048)
			(end 0.120396 0.2794)
			(stroke
				(width 0.1)
				(type default)
			)
			(layer "F.Fab")
		)
		(fp_line
			(start -0.12065 0.3048)
			(end -0.67945 0.3048)
			(stroke
				(width 0.1)
				(type default)
			)
			(layer "F.Fab")
		)
		(fp_line
			(start -0.67945 0.3048)
			(end -0.67945 -0.305054)
			(stroke
				(width 0.1)
				(type default)
			)
			(layer "F.Fab")
		)
		(pad "1" smd circle
			(at -0.40005 0 90)
			(size 0 0)
			(layers "F.Cu" "F.Mask" "F.Paste")
			(net "FM_AC_PWR_BTN_PDB_N")
		)
		(pad "2" smd circle
			(at 0.40005 0 90)
			(size 0 0)
			(layers "F.Cu" "F.Mask" "F.Paste")
			(net "GND")
		)
	)
	(footprint ""
		(layer "F.Cu")
		(at 276.520402 -76.110084 180)
		(property "Reference" ""
			(at 0 0 180)
			(layer "F.SilkS")
			(hide yes)
			(effects
				(font
					(size 1.27 1.27)
				)
			)
		)
		(property "Value" ""
			(at 0 0 180)
			(layer "F.Fab")
			(effects
				(font
					(size 1.27 1.27)
				)
			)
		)
		(duplicate_pad_numbers_are_jumpers no)
		(pad "1" smd circle
			(at 0 0 180)
			(size 0.9906 0.9906)
			(layers "F.Cu" "F.Mask" "F.Paste")
			(net "Net_44")
		)
		(zone
			(layer "F.Cu")
			(hatch none 0.5)
			(connect_pads
				(clearance 0)
			)
			(min_thickness 0.25)
			(keepout
				(tracks not_allowed)
				(vias allowed)
				(pads allowed)
				(copperpour not_allowed)
				(footprints allowed)
			)
			(placement
				(enabled no)
				(sheetname "")
			)
			(fill
				(thermal_gap 0.5)
				(thermal_bridge_width 0.5)
				(island_removal_mode 0)
			)
			(polygon
				(pts
					(arc
						(start 278.146002 -76.110084)
						(mid 274.894802 -76.110084)
						(end 278.146002 -76.110084)
					)
				)
			)
		)
	)
	(footprint ""
		(layer "F.Cu")
		(at 180.225954 -356.152958 90)
		(property "Reference" "PC503_1"
			(at 0 0 90)
			(layer "F.SilkS")
			(hide yes)
			(effects
				(font
					(size 1.27 1.27)
				)
			)
		)
		(property "Value" ""
			(at 0 0 90)
			(layer "F.Fab")
			(effects
				(font
					(size 1.27 1.27)
				)
			)
		)
		(duplicate_pad_numbers_are_jumpers no)
		(fp_line
			(start 0.7874 -0.4064)
			(end 0.7874 0.4064)
			(stroke
				(width 0.1524)
				(type default)
			)
			(layer "F.SilkS")
		)
		(fp_line
			(start -0.7874 -0.4064)
			(end 0.7874 -0.4064)
			(stroke
				(width 0.1524)
				(type default)
			)
			(layer "F.SilkS")
		)
		(fp_line
			(start 0.7874 0.4064)
			(end -0.7874 0.4064)
			(stroke
				(width 0.1524)
				(type default)
			)
			(layer "F.SilkS")
		)
		(fp_line
			(start -0.7874 0.4064)
			(end -0.7874 -0.4064)
			(stroke
				(width 0.1524)
				(type default)
			)
			(layer "F.SilkS")
		)
		(fp_line
			(start -0.12065 -0.305054)
			(end -0.12065 -0.2794)
			(stroke
				(width 0.1)
				(type default)
			)
			(layer "F.Fab")
		)
		(fp_line
			(start -0.67945 -0.305054)
			(end -0.12065 -0.305054)
			(stroke
				(width 0.1)
				(type default)
			)
			(layer "F.Fab")
		)
		(fp_line
			(start 0.67945 -0.3048)
			(end 0.67945 0.3048)
			(stroke
				(width 0.1)
				(type default)
			)
			(layer "F.Fab")
		)
		(fp_line
			(start 0.12065 -0.3048)
			(end 0.67945 -0.3048)
			(stroke
				(width 0.1)
				(type default)
			)
			(layer "F.Fab")
		)
		(fp_line
			(start 0.12065 -0.2794)
			(end 0.12065 -0.3048)
			(stroke
				(width 0.1)
				(type default)
			)
			(layer "F.Fab")
		)
		(fp_line
			(start -0.12065 -0.2794)
			(end 0.12065 -0.2794)
			(stroke
				(width 0.1)
				(type default)
			)
			(layer "F.Fab")
		)
		(fp_line
			(start 0.120396 0.2794)
			(end -0.12065 0.2794)
			(stroke
				(width 0.1)
				(type default)
			)
			(layer "F.Fab")
		)
		(fp_line
			(start -0.12065 0.2794)
			(end -0.12065 0.3048)
			(stroke
				(width 0.1)
				(type default)
			)
			(layer "F.Fab")
		)
		(fp_line
			(start 0.67945 0.3048)
			(end 0.120396 0.3048)
			(stroke
				(width 0.1)
				(type default)
			)
			(layer "F.Fab")
		)
		(fp_line
			(start 0.120396 0.3048)
			(end 0.120396 0.2794)
			(stroke
				(width 0.1)
				(type default)
			)
			(layer "F.Fab")
		)
		(fp_line
			(start -0.12065 0.3048)
			(end -0.67945 0.3048)
			(stroke
				(width 0.1)
				(type default)
			)
			(layer "F.Fab")
		)
		(fp_line
			(start -0.67945 0.3048)
			(end -0.67945 -0.305054)
			(stroke
				(width 0.1)
				(type default)
			)
			(layer "F.Fab")
		)
		(pad "1" smd circle
			(at -0.40005 0 90)
			(size 0 0)
			(layers "F.Cu" "F.Mask" "F.Paste")
			(net "PVDD11_S3_P1_VCCS")
		)
		(pad "2" smd circle
			(at 0.40005 0 90)
			(size 0 0)
			(layers "F.Cu" "F.Mask" "F.Paste")
			(net "GND")
		)
	)
	(footprint ""
		(layer "F.Cu")
		(at 384.390392 -65.541652 -90)
		(property "Reference" "C551"
			(at 0 0 270)
			(layer "F.SilkS")
			(hide yes)
			(effects
				(font
					(size 1.27 1.27)
				)
			)
		)
		(property "Value" ""
			(at 0 0 270)
			(layer "F.Fab")
			(effects
				(font
					(size 1.27 1.27)
				)
			)
		)
		(duplicate_pad_numbers_are_jumpers no)
		(fp_line
			(start -0.7874 0.4064)
			(end -0.7874 -0.4064)
			(stroke
				(width 0.1524)
				(type default)
			)
			(layer "F.SilkS")
		)
		(fp_line
			(start 0.7874 0.4064)
			(end -0.7874 0.4064)
			(stroke
				(width 0.1524)
				(type default)
			)
			(layer "F.SilkS")
		)
		(fp_line
			(start -0.7874 -0.4064)
			(end 0.7874 -0.4064)
			(stroke
				(width 0.1524)
				(type default)
			)
			(layer "F.SilkS")
		)
		(fp_line
			(start 0.7874 -0.4064)
			(end 0.7874 0.4064)
			(stroke
				(width 0.1524)
				(type default)
			)
			(layer "F.SilkS")
		)
		(fp_line
			(start -0.67945 0.3048)
			(end -0.67945 -0.305054)
			(stroke
				(width 0.1)
				(type default)
			)
			(layer "F.Fab")
		)
		(fp_line
			(start -0.12065 0.3048)
			(end -0.67945 0.3048)
			(stroke
				(width 0.1)
				(type default)
			)
			(layer "F.Fab")
		)
		(fp_line
			(start 0.120396 0.3048)
			(end 0.120396 0.2794)
			(stroke
				(width 0.1)
				(type default)
			)
			(layer "F.Fab")
		)
		(fp_line
			(start 0.67945 0.3048)
			(end 0.120396 0.3048)
			(stroke
				(width 0.1)
				(type default)
			)
			(layer "F.Fab")
		)
		(fp_line
			(start -0.12065 0.2794)
			(end -0.12065 0.3048)
			(stroke
				(width 0.1)
				(type default)
			)
			(layer "F.Fab")
		)
		(fp_line
			(start 0.120396 0.2794)
			(end -0.12065 0.2794)
			(stroke
				(width 0.1)
				(type default)
			)
			(layer "F.Fab")
		)
		(fp_line
			(start -0.12065 -0.2794)
			(end 0.12065 -0.2794)
			(stroke
				(width 0.1)
				(type default)
			)
			(layer "F.Fab")
		)
		(fp_line
			(start 0.12065 -0.2794)
			(end 0.12065 -0.3048)
			(stroke
				(width 0.1)
				(type default)
			)
			(layer "F.Fab")
		)
		(fp_line
			(start 0.12065 -0.3048)
			(end 0.67945 -0.3048)
			(stroke
				(width 0.1)
				(type default)
			)
			(layer "F.Fab")
		)
		(fp_line
			(start 0.67945 -0.3048)
			(end 0.67945 0.3048)
			(stroke
				(width 0.1)
				(type default)
			)
			(layer "F.Fab")
		)
		(fp_line
			(start -0.67945 -0.305054)
			(end -0.12065 -0.305054)
			(stroke
				(width 0.1)
				(type default)
			)
			(layer "F.Fab")
		)
		(fp_line
			(start -0.12065 -0.305054)
			(end -0.12065 -0.2794)
			(stroke
				(width 0.1)
				(type default)
			)
			(layer "F.Fab")
		)
		(pad "1" smd circle
			(at -0.40005 0 270)
			(size 0 0)
			(layers "F.Cu" "F.Mask" "F.Paste")
			(net "CPU0_HDT_CONN_TESTEN")
		)
		(pad "2" smd circle
			(at 0.40005 0 270)
			(size 0 0)
			(layers "F.Cu" "F.Mask" "F.Paste")
			(net "GND")
		)
	)
	(footprint ""
		(layer "F.Cu")
		(at 168.355518 -125.762004)
		(property "Reference" "R6139"
			(at 0 0 0)
			(layer "F.SilkS")
			(hide yes)
			(effects
				(font
					(size 1.27 1.27)
				)
			)
		)
		(property "Value" ""
			(at 0 0 0)
			(layer "F.Fab")
			(effects
				(font
					(size 1.27 1.27)
				)
			)
		)
		(duplicate_pad_numbers_are_jumpers no)
		(fp_line
			(start -0.7874 -0.4064)
			(end 0.7874 -0.4064)
			(stroke
				(width 0.1524)
				(type default)
			)
			(layer "F.SilkS")
		)
		(fp_line
			(start -0.7874 0.4064)
			(end -0.7874 -0.4064)
			(stroke
				(width 0.1524)
				(type default)
			)
			(layer "F.SilkS")
		)
		(fp_line
			(start 0.7874 -0.4064)
			(end 0.7874 0.4064)
			(stroke
				(width 0.1524)
				(type default)
			)
			(layer "F.SilkS")
		)
		(fp_line
			(start 0.7874 0.4064)
			(end -0.7874 0.4064)
			(stroke
				(width 0.1524)
				(type default)
			)
			(layer "F.SilkS")
		)
		(fp_line
			(start -0.67945 -0.305054)
			(end -0.12065 -0.305054)
			(stroke
				(width 0.1)
				(type default)
			)
			(layer "F.Fab")
		)
		(fp_line
			(start -0.67945 0.3048)
			(end -0.67945 -0.305054)
			(stroke
				(width 0.1)
				(type default)
			)
			(layer "F.Fab")
		)
		(fp_line
			(start -0.12065 -0.305054)
			(end -0.12065 -0.2794)
			(stroke
				(width 0.1)
				(type default)
			)
			(layer "F.Fab")
		)
		(fp_line
			(start -0.12065 -0.2794)
			(end 0.12065 -0.2794)
			(stroke
				(width 0.1)
				(type default)
			)
			(layer "F.Fab")
		)
		(fp_line
			(start -0.12065 0.2794)
			(end -0.12065 0.3048)
			(stroke
				(width 0.1)
				(type default)
			)
			(layer "F.Fab")
		)
		(fp_line
			(start -0.12065 0.3048)
			(end -0.67945 0.3048)
			(stroke
				(width 0.1)
				(type default)
			)
			(layer "F.Fab")
		)
		(fp_line
			(start 0.120396 0.2794)
			(end -0.12065 0.2794)
			(stroke
				(width 0.1)
				(type default)
			)
			(layer "F.Fab")
		)
		(fp_line
			(start 0.120396 0.3048)
			(end 0.120396 0.2794)
			(stroke
				(width 0.1)
				(type default)
			)
			(layer "F.Fab")
		)
		(fp_line
			(start 0.12065 -0.3048)
			(end 0.67945 -0.3048)
			(stroke
				(width 0.1)
				(type default)
			)
			(layer "F.Fab")
		)
		(fp_line
			(start 0.12065 -0.2794)
			(end 0.12065 -0.3048)
			(stroke
				(width 0.1)
				(type default)
			)
			(layer "F.Fab")
		)
		(fp_line
			(start 0.67945 -0.3048)
			(end 0.67945 0.3048)
			(stroke
				(width 0.1)
				(type default)
			)
			(layer "F.Fab")
		)
		(fp_line
			(start 0.67945 0.3048)
			(end 0.120396 0.3048)
			(stroke
				(width 0.1)
				(type default)
			)
			(layer "F.Fab")
		)
		(pad "1" smd circle
			(at -0.40005 0)
			(size 0 0)
			(layers "F.Cu" "F.Mask" "F.Paste")
			(net "P3V3_AUX")
		)
		(pad "2" smd circle
			(at 0.40005 0)
			(size 0 0)
			(layers "F.Cu" "F.Mask" "F.Paste")
			(net "FM_BOARD_BMC_SKU_ID1")
		)
	)
	(footprint ""
		(layer "F.Cu")
		(at 63.660528 -351.372932 -90)
		(property "Reference" "PC413"
			(at 0 0 270)
			(layer "F.SilkS")
			(hide yes)
			(effects
				(font
					(size 1.27 1.27)
				)
			)
		)
		(property "Value" ""
			(at 0 0 270)
			(layer "F.Fab")
			(effects
				(font
					(size 1.27 1.27)
				)
			)
		)
		(duplicate_pad_numbers_are_jumpers no)
		(fp_line
			(start -0.7874 0.4064)
			(end -0.7874 -0.4064)
			(stroke
				(width 0.1524)
				(type default)
			)
			(layer "F.SilkS")
		)
		(fp_line
			(start 0.7874 0.4064)
			(end -0.7874 0.4064)
			(stroke
				(width 0.1524)
				(type default)
			)
			(layer "F.SilkS")
		)
		(fp_line
			(start -0.7874 -0.4064)
			(end 0.7874 -0.4064)
			(stroke
				(width 0.1524)
				(type default)
			)
			(layer "F.SilkS")
		)
		(fp_line
			(start 0.7874 -0.4064)
			(end 0.7874 0.4064)
			(stroke
				(width 0.1524)
				(type default)
			)
			(layer "F.SilkS")
		)
		(fp_line
			(start -0.67945 0.3048)
			(end -0.67945 -0.305054)
			(stroke
				(width 0.1)
				(type default)
			)
			(layer "F.Fab")
		)
		(fp_line
			(start -0.12065 0.3048)
			(end -0.67945 0.3048)
			(stroke
				(width 0.1)
				(type default)
			)
			(layer "F.Fab")
		)
		(fp_line
			(start 0.120396 0.3048)
			(end 0.120396 0.2794)
			(stroke
				(width 0.1)
				(type default)
			)
			(layer "F.Fab")
		)
		(fp_line
			(start 0.67945 0.3048)
			(end 0.120396 0.3048)
			(stroke
				(width 0.1)
				(type default)
			)
			(layer "F.Fab")
		)
		(fp_line
			(start -0.12065 0.2794)
			(end -0.12065 0.3048)
			(stroke
				(width 0.1)
				(type default)
			)
			(layer "F.Fab")
		)
		(fp_line
			(start 0.120396 0.2794)
			(end -0.12065 0.2794)
			(stroke
				(width 0.1)
				(type default)
			)
			(layer "F.Fab")
		)
		(fp_line
			(start -0.12065 -0.2794)
			(end 0.12065 -0.2794)
			(stroke
				(width 0.1)
				(type default)
			)
			(layer "F.Fab")
		)
		(fp_line
			(start 0.12065 -0.2794)
			(end 0.12065 -0.3048)
			(stroke
				(width 0.1)
				(type default)
			)
			(layer "F.Fab")
		)
		(fp_line
			(start 0.12065 -0.3048)
			(end 0.67945 -0.3048)
			(stroke
				(width 0.1)
				(type default)
			)
			(layer "F.Fab")
		)
		(fp_line
			(start 0.67945 -0.3048)
			(end 0.67945 0.3048)
			(stroke
				(width 0.1)
				(type default)
			)
			(layer "F.Fab")
		)
		(fp_line
			(start -0.67945 -0.305054)
			(end -0.12065 -0.305054)
			(stroke
				(width 0.1)
				(type default)
			)
			(layer "F.Fab")
		)
		(fp_line
			(start -0.12065 -0.305054)
			(end -0.12065 -0.2794)
			(stroke
				(width 0.1)
				(type default)
			)
			(layer "F.Fab")
		)
		(pad "1" smd circle
			(at -0.40005 0 270)
			(size 0 0)
			(layers "F.Cu" "F.Mask" "F.Paste")
			(net "SW_PVDDCR_CPU1_P1_BOOT4_R")
		)
		(pad "2" smd circle
			(at 0.40005 0 270)
			(size 0 0)
			(layers "F.Cu" "F.Mask" "F.Paste")
			(net "SW_PVDDCR_CPU1_P1_BOOTR4")
		)
	)
	(footprint ""
		(layer "F.Cu")
		(at 239.152684 -52.92725)
		(property "Reference" "C1996"
			(at 0 0 0)
			(layer "F.SilkS")
			(hide yes)
			(effects
				(font
					(size 1.27 1.27)
				)
			)
		)
		(property "Value" ""
			(at 0 0 0)
			(layer "F.Fab")
			(effects
				(font
					(size 1.27 1.27)
				)
			)
		)
		(duplicate_pad_numbers_are_jumpers no)
		(fp_line
			(start -0.299974 -0.150114)
			(end 0.299974 -0.150114)
			(stroke
				(width 0.1)
				(type default)
			)
			(layer "F.Fab")
		)
		(fp_line
			(start -0.299974 0.150114)
			(end -0.299974 -0.150114)
			(stroke
				(width 0.1)
				(type default)
			)
			(layer "F.Fab")
		)
		(fp_line
			(start 0.299974 -0.150114)
			(end 0.299974 0.150114)
			(stroke
				(width 0.1)
				(type default)
			)
			(layer "F.Fab")
		)
		(fp_line
			(start 0.299974 0.150114)
			(end -0.299974 0.150114)
			(stroke
				(width 0.1)
				(type default)
			)
			(layer "F.Fab")
		)
		(pad "1" smd rect
			(at -0.2667 0)
			(size 0.3048 0.381)
			(layers "F.Cu" "F.Mask" "F.Paste")
			(net "P3E_CPU0_P4_TX_C_DN<0>")
		)
		(pad "2" smd rect
			(at 0.2667 0)
			(size 0.3048 0.381)
			(layers "F.Cu" "F.Mask" "F.Paste")
			(net "P3E_CPU0_P4_TX_DN<0>")
		)
	)
	(footprint ""
		(layer "F.Cu")
		(at 267.068046 -106.847894 180)
		(property "Reference" "U148"
			(at 1.889252 3.59664 0)
			(unlocked yes)
			(layer "F.SilkS")
			(effects
				(font
					(size 0.7874 0.5842)
					(thickness 0.1524)
				)
				(justify left)
			)
		)
		(property "Value" ""
			(at 0 0 180)
			(layer "F.Fab")
			(effects
				(font
					(size 1.27 1.27)
				)
			)
		)
		(duplicate_pad_numbers_are_jumpers no)
		(fp_line
			(start 1.868932 2.549906)
			(end 1.868932 -2.549906)
			(stroke
				(width 0.1524)
				(type default)
			)
			(layer "F.SilkS")
		)
		(fp_line
			(start 1.868932 -2.549906)
			(end 1.025906 -2.549906)
			(stroke
				(width 0.1524)
				(type default)
			)
			(layer "F.SilkS")
		)
		(fp_line
			(start 1.025906 -2.549906)
			(end 0 -1.524)
			(stroke
				(width 0.1524)
				(type default)
			)
			(layer "F.SilkS")
		)
		(fp_line
			(start 0 -1.524)
			(end -1.025906 -2.549906)
			(stroke
				(width 0.1524)
				(type default)
			)
			(layer "F.SilkS")
		)
		(fp_line
			(start -1.025906 -2.549906)
			(end -1.868932 -2.549906)
			(stroke
				(width 0.1524)
				(type default)
			)
			(layer "F.SilkS")
		)
		(fp_line
			(start -1.868932 2.549906)
			(end 1.868932 2.549906)
			(stroke
				(width 0.1524)
				(type default)
			)
			(layer "F.SilkS")
		)
		(fp_line
			(start -1.868932 -2.549906)
			(end -1.868932 2.549906)
			(stroke
				(width 0.1524)
				(type default)
			)
			(layer "F.SilkS")
		)
		(fp_poly
			(pts
				(xy -3.7592 -2.295398) (xy -4.7752 -1.787398) (xy -4.7752 -2.803398)
			)
			(stroke
				(width 0)
				(type default)
			)
			(fill yes)
			(layer "F.SilkS")
		)
		(fp_line
			(start 2.249932 2.549906)
			(end 2.249932 -2.549906)
			(stroke
				(width 0.1)
				(type default)
			)
			(layer "F.Fab")
		)
		(fp_line
			(start 2.249932 -2.549906)
			(end -2.249932 -2.549906)
			(stroke
				(width 0.1)
				(type default)
			)
			(layer "F.Fab")
		)
		(fp_line
			(start -2.249932 2.549906)
			(end 2.249932 2.549906)
			(stroke
				(width 0.1)
				(type default)
			)
			(layer "F.Fab")
		)
		(fp_line
			(start -2.249932 -2.549906)
			(end -2.249932 2.549906)
			(stroke
				(width 0.1)
				(type default)
			)
			(layer "F.Fab")
		)
		(fp_poly
			(pts
				(xy -4.7752 -1.787398) (xy -4.7752 -2.803398) (xy -3.7592 -2.295398)
			)
			(stroke
				(width 0)
				(type default)
			)
			(fill yes)
			(layer "F.Fab")
		)
		(pad "1" smd rect
			(at -2.800096 -2.275078 90)
			(size 0.3556 1.6002)
			(layers "F.Cu" "F.Mask" "F.Paste")
			(net "P3V3_AUX")
		)
		(pad "2" smd rect
			(at -2.800096 -1.625092 90)
			(size 0.3556 1.6002)
			(layers "F.Cu" "F.Mask" "F.Paste")
			(net "P3V3_AUX")
		)
		(pad "3" smd rect
			(at -2.800096 -0.975106 90)
			(size 0.3556 1.6002)
			(layers "F.Cu" "F.Mask" "F.Paste")
			(net "JTAG_SCM_MUX_TCK")
		)
		(pad "4" smd rect
			(at -2.800096 -0.32512 90)
			(size 0.3556 1.6002)
			(layers "F.Cu" "F.Mask" "F.Paste")
			(net "JTAG_SCM_MUX_TMS")
		)
		(pad "5" smd rect
			(at -2.800096 0.32512 90)
			(size 0.3556 1.6002)
			(layers "F.Cu" "F.Mask" "F.Paste")
			(net "JTAG_SCM_TRST_N")
		)
		(pad "6" smd rect
			(at -2.800096 0.975106 90)
			(size 0.3556 1.6002)
			(layers "F.Cu" "F.Mask" "F.Paste")
			(net "JTAG_SCM_DBREQ_N")
		)
		(pad "7" smd rect
			(at -2.800096 1.625092 90)
			(size 0.3556 1.6002)
			(layers "F.Cu" "F.Mask" "F.Paste")
			(net "P3V3_AUX")
		)
		(pad "8" smd rect
			(at -2.800096 2.275078 90)
			(size 0.3556 1.6002)
			(layers "F.Cu" "F.Mask" "F.Paste")
			(net "P3V3_AUX")
		)
		(pad "9" smd rect
			(at 2.800096 2.275078 90)
			(size 0.3556 1.6002)
			(layers "F.Cu" "F.Mask" "F.Paste")
			(net "JTAG_BMC_OE_N")
		)
		(pad "10" smd rect
			(at 2.800096 1.625092 90)
			(size 0.3556 1.6002)
			(layers "F.Cu" "F.Mask" "F.Paste")
			(net "GND")
		)
		(pad "11" smd rect
			(at 2.800096 0.975106 90)
			(size 0.3556 1.6002)
			(layers "F.Cu" "F.Mask" "F.Paste")
			(net "JTAG_DBREQ_R_N")
		)
		(pad "12" smd rect
			(at 2.800096 0.32512 90)
			(size 0.3556 1.6002)
			(layers "F.Cu" "F.Mask" "F.Paste")
			(net "JTAG_TRST_R_N")
		)
		(pad "13" smd rect
			(at 2.800096 -0.32512 90)
			(size 0.3556 1.6002)
			(layers "F.Cu" "F.Mask" "F.Paste")
			(net "JTAG_TMS_R")
		)
		(pad "14" smd rect
			(at 2.800096 -0.975106 90)
			(size 0.3556 1.6002)
			(layers "F.Cu" "F.Mask" "F.Paste")
			(net "JTAG_TCK_R")
		)
		(pad "15" smd rect
			(at 2.800096 -1.625092 90)
			(size 0.3556 1.6002)
			(layers "F.Cu" "F.Mask" "F.Paste")
			(net "PVDD18_S5_P0")
		)
		(pad "16" smd rect
			(at 2.800096 -2.275078 90)
			(size 0.3556 1.6002)
			(layers "F.Cu" "F.Mask" "F.Paste")
			(net "P3V3_AUX")
		)
	)
	(footprint ""
		(layer "F.Cu")
		(at 338.41944 -142.28953 -90)
		(property "Reference" "PC212"
			(at 0 0 270)
			(layer "F.SilkS")
			(hide yes)
			(effects
				(font
					(size 1.27 1.27)
				)
			)
		)
		(property "Value" ""
			(at 0 0 270)
			(layer "F.Fab")
			(effects
				(font
					(size 1.27 1.27)
				)
			)
		)
		(duplicate_pad_numbers_are_jumpers no)
		(fp_line
			(start -0.7874 0.4064)
			(end -0.7874 -0.4064)
			(stroke
				(width 0.1524)
				(type default)
			)
			(layer "F.SilkS")
		)
		(fp_line
			(start 0.7874 0.4064)
			(end -0.7874 0.4064)
			(stroke
				(width 0.1524)
				(type default)
			)
			(layer "F.SilkS")
		)
		(fp_line
			(start -0.7874 -0.4064)
			(end 0.7874 -0.4064)
			(stroke
				(width 0.1524)
				(type default)
			)
			(layer "F.SilkS")
		)
		(fp_line
			(start 0.7874 -0.4064)
			(end 0.7874 0.4064)
			(stroke
				(width 0.1524)
				(type default)
			)
			(layer "F.SilkS")
		)
		(fp_line
			(start -0.67945 0.3048)
			(end -0.67945 -0.305054)
			(stroke
				(width 0.1)
				(type default)
			)
			(layer "F.Fab")
		)
		(fp_line
			(start -0.12065 0.3048)
			(end -0.67945 0.3048)
			(stroke
				(width 0.1)
				(type default)
			)
			(layer "F.Fab")
		)
		(fp_line
			(start 0.120396 0.3048)
			(end 0.120396 0.2794)
			(stroke
				(width 0.1)
				(type default)
			)
			(layer "F.Fab")
		)
		(fp_line
			(start 0.67945 0.3048)
			(end 0.120396 0.3048)
			(stroke
				(width 0.1)
				(type default)
			)
			(layer "F.Fab")
		)
		(fp_line
			(start -0.12065 0.2794)
			(end -0.12065 0.3048)
			(stroke
				(width 0.1)
				(type default)
			)
			(layer "F.Fab")
		)
		(fp_line
			(start 0.120396 0.2794)
			(end -0.12065 0.2794)
			(stroke
				(width 0.1)
				(type default)
			)
			(layer "F.Fab")
		)
		(fp_line
			(start -0.12065 -0.2794)
			(end 0.12065 -0.2794)
			(stroke
				(width 0.1)
				(type default)
			)
			(layer "F.Fab")
		)
		(fp_line
			(start 0.12065 -0.2794)
			(end 0.12065 -0.3048)
			(stroke
				(width 0.1)
				(type default)
			)
			(layer "F.Fab")
		)
		(fp_line
			(start 0.12065 -0.3048)
			(end 0.67945 -0.3048)
			(stroke
				(width 0.1)
				(type default)
			)
			(layer "F.Fab")
		)
		(fp_line
			(start 0.67945 -0.3048)
			(end 0.67945 0.3048)
			(stroke
				(width 0.1)
				(type default)
			)
			(layer "F.Fab")
		)
		(fp_line
			(start -0.67945 -0.305054)
			(end -0.12065 -0.305054)
			(stroke
				(width 0.1)
				(type default)
			)
			(layer "F.Fab")
		)
		(fp_line
			(start -0.12065 -0.305054)
			(end -0.12065 -0.2794)
			(stroke
				(width 0.1)
				(type default)
			)
			(layer "F.Fab")
		)
		(pad "1" smd circle
			(at -0.40005 0 270)
			(size 0 0)
			(layers "F.Cu" "F.Mask" "F.Paste")
			(net "PVDD18_S5_P0_VCC")
		)
		(pad "2" smd circle
			(at 0.40005 0 270)
			(size 0 0)
			(layers "F.Cu" "F.Mask" "F.Paste")
			(net "GND")
		)
	)
	(footprint ""
		(layer "F.Cu")
		(at 25.638506 19.444716 -90)
		(property "Reference" "BATTERY_BT2"
			(at 0 0 270)
			(layer "F.SilkS")
			(hide yes)
			(effects
				(font
					(size 1.27 1.27)
				)
			)
		)
		(property "Value" ""
			(at 0 0 270)
			(layer "F.Fab")
			(effects
				(font
					(size 1.27 1.27)
				)
			)
		)
		(duplicate_pad_numbers_are_jumpers no)
		(pad "1" smd circle
			(at 0 0 270)
			(size 0.762 0.762)
			(layers "F.Cu" "F.Mask" "F.Paste")
			(net "Net_2616")
		)
	)
	(footprint ""
		(layer "F.Cu")
		(at 238.859822 -290.341812 90)
		(property "Reference" "PR6505"
			(at 0 0 90)
			(layer "F.SilkS")
			(hide yes)
			(effects
				(font
					(size 1.27 1.27)
				)
			)
		)
		(property "Value" ""
			(at 0 0 90)
			(layer "F.Fab")
			(effects
				(font
					(size 1.27 1.27)
				)
			)
		)
		(duplicate_pad_numbers_are_jumpers no)
		(fp_line
			(start 0.7874 -0.4064)
			(end 0.7874 0.4064)
			(stroke
				(width 0.1524)
				(type default)
			)
			(layer "F.SilkS")
		)
		(fp_line
			(start -0.7874 -0.4064)
			(end 0.7874 -0.4064)
			(stroke
				(width 0.1524)
				(type default)
			)
			(layer "F.SilkS")
		)
		(fp_line
			(start 0.7874 0.4064)
			(end -0.7874 0.4064)
			(stroke
				(width 0.1524)
				(type default)
			)
			(layer "F.SilkS")
		)
		(fp_line
			(start -0.7874 0.4064)
			(end -0.7874 -0.4064)
			(stroke
				(width 0.1524)
				(type default)
			)
			(layer "F.SilkS")
		)
		(fp_line
			(start -0.12065 -0.305054)
			(end -0.12065 -0.2794)
			(stroke
				(width 0.1)
				(type default)
			)
			(layer "F.Fab")
		)
		(fp_line
			(start -0.67945 -0.305054)
			(end -0.12065 -0.305054)
			(stroke
				(width 0.1)
				(type default)
			)
			(layer "F.Fab")
		)
		(fp_line
			(start 0.67945 -0.3048)
			(end 0.67945 0.3048)
			(stroke
				(width 0.1)
				(type default)
			)
			(layer "F.Fab")
		)
		(fp_line
			(start 0.12065 -0.3048)
			(end 0.67945 -0.3048)
			(stroke
				(width 0.1)
				(type default)
			)
			(layer "F.Fab")
		)
		(fp_line
			(start 0.12065 -0.2794)
			(end 0.12065 -0.3048)
			(stroke
				(width 0.1)
				(type default)
			)
			(layer "F.Fab")
		)
		(fp_line
			(start -0.12065 -0.2794)
			(end 0.12065 -0.2794)
			(stroke
				(width 0.1)
				(type default)
			)
			(layer "F.Fab")
		)
		(fp_line
			(start 0.120396 0.2794)
			(end -0.12065 0.2794)
			(stroke
				(width 0.1)
				(type default)
			)
			(layer "F.Fab")
		)
		(fp_line
			(start -0.12065 0.2794)
			(end -0.12065 0.3048)
			(stroke
				(width 0.1)
				(type default)
			)
			(layer "F.Fab")
		)
		(fp_line
			(start 0.67945 0.3048)
			(end 0.120396 0.3048)
			(stroke
				(width 0.1)
				(type default)
			)
			(layer "F.Fab")
		)
		(fp_line
			(start 0.120396 0.3048)
			(end 0.120396 0.2794)
			(stroke
				(width 0.1)
				(type default)
			)
			(layer "F.Fab")
		)
		(fp_line
			(start -0.12065 0.3048)
			(end -0.67945 0.3048)
			(stroke
				(width 0.1)
				(type default)
			)
			(layer "F.Fab")
		)
		(fp_line
			(start -0.67945 0.3048)
			(end -0.67945 -0.305054)
			(stroke
				(width 0.1)
				(type default)
			)
			(layer "F.Fab")
		)
		(pad "1" smd circle
			(at -0.40005 0 90)
			(size 0 0)
			(layers "F.Cu" "F.Mask" "F.Paste")
			(net "P1V8_RETIMER_CPU0_FB")
		)
		(pad "2" smd circle
			(at 0.40005 0 90)
			(size 0 0)
			(layers "F.Cu" "F.Mask" "F.Paste")
			(net "P1V8_CPU0_RT_1D")
		)
	)
	(footprint ""
		(layer "F.Cu")
		(at 245.222268 -42.26179 -90)
		(property "Reference" "C1279"
			(at 0 0 270)
			(layer "F.SilkS")
			(hide yes)
			(effects
				(font
					(size 1.27 1.27)
				)
			)
		)
		(property "Value" ""
			(at 0 0 270)
			(layer "F.Fab")
			(effects
				(font
					(size 1.27 1.27)
				)
			)
		)
		(duplicate_pad_numbers_are_jumpers no)
		(fp_line
			(start -0.7874 0.4064)
			(end -0.7874 -0.4064)
			(stroke
				(width 0.1524)
				(type default)
			)
			(layer "F.SilkS")
		)
		(fp_line
			(start 0.7874 0.4064)
			(end -0.7874 0.4064)
			(stroke
				(width 0.1524)
				(type default)
			)
			(layer "F.SilkS")
		)
		(fp_line
			(start -0.7874 -0.4064)
			(end 0.7874 -0.4064)
			(stroke
				(width 0.1524)
				(type default)
			)
			(layer "F.SilkS")
		)
		(fp_line
			(start 0.7874 -0.4064)
			(end 0.7874 0.4064)
			(stroke
				(width 0.1524)
				(type default)
			)
			(layer "F.SilkS")
		)
		(fp_line
			(start -0.67945 0.3048)
			(end -0.67945 -0.305054)
			(stroke
				(width 0.1)
				(type default)
			)
			(layer "F.Fab")
		)
		(fp_line
			(start -0.12065 0.3048)
			(end -0.67945 0.3048)
			(stroke
				(width 0.1)
				(type default)
			)
			(layer "F.Fab")
		)
		(fp_line
			(start 0.120396 0.3048)
			(end 0.120396 0.2794)
			(stroke
				(width 0.1)
				(type default)
			)
			(layer "F.Fab")
		)
		(fp_line
			(start 0.67945 0.3048)
			(end 0.120396 0.3048)
			(stroke
				(width 0.1)
				(type default)
			)
			(layer "F.Fab")
		)
		(fp_line
			(start -0.12065 0.2794)
			(end -0.12065 0.3048)
			(stroke
				(width 0.1)
				(type default)
			)
			(layer "F.Fab")
		)
		(fp_line
			(start 0.120396 0.2794)
			(end -0.12065 0.2794)
			(stroke
				(width 0.1)
				(type default)
			)
			(layer "F.Fab")
		)
		(fp_line
			(start -0.12065 -0.2794)
			(end 0.12065 -0.2794)
			(stroke
				(width 0.1)
				(type default)
			)
			(layer "F.Fab")
		)
		(fp_line
			(start 0.12065 -0.2794)
			(end 0.12065 -0.3048)
			(stroke
				(width 0.1)
				(type default)
			)
			(layer "F.Fab")
		)
		(fp_line
			(start 0.12065 -0.3048)
			(end 0.67945 -0.3048)
			(stroke
				(width 0.1)
				(type default)
			)
			(layer "F.Fab")
		)
		(fp_line
			(start 0.67945 -0.3048)
			(end 0.67945 0.3048)
			(stroke
				(width 0.1)
				(type default)
			)
			(layer "F.Fab")
		)
		(fp_line
			(start -0.67945 -0.305054)
			(end -0.12065 -0.305054)
			(stroke
				(width 0.1)
				(type default)
			)
			(layer "F.Fab")
		)
		(fp_line
			(start -0.12065 -0.305054)
			(end -0.12065 -0.2794)
			(stroke
				(width 0.1)
				(type default)
			)
			(layer "F.Fab")
		)
		(pad "1" smd circle
			(at -0.40005 0 270)
			(size 0 0)
			(layers "F.Cu" "F.Mask" "F.Paste")
			(net "P12V_E1S_0_R")
		)
		(pad "2" smd circle
			(at 0.40005 0 270)
			(size 0 0)
			(layers "F.Cu" "F.Mask" "F.Paste")
			(net "GND")
		)
	)
	(footprint ""
		(layer "F.Cu")
		(at 279.527 -416.306)
		(property "Reference" "R4489"
			(at 0 0 0)
			(layer "F.SilkS")
			(hide yes)
			(effects
				(font
					(size 1.27 1.27)
				)
			)
		)
		(property "Value" ""
			(at 0 0 0)
			(layer "F.Fab")
			(effects
				(font
					(size 1.27 1.27)
				)
			)
		)
		(duplicate_pad_numbers_are_jumpers no)
		(fp_line
			(start -0.7874 -0.4064)
			(end 0.7874 -0.4064)
			(stroke
				(width 0.1524)
				(type default)
			)
			(layer "F.SilkS")
		)
		(fp_line
			(start -0.7874 0.4064)
			(end -0.7874 -0.4064)
			(stroke
				(width 0.1524)
				(type default)
			)
			(layer "F.SilkS")
		)
		(fp_line
			(start 0.7874 -0.4064)
			(end 0.7874 0.4064)
			(stroke
				(width 0.1524)
				(type default)
			)
			(layer "F.SilkS")
		)
		(fp_line
			(start 0.7874 0.4064)
			(end -0.7874 0.4064)
			(stroke
				(width 0.1524)
				(type default)
			)
			(layer "F.SilkS")
		)
		(fp_line
			(start -0.67945 -0.305054)
			(end -0.12065 -0.305054)
			(stroke
				(width 0.1)
				(type default)
			)
			(layer "F.Fab")
		)
		(fp_line
			(start -0.67945 0.3048)
			(end -0.67945 -0.305054)
			(stroke
				(width 0.1)
				(type default)
			)
			(layer "F.Fab")
		)
		(fp_line
			(start -0.12065 -0.305054)
			(end -0.12065 -0.2794)
			(stroke
				(width 0.1)
				(type default)
			)
			(layer "F.Fab")
		)
		(fp_line
			(start -0.12065 -0.2794)
			(end 0.12065 -0.2794)
			(stroke
				(width 0.1)
				(type default)
			)
			(layer "F.Fab")
		)
		(fp_line
			(start -0.12065 0.2794)
			(end -0.12065 0.3048)
			(stroke
				(width 0.1)
				(type default)
			)
			(layer "F.Fab")
		)
		(fp_line
			(start -0.12065 0.3048)
			(end -0.67945 0.3048)
			(stroke
				(width 0.1)
				(type default)
			)
			(layer "F.Fab")
		)
		(fp_line
			(start 0.120396 0.2794)
			(end -0.12065 0.2794)
			(stroke
				(width 0.1)
				(type default)
			)
			(layer "F.Fab")
		)
		(fp_line
			(start 0.120396 0.3048)
			(end 0.120396 0.2794)
			(stroke
				(width 0.1)
				(type default)
			)
			(layer "F.Fab")
		)
		(fp_line
			(start 0.12065 -0.3048)
			(end 0.67945 -0.3048)
			(stroke
				(width 0.1)
				(type default)
			)
			(layer "F.Fab")
		)
		(fp_line
			(start 0.12065 -0.2794)
			(end 0.12065 -0.3048)
			(stroke
				(width 0.1)
				(type default)
			)
			(layer "F.Fab")
		)
		(fp_line
			(start 0.67945 -0.3048)
			(end 0.67945 0.3048)
			(stroke
				(width 0.1)
				(type default)
			)
			(layer "F.Fab")
		)
		(fp_line
			(start 0.67945 0.3048)
			(end 0.120396 0.3048)
			(stroke
				(width 0.1)
				(type default)
			)
			(layer "F.Fab")
		)
		(pad "1" smd circle
			(at -0.40005 0)
			(size 0 0)
			(layers "F.Cu" "F.Mask" "F.Paste")
			(net "P3V3_AUX")
		)
		(pad "2" smd circle
			(at 0.40005 0)
			(size 0 0)
			(layers "F.Cu" "F.Mask" "F.Paste")
			(net "CLK_9ZXL045_P0_SADR0")
		)
	)
	(footprint ""
		(layer "F.Cu")
		(at 271.085056 -114.21237)
		(property "Reference" "R3722"
			(at 0 0 0)
			(layer "F.SilkS")
			(hide yes)
			(effects
				(font
					(size 1.27 1.27)
				)
			)
		)
		(property "Value" ""
			(at 0 0 0)
			(layer "F.Fab")
			(effects
				(font
					(size 1.27 1.27)
				)
			)
		)
		(duplicate_pad_numbers_are_jumpers no)
		(fp_line
			(start -0.7874 -0.4064)
			(end 0.7874 -0.4064)
			(stroke
				(width 0.1524)
				(type default)
			)
			(layer "F.SilkS")
		)
		(fp_line
			(start -0.7874 0.4064)
			(end -0.7874 -0.4064)
			(stroke
				(width 0.1524)
				(type default)
			)
			(layer "F.SilkS")
		)
		(fp_line
			(start 0.7874 -0.4064)
			(end 0.7874 0.4064)
			(stroke
				(width 0.1524)
				(type default)
			)
			(layer "F.SilkS")
		)
		(fp_line
			(start 0.7874 0.4064)
			(end -0.7874 0.4064)
			(stroke
				(width 0.1524)
				(type default)
			)
			(layer "F.SilkS")
		)
		(fp_line
			(start -0.67945 -0.305054)
			(end -0.12065 -0.305054)
			(stroke
				(width 0.1)
				(type default)
			)
			(layer "F.Fab")
		)
		(fp_line
			(start -0.67945 0.3048)
			(end -0.67945 -0.305054)
			(stroke
				(width 0.1)
				(type default)
			)
			(layer "F.Fab")
		)
		(fp_line
			(start -0.12065 -0.305054)
			(end -0.12065 -0.2794)
			(stroke
				(width 0.1)
				(type default)
			)
			(layer "F.Fab")
		)
		(fp_line
			(start -0.12065 -0.2794)
			(end 0.12065 -0.2794)
			(stroke
				(width 0.1)
				(type default)
			)
			(layer "F.Fab")
		)
		(fp_line
			(start -0.12065 0.2794)
			(end -0.12065 0.3048)
			(stroke
				(width 0.1)
				(type default)
			)
			(layer "F.Fab")
		)
		(fp_line
			(start -0.12065 0.3048)
			(end -0.67945 0.3048)
			(stroke
				(width 0.1)
				(type default)
			)
			(layer "F.Fab")
		)
		(fp_line
			(start 0.120396 0.2794)
			(end -0.12065 0.2794)
			(stroke
				(width 0.1)
				(type default)
			)
			(layer "F.Fab")
		)
		(fp_line
			(start 0.120396 0.3048)
			(end 0.120396 0.2794)
			(stroke
				(width 0.1)
				(type default)
			)
			(layer "F.Fab")
		)
		(fp_line
			(start 0.12065 -0.3048)
			(end 0.67945 -0.3048)
			(stroke
				(width 0.1)
				(type default)
			)
			(layer "F.Fab")
		)
		(fp_line
			(start 0.12065 -0.2794)
			(end 0.12065 -0.3048)
			(stroke
				(width 0.1)
				(type default)
			)
			(layer "F.Fab")
		)
		(fp_line
			(start 0.67945 -0.3048)
			(end 0.67945 0.3048)
			(stroke
				(width 0.1)
				(type default)
			)
			(layer "F.Fab")
		)
		(fp_line
			(start 0.67945 0.3048)
			(end 0.120396 0.3048)
			(stroke
				(width 0.1)
				(type default)
			)
			(layer "F.Fab")
		)
		(pad "1" smd circle
			(at -0.40005 0)
			(size 0 0)
			(layers "F.Cu" "F.Mask" "F.Paste")
			(net "SMB_LM75_3_3V3AUX_SDA_R")
		)
		(pad "2" smd circle
			(at 0.40005 0)
			(size 0 0)
			(layers "F.Cu" "F.Mask" "F.Paste")
			(net "SMB_LM75_3_3V3AUX_SDA")
		)
	)
	(footprint ""
		(layer "F.Cu")
		(at 439.471308 -405.788622 -90)
		(property "Reference" "PR6550"
			(at 0 0 270)
			(layer "F.SilkS")
			(hide yes)
			(effects
				(font
					(size 1.27 1.27)
				)
			)
		)
		(property "Value" ""
			(at 0 0 270)
			(layer "F.Fab")
			(effects
				(font
					(size 1.27 1.27)
				)
			)
		)
		(duplicate_pad_numbers_are_jumpers no)
		(fp_line
			(start -0.7874 0.4064)
			(end -0.7874 -0.4064)
			(stroke
				(width 0.1524)
				(type default)
			)
			(layer "F.SilkS")
		)
		(fp_line
			(start 0.7874 0.4064)
			(end -0.7874 0.4064)
			(stroke
				(width 0.1524)
				(type default)
			)
			(layer "F.SilkS")
		)
		(fp_line
			(start -0.7874 -0.4064)
			(end 0.7874 -0.4064)
			(stroke
				(width 0.1524)
				(type default)
			)
			(layer "F.SilkS")
		)
		(fp_line
			(start 0.7874 -0.4064)
			(end 0.7874 0.4064)
			(stroke
				(width 0.1524)
				(type default)
			)
			(layer "F.SilkS")
		)
		(fp_line
			(start -0.67945 0.3048)
			(end -0.67945 -0.305054)
			(stroke
				(width 0.1)
				(type default)
			)
			(layer "F.Fab")
		)
		(fp_line
			(start -0.12065 0.3048)
			(end -0.67945 0.3048)
			(stroke
				(width 0.1)
				(type default)
			)
			(layer "F.Fab")
		)
		(fp_line
			(start 0.120396 0.3048)
			(end 0.120396 0.2794)
			(stroke
				(width 0.1)
				(type default)
			)
			(layer "F.Fab")
		)
		(fp_line
			(start 0.67945 0.3048)
			(end 0.120396 0.3048)
			(stroke
				(width 0.1)
				(type default)
			)
			(layer "F.Fab")
		)
		(fp_line
			(start -0.12065 0.2794)
			(end -0.12065 0.3048)
			(stroke
				(width 0.1)
				(type default)
			)
			(layer "F.Fab")
		)
		(fp_line
			(start 0.120396 0.2794)
			(end -0.12065 0.2794)
			(stroke
				(width 0.1)
				(type default)
			)
			(layer "F.Fab")
		)
		(fp_line
			(start -0.12065 -0.2794)
			(end 0.12065 -0.2794)
			(stroke
				(width 0.1)
				(type default)
			)
			(layer "F.Fab")
		)
		(fp_line
			(start 0.12065 -0.2794)
			(end 0.12065 -0.3048)
			(stroke
				(width 0.1)
				(type default)
			)
			(layer "F.Fab")
		)
		(fp_line
			(start 0.12065 -0.3048)
			(end 0.67945 -0.3048)
			(stroke
				(width 0.1)
				(type default)
			)
			(layer "F.Fab")
		)
		(fp_line
			(start 0.67945 -0.3048)
			(end 0.67945 0.3048)
			(stroke
				(width 0.1)
				(type default)
			)
			(layer "F.Fab")
		)
		(fp_line
			(start -0.67945 -0.305054)
			(end -0.12065 -0.305054)
			(stroke
				(width 0.1)
				(type default)
			)
			(layer "F.Fab")
		)
		(fp_line
			(start -0.12065 -0.305054)
			(end -0.12065 -0.2794)
			(stroke
				(width 0.1)
				(type default)
			)
			(layer "F.Fab")
		)
		(pad "1" smd circle
			(at -0.40005 0 270)
			(size 0 0)
			(layers "F.Cu" "F.Mask" "F.Paste")
			(net "P5V_AUX")
		)
		(pad "2" smd circle
			(at 0.40005 0 270)
			(size 0 0)
			(layers "F.Cu" "F.Mask" "F.Paste")
			(net "P0V9_RETIMER_CPU0_PVCC")
		)
	)
	(footprint ""
		(layer "F.Cu")
		(at 457.687426 -103.646224)
		(property "Reference" "U8"
			(at -2.8321 -1.679448 0)
			(unlocked yes)
			(layer "F.SilkS")
			(effects
				(font
					(size 0.7874 0.5842)
					(thickness 0.1524)
				)
				(justify left)
			)
		)
		(property "Value" ""
			(at 0 0 0)
			(layer "F.Fab")
			(effects
				(font
					(size 1.27 1.27)
				)
			)
		)
		(duplicate_pad_numbers_are_jumpers no)
		(fp_line
			(start -1.38176 -1.100074)
			(end -1.38176 1.100074)
			(stroke
				(width 0.1524)
				(type default)
			)
			(layer "F.SilkS")
		)
		(fp_line
			(start -1.38176 1.100074)
			(end 1.38176 1.100074)
			(stroke
				(width 0.1524)
				(type default)
			)
			(layer "F.SilkS")
		)
		(fp_line
			(start -0.592074 -1.100074)
			(end -1.38176 -1.100074)
			(stroke
				(width 0.1524)
				(type default)
			)
			(layer "F.SilkS")
		)
		(fp_line
			(start 0 -0.508)
			(end -0.592074 -1.100074)
			(stroke
				(width 0.1524)
				(type default)
			)
			(layer "F.SilkS")
		)
		(fp_line
			(start 0.592074 -1.100074)
			(end 0 -0.508)
			(stroke
				(width 0.1524)
				(type default)
			)
			(layer "F.SilkS")
		)
		(fp_line
			(start 1.38176 -1.100074)
			(end 0.592074 -1.100074)
			(stroke
				(width 0.1524)
				(type default)
			)
			(layer "F.SilkS")
		)
		(fp_line
			(start 1.38176 1.100074)
			(end 1.38176 -1.100074)
			(stroke
				(width 0.1524)
				(type default)
			)
			(layer "F.SilkS")
		)
		(fp_poly
			(pts
				(xy -1.9431 -0.429768) (xy -1.9431 -0.870204) (xy -1.50241 -0.649986)
			)
			(stroke
				(width 0)
				(type default)
			)
			(fill yes)
			(layer "F.SilkS")
		)
		(fp_line
			(start -0.674878 -1.100074)
			(end -0.674878 1.100074)
			(stroke
				(width 0.1)
				(type default)
			)
			(layer "F.Fab")
		)
		(fp_line
			(start -0.674878 1.100074)
			(end 0.674878 1.100074)
			(stroke
				(width 0.1)
				(type default)
			)
			(layer "F.Fab")
		)
		(fp_line
			(start 0.674878 -1.100074)
			(end -0.674878 -1.100074)
			(stroke
				(width 0.1)
				(type default)
			)
			(layer "F.Fab")
		)
		(fp_line
			(start 0.674878 1.100074)
			(end 0.674878 -1.100074)
			(stroke
				(width 0.1)
				(type default)
			)
			(layer "F.Fab")
		)
		(fp_poly
			(pts
				(xy -1.9431 -0.870204) (xy -1.50241 -0.649986) (xy -1.9431 -0.429768)
			)
			(stroke
				(width 0)
				(type default)
			)
			(fill yes)
			(layer "F.Fab")
		)
		(pad "1" smd rect
			(at -0.94996 -0.649986 270)
			(size 0.4318 0.6096)
			(layers "F.Cu" "F.Mask" "F.Paste")
			(net "OCP_SFF_PRSNT2_R_N")
		)
		(pad "2" smd rect
			(at -0.94996 0 270)
			(size 0.4318 0.6096)
			(layers "F.Cu" "F.Mask" "F.Paste")
			(net "GND")
		)
		(pad "3" smd rect
			(at -0.94996 0.649986 270)
			(size 0.4318 0.6096)
			(layers "F.Cu" "F.Mask" "F.Paste")
			(net "OCP_SFF_PRSNT3_R_N")
		)
		(pad "4" smd rect
			(at 0.94996 0.649986 270)
			(size 0.4318 0.6096)
			(layers "F.Cu" "F.Mask" "F.Paste")
			(net "HP_LVC3_OCP_V3_1_PRSNT2_N_R")
		)
		(pad "5" smd rect
			(at 0.94996 0 270)
			(size 0.4318 0.6096)
			(layers "F.Cu" "F.Mask" "F.Paste")
			(net "P3V3_AUX")
		)
		(pad "6" smd rect
			(at 0.94996 -0.649986 270)
			(size 0.4318 0.6096)
			(layers "F.Cu" "F.Mask" "F.Paste")
			(net "HP_LVC3_OCP_V3_1_PRSNT2_N_R")
		)
	)
	(footprint ""
		(layer "F.Cu")
		(at 169.799 -132.08)
		(property "Reference" "U100"
			(at -5.050536 -1.718564 0)
			(unlocked yes)
			(layer "F.SilkS")
			(effects
				(font
					(size 0.7874 0.5842)
					(thickness 0.1524)
				)
				(justify left)
			)
		)
		(property "Value" ""
			(at 0 0 0)
			(layer "F.Fab")
			(effects
				(font
					(size 1.27 1.27)
				)
			)
		)
		(duplicate_pad_numbers_are_jumpers no)
		(fp_line
			(start -1.934972 -1.5494)
			(end 1.934972 -1.5494)
			(stroke
				(width 0.1524)
				(type default)
			)
			(layer "F.SilkS")
		)
		(fp_line
			(start -1.934972 1.5494)
			(end -1.934972 -1.5494)
			(stroke
				(width 0.1524)
				(type default)
			)
			(layer "F.SilkS")
		)
		(fp_line
			(start 1.934972 -1.5494)
			(end 1.934972 1.5494)
			(stroke
				(width 0.1524)
				(type default)
			)
			(layer "F.SilkS")
		)
		(fp_line
			(start 1.934972 1.5494)
			(end -1.934972 1.5494)
			(stroke
				(width 0.1524)
				(type default)
			)
			(layer "F.SilkS")
		)
		(fp_line
			(start -0.901446 -1.5494)
			(end 0.901446 -1.5494)
			(stroke
				(width 0.1)
				(type default)
			)
			(layer "F.Fab")
		)
		(fp_line
			(start -0.901446 1.5494)
			(end -0.901446 -1.5494)
			(stroke
				(width 0.1)
				(type default)
			)
			(layer "F.Fab")
		)
		(fp_line
			(start 0.901446 -1.5494)
			(end 0.901446 1.5494)
			(stroke
				(width 0.1)
				(type default)
			)
			(layer "F.Fab")
		)
		(fp_line
			(start 0.901446 1.5494)
			(end -0.901446 1.5494)
			(stroke
				(width 0.1)
				(type default)
			)
			(layer "F.Fab")
		)
		(pad "1" smd rect
			(at -1.299972 -0.94996 270)
			(size 0.8128 1.016)
			(layers "F.Cu" "F.Mask" "F.Paste")
			(net "PWRGD_P5V_R")
		)
		(pad "2" smd rect
			(at -1.299972 0.94996 270)
			(size 0.8128 1.016)
			(layers "F.Cu" "F.Mask" "F.Paste")
			(net "GND")
		)
		(pad "3" smd rect
			(at 1.299972 0 270)
			(size 0.8128 1.016)
			(layers "F.Cu" "F.Mask" "F.Paste")
			(net "P5V")
		)
	)
	(footprint ""
		(layer "F.Cu")
		(at 171.9072 -94.833948 -90)
		(property "Reference" "R6013"
			(at 0 0 270)
			(layer "F.SilkS")
			(hide yes)
			(effects
				(font
					(size 1.27 1.27)
				)
			)
		)
		(property "Value" ""
			(at 0 0 270)
			(layer "F.Fab")
			(effects
				(font
					(size 1.27 1.27)
				)
			)
		)
		(duplicate_pad_numbers_are_jumpers no)
		(fp_line
			(start -0.7874 0.4064)
			(end -0.7874 -0.4064)
			(stroke
				(width 0.1524)
				(type default)
			)
			(layer "F.SilkS")
		)
		(fp_line
			(start 0.7874 0.4064)
			(end -0.7874 0.4064)
			(stroke
				(width 0.1524)
				(type default)
			)
			(layer "F.SilkS")
		)
		(fp_line
			(start -0.7874 -0.4064)
			(end 0.7874 -0.4064)
			(stroke
				(width 0.1524)
				(type default)
			)
			(layer "F.SilkS")
		)
		(fp_line
			(start 0.7874 -0.4064)
			(end 0.7874 0.4064)
			(stroke
				(width 0.1524)
				(type default)
			)
			(layer "F.SilkS")
		)
		(fp_line
			(start -0.67945 0.3048)
			(end -0.67945 -0.305054)
			(stroke
				(width 0.1)
				(type default)
			)
			(layer "F.Fab")
		)
		(fp_line
			(start -0.12065 0.3048)
			(end -0.67945 0.3048)
			(stroke
				(width 0.1)
				(type default)
			)
			(layer "F.Fab")
		)
		(fp_line
			(start 0.120396 0.3048)
			(end 0.120396 0.2794)
			(stroke
				(width 0.1)
				(type default)
			)
			(layer "F.Fab")
		)
		(fp_line
			(start 0.67945 0.3048)
			(end 0.120396 0.3048)
			(stroke
				(width 0.1)
				(type default)
			)
			(layer "F.Fab")
		)
		(fp_line
			(start -0.12065 0.2794)
			(end -0.12065 0.3048)
			(stroke
				(width 0.1)
				(type default)
			)
			(layer "F.Fab")
		)
		(fp_line
			(start 0.120396 0.2794)
			(end -0.12065 0.2794)
			(stroke
				(width 0.1)
				(type default)
			)
			(layer "F.Fab")
		)
		(fp_line
			(start -0.12065 -0.2794)
			(end 0.12065 -0.2794)
			(stroke
				(width 0.1)
				(type default)
			)
			(layer "F.Fab")
		)
		(fp_line
			(start 0.12065 -0.2794)
			(end 0.12065 -0.3048)
			(stroke
				(width 0.1)
				(type default)
			)
			(layer "F.Fab")
		)
		(fp_line
			(start 0.12065 -0.3048)
			(end 0.67945 -0.3048)
			(stroke
				(width 0.1)
				(type default)
			)
			(layer "F.Fab")
		)
		(fp_line
			(start 0.67945 -0.3048)
			(end 0.67945 0.3048)
			(stroke
				(width 0.1)
				(type default)
			)
			(layer "F.Fab")
		)
		(fp_line
			(start -0.67945 -0.305054)
			(end -0.12065 -0.305054)
			(stroke
				(width 0.1)
				(type default)
			)
			(layer "F.Fab")
		)
		(fp_line
			(start -0.12065 -0.305054)
			(end -0.12065 -0.2794)
			(stroke
				(width 0.1)
				(type default)
			)
			(layer "F.Fab")
		)
		(pad "1" smd circle
			(at -0.40005 0 270)
			(size 0 0)
			(layers "F.Cu" "F.Mask" "F.Paste")
			(net "SGPIO_SCM_CLK_<1>")
		)
		(pad "2" smd circle
			(at 0.40005 0 270)
			(size 0 0)
			(layers "F.Cu" "F.Mask" "F.Paste")
			(net "SGPIO_SCM_CLK_R_<1>")
		)
	)
	(footprint ""
		(layer "F.Cu")
		(at 138.067542 -382.6764 180)
		(property "Reference" "R927"
			(at 0 0 180)
			(layer "F.SilkS")
			(hide yes)
			(effects
				(font
					(size 1.27 1.27)
				)
			)
		)
		(property "Value" ""
			(at 0 0 180)
			(layer "F.Fab")
			(effects
				(font
					(size 1.27 1.27)
				)
			)
		)
		(duplicate_pad_numbers_are_jumpers no)
		(fp_line
			(start 0.32512 0.175006)
			(end -0.32512 0.175006)
			(stroke
				(width 0.1)
				(type default)
			)
			(layer "F.Fab")
		)
		(fp_line
			(start 0.32512 -0.175006)
			(end 0.32512 0.175006)
			(stroke
				(width 0.1)
				(type default)
			)
			(layer "F.Fab")
		)
		(fp_line
			(start -0.32512 0.175006)
			(end -0.32512 -0.175006)
			(stroke
				(width 0.1)
				(type default)
			)
			(layer "F.Fab")
		)
		(fp_line
			(start -0.32512 -0.175006)
			(end 0.32512 -0.175006)
			(stroke
				(width 0.1)
				(type default)
			)
			(layer "F.Fab")
		)
		(pad "1" smd rect
			(at -0.2667 0 180)
			(size 0.3048 0.381)
			(layers "F.Cu" "F.Mask" "F.Paste")
			(net "P1V8_CPU1_RT_1D")
		)
		(pad "2" smd rect
			(at 0.2667 0)
			(size 0.3048 0.381)
			(layers "F.Cu" "F.Mask" "F.Paste")
			(net "RT_CPU1_P3_ADDR1")
		)
	)
	(footprint ""
		(layer "F.Cu")
		(at 192.47358 -413.964882 90)
		(property "Reference" "R2940"
			(at 0 0 90)
			(layer "F.SilkS")
			(hide yes)
			(effects
				(font
					(size 1.27 1.27)
				)
			)
		)
		(property "Value" ""
			(at 0 0 90)
			(layer "F.Fab")
			(effects
				(font
					(size 1.27 1.27)
				)
			)
		)
		(duplicate_pad_numbers_are_jumpers no)
		(fp_line
			(start 0.7874 -0.4064)
			(end 0.7874 0.4064)
			(stroke
				(width 0.1524)
				(type default)
			)
			(layer "F.SilkS")
		)
		(fp_line
			(start -0.7874 -0.4064)
			(end 0.7874 -0.4064)
			(stroke
				(width 0.1524)
				(type default)
			)
			(layer "F.SilkS")
		)
		(fp_line
			(start 0.7874 0.4064)
			(end -0.7874 0.4064)
			(stroke
				(width 0.1524)
				(type default)
			)
			(layer "F.SilkS")
		)
		(fp_line
			(start -0.7874 0.4064)
			(end -0.7874 -0.4064)
			(stroke
				(width 0.1524)
				(type default)
			)
			(layer "F.SilkS")
		)
		(fp_line
			(start -0.12065 -0.305054)
			(end -0.12065 -0.2794)
			(stroke
				(width 0.1)
				(type default)
			)
			(layer "F.Fab")
		)
		(fp_line
			(start -0.67945 -0.305054)
			(end -0.12065 -0.305054)
			(stroke
				(width 0.1)
				(type default)
			)
			(layer "F.Fab")
		)
		(fp_line
			(start 0.67945 -0.3048)
			(end 0.67945 0.3048)
			(stroke
				(width 0.1)
				(type default)
			)
			(layer "F.Fab")
		)
		(fp_line
			(start 0.12065 -0.3048)
			(end 0.67945 -0.3048)
			(stroke
				(width 0.1)
				(type default)
			)
			(layer "F.Fab")
		)
		(fp_line
			(start 0.12065 -0.2794)
			(end 0.12065 -0.3048)
			(stroke
				(width 0.1)
				(type default)
			)
			(layer "F.Fab")
		)
		(fp_line
			(start -0.12065 -0.2794)
			(end 0.12065 -0.2794)
			(stroke
				(width 0.1)
				(type default)
			)
			(layer "F.Fab")
		)
		(fp_line
			(start 0.120396 0.2794)
			(end -0.12065 0.2794)
			(stroke
				(width 0.1)
				(type default)
			)
			(layer "F.Fab")
		)
		(fp_line
			(start -0.12065 0.2794)
			(end -0.12065 0.3048)
			(stroke
				(width 0.1)
				(type default)
			)
			(layer "F.Fab")
		)
		(fp_line
			(start 0.67945 0.3048)
			(end 0.120396 0.3048)
			(stroke
				(width 0.1)
				(type default)
			)
			(layer "F.Fab")
		)
		(fp_line
			(start 0.120396 0.3048)
			(end 0.120396 0.2794)
			(stroke
				(width 0.1)
				(type default)
			)
			(layer "F.Fab")
		)
		(fp_line
			(start -0.12065 0.3048)
			(end -0.67945 0.3048)
			(stroke
				(width 0.1)
				(type default)
			)
			(layer "F.Fab")
		)
		(fp_line
			(start -0.67945 0.3048)
			(end -0.67945 -0.305054)
			(stroke
				(width 0.1)
				(type default)
			)
			(layer "F.Fab")
		)
		(pad "1" smd circle
			(at -0.40005 0 90)
			(size 0 0)
			(layers "F.Cu" "F.Mask" "F.Paste")
			(net "P3V3_AUX")
		)
		(pad "2" smd circle
			(at 0.40005 0 90)
			(size 0 0)
			(layers "F.Cu" "F.Mask" "F.Paste")
			(net "FM_GPU_HSC_EN")
		)
	)
	(footprint ""
		(layer "F.Cu")
		(at 400.31924 -378.95403 -90)
		(property "Reference" "C863"
			(at 0 0 270)
			(layer "F.SilkS")
			(hide yes)
			(effects
				(font
					(size 1.27 1.27)
				)
			)
		)
		(property "Value" ""
			(at 0 0 270)
			(layer "F.Fab")
			(effects
				(font
					(size 1.27 1.27)
				)
			)
		)
		(duplicate_pad_numbers_are_jumpers no)
		(fp_line
			(start -0.299974 0.150114)
			(end -0.299974 -0.150114)
			(stroke
				(width 0.1)
				(type default)
			)
			(layer "F.Fab")
		)
		(fp_line
			(start 0.299974 0.150114)
			(end -0.299974 0.150114)
			(stroke
				(width 0.1)
				(type default)
			)
			(layer "F.Fab")
		)
		(fp_line
			(start -0.299974 -0.150114)
			(end 0.299974 -0.150114)
			(stroke
				(width 0.1)
				(type default)
			)
			(layer "F.Fab")
		)
		(fp_line
			(start 0.299974 -0.150114)
			(end 0.299974 0.150114)
			(stroke
				(width 0.1)
				(type default)
			)
			(layer "F.Fab")
		)
		(pad "1" smd rect
			(at -0.2667 0 270)
			(size 0.3048 0.381)
			(layers "F.Cu" "F.Mask" "F.Paste")
			(net "P5E_CPU0_P2_TX_C_DP<3>")
		)
		(pad "2" smd rect
			(at 0.2667 0 270)
			(size 0.3048 0.381)
			(layers "F.Cu" "F.Mask" "F.Paste")
			(net "P5E_CPU0_P2_TX_DP<3>")
		)
	)
	(footprint ""
		(layer "F.Cu")
		(at 254.11684 -92.719144 -90)
		(property "Reference" "R1638"
			(at 0 0 270)
			(layer "F.SilkS")
			(hide yes)
			(effects
				(font
					(size 1.27 1.27)
				)
			)
		)
		(property "Value" ""
			(at 0 0 270)
			(layer "F.Fab")
			(effects
				(font
					(size 1.27 1.27)
				)
			)
		)
		(duplicate_pad_numbers_are_jumpers no)
		(fp_line
			(start -0.7874 0.4064)
			(end -0.7874 -0.4064)
			(stroke
				(width 0.1524)
				(type default)
			)
			(layer "F.SilkS")
		)
		(fp_line
			(start 0.7874 0.4064)
			(end -0.7874 0.4064)
			(stroke
				(width 0.1524)
				(type default)
			)
			(layer "F.SilkS")
		)
		(fp_line
			(start -0.7874 -0.4064)
			(end 0.7874 -0.4064)
			(stroke
				(width 0.1524)
				(type default)
			)
			(layer "F.SilkS")
		)
		(fp_line
			(start 0.7874 -0.4064)
			(end 0.7874 0.4064)
			(stroke
				(width 0.1524)
				(type default)
			)
			(layer "F.SilkS")
		)
		(fp_line
			(start -0.67945 0.3048)
			(end -0.67945 -0.305054)
			(stroke
				(width 0.1)
				(type default)
			)
			(layer "F.Fab")
		)
		(fp_line
			(start -0.12065 0.3048)
			(end -0.67945 0.3048)
			(stroke
				(width 0.1)
				(type default)
			)
			(layer "F.Fab")
		)
		(fp_line
			(start 0.120396 0.3048)
			(end 0.120396 0.2794)
			(stroke
				(width 0.1)
				(type default)
			)
			(layer "F.Fab")
		)
		(fp_line
			(start 0.67945 0.3048)
			(end 0.120396 0.3048)
			(stroke
				(width 0.1)
				(type default)
			)
			(layer "F.Fab")
		)
		(fp_line
			(start -0.12065 0.2794)
			(end -0.12065 0.3048)
			(stroke
				(width 0.1)
				(type default)
			)
			(layer "F.Fab")
		)
		(fp_line
			(start 0.120396 0.2794)
			(end -0.12065 0.2794)
			(stroke
				(width 0.1)
				(type default)
			)
			(layer "F.Fab")
		)
		(fp_line
			(start -0.12065 -0.2794)
			(end 0.12065 -0.2794)
			(stroke
				(width 0.1)
				(type default)
			)
			(layer "F.Fab")
		)
		(fp_line
			(start 0.12065 -0.2794)
			(end 0.12065 -0.3048)
			(stroke
				(width 0.1)
				(type default)
			)
			(layer "F.Fab")
		)
		(fp_line
			(start 0.12065 -0.3048)
			(end 0.67945 -0.3048)
			(stroke
				(width 0.1)
				(type default)
			)
			(layer "F.Fab")
		)
		(fp_line
			(start 0.67945 -0.3048)
			(end 0.67945 0.3048)
			(stroke
				(width 0.1)
				(type default)
			)
			(layer "F.Fab")
		)
		(fp_line
			(start -0.67945 -0.305054)
			(end -0.12065 -0.305054)
			(stroke
				(width 0.1)
				(type default)
			)
			(layer "F.Fab")
		)
		(fp_line
			(start -0.12065 -0.305054)
			(end -0.12065 -0.2794)
			(stroke
				(width 0.1)
				(type default)
			)
			(layer "F.Fab")
		)
		(pad "1" smd circle
			(at -0.40005 0 270)
			(size 0 0)
			(layers "F.Cu" "F.Mask" "F.Paste")
			(net "JTAG_P0_R_TCK")
		)
		(pad "2" smd circle
			(at 0.40005 0 270)
			(size 0 0)
			(layers "F.Cu" "F.Mask" "F.Paste")
			(net "JTAG_CPU0_TCK")
		)
	)
	(footprint ""
		(layer "F.Cu")
		(at 463.465926 -96.406208)
		(property "Reference" "R2474"
			(at 0 0 0)
			(layer "F.SilkS")
			(hide yes)
			(effects
				(font
					(size 1.27 1.27)
				)
			)
		)
		(property "Value" ""
			(at 0 0 0)
			(layer "F.Fab")
			(effects
				(font
					(size 1.27 1.27)
				)
			)
		)
		(duplicate_pad_numbers_are_jumpers no)
		(fp_line
			(start -0.7874 -0.4064)
			(end 0.7874 -0.4064)
			(stroke
				(width 0.1524)
				(type default)
			)
			(layer "F.SilkS")
		)
		(fp_line
			(start -0.7874 0.4064)
			(end -0.7874 -0.4064)
			(stroke
				(width 0.1524)
				(type default)
			)
			(layer "F.SilkS")
		)
		(fp_line
			(start 0.7874 -0.4064)
			(end 0.7874 0.4064)
			(stroke
				(width 0.1524)
				(type default)
			)
			(layer "F.SilkS")
		)
		(fp_line
			(start 0.7874 0.4064)
			(end -0.7874 0.4064)
			(stroke
				(width 0.1524)
				(type default)
			)
			(layer "F.SilkS")
		)
		(fp_line
			(start -0.67945 -0.305054)
			(end -0.12065 -0.305054)
			(stroke
				(width 0.1)
				(type default)
			)
			(layer "F.Fab")
		)
		(fp_line
			(start -0.67945 0.3048)
			(end -0.67945 -0.305054)
			(stroke
				(width 0.1)
				(type default)
			)
			(layer "F.Fab")
		)
		(fp_line
			(start -0.12065 -0.305054)
			(end -0.12065 -0.2794)
			(stroke
				(width 0.1)
				(type default)
			)
			(layer "F.Fab")
		)
		(fp_line
			(start -0.12065 -0.2794)
			(end 0.12065 -0.2794)
			(stroke
				(width 0.1)
				(type default)
			)
			(layer "F.Fab")
		)
		(fp_line
			(start -0.12065 0.2794)
			(end -0.12065 0.3048)
			(stroke
				(width 0.1)
				(type default)
			)
			(layer "F.Fab")
		)
		(fp_line
			(start -0.12065 0.3048)
			(end -0.67945 0.3048)
			(stroke
				(width 0.1)
				(type default)
			)
			(layer "F.Fab")
		)
		(fp_line
			(start 0.120396 0.2794)
			(end -0.12065 0.2794)
			(stroke
				(width 0.1)
				(type default)
			)
			(layer "F.Fab")
		)
		(fp_line
			(start 0.120396 0.3048)
			(end 0.120396 0.2794)
			(stroke
				(width 0.1)
				(type default)
			)
			(layer "F.Fab")
		)
		(fp_line
			(start 0.12065 -0.3048)
			(end 0.67945 -0.3048)
			(stroke
				(width 0.1)
				(type default)
			)
			(layer "F.Fab")
		)
		(fp_line
			(start 0.12065 -0.2794)
			(end 0.12065 -0.3048)
			(stroke
				(width 0.1)
				(type default)
			)
			(layer "F.Fab")
		)
		(fp_line
			(start 0.67945 -0.3048)
			(end 0.67945 0.3048)
			(stroke
				(width 0.1)
				(type default)
			)
			(layer "F.Fab")
		)
		(fp_line
			(start 0.67945 0.3048)
			(end 0.120396 0.3048)
			(stroke
				(width 0.1)
				(type default)
			)
			(layer "F.Fab")
		)
		(pad "1" smd circle
			(at -0.40005 0)
			(size 0 0)
			(layers "F.Cu" "F.Mask" "F.Paste")
			(net "FM_NCSI_OCP_SFF_R_OE")
		)
		(pad "2" smd circle
			(at 0.40005 0)
			(size 0 0)
			(layers "F.Cu" "F.Mask" "F.Paste")
			(net "FB_BMC_ISOLATE")
		)
	)
	(footprint ""
		(layer "F.Cu")
		(at 462.20507 -42.004488 90)
		(property "Reference" "R4070"
			(at 0 0 90)
			(layer "F.SilkS")
			(hide yes)
			(effects
				(font
					(size 1.27 1.27)
				)
			)
		)
		(property "Value" ""
			(at 0 0 90)
			(layer "F.Fab")
			(effects
				(font
					(size 1.27 1.27)
				)
			)
		)
		(duplicate_pad_numbers_are_jumpers no)
		(fp_line
			(start 0.7874 -0.4064)
			(end 0.7874 0.4064)
			(stroke
				(width 0.1524)
				(type default)
			)
			(layer "F.SilkS")
		)
		(fp_line
			(start -0.7874 -0.4064)
			(end 0.7874 -0.4064)
			(stroke
				(width 0.1524)
				(type default)
			)
			(layer "F.SilkS")
		)
		(fp_line
			(start 0.7874 0.4064)
			(end -0.7874 0.4064)
			(stroke
				(width 0.1524)
				(type default)
			)
			(layer "F.SilkS")
		)
		(fp_line
			(start -0.7874 0.4064)
			(end -0.7874 -0.4064)
			(stroke
				(width 0.1524)
				(type default)
			)
			(layer "F.SilkS")
		)
		(fp_line
			(start -0.12065 -0.305054)
			(end -0.12065 -0.2794)
			(stroke
				(width 0.1)
				(type default)
			)
			(layer "F.Fab")
		)
		(fp_line
			(start -0.67945 -0.305054)
			(end -0.12065 -0.305054)
			(stroke
				(width 0.1)
				(type default)
			)
			(layer "F.Fab")
		)
		(fp_line
			(start 0.67945 -0.3048)
			(end 0.67945 0.3048)
			(stroke
				(width 0.1)
				(type default)
			)
			(layer "F.Fab")
		)
		(fp_line
			(start 0.12065 -0.3048)
			(end 0.67945 -0.3048)
			(stroke
				(width 0.1)
				(type default)
			)
			(layer "F.Fab")
		)
		(fp_line
			(start 0.12065 -0.2794)
			(end 0.12065 -0.3048)
			(stroke
				(width 0.1)
				(type default)
			)
			(layer "F.Fab")
		)
		(fp_line
			(start -0.12065 -0.2794)
			(end 0.12065 -0.2794)
			(stroke
				(width 0.1)
				(type default)
			)
			(layer "F.Fab")
		)
		(fp_line
			(start 0.120396 0.2794)
			(end -0.12065 0.2794)
			(stroke
				(width 0.1)
				(type default)
			)
			(layer "F.Fab")
		)
		(fp_line
			(start -0.12065 0.2794)
			(end -0.12065 0.3048)
			(stroke
				(width 0.1)
				(type default)
			)
			(layer "F.Fab")
		)
		(fp_line
			(start 0.67945 0.3048)
			(end 0.120396 0.3048)
			(stroke
				(width 0.1)
				(type default)
			)
			(layer "F.Fab")
		)
		(fp_line
			(start 0.120396 0.3048)
			(end 0.120396 0.2794)
			(stroke
				(width 0.1)
				(type default)
			)
			(layer "F.Fab")
		)
		(fp_line
			(start -0.12065 0.3048)
			(end -0.67945 0.3048)
			(stroke
				(width 0.1)
				(type default)
			)
			(layer "F.Fab")
		)
		(fp_line
			(start -0.67945 0.3048)
			(end -0.67945 -0.305054)
			(stroke
				(width 0.1)
				(type default)
			)
			(layer "F.Fab")
		)
		(pad "1" smd circle
			(at -0.40005 0 90)
			(size 0 0)
			(layers "F.Cu" "F.Mask" "F.Paste")
			(net "P12V_AUX")
		)
		(pad "2" smd circle
			(at 0.40005 0 90)
			(size 0 0)
			(layers "F.Cu" "F.Mask" "F.Paste")
			(net "P3V3_OCP_1_EN_G")
		)
	)
	(footprint ""
		(layer "F.Cu")
		(at 358.727502 -164.638482 -90)
		(property "Reference" "PC566_5"
			(at 0 0 270)
			(layer "F.SilkS")
			(hide yes)
			(effects
				(font
					(size 1.27 1.27)
				)
			)
		)
		(property "Value" ""
			(at 0 0 270)
			(layer "F.Fab")
			(effects
				(font
					(size 1.27 1.27)
				)
			)
		)
		(duplicate_pad_numbers_are_jumpers no)
		(fp_line
			(start -0.7874 0.4064)
			(end -0.7874 -0.4064)
			(stroke
				(width 0.1524)
				(type default)
			)
			(layer "F.SilkS")
		)
		(fp_line
			(start 0.7874 0.4064)
			(end -0.7874 0.4064)
			(stroke
				(width 0.1524)
				(type default)
			)
			(layer "F.SilkS")
		)
		(fp_line
			(start -0.7874 -0.4064)
			(end 0.7874 -0.4064)
			(stroke
				(width 0.1524)
				(type default)
			)
			(layer "F.SilkS")
		)
		(fp_line
			(start 0.7874 -0.4064)
			(end 0.7874 0.4064)
			(stroke
				(width 0.1524)
				(type default)
			)
			(layer "F.SilkS")
		)
		(fp_line
			(start -0.67945 0.3048)
			(end -0.67945 -0.305054)
			(stroke
				(width 0.1)
				(type default)
			)
			(layer "F.Fab")
		)
		(fp_line
			(start -0.12065 0.3048)
			(end -0.67945 0.3048)
			(stroke
				(width 0.1)
				(type default)
			)
			(layer "F.Fab")
		)
		(fp_line
			(start 0.120396 0.3048)
			(end 0.120396 0.2794)
			(stroke
				(width 0.1)
				(type default)
			)
			(layer "F.Fab")
		)
		(fp_line
			(start 0.67945 0.3048)
			(end 0.120396 0.3048)
			(stroke
				(width 0.1)
				(type default)
			)
			(layer "F.Fab")
		)
		(fp_line
			(start -0.12065 0.2794)
			(end -0.12065 0.3048)
			(stroke
				(width 0.1)
				(type default)
			)
			(layer "F.Fab")
		)
		(fp_line
			(start 0.120396 0.2794)
			(end -0.12065 0.2794)
			(stroke
				(width 0.1)
				(type default)
			)
			(layer "F.Fab")
		)
		(fp_line
			(start -0.12065 -0.2794)
			(end 0.12065 -0.2794)
			(stroke
				(width 0.1)
				(type default)
			)
			(layer "F.Fab")
		)
		(fp_line
			(start 0.12065 -0.2794)
			(end 0.12065 -0.3048)
			(stroke
				(width 0.1)
				(type default)
			)
			(layer "F.Fab")
		)
		(fp_line
			(start 0.12065 -0.3048)
			(end 0.67945 -0.3048)
			(stroke
				(width 0.1)
				(type default)
			)
			(layer "F.Fab")
		)
		(fp_line
			(start 0.67945 -0.3048)
			(end 0.67945 0.3048)
			(stroke
				(width 0.1)
				(type default)
			)
			(layer "F.Fab")
		)
		(fp_line
			(start -0.67945 -0.305054)
			(end -0.12065 -0.305054)
			(stroke
				(width 0.1)
				(type default)
			)
			(layer "F.Fab")
		)
		(fp_line
			(start -0.12065 -0.305054)
			(end -0.12065 -0.2794)
			(stroke
				(width 0.1)
				(type default)
			)
			(layer "F.Fab")
		)
		(pad "1" smd circle
			(at -0.40005 0 270)
			(size 0 0)
			(layers "F.Cu" "F.Mask" "F.Paste")
			(net "PVDDCR_CPU0_P0_VCCS")
		)
		(pad "2" smd circle
			(at 0.40005 0 270)
			(size 0 0)
			(layers "F.Cu" "F.Mask" "F.Paste")
			(net "GND")
		)
	)
	(footprint ""
		(layer "F.Cu")
		(at 38.0746 -437.226964 -90)
		(property "Reference" "R2910"
			(at 0 0 270)
			(layer "F.SilkS")
			(hide yes)
			(effects
				(font
					(size 1.27 1.27)
				)
			)
		)
		(property "Value" ""
			(at 0 0 270)
			(layer "F.Fab")
			(effects
				(font
					(size 1.27 1.27)
				)
			)
		)
		(duplicate_pad_numbers_are_jumpers no)
		(fp_line
			(start -0.7874 0.4064)
			(end -0.7874 -0.4064)
			(stroke
				(width 0.1524)
				(type default)
			)
			(layer "F.SilkS")
		)
		(fp_line
			(start 0.7874 0.4064)
			(end -0.7874 0.4064)
			(stroke
				(width 0.1524)
				(type default)
			)
			(layer "F.SilkS")
		)
		(fp_line
			(start -0.7874 -0.4064)
			(end 0.7874 -0.4064)
			(stroke
				(width 0.1524)
				(type default)
			)
			(layer "F.SilkS")
		)
		(fp_line
			(start 0.7874 -0.4064)
			(end 0.7874 0.4064)
			(stroke
				(width 0.1524)
				(type default)
			)
			(layer "F.SilkS")
		)
		(fp_line
			(start -0.67945 0.3048)
			(end -0.67945 -0.305054)
			(stroke
				(width 0.1)
				(type default)
			)
			(layer "F.Fab")
		)
		(fp_line
			(start -0.12065 0.3048)
			(end -0.67945 0.3048)
			(stroke
				(width 0.1)
				(type default)
			)
			(layer "F.Fab")
		)
		(fp_line
			(start 0.120396 0.3048)
			(end 0.120396 0.2794)
			(stroke
				(width 0.1)
				(type default)
			)
			(layer "F.Fab")
		)
		(fp_line
			(start 0.67945 0.3048)
			(end 0.120396 0.3048)
			(stroke
				(width 0.1)
				(type default)
			)
			(layer "F.Fab")
		)
		(fp_line
			(start -0.12065 0.2794)
			(end -0.12065 0.3048)
			(stroke
				(width 0.1)
				(type default)
			)
			(layer "F.Fab")
		)
		(fp_line
			(start 0.120396 0.2794)
			(end -0.12065 0.2794)
			(stroke
				(width 0.1)
				(type default)
			)
			(layer "F.Fab")
		)
		(fp_line
			(start -0.12065 -0.2794)
			(end 0.12065 -0.2794)
			(stroke
				(width 0.1)
				(type default)
			)
			(layer "F.Fab")
		)
		(fp_line
			(start 0.12065 -0.2794)
			(end 0.12065 -0.3048)
			(stroke
				(width 0.1)
				(type default)
			)
			(layer "F.Fab")
		)
		(fp_line
			(start 0.12065 -0.3048)
			(end 0.67945 -0.3048)
			(stroke
				(width 0.1)
				(type default)
			)
			(layer "F.Fab")
		)
		(fp_line
			(start 0.67945 -0.3048)
			(end 0.67945 0.3048)
			(stroke
				(width 0.1)
				(type default)
			)
			(layer "F.Fab")
		)
		(fp_line
			(start -0.67945 -0.305054)
			(end -0.12065 -0.305054)
			(stroke
				(width 0.1)
				(type default)
			)
			(layer "F.Fab")
		)
		(fp_line
			(start -0.12065 -0.305054)
			(end -0.12065 -0.2794)
			(stroke
				(width 0.1)
				(type default)
			)
			(layer "F.Fab")
		)
		(pad "1" smd circle
			(at -0.40005 0 270)
			(size 0 0)
			(layers "F.Cu" "F.Mask" "F.Paste")
			(net "P3V3_AUX")
		)
		(pad "2" smd circle
			(at 0.40005 0 270)
			(size 0 0)
			(layers "F.Cu" "F.Mask" "F.Paste")
			(net "FM_SWB_PWR_EN_R")
		)
	)
	(footprint ""
		(layer "F.Cu")
		(at 242.588542 -294.936926 180)
		(property "Reference" "PC6505"
			(at 0 0 180)
			(layer "F.SilkS")
			(hide yes)
			(effects
				(font
					(size 1.27 1.27)
				)
			)
		)
		(property "Value" ""
			(at 0 0 180)
			(layer "F.Fab")
			(effects
				(font
					(size 1.27 1.27)
				)
			)
		)
		(duplicate_pad_numbers_are_jumpers no)
		(fp_line
			(start 0.7874 0.4064)
			(end -0.7874 0.4064)
			(stroke
				(width 0.1524)
				(type default)
			)
			(layer "F.SilkS")
		)
		(fp_line
			(start 0.7874 -0.4064)
			(end 0.7874 0.4064)
			(stroke
				(width 0.1524)
				(type default)
			)
			(layer "F.SilkS")
		)
		(fp_line
			(start -0.7874 0.4064)
			(end -0.7874 -0.4064)
			(stroke
				(width 0.1524)
				(type default)
			)
			(layer "F.SilkS")
		)
		(fp_line
			(start -0.7874 -0.4064)
			(end 0.7874 -0.4064)
			(stroke
				(width 0.1524)
				(type default)
			)
			(layer "F.SilkS")
		)
		(fp_line
			(start 0.67945 0.3048)
			(end 0.120396 0.3048)
			(stroke
				(width 0.1)
				(type default)
			)
			(layer "F.Fab")
		)
		(fp_line
			(start 0.67945 -0.3048)
			(end 0.67945 0.3048)
			(stroke
				(width 0.1)
				(type default)
			)
			(layer "F.Fab")
		)
		(fp_line
			(start 0.12065 -0.2794)
			(end 0.12065 -0.3048)
			(stroke
				(width 0.1)
				(type default)
			)
			(layer "F.Fab")
		)
		(fp_line
			(start 0.12065 -0.3048)
			(end 0.67945 -0.3048)
			(stroke
				(width 0.1)
				(type default)
			)
			(layer "F.Fab")
		)
		(fp_line
			(start 0.120396 0.3048)
			(end 0.120396 0.2794)
			(stroke
				(width 0.1)
				(type default)
			)
			(layer "F.Fab")
		)
		(fp_line
			(start 0.120396 0.2794)
			(end -0.12065 0.2794)
			(stroke
				(width 0.1)
				(type default)
			)
			(layer "F.Fab")
		)
		(fp_line
			(start -0.12065 0.3048)
			(end -0.67945 0.3048)
			(stroke
				(width 0.1)
				(type default)
			)
			(layer "F.Fab")
		)
		(fp_line
			(start -0.12065 0.2794)
			(end -0.12065 0.3048)
			(stroke
				(width 0.1)
				(type default)
			)
			(layer "F.Fab")
		)
		(fp_line
			(start -0.12065 -0.2794)
			(end 0.12065 -0.2794)
			(stroke
				(width 0.1)
				(type default)
			)
			(layer "F.Fab")
		)
		(fp_line
			(start -0.12065 -0.305054)
			(end -0.12065 -0.2794)
			(stroke
				(width 0.1)
				(type default)
			)
			(layer "F.Fab")
		)
		(fp_line
			(start -0.67945 0.3048)
			(end -0.67945 -0.305054)
			(stroke
				(width 0.1)
				(type default)
			)
			(layer "F.Fab")
		)
		(fp_line
			(start -0.67945 -0.305054)
			(end -0.12065 -0.305054)
			(stroke
				(width 0.1)
				(type default)
			)
			(layer "F.Fab")
		)
		(pad "1" smd circle
			(at -0.40005 0 180)
			(size 0 0)
			(layers "F.Cu" "F.Mask" "F.Paste")
			(net "SW_P12V_AUX_P1V8_RETIMER_CPU0_FLT")
		)
		(pad "2" smd circle
			(at 0.40005 0 180)
			(size 0 0)
			(layers "F.Cu" "F.Mask" "F.Paste")
			(net "GND")
		)
	)
	(footprint ""
		(layer "F.Cu")
		(at 408.758644 -139.362942 -90)
		(property "Reference" "PR8092"
			(at 0 0 270)
			(layer "F.SilkS")
			(hide yes)
			(effects
				(font
					(size 1.27 1.27)
				)
			)
		)
		(property "Value" ""
			(at 0 0 270)
			(layer "F.Fab")
			(effects
				(font
					(size 1.27 1.27)
				)
			)
		)
		(duplicate_pad_numbers_are_jumpers no)
		(fp_line
			(start -0.7874 0.4064)
			(end -0.7874 -0.4064)
			(stroke
				(width 0.1524)
				(type default)
			)
			(layer "F.SilkS")
		)
		(fp_line
			(start 0.7874 0.4064)
			(end -0.7874 0.4064)
			(stroke
				(width 0.1524)
				(type default)
			)
			(layer "F.SilkS")
		)
		(fp_line
			(start -0.7874 -0.4064)
			(end 0.7874 -0.4064)
			(stroke
				(width 0.1524)
				(type default)
			)
			(layer "F.SilkS")
		)
		(fp_line
			(start 0.7874 -0.4064)
			(end 0.7874 0.4064)
			(stroke
				(width 0.1524)
				(type default)
			)
			(layer "F.SilkS")
		)
		(fp_line
			(start -0.67945 0.3048)
			(end -0.67945 -0.305054)
			(stroke
				(width 0.1)
				(type default)
			)
			(layer "F.Fab")
		)
		(fp_line
			(start -0.12065 0.3048)
			(end -0.67945 0.3048)
			(stroke
				(width 0.1)
				(type default)
			)
			(layer "F.Fab")
		)
		(fp_line
			(start 0.120396 0.3048)
			(end 0.120396 0.2794)
			(stroke
				(width 0.1)
				(type default)
			)
			(layer "F.Fab")
		)
		(fp_line
			(start 0.67945 0.3048)
			(end 0.120396 0.3048)
			(stroke
				(width 0.1)
				(type default)
			)
			(layer "F.Fab")
		)
		(fp_line
			(start -0.12065 0.2794)
			(end -0.12065 0.3048)
			(stroke
				(width 0.1)
				(type default)
			)
			(layer "F.Fab")
		)
		(fp_line
			(start 0.120396 0.2794)
			(end -0.12065 0.2794)
			(stroke
				(width 0.1)
				(type default)
			)
			(layer "F.Fab")
		)
		(fp_line
			(start -0.12065 -0.2794)
			(end 0.12065 -0.2794)
			(stroke
				(width 0.1)
				(type default)
			)
			(layer "F.Fab")
		)
		(fp_line
			(start 0.12065 -0.2794)
			(end 0.12065 -0.3048)
			(stroke
				(width 0.1)
				(type default)
			)
			(layer "F.Fab")
		)
		(fp_line
			(start 0.12065 -0.3048)
			(end 0.67945 -0.3048)
			(stroke
				(width 0.1)
				(type default)
			)
			(layer "F.Fab")
		)
		(fp_line
			(start 0.67945 -0.3048)
			(end 0.67945 0.3048)
			(stroke
				(width 0.1)
				(type default)
			)
			(layer "F.Fab")
		)
		(fp_line
			(start -0.67945 -0.305054)
			(end -0.12065 -0.305054)
			(stroke
				(width 0.1)
				(type default)
			)
			(layer "F.Fab")
		)
		(fp_line
			(start -0.12065 -0.305054)
			(end -0.12065 -0.2794)
			(stroke
				(width 0.1)
				(type default)
			)
			(layer "F.Fab")
		)
		(pad "1" smd circle
			(at -0.40005 0 270)
			(size 0 0)
			(layers "F.Cu" "F.Mask" "F.Paste")
			(net "P5V_AUX_FB")
		)
		(pad "2" smd circle
			(at 0.40005 0 270)
			(size 0 0)
			(layers "F.Cu" "F.Mask" "F.Paste")
			(net "P5V_AUX")
		)
	)
	(footprint ""
		(layer "F.Cu")
		(at 172.878242 -28.03779 90)
		(property "Reference" "PR4010"
			(at 0 0 90)
			(layer "F.SilkS")
			(hide yes)
			(effects
				(font
					(size 1.27 1.27)
				)
			)
		)
		(property "Value" ""
			(at 0 0 90)
			(layer "F.Fab")
			(effects
				(font
					(size 1.27 1.27)
				)
			)
		)
		(duplicate_pad_numbers_are_jumpers no)
		(fp_line
			(start 0.7874 -0.4064)
			(end 0.7874 0.4064)
			(stroke
				(width 0.1524)
				(type default)
			)
			(layer "F.SilkS")
		)
		(fp_line
			(start -0.7874 -0.4064)
			(end 0.7874 -0.4064)
			(stroke
				(width 0.1524)
				(type default)
			)
			(layer "F.SilkS")
		)
		(fp_line
			(start 0.7874 0.4064)
			(end -0.7874 0.4064)
			(stroke
				(width 0.1524)
				(type default)
			)
			(layer "F.SilkS")
		)
		(fp_line
			(start -0.7874 0.4064)
			(end -0.7874 -0.4064)
			(stroke
				(width 0.1524)
				(type default)
			)
			(layer "F.SilkS")
		)
		(fp_line
			(start -0.12065 -0.305054)
			(end -0.12065 -0.2794)
			(stroke
				(width 0.1)
				(type default)
			)
			(layer "F.Fab")
		)
		(fp_line
			(start -0.67945 -0.305054)
			(end -0.12065 -0.305054)
			(stroke
				(width 0.1)
				(type default)
			)
			(layer "F.Fab")
		)
		(fp_line
			(start 0.67945 -0.3048)
			(end 0.67945 0.3048)
			(stroke
				(width 0.1)
				(type default)
			)
			(layer "F.Fab")
		)
		(fp_line
			(start 0.12065 -0.3048)
			(end 0.67945 -0.3048)
			(stroke
				(width 0.1)
				(type default)
			)
			(layer "F.Fab")
		)
		(fp_line
			(start 0.12065 -0.2794)
			(end 0.12065 -0.3048)
			(stroke
				(width 0.1)
				(type default)
			)
			(layer "F.Fab")
		)
		(fp_line
			(start -0.12065 -0.2794)
			(end 0.12065 -0.2794)
			(stroke
				(width 0.1)
				(type default)
			)
			(layer "F.Fab")
		)
		(fp_line
			(start 0.120396 0.2794)
			(end -0.12065 0.2794)
			(stroke
				(width 0.1)
				(type default)
			)
			(layer "F.Fab")
		)
		(fp_line
			(start -0.12065 0.2794)
			(end -0.12065 0.3048)
			(stroke
				(width 0.1)
				(type default)
			)
			(layer "F.Fab")
		)
		(fp_line
			(start 0.67945 0.3048)
			(end 0.120396 0.3048)
			(stroke
				(width 0.1)
				(type default)
			)
			(layer "F.Fab")
		)
		(fp_line
			(start 0.120396 0.3048)
			(end 0.120396 0.2794)
			(stroke
				(width 0.1)
				(type default)
			)
			(layer "F.Fab")
		)
		(fp_line
			(start -0.12065 0.3048)
			(end -0.67945 0.3048)
			(stroke
				(width 0.1)
				(type default)
			)
			(layer "F.Fab")
		)
		(fp_line
			(start -0.67945 0.3048)
			(end -0.67945 -0.305054)
			(stroke
				(width 0.1)
				(type default)
			)
			(layer "F.Fab")
		)
		(pad "1" smd circle
			(at -0.40005 0 90)
			(size 0 0)
			(layers "F.Cu" "F.Mask" "F.Paste")
			(net "P12V_AUX")
		)
		(pad "2" smd circle
			(at 0.40005 0 90)
			(size 0 0)
			(layers "F.Cu" "F.Mask" "F.Paste")
			(net "P12V_SCM_OV_FB")
		)
	)
	(footprint ""
		(layer "F.Cu")
		(at 37.681662 -419.249098 -90)
		(property "Reference" "R3293"
			(at 0 0 270)
			(layer "F.SilkS")
			(hide yes)
			(effects
				(font
					(size 1.27 1.27)
				)
			)
		)
		(property "Value" ""
			(at 0 0 270)
			(layer "F.Fab")
			(effects
				(font
					(size 1.27 1.27)
				)
			)
		)
		(duplicate_pad_numbers_are_jumpers no)
		(fp_line
			(start -0.7874 0.4064)
			(end -0.7874 -0.4064)
			(stroke
				(width 0.1524)
				(type default)
			)
			(layer "F.SilkS")
		)
		(fp_line
			(start 0.7874 0.4064)
			(end -0.7874 0.4064)
			(stroke
				(width 0.1524)
				(type default)
			)
			(layer "F.SilkS")
		)
		(fp_line
			(start -0.7874 -0.4064)
			(end 0.7874 -0.4064)
			(stroke
				(width 0.1524)
				(type default)
			)
			(layer "F.SilkS")
		)
		(fp_line
			(start 0.7874 -0.4064)
			(end 0.7874 0.4064)
			(stroke
				(width 0.1524)
				(type default)
			)
			(layer "F.SilkS")
		)
		(fp_line
			(start -0.67945 0.3048)
			(end -0.67945 -0.305054)
			(stroke
				(width 0.1)
				(type default)
			)
			(layer "F.Fab")
		)
		(fp_line
			(start -0.12065 0.3048)
			(end -0.67945 0.3048)
			(stroke
				(width 0.1)
				(type default)
			)
			(layer "F.Fab")
		)
		(fp_line
			(start 0.120396 0.3048)
			(end 0.120396 0.2794)
			(stroke
				(width 0.1)
				(type default)
			)
			(layer "F.Fab")
		)
		(fp_line
			(start 0.67945 0.3048)
			(end 0.120396 0.3048)
			(stroke
				(width 0.1)
				(type default)
			)
			(layer "F.Fab")
		)
		(fp_line
			(start -0.12065 0.2794)
			(end -0.12065 0.3048)
			(stroke
				(width 0.1)
				(type default)
			)
			(layer "F.Fab")
		)
		(fp_line
			(start 0.120396 0.2794)
			(end -0.12065 0.2794)
			(stroke
				(width 0.1)
				(type default)
			)
			(layer "F.Fab")
		)
		(fp_line
			(start -0.12065 -0.2794)
			(end 0.12065 -0.2794)
			(stroke
				(width 0.1)
				(type default)
			)
			(layer "F.Fab")
		)
		(fp_line
			(start 0.12065 -0.2794)
			(end 0.12065 -0.3048)
			(stroke
				(width 0.1)
				(type default)
			)
			(layer "F.Fab")
		)
		(fp_line
			(start 0.12065 -0.3048)
			(end 0.67945 -0.3048)
			(stroke
				(width 0.1)
				(type default)
			)
			(layer "F.Fab")
		)
		(fp_line
			(start 0.67945 -0.3048)
			(end 0.67945 0.3048)
			(stroke
				(width 0.1)
				(type default)
			)
			(layer "F.Fab")
		)
		(fp_line
			(start -0.67945 -0.305054)
			(end -0.12065 -0.305054)
			(stroke
				(width 0.1)
				(type default)
			)
			(layer "F.Fab")
		)
		(fp_line
			(start -0.12065 -0.305054)
			(end -0.12065 -0.2794)
			(stroke
				(width 0.1)
				(type default)
			)
			(layer "F.Fab")
		)
		(pad "1" smd circle
			(at -0.40005 0 270)
			(size 0 0)
			(layers "F.Cu" "F.Mask" "F.Paste")
			(net "FM_P2E_MODE")
		)
		(pad "2" smd circle
			(at 0.40005 0 270)
			(size 0 0)
			(layers "F.Cu" "F.Mask" "F.Paste")
			(net "GND")
		)
	)
	(footprint ""
		(layer "F.Cu")
		(at 33.865058 -170.50766)
		(property "Reference" "R1334"
			(at 0 0 0)
			(layer "F.SilkS")
			(hide yes)
			(effects
				(font
					(size 1.27 1.27)
				)
			)
		)
		(property "Value" ""
			(at 0 0 0)
			(layer "F.Fab")
			(effects
				(font
					(size 1.27 1.27)
				)
			)
		)
		(duplicate_pad_numbers_are_jumpers no)
		(fp_line
			(start -0.7874 -0.4064)
			(end 0.7874 -0.4064)
			(stroke
				(width 0.1524)
				(type default)
			)
			(layer "F.SilkS")
		)
		(fp_line
			(start -0.7874 0.4064)
			(end -0.7874 -0.4064)
			(stroke
				(width 0.1524)
				(type default)
			)
			(layer "F.SilkS")
		)
		(fp_line
			(start 0.7874 -0.4064)
			(end 0.7874 0.4064)
			(stroke
				(width 0.1524)
				(type default)
			)
			(layer "F.SilkS")
		)
		(fp_line
			(start 0.7874 0.4064)
			(end -0.7874 0.4064)
			(stroke
				(width 0.1524)
				(type default)
			)
			(layer "F.SilkS")
		)
		(fp_line
			(start -0.67945 -0.305054)
			(end -0.12065 -0.305054)
			(stroke
				(width 0.1)
				(type default)
			)
			(layer "F.Fab")
		)
		(fp_line
			(start -0.67945 0.3048)
			(end -0.67945 -0.305054)
			(stroke
				(width 0.1)
				(type default)
			)
			(layer "F.Fab")
		)
		(fp_line
			(start -0.12065 -0.305054)
			(end -0.12065 -0.2794)
			(stroke
				(width 0.1)
				(type default)
			)
			(layer "F.Fab")
		)
		(fp_line
			(start -0.12065 -0.2794)
			(end 0.12065 -0.2794)
			(stroke
				(width 0.1)
				(type default)
			)
			(layer "F.Fab")
		)
		(fp_line
			(start -0.12065 0.2794)
			(end -0.12065 0.3048)
			(stroke
				(width 0.1)
				(type default)
			)
			(layer "F.Fab")
		)
		(fp_line
			(start -0.12065 0.3048)
			(end -0.67945 0.3048)
			(stroke
				(width 0.1)
				(type default)
			)
			(layer "F.Fab")
		)
		(fp_line
			(start 0.120396 0.2794)
			(end -0.12065 0.2794)
			(stroke
				(width 0.1)
				(type default)
			)
			(layer "F.Fab")
		)
		(fp_line
			(start 0.120396 0.3048)
			(end 0.120396 0.2794)
			(stroke
				(width 0.1)
				(type default)
			)
			(layer "F.Fab")
		)
		(fp_line
			(start 0.12065 -0.3048)
			(end 0.67945 -0.3048)
			(stroke
				(width 0.1)
				(type default)
			)
			(layer "F.Fab")
		)
		(fp_line
			(start 0.12065 -0.2794)
			(end 0.12065 -0.3048)
			(stroke
				(width 0.1)
				(type default)
			)
			(layer "F.Fab")
		)
		(fp_line
			(start 0.67945 -0.3048)
			(end 0.67945 0.3048)
			(stroke
				(width 0.1)
				(type default)
			)
			(layer "F.Fab")
		)
		(fp_line
			(start 0.67945 0.3048)
			(end 0.120396 0.3048)
			(stroke
				(width 0.1)
				(type default)
			)
			(layer "F.Fab")
		)
		(pad "1" smd rect
			(at -0.40005 0 180)
			(size 0.4572 0.508)
			(layers "F.Cu" "F.Mask" "F.Paste")
			(net "I3C_SPD_DDRAF_CPU1_BYPASS_SCL")
		)
		(pad "2" smd rect
			(at 0.40005 0 180)
			(size 0.4572 0.508)
			(layers "F.Cu" "F.Mask" "F.Paste")
			(net "I3C_SPD_DDRAF_CPU1_SCL")
		)
	)
	(footprint ""
		(layer "F.Cu")
		(at 315.399928 -23.92934)
		(property "Reference" "U99"
			(at -2.032 -2.377948 0)
			(unlocked yes)
			(layer "F.SilkS")
			(effects
				(font
					(size 0.7874 0.5842)
					(thickness 0.1524)
				)
				(justify left)
			)
		)
		(property "Value" ""
			(at 0 0 0)
			(layer "F.Fab")
			(effects
				(font
					(size 1.27 1.27)
				)
			)
		)
		(duplicate_pad_numbers_are_jumpers no)
		(fp_line
			(start -2.0574 -1.651)
			(end -0.381 -1.651)
			(stroke
				(width 0.1524)
				(type default)
			)
			(layer "F.SilkS")
		)
		(fp_line
			(start -2.0574 1.651)
			(end -2.0574 -1.651)
			(stroke
				(width 0.1524)
				(type default)
			)
			(layer "F.SilkS")
		)
		(fp_line
			(start -0.381 -1.651)
			(end 0 -1.016)
			(stroke
				(width 0.1524)
				(type default)
			)
			(layer "F.SilkS")
		)
		(fp_line
			(start 0 -1.016)
			(end 0.381 -1.651)
			(stroke
				(width 0.1524)
				(type default)
			)
			(layer "F.SilkS")
		)
		(fp_line
			(start 0.381 -1.651)
			(end 2.0574 -1.651)
			(stroke
				(width 0.1524)
				(type default)
			)
			(layer "F.SilkS")
		)
		(fp_line
			(start 2.0574 -1.651)
			(end 2.0574 1.651)
			(stroke
				(width 0.1524)
				(type default)
			)
			(layer "F.SilkS")
		)
		(fp_line
			(start 2.0574 1.651)
			(end -2.0574 1.651)
			(stroke
				(width 0.1524)
				(type default)
			)
			(layer "F.SilkS")
		)
		(fp_poly
			(pts
				(xy -2.159 -1.016) (xy -2.71272 -0.719328) (xy -2.71272 -1.344168)
			)
			(stroke
				(width 0)
				(type default)
			)
			(fill yes)
			(layer "F.SilkS")
		)
		(fp_line
			(start -1.599946 -1.199896)
			(end -0.899922 -1.199896)
			(stroke
				(width 0.1)
				(type default)
			)
			(layer "F.Fab")
		)
		(fp_line
			(start -1.599946 1.199896)
			(end -1.599946 -1.199896)
			(stroke
				(width 0.1)
				(type default)
			)
			(layer "F.Fab")
		)
		(fp_line
			(start -0.899922 -1.549908)
			(end 0.899922 -1.549908)
			(stroke
				(width 0.1)
				(type default)
			)
			(layer "F.Fab")
		)
		(fp_line
			(start -0.899922 -1.199896)
			(end -0.899922 -1.549908)
			(stroke
				(width 0.1)
				(type default)
			)
			(layer "F.Fab")
		)
		(fp_line
			(start -0.899922 1.199896)
			(end -1.599946 1.199896)
			(stroke
				(width 0.1)
				(type default)
			)
			(layer "F.Fab")
		)
		(fp_line
			(start -0.899922 1.549908)
			(end -0.899922 1.199896)
			(stroke
				(width 0.1)
				(type default)
			)
			(layer "F.Fab")
		)
		(fp_line
			(start 0.899922 -1.549908)
			(end 0.899922 -1.199896)
			(stroke
				(width 0.1)
				(type default)
			)
			(layer "F.Fab")
		)
		(fp_line
			(start 0.899922 -1.199896)
			(end 1.599946 -1.199896)
			(stroke
				(width 0.1)
				(type default)
			)
			(layer "F.Fab")
		)
		(fp_line
			(start 0.899922 1.199896)
			(end 0.899922 1.549908)
			(stroke
				(width 0.1)
				(type default)
			)
			(layer "F.Fab")
		)
		(fp_line
			(start 0.899922 1.549908)
			(end -0.899922 1.549908)
			(stroke
				(width 0.1)
				(type default)
			)
			(layer "F.Fab")
		)
		(fp_line
			(start 1.599946 -1.199896)
			(end 1.599946 1.199896)
			(stroke
				(width 0.1)
				(type default)
			)
			(layer "F.Fab")
		)
		(fp_line
			(start 1.599946 1.199896)
			(end 0.899922 1.199896)
			(stroke
				(width 0.1)
				(type default)
			)
			(layer "F.Fab")
		)
		(fp_poly
			(pts
				(xy -2.71272 -0.719328) (xy -2.71272 -1.344168) (xy -2.159 -1.016)
			)
			(stroke
				(width 0)
				(type default)
			)
			(fill yes)
			(layer "F.Fab")
		)
		(pad "1" smd rect
			(at -1.225042 -0.94996 270)
			(size 0.5588 1.3462)
			(layers "F.Cu" "F.Mask" "F.Paste")
			(net "Net_10727")
		)
		(pad "2" smd rect
			(at -1.225042 0 270)
			(size 0.5588 1.3462)
			(layers "F.Cu" "F.Mask" "F.Paste")
			(net "FW_RECOVERY_R")
		)
		(pad "3" smd rect
			(at -1.225042 0.94996 270)
			(size 0.5588 1.3462)
			(layers "F.Cu" "F.Mask" "F.Paste")
			(net "GND")
		)
		(pad "4" smd rect
			(at 1.225042 0.94996 270)
			(size 0.5588 1.3462)
			(layers "F.Cu" "F.Mask" "F.Paste")
			(net "SCM_JTAG_MUX_S1")
		)
		(pad "5" smd rect
			(at 1.225042 -0.94996 270)
			(size 0.5588 1.3462)
			(layers "F.Cu" "F.Mask" "F.Paste")
			(net "P3V3_AUX")
		)
	)
	(footprint ""
		(layer "F.Cu")
		(at 414.325562 -361.814364 180)
		(property "Reference" "PR129"
			(at 0 0 180)
			(layer "F.SilkS")
			(hide yes)
			(effects
				(font
					(size 1.27 1.27)
				)
			)
		)
		(property "Value" ""
			(at 0 0 180)
			(layer "F.Fab")
			(effects
				(font
					(size 1.27 1.27)
				)
			)
		)
		(duplicate_pad_numbers_are_jumpers no)
		(fp_line
			(start 0.7874 0.4064)
			(end -0.7874 0.4064)
			(stroke
				(width 0.1524)
				(type default)
			)
			(layer "F.SilkS")
		)
		(fp_line
			(start 0.7874 -0.4064)
			(end 0.7874 0.4064)
			(stroke
				(width 0.1524)
				(type default)
			)
			(layer "F.SilkS")
		)
		(fp_line
			(start -0.7874 0.4064)
			(end -0.7874 -0.4064)
			(stroke
				(width 0.1524)
				(type default)
			)
			(layer "F.SilkS")
		)
		(fp_line
			(start -0.7874 -0.4064)
			(end 0.7874 -0.4064)
			(stroke
				(width 0.1524)
				(type default)
			)
			(layer "F.SilkS")
		)
		(fp_line
			(start 0.67945 0.3048)
			(end 0.120396 0.3048)
			(stroke
				(width 0.1)
				(type default)
			)
			(layer "F.Fab")
		)
		(fp_line
			(start 0.67945 -0.3048)
			(end 0.67945 0.3048)
			(stroke
				(width 0.1)
				(type default)
			)
			(layer "F.Fab")
		)
		(fp_line
			(start 0.12065 -0.2794)
			(end 0.12065 -0.3048)
			(stroke
				(width 0.1)
				(type default)
			)
			(layer "F.Fab")
		)
		(fp_line
			(start 0.12065 -0.3048)
			(end 0.67945 -0.3048)
			(stroke
				(width 0.1)
				(type default)
			)
			(layer "F.Fab")
		)
		(fp_line
			(start 0.120396 0.3048)
			(end 0.120396 0.2794)
			(stroke
				(width 0.1)
				(type default)
			)
			(layer "F.Fab")
		)
		(fp_line
			(start 0.120396 0.2794)
			(end -0.12065 0.2794)
			(stroke
				(width 0.1)
				(type default)
			)
			(layer "F.Fab")
		)
		(fp_line
			(start -0.12065 0.3048)
			(end -0.67945 0.3048)
			(stroke
				(width 0.1)
				(type default)
			)
			(layer "F.Fab")
		)
		(fp_line
			(start -0.12065 0.2794)
			(end -0.12065 0.3048)
			(stroke
				(width 0.1)
				(type default)
			)
			(layer "F.Fab")
		)
		(fp_line
			(start -0.12065 -0.2794)
			(end 0.12065 -0.2794)
			(stroke
				(width 0.1)
				(type default)
			)
			(layer "F.Fab")
		)
		(fp_line
			(start -0.12065 -0.305054)
			(end -0.12065 -0.2794)
			(stroke
				(width 0.1)
				(type default)
			)
			(layer "F.Fab")
		)
		(fp_line
			(start -0.67945 0.3048)
			(end -0.67945 -0.305054)
			(stroke
				(width 0.1)
				(type default)
			)
			(layer "F.Fab")
		)
		(fp_line
			(start -0.67945 -0.305054)
			(end -0.12065 -0.305054)
			(stroke
				(width 0.1)
				(type default)
			)
			(layer "F.Fab")
		)
		(pad "1" smd circle
			(at -0.40005 0 180)
			(size 0 0)
			(layers "F.Cu" "F.Mask" "F.Paste")
			(net "PVDD11_S3_P0_RESET_N_R")
		)
		(pad "2" smd circle
			(at 0.40005 0 180)
			(size 0 0)
			(layers "F.Cu" "F.Mask" "F.Paste")
			(net "PVDD11_S3_P0_RESET_N")
		)
	)
	(footprint ""
		(layer "F.Cu")
		(at 83.439254 -337.643724 90)
		(property "Reference" "PC369"
			(at 0 0 90)
			(layer "F.SilkS")
			(hide yes)
			(effects
				(font
					(size 1.27 1.27)
				)
			)
		)
		(property "Value" ""
			(at 0 0 90)
			(layer "F.Fab")
			(effects
				(font
					(size 1.27 1.27)
				)
			)
		)
		(duplicate_pad_numbers_are_jumpers no)
		(fp_line
			(start 0.7874 -0.4064)
			(end 0.7874 0.4064)
			(stroke
				(width 0.1524)
				(type default)
			)
			(layer "F.SilkS")
		)
		(fp_line
			(start -0.7874 -0.4064)
			(end 0.7874 -0.4064)
			(stroke
				(width 0.1524)
				(type default)
			)
			(layer "F.SilkS")
		)
		(fp_line
			(start 0.7874 0.4064)
			(end 0.481076 0.4064)
			(stroke
				(width 0.1524)
				(type default)
			)
			(layer "F.SilkS")
		)
		(fp_line
			(start -0.306324 0.4064)
			(end -0.7874 0.4064)
			(stroke
				(width 0.1524)
				(type default)
			)
			(layer "F.SilkS")
		)
		(fp_line
			(start -0.7874 0.4064)
			(end -0.7874 -0.4064)
			(stroke
				(width 0.1524)
				(type default)
			)
			(layer "F.SilkS")
		)
		(fp_line
			(start -0.12065 -0.305054)
			(end -0.12065 -0.2794)
			(stroke
				(width 0.1)
				(type default)
			)
			(layer "F.Fab")
		)
		(fp_line
			(start -0.67945 -0.305054)
			(end -0.12065 -0.305054)
			(stroke
				(width 0.1)
				(type default)
			)
			(layer "F.Fab")
		)
		(fp_line
			(start 0.67945 -0.3048)
			(end 0.67945 0.3048)
			(stroke
				(width 0.1)
				(type default)
			)
			(layer "F.Fab")
		)
		(fp_line
			(start 0.12065 -0.3048)
			(end 0.67945 -0.3048)
			(stroke
				(width 0.1)
				(type default)
			)
			(layer "F.Fab")
		)
		(fp_line
			(start 0.12065 -0.2794)
			(end 0.12065 -0.3048)
			(stroke
				(width 0.1)
				(type default)
			)
			(layer "F.Fab")
		)
		(fp_line
			(start -0.12065 -0.2794)
			(end 0.12065 -0.2794)
			(stroke
				(width 0.1)
				(type default)
			)
			(layer "F.Fab")
		)
		(fp_line
			(start 0.120396 0.2794)
			(end -0.12065 0.2794)
			(stroke
				(width 0.1)
				(type default)
			)
			(layer "F.Fab")
		)
		(fp_line
			(start -0.12065 0.2794)
			(end -0.12065 0.3048)
			(stroke
				(width 0.1)
				(type default)
			)
			(layer "F.Fab")
		)
		(fp_line
			(start 0.67945 0.3048)
			(end 0.120396 0.3048)
			(stroke
				(width 0.1)
				(type default)
			)
			(layer "F.Fab")
		)
		(fp_line
			(start 0.120396 0.3048)
			(end 0.120396 0.2794)
			(stroke
				(width 0.1)
				(type default)
			)
			(layer "F.Fab")
		)
		(fp_line
			(start -0.12065 0.3048)
			(end -0.67945 0.3048)
			(stroke
				(width 0.1)
				(type default)
			)
			(layer "F.Fab")
		)
		(fp_line
			(start -0.67945 0.3048)
			(end -0.67945 -0.305054)
			(stroke
				(width 0.1)
				(type default)
			)
			(layer "F.Fab")
		)
		(pad "1" smd circle
			(at -0.40005 0 90)
			(size 0 0)
			(layers "F.Cu" "F.Mask" "F.Paste")
			(net "PVDDCR_CPU1_P1_VCC1")
		)
		(pad "2" smd circle
			(at 0.40005 0 90)
			(size 0 0)
			(layers "F.Cu" "F.Mask" "F.Paste")
			(net "GND")
		)
	)
	(footprint ""
		(layer "F.Cu")
		(at 97.279968 -425.817284 -90)
		(property "Reference" "R4058"
			(at 0 0 270)
			(layer "F.SilkS")
			(hide yes)
			(effects
				(font
					(size 1.27 1.27)
				)
			)
		)
		(property "Value" ""
			(at 0 0 270)
			(layer "F.Fab")
			(effects
				(font
					(size 1.27 1.27)
				)
			)
		)
		(duplicate_pad_numbers_are_jumpers no)
		(fp_line
			(start -0.7874 0.4064)
			(end -0.7874 -0.4064)
			(stroke
				(width 0.1524)
				(type default)
			)
			(layer "F.SilkS")
		)
		(fp_line
			(start 0.7874 0.4064)
			(end -0.7874 0.4064)
			(stroke
				(width 0.1524)
				(type default)
			)
			(layer "F.SilkS")
		)
		(fp_line
			(start -0.7874 -0.4064)
			(end 0.7874 -0.4064)
			(stroke
				(width 0.1524)
				(type default)
			)
			(layer "F.SilkS")
		)
		(fp_line
			(start 0.7874 -0.4064)
			(end 0.7874 0.4064)
			(stroke
				(width 0.1524)
				(type default)
			)
			(layer "F.SilkS")
		)
		(fp_line
			(start -0.67945 0.3048)
			(end -0.67945 -0.305054)
			(stroke
				(width 0.1)
				(type default)
			)
			(layer "F.Fab")
		)
		(fp_line
			(start -0.12065 0.3048)
			(end -0.67945 0.3048)
			(stroke
				(width 0.1)
				(type default)
			)
			(layer "F.Fab")
		)
		(fp_line
			(start 0.120396 0.3048)
			(end 0.120396 0.2794)
			(stroke
				(width 0.1)
				(type default)
			)
			(layer "F.Fab")
		)
		(fp_line
			(start 0.67945 0.3048)
			(end 0.120396 0.3048)
			(stroke
				(width 0.1)
				(type default)
			)
			(layer "F.Fab")
		)
		(fp_line
			(start -0.12065 0.2794)
			(end -0.12065 0.3048)
			(stroke
				(width 0.1)
				(type default)
			)
			(layer "F.Fab")
		)
		(fp_line
			(start 0.120396 0.2794)
			(end -0.12065 0.2794)
			(stroke
				(width 0.1)
				(type default)
			)
			(layer "F.Fab")
		)
		(fp_line
			(start -0.12065 -0.2794)
			(end 0.12065 -0.2794)
			(stroke
				(width 0.1)
				(type default)
			)
			(layer "F.Fab")
		)
		(fp_line
			(start 0.12065 -0.2794)
			(end 0.12065 -0.3048)
			(stroke
				(width 0.1)
				(type default)
			)
			(layer "F.Fab")
		)
		(fp_line
			(start 0.12065 -0.3048)
			(end 0.67945 -0.3048)
			(stroke
				(width 0.1)
				(type default)
			)
			(layer "F.Fab")
		)
		(fp_line
			(start 0.67945 -0.3048)
			(end 0.67945 0.3048)
			(stroke
				(width 0.1)
				(type default)
			)
			(layer "F.Fab")
		)
		(fp_line
			(start -0.67945 -0.305054)
			(end -0.12065 -0.305054)
			(stroke
				(width 0.1)
				(type default)
			)
			(layer "F.Fab")
		)
		(fp_line
			(start -0.12065 -0.305054)
			(end -0.12065 -0.2794)
			(stroke
				(width 0.1)
				(type default)
			)
			(layer "F.Fab")
		)
		(pad "1" smd circle
			(at -0.40005 0 270)
			(size 0 0)
			(layers "F.Cu" "F.Mask" "F.Paste")
			(net "P3V3_AUX")
		)
		(pad "2" smd circle
			(at 0.40005 0 270)
			(size 0 0)
			(layers "F.Cu" "F.Mask" "F.Paste")
			(net "PRSNT_SWB_N")
		)
	)
	(footprint ""
		(layer "F.Cu")
		(at 350.44761 -63.904876 180)
		(property "Reference" "R485"
			(at 0 0 180)
			(layer "F.SilkS")
			(hide yes)
			(effects
				(font
					(size 1.27 1.27)
				)
			)
		)
		(property "Value" ""
			(at 0 0 180)
			(layer "F.Fab")
			(effects
				(font
					(size 1.27 1.27)
				)
			)
		)
		(duplicate_pad_numbers_are_jumpers no)
		(fp_line
			(start 0.7874 0.4064)
			(end -0.7874 0.4064)
			(stroke
				(width 0.1524)
				(type default)
			)
			(layer "F.SilkS")
		)
		(fp_line
			(start 0.7874 -0.4064)
			(end 0.7874 0.4064)
			(stroke
				(width 0.1524)
				(type default)
			)
			(layer "F.SilkS")
		)
		(fp_line
			(start -0.7874 0.4064)
			(end -0.7874 -0.4064)
			(stroke
				(width 0.1524)
				(type default)
			)
			(layer "F.SilkS")
		)
		(fp_line
			(start -0.7874 -0.4064)
			(end 0.7874 -0.4064)
			(stroke
				(width 0.1524)
				(type default)
			)
			(layer "F.SilkS")
		)
		(fp_line
			(start 0.67945 0.3048)
			(end 0.120396 0.3048)
			(stroke
				(width 0.1)
				(type default)
			)
			(layer "F.Fab")
		)
		(fp_line
			(start 0.67945 -0.3048)
			(end 0.67945 0.3048)
			(stroke
				(width 0.1)
				(type default)
			)
			(layer "F.Fab")
		)
		(fp_line
			(start 0.12065 -0.2794)
			(end 0.12065 -0.3048)
			(stroke
				(width 0.1)
				(type default)
			)
			(layer "F.Fab")
		)
		(fp_line
			(start 0.12065 -0.3048)
			(end 0.67945 -0.3048)
			(stroke
				(width 0.1)
				(type default)
			)
			(layer "F.Fab")
		)
		(fp_line
			(start 0.120396 0.3048)
			(end 0.120396 0.2794)
			(stroke
				(width 0.1)
				(type default)
			)
			(layer "F.Fab")
		)
		(fp_line
			(start 0.120396 0.2794)
			(end -0.12065 0.2794)
			(stroke
				(width 0.1)
				(type default)
			)
			(layer "F.Fab")
		)
		(fp_line
			(start -0.12065 0.3048)
			(end -0.67945 0.3048)
			(stroke
				(width 0.1)
				(type default)
			)
			(layer "F.Fab")
		)
		(fp_line
			(start -0.12065 0.2794)
			(end -0.12065 0.3048)
			(stroke
				(width 0.1)
				(type default)
			)
			(layer "F.Fab")
		)
		(fp_line
			(start -0.12065 -0.2794)
			(end 0.12065 -0.2794)
			(stroke
				(width 0.1)
				(type default)
			)
			(layer "F.Fab")
		)
		(fp_line
			(start -0.12065 -0.305054)
			(end -0.12065 -0.2794)
			(stroke
				(width 0.1)
				(type default)
			)
			(layer "F.Fab")
		)
		(fp_line
			(start -0.67945 0.3048)
			(end -0.67945 -0.305054)
			(stroke
				(width 0.1)
				(type default)
			)
			(layer "F.Fab")
		)
		(fp_line
			(start -0.67945 -0.305054)
			(end -0.12065 -0.305054)
			(stroke
				(width 0.1)
				(type default)
			)
			(layer "F.Fab")
		)
		(pad "1" smd circle
			(at -0.40005 0 180)
			(size 0 0)
			(layers "F.Cu" "F.Mask" "F.Paste")
			(net "CPU0_XTRIG_L7")
		)
		(pad "2" smd circle
			(at 0.40005 0 180)
			(size 0 0)
			(layers "F.Cu" "F.Mask" "F.Paste")
			(net "CPU0_XTRIG_R1_L7")
		)
	)
	(footprint ""
		(layer "F.Cu")
		(at 105.84561 -67.60591)
		(property "Reference" "R6222"
			(at 0 0 0)
			(layer "F.SilkS")
			(hide yes)
			(effects
				(font
					(size 1.27 1.27)
				)
			)
		)
		(property "Value" ""
			(at 0 0 0)
			(layer "F.Fab")
			(effects
				(font
					(size 1.27 1.27)
				)
			)
		)
		(duplicate_pad_numbers_are_jumpers no)
		(fp_line
			(start -0.7874 -0.4064)
			(end 0.7874 -0.4064)
			(stroke
				(width 0.1524)
				(type default)
			)
			(layer "F.SilkS")
		)
		(fp_line
			(start -0.7874 0.4064)
			(end -0.7874 -0.4064)
			(stroke
				(width 0.1524)
				(type default)
			)
			(layer "F.SilkS")
		)
		(fp_line
			(start 0.7874 -0.4064)
			(end 0.7874 0.4064)
			(stroke
				(width 0.1524)
				(type default)
			)
			(layer "F.SilkS")
		)
		(fp_line
			(start 0.7874 0.4064)
			(end -0.7874 0.4064)
			(stroke
				(width 0.1524)
				(type default)
			)
			(layer "F.SilkS")
		)
		(fp_line
			(start -0.67945 -0.305054)
			(end -0.12065 -0.305054)
			(stroke
				(width 0.1)
				(type default)
			)
			(layer "F.Fab")
		)
		(fp_line
			(start -0.67945 0.3048)
			(end -0.67945 -0.305054)
			(stroke
				(width 0.1)
				(type default)
			)
			(layer "F.Fab")
		)
		(fp_line
			(start -0.12065 -0.305054)
			(end -0.12065 -0.2794)
			(stroke
				(width 0.1)
				(type default)
			)
			(layer "F.Fab")
		)
		(fp_line
			(start -0.12065 -0.2794)
			(end 0.12065 -0.2794)
			(stroke
				(width 0.1)
				(type default)
			)
			(layer "F.Fab")
		)
		(fp_line
			(start -0.12065 0.2794)
			(end -0.12065 0.3048)
			(stroke
				(width 0.1)
				(type default)
			)
			(layer "F.Fab")
		)
		(fp_line
			(start -0.12065 0.3048)
			(end -0.67945 0.3048)
			(stroke
				(width 0.1)
				(type default)
			)
			(layer "F.Fab")
		)
		(fp_line
			(start 0.120396 0.2794)
			(end -0.12065 0.2794)
			(stroke
				(width 0.1)
				(type default)
			)
			(layer "F.Fab")
		)
		(fp_line
			(start 0.120396 0.3048)
			(end 0.120396 0.2794)
			(stroke
				(width 0.1)
				(type default)
			)
			(layer "F.Fab")
		)
		(fp_line
			(start 0.12065 -0.3048)
			(end 0.67945 -0.3048)
			(stroke
				(width 0.1)
				(type default)
			)
			(layer "F.Fab")
		)
		(fp_line
			(start 0.12065 -0.2794)
			(end 0.12065 -0.3048)
			(stroke
				(width 0.1)
				(type default)
			)
			(layer "F.Fab")
		)
		(fp_line
			(start 0.67945 -0.3048)
			(end 0.67945 0.3048)
			(stroke
				(width 0.1)
				(type default)
			)
			(layer "F.Fab")
		)
		(fp_line
			(start 0.67945 0.3048)
			(end 0.120396 0.3048)
			(stroke
				(width 0.1)
				(type default)
			)
			(layer "F.Fab")
		)
		(pad "1" smd circle
			(at -0.40005 0)
			(size 0 0)
			(layers "F.Cu" "F.Mask" "F.Paste")
			(net "P3V3_AUX")
		)
		(pad "2" smd circle
			(at 0.40005 0)
			(size 0 0)
			(layers "F.Cu" "F.Mask" "F.Paste")
			(net "USB_CPU0_ADD_A0")
		)
	)
	(footprint ""
		(layer "F.Cu")
		(at 177.984912 -412.257748 180)
		(property "Reference" "R347"
			(at 0 0 180)
			(layer "F.SilkS")
			(hide yes)
			(effects
				(font
					(size 1.27 1.27)
				)
			)
		)
		(property "Value" ""
			(at 0 0 180)
			(layer "F.Fab")
			(effects
				(font
					(size 1.27 1.27)
				)
			)
		)
		(duplicate_pad_numbers_are_jumpers no)
		(fp_line
			(start 0.7874 0.4064)
			(end -0.7874 0.4064)
			(stroke
				(width 0.1524)
				(type default)
			)
			(layer "F.SilkS")
		)
		(fp_line
			(start 0.7874 -0.4064)
			(end 0.7874 0.4064)
			(stroke
				(width 0.1524)
				(type default)
			)
			(layer "F.SilkS")
		)
		(fp_line
			(start -0.7874 0.4064)
			(end -0.7874 -0.4064)
			(stroke
				(width 0.1524)
				(type default)
			)
			(layer "F.SilkS")
		)
		(fp_line
			(start -0.7874 -0.4064)
			(end 0.7874 -0.4064)
			(stroke
				(width 0.1524)
				(type default)
			)
			(layer "F.SilkS")
		)
		(fp_line
			(start 0.67945 0.3048)
			(end 0.120396 0.3048)
			(stroke
				(width 0.1)
				(type default)
			)
			(layer "F.Fab")
		)
		(fp_line
			(start 0.67945 -0.3048)
			(end 0.67945 0.3048)
			(stroke
				(width 0.1)
				(type default)
			)
			(layer "F.Fab")
		)
		(fp_line
			(start 0.12065 -0.2794)
			(end 0.12065 -0.3048)
			(stroke
				(width 0.1)
				(type default)
			)
			(layer "F.Fab")
		)
		(fp_line
			(start 0.12065 -0.3048)
			(end 0.67945 -0.3048)
			(stroke
				(width 0.1)
				(type default)
			)
			(layer "F.Fab")
		)
		(fp_line
			(start 0.120396 0.3048)
			(end 0.120396 0.2794)
			(stroke
				(width 0.1)
				(type default)
			)
			(layer "F.Fab")
		)
		(fp_line
			(start 0.120396 0.2794)
			(end -0.12065 0.2794)
			(stroke
				(width 0.1)
				(type default)
			)
			(layer "F.Fab")
		)
		(fp_line
			(start -0.12065 0.3048)
			(end -0.67945 0.3048)
			(stroke
				(width 0.1)
				(type default)
			)
			(layer "F.Fab")
		)
		(fp_line
			(start -0.12065 0.2794)
			(end -0.12065 0.3048)
			(stroke
				(width 0.1)
				(type default)
			)
			(layer "F.Fab")
		)
		(fp_line
			(start -0.12065 -0.2794)
			(end 0.12065 -0.2794)
			(stroke
				(width 0.1)
				(type default)
			)
			(layer "F.Fab")
		)
		(fp_line
			(start -0.12065 -0.305054)
			(end -0.12065 -0.2794)
			(stroke
				(width 0.1)
				(type default)
			)
			(layer "F.Fab")
		)
		(fp_line
			(start -0.67945 0.3048)
			(end -0.67945 -0.305054)
			(stroke
				(width 0.1)
				(type default)
			)
			(layer "F.Fab")
		)
		(fp_line
			(start -0.67945 -0.305054)
			(end -0.12065 -0.305054)
			(stroke
				(width 0.1)
				(type default)
			)
			(layer "F.Fab")
		)
		(pad "1" smd circle
			(at -0.40005 0 180)
			(size 0 0)
			(layers "F.Cu" "F.Mask" "F.Paste")
			(net "SMB_SML1_PMBUS_HSC_SCL")
		)
		(pad "2" smd circle
			(at 0.40005 0 180)
			(size 0 0)
			(layers "F.Cu" "F.Mask" "F.Paste")
			(net "SMB_SML1_PMBUS_HSC_R1_SCL")
		)
	)
	(footprint ""
		(layer "F.Cu")
		(at 451.497192 -20.979638)
		(property "Reference" "PU203"
			(at 2.76479 -1.83896 0)
			(unlocked yes)
			(layer "F.SilkS")
			(effects
				(font
					(size 0.7874 0.5842)
					(thickness 0.1524)
				)
				(justify left)
			)
		)
		(property "Value" ""
			(at 0 0 0)
			(layer "F.Fab")
			(effects
				(font
					(size 1.27 1.27)
				)
			)
		)
		(duplicate_pad_numbers_are_jumpers no)
		(fp_line
			(start -1.774952 -1.039876)
			(end -1.774952 1.039876)
			(stroke
				(width 0.1524)
				(type default)
			)
			(layer "F.SilkS")
		)
		(fp_line
			(start -1.774952 1.039876)
			(end 1.774952 1.039876)
			(stroke
				(width 0.1524)
				(type default)
			)
			(layer "F.SilkS")
		)
		(fp_line
			(start 1.774952 -1.039876)
			(end -1.774952 -1.039876)
			(stroke
				(width 0.1524)
				(type default)
			)
			(layer "F.SilkS")
		)
		(fp_line
			(start 1.774952 1.039876)
			(end 1.774952 -1.039876)
			(stroke
				(width 0.1524)
				(type default)
			)
			(layer "F.SilkS")
		)
		(fp_poly
			(pts
				(xy -0.999998 -1.801876) (xy -0.999998 -1.039876) (xy -1.769872 -1.039876) (xy -1.769872 -0.249936)
				(xy -2.531872 -0.249936) (xy -2.531872 -1.801876)
			)
			(stroke
				(width 0)
				(type default)
			)
			(fill yes)
			(layer "F.SilkS")
		)
		(fp_line
			(start -1.769872 -1.039876)
			(end -1.769872 1.039876)
			(stroke
				(width 0.1)
				(type default)
			)
			(layer "F.Fab")
		)
		(fp_line
			(start -1.769872 1.039876)
			(end 1.769872 1.039876)
			(stroke
				(width 0.1)
				(type default)
			)
			(layer "F.Fab")
		)
		(fp_line
			(start 1.769872 -1.039876)
			(end -1.769872 -1.039876)
			(stroke
				(width 0.1)
				(type default)
			)
			(layer "F.Fab")
		)
		(fp_line
			(start 1.769872 1.039876)
			(end 1.769872 -1.039876)
			(stroke
				(width 0.1)
				(type default)
			)
			(layer "F.Fab")
		)
		(fp_poly
			(pts
				(xy -1.769872 -1.039876) (xy -0.999998 -1.039876) (xy -0.999998 -1.801876) (xy -2.531872 -1.801876)
				(xy -2.531872 -0.249936) (xy -1.769872 -0.249936)
			)
			(stroke
				(width 0)
				(type default)
			)
			(fill yes)
			(layer "F.Fab")
		)
		(pad "A1" smd circle
			(at -1.500124 -0.750062)
			(size 0.2286 0.2286)
			(layers "F.Cu" "F.Mask" "F.Paste")
			(net "P12V_OCP_SENSE_1")
		)
		(pad "A2" smd circle
			(at -0.999998 -0.750062)
			(size 0.2286 0.2286)
			(layers "F.Cu" "F.Mask" "F.Paste")
			(net "P12V_OCP_VCC_1")
		)
		(pad "A3" smd circle
			(at -0.499872 -0.750062)
			(size 0.2286 0.2286)
			(layers "F.Cu" "F.Mask" "F.Paste")
			(net "P12V_AUX")
		)
		(pad "A4" smd circle
			(at 0 -0.750062)
			(size 0.2286 0.2286)
			(layers "F.Cu" "F.Mask" "F.Paste")
			(net "P12V_OCP_SFF")
		)
		(pad "A5" smd circle
			(at 0.499872 -0.750062)
			(size 0.2286 0.2286)
			(layers "F.Cu" "F.Mask" "F.Paste")
			(net "P12V_AUX")
		)
		(pad "A6" smd circle
			(at 0.999998 -0.750062)
			(size 0.2286 0.2286)
			(layers "F.Cu" "F.Mask" "F.Paste")
			(net "P12V_OCP_GATE_1")
		)
		(pad "A7" smd circle
			(at 1.500124 -0.750062)
			(size 0.2286 0.2286)
			(layers "F.Cu" "F.Mask" "F.Paste")
			(net "GND")
		)
		(pad "B1" smd circle
			(at -1.500124 -0.249936)
			(size 0.2286 0.2286)
			(layers "F.Cu" "F.Mask" "F.Paste")
			(net "P12V_OCP_CB_1")
		)
		(pad "B2" smd circle
			(at -0.999998 -0.249936)
			(size 0.2286 0.2286)
			(layers "F.Cu" "F.Mask" "F.Paste")
			(net "GND")
		)
		(pad "B3" smd circle
			(at -0.499872 -0.249936)
			(size 0.2286 0.2286)
			(layers "F.Cu" "F.Mask" "F.Paste")
			(net "P12V_AUX")
		)
		(pad "B4" smd circle
			(at 0 -0.249936)
			(size 0.2286 0.2286)
			(layers "F.Cu" "F.Mask" "F.Paste")
			(net "P12V_OCP_SFF")
		)
		(pad "B5" smd circle
			(at 0.499872 -0.249936)
			(size 0.2286 0.2286)
			(layers "F.Cu" "F.Mask" "F.Paste")
			(net "P12V_AUX")
		)
		(pad "B6" smd circle
			(at 0.999998 -0.249936)
			(size 0.2286 0.2286)
			(layers "F.Cu" "F.Mask" "F.Paste")
			(net "P12V_OCP_SFF")
		)
		(pad "B7" smd circle
			(at 1.500124 -0.249936)
			(size 0.2286 0.2286)
			(layers "F.Cu" "F.Mask" "F.Paste")
			(net "GND")
		)
		(pad "C1" smd circle
			(at -1.500124 0.249936)
			(size 0.2286 0.2286)
			(layers "F.Cu" "F.Mask" "F.Paste")
			(net "GND")
		)
		(pad "C2" smd circle
			(at -0.999998 0.249936)
			(size 0.2286 0.2286)
			(layers "F.Cu" "F.Mask" "F.Paste")
			(net "GND")
		)
		(pad "C3" smd circle
			(at -0.499872 0.249936)
			(size 0.2286 0.2286)
			(layers "F.Cu" "F.Mask" "F.Paste")
			(net "P12V_AUX")
		)
		(pad "C4" smd circle
			(at 0 0.249936)
			(size 0.2286 0.2286)
			(layers "F.Cu" "F.Mask" "F.Paste")
			(net "P12V_OCP_SFF")
		)
		(pad "C5" smd circle
			(at 0.499872 0.249936)
			(size 0.2286 0.2286)
			(layers "F.Cu" "F.Mask" "F.Paste")
			(net "P12V_AUX")
		)
		(pad "C6" smd circle
			(at 0.999998 0.249936)
			(size 0.2286 0.2286)
			(layers "F.Cu" "F.Mask" "F.Paste")
			(net "P12V_OCP_SFF")
		)
		(pad "C7" smd circle
			(at 1.500124 0.249936)
			(size 0.2286 0.2286)
			(layers "F.Cu" "F.Mask" "F.Paste")
			(net "P12V_OCP_FAULT_1")
		)
		(pad "D1" smd circle
			(at -1.500124 0.750062)
			(size 0.2286 0.2286)
			(layers "F.Cu" "F.Mask" "F.Paste")
			(net "P12V_OCP_REG_1")
		)
		(pad "D2" smd circle
			(at -0.999998 0.750062)
			(size 0.2286 0.2286)
			(layers "F.Cu" "F.Mask" "F.Paste")
			(net "P12V_OCP_UV_1")
		)
		(pad "D3" smd circle
			(at -0.499872 0.750062)
			(size 0.2286 0.2286)
			(layers "F.Cu" "F.Mask" "F.Paste")
			(net "P12V_OCP_OV_1")
		)
		(pad "D4" smd circle
			(at 0 0.750062)
			(size 0.2286 0.2286)
			(layers "F.Cu" "F.Mask" "F.Paste")
			(net "P12V_OCP_SFF")
		)
		(pad "D5" smd circle
			(at 0.499872 0.750062)
			(size 0.2286 0.2286)
			(layers "F.Cu" "F.Mask" "F.Paste")
			(net "P12V_AUX")
		)
		(pad "D6" smd circle
			(at 0.999998 0.750062)
			(size 0.2286 0.2286)
			(layers "F.Cu" "F.Mask" "F.Paste")
			(net "P12V_OCP_SFF")
		)
		(pad "D7" smd circle
			(at 1.500124 0.750062)
			(size 0.2286 0.2286)
			(layers "F.Cu" "F.Mask" "F.Paste")
			(net "P12V_OCP_PWRGD_1")
		)
	)
	(footprint ""
		(layer "F.Cu")
		(at 64.83858 -54.22138 -90)
		(property "Reference" "C9051"
			(at 0 0 270)
			(layer "F.SilkS")
			(hide yes)
			(effects
				(font
					(size 1.27 1.27)
				)
			)
		)
		(property "Value" ""
			(at 0 0 270)
			(layer "F.Fab")
			(effects
				(font
					(size 1.27 1.27)
				)
			)
		)
		(duplicate_pad_numbers_are_jumpers no)
		(fp_line
			(start -0.7874 0.4064)
			(end -0.7874 -0.4064)
			(stroke
				(width 0.1524)
				(type default)
			)
			(layer "F.SilkS")
		)
		(fp_line
			(start 0.7874 0.4064)
			(end -0.7874 0.4064)
			(stroke
				(width 0.1524)
				(type default)
			)
			(layer "F.SilkS")
		)
		(fp_line
			(start -0.7874 -0.4064)
			(end 0.7874 -0.4064)
			(stroke
				(width 0.1524)
				(type default)
			)
			(layer "F.SilkS")
		)
		(fp_line
			(start 0.7874 -0.4064)
			(end 0.7874 0.4064)
			(stroke
				(width 0.1524)
				(type default)
			)
			(layer "F.SilkS")
		)
		(fp_line
			(start -0.67945 0.3048)
			(end -0.67945 -0.305054)
			(stroke
				(width 0.1)
				(type default)
			)
			(layer "F.Fab")
		)
		(fp_line
			(start -0.12065 0.3048)
			(end -0.67945 0.3048)
			(stroke
				(width 0.1)
				(type default)
			)
			(layer "F.Fab")
		)
		(fp_line
			(start 0.120396 0.3048)
			(end 0.120396 0.2794)
			(stroke
				(width 0.1)
				(type default)
			)
			(layer "F.Fab")
		)
		(fp_line
			(start 0.67945 0.3048)
			(end 0.120396 0.3048)
			(stroke
				(width 0.1)
				(type default)
			)
			(layer "F.Fab")
		)
		(fp_line
			(start -0.12065 0.2794)
			(end -0.12065 0.3048)
			(stroke
				(width 0.1)
				(type default)
			)
			(layer "F.Fab")
		)
		(fp_line
			(start 0.120396 0.2794)
			(end -0.12065 0.2794)
			(stroke
				(width 0.1)
				(type default)
			)
			(layer "F.Fab")
		)
		(fp_line
			(start -0.12065 -0.2794)
			(end 0.12065 -0.2794)
			(stroke
				(width 0.1)
				(type default)
			)
			(layer "F.Fab")
		)
		(fp_line
			(start 0.12065 -0.2794)
			(end 0.12065 -0.3048)
			(stroke
				(width 0.1)
				(type default)
			)
			(layer "F.Fab")
		)
		(fp_line
			(start 0.12065 -0.3048)
			(end 0.67945 -0.3048)
			(stroke
				(width 0.1)
				(type default)
			)
			(layer "F.Fab")
		)
		(fp_line
			(start 0.67945 -0.3048)
			(end 0.67945 0.3048)
			(stroke
				(width 0.1)
				(type default)
			)
			(layer "F.Fab")
		)
		(fp_line
			(start -0.67945 -0.305054)
			(end -0.12065 -0.305054)
			(stroke
				(width 0.1)
				(type default)
			)
			(layer "F.Fab")
		)
		(fp_line
			(start -0.12065 -0.305054)
			(end -0.12065 -0.2794)
			(stroke
				(width 0.1)
				(type default)
			)
			(layer "F.Fab")
		)
		(pad "1" smd circle
			(at -0.40005 0 270)
			(size 0 0)
			(layers "F.Cu" "F.Mask" "F.Paste")
			(net "P3V3_AUX")
		)
		(pad "2" smd circle
			(at 0.40005 0 270)
			(size 0 0)
			(layers "F.Cu" "F.Mask" "F.Paste")
			(net "GND")
		)
	)
	(footprint ""
		(layer "F.Cu")
		(at 299.767498 -14.48181 180)
		(property "Reference" "R4196"
			(at 0 0 180)
			(layer "F.SilkS")
			(hide yes)
			(effects
				(font
					(size 1.27 1.27)
				)
			)
		)
		(property "Value" ""
			(at 0 0 180)
			(layer "F.Fab")
			(effects
				(font
					(size 1.27 1.27)
				)
			)
		)
		(duplicate_pad_numbers_are_jumpers no)
		(fp_line
			(start 0.7874 0.4064)
			(end -0.7874 0.4064)
			(stroke
				(width 0.1524)
				(type default)
			)
			(layer "F.SilkS")
		)
		(fp_line
			(start 0.7874 -0.4064)
			(end 0.7874 0.4064)
			(stroke
				(width 0.1524)
				(type default)
			)
			(layer "F.SilkS")
		)
		(fp_line
			(start -0.7874 0.4064)
			(end -0.7874 -0.4064)
			(stroke
				(width 0.1524)
				(type default)
			)
			(layer "F.SilkS")
		)
		(fp_line
			(start -0.7874 -0.4064)
			(end 0.7874 -0.4064)
			(stroke
				(width 0.1524)
				(type default)
			)
			(layer "F.SilkS")
		)
		(fp_line
			(start 0.67945 0.3048)
			(end 0.120396 0.3048)
			(stroke
				(width 0.1)
				(type default)
			)
			(layer "F.Fab")
		)
		(fp_line
			(start 0.67945 -0.3048)
			(end 0.67945 0.3048)
			(stroke
				(width 0.1)
				(type default)
			)
			(layer "F.Fab")
		)
		(fp_line
			(start 0.12065 -0.2794)
			(end 0.12065 -0.3048)
			(stroke
				(width 0.1)
				(type default)
			)
			(layer "F.Fab")
		)
		(fp_line
			(start 0.12065 -0.3048)
			(end 0.67945 -0.3048)
			(stroke
				(width 0.1)
				(type default)
			)
			(layer "F.Fab")
		)
		(fp_line
			(start 0.120396 0.3048)
			(end 0.120396 0.2794)
			(stroke
				(width 0.1)
				(type default)
			)
			(layer "F.Fab")
		)
		(fp_line
			(start 0.120396 0.2794)
			(end -0.12065 0.2794)
			(stroke
				(width 0.1)
				(type default)
			)
			(layer "F.Fab")
		)
		(fp_line
			(start -0.12065 0.3048)
			(end -0.67945 0.3048)
			(stroke
				(width 0.1)
				(type default)
			)
			(layer "F.Fab")
		)
		(fp_line
			(start -0.12065 0.2794)
			(end -0.12065 0.3048)
			(stroke
				(width 0.1)
				(type default)
			)
			(layer "F.Fab")
		)
		(fp_line
			(start -0.12065 -0.2794)
			(end 0.12065 -0.2794)
			(stroke
				(width 0.1)
				(type default)
			)
			(layer "F.Fab")
		)
		(fp_line
			(start -0.12065 -0.305054)
			(end -0.12065 -0.2794)
			(stroke
				(width 0.1)
				(type default)
			)
			(layer "F.Fab")
		)
		(fp_line
			(start -0.67945 0.3048)
			(end -0.67945 -0.305054)
			(stroke
				(width 0.1)
				(type default)
			)
			(layer "F.Fab")
		)
		(fp_line
			(start -0.67945 -0.305054)
			(end -0.12065 -0.305054)
			(stroke
				(width 0.1)
				(type default)
			)
			(layer "F.Fab")
		)
		(pad "1" smd circle
			(at -0.40005 0 180)
			(size 0 0)
			(layers "F.Cu" "F.Mask" "F.Paste")
			(net "P3V3_AUX")
		)
		(pad "2" smd circle
			(at 0.40005 0 180)
			(size 0 0)
			(layers "F.Cu" "F.Mask" "F.Paste")
			(net "U271_1_ADD1")
		)
	)
	(footprint ""
		(layer "F.Cu")
		(at 123.704096 -373.03583 -90)
		(property "Reference" "C1531"
			(at 0 0 270)
			(layer "F.SilkS")
			(hide yes)
			(effects
				(font
					(size 1.27 1.27)
				)
			)
		)
		(property "Value" ""
			(at 0 0 270)
			(layer "F.Fab")
			(effects
				(font
					(size 1.27 1.27)
				)
			)
		)
		(duplicate_pad_numbers_are_jumpers no)
		(fp_line
			(start -0.299974 0.150114)
			(end -0.299974 -0.150114)
			(stroke
				(width 0.1)
				(type default)
			)
			(layer "F.Fab")
		)
		(fp_line
			(start 0.299974 0.150114)
			(end -0.299974 0.150114)
			(stroke
				(width 0.1)
				(type default)
			)
			(layer "F.Fab")
		)
		(fp_line
			(start -0.299974 -0.150114)
			(end 0.299974 -0.150114)
			(stroke
				(width 0.1)
				(type default)
			)
			(layer "F.Fab")
		)
		(fp_line
			(start 0.299974 -0.150114)
			(end 0.299974 0.150114)
			(stroke
				(width 0.1)
				(type default)
			)
			(layer "F.Fab")
		)
		(pad "1" smd rect
			(at -0.2667 0 270)
			(size 0.3048 0.381)
			(layers "F.Cu" "F.Mask" "F.Paste")
			(net "P5E_CPU1_P3_TX_C_DP<8>")
		)
		(pad "2" smd rect
			(at 0.2667 0 270)
			(size 0.3048 0.381)
			(layers "F.Cu" "F.Mask" "F.Paste")
			(net "P5E_CPU1_P3_TX_DP<8>")
		)
	)
	(footprint ""
		(layer "F.Cu")
		(at 256.47269 -40.498522 90)
		(property "Reference" "PC2214"
			(at 0 0 90)
			(layer "F.SilkS")
			(hide yes)
			(effects
				(font
					(size 1.27 1.27)
				)
			)
		)
		(property "Value" ""
			(at 0 0 90)
			(layer "F.Fab")
			(effects
				(font
					(size 1.27 1.27)
				)
			)
		)
		(duplicate_pad_numbers_are_jumpers no)
		(fp_line
			(start 0.7874 -0.4064)
			(end 0.7874 0.4064)
			(stroke
				(width 0.1524)
				(type default)
			)
			(layer "F.SilkS")
		)
		(fp_line
			(start -0.7874 -0.4064)
			(end 0.7874 -0.4064)
			(stroke
				(width 0.1524)
				(type default)
			)
			(layer "F.SilkS")
		)
		(fp_line
			(start 0.7874 0.4064)
			(end -0.7874 0.4064)
			(stroke
				(width 0.1524)
				(type default)
			)
			(layer "F.SilkS")
		)
		(fp_line
			(start -0.7874 0.4064)
			(end -0.7874 -0.4064)
			(stroke
				(width 0.1524)
				(type default)
			)
			(layer "F.SilkS")
		)
		(fp_line
			(start -0.12065 -0.305054)
			(end -0.12065 -0.2794)
			(stroke
				(width 0.1)
				(type default)
			)
			(layer "F.Fab")
		)
		(fp_line
			(start -0.67945 -0.305054)
			(end -0.12065 -0.305054)
			(stroke
				(width 0.1)
				(type default)
			)
			(layer "F.Fab")
		)
		(fp_line
			(start 0.67945 -0.3048)
			(end 0.67945 0.3048)
			(stroke
				(width 0.1)
				(type default)
			)
			(layer "F.Fab")
		)
		(fp_line
			(start 0.12065 -0.3048)
			(end 0.67945 -0.3048)
			(stroke
				(width 0.1)
				(type default)
			)
			(layer "F.Fab")
		)
		(fp_line
			(start 0.12065 -0.2794)
			(end 0.12065 -0.3048)
			(stroke
				(width 0.1)
				(type default)
			)
			(layer "F.Fab")
		)
		(fp_line
			(start -0.12065 -0.2794)
			(end 0.12065 -0.2794)
			(stroke
				(width 0.1)
				(type default)
			)
			(layer "F.Fab")
		)
		(fp_line
			(start 0.120396 0.2794)
			(end -0.12065 0.2794)
			(stroke
				(width 0.1)
				(type default)
			)
			(layer "F.Fab")
		)
		(fp_line
			(start -0.12065 0.2794)
			(end -0.12065 0.3048)
			(stroke
				(width 0.1)
				(type default)
			)
			(layer "F.Fab")
		)
		(fp_line
			(start 0.67945 0.3048)
			(end 0.120396 0.3048)
			(stroke
				(width 0.1)
				(type default)
			)
			(layer "F.Fab")
		)
		(fp_line
			(start 0.120396 0.3048)
			(end 0.120396 0.2794)
			(stroke
				(width 0.1)
				(type default)
			)
			(layer "F.Fab")
		)
		(fp_line
			(start -0.12065 0.3048)
			(end -0.67945 0.3048)
			(stroke
				(width 0.1)
				(type default)
			)
			(layer "F.Fab")
		)
		(fp_line
			(start -0.67945 0.3048)
			(end -0.67945 -0.305054)
			(stroke
				(width 0.1)
				(type default)
			)
			(layer "F.Fab")
		)
		(pad "1" smd circle
			(at -0.40005 0 90)
			(size 0 0)
			(layers "F.Cu" "F.Mask" "F.Paste")
			(net "P12V_E1S_0")
		)
		(pad "2" smd circle
			(at 0.40005 0 90)
			(size 0 0)
			(layers "F.Cu" "F.Mask" "F.Paste")
			(net "P12V_E1S_GATE_0")
		)
	)
	(footprint ""
		(layer "F.Cu")
		(at 399.171668 -396.412974 90)
		(property "Reference" "R634"
			(at 0 0 90)
			(layer "F.SilkS")
			(hide yes)
			(effects
				(font
					(size 1.27 1.27)
				)
			)
		)
		(property "Value" ""
			(at 0 0 90)
			(layer "F.Fab")
			(effects
				(font
					(size 1.27 1.27)
				)
			)
		)
		(duplicate_pad_numbers_are_jumpers no)
		(fp_line
			(start 0.32512 -0.175006)
			(end 0.32512 0.175006)
			(stroke
				(width 0.1)
				(type default)
			)
			(layer "F.Fab")
		)
		(fp_line
			(start -0.32512 -0.175006)
			(end 0.32512 -0.175006)
			(stroke
				(width 0.1)
				(type default)
			)
			(layer "F.Fab")
		)
		(fp_line
			(start 0.32512 0.175006)
			(end -0.32512 0.175006)
			(stroke
				(width 0.1)
				(type default)
			)
			(layer "F.Fab")
		)
		(fp_line
			(start -0.32512 0.175006)
			(end -0.32512 -0.175006)
			(stroke
				(width 0.1)
				(type default)
			)
			(layer "F.Fab")
		)
		(pad "1" smd rect
			(at -0.2667 0 90)
			(size 0.3048 0.381)
			(layers "F.Cu" "F.Mask" "F.Paste")
			(net "CLK_100M_RETIMER_CPU0_P2_DP")
		)
		(pad "2" smd rect
			(at 0.2667 0 270)
			(size 0.3048 0.381)
			(layers "F.Cu" "F.Mask" "F.Paste")
			(net "GND")
		)
	)
	(footprint ""
		(layer "F.Cu")
		(at 395.269212 -321.148202 90)
		(property "Reference" "R581"
			(at 0 0 90)
			(layer "F.SilkS")
			(hide yes)
			(effects
				(font
					(size 1.27 1.27)
				)
			)
		)
		(property "Value" ""
			(at 0 0 90)
			(layer "F.Fab")
			(effects
				(font
					(size 1.27 1.27)
				)
			)
		)
		(duplicate_pad_numbers_are_jumpers no)
		(fp_line
			(start 0.7874 -0.4064)
			(end 0.7874 0.4064)
			(stroke
				(width 0.1524)
				(type default)
			)
			(layer "F.SilkS")
		)
		(fp_line
			(start -0.7874 -0.4064)
			(end 0.7874 -0.4064)
			(stroke
				(width 0.1524)
				(type default)
			)
			(layer "F.SilkS")
		)
		(fp_line
			(start 0.7874 0.4064)
			(end -0.7874 0.4064)
			(stroke
				(width 0.1524)
				(type default)
			)
			(layer "F.SilkS")
		)
		(fp_line
			(start -0.7874 0.4064)
			(end -0.7874 -0.4064)
			(stroke
				(width 0.1524)
				(type default)
			)
			(layer "F.SilkS")
		)
		(fp_line
			(start -0.12065 -0.305054)
			(end -0.12065 -0.2794)
			(stroke
				(width 0.1)
				(type default)
			)
			(layer "F.Fab")
		)
		(fp_line
			(start -0.67945 -0.305054)
			(end -0.12065 -0.305054)
			(stroke
				(width 0.1)
				(type default)
			)
			(layer "F.Fab")
		)
		(fp_line
			(start 0.67945 -0.3048)
			(end 0.67945 0.3048)
			(stroke
				(width 0.1)
				(type default)
			)
			(layer "F.Fab")
		)
		(fp_line
			(start 0.12065 -0.3048)
			(end 0.67945 -0.3048)
			(stroke
				(width 0.1)
				(type default)
			)
			(layer "F.Fab")
		)
		(fp_line
			(start 0.12065 -0.2794)
			(end 0.12065 -0.3048)
			(stroke
				(width 0.1)
				(type default)
			)
			(layer "F.Fab")
		)
		(fp_line
			(start -0.12065 -0.2794)
			(end 0.12065 -0.2794)
			(stroke
				(width 0.1)
				(type default)
			)
			(layer "F.Fab")
		)
		(fp_line
			(start 0.120396 0.2794)
			(end -0.12065 0.2794)
			(stroke
				(width 0.1)
				(type default)
			)
			(layer "F.Fab")
		)
		(fp_line
			(start -0.12065 0.2794)
			(end -0.12065 0.3048)
			(stroke
				(width 0.1)
				(type default)
			)
			(layer "F.Fab")
		)
		(fp_line
			(start 0.67945 0.3048)
			(end 0.120396 0.3048)
			(stroke
				(width 0.1)
				(type default)
			)
			(layer "F.Fab")
		)
		(fp_line
			(start 0.120396 0.3048)
			(end 0.120396 0.2794)
			(stroke
				(width 0.1)
				(type default)
			)
			(layer "F.Fab")
		)
		(fp_line
			(start -0.12065 0.3048)
			(end -0.67945 0.3048)
			(stroke
				(width 0.1)
				(type default)
			)
			(layer "F.Fab")
		)
		(fp_line
			(start -0.67945 0.3048)
			(end -0.67945 -0.305054)
			(stroke
				(width 0.1)
				(type default)
			)
			(layer "F.Fab")
		)
		(pad "1" smd circle
			(at -0.40005 0 90)
			(size 0 0)
			(layers "F.Cu" "F.Mask" "F.Paste")
			(net "RST_CPU0_RSMRST_N")
		)
		(pad "2" smd circle
			(at 0.40005 0 90)
			(size 0 0)
			(layers "F.Cu" "F.Mask" "F.Paste")
			(net "PVDD18_S5_P0")
		)
	)
	(footprint ""
		(layer "F.Cu")
		(at 384.036062 -416.899344 -90)
		(property "Reference" "C6573"
			(at 0 0 270)
			(layer "F.SilkS")
			(hide yes)
			(effects
				(font
					(size 1.27 1.27)
				)
			)
		)
		(property "Value" ""
			(at 0 0 270)
			(layer "F.Fab")
			(effects
				(font
					(size 1.27 1.27)
				)
			)
		)
		(duplicate_pad_numbers_are_jumpers no)
		(fp_line
			(start -0.299974 0.150114)
			(end -0.299974 -0.150114)
			(stroke
				(width 0.1)
				(type default)
			)
			(layer "F.Fab")
		)
		(fp_line
			(start 0.299974 0.150114)
			(end -0.299974 0.150114)
			(stroke
				(width 0.1)
				(type default)
			)
			(layer "F.Fab")
		)
		(fp_line
			(start -0.299974 -0.150114)
			(end 0.299974 -0.150114)
			(stroke
				(width 0.1)
				(type default)
			)
			(layer "F.Fab")
		)
		(fp_line
			(start 0.299974 -0.150114)
			(end 0.299974 0.150114)
			(stroke
				(width 0.1)
				(type default)
			)
			(layer "F.Fab")
		)
		(pad "1" smd rect
			(at -0.2667 0 270)
			(size 0.3048 0.381)
			(layers "F.Cu" "F.Mask" "F.Paste")
			(net "P5E_CPU0_P2_TX_BUF_C_DP<4>")
		)
		(pad "2" smd rect
			(at 0.2667 0 270)
			(size 0.3048 0.381)
			(layers "F.Cu" "F.Mask" "F.Paste")
			(net "P5E_CPU0_P2_TX_BUF_DP<4>")
		)
	)
	(footprint ""
		(layer "F.Cu")
		(at 432.308 -405.13)
		(property "Reference" "R1477"
			(at 0 0 0)
			(layer "F.SilkS")
			(hide yes)
			(effects
				(font
					(size 1.27 1.27)
				)
			)
		)
		(property "Value" ""
			(at 0 0 0)
			(layer "F.Fab")
			(effects
				(font
					(size 1.27 1.27)
				)
			)
		)
		(duplicate_pad_numbers_are_jumpers no)
		(fp_line
			(start -0.32512 -0.175006)
			(end 0.32512 -0.175006)
			(stroke
				(width 0.1)
				(type default)
			)
			(layer "F.Fab")
		)
		(fp_line
			(start -0.32512 0.175006)
			(end -0.32512 -0.175006)
			(stroke
				(width 0.1)
				(type default)
			)
			(layer "F.Fab")
		)
		(fp_line
			(start 0.32512 -0.175006)
			(end 0.32512 0.175006)
			(stroke
				(width 0.1)
				(type default)
			)
			(layer "F.Fab")
		)
		(fp_line
			(start 0.32512 0.175006)
			(end -0.32512 0.175006)
			(stroke
				(width 0.1)
				(type default)
			)
			(layer "F.Fab")
		)
		(pad "1" smd rect
			(at -0.2667 0)
			(size 0.3048 0.381)
			(layers "F.Cu" "F.Mask" "F.Paste")
			(net "P1V8_CPU0_RT_1D")
		)
		(pad "2" smd rect
			(at 0.2667 0 180)
			(size 0.3048 0.381)
			(layers "F.Cu" "F.Mask" "F.Paste")
			(net "JTAG_TMS_RT_CPU0_P2")
		)
	)
	(footprint ""
		(layer "F.Cu")
		(at 364.362238 -412.370016 180)
		(property "Reference" "C9000"
			(at 0 0 180)
			(layer "F.SilkS")
			(hide yes)
			(effects
				(font
					(size 1.27 1.27)
				)
			)
		)
		(property "Value" ""
			(at 0 0 180)
			(layer "F.Fab")
			(effects
				(font
					(size 1.27 1.27)
				)
			)
		)
		(duplicate_pad_numbers_are_jumpers no)
		(fp_line
			(start 0.7874 0.4064)
			(end -0.7874 0.4064)
			(stroke
				(width 0.1524)
				(type default)
			)
			(layer "F.SilkS")
		)
		(fp_line
			(start 0.7874 -0.4064)
			(end 0.7874 0.4064)
			(stroke
				(width 0.1524)
				(type default)
			)
			(layer "F.SilkS")
		)
		(fp_line
			(start -0.7874 0.4064)
			(end -0.7874 -0.4064)
			(stroke
				(width 0.1524)
				(type default)
			)
			(layer "F.SilkS")
		)
		(fp_line
			(start -0.7874 -0.4064)
			(end 0.7874 -0.4064)
			(stroke
				(width 0.1524)
				(type default)
			)
			(layer "F.SilkS")
		)
		(fp_line
			(start 0.67945 0.3048)
			(end 0.120396 0.3048)
			(stroke
				(width 0.1)
				(type default)
			)
			(layer "F.Fab")
		)
		(fp_line
			(start 0.67945 -0.3048)
			(end 0.67945 0.3048)
			(stroke
				(width 0.1)
				(type default)
			)
			(layer "F.Fab")
		)
		(fp_line
			(start 0.12065 -0.2794)
			(end 0.12065 -0.3048)
			(stroke
				(width 0.1)
				(type default)
			)
			(layer "F.Fab")
		)
		(fp_line
			(start 0.12065 -0.3048)
			(end 0.67945 -0.3048)
			(stroke
				(width 0.1)
				(type default)
			)
			(layer "F.Fab")
		)
		(fp_line
			(start 0.120396 0.3048)
			(end 0.120396 0.2794)
			(stroke
				(width 0.1)
				(type default)
			)
			(layer "F.Fab")
		)
		(fp_line
			(start 0.120396 0.2794)
			(end -0.12065 0.2794)
			(stroke
				(width 0.1)
				(type default)
			)
			(layer "F.Fab")
		)
		(fp_line
			(start -0.12065 0.3048)
			(end -0.67945 0.3048)
			(stroke
				(width 0.1)
				(type default)
			)
			(layer "F.Fab")
		)
		(fp_line
			(start -0.12065 0.2794)
			(end -0.12065 0.3048)
			(stroke
				(width 0.1)
				(type default)
			)
			(layer "F.Fab")
		)
		(fp_line
			(start -0.12065 -0.2794)
			(end 0.12065 -0.2794)
			(stroke
				(width 0.1)
				(type default)
			)
			(layer "F.Fab")
		)
		(fp_line
			(start -0.12065 -0.305054)
			(end -0.12065 -0.2794)
			(stroke
				(width 0.1)
				(type default)
			)
			(layer "F.Fab")
		)
		(fp_line
			(start -0.67945 0.3048)
			(end -0.67945 -0.305054)
			(stroke
				(width 0.1)
				(type default)
			)
			(layer "F.Fab")
		)
		(fp_line
			(start -0.67945 -0.305054)
			(end -0.12065 -0.305054)
			(stroke
				(width 0.1)
				(type default)
			)
			(layer "F.Fab")
		)
		(pad "1" smd circle
			(at -0.40005 0 180)
			(size 0 0)
			(layers "F.Cu" "F.Mask" "F.Paste")
			(net "PRSNT_CABLE_SWB_B1_ISO_N")
		)
		(pad "2" smd circle
			(at 0.40005 0 180)
			(size 0 0)
			(layers "F.Cu" "F.Mask" "F.Paste")
			(net "GND")
		)
	)
	(footprint ""
		(layer "F.Cu")
		(at 103.520494 -386.44068 90)
		(property "Reference" "C110"
			(at 0 0 90)
			(layer "F.SilkS")
			(hide yes)
			(effects
				(font
					(size 1.27 1.27)
				)
			)
		)
		(property "Value" ""
			(at 0 0 90)
			(layer "F.Fab")
			(effects
				(font
					(size 1.27 1.27)
				)
			)
		)
		(duplicate_pad_numbers_are_jumpers no)
		(fp_line
			(start 0.7874 -0.4064)
			(end 0.7874 0.4064)
			(stroke
				(width 0.1524)
				(type default)
			)
			(layer "F.SilkS")
		)
		(fp_line
			(start -0.7874 -0.4064)
			(end 0.7874 -0.4064)
			(stroke
				(width 0.1524)
				(type default)
			)
			(layer "F.SilkS")
		)
		(fp_line
			(start 0.7874 0.4064)
			(end -0.7874 0.4064)
			(stroke
				(width 0.1524)
				(type default)
			)
			(layer "F.SilkS")
		)
		(fp_line
			(start -0.7874 0.4064)
			(end -0.7874 -0.4064)
			(stroke
				(width 0.1524)
				(type default)
			)
			(layer "F.SilkS")
		)
		(fp_line
			(start -0.12065 -0.305054)
			(end -0.12065 -0.2794)
			(stroke
				(width 0.1)
				(type default)
			)
			(layer "F.Fab")
		)
		(fp_line
			(start -0.67945 -0.305054)
			(end -0.12065 -0.305054)
			(stroke
				(width 0.1)
				(type default)
			)
			(layer "F.Fab")
		)
		(fp_line
			(start 0.67945 -0.3048)
			(end 0.67945 0.3048)
			(stroke
				(width 0.1)
				(type default)
			)
			(layer "F.Fab")
		)
		(fp_line
			(start 0.12065 -0.3048)
			(end 0.67945 -0.3048)
			(stroke
				(width 0.1)
				(type default)
			)
			(layer "F.Fab")
		)
		(fp_line
			(start 0.12065 -0.2794)
			(end 0.12065 -0.3048)
			(stroke
				(width 0.1)
				(type default)
			)
			(layer "F.Fab")
		)
		(fp_line
			(start -0.12065 -0.2794)
			(end 0.12065 -0.2794)
			(stroke
				(width 0.1)
				(type default)
			)
			(layer "F.Fab")
		)
		(fp_line
			(start 0.120396 0.2794)
			(end -0.12065 0.2794)
			(stroke
				(width 0.1)
				(type default)
			)
			(layer "F.Fab")
		)
		(fp_line
			(start -0.12065 0.2794)
			(end -0.12065 0.3048)
			(stroke
				(width 0.1)
				(type default)
			)
			(layer "F.Fab")
		)
		(fp_line
			(start 0.67945 0.3048)
			(end 0.120396 0.3048)
			(stroke
				(width 0.1)
				(type default)
			)
			(layer "F.Fab")
		)
		(fp_line
			(start 0.120396 0.3048)
			(end 0.120396 0.2794)
			(stroke
				(width 0.1)
				(type default)
			)
			(layer "F.Fab")
		)
		(fp_line
			(start -0.12065 0.3048)
			(end -0.67945 0.3048)
			(stroke
				(width 0.1)
				(type default)
			)
			(layer "F.Fab")
		)
		(fp_line
			(start -0.67945 0.3048)
			(end -0.67945 -0.305054)
			(stroke
				(width 0.1)
				(type default)
			)
			(layer "F.Fab")
		)
		(pad "1" smd circle
			(at -0.40005 0 90)
			(size 0 0)
			(layers "F.Cu" "F.Mask" "F.Paste")
			(net "P1V8_CPU1_RT_1D")
		)
		(pad "2" smd circle
			(at 0.40005 0 90)
			(size 0 0)
			(layers "F.Cu" "F.Mask" "F.Paste")
			(net "GND")
		)
	)
	(footprint ""
		(layer "F.Cu")
		(at 105.84561 -64.55791 180)
		(property "Reference" "R6221"
			(at 0 0 180)
			(layer "F.SilkS")
			(hide yes)
			(effects
				(font
					(size 1.27 1.27)
				)
			)
		)
		(property "Value" ""
			(at 0 0 180)
			(layer "F.Fab")
			(effects
				(font
					(size 1.27 1.27)
				)
			)
		)
		(duplicate_pad_numbers_are_jumpers no)
		(fp_line
			(start 0.7874 0.4064)
			(end -0.7874 0.4064)
			(stroke
				(width 0.1524)
				(type default)
			)
			(layer "F.SilkS")
		)
		(fp_line
			(start 0.7874 -0.4064)
			(end 0.7874 0.4064)
			(stroke
				(width 0.1524)
				(type default)
			)
			(layer "F.SilkS")
		)
		(fp_line
			(start -0.7874 0.4064)
			(end -0.7874 -0.4064)
			(stroke
				(width 0.1524)
				(type default)
			)
			(layer "F.SilkS")
		)
		(fp_line
			(start -0.7874 -0.4064)
			(end 0.7874 -0.4064)
			(stroke
				(width 0.1524)
				(type default)
			)
			(layer "F.SilkS")
		)
		(fp_line
			(start 0.67945 0.3048)
			(end 0.120396 0.3048)
			(stroke
				(width 0.1)
				(type default)
			)
			(layer "F.Fab")
		)
		(fp_line
			(start 0.67945 -0.3048)
			(end 0.67945 0.3048)
			(stroke
				(width 0.1)
				(type default)
			)
			(layer "F.Fab")
		)
		(fp_line
			(start 0.12065 -0.2794)
			(end 0.12065 -0.3048)
			(stroke
				(width 0.1)
				(type default)
			)
			(layer "F.Fab")
		)
		(fp_line
			(start 0.12065 -0.3048)
			(end 0.67945 -0.3048)
			(stroke
				(width 0.1)
				(type default)
			)
			(layer "F.Fab")
		)
		(fp_line
			(start 0.120396 0.3048)
			(end 0.120396 0.2794)
			(stroke
				(width 0.1)
				(type default)
			)
			(layer "F.Fab")
		)
		(fp_line
			(start 0.120396 0.2794)
			(end -0.12065 0.2794)
			(stroke
				(width 0.1)
				(type default)
			)
			(layer "F.Fab")
		)
		(fp_line
			(start -0.12065 0.3048)
			(end -0.67945 0.3048)
			(stroke
				(width 0.1)
				(type default)
			)
			(layer "F.Fab")
		)
		(fp_line
			(start -0.12065 0.2794)
			(end -0.12065 0.3048)
			(stroke
				(width 0.1)
				(type default)
			)
			(layer "F.Fab")
		)
		(fp_line
			(start -0.12065 -0.2794)
			(end 0.12065 -0.2794)
			(stroke
				(width 0.1)
				(type default)
			)
			(layer "F.Fab")
		)
		(fp_line
			(start -0.12065 -0.305054)
			(end -0.12065 -0.2794)
			(stroke
				(width 0.1)
				(type default)
			)
			(layer "F.Fab")
		)
		(fp_line
			(start -0.67945 0.3048)
			(end -0.67945 -0.305054)
			(stroke
				(width 0.1)
				(type default)
			)
			(layer "F.Fab")
		)
		(fp_line
			(start -0.67945 -0.305054)
			(end -0.12065 -0.305054)
			(stroke
				(width 0.1)
				(type default)
			)
			(layer "F.Fab")
		)
		(pad "1" smd circle
			(at -0.40005 0 180)
			(size 0 0)
			(layers "F.Cu" "F.Mask" "F.Paste")
			(net "USB_CPU0_ADD_A2")
		)
		(pad "2" smd circle
			(at 0.40005 0 180)
			(size 0 0)
			(layers "F.Cu" "F.Mask" "F.Paste")
			(net "GND")
		)
	)
	(footprint ""
		(layer "F.Cu")
		(at 387.431026 -51.1175)
		(property "Reference" "C604"
			(at 0 0 0)
			(layer "F.SilkS")
			(hide yes)
			(effects
				(font
					(size 1.27 1.27)
				)
			)
		)
		(property "Value" ""
			(at 0 0 0)
			(layer "F.Fab")
			(effects
				(font
					(size 1.27 1.27)
				)
			)
		)
		(duplicate_pad_numbers_are_jumpers no)
		(fp_line
			(start -0.7874 -0.4064)
			(end 0.7874 -0.4064)
			(stroke
				(width 0.1524)
				(type default)
			)
			(layer "F.SilkS")
		)
		(fp_line
			(start -0.7874 0.4064)
			(end -0.7874 -0.4064)
			(stroke
				(width 0.1524)
				(type default)
			)
			(layer "F.SilkS")
		)
		(fp_line
			(start 0.7874 -0.4064)
			(end 0.7874 0.4064)
			(stroke
				(width 0.1524)
				(type default)
			)
			(layer "F.SilkS")
		)
		(fp_line
			(start 0.7874 0.4064)
			(end -0.7874 0.4064)
			(stroke
				(width 0.1524)
				(type default)
			)
			(layer "F.SilkS")
		)
		(fp_line
			(start -0.67945 -0.305054)
			(end -0.12065 -0.305054)
			(stroke
				(width 0.1)
				(type default)
			)
			(layer "F.Fab")
		)
		(fp_line
			(start -0.67945 0.3048)
			(end -0.67945 -0.305054)
			(stroke
				(width 0.1)
				(type default)
			)
			(layer "F.Fab")
		)
		(fp_line
			(start -0.12065 -0.305054)
			(end -0.12065 -0.2794)
			(stroke
				(width 0.1)
				(type default)
			)
			(layer "F.Fab")
		)
		(fp_line
			(start -0.12065 -0.2794)
			(end 0.12065 -0.2794)
			(stroke
				(width 0.1)
				(type default)
			)
			(layer "F.Fab")
		)
		(fp_line
			(start -0.12065 0.2794)
			(end -0.12065 0.3048)
			(stroke
				(width 0.1)
				(type default)
			)
			(layer "F.Fab")
		)
		(fp_line
			(start -0.12065 0.3048)
			(end -0.67945 0.3048)
			(stroke
				(width 0.1)
				(type default)
			)
			(layer "F.Fab")
		)
		(fp_line
			(start 0.120396 0.2794)
			(end -0.12065 0.2794)
			(stroke
				(width 0.1)
				(type default)
			)
			(layer "F.Fab")
		)
		(fp_line
			(start 0.120396 0.3048)
			(end 0.120396 0.2794)
			(stroke
				(width 0.1)
				(type default)
			)
			(layer "F.Fab")
		)
		(fp_line
			(start 0.12065 -0.3048)
			(end 0.67945 -0.3048)
			(stroke
				(width 0.1)
				(type default)
			)
			(layer "F.Fab")
		)
		(fp_line
			(start 0.12065 -0.2794)
			(end 0.12065 -0.3048)
			(stroke
				(width 0.1)
				(type default)
			)
			(layer "F.Fab")
		)
		(fp_line
			(start 0.67945 -0.3048)
			(end 0.67945 0.3048)
			(stroke
				(width 0.1)
				(type default)
			)
			(layer "F.Fab")
		)
		(fp_line
			(start 0.67945 0.3048)
			(end 0.120396 0.3048)
			(stroke
				(width 0.1)
				(type default)
			)
			(layer "F.Fab")
		)
		(pad "1" smd circle
			(at -0.40005 0)
			(size 0 0)
			(layers "F.Cu" "F.Mask" "F.Paste")
			(net "HDT_HDR_TCK")
		)
		(pad "2" smd circle
			(at 0.40005 0)
			(size 0 0)
			(layers "F.Cu" "F.Mask" "F.Paste")
			(net "GND")
		)
	)
	(footprint ""
		(layer "F.Cu")
		(at 137.971784 -48.325024 180)
		(property "Reference" "R6206"
			(at 0 0 180)
			(layer "F.SilkS")
			(hide yes)
			(effects
				(font
					(size 1.27 1.27)
				)
			)
		)
		(property "Value" ""
			(at 0 0 180)
			(layer "F.Fab")
			(effects
				(font
					(size 1.27 1.27)
				)
			)
		)
		(duplicate_pad_numbers_are_jumpers no)
		(fp_line
			(start 0.7874 0.4064)
			(end -0.7874 0.4064)
			(stroke
				(width 0.1524)
				(type default)
			)
			(layer "F.SilkS")
		)
		(fp_line
			(start 0.7874 -0.4064)
			(end 0.7874 0.4064)
			(stroke
				(width 0.1524)
				(type default)
			)
			(layer "F.SilkS")
		)
		(fp_line
			(start -0.7874 0.4064)
			(end -0.7874 -0.4064)
			(stroke
				(width 0.1524)
				(type default)
			)
			(layer "F.SilkS")
		)
		(fp_line
			(start -0.7874 -0.4064)
			(end 0.7874 -0.4064)
			(stroke
				(width 0.1524)
				(type default)
			)
			(layer "F.SilkS")
		)
		(fp_line
			(start 0.67945 0.3048)
			(end 0.120396 0.3048)
			(stroke
				(width 0.1)
				(type default)
			)
			(layer "F.Fab")
		)
		(fp_line
			(start 0.67945 -0.3048)
			(end 0.67945 0.3048)
			(stroke
				(width 0.1)
				(type default)
			)
			(layer "F.Fab")
		)
		(fp_line
			(start 0.12065 -0.2794)
			(end 0.12065 -0.3048)
			(stroke
				(width 0.1)
				(type default)
			)
			(layer "F.Fab")
		)
		(fp_line
			(start 0.12065 -0.3048)
			(end 0.67945 -0.3048)
			(stroke
				(width 0.1)
				(type default)
			)
			(layer "F.Fab")
		)
		(fp_line
			(start 0.120396 0.3048)
			(end 0.120396 0.2794)
			(stroke
				(width 0.1)
				(type default)
			)
			(layer "F.Fab")
		)
		(fp_line
			(start 0.120396 0.2794)
			(end -0.12065 0.2794)
			(stroke
				(width 0.1)
				(type default)
			)
			(layer "F.Fab")
		)
		(fp_line
			(start -0.12065 0.3048)
			(end -0.67945 0.3048)
			(stroke
				(width 0.1)
				(type default)
			)
			(layer "F.Fab")
		)
		(fp_line
			(start -0.12065 0.2794)
			(end -0.12065 0.3048)
			(stroke
				(width 0.1)
				(type default)
			)
			(layer "F.Fab")
		)
		(fp_line
			(start -0.12065 -0.2794)
			(end 0.12065 -0.2794)
			(stroke
				(width 0.1)
				(type default)
			)
			(layer "F.Fab")
		)
		(fp_line
			(start -0.12065 -0.305054)
			(end -0.12065 -0.2794)
			(stroke
				(width 0.1)
				(type default)
			)
			(layer "F.Fab")
		)
		(fp_line
			(start -0.67945 0.3048)
			(end -0.67945 -0.305054)
			(stroke
				(width 0.1)
				(type default)
			)
			(layer "F.Fab")
		)
		(fp_line
			(start -0.67945 -0.305054)
			(end -0.12065 -0.305054)
			(stroke
				(width 0.1)
				(type default)
			)
			(layer "F.Fab")
		)
		(pad "1" smd circle
			(at -0.40005 0 180)
			(size 0 0)
			(layers "F.Cu" "F.Mask" "F.Paste")
			(net "P3V3_AUX")
		)
		(pad "2" smd circle
			(at 0.40005 0 180)
			(size 0 0)
			(layers "F.Cu" "F.Mask" "F.Paste")
			(net "PU_CPU0_USB_HUB_RESERVED2")
		)
	)
	(footprint ""
		(layer "F.Cu")
		(at 461.41132 -38.565836)
		(property "Reference" "C36"
			(at 0 0 0)
			(layer "F.SilkS")
			(hide yes)
			(effects
				(font
					(size 1.27 1.27)
				)
			)
		)
		(property "Value" ""
			(at 0 0 0)
			(layer "F.Fab")
			(effects
				(font
					(size 1.27 1.27)
				)
			)
		)
		(duplicate_pad_numbers_are_jumpers no)
		(fp_line
			(start -0.7874 -0.4064)
			(end 0.7874 -0.4064)
			(stroke
				(width 0.1524)
				(type default)
			)
			(layer "F.SilkS")
		)
		(fp_line
			(start -0.7874 0.4064)
			(end -0.7874 -0.4064)
			(stroke
				(width 0.1524)
				(type default)
			)
			(layer "F.SilkS")
		)
		(fp_line
			(start 0.7874 -0.4064)
			(end 0.7874 0.4064)
			(stroke
				(width 0.1524)
				(type default)
			)
			(layer "F.SilkS")
		)
		(fp_line
			(start 0.7874 0.4064)
			(end -0.7874 0.4064)
			(stroke
				(width 0.1524)
				(type default)
			)
			(layer "F.SilkS")
		)
		(fp_line
			(start -0.67945 -0.305054)
			(end -0.12065 -0.305054)
			(stroke
				(width 0.1)
				(type default)
			)
			(layer "F.Fab")
		)
		(fp_line
			(start -0.67945 0.3048)
			(end -0.67945 -0.305054)
			(stroke
				(width 0.1)
				(type default)
			)
			(layer "F.Fab")
		)
		(fp_line
			(start -0.12065 -0.305054)
			(end -0.12065 -0.2794)
			(stroke
				(width 0.1)
				(type default)
			)
			(layer "F.Fab")
		)
		(fp_line
			(start -0.12065 -0.2794)
			(end 0.12065 -0.2794)
			(stroke
				(width 0.1)
				(type default)
			)
			(layer "F.Fab")
		)
		(fp_line
			(start -0.12065 0.2794)
			(end -0.12065 0.3048)
			(stroke
				(width 0.1)
				(type default)
			)
			(layer "F.Fab")
		)
		(fp_line
			(start -0.12065 0.3048)
			(end -0.67945 0.3048)
			(stroke
				(width 0.1)
				(type default)
			)
			(layer "F.Fab")
		)
		(fp_line
			(start 0.120396 0.2794)
			(end -0.12065 0.2794)
			(stroke
				(width 0.1)
				(type default)
			)
			(layer "F.Fab")
		)
		(fp_line
			(start 0.120396 0.3048)
			(end 0.120396 0.2794)
			(stroke
				(width 0.1)
				(type default)
			)
			(layer "F.Fab")
		)
		(fp_line
			(start 0.12065 -0.3048)
			(end 0.67945 -0.3048)
			(stroke
				(width 0.1)
				(type default)
			)
			(layer "F.Fab")
		)
		(fp_line
			(start 0.12065 -0.2794)
			(end 0.12065 -0.3048)
			(stroke
				(width 0.1)
				(type default)
			)
			(layer "F.Fab")
		)
		(fp_line
			(start 0.67945 -0.3048)
			(end 0.67945 0.3048)
			(stroke
				(width 0.1)
				(type default)
			)
			(layer "F.Fab")
		)
		(fp_line
			(start 0.67945 0.3048)
			(end 0.120396 0.3048)
			(stroke
				(width 0.1)
				(type default)
			)
			(layer "F.Fab")
		)
		(pad "1" smd circle
			(at -0.40005 0)
			(size 0 0)
			(layers "F.Cu" "F.Mask" "F.Paste")
			(net "P3V3_AUX")
		)
		(pad "2" smd circle
			(at 0.40005 0)
			(size 0 0)
			(layers "F.Cu" "F.Mask" "F.Paste")
			(net "GND")
		)
	)
	(footprint ""
		(layer "F.Cu")
		(at 118.379494 -167.06596 -90)
		(property "Reference" "PC317_7"
			(at 0 0 270)
			(layer "F.SilkS")
			(hide yes)
			(effects
				(font
					(size 1.27 1.27)
				)
			)
		)
		(property "Value" ""
			(at 0 0 270)
			(layer "F.Fab")
			(effects
				(font
					(size 1.27 1.27)
				)
			)
		)
		(duplicate_pad_numbers_are_jumpers no)
		(fp_line
			(start -0.7874 0.4064)
			(end -0.7874 -0.4064)
			(stroke
				(width 0.1524)
				(type default)
			)
			(layer "F.SilkS")
		)
		(fp_line
			(start 0.7874 0.4064)
			(end -0.7874 0.4064)
			(stroke
				(width 0.1524)
				(type default)
			)
			(layer "F.SilkS")
		)
		(fp_line
			(start -0.7874 -0.4064)
			(end 0.7874 -0.4064)
			(stroke
				(width 0.1524)
				(type default)
			)
			(layer "F.SilkS")
		)
		(fp_line
			(start 0.7874 -0.4064)
			(end 0.7874 0.4064)
			(stroke
				(width 0.1524)
				(type default)
			)
			(layer "F.SilkS")
		)
		(fp_line
			(start -0.67945 0.3048)
			(end -0.67945 -0.305054)
			(stroke
				(width 0.1)
				(type default)
			)
			(layer "F.Fab")
		)
		(fp_line
			(start -0.12065 0.3048)
			(end -0.67945 0.3048)
			(stroke
				(width 0.1)
				(type default)
			)
			(layer "F.Fab")
		)
		(fp_line
			(start 0.120396 0.3048)
			(end 0.120396 0.2794)
			(stroke
				(width 0.1)
				(type default)
			)
			(layer "F.Fab")
		)
		(fp_line
			(start 0.67945 0.3048)
			(end 0.120396 0.3048)
			(stroke
				(width 0.1)
				(type default)
			)
			(layer "F.Fab")
		)
		(fp_line
			(start -0.12065 0.2794)
			(end -0.12065 0.3048)
			(stroke
				(width 0.1)
				(type default)
			)
			(layer "F.Fab")
		)
		(fp_line
			(start 0.120396 0.2794)
			(end -0.12065 0.2794)
			(stroke
				(width 0.1)
				(type default)
			)
			(layer "F.Fab")
		)
		(fp_line
			(start -0.12065 -0.2794)
			(end 0.12065 -0.2794)
			(stroke
				(width 0.1)
				(type default)
			)
			(layer "F.Fab")
		)
		(fp_line
			(start 0.12065 -0.2794)
			(end 0.12065 -0.3048)
			(stroke
				(width 0.1)
				(type default)
			)
			(layer "F.Fab")
		)
		(fp_line
			(start 0.12065 -0.3048)
			(end 0.67945 -0.3048)
			(stroke
				(width 0.1)
				(type default)
			)
			(layer "F.Fab")
		)
		(fp_line
			(start 0.67945 -0.3048)
			(end 0.67945 0.3048)
			(stroke
				(width 0.1)
				(type default)
			)
			(layer "F.Fab")
		)
		(fp_line
			(start -0.67945 -0.305054)
			(end -0.12065 -0.305054)
			(stroke
				(width 0.1)
				(type default)
			)
			(layer "F.Fab")
		)
		(fp_line
			(start -0.12065 -0.305054)
			(end -0.12065 -0.2794)
			(stroke
				(width 0.1)
				(type default)
			)
			(layer "F.Fab")
		)
		(pad "1" smd circle
			(at -0.40005 0 270)
			(size 0 0)
			(layers "F.Cu" "F.Mask" "F.Paste")
			(net "PVDDCR_CPU0_P1_VCCS")
		)
		(pad "2" smd circle
			(at 0.40005 0 270)
			(size 0 0)
			(layers "F.Cu" "F.Mask" "F.Paste")
			(net "GND")
		)
	)
	(footprint ""
		(layer "F.Cu")
		(at 103.601266 -401.329906 -90)
		(property "Reference" "U12"
			(at 0.837184 -3.221482 90)
			(unlocked yes)
			(layer "F.SilkS")
			(effects
				(font
					(size 0.7874 0.5842)
					(thickness 0.1524)
				)
				(justify left)
			)
		)
		(property "Value" ""
			(at 0 0 270)
			(layer "F.Fab")
			(effects
				(font
					(size 1.27 1.27)
				)
			)
		)
		(duplicate_pad_numbers_are_jumpers no)
		(fp_line
			(start -1.8288 2.500122)
			(end 1.8288 2.500122)
			(stroke
				(width 0.1524)
				(type default)
			)
			(layer "F.SilkS")
		)
		(fp_line
			(start 1.8288 2.500122)
			(end 1.8288 -2.500122)
			(stroke
				(width 0.1524)
				(type default)
			)
			(layer "F.SilkS")
		)
		(fp_line
			(start 0 -1.4224)
			(end -1.077722 -2.500122)
			(stroke
				(width 0.1524)
				(type default)
			)
			(layer "F.SilkS")
		)
		(fp_line
			(start -1.8288 -2.500122)
			(end -1.8288 2.500122)
			(stroke
				(width 0.1524)
				(type default)
			)
			(layer "F.SilkS")
		)
		(fp_line
			(start -1.077722 -2.500122)
			(end -1.8288 -2.500122)
			(stroke
				(width 0.1524)
				(type default)
			)
			(layer "F.SilkS")
		)
		(fp_line
			(start 1.077722 -2.500122)
			(end 0 -1.4224)
			(stroke
				(width 0.1524)
				(type default)
			)
			(layer "F.SilkS")
		)
		(fp_line
			(start 1.8288 -2.500122)
			(end 1.077722 -2.500122)
			(stroke
				(width 0.1524)
				(type default)
			)
			(layer "F.SilkS")
		)
		(fp_poly
			(pts
				(xy -4.932934 -2.31648) (xy -4.932934 -1.30048) (xy -3.916934 -1.80848)
			)
			(stroke
				(width 0)
				(type default)
			)
			(fill yes)
			(layer "F.SilkS")
		)
		(fp_line
			(start -1.999996 2.500122)
			(end 1.999996 2.500122)
			(stroke
				(width 0.1)
				(type default)
			)
			(layer "F.Fab")
		)
		(fp_line
			(start 1.999996 2.500122)
			(end 1.999996 -2.500122)
			(stroke
				(width 0.1)
				(type default)
			)
			(layer "F.Fab")
		)
		(fp_line
			(start -1.999996 -2.500122)
			(end -1.999996 2.500122)
			(stroke
				(width 0.1)
				(type default)
			)
			(layer "F.Fab")
		)
		(fp_line
			(start 1.999996 -2.500122)
			(end -1.999996 -2.500122)
			(stroke
				(width 0.1)
				(type default)
			)
			(layer "F.Fab")
		)
		(fp_poly
			(pts
				(xy -4.5085 -2.413) (xy -4.5085 -1.397) (xy -3.4925 -1.905)
			)
			(stroke
				(width 0)
				(type default)
			)
			(fill yes)
			(layer "F.Fab")
		)
		(pad "1" smd rect
			(at -2.599944 -1.905 180)
			(size 0.889 1.27)
			(layers "F.Cu" "F.Mask" "F.Paste")
			(net "Net_10845")
		)
		(pad "2" smd rect
			(at -2.599944 -0.635 180)
			(size 0.889 1.27)
			(layers "F.Cu" "F.Mask" "F.Paste")
			(net "Net_10844")
		)
		(pad "3" smd rect
			(at -2.599944 0.635 180)
			(size 0.889 1.27)
			(layers "F.Cu" "F.Mask" "F.Paste")
			(net "U12_E2")
		)
		(pad "4" smd rect
			(at -2.599944 1.905 180)
			(size 0.889 1.27)
			(layers "F.Cu" "F.Mask" "F.Paste")
			(net "GND")
		)
		(pad "5" smd rect
			(at 2.599944 1.905 180)
			(size 0.889 1.27)
			(layers "F.Cu" "F.Mask" "F.Paste")
			(net "SMB_RT_CPU1_P0_ROM_SDA")
		)
		(pad "6" smd rect
			(at 2.599944 0.635 180)
			(size 0.889 1.27)
			(layers "F.Cu" "F.Mask" "F.Paste")
			(net "SMB_RT_CPU1_P0_ROM_SCL")
		)
		(pad "7" smd rect
			(at 2.599944 -0.635 180)
			(size 0.889 1.27)
			(layers "F.Cu" "F.Mask" "F.Paste")
			(net "GND")
		)
		(pad "8" smd rect
			(at 2.599944 -1.905 180)
			(size 0.889 1.27)
			(layers "F.Cu" "F.Mask" "F.Paste")
			(net "P1V8_CPU1_RT_1D")
		)
	)
	(footprint ""
		(layer "F.Cu")
		(at 321.980306 -335.09458 -90)
		(property "Reference" "PC118_3"
			(at 0 0 270)
			(layer "F.SilkS")
			(hide yes)
			(effects
				(font
					(size 1.27 1.27)
				)
			)
		)
		(property "Value" ""
			(at 0 0 270)
			(layer "F.Fab")
			(effects
				(font
					(size 1.27 1.27)
				)
			)
		)
		(duplicate_pad_numbers_are_jumpers no)
		(fp_line
			(start -0.7874 0.4064)
			(end -0.7874 -0.4064)
			(stroke
				(width 0.1524)
				(type default)
			)
			(layer "F.SilkS")
		)
		(fp_line
			(start 0.7874 0.4064)
			(end -0.7874 0.4064)
			(stroke
				(width 0.1524)
				(type default)
			)
			(layer "F.SilkS")
		)
		(fp_line
			(start -0.7874 -0.4064)
			(end 0.7874 -0.4064)
			(stroke
				(width 0.1524)
				(type default)
			)
			(layer "F.SilkS")
		)
		(fp_line
			(start 0.7874 -0.4064)
			(end 0.7874 0.4064)
			(stroke
				(width 0.1524)
				(type default)
			)
			(layer "F.SilkS")
		)
		(fp_line
			(start -0.67945 0.3048)
			(end -0.67945 -0.305054)
			(stroke
				(width 0.1)
				(type default)
			)
			(layer "F.Fab")
		)
		(fp_line
			(start -0.12065 0.3048)
			(end -0.67945 0.3048)
			(stroke
				(width 0.1)
				(type default)
			)
			(layer "F.Fab")
		)
		(fp_line
			(start 0.120396 0.3048)
			(end 0.120396 0.2794)
			(stroke
				(width 0.1)
				(type default)
			)
			(layer "F.Fab")
		)
		(fp_line
			(start 0.67945 0.3048)
			(end 0.120396 0.3048)
			(stroke
				(width 0.1)
				(type default)
			)
			(layer "F.Fab")
		)
		(fp_line
			(start -0.12065 0.2794)
			(end -0.12065 0.3048)
			(stroke
				(width 0.1)
				(type default)
			)
			(layer "F.Fab")
		)
		(fp_line
			(start 0.120396 0.2794)
			(end -0.12065 0.2794)
			(stroke
				(width 0.1)
				(type default)
			)
			(layer "F.Fab")
		)
		(fp_line
			(start -0.12065 -0.2794)
			(end 0.12065 -0.2794)
			(stroke
				(width 0.1)
				(type default)
			)
			(layer "F.Fab")
		)
		(fp_line
			(start 0.12065 -0.2794)
			(end 0.12065 -0.3048)
			(stroke
				(width 0.1)
				(type default)
			)
			(layer "F.Fab")
		)
		(fp_line
			(start 0.12065 -0.3048)
			(end 0.67945 -0.3048)
			(stroke
				(width 0.1)
				(type default)
			)
			(layer "F.Fab")
		)
		(fp_line
			(start 0.67945 -0.3048)
			(end 0.67945 0.3048)
			(stroke
				(width 0.1)
				(type default)
			)
			(layer "F.Fab")
		)
		(fp_line
			(start -0.67945 -0.305054)
			(end -0.12065 -0.305054)
			(stroke
				(width 0.1)
				(type default)
			)
			(layer "F.Fab")
		)
		(fp_line
			(start -0.12065 -0.305054)
			(end -0.12065 -0.2794)
			(stroke
				(width 0.1)
				(type default)
			)
			(layer "F.Fab")
		)
		(pad "1" smd circle
			(at -0.40005 0 270)
			(size 0 0)
			(layers "F.Cu" "F.Mask" "F.Paste")
			(net "SW_P12V_AUX_PVDDCR_CPU1_P0_FLT")
		)
		(pad "2" smd circle
			(at 0.40005 0 270)
			(size 0 0)
			(layers "F.Cu" "F.Mask" "F.Paste")
			(net "GND")
		)
	)
	(footprint ""
		(layer "F.Cu")
		(at 432.308 -407.4922)
		(property "Reference" "R1476"
			(at 0 0 0)
			(layer "F.SilkS")
			(hide yes)
			(effects
				(font
					(size 1.27 1.27)
				)
			)
		)
		(property "Value" ""
			(at 0 0 0)
			(layer "F.Fab")
			(effects
				(font
					(size 1.27 1.27)
				)
			)
		)
		(duplicate_pad_numbers_are_jumpers no)
		(fp_line
			(start -0.32512 -0.175006)
			(end 0.32512 -0.175006)
			(stroke
				(width 0.1)
				(type default)
			)
			(layer "F.Fab")
		)
		(fp_line
			(start -0.32512 0.175006)
			(end -0.32512 -0.175006)
			(stroke
				(width 0.1)
				(type default)
			)
			(layer "F.Fab")
		)
		(fp_line
			(start 0.32512 -0.175006)
			(end 0.32512 0.175006)
			(stroke
				(width 0.1)
				(type default)
			)
			(layer "F.Fab")
		)
		(fp_line
			(start 0.32512 0.175006)
			(end -0.32512 0.175006)
			(stroke
				(width 0.1)
				(type default)
			)
			(layer "F.Fab")
		)
		(pad "1" smd rect
			(at -0.2667 0)
			(size 0.3048 0.381)
			(layers "F.Cu" "F.Mask" "F.Paste")
			(net "P1V8_CPU0_RT_1D")
		)
		(pad "2" smd rect
			(at 0.2667 0 180)
			(size 0.3048 0.381)
			(layers "F.Cu" "F.Mask" "F.Paste")
			(net "JTAG_TDI_RT_CPU0_P2")
		)
	)
	(footprint ""
		(layer "F.Cu")
		(at 178.830224 -147.086574 90)
		(property "Reference" "R499"
			(at 0 0 90)
			(layer "F.SilkS")
			(hide yes)
			(effects
				(font
					(size 1.27 1.27)
				)
			)
		)
		(property "Value" ""
			(at 0 0 90)
			(layer "F.Fab")
			(effects
				(font
					(size 1.27 1.27)
				)
			)
		)
		(duplicate_pad_numbers_are_jumpers no)
		(fp_line
			(start 0.7874 -0.4064)
			(end 0.7874 0.4064)
			(stroke
				(width 0.1524)
				(type default)
			)
			(layer "F.SilkS")
		)
		(fp_line
			(start -0.7874 -0.4064)
			(end 0.7874 -0.4064)
			(stroke
				(width 0.1524)
				(type default)
			)
			(layer "F.SilkS")
		)
		(fp_line
			(start 0.7874 0.4064)
			(end -0.7874 0.4064)
			(stroke
				(width 0.1524)
				(type default)
			)
			(layer "F.SilkS")
		)
		(fp_line
			(start -0.7874 0.4064)
			(end -0.7874 -0.4064)
			(stroke
				(width 0.1524)
				(type default)
			)
			(layer "F.SilkS")
		)
		(fp_line
			(start -0.12065 -0.305054)
			(end -0.12065 -0.2794)
			(stroke
				(width 0.1)
				(type default)
			)
			(layer "F.Fab")
		)
		(fp_line
			(start -0.67945 -0.305054)
			(end -0.12065 -0.305054)
			(stroke
				(width 0.1)
				(type default)
			)
			(layer "F.Fab")
		)
		(fp_line
			(start 0.67945 -0.3048)
			(end 0.67945 0.3048)
			(stroke
				(width 0.1)
				(type default)
			)
			(layer "F.Fab")
		)
		(fp_line
			(start 0.12065 -0.3048)
			(end 0.67945 -0.3048)
			(stroke
				(width 0.1)
				(type default)
			)
			(layer "F.Fab")
		)
		(fp_line
			(start 0.12065 -0.2794)
			(end 0.12065 -0.3048)
			(stroke
				(width 0.1)
				(type default)
			)
			(layer "F.Fab")
		)
		(fp_line
			(start -0.12065 -0.2794)
			(end 0.12065 -0.2794)
			(stroke
				(width 0.1)
				(type default)
			)
			(layer "F.Fab")
		)
		(fp_line
			(start 0.120396 0.2794)
			(end -0.12065 0.2794)
			(stroke
				(width 0.1)
				(type default)
			)
			(layer "F.Fab")
		)
		(fp_line
			(start -0.12065 0.2794)
			(end -0.12065 0.3048)
			(stroke
				(width 0.1)
				(type default)
			)
			(layer "F.Fab")
		)
		(fp_line
			(start 0.67945 0.3048)
			(end 0.120396 0.3048)
			(stroke
				(width 0.1)
				(type default)
			)
			(layer "F.Fab")
		)
		(fp_line
			(start 0.120396 0.3048)
			(end 0.120396 0.2794)
			(stroke
				(width 0.1)
				(type default)
			)
			(layer "F.Fab")
		)
		(fp_line
			(start -0.12065 0.3048)
			(end -0.67945 0.3048)
			(stroke
				(width 0.1)
				(type default)
			)
			(layer "F.Fab")
		)
		(fp_line
			(start -0.67945 0.3048)
			(end -0.67945 -0.305054)
			(stroke
				(width 0.1)
				(type default)
			)
			(layer "F.Fab")
		)
		(pad "1" smd circle
			(at -0.40005 0 90)
			(size 0 0)
			(layers "F.Cu" "F.Mask" "F.Paste")
			(net "P3V3_AUX")
		)
		(pad "2" smd circle
			(at 0.40005 0 90)
			(size 0 0)
			(layers "F.Cu" "F.Mask" "F.Paste")
			(net "SMB_CPU0_4_XLTR_SCL")
		)
	)
	(footprint ""
		(layer "F.Cu")
		(at 163.4236 -440.182)
		(property "Reference" "R2830"
			(at 0 0 0)
			(layer "F.SilkS")
			(hide yes)
			(effects
				(font
					(size 1.27 1.27)
				)
			)
		)
		(property "Value" ""
			(at 0 0 0)
			(layer "F.Fab")
			(effects
				(font
					(size 1.27 1.27)
				)
			)
		)
		(duplicate_pad_numbers_are_jumpers no)
		(fp_line
			(start -0.7874 -0.4064)
			(end 0.7874 -0.4064)
			(stroke
				(width 0.1524)
				(type default)
			)
			(layer "F.SilkS")
		)
		(fp_line
			(start -0.7874 0.4064)
			(end -0.7874 -0.4064)
			(stroke
				(width 0.1524)
				(type default)
			)
			(layer "F.SilkS")
		)
		(fp_line
			(start 0.7874 -0.4064)
			(end 0.7874 0.4064)
			(stroke
				(width 0.1524)
				(type default)
			)
			(layer "F.SilkS")
		)
		(fp_line
			(start 0.7874 0.4064)
			(end -0.7874 0.4064)
			(stroke
				(width 0.1524)
				(type default)
			)
			(layer "F.SilkS")
		)
		(fp_line
			(start -0.67945 -0.305054)
			(end -0.12065 -0.305054)
			(stroke
				(width 0.1)
				(type default)
			)
			(layer "F.Fab")
		)
		(fp_line
			(start -0.67945 0.3048)
			(end -0.67945 -0.305054)
			(stroke
				(width 0.1)
				(type default)
			)
			(layer "F.Fab")
		)
		(fp_line
			(start -0.12065 -0.305054)
			(end -0.12065 -0.2794)
			(stroke
				(width 0.1)
				(type default)
			)
			(layer "F.Fab")
		)
		(fp_line
			(start -0.12065 -0.2794)
			(end 0.12065 -0.2794)
			(stroke
				(width 0.1)
				(type default)
			)
			(layer "F.Fab")
		)
		(fp_line
			(start -0.12065 0.2794)
			(end -0.12065 0.3048)
			(stroke
				(width 0.1)
				(type default)
			)
			(layer "F.Fab")
		)
		(fp_line
			(start -0.12065 0.3048)
			(end -0.67945 0.3048)
			(stroke
				(width 0.1)
				(type default)
			)
			(layer "F.Fab")
		)
		(fp_line
			(start 0.120396 0.2794)
			(end -0.12065 0.2794)
			(stroke
				(width 0.1)
				(type default)
			)
			(layer "F.Fab")
		)
		(fp_line
			(start 0.120396 0.3048)
			(end 0.120396 0.2794)
			(stroke
				(width 0.1)
				(type default)
			)
			(layer "F.Fab")
		)
		(fp_line
			(start 0.12065 -0.3048)
			(end 0.67945 -0.3048)
			(stroke
				(width 0.1)
				(type default)
			)
			(layer "F.Fab")
		)
		(fp_line
			(start 0.12065 -0.2794)
			(end 0.12065 -0.3048)
			(stroke
				(width 0.1)
				(type default)
			)
			(layer "F.Fab")
		)
		(fp_line
			(start 0.67945 -0.3048)
			(end 0.67945 0.3048)
			(stroke
				(width 0.1)
				(type default)
			)
			(layer "F.Fab")
		)
		(fp_line
			(start 0.67945 0.3048)
			(end 0.120396 0.3048)
			(stroke
				(width 0.1)
				(type default)
			)
			(layer "F.Fab")
		)
		(pad "1" smd circle
			(at -0.40005 0)
			(size 0 0)
			(layers "F.Cu" "F.Mask" "F.Paste")
			(net "P3V3_AUX")
		)
		(pad "2" smd circle
			(at 0.40005 0)
			(size 0 0)
			(layers "F.Cu" "F.Mask" "F.Paste")
			(net "BIC_MONITER")
		)
	)
	(footprint ""
		(layer "F.Cu")
		(at 351.4852 -407.8732 90)
		(property "Reference" "R1470"
			(at 0 0 90)
			(layer "F.SilkS")
			(hide yes)
			(effects
				(font
					(size 1.27 1.27)
				)
			)
		)
		(property "Value" ""
			(at 0 0 90)
			(layer "F.Fab")
			(effects
				(font
					(size 1.27 1.27)
				)
			)
		)
		(duplicate_pad_numbers_are_jumpers no)
		(fp_line
			(start 0.32512 -0.175006)
			(end 0.32512 0.175006)
			(stroke
				(width 0.1)
				(type default)
			)
			(layer "F.Fab")
		)
		(fp_line
			(start -0.32512 -0.175006)
			(end 0.32512 -0.175006)
			(stroke
				(width 0.1)
				(type default)
			)
			(layer "F.Fab")
		)
		(fp_line
			(start 0.32512 0.175006)
			(end -0.32512 0.175006)
			(stroke
				(width 0.1)
				(type default)
			)
			(layer "F.Fab")
		)
		(fp_line
			(start -0.32512 0.175006)
			(end -0.32512 -0.175006)
			(stroke
				(width 0.1)
				(type default)
			)
			(layer "F.Fab")
		)
		(pad "1" smd rect
			(at -0.2667 0 90)
			(size 0.3048 0.381)
			(layers "F.Cu" "F.Mask" "F.Paste")
			(net "P1V8_CPU0_RT_1D")
		)
		(pad "2" smd rect
			(at 0.2667 0 270)
			(size 0.3048 0.381)
			(layers "F.Cu" "F.Mask" "F.Paste")
			(net "JTAG_TDI_RT_CPU0_P1")
		)
	)
	(footprint ""
		(layer "F.Cu")
		(at 154.17419 -102.688898)
		(property "Reference" "U239"
			(at -2.004314 1.730248 0)
			(unlocked yes)
			(layer "F.SilkS")
			(effects
				(font
					(size 0.7874 0.5842)
					(thickness 0.1524)
				)
				(justify left)
			)
		)
		(property "Value" ""
			(at 0 0 0)
			(layer "F.Fab")
			(effects
				(font
					(size 1.27 1.27)
				)
			)
		)
		(duplicate_pad_numbers_are_jumpers no)
		(fp_line
			(start -1.400048 1.100074)
			(end -1.400048 -1.100074)
			(stroke
				(width 0.1524)
				(type default)
			)
			(layer "F.SilkS")
		)
		(fp_line
			(start 1.400048 -1.100074)
			(end -1.400048 -1.100074)
			(stroke
				(width 0.1524)
				(type default)
			)
			(layer "F.SilkS")
		)
		(fp_line
			(start 1.400048 -1.100074)
			(end 1.400048 1.100074)
			(stroke
				(width 0.1524)
				(type default)
			)
			(layer "F.SilkS")
		)
		(fp_line
			(start 1.400048 1.100074)
			(end -1.400048 1.100074)
			(stroke
				(width 0.1524)
				(type default)
			)
			(layer "F.SilkS")
		)
		(fp_poly
			(pts
				(xy -2.606548 -0.418846) (xy -2.606548 -1.434846) (xy -1.590548 -0.926846)
			)
			(stroke
				(width 0)
				(type default)
			)
			(fill yes)
			(layer "F.SilkS")
		)
		(fp_line
			(start -0.674878 -1.100074)
			(end 0.674878 -1.100074)
			(stroke
				(width 0.1)
				(type default)
			)
			(layer "F.Fab")
		)
		(fp_line
			(start -0.674878 1.100074)
			(end -0.674878 -1.100074)
			(stroke
				(width 0.1)
				(type default)
			)
			(layer "F.Fab")
		)
		(fp_line
			(start 0.674878 -1.100074)
			(end 0.674878 1.100074)
			(stroke
				(width 0.1)
				(type default)
			)
			(layer "F.Fab")
		)
		(fp_line
			(start 0.674878 1.100074)
			(end -0.674878 1.100074)
			(stroke
				(width 0.1)
				(type default)
			)
			(layer "F.Fab")
		)
		(fp_poly
			(pts
				(xy -1.590548 -0.649986) (xy -2.606548 -1.157986) (xy -2.606548 -0.141986)
			)
			(stroke
				(width 0)
				(type default)
			)
			(fill yes)
			(layer "F.Fab")
		)
		(pad "1" smd rect
			(at -0.94996 -0.649986 270)
			(size 0.4318 0.6096)
			(layers "F.Cu" "F.Mask" "F.Paste")
			(net "PU_BUFFER_HDD_ACTIVITY")
		)
		(pad "2" smd rect
			(at -0.94996 0 270)
			(size 0.4318 0.6096)
			(layers "F.Cu" "F.Mask" "F.Paste")
			(net "LED_HDD_ACTIVITY_N")
		)
		(pad "3" smd rect
			(at -0.94996 0.649986 270)
			(size 0.4318 0.6096)
			(layers "F.Cu" "F.Mask" "F.Paste")
			(net "GND")
		)
		(pad "4" smd rect
			(at 0.94996 0.649986 270)
			(size 0.4318 0.6096)
			(layers "F.Cu" "F.Mask" "F.Paste")
			(net "LED_HDD_ACTIVITY_B_N")
		)
		(pad "5" smd rect
			(at 0.94996 -0.649986 270)
			(size 0.4318 0.6096)
			(layers "F.Cu" "F.Mask" "F.Paste")
			(net "P3V3_AUX")
		)
	)
	(footprint ""
		(layer "F.Cu")
		(at 87.24011 -325.661274)
		(property "Reference" "PL40"
			(at -3.16611 -16.704056 0)
			(unlocked yes)
			(layer "F.SilkS")
			(effects
				(font
					(size 0.7874 0.5842)
					(thickness 0.1524)
				)
				(justify left)
			)
		)
		(property "Value" ""
			(at 0 0 0)
			(layer "F.Fab")
			(effects
				(font
					(size 1.27 1.27)
				)
			)
		)
		(duplicate_pad_numbers_are_jumpers no)
		(fp_line
			(start -3.750056 -5.500116)
			(end -2.393442 -5.500116)
			(stroke
				(width 0.1524)
				(type default)
			)
			(layer "F.SilkS")
		)
		(fp_line
			(start -3.750056 5.500116)
			(end -3.750056 -5.500116)
			(stroke
				(width 0.1524)
				(type default)
			)
			(layer "F.SilkS")
		)
		(fp_line
			(start -2.393442 5.500116)
			(end -3.750056 5.500116)
			(stroke
				(width 0.1524)
				(type default)
			)
			(layer "F.SilkS")
		)
		(fp_line
			(start 2.393442 5.500116)
			(end 3.750056 5.500116)
			(stroke
				(width 0.1524)
				(type default)
			)
			(layer "F.SilkS")
		)
		(fp_line
			(start 3.750056 -5.500116)
			(end 2.393442 -5.500116)
			(stroke
				(width 0.1524)
				(type default)
			)
			(layer "F.SilkS")
		)
		(fp_line
			(start 3.750056 5.500116)
			(end 3.750056 -5.500116)
			(stroke
				(width 0.1524)
				(type default)
			)
			(layer "F.SilkS")
		)
		(fp_poly
			(pts
				(xy -3.9116 -4.249928) (xy -4.3434 -4.034028) (xy -4.3434 -4.465828)
			)
			(stroke
				(width 0)
				(type default)
			)
			(fill yes)
			(layer "F.SilkS")
		)
		(fp_line
			(start -3.750056 -5.500116)
			(end -3.750056 5.500116)
			(stroke
				(width 0.1)
				(type default)
			)
			(layer "F.Fab")
		)
		(fp_line
			(start -3.750056 5.500116)
			(end 3.750056 5.500116)
			(stroke
				(width 0.1)
				(type default)
			)
			(layer "F.Fab")
		)
		(fp_line
			(start 3.750056 -5.500116)
			(end -3.750056 -5.500116)
			(stroke
				(width 0.1)
				(type default)
			)
			(layer "F.Fab")
		)
		(fp_line
			(start 3.750056 5.500116)
			(end 3.750056 -5.500116)
			(stroke
				(width 0.1)
				(type default)
			)
			(layer "F.Fab")
		)
		(fp_poly
			(pts
				(xy -4.9276 -4.757928) (xy -4.9276 -3.741928) (xy -3.9116 -4.249928)
			)
			(stroke
				(width 0)
				(type default)
			)
			(fill yes)
			(layer "F.Fab")
		)
		(pad "1" smd rect
			(at 0 -4.249928 270)
			(size 2.413 4.5212)
			(layers "F.Cu" "F.Mask" "F.Paste")
			(net "SW_PVDDCR_CPU1_P1_SW1")
		)
		(pad "2" smd rect
			(at 0 -1.175004 270)
			(size 1.3716 4.5212)
			(layers "F.Cu" "F.Mask" "F.Paste")
			(net "IND_CPU1_P1_CPL5")
		)
		(pad "3" smd rect
			(at 0 1.175004 270)
			(size 1.3716 4.5212)
			(layers "F.Cu" "F.Mask" "F.Paste")
			(net "IND_CPU1_P1_CPL1")
		)
		(pad "4" smd rect
			(at 0 4.249928 270)
			(size 2.413 4.5212)
			(layers "F.Cu" "F.Mask" "F.Paste")
			(net "PVDDCR_CPU1_P1")
		)
	)
	(footprint ""
		(layer "F.Cu")
		(at 26.793444 -424.525694 180)
		(property "Reference" "R3274"
			(at 0 0 180)
			(layer "F.SilkS")
			(hide yes)
			(effects
				(font
					(size 1.27 1.27)
				)
			)
		)
		(property "Value" ""
			(at 0 0 180)
			(layer "F.Fab")
			(effects
				(font
					(size 1.27 1.27)
				)
			)
		)
		(duplicate_pad_numbers_are_jumpers no)
		(fp_line
			(start 0.7874 0.4064)
			(end -0.7874 0.4064)
			(stroke
				(width 0.1524)
				(type default)
			)
			(layer "F.SilkS")
		)
		(fp_line
			(start 0.7874 -0.4064)
			(end 0.7874 0.4064)
			(stroke
				(width 0.1524)
				(type default)
			)
			(layer "F.SilkS")
		)
		(fp_line
			(start -0.7874 0.4064)
			(end -0.7874 -0.4064)
			(stroke
				(width 0.1524)
				(type default)
			)
			(layer "F.SilkS")
		)
		(fp_line
			(start -0.7874 -0.4064)
			(end 0.7874 -0.4064)
			(stroke
				(width 0.1524)
				(type default)
			)
			(layer "F.SilkS")
		)
		(fp_line
			(start 0.67945 0.3048)
			(end 0.120396 0.3048)
			(stroke
				(width 0.1)
				(type default)
			)
			(layer "F.Fab")
		)
		(fp_line
			(start 0.67945 -0.3048)
			(end 0.67945 0.3048)
			(stroke
				(width 0.1)
				(type default)
			)
			(layer "F.Fab")
		)
		(fp_line
			(start 0.12065 -0.2794)
			(end 0.12065 -0.3048)
			(stroke
				(width 0.1)
				(type default)
			)
			(layer "F.Fab")
		)
		(fp_line
			(start 0.12065 -0.3048)
			(end 0.67945 -0.3048)
			(stroke
				(width 0.1)
				(type default)
			)
			(layer "F.Fab")
		)
		(fp_line
			(start 0.120396 0.3048)
			(end 0.120396 0.2794)
			(stroke
				(width 0.1)
				(type default)
			)
			(layer "F.Fab")
		)
		(fp_line
			(start 0.120396 0.2794)
			(end -0.12065 0.2794)
			(stroke
				(width 0.1)
				(type default)
			)
			(layer "F.Fab")
		)
		(fp_line
			(start -0.12065 0.3048)
			(end -0.67945 0.3048)
			(stroke
				(width 0.1)
				(type default)
			)
			(layer "F.Fab")
		)
		(fp_line
			(start -0.12065 0.2794)
			(end -0.12065 0.3048)
			(stroke
				(width 0.1)
				(type default)
			)
			(layer "F.Fab")
		)
		(fp_line
			(start -0.12065 -0.2794)
			(end 0.12065 -0.2794)
			(stroke
				(width 0.1)
				(type default)
			)
			(layer "F.Fab")
		)
		(fp_line
			(start -0.12065 -0.305054)
			(end -0.12065 -0.2794)
			(stroke
				(width 0.1)
				(type default)
			)
			(layer "F.Fab")
		)
		(fp_line
			(start -0.67945 0.3048)
			(end -0.67945 -0.305054)
			(stroke
				(width 0.1)
				(type default)
			)
			(layer "F.Fab")
		)
		(fp_line
			(start -0.67945 -0.305054)
			(end -0.12065 -0.305054)
			(stroke
				(width 0.1)
				(type default)
			)
			(layer "F.Fab")
		)
		(pad "1" smd circle
			(at -0.40005 0 180)
			(size 0 0)
			(layers "F.Cu" "F.Mask" "F.Paste")
			(net "FM_P2E_EQA0")
		)
		(pad "2" smd circle
			(at 0.40005 0 180)
			(size 0 0)
			(layers "F.Cu" "F.Mask" "F.Paste")
			(net "GND")
		)
	)
	(footprint ""
		(layer "F.Cu")
		(at 141.624812 -50.556414)
		(property "Reference" "C6027"
			(at 0 0 0)
			(layer "F.SilkS")
			(hide yes)
			(effects
				(font
					(size 1.27 1.27)
				)
			)
		)
		(property "Value" ""
			(at 0 0 0)
			(layer "F.Fab")
			(effects
				(font
					(size 1.27 1.27)
				)
			)
		)
		(duplicate_pad_numbers_are_jumpers no)
		(fp_line
			(start -1.524 -0.762)
			(end 1.524 -0.762)
			(stroke
				(width 0.1524)
				(type default)
			)
			(layer "F.SilkS")
		)
		(fp_line
			(start -1.524 0.762)
			(end -1.524 -0.762)
			(stroke
				(width 0.1524)
				(type default)
			)
			(layer "F.SilkS")
		)
		(fp_line
			(start 1.524 -0.762)
			(end 1.524 0.762)
			(stroke
				(width 0.1524)
				(type default)
			)
			(layer "F.SilkS")
		)
		(fp_line
			(start 1.524 0.762)
			(end -1.524 0.762)
			(stroke
				(width 0.1524)
				(type default)
			)
			(layer "F.SilkS")
		)
		(fp_line
			(start -1.1049 -0.724916)
			(end -1.1049 0.724916)
			(stroke
				(width 0.1)
				(type default)
			)
			(layer "F.Fab")
		)
		(fp_line
			(start -1.1049 0.724916)
			(end 1.1049 0.724916)
			(stroke
				(width 0.1)
				(type default)
			)
			(layer "F.Fab")
		)
		(fp_line
			(start 1.1049 -0.724916)
			(end -1.1049 -0.724916)
			(stroke
				(width 0.1)
				(type default)
			)
			(layer "F.Fab")
		)
		(fp_line
			(start 1.1049 0.724916)
			(end 1.1049 -0.724916)
			(stroke
				(width 0.1)
				(type default)
			)
			(layer "F.Fab")
		)
		(pad "1" smd rect
			(at -0.889 0 180)
			(size 1.016 1.27)
			(layers "F.Cu" "F.Mask" "F.Paste")
			(net "P5V_AUX")
		)
		(pad "2" smd rect
			(at 0.889 0 180)
			(size 1.016 1.27)
			(layers "F.Cu" "F.Mask" "F.Paste")
			(net "GND")
		)
	)
	(footprint ""
		(layer "F.Cu")
		(at 416.179 -99.441 -90)
		(property "Reference" "U8001"
			(at -3.030474 1.59004 0)
			(unlocked yes)
			(layer "F.SilkS")
			(effects
				(font
					(size 0.7874 0.5842)
					(thickness 0.1524)
				)
				(justify left)
			)
		)
		(property "Value" ""
			(at 0 0 270)
			(layer "F.Fab")
			(effects
				(font
					(size 1.27 1.27)
				)
			)
		)
		(duplicate_pad_numbers_are_jumpers no)
		(fp_line
			(start -1.759712 1.500124)
			(end -1.759712 -1.500124)
			(stroke
				(width 0.1524)
				(type default)
			)
			(layer "F.SilkS")
		)
		(fp_line
			(start 1.759712 1.500124)
			(end -1.759712 1.500124)
			(stroke
				(width 0.1524)
				(type default)
			)
			(layer "F.SilkS")
		)
		(fp_line
			(start -1.759712 -1.500124)
			(end 1.759712 -1.500124)
			(stroke
				(width 0.1524)
				(type default)
			)
			(layer "F.SilkS")
		)
		(fp_line
			(start 1.759712 -1.500124)
			(end 1.759712 1.500124)
			(stroke
				(width 0.1524)
				(type default)
			)
			(layer "F.SilkS")
		)
		(fp_line
			(start -0.700024 1.500124)
			(end -0.700024 -1.500124)
			(stroke
				(width 0.1)
				(type default)
			)
			(layer "F.Fab")
		)
		(fp_line
			(start 0.700024 1.500124)
			(end -0.700024 1.500124)
			(stroke
				(width 0.1)
				(type default)
			)
			(layer "F.Fab")
		)
		(fp_line
			(start -0.700024 -1.500124)
			(end 0.700024 -1.500124)
			(stroke
				(width 0.1)
				(type default)
			)
			(layer "F.Fab")
		)
		(fp_line
			(start 0.700024 -1.500124)
			(end 0.700024 1.500124)
			(stroke
				(width 0.1)
				(type default)
			)
			(layer "F.Fab")
		)
		(pad "1" smd rect
			(at -1.150112 -0.94996 180)
			(size 0.6604 0.9652)
			(layers "F.Cu" "F.Mask" "F.Paste")
			(net "GND")
		)
		(pad "2" smd rect
			(at -1.150112 0.94996 180)
			(size 0.6604 0.9652)
			(layers "F.Cu" "F.Mask" "F.Paste")
			(net "OCP_V3_1_P3V3_R1_PWRGD")
		)
		(pad "3" smd rect
			(at 1.150112 0 180)
			(size 0.6604 0.9652)
			(layers "F.Cu" "F.Mask" "F.Paste")
			(net "P3V3_OCP_SFF_R")
		)
	)
	(footprint ""
		(layer "F.Cu")
		(at 449.443602 -422.01211 180)
		(property "Reference" "PR6603"
			(at 0 0 180)
			(layer "F.SilkS")
			(hide yes)
			(effects
				(font
					(size 1.27 1.27)
				)
			)
		)
		(property "Value" ""
			(at 0 0 180)
			(layer "F.Fab")
			(effects
				(font
					(size 1.27 1.27)
				)
			)
		)
		(duplicate_pad_numbers_are_jumpers no)
		(fp_line
			(start 0.7874 0.4064)
			(end -0.7874 0.4064)
			(stroke
				(width 0.1524)
				(type default)
			)
			(layer "F.SilkS")
		)
		(fp_line
			(start 0.7874 -0.4064)
			(end 0.7874 0.4064)
			(stroke
				(width 0.1524)
				(type default)
			)
			(layer "F.SilkS")
		)
		(fp_line
			(start -0.7874 0.4064)
			(end -0.7874 -0.4064)
			(stroke
				(width 0.1524)
				(type default)
			)
			(layer "F.SilkS")
		)
		(fp_line
			(start -0.7874 -0.4064)
			(end 0.7874 -0.4064)
			(stroke
				(width 0.1524)
				(type default)
			)
			(layer "F.SilkS")
		)
		(fp_line
			(start 0.67945 0.3048)
			(end 0.120396 0.3048)
			(stroke
				(width 0.1)
				(type default)
			)
			(layer "F.Fab")
		)
		(fp_line
			(start 0.67945 -0.3048)
			(end 0.67945 0.3048)
			(stroke
				(width 0.1)
				(type default)
			)
			(layer "F.Fab")
		)
		(fp_line
			(start 0.12065 -0.2794)
			(end 0.12065 -0.3048)
			(stroke
				(width 0.1)
				(type default)
			)
			(layer "F.Fab")
		)
		(fp_line
			(start 0.12065 -0.3048)
			(end 0.67945 -0.3048)
			(stroke
				(width 0.1)
				(type default)
			)
			(layer "F.Fab")
		)
		(fp_line
			(start 0.120396 0.3048)
			(end 0.120396 0.2794)
			(stroke
				(width 0.1)
				(type default)
			)
			(layer "F.Fab")
		)
		(fp_line
			(start 0.120396 0.2794)
			(end -0.12065 0.2794)
			(stroke
				(width 0.1)
				(type default)
			)
			(layer "F.Fab")
		)
		(fp_line
			(start -0.12065 0.3048)
			(end -0.67945 0.3048)
			(stroke
				(width 0.1)
				(type default)
			)
			(layer "F.Fab")
		)
		(fp_line
			(start -0.12065 0.2794)
			(end -0.12065 0.3048)
			(stroke
				(width 0.1)
				(type default)
			)
			(layer "F.Fab")
		)
		(fp_line
			(start -0.12065 -0.2794)
			(end 0.12065 -0.2794)
			(stroke
				(width 0.1)
				(type default)
			)
			(layer "F.Fab")
		)
		(fp_line
			(start -0.12065 -0.305054)
			(end -0.12065 -0.2794)
			(stroke
				(width 0.1)
				(type default)
			)
			(layer "F.Fab")
		)
		(fp_line
			(start -0.67945 0.3048)
			(end -0.67945 -0.305054)
			(stroke
				(width 0.1)
				(type default)
			)
			(layer "F.Fab")
		)
		(fp_line
			(start -0.67945 -0.305054)
			(end -0.12065 -0.305054)
			(stroke
				(width 0.1)
				(type default)
			)
			(layer "F.Fab")
		)
		(pad "1" smd circle
			(at -0.40005 0 180)
			(size 0 0)
			(layers "F.Cu" "F.Mask" "F.Paste")
			(net "GND")
		)
		(pad "2" smd circle
			(at 0.40005 0 180)
			(size 0 0)
			(layers "F.Cu" "F.Mask" "F.Paste")
			(net "P0V9_RETIMER_CPU0_ADDR")
		)
	)
	(footprint ""
		(layer "F.Cu")
		(at 423.35704 -435.436772)
		(property "Reference" "Q135"
			(at -1.4224 -1.768348 0)
			(unlocked yes)
			(layer "F.SilkS")
			(effects
				(font
					(size 0.7874 0.5842)
					(thickness 0.1524)
				)
				(justify left)
			)
		)
		(property "Value" ""
			(at 0 0 0)
			(layer "F.Fab")
			(effects
				(font
					(size 1.27 1.27)
				)
			)
		)
		(duplicate_pad_numbers_are_jumpers no)
		(fp_line
			(start -1.332738 -1.100074)
			(end -0.4826 -1.100074)
			(stroke
				(width 0.1524)
				(type default)
			)
			(layer "F.SilkS")
		)
		(fp_line
			(start -1.332738 1.100074)
			(end -1.332738 -1.100074)
			(stroke
				(width 0.1524)
				(type default)
			)
			(layer "F.SilkS")
		)
		(fp_line
			(start -0.4826 -1.100074)
			(end 0 -0.541274)
			(stroke
				(width 0.1524)
				(type default)
			)
			(layer "F.SilkS")
		)
		(fp_line
			(start 0 -0.541274)
			(end 0.4826 -1.100074)
			(stroke
				(width 0.1524)
				(type default)
			)
			(layer "F.SilkS")
		)
		(fp_line
			(start 0.4826 -1.100074)
			(end 1.332738 -1.100074)
			(stroke
				(width 0.1524)
				(type default)
			)
			(layer "F.SilkS")
		)
		(fp_line
			(start 1.332738 -1.100074)
			(end 1.332738 1.100074)
			(stroke
				(width 0.1524)
				(type default)
			)
			(layer "F.SilkS")
		)
		(fp_line
			(start 1.332738 1.100074)
			(end -1.332738 1.100074)
			(stroke
				(width 0.1524)
				(type default)
			)
			(layer "F.SilkS")
		)
		(fp_poly
			(pts
				(xy -1.467104 -1.206246) (xy -2.16916 -0.855218) (xy -2.16916 -1.557274)
			)
			(stroke
				(width 0)
				(type default)
			)
			(fill yes)
			(layer "F.SilkS")
		)
		(fp_line
			(start -0.674878 -1.100074)
			(end 0.674878 -1.100074)
			(stroke
				(width 0.1)
				(type default)
			)
			(layer "F.Fab")
		)
		(fp_line
			(start -0.674878 1.100074)
			(end -0.674878 -1.100074)
			(stroke
				(width 0.1)
				(type default)
			)
			(layer "F.Fab")
		)
		(fp_line
			(start 0.674878 -1.100074)
			(end 0.674878 1.100074)
			(stroke
				(width 0.1)
				(type default)
			)
			(layer "F.Fab")
		)
		(fp_line
			(start 0.674878 1.100074)
			(end -0.674878 1.100074)
			(stroke
				(width 0.1)
				(type default)
			)
			(layer "F.Fab")
		)
		(fp_poly
			(pts
				(xy -2.2352 -0.298958) (xy -2.2352 -1.001014) (xy -1.533144 -0.649986)
			)
			(stroke
				(width 0)
				(type default)
			)
			(fill yes)
			(layer "F.Fab")
		)
		(pad "1" smd rect
			(at -0.94996 -0.649986 90)
			(size 0.4318 0.508)
			(layers "F.Cu" "F.Mask" "F.Paste")
			(net "GND")
		)
		(pad "2" smd rect
			(at -0.94996 0 90)
			(size 0.4318 0.508)
			(layers "F.Cu" "F.Mask" "F.Paste")
			(net "GPU_3V3IO_RSVD1")
		)
		(pad "3" smd rect
			(at -0.94996 0.649986 90)
			(size 0.4318 0.508)
			(layers "F.Cu" "F.Mask" "F.Paste")
			(net "GPU_3V3IO_RSVD1_ISO")
		)
		(pad "4" smd rect
			(at 0.94996 0.649986 90)
			(size 0.4318 0.508)
			(layers "F.Cu" "F.Mask" "F.Paste")
			(net "GND")
		)
		(pad "5" smd rect
			(at 0.94996 0 90)
			(size 0.4318 0.508)
			(layers "F.Cu" "F.Mask" "F.Paste")
			(net "GPU_3V3IO_RSVD1_N")
		)
		(pad "6" smd rect
			(at 0.94996 -0.649986 90)
			(size 0.4318 0.508)
			(layers "F.Cu" "F.Mask" "F.Paste")
			(net "GPU_3V3IO_RSVD1_N")
		)
	)
	(footprint ""
		(layer "F.Cu")
		(at 291.799772 -18.983452)
		(property "Reference" "R4182"
			(at 0 0 0)
			(layer "F.SilkS")
			(hide yes)
			(effects
				(font
					(size 1.27 1.27)
				)
			)
		)
		(property "Value" ""
			(at 0 0 0)
			(layer "F.Fab")
			(effects
				(font
					(size 1.27 1.27)
				)
			)
		)
		(duplicate_pad_numbers_are_jumpers no)
		(fp_line
			(start -0.7874 -0.4064)
			(end 0.7874 -0.4064)
			(stroke
				(width 0.1524)
				(type default)
			)
			(layer "F.SilkS")
		)
		(fp_line
			(start -0.7874 0.4064)
			(end -0.7874 -0.4064)
			(stroke
				(width 0.1524)
				(type default)
			)
			(layer "F.SilkS")
		)
		(fp_line
			(start 0.7874 -0.4064)
			(end 0.7874 0.4064)
			(stroke
				(width 0.1524)
				(type default)
			)
			(layer "F.SilkS")
		)
		(fp_line
			(start 0.7874 0.4064)
			(end -0.7874 0.4064)
			(stroke
				(width 0.1524)
				(type default)
			)
			(layer "F.SilkS")
		)
		(fp_line
			(start -0.67945 -0.305054)
			(end -0.12065 -0.305054)
			(stroke
				(width 0.1)
				(type default)
			)
			(layer "F.Fab")
		)
		(fp_line
			(start -0.67945 0.3048)
			(end -0.67945 -0.305054)
			(stroke
				(width 0.1)
				(type default)
			)
			(layer "F.Fab")
		)
		(fp_line
			(start -0.12065 -0.305054)
			(end -0.12065 -0.2794)
			(stroke
				(width 0.1)
				(type default)
			)
			(layer "F.Fab")
		)
		(fp_line
			(start -0.12065 -0.2794)
			(end 0.12065 -0.2794)
			(stroke
				(width 0.1)
				(type default)
			)
			(layer "F.Fab")
		)
		(fp_line
			(start -0.12065 0.2794)
			(end -0.12065 0.3048)
			(stroke
				(width 0.1)
				(type default)
			)
			(layer "F.Fab")
		)
		(fp_line
			(start -0.12065 0.3048)
			(end -0.67945 0.3048)
			(stroke
				(width 0.1)
				(type default)
			)
			(layer "F.Fab")
		)
		(fp_line
			(start 0.120396 0.2794)
			(end -0.12065 0.2794)
			(stroke
				(width 0.1)
				(type default)
			)
			(layer "F.Fab")
		)
		(fp_line
			(start 0.120396 0.3048)
			(end 0.120396 0.2794)
			(stroke
				(width 0.1)
				(type default)
			)
			(layer "F.Fab")
		)
		(fp_line
			(start 0.12065 -0.3048)
			(end 0.67945 -0.3048)
			(stroke
				(width 0.1)
				(type default)
			)
			(layer "F.Fab")
		)
		(fp_line
			(start 0.12065 -0.2794)
			(end 0.12065 -0.3048)
			(stroke
				(width 0.1)
				(type default)
			)
			(layer "F.Fab")
		)
		(fp_line
			(start 0.67945 -0.3048)
			(end 0.67945 0.3048)
			(stroke
				(width 0.1)
				(type default)
			)
			(layer "F.Fab")
		)
		(fp_line
			(start 0.67945 0.3048)
			(end 0.120396 0.3048)
			(stroke
				(width 0.1)
				(type default)
			)
			(layer "F.Fab")
		)
		(pad "1" smd circle
			(at -0.40005 0)
			(size 0 0)
			(layers "F.Cu" "F.Mask" "F.Paste")
			(net "SMB_LM75_1_3V3AUX_SDA")
		)
		(pad "2" smd circle
			(at 0.40005 0)
			(size 0 0)
			(layers "F.Cu" "F.Mask" "F.Paste")
			(net "SMB_LM75_1_3V3AUX_SDA_R1")
		)
	)
	(footprint ""
		(layer "F.Cu")
		(at 370.225066 -424.002962 90)
		(property "Reference" "R4191"
			(at 0 0 90)
			(layer "F.SilkS")
			(hide yes)
			(effects
				(font
					(size 1.27 1.27)
				)
			)
		)
		(property "Value" ""
			(at 0 0 90)
			(layer "F.Fab")
			(effects
				(font
					(size 1.27 1.27)
				)
			)
		)
		(duplicate_pad_numbers_are_jumpers no)
		(fp_line
			(start 0.7874 -0.4064)
			(end 0.7874 0.4064)
			(stroke
				(width 0.1524)
				(type default)
			)
			(layer "F.SilkS")
		)
		(fp_line
			(start -0.7874 -0.4064)
			(end 0.7874 -0.4064)
			(stroke
				(width 0.1524)
				(type default)
			)
			(layer "F.SilkS")
		)
		(fp_line
			(start 0.7874 0.4064)
			(end -0.7874 0.4064)
			(stroke
				(width 0.1524)
				(type default)
			)
			(layer "F.SilkS")
		)
		(fp_line
			(start -0.7874 0.4064)
			(end -0.7874 -0.4064)
			(stroke
				(width 0.1524)
				(type default)
			)
			(layer "F.SilkS")
		)
		(fp_line
			(start -0.12065 -0.305054)
			(end -0.12065 -0.2794)
			(stroke
				(width 0.1)
				(type default)
			)
			(layer "F.Fab")
		)
		(fp_line
			(start -0.67945 -0.305054)
			(end -0.12065 -0.305054)
			(stroke
				(width 0.1)
				(type default)
			)
			(layer "F.Fab")
		)
		(fp_line
			(start 0.67945 -0.3048)
			(end 0.67945 0.3048)
			(stroke
				(width 0.1)
				(type default)
			)
			(layer "F.Fab")
		)
		(fp_line
			(start 0.12065 -0.3048)
			(end 0.67945 -0.3048)
			(stroke
				(width 0.1)
				(type default)
			)
			(layer "F.Fab")
		)
		(fp_line
			(start 0.12065 -0.2794)
			(end 0.12065 -0.3048)
			(stroke
				(width 0.1)
				(type default)
			)
			(layer "F.Fab")
		)
		(fp_line
			(start -0.12065 -0.2794)
			(end 0.12065 -0.2794)
			(stroke
				(width 0.1)
				(type default)
			)
			(layer "F.Fab")
		)
		(fp_line
			(start 0.120396 0.2794)
			(end -0.12065 0.2794)
			(stroke
				(width 0.1)
				(type default)
			)
			(layer "F.Fab")
		)
		(fp_line
			(start -0.12065 0.2794)
			(end -0.12065 0.3048)
			(stroke
				(width 0.1)
				(type default)
			)
			(layer "F.Fab")
		)
		(fp_line
			(start 0.67945 0.3048)
			(end 0.120396 0.3048)
			(stroke
				(width 0.1)
				(type default)
			)
			(layer "F.Fab")
		)
		(fp_line
			(start 0.120396 0.3048)
			(end 0.120396 0.2794)
			(stroke
				(width 0.1)
				(type default)
			)
			(layer "F.Fab")
		)
		(fp_line
			(start -0.12065 0.3048)
			(end -0.67945 0.3048)
			(stroke
				(width 0.1)
				(type default)
			)
			(layer "F.Fab")
		)
		(fp_line
			(start -0.67945 0.3048)
			(end -0.67945 -0.305054)
			(stroke
				(width 0.1)
				(type default)
			)
			(layer "F.Fab")
		)
		(pad "1" smd circle
			(at -0.40005 0 90)
			(size 0 0)
			(layers "F.Cu" "F.Mask" "F.Paste")
			(net "U270_0_ADD2")
		)
		(pad "2" smd circle
			(at 0.40005 0 90)
			(size 0 0)
			(layers "F.Cu" "F.Mask" "F.Paste")
			(net "GND")
		)
	)
	(footprint ""
		(layer "F.Cu")
		(at 54.30266 -351.372932 90)
		(property "Reference" "PR279"
			(at 0 0 90)
			(layer "F.SilkS")
			(hide yes)
			(effects
				(font
					(size 1.27 1.27)
				)
			)
		)
		(property "Value" ""
			(at 0 0 90)
			(layer "F.Fab")
			(effects
				(font
					(size 1.27 1.27)
				)
			)
		)
		(duplicate_pad_numbers_are_jumpers no)
		(fp_line
			(start 0.7874 -0.4064)
			(end 0.7874 0.4064)
			(stroke
				(width 0.1524)
				(type default)
			)
			(layer "F.SilkS")
		)
		(fp_line
			(start -0.7874 -0.4064)
			(end 0.7874 -0.4064)
			(stroke
				(width 0.1524)
				(type default)
			)
			(layer "F.SilkS")
		)
		(fp_line
			(start 0.7874 0.4064)
			(end -0.7874 0.4064)
			(stroke
				(width 0.1524)
				(type default)
			)
			(layer "F.SilkS")
		)
		(fp_line
			(start -0.7874 0.4064)
			(end -0.7874 -0.4064)
			(stroke
				(width 0.1524)
				(type default)
			)
			(layer "F.SilkS")
		)
		(fp_line
			(start -0.12065 -0.305054)
			(end -0.12065 -0.2794)
			(stroke
				(width 0.1)
				(type default)
			)
			(layer "F.Fab")
		)
		(fp_line
			(start -0.67945 -0.305054)
			(end -0.12065 -0.305054)
			(stroke
				(width 0.1)
				(type default)
			)
			(layer "F.Fab")
		)
		(fp_line
			(start 0.67945 -0.3048)
			(end 0.67945 0.3048)
			(stroke
				(width 0.1)
				(type default)
			)
			(layer "F.Fab")
		)
		(fp_line
			(start 0.12065 -0.3048)
			(end 0.67945 -0.3048)
			(stroke
				(width 0.1)
				(type default)
			)
			(layer "F.Fab")
		)
		(fp_line
			(start 0.12065 -0.2794)
			(end 0.12065 -0.3048)
			(stroke
				(width 0.1)
				(type default)
			)
			(layer "F.Fab")
		)
		(fp_line
			(start -0.12065 -0.2794)
			(end 0.12065 -0.2794)
			(stroke
				(width 0.1)
				(type default)
			)
			(layer "F.Fab")
		)
		(fp_line
			(start 0.120396 0.2794)
			(end -0.12065 0.2794)
			(stroke
				(width 0.1)
				(type default)
			)
			(layer "F.Fab")
		)
		(fp_line
			(start -0.12065 0.2794)
			(end -0.12065 0.3048)
			(stroke
				(width 0.1)
				(type default)
			)
			(layer "F.Fab")
		)
		(fp_line
			(start 0.67945 0.3048)
			(end 0.120396 0.3048)
			(stroke
				(width 0.1)
				(type default)
			)
			(layer "F.Fab")
		)
		(fp_line
			(start 0.120396 0.3048)
			(end 0.120396 0.2794)
			(stroke
				(width 0.1)
				(type default)
			)
			(layer "F.Fab")
		)
		(fp_line
			(start -0.12065 0.3048)
			(end -0.67945 0.3048)
			(stroke
				(width 0.1)
				(type default)
			)
			(layer "F.Fab")
		)
		(fp_line
			(start -0.67945 0.3048)
			(end -0.67945 -0.305054)
			(stroke
				(width 0.1)
				(type default)
			)
			(layer "F.Fab")
		)
		(pad "1" smd circle
			(at -0.40005 0 90)
			(size 0 0)
			(layers "F.Cu" "F.Mask" "F.Paste")
			(net "SW_PVDDIO_P1_BOOT1")
		)
		(pad "2" smd circle
			(at 0.40005 0 90)
			(size 0 0)
			(layers "F.Cu" "F.Mask" "F.Paste")
			(net "SW_PVDDIO_P1_BOOT1_R")
		)
	)
	(footprint ""
		(layer "F.Cu")
		(at 450.508878 -399.340578 90)
		(property "Reference" "PC6575"
			(at 0 0 90)
			(layer "F.SilkS")
			(hide yes)
			(effects
				(font
					(size 1.27 1.27)
				)
			)
		)
		(property "Value" ""
			(at 0 0 90)
			(layer "F.Fab")
			(effects
				(font
					(size 1.27 1.27)
				)
			)
		)
		(duplicate_pad_numbers_are_jumpers no)
		(fp_line
			(start 0.7874 -0.4064)
			(end 0.7874 -0.192278)
			(stroke
				(width 0.1524)
				(type default)
			)
			(layer "F.SilkS")
		)
		(fp_line
			(start -0.7874 -0.4064)
			(end 0.7874 -0.4064)
			(stroke
				(width 0.1524)
				(type default)
			)
			(layer "F.SilkS")
		)
		(fp_line
			(start 0.455422 0.4064)
			(end -0.7874 0.4064)
			(stroke
				(width 0.1524)
				(type default)
			)
			(layer "F.SilkS")
		)
		(fp_line
			(start -0.7874 0.4064)
			(end -0.7874 -0.4064)
			(stroke
				(width 0.1524)
				(type default)
			)
			(layer "F.SilkS")
		)
		(fp_line
			(start -0.12065 -0.305054)
			(end -0.12065 -0.2794)
			(stroke
				(width 0.1)
				(type default)
			)
			(layer "F.Fab")
		)
		(fp_line
			(start -0.67945 -0.305054)
			(end -0.12065 -0.305054)
			(stroke
				(width 0.1)
				(type default)
			)
			(layer "F.Fab")
		)
		(fp_line
			(start 0.67945 -0.3048)
			(end 0.67945 0.3048)
			(stroke
				(width 0.1)
				(type default)
			)
			(layer "F.Fab")
		)
		(fp_line
			(start 0.12065 -0.3048)
			(end 0.67945 -0.3048)
			(stroke
				(width 0.1)
				(type default)
			)
			(layer "F.Fab")
		)
		(fp_line
			(start 0.12065 -0.2794)
			(end 0.12065 -0.3048)
			(stroke
				(width 0.1)
				(type default)
			)
			(layer "F.Fab")
		)
		(fp_line
			(start -0.12065 -0.2794)
			(end 0.12065 -0.2794)
			(stroke
				(width 0.1)
				(type default)
			)
			(layer "F.Fab")
		)
		(fp_line
			(start 0.120396 0.2794)
			(end -0.12065 0.2794)
			(stroke
				(width 0.1)
				(type default)
			)
			(layer "F.Fab")
		)
		(fp_line
			(start -0.12065 0.2794)
			(end -0.12065 0.3048)
			(stroke
				(width 0.1)
				(type default)
			)
			(layer "F.Fab")
		)
		(fp_line
			(start 0.67945 0.3048)
			(end 0.120396 0.3048)
			(stroke
				(width 0.1)
				(type default)
			)
			(layer "F.Fab")
		)
		(fp_line
			(start 0.120396 0.3048)
			(end 0.120396 0.2794)
			(stroke
				(width 0.1)
				(type default)
			)
			(layer "F.Fab")
		)
		(fp_line
			(start -0.12065 0.3048)
			(end -0.67945 0.3048)
			(stroke
				(width 0.1)
				(type default)
			)
			(layer "F.Fab")
		)
		(fp_line
			(start -0.67945 0.3048)
			(end -0.67945 -0.305054)
			(stroke
				(width 0.1)
				(type default)
			)
			(layer "F.Fab")
		)
		(pad "1" smd circle
			(at -0.40005 0 90)
			(size 0 0)
			(layers "F.Cu" "F.Mask" "F.Paste")
			(net "P0V9_RETIMER_CPU0_VCC2")
		)
		(pad "2" smd circle
			(at 0.40005 0 90)
			(size 0 0)
			(layers "F.Cu" "F.Mask" "F.Paste")
			(net "GND")
		)
	)
	(footprint ""
		(layer "F.Cu")
		(at 76.252324 -408.517344 -90)
		(property "Reference" "C6647"
			(at 0 0 270)
			(layer "F.SilkS")
			(hide yes)
			(effects
				(font
					(size 1.27 1.27)
				)
			)
		)
		(property "Value" ""
			(at 0 0 270)
			(layer "F.Fab")
			(effects
				(font
					(size 1.27 1.27)
				)
			)
		)
		(duplicate_pad_numbers_are_jumpers no)
		(fp_line
			(start -0.299974 0.150114)
			(end -0.299974 -0.150114)
			(stroke
				(width 0.1)
				(type default)
			)
			(layer "F.Fab")
		)
		(fp_line
			(start 0.299974 0.150114)
			(end -0.299974 0.150114)
			(stroke
				(width 0.1)
				(type default)
			)
			(layer "F.Fab")
		)
		(fp_line
			(start -0.299974 -0.150114)
			(end 0.299974 -0.150114)
			(stroke
				(width 0.1)
				(type default)
			)
			(layer "F.Fab")
		)
		(fp_line
			(start 0.299974 -0.150114)
			(end 0.299974 0.150114)
			(stroke
				(width 0.1)
				(type default)
			)
			(layer "F.Fab")
		)
		(pad "1" smd rect
			(at -0.2667 0 270)
			(size 0.3048 0.381)
			(layers "F.Cu" "F.Mask" "F.Paste")
			(net "P5E_CPU1_P0_TX_BUF_C_DP<9>")
		)
		(pad "2" smd rect
			(at 0.2667 0 270)
			(size 0.3048 0.381)
			(layers "F.Cu" "F.Mask" "F.Paste")
			(net "P5E_CPU1_P0_TX_BUF_DP<9>")
		)
	)
	(footprint ""
		(layer "F.Cu")
		(at 66.635122 -148.335746 180)
		(property "Reference" "PC19"
			(at 0 0 180)
			(layer "F.SilkS")
			(hide yes)
			(effects
				(font
					(size 1.27 1.27)
				)
			)
		)
		(property "Value" ""
			(at 0 0 180)
			(layer "F.Fab")
			(effects
				(font
					(size 1.27 1.27)
				)
			)
		)
		(duplicate_pad_numbers_are_jumpers no)
		(fp_line
			(start 0.7874 0.4064)
			(end -0.7874 0.4064)
			(stroke
				(width 0.1524)
				(type default)
			)
			(layer "F.SilkS")
		)
		(fp_line
			(start 0.7874 -0.4064)
			(end 0.7874 0.4064)
			(stroke
				(width 0.1524)
				(type default)
			)
			(layer "F.SilkS")
		)
		(fp_line
			(start -0.7874 0.4064)
			(end -0.7874 -0.4064)
			(stroke
				(width 0.1524)
				(type default)
			)
			(layer "F.SilkS")
		)
		(fp_line
			(start -0.7874 -0.4064)
			(end 0.7874 -0.4064)
			(stroke
				(width 0.1524)
				(type default)
			)
			(layer "F.SilkS")
		)
		(fp_line
			(start 0.67945 0.3048)
			(end 0.120396 0.3048)
			(stroke
				(width 0.1)
				(type default)
			)
			(layer "F.Fab")
		)
		(fp_line
			(start 0.67945 -0.3048)
			(end 0.67945 0.3048)
			(stroke
				(width 0.1)
				(type default)
			)
			(layer "F.Fab")
		)
		(fp_line
			(start 0.12065 -0.2794)
			(end 0.12065 -0.3048)
			(stroke
				(width 0.1)
				(type default)
			)
			(layer "F.Fab")
		)
		(fp_line
			(start 0.12065 -0.3048)
			(end 0.67945 -0.3048)
			(stroke
				(width 0.1)
				(type default)
			)
			(layer "F.Fab")
		)
		(fp_line
			(start 0.120396 0.3048)
			(end 0.120396 0.2794)
			(stroke
				(width 0.1)
				(type default)
			)
			(layer "F.Fab")
		)
		(fp_line
			(start 0.120396 0.2794)
			(end -0.12065 0.2794)
			(stroke
				(width 0.1)
				(type default)
			)
			(layer "F.Fab")
		)
		(fp_line
			(start -0.12065 0.3048)
			(end -0.67945 0.3048)
			(stroke
				(width 0.1)
				(type default)
			)
			(layer "F.Fab")
		)
		(fp_line
			(start -0.12065 0.2794)
			(end -0.12065 0.3048)
			(stroke
				(width 0.1)
				(type default)
			)
			(layer "F.Fab")
		)
		(fp_line
			(start -0.12065 -0.2794)
			(end 0.12065 -0.2794)
			(stroke
				(width 0.1)
				(type default)
			)
			(layer "F.Fab")
		)
		(fp_line
			(start -0.12065 -0.305054)
			(end -0.12065 -0.2794)
			(stroke
				(width 0.1)
				(type default)
			)
			(layer "F.Fab")
		)
		(fp_line
			(start -0.67945 0.3048)
			(end -0.67945 -0.305054)
			(stroke
				(width 0.1)
				(type default)
			)
			(layer "F.Fab")
		)
		(fp_line
			(start -0.67945 -0.305054)
			(end -0.12065 -0.305054)
			(stroke
				(width 0.1)
				(type default)
			)
			(layer "F.Fab")
		)
		(pad "1" smd circle
			(at -0.40005 0 180)
			(size 0 0)
			(layers "F.Cu" "F.Mask" "F.Paste")
			(net "SW_PVDD18_S5_P1_BST_R")
		)
		(pad "2" smd circle
			(at 0.40005 0 180)
			(size 0 0)
			(layers "F.Cu" "F.Mask" "F.Paste")
			(net "SW_PVDD18_S5_P1_SW")
		)
	)
	(footprint ""
		(layer "F.Cu")
		(at 251.16409 -49.137062 -90)
		(property "Reference" "PC2206"
			(at 0 0 270)
			(layer "F.SilkS")
			(hide yes)
			(effects
				(font
					(size 1.27 1.27)
				)
			)
		)
		(property "Value" ""
			(at 0 0 270)
			(layer "F.Fab")
			(effects
				(font
					(size 1.27 1.27)
				)
			)
		)
		(duplicate_pad_numbers_are_jumpers no)
		(fp_line
			(start -0.7874 0.4064)
			(end -0.7874 -0.4064)
			(stroke
				(width 0.1524)
				(type default)
			)
			(layer "F.SilkS")
		)
		(fp_line
			(start 0.7874 0.4064)
			(end -0.7874 0.4064)
			(stroke
				(width 0.1524)
				(type default)
			)
			(layer "F.SilkS")
		)
		(fp_line
			(start -0.7874 -0.4064)
			(end 0.7874 -0.4064)
			(stroke
				(width 0.1524)
				(type default)
			)
			(layer "F.SilkS")
		)
		(fp_line
			(start 0.7874 -0.4064)
			(end 0.7874 0.4064)
			(stroke
				(width 0.1524)
				(type default)
			)
			(layer "F.SilkS")
		)
		(fp_line
			(start -0.67945 0.3048)
			(end -0.67945 -0.305054)
			(stroke
				(width 0.1)
				(type default)
			)
			(layer "F.Fab")
		)
		(fp_line
			(start -0.12065 0.3048)
			(end -0.67945 0.3048)
			(stroke
				(width 0.1)
				(type default)
			)
			(layer "F.Fab")
		)
		(fp_line
			(start 0.120396 0.3048)
			(end 0.120396 0.2794)
			(stroke
				(width 0.1)
				(type default)
			)
			(layer "F.Fab")
		)
		(fp_line
			(start 0.67945 0.3048)
			(end 0.120396 0.3048)
			(stroke
				(width 0.1)
				(type default)
			)
			(layer "F.Fab")
		)
		(fp_line
			(start -0.12065 0.2794)
			(end -0.12065 0.3048)
			(stroke
				(width 0.1)
				(type default)
			)
			(layer "F.Fab")
		)
		(fp_line
			(start 0.120396 0.2794)
			(end -0.12065 0.2794)
			(stroke
				(width 0.1)
				(type default)
			)
			(layer "F.Fab")
		)
		(fp_line
			(start -0.12065 -0.2794)
			(end 0.12065 -0.2794)
			(stroke
				(width 0.1)
				(type default)
			)
			(layer "F.Fab")
		)
		(fp_line
			(start 0.12065 -0.2794)
			(end 0.12065 -0.3048)
			(stroke
				(width 0.1)
				(type default)
			)
			(layer "F.Fab")
		)
		(fp_line
			(start 0.12065 -0.3048)
			(end 0.67945 -0.3048)
			(stroke
				(width 0.1)
				(type default)
			)
			(layer "F.Fab")
		)
		(fp_line
			(start 0.67945 -0.3048)
			(end 0.67945 0.3048)
			(stroke
				(width 0.1)
				(type default)
			)
			(layer "F.Fab")
		)
		(fp_line
			(start -0.67945 -0.305054)
			(end -0.12065 -0.305054)
			(stroke
				(width 0.1)
				(type default)
			)
			(layer "F.Fab")
		)
		(fp_line
			(start -0.12065 -0.305054)
			(end -0.12065 -0.2794)
			(stroke
				(width 0.1)
				(type default)
			)
			(layer "F.Fab")
		)
		(pad "1" smd circle
			(at -0.40005 0 270)
			(size 0 0)
			(layers "F.Cu" "F.Mask" "F.Paste")
			(net "P12V_E1S_0")
		)
		(pad "2" smd circle
			(at 0.40005 0 270)
			(size 0 0)
			(layers "F.Cu" "F.Mask" "F.Paste")
			(net "GND")
		)
	)
	(footprint ""
		(layer "F.Cu")
		(at 231.540558 -401.920202 180)
		(property "Reference" "PU297"
			(at 2.622804 -5.10286 90)
			(unlocked yes)
			(layer "F.SilkS")
			(effects
				(font
					(size 0.7874 0.5842)
					(thickness 0.1524)
				)
			)
		)
		(property "Value" ""
			(at 0 0 180)
			(layer "F.Fab")
			(effects
				(font
					(size 1.27 1.27)
				)
			)
		)
		(duplicate_pad_numbers_are_jumpers no)
		(fp_line
			(start 2.567686 2.567686)
			(end 2.567686 -2.567686)
			(stroke
				(width 0.1524)
				(type default)
			)
			(layer "F.SilkS")
		)
		(fp_line
			(start 2.567686 -2.567686)
			(end -2.567686 -2.567686)
			(stroke
				(width 0.1524)
				(type default)
			)
			(layer "F.SilkS")
		)
		(fp_line
			(start -2.567686 2.567686)
			(end 2.567686 2.567686)
			(stroke
				(width 0.1524)
				(type default)
			)
			(layer "F.SilkS")
		)
		(fp_line
			(start -2.567686 -2.567686)
			(end -2.567686 2.567686)
			(stroke
				(width 0.1524)
				(type default)
			)
			(layer "F.SilkS")
		)
		(fp_poly
			(pts
				(xy -2.632456 -2.13233) (xy -3.709924 -2.491486) (xy -2.991612 -3.209798)
			)
			(stroke
				(width 0)
				(type default)
			)
			(fill yes)
			(layer "F.SilkS")
		)
		(fp_line
			(start 2.549906 2.549906)
			(end 2.549906 -2.549906)
			(stroke
				(width 0.1)
				(type default)
			)
			(layer "F.Fab")
		)
		(fp_line
			(start 2.549906 -2.549906)
			(end -2.549906 -2.549906)
			(stroke
				(width 0.1)
				(type default)
			)
			(layer "F.Fab")
		)
		(fp_line
			(start -2.549906 2.549906)
			(end 2.549906 2.549906)
			(stroke
				(width 0.1)
				(type default)
			)
			(layer "F.Fab")
		)
		(fp_line
			(start -2.549906 -2.549906)
			(end -2.549906 2.549906)
			(stroke
				(width 0.1)
				(type default)
			)
			(layer "F.Fab")
		)
		(fp_poly
			(pts
				(xy -3.806698 -2.25806) (xy -3.806698 -1.24206) (xy -2.790698 -1.75006)
			)
			(stroke
				(width 0)
				(type default)
			)
			(fill yes)
			(layer "F.Fab")
		)
		(pad "1" smd rect
			(at -2.250186 -1.75006 270)
			(size 0.254 0.3556)
			(layers "F.Cu" "F.Mask" "F.Paste")
			(net "P12V_AUX")
		)
		(pad "2" smd rect
			(at -2.237486 -1.249934 270)
			(size 0.254 0.381)
			(layers "F.Cu" "F.Mask" "F.Paste")
			(net "P12V_AUX")
		)
		(pad "3" smd rect
			(at -2.237486 -0.750062 270)
			(size 0.254 0.381)
			(layers "F.Cu" "F.Mask" "F.Paste")
			(net "HSC_D_OC_4")
		)
		(pad "4" smd rect
			(at -2.237486 -0.249936 270)
			(size 0.254 0.381)
			(layers "F.Cu" "F.Mask" "F.Paste")
			(net "HSC_ON")
		)
		(pad "5" smd rect
			(at -2.237486 0.249936 270)
			(size 0.254 0.381)
			(layers "F.Cu" "F.Mask" "F.Paste")
			(net "HSC_FAULT")
		)
		(pad "6" smd rect
			(at -2.237486 0.750062 270)
			(size 0.254 0.381)
			(layers "F.Cu" "F.Mask" "F.Paste")
			(net "HSC_FLT_TYPE_4")
		)
		(pad "7" smd rect
			(at -2.237486 1.249934 270)
			(size 0.254 0.381)
			(layers "F.Cu" "F.Mask" "F.Paste")
			(net "HSC_NC1_4")
		)
		(pad "8" smd rect
			(at -2.250186 1.75006 270)
			(size 0.254 0.3556)
			(layers "F.Cu" "F.Mask" "F.Paste")
			(net "HSC_MODE_4")
		)
		(pad "9" smd rect
			(at -1.75006 2.250186 180)
			(size 0.254 0.3556)
			(layers "F.Cu" "F.Mask" "F.Paste")
			(net "P12V_PSU")
		)
		(pad "10" smd rect
			(at -1.249934 2.237486 180)
			(size 0.254 0.381)
			(layers "F.Cu" "F.Mask" "F.Paste")
			(net "P12V_PSU")
		)
		(pad "11" smd rect
			(at -0.750062 2.237486 180)
			(size 0.254 0.381)
			(layers "F.Cu" "F.Mask" "F.Paste")
			(net "P12V_PSU")
		)
		(pad "12" smd rect
			(at -0.249936 2.237486 180)
			(size 0.254 0.381)
			(layers "F.Cu" "F.Mask" "F.Paste")
			(net "P12V_PSU")
		)
		(pad "13" smd rect
			(at 0.249936 2.237486 180)
			(size 0.254 0.381)
			(layers "F.Cu" "F.Mask" "F.Paste")
			(net "P12V_PSU")
		)
		(pad "14" smd rect
			(at 0.750062 2.237486 180)
			(size 0.254 0.381)
			(layers "F.Cu" "F.Mask" "F.Paste")
			(net "P12V_PSU")
		)
		(pad "15" smd rect
			(at 1.249934 2.237486 180)
			(size 0.254 0.381)
			(layers "F.Cu" "F.Mask" "F.Paste")
			(net "P12V_PSU")
		)
		(pad "16" smd rect
			(at 1.75006 2.250186 180)
			(size 0.254 0.3556)
			(layers "F.Cu" "F.Mask" "F.Paste")
			(net "P12V_PSU")
		)
		(pad "17" smd rect
			(at 2.250186 1.75006 270)
			(size 0.254 0.3556)
			(layers "F.Cu" "F.Mask" "F.Paste")
			(net "HSC_SCREF_4")
		)
		(pad "18" smd rect
			(at 2.237486 1.249934 270)
			(size 0.254 0.381)
			(layers "F.Cu" "F.Mask" "F.Paste")
			(net "HSC_VTEMP")
		)
		(pad "19" smd rect
			(at 2.237486 0.750062 270)
			(size 0.254 0.381)
			(layers "F.Cu" "F.Mask" "F.Paste")
			(net "HSC_SS")
		)
		(pad "20" smd rect
			(at 2.237486 0.249936 270)
			(size 0.254 0.381)
			(layers "F.Cu" "F.Mask" "F.Paste")
			(net "AGND_HSC")
		)
		(pad "21" smd rect
			(at 2.237486 -0.249936 270)
			(size 0.254 0.381)
			(layers "F.Cu" "F.Mask" "F.Paste")
			(net "HSC_VDD_R_4")
		)
		(pad "22" smd rect
			(at 2.237486 -0.750062 270)
			(size 0.254 0.381)
			(layers "F.Cu" "F.Mask" "F.Paste")
			(net "HSC_IMON")
		)
		(pad "23" smd rect
			(at 2.237486 -1.249934 270)
			(size 0.254 0.381)
			(layers "F.Cu" "F.Mask" "F.Paste")
			(net "HSC_CS_4")
		)
		(pad "24" smd rect
			(at 2.250186 -1.75006 270)
			(size 0.254 0.3556)
			(layers "F.Cu" "F.Mask" "F.Paste")
			(net "HSC_OCREF")
		)
		(pad "25" smd rect
			(at 1.75006 -2.250186 180)
			(size 0.254 0.3556)
			(layers "F.Cu" "F.Mask" "F.Paste")
			(net "P12V_AUX")
		)
		(pad "26" smd rect
			(at 1.249934 -2.237486 180)
			(size 0.254 0.381)
			(layers "F.Cu" "F.Mask" "F.Paste")
			(net "P12V_AUX")
		)
		(pad "27" smd rect
			(at 0.750062 -2.237486 180)
			(size 0.254 0.381)
			(layers "F.Cu" "F.Mask" "F.Paste")
			(net "P12V_AUX")
		)
		(pad "28" smd rect
			(at 0.249936 -2.237486 180)
			(size 0.254 0.381)
			(layers "F.Cu" "F.Mask" "F.Paste")
			(net "P12V_AUX")
		)
		(pad "29" smd rect
			(at -0.249936 -2.237486 180)
			(size 0.254 0.381)
			(layers "F.Cu" "F.Mask" "F.Paste")
			(net "P12V_AUX")
		)
		(pad "30" smd rect
			(at -0.750062 -2.237486 180)
			(size 0.254 0.381)
			(layers "F.Cu" "F.Mask" "F.Paste")
			(net "P12V_AUX")
		)
		(pad "31" smd rect
			(at -1.249934 -2.237486 180)
			(size 0.254 0.381)
			(layers "F.Cu" "F.Mask" "F.Paste")
			(net "P12V_AUX")
		)
		(pad "32" smd rect
			(at -1.75006 -2.250186 180)
			(size 0.254 0.3556)
			(layers "F.Cu" "F.Mask" "F.Paste")
			(net "P12V_AUX")
		)
		(pad "33" smd rect
			(at 0 0 180)
			(size 3.4036 3.4036)
			(layers "F.Cu" "F.Mask" "F.Paste")
			(net "P12V_PSU")
		)
		(zone
			(layer "F.Cu")
			(hatch none 0.5)
			(connect_pads
				(clearance 0)
			)
			(min_thickness 0.25)
			(keepout
				(tracks not_allowed)
				(vias allowed)
				(pads allowed)
				(copperpour not_allowed)
				(footprints allowed)
			)
			(placement
				(enabled no)
				(sheetname "")
			)
			(fill
				(thermal_gap 0.5)
				(thermal_bridge_width 0.5)
				(island_removal_mode 0)
			)
			(polygon
				(pts
					(xy 229.518972 -403.479) (xy 229.787958 -403.479) (xy 229.787958 -400.167602) (xy 233.293158 -400.167602)
					(xy 233.293158 -402.428202) (xy 233.536744 -402.428202) (xy 233.536744 -400.472402) (xy 233.562144 -400.472402)
					(xy 233.562144 -399.898616) (xy 232.988358 -399.898616) (xy 232.988358 -399.924016) (xy 230.092758 -399.924016)
					(xy 230.092758 -399.898616) (xy 229.518972 -399.898616) (xy 229.518972 -400.472402) (xy 229.544372 -400.472402)
					(xy 229.544372 -403.368002) (xy 229.518972 -403.368002)
				)
			)
		)
	)
	(footprint ""
		(layer "F.Cu")
		(at 10.7061 -394.22832 -90)
		(property "Reference" "PR6620"
			(at 0 0 270)
			(layer "F.SilkS")
			(hide yes)
			(effects
				(font
					(size 1.27 1.27)
				)
			)
		)
		(property "Value" ""
			(at 0 0 270)
			(layer "F.Fab")
			(effects
				(font
					(size 1.27 1.27)
				)
			)
		)
		(duplicate_pad_numbers_are_jumpers no)
		(fp_line
			(start -0.7874 0.4064)
			(end -0.7874 -0.4064)
			(stroke
				(width 0.1524)
				(type default)
			)
			(layer "F.SilkS")
		)
		(fp_line
			(start 0.7874 0.4064)
			(end -0.7874 0.4064)
			(stroke
				(width 0.1524)
				(type default)
			)
			(layer "F.SilkS")
		)
		(fp_line
			(start -0.7874 -0.4064)
			(end 0.7874 -0.4064)
			(stroke
				(width 0.1524)
				(type default)
			)
			(layer "F.SilkS")
		)
		(fp_line
			(start 0.7874 -0.4064)
			(end 0.7874 0.4064)
			(stroke
				(width 0.1524)
				(type default)
			)
			(layer "F.SilkS")
		)
		(fp_line
			(start -0.67945 0.3048)
			(end -0.67945 -0.305054)
			(stroke
				(width 0.1)
				(type default)
			)
			(layer "F.Fab")
		)
		(fp_line
			(start -0.12065 0.3048)
			(end -0.67945 0.3048)
			(stroke
				(width 0.1)
				(type default)
			)
			(layer "F.Fab")
		)
		(fp_line
			(start 0.120396 0.3048)
			(end 0.120396 0.2794)
			(stroke
				(width 0.1)
				(type default)
			)
			(layer "F.Fab")
		)
		(fp_line
			(start 0.67945 0.3048)
			(end 0.120396 0.3048)
			(stroke
				(width 0.1)
				(type default)
			)
			(layer "F.Fab")
		)
		(fp_line
			(start -0.12065 0.2794)
			(end -0.12065 0.3048)
			(stroke
				(width 0.1)
				(type default)
			)
			(layer "F.Fab")
		)
		(fp_line
			(start 0.120396 0.2794)
			(end -0.12065 0.2794)
			(stroke
				(width 0.1)
				(type default)
			)
			(layer "F.Fab")
		)
		(fp_line
			(start -0.12065 -0.2794)
			(end 0.12065 -0.2794)
			(stroke
				(width 0.1)
				(type default)
			)
			(layer "F.Fab")
		)
		(fp_line
			(start 0.12065 -0.2794)
			(end 0.12065 -0.3048)
			(stroke
				(width 0.1)
				(type default)
			)
			(layer "F.Fab")
		)
		(fp_line
			(start 0.12065 -0.3048)
			(end 0.67945 -0.3048)
			(stroke
				(width 0.1)
				(type default)
			)
			(layer "F.Fab")
		)
		(fp_line
			(start 0.67945 -0.3048)
			(end 0.67945 0.3048)
			(stroke
				(width 0.1)
				(type default)
			)
			(layer "F.Fab")
		)
		(fp_line
			(start -0.67945 -0.305054)
			(end -0.12065 -0.305054)
			(stroke
				(width 0.1)
				(type default)
			)
			(layer "F.Fab")
		)
		(fp_line
			(start -0.12065 -0.305054)
			(end -0.12065 -0.2794)
			(stroke
				(width 0.1)
				(type default)
			)
			(layer "F.Fab")
		)
		(pad "1" smd circle
			(at -0.40005 0 270)
			(size 0 0)
			(layers "F.Cu" "F.Mask" "F.Paste")
			(net "P3V3_AUX")
		)
		(pad "2" smd circle
			(at 0.40005 0 270)
			(size 0 0)
			(layers "F.Cu" "F.Mask" "F.Paste")
			(net "P0V9_RETIMER_CPU1_PVCC")
		)
	)
	(footprint ""
		(layer "F.Cu")
		(at 46.16704 -434.057552 -90)
		(property "Reference" "R3509"
			(at 0 0 270)
			(layer "F.SilkS")
			(hide yes)
			(effects
				(font
					(size 1.27 1.27)
				)
			)
		)
		(property "Value" ""
			(at 0 0 270)
			(layer "F.Fab")
			(effects
				(font
					(size 1.27 1.27)
				)
			)
		)
		(duplicate_pad_numbers_are_jumpers no)
		(fp_line
			(start -0.7874 0.4064)
			(end -0.7874 -0.4064)
			(stroke
				(width 0.1524)
				(type default)
			)
			(layer "F.SilkS")
		)
		(fp_line
			(start 0.7874 0.4064)
			(end -0.7874 0.4064)
			(stroke
				(width 0.1524)
				(type default)
			)
			(layer "F.SilkS")
		)
		(fp_line
			(start -0.7874 -0.4064)
			(end 0.7874 -0.4064)
			(stroke
				(width 0.1524)
				(type default)
			)
			(layer "F.SilkS")
		)
		(fp_line
			(start 0.7874 -0.4064)
			(end 0.7874 0.4064)
			(stroke
				(width 0.1524)
				(type default)
			)
			(layer "F.SilkS")
		)
		(fp_line
			(start -0.67945 0.3048)
			(end -0.67945 -0.305054)
			(stroke
				(width 0.1)
				(type default)
			)
			(layer "F.Fab")
		)
		(fp_line
			(start -0.12065 0.3048)
			(end -0.67945 0.3048)
			(stroke
				(width 0.1)
				(type default)
			)
			(layer "F.Fab")
		)
		(fp_line
			(start 0.120396 0.3048)
			(end 0.120396 0.2794)
			(stroke
				(width 0.1)
				(type default)
			)
			(layer "F.Fab")
		)
		(fp_line
			(start 0.67945 0.3048)
			(end 0.120396 0.3048)
			(stroke
				(width 0.1)
				(type default)
			)
			(layer "F.Fab")
		)
		(fp_line
			(start -0.12065 0.2794)
			(end -0.12065 0.3048)
			(stroke
				(width 0.1)
				(type default)
			)
			(layer "F.Fab")
		)
		(fp_line
			(start 0.120396 0.2794)
			(end -0.12065 0.2794)
			(stroke
				(width 0.1)
				(type default)
			)
			(layer "F.Fab")
		)
		(fp_line
			(start -0.12065 -0.2794)
			(end 0.12065 -0.2794)
			(stroke
				(width 0.1)
				(type default)
			)
			(layer "F.Fab")
		)
		(fp_line
			(start 0.12065 -0.2794)
			(end 0.12065 -0.3048)
			(stroke
				(width 0.1)
				(type default)
			)
			(layer "F.Fab")
		)
		(fp_line
			(start 0.12065 -0.3048)
			(end 0.67945 -0.3048)
			(stroke
				(width 0.1)
				(type default)
			)
			(layer "F.Fab")
		)
		(fp_line
			(start 0.67945 -0.3048)
			(end 0.67945 0.3048)
			(stroke
				(width 0.1)
				(type default)
			)
			(layer "F.Fab")
		)
		(fp_line
			(start -0.67945 -0.305054)
			(end -0.12065 -0.305054)
			(stroke
				(width 0.1)
				(type default)
			)
			(layer "F.Fab")
		)
		(fp_line
			(start -0.12065 -0.305054)
			(end -0.12065 -0.2794)
			(stroke
				(width 0.1)
				(type default)
			)
			(layer "F.Fab")
		)
		(pad "1" smd circle
			(at -0.40005 0 270)
			(size 0 0)
			(layers "F.Cu" "F.Mask" "F.Paste")
			(net "GPU_FPGA_RST_R1_BUF_N")
		)
		(pad "2" smd circle
			(at 0.40005 0 270)
			(size 0 0)
			(layers "F.Cu" "F.Mask" "F.Paste")
			(net "GND")
		)
	)
	(footprint ""
		(layer "F.Cu")
		(at 24.765 -365.76 180)
		(property "Reference" "C8360"
			(at 0 0 180)
			(layer "F.SilkS")
			(hide yes)
			(effects
				(font
					(size 1.27 1.27)
				)
			)
		)
		(property "Value" ""
			(at 0 0 180)
			(layer "F.Fab")
			(effects
				(font
					(size 1.27 1.27)
				)
			)
		)
		(duplicate_pad_numbers_are_jumpers no)
		(fp_line
			(start 0.7874 0.4064)
			(end -0.7874 0.4064)
			(stroke
				(width 0.1524)
				(type default)
			)
			(layer "F.SilkS")
		)
		(fp_line
			(start 0.7874 -0.4064)
			(end 0.7874 0.4064)
			(stroke
				(width 0.1524)
				(type default)
			)
			(layer "F.SilkS")
		)
		(fp_line
			(start -0.7874 0.4064)
			(end -0.7874 -0.4064)
			(stroke
				(width 0.1524)
				(type default)
			)
			(layer "F.SilkS")
		)
		(fp_line
			(start -0.7874 -0.4064)
			(end 0.7874 -0.4064)
			(stroke
				(width 0.1524)
				(type default)
			)
			(layer "F.SilkS")
		)
		(fp_line
			(start 0.67945 0.3048)
			(end 0.120396 0.3048)
			(stroke
				(width 0.1)
				(type default)
			)
			(layer "F.Fab")
		)
		(fp_line
			(start 0.67945 -0.3048)
			(end 0.67945 0.3048)
			(stroke
				(width 0.1)
				(type default)
			)
			(layer "F.Fab")
		)
		(fp_line
			(start 0.12065 -0.2794)
			(end 0.12065 -0.3048)
			(stroke
				(width 0.1)
				(type default)
			)
			(layer "F.Fab")
		)
		(fp_line
			(start 0.12065 -0.3048)
			(end 0.67945 -0.3048)
			(stroke
				(width 0.1)
				(type default)
			)
			(layer "F.Fab")
		)
		(fp_line
			(start 0.120396 0.3048)
			(end 0.120396 0.2794)
			(stroke
				(width 0.1)
				(type default)
			)
			(layer "F.Fab")
		)
		(fp_line
			(start 0.120396 0.2794)
			(end -0.12065 0.2794)
			(stroke
				(width 0.1)
				(type default)
			)
			(layer "F.Fab")
		)
		(fp_line
			(start -0.12065 0.3048)
			(end -0.67945 0.3048)
			(stroke
				(width 0.1)
				(type default)
			)
			(layer "F.Fab")
		)
		(fp_line
			(start -0.12065 0.2794)
			(end -0.12065 0.3048)
			(stroke
				(width 0.1)
				(type default)
			)
			(layer "F.Fab")
		)
		(fp_line
			(start -0.12065 -0.2794)
			(end 0.12065 -0.2794)
			(stroke
				(width 0.1)
				(type default)
			)
			(layer "F.Fab")
		)
		(fp_line
			(start -0.12065 -0.305054)
			(end -0.12065 -0.2794)
			(stroke
				(width 0.1)
				(type default)
			)
			(layer "F.Fab")
		)
		(fp_line
			(start -0.67945 0.3048)
			(end -0.67945 -0.305054)
			(stroke
				(width 0.1)
				(type default)
			)
			(layer "F.Fab")
		)
		(fp_line
			(start -0.67945 -0.305054)
			(end -0.12065 -0.305054)
			(stroke
				(width 0.1)
				(type default)
			)
			(layer "F.Fab")
		)
		(pad "1" smd circle
			(at -0.40005 0 180)
			(size 0 0)
			(layers "F.Cu" "F.Mask" "F.Paste")
			(net "PWRGD_PVDDCR_CPU1_P1_R")
		)
		(pad "2" smd circle
			(at 0.40005 0 180)
			(size 0 0)
			(layers "F.Cu" "F.Mask" "F.Paste")
			(net "GND")
		)
	)
	(footprint ""
		(layer "F.Cu")
		(at 418.21354 -109.231176 90)
		(property "Reference" "PC2161"
			(at 0 0 90)
			(layer "F.SilkS")
			(hide yes)
			(effects
				(font
					(size 1.27 1.27)
				)
			)
		)
		(property "Value" ""
			(at 0 0 90)
			(layer "F.Fab")
			(effects
				(font
					(size 1.27 1.27)
				)
			)
		)
		(duplicate_pad_numbers_are_jumpers no)
		(fp_line
			(start 0.7874 -0.4064)
			(end 0.7874 0.4064)
			(stroke
				(width 0.1524)
				(type default)
			)
			(layer "F.SilkS")
		)
		(fp_line
			(start -0.7874 -0.4064)
			(end 0.7874 -0.4064)
			(stroke
				(width 0.1524)
				(type default)
			)
			(layer "F.SilkS")
		)
		(fp_line
			(start 0.7874 0.4064)
			(end -0.7874 0.4064)
			(stroke
				(width 0.1524)
				(type default)
			)
			(layer "F.SilkS")
		)
		(fp_line
			(start -0.7874 0.4064)
			(end -0.7874 -0.4064)
			(stroke
				(width 0.1524)
				(type default)
			)
			(layer "F.SilkS")
		)
		(fp_line
			(start -0.12065 -0.305054)
			(end -0.12065 -0.2794)
			(stroke
				(width 0.1)
				(type default)
			)
			(layer "F.Fab")
		)
		(fp_line
			(start -0.67945 -0.305054)
			(end -0.12065 -0.305054)
			(stroke
				(width 0.1)
				(type default)
			)
			(layer "F.Fab")
		)
		(fp_line
			(start 0.67945 -0.3048)
			(end 0.67945 0.3048)
			(stroke
				(width 0.1)
				(type default)
			)
			(layer "F.Fab")
		)
		(fp_line
			(start 0.12065 -0.3048)
			(end 0.67945 -0.3048)
			(stroke
				(width 0.1)
				(type default)
			)
			(layer "F.Fab")
		)
		(fp_line
			(start 0.12065 -0.2794)
			(end 0.12065 -0.3048)
			(stroke
				(width 0.1)
				(type default)
			)
			(layer "F.Fab")
		)
		(fp_line
			(start -0.12065 -0.2794)
			(end 0.12065 -0.2794)
			(stroke
				(width 0.1)
				(type default)
			)
			(layer "F.Fab")
		)
		(fp_line
			(start 0.120396 0.2794)
			(end -0.12065 0.2794)
			(stroke
				(width 0.1)
				(type default)
			)
			(layer "F.Fab")
		)
		(fp_line
			(start -0.12065 0.2794)
			(end -0.12065 0.3048)
			(stroke
				(width 0.1)
				(type default)
			)
			(layer "F.Fab")
		)
		(fp_line
			(start 0.67945 0.3048)
			(end 0.120396 0.3048)
			(stroke
				(width 0.1)
				(type default)
			)
			(layer "F.Fab")
		)
		(fp_line
			(start 0.120396 0.3048)
			(end 0.120396 0.2794)
			(stroke
				(width 0.1)
				(type default)
			)
			(layer "F.Fab")
		)
		(fp_line
			(start -0.12065 0.3048)
			(end -0.67945 0.3048)
			(stroke
				(width 0.1)
				(type default)
			)
			(layer "F.Fab")
		)
		(fp_line
			(start -0.67945 0.3048)
			(end -0.67945 -0.305054)
			(stroke
				(width 0.1)
				(type default)
			)
			(layer "F.Fab")
		)
		(pad "1" smd circle
			(at -0.40005 0 90)
			(size 0 0)
			(layers "F.Cu" "F.Mask" "F.Paste")
			(net "P3V3_OCP_DVDT_1")
		)
		(pad "2" smd circle
			(at 0.40005 0 90)
			(size 0 0)
			(layers "F.Cu" "F.Mask" "F.Paste")
			(net "GND")
		)
	)
	(footprint ""
		(layer "F.Cu")
		(at 328.699876 -70.098412 90)
		(property "Reference" "D76"
			(at -3.934714 -0.691642 90)
			(unlocked yes)
			(layer "F.SilkS")
			(effects
				(font
					(size 0.7874 0.5842)
					(thickness 0.1524)
				)
				(justify left)
			)
		)
		(property "Value" ""
			(at 0 0 90)
			(layer "F.Fab")
			(effects
				(font
					(size 1.27 1.27)
				)
			)
		)
		(duplicate_pad_numbers_are_jumpers no)
		(fp_line
			(start 1.16078 -0.4826)
			(end 1.16078 0.4826)
			(stroke
				(width 0.1524)
				(type default)
			)
			(layer "F.SilkS")
		)
		(fp_line
			(start 1.03378 -0.4826)
			(end 1.03378 0.4826)
			(stroke
				(width 0.1524)
				(type default)
			)
			(layer "F.SilkS")
		)
		(fp_line
			(start 0.90678 -0.4826)
			(end 0.90678 0.4826)
			(stroke
				(width 0.1524)
				(type default)
			)
			(layer "F.SilkS")
		)
		(fp_line
			(start -0.64008 -0.4826)
			(end 1.16078 -0.4826)
			(stroke
				(width 0.1524)
				(type default)
			)
			(layer "F.SilkS")
		)
		(fp_line
			(start -0.79248 -0.4826)
			(end 1.03378 -0.4826)
			(stroke
				(width 0.1524)
				(type default)
			)
			(layer "F.SilkS")
		)
		(fp_line
			(start -0.89408 -0.4826)
			(end 0.90678 -0.4826)
			(stroke
				(width 0.1524)
				(type default)
			)
			(layer "F.SilkS")
		)
		(fp_line
			(start 1.16078 0.4826)
			(end -0.64008 0.4826)
			(stroke
				(width 0.1524)
				(type default)
			)
			(layer "F.SilkS")
		)
		(fp_line
			(start 1.03378 0.4826)
			(end -0.79248 0.4826)
			(stroke
				(width 0.1524)
				(type default)
			)
			(layer "F.SilkS")
		)
		(fp_line
			(start 0.90678 0.4826)
			(end -0.90678 0.4826)
			(stroke
				(width 0.1524)
				(type default)
			)
			(layer "F.SilkS")
		)
		(fp_line
			(start -0.90678 0.4826)
			(end -0.90678 -0.4699)
			(stroke
				(width 0.1524)
				(type default)
			)
			(layer "F.SilkS")
		)
		(fp_line
			(start 0.499872 -0.249936)
			(end 0.499872 0.249936)
			(stroke
				(width 0.1)
				(type default)
			)
			(layer "F.Fab")
		)
		(fp_line
			(start -0.499872 -0.249936)
			(end 0.499872 -0.249936)
			(stroke
				(width 0.1)
				(type default)
			)
			(layer "F.Fab")
		)
		(fp_line
			(start 0.499872 0.249936)
			(end -0.499872 0.249936)
			(stroke
				(width 0.1)
				(type default)
			)
			(layer "F.Fab")
		)
		(fp_line
			(start -0.499872 0.249936)
			(end -0.499872 -0.249936)
			(stroke
				(width 0.1)
				(type default)
			)
			(layer "F.Fab")
		)
		(pad "A" smd rect
			(at -0.47498 0 90)
			(size 0.6096 0.7112)
			(layers "F.Cu" "F.Mask" "F.Paste")
			(net "LED_PWRGD_PVDDCR_CPU1_P0_R")
		)
		(pad "C" smd rect
			(at 0.47498 0 90)
			(size 0.6096 0.7112)
			(layers "F.Cu" "F.Mask" "F.Paste")
			(net "LED_PWRGD_PVDDCR_CPU1_P0_D")
		)
	)
	(footprint ""
		(layer "F.Cu")
		(at 132.715 -109.474 -90)
		(property "Reference" "R8115"
			(at 0 0 270)
			(layer "F.SilkS")
			(hide yes)
			(effects
				(font
					(size 1.27 1.27)
				)
			)
		)
		(property "Value" ""
			(at 0 0 270)
			(layer "F.Fab")
			(effects
				(font
					(size 1.27 1.27)
				)
			)
		)
		(duplicate_pad_numbers_are_jumpers no)
		(fp_line
			(start -0.7874 0.4064)
			(end -0.7874 -0.4064)
			(stroke
				(width 0.1524)
				(type default)
			)
			(layer "F.SilkS")
		)
		(fp_line
			(start 0.7874 0.4064)
			(end -0.7874 0.4064)
			(stroke
				(width 0.1524)
				(type default)
			)
			(layer "F.SilkS")
		)
		(fp_line
			(start -0.7874 -0.4064)
			(end 0.7874 -0.4064)
			(stroke
				(width 0.1524)
				(type default)
			)
			(layer "F.SilkS")
		)
		(fp_line
			(start 0.7874 -0.4064)
			(end 0.7874 0.4064)
			(stroke
				(width 0.1524)
				(type default)
			)
			(layer "F.SilkS")
		)
		(fp_line
			(start -0.67945 0.3048)
			(end -0.67945 -0.305054)
			(stroke
				(width 0.1)
				(type default)
			)
			(layer "F.Fab")
		)
		(fp_line
			(start -0.12065 0.3048)
			(end -0.67945 0.3048)
			(stroke
				(width 0.1)
				(type default)
			)
			(layer "F.Fab")
		)
		(fp_line
			(start 0.120396 0.3048)
			(end 0.120396 0.2794)
			(stroke
				(width 0.1)
				(type default)
			)
			(layer "F.Fab")
		)
		(fp_line
			(start 0.67945 0.3048)
			(end 0.120396 0.3048)
			(stroke
				(width 0.1)
				(type default)
			)
			(layer "F.Fab")
		)
		(fp_line
			(start -0.12065 0.2794)
			(end -0.12065 0.3048)
			(stroke
				(width 0.1)
				(type default)
			)
			(layer "F.Fab")
		)
		(fp_line
			(start 0.120396 0.2794)
			(end -0.12065 0.2794)
			(stroke
				(width 0.1)
				(type default)
			)
			(layer "F.Fab")
		)
		(fp_line
			(start -0.12065 -0.2794)
			(end 0.12065 -0.2794)
			(stroke
				(width 0.1)
				(type default)
			)
			(layer "F.Fab")
		)
		(fp_line
			(start 0.12065 -0.2794)
			(end 0.12065 -0.3048)
			(stroke
				(width 0.1)
				(type default)
			)
			(layer "F.Fab")
		)
		(fp_line
			(start 0.12065 -0.3048)
			(end 0.67945 -0.3048)
			(stroke
				(width 0.1)
				(type default)
			)
			(layer "F.Fab")
		)
		(fp_line
			(start 0.67945 -0.3048)
			(end 0.67945 0.3048)
			(stroke
				(width 0.1)
				(type default)
			)
			(layer "F.Fab")
		)
		(fp_line
			(start -0.67945 -0.305054)
			(end -0.12065 -0.305054)
			(stroke
				(width 0.1)
				(type default)
			)
			(layer "F.Fab")
		)
		(fp_line
			(start -0.12065 -0.305054)
			(end -0.12065 -0.2794)
			(stroke
				(width 0.1)
				(type default)
			)
			(layer "F.Fab")
		)
		(pad "1" smd circle
			(at -0.40005 0 270)
			(size 0 0)
			(layers "F.Cu" "F.Mask" "F.Paste")
			(net "P12V_AUX_UV_ADR_TRIGGER")
		)
		(pad "2" smd circle
			(at 0.40005 0 270)
			(size 0 0)
			(layers "F.Cu" "F.Mask" "F.Paste")
			(net "GND")
		)
	)
	(footprint ""
		(layer "F.Cu")
		(at 212.471508 -5.077206)
		(property "Reference" "J78"
			(at -4.352036 0.945388 90)
			(unlocked yes)
			(layer "F.SilkS")
			(effects
				(font
					(size 0.7874 0.5842)
					(thickness 0.1524)
				)
				(justify left)
			)
		)
		(property "Value" ""
			(at 0 0 0)
			(layer "F.Fab")
			(effects
				(font
					(size 1.27 1.27)
				)
			)
		)
		(duplicate_pad_numbers_are_jumpers no)
		(fp_line
			(start -1.2192 -2.06756)
			(end 1.2192 -2.06756)
			(stroke
				(width 0.1524)
				(type default)
			)
			(layer "F.SilkS")
		)
		(fp_line
			(start -1.2192 2.06756)
			(end -1.2192 -2.06756)
			(stroke
				(width 0.1524)
				(type default)
			)
			(layer "F.SilkS")
		)
		(fp_line
			(start 1.2192 -2.06756)
			(end 1.2192 2.06756)
			(stroke
				(width 0.1524)
				(type default)
			)
			(layer "F.SilkS")
		)
		(fp_line
			(start 1.2192 2.06756)
			(end -1.2192 2.06756)
			(stroke
				(width 0.1524)
				(type default)
			)
			(layer "F.SilkS")
		)
		(pad "" np_thru_hole circle
			(at -2.8829 -1.27 270)
			(size 1.0414 1.0414)
			(drill 1.0414)
			(layers "*.Cu" "*.Mask")
			(clearance 0.381)
			(thermal_gap 0.381)
		)
		(pad "" np_thru_hole circle
			(at -2.8829 1.27 270)
			(size 1.0414 1.0414)
			(drill 1.0414)
			(layers "*.Cu" "*.Mask")
			(clearance 0.381)
			(thermal_gap 0.381)
		)
		(pad "" np_thru_hole circle
			(at 3.4671 -1.27 270)
			(size 1.0414 1.0414)
			(drill 1.0414)
			(layers "*.Cu" "*.Mask")
			(clearance 0.381)
			(thermal_gap 0.381)
		)
		(pad "" np_thru_hole circle
			(at 3.4671 1.27 270)
			(size 1.0414 1.0414)
			(drill 1.0414)
			(layers "*.Cu" "*.Mask")
			(clearance 0.381)
			(thermal_gap 0.381)
		)
		(pad "1" smd rect
			(at 0.8255 -0.249936 270)
			(size 0.3048 0.508)
			(layers "F.Cu" "F.Mask" "F.Paste")
			(net "DELTA_L_85_10INCH_IN2_DP")
		)
		(pad "2" smd rect
			(at 0.8255 0.249936 270)
			(size 0.3048 0.508)
			(layers "F.Cu" "F.Mask" "F.Paste")
			(net "DELTA_L_85_10INCH_IN2_DN")
		)
		(pad "3" smd circle
			(at 0 0)
			(size 0 0)
			(layers "F.Cu" "F.Mask" "F.Paste")
			(net "DELTA_L_GND_1")
		)
		(zone
			(layer "F.Cu")
			(hatch none 0.5)
			(connect_pads
				(clearance 0)
			)
			(min_thickness 0.25)
			(keepout
				(tracks not_allowed)
				(vias allowed)
				(pads allowed)
				(copperpour not_allowed)
				(footprints allowed)
			)
			(placement
				(enabled no)
				(sheetname "")
			)
			(fill
				(thermal_gap 0.5)
				(thermal_bridge_width 0.5)
				(island_removal_mode 0)
			)
			(polygon
				(pts
					(xy 213.589108 -5.625846) (xy 213.589108 -5.530342) (xy 212.992208 -5.530342) (xy 212.992208 -5.123942)
					(xy 213.589108 -5.123942) (xy 213.589108 -5.03047) (xy 212.992208 -5.03047) (xy 212.992208 -4.62407)
					(xy 213.589108 -4.62407) (xy 213.589108 -4.528566) (xy 212.890608 -4.528566) (xy 212.890608 -5.625846)
				)
			)
		)
		(zone
			(layers "F.Cu" "B.Cu" "In1.Cu" "In2.Cu" "In3.Cu" "In4.Cu" "In5.Cu" "In6.Cu"
				"In7.Cu" "In8.Cu" "In9.Cu" "In10.Cu" "In11.Cu" "In12.Cu" "In13.Cu" "In14.Cu"
				"In15.Cu" "In16.Cu"
			)
			(hatch none 0.5)
			(connect_pads
				(clearance 0)
			)
			(min_thickness 0.25)
			(keepout
				(tracks not_allowed)
				(vias allowed)
				(pads allowed)
				(copperpour not_allowed)
				(footprints allowed)
			)
			(placement
				(enabled no)
				(sheetname "")
			)
			(fill
				(thermal_gap 0.5)
				(thermal_bridge_width 0.5)
				(island_removal_mode 0)
			)
			(polygon
				(pts
					(arc
						(start 210.515708 -6.347206)
						(mid 208.661508 -6.347206)
						(end 210.515708 -6.347206)
					)
				)
			)
		)
		(zone
			(layers "F.Cu" "B.Cu" "In1.Cu" "In2.Cu" "In3.Cu" "In4.Cu" "In5.Cu" "In6.Cu"
				"In7.Cu" "In8.Cu" "In9.Cu" "In10.Cu" "In11.Cu" "In12.Cu" "In13.Cu" "In14.Cu"
				"In15.Cu" "In16.Cu"
			)
			(hatch none 0.5)
			(connect_pads
				(clearance 0)
			)
			(min_thickness 0.25)
			(keepout
				(tracks not_allowed)
				(vias allowed)
				(pads allowed)
				(copperpour not_allowed)
				(footprints allowed)
			)
			(placement
				(enabled no)
				(sheetname "")
			)
			(fill
				(thermal_gap 0.5)
				(thermal_bridge_width 0.5)
				(island_removal_mode 0)
			)
			(polygon
				(pts
					(arc
						(start 210.515708 -3.807206)
						(mid 208.661508 -3.807206)
						(end 210.515708 -3.807206)
					)
				)
			)
		)
		(zone
			(layers "F.Cu" "B.Cu" "In1.Cu" "In2.Cu" "In3.Cu" "In4.Cu" "In5.Cu" "In6.Cu"
				"In7.Cu" "In8.Cu" "In9.Cu" "In10.Cu" "In11.Cu" "In12.Cu" "In13.Cu" "In14.Cu"
				"In15.Cu" "In16.Cu"
			)
			(hatch none 0.5)
			(connect_pads
				(clearance 0)
			)
			(min_thickness 0.25)
			(keepout
				(tracks not_allowed)
				(vias allowed)
				(pads allowed)
				(copperpour not_allowed)
				(footprints allowed)
			)
			(placement
				(enabled no)
				(sheetname "")
			)
			(fill
				(thermal_gap 0.5)
				(thermal_bridge_width 0.5)
				(island_removal_mode 0)
			)
			(polygon
				(pts
					(arc
						(start 216.865708 -6.347206)
						(mid 215.011508 -6.347206)
						(end 216.865708 -6.347206)
					)
				)
			)
		)
		(zone
			(layers "F.Cu" "B.Cu" "In1.Cu" "In2.Cu" "In3.Cu" "In4.Cu" "In5.Cu" "In6.Cu"
				"In7.Cu" "In8.Cu" "In9.Cu" "In10.Cu" "In11.Cu" "In12.Cu" "In13.Cu" "In14.Cu"
				"In15.Cu" "In16.Cu"
			)
			(hatch none 0.5)
			(connect_pads
				(clearance 0)
			)
			(min_thickness 0.25)
			(keepout
				(tracks not_allowed)
				(vias allowed)
				(pads allowed)
				(copperpour not_allowed)
				(footprints allowed)
			)
			(placement
				(enabled no)
				(sheetname "")
			)
			(fill
				(thermal_gap 0.5)
				(thermal_bridge_width 0.5)
				(island_removal_mode 0)
			)
			(polygon
				(pts
					(arc
						(start 216.865708 -3.807206)
						(mid 215.011508 -3.807206)
						(end 216.865708 -3.807206)
					)
				)
			)
		)
	)
	(footprint ""
		(layer "F.Cu")
		(at 24.765 -366.903)
		(property "Reference" "R8248"
			(at 0 0 0)
			(layer "F.SilkS")
			(hide yes)
			(effects
				(font
					(size 1.27 1.27)
				)
			)
		)
		(property "Value" ""
			(at 0 0 0)
			(layer "F.Fab")
			(effects
				(font
					(size 1.27 1.27)
				)
			)
		)
		(duplicate_pad_numbers_are_jumpers no)
		(fp_line
			(start -0.7874 -0.4064)
			(end 0.7874 -0.4064)
			(stroke
				(width 0.1524)
				(type default)
			)
			(layer "F.SilkS")
		)
		(fp_line
			(start -0.7874 0.4064)
			(end -0.7874 -0.4064)
			(stroke
				(width 0.1524)
				(type default)
			)
			(layer "F.SilkS")
		)
		(fp_line
			(start 0.7874 -0.4064)
			(end 0.7874 0.4064)
			(stroke
				(width 0.1524)
				(type default)
			)
			(layer "F.SilkS")
		)
		(fp_line
			(start 0.7874 0.4064)
			(end -0.7874 0.4064)
			(stroke
				(width 0.1524)
				(type default)
			)
			(layer "F.SilkS")
		)
		(fp_line
			(start -0.67945 -0.305054)
			(end -0.12065 -0.305054)
			(stroke
				(width 0.1)
				(type default)
			)
			(layer "F.Fab")
		)
		(fp_line
			(start -0.67945 0.3048)
			(end -0.67945 -0.305054)
			(stroke
				(width 0.1)
				(type default)
			)
			(layer "F.Fab")
		)
		(fp_line
			(start -0.12065 -0.305054)
			(end -0.12065 -0.2794)
			(stroke
				(width 0.1)
				(type default)
			)
			(layer "F.Fab")
		)
		(fp_line
			(start -0.12065 -0.2794)
			(end 0.12065 -0.2794)
			(stroke
				(width 0.1)
				(type default)
			)
			(layer "F.Fab")
		)
		(fp_line
			(start -0.12065 0.2794)
			(end -0.12065 0.3048)
			(stroke
				(width 0.1)
				(type default)
			)
			(layer "F.Fab")
		)
		(fp_line
			(start -0.12065 0.3048)
			(end -0.67945 0.3048)
			(stroke
				(width 0.1)
				(type default)
			)
			(layer "F.Fab")
		)
		(fp_line
			(start 0.120396 0.2794)
			(end -0.12065 0.2794)
			(stroke
				(width 0.1)
				(type default)
			)
			(layer "F.Fab")
		)
		(fp_line
			(start 0.120396 0.3048)
			(end 0.120396 0.2794)
			(stroke
				(width 0.1)
				(type default)
			)
			(layer "F.Fab")
		)
		(fp_line
			(start 0.12065 -0.3048)
			(end 0.67945 -0.3048)
			(stroke
				(width 0.1)
				(type default)
			)
			(layer "F.Fab")
		)
		(fp_line
			(start 0.12065 -0.2794)
			(end 0.12065 -0.3048)
			(stroke
				(width 0.1)
				(type default)
			)
			(layer "F.Fab")
		)
		(fp_line
			(start 0.67945 -0.3048)
			(end 0.67945 0.3048)
			(stroke
				(width 0.1)
				(type default)
			)
			(layer "F.Fab")
		)
		(fp_line
			(start 0.67945 0.3048)
			(end 0.120396 0.3048)
			(stroke
				(width 0.1)
				(type default)
			)
			(layer "F.Fab")
		)
		(pad "1" smd circle
			(at -0.40005 0)
			(size 0 0)
			(layers "F.Cu" "F.Mask" "F.Paste")
			(net "SMB_SCM_2_R1_SCL")
		)
		(pad "2" smd circle
			(at 0.40005 0)
			(size 0 0)
			(layers "F.Cu" "F.Mask" "F.Paste")
			(net "SMB_CLK_PVDDCR_CPU1_P1_R")
		)
	)
	(footprint ""
		(layer "F.Cu")
		(at 164.143944 -344.153998 -90)
		(property "Reference" "PR13"
			(at 0 0 270)
			(layer "F.SilkS")
			(hide yes)
			(effects
				(font
					(size 1.27 1.27)
				)
			)
		)
		(property "Value" ""
			(at 0 0 270)
			(layer "F.Fab")
			(effects
				(font
					(size 1.27 1.27)
				)
			)
		)
		(duplicate_pad_numbers_are_jumpers no)
		(fp_line
			(start -0.7874 0.4064)
			(end -0.7874 -0.4064)
			(stroke
				(width 0.1524)
				(type default)
			)
			(layer "F.SilkS")
		)
		(fp_line
			(start 0.7874 0.4064)
			(end -0.7874 0.4064)
			(stroke
				(width 0.1524)
				(type default)
			)
			(layer "F.SilkS")
		)
		(fp_line
			(start -0.7874 -0.4064)
			(end 0.7874 -0.4064)
			(stroke
				(width 0.1524)
				(type default)
			)
			(layer "F.SilkS")
		)
		(fp_line
			(start 0.7874 -0.4064)
			(end 0.7874 0.4064)
			(stroke
				(width 0.1524)
				(type default)
			)
			(layer "F.SilkS")
		)
		(fp_line
			(start -0.67945 0.3048)
			(end -0.67945 -0.305054)
			(stroke
				(width 0.1)
				(type default)
			)
			(layer "F.Fab")
		)
		(fp_line
			(start -0.12065 0.3048)
			(end -0.67945 0.3048)
			(stroke
				(width 0.1)
				(type default)
			)
			(layer "F.Fab")
		)
		(fp_line
			(start 0.120396 0.3048)
			(end 0.120396 0.2794)
			(stroke
				(width 0.1)
				(type default)
			)
			(layer "F.Fab")
		)
		(fp_line
			(start 0.67945 0.3048)
			(end 0.120396 0.3048)
			(stroke
				(width 0.1)
				(type default)
			)
			(layer "F.Fab")
		)
		(fp_line
			(start -0.12065 0.2794)
			(end -0.12065 0.3048)
			(stroke
				(width 0.1)
				(type default)
			)
			(layer "F.Fab")
		)
		(fp_line
			(start 0.120396 0.2794)
			(end -0.12065 0.2794)
			(stroke
				(width 0.1)
				(type default)
			)
			(layer "F.Fab")
		)
		(fp_line
			(start -0.12065 -0.2794)
			(end 0.12065 -0.2794)
			(stroke
				(width 0.1)
				(type default)
			)
			(layer "F.Fab")
		)
		(fp_line
			(start 0.12065 -0.2794)
			(end 0.12065 -0.3048)
			(stroke
				(width 0.1)
				(type default)
			)
			(layer "F.Fab")
		)
		(fp_line
			(start 0.12065 -0.3048)
			(end 0.67945 -0.3048)
			(stroke
				(width 0.1)
				(type default)
			)
			(layer "F.Fab")
		)
		(fp_line
			(start 0.67945 -0.3048)
			(end 0.67945 0.3048)
			(stroke
				(width 0.1)
				(type default)
			)
			(layer "F.Fab")
		)
		(fp_line
			(start -0.67945 -0.305054)
			(end -0.12065 -0.305054)
			(stroke
				(width 0.1)
				(type default)
			)
			(layer "F.Fab")
		)
		(fp_line
			(start -0.12065 -0.305054)
			(end -0.12065 -0.2794)
			(stroke
				(width 0.1)
				(type default)
			)
			(layer "F.Fab")
		)
		(pad "1" smd circle
			(at -0.40005 0 270)
			(size 0 0)
			(layers "F.Cu" "F.Mask" "F.Paste")
			(net "NC_PVDD11_S3_P1_IMON5")
		)
		(pad "2" smd circle
			(at 0.40005 0 270)
			(size 0 0)
			(layers "F.Cu" "F.Mask" "F.Paste")
			(net "GND")
		)
	)
	(footprint ""
		(layer "F.Cu")
		(at 61.90488 -19.268948 180)
		(property "Reference" "R3164"
			(at 0 0 180)
			(layer "F.SilkS")
			(hide yes)
			(effects
				(font
					(size 1.27 1.27)
				)
			)
		)
		(property "Value" ""
			(at 0 0 180)
			(layer "F.Fab")
			(effects
				(font
					(size 1.27 1.27)
				)
			)
		)
		(duplicate_pad_numbers_are_jumpers no)
		(fp_line
			(start 0.7874 0.4064)
			(end -0.7874 0.4064)
			(stroke
				(width 0.1524)
				(type default)
			)
			(layer "F.SilkS")
		)
		(fp_line
			(start 0.7874 -0.4064)
			(end 0.7874 0.4064)
			(stroke
				(width 0.1524)
				(type default)
			)
			(layer "F.SilkS")
		)
		(fp_line
			(start -0.7874 0.4064)
			(end -0.7874 -0.4064)
			(stroke
				(width 0.1524)
				(type default)
			)
			(layer "F.SilkS")
		)
		(fp_line
			(start -0.7874 -0.4064)
			(end 0.7874 -0.4064)
			(stroke
				(width 0.1524)
				(type default)
			)
			(layer "F.SilkS")
		)
		(fp_line
			(start 0.67945 0.3048)
			(end 0.120396 0.3048)
			(stroke
				(width 0.1)
				(type default)
			)
			(layer "F.Fab")
		)
		(fp_line
			(start 0.67945 -0.3048)
			(end 0.67945 0.3048)
			(stroke
				(width 0.1)
				(type default)
			)
			(layer "F.Fab")
		)
		(fp_line
			(start 0.12065 -0.2794)
			(end 0.12065 -0.3048)
			(stroke
				(width 0.1)
				(type default)
			)
			(layer "F.Fab")
		)
		(fp_line
			(start 0.12065 -0.3048)
			(end 0.67945 -0.3048)
			(stroke
				(width 0.1)
				(type default)
			)
			(layer "F.Fab")
		)
		(fp_line
			(start 0.120396 0.3048)
			(end 0.120396 0.2794)
			(stroke
				(width 0.1)
				(type default)
			)
			(layer "F.Fab")
		)
		(fp_line
			(start 0.120396 0.2794)
			(end -0.12065 0.2794)
			(stroke
				(width 0.1)
				(type default)
			)
			(layer "F.Fab")
		)
		(fp_line
			(start -0.12065 0.3048)
			(end -0.67945 0.3048)
			(stroke
				(width 0.1)
				(type default)
			)
			(layer "F.Fab")
		)
		(fp_line
			(start -0.12065 0.2794)
			(end -0.12065 0.3048)
			(stroke
				(width 0.1)
				(type default)
			)
			(layer "F.Fab")
		)
		(fp_line
			(start -0.12065 -0.2794)
			(end 0.12065 -0.2794)
			(stroke
				(width 0.1)
				(type default)
			)
			(layer "F.Fab")
		)
		(fp_line
			(start -0.12065 -0.305054)
			(end -0.12065 -0.2794)
			(stroke
				(width 0.1)
				(type default)
			)
			(layer "F.Fab")
		)
		(fp_line
			(start -0.67945 0.3048)
			(end -0.67945 -0.305054)
			(stroke
				(width 0.1)
				(type default)
			)
			(layer "F.Fab")
		)
		(fp_line
			(start -0.67945 -0.305054)
			(end -0.12065 -0.305054)
			(stroke
				(width 0.1)
				(type default)
			)
			(layer "F.Fab")
		)
		(pad "1" smd circle
			(at -0.40005 0 180)
			(size 0 0)
			(layers "F.Cu" "F.Mask" "F.Paste")
			(net "GND")
		)
		(pad "2" smd circle
			(at 0.40005 0 180)
			(size 0 0)
			(layers "F.Cu" "F.Mask" "F.Paste")
			(net "OCP_V3_2_AUX_PWR_EN")
		)
	)
	(footprint ""
		(layer "F.Cu")
		(at 209.172556 -34.772092 90)
		(property "Reference" "U265"
			(at 3.273806 -3.826256 0)
			(unlocked yes)
			(layer "F.SilkS")
			(effects
				(font
					(size 0.7874 0.5842)
					(thickness 0.1524)
				)
			)
		)
		(property "Value" ""
			(at 0 0 90)
			(layer "F.Fab")
			(effects
				(font
					(size 1.27 1.27)
				)
			)
		)
		(duplicate_pad_numbers_are_jumpers no)
		(fp_line
			(start 1.500124 -1.500124)
			(end 1.500124 -1.004062)
			(stroke
				(width 0.1524)
				(type default)
			)
			(layer "F.SilkS")
		)
		(fp_line
			(start 1.004062 -1.500124)
			(end 1.500124 -1.500124)
			(stroke
				(width 0.1524)
				(type default)
			)
			(layer "F.SilkS")
		)
		(fp_line
			(start -1.500124 -1.500124)
			(end -1.004062 -1.500124)
			(stroke
				(width 0.1524)
				(type default)
			)
			(layer "F.SilkS")
		)
		(fp_line
			(start -1.500124 -1.004062)
			(end -1.500124 -1.500124)
			(stroke
				(width 0.1524)
				(type default)
			)
			(layer "F.SilkS")
		)
		(fp_line
			(start 1.500124 1.004062)
			(end 1.500124 1.500124)
			(stroke
				(width 0.1524)
				(type default)
			)
			(layer "F.SilkS")
		)
		(fp_line
			(start 1.500124 1.500124)
			(end 1.004062 1.500124)
			(stroke
				(width 0.1524)
				(type default)
			)
			(layer "F.SilkS")
		)
		(fp_line
			(start -1.004062 1.500124)
			(end -1.500124 1.500124)
			(stroke
				(width 0.1524)
				(type default)
			)
			(layer "F.SilkS")
		)
		(fp_line
			(start -1.500124 1.500124)
			(end -1.500124 1.004062)
			(stroke
				(width 0.1524)
				(type default)
			)
			(layer "F.SilkS")
		)
		(fp_poly
			(pts
				(xy -2.868422 -1.547368) (xy -2.15011 -2.265934) (xy -1.790954 -1.188212)
			)
			(stroke
				(width 0)
				(type default)
			)
			(fill yes)
			(layer "F.SilkS")
		)
		(fp_line
			(start 1.500124 -1.500124)
			(end 1.500124 1.500124)
			(stroke
				(width 0.1)
				(type default)
			)
			(layer "F.Fab")
		)
		(fp_line
			(start -1.500124 -1.500124)
			(end 1.500124 -1.500124)
			(stroke
				(width 0.1)
				(type default)
			)
			(layer "F.Fab")
		)
		(fp_line
			(start 1.500124 1.500124)
			(end -1.500124 1.500124)
			(stroke
				(width 0.1)
				(type default)
			)
			(layer "F.Fab")
		)
		(fp_line
			(start -1.500124 1.500124)
			(end -1.500124 -1.500124)
			(stroke
				(width 0.1)
				(type default)
			)
			(layer "F.Fab")
		)
		(fp_poly
			(pts
				(xy -2.847848 -1.258062) (xy -2.847848 -0.242062) (xy -1.831848 -0.750062)
			)
			(stroke
				(width 0)
				(type default)
			)
			(fill yes)
			(layer "F.Fab")
		)
		(pad "1" smd rect
			(at -1.400048 -0.750062)
			(size 0.2286 0.6096)
			(layers "F.Cu" "F.Mask" "F.Paste")
			(net "INA230_5_A1")
		)
		(pad "2" smd rect
			(at -1.400048 -0.249936)
			(size 0.2286 0.6096)
			(layers "F.Cu" "F.Mask" "F.Paste")
			(net "INA230_5_A0")
		)
		(pad "3" smd rect
			(at -1.400048 0.249936)
			(size 0.2286 0.6096)
			(layers "F.Cu" "F.Mask" "F.Paste")
			(net "P12V_SCM_ADC_ALERT_R")
		)
		(pad "4" smd rect
			(at -1.400048 0.750062)
			(size 0.2286 0.6096)
			(layers "F.Cu" "F.Mask" "F.Paste")
			(net "SMB_INA230_5_3V3AUX_SDA_R1")
		)
		(pad "5" smd rect
			(at -0.750062 1.400048 90)
			(size 0.2286 0.6096)
			(layers "F.Cu" "F.Mask" "F.Paste")
			(net "SMB_INA230_5_3V3AUX_SCL_R1")
		)
		(pad "6" smd rect
			(at -0.249936 1.400048 90)
			(size 0.2286 0.6096)
			(layers "F.Cu" "F.Mask" "F.Paste")
			(net "NC_INA230_5_NC0")
		)
		(pad "7" smd rect
			(at 0.249936 1.400048 90)
			(size 0.2286 0.6096)
			(layers "F.Cu" "F.Mask" "F.Paste")
			(net "NC_INA230_5_NC1")
		)
		(pad "8" smd rect
			(at 0.750062 1.400048 90)
			(size 0.2286 0.6096)
			(layers "F.Cu" "F.Mask" "F.Paste")
			(net "NC_INA230_5_NC2")
		)
		(pad "9" smd rect
			(at 1.400048 0.750062)
			(size 0.2286 0.6096)
			(layers "F.Cu" "F.Mask" "F.Paste")
			(net "P3V3_AUX")
		)
		(pad "10" smd rect
			(at 1.400048 0.249936)
			(size 0.2286 0.6096)
			(layers "F.Cu" "F.Mask" "F.Paste")
			(net "GND")
		)
		(pad "11" smd rect
			(at 1.400048 -0.249936)
			(size 0.2286 0.6096)
			(layers "F.Cu" "F.Mask" "F.Paste")
			(net "P12V_SCM_R")
		)
		(pad "12" smd rect
			(at 1.400048 -0.750062)
			(size 0.2286 0.6096)
			(layers "F.Cu" "F.Mask" "F.Paste")
			(net "VSENSE_P12V_INA230_5_INN")
		)
		(pad "13" smd rect
			(at 0.750062 -1.400048 90)
			(size 0.2286 0.6096)
			(layers "F.Cu" "F.Mask" "F.Paste")
			(net "VSENSE_P12V_INA230_5_INP")
		)
		(pad "14" smd rect
			(at 0.249936 -1.400048 90)
			(size 0.2286 0.6096)
			(layers "F.Cu" "F.Mask" "F.Paste")
			(net "NC_INA230_5_NC3")
		)
		(pad "15" smd rect
			(at -0.249936 -1.400048 90)
			(size 0.2286 0.6096)
			(layers "F.Cu" "F.Mask" "F.Paste")
			(net "NC_INA230_5_NC4")
		)
		(pad "16" smd rect
			(at -0.750062 -1.400048 90)
			(size 0.2286 0.6096)
			(layers "F.Cu" "F.Mask" "F.Paste")
			(net "NC_INA230_5_NC5")
		)
		(pad "TH" smd rect
			(at 0 0 90)
			(size 1.7018 1.7018)
			(layers "F.Cu" "F.Mask" "F.Paste")
			(net "GND")
		)
		(zone
			(layer "F.Cu")
			(hatch none 0.5)
			(connect_pads
				(clearance 0)
			)
			(min_thickness 0.25)
			(keepout
				(tracks not_allowed)
				(vias allowed)
				(pads allowed)
				(copperpour not_allowed)
				(footprints allowed)
			)
			(placement
				(enabled no)
				(sheetname "")
			)
			(fill
				(thermal_gap 0.5)
				(thermal_bridge_width 0.5)
				(island_removal_mode 0)
			)
			(polygon
				(pts
					(xy 209.147156 -33.727644) (xy 208.128108 -33.727644) (xy 208.128108 -35.81654) (xy 210.217004 -35.81654)
					(xy 210.217004 -33.727644) (xy 209.172556 -33.727644) (xy 209.172556 -33.870392) (xy 210.074256 -33.870392)
					(xy 210.074256 -35.673792) (xy 208.270856 -35.673792) (xy 208.270856 -33.870392) (xy 209.147156 -33.870392)
				)
			)
		)
	)
	(footprint ""
		(layer "F.Cu")
		(at 346.549726 -28.291028 -90)
		(property "Reference" "U86"
			(at 1.804416 -2.63652 90)
			(unlocked yes)
			(layer "F.SilkS")
			(effects
				(font
					(size 0.7874 0.5842)
					(thickness 0.1524)
				)
				(justify left)
			)
		)
		(property "Value" ""
			(at 0 0 270)
			(layer "F.Fab")
			(effects
				(font
					(size 1.27 1.27)
				)
			)
		)
		(duplicate_pad_numbers_are_jumpers no)
		(fp_line
			(start -2.0574 1.651)
			(end -2.0574 -1.651)
			(stroke
				(width 0.1524)
				(type default)
			)
			(layer "F.SilkS")
		)
		(fp_line
			(start 2.0574 1.651)
			(end -2.0574 1.651)
			(stroke
				(width 0.1524)
				(type default)
			)
			(layer "F.SilkS")
		)
		(fp_line
			(start 0 -1.016)
			(end 0.381 -1.651)
			(stroke
				(width 0.1524)
				(type default)
			)
			(layer "F.SilkS")
		)
		(fp_line
			(start -2.0574 -1.651)
			(end -0.381 -1.651)
			(stroke
				(width 0.1524)
				(type default)
			)
			(layer "F.SilkS")
		)
		(fp_line
			(start -0.381 -1.651)
			(end 0 -1.016)
			(stroke
				(width 0.1524)
				(type default)
			)
			(layer "F.SilkS")
		)
		(fp_line
			(start 0.381 -1.651)
			(end 2.0574 -1.651)
			(stroke
				(width 0.1524)
				(type default)
			)
			(layer "F.SilkS")
		)
		(fp_line
			(start 2.0574 -1.651)
			(end 2.0574 1.651)
			(stroke
				(width 0.1524)
				(type default)
			)
			(layer "F.SilkS")
		)
		(fp_poly
			(pts
				(xy -2.159 -1.016) (xy -2.71272 -0.719328) (xy -2.71272 -1.344168)
			)
			(stroke
				(width 0)
				(type default)
			)
			(fill yes)
			(layer "F.SilkS")
		)
		(fp_line
			(start -0.899922 1.549908)
			(end -0.899922 1.199896)
			(stroke
				(width 0.1)
				(type default)
			)
			(layer "F.Fab")
		)
		(fp_line
			(start 0.899922 1.549908)
			(end -0.899922 1.549908)
			(stroke
				(width 0.1)
				(type default)
			)
			(layer "F.Fab")
		)
		(fp_line
			(start -1.599946 1.199896)
			(end -1.599946 -1.199896)
			(stroke
				(width 0.1)
				(type default)
			)
			(layer "F.Fab")
		)
		(fp_line
			(start -0.899922 1.199896)
			(end -1.599946 1.199896)
			(stroke
				(width 0.1)
				(type default)
			)
			(layer "F.Fab")
		)
		(fp_line
			(start 0.899922 1.199896)
			(end 0.899922 1.549908)
			(stroke
				(width 0.1)
				(type default)
			)
			(layer "F.Fab")
		)
		(fp_line
			(start 1.599946 1.199896)
			(end 0.899922 1.199896)
			(stroke
				(width 0.1)
				(type default)
			)
			(layer "F.Fab")
		)
		(fp_line
			(start -1.599946 -1.199896)
			(end -0.899922 -1.199896)
			(stroke
				(width 0.1)
				(type default)
			)
			(layer "F.Fab")
		)
		(fp_line
			(start -0.899922 -1.199896)
			(end -0.899922 -1.549908)
			(stroke
				(width 0.1)
				(type default)
			)
			(layer "F.Fab")
		)
		(fp_line
			(start 0.899922 -1.199896)
			(end 1.599946 -1.199896)
			(stroke
				(width 0.1)
				(type default)
			)
			(layer "F.Fab")
		)
		(fp_line
			(start 1.599946 -1.199896)
			(end 1.599946 1.199896)
			(stroke
				(width 0.1)
				(type default)
			)
			(layer "F.Fab")
		)
		(fp_line
			(start -0.899922 -1.549908)
			(end 0.899922 -1.549908)
			(stroke
				(width 0.1)
				(type default)
			)
			(layer "F.Fab")
		)
		(fp_line
			(start 0.899922 -1.549908)
			(end 0.899922 -1.199896)
			(stroke
				(width 0.1)
				(type default)
			)
			(layer "F.Fab")
		)
		(fp_poly
			(pts
				(xy -2.71272 -0.719328) (xy -2.71272 -1.344168) (xy -2.159 -1.016)
			)
			(stroke
				(width 0)
				(type default)
			)
			(fill yes)
			(layer "F.Fab")
		)
		(pad "1" smd rect
			(at -1.225042 -0.94996 180)
			(size 0.5588 1.3462)
			(layers "F.Cu" "F.Mask" "F.Paste")
			(net "Net_10731")
		)
		(pad "2" smd rect
			(at -1.225042 0 180)
			(size 0.5588 1.3462)
			(layers "F.Cu" "F.Mask" "F.Paste")
			(net "FM_SMERR_LED_N")
		)
		(pad "3" smd rect
			(at -1.225042 0.94996 180)
			(size 0.5588 1.3462)
			(layers "F.Cu" "F.Mask" "F.Paste")
			(net "GND")
		)
		(pad "4" smd rect
			(at 1.225042 0.94996 180)
			(size 0.5588 1.3462)
			(layers "F.Cu" "F.Mask" "F.Paste")
			(net "FM_SMERR_BUF_LED_N")
		)
		(pad "5" smd rect
			(at 1.225042 -0.94996 180)
			(size 0.5588 1.3462)
			(layers "F.Cu" "F.Mask" "F.Paste")
			(net "P1V8_AUX")
		)
	)
	(footprint ""
		(layer "F.Cu")
		(at 55.329328 -351.372932 -90)
		(property "Reference" "PC447"
			(at 0 0 270)
			(layer "F.SilkS")
			(hide yes)
			(effects
				(font
					(size 1.27 1.27)
				)
			)
		)
		(property "Value" ""
			(at 0 0 270)
			(layer "F.Fab")
			(effects
				(font
					(size 1.27 1.27)
				)
			)
		)
		(duplicate_pad_numbers_are_jumpers no)
		(fp_line
			(start -0.7874 0.4064)
			(end -0.7874 -0.4064)
			(stroke
				(width 0.1524)
				(type default)
			)
			(layer "F.SilkS")
		)
		(fp_line
			(start 0.7874 0.4064)
			(end -0.7874 0.4064)
			(stroke
				(width 0.1524)
				(type default)
			)
			(layer "F.SilkS")
		)
		(fp_line
			(start -0.7874 -0.4064)
			(end 0.7874 -0.4064)
			(stroke
				(width 0.1524)
				(type default)
			)
			(layer "F.SilkS")
		)
		(fp_line
			(start 0.7874 -0.4064)
			(end 0.7874 0.4064)
			(stroke
				(width 0.1524)
				(type default)
			)
			(layer "F.SilkS")
		)
		(fp_line
			(start -0.67945 0.3048)
			(end -0.67945 -0.305054)
			(stroke
				(width 0.1)
				(type default)
			)
			(layer "F.Fab")
		)
		(fp_line
			(start -0.12065 0.3048)
			(end -0.67945 0.3048)
			(stroke
				(width 0.1)
				(type default)
			)
			(layer "F.Fab")
		)
		(fp_line
			(start 0.120396 0.3048)
			(end 0.120396 0.2794)
			(stroke
				(width 0.1)
				(type default)
			)
			(layer "F.Fab")
		)
		(fp_line
			(start 0.67945 0.3048)
			(end 0.120396 0.3048)
			(stroke
				(width 0.1)
				(type default)
			)
			(layer "F.Fab")
		)
		(fp_line
			(start -0.12065 0.2794)
			(end -0.12065 0.3048)
			(stroke
				(width 0.1)
				(type default)
			)
			(layer "F.Fab")
		)
		(fp_line
			(start 0.120396 0.2794)
			(end -0.12065 0.2794)
			(stroke
				(width 0.1)
				(type default)
			)
			(layer "F.Fab")
		)
		(fp_line
			(start -0.12065 -0.2794)
			(end 0.12065 -0.2794)
			(stroke
				(width 0.1)
				(type default)
			)
			(layer "F.Fab")
		)
		(fp_line
			(start 0.12065 -0.2794)
			(end 0.12065 -0.3048)
			(stroke
				(width 0.1)
				(type default)
			)
			(layer "F.Fab")
		)
		(fp_line
			(start 0.12065 -0.3048)
			(end 0.67945 -0.3048)
			(stroke
				(width 0.1)
				(type default)
			)
			(layer "F.Fab")
		)
		(fp_line
			(start 0.67945 -0.3048)
			(end 0.67945 0.3048)
			(stroke
				(width 0.1)
				(type default)
			)
			(layer "F.Fab")
		)
		(fp_line
			(start -0.67945 -0.305054)
			(end -0.12065 -0.305054)
			(stroke
				(width 0.1)
				(type default)
			)
			(layer "F.Fab")
		)
		(fp_line
			(start -0.12065 -0.305054)
			(end -0.12065 -0.2794)
			(stroke
				(width 0.1)
				(type default)
			)
			(layer "F.Fab")
		)
		(pad "1" smd circle
			(at -0.40005 0 270)
			(size 0 0)
			(layers "F.Cu" "F.Mask" "F.Paste")
			(net "SW_PVDDIO_P1_BOOT1_R")
		)
		(pad "2" smd circle
			(at 0.40005 0 270)
			(size 0 0)
			(layers "F.Cu" "F.Mask" "F.Paste")
			(net "SW_PVDDIO_P1_BOOTR1")
		)
	)
	(footprint ""
		(layer "F.Cu")
		(at 115.815872 -73.954132 90)
		(property "Reference" "PL6003"
			(at 0 0 90)
			(layer "F.SilkS")
			(hide yes)
			(effects
				(font
					(size 1.27 1.27)
				)
			)
		)
		(property "Value" ""
			(at 0 0 90)
			(layer "F.Fab")
			(effects
				(font
					(size 1.27 1.27)
				)
			)
		)
		(duplicate_pad_numbers_are_jumpers no)
		(fp_line
			(start -1.27 -0.5842)
			(end 1.27 -0.5842)
			(stroke
				(width 0.1524)
				(type default)
			)
			(layer "F.SilkS")
		)
		(fp_line
			(start -1.27 -0.5588)
			(end -1.27 -0.5842)
			(stroke
				(width 0.1524)
				(type default)
			)
			(layer "F.SilkS")
		)
		(fp_line
			(start 1.27 0.5842)
			(end 1.27 -0.5842)
			(stroke
				(width 0.1524)
				(type default)
			)
			(layer "F.SilkS")
		)
		(fp_line
			(start 1.27 0.5842)
			(end -1.27 0.5842)
			(stroke
				(width 0.1524)
				(type default)
			)
			(layer "F.SilkS")
		)
		(fp_line
			(start -1.27 0.5842)
			(end -1.27 -0.5842)
			(stroke
				(width 0.1524)
				(type default)
			)
			(layer "F.SilkS")
		)
		(fp_line
			(start 0.9144 -0.508)
			(end 0.9144 -0.406654)
			(stroke
				(width 0.1)
				(type default)
			)
			(layer "F.Fab")
		)
		(fp_line
			(start -0.9144 -0.508)
			(end 0.9144 -0.508)
			(stroke
				(width 0.1)
				(type default)
			)
			(layer "F.Fab")
		)
		(fp_line
			(start 1.1938 -0.406654)
			(end 1.1938 0.4064)
			(stroke
				(width 0.1)
				(type default)
			)
			(layer "F.Fab")
		)
		(fp_line
			(start 0.9144 -0.406654)
			(end 1.1938 -0.406654)
			(stroke
				(width 0.1)
				(type default)
			)
			(layer "F.Fab")
		)
		(fp_line
			(start -0.9144 -0.406654)
			(end -0.9144 -0.508)
			(stroke
				(width 0.1)
				(type default)
			)
			(layer "F.Fab")
		)
		(fp_line
			(start -1.194308 -0.406654)
			(end -0.9144 -0.406654)
			(stroke
				(width 0.1)
				(type default)
			)
			(layer "F.Fab")
		)
		(fp_line
			(start 1.1938 0.4064)
			(end 0.9144 0.4064)
			(stroke
				(width 0.1)
				(type default)
			)
			(layer "F.Fab")
		)
		(fp_line
			(start 0.9144 0.4064)
			(end 0.9144 0.508)
			(stroke
				(width 0.1)
				(type default)
			)
			(layer "F.Fab")
		)
		(fp_line
			(start -0.9144 0.406654)
			(end -1.194308 0.406654)
			(stroke
				(width 0.1)
				(type default)
			)
			(layer "F.Fab")
		)
		(fp_line
			(start -1.194308 0.406654)
			(end -1.194308 -0.406654)
			(stroke
				(width 0.1)
				(type default)
			)
			(layer "F.Fab")
		)
		(fp_line
			(start 0.9144 0.508)
			(end -0.9144 0.508)
			(stroke
				(width 0.1)
				(type default)
			)
			(layer "F.Fab")
		)
		(fp_line
			(start -0.9144 0.508)
			(end -0.9144 0.406654)
			(stroke
				(width 0.1)
				(type default)
			)
			(layer "F.Fab")
		)
		(pad "1" smd rect
			(at -0.7366 0)
			(size 0.7112 0.8128)
			(layers "F.Cu" "F.Mask" "F.Paste")
			(net "P12V_AUX")
		)
		(pad "2" smd rect
			(at 0.7366 0)
			(size 0.7112 0.8128)
			(layers "F.Cu" "F.Mask" "F.Paste")
			(net "SW_P12V_AUX_P1V2_AUX_FLT")
		)
	)
	(footprint ""
		(layer "F.Cu")
		(at 35.65144 -108.09732 -90)
		(property "Reference" "R1007"
			(at 0 0 270)
			(layer "F.SilkS")
			(hide yes)
			(effects
				(font
					(size 1.27 1.27)
				)
			)
		)
		(property "Value" ""
			(at 0 0 270)
			(layer "F.Fab")
			(effects
				(font
					(size 1.27 1.27)
				)
			)
		)
		(duplicate_pad_numbers_are_jumpers no)
		(fp_line
			(start -0.7874 0.4064)
			(end -0.7874 -0.4064)
			(stroke
				(width 0.1524)
				(type default)
			)
			(layer "F.SilkS")
		)
		(fp_line
			(start 0.7874 0.4064)
			(end -0.7874 0.4064)
			(stroke
				(width 0.1524)
				(type default)
			)
			(layer "F.SilkS")
		)
		(fp_line
			(start -0.7874 -0.4064)
			(end 0.7874 -0.4064)
			(stroke
				(width 0.1524)
				(type default)
			)
			(layer "F.SilkS")
		)
		(fp_line
			(start 0.7874 -0.4064)
			(end 0.7874 0.4064)
			(stroke
				(width 0.1524)
				(type default)
			)
			(layer "F.SilkS")
		)
		(fp_line
			(start -0.67945 0.3048)
			(end -0.67945 -0.305054)
			(stroke
				(width 0.1)
				(type default)
			)
			(layer "F.Fab")
		)
		(fp_line
			(start -0.12065 0.3048)
			(end -0.67945 0.3048)
			(stroke
				(width 0.1)
				(type default)
			)
			(layer "F.Fab")
		)
		(fp_line
			(start 0.120396 0.3048)
			(end 0.120396 0.2794)
			(stroke
				(width 0.1)
				(type default)
			)
			(layer "F.Fab")
		)
		(fp_line
			(start 0.67945 0.3048)
			(end 0.120396 0.3048)
			(stroke
				(width 0.1)
				(type default)
			)
			(layer "F.Fab")
		)
		(fp_line
			(start -0.12065 0.2794)
			(end -0.12065 0.3048)
			(stroke
				(width 0.1)
				(type default)
			)
			(layer "F.Fab")
		)
		(fp_line
			(start 0.120396 0.2794)
			(end -0.12065 0.2794)
			(stroke
				(width 0.1)
				(type default)
			)
			(layer "F.Fab")
		)
		(fp_line
			(start -0.12065 -0.2794)
			(end 0.12065 -0.2794)
			(stroke
				(width 0.1)
				(type default)
			)
			(layer "F.Fab")
		)
		(fp_line
			(start 0.12065 -0.2794)
			(end 0.12065 -0.3048)
			(stroke
				(width 0.1)
				(type default)
			)
			(layer "F.Fab")
		)
		(fp_line
			(start 0.12065 -0.3048)
			(end 0.67945 -0.3048)
			(stroke
				(width 0.1)
				(type default)
			)
			(layer "F.Fab")
		)
		(fp_line
			(start 0.67945 -0.3048)
			(end 0.67945 0.3048)
			(stroke
				(width 0.1)
				(type default)
			)
			(layer "F.Fab")
		)
		(fp_line
			(start -0.67945 -0.305054)
			(end -0.12065 -0.305054)
			(stroke
				(width 0.1)
				(type default)
			)
			(layer "F.Fab")
		)
		(fp_line
			(start -0.12065 -0.305054)
			(end -0.12065 -0.2794)
			(stroke
				(width 0.1)
				(type default)
			)
			(layer "F.Fab")
		)
		(pad "1" smd circle
			(at -0.40005 0 270)
			(size 0 0)
			(layers "F.Cu" "F.Mask" "F.Paste")
			(net "P12V_AUX")
		)
		(pad "2" smd circle
			(at 0.40005 0 270)
			(size 0 0)
			(layers "F.Cu" "F.Mask" "F.Paste")
			(net "P12V_AUX_DSC_G1")
		)
	)
	(footprint ""
		(layer "F.Cu")
		(at 419.76294 -101.270308 90)
		(property "Reference" "PR3846"
			(at 0 0 90)
			(layer "F.SilkS")
			(hide yes)
			(effects
				(font
					(size 1.27 1.27)
				)
			)
		)
		(property "Value" ""
			(at 0 0 90)
			(layer "F.Fab")
			(effects
				(font
					(size 1.27 1.27)
				)
			)
		)
		(duplicate_pad_numbers_are_jumpers no)
		(fp_line
			(start 0.7874 -0.4064)
			(end 0.7874 0.4064)
			(stroke
				(width 0.1524)
				(type default)
			)
			(layer "F.SilkS")
		)
		(fp_line
			(start -0.7874 -0.4064)
			(end 0.7874 -0.4064)
			(stroke
				(width 0.1524)
				(type default)
			)
			(layer "F.SilkS")
		)
		(fp_line
			(start 0.7874 0.4064)
			(end -0.7874 0.4064)
			(stroke
				(width 0.1524)
				(type default)
			)
			(layer "F.SilkS")
		)
		(fp_line
			(start -0.7874 0.4064)
			(end -0.7874 -0.4064)
			(stroke
				(width 0.1524)
				(type default)
			)
			(layer "F.SilkS")
		)
		(fp_line
			(start -0.12065 -0.305054)
			(end -0.12065 -0.2794)
			(stroke
				(width 0.1)
				(type default)
			)
			(layer "F.Fab")
		)
		(fp_line
			(start -0.67945 -0.305054)
			(end -0.12065 -0.305054)
			(stroke
				(width 0.1)
				(type default)
			)
			(layer "F.Fab")
		)
		(fp_line
			(start 0.67945 -0.3048)
			(end 0.67945 0.3048)
			(stroke
				(width 0.1)
				(type default)
			)
			(layer "F.Fab")
		)
		(fp_line
			(start 0.12065 -0.3048)
			(end 0.67945 -0.3048)
			(stroke
				(width 0.1)
				(type default)
			)
			(layer "F.Fab")
		)
		(fp_line
			(start 0.12065 -0.2794)
			(end 0.12065 -0.3048)
			(stroke
				(width 0.1)
				(type default)
			)
			(layer "F.Fab")
		)
		(fp_line
			(start -0.12065 -0.2794)
			(end 0.12065 -0.2794)
			(stroke
				(width 0.1)
				(type default)
			)
			(layer "F.Fab")
		)
		(fp_line
			(start 0.120396 0.2794)
			(end -0.12065 0.2794)
			(stroke
				(width 0.1)
				(type default)
			)
			(layer "F.Fab")
		)
		(fp_line
			(start -0.12065 0.2794)
			(end -0.12065 0.3048)
			(stroke
				(width 0.1)
				(type default)
			)
			(layer "F.Fab")
		)
		(fp_line
			(start 0.67945 0.3048)
			(end 0.120396 0.3048)
			(stroke
				(width 0.1)
				(type default)
			)
			(layer "F.Fab")
		)
		(fp_line
			(start 0.120396 0.3048)
			(end 0.120396 0.2794)
			(stroke
				(width 0.1)
				(type default)
			)
			(layer "F.Fab")
		)
		(fp_line
			(start -0.12065 0.3048)
			(end -0.67945 0.3048)
			(stroke
				(width 0.1)
				(type default)
			)
			(layer "F.Fab")
		)
		(fp_line
			(start -0.67945 0.3048)
			(end -0.67945 -0.305054)
			(stroke
				(width 0.1)
				(type default)
			)
			(layer "F.Fab")
		)
		(pad "1" smd circle
			(at -0.40005 0 90)
			(size 0 0)
			(layers "F.Cu" "F.Mask" "F.Paste")
			(net "GND")
		)
		(pad "2" smd circle
			(at 0.40005 0 90)
			(size 0 0)
			(layers "F.Cu" "F.Mask" "F.Paste")
			(net "P3V3_OCP_ILIMIT_1")
		)
	)
	(footprint ""
		(layer "F.Cu")
		(at 200.98512 -332.612238 -90)
		(property "Reference" "PL72"
			(at -0.763524 -4.20243 90)
			(unlocked yes)
			(layer "F.SilkS")
			(effects
				(font
					(size 0.7874 0.5842)
					(thickness 0.1524)
				)
				(justify left)
			)
		)
		(property "Value" ""
			(at 0 0 270)
			(layer "F.Fab")
			(effects
				(font
					(size 1.27 1.27)
				)
			)
		)
		(duplicate_pad_numbers_are_jumpers no)
		(fp_line
			(start -3.64998 3.350006)
			(end -3.64998 1.8288)
			(stroke
				(width 0.1524)
				(type default)
			)
			(layer "F.SilkS")
		)
		(fp_line
			(start 3.64998 3.350006)
			(end -3.64998 3.350006)
			(stroke
				(width 0.1524)
				(type default)
			)
			(layer "F.SilkS")
		)
		(fp_line
			(start 3.64998 1.8034)
			(end 3.64998 3.350006)
			(stroke
				(width 0.1524)
				(type default)
			)
			(layer "F.SilkS")
		)
		(fp_line
			(start -3.64998 -1.8034)
			(end -3.64998 -3.350006)
			(stroke
				(width 0.1524)
				(type default)
			)
			(layer "F.SilkS")
		)
		(fp_line
			(start -3.6576 -3.350006)
			(end 3.64998 -3.350006)
			(stroke
				(width 0.1524)
				(type default)
			)
			(layer "F.SilkS")
		)
		(fp_line
			(start 3.64998 -3.350006)
			(end 3.64998 -1.8034)
			(stroke
				(width 0.1524)
				(type default)
			)
			(layer "F.SilkS")
		)
		(fp_line
			(start -3.64998 3.350006)
			(end -3.64998 -3.350006)
			(stroke
				(width 0.1)
				(type default)
			)
			(layer "F.Fab")
		)
		(fp_line
			(start 3.64998 3.350006)
			(end -3.64998 3.350006)
			(stroke
				(width 0.1)
				(type default)
			)
			(layer "F.Fab")
		)
		(fp_line
			(start -3.64998 -3.350006)
			(end 3.64998 -3.350006)
			(stroke
				(width 0.1)
				(type default)
			)
			(layer "F.Fab")
		)
		(fp_line
			(start 3.64998 -3.350006)
			(end 3.64998 3.350006)
			(stroke
				(width 0.1)
				(type default)
			)
			(layer "F.Fab")
		)
		(pad "1" smd rect
			(at -2.92481 0 270)
			(size 2.15392 3.302)
			(layers "F.Cu" "F.Mask" "F.Paste")
			(net "SW_PVDD_33_S5_SW")
		)
		(pad "2" smd rect
			(at 2.92481 0 270)
			(size 2.15392 3.302)
			(layers "F.Cu" "F.Mask" "F.Paste")
			(net "PVDD_33_S5")
		)
	)
	(footprint ""
		(layer "F.Cu")
		(at 435.621176 -103.77043 90)
		(property "Reference" "PC2144"
			(at 0 0 90)
			(layer "F.SilkS")
			(hide yes)
			(effects
				(font
					(size 1.27 1.27)
				)
			)
		)
		(property "Value" ""
			(at 0 0 90)
			(layer "F.Fab")
			(effects
				(font
					(size 1.27 1.27)
				)
			)
		)
		(duplicate_pad_numbers_are_jumpers no)
		(fp_line
			(start 0.7874 -0.4064)
			(end 0.7874 0.4064)
			(stroke
				(width 0.1524)
				(type default)
			)
			(layer "F.SilkS")
		)
		(fp_line
			(start -0.7874 -0.4064)
			(end 0.7874 -0.4064)
			(stroke
				(width 0.1524)
				(type default)
			)
			(layer "F.SilkS")
		)
		(fp_line
			(start 0.7874 0.4064)
			(end -0.7874 0.4064)
			(stroke
				(width 0.1524)
				(type default)
			)
			(layer "F.SilkS")
		)
		(fp_line
			(start -0.7874 0.4064)
			(end -0.7874 -0.4064)
			(stroke
				(width 0.1524)
				(type default)
			)
			(layer "F.SilkS")
		)
		(fp_line
			(start -0.12065 -0.305054)
			(end -0.12065 -0.2794)
			(stroke
				(width 0.1)
				(type default)
			)
			(layer "F.Fab")
		)
		(fp_line
			(start -0.67945 -0.305054)
			(end -0.12065 -0.305054)
			(stroke
				(width 0.1)
				(type default)
			)
			(layer "F.Fab")
		)
		(fp_line
			(start 0.67945 -0.3048)
			(end 0.67945 0.3048)
			(stroke
				(width 0.1)
				(type default)
			)
			(layer "F.Fab")
		)
		(fp_line
			(start 0.12065 -0.3048)
			(end 0.67945 -0.3048)
			(stroke
				(width 0.1)
				(type default)
			)
			(layer "F.Fab")
		)
		(fp_line
			(start 0.12065 -0.2794)
			(end 0.12065 -0.3048)
			(stroke
				(width 0.1)
				(type default)
			)
			(layer "F.Fab")
		)
		(fp_line
			(start -0.12065 -0.2794)
			(end 0.12065 -0.2794)
			(stroke
				(width 0.1)
				(type default)
			)
			(layer "F.Fab")
		)
		(fp_line
			(start 0.120396 0.2794)
			(end -0.12065 0.2794)
			(stroke
				(width 0.1)
				(type default)
			)
			(layer "F.Fab")
		)
		(fp_line
			(start -0.12065 0.2794)
			(end -0.12065 0.3048)
			(stroke
				(width 0.1)
				(type default)
			)
			(layer "F.Fab")
		)
		(fp_line
			(start 0.67945 0.3048)
			(end 0.120396 0.3048)
			(stroke
				(width 0.1)
				(type default)
			)
			(layer "F.Fab")
		)
		(fp_line
			(start 0.120396 0.3048)
			(end 0.120396 0.2794)
			(stroke
				(width 0.1)
				(type default)
			)
			(layer "F.Fab")
		)
		(fp_line
			(start -0.12065 0.3048)
			(end -0.67945 0.3048)
			(stroke
				(width 0.1)
				(type default)
			)
			(layer "F.Fab")
		)
		(fp_line
			(start -0.67945 0.3048)
			(end -0.67945 -0.305054)
			(stroke
				(width 0.1)
				(type default)
			)
			(layer "F.Fab")
		)
		(pad "1" smd circle
			(at -0.40005 0 90)
			(size 0 0)
			(layers "F.Cu" "F.Mask" "F.Paste")
			(net "P3V3_OCP_SFF_R")
		)
		(pad "2" smd circle
			(at 0.40005 0 90)
			(size 0 0)
			(layers "F.Cu" "F.Mask" "F.Paste")
			(net "P3V3_OCP_GATE_PU202_1")
		)
	)
	(footprint ""
		(layer "F.Cu")
		(at 111.133128 -179.906168 -90)
		(property "Reference" "PR523"
			(at 0 0 270)
			(layer "F.SilkS")
			(hide yes)
			(effects
				(font
					(size 1.27 1.27)
				)
			)
		)
		(property "Value" ""
			(at 0 0 270)
			(layer "F.Fab")
			(effects
				(font
					(size 1.27 1.27)
				)
			)
		)
		(duplicate_pad_numbers_are_jumpers no)
		(fp_line
			(start -0.7874 0.4064)
			(end -0.7874 -0.4064)
			(stroke
				(width 0.1524)
				(type default)
			)
			(layer "F.SilkS")
		)
		(fp_line
			(start 0.7874 0.4064)
			(end -0.7874 0.4064)
			(stroke
				(width 0.1524)
				(type default)
			)
			(layer "F.SilkS")
		)
		(fp_line
			(start -0.7874 -0.4064)
			(end 0.7874 -0.4064)
			(stroke
				(width 0.1524)
				(type default)
			)
			(layer "F.SilkS")
		)
		(fp_line
			(start 0.7874 -0.4064)
			(end 0.7874 0.4064)
			(stroke
				(width 0.1524)
				(type default)
			)
			(layer "F.SilkS")
		)
		(fp_line
			(start -0.67945 0.3048)
			(end -0.67945 -0.305054)
			(stroke
				(width 0.1)
				(type default)
			)
			(layer "F.Fab")
		)
		(fp_line
			(start -0.12065 0.3048)
			(end -0.67945 0.3048)
			(stroke
				(width 0.1)
				(type default)
			)
			(layer "F.Fab")
		)
		(fp_line
			(start 0.120396 0.3048)
			(end 0.120396 0.2794)
			(stroke
				(width 0.1)
				(type default)
			)
			(layer "F.Fab")
		)
		(fp_line
			(start 0.67945 0.3048)
			(end 0.120396 0.3048)
			(stroke
				(width 0.1)
				(type default)
			)
			(layer "F.Fab")
		)
		(fp_line
			(start -0.12065 0.2794)
			(end -0.12065 0.3048)
			(stroke
				(width 0.1)
				(type default)
			)
			(layer "F.Fab")
		)
		(fp_line
			(start 0.120396 0.2794)
			(end -0.12065 0.2794)
			(stroke
				(width 0.1)
				(type default)
			)
			(layer "F.Fab")
		)
		(fp_line
			(start -0.12065 -0.2794)
			(end 0.12065 -0.2794)
			(stroke
				(width 0.1)
				(type default)
			)
			(layer "F.Fab")
		)
		(fp_line
			(start 0.12065 -0.2794)
			(end 0.12065 -0.3048)
			(stroke
				(width 0.1)
				(type default)
			)
			(layer "F.Fab")
		)
		(fp_line
			(start 0.12065 -0.3048)
			(end 0.67945 -0.3048)
			(stroke
				(width 0.1)
				(type default)
			)
			(layer "F.Fab")
		)
		(fp_line
			(start 0.67945 -0.3048)
			(end 0.67945 0.3048)
			(stroke
				(width 0.1)
				(type default)
			)
			(layer "F.Fab")
		)
		(fp_line
			(start -0.67945 -0.305054)
			(end -0.12065 -0.305054)
			(stroke
				(width 0.1)
				(type default)
			)
			(layer "F.Fab")
		)
		(fp_line
			(start -0.12065 -0.305054)
			(end -0.12065 -0.2794)
			(stroke
				(width 0.1)
				(type default)
			)
			(layer "F.Fab")
		)
		(pad "1" smd circle
			(at -0.40005 0 270)
			(size 0 0)
			(layers "F.Cu" "F.Mask" "F.Paste")
			(net "SW_PVDDCR_CPU0_P1_SW4_RC")
		)
		(pad "2" smd circle
			(at 0.40005 0 270)
			(size 0 0)
			(layers "F.Cu" "F.Mask" "F.Paste")
			(net "GND")
		)
	)
	(footprint ""
		(layer "F.Cu")
		(at 361.22229 -395.1732 90)
		(property "Reference" "R1016"
			(at 0 0 90)
			(layer "F.SilkS")
			(hide yes)
			(effects
				(font
					(size 1.27 1.27)
				)
			)
		)
		(property "Value" ""
			(at 0 0 90)
			(layer "F.Fab")
			(effects
				(font
					(size 1.27 1.27)
				)
			)
		)
		(duplicate_pad_numbers_are_jumpers no)
		(fp_line
			(start 0.32512 -0.175006)
			(end 0.32512 0.175006)
			(stroke
				(width 0.1)
				(type default)
			)
			(layer "F.Fab")
		)
		(fp_line
			(start -0.32512 -0.175006)
			(end 0.32512 -0.175006)
			(stroke
				(width 0.1)
				(type default)
			)
			(layer "F.Fab")
		)
		(fp_line
			(start 0.32512 0.175006)
			(end -0.32512 0.175006)
			(stroke
				(width 0.1)
				(type default)
			)
			(layer "F.Fab")
		)
		(fp_line
			(start -0.32512 0.175006)
			(end -0.32512 -0.175006)
			(stroke
				(width 0.1)
				(type default)
			)
			(layer "F.Fab")
		)
		(pad "1" smd rect
			(at -0.2667 0 90)
			(size 0.3048 0.381)
			(layers "F.Cu" "F.Mask" "F.Paste")
			(net "RT_CPU0_P1_ADDR2")
		)
		(pad "2" smd rect
			(at 0.2667 0 270)
			(size 0.3048 0.381)
			(layers "F.Cu" "F.Mask" "F.Paste")
			(net "GND")
		)
	)
	(footprint ""
		(layer "F.Cu")
		(at 96.058736 -119.469154 -90)
		(property "Reference" "R1363"
			(at 0 0 270)
			(layer "F.SilkS")
			(hide yes)
			(effects
				(font
					(size 1.27 1.27)
				)
			)
		)
		(property "Value" ""
			(at 0 0 270)
			(layer "F.Fab")
			(effects
				(font
					(size 1.27 1.27)
				)
			)
		)
		(duplicate_pad_numbers_are_jumpers no)
		(fp_line
			(start -0.7874 0.4064)
			(end -0.7874 -0.4064)
			(stroke
				(width 0.1524)
				(type default)
			)
			(layer "F.SilkS")
		)
		(fp_line
			(start 0.7874 0.4064)
			(end -0.7874 0.4064)
			(stroke
				(width 0.1524)
				(type default)
			)
			(layer "F.SilkS")
		)
		(fp_line
			(start -0.7874 -0.4064)
			(end 0.7874 -0.4064)
			(stroke
				(width 0.1524)
				(type default)
			)
			(layer "F.SilkS")
		)
		(fp_line
			(start 0.7874 -0.4064)
			(end 0.7874 0.4064)
			(stroke
				(width 0.1524)
				(type default)
			)
			(layer "F.SilkS")
		)
		(fp_line
			(start -0.67945 0.3048)
			(end -0.67945 -0.305054)
			(stroke
				(width 0.1)
				(type default)
			)
			(layer "F.Fab")
		)
		(fp_line
			(start -0.12065 0.3048)
			(end -0.67945 0.3048)
			(stroke
				(width 0.1)
				(type default)
			)
			(layer "F.Fab")
		)
		(fp_line
			(start 0.120396 0.3048)
			(end 0.120396 0.2794)
			(stroke
				(width 0.1)
				(type default)
			)
			(layer "F.Fab")
		)
		(fp_line
			(start 0.67945 0.3048)
			(end 0.120396 0.3048)
			(stroke
				(width 0.1)
				(type default)
			)
			(layer "F.Fab")
		)
		(fp_line
			(start -0.12065 0.2794)
			(end -0.12065 0.3048)
			(stroke
				(width 0.1)
				(type default)
			)
			(layer "F.Fab")
		)
		(fp_line
			(start 0.120396 0.2794)
			(end -0.12065 0.2794)
			(stroke
				(width 0.1)
				(type default)
			)
			(layer "F.Fab")
		)
		(fp_line
			(start -0.12065 -0.2794)
			(end 0.12065 -0.2794)
			(stroke
				(width 0.1)
				(type default)
			)
			(layer "F.Fab")
		)
		(fp_line
			(start 0.12065 -0.2794)
			(end 0.12065 -0.3048)
			(stroke
				(width 0.1)
				(type default)
			)
			(layer "F.Fab")
		)
		(fp_line
			(start 0.12065 -0.3048)
			(end 0.67945 -0.3048)
			(stroke
				(width 0.1)
				(type default)
			)
			(layer "F.Fab")
		)
		(fp_line
			(start 0.67945 -0.3048)
			(end 0.67945 0.3048)
			(stroke
				(width 0.1)
				(type default)
			)
			(layer "F.Fab")
		)
		(fp_line
			(start -0.67945 -0.305054)
			(end -0.12065 -0.305054)
			(stroke
				(width 0.1)
				(type default)
			)
			(layer "F.Fab")
		)
		(fp_line
			(start -0.12065 -0.305054)
			(end -0.12065 -0.2794)
			(stroke
				(width 0.1)
				(type default)
			)
			(layer "F.Fab")
		)
		(pad "1" smd circle
			(at -0.40005 0 270)
			(size 0 0)
			(layers "F.Cu" "F.Mask" "F.Paste")
			(net "PWRGD_P12V_MEM")
		)
		(pad "2" smd circle
			(at 0.40005 0 270)
			(size 0 0)
			(layers "F.Cu" "F.Mask" "F.Paste")
			(net "PWRGD_P12V_MEM_R")
		)
	)
	(footprint ""
		(layer "F.Cu")
		(at 110.235238 -39.40175 90)
		(property "Reference" "R6290"
			(at 0 0 90)
			(layer "F.SilkS")
			(hide yes)
			(effects
				(font
					(size 1.27 1.27)
				)
			)
		)
		(property "Value" ""
			(at 0 0 90)
			(layer "F.Fab")
			(effects
				(font
					(size 1.27 1.27)
				)
			)
		)
		(duplicate_pad_numbers_are_jumpers no)
		(fp_line
			(start 0.7874 -0.4064)
			(end 0.7874 0.4064)
			(stroke
				(width 0.1524)
				(type default)
			)
			(layer "F.SilkS")
		)
		(fp_line
			(start -0.7874 -0.4064)
			(end 0.7874 -0.4064)
			(stroke
				(width 0.1524)
				(type default)
			)
			(layer "F.SilkS")
		)
		(fp_line
			(start 0.7874 0.4064)
			(end -0.7874 0.4064)
			(stroke
				(width 0.1524)
				(type default)
			)
			(layer "F.SilkS")
		)
		(fp_line
			(start -0.7874 0.4064)
			(end -0.7874 -0.4064)
			(stroke
				(width 0.1524)
				(type default)
			)
			(layer "F.SilkS")
		)
		(fp_line
			(start -0.12065 -0.305054)
			(end -0.12065 -0.2794)
			(stroke
				(width 0.1)
				(type default)
			)
			(layer "F.Fab")
		)
		(fp_line
			(start -0.67945 -0.305054)
			(end -0.12065 -0.305054)
			(stroke
				(width 0.1)
				(type default)
			)
			(layer "F.Fab")
		)
		(fp_line
			(start 0.67945 -0.3048)
			(end 0.67945 0.3048)
			(stroke
				(width 0.1)
				(type default)
			)
			(layer "F.Fab")
		)
		(fp_line
			(start 0.12065 -0.3048)
			(end 0.67945 -0.3048)
			(stroke
				(width 0.1)
				(type default)
			)
			(layer "F.Fab")
		)
		(fp_line
			(start 0.12065 -0.2794)
			(end 0.12065 -0.3048)
			(stroke
				(width 0.1)
				(type default)
			)
			(layer "F.Fab")
		)
		(fp_line
			(start -0.12065 -0.2794)
			(end 0.12065 -0.2794)
			(stroke
				(width 0.1)
				(type default)
			)
			(layer "F.Fab")
		)
		(fp_line
			(start 0.120396 0.2794)
			(end -0.12065 0.2794)
			(stroke
				(width 0.1)
				(type default)
			)
			(layer "F.Fab")
		)
		(fp_line
			(start -0.12065 0.2794)
			(end -0.12065 0.3048)
			(stroke
				(width 0.1)
				(type default)
			)
			(layer "F.Fab")
		)
		(fp_line
			(start 0.67945 0.3048)
			(end 0.120396 0.3048)
			(stroke
				(width 0.1)
				(type default)
			)
			(layer "F.Fab")
		)
		(fp_line
			(start 0.120396 0.3048)
			(end 0.120396 0.2794)
			(stroke
				(width 0.1)
				(type default)
			)
			(layer "F.Fab")
		)
		(fp_line
			(start -0.12065 0.3048)
			(end -0.67945 0.3048)
			(stroke
				(width 0.1)
				(type default)
			)
			(layer "F.Fab")
		)
		(fp_line
			(start -0.67945 0.3048)
			(end -0.67945 -0.305054)
			(stroke
				(width 0.1)
				(type default)
			)
			(layer "F.Fab")
		)
		(pad "1" smd circle
			(at -0.40005 0 90)
			(size 0 0)
			(layers "F.Cu" "F.Mask" "F.Paste")
			(net "USB_HUB2_TI_GANGED_MRP_I2C_SLV_CFG0")
		)
		(pad "2" smd circle
			(at 0.40005 0 90)
			(size 0 0)
			(layers "F.Cu" "F.Mask" "F.Paste")
			(net "USB_HUB2_TI_GANGED")
		)
	)
	(footprint ""
		(layer "F.Cu")
		(at 169.121328 -388.366 90)
		(property "Reference" "C369"
			(at 0 0 90)
			(layer "F.SilkS")
			(hide yes)
			(effects
				(font
					(size 1.27 1.27)
				)
			)
		)
		(property "Value" ""
			(at 0 0 90)
			(layer "F.Fab")
			(effects
				(font
					(size 1.27 1.27)
				)
			)
		)
		(duplicate_pad_numbers_are_jumpers no)
		(fp_line
			(start 0.7874 -0.4064)
			(end 0.7874 0.4064)
			(stroke
				(width 0.1524)
				(type default)
			)
			(layer "F.SilkS")
		)
		(fp_line
			(start -0.7874 -0.4064)
			(end 0.7874 -0.4064)
			(stroke
				(width 0.1524)
				(type default)
			)
			(layer "F.SilkS")
		)
		(fp_line
			(start 0.7874 0.4064)
			(end -0.7874 0.4064)
			(stroke
				(width 0.1524)
				(type default)
			)
			(layer "F.SilkS")
		)
		(fp_line
			(start -0.7874 0.4064)
			(end -0.7874 -0.4064)
			(stroke
				(width 0.1524)
				(type default)
			)
			(layer "F.SilkS")
		)
		(fp_line
			(start -0.12065 -0.305054)
			(end -0.12065 -0.2794)
			(stroke
				(width 0.1)
				(type default)
			)
			(layer "F.Fab")
		)
		(fp_line
			(start -0.67945 -0.305054)
			(end -0.12065 -0.305054)
			(stroke
				(width 0.1)
				(type default)
			)
			(layer "F.Fab")
		)
		(fp_line
			(start 0.67945 -0.3048)
			(end 0.67945 0.3048)
			(stroke
				(width 0.1)
				(type default)
			)
			(layer "F.Fab")
		)
		(fp_line
			(start 0.12065 -0.3048)
			(end 0.67945 -0.3048)
			(stroke
				(width 0.1)
				(type default)
			)
			(layer "F.Fab")
		)
		(fp_line
			(start 0.12065 -0.2794)
			(end 0.12065 -0.3048)
			(stroke
				(width 0.1)
				(type default)
			)
			(layer "F.Fab")
		)
		(fp_line
			(start -0.12065 -0.2794)
			(end 0.12065 -0.2794)
			(stroke
				(width 0.1)
				(type default)
			)
			(layer "F.Fab")
		)
		(fp_line
			(start 0.120396 0.2794)
			(end -0.12065 0.2794)
			(stroke
				(width 0.1)
				(type default)
			)
			(layer "F.Fab")
		)
		(fp_line
			(start -0.12065 0.2794)
			(end -0.12065 0.3048)
			(stroke
				(width 0.1)
				(type default)
			)
			(layer "F.Fab")
		)
		(fp_line
			(start 0.67945 0.3048)
			(end 0.120396 0.3048)
			(stroke
				(width 0.1)
				(type default)
			)
			(layer "F.Fab")
		)
		(fp_line
			(start 0.120396 0.3048)
			(end 0.120396 0.2794)
			(stroke
				(width 0.1)
				(type default)
			)
			(layer "F.Fab")
		)
		(fp_line
			(start -0.12065 0.3048)
			(end -0.67945 0.3048)
			(stroke
				(width 0.1)
				(type default)
			)
			(layer "F.Fab")
		)
		(fp_line
			(start -0.67945 0.3048)
			(end -0.67945 -0.305054)
			(stroke
				(width 0.1)
				(type default)
			)
			(layer "F.Fab")
		)
		(pad "1" smd circle
			(at -0.40005 0 90)
			(size 0 0)
			(layers "F.Cu" "F.Mask" "F.Paste")
			(net "P1V8_CPU1_RT2_1A")
		)
		(pad "2" smd circle
			(at 0.40005 0 90)
			(size 0 0)
			(layers "F.Cu" "F.Mask" "F.Paste")
			(net "GND")
		)
	)
	(footprint ""
		(layer "F.Cu")
		(at 422.26611 -365.804196 90)
		(property "Reference" "PC200"
			(at 0 0 90)
			(layer "F.SilkS")
			(hide yes)
			(effects
				(font
					(size 1.27 1.27)
				)
			)
		)
		(property "Value" ""
			(at 0 0 90)
			(layer "F.Fab")
			(effects
				(font
					(size 1.27 1.27)
				)
			)
		)
		(duplicate_pad_numbers_are_jumpers no)
		(fp_line
			(start 0.7874 -0.4064)
			(end 0.7874 0.4064)
			(stroke
				(width 0.1524)
				(type default)
			)
			(layer "F.SilkS")
		)
		(fp_line
			(start -0.7874 -0.4064)
			(end 0.7874 -0.4064)
			(stroke
				(width 0.1524)
				(type default)
			)
			(layer "F.SilkS")
		)
		(fp_line
			(start 0.7874 0.4064)
			(end -0.7874 0.4064)
			(stroke
				(width 0.1524)
				(type default)
			)
			(layer "F.SilkS")
		)
		(fp_line
			(start -0.7874 0.4064)
			(end -0.7874 -0.4064)
			(stroke
				(width 0.1524)
				(type default)
			)
			(layer "F.SilkS")
		)
		(fp_line
			(start -0.12065 -0.305054)
			(end -0.12065 -0.2794)
			(stroke
				(width 0.1)
				(type default)
			)
			(layer "F.Fab")
		)
		(fp_line
			(start -0.67945 -0.305054)
			(end -0.12065 -0.305054)
			(stroke
				(width 0.1)
				(type default)
			)
			(layer "F.Fab")
		)
		(fp_line
			(start 0.67945 -0.3048)
			(end 0.67945 0.3048)
			(stroke
				(width 0.1)
				(type default)
			)
			(layer "F.Fab")
		)
		(fp_line
			(start 0.12065 -0.3048)
			(end 0.67945 -0.3048)
			(stroke
				(width 0.1)
				(type default)
			)
			(layer "F.Fab")
		)
		(fp_line
			(start 0.12065 -0.2794)
			(end 0.12065 -0.3048)
			(stroke
				(width 0.1)
				(type default)
			)
			(layer "F.Fab")
		)
		(fp_line
			(start -0.12065 -0.2794)
			(end 0.12065 -0.2794)
			(stroke
				(width 0.1)
				(type default)
			)
			(layer "F.Fab")
		)
		(fp_line
			(start 0.120396 0.2794)
			(end -0.12065 0.2794)
			(stroke
				(width 0.1)
				(type default)
			)
			(layer "F.Fab")
		)
		(fp_line
			(start -0.12065 0.2794)
			(end -0.12065 0.3048)
			(stroke
				(width 0.1)
				(type default)
			)
			(layer "F.Fab")
		)
		(fp_line
			(start 0.67945 0.3048)
			(end 0.120396 0.3048)
			(stroke
				(width 0.1)
				(type default)
			)
			(layer "F.Fab")
		)
		(fp_line
			(start 0.120396 0.3048)
			(end 0.120396 0.2794)
			(stroke
				(width 0.1)
				(type default)
			)
			(layer "F.Fab")
		)
		(fp_line
			(start -0.12065 0.3048)
			(end -0.67945 0.3048)
			(stroke
				(width 0.1)
				(type default)
			)
			(layer "F.Fab")
		)
		(fp_line
			(start -0.67945 0.3048)
			(end -0.67945 -0.305054)
			(stroke
				(width 0.1)
				(type default)
			)
			(layer "F.Fab")
		)
		(pad "1" smd circle
			(at -0.40005 0 90)
			(size 0 0)
			(layers "F.Cu" "F.Mask" "F.Paste")
			(net "PVDD11_S3_P0_VCC")
		)
		(pad "2" smd circle
			(at 0.40005 0 90)
			(size 0 0)
			(layers "F.Cu" "F.Mask" "F.Paste")
			(net "GND")
		)
	)
	(footprint ""
		(layer "F.Cu")
		(at 213.928198 -123.565412)
		(property "Reference" "R877"
			(at 0 0 0)
			(layer "F.SilkS")
			(hide yes)
			(effects
				(font
					(size 1.27 1.27)
				)
			)
		)
		(property "Value" ""
			(at 0 0 0)
			(layer "F.Fab")
			(effects
				(font
					(size 1.27 1.27)
				)
			)
		)
		(duplicate_pad_numbers_are_jumpers no)
		(fp_line
			(start -0.7874 -0.4064)
			(end 0.7874 -0.4064)
			(stroke
				(width 0.1524)
				(type default)
			)
			(layer "F.SilkS")
		)
		(fp_line
			(start -0.7874 0.4064)
			(end -0.7874 -0.4064)
			(stroke
				(width 0.1524)
				(type default)
			)
			(layer "F.SilkS")
		)
		(fp_line
			(start 0.7874 -0.4064)
			(end 0.7874 0.4064)
			(stroke
				(width 0.1524)
				(type default)
			)
			(layer "F.SilkS")
		)
		(fp_line
			(start 0.7874 0.4064)
			(end -0.7874 0.4064)
			(stroke
				(width 0.1524)
				(type default)
			)
			(layer "F.SilkS")
		)
		(fp_line
			(start -0.67945 -0.305054)
			(end -0.12065 -0.305054)
			(stroke
				(width 0.1)
				(type default)
			)
			(layer "F.Fab")
		)
		(fp_line
			(start -0.67945 0.3048)
			(end -0.67945 -0.305054)
			(stroke
				(width 0.1)
				(type default)
			)
			(layer "F.Fab")
		)
		(fp_line
			(start -0.12065 -0.305054)
			(end -0.12065 -0.2794)
			(stroke
				(width 0.1)
				(type default)
			)
			(layer "F.Fab")
		)
		(fp_line
			(start -0.12065 -0.2794)
			(end 0.12065 -0.2794)
			(stroke
				(width 0.1)
				(type default)
			)
			(layer "F.Fab")
		)
		(fp_line
			(start -0.12065 0.2794)
			(end -0.12065 0.3048)
			(stroke
				(width 0.1)
				(type default)
			)
			(layer "F.Fab")
		)
		(fp_line
			(start -0.12065 0.3048)
			(end -0.67945 0.3048)
			(stroke
				(width 0.1)
				(type default)
			)
			(layer "F.Fab")
		)
		(fp_line
			(start 0.120396 0.2794)
			(end -0.12065 0.2794)
			(stroke
				(width 0.1)
				(type default)
			)
			(layer "F.Fab")
		)
		(fp_line
			(start 0.120396 0.3048)
			(end 0.120396 0.2794)
			(stroke
				(width 0.1)
				(type default)
			)
			(layer "F.Fab")
		)
		(fp_line
			(start 0.12065 -0.3048)
			(end 0.67945 -0.3048)
			(stroke
				(width 0.1)
				(type default)
			)
			(layer "F.Fab")
		)
		(fp_line
			(start 0.12065 -0.2794)
			(end 0.12065 -0.3048)
			(stroke
				(width 0.1)
				(type default)
			)
			(layer "F.Fab")
		)
		(fp_line
			(start 0.67945 -0.3048)
			(end 0.67945 0.3048)
			(stroke
				(width 0.1)
				(type default)
			)
			(layer "F.Fab")
		)
		(fp_line
			(start 0.67945 0.3048)
			(end 0.120396 0.3048)
			(stroke
				(width 0.1)
				(type default)
			)
			(layer "F.Fab")
		)
		(pad "1" smd circle
			(at -0.40005 0)
			(size 0 0)
			(layers "F.Cu" "F.Mask" "F.Paste")
			(net "RST_PERST_OCP_SFF_BUF2_N")
		)
		(pad "2" smd circle
			(at 0.40005 0)
			(size 0 0)
			(layers "F.Cu" "F.Mask" "F.Paste")
			(net "RST_PERST0_OCP_SFF_N")
		)
	)
	(footprint ""
		(layer "F.Cu")
		(at 109.918754 -327.582276 180)
		(property "Reference" "PR226"
			(at 0 0 180)
			(layer "F.SilkS")
			(hide yes)
			(effects
				(font
					(size 1.27 1.27)
				)
			)
		)
		(property "Value" ""
			(at 0 0 180)
			(layer "F.Fab")
			(effects
				(font
					(size 1.27 1.27)
				)
			)
		)
		(duplicate_pad_numbers_are_jumpers no)
		(fp_line
			(start 0.7874 0.4064)
			(end -0.7874 0.4064)
			(stroke
				(width 0.1524)
				(type default)
			)
			(layer "F.SilkS")
		)
		(fp_line
			(start 0.7874 -0.4064)
			(end 0.7874 0.4064)
			(stroke
				(width 0.1524)
				(type default)
			)
			(layer "F.SilkS")
		)
		(fp_line
			(start -0.7874 0.4064)
			(end -0.7874 -0.4064)
			(stroke
				(width 0.1524)
				(type default)
			)
			(layer "F.SilkS")
		)
		(fp_line
			(start -0.7874 -0.4064)
			(end 0.7874 -0.4064)
			(stroke
				(width 0.1524)
				(type default)
			)
			(layer "F.SilkS")
		)
		(fp_line
			(start 0.67945 0.3048)
			(end 0.120396 0.3048)
			(stroke
				(width 0.1)
				(type default)
			)
			(layer "F.Fab")
		)
		(fp_line
			(start 0.67945 -0.3048)
			(end 0.67945 0.3048)
			(stroke
				(width 0.1)
				(type default)
			)
			(layer "F.Fab")
		)
		(fp_line
			(start 0.12065 -0.2794)
			(end 0.12065 -0.3048)
			(stroke
				(width 0.1)
				(type default)
			)
			(layer "F.Fab")
		)
		(fp_line
			(start 0.12065 -0.3048)
			(end 0.67945 -0.3048)
			(stroke
				(width 0.1)
				(type default)
			)
			(layer "F.Fab")
		)
		(fp_line
			(start 0.120396 0.3048)
			(end 0.120396 0.2794)
			(stroke
				(width 0.1)
				(type default)
			)
			(layer "F.Fab")
		)
		(fp_line
			(start 0.120396 0.2794)
			(end -0.12065 0.2794)
			(stroke
				(width 0.1)
				(type default)
			)
			(layer "F.Fab")
		)
		(fp_line
			(start -0.12065 0.3048)
			(end -0.67945 0.3048)
			(stroke
				(width 0.1)
				(type default)
			)
			(layer "F.Fab")
		)
		(fp_line
			(start -0.12065 0.2794)
			(end -0.12065 0.3048)
			(stroke
				(width 0.1)
				(type default)
			)
			(layer "F.Fab")
		)
		(fp_line
			(start -0.12065 -0.2794)
			(end 0.12065 -0.2794)
			(stroke
				(width 0.1)
				(type default)
			)
			(layer "F.Fab")
		)
		(fp_line
			(start -0.12065 -0.305054)
			(end -0.12065 -0.2794)
			(stroke
				(width 0.1)
				(type default)
			)
			(layer "F.Fab")
		)
		(fp_line
			(start -0.67945 0.3048)
			(end -0.67945 -0.305054)
			(stroke
				(width 0.1)
				(type default)
			)
			(layer "F.Fab")
		)
		(fp_line
			(start -0.67945 -0.305054)
			(end -0.12065 -0.305054)
			(stroke
				(width 0.1)
				(type default)
			)
			(layer "F.Fab")
		)
		(pad "1" smd circle
			(at -0.40005 0 180)
			(size 0 0)
			(layers "F.Cu" "F.Mask" "F.Paste")
			(net "VSENSE_VSS_SENSE_C_P1")
		)
		(pad "2" smd circle
			(at 0.40005 0 180)
			(size 0 0)
			(layers "F.Cu" "F.Mask" "F.Paste")
			(net "GND")
		)
	)
	(footprint ""
		(layer "F.Cu")
		(at 165.2016 -438.912)
		(property "Reference" "C1773"
			(at 0 0 0)
			(layer "F.SilkS")
			(hide yes)
			(effects
				(font
					(size 1.27 1.27)
				)
			)
		)
		(property "Value" ""
			(at 0 0 0)
			(layer "F.Fab")
			(effects
				(font
					(size 1.27 1.27)
				)
			)
		)
		(duplicate_pad_numbers_are_jumpers no)
		(fp_line
			(start -0.7874 -0.4064)
			(end 0.7874 -0.4064)
			(stroke
				(width 0.1524)
				(type default)
			)
			(layer "F.SilkS")
		)
		(fp_line
			(start -0.7874 0.4064)
			(end -0.7874 -0.4064)
			(stroke
				(width 0.1524)
				(type default)
			)
			(layer "F.SilkS")
		)
		(fp_line
			(start 0.7874 -0.4064)
			(end 0.7874 0.4064)
			(stroke
				(width 0.1524)
				(type default)
			)
			(layer "F.SilkS")
		)
		(fp_line
			(start 0.7874 0.4064)
			(end -0.7874 0.4064)
			(stroke
				(width 0.1524)
				(type default)
			)
			(layer "F.SilkS")
		)
		(fp_line
			(start -0.67945 -0.305054)
			(end -0.12065 -0.305054)
			(stroke
				(width 0.1)
				(type default)
			)
			(layer "F.Fab")
		)
		(fp_line
			(start -0.67945 0.3048)
			(end -0.67945 -0.305054)
			(stroke
				(width 0.1)
				(type default)
			)
			(layer "F.Fab")
		)
		(fp_line
			(start -0.12065 -0.305054)
			(end -0.12065 -0.2794)
			(stroke
				(width 0.1)
				(type default)
			)
			(layer "F.Fab")
		)
		(fp_line
			(start -0.12065 -0.2794)
			(end 0.12065 -0.2794)
			(stroke
				(width 0.1)
				(type default)
			)
			(layer "F.Fab")
		)
		(fp_line
			(start -0.12065 0.2794)
			(end -0.12065 0.3048)
			(stroke
				(width 0.1)
				(type default)
			)
			(layer "F.Fab")
		)
		(fp_line
			(start -0.12065 0.3048)
			(end -0.67945 0.3048)
			(stroke
				(width 0.1)
				(type default)
			)
			(layer "F.Fab")
		)
		(fp_line
			(start 0.120396 0.2794)
			(end -0.12065 0.2794)
			(stroke
				(width 0.1)
				(type default)
			)
			(layer "F.Fab")
		)
		(fp_line
			(start 0.120396 0.3048)
			(end 0.120396 0.2794)
			(stroke
				(width 0.1)
				(type default)
			)
			(layer "F.Fab")
		)
		(fp_line
			(start 0.12065 -0.3048)
			(end 0.67945 -0.3048)
			(stroke
				(width 0.1)
				(type default)
			)
			(layer "F.Fab")
		)
		(fp_line
			(start 0.12065 -0.2794)
			(end 0.12065 -0.3048)
			(stroke
				(width 0.1)
				(type default)
			)
			(layer "F.Fab")
		)
		(fp_line
			(start 0.67945 -0.3048)
			(end 0.67945 0.3048)
			(stroke
				(width 0.1)
				(type default)
			)
			(layer "F.Fab")
		)
		(fp_line
			(start 0.67945 0.3048)
			(end 0.120396 0.3048)
			(stroke
				(width 0.1)
				(type default)
			)
			(layer "F.Fab")
		)
		(pad "1" smd circle
			(at -0.40005 0)
			(size 0 0)
			(layers "F.Cu" "F.Mask" "F.Paste")
			(net "BIC_MONITER_ISO")
		)
		(pad "2" smd circle
			(at 0.40005 0)
			(size 0 0)
			(layers "F.Cu" "F.Mask" "F.Paste")
			(net "GND")
		)
	)
	(footprint ""
		(layer "F.Cu")
		(at 21.938996 -390.949434 90)
		(property "Reference" "PC6645"
			(at 0 0 90)
			(layer "F.SilkS")
			(hide yes)
			(effects
				(font
					(size 1.27 1.27)
				)
			)
		)
		(property "Value" ""
			(at 0 0 90)
			(layer "F.Fab")
			(effects
				(font
					(size 1.27 1.27)
				)
			)
		)
		(duplicate_pad_numbers_are_jumpers no)
		(fp_line
			(start 0.7874 -0.4064)
			(end 0.7874 -0.221996)
			(stroke
				(width 0.1524)
				(type default)
			)
			(layer "F.SilkS")
		)
		(fp_line
			(start -0.7874 -0.4064)
			(end 0.7874 -0.4064)
			(stroke
				(width 0.1524)
				(type default)
			)
			(layer "F.SilkS")
		)
		(fp_line
			(start 0.464566 0.4064)
			(end -0.7874 0.4064)
			(stroke
				(width 0.1524)
				(type default)
			)
			(layer "F.SilkS")
		)
		(fp_line
			(start -0.7874 0.4064)
			(end -0.7874 -0.4064)
			(stroke
				(width 0.1524)
				(type default)
			)
			(layer "F.SilkS")
		)
		(fp_line
			(start -0.12065 -0.305054)
			(end -0.12065 -0.2794)
			(stroke
				(width 0.1)
				(type default)
			)
			(layer "F.Fab")
		)
		(fp_line
			(start -0.67945 -0.305054)
			(end -0.12065 -0.305054)
			(stroke
				(width 0.1)
				(type default)
			)
			(layer "F.Fab")
		)
		(fp_line
			(start 0.67945 -0.3048)
			(end 0.67945 0.3048)
			(stroke
				(width 0.1)
				(type default)
			)
			(layer "F.Fab")
		)
		(fp_line
			(start 0.12065 -0.3048)
			(end 0.67945 -0.3048)
			(stroke
				(width 0.1)
				(type default)
			)
			(layer "F.Fab")
		)
		(fp_line
			(start 0.12065 -0.2794)
			(end 0.12065 -0.3048)
			(stroke
				(width 0.1)
				(type default)
			)
			(layer "F.Fab")
		)
		(fp_line
			(start -0.12065 -0.2794)
			(end 0.12065 -0.2794)
			(stroke
				(width 0.1)
				(type default)
			)
			(layer "F.Fab")
		)
		(fp_line
			(start 0.120396 0.2794)
			(end -0.12065 0.2794)
			(stroke
				(width 0.1)
				(type default)
			)
			(layer "F.Fab")
		)
		(fp_line
			(start -0.12065 0.2794)
			(end -0.12065 0.3048)
			(stroke
				(width 0.1)
				(type default)
			)
			(layer "F.Fab")
		)
		(fp_line
			(start 0.67945 0.3048)
			(end 0.120396 0.3048)
			(stroke
				(width 0.1)
				(type default)
			)
			(layer "F.Fab")
		)
		(fp_line
			(start 0.120396 0.3048)
			(end 0.120396 0.2794)
			(stroke
				(width 0.1)
				(type default)
			)
			(layer "F.Fab")
		)
		(fp_line
			(start -0.12065 0.3048)
			(end -0.67945 0.3048)
			(stroke
				(width 0.1)
				(type default)
			)
			(layer "F.Fab")
		)
		(fp_line
			(start -0.67945 0.3048)
			(end -0.67945 -0.305054)
			(stroke
				(width 0.1)
				(type default)
			)
			(layer "F.Fab")
		)
		(pad "1" smd circle
			(at -0.40005 0 90)
			(size 0 0)
			(layers "F.Cu" "F.Mask" "F.Paste")
			(net "P0V9_RETIMER_CPU1_VCC2")
		)
		(pad "2" smd circle
			(at 0.40005 0 90)
			(size 0 0)
			(layers "F.Cu" "F.Mask" "F.Paste")
			(net "GND")
		)
	)
	(footprint ""
		(layer "F.Cu")
		(at 228.650038 -44.494958)
		(property "Reference" "H77"
			(at -1.143 -3.266948 0)
			(unlocked yes)
			(layer "B.SilkS")
			(effects
				(font
					(size 0.7874 0.5842)
					(thickness 0.1524)
				)
				(justify left mirror)
			)
		)
		(property "Value" ""
			(at 0 0 0)
			(layer "F.Fab")
			(effects
				(font
					(size 1.27 1.27)
				)
			)
		)
		(duplicate_pad_numbers_are_jumpers no)
		(pad "1" thru_hole rect
			(at 0 0)
			(size 4.2164 5.0038)
			(drill 2.0066
				(offset 0.099822 0)
			)
			(layers "*.Cu" "*.Mask")
			(remove_unused_layers no)
			(net "GND")
			(clearance -0.8509)
			(padstack
				(mode front_inner_back)
				(layer "Inner"
					(shape circle)
					(size 4.0132 4.0132)
					(clearance -0.7493)
				)
				(layer "B.Cu"
					(shape circle)
					(size 4.0132 4.0132)
					(clearance -0.7493)
				)
			)
		)
	)
	(footprint ""
		(layer "F.Cu")
		(at 132.42417 -156.531056 180)
		(property "Reference" "PU32"
			(at 6.086856 -5.12572 0)
			(unlocked yes)
			(layer "F.SilkS")
			(effects
				(font
					(size 0.7874 0.5842)
					(thickness 0.1524)
				)
				(justify left)
			)
		)
		(property "Value" ""
			(at 0 0 180)
			(layer "F.Fab")
			(effects
				(font
					(size 1.27 1.27)
				)
			)
		)
		(duplicate_pad_numbers_are_jumpers no)
		(fp_line
			(start 2.500122 2.999994)
			(end 2.2987 2.999994)
			(stroke
				(width 0.1524)
				(type default)
			)
			(layer "F.SilkS")
		)
		(fp_line
			(start 2.500122 2.339594)
			(end 2.500122 2.999994)
			(stroke
				(width 0.1524)
				(type default)
			)
			(layer "F.SilkS")
		)
		(fp_line
			(start 2.500122 -2.999994)
			(end 2.500122 -2.44348)
			(stroke
				(width 0.1524)
				(type default)
			)
			(layer "F.SilkS")
		)
		(fp_line
			(start 2.31394 -2.999994)
			(end 2.500122 -2.999994)
			(stroke
				(width 0.1524)
				(type default)
			)
			(layer "F.SilkS")
		)
		(fp_line
			(start -2.2987 2.999994)
			(end -2.500122 2.999994)
			(stroke
				(width 0.1524)
				(type default)
			)
			(layer "F.SilkS")
		)
		(fp_line
			(start -2.500122 2.999994)
			(end -2.500122 2.339594)
			(stroke
				(width 0.1524)
				(type default)
			)
			(layer "F.SilkS")
		)
		(fp_line
			(start -2.500122 0.6604)
			(end -2.500122 0.229108)
			(stroke
				(width 0.1524)
				(type default)
			)
			(layer "F.SilkS")
		)
		(fp_line
			(start -2.500122 -2.529078)
			(end -2.500122 -2.999994)
			(stroke
				(width 0.1524)
				(type default)
			)
			(layer "F.SilkS")
		)
		(fp_line
			(start -2.500122 -2.999994)
			(end -2.24409 -2.999994)
			(stroke
				(width 0.1524)
				(type default)
			)
			(layer "F.SilkS")
		)
		(fp_poly
			(pts
				(xy -2.710688 -2.451608) (xy -3.384296 -2.676144) (xy -2.935224 -3.125216)
			)
			(stroke
				(width 0)
				(type default)
			)
			(fill yes)
			(layer "F.SilkS")
		)
		(fp_line
			(start 2.500122 2.999994)
			(end -2.500122 2.999994)
			(stroke
				(width 0.1)
				(type default)
			)
			(layer "F.Fab")
		)
		(fp_line
			(start 2.500122 -2.999994)
			(end 2.500122 2.999994)
			(stroke
				(width 0.1)
				(type default)
			)
			(layer "F.Fab")
		)
		(fp_line
			(start -2.500122 2.999994)
			(end -2.500122 -2.999994)
			(stroke
				(width 0.1)
				(type default)
			)
			(layer "F.Fab")
		)
		(fp_line
			(start -2.500122 -2.999994)
			(end 2.500122 -2.999994)
			(stroke
				(width 0.1)
				(type default)
			)
			(layer "F.Fab")
		)
		(fp_poly
			(pts
				(xy -4.218432 -2.783078) (xy -4.218432 -1.767078) (xy -3.202432 -2.275078)
			)
			(stroke
				(width 0)
				(type default)
			)
			(fill yes)
			(layer "F.Fab")
		)
		(pad "1" smd rect
			(at -2.400046 -2.275078 270)
			(size 0.2286 0.6096)
			(layers "F.Cu" "F.Mask" "F.Paste")
			(net "PVDDCR_SOC_P1_VOS3")
		)
		(pad "2" smd rect
			(at -2.400046 -1.82499 270)
			(size 0.2286 0.6096)
			(layers "F.Cu" "F.Mask" "F.Paste")
			(net "GND")
		)
		(pad "3" smd rect
			(at -2.400046 -1.374902 270)
			(size 0.2286 0.6096)
			(layers "F.Cu" "F.Mask" "F.Paste")
			(net "PVDDCR_SOC_P1_VCC3")
		)
		(pad "4" smd rect
			(at -2.400046 -0.925068 270)
			(size 0.2286 0.6096)
			(layers "F.Cu" "F.Mask" "F.Paste")
			(net "PVDDCR_CPU0_P1_PVCC")
		)
		(pad "5" smd rect
			(at -2.400046 -0.47498 270)
			(size 0.2286 0.6096)
			(layers "F.Cu" "F.Mask" "F.Paste")
			(net "GND")
		)
		(pad "6" smd rect
			(at -2.400046 -0.024892 270)
			(size 0.2286 0.6096)
			(layers "F.Cu" "F.Mask" "F.Paste")
			(net "NC_PVDDCR_SOC_P1_GL1_3")
		)
		(pad "7_9-20_24" smd circle
			(at 0 1.150112 270)
			(size 0 0)
			(layers "F.Cu" "F.Mask" "F.Paste")
			(net "GND")
		)
		(pad "10_19" smd rect
			(at 0 2.899918 270)
			(size 0.6096 4.318)
			(layers "F.Cu" "F.Mask" "F.Paste")
			(net "SW_PVDDCR_SOC_P1_SW3")
		)
		(pad "25_29" smd rect
			(at 1.549908 -1.279906 90)
			(size 2.0574 2.3114)
			(layers "F.Cu" "F.Mask" "F.Paste")
			(net "SW_P12V_AUX_PVDDCR_SOC_P1_FLT")
		)
		(pad "30" smd rect
			(at 2.05994 -2.899918 180)
			(size 0.2286 0.6096)
			(layers "F.Cu" "F.Mask" "F.Paste")
			(net "SW_P12V_AUX_PVDDCR_SOC_P1_FLT")
		)
		(pad "31" smd rect
			(at 1.610106 -2.899918 180)
			(size 0.2286 0.6096)
			(layers "F.Cu" "F.Mask" "F.Paste")
			(net "NC_PVDDCR_SOC_P1_DNC3")
		)
		(pad "32" smd rect
			(at 1.160018 -2.899918 180)
			(size 0.2286 0.6096)
			(layers "F.Cu" "F.Mask" "F.Paste")
			(net "SW_PVDDCR_SOC_P1_PH3")
		)
		(pad "33" smd rect
			(at 0.70993 -2.899918 180)
			(size 0.2286 0.6096)
			(layers "F.Cu" "F.Mask" "F.Paste")
			(net "SW_PVDDCR_SOC_P1_BOOT3")
		)
		(pad "34" smd rect
			(at 0.260096 -2.899918 180)
			(size 0.2286 0.6096)
			(layers "F.Cu" "F.Mask" "F.Paste")
			(net "PVDDCR_SOC_P1_PWM3")
		)
		(pad "35" smd rect
			(at -0.189992 -2.899918 180)
			(size 0.2286 0.6096)
			(layers "F.Cu" "F.Mask" "F.Paste")
			(net "PVDDCR_SOC_P1_VCC3")
		)
		(pad "36" smd rect
			(at -0.64008 -2.899918 180)
			(size 0.2286 0.6096)
			(layers "F.Cu" "F.Mask" "F.Paste")
			(net "PVDDCR_SOC_P1_TEMP1")
		)
		(pad "37" smd rect
			(at -1.089914 -2.899918 180)
			(size 0.2286 0.6096)
			(layers "F.Cu" "F.Mask" "F.Paste")
			(net "PVDDCR_SOC_P1_LSET3")
		)
		(pad "38" smd rect
			(at -1.540002 -2.899918 180)
			(size 0.2286 0.6096)
			(layers "F.Cu" "F.Mask" "F.Paste")
			(net "PVDDCR_SOC_P1_IMON3")
		)
		(pad "39" smd rect
			(at -1.99009 -2.899918 180)
			(size 0.2286 0.6096)
			(layers "F.Cu" "F.Mask" "F.Paste")
			(net "PVDDCR_CPU0_P1_VCCS")
		)
		(pad "40" smd rect
			(at -0.87503 -1.27508 180)
			(size 1.7526 1.9558)
			(layers "F.Cu" "F.Mask" "F.Paste")
			(net "GND")
		)
		(pad "41" smd rect
			(at -1.525016 0.249936 90)
			(size 0.3048 0.4572)
			(layers "F.Cu" "F.Mask" "F.Paste")
			(net "NC_PVDDCR_SOC_P1_GL2_3")
		)
		(zone
			(layer "F.Cu")
			(hatch none 0.5)
			(connect_pads
				(clearance 0)
			)
			(min_thickness 0.25)
			(keepout
				(tracks not_allowed)
				(vias allowed)
				(pads allowed)
				(copperpour not_allowed)
				(footprints allowed)
			)
			(placement
				(enabled no)
				(sheetname "")
			)
			(fill
				(thermal_gap 0.5)
				(thermal_bridge_width 0.5)
				(island_removal_mode 0)
			)
			(polygon
				(pts
					(xy 134.924292 -159.075374) (xy 134.924292 -158.78175) (xy 129.924048 -158.78175) (xy 129.924048 -159.075374)
					(xy 130.21437 -159.075374) (xy 134.63397 -159.075374)
				)
			)
		)
		(zone
			(layer "F.Cu")
			(hatch none 0.5)
			(connect_pads
				(clearance 0)
			)
			(min_thickness 0.25)
			(keepout
				(tracks not_allowed)
				(vias allowed)
				(pads allowed)
				(copperpour not_allowed)
				(footprints allowed)
			)
			(placement
				(enabled no)
				(sheetname "")
			)
			(fill
				(thermal_gap 0.5)
				(thermal_bridge_width 0.5)
				(island_removal_mode 0)
			)
			(polygon
				(pts
					(xy 132.3721 -156.284676) (xy 132.3721 -154.227276) (xy 134.2263 -154.227276) (xy 134.2263 -154.468322)
					(xy 134.468616 -154.468322) (xy 134.468616 -153.986738) (xy 130.558794 -153.986738) (xy 130.558794 -154.17165)
					(xy 132.080762 -154.17165) (xy 132.080762 -156.33065) (xy 129.924048 -156.33065) (xy 129.924048 -156.580332)
					(xy 132.076444 -156.580332)
				)
			)
		)
	)
	(footprint ""
		(layer "F.Cu")
		(at 65.572894 -35.784028)
		(property "Reference" "R4059"
			(at 0 0 0)
			(layer "F.SilkS")
			(hide yes)
			(effects
				(font
					(size 1.27 1.27)
				)
			)
		)
		(property "Value" ""
			(at 0 0 0)
			(layer "F.Fab")
			(effects
				(font
					(size 1.27 1.27)
				)
			)
		)
		(duplicate_pad_numbers_are_jumpers no)
		(fp_line
			(start -0.7874 -0.4064)
			(end 0.7874 -0.4064)
			(stroke
				(width 0.1524)
				(type default)
			)
			(layer "F.SilkS")
		)
		(fp_line
			(start -0.7874 0.4064)
			(end -0.7874 -0.4064)
			(stroke
				(width 0.1524)
				(type default)
			)
			(layer "F.SilkS")
		)
		(fp_line
			(start 0.7874 -0.4064)
			(end 0.7874 0.4064)
			(stroke
				(width 0.1524)
				(type default)
			)
			(layer "F.SilkS")
		)
		(fp_line
			(start 0.7874 0.4064)
			(end -0.7874 0.4064)
			(stroke
				(width 0.1524)
				(type default)
			)
			(layer "F.SilkS")
		)
		(fp_line
			(start -0.67945 -0.305054)
			(end -0.12065 -0.305054)
			(stroke
				(width 0.1)
				(type default)
			)
			(layer "F.Fab")
		)
		(fp_line
			(start -0.67945 0.3048)
			(end -0.67945 -0.305054)
			(stroke
				(width 0.1)
				(type default)
			)
			(layer "F.Fab")
		)
		(fp_line
			(start -0.12065 -0.305054)
			(end -0.12065 -0.2794)
			(stroke
				(width 0.1)
				(type default)
			)
			(layer "F.Fab")
		)
		(fp_line
			(start -0.12065 -0.2794)
			(end 0.12065 -0.2794)
			(stroke
				(width 0.1)
				(type default)
			)
			(layer "F.Fab")
		)
		(fp_line
			(start -0.12065 0.2794)
			(end -0.12065 0.3048)
			(stroke
				(width 0.1)
				(type default)
			)
			(layer "F.Fab")
		)
		(fp_line
			(start -0.12065 0.3048)
			(end -0.67945 0.3048)
			(stroke
				(width 0.1)
				(type default)
			)
			(layer "F.Fab")
		)
		(fp_line
			(start 0.120396 0.2794)
			(end -0.12065 0.2794)
			(stroke
				(width 0.1)
				(type default)
			)
			(layer "F.Fab")
		)
		(fp_line
			(start 0.120396 0.3048)
			(end 0.120396 0.2794)
			(stroke
				(width 0.1)
				(type default)
			)
			(layer "F.Fab")
		)
		(fp_line
			(start 0.12065 -0.3048)
			(end 0.67945 -0.3048)
			(stroke
				(width 0.1)
				(type default)
			)
			(layer "F.Fab")
		)
		(fp_line
			(start 0.12065 -0.2794)
			(end 0.12065 -0.3048)
			(stroke
				(width 0.1)
				(type default)
			)
			(layer "F.Fab")
		)
		(fp_line
			(start 0.67945 -0.3048)
			(end 0.67945 0.3048)
			(stroke
				(width 0.1)
				(type default)
			)
			(layer "F.Fab")
		)
		(fp_line
			(start 0.67945 0.3048)
			(end 0.120396 0.3048)
			(stroke
				(width 0.1)
				(type default)
			)
			(layer "F.Fab")
		)
		(pad "1" smd circle
			(at -0.40005 0)
			(size 0 0)
			(layers "F.Cu" "F.Mask" "F.Paste")
			(net "P12V_OCP_V3_2_EN_R")
		)
		(pad "2" smd circle
			(at 0.40005 0)
			(size 0 0)
			(layers "F.Cu" "F.Mask" "F.Paste")
			(net "P12V_OCP_EN_2_R")
		)
	)
	(footprint ""
		(layer "F.Cu")
		(at 187.563506 -353.986084 90)
		(property "Reference" "PC506"
			(at 0 0 90)
			(layer "F.SilkS")
			(hide yes)
			(effects
				(font
					(size 1.27 1.27)
				)
			)
		)
		(property "Value" ""
			(at 0 0 90)
			(layer "F.Fab")
			(effects
				(font
					(size 1.27 1.27)
				)
			)
		)
		(duplicate_pad_numbers_are_jumpers no)
		(fp_line
			(start 0.7874 -0.4064)
			(end 0.7874 0.4064)
			(stroke
				(width 0.1524)
				(type default)
			)
			(layer "F.SilkS")
		)
		(fp_line
			(start -0.7874 -0.4064)
			(end 0.7874 -0.4064)
			(stroke
				(width 0.1524)
				(type default)
			)
			(layer "F.SilkS")
		)
		(fp_line
			(start 0.7874 0.4064)
			(end 0.445516 0.4064)
			(stroke
				(width 0.1524)
				(type default)
			)
			(layer "F.SilkS")
		)
		(fp_line
			(start -0.291084 0.4064)
			(end -0.7874 0.4064)
			(stroke
				(width 0.1524)
				(type default)
			)
			(layer "F.SilkS")
		)
		(fp_line
			(start -0.7874 0.4064)
			(end -0.7874 -0.4064)
			(stroke
				(width 0.1524)
				(type default)
			)
			(layer "F.SilkS")
		)
		(fp_line
			(start -0.12065 -0.305054)
			(end -0.12065 -0.2794)
			(stroke
				(width 0.1)
				(type default)
			)
			(layer "F.Fab")
		)
		(fp_line
			(start -0.67945 -0.305054)
			(end -0.12065 -0.305054)
			(stroke
				(width 0.1)
				(type default)
			)
			(layer "F.Fab")
		)
		(fp_line
			(start 0.67945 -0.3048)
			(end 0.67945 0.3048)
			(stroke
				(width 0.1)
				(type default)
			)
			(layer "F.Fab")
		)
		(fp_line
			(start 0.12065 -0.3048)
			(end 0.67945 -0.3048)
			(stroke
				(width 0.1)
				(type default)
			)
			(layer "F.Fab")
		)
		(fp_line
			(start 0.12065 -0.2794)
			(end 0.12065 -0.3048)
			(stroke
				(width 0.1)
				(type default)
			)
			(layer "F.Fab")
		)
		(fp_line
			(start -0.12065 -0.2794)
			(end 0.12065 -0.2794)
			(stroke
				(width 0.1)
				(type default)
			)
			(layer "F.Fab")
		)
		(fp_line
			(start 0.120396 0.2794)
			(end -0.12065 0.2794)
			(stroke
				(width 0.1)
				(type default)
			)
			(layer "F.Fab")
		)
		(fp_line
			(start -0.12065 0.2794)
			(end -0.12065 0.3048)
			(stroke
				(width 0.1)
				(type default)
			)
			(layer "F.Fab")
		)
		(fp_line
			(start 0.67945 0.3048)
			(end 0.120396 0.3048)
			(stroke
				(width 0.1)
				(type default)
			)
			(layer "F.Fab")
		)
		(fp_line
			(start 0.120396 0.3048)
			(end 0.120396 0.2794)
			(stroke
				(width 0.1)
				(type default)
			)
			(layer "F.Fab")
		)
		(fp_line
			(start -0.12065 0.3048)
			(end -0.67945 0.3048)
			(stroke
				(width 0.1)
				(type default)
			)
			(layer "F.Fab")
		)
		(fp_line
			(start -0.67945 0.3048)
			(end -0.67945 -0.305054)
			(stroke
				(width 0.1)
				(type default)
			)
			(layer "F.Fab")
		)
		(pad "1" smd circle
			(at -0.40005 0 90)
			(size 0 0)
			(layers "F.Cu" "F.Mask" "F.Paste")
			(net "PVDD11_S3_P1_VCC2")
		)
		(pad "2" smd circle
			(at 0.40005 0 90)
			(size 0 0)
			(layers "F.Cu" "F.Mask" "F.Paste")
			(net "GND")
		)
	)
	(footprint ""
		(layer "F.Cu")
		(at 192.151 -133.568948 90)
		(property "Reference" "R173"
			(at 0 0 90)
			(layer "F.SilkS")
			(hide yes)
			(effects
				(font
					(size 1.27 1.27)
				)
			)
		)
		(property "Value" ""
			(at 0 0 90)
			(layer "F.Fab")
			(effects
				(font
					(size 1.27 1.27)
				)
			)
		)
		(duplicate_pad_numbers_are_jumpers no)
		(fp_line
			(start 0.7874 -0.4064)
			(end 0.7874 0.4064)
			(stroke
				(width 0.1524)
				(type default)
			)
			(layer "F.SilkS")
		)
		(fp_line
			(start -0.7874 -0.4064)
			(end 0.7874 -0.4064)
			(stroke
				(width 0.1524)
				(type default)
			)
			(layer "F.SilkS")
		)
		(fp_line
			(start 0.7874 0.4064)
			(end -0.7874 0.4064)
			(stroke
				(width 0.1524)
				(type default)
			)
			(layer "F.SilkS")
		)
		(fp_line
			(start -0.7874 0.4064)
			(end -0.7874 -0.4064)
			(stroke
				(width 0.1524)
				(type default)
			)
			(layer "F.SilkS")
		)
		(fp_line
			(start -0.12065 -0.305054)
			(end -0.12065 -0.2794)
			(stroke
				(width 0.1)
				(type default)
			)
			(layer "F.Fab")
		)
		(fp_line
			(start -0.67945 -0.305054)
			(end -0.12065 -0.305054)
			(stroke
				(width 0.1)
				(type default)
			)
			(layer "F.Fab")
		)
		(fp_line
			(start 0.67945 -0.3048)
			(end 0.67945 0.3048)
			(stroke
				(width 0.1)
				(type default)
			)
			(layer "F.Fab")
		)
		(fp_line
			(start 0.12065 -0.3048)
			(end 0.67945 -0.3048)
			(stroke
				(width 0.1)
				(type default)
			)
			(layer "F.Fab")
		)
		(fp_line
			(start 0.12065 -0.2794)
			(end 0.12065 -0.3048)
			(stroke
				(width 0.1)
				(type default)
			)
			(layer "F.Fab")
		)
		(fp_line
			(start -0.12065 -0.2794)
			(end 0.12065 -0.2794)
			(stroke
				(width 0.1)
				(type default)
			)
			(layer "F.Fab")
		)
		(fp_line
			(start 0.120396 0.2794)
			(end -0.12065 0.2794)
			(stroke
				(width 0.1)
				(type default)
			)
			(layer "F.Fab")
		)
		(fp_line
			(start -0.12065 0.2794)
			(end -0.12065 0.3048)
			(stroke
				(width 0.1)
				(type default)
			)
			(layer "F.Fab")
		)
		(fp_line
			(start 0.67945 0.3048)
			(end 0.120396 0.3048)
			(stroke
				(width 0.1)
				(type default)
			)
			(layer "F.Fab")
		)
		(fp_line
			(start 0.120396 0.3048)
			(end 0.120396 0.2794)
			(stroke
				(width 0.1)
				(type default)
			)
			(layer "F.Fab")
		)
		(fp_line
			(start -0.12065 0.3048)
			(end -0.67945 0.3048)
			(stroke
				(width 0.1)
				(type default)
			)
			(layer "F.Fab")
		)
		(fp_line
			(start -0.67945 0.3048)
			(end -0.67945 -0.305054)
			(stroke
				(width 0.1)
				(type default)
			)
			(layer "F.Fab")
		)
		(pad "1" smd circle
			(at -0.40005 0 90)
			(size 0 0)
			(layers "F.Cu" "F.Mask" "F.Paste")
			(net "FM_PLD_CPU1_PRSNT_HDT")
		)
		(pad "2" smd circle
			(at 0.40005 0 90)
			(size 0 0)
			(layers "F.Cu" "F.Mask" "F.Paste")
			(net "CPU1_HDT_BYPASS_SEL")
		)
	)
	(footprint ""
		(layer "F.Cu")
		(at 189.327028 -428.94758 -90)
		(property "Reference" "R9010"
			(at 0 0 270)
			(layer "F.SilkS")
			(hide yes)
			(effects
				(font
					(size 1.27 1.27)
				)
			)
		)
		(property "Value" ""
			(at 0 0 270)
			(layer "F.Fab")
			(effects
				(font
					(size 1.27 1.27)
				)
			)
		)
		(duplicate_pad_numbers_are_jumpers no)
		(fp_line
			(start -0.7874 0.4064)
			(end -0.7874 -0.4064)
			(stroke
				(width 0.1524)
				(type default)
			)
			(layer "F.SilkS")
		)
		(fp_line
			(start 0.7874 0.4064)
			(end -0.7874 0.4064)
			(stroke
				(width 0.1524)
				(type default)
			)
			(layer "F.SilkS")
		)
		(fp_line
			(start -0.7874 -0.4064)
			(end 0.7874 -0.4064)
			(stroke
				(width 0.1524)
				(type default)
			)
			(layer "F.SilkS")
		)
		(fp_line
			(start 0.7874 -0.4064)
			(end 0.7874 0.4064)
			(stroke
				(width 0.1524)
				(type default)
			)
			(layer "F.SilkS")
		)
		(fp_line
			(start -0.67945 0.3048)
			(end -0.67945 -0.305054)
			(stroke
				(width 0.1)
				(type default)
			)
			(layer "F.Fab")
		)
		(fp_line
			(start -0.12065 0.3048)
			(end -0.67945 0.3048)
			(stroke
				(width 0.1)
				(type default)
			)
			(layer "F.Fab")
		)
		(fp_line
			(start 0.120396 0.3048)
			(end 0.120396 0.2794)
			(stroke
				(width 0.1)
				(type default)
			)
			(layer "F.Fab")
		)
		(fp_line
			(start 0.67945 0.3048)
			(end 0.120396 0.3048)
			(stroke
				(width 0.1)
				(type default)
			)
			(layer "F.Fab")
		)
		(fp_line
			(start -0.12065 0.2794)
			(end -0.12065 0.3048)
			(stroke
				(width 0.1)
				(type default)
			)
			(layer "F.Fab")
		)
		(fp_line
			(start 0.120396 0.2794)
			(end -0.12065 0.2794)
			(stroke
				(width 0.1)
				(type default)
			)
			(layer "F.Fab")
		)
		(fp_line
			(start -0.12065 -0.2794)
			(end 0.12065 -0.2794)
			(stroke
				(width 0.1)
				(type default)
			)
			(layer "F.Fab")
		)
		(fp_line
			(start 0.12065 -0.2794)
			(end 0.12065 -0.3048)
			(stroke
				(width 0.1)
				(type default)
			)
			(layer "F.Fab")
		)
		(fp_line
			(start 0.12065 -0.3048)
			(end 0.67945 -0.3048)
			(stroke
				(width 0.1)
				(type default)
			)
			(layer "F.Fab")
		)
		(fp_line
			(start 0.67945 -0.3048)
			(end 0.67945 0.3048)
			(stroke
				(width 0.1)
				(type default)
			)
			(layer "F.Fab")
		)
		(fp_line
			(start -0.67945 -0.305054)
			(end -0.12065 -0.305054)
			(stroke
				(width 0.1)
				(type default)
			)
			(layer "F.Fab")
		)
		(fp_line
			(start -0.12065 -0.305054)
			(end -0.12065 -0.2794)
			(stroke
				(width 0.1)
				(type default)
			)
			(layer "F.Fab")
		)
		(pad "1" smd circle
			(at -0.40005 0 270)
			(size 0 0)
			(layers "F.Cu" "F.Mask" "F.Paste")
			(net "PRSNT_CABLE_SWB_B1_ISO_N")
		)
		(pad "2" smd circle
			(at 0.40005 0 270)
			(size 0 0)
			(layers "F.Cu" "F.Mask" "F.Paste")
			(net "PRSNT_CABLE_SWB_B1_ISO_R_N")
		)
	)
	(footprint ""
		(layer "F.Cu")
		(at 356.69601 -404.0124 -90)
		(property "Reference" "R1004"
			(at 0 0 270)
			(layer "F.SilkS")
			(hide yes)
			(effects
				(font
					(size 1.27 1.27)
				)
			)
		)
		(property "Value" ""
			(at 0 0 270)
			(layer "F.Fab")
			(effects
				(font
					(size 1.27 1.27)
				)
			)
		)
		(duplicate_pad_numbers_are_jumpers no)
		(fp_line
			(start -0.32512 0.175006)
			(end -0.32512 -0.175006)
			(stroke
				(width 0.1)
				(type default)
			)
			(layer "F.Fab")
		)
		(fp_line
			(start 0.32512 0.175006)
			(end -0.32512 0.175006)
			(stroke
				(width 0.1)
				(type default)
			)
			(layer "F.Fab")
		)
		(fp_line
			(start -0.32512 -0.175006)
			(end 0.32512 -0.175006)
			(stroke
				(width 0.1)
				(type default)
			)
			(layer "F.Fab")
		)
		(fp_line
			(start 0.32512 -0.175006)
			(end 0.32512 0.175006)
			(stroke
				(width 0.1)
				(type default)
			)
			(layer "F.Fab")
		)
		(pad "1" smd rect
			(at -0.2667 0 270)
			(size 0.3048 0.381)
			(layers "F.Cu" "F.Mask" "F.Paste")
			(net "RST_RT_CPU0_P1_PERST_N")
		)
		(pad "2" smd rect
			(at 0.2667 0 90)
			(size 0.3048 0.381)
			(layers "F.Cu" "F.Mask" "F.Paste")
			(net "RST_RT_CPU0_P1_PERST_R_N")
		)
	)
	(footprint ""
		(layer "F.Cu")
		(at 208.926684 -111.576866 180)
		(property "Reference" "R2262"
			(at 0 0 180)
			(layer "F.SilkS")
			(hide yes)
			(effects
				(font
					(size 1.27 1.27)
				)
			)
		)
		(property "Value" ""
			(at 0 0 180)
			(layer "F.Fab")
			(effects
				(font
					(size 1.27 1.27)
				)
			)
		)
		(duplicate_pad_numbers_are_jumpers no)
		(fp_line
			(start 0.7874 0.4064)
			(end -0.7874 0.4064)
			(stroke
				(width 0.1524)
				(type default)
			)
			(layer "F.SilkS")
		)
		(fp_line
			(start 0.7874 -0.4064)
			(end 0.7874 0.4064)
			(stroke
				(width 0.1524)
				(type default)
			)
			(layer "F.SilkS")
		)
		(fp_line
			(start -0.7874 0.4064)
			(end -0.7874 -0.4064)
			(stroke
				(width 0.1524)
				(type default)
			)
			(layer "F.SilkS")
		)
		(fp_line
			(start -0.7874 -0.4064)
			(end 0.7874 -0.4064)
			(stroke
				(width 0.1524)
				(type default)
			)
			(layer "F.SilkS")
		)
		(fp_line
			(start 0.67945 0.3048)
			(end 0.120396 0.3048)
			(stroke
				(width 0.1)
				(type default)
			)
			(layer "F.Fab")
		)
		(fp_line
			(start 0.67945 -0.3048)
			(end 0.67945 0.3048)
			(stroke
				(width 0.1)
				(type default)
			)
			(layer "F.Fab")
		)
		(fp_line
			(start 0.12065 -0.2794)
			(end 0.12065 -0.3048)
			(stroke
				(width 0.1)
				(type default)
			)
			(layer "F.Fab")
		)
		(fp_line
			(start 0.12065 -0.3048)
			(end 0.67945 -0.3048)
			(stroke
				(width 0.1)
				(type default)
			)
			(layer "F.Fab")
		)
		(fp_line
			(start 0.120396 0.3048)
			(end 0.120396 0.2794)
			(stroke
				(width 0.1)
				(type default)
			)
			(layer "F.Fab")
		)
		(fp_line
			(start 0.120396 0.2794)
			(end -0.12065 0.2794)
			(stroke
				(width 0.1)
				(type default)
			)
			(layer "F.Fab")
		)
		(fp_line
			(start -0.12065 0.3048)
			(end -0.67945 0.3048)
			(stroke
				(width 0.1)
				(type default)
			)
			(layer "F.Fab")
		)
		(fp_line
			(start -0.12065 0.2794)
			(end -0.12065 0.3048)
			(stroke
				(width 0.1)
				(type default)
			)
			(layer "F.Fab")
		)
		(fp_line
			(start -0.12065 -0.2794)
			(end 0.12065 -0.2794)
			(stroke
				(width 0.1)
				(type default)
			)
			(layer "F.Fab")
		)
		(fp_line
			(start -0.12065 -0.305054)
			(end -0.12065 -0.2794)
			(stroke
				(width 0.1)
				(type default)
			)
			(layer "F.Fab")
		)
		(fp_line
			(start -0.67945 0.3048)
			(end -0.67945 -0.305054)
			(stroke
				(width 0.1)
				(type default)
			)
			(layer "F.Fab")
		)
		(fp_line
			(start -0.67945 -0.305054)
			(end -0.12065 -0.305054)
			(stroke
				(width 0.1)
				(type default)
			)
			(layer "F.Fab")
		)
		(pad "1" smd circle
			(at -0.40005 0 180)
			(size 0 0)
			(layers "F.Cu" "F.Mask" "F.Paste")
			(net "FM_GPU_PWR_EN_R")
		)
		(pad "2" smd circle
			(at 0.40005 0 180)
			(size 0 0)
			(layers "F.Cu" "F.Mask" "F.Paste")
			(net "FM_GPU_PWR_EN")
		)
	)
	(footprint ""
		(layer "F.Cu")
		(at 146.104864 -194.567048 90)
		(property "Reference" "PR170"
			(at 0 0 90)
			(layer "F.SilkS")
			(hide yes)
			(effects
				(font
					(size 1.27 1.27)
				)
			)
		)
		(property "Value" ""
			(at 0 0 90)
			(layer "F.Fab")
			(effects
				(font
					(size 1.27 1.27)
				)
			)
		)
		(duplicate_pad_numbers_are_jumpers no)
		(fp_line
			(start 0.7874 -0.4064)
			(end 0.7874 0.4064)
			(stroke
				(width 0.1524)
				(type default)
			)
			(layer "F.SilkS")
		)
		(fp_line
			(start -0.7874 -0.4064)
			(end 0.7874 -0.4064)
			(stroke
				(width 0.1524)
				(type default)
			)
			(layer "F.SilkS")
		)
		(fp_line
			(start 0.7874 0.4064)
			(end -0.7874 0.4064)
			(stroke
				(width 0.1524)
				(type default)
			)
			(layer "F.SilkS")
		)
		(fp_line
			(start -0.7874 0.4064)
			(end -0.7874 -0.4064)
			(stroke
				(width 0.1524)
				(type default)
			)
			(layer "F.SilkS")
		)
		(fp_line
			(start -0.12065 -0.305054)
			(end -0.12065 -0.2794)
			(stroke
				(width 0.1)
				(type default)
			)
			(layer "F.Fab")
		)
		(fp_line
			(start -0.67945 -0.305054)
			(end -0.12065 -0.305054)
			(stroke
				(width 0.1)
				(type default)
			)
			(layer "F.Fab")
		)
		(fp_line
			(start 0.67945 -0.3048)
			(end 0.67945 0.3048)
			(stroke
				(width 0.1)
				(type default)
			)
			(layer "F.Fab")
		)
		(fp_line
			(start 0.12065 -0.3048)
			(end 0.67945 -0.3048)
			(stroke
				(width 0.1)
				(type default)
			)
			(layer "F.Fab")
		)
		(fp_line
			(start 0.12065 -0.2794)
			(end 0.12065 -0.3048)
			(stroke
				(width 0.1)
				(type default)
			)
			(layer "F.Fab")
		)
		(fp_line
			(start -0.12065 -0.2794)
			(end 0.12065 -0.2794)
			(stroke
				(width 0.1)
				(type default)
			)
			(layer "F.Fab")
		)
		(fp_line
			(start 0.120396 0.2794)
			(end -0.12065 0.2794)
			(stroke
				(width 0.1)
				(type default)
			)
			(layer "F.Fab")
		)
		(fp_line
			(start -0.12065 0.2794)
			(end -0.12065 0.3048)
			(stroke
				(width 0.1)
				(type default)
			)
			(layer "F.Fab")
		)
		(fp_line
			(start 0.67945 0.3048)
			(end 0.120396 0.3048)
			(stroke
				(width 0.1)
				(type default)
			)
			(layer "F.Fab")
		)
		(fp_line
			(start 0.120396 0.3048)
			(end 0.120396 0.2794)
			(stroke
				(width 0.1)
				(type default)
			)
			(layer "F.Fab")
		)
		(fp_line
			(start -0.12065 0.3048)
			(end -0.67945 0.3048)
			(stroke
				(width 0.1)
				(type default)
			)
			(layer "F.Fab")
		)
		(fp_line
			(start -0.67945 0.3048)
			(end -0.67945 -0.305054)
			(stroke
				(width 0.1)
				(type default)
			)
			(layer "F.Fab")
		)
		(pad "1" smd circle
			(at -0.40005 0 90)
			(size 0 0)
			(layers "F.Cu" "F.Mask" "F.Paste")
			(net "SVID_PVDDCR_CPU0_P1_SVD_R")
		)
		(pad "2" smd circle
			(at 0.40005 0 90)
			(size 0 0)
			(layers "F.Cu" "F.Mask" "F.Paste")
			(net "SVID_PVDDCR_CPU0_P1_SVD")
		)
	)
	(footprint ""
		(layer "F.Cu")
		(at 356.234746 -416.145218 90)
		(property "Reference" "Q134"
			(at -1.4224 -2.44348 90)
			(unlocked yes)
			(layer "F.SilkS")
			(effects
				(font
					(size 0.7874 0.5842)
					(thickness 0.1524)
				)
				(justify left)
			)
		)
		(property "Value" ""
			(at 0 0 90)
			(layer "F.Fab")
			(effects
				(font
					(size 1.27 1.27)
				)
			)
		)
		(duplicate_pad_numbers_are_jumpers no)
		(fp_line
			(start 1.332738 -1.100074)
			(end 1.332738 1.100074)
			(stroke
				(width 0.1524)
				(type default)
			)
			(layer "F.SilkS")
		)
		(fp_line
			(start 0.4826 -1.100074)
			(end 1.332738 -1.100074)
			(stroke
				(width 0.1524)
				(type default)
			)
			(layer "F.SilkS")
		)
		(fp_line
			(start -0.4826 -1.100074)
			(end 0 -0.541274)
			(stroke
				(width 0.1524)
				(type default)
			)
			(layer "F.SilkS")
		)
		(fp_line
			(start -1.332738 -1.100074)
			(end -0.4826 -1.100074)
			(stroke
				(width 0.1524)
				(type default)
			)
			(layer "F.SilkS")
		)
		(fp_line
			(start 0 -0.541274)
			(end 0.4826 -1.100074)
			(stroke
				(width 0.1524)
				(type default)
			)
			(layer "F.SilkS")
		)
		(fp_line
			(start 1.332738 1.100074)
			(end -1.332738 1.100074)
			(stroke
				(width 0.1524)
				(type default)
			)
			(layer "F.SilkS")
		)
		(fp_line
			(start -1.332738 1.100074)
			(end -1.332738 -1.100074)
			(stroke
				(width 0.1524)
				(type default)
			)
			(layer "F.SilkS")
		)
		(fp_poly
			(pts
				(xy -1.489456 -1.189482) (xy -2.23393 -1.43764) (xy -1.737614 -1.933956)
			)
			(stroke
				(width 0)
				(type default)
			)
			(fill yes)
			(layer "F.SilkS")
		)
		(fp_line
			(start 0.674878 -1.100074)
			(end 0.674878 1.100074)
			(stroke
				(width 0.1)
				(type default)
			)
			(layer "F.Fab")
		)
		(fp_line
			(start -0.674878 -1.100074)
			(end 0.674878 -1.100074)
			(stroke
				(width 0.1)
				(type default)
			)
			(layer "F.Fab")
		)
		(fp_line
			(start 0.674878 1.100074)
			(end -0.674878 1.100074)
			(stroke
				(width 0.1)
				(type default)
			)
			(layer "F.Fab")
		)
		(fp_line
			(start -0.674878 1.100074)
			(end -0.674878 -1.100074)
			(stroke
				(width 0.1)
				(type default)
			)
			(layer "F.Fab")
		)
		(fp_poly
			(pts
				(xy -2.2352 -0.298958) (xy -2.2352 -1.001014) (xy -1.533144 -0.649986)
			)
			(stroke
				(width 0)
				(type default)
			)
			(fill yes)
			(layer "F.Fab")
		)
		(pad "1" smd rect
			(at -0.94996 -0.649986 180)
			(size 0.4318 0.508)
			(layers "F.Cu" "F.Mask" "F.Paste")
			(net "GND")
		)
		(pad "2" smd rect
			(at -0.94996 0 180)
			(size 0.4318 0.508)
			(layers "F.Cu" "F.Mask" "F.Paste")
			(net "PRSNT_CABLE_GPU_A1_N")
		)
		(pad "3" smd rect
			(at -0.94996 0.649986 180)
			(size 0.4318 0.508)
			(layers "F.Cu" "F.Mask" "F.Paste")
			(net "PRSNT_CABLE_GPU_A1_ISO_N")
		)
		(pad "4" smd rect
			(at 0.94996 0.649986 180)
			(size 0.4318 0.508)
			(layers "F.Cu" "F.Mask" "F.Paste")
			(net "GND")
		)
		(pad "5" smd rect
			(at 0.94996 0 180)
			(size 0.4318 0.508)
			(layers "F.Cu" "F.Mask" "F.Paste")
			(net "PRSNT_CABLE_GPU_A1")
		)
		(pad "6" smd rect
			(at 0.94996 -0.649986 180)
			(size 0.4318 0.508)
			(layers "F.Cu" "F.Mask" "F.Paste")
			(net "PRSNT_CABLE_GPU_A1")
		)
	)
	(footprint ""
		(layer "F.Cu")
		(at 147.16379 -96.012508 90)
		(property "Reference" "C1879"
			(at 0 0 90)
			(layer "F.SilkS")
			(hide yes)
			(effects
				(font
					(size 1.27 1.27)
				)
			)
		)
		(property "Value" ""
			(at 0 0 90)
			(layer "F.Fab")
			(effects
				(font
					(size 1.27 1.27)
				)
			)
		)
		(duplicate_pad_numbers_are_jumpers no)
		(fp_line
			(start 0.7874 -0.4064)
			(end 0.7874 0.4064)
			(stroke
				(width 0.1524)
				(type default)
			)
			(layer "F.SilkS")
		)
		(fp_line
			(start -0.7874 -0.4064)
			(end 0.7874 -0.4064)
			(stroke
				(width 0.1524)
				(type default)
			)
			(layer "F.SilkS")
		)
		(fp_line
			(start 0.7874 0.4064)
			(end -0.7874 0.4064)
			(stroke
				(width 0.1524)
				(type default)
			)
			(layer "F.SilkS")
		)
		(fp_line
			(start -0.7874 0.4064)
			(end -0.7874 -0.4064)
			(stroke
				(width 0.1524)
				(type default)
			)
			(layer "F.SilkS")
		)
		(fp_line
			(start -0.12065 -0.305054)
			(end -0.12065 -0.2794)
			(stroke
				(width 0.1)
				(type default)
			)
			(layer "F.Fab")
		)
		(fp_line
			(start -0.67945 -0.305054)
			(end -0.12065 -0.305054)
			(stroke
				(width 0.1)
				(type default)
			)
			(layer "F.Fab")
		)
		(fp_line
			(start 0.67945 -0.3048)
			(end 0.67945 0.3048)
			(stroke
				(width 0.1)
				(type default)
			)
			(layer "F.Fab")
		)
		(fp_line
			(start 0.12065 -0.3048)
			(end 0.67945 -0.3048)
			(stroke
				(width 0.1)
				(type default)
			)
			(layer "F.Fab")
		)
		(fp_line
			(start 0.12065 -0.2794)
			(end 0.12065 -0.3048)
			(stroke
				(width 0.1)
				(type default)
			)
			(layer "F.Fab")
		)
		(fp_line
			(start -0.12065 -0.2794)
			(end 0.12065 -0.2794)
			(stroke
				(width 0.1)
				(type default)
			)
			(layer "F.Fab")
		)
		(fp_line
			(start 0.120396 0.2794)
			(end -0.12065 0.2794)
			(stroke
				(width 0.1)
				(type default)
			)
			(layer "F.Fab")
		)
		(fp_line
			(start -0.12065 0.2794)
			(end -0.12065 0.3048)
			(stroke
				(width 0.1)
				(type default)
			)
			(layer "F.Fab")
		)
		(fp_line
			(start 0.67945 0.3048)
			(end 0.120396 0.3048)
			(stroke
				(width 0.1)
				(type default)
			)
			(layer "F.Fab")
		)
		(fp_line
			(start 0.120396 0.3048)
			(end 0.120396 0.2794)
			(stroke
				(width 0.1)
				(type default)
			)
			(layer "F.Fab")
		)
		(fp_line
			(start -0.12065 0.3048)
			(end -0.67945 0.3048)
			(stroke
				(width 0.1)
				(type default)
			)
			(layer "F.Fab")
		)
		(fp_line
			(start -0.67945 0.3048)
			(end -0.67945 -0.305054)
			(stroke
				(width 0.1)
				(type default)
			)
			(layer "F.Fab")
		)
		(pad "1" smd circle
			(at -0.40005 0 90)
			(size 0 0)
			(layers "F.Cu" "F.Mask" "F.Paste")
			(net "P3V3_AUX")
		)
		(pad "2" smd circle
			(at 0.40005 0 90)
			(size 0 0)
			(layers "F.Cu" "F.Mask" "F.Paste")
			(net "GND")
		)
	)
	(footprint ""
		(layer "F.Cu")
		(at 131.64058 -26.99258 -90)
		(property "Reference" "R6193"
			(at 0 0 270)
			(layer "F.SilkS")
			(hide yes)
			(effects
				(font
					(size 1.27 1.27)
				)
			)
		)
		(property "Value" ""
			(at 0 0 270)
			(layer "F.Fab")
			(effects
				(font
					(size 1.27 1.27)
				)
			)
		)
		(duplicate_pad_numbers_are_jumpers no)
		(fp_line
			(start -0.32512 0.175006)
			(end -0.32512 -0.175006)
			(stroke
				(width 0.1)
				(type default)
			)
			(layer "F.Fab")
		)
		(fp_line
			(start 0.32512 0.175006)
			(end -0.32512 0.175006)
			(stroke
				(width 0.1)
				(type default)
			)
			(layer "F.Fab")
		)
		(fp_line
			(start -0.32512 -0.175006)
			(end 0.32512 -0.175006)
			(stroke
				(width 0.1)
				(type default)
			)
			(layer "F.Fab")
		)
		(fp_line
			(start 0.32512 -0.175006)
			(end 0.32512 0.175006)
			(stroke
				(width 0.1)
				(type default)
			)
			(layer "F.Fab")
		)
		(pad "1" smd rect
			(at -0.2667 0 270)
			(size 0.3048 0.381)
			(layers "F.Cu" "F.Mask" "F.Paste")
			(net "USB2_CPU0_P0_DN")
		)
		(pad "2" smd rect
			(at 0.2667 0 90)
			(size 0.3048 0.381)
			(layers "F.Cu" "F.Mask" "F.Paste")
			(net "USB2_CPU0_P0_R2_DN")
		)
	)
	(footprint ""
		(layer "F.Cu")
		(at 371.794278 -176.59731)
		(property "Reference" "PC482_2"
			(at 0 0 0)
			(layer "F.SilkS")
			(hide yes)
			(effects
				(font
					(size 1.27 1.27)
				)
			)
		)
		(property "Value" ""
			(at 0 0 0)
			(layer "F.Fab")
			(effects
				(font
					(size 1.27 1.27)
				)
			)
		)
		(duplicate_pad_numbers_are_jumpers no)
		(fp_line
			(start -0.7874 -0.4064)
			(end 0.7874 -0.4064)
			(stroke
				(width 0.1524)
				(type default)
			)
			(layer "F.SilkS")
		)
		(fp_line
			(start -0.7874 0.4064)
			(end -0.7874 -0.4064)
			(stroke
				(width 0.1524)
				(type default)
			)
			(layer "F.SilkS")
		)
		(fp_line
			(start 0.7874 -0.4064)
			(end 0.7874 0.4064)
			(stroke
				(width 0.1524)
				(type default)
			)
			(layer "F.SilkS")
		)
		(fp_line
			(start 0.7874 0.4064)
			(end -0.7874 0.4064)
			(stroke
				(width 0.1524)
				(type default)
			)
			(layer "F.SilkS")
		)
		(fp_line
			(start -0.67945 -0.305054)
			(end -0.12065 -0.305054)
			(stroke
				(width 0.1)
				(type default)
			)
			(layer "F.Fab")
		)
		(fp_line
			(start -0.67945 0.3048)
			(end -0.67945 -0.305054)
			(stroke
				(width 0.1)
				(type default)
			)
			(layer "F.Fab")
		)
		(fp_line
			(start -0.12065 -0.305054)
			(end -0.12065 -0.2794)
			(stroke
				(width 0.1)
				(type default)
			)
			(layer "F.Fab")
		)
		(fp_line
			(start -0.12065 -0.2794)
			(end 0.12065 -0.2794)
			(stroke
				(width 0.1)
				(type default)
			)
			(layer "F.Fab")
		)
		(fp_line
			(start -0.12065 0.2794)
			(end -0.12065 0.3048)
			(stroke
				(width 0.1)
				(type default)
			)
			(layer "F.Fab")
		)
		(fp_line
			(start -0.12065 0.3048)
			(end -0.67945 0.3048)
			(stroke
				(width 0.1)
				(type default)
			)
			(layer "F.Fab")
		)
		(fp_line
			(start 0.120396 0.2794)
			(end -0.12065 0.2794)
			(stroke
				(width 0.1)
				(type default)
			)
			(layer "F.Fab")
		)
		(fp_line
			(start 0.120396 0.3048)
			(end 0.120396 0.2794)
			(stroke
				(width 0.1)
				(type default)
			)
			(layer "F.Fab")
		)
		(fp_line
			(start 0.12065 -0.3048)
			(end 0.67945 -0.3048)
			(stroke
				(width 0.1)
				(type default)
			)
			(layer "F.Fab")
		)
		(fp_line
			(start 0.12065 -0.2794)
			(end 0.12065 -0.3048)
			(stroke
				(width 0.1)
				(type default)
			)
			(layer "F.Fab")
		)
		(fp_line
			(start 0.67945 -0.3048)
			(end 0.67945 0.3048)
			(stroke
				(width 0.1)
				(type default)
			)
			(layer "F.Fab")
		)
		(fp_line
			(start 0.67945 0.3048)
			(end 0.120396 0.3048)
			(stroke
				(width 0.1)
				(type default)
			)
			(layer "F.Fab")
		)
		(pad "1" smd circle
			(at -0.40005 0)
			(size 0 0)
			(layers "F.Cu" "F.Mask" "F.Paste")
			(net "SW_P12V_AUX_PVDDCR_CPU0_P0_FLT")
		)
		(pad "2" smd circle
			(at 0.40005 0)
			(size 0 0)
			(layers "F.Cu" "F.Mask" "F.Paste")
			(net "GND")
		)
	)
	(footprint ""
		(layer "F.Cu")
		(at 352.705416 -438.992772 180)
		(property "Reference" "R4548"
			(at 0 0 180)
			(layer "F.SilkS")
			(hide yes)
			(effects
				(font
					(size 1.27 1.27)
				)
			)
		)
		(property "Value" ""
			(at 0 0 180)
			(layer "F.Fab")
			(effects
				(font
					(size 1.27 1.27)
				)
			)
		)
		(duplicate_pad_numbers_are_jumpers no)
		(fp_line
			(start 0.7874 0.4064)
			(end -0.7874 0.4064)
			(stroke
				(width 0.1524)
				(type default)
			)
			(layer "F.SilkS")
		)
		(fp_line
			(start 0.7874 -0.4064)
			(end 0.7874 0.4064)
			(stroke
				(width 0.1524)
				(type default)
			)
			(layer "F.SilkS")
		)
		(fp_line
			(start -0.7874 0.4064)
			(end -0.7874 -0.4064)
			(stroke
				(width 0.1524)
				(type default)
			)
			(layer "F.SilkS")
		)
		(fp_line
			(start -0.7874 -0.4064)
			(end 0.7874 -0.4064)
			(stroke
				(width 0.1524)
				(type default)
			)
			(layer "F.SilkS")
		)
		(fp_line
			(start 0.67945 0.3048)
			(end 0.120396 0.3048)
			(stroke
				(width 0.1)
				(type default)
			)
			(layer "F.Fab")
		)
		(fp_line
			(start 0.67945 -0.3048)
			(end 0.67945 0.3048)
			(stroke
				(width 0.1)
				(type default)
			)
			(layer "F.Fab")
		)
		(fp_line
			(start 0.12065 -0.2794)
			(end 0.12065 -0.3048)
			(stroke
				(width 0.1)
				(type default)
			)
			(layer "F.Fab")
		)
		(fp_line
			(start 0.12065 -0.3048)
			(end 0.67945 -0.3048)
			(stroke
				(width 0.1)
				(type default)
			)
			(layer "F.Fab")
		)
		(fp_line
			(start 0.120396 0.3048)
			(end 0.120396 0.2794)
			(stroke
				(width 0.1)
				(type default)
			)
			(layer "F.Fab")
		)
		(fp_line
			(start 0.120396 0.2794)
			(end -0.12065 0.2794)
			(stroke
				(width 0.1)
				(type default)
			)
			(layer "F.Fab")
		)
		(fp_line
			(start -0.12065 0.3048)
			(end -0.67945 0.3048)
			(stroke
				(width 0.1)
				(type default)
			)
			(layer "F.Fab")
		)
		(fp_line
			(start -0.12065 0.2794)
			(end -0.12065 0.3048)
			(stroke
				(width 0.1)
				(type default)
			)
			(layer "F.Fab")
		)
		(fp_line
			(start -0.12065 -0.2794)
			(end 0.12065 -0.2794)
			(stroke
				(width 0.1)
				(type default)
			)
			(layer "F.Fab")
		)
		(fp_line
			(start -0.12065 -0.305054)
			(end -0.12065 -0.2794)
			(stroke
				(width 0.1)
				(type default)
			)
			(layer "F.Fab")
		)
		(fp_line
			(start -0.67945 0.3048)
			(end -0.67945 -0.305054)
			(stroke
				(width 0.1)
				(type default)
			)
			(layer "F.Fab")
		)
		(fp_line
			(start -0.67945 -0.305054)
			(end -0.12065 -0.305054)
			(stroke
				(width 0.1)
				(type default)
			)
			(layer "F.Fab")
		)
		(pad "1" smd circle
			(at -0.40005 0 180)
			(size 0 0)
			(layers "F.Cu" "F.Mask" "F.Paste")
			(net "SWB_HSC_EN")
		)
		(pad "2" smd circle
			(at 0.40005 0 180)
			(size 0 0)
			(layers "F.Cu" "F.Mask" "F.Paste")
			(net "GND")
		)
	)
	(footprint ""
		(layer "F.Cu")
		(at 397.369538 -392.1252)
		(property "Reference" "R1077"
			(at 0 0 0)
			(layer "F.SilkS")
			(hide yes)
			(effects
				(font
					(size 1.27 1.27)
				)
			)
		)
		(property "Value" ""
			(at 0 0 0)
			(layer "F.Fab")
			(effects
				(font
					(size 1.27 1.27)
				)
			)
		)
		(duplicate_pad_numbers_are_jumpers no)
		(fp_line
			(start -0.32512 -0.175006)
			(end 0.32512 -0.175006)
			(stroke
				(width 0.1)
				(type default)
			)
			(layer "F.Fab")
		)
		(fp_line
			(start -0.32512 0.175006)
			(end -0.32512 -0.175006)
			(stroke
				(width 0.1)
				(type default)
			)
			(layer "F.Fab")
		)
		(fp_line
			(start 0.32512 -0.175006)
			(end 0.32512 0.175006)
			(stroke
				(width 0.1)
				(type default)
			)
			(layer "F.Fab")
		)
		(fp_line
			(start 0.32512 0.175006)
			(end -0.32512 0.175006)
			(stroke
				(width 0.1)
				(type default)
			)
			(layer "F.Fab")
		)
		(pad "1" smd rect
			(at -0.2667 0)
			(size 0.3048 0.381)
			(layers "F.Cu" "F.Mask" "F.Paste")
			(net "P1V8_CPU0_RT_1D")
		)
		(pad "2" smd rect
			(at 0.2667 0 180)
			(size 0.3048 0.381)
			(layers "F.Cu" "F.Mask" "F.Paste")
			(net "TEST2_RT_CPU0_P2")
		)
	)
	(footprint ""
		(layer "F.Cu")
		(at 423.631868 -360.824018)
		(property "Reference" "PR126"
			(at 0 0 0)
			(layer "F.SilkS")
			(hide yes)
			(effects
				(font
					(size 1.27 1.27)
				)
			)
		)
		(property "Value" ""
			(at 0 0 0)
			(layer "F.Fab")
			(effects
				(font
					(size 1.27 1.27)
				)
			)
		)
		(duplicate_pad_numbers_are_jumpers no)
		(fp_line
			(start -0.7874 -0.4064)
			(end 0.7874 -0.4064)
			(stroke
				(width 0.1524)
				(type default)
			)
			(layer "F.SilkS")
		)
		(fp_line
			(start -0.7874 0.4064)
			(end -0.7874 -0.4064)
			(stroke
				(width 0.1524)
				(type default)
			)
			(layer "F.SilkS")
		)
		(fp_line
			(start 0.7874 -0.4064)
			(end 0.7874 0.4064)
			(stroke
				(width 0.1524)
				(type default)
			)
			(layer "F.SilkS")
		)
		(fp_line
			(start 0.7874 0.4064)
			(end -0.7874 0.4064)
			(stroke
				(width 0.1524)
				(type default)
			)
			(layer "F.SilkS")
		)
		(fp_line
			(start -0.67945 -0.305054)
			(end -0.12065 -0.305054)
			(stroke
				(width 0.1)
				(type default)
			)
			(layer "F.Fab")
		)
		(fp_line
			(start -0.67945 0.3048)
			(end -0.67945 -0.305054)
			(stroke
				(width 0.1)
				(type default)
			)
			(layer "F.Fab")
		)
		(fp_line
			(start -0.12065 -0.305054)
			(end -0.12065 -0.2794)
			(stroke
				(width 0.1)
				(type default)
			)
			(layer "F.Fab")
		)
		(fp_line
			(start -0.12065 -0.2794)
			(end 0.12065 -0.2794)
			(stroke
				(width 0.1)
				(type default)
			)
			(layer "F.Fab")
		)
		(fp_line
			(start -0.12065 0.2794)
			(end -0.12065 0.3048)
			(stroke
				(width 0.1)
				(type default)
			)
			(layer "F.Fab")
		)
		(fp_line
			(start -0.12065 0.3048)
			(end -0.67945 0.3048)
			(stroke
				(width 0.1)
				(type default)
			)
			(layer "F.Fab")
		)
		(fp_line
			(start 0.120396 0.2794)
			(end -0.12065 0.2794)
			(stroke
				(width 0.1)
				(type default)
			)
			(layer "F.Fab")
		)
		(fp_line
			(start 0.120396 0.3048)
			(end 0.120396 0.2794)
			(stroke
				(width 0.1)
				(type default)
			)
			(layer "F.Fab")
		)
		(fp_line
			(start 0.12065 -0.3048)
			(end 0.67945 -0.3048)
			(stroke
				(width 0.1)
				(type default)
			)
			(layer "F.Fab")
		)
		(fp_line
			(start 0.12065 -0.2794)
			(end 0.12065 -0.3048)
			(stroke
				(width 0.1)
				(type default)
			)
			(layer "F.Fab")
		)
		(fp_line
			(start 0.67945 -0.3048)
			(end 0.67945 0.3048)
			(stroke
				(width 0.1)
				(type default)
			)
			(layer "F.Fab")
		)
		(fp_line
			(start 0.67945 0.3048)
			(end 0.120396 0.3048)
			(stroke
				(width 0.1)
				(type default)
			)
			(layer "F.Fab")
		)
		(pad "1" smd circle
			(at -0.40005 0)
			(size 0 0)
			(layers "F.Cu" "F.Mask" "F.Paste")
			(net "PVDD11_S3_P0_ADDR_CFG")
		)
		(pad "2" smd circle
			(at 0.40005 0)
			(size 0 0)
			(layers "F.Cu" "F.Mask" "F.Paste")
			(net "GND")
		)
	)
	(footprint ""
		(layer "F.Cu")
		(at 215.585548 -133.600952 90)
		(property "Reference" "C345"
			(at 0 0 90)
			(layer "F.SilkS")
			(hide yes)
			(effects
				(font
					(size 1.27 1.27)
				)
			)
		)
		(property "Value" ""
			(at 0 0 90)
			(layer "F.Fab")
			(effects
				(font
					(size 1.27 1.27)
				)
			)
		)
		(duplicate_pad_numbers_are_jumpers no)
		(fp_line
			(start 0.7874 -0.4064)
			(end 0.7874 0.4064)
			(stroke
				(width 0.1524)
				(type default)
			)
			(layer "F.SilkS")
		)
		(fp_line
			(start -0.7874 -0.4064)
			(end 0.7874 -0.4064)
			(stroke
				(width 0.1524)
				(type default)
			)
			(layer "F.SilkS")
		)
		(fp_line
			(start 0.7874 0.4064)
			(end -0.7874 0.4064)
			(stroke
				(width 0.1524)
				(type default)
			)
			(layer "F.SilkS")
		)
		(fp_line
			(start -0.7874 0.4064)
			(end -0.7874 -0.4064)
			(stroke
				(width 0.1524)
				(type default)
			)
			(layer "F.SilkS")
		)
		(fp_line
			(start -0.12065 -0.305054)
			(end -0.12065 -0.2794)
			(stroke
				(width 0.1)
				(type default)
			)
			(layer "F.Fab")
		)
		(fp_line
			(start -0.67945 -0.305054)
			(end -0.12065 -0.305054)
			(stroke
				(width 0.1)
				(type default)
			)
			(layer "F.Fab")
		)
		(fp_line
			(start 0.67945 -0.3048)
			(end 0.67945 0.3048)
			(stroke
				(width 0.1)
				(type default)
			)
			(layer "F.Fab")
		)
		(fp_line
			(start 0.12065 -0.3048)
			(end 0.67945 -0.3048)
			(stroke
				(width 0.1)
				(type default)
			)
			(layer "F.Fab")
		)
		(fp_line
			(start 0.12065 -0.2794)
			(end 0.12065 -0.3048)
			(stroke
				(width 0.1)
				(type default)
			)
			(layer "F.Fab")
		)
		(fp_line
			(start -0.12065 -0.2794)
			(end 0.12065 -0.2794)
			(stroke
				(width 0.1)
				(type default)
			)
			(layer "F.Fab")
		)
		(fp_line
			(start 0.120396 0.2794)
			(end -0.12065 0.2794)
			(stroke
				(width 0.1)
				(type default)
			)
			(layer "F.Fab")
		)
		(fp_line
			(start -0.12065 0.2794)
			(end -0.12065 0.3048)
			(stroke
				(width 0.1)
				(type default)
			)
			(layer "F.Fab")
		)
		(fp_line
			(start 0.67945 0.3048)
			(end 0.120396 0.3048)
			(stroke
				(width 0.1)
				(type default)
			)
			(layer "F.Fab")
		)
		(fp_line
			(start 0.120396 0.3048)
			(end 0.120396 0.2794)
			(stroke
				(width 0.1)
				(type default)
			)
			(layer "F.Fab")
		)
		(fp_line
			(start -0.12065 0.3048)
			(end -0.67945 0.3048)
			(stroke
				(width 0.1)
				(type default)
			)
			(layer "F.Fab")
		)
		(fp_line
			(start -0.67945 0.3048)
			(end -0.67945 -0.305054)
			(stroke
				(width 0.1)
				(type default)
			)
			(layer "F.Fab")
		)
		(pad "1" smd circle
			(at -0.40005 0 90)
			(size 0 0)
			(layers "F.Cu" "F.Mask" "F.Paste")
			(net "P1V8_AUX_ENABLE")
		)
		(pad "2" smd circle
			(at 0.40005 0 90)
			(size 0 0)
			(layers "F.Cu" "F.Mask" "F.Paste")
			(net "GND")
		)
	)
	(footprint ""
		(layer "F.Cu")
		(at 367.931446 -30.135322 90)
		(property "Reference" "R823"
			(at 0 0 90)
			(layer "F.SilkS")
			(hide yes)
			(effects
				(font
					(size 1.27 1.27)
				)
			)
		)
		(property "Value" ""
			(at 0 0 90)
			(layer "F.Fab")
			(effects
				(font
					(size 1.27 1.27)
				)
			)
		)
		(duplicate_pad_numbers_are_jumpers no)
		(fp_line
			(start 0.7874 -0.4064)
			(end 0.7874 0.4064)
			(stroke
				(width 0.1524)
				(type default)
			)
			(layer "F.SilkS")
		)
		(fp_line
			(start -0.7874 -0.4064)
			(end 0.7874 -0.4064)
			(stroke
				(width 0.1524)
				(type default)
			)
			(layer "F.SilkS")
		)
		(fp_line
			(start 0.7874 0.4064)
			(end -0.7874 0.4064)
			(stroke
				(width 0.1524)
				(type default)
			)
			(layer "F.SilkS")
		)
		(fp_line
			(start -0.7874 0.4064)
			(end -0.7874 -0.4064)
			(stroke
				(width 0.1524)
				(type default)
			)
			(layer "F.SilkS")
		)
		(fp_line
			(start -0.12065 -0.305054)
			(end -0.12065 -0.2794)
			(stroke
				(width 0.1)
				(type default)
			)
			(layer "F.Fab")
		)
		(fp_line
			(start -0.67945 -0.305054)
			(end -0.12065 -0.305054)
			(stroke
				(width 0.1)
				(type default)
			)
			(layer "F.Fab")
		)
		(fp_line
			(start 0.67945 -0.3048)
			(end 0.67945 0.3048)
			(stroke
				(width 0.1)
				(type default)
			)
			(layer "F.Fab")
		)
		(fp_line
			(start 0.12065 -0.3048)
			(end 0.67945 -0.3048)
			(stroke
				(width 0.1)
				(type default)
			)
			(layer "F.Fab")
		)
		(fp_line
			(start 0.12065 -0.2794)
			(end 0.12065 -0.3048)
			(stroke
				(width 0.1)
				(type default)
			)
			(layer "F.Fab")
		)
		(fp_line
			(start -0.12065 -0.2794)
			(end 0.12065 -0.2794)
			(stroke
				(width 0.1)
				(type default)
			)
			(layer "F.Fab")
		)
		(fp_line
			(start 0.120396 0.2794)
			(end -0.12065 0.2794)
			(stroke
				(width 0.1)
				(type default)
			)
			(layer "F.Fab")
		)
		(fp_line
			(start -0.12065 0.2794)
			(end -0.12065 0.3048)
			(stroke
				(width 0.1)
				(type default)
			)
			(layer "F.Fab")
		)
		(fp_line
			(start 0.67945 0.3048)
			(end 0.120396 0.3048)
			(stroke
				(width 0.1)
				(type default)
			)
			(layer "F.Fab")
		)
		(fp_line
			(start 0.120396 0.3048)
			(end 0.120396 0.2794)
			(stroke
				(width 0.1)
				(type default)
			)
			(layer "F.Fab")
		)
		(fp_line
			(start -0.12065 0.3048)
			(end -0.67945 0.3048)
			(stroke
				(width 0.1)
				(type default)
			)
			(layer "F.Fab")
		)
		(fp_line
			(start -0.67945 0.3048)
			(end -0.67945 -0.305054)
			(stroke
				(width 0.1)
				(type default)
			)
			(layer "F.Fab")
		)
		(pad "1" smd circle
			(at -0.40005 0 90)
			(size 0 0)
			(layers "F.Cu" "F.Mask" "F.Paste")
			(net "P3V3_AUX")
		)
		(pad "2" smd circle
			(at 0.40005 0 90)
			(size 0 0)
			(layers "F.Cu" "F.Mask" "F.Paste")
			(net "UART_CPU0_SCM_LVC3_UART1_R_RX")
		)
	)
	(footprint ""
		(layer "F.Cu")
		(at 224.898712 -67.921378)
		(property "Reference" "R3973"
			(at 0 0 0)
			(layer "F.SilkS")
			(hide yes)
			(effects
				(font
					(size 1.27 1.27)
				)
			)
		)
		(property "Value" ""
			(at 0 0 0)
			(layer "F.Fab")
			(effects
				(font
					(size 1.27 1.27)
				)
			)
		)
		(duplicate_pad_numbers_are_jumpers no)
		(fp_line
			(start -0.7874 -0.4064)
			(end 0.7874 -0.4064)
			(stroke
				(width 0.1524)
				(type default)
			)
			(layer "F.SilkS")
		)
		(fp_line
			(start -0.7874 0.4064)
			(end -0.7874 -0.4064)
			(stroke
				(width 0.1524)
				(type default)
			)
			(layer "F.SilkS")
		)
		(fp_line
			(start 0.7874 -0.4064)
			(end 0.7874 0.4064)
			(stroke
				(width 0.1524)
				(type default)
			)
			(layer "F.SilkS")
		)
		(fp_line
			(start 0.7874 0.4064)
			(end -0.7874 0.4064)
			(stroke
				(width 0.1524)
				(type default)
			)
			(layer "F.SilkS")
		)
		(fp_line
			(start -0.67945 -0.305054)
			(end -0.12065 -0.305054)
			(stroke
				(width 0.1)
				(type default)
			)
			(layer "F.Fab")
		)
		(fp_line
			(start -0.67945 0.3048)
			(end -0.67945 -0.305054)
			(stroke
				(width 0.1)
				(type default)
			)
			(layer "F.Fab")
		)
		(fp_line
			(start -0.12065 -0.305054)
			(end -0.12065 -0.2794)
			(stroke
				(width 0.1)
				(type default)
			)
			(layer "F.Fab")
		)
		(fp_line
			(start -0.12065 -0.2794)
			(end 0.12065 -0.2794)
			(stroke
				(width 0.1)
				(type default)
			)
			(layer "F.Fab")
		)
		(fp_line
			(start -0.12065 0.2794)
			(end -0.12065 0.3048)
			(stroke
				(width 0.1)
				(type default)
			)
			(layer "F.Fab")
		)
		(fp_line
			(start -0.12065 0.3048)
			(end -0.67945 0.3048)
			(stroke
				(width 0.1)
				(type default)
			)
			(layer "F.Fab")
		)
		(fp_line
			(start 0.120396 0.2794)
			(end -0.12065 0.2794)
			(stroke
				(width 0.1)
				(type default)
			)
			(layer "F.Fab")
		)
		(fp_line
			(start 0.120396 0.3048)
			(end 0.120396 0.2794)
			(stroke
				(width 0.1)
				(type default)
			)
			(layer "F.Fab")
		)
		(fp_line
			(start 0.12065 -0.3048)
			(end 0.67945 -0.3048)
			(stroke
				(width 0.1)
				(type default)
			)
			(layer "F.Fab")
		)
		(fp_line
			(start 0.12065 -0.2794)
			(end 0.12065 -0.3048)
			(stroke
				(width 0.1)
				(type default)
			)
			(layer "F.Fab")
		)
		(fp_line
			(start 0.67945 -0.3048)
			(end 0.67945 0.3048)
			(stroke
				(width 0.1)
				(type default)
			)
			(layer "F.Fab")
		)
		(fp_line
			(start 0.67945 0.3048)
			(end 0.120396 0.3048)
			(stroke
				(width 0.1)
				(type default)
			)
			(layer "F.Fab")
		)
		(pad "1" smd circle
			(at -0.40005 0)
			(size 0 0)
			(layers "F.Cu" "F.Mask" "F.Paste")
			(net "P3V3_E1S_PWRGD_0")
		)
		(pad "2" smd circle
			(at 0.40005 0)
			(size 0 0)
			(layers "F.Cu" "F.Mask" "F.Paste")
			(net "P3V3_E1S_PWRGD_0_R")
		)
	)
	(footprint ""
		(layer "F.Cu")
		(at 114.197638 -395.221206 -90)
		(property "Reference" "R924"
			(at 0 0 270)
			(layer "F.SilkS")
			(hide yes)
			(effects
				(font
					(size 1.27 1.27)
				)
			)
		)
		(property "Value" ""
			(at 0 0 270)
			(layer "F.Fab")
			(effects
				(font
					(size 1.27 1.27)
				)
			)
		)
		(duplicate_pad_numbers_are_jumpers no)
		(fp_line
			(start -0.32512 0.175006)
			(end -0.32512 -0.175006)
			(stroke
				(width 0.1)
				(type default)
			)
			(layer "F.Fab")
		)
		(fp_line
			(start 0.32512 0.175006)
			(end -0.32512 0.175006)
			(stroke
				(width 0.1)
				(type default)
			)
			(layer "F.Fab")
		)
		(fp_line
			(start -0.32512 -0.175006)
			(end 0.32512 -0.175006)
			(stroke
				(width 0.1)
				(type default)
			)
			(layer "F.Fab")
		)
		(fp_line
			(start 0.32512 -0.175006)
			(end 0.32512 0.175006)
			(stroke
				(width 0.1)
				(type default)
			)
			(layer "F.Fab")
		)
		(pad "1" smd rect
			(at -0.2667 0 270)
			(size 0.3048 0.381)
			(layers "F.Cu" "F.Mask" "F.Paste")
			(net "JTAG_TEST_MODE_RT_CPU1_P3")
		)
		(pad "2" smd rect
			(at 0.2667 0 90)
			(size 0.3048 0.381)
			(layers "F.Cu" "F.Mask" "F.Paste")
			(net "GND")
		)
	)
	(footprint ""
		(layer "F.Cu")
		(at 450.857366 -180.106066 180)
		(property "Reference" "R1838"
			(at -4.945634 -3.856736 0)
			(unlocked yes)
			(layer "F.SilkS")
			(effects
				(font
					(size 0.7874 0.5842)
					(thickness 0.1524)
				)
				(justify left)
			)
		)
		(property "Value" ""
			(at 0 0 180)
			(layer "F.Fab")
			(effects
				(font
					(size 1.27 1.27)
				)
			)
		)
		(duplicate_pad_numbers_are_jumpers no)
		(fp_line
			(start 4.0386 1.7526)
			(end -4.0386 1.7526)
			(stroke
				(width 0.1524)
				(type default)
			)
			(layer "F.SilkS")
		)
		(fp_line
			(start 4.0386 -1.7526)
			(end 4.0386 1.7526)
			(stroke
				(width 0.1524)
				(type default)
			)
			(layer "F.SilkS")
		)
		(fp_line
			(start -4.0386 1.7526)
			(end -4.0386 -1.7526)
			(stroke
				(width 0.1524)
				(type default)
			)
			(layer "F.SilkS")
		)
		(fp_line
			(start -4.0386 -1.7526)
			(end 4.0386 -1.7526)
			(stroke
				(width 0.1524)
				(type default)
			)
			(layer "F.SilkS")
		)
		(fp_line
			(start 4.0386 1.7526)
			(end -4.0386 1.7526)
			(stroke
				(width 0.1)
				(type default)
			)
			(layer "F.Fab")
		)
		(fp_line
			(start 4.0386 -1.7526)
			(end 4.0386 1.7526)
			(stroke
				(width 0.1)
				(type default)
			)
			(layer "F.Fab")
		)
		(fp_line
			(start -4.0386 1.7526)
			(end -4.0386 -1.7526)
			(stroke
				(width 0.1)
				(type default)
			)
			(layer "F.Fab")
		)
		(fp_line
			(start -4.0386 -1.7526)
			(end 4.0386 -1.7526)
			(stroke
				(width 0.1)
				(type default)
			)
			(layer "F.Fab")
		)
		(pad "1" smd circle
			(at -3.700018 0 90)
			(size 0 0)
			(layers "F.Cu" "F.Mask" "F.Paste")
			(net "P12V_AUX")
		)
		(pad "2" smd circle
			(at 3.700018 0 270)
			(size 0 0)
			(layers "F.Cu" "F.Mask" "F.Paste")
			(net "P12V_MEM_CPU0")
		)
		(pad "3" smd rect
			(at -2.70002 0 270)
			(size 0.4064 1.1176)
			(layers "F.Cu" "F.Mask" "F.Paste")
			(net "TP_P12V_AUX_CPU0_DIMM_ISEN_P")
		)
		(pad "4" smd rect
			(at 2.70002 0 270)
			(size 0.4064 1.1176)
			(layers "F.Cu" "F.Mask" "F.Paste")
			(net "TP_P12V_AUX_CPU0_DIMM_ISEN_N")
		)
	)
	(footprint ""
		(layer "F.Cu")
		(at 155.459938 -118.132352 180)
		(property "Reference" "U206"
			(at -2.499106 -1.948434 0)
			(unlocked yes)
			(layer "F.SilkS")
			(effects
				(font
					(size 0.7874 0.5842)
					(thickness 0.1524)
				)
				(justify left)
			)
		)
		(property "Value" ""
			(at 0 0 180)
			(layer "F.Fab")
			(effects
				(font
					(size 1.27 1.27)
				)
			)
		)
		(duplicate_pad_numbers_are_jumpers no)
		(fp_line
			(start 2.046478 1.450086)
			(end 2.046478 -1.450086)
			(stroke
				(width 0.1524)
				(type default)
			)
			(layer "F.SilkS")
		)
		(fp_line
			(start 2.046478 -1.450086)
			(end 0.484886 -1.450086)
			(stroke
				(width 0.1524)
				(type default)
			)
			(layer "F.SilkS")
		)
		(fp_line
			(start 0.484886 -1.450086)
			(end 0 -0.762)
			(stroke
				(width 0.1524)
				(type default)
			)
			(layer "F.SilkS")
		)
		(fp_line
			(start 0 -0.762)
			(end -0.484886 -1.450086)
			(stroke
				(width 0.1524)
				(type default)
			)
			(layer "F.SilkS")
		)
		(fp_line
			(start -0.484886 -1.450086)
			(end -2.046478 -1.450086)
			(stroke
				(width 0.1524)
				(type default)
			)
			(layer "F.SilkS")
		)
		(fp_line
			(start -2.046478 1.450086)
			(end 2.046478 1.450086)
			(stroke
				(width 0.1524)
				(type default)
			)
			(layer "F.SilkS")
		)
		(fp_line
			(start -2.046478 -1.450086)
			(end -2.046478 1.450086)
			(stroke
				(width 0.1524)
				(type default)
			)
			(layer "F.SilkS")
		)
		(fp_poly
			(pts
				(xy -3.021076 -0.973836) (xy -4.037076 -0.465836) (xy -4.037076 -1.481836)
			)
			(stroke
				(width 0)
				(type default)
			)
			(fill yes)
			(layer "F.SilkS")
		)
		(fp_line
			(start 0.87503 1.450086)
			(end 0.87503 -1.450086)
			(stroke
				(width 0.1)
				(type default)
			)
			(layer "F.Fab")
		)
		(fp_line
			(start 0.87503 -1.450086)
			(end -0.87503 -1.450086)
			(stroke
				(width 0.1)
				(type default)
			)
			(layer "F.Fab")
		)
		(fp_line
			(start -0.87503 1.450086)
			(end 0.87503 1.450086)
			(stroke
				(width 0.1)
				(type default)
			)
			(layer "F.Fab")
		)
		(fp_line
			(start -0.87503 -1.450086)
			(end -0.87503 1.450086)
			(stroke
				(width 0.1)
				(type default)
			)
			(layer "F.Fab")
		)
		(fp_poly
			(pts
				(xy -3.2512 -0.44196) (xy -3.2512 -1.45796) (xy -2.2352 -0.94996)
			)
			(stroke
				(width 0)
				(type default)
			)
			(fill yes)
			(layer "F.Fab")
		)
		(pad "1" smd rect
			(at -1.309878 -0.94996 270)
			(size 0.635 1.2192)
			(layers "F.Cu" "F.Mask" "F.Paste")
			(net "FM_UV_ADR_TRIGGER_N")
		)
		(pad "2" smd rect
			(at -1.309878 0 270)
			(size 0.635 1.2192)
			(layers "F.Cu" "F.Mask" "F.Paste")
			(net "GND")
		)
		(pad "3" smd rect
			(at -1.309878 0.94996 270)
			(size 0.635 1.2192)
			(layers "F.Cu" "F.Mask" "F.Paste")
			(net "A_P12V_STBY_ADR_TRIGGER")
		)
		(pad "4" smd rect
			(at 1.309878 0.94996 270)
			(size 0.635 1.2192)
			(layers "F.Cu" "F.Mask" "F.Paste")
			(net "A_P12V_STBY_FP_TRIGGER")
		)
		(pad "5" smd rect
			(at 1.309878 0 270)
			(size 0.635 1.2192)
			(layers "F.Cu" "F.Mask" "F.Paste")
			(net "U206_VS")
		)
		(pad "6" smd rect
			(at 1.309878 -0.94996 270)
			(size 0.635 1.2192)
			(layers "F.Cu" "F.Mask" "F.Paste")
			(net "A_P12V_STBY_FPH_GATE")
		)
	)
	(footprint ""
		(layer "F.Cu")
		(at 358.389936 -392.48588 180)
		(property "Reference" "R1003"
			(at 0 0 180)
			(layer "F.SilkS")
			(hide yes)
			(effects
				(font
					(size 1.27 1.27)
				)
			)
		)
		(property "Value" ""
			(at 0 0 180)
			(layer "F.Fab")
			(effects
				(font
					(size 1.27 1.27)
				)
			)
		)
		(duplicate_pad_numbers_are_jumpers no)
		(fp_line
			(start 0.7874 0.4064)
			(end -0.7874 0.4064)
			(stroke
				(width 0.1524)
				(type default)
			)
			(layer "F.SilkS")
		)
		(fp_line
			(start 0.7874 -0.4064)
			(end 0.7874 0.4064)
			(stroke
				(width 0.1524)
				(type default)
			)
			(layer "F.SilkS")
		)
		(fp_line
			(start -0.7874 0.4064)
			(end -0.7874 -0.4064)
			(stroke
				(width 0.1524)
				(type default)
			)
			(layer "F.SilkS")
		)
		(fp_line
			(start -0.7874 -0.4064)
			(end 0.7874 -0.4064)
			(stroke
				(width 0.1524)
				(type default)
			)
			(layer "F.SilkS")
		)
		(fp_line
			(start 0.67945 0.3048)
			(end 0.120396 0.3048)
			(stroke
				(width 0.1)
				(type default)
			)
			(layer "F.Fab")
		)
		(fp_line
			(start 0.67945 -0.3048)
			(end 0.67945 0.3048)
			(stroke
				(width 0.1)
				(type default)
			)
			(layer "F.Fab")
		)
		(fp_line
			(start 0.12065 -0.2794)
			(end 0.12065 -0.3048)
			(stroke
				(width 0.1)
				(type default)
			)
			(layer "F.Fab")
		)
		(fp_line
			(start 0.12065 -0.3048)
			(end 0.67945 -0.3048)
			(stroke
				(width 0.1)
				(type default)
			)
			(layer "F.Fab")
		)
		(fp_line
			(start 0.120396 0.3048)
			(end 0.120396 0.2794)
			(stroke
				(width 0.1)
				(type default)
			)
			(layer "F.Fab")
		)
		(fp_line
			(start 0.120396 0.2794)
			(end -0.12065 0.2794)
			(stroke
				(width 0.1)
				(type default)
			)
			(layer "F.Fab")
		)
		(fp_line
			(start -0.12065 0.3048)
			(end -0.67945 0.3048)
			(stroke
				(width 0.1)
				(type default)
			)
			(layer "F.Fab")
		)
		(fp_line
			(start -0.12065 0.2794)
			(end -0.12065 0.3048)
			(stroke
				(width 0.1)
				(type default)
			)
			(layer "F.Fab")
		)
		(fp_line
			(start -0.12065 -0.2794)
			(end 0.12065 -0.2794)
			(stroke
				(width 0.1)
				(type default)
			)
			(layer "F.Fab")
		)
		(fp_line
			(start -0.12065 -0.305054)
			(end -0.12065 -0.2794)
			(stroke
				(width 0.1)
				(type default)
			)
			(layer "F.Fab")
		)
		(fp_line
			(start -0.67945 0.3048)
			(end -0.67945 -0.305054)
			(stroke
				(width 0.1)
				(type default)
			)
			(layer "F.Fab")
		)
		(fp_line
			(start -0.67945 -0.305054)
			(end -0.12065 -0.305054)
			(stroke
				(width 0.1)
				(type default)
			)
			(layer "F.Fab")
		)
		(pad "1" smd rect
			(at -0.40005 0)
			(size 0.4572 0.508)
			(layers "F.Cu" "F.Mask" "F.Paste")
			(net "P1V8_CPU0_RT1_1A_1D")
		)
		(pad "2" smd rect
			(at 0.40005 0)
			(size 0.4572 0.508)
			(layers "F.Cu" "F.Mask" "F.Paste")
			(net "P1V8_CPU0_RT1_1A")
		)
	)
	(footprint ""
		(layer "F.Cu")
		(at 386.184902 -416.899344 -90)
		(property "Reference" "C6576"
			(at 0 0 270)
			(layer "F.SilkS")
			(hide yes)
			(effects
				(font
					(size 1.27 1.27)
				)
			)
		)
		(property "Value" ""
			(at 0 0 270)
			(layer "F.Fab")
			(effects
				(font
					(size 1.27 1.27)
				)
			)
		)
		(duplicate_pad_numbers_are_jumpers no)
		(fp_line
			(start -0.299974 0.150114)
			(end -0.299974 -0.150114)
			(stroke
				(width 0.1)
				(type default)
			)
			(layer "F.Fab")
		)
		(fp_line
			(start 0.299974 0.150114)
			(end -0.299974 0.150114)
			(stroke
				(width 0.1)
				(type default)
			)
			(layer "F.Fab")
		)
		(fp_line
			(start -0.299974 -0.150114)
			(end 0.299974 -0.150114)
			(stroke
				(width 0.1)
				(type default)
			)
			(layer "F.Fab")
		)
		(fp_line
			(start 0.299974 -0.150114)
			(end 0.299974 0.150114)
			(stroke
				(width 0.1)
				(type default)
			)
			(layer "F.Fab")
		)
		(pad "1" smd rect
			(at -0.2667 0 270)
			(size 0.3048 0.381)
			(layers "F.Cu" "F.Mask" "F.Paste")
			(net "P5E_CPU0_P2_TX_BUF_C_DN<5>")
		)
		(pad "2" smd rect
			(at 0.2667 0 270)
			(size 0.3048 0.381)
			(layers "F.Cu" "F.Mask" "F.Paste")
			(net "P5E_CPU0_P2_TX_BUF_DN<5>")
		)
	)
	(footprint ""
		(layer "F.Cu")
		(at 226.0981 -407.068782 180)
		(property "Reference" "PR3982"
			(at 0 0 180)
			(layer "F.SilkS")
			(hide yes)
			(effects
				(font
					(size 1.27 1.27)
				)
			)
		)
		(property "Value" ""
			(at 0 0 180)
			(layer "F.Fab")
			(effects
				(font
					(size 1.27 1.27)
				)
			)
		)
		(duplicate_pad_numbers_are_jumpers no)
		(fp_line
			(start 0.7874 0.4064)
			(end -0.7874 0.4064)
			(stroke
				(width 0.1524)
				(type default)
			)
			(layer "F.SilkS")
		)
		(fp_line
			(start 0.7874 -0.4064)
			(end 0.7874 0.4064)
			(stroke
				(width 0.1524)
				(type default)
			)
			(layer "F.SilkS")
		)
		(fp_line
			(start -0.7874 0.4064)
			(end -0.7874 -0.4064)
			(stroke
				(width 0.1524)
				(type default)
			)
			(layer "F.SilkS")
		)
		(fp_line
			(start -0.7874 -0.4064)
			(end 0.7874 -0.4064)
			(stroke
				(width 0.1524)
				(type default)
			)
			(layer "F.SilkS")
		)
		(fp_line
			(start 0.67945 0.3048)
			(end 0.120396 0.3048)
			(stroke
				(width 0.1)
				(type default)
			)
			(layer "F.Fab")
		)
		(fp_line
			(start 0.67945 -0.3048)
			(end 0.67945 0.3048)
			(stroke
				(width 0.1)
				(type default)
			)
			(layer "F.Fab")
		)
		(fp_line
			(start 0.12065 -0.2794)
			(end 0.12065 -0.3048)
			(stroke
				(width 0.1)
				(type default)
			)
			(layer "F.Fab")
		)
		(fp_line
			(start 0.12065 -0.3048)
			(end 0.67945 -0.3048)
			(stroke
				(width 0.1)
				(type default)
			)
			(layer "F.Fab")
		)
		(fp_line
			(start 0.120396 0.3048)
			(end 0.120396 0.2794)
			(stroke
				(width 0.1)
				(type default)
			)
			(layer "F.Fab")
		)
		(fp_line
			(start 0.120396 0.2794)
			(end -0.12065 0.2794)
			(stroke
				(width 0.1)
				(type default)
			)
			(layer "F.Fab")
		)
		(fp_line
			(start -0.12065 0.3048)
			(end -0.67945 0.3048)
			(stroke
				(width 0.1)
				(type default)
			)
			(layer "F.Fab")
		)
		(fp_line
			(start -0.12065 0.2794)
			(end -0.12065 0.3048)
			(stroke
				(width 0.1)
				(type default)
			)
			(layer "F.Fab")
		)
		(fp_line
			(start -0.12065 -0.2794)
			(end 0.12065 -0.2794)
			(stroke
				(width 0.1)
				(type default)
			)
			(layer "F.Fab")
		)
		(fp_line
			(start -0.12065 -0.305054)
			(end -0.12065 -0.2794)
			(stroke
				(width 0.1)
				(type default)
			)
			(layer "F.Fab")
		)
		(fp_line
			(start -0.67945 0.3048)
			(end -0.67945 -0.305054)
			(stroke
				(width 0.1)
				(type default)
			)
			(layer "F.Fab")
		)
		(fp_line
			(start -0.67945 -0.305054)
			(end -0.12065 -0.305054)
			(stroke
				(width 0.1)
				(type default)
			)
			(layer "F.Fab")
		)
		(pad "1" smd circle
			(at -0.40005 0 180)
			(size 0 0)
			(layers "F.Cu" "F.Mask" "F.Paste")
			(net "AGND_HSC")
		)
		(pad "2" smd circle
			(at 0.40005 0 180)
			(size 0 0)
			(layers "F.Cu" "F.Mask" "F.Paste")
			(net "HSC_MODE_3")
		)
	)
	(footprint ""
		(layer "F.Cu")
		(at 137.974832 -76.242672 90)
		(property "Reference" "PL6002"
			(at 0 0 90)
			(layer "F.SilkS")
			(hide yes)
			(effects
				(font
					(size 1.27 1.27)
				)
			)
		)
		(property "Value" ""
			(at 0 0 90)
			(layer "F.Fab")
			(effects
				(font
					(size 1.27 1.27)
				)
			)
		)
		(duplicate_pad_numbers_are_jumpers no)
		(fp_line
			(start -1.27 -0.5842)
			(end 1.27 -0.5842)
			(stroke
				(width 0.1524)
				(type default)
			)
			(layer "F.SilkS")
		)
		(fp_line
			(start -1.27 -0.5588)
			(end -1.27 -0.5842)
			(stroke
				(width 0.1524)
				(type default)
			)
			(layer "F.SilkS")
		)
		(fp_line
			(start 1.27 0.5842)
			(end 1.27 -0.5842)
			(stroke
				(width 0.1524)
				(type default)
			)
			(layer "F.SilkS")
		)
		(fp_line
			(start 1.27 0.5842)
			(end -1.27 0.5842)
			(stroke
				(width 0.1524)
				(type default)
			)
			(layer "F.SilkS")
		)
		(fp_line
			(start -1.27 0.5842)
			(end -1.27 -0.5842)
			(stroke
				(width 0.1524)
				(type default)
			)
			(layer "F.SilkS")
		)
		(fp_line
			(start 0.9144 -0.508)
			(end 0.9144 -0.406654)
			(stroke
				(width 0.1)
				(type default)
			)
			(layer "F.Fab")
		)
		(fp_line
			(start -0.9144 -0.508)
			(end 0.9144 -0.508)
			(stroke
				(width 0.1)
				(type default)
			)
			(layer "F.Fab")
		)
		(fp_line
			(start 1.1938 -0.406654)
			(end 1.1938 0.4064)
			(stroke
				(width 0.1)
				(type default)
			)
			(layer "F.Fab")
		)
		(fp_line
			(start 0.9144 -0.406654)
			(end 1.1938 -0.406654)
			(stroke
				(width 0.1)
				(type default)
			)
			(layer "F.Fab")
		)
		(fp_line
			(start -0.9144 -0.406654)
			(end -0.9144 -0.508)
			(stroke
				(width 0.1)
				(type default)
			)
			(layer "F.Fab")
		)
		(fp_line
			(start -1.194308 -0.406654)
			(end -0.9144 -0.406654)
			(stroke
				(width 0.1)
				(type default)
			)
			(layer "F.Fab")
		)
		(fp_line
			(start 1.1938 0.4064)
			(end 0.9144 0.4064)
			(stroke
				(width 0.1)
				(type default)
			)
			(layer "F.Fab")
		)
		(fp_line
			(start 0.9144 0.4064)
			(end 0.9144 0.508)
			(stroke
				(width 0.1)
				(type default)
			)
			(layer "F.Fab")
		)
		(fp_line
			(start -0.9144 0.406654)
			(end -1.194308 0.406654)
			(stroke
				(width 0.1)
				(type default)
			)
			(layer "F.Fab")
		)
		(fp_line
			(start -1.194308 0.406654)
			(end -1.194308 -0.406654)
			(stroke
				(width 0.1)
				(type default)
			)
			(layer "F.Fab")
		)
		(fp_line
			(start 0.9144 0.508)
			(end -0.9144 0.508)
			(stroke
				(width 0.1)
				(type default)
			)
			(layer "F.Fab")
		)
		(fp_line
			(start -0.9144 0.508)
			(end -0.9144 0.406654)
			(stroke
				(width 0.1)
				(type default)
			)
			(layer "F.Fab")
		)
		(pad "1" smd rect
			(at -0.7366 0)
			(size 0.7112 0.8128)
			(layers "F.Cu" "F.Mask" "F.Paste")
			(net "P12V_AUX")
		)
		(pad "2" smd rect
			(at 0.7366 0)
			(size 0.7112 0.8128)
			(layers "F.Cu" "F.Mask" "F.Paste")
			(net "SW_P12V_AUX_P1V8_AUX_FLT")
		)
	)
	(footprint ""
		(layer "F.Cu")
		(at 120.358662 -16.50365)
		(property "Reference" "R4201"
			(at 0 0 0)
			(layer "F.SilkS")
			(hide yes)
			(effects
				(font
					(size 1.27 1.27)
				)
			)
		)
		(property "Value" ""
			(at 0 0 0)
			(layer "F.Fab")
			(effects
				(font
					(size 1.27 1.27)
				)
			)
		)
		(duplicate_pad_numbers_are_jumpers no)
		(fp_line
			(start -0.7874 -0.4064)
			(end 0.7874 -0.4064)
			(stroke
				(width 0.1524)
				(type default)
			)
			(layer "F.SilkS")
		)
		(fp_line
			(start -0.7874 0.4064)
			(end -0.7874 -0.4064)
			(stroke
				(width 0.1524)
				(type default)
			)
			(layer "F.SilkS")
		)
		(fp_line
			(start 0.7874 -0.4064)
			(end 0.7874 0.4064)
			(stroke
				(width 0.1524)
				(type default)
			)
			(layer "F.SilkS")
		)
		(fp_line
			(start 0.7874 0.4064)
			(end -0.7874 0.4064)
			(stroke
				(width 0.1524)
				(type default)
			)
			(layer "F.SilkS")
		)
		(fp_line
			(start -0.67945 -0.305054)
			(end -0.12065 -0.305054)
			(stroke
				(width 0.1)
				(type default)
			)
			(layer "F.Fab")
		)
		(fp_line
			(start -0.67945 0.3048)
			(end -0.67945 -0.305054)
			(stroke
				(width 0.1)
				(type default)
			)
			(layer "F.Fab")
		)
		(fp_line
			(start -0.12065 -0.305054)
			(end -0.12065 -0.2794)
			(stroke
				(width 0.1)
				(type default)
			)
			(layer "F.Fab")
		)
		(fp_line
			(start -0.12065 -0.2794)
			(end 0.12065 -0.2794)
			(stroke
				(width 0.1)
				(type default)
			)
			(layer "F.Fab")
		)
		(fp_line
			(start -0.12065 0.2794)
			(end -0.12065 0.3048)
			(stroke
				(width 0.1)
				(type default)
			)
			(layer "F.Fab")
		)
		(fp_line
			(start -0.12065 0.3048)
			(end -0.67945 0.3048)
			(stroke
				(width 0.1)
				(type default)
			)
			(layer "F.Fab")
		)
		(fp_line
			(start 0.120396 0.2794)
			(end -0.12065 0.2794)
			(stroke
				(width 0.1)
				(type default)
			)
			(layer "F.Fab")
		)
		(fp_line
			(start 0.120396 0.3048)
			(end 0.120396 0.2794)
			(stroke
				(width 0.1)
				(type default)
			)
			(layer "F.Fab")
		)
		(fp_line
			(start 0.12065 -0.3048)
			(end 0.67945 -0.3048)
			(stroke
				(width 0.1)
				(type default)
			)
			(layer "F.Fab")
		)
		(fp_line
			(start 0.12065 -0.2794)
			(end 0.12065 -0.3048)
			(stroke
				(width 0.1)
				(type default)
			)
			(layer "F.Fab")
		)
		(fp_line
			(start 0.67945 -0.3048)
			(end 0.67945 0.3048)
			(stroke
				(width 0.1)
				(type default)
			)
			(layer "F.Fab")
		)
		(fp_line
			(start 0.67945 0.3048)
			(end 0.120396 0.3048)
			(stroke
				(width 0.1)
				(type default)
			)
			(layer "F.Fab")
		)
		(pad "1" smd circle
			(at -0.40005 0)
			(size 0 0)
			(layers "F.Cu" "F.Mask" "F.Paste")
			(net "U273_3_ADD0")
		)
		(pad "2" smd circle
			(at 0.40005 0)
			(size 0 0)
			(layers "F.Cu" "F.Mask" "F.Paste")
			(net "GND")
		)
	)
	(footprint ""
		(layer "F.Cu")
		(at 314.567316 -113.60277)
		(property "Reference" "C1"
			(at 0 0 0)
			(layer "F.SilkS")
			(hide yes)
			(effects
				(font
					(size 1.27 1.27)
				)
			)
		)
		(property "Value" ""
			(at 0 0 0)
			(layer "F.Fab")
			(effects
				(font
					(size 1.27 1.27)
				)
			)
		)
		(duplicate_pad_numbers_are_jumpers no)
		(fp_line
			(start -0.7874 -0.4064)
			(end 0.7874 -0.4064)
			(stroke
				(width 0.1524)
				(type default)
			)
			(layer "F.SilkS")
		)
		(fp_line
			(start -0.7874 0.4064)
			(end -0.7874 -0.4064)
			(stroke
				(width 0.1524)
				(type default)
			)
			(layer "F.SilkS")
		)
		(fp_line
			(start 0.7874 -0.4064)
			(end 0.7874 0.4064)
			(stroke
				(width 0.1524)
				(type default)
			)
			(layer "F.SilkS")
		)
		(fp_line
			(start 0.7874 0.4064)
			(end -0.7874 0.4064)
			(stroke
				(width 0.1524)
				(type default)
			)
			(layer "F.SilkS")
		)
		(fp_line
			(start -0.67945 -0.305054)
			(end -0.12065 -0.305054)
			(stroke
				(width 0.1)
				(type default)
			)
			(layer "F.Fab")
		)
		(fp_line
			(start -0.67945 0.3048)
			(end -0.67945 -0.305054)
			(stroke
				(width 0.1)
				(type default)
			)
			(layer "F.Fab")
		)
		(fp_line
			(start -0.12065 -0.305054)
			(end -0.12065 -0.2794)
			(stroke
				(width 0.1)
				(type default)
			)
			(layer "F.Fab")
		)
		(fp_line
			(start -0.12065 -0.2794)
			(end 0.12065 -0.2794)
			(stroke
				(width 0.1)
				(type default)
			)
			(layer "F.Fab")
		)
		(fp_line
			(start -0.12065 0.2794)
			(end -0.12065 0.3048)
			(stroke
				(width 0.1)
				(type default)
			)
			(layer "F.Fab")
		)
		(fp_line
			(start -0.12065 0.3048)
			(end -0.67945 0.3048)
			(stroke
				(width 0.1)
				(type default)
			)
			(layer "F.Fab")
		)
		(fp_line
			(start 0.120396 0.2794)
			(end -0.12065 0.2794)
			(stroke
				(width 0.1)
				(type default)
			)
			(layer "F.Fab")
		)
		(fp_line
			(start 0.120396 0.3048)
			(end 0.120396 0.2794)
			(stroke
				(width 0.1)
				(type default)
			)
			(layer "F.Fab")
		)
		(fp_line
			(start 0.12065 -0.3048)
			(end 0.67945 -0.3048)
			(stroke
				(width 0.1)
				(type default)
			)
			(layer "F.Fab")
		)
		(fp_line
			(start 0.12065 -0.2794)
			(end 0.12065 -0.3048)
			(stroke
				(width 0.1)
				(type default)
			)
			(layer "F.Fab")
		)
		(fp_line
			(start 0.67945 -0.3048)
			(end 0.67945 0.3048)
			(stroke
				(width 0.1)
				(type default)
			)
			(layer "F.Fab")
		)
		(fp_line
			(start 0.67945 0.3048)
			(end 0.120396 0.3048)
			(stroke
				(width 0.1)
				(type default)
			)
			(layer "F.Fab")
		)
		(pad "1" smd circle
			(at -0.40005 0)
			(size 0 0)
			(layers "F.Cu" "F.Mask" "F.Paste")
			(net "P3V3_AUX")
		)
		(pad "2" smd circle
			(at 0.40005 0)
			(size 0 0)
			(layers "F.Cu" "F.Mask" "F.Paste")
			(net "GND")
		)
	)
	(footprint ""
		(layer "F.Cu")
		(at 69.741034 -376.067828)
		(property "Reference" "C809"
			(at 0 0 0)
			(layer "F.SilkS")
			(hide yes)
			(effects
				(font
					(size 1.27 1.27)
				)
			)
		)
		(property "Value" ""
			(at 0 0 0)
			(layer "F.Fab")
			(effects
				(font
					(size 1.27 1.27)
				)
			)
		)
		(duplicate_pad_numbers_are_jumpers no)
		(fp_line
			(start -0.299974 -0.150114)
			(end 0.299974 -0.150114)
			(stroke
				(width 0.1)
				(type default)
			)
			(layer "F.Fab")
		)
		(fp_line
			(start -0.299974 0.150114)
			(end -0.299974 -0.150114)
			(stroke
				(width 0.1)
				(type default)
			)
			(layer "F.Fab")
		)
		(fp_line
			(start 0.299974 -0.150114)
			(end 0.299974 0.150114)
			(stroke
				(width 0.1)
				(type default)
			)
			(layer "F.Fab")
		)
		(fp_line
			(start 0.299974 0.150114)
			(end -0.299974 0.150114)
			(stroke
				(width 0.1)
				(type default)
			)
			(layer "F.Fab")
		)
		(pad "1" smd rect
			(at -0.2667 0)
			(size 0.3048 0.381)
			(layers "F.Cu" "F.Mask" "F.Paste")
			(net "P5E_CPU1_P0_TX_C_DP<14>")
		)
		(pad "2" smd rect
			(at 0.2667 0)
			(size 0.3048 0.381)
			(layers "F.Cu" "F.Mask" "F.Paste")
			(net "P5E_CPU1_P0_TX_DP<14>")
		)
	)
	(footprint ""
		(layer "F.Cu")
		(at 317.709296 -383.88163 -90)
		(property "Reference" "C913"
			(at 0 0 270)
			(layer "F.SilkS")
			(hide yes)
			(effects
				(font
					(size 1.27 1.27)
				)
			)
		)
		(property "Value" ""
			(at 0 0 270)
			(layer "F.Fab")
			(effects
				(font
					(size 1.27 1.27)
				)
			)
		)
		(duplicate_pad_numbers_are_jumpers no)
		(fp_line
			(start -0.299974 0.150114)
			(end -0.299974 -0.150114)
			(stroke
				(width 0.1)
				(type default)
			)
			(layer "F.Fab")
		)
		(fp_line
			(start 0.299974 0.150114)
			(end -0.299974 0.150114)
			(stroke
				(width 0.1)
				(type default)
			)
			(layer "F.Fab")
		)
		(fp_line
			(start -0.299974 -0.150114)
			(end 0.299974 -0.150114)
			(stroke
				(width 0.1)
				(type default)
			)
			(layer "F.Fab")
		)
		(fp_line
			(start 0.299974 -0.150114)
			(end 0.299974 0.150114)
			(stroke
				(width 0.1)
				(type default)
			)
			(layer "F.Fab")
		)
		(pad "1" smd rect
			(at -0.2667 0 270)
			(size 0.3048 0.381)
			(layers "F.Cu" "F.Mask" "F.Paste")
			(net "P5E_CPU0_P0_TX_C_DP<10>")
		)
		(pad "2" smd rect
			(at 0.2667 0 270)
			(size 0.3048 0.381)
			(layers "F.Cu" "F.Mask" "F.Paste")
			(net "P5E_CPU0_P0_TX_DP<10>")
		)
	)
	(footprint ""
		(layer "F.Cu")
		(at 330.365354 -133.964172 180)
		(property "Reference" "PC6001"
			(at 0 0 180)
			(layer "F.SilkS")
			(hide yes)
			(effects
				(font
					(size 1.27 1.27)
				)
			)
		)
		(property "Value" ""
			(at 0 0 180)
			(layer "F.Fab")
			(effects
				(font
					(size 1.27 1.27)
				)
			)
		)
		(duplicate_pad_numbers_are_jumpers no)
		(fp_line
			(start 0.7874 0.4064)
			(end -0.7874 0.4064)
			(stroke
				(width 0.1524)
				(type default)
			)
			(layer "F.SilkS")
		)
		(fp_line
			(start 0.7874 -0.4064)
			(end 0.7874 0.4064)
			(stroke
				(width 0.1524)
				(type default)
			)
			(layer "F.SilkS")
		)
		(fp_line
			(start -0.7874 0.4064)
			(end -0.7874 -0.4064)
			(stroke
				(width 0.1524)
				(type default)
			)
			(layer "F.SilkS")
		)
		(fp_line
			(start -0.7874 -0.4064)
			(end 0.7874 -0.4064)
			(stroke
				(width 0.1524)
				(type default)
			)
			(layer "F.SilkS")
		)
		(fp_line
			(start 0.67945 0.3048)
			(end 0.120396 0.3048)
			(stroke
				(width 0.1)
				(type default)
			)
			(layer "F.Fab")
		)
		(fp_line
			(start 0.67945 -0.3048)
			(end 0.67945 0.3048)
			(stroke
				(width 0.1)
				(type default)
			)
			(layer "F.Fab")
		)
		(fp_line
			(start 0.12065 -0.2794)
			(end 0.12065 -0.3048)
			(stroke
				(width 0.1)
				(type default)
			)
			(layer "F.Fab")
		)
		(fp_line
			(start 0.12065 -0.3048)
			(end 0.67945 -0.3048)
			(stroke
				(width 0.1)
				(type default)
			)
			(layer "F.Fab")
		)
		(fp_line
			(start 0.120396 0.3048)
			(end 0.120396 0.2794)
			(stroke
				(width 0.1)
				(type default)
			)
			(layer "F.Fab")
		)
		(fp_line
			(start 0.120396 0.2794)
			(end -0.12065 0.2794)
			(stroke
				(width 0.1)
				(type default)
			)
			(layer "F.Fab")
		)
		(fp_line
			(start -0.12065 0.3048)
			(end -0.67945 0.3048)
			(stroke
				(width 0.1)
				(type default)
			)
			(layer "F.Fab")
		)
		(fp_line
			(start -0.12065 0.2794)
			(end -0.12065 0.3048)
			(stroke
				(width 0.1)
				(type default)
			)
			(layer "F.Fab")
		)
		(fp_line
			(start -0.12065 -0.2794)
			(end 0.12065 -0.2794)
			(stroke
				(width 0.1)
				(type default)
			)
			(layer "F.Fab")
		)
		(fp_line
			(start -0.12065 -0.305054)
			(end -0.12065 -0.2794)
			(stroke
				(width 0.1)
				(type default)
			)
			(layer "F.Fab")
		)
		(fp_line
			(start -0.67945 0.3048)
			(end -0.67945 -0.305054)
			(stroke
				(width 0.1)
				(type default)
			)
			(layer "F.Fab")
		)
		(fp_line
			(start -0.67945 -0.305054)
			(end -0.12065 -0.305054)
			(stroke
				(width 0.1)
				(type default)
			)
			(layer "F.Fab")
		)
		(pad "1" smd circle
			(at -0.40005 0 180)
			(size 0 0)
			(layers "F.Cu" "F.Mask" "F.Paste")
			(net "P12V_AUX")
		)
		(pad "2" smd circle
			(at 0.40005 0 180)
			(size 0 0)
			(layers "F.Cu" "F.Mask" "F.Paste")
			(net "GND")
		)
	)
	(footprint ""
		(layer "F.Cu")
		(at 100.48367 -408.183588 180)
		(property "Reference" "C90"
			(at 0 0 180)
			(layer "F.SilkS")
			(hide yes)
			(effects
				(font
					(size 1.27 1.27)
				)
			)
		)
		(property "Value" ""
			(at 0 0 180)
			(layer "F.Fab")
			(effects
				(font
					(size 1.27 1.27)
				)
			)
		)
		(duplicate_pad_numbers_are_jumpers no)
		(fp_line
			(start 0.7874 0.4064)
			(end -0.7874 0.4064)
			(stroke
				(width 0.1524)
				(type default)
			)
			(layer "F.SilkS")
		)
		(fp_line
			(start 0.7874 -0.4064)
			(end 0.7874 0.4064)
			(stroke
				(width 0.1524)
				(type default)
			)
			(layer "F.SilkS")
		)
		(fp_line
			(start -0.7874 0.4064)
			(end -0.7874 -0.4064)
			(stroke
				(width 0.1524)
				(type default)
			)
			(layer "F.SilkS")
		)
		(fp_line
			(start -0.7874 -0.4064)
			(end 0.7874 -0.4064)
			(stroke
				(width 0.1524)
				(type default)
			)
			(layer "F.SilkS")
		)
		(fp_line
			(start 0.67945 0.3048)
			(end 0.120396 0.3048)
			(stroke
				(width 0.1)
				(type default)
			)
			(layer "F.Fab")
		)
		(fp_line
			(start 0.67945 -0.3048)
			(end 0.67945 0.3048)
			(stroke
				(width 0.1)
				(type default)
			)
			(layer "F.Fab")
		)
		(fp_line
			(start 0.12065 -0.2794)
			(end 0.12065 -0.3048)
			(stroke
				(width 0.1)
				(type default)
			)
			(layer "F.Fab")
		)
		(fp_line
			(start 0.12065 -0.3048)
			(end 0.67945 -0.3048)
			(stroke
				(width 0.1)
				(type default)
			)
			(layer "F.Fab")
		)
		(fp_line
			(start 0.120396 0.3048)
			(end 0.120396 0.2794)
			(stroke
				(width 0.1)
				(type default)
			)
			(layer "F.Fab")
		)
		(fp_line
			(start 0.120396 0.2794)
			(end -0.12065 0.2794)
			(stroke
				(width 0.1)
				(type default)
			)
			(layer "F.Fab")
		)
		(fp_line
			(start -0.12065 0.3048)
			(end -0.67945 0.3048)
			(stroke
				(width 0.1)
				(type default)
			)
			(layer "F.Fab")
		)
		(fp_line
			(start -0.12065 0.2794)
			(end -0.12065 0.3048)
			(stroke
				(width 0.1)
				(type default)
			)
			(layer "F.Fab")
		)
		(fp_line
			(start -0.12065 -0.2794)
			(end 0.12065 -0.2794)
			(stroke
				(width 0.1)
				(type default)
			)
			(layer "F.Fab")
		)
		(fp_line
			(start -0.12065 -0.305054)
			(end -0.12065 -0.2794)
			(stroke
				(width 0.1)
				(type default)
			)
			(layer "F.Fab")
		)
		(fp_line
			(start -0.67945 0.3048)
			(end -0.67945 -0.305054)
			(stroke
				(width 0.1)
				(type default)
			)
			(layer "F.Fab")
		)
		(fp_line
			(start -0.67945 -0.305054)
			(end -0.12065 -0.305054)
			(stroke
				(width 0.1)
				(type default)
			)
			(layer "F.Fab")
		)
		(pad "1" smd circle
			(at -0.40005 0 180)
			(size 0 0)
			(layers "F.Cu" "F.Mask" "F.Paste")
			(net "P3V3_9ZXL045_P1_VDD")
		)
		(pad "2" smd circle
			(at 0.40005 0 180)
			(size 0 0)
			(layers "F.Cu" "F.Mask" "F.Paste")
			(net "GND")
		)
	)
	(footprint ""
		(layer "F.Cu")
		(at 24.765 -358.775)
		(property "Reference" "R8238"
			(at 0 0 0)
			(layer "F.SilkS")
			(hide yes)
			(effects
				(font
					(size 1.27 1.27)
				)
			)
		)
		(property "Value" ""
			(at 0 0 0)
			(layer "F.Fab")
			(effects
				(font
					(size 1.27 1.27)
				)
			)
		)
		(duplicate_pad_numbers_are_jumpers no)
		(fp_line
			(start -0.7874 -0.4064)
			(end 0.7874 -0.4064)
			(stroke
				(width 0.1524)
				(type default)
			)
			(layer "F.SilkS")
		)
		(fp_line
			(start -0.7874 0.4064)
			(end -0.7874 -0.4064)
			(stroke
				(width 0.1524)
				(type default)
			)
			(layer "F.SilkS")
		)
		(fp_line
			(start 0.7874 -0.4064)
			(end 0.7874 0.4064)
			(stroke
				(width 0.1524)
				(type default)
			)
			(layer "F.SilkS")
		)
		(fp_line
			(start 0.7874 0.4064)
			(end -0.7874 0.4064)
			(stroke
				(width 0.1524)
				(type default)
			)
			(layer "F.SilkS")
		)
		(fp_line
			(start -0.67945 -0.305054)
			(end -0.12065 -0.305054)
			(stroke
				(width 0.1)
				(type default)
			)
			(layer "F.Fab")
		)
		(fp_line
			(start -0.67945 0.3048)
			(end -0.67945 -0.305054)
			(stroke
				(width 0.1)
				(type default)
			)
			(layer "F.Fab")
		)
		(fp_line
			(start -0.12065 -0.305054)
			(end -0.12065 -0.2794)
			(stroke
				(width 0.1)
				(type default)
			)
			(layer "F.Fab")
		)
		(fp_line
			(start -0.12065 -0.2794)
			(end 0.12065 -0.2794)
			(stroke
				(width 0.1)
				(type default)
			)
			(layer "F.Fab")
		)
		(fp_line
			(start -0.12065 0.2794)
			(end -0.12065 0.3048)
			(stroke
				(width 0.1)
				(type default)
			)
			(layer "F.Fab")
		)
		(fp_line
			(start -0.12065 0.3048)
			(end -0.67945 0.3048)
			(stroke
				(width 0.1)
				(type default)
			)
			(layer "F.Fab")
		)
		(fp_line
			(start 0.120396 0.2794)
			(end -0.12065 0.2794)
			(stroke
				(width 0.1)
				(type default)
			)
			(layer "F.Fab")
		)
		(fp_line
			(start 0.120396 0.3048)
			(end 0.120396 0.2794)
			(stroke
				(width 0.1)
				(type default)
			)
			(layer "F.Fab")
		)
		(fp_line
			(start 0.12065 -0.3048)
			(end 0.67945 -0.3048)
			(stroke
				(width 0.1)
				(type default)
			)
			(layer "F.Fab")
		)
		(fp_line
			(start 0.12065 -0.2794)
			(end 0.12065 -0.3048)
			(stroke
				(width 0.1)
				(type default)
			)
			(layer "F.Fab")
		)
		(fp_line
			(start 0.67945 -0.3048)
			(end 0.67945 0.3048)
			(stroke
				(width 0.1)
				(type default)
			)
			(layer "F.Fab")
		)
		(fp_line
			(start 0.67945 0.3048)
			(end 0.120396 0.3048)
			(stroke
				(width 0.1)
				(type default)
			)
			(layer "F.Fab")
		)
		(pad "1" smd circle
			(at -0.40005 0)
			(size 0 0)
			(layers "F.Cu" "F.Mask" "F.Paste")
			(net "SVID_PVDDCR_CPU1_P1_SVTO")
		)
		(pad "2" smd circle
			(at 0.40005 0)
			(size 0 0)
			(layers "F.Cu" "F.Mask" "F.Paste")
			(net "SVID_PVDDCR_CPU1_P1_SVTO_R")
		)
	)
	(footprint ""
		(layer "F.Cu")
		(at 90.654124 -408.517344 -90)
		(property "Reference" "C6658"
			(at 0 0 270)
			(layer "F.SilkS")
			(hide yes)
			(effects
				(font
					(size 1.27 1.27)
				)
			)
		)
		(property "Value" ""
			(at 0 0 270)
			(layer "F.Fab")
			(effects
				(font
					(size 1.27 1.27)
				)
			)
		)
		(duplicate_pad_numbers_are_jumpers no)
		(fp_line
			(start -0.299974 0.150114)
			(end -0.299974 -0.150114)
			(stroke
				(width 0.1)
				(type default)
			)
			(layer "F.Fab")
		)
		(fp_line
			(start 0.299974 0.150114)
			(end -0.299974 0.150114)
			(stroke
				(width 0.1)
				(type default)
			)
			(layer "F.Fab")
		)
		(fp_line
			(start -0.299974 -0.150114)
			(end 0.299974 -0.150114)
			(stroke
				(width 0.1)
				(type default)
			)
			(layer "F.Fab")
		)
		(fp_line
			(start 0.299974 -0.150114)
			(end 0.299974 0.150114)
			(stroke
				(width 0.1)
				(type default)
			)
			(layer "F.Fab")
		)
		(pad "1" smd rect
			(at -0.2667 0 270)
			(size 0.3048 0.381)
			(layers "F.Cu" "F.Mask" "F.Paste")
			(net "P5E_CPU1_P0_TX_BUF_C_DN<14>")
		)
		(pad "2" smd rect
			(at 0.2667 0 270)
			(size 0.3048 0.381)
			(layers "F.Cu" "F.Mask" "F.Paste")
			(net "P5E_CPU1_P0_TX_BUF_DN<14>")
		)
	)
	(footprint ""
		(layer "F.Cu")
		(at 100.332286 -402.917406 -90)
		(property "Reference" "R1201"
			(at 0 0 270)
			(layer "F.SilkS")
			(hide yes)
			(effects
				(font
					(size 1.27 1.27)
				)
			)
		)
		(property "Value" ""
			(at 0 0 270)
			(layer "F.Fab")
			(effects
				(font
					(size 1.27 1.27)
				)
			)
		)
		(duplicate_pad_numbers_are_jumpers no)
		(fp_line
			(start -0.32512 0.175006)
			(end -0.32512 -0.175006)
			(stroke
				(width 0.1)
				(type default)
			)
			(layer "F.Fab")
		)
		(fp_line
			(start 0.32512 0.175006)
			(end -0.32512 0.175006)
			(stroke
				(width 0.1)
				(type default)
			)
			(layer "F.Fab")
		)
		(fp_line
			(start -0.32512 -0.175006)
			(end 0.32512 -0.175006)
			(stroke
				(width 0.1)
				(type default)
			)
			(layer "F.Fab")
		)
		(fp_line
			(start 0.32512 -0.175006)
			(end 0.32512 0.175006)
			(stroke
				(width 0.1)
				(type default)
			)
			(layer "F.Fab")
		)
		(pad "1" smd rect
			(at -0.2667 0 270)
			(size 0.3048 0.381)
			(layers "F.Cu" "F.Mask" "F.Paste")
			(net "RST_SMB_RT_ROM_R1_N")
		)
		(pad "2" smd rect
			(at 0.2667 0 90)
			(size 0.3048 0.381)
			(layers "F.Cu" "F.Mask" "F.Paste")
			(net "FM_SMB_RT_ROM_MUX1_SEL")
		)
	)
	(footprint ""
		(layer "F.Cu")
		(at 213.061804 -22.974554 180)
		(property "Reference" "R1140"
			(at 0 0 180)
			(layer "F.SilkS")
			(hide yes)
			(effects
				(font
					(size 1.27 1.27)
				)
			)
		)
		(property "Value" ""
			(at 0 0 180)
			(layer "F.Fab")
			(effects
				(font
					(size 1.27 1.27)
				)
			)
		)
		(duplicate_pad_numbers_are_jumpers no)
		(fp_line
			(start 0.7874 0.4064)
			(end -0.7874 0.4064)
			(stroke
				(width 0.1524)
				(type default)
			)
			(layer "F.SilkS")
		)
		(fp_line
			(start 0.7874 -0.4064)
			(end 0.7874 0.4064)
			(stroke
				(width 0.1524)
				(type default)
			)
			(layer "F.SilkS")
		)
		(fp_line
			(start -0.7874 0.4064)
			(end -0.7874 -0.4064)
			(stroke
				(width 0.1524)
				(type default)
			)
			(layer "F.SilkS")
		)
		(fp_line
			(start -0.7874 -0.4064)
			(end 0.7874 -0.4064)
			(stroke
				(width 0.1524)
				(type default)
			)
			(layer "F.SilkS")
		)
		(fp_line
			(start 0.67945 0.3048)
			(end 0.120396 0.3048)
			(stroke
				(width 0.1)
				(type default)
			)
			(layer "F.Fab")
		)
		(fp_line
			(start 0.67945 -0.3048)
			(end 0.67945 0.3048)
			(stroke
				(width 0.1)
				(type default)
			)
			(layer "F.Fab")
		)
		(fp_line
			(start 0.12065 -0.2794)
			(end 0.12065 -0.3048)
			(stroke
				(width 0.1)
				(type default)
			)
			(layer "F.Fab")
		)
		(fp_line
			(start 0.12065 -0.3048)
			(end 0.67945 -0.3048)
			(stroke
				(width 0.1)
				(type default)
			)
			(layer "F.Fab")
		)
		(fp_line
			(start 0.120396 0.3048)
			(end 0.120396 0.2794)
			(stroke
				(width 0.1)
				(type default)
			)
			(layer "F.Fab")
		)
		(fp_line
			(start 0.120396 0.2794)
			(end -0.12065 0.2794)
			(stroke
				(width 0.1)
				(type default)
			)
			(layer "F.Fab")
		)
		(fp_line
			(start -0.12065 0.3048)
			(end -0.67945 0.3048)
			(stroke
				(width 0.1)
				(type default)
			)
			(layer "F.Fab")
		)
		(fp_line
			(start -0.12065 0.2794)
			(end -0.12065 0.3048)
			(stroke
				(width 0.1)
				(type default)
			)
			(layer "F.Fab")
		)
		(fp_line
			(start -0.12065 -0.2794)
			(end 0.12065 -0.2794)
			(stroke
				(width 0.1)
				(type default)
			)
			(layer "F.Fab")
		)
		(fp_line
			(start -0.12065 -0.305054)
			(end -0.12065 -0.2794)
			(stroke
				(width 0.1)
				(type default)
			)
			(layer "F.Fab")
		)
		(fp_line
			(start -0.67945 0.3048)
			(end -0.67945 -0.305054)
			(stroke
				(width 0.1)
				(type default)
			)
			(layer "F.Fab")
		)
		(fp_line
			(start -0.67945 -0.305054)
			(end -0.12065 -0.305054)
			(stroke
				(width 0.1)
				(type default)
			)
			(layer "F.Fab")
		)
		(pad "1" smd circle
			(at -0.40005 0 180)
			(size 0 0)
			(layers "F.Cu" "F.Mask" "F.Paste")
			(net "CLK_50M_BMC_MAC_R")
		)
		(pad "2" smd circle
			(at 0.40005 0 180)
			(size 0 0)
			(layers "F.Cu" "F.Mask" "F.Paste")
			(net "CLK_50M_RMII_BMC_OCP")
		)
	)
	(footprint ""
		(layer "F.Cu")
		(at 152.316434 -110.731046)
		(property "Reference" "U92"
			(at -5.426202 -1.786636 0)
			(unlocked yes)
			(layer "F.SilkS")
			(effects
				(font
					(size 0.7874 0.5842)
					(thickness 0.1524)
				)
				(justify left)
			)
		)
		(property "Value" ""
			(at 0 0 0)
			(layer "F.Fab")
			(effects
				(font
					(size 1.27 1.27)
				)
			)
		)
		(duplicate_pad_numbers_are_jumpers no)
		(fp_line
			(start -2.0574 -1.651)
			(end -0.381 -1.651)
			(stroke
				(width 0.1524)
				(type default)
			)
			(layer "F.SilkS")
		)
		(fp_line
			(start -2.0574 1.651)
			(end -2.0574 -1.651)
			(stroke
				(width 0.1524)
				(type default)
			)
			(layer "F.SilkS")
		)
		(fp_line
			(start -0.381 -1.651)
			(end 0 -1.016)
			(stroke
				(width 0.1524)
				(type default)
			)
			(layer "F.SilkS")
		)
		(fp_line
			(start 0 -1.016)
			(end 0.381 -1.651)
			(stroke
				(width 0.1524)
				(type default)
			)
			(layer "F.SilkS")
		)
		(fp_line
			(start 0.381 -1.651)
			(end 2.0574 -1.651)
			(stroke
				(width 0.1524)
				(type default)
			)
			(layer "F.SilkS")
		)
		(fp_line
			(start 2.0574 -1.651)
			(end 2.0574 1.651)
			(stroke
				(width 0.1524)
				(type default)
			)
			(layer "F.SilkS")
		)
		(fp_line
			(start 2.0574 1.651)
			(end -2.0574 1.651)
			(stroke
				(width 0.1524)
				(type default)
			)
			(layer "F.SilkS")
		)
		(fp_poly
			(pts
				(xy -2.159 -1.016) (xy -2.71272 -0.719328) (xy -2.71272 -1.344168)
			)
			(stroke
				(width 0)
				(type default)
			)
			(fill yes)
			(layer "F.SilkS")
		)
		(fp_line
			(start -1.599946 -1.199896)
			(end -0.899922 -1.199896)
			(stroke
				(width 0.1)
				(type default)
			)
			(layer "F.Fab")
		)
		(fp_line
			(start -1.599946 1.199896)
			(end -1.599946 -1.199896)
			(stroke
				(width 0.1)
				(type default)
			)
			(layer "F.Fab")
		)
		(fp_line
			(start -0.899922 -1.549908)
			(end 0.899922 -1.549908)
			(stroke
				(width 0.1)
				(type default)
			)
			(layer "F.Fab")
		)
		(fp_line
			(start -0.899922 -1.199896)
			(end -0.899922 -1.549908)
			(stroke
				(width 0.1)
				(type default)
			)
			(layer "F.Fab")
		)
		(fp_line
			(start -0.899922 1.199896)
			(end -1.599946 1.199896)
			(stroke
				(width 0.1)
				(type default)
			)
			(layer "F.Fab")
		)
		(fp_line
			(start -0.899922 1.549908)
			(end -0.899922 1.199896)
			(stroke
				(width 0.1)
				(type default)
			)
			(layer "F.Fab")
		)
		(fp_line
			(start 0.899922 -1.549908)
			(end 0.899922 -1.199896)
			(stroke
				(width 0.1)
				(type default)
			)
			(layer "F.Fab")
		)
		(fp_line
			(start 0.899922 -1.199896)
			(end 1.599946 -1.199896)
			(stroke
				(width 0.1)
				(type default)
			)
			(layer "F.Fab")
		)
		(fp_line
			(start 0.899922 1.199896)
			(end 0.899922 1.549908)
			(stroke
				(width 0.1)
				(type default)
			)
			(layer "F.Fab")
		)
		(fp_line
			(start 0.899922 1.549908)
			(end -0.899922 1.549908)
			(stroke
				(width 0.1)
				(type default)
			)
			(layer "F.Fab")
		)
		(fp_line
			(start 1.599946 -1.199896)
			(end 1.599946 1.199896)
			(stroke
				(width 0.1)
				(type default)
			)
			(layer "F.Fab")
		)
		(fp_line
			(start 1.599946 1.199896)
			(end 0.899922 1.199896)
			(stroke
				(width 0.1)
				(type default)
			)
			(layer "F.Fab")
		)
		(fp_poly
			(pts
				(xy -2.71272 -0.719328) (xy -2.71272 -1.344168) (xy -2.159 -1.016)
			)
			(stroke
				(width 0)
				(type default)
			)
			(fill yes)
			(layer "F.Fab")
		)
		(pad "1" smd rect
			(at -1.225042 -0.94996 270)
			(size 0.5588 1.3462)
			(layers "F.Cu" "F.Mask" "F.Paste")
			(net "Net_10730")
		)
		(pad "2" smd rect
			(at -1.225042 0 270)
			(size 0.5588 1.3462)
			(layers "F.Cu" "F.Mask" "F.Paste")
			(net "SCM_IRQ_1V8_N")
		)
		(pad "3" smd rect
			(at -1.225042 0.94996 270)
			(size 0.5588 1.3462)
			(layers "F.Cu" "F.Mask" "F.Paste")
			(net "GND")
		)
		(pad "4" smd rect
			(at 1.225042 0.94996 270)
			(size 0.5588 1.3462)
			(layers "F.Cu" "F.Mask" "F.Paste")
			(net "SCM_IRQ_R_N")
		)
		(pad "5" smd rect
			(at 1.225042 -0.94996 270)
			(size 0.5588 1.3462)
			(layers "F.Cu" "F.Mask" "F.Paste")
			(net "P1V8_AUX")
		)
	)
	(footprint ""
		(layer "F.Cu")
		(at 97.640902 -370.57203 -90)
		(property "Reference" "C717"
			(at 0 0 270)
			(layer "F.SilkS")
			(hide yes)
			(effects
				(font
					(size 1.27 1.27)
				)
			)
		)
		(property "Value" ""
			(at 0 0 270)
			(layer "F.Fab")
			(effects
				(font
					(size 1.27 1.27)
				)
			)
		)
		(duplicate_pad_numbers_are_jumpers no)
		(fp_line
			(start -0.299974 0.150114)
			(end -0.299974 -0.150114)
			(stroke
				(width 0.1)
				(type default)
			)
			(layer "F.Fab")
		)
		(fp_line
			(start 0.299974 0.150114)
			(end -0.299974 0.150114)
			(stroke
				(width 0.1)
				(type default)
			)
			(layer "F.Fab")
		)
		(fp_line
			(start -0.299974 -0.150114)
			(end 0.299974 -0.150114)
			(stroke
				(width 0.1)
				(type default)
			)
			(layer "F.Fab")
		)
		(fp_line
			(start 0.299974 -0.150114)
			(end 0.299974 0.150114)
			(stroke
				(width 0.1)
				(type default)
			)
			(layer "F.Fab")
		)
		(pad "1" smd rect
			(at -0.2667 0 270)
			(size 0.3048 0.381)
			(layers "F.Cu" "F.Mask" "F.Paste")
			(net "P5E_CPU1_P1_TX_C_DP<12>")
		)
		(pad "2" smd rect
			(at 0.2667 0 270)
			(size 0.3048 0.381)
			(layers "F.Cu" "F.Mask" "F.Paste")
			(net "P5E_CPU1_P1_TX_DP<12>")
		)
	)
	(footprint ""
		(layer "F.Cu")
		(at 76.250546 -394.903452 90)
		(property "Reference" "R732"
			(at 0 0 90)
			(layer "F.SilkS")
			(hide yes)
			(effects
				(font
					(size 1.27 1.27)
				)
			)
		)
		(property "Value" ""
			(at 0 0 90)
			(layer "F.Fab")
			(effects
				(font
					(size 1.27 1.27)
				)
			)
		)
		(duplicate_pad_numbers_are_jumpers no)
		(fp_line
			(start 0.32512 -0.175006)
			(end 0.32512 0.175006)
			(stroke
				(width 0.1)
				(type default)
			)
			(layer "F.Fab")
		)
		(fp_line
			(start -0.32512 -0.175006)
			(end 0.32512 -0.175006)
			(stroke
				(width 0.1)
				(type default)
			)
			(layer "F.Fab")
		)
		(fp_line
			(start 0.32512 0.175006)
			(end -0.32512 0.175006)
			(stroke
				(width 0.1)
				(type default)
			)
			(layer "F.Fab")
		)
		(fp_line
			(start -0.32512 0.175006)
			(end -0.32512 -0.175006)
			(stroke
				(width 0.1)
				(type default)
			)
			(layer "F.Fab")
		)
		(pad "1" smd rect
			(at -0.2667 0 90)
			(size 0.3048 0.381)
			(layers "F.Cu" "F.Mask" "F.Paste")
			(net "RST_RT_CPU1_P1_RESET_N")
		)
		(pad "2" smd rect
			(at 0.2667 0 270)
			(size 0.3048 0.381)
			(layers "F.Cu" "F.Mask" "F.Paste")
			(net "RST_RT_CPU1_P1_RESET_R_N")
		)
	)
	(footprint ""
		(layer "F.Cu")
		(at 442.340238 -364.49127)
		(property "Reference" "PC6003"
			(at 0 0 0)
			(layer "F.SilkS")
			(hide yes)
			(effects
				(font
					(size 1.27 1.27)
				)
			)
		)
		(property "Value" ""
			(at 0 0 0)
			(layer "F.Fab")
			(effects
				(font
					(size 1.27 1.27)
				)
			)
		)
		(duplicate_pad_numbers_are_jumpers no)
		(fp_line
			(start -0.7874 -0.4064)
			(end 0.7874 -0.4064)
			(stroke
				(width 0.1524)
				(type default)
			)
			(layer "F.SilkS")
		)
		(fp_line
			(start -0.7874 0.4064)
			(end -0.7874 -0.4064)
			(stroke
				(width 0.1524)
				(type default)
			)
			(layer "F.SilkS")
		)
		(fp_line
			(start 0.7874 -0.4064)
			(end 0.7874 0.4064)
			(stroke
				(width 0.1524)
				(type default)
			)
			(layer "F.SilkS")
		)
		(fp_line
			(start 0.7874 0.4064)
			(end -0.7874 0.4064)
			(stroke
				(width 0.1524)
				(type default)
			)
			(layer "F.SilkS")
		)
		(fp_line
			(start -0.67945 -0.305054)
			(end -0.12065 -0.305054)
			(stroke
				(width 0.1)
				(type default)
			)
			(layer "F.Fab")
		)
		(fp_line
			(start -0.67945 0.3048)
			(end -0.67945 -0.305054)
			(stroke
				(width 0.1)
				(type default)
			)
			(layer "F.Fab")
		)
		(fp_line
			(start -0.12065 -0.305054)
			(end -0.12065 -0.2794)
			(stroke
				(width 0.1)
				(type default)
			)
			(layer "F.Fab")
		)
		(fp_line
			(start -0.12065 -0.2794)
			(end 0.12065 -0.2794)
			(stroke
				(width 0.1)
				(type default)
			)
			(layer "F.Fab")
		)
		(fp_line
			(start -0.12065 0.2794)
			(end -0.12065 0.3048)
			(stroke
				(width 0.1)
				(type default)
			)
			(layer "F.Fab")
		)
		(fp_line
			(start -0.12065 0.3048)
			(end -0.67945 0.3048)
			(stroke
				(width 0.1)
				(type default)
			)
			(layer "F.Fab")
		)
		(fp_line
			(start 0.120396 0.2794)
			(end -0.12065 0.2794)
			(stroke
				(width 0.1)
				(type default)
			)
			(layer "F.Fab")
		)
		(fp_line
			(start 0.120396 0.3048)
			(end 0.120396 0.2794)
			(stroke
				(width 0.1)
				(type default)
			)
			(layer "F.Fab")
		)
		(fp_line
			(start 0.12065 -0.3048)
			(end 0.67945 -0.3048)
			(stroke
				(width 0.1)
				(type default)
			)
			(layer "F.Fab")
		)
		(fp_line
			(start 0.12065 -0.2794)
			(end 0.12065 -0.3048)
			(stroke
				(width 0.1)
				(type default)
			)
			(layer "F.Fab")
		)
		(fp_line
			(start 0.67945 -0.3048)
			(end 0.67945 0.3048)
			(stroke
				(width 0.1)
				(type default)
			)
			(layer "F.Fab")
		)
		(fp_line
			(start 0.67945 0.3048)
			(end 0.120396 0.3048)
			(stroke
				(width 0.1)
				(type default)
			)
			(layer "F.Fab")
		)
		(pad "1" smd circle
			(at -0.40005 0)
			(size 0 0)
			(layers "F.Cu" "F.Mask" "F.Paste")
			(net "P12V_AUX")
		)
		(pad "2" smd circle
			(at 0.40005 0)
			(size 0 0)
			(layers "F.Cu" "F.Mask" "F.Paste")
			(net "GND")
		)
	)
	(footprint ""
		(layer "F.Cu")
		(at 289.589718 -423.456608 90)
		(property "Reference" "R6802"
			(at 0 0 90)
			(layer "F.SilkS")
			(hide yes)
			(effects
				(font
					(size 1.27 1.27)
				)
			)
		)
		(property "Value" ""
			(at 0 0 90)
			(layer "F.Fab")
			(effects
				(font
					(size 1.27 1.27)
				)
			)
		)
		(duplicate_pad_numbers_are_jumpers no)
		(fp_line
			(start 0.7874 -0.4064)
			(end 0.7874 0.4064)
			(stroke
				(width 0.1524)
				(type default)
			)
			(layer "F.SilkS")
		)
		(fp_line
			(start -0.7874 -0.4064)
			(end 0.7874 -0.4064)
			(stroke
				(width 0.1524)
				(type default)
			)
			(layer "F.SilkS")
		)
		(fp_line
			(start 0.7874 0.4064)
			(end -0.7874 0.4064)
			(stroke
				(width 0.1524)
				(type default)
			)
			(layer "F.SilkS")
		)
		(fp_line
			(start -0.7874 0.4064)
			(end -0.7874 -0.4064)
			(stroke
				(width 0.1524)
				(type default)
			)
			(layer "F.SilkS")
		)
		(fp_line
			(start -0.12065 -0.305054)
			(end -0.12065 -0.2794)
			(stroke
				(width 0.1)
				(type default)
			)
			(layer "F.Fab")
		)
		(fp_line
			(start -0.67945 -0.305054)
			(end -0.12065 -0.305054)
			(stroke
				(width 0.1)
				(type default)
			)
			(layer "F.Fab")
		)
		(fp_line
			(start 0.67945 -0.3048)
			(end 0.67945 0.3048)
			(stroke
				(width 0.1)
				(type default)
			)
			(layer "F.Fab")
		)
		(fp_line
			(start 0.12065 -0.3048)
			(end 0.67945 -0.3048)
			(stroke
				(width 0.1)
				(type default)
			)
			(layer "F.Fab")
		)
		(fp_line
			(start 0.12065 -0.2794)
			(end 0.12065 -0.3048)
			(stroke
				(width 0.1)
				(type default)
			)
			(layer "F.Fab")
		)
		(fp_line
			(start -0.12065 -0.2794)
			(end 0.12065 -0.2794)
			(stroke
				(width 0.1)
				(type default)
			)
			(layer "F.Fab")
		)
		(fp_line
			(start 0.120396 0.2794)
			(end -0.12065 0.2794)
			(stroke
				(width 0.1)
				(type default)
			)
			(layer "F.Fab")
		)
		(fp_line
			(start -0.12065 0.2794)
			(end -0.12065 0.3048)
			(stroke
				(width 0.1)
				(type default)
			)
			(layer "F.Fab")
		)
		(fp_line
			(start 0.67945 0.3048)
			(end 0.120396 0.3048)
			(stroke
				(width 0.1)
				(type default)
			)
			(layer "F.Fab")
		)
		(fp_line
			(start 0.120396 0.3048)
			(end 0.120396 0.2794)
			(stroke
				(width 0.1)
				(type default)
			)
			(layer "F.Fab")
		)
		(fp_line
			(start -0.12065 0.3048)
			(end -0.67945 0.3048)
			(stroke
				(width 0.1)
				(type default)
			)
			(layer "F.Fab")
		)
		(fp_line
			(start -0.67945 0.3048)
			(end -0.67945 -0.305054)
			(stroke
				(width 0.1)
				(type default)
			)
			(layer "F.Fab")
		)
		(pad "1" smd circle
			(at -0.40005 0 90)
			(size 0 0)
			(layers "F.Cu" "F.Mask" "F.Paste")
			(net "FM_9ZXL045_P0_3_OE_N")
		)
		(pad "2" smd circle
			(at 0.40005 0 90)
			(size 0 0)
			(layers "F.Cu" "F.Mask" "F.Paste")
			(net "GND")
		)
	)
	(footprint ""
		(layer "F.Cu")
		(at 105.960164 -259.355336)
		(property "Reference" "C2278"
			(at 0 0 0)
			(layer "F.SilkS")
			(hide yes)
			(effects
				(font
					(size 1.27 1.27)
				)
			)
		)
		(property "Value" ""
			(at 0 0 0)
			(layer "F.Fab")
			(effects
				(font
					(size 1.27 1.27)
				)
			)
		)
		(duplicate_pad_numbers_are_jumpers no)
		(fp_line
			(start -0.7874 -0.4064)
			(end 0.7874 -0.4064)
			(stroke
				(width 0.1524)
				(type default)
			)
			(layer "F.SilkS")
		)
		(fp_line
			(start -0.7874 0.4064)
			(end -0.7874 -0.4064)
			(stroke
				(width 0.1524)
				(type default)
			)
			(layer "F.SilkS")
		)
		(fp_line
			(start 0.7874 -0.4064)
			(end 0.7874 0.4064)
			(stroke
				(width 0.1524)
				(type default)
			)
			(layer "F.SilkS")
		)
		(fp_line
			(start 0.7874 0.4064)
			(end -0.7874 0.4064)
			(stroke
				(width 0.1524)
				(type default)
			)
			(layer "F.SilkS")
		)
		(fp_line
			(start -0.67945 -0.305054)
			(end -0.12065 -0.305054)
			(stroke
				(width 0.1)
				(type default)
			)
			(layer "F.Fab")
		)
		(fp_line
			(start -0.67945 0.3048)
			(end -0.67945 -0.305054)
			(stroke
				(width 0.1)
				(type default)
			)
			(layer "F.Fab")
		)
		(fp_line
			(start -0.12065 -0.305054)
			(end -0.12065 -0.2794)
			(stroke
				(width 0.1)
				(type default)
			)
			(layer "F.Fab")
		)
		(fp_line
			(start -0.12065 -0.2794)
			(end 0.12065 -0.2794)
			(stroke
				(width 0.1)
				(type default)
			)
			(layer "F.Fab")
		)
		(fp_line
			(start -0.12065 0.2794)
			(end -0.12065 0.3048)
			(stroke
				(width 0.1)
				(type default)
			)
			(layer "F.Fab")
		)
		(fp_line
			(start -0.12065 0.3048)
			(end -0.67945 0.3048)
			(stroke
				(width 0.1)
				(type default)
			)
			(layer "F.Fab")
		)
		(fp_line
			(start 0.120396 0.2794)
			(end -0.12065 0.2794)
			(stroke
				(width 0.1)
				(type default)
			)
			(layer "F.Fab")
		)
		(fp_line
			(start 0.120396 0.3048)
			(end 0.120396 0.2794)
			(stroke
				(width 0.1)
				(type default)
			)
			(layer "F.Fab")
		)
		(fp_line
			(start 0.12065 -0.3048)
			(end 0.67945 -0.3048)
			(stroke
				(width 0.1)
				(type default)
			)
			(layer "F.Fab")
		)
		(fp_line
			(start 0.12065 -0.2794)
			(end 0.12065 -0.3048)
			(stroke
				(width 0.1)
				(type default)
			)
			(layer "F.Fab")
		)
		(fp_line
			(start 0.67945 -0.3048)
			(end 0.67945 0.3048)
			(stroke
				(width 0.1)
				(type default)
			)
			(layer "F.Fab")
		)
		(fp_line
			(start 0.67945 0.3048)
			(end 0.120396 0.3048)
			(stroke
				(width 0.1)
				(type default)
			)
			(layer "F.Fab")
		)
		(pad "1" smd circle
			(at -0.40005 0)
			(size 0 0)
			(layers "F.Cu" "F.Mask" "F.Paste")
			(net "PVDDIO_P1")
		)
		(pad "2" smd circle
			(at 0.40005 0)
			(size 0 0)
			(layers "F.Cu" "F.Mask" "F.Paste")
			(net "GND")
		)
	)
	(footprint ""
		(layer "F.Cu")
		(at 62.48273 -40.031162)
		(property "Reference" "Q119"
			(at -1.424432 -2.13614 0)
			(unlocked yes)
			(layer "F.SilkS")
			(effects
				(font
					(size 0.7874 0.5842)
					(thickness 0.1524)
				)
				(justify left)
			)
		)
		(property "Value" ""
			(at 0 0 0)
			(layer "F.Fab")
			(effects
				(font
					(size 1.27 1.27)
				)
			)
		)
		(duplicate_pad_numbers_are_jumpers no)
		(fp_line
			(start -1.332738 -1.100074)
			(end -0.4826 -1.100074)
			(stroke
				(width 0.1524)
				(type default)
			)
			(layer "F.SilkS")
		)
		(fp_line
			(start -1.332738 1.100074)
			(end -1.332738 -1.100074)
			(stroke
				(width 0.1524)
				(type default)
			)
			(layer "F.SilkS")
		)
		(fp_line
			(start -0.4826 -1.100074)
			(end 0 -0.541274)
			(stroke
				(width 0.1524)
				(type default)
			)
			(layer "F.SilkS")
		)
		(fp_line
			(start 0 -0.541274)
			(end 0.4826 -1.100074)
			(stroke
				(width 0.1524)
				(type default)
			)
			(layer "F.SilkS")
		)
		(fp_line
			(start 0.4826 -1.100074)
			(end 1.332738 -1.100074)
			(stroke
				(width 0.1524)
				(type default)
			)
			(layer "F.SilkS")
		)
		(fp_line
			(start 1.332738 -1.100074)
			(end 1.332738 1.100074)
			(stroke
				(width 0.1524)
				(type default)
			)
			(layer "F.SilkS")
		)
		(fp_line
			(start 1.332738 1.100074)
			(end -1.332738 1.100074)
			(stroke
				(width 0.1524)
				(type default)
			)
			(layer "F.SilkS")
		)
		(fp_poly
			(pts
				(xy -1.533144 -0.649986) (xy -2.2352 -0.298958) (xy -2.2352 -1.001014)
			)
			(stroke
				(width 0)
				(type default)
			)
			(fill yes)
			(layer "F.SilkS")
		)
		(fp_line
			(start -0.674878 -1.100074)
			(end 0.674878 -1.100074)
			(stroke
				(width 0.1)
				(type default)
			)
			(layer "F.Fab")
		)
		(fp_line
			(start -0.674878 1.100074)
			(end -0.674878 -1.100074)
			(stroke
				(width 0.1)
				(type default)
			)
			(layer "F.Fab")
		)
		(fp_line
			(start 0.674878 -1.100074)
			(end 0.674878 1.100074)
			(stroke
				(width 0.1)
				(type default)
			)
			(layer "F.Fab")
		)
		(fp_line
			(start 0.674878 1.100074)
			(end -0.674878 1.100074)
			(stroke
				(width 0.1)
				(type default)
			)
			(layer "F.Fab")
		)
		(fp_poly
			(pts
				(xy -2.2352 -0.298958) (xy -2.2352 -1.001014) (xy -1.533144 -0.649986)
			)
			(stroke
				(width 0)
				(type default)
			)
			(fill yes)
			(layer "F.Fab")
		)
		(pad "1" smd rect
			(at -0.94996 -0.649986 90)
			(size 0.4318 0.508)
			(layers "F.Cu" "F.Mask" "F.Paste")
			(net "GND")
		)
		(pad "2" smd rect
			(at -0.94996 0 90)
			(size 0.4318 0.508)
			(layers "F.Cu" "F.Mask" "F.Paste")
			(net "P3V3_OCP_EN_2_R")
		)
		(pad "3" smd rect
			(at -0.94996 0.649986 90)
			(size 0.4318 0.508)
			(layers "F.Cu" "F.Mask" "F.Paste")
			(net "P3V3_OCP_UV_2_R1")
		)
		(pad "4" smd rect
			(at 0.94996 0.649986 90)
			(size 0.4318 0.508)
			(layers "F.Cu" "F.Mask" "F.Paste")
			(net "GND")
		)
		(pad "5" smd rect
			(at 0.94996 0 90)
			(size 0.4318 0.508)
			(layers "F.Cu" "F.Mask" "F.Paste")
			(net "P3V3_OCP_2_EN_G")
		)
		(pad "6" smd rect
			(at 0.94996 -0.649986 90)
			(size 0.4318 0.508)
			(layers "F.Cu" "F.Mask" "F.Paste")
			(net "P3V3_OCP_2_EN_G")
		)
	)
	(footprint ""
		(layer "F.Cu")
		(at 154.293824 -191.358266 -90)
		(property "Reference" "R3355"
			(at 0 0 270)
			(layer "F.SilkS")
			(hide yes)
			(effects
				(font
					(size 1.27 1.27)
				)
			)
		)
		(property "Value" ""
			(at 0 0 270)
			(layer "F.Fab")
			(effects
				(font
					(size 1.27 1.27)
				)
			)
		)
		(duplicate_pad_numbers_are_jumpers no)
		(fp_line
			(start 0.324866 0.4064)
			(end -0.386334 0.4064)
			(stroke
				(width 0.1524)
				(type default)
			)
			(layer "F.SilkS")
		)
		(fp_line
			(start -0.7874 -0.011176)
			(end -0.7874 -0.4064)
			(stroke
				(width 0.1524)
				(type default)
			)
			(layer "F.SilkS")
		)
		(fp_line
			(start -0.7874 -0.4064)
			(end 0.7874 -0.4064)
			(stroke
				(width 0.1524)
				(type default)
			)
			(layer "F.SilkS")
		)
		(fp_line
			(start 0.7874 -0.4064)
			(end 0.7874 -0.011176)
			(stroke
				(width 0.1524)
				(type default)
			)
			(layer "F.SilkS")
		)
		(fp_line
			(start -0.67945 0.3048)
			(end -0.67945 -0.305054)
			(stroke
				(width 0.1)
				(type default)
			)
			(layer "F.Fab")
		)
		(fp_line
			(start -0.12065 0.3048)
			(end -0.67945 0.3048)
			(stroke
				(width 0.1)
				(type default)
			)
			(layer "F.Fab")
		)
		(fp_line
			(start 0.120396 0.3048)
			(end 0.120396 0.2794)
			(stroke
				(width 0.1)
				(type default)
			)
			(layer "F.Fab")
		)
		(fp_line
			(start 0.67945 0.3048)
			(end 0.120396 0.3048)
			(stroke
				(width 0.1)
				(type default)
			)
			(layer "F.Fab")
		)
		(fp_line
			(start -0.12065 0.2794)
			(end -0.12065 0.3048)
			(stroke
				(width 0.1)
				(type default)
			)
			(layer "F.Fab")
		)
		(fp_line
			(start 0.120396 0.2794)
			(end -0.12065 0.2794)
			(stroke
				(width 0.1)
				(type default)
			)
			(layer "F.Fab")
		)
		(fp_line
			(start -0.12065 -0.2794)
			(end 0.12065 -0.2794)
			(stroke
				(width 0.1)
				(type default)
			)
			(layer "F.Fab")
		)
		(fp_line
			(start 0.12065 -0.2794)
			(end 0.12065 -0.3048)
			(stroke
				(width 0.1)
				(type default)
			)
			(layer "F.Fab")
		)
		(fp_line
			(start 0.12065 -0.3048)
			(end 0.67945 -0.3048)
			(stroke
				(width 0.1)
				(type default)
			)
			(layer "F.Fab")
		)
		(fp_line
			(start 0.67945 -0.3048)
			(end 0.67945 0.3048)
			(stroke
				(width 0.1)
				(type default)
			)
			(layer "F.Fab")
		)
		(fp_line
			(start -0.67945 -0.305054)
			(end -0.12065 -0.305054)
			(stroke
				(width 0.1)
				(type default)
			)
			(layer "F.Fab")
		)
		(fp_line
			(start -0.12065 -0.305054)
			(end -0.12065 -0.2794)
			(stroke
				(width 0.1)
				(type default)
			)
			(layer "F.Fab")
		)
		(pad "1" smd circle
			(at -0.40005 0 270)
			(size 0 0)
			(layers "F.Cu" "F.Mask" "F.Paste")
			(net "CLK_100M_CPU1_CLK01_R_DN")
		)
		(pad "2" smd circle
			(at 0.40005 0 270)
			(size 0 0)
			(layers "F.Cu" "F.Mask" "F.Paste")
			(net "CLK_100M_CPU1_CLK01_DN")
		)
	)
	(footprint ""
		(layer "F.Cu")
		(at 13.621258 -427.098206 180)
		(property "Reference" "R6168"
			(at 0 0 180)
			(layer "F.SilkS")
			(hide yes)
			(effects
				(font
					(size 1.27 1.27)
				)
			)
		)
		(property "Value" ""
			(at 0 0 180)
			(layer "F.Fab")
			(effects
				(font
					(size 1.27 1.27)
				)
			)
		)
		(duplicate_pad_numbers_are_jumpers no)
		(fp_line
			(start 0.7874 0.4064)
			(end -0.7874 0.4064)
			(stroke
				(width 0.1524)
				(type default)
			)
			(layer "F.SilkS")
		)
		(fp_line
			(start 0.7874 -0.4064)
			(end 0.7874 0.4064)
			(stroke
				(width 0.1524)
				(type default)
			)
			(layer "F.SilkS")
		)
		(fp_line
			(start -0.7874 0.4064)
			(end -0.7874 -0.4064)
			(stroke
				(width 0.1524)
				(type default)
			)
			(layer "F.SilkS")
		)
		(fp_line
			(start -0.7874 -0.4064)
			(end 0.7874 -0.4064)
			(stroke
				(width 0.1524)
				(type default)
			)
			(layer "F.SilkS")
		)
		(fp_line
			(start 0.67945 0.3048)
			(end 0.120396 0.3048)
			(stroke
				(width 0.1)
				(type default)
			)
			(layer "F.Fab")
		)
		(fp_line
			(start 0.67945 -0.3048)
			(end 0.67945 0.3048)
			(stroke
				(width 0.1)
				(type default)
			)
			(layer "F.Fab")
		)
		(fp_line
			(start 0.12065 -0.2794)
			(end 0.12065 -0.3048)
			(stroke
				(width 0.1)
				(type default)
			)
			(layer "F.Fab")
		)
		(fp_line
			(start 0.12065 -0.3048)
			(end 0.67945 -0.3048)
			(stroke
				(width 0.1)
				(type default)
			)
			(layer "F.Fab")
		)
		(fp_line
			(start 0.120396 0.3048)
			(end 0.120396 0.2794)
			(stroke
				(width 0.1)
				(type default)
			)
			(layer "F.Fab")
		)
		(fp_line
			(start 0.120396 0.2794)
			(end -0.12065 0.2794)
			(stroke
				(width 0.1)
				(type default)
			)
			(layer "F.Fab")
		)
		(fp_line
			(start -0.12065 0.3048)
			(end -0.67945 0.3048)
			(stroke
				(width 0.1)
				(type default)
			)
			(layer "F.Fab")
		)
		(fp_line
			(start -0.12065 0.2794)
			(end -0.12065 0.3048)
			(stroke
				(width 0.1)
				(type default)
			)
			(layer "F.Fab")
		)
		(fp_line
			(start -0.12065 -0.2794)
			(end 0.12065 -0.2794)
			(stroke
				(width 0.1)
				(type default)
			)
			(layer "F.Fab")
		)
		(fp_line
			(start -0.12065 -0.305054)
			(end -0.12065 -0.2794)
			(stroke
				(width 0.1)
				(type default)
			)
			(layer "F.Fab")
		)
		(fp_line
			(start -0.67945 0.3048)
			(end -0.67945 -0.305054)
			(stroke
				(width 0.1)
				(type default)
			)
			(layer "F.Fab")
		)
		(fp_line
			(start -0.67945 -0.305054)
			(end -0.12065 -0.305054)
			(stroke
				(width 0.1)
				(type default)
			)
			(layer "F.Fab")
		)
		(pad "1" smd circle
			(at -0.40005 0 180)
			(size 0 0)
			(layers "F.Cu" "F.Mask" "F.Paste")
			(net "FM_P2E_BUF2_VODB_DB")
		)
		(pad "2" smd circle
			(at 0.40005 0 180)
			(size 0 0)
			(layers "F.Cu" "F.Mask" "F.Paste")
			(net "GND")
		)
	)
	(footprint ""
		(layer "F.Cu")
		(at 327.179178 -42.176954)
		(property "Reference" "R2843"
			(at 0 0 0)
			(layer "F.SilkS")
			(hide yes)
			(effects
				(font
					(size 1.27 1.27)
				)
			)
		)
		(property "Value" ""
			(at 0 0 0)
			(layer "F.Fab")
			(effects
				(font
					(size 1.27 1.27)
				)
			)
		)
		(duplicate_pad_numbers_are_jumpers no)
		(fp_line
			(start -0.7874 -0.4064)
			(end 0.7874 -0.4064)
			(stroke
				(width 0.1524)
				(type default)
			)
			(layer "F.SilkS")
		)
		(fp_line
			(start -0.7874 0.4064)
			(end -0.7874 -0.4064)
			(stroke
				(width 0.1524)
				(type default)
			)
			(layer "F.SilkS")
		)
		(fp_line
			(start 0.7874 -0.4064)
			(end 0.7874 0.4064)
			(stroke
				(width 0.1524)
				(type default)
			)
			(layer "F.SilkS")
		)
		(fp_line
			(start 0.7874 0.4064)
			(end -0.7874 0.4064)
			(stroke
				(width 0.1524)
				(type default)
			)
			(layer "F.SilkS")
		)
		(fp_line
			(start -0.67945 -0.305054)
			(end -0.12065 -0.305054)
			(stroke
				(width 0.1)
				(type default)
			)
			(layer "F.Fab")
		)
		(fp_line
			(start -0.67945 0.3048)
			(end -0.67945 -0.305054)
			(stroke
				(width 0.1)
				(type default)
			)
			(layer "F.Fab")
		)
		(fp_line
			(start -0.12065 -0.305054)
			(end -0.12065 -0.2794)
			(stroke
				(width 0.1)
				(type default)
			)
			(layer "F.Fab")
		)
		(fp_line
			(start -0.12065 -0.2794)
			(end 0.12065 -0.2794)
			(stroke
				(width 0.1)
				(type default)
			)
			(layer "F.Fab")
		)
		(fp_line
			(start -0.12065 0.2794)
			(end -0.12065 0.3048)
			(stroke
				(width 0.1)
				(type default)
			)
			(layer "F.Fab")
		)
		(fp_line
			(start -0.12065 0.3048)
			(end -0.67945 0.3048)
			(stroke
				(width 0.1)
				(type default)
			)
			(layer "F.Fab")
		)
		(fp_line
			(start 0.120396 0.2794)
			(end -0.12065 0.2794)
			(stroke
				(width 0.1)
				(type default)
			)
			(layer "F.Fab")
		)
		(fp_line
			(start 0.120396 0.3048)
			(end 0.120396 0.2794)
			(stroke
				(width 0.1)
				(type default)
			)
			(layer "F.Fab")
		)
		(fp_line
			(start 0.12065 -0.3048)
			(end 0.67945 -0.3048)
			(stroke
				(width 0.1)
				(type default)
			)
			(layer "F.Fab")
		)
		(fp_line
			(start 0.12065 -0.2794)
			(end 0.12065 -0.3048)
			(stroke
				(width 0.1)
				(type default)
			)
			(layer "F.Fab")
		)
		(fp_line
			(start 0.67945 -0.3048)
			(end 0.67945 0.3048)
			(stroke
				(width 0.1)
				(type default)
			)
			(layer "F.Fab")
		)
		(fp_line
			(start 0.67945 0.3048)
			(end 0.120396 0.3048)
			(stroke
				(width 0.1)
				(type default)
			)
			(layer "F.Fab")
		)
		(pad "1" smd circle
			(at -0.40005 0)
			(size 0 0)
			(layers "F.Cu" "F.Mask" "F.Paste")
			(net "P3V3_ADC")
		)
		(pad "2" smd circle
			(at 0.40005 0)
			(size 0 0)
			(layers "F.Cu" "F.Mask" "F.Paste")
			(net "GND")
		)
	)
	(footprint ""
		(layer "F.Cu")
		(at 152.270206 -191.35471 -90)
		(property "Reference" "R3201"
			(at 0 0 270)
			(layer "F.SilkS")
			(hide yes)
			(effects
				(font
					(size 1.27 1.27)
				)
			)
		)
		(property "Value" ""
			(at 0 0 270)
			(layer "F.Fab")
			(effects
				(font
					(size 1.27 1.27)
				)
			)
		)
		(duplicate_pad_numbers_are_jumpers no)
		(fp_line
			(start 0.42291 0.4064)
			(end -0.41529 0.4064)
			(stroke
				(width 0.1524)
				(type default)
			)
			(layer "F.SilkS")
		)
		(fp_line
			(start -0.7874 -0.002794)
			(end -0.7874 -0.4064)
			(stroke
				(width 0.1524)
				(type default)
			)
			(layer "F.SilkS")
		)
		(fp_line
			(start -0.7874 -0.4064)
			(end 0.7874 -0.4064)
			(stroke
				(width 0.1524)
				(type default)
			)
			(layer "F.SilkS")
		)
		(fp_line
			(start 0.7874 -0.4064)
			(end 0.7874 -0.002794)
			(stroke
				(width 0.1524)
				(type default)
			)
			(layer "F.SilkS")
		)
		(fp_line
			(start -0.67945 0.3048)
			(end -0.67945 -0.305054)
			(stroke
				(width 0.1)
				(type default)
			)
			(layer "F.Fab")
		)
		(fp_line
			(start -0.12065 0.3048)
			(end -0.67945 0.3048)
			(stroke
				(width 0.1)
				(type default)
			)
			(layer "F.Fab")
		)
		(fp_line
			(start 0.120396 0.3048)
			(end 0.120396 0.2794)
			(stroke
				(width 0.1)
				(type default)
			)
			(layer "F.Fab")
		)
		(fp_line
			(start 0.67945 0.3048)
			(end 0.120396 0.3048)
			(stroke
				(width 0.1)
				(type default)
			)
			(layer "F.Fab")
		)
		(fp_line
			(start -0.12065 0.2794)
			(end -0.12065 0.3048)
			(stroke
				(width 0.1)
				(type default)
			)
			(layer "F.Fab")
		)
		(fp_line
			(start 0.120396 0.2794)
			(end -0.12065 0.2794)
			(stroke
				(width 0.1)
				(type default)
			)
			(layer "F.Fab")
		)
		(fp_line
			(start -0.12065 -0.2794)
			(end 0.12065 -0.2794)
			(stroke
				(width 0.1)
				(type default)
			)
			(layer "F.Fab")
		)
		(fp_line
			(start 0.12065 -0.2794)
			(end 0.12065 -0.3048)
			(stroke
				(width 0.1)
				(type default)
			)
			(layer "F.Fab")
		)
		(fp_line
			(start 0.12065 -0.3048)
			(end 0.67945 -0.3048)
			(stroke
				(width 0.1)
				(type default)
			)
			(layer "F.Fab")
		)
		(fp_line
			(start 0.67945 -0.3048)
			(end 0.67945 0.3048)
			(stroke
				(width 0.1)
				(type default)
			)
			(layer "F.Fab")
		)
		(fp_line
			(start -0.67945 -0.305054)
			(end -0.12065 -0.305054)
			(stroke
				(width 0.1)
				(type default)
			)
			(layer "F.Fab")
		)
		(fp_line
			(start -0.12065 -0.305054)
			(end -0.12065 -0.2794)
			(stroke
				(width 0.1)
				(type default)
			)
			(layer "F.Fab")
		)
		(pad "1" smd circle
			(at -0.40005 0 270)
			(size 0 0)
			(layers "F.Cu" "F.Mask" "F.Paste")
			(net "CLK_100M_CPU1_CLK05_R_DN")
		)
		(pad "2" smd circle
			(at 0.40005 0 270)
			(size 0 0)
			(layers "F.Cu" "F.Mask" "F.Paste")
			(net "CLK_100M_CPU1_CLK05_DN")
		)
	)
	(footprint ""
		(layer "F.Cu")
		(at 120.69826 -30.389576)
		(property "Reference" "R6268"
			(at 0 0 0)
			(layer "F.SilkS")
			(hide yes)
			(effects
				(font
					(size 1.27 1.27)
				)
			)
		)
		(property "Value" ""
			(at 0 0 0)
			(layer "F.Fab")
			(effects
				(font
					(size 1.27 1.27)
				)
			)
		)
		(duplicate_pad_numbers_are_jumpers no)
		(fp_line
			(start -0.7874 -0.4064)
			(end 0.7874 -0.4064)
			(stroke
				(width 0.1524)
				(type default)
			)
			(layer "F.SilkS")
		)
		(fp_line
			(start -0.7874 0.4064)
			(end -0.7874 -0.4064)
			(stroke
				(width 0.1524)
				(type default)
			)
			(layer "F.SilkS")
		)
		(fp_line
			(start 0.7874 -0.4064)
			(end 0.7874 0.4064)
			(stroke
				(width 0.1524)
				(type default)
			)
			(layer "F.SilkS")
		)
		(fp_line
			(start 0.7874 0.4064)
			(end -0.7874 0.4064)
			(stroke
				(width 0.1524)
				(type default)
			)
			(layer "F.SilkS")
		)
		(fp_line
			(start -0.67945 -0.305054)
			(end -0.12065 -0.305054)
			(stroke
				(width 0.1)
				(type default)
			)
			(layer "F.Fab")
		)
		(fp_line
			(start -0.67945 0.3048)
			(end -0.67945 -0.305054)
			(stroke
				(width 0.1)
				(type default)
			)
			(layer "F.Fab")
		)
		(fp_line
			(start -0.12065 -0.305054)
			(end -0.12065 -0.2794)
			(stroke
				(width 0.1)
				(type default)
			)
			(layer "F.Fab")
		)
		(fp_line
			(start -0.12065 -0.2794)
			(end 0.12065 -0.2794)
			(stroke
				(width 0.1)
				(type default)
			)
			(layer "F.Fab")
		)
		(fp_line
			(start -0.12065 0.2794)
			(end -0.12065 0.3048)
			(stroke
				(width 0.1)
				(type default)
			)
			(layer "F.Fab")
		)
		(fp_line
			(start -0.12065 0.3048)
			(end -0.67945 0.3048)
			(stroke
				(width 0.1)
				(type default)
			)
			(layer "F.Fab")
		)
		(fp_line
			(start 0.120396 0.2794)
			(end -0.12065 0.2794)
			(stroke
				(width 0.1)
				(type default)
			)
			(layer "F.Fab")
		)
		(fp_line
			(start 0.120396 0.3048)
			(end 0.120396 0.2794)
			(stroke
				(width 0.1)
				(type default)
			)
			(layer "F.Fab")
		)
		(fp_line
			(start 0.12065 -0.3048)
			(end 0.67945 -0.3048)
			(stroke
				(width 0.1)
				(type default)
			)
			(layer "F.Fab")
		)
		(fp_line
			(start 0.12065 -0.2794)
			(end 0.12065 -0.3048)
			(stroke
				(width 0.1)
				(type default)
			)
			(layer "F.Fab")
		)
		(fp_line
			(start 0.67945 -0.3048)
			(end 0.67945 0.3048)
			(stroke
				(width 0.1)
				(type default)
			)
			(layer "F.Fab")
		)
		(fp_line
			(start 0.67945 0.3048)
			(end 0.120396 0.3048)
			(stroke
				(width 0.1)
				(type default)
			)
			(layer "F.Fab")
		)
		(pad "1" smd circle
			(at -0.40005 0)
			(size 0 0)
			(layers "F.Cu" "F.Mask" "F.Paste")
			(net "USB_HUB2_TI_USB_SSRXM_DN4_MRP_VDD12")
		)
		(pad "2" smd circle
			(at 0.40005 0)
			(size 0 0)
			(layers "F.Cu" "F.Mask" "F.Paste")
			(net "P1V2_CPU0_USB2_DVDD12")
		)
	)
	(footprint ""
		(layer "F.Cu")
		(at 333.219044 -378.95403 -90)
		(property "Reference" "C959"
			(at 0 0 270)
			(layer "F.SilkS")
			(hide yes)
			(effects
				(font
					(size 1.27 1.27)
				)
			)
		)
		(property "Value" ""
			(at 0 0 270)
			(layer "F.Fab")
			(effects
				(font
					(size 1.27 1.27)
				)
			)
		)
		(duplicate_pad_numbers_are_jumpers no)
		(fp_line
			(start -0.299974 0.150114)
			(end -0.299974 -0.150114)
			(stroke
				(width 0.1)
				(type default)
			)
			(layer "F.Fab")
		)
		(fp_line
			(start 0.299974 0.150114)
			(end -0.299974 0.150114)
			(stroke
				(width 0.1)
				(type default)
			)
			(layer "F.Fab")
		)
		(fp_line
			(start -0.299974 -0.150114)
			(end 0.299974 -0.150114)
			(stroke
				(width 0.1)
				(type default)
			)
			(layer "F.Fab")
		)
		(fp_line
			(start 0.299974 -0.150114)
			(end 0.299974 0.150114)
			(stroke
				(width 0.1)
				(type default)
			)
			(layer "F.Fab")
		)
		(pad "1" smd rect
			(at -0.2667 0 270)
			(size 0.3048 0.381)
			(layers "F.Cu" "F.Mask" "F.Paste")
			(net "P5E_CPU0_P1_TX_C_DP<3>")
		)
		(pad "2" smd rect
			(at 0.2667 0 270)
			(size 0.3048 0.381)
			(layers "F.Cu" "F.Mask" "F.Paste")
			(net "P5E_CPU0_P1_TX_DP<3>")
		)
	)
	(footprint ""
		(layer "F.Cu")
		(at 455.534776 -46.264576 -90)
		(property "Reference" "PC569"
			(at 0 0 270)
			(layer "F.SilkS")
			(hide yes)
			(effects
				(font
					(size 1.27 1.27)
				)
			)
		)
		(property "Value" ""
			(at 0 0 270)
			(layer "F.Fab")
			(effects
				(font
					(size 1.27 1.27)
				)
			)
		)
		(duplicate_pad_numbers_are_jumpers no)
		(fp_line
			(start -0.7874 0.4064)
			(end -0.7874 -0.4064)
			(stroke
				(width 0.1524)
				(type default)
			)
			(layer "F.SilkS")
		)
		(fp_line
			(start 0.7874 0.4064)
			(end -0.7874 0.4064)
			(stroke
				(width 0.1524)
				(type default)
			)
			(layer "F.SilkS")
		)
		(fp_line
			(start -0.7874 -0.4064)
			(end 0.7874 -0.4064)
			(stroke
				(width 0.1524)
				(type default)
			)
			(layer "F.SilkS")
		)
		(fp_line
			(start 0.7874 -0.4064)
			(end 0.7874 0.4064)
			(stroke
				(width 0.1524)
				(type default)
			)
			(layer "F.SilkS")
		)
		(fp_line
			(start -0.67945 0.3048)
			(end -0.67945 -0.305054)
			(stroke
				(width 0.1)
				(type default)
			)
			(layer "F.Fab")
		)
		(fp_line
			(start -0.12065 0.3048)
			(end -0.67945 0.3048)
			(stroke
				(width 0.1)
				(type default)
			)
			(layer "F.Fab")
		)
		(fp_line
			(start 0.120396 0.3048)
			(end 0.120396 0.2794)
			(stroke
				(width 0.1)
				(type default)
			)
			(layer "F.Fab")
		)
		(fp_line
			(start 0.67945 0.3048)
			(end 0.120396 0.3048)
			(stroke
				(width 0.1)
				(type default)
			)
			(layer "F.Fab")
		)
		(fp_line
			(start -0.12065 0.2794)
			(end -0.12065 0.3048)
			(stroke
				(width 0.1)
				(type default)
			)
			(layer "F.Fab")
		)
		(fp_line
			(start 0.120396 0.2794)
			(end -0.12065 0.2794)
			(stroke
				(width 0.1)
				(type default)
			)
			(layer "F.Fab")
		)
		(fp_line
			(start -0.12065 -0.2794)
			(end 0.12065 -0.2794)
			(stroke
				(width 0.1)
				(type default)
			)
			(layer "F.Fab")
		)
		(fp_line
			(start 0.12065 -0.2794)
			(end 0.12065 -0.3048)
			(stroke
				(width 0.1)
				(type default)
			)
			(layer "F.Fab")
		)
		(fp_line
			(start 0.12065 -0.3048)
			(end 0.67945 -0.3048)
			(stroke
				(width 0.1)
				(type default)
			)
			(layer "F.Fab")
		)
		(fp_line
			(start 0.67945 -0.3048)
			(end 0.67945 0.3048)
			(stroke
				(width 0.1)
				(type default)
			)
			(layer "F.Fab")
		)
		(fp_line
			(start -0.67945 -0.305054)
			(end -0.12065 -0.305054)
			(stroke
				(width 0.1)
				(type default)
			)
			(layer "F.Fab")
		)
		(fp_line
			(start -0.12065 -0.305054)
			(end -0.12065 -0.2794)
			(stroke
				(width 0.1)
				(type default)
			)
			(layer "F.Fab")
		)
		(pad "1" smd circle
			(at -0.40005 0 270)
			(size 0 0)
			(layers "F.Cu" "F.Mask" "F.Paste")
			(net "P3V3_AUX_FB")
		)
		(pad "2" smd circle
			(at 0.40005 0 270)
			(size 0 0)
			(layers "F.Cu" "F.Mask" "F.Paste")
			(net "P3V3_AUX")
		)
	)
	(footprint ""
		(layer "F.Cu")
		(at 38.697662 -419.249098 90)
		(property "Reference" "R3266"
			(at 0 0 90)
			(layer "F.SilkS")
			(hide yes)
			(effects
				(font
					(size 1.27 1.27)
				)
			)
		)
		(property "Value" ""
			(at 0 0 90)
			(layer "F.Fab")
			(effects
				(font
					(size 1.27 1.27)
				)
			)
		)
		(duplicate_pad_numbers_are_jumpers no)
		(fp_line
			(start 0.7874 -0.4064)
			(end 0.7874 0.4064)
			(stroke
				(width 0.1524)
				(type default)
			)
			(layer "F.SilkS")
		)
		(fp_line
			(start -0.7874 -0.4064)
			(end 0.7874 -0.4064)
			(stroke
				(width 0.1524)
				(type default)
			)
			(layer "F.SilkS")
		)
		(fp_line
			(start 0.7874 0.4064)
			(end -0.7874 0.4064)
			(stroke
				(width 0.1524)
				(type default)
			)
			(layer "F.SilkS")
		)
		(fp_line
			(start -0.7874 0.4064)
			(end -0.7874 -0.4064)
			(stroke
				(width 0.1524)
				(type default)
			)
			(layer "F.SilkS")
		)
		(fp_line
			(start -0.12065 -0.305054)
			(end -0.12065 -0.2794)
			(stroke
				(width 0.1)
				(type default)
			)
			(layer "F.Fab")
		)
		(fp_line
			(start -0.67945 -0.305054)
			(end -0.12065 -0.305054)
			(stroke
				(width 0.1)
				(type default)
			)
			(layer "F.Fab")
		)
		(fp_line
			(start 0.67945 -0.3048)
			(end 0.67945 0.3048)
			(stroke
				(width 0.1)
				(type default)
			)
			(layer "F.Fab")
		)
		(fp_line
			(start 0.12065 -0.3048)
			(end 0.67945 -0.3048)
			(stroke
				(width 0.1)
				(type default)
			)
			(layer "F.Fab")
		)
		(fp_line
			(start 0.12065 -0.2794)
			(end 0.12065 -0.3048)
			(stroke
				(width 0.1)
				(type default)
			)
			(layer "F.Fab")
		)
		(fp_line
			(start -0.12065 -0.2794)
			(end 0.12065 -0.2794)
			(stroke
				(width 0.1)
				(type default)
			)
			(layer "F.Fab")
		)
		(fp_line
			(start 0.120396 0.2794)
			(end -0.12065 0.2794)
			(stroke
				(width 0.1)
				(type default)
			)
			(layer "F.Fab")
		)
		(fp_line
			(start -0.12065 0.2794)
			(end -0.12065 0.3048)
			(stroke
				(width 0.1)
				(type default)
			)
			(layer "F.Fab")
		)
		(fp_line
			(start 0.67945 0.3048)
			(end 0.120396 0.3048)
			(stroke
				(width 0.1)
				(type default)
			)
			(layer "F.Fab")
		)
		(fp_line
			(start 0.120396 0.3048)
			(end 0.120396 0.2794)
			(stroke
				(width 0.1)
				(type default)
			)
			(layer "F.Fab")
		)
		(fp_line
			(start -0.12065 0.3048)
			(end -0.67945 0.3048)
			(stroke
				(width 0.1)
				(type default)
			)
			(layer "F.Fab")
		)
		(fp_line
			(start -0.67945 0.3048)
			(end -0.67945 -0.305054)
			(stroke
				(width 0.1)
				(type default)
			)
			(layer "F.Fab")
		)
		(pad "1" smd circle
			(at -0.40005 0 90)
			(size 0 0)
			(layers "F.Cu" "F.Mask" "F.Paste")
			(net "P3V3_AUX")
		)
		(pad "2" smd circle
			(at 0.40005 0 90)
			(size 0 0)
			(layers "F.Cu" "F.Mask" "F.Paste")
			(net "FM_P2E_MODE")
		)
	)
	(footprint ""
		(layer "F.Cu")
		(at 426.213778 -398.71523)
		(property "Reference" "C798"
			(at 0 0 0)
			(layer "F.SilkS")
			(hide yes)
			(effects
				(font
					(size 1.27 1.27)
				)
			)
		)
		(property "Value" ""
			(at 0 0 0)
			(layer "F.Fab")
			(effects
				(font
					(size 1.27 1.27)
				)
			)
		)
		(duplicate_pad_numbers_are_jumpers no)
		(fp_line
			(start -1.524 -0.762)
			(end 1.524 -0.762)
			(stroke
				(width 0.1524)
				(type default)
			)
			(layer "F.SilkS")
		)
		(fp_line
			(start -1.524 0.762)
			(end -1.524 -0.762)
			(stroke
				(width 0.1524)
				(type default)
			)
			(layer "F.SilkS")
		)
		(fp_line
			(start 1.524 -0.762)
			(end 1.524 0.762)
			(stroke
				(width 0.1524)
				(type default)
			)
			(layer "F.SilkS")
		)
		(fp_line
			(start 1.524 0.762)
			(end -1.524 0.762)
			(stroke
				(width 0.1524)
				(type default)
			)
			(layer "F.SilkS")
		)
		(fp_line
			(start -1.1049 -0.724916)
			(end -1.1049 0.724916)
			(stroke
				(width 0.1)
				(type default)
			)
			(layer "F.Fab")
		)
		(fp_line
			(start -1.1049 0.724916)
			(end 1.1049 0.724916)
			(stroke
				(width 0.1)
				(type default)
			)
			(layer "F.Fab")
		)
		(fp_line
			(start 1.1049 -0.724916)
			(end -1.1049 -0.724916)
			(stroke
				(width 0.1)
				(type default)
			)
			(layer "F.Fab")
		)
		(fp_line
			(start 1.1049 0.724916)
			(end 1.1049 -0.724916)
			(stroke
				(width 0.1)
				(type default)
			)
			(layer "F.Fab")
		)
		(pad "1" smd rect
			(at -0.889 0 180)
			(size 1.016 1.27)
			(layers "F.Cu" "F.Mask" "F.Paste")
			(net "P0V9_CPU0_RT2_2A")
		)
		(pad "2" smd rect
			(at 0.889 0 180)
			(size 1.016 1.27)
			(layers "F.Cu" "F.Mask" "F.Paste")
			(net "GND")
		)
	)
	(footprint ""
		(layer "F.Cu")
		(at 36.640262 -419.249098 -90)
		(property "Reference" "R3288"
			(at 0 0 270)
			(layer "F.SilkS")
			(hide yes)
			(effects
				(font
					(size 1.27 1.27)
				)
			)
		)
		(property "Value" ""
			(at 0 0 270)
			(layer "F.Fab")
			(effects
				(font
					(size 1.27 1.27)
				)
			)
		)
		(duplicate_pad_numbers_are_jumpers no)
		(fp_line
			(start -0.7874 0.4064)
			(end -0.7874 -0.4064)
			(stroke
				(width 0.1524)
				(type default)
			)
			(layer "F.SilkS")
		)
		(fp_line
			(start 0.7874 0.4064)
			(end -0.7874 0.4064)
			(stroke
				(width 0.1524)
				(type default)
			)
			(layer "F.SilkS")
		)
		(fp_line
			(start -0.7874 -0.4064)
			(end 0.7874 -0.4064)
			(stroke
				(width 0.1524)
				(type default)
			)
			(layer "F.SilkS")
		)
		(fp_line
			(start 0.7874 -0.4064)
			(end 0.7874 0.4064)
			(stroke
				(width 0.1524)
				(type default)
			)
			(layer "F.SilkS")
		)
		(fp_line
			(start -0.67945 0.3048)
			(end -0.67945 -0.305054)
			(stroke
				(width 0.1)
				(type default)
			)
			(layer "F.Fab")
		)
		(fp_line
			(start -0.12065 0.3048)
			(end -0.67945 0.3048)
			(stroke
				(width 0.1)
				(type default)
			)
			(layer "F.Fab")
		)
		(fp_line
			(start 0.120396 0.3048)
			(end 0.120396 0.2794)
			(stroke
				(width 0.1)
				(type default)
			)
			(layer "F.Fab")
		)
		(fp_line
			(start 0.67945 0.3048)
			(end 0.120396 0.3048)
			(stroke
				(width 0.1)
				(type default)
			)
			(layer "F.Fab")
		)
		(fp_line
			(start -0.12065 0.2794)
			(end -0.12065 0.3048)
			(stroke
				(width 0.1)
				(type default)
			)
			(layer "F.Fab")
		)
		(fp_line
			(start 0.120396 0.2794)
			(end -0.12065 0.2794)
			(stroke
				(width 0.1)
				(type default)
			)
			(layer "F.Fab")
		)
		(fp_line
			(start -0.12065 -0.2794)
			(end 0.12065 -0.2794)
			(stroke
				(width 0.1)
				(type default)
			)
			(layer "F.Fab")
		)
		(fp_line
			(start 0.12065 -0.2794)
			(end 0.12065 -0.3048)
			(stroke
				(width 0.1)
				(type default)
			)
			(layer "F.Fab")
		)
		(fp_line
			(start 0.12065 -0.3048)
			(end 0.67945 -0.3048)
			(stroke
				(width 0.1)
				(type default)
			)
			(layer "F.Fab")
		)
		(fp_line
			(start 0.67945 -0.3048)
			(end 0.67945 0.3048)
			(stroke
				(width 0.1)
				(type default)
			)
			(layer "F.Fab")
		)
		(fp_line
			(start -0.67945 -0.305054)
			(end -0.12065 -0.305054)
			(stroke
				(width 0.1)
				(type default)
			)
			(layer "F.Fab")
		)
		(fp_line
			(start -0.12065 -0.305054)
			(end -0.12065 -0.2794)
			(stroke
				(width 0.1)
				(type default)
			)
			(layer "F.Fab")
		)
		(pad "1" smd circle
			(at -0.40005 0 270)
			(size 0 0)
			(layers "F.Cu" "F.Mask" "F.Paste")
			(net "FM_P2E_SWA")
		)
		(pad "2" smd circle
			(at 0.40005 0 270)
			(size 0 0)
			(layers "F.Cu" "F.Mask" "F.Paste")
			(net "GND")
		)
	)
	(footprint ""
		(layer "F.Cu")
		(at 444.457582 -53.188108 90)
		(property "Reference" "PC2263"
			(at 0 0 90)
			(layer "F.SilkS")
			(hide yes)
			(effects
				(font
					(size 1.27 1.27)
				)
			)
		)
		(property "Value" ""
			(at 0 0 90)
			(layer "F.Fab")
			(effects
				(font
					(size 1.27 1.27)
				)
			)
		)
		(duplicate_pad_numbers_are_jumpers no)
		(fp_line
			(start 1.524 -0.762)
			(end 1.524 0.762)
			(stroke
				(width 0.1524)
				(type default)
			)
			(layer "F.SilkS")
		)
		(fp_line
			(start -1.524 -0.762)
			(end 1.524 -0.762)
			(stroke
				(width 0.1524)
				(type default)
			)
			(layer "F.SilkS")
		)
		(fp_line
			(start 1.524 0.762)
			(end -1.524 0.762)
			(stroke
				(width 0.1524)
				(type default)
			)
			(layer "F.SilkS")
		)
		(fp_line
			(start -1.524 0.762)
			(end -1.524 -0.762)
			(stroke
				(width 0.1524)
				(type default)
			)
			(layer "F.SilkS")
		)
		(fp_line
			(start 1.1049 -0.724916)
			(end -1.1049 -0.724916)
			(stroke
				(width 0.1)
				(type default)
			)
			(layer "F.Fab")
		)
		(fp_line
			(start -1.1049 -0.724916)
			(end -1.1049 0.724916)
			(stroke
				(width 0.1)
				(type default)
			)
			(layer "F.Fab")
		)
		(fp_line
			(start 1.1049 0.724916)
			(end 1.1049 -0.724916)
			(stroke
				(width 0.1)
				(type default)
			)
			(layer "F.Fab")
		)
		(fp_line
			(start -1.1049 0.724916)
			(end 1.1049 0.724916)
			(stroke
				(width 0.1)
				(type default)
			)
			(layer "F.Fab")
		)
		(pad "1" smd rect
			(at -0.889 0 270)
			(size 1.016 1.27)
			(layers "F.Cu" "F.Mask" "F.Paste")
			(net "SW_P3V3_AUX_FLT")
		)
		(pad "2" smd rect
			(at 0.889 0 270)
			(size 1.016 1.27)
			(layers "F.Cu" "F.Mask" "F.Paste")
			(net "GND")
		)
	)
	(footprint ""
		(layer "F.Cu")
		(at 38.666928 -351.372932 -90)
		(property "Reference" "PC631"
			(at 0 0 270)
			(layer "F.SilkS")
			(hide yes)
			(effects
				(font
					(size 1.27 1.27)
				)
			)
		)
		(property "Value" ""
			(at 0 0 270)
			(layer "F.Fab")
			(effects
				(font
					(size 1.27 1.27)
				)
			)
		)
		(duplicate_pad_numbers_are_jumpers no)
		(fp_line
			(start -0.7874 0.4064)
			(end -0.7874 -0.4064)
			(stroke
				(width 0.1524)
				(type default)
			)
			(layer "F.SilkS")
		)
		(fp_line
			(start 0.7874 0.4064)
			(end -0.7874 0.4064)
			(stroke
				(width 0.1524)
				(type default)
			)
			(layer "F.SilkS")
		)
		(fp_line
			(start -0.7874 -0.4064)
			(end 0.7874 -0.4064)
			(stroke
				(width 0.1524)
				(type default)
			)
			(layer "F.SilkS")
		)
		(fp_line
			(start 0.7874 -0.4064)
			(end 0.7874 0.4064)
			(stroke
				(width 0.1524)
				(type default)
			)
			(layer "F.SilkS")
		)
		(fp_line
			(start -0.67945 0.3048)
			(end -0.67945 -0.305054)
			(stroke
				(width 0.1)
				(type default)
			)
			(layer "F.Fab")
		)
		(fp_line
			(start -0.12065 0.3048)
			(end -0.67945 0.3048)
			(stroke
				(width 0.1)
				(type default)
			)
			(layer "F.Fab")
		)
		(fp_line
			(start 0.120396 0.3048)
			(end 0.120396 0.2794)
			(stroke
				(width 0.1)
				(type default)
			)
			(layer "F.Fab")
		)
		(fp_line
			(start 0.67945 0.3048)
			(end 0.120396 0.3048)
			(stroke
				(width 0.1)
				(type default)
			)
			(layer "F.Fab")
		)
		(fp_line
			(start -0.12065 0.2794)
			(end -0.12065 0.3048)
			(stroke
				(width 0.1)
				(type default)
			)
			(layer "F.Fab")
		)
		(fp_line
			(start 0.120396 0.2794)
			(end -0.12065 0.2794)
			(stroke
				(width 0.1)
				(type default)
			)
			(layer "F.Fab")
		)
		(fp_line
			(start -0.12065 -0.2794)
			(end 0.12065 -0.2794)
			(stroke
				(width 0.1)
				(type default)
			)
			(layer "F.Fab")
		)
		(fp_line
			(start 0.12065 -0.2794)
			(end 0.12065 -0.3048)
			(stroke
				(width 0.1)
				(type default)
			)
			(layer "F.Fab")
		)
		(fp_line
			(start 0.12065 -0.3048)
			(end 0.67945 -0.3048)
			(stroke
				(width 0.1)
				(type default)
			)
			(layer "F.Fab")
		)
		(fp_line
			(start 0.67945 -0.3048)
			(end 0.67945 0.3048)
			(stroke
				(width 0.1)
				(type default)
			)
			(layer "F.Fab")
		)
		(fp_line
			(start -0.67945 -0.305054)
			(end -0.12065 -0.305054)
			(stroke
				(width 0.1)
				(type default)
			)
			(layer "F.Fab")
		)
		(fp_line
			(start -0.12065 -0.305054)
			(end -0.12065 -0.2794)
			(stroke
				(width 0.1)
				(type default)
			)
			(layer "F.Fab")
		)
		(pad "1" smd circle
			(at -0.40005 0 270)
			(size 0 0)
			(layers "F.Cu" "F.Mask" "F.Paste")
			(net "SW_PVDDIO_P1_BOOT3_R")
		)
		(pad "2" smd circle
			(at 0.40005 0 270)
			(size 0 0)
			(layers "F.Cu" "F.Mask" "F.Paste")
			(net "SW_PVDDIO_P1_BOOTR3")
		)
	)
	(footprint ""
		(layer "F.Cu")
		(at 450.508878 -397.562578 -90)
		(property "Reference" "PC6551_09P0_2"
			(at 0 0 270)
			(layer "F.SilkS")
			(hide yes)
			(effects
				(font
					(size 1.27 1.27)
				)
			)
		)
		(property "Value" ""
			(at 0 0 270)
			(layer "F.Fab")
			(effects
				(font
					(size 1.27 1.27)
				)
			)
		)
		(duplicate_pad_numbers_are_jumpers no)
		(fp_line
			(start -0.7874 0.4064)
			(end -0.7874 -0.4064)
			(stroke
				(width 0.1524)
				(type default)
			)
			(layer "F.SilkS")
		)
		(fp_line
			(start 0.7874 0.4064)
			(end -0.7874 0.4064)
			(stroke
				(width 0.1524)
				(type default)
			)
			(layer "F.SilkS")
		)
		(fp_line
			(start -0.7874 -0.4064)
			(end 0.7874 -0.4064)
			(stroke
				(width 0.1524)
				(type default)
			)
			(layer "F.SilkS")
		)
		(fp_line
			(start 0.7874 -0.4064)
			(end 0.7874 0.4064)
			(stroke
				(width 0.1524)
				(type default)
			)
			(layer "F.SilkS")
		)
		(fp_line
			(start -0.67945 0.3048)
			(end -0.67945 -0.305054)
			(stroke
				(width 0.1)
				(type default)
			)
			(layer "F.Fab")
		)
		(fp_line
			(start -0.12065 0.3048)
			(end -0.67945 0.3048)
			(stroke
				(width 0.1)
				(type default)
			)
			(layer "F.Fab")
		)
		(fp_line
			(start 0.120396 0.3048)
			(end 0.120396 0.2794)
			(stroke
				(width 0.1)
				(type default)
			)
			(layer "F.Fab")
		)
		(fp_line
			(start 0.67945 0.3048)
			(end 0.120396 0.3048)
			(stroke
				(width 0.1)
				(type default)
			)
			(layer "F.Fab")
		)
		(fp_line
			(start -0.12065 0.2794)
			(end -0.12065 0.3048)
			(stroke
				(width 0.1)
				(type default)
			)
			(layer "F.Fab")
		)
		(fp_line
			(start 0.120396 0.2794)
			(end -0.12065 0.2794)
			(stroke
				(width 0.1)
				(type default)
			)
			(layer "F.Fab")
		)
		(fp_line
			(start -0.12065 -0.2794)
			(end 0.12065 -0.2794)
			(stroke
				(width 0.1)
				(type default)
			)
			(layer "F.Fab")
		)
		(fp_line
			(start 0.12065 -0.2794)
			(end 0.12065 -0.3048)
			(stroke
				(width 0.1)
				(type default)
			)
			(layer "F.Fab")
		)
		(fp_line
			(start 0.12065 -0.3048)
			(end 0.67945 -0.3048)
			(stroke
				(width 0.1)
				(type default)
			)
			(layer "F.Fab")
		)
		(fp_line
			(start 0.67945 -0.3048)
			(end 0.67945 0.3048)
			(stroke
				(width 0.1)
				(type default)
			)
			(layer "F.Fab")
		)
		(fp_line
			(start -0.67945 -0.305054)
			(end -0.12065 -0.305054)
			(stroke
				(width 0.1)
				(type default)
			)
			(layer "F.Fab")
		)
		(fp_line
			(start -0.12065 -0.305054)
			(end -0.12065 -0.2794)
			(stroke
				(width 0.1)
				(type default)
			)
			(layer "F.Fab")
		)
		(pad "1" smd circle
			(at -0.40005 0 270)
			(size 0 0)
			(layers "F.Cu" "F.Mask" "F.Paste")
			(net "P0V9_RETIMER_CPU0_PVCC")
		)
		(pad "2" smd circle
			(at 0.40005 0 270)
			(size 0 0)
			(layers "F.Cu" "F.Mask" "F.Paste")
			(net "GND")
		)
	)
	(footprint ""
		(layer "F.Cu")
		(at 304.682906 -416.899344 -90)
		(property "Reference" "C6501"
			(at 0 0 270)
			(layer "F.SilkS")
			(hide yes)
			(effects
				(font
					(size 1.27 1.27)
				)
			)
		)
		(property "Value" ""
			(at 0 0 270)
			(layer "F.Fab")
			(effects
				(font
					(size 1.27 1.27)
				)
			)
		)
		(duplicate_pad_numbers_are_jumpers no)
		(fp_line
			(start -0.299974 0.150114)
			(end -0.299974 -0.150114)
			(stroke
				(width 0.1)
				(type default)
			)
			(layer "F.Fab")
		)
		(fp_line
			(start 0.299974 0.150114)
			(end -0.299974 0.150114)
			(stroke
				(width 0.1)
				(type default)
			)
			(layer "F.Fab")
		)
		(fp_line
			(start -0.299974 -0.150114)
			(end 0.299974 -0.150114)
			(stroke
				(width 0.1)
				(type default)
			)
			(layer "F.Fab")
		)
		(fp_line
			(start 0.299974 -0.150114)
			(end 0.299974 0.150114)
			(stroke
				(width 0.1)
				(type default)
			)
			(layer "F.Fab")
		)
		(pad "1" smd rect
			(at -0.2667 0 270)
			(size 0.3048 0.381)
			(layers "F.Cu" "F.Mask" "F.Paste")
			(net "P5E_CPU0_P0_TX_BUF_C_DP<0>")
		)
		(pad "2" smd rect
			(at 0.2667 0 270)
			(size 0.3048 0.381)
			(layers "F.Cu" "F.Mask" "F.Paste")
			(net "P5E_CPU0_P0_TX_BUF_DP<0>")
		)
	)
	(footprint ""
		(layer "F.Cu")
		(at 142.155672 -387.764274)
		(property "Reference" "R619"
			(at 0 0 0)
			(layer "F.SilkS")
			(hide yes)
			(effects
				(font
					(size 1.27 1.27)
				)
			)
		)
		(property "Value" ""
			(at 0 0 0)
			(layer "F.Fab")
			(effects
				(font
					(size 1.27 1.27)
				)
			)
		)
		(duplicate_pad_numbers_are_jumpers no)
		(fp_line
			(start -0.32512 -0.175006)
			(end 0.32512 -0.175006)
			(stroke
				(width 0.1)
				(type default)
			)
			(layer "F.Fab")
		)
		(fp_line
			(start -0.32512 0.175006)
			(end -0.32512 -0.175006)
			(stroke
				(width 0.1)
				(type default)
			)
			(layer "F.Fab")
		)
		(fp_line
			(start 0.32512 -0.175006)
			(end 0.32512 0.175006)
			(stroke
				(width 0.1)
				(type default)
			)
			(layer "F.Fab")
		)
		(fp_line
			(start 0.32512 0.175006)
			(end -0.32512 0.175006)
			(stroke
				(width 0.1)
				(type default)
			)
			(layer "F.Fab")
		)
		(pad "1" smd rect
			(at -0.2667 0)
			(size 0.3048 0.381)
			(layers "F.Cu" "F.Mask" "F.Paste")
			(net "CLK_100M_RETIMER_CPU1_P2_R_DP")
		)
		(pad "2" smd rect
			(at 0.2667 0 180)
			(size 0.3048 0.381)
			(layers "F.Cu" "F.Mask" "F.Paste")
			(net "CLK_100M_RETIMER_CPU1_P2_DP")
		)
	)
	(footprint ""
		(layer "F.Cu")
		(at 455.617834 -93.437964)
		(property "Reference" "R3231"
			(at 0 0 0)
			(layer "F.SilkS")
			(hide yes)
			(effects
				(font
					(size 1.27 1.27)
				)
			)
		)
		(property "Value" ""
			(at 0 0 0)
			(layer "F.Fab")
			(effects
				(font
					(size 1.27 1.27)
				)
			)
		)
		(duplicate_pad_numbers_are_jumpers no)
		(fp_line
			(start -0.7874 -0.4064)
			(end 0.7874 -0.4064)
			(stroke
				(width 0.1524)
				(type default)
			)
			(layer "F.SilkS")
		)
		(fp_line
			(start -0.7874 0.4064)
			(end -0.7874 -0.4064)
			(stroke
				(width 0.1524)
				(type default)
			)
			(layer "F.SilkS")
		)
		(fp_line
			(start 0.7874 -0.4064)
			(end 0.7874 0.4064)
			(stroke
				(width 0.1524)
				(type default)
			)
			(layer "F.SilkS")
		)
		(fp_line
			(start 0.7874 0.4064)
			(end -0.7874 0.4064)
			(stroke
				(width 0.1524)
				(type default)
			)
			(layer "F.SilkS")
		)
		(fp_line
			(start -0.67945 -0.305054)
			(end -0.12065 -0.305054)
			(stroke
				(width 0.1)
				(type default)
			)
			(layer "F.Fab")
		)
		(fp_line
			(start -0.67945 0.3048)
			(end -0.67945 -0.305054)
			(stroke
				(width 0.1)
				(type default)
			)
			(layer "F.Fab")
		)
		(fp_line
			(start -0.12065 -0.305054)
			(end -0.12065 -0.2794)
			(stroke
				(width 0.1)
				(type default)
			)
			(layer "F.Fab")
		)
		(fp_line
			(start -0.12065 -0.2794)
			(end 0.12065 -0.2794)
			(stroke
				(width 0.1)
				(type default)
			)
			(layer "F.Fab")
		)
		(fp_line
			(start -0.12065 0.2794)
			(end -0.12065 0.3048)
			(stroke
				(width 0.1)
				(type default)
			)
			(layer "F.Fab")
		)
		(fp_line
			(start -0.12065 0.3048)
			(end -0.67945 0.3048)
			(stroke
				(width 0.1)
				(type default)
			)
			(layer "F.Fab")
		)
		(fp_line
			(start 0.120396 0.2794)
			(end -0.12065 0.2794)
			(stroke
				(width 0.1)
				(type default)
			)
			(layer "F.Fab")
		)
		(fp_line
			(start 0.120396 0.3048)
			(end 0.120396 0.2794)
			(stroke
				(width 0.1)
				(type default)
			)
			(layer "F.Fab")
		)
		(fp_line
			(start 0.12065 -0.3048)
			(end 0.67945 -0.3048)
			(stroke
				(width 0.1)
				(type default)
			)
			(layer "F.Fab")
		)
		(fp_line
			(start 0.12065 -0.2794)
			(end 0.12065 -0.3048)
			(stroke
				(width 0.1)
				(type default)
			)
			(layer "F.Fab")
		)
		(fp_line
			(start 0.67945 -0.3048)
			(end 0.67945 0.3048)
			(stroke
				(width 0.1)
				(type default)
			)
			(layer "F.Fab")
		)
		(fp_line
			(start 0.67945 0.3048)
			(end 0.120396 0.3048)
			(stroke
				(width 0.1)
				(type default)
			)
			(layer "F.Fab")
		)
		(pad "1" smd circle
			(at -0.40005 0)
			(size 0 0)
			(layers "F.Cu" "F.Mask" "F.Paste")
			(net "OCP_SFF_AUX_PWR_EN")
		)
		(pad "2" smd circle
			(at 0.40005 0)
			(size 0 0)
			(layers "F.Cu" "F.Mask" "F.Paste")
			(net "OCP_SFF_AUX_PWR_EN_R2")
		)
	)
	(footprint ""
		(layer "F.Cu")
		(at 151.254206 -191.35471 -90)
		(property "Reference" "R3200"
			(at 0 0 270)
			(layer "F.SilkS")
			(hide yes)
			(effects
				(font
					(size 1.27 1.27)
				)
			)
		)
		(property "Value" ""
			(at 0 0 270)
			(layer "F.Fab")
			(effects
				(font
					(size 1.27 1.27)
				)
			)
		)
		(duplicate_pad_numbers_are_jumpers no)
		(fp_line
			(start -0.7874 0.4064)
			(end -0.7874 0.073406)
			(stroke
				(width 0.1524)
				(type default)
			)
			(layer "F.SilkS")
		)
		(fp_line
			(start 0.7874 0.4064)
			(end -0.7874 0.4064)
			(stroke
				(width 0.1524)
				(type default)
			)
			(layer "F.SilkS")
		)
		(fp_line
			(start 0.7874 -0.053594)
			(end 0.7874 0.4064)
			(stroke
				(width 0.1524)
				(type default)
			)
			(layer "F.SilkS")
		)
		(fp_line
			(start -0.41529 -0.4064)
			(end 0.42291 -0.4064)
			(stroke
				(width 0.1524)
				(type default)
			)
			(layer "F.SilkS")
		)
		(fp_line
			(start -0.67945 0.3048)
			(end -0.67945 -0.305054)
			(stroke
				(width 0.1)
				(type default)
			)
			(layer "F.Fab")
		)
		(fp_line
			(start -0.12065 0.3048)
			(end -0.67945 0.3048)
			(stroke
				(width 0.1)
				(type default)
			)
			(layer "F.Fab")
		)
		(fp_line
			(start 0.120396 0.3048)
			(end 0.120396 0.2794)
			(stroke
				(width 0.1)
				(type default)
			)
			(layer "F.Fab")
		)
		(fp_line
			(start 0.67945 0.3048)
			(end 0.120396 0.3048)
			(stroke
				(width 0.1)
				(type default)
			)
			(layer "F.Fab")
		)
		(fp_line
			(start -0.12065 0.2794)
			(end -0.12065 0.3048)
			(stroke
				(width 0.1)
				(type default)
			)
			(layer "F.Fab")
		)
		(fp_line
			(start 0.120396 0.2794)
			(end -0.12065 0.2794)
			(stroke
				(width 0.1)
				(type default)
			)
			(layer "F.Fab")
		)
		(fp_line
			(start -0.12065 -0.2794)
			(end 0.12065 -0.2794)
			(stroke
				(width 0.1)
				(type default)
			)
			(layer "F.Fab")
		)
		(fp_line
			(start 0.12065 -0.2794)
			(end 0.12065 -0.3048)
			(stroke
				(width 0.1)
				(type default)
			)
			(layer "F.Fab")
		)
		(fp_line
			(start 0.12065 -0.3048)
			(end 0.67945 -0.3048)
			(stroke
				(width 0.1)
				(type default)
			)
			(layer "F.Fab")
		)
		(fp_line
			(start 0.67945 -0.3048)
			(end 0.67945 0.3048)
			(stroke
				(width 0.1)
				(type default)
			)
			(layer "F.Fab")
		)
		(fp_line
			(start -0.67945 -0.305054)
			(end -0.12065 -0.305054)
			(stroke
				(width 0.1)
				(type default)
			)
			(layer "F.Fab")
		)
		(fp_line
			(start -0.12065 -0.305054)
			(end -0.12065 -0.2794)
			(stroke
				(width 0.1)
				(type default)
			)
			(layer "F.Fab")
		)
		(pad "1" smd circle
			(at -0.40005 0 270)
			(size 0 0)
			(layers "F.Cu" "F.Mask" "F.Paste")
			(net "CLK_100M_CPU1_CLK05_R_DP")
		)
		(pad "2" smd circle
			(at 0.40005 0 270)
			(size 0 0)
			(layers "F.Cu" "F.Mask" "F.Paste")
			(net "CLK_100M_CPU1_CLK05_DP")
		)
	)
	(footprint ""
		(layer "F.Cu")
		(at 254.35433 -55.860442 -90)
		(property "Reference" "R3948"
			(at 0 0 270)
			(layer "F.SilkS")
			(hide yes)
			(effects
				(font
					(size 1.27 1.27)
				)
			)
		)
		(property "Value" ""
			(at 0 0 270)
			(layer "F.Fab")
			(effects
				(font
					(size 1.27 1.27)
				)
			)
		)
		(duplicate_pad_numbers_are_jumpers no)
		(fp_line
			(start -0.7874 0.4064)
			(end -0.7874 -0.4064)
			(stroke
				(width 0.1524)
				(type default)
			)
			(layer "F.SilkS")
		)
		(fp_line
			(start 0.7874 0.4064)
			(end -0.7874 0.4064)
			(stroke
				(width 0.1524)
				(type default)
			)
			(layer "F.SilkS")
		)
		(fp_line
			(start -0.7874 -0.4064)
			(end 0.7874 -0.4064)
			(stroke
				(width 0.1524)
				(type default)
			)
			(layer "F.SilkS")
		)
		(fp_line
			(start 0.7874 -0.4064)
			(end 0.7874 0.4064)
			(stroke
				(width 0.1524)
				(type default)
			)
			(layer "F.SilkS")
		)
		(fp_line
			(start -0.67945 0.3048)
			(end -0.67945 -0.305054)
			(stroke
				(width 0.1)
				(type default)
			)
			(layer "F.Fab")
		)
		(fp_line
			(start -0.12065 0.3048)
			(end -0.67945 0.3048)
			(stroke
				(width 0.1)
				(type default)
			)
			(layer "F.Fab")
		)
		(fp_line
			(start 0.120396 0.3048)
			(end 0.120396 0.2794)
			(stroke
				(width 0.1)
				(type default)
			)
			(layer "F.Fab")
		)
		(fp_line
			(start 0.67945 0.3048)
			(end 0.120396 0.3048)
			(stroke
				(width 0.1)
				(type default)
			)
			(layer "F.Fab")
		)
		(fp_line
			(start -0.12065 0.2794)
			(end -0.12065 0.3048)
			(stroke
				(width 0.1)
				(type default)
			)
			(layer "F.Fab")
		)
		(fp_line
			(start 0.120396 0.2794)
			(end -0.12065 0.2794)
			(stroke
				(width 0.1)
				(type default)
			)
			(layer "F.Fab")
		)
		(fp_line
			(start -0.12065 -0.2794)
			(end 0.12065 -0.2794)
			(stroke
				(width 0.1)
				(type default)
			)
			(layer "F.Fab")
		)
		(fp_line
			(start 0.12065 -0.2794)
			(end 0.12065 -0.3048)
			(stroke
				(width 0.1)
				(type default)
			)
			(layer "F.Fab")
		)
		(fp_line
			(start 0.12065 -0.3048)
			(end 0.67945 -0.3048)
			(stroke
				(width 0.1)
				(type default)
			)
			(layer "F.Fab")
		)
		(fp_line
			(start 0.67945 -0.3048)
			(end 0.67945 0.3048)
			(stroke
				(width 0.1)
				(type default)
			)
			(layer "F.Fab")
		)
		(fp_line
			(start -0.67945 -0.305054)
			(end -0.12065 -0.305054)
			(stroke
				(width 0.1)
				(type default)
			)
			(layer "F.Fab")
		)
		(fp_line
			(start -0.12065 -0.305054)
			(end -0.12065 -0.2794)
			(stroke
				(width 0.1)
				(type default)
			)
			(layer "F.Fab")
		)
		(pad "1" smd circle
			(at -0.40005 0 270)
			(size 0 0)
			(layers "F.Cu" "F.Mask" "F.Paste")
			(net "P3V3_AUX")
		)
		(pad "2" smd circle
			(at 0.40005 0 270)
			(size 0 0)
			(layers "F.Cu" "F.Mask" "F.Paste")
			(net "HP_LVC3_E1S_0_HSC_PWRGD")
		)
	)
	(footprint ""
		(layer "F.Cu")
		(at 161.29 -356.362 90)
		(property "Reference" "R350"
			(at 0 0 90)
			(layer "F.SilkS")
			(hide yes)
			(effects
				(font
					(size 1.27 1.27)
				)
			)
		)
		(property "Value" ""
			(at 0 0 90)
			(layer "F.Fab")
			(effects
				(font
					(size 1.27 1.27)
				)
			)
		)
		(duplicate_pad_numbers_are_jumpers no)
		(fp_line
			(start 0.7874 -0.4064)
			(end 0.7874 0.4064)
			(stroke
				(width 0.1524)
				(type default)
			)
			(layer "F.SilkS")
		)
		(fp_line
			(start -0.7874 -0.4064)
			(end 0.7874 -0.4064)
			(stroke
				(width 0.1524)
				(type default)
			)
			(layer "F.SilkS")
		)
		(fp_line
			(start 0.7874 0.4064)
			(end -0.7874 0.4064)
			(stroke
				(width 0.1524)
				(type default)
			)
			(layer "F.SilkS")
		)
		(fp_line
			(start -0.7874 0.4064)
			(end -0.7874 -0.4064)
			(stroke
				(width 0.1524)
				(type default)
			)
			(layer "F.SilkS")
		)
		(fp_line
			(start -0.12065 -0.305054)
			(end -0.12065 -0.2794)
			(stroke
				(width 0.1)
				(type default)
			)
			(layer "F.Fab")
		)
		(fp_line
			(start -0.67945 -0.305054)
			(end -0.12065 -0.305054)
			(stroke
				(width 0.1)
				(type default)
			)
			(layer "F.Fab")
		)
		(fp_line
			(start 0.67945 -0.3048)
			(end 0.67945 0.3048)
			(stroke
				(width 0.1)
				(type default)
			)
			(layer "F.Fab")
		)
		(fp_line
			(start 0.12065 -0.3048)
			(end 0.67945 -0.3048)
			(stroke
				(width 0.1)
				(type default)
			)
			(layer "F.Fab")
		)
		(fp_line
			(start 0.12065 -0.2794)
			(end 0.12065 -0.3048)
			(stroke
				(width 0.1)
				(type default)
			)
			(layer "F.Fab")
		)
		(fp_line
			(start -0.12065 -0.2794)
			(end 0.12065 -0.2794)
			(stroke
				(width 0.1)
				(type default)
			)
			(layer "F.Fab")
		)
		(fp_line
			(start 0.120396 0.2794)
			(end -0.12065 0.2794)
			(stroke
				(width 0.1)
				(type default)
			)
			(layer "F.Fab")
		)
		(fp_line
			(start -0.12065 0.2794)
			(end -0.12065 0.3048)
			(stroke
				(width 0.1)
				(type default)
			)
			(layer "F.Fab")
		)
		(fp_line
			(start 0.67945 0.3048)
			(end 0.120396 0.3048)
			(stroke
				(width 0.1)
				(type default)
			)
			(layer "F.Fab")
		)
		(fp_line
			(start 0.120396 0.3048)
			(end 0.120396 0.2794)
			(stroke
				(width 0.1)
				(type default)
			)
			(layer "F.Fab")
		)
		(fp_line
			(start -0.12065 0.3048)
			(end -0.67945 0.3048)
			(stroke
				(width 0.1)
				(type default)
			)
			(layer "F.Fab")
		)
		(fp_line
			(start -0.67945 0.3048)
			(end -0.67945 -0.305054)
			(stroke
				(width 0.1)
				(type default)
			)
			(layer "F.Fab")
		)
		(pad "1" smd circle
			(at -0.40005 0 90)
			(size 0 0)
			(layers "F.Cu" "F.Mask" "F.Paste")
			(net "SMB_SCM_2_R2_SDA")
		)
		(pad "2" smd circle
			(at 0.40005 0 90)
			(size 0 0)
			(layers "F.Cu" "F.Mask" "F.Paste")
			(net "SMB_SCM_2_R5_SDA")
		)
	)
	(footprint ""
		(layer "F.Cu")
		(at 12.954 -79.0194)
		(property "Reference" "U58"
			(at -1.4732 -1.768348 0)
			(unlocked yes)
			(layer "F.SilkS")
			(effects
				(font
					(size 0.7874 0.5842)
					(thickness 0.1524)
				)
				(justify left)
			)
		)
		(property "Value" ""
			(at 0 0 0)
			(layer "F.Fab")
			(effects
				(font
					(size 1.27 1.27)
				)
			)
		)
		(duplicate_pad_numbers_are_jumpers no)
		(fp_line
			(start -1.38176 -1.100074)
			(end -1.38176 1.100074)
			(stroke
				(width 0.1524)
				(type default)
			)
			(layer "F.SilkS")
		)
		(fp_line
			(start -1.38176 1.100074)
			(end 1.38176 1.100074)
			(stroke
				(width 0.1524)
				(type default)
			)
			(layer "F.SilkS")
		)
		(fp_line
			(start -0.592074 -1.100074)
			(end -1.38176 -1.100074)
			(stroke
				(width 0.1524)
				(type default)
			)
			(layer "F.SilkS")
		)
		(fp_line
			(start 0 -0.508)
			(end -0.592074 -1.100074)
			(stroke
				(width 0.1524)
				(type default)
			)
			(layer "F.SilkS")
		)
		(fp_line
			(start 0.592074 -1.100074)
			(end 0 -0.508)
			(stroke
				(width 0.1524)
				(type default)
			)
			(layer "F.SilkS")
		)
		(fp_line
			(start 1.38176 -1.100074)
			(end 0.592074 -1.100074)
			(stroke
				(width 0.1524)
				(type default)
			)
			(layer "F.SilkS")
		)
		(fp_line
			(start 1.38176 1.100074)
			(end 1.38176 -1.100074)
			(stroke
				(width 0.1524)
				(type default)
			)
			(layer "F.SilkS")
		)
		(fp_poly
			(pts
				(xy -1.896618 -0.424688) (xy -1.896618 -0.865124) (xy -1.455928 -0.644906)
			)
			(stroke
				(width 0)
				(type default)
			)
			(fill yes)
			(layer "F.SilkS")
		)
		(fp_line
			(start -0.674878 -1.100074)
			(end -0.674878 1.100074)
			(stroke
				(width 0.1)
				(type default)
			)
			(layer "F.Fab")
		)
		(fp_line
			(start -0.674878 1.100074)
			(end 0.674878 1.100074)
			(stroke
				(width 0.1)
				(type default)
			)
			(layer "F.Fab")
		)
		(fp_line
			(start 0.674878 -1.100074)
			(end -0.674878 -1.100074)
			(stroke
				(width 0.1)
				(type default)
			)
			(layer "F.Fab")
		)
		(fp_line
			(start 0.674878 1.100074)
			(end 0.674878 -1.100074)
			(stroke
				(width 0.1)
				(type default)
			)
			(layer "F.Fab")
		)
		(fp_poly
			(pts
				(xy -1.9431 -0.870204) (xy -1.50241 -0.649986) (xy -1.9431 -0.429768)
			)
			(stroke
				(width 0)
				(type default)
			)
			(fill yes)
			(layer "F.Fab")
		)
		(pad "1" smd rect
			(at -0.94996 -0.649986 270)
			(size 0.4318 0.6096)
			(layers "F.Cu" "F.Mask" "F.Paste")
			(net "OCP_V3_2_PRSNT0_R_N")
		)
		(pad "2" smd rect
			(at -0.94996 0 270)
			(size 0.4318 0.6096)
			(layers "F.Cu" "F.Mask" "F.Paste")
			(net "GND")
		)
		(pad "3" smd rect
			(at -0.94996 0.649986 270)
			(size 0.4318 0.6096)
			(layers "F.Cu" "F.Mask" "F.Paste")
			(net "OCP_V3_2_PRSNT1_R_N")
		)
		(pad "4" smd rect
			(at 0.94996 0.649986 270)
			(size 0.4318 0.6096)
			(layers "F.Cu" "F.Mask" "F.Paste")
			(net "HP_LVC3_OCP_V3_2_PRSNT2_N_R")
		)
		(pad "5" smd rect
			(at 0.94996 0 270)
			(size 0.4318 0.6096)
			(layers "F.Cu" "F.Mask" "F.Paste")
			(net "P3V3_AUX")
		)
		(pad "6" smd rect
			(at 0.94996 -0.649986 270)
			(size 0.4318 0.6096)
			(layers "F.Cu" "F.Mask" "F.Paste")
			(net "HP_LVC3_OCP_V3_2_PRSNT2_N_R")
		)
	)
	(footprint ""
		(layer "F.Cu")
		(at 37.592 -359.664 90)
		(property "Reference" "PR246"
			(at 0 0 90)
			(layer "F.SilkS")
			(hide yes)
			(effects
				(font
					(size 1.27 1.27)
				)
			)
		)
		(property "Value" ""
			(at 0 0 90)
			(layer "F.Fab")
			(effects
				(font
					(size 1.27 1.27)
				)
			)
		)
		(duplicate_pad_numbers_are_jumpers no)
		(fp_line
			(start 0.7874 -0.4064)
			(end 0.7874 0.4064)
			(stroke
				(width 0.1524)
				(type default)
			)
			(layer "F.SilkS")
		)
		(fp_line
			(start -0.7874 -0.4064)
			(end 0.7874 -0.4064)
			(stroke
				(width 0.1524)
				(type default)
			)
			(layer "F.SilkS")
		)
		(fp_line
			(start 0.7874 0.4064)
			(end -0.7874 0.4064)
			(stroke
				(width 0.1524)
				(type default)
			)
			(layer "F.SilkS")
		)
		(fp_line
			(start -0.7874 0.4064)
			(end -0.7874 -0.4064)
			(stroke
				(width 0.1524)
				(type default)
			)
			(layer "F.SilkS")
		)
		(fp_line
			(start -0.12065 -0.305054)
			(end -0.12065 -0.2794)
			(stroke
				(width 0.1)
				(type default)
			)
			(layer "F.Fab")
		)
		(fp_line
			(start -0.67945 -0.305054)
			(end -0.12065 -0.305054)
			(stroke
				(width 0.1)
				(type default)
			)
			(layer "F.Fab")
		)
		(fp_line
			(start 0.67945 -0.3048)
			(end 0.67945 0.3048)
			(stroke
				(width 0.1)
				(type default)
			)
			(layer "F.Fab")
		)
		(fp_line
			(start 0.12065 -0.3048)
			(end 0.67945 -0.3048)
			(stroke
				(width 0.1)
				(type default)
			)
			(layer "F.Fab")
		)
		(fp_line
			(start 0.12065 -0.2794)
			(end 0.12065 -0.3048)
			(stroke
				(width 0.1)
				(type default)
			)
			(layer "F.Fab")
		)
		(fp_line
			(start -0.12065 -0.2794)
			(end 0.12065 -0.2794)
			(stroke
				(width 0.1)
				(type default)
			)
			(layer "F.Fab")
		)
		(fp_line
			(start 0.120396 0.2794)
			(end -0.12065 0.2794)
			(stroke
				(width 0.1)
				(type default)
			)
			(layer "F.Fab")
		)
		(fp_line
			(start -0.12065 0.2794)
			(end -0.12065 0.3048)
			(stroke
				(width 0.1)
				(type default)
			)
			(layer "F.Fab")
		)
		(fp_line
			(start 0.67945 0.3048)
			(end 0.120396 0.3048)
			(stroke
				(width 0.1)
				(type default)
			)
			(layer "F.Fab")
		)
		(fp_line
			(start 0.120396 0.3048)
			(end 0.120396 0.2794)
			(stroke
				(width 0.1)
				(type default)
			)
			(layer "F.Fab")
		)
		(fp_line
			(start -0.12065 0.3048)
			(end -0.67945 0.3048)
			(stroke
				(width 0.1)
				(type default)
			)
			(layer "F.Fab")
		)
		(fp_line
			(start -0.67945 0.3048)
			(end -0.67945 -0.305054)
			(stroke
				(width 0.1)
				(type default)
			)
			(layer "F.Fab")
		)
		(pad "1" smd circle
			(at -0.40005 0 90)
			(size 0 0)
			(layers "F.Cu" "F.Mask" "F.Paste")
			(net "VSENSE_PVDDIO_P1_DP")
		)
		(pad "2" smd circle
			(at 0.40005 0 90)
			(size 0 0)
			(layers "F.Cu" "F.Mask" "F.Paste")
			(net "VSENSE_PVDDIO_P1_VSEN1")
		)
	)
	(footprint ""
		(layer "F.Cu")
		(at 129.723896 -375.49963 -90)
		(property "Reference" "C1526"
			(at 0 0 270)
			(layer "F.SilkS")
			(hide yes)
			(effects
				(font
					(size 1.27 1.27)
				)
			)
		)
		(property "Value" ""
			(at 0 0 270)
			(layer "F.Fab")
			(effects
				(font
					(size 1.27 1.27)
				)
			)
		)
		(duplicate_pad_numbers_are_jumpers no)
		(fp_line
			(start -0.299974 0.150114)
			(end -0.299974 -0.150114)
			(stroke
				(width 0.1)
				(type default)
			)
			(layer "F.Fab")
		)
		(fp_line
			(start 0.299974 0.150114)
			(end -0.299974 0.150114)
			(stroke
				(width 0.1)
				(type default)
			)
			(layer "F.Fab")
		)
		(fp_line
			(start -0.299974 -0.150114)
			(end 0.299974 -0.150114)
			(stroke
				(width 0.1)
				(type default)
			)
			(layer "F.Fab")
		)
		(fp_line
			(start 0.299974 -0.150114)
			(end 0.299974 0.150114)
			(stroke
				(width 0.1)
				(type default)
			)
			(layer "F.Fab")
		)
		(pad "1" smd rect
			(at -0.2667 0 270)
			(size 0.3048 0.381)
			(layers "F.Cu" "F.Mask" "F.Paste")
			(net "P5E_CPU1_P3_TX_C_DN<10>")
		)
		(pad "2" smd rect
			(at 0.2667 0 270)
			(size 0.3048 0.381)
			(layers "F.Cu" "F.Mask" "F.Paste")
			(net "P5E_CPU1_P3_TX_DN<10>")
		)
	)
	(footprint ""
		(layer "F.Cu")
		(at 91.748102 -370.57203 -90)
		(property "Reference" "C722"
			(at 0 0 270)
			(layer "F.SilkS")
			(hide yes)
			(effects
				(font
					(size 1.27 1.27)
				)
			)
		)
		(property "Value" ""
			(at 0 0 270)
			(layer "F.Fab")
			(effects
				(font
					(size 1.27 1.27)
				)
			)
		)
		(duplicate_pad_numbers_are_jumpers no)
		(fp_line
			(start -0.299974 0.150114)
			(end -0.299974 -0.150114)
			(stroke
				(width 0.1)
				(type default)
			)
			(layer "F.Fab")
		)
		(fp_line
			(start 0.299974 0.150114)
			(end -0.299974 0.150114)
			(stroke
				(width 0.1)
				(type default)
			)
			(layer "F.Fab")
		)
		(fp_line
			(start -0.299974 -0.150114)
			(end 0.299974 -0.150114)
			(stroke
				(width 0.1)
				(type default)
			)
			(layer "F.Fab")
		)
		(fp_line
			(start 0.299974 -0.150114)
			(end 0.299974 0.150114)
			(stroke
				(width 0.1)
				(type default)
			)
			(layer "F.Fab")
		)
		(pad "1" smd rect
			(at -0.2667 0 270)
			(size 0.3048 0.381)
			(layers "F.Cu" "F.Mask" "F.Paste")
			(net "P5E_CPU1_P1_TX_C_DN<9>")
		)
		(pad "2" smd rect
			(at 0.2667 0 270)
			(size 0.3048 0.381)
			(layers "F.Cu" "F.Mask" "F.Paste")
			(net "P5E_CPU1_P1_TX_DN<9>")
		)
	)
	(footprint ""
		(layer "F.Cu")
		(at 250.55957 -67.254374 180)
		(property "Reference" "R4073"
			(at 0 0 180)
			(layer "F.SilkS")
			(hide yes)
			(effects
				(font
					(size 1.27 1.27)
				)
			)
		)
		(property "Value" ""
			(at 0 0 180)
			(layer "F.Fab")
			(effects
				(font
					(size 1.27 1.27)
				)
			)
		)
		(duplicate_pad_numbers_are_jumpers no)
		(fp_line
			(start 0.7874 0.4064)
			(end -0.7874 0.4064)
			(stroke
				(width 0.1524)
				(type default)
			)
			(layer "F.SilkS")
		)
		(fp_line
			(start 0.7874 -0.4064)
			(end 0.7874 0.4064)
			(stroke
				(width 0.1524)
				(type default)
			)
			(layer "F.SilkS")
		)
		(fp_line
			(start -0.7874 0.4064)
			(end -0.7874 -0.4064)
			(stroke
				(width 0.1524)
				(type default)
			)
			(layer "F.SilkS")
		)
		(fp_line
			(start -0.7874 -0.4064)
			(end 0.7874 -0.4064)
			(stroke
				(width 0.1524)
				(type default)
			)
			(layer "F.SilkS")
		)
		(fp_line
			(start 0.67945 0.3048)
			(end 0.120396 0.3048)
			(stroke
				(width 0.1)
				(type default)
			)
			(layer "F.Fab")
		)
		(fp_line
			(start 0.67945 -0.3048)
			(end 0.67945 0.3048)
			(stroke
				(width 0.1)
				(type default)
			)
			(layer "F.Fab")
		)
		(fp_line
			(start 0.12065 -0.2794)
			(end 0.12065 -0.3048)
			(stroke
				(width 0.1)
				(type default)
			)
			(layer "F.Fab")
		)
		(fp_line
			(start 0.12065 -0.3048)
			(end 0.67945 -0.3048)
			(stroke
				(width 0.1)
				(type default)
			)
			(layer "F.Fab")
		)
		(fp_line
			(start 0.120396 0.3048)
			(end 0.120396 0.2794)
			(stroke
				(width 0.1)
				(type default)
			)
			(layer "F.Fab")
		)
		(fp_line
			(start 0.120396 0.2794)
			(end -0.12065 0.2794)
			(stroke
				(width 0.1)
				(type default)
			)
			(layer "F.Fab")
		)
		(fp_line
			(start -0.12065 0.3048)
			(end -0.67945 0.3048)
			(stroke
				(width 0.1)
				(type default)
			)
			(layer "F.Fab")
		)
		(fp_line
			(start -0.12065 0.2794)
			(end -0.12065 0.3048)
			(stroke
				(width 0.1)
				(type default)
			)
			(layer "F.Fab")
		)
		(fp_line
			(start -0.12065 -0.2794)
			(end 0.12065 -0.2794)
			(stroke
				(width 0.1)
				(type default)
			)
			(layer "F.Fab")
		)
		(fp_line
			(start -0.12065 -0.305054)
			(end -0.12065 -0.2794)
			(stroke
				(width 0.1)
				(type default)
			)
			(layer "F.Fab")
		)
		(fp_line
			(start -0.67945 0.3048)
			(end -0.67945 -0.305054)
			(stroke
				(width 0.1)
				(type default)
			)
			(layer "F.Fab")
		)
		(fp_line
			(start -0.67945 -0.305054)
			(end -0.12065 -0.305054)
			(stroke
				(width 0.1)
				(type default)
			)
			(layer "F.Fab")
		)
		(pad "1" smd circle
			(at -0.40005 0 180)
			(size 0 0)
			(layers "F.Cu" "F.Mask" "F.Paste")
			(net "P12V_E1S_EN_0_R")
		)
		(pad "2" smd circle
			(at 0.40005 0 180)
			(size 0 0)
			(layers "F.Cu" "F.Mask" "F.Paste")
			(net "GND")
		)
	)
	(footprint ""
		(layer "F.Cu")
		(at 42.637964 -172.922946 180)
		(property "Reference" "R5018"
			(at 0 0 180)
			(layer "F.SilkS")
			(hide yes)
			(effects
				(font
					(size 1.27 1.27)
				)
			)
		)
		(property "Value" ""
			(at 0 0 180)
			(layer "F.Fab")
			(effects
				(font
					(size 1.27 1.27)
				)
			)
		)
		(duplicate_pad_numbers_are_jumpers no)
		(fp_line
			(start 0.7874 0.4064)
			(end -0.7874 0.4064)
			(stroke
				(width 0.1524)
				(type default)
			)
			(layer "F.SilkS")
		)
		(fp_line
			(start 0.7874 -0.4064)
			(end 0.7874 0.4064)
			(stroke
				(width 0.1524)
				(type default)
			)
			(layer "F.SilkS")
		)
		(fp_line
			(start -0.7874 0.4064)
			(end -0.7874 -0.4064)
			(stroke
				(width 0.1524)
				(type default)
			)
			(layer "F.SilkS")
		)
		(fp_line
			(start -0.7874 -0.4064)
			(end 0.7874 -0.4064)
			(stroke
				(width 0.1524)
				(type default)
			)
			(layer "F.SilkS")
		)
		(fp_line
			(start 0.67945 0.3048)
			(end 0.120396 0.3048)
			(stroke
				(width 0.1)
				(type default)
			)
			(layer "F.Fab")
		)
		(fp_line
			(start 0.67945 -0.3048)
			(end 0.67945 0.3048)
			(stroke
				(width 0.1)
				(type default)
			)
			(layer "F.Fab")
		)
		(fp_line
			(start 0.12065 -0.2794)
			(end 0.12065 -0.3048)
			(stroke
				(width 0.1)
				(type default)
			)
			(layer "F.Fab")
		)
		(fp_line
			(start 0.12065 -0.3048)
			(end 0.67945 -0.3048)
			(stroke
				(width 0.1)
				(type default)
			)
			(layer "F.Fab")
		)
		(fp_line
			(start 0.120396 0.3048)
			(end 0.120396 0.2794)
			(stroke
				(width 0.1)
				(type default)
			)
			(layer "F.Fab")
		)
		(fp_line
			(start 0.120396 0.2794)
			(end -0.12065 0.2794)
			(stroke
				(width 0.1)
				(type default)
			)
			(layer "F.Fab")
		)
		(fp_line
			(start -0.12065 0.3048)
			(end -0.67945 0.3048)
			(stroke
				(width 0.1)
				(type default)
			)
			(layer "F.Fab")
		)
		(fp_line
			(start -0.12065 0.2794)
			(end -0.12065 0.3048)
			(stroke
				(width 0.1)
				(type default)
			)
			(layer "F.Fab")
		)
		(fp_line
			(start -0.12065 -0.2794)
			(end 0.12065 -0.2794)
			(stroke
				(width 0.1)
				(type default)
			)
			(layer "F.Fab")
		)
		(fp_line
			(start -0.12065 -0.305054)
			(end -0.12065 -0.2794)
			(stroke
				(width 0.1)
				(type default)
			)
			(layer "F.Fab")
		)
		(fp_line
			(start -0.67945 0.3048)
			(end -0.67945 -0.305054)
			(stroke
				(width 0.1)
				(type default)
			)
			(layer "F.Fab")
		)
		(fp_line
			(start -0.67945 -0.305054)
			(end -0.12065 -0.305054)
			(stroke
				(width 0.1)
				(type default)
			)
			(layer "F.Fab")
		)
		(pad "1" smd circle
			(at -0.40005 0 180)
			(size 0 0)
			(layers "F.Cu" "F.Mask" "F.Paste")
			(net "PVDD11_S3_P1")
		)
		(pad "2" smd circle
			(at 0.40005 0 180)
			(size 0 0)
			(layers "F.Cu" "F.Mask" "F.Paste")
			(net "I3C_SCM_2_R_SCL")
		)
	)
	(footprint ""
		(layer "F.Cu")
		(at 249.765312 -54.440582 -90)
		(property "Reference" "PR3957"
			(at 0 0 270)
			(layer "F.SilkS")
			(hide yes)
			(effects
				(font
					(size 1.27 1.27)
				)
			)
		)
		(property "Value" ""
			(at 0 0 270)
			(layer "F.Fab")
			(effects
				(font
					(size 1.27 1.27)
				)
			)
		)
		(duplicate_pad_numbers_are_jumpers no)
		(fp_line
			(start -1.2954 0.5842)
			(end -1.2954 -0.5842)
			(stroke
				(width 0.1524)
				(type default)
			)
			(layer "F.SilkS")
		)
		(fp_line
			(start 1.2954 0.5842)
			(end -1.2954 0.5842)
			(stroke
				(width 0.1524)
				(type default)
			)
			(layer "F.SilkS")
		)
		(fp_line
			(start -1.2954 -0.5842)
			(end 1.2954 -0.5842)
			(stroke
				(width 0.1524)
				(type default)
			)
			(layer "F.SilkS")
		)
		(fp_line
			(start 1.2954 -0.5842)
			(end 1.2954 0.5842)
			(stroke
				(width 0.1524)
				(type default)
			)
			(layer "F.SilkS")
		)
		(fp_line
			(start -0.8636 0.4572)
			(end -0.8636 0.4318)
			(stroke
				(width 0.1)
				(type default)
			)
			(layer "F.Fab")
		)
		(fp_line
			(start 0.8636 0.4572)
			(end -0.8636 0.4572)
			(stroke
				(width 0.1)
				(type default)
			)
			(layer "F.Fab")
		)
		(fp_line
			(start -0.8636 0.4318)
			(end -0.8636 0.4064)
			(stroke
				(width 0.1)
				(type default)
			)
			(layer "F.Fab")
		)
		(fp_line
			(start -1.1938 0.4064)
			(end -1.1938 -0.406654)
			(stroke
				(width 0.1)
				(type default)
			)
			(layer "F.Fab")
		)
		(fp_line
			(start -0.8636 0.4064)
			(end -1.1938 0.4064)
			(stroke
				(width 0.1)
				(type default)
			)
			(layer "F.Fab")
		)
		(fp_line
			(start 0.8636 0.4064)
			(end 0.8636 0.4572)
			(stroke
				(width 0.1)
				(type default)
			)
			(layer "F.Fab")
		)
		(fp_line
			(start 1.1938 0.4064)
			(end 0.8636 0.4064)
			(stroke
				(width 0.1)
				(type default)
			)
			(layer "F.Fab")
		)
		(fp_line
			(start -1.1938 -0.406654)
			(end -0.8636 -0.406654)
			(stroke
				(width 0.1)
				(type default)
			)
			(layer "F.Fab")
		)
		(fp_line
			(start -0.8636 -0.406654)
			(end -0.8636 -0.4572)
			(stroke
				(width 0.1)
				(type default)
			)
			(layer "F.Fab")
		)
		(fp_line
			(start 0.8636 -0.406654)
			(end 1.1938 -0.406654)
			(stroke
				(width 0.1)
				(type default)
			)
			(layer "F.Fab")
		)
		(fp_line
			(start 1.1938 -0.406654)
			(end 1.1938 0.4064)
			(stroke
				(width 0.1)
				(type default)
			)
			(layer "F.Fab")
		)
		(fp_line
			(start -0.8636 -0.4572)
			(end 0.8636 -0.4572)
			(stroke
				(width 0.1)
				(type default)
			)
			(layer "F.Fab")
		)
		(fp_line
			(start 0.8636 -0.4572)
			(end 0.8636 -0.406654)
			(stroke
				(width 0.1)
				(type default)
			)
			(layer "F.Fab")
		)
		(pad "1" smd rect
			(at -0.7366 0 180)
			(size 0.7112 0.8128)
			(layers "F.Cu" "F.Mask" "F.Paste")
			(net "P12V_AUX")
		)
		(pad "2" smd rect
			(at 0.7366 0 180)
			(size 0.7112 0.8128)
			(layers "F.Cu" "F.Mask" "F.Paste")
			(net "P12V_E1S_AVIN_PD_0")
		)
	)
	(footprint ""
		(layer "F.Cu")
		(at 111.927894 -258.880356 180)
		(property "Reference" "U26"
			(at -45.05579 -61.794136 0)
			(unlocked yes)
			(layer "F.SilkS")
			(effects
				(font
					(size 0.7874 0.5842)
					(thickness 0.1524)
				)
			)
		)
		(property "Value" ""
			(at 0 0 180)
			(layer "F.Fab")
			(effects
				(font
					(size 1.27 1.27)
				)
			)
		)
		(duplicate_pad_numbers_are_jumpers no)
		(fp_line
			(start 46.699932 95.149924)
			(end 39.814754 95.149924)
			(stroke
				(width 0.1524)
				(type default)
			)
			(layer "F.SilkS")
		)
		(fp_line
			(start 46.699932 89.086944)
			(end 46.699932 95.149924)
			(stroke
				(width 0.1524)
				(type default)
			)
			(layer "F.SilkS")
		)
		(fp_line
			(start 46.699932 84.344764)
			(end 46.699932 86.925404)
			(stroke
				(width 0.1524)
				(type default)
			)
			(layer "F.SilkS")
		)
		(fp_line
			(start 46.699932 60.149994)
			(end -6.436106 60.149994)
			(stroke
				(width 0.1524)
				(type default)
			)
			(layer "F.SilkS")
		)
		(fp_line
			(start 46.699932 51.939444)
			(end 46.699932 72.698864)
			(stroke
				(width 0.1524)
				(type default)
			)
			(layer "F.SilkS")
		)
		(fp_line
			(start 46.699932 43.405044)
			(end 46.699932 49.297844)
			(stroke
				(width 0.1524)
				(type default)
			)
			(layer "F.SilkS")
		)
		(fp_line
			(start 46.699932 34.667444)
			(end 46.699932 39.671244)
			(stroke
				(width 0.1524)
				(type default)
			)
			(layer "F.SilkS")
		)
		(fp_line
			(start 46.699932 23.999444)
			(end 46.699932 27.936444)
			(stroke
				(width 0.1524)
				(type default)
			)
			(layer "F.SilkS")
		)
		(fp_line
			(start 46.699932 15.617444)
			(end 46.699932 19.808444)
			(stroke
				(width 0.1524)
				(type default)
			)
			(layer "F.SilkS")
		)
		(fp_line
			(start 46.699932 -1.933956)
			(end 46.699932 11.477244)
			(stroke
				(width 0.1524)
				(type default)
			)
			(layer "F.SilkS")
		)
		(fp_line
			(start 46.699932 -11.687556)
			(end 46.699932 -3.483356)
			(stroke
				(width 0.1524)
				(type default)
			)
			(layer "F.SilkS")
		)
		(fp_line
			(start 46.699932 -21.034756)
			(end 46.699932 -16.437356)
			(stroke
				(width 0.1524)
				(type default)
			)
			(layer "F.SilkS")
		)
		(fp_line
			(start 46.699932 -28.680156)
			(end 46.699932 -25.428956)
			(stroke
				(width 0.1524)
				(type default)
			)
			(layer "F.SilkS")
		)
		(fp_line
			(start 46.699932 -42.802556)
			(end 46.699932 -38.560756)
			(stroke
				(width 0.1524)
				(type default)
			)
			(layer "F.SilkS")
		)
		(fp_line
			(start 46.699932 -51.082956)
			(end 46.699932 -46.968156)
			(stroke
				(width 0.1524)
				(type default)
			)
			(layer "F.SilkS")
		)
		(fp_line
			(start 46.699932 -60.300108)
			(end 46.699932 -54.537356)
			(stroke
				(width 0.1524)
				(type default)
			)
			(layer "F.SilkS")
		)
		(fp_line
			(start 35.999928 37.69995)
			(end 14.798294 37.69995)
			(stroke
				(width 0.1524)
				(type default)
			)
			(layer "F.SilkS")
		)
		(fp_line
			(start 35.999928 33.473644)
			(end 35.999928 37.69995)
			(stroke
				(width 0.1524)
				(type default)
			)
			(layer "F.SilkS")
		)
		(fp_line
			(start 35.999928 27.834844)
			(end 35.999928 30.959044)
			(stroke
				(width 0.1524)
				(type default)
			)
			(layer "F.SilkS")
		)
		(fp_line
			(start 35.999928 22.932644)
			(end 35.999928 25.955244)
			(stroke
				(width 0.1524)
				(type default)
			)
			(layer "F.SilkS")
		)
		(fp_line
			(start 35.999928 18.132044)
			(end 35.999928 21.053044)
			(stroke
				(width 0.1524)
				(type default)
			)
			(layer "F.SilkS")
		)
		(fp_line
			(start 35.999928 13.407644)
			(end 35.999928 16.074644)
			(stroke
				(width 0.1524)
				(type default)
			)
			(layer "F.SilkS")
		)
		(fp_line
			(start 35.999928 -0.613156)
			(end 35.999928 11.426444)
			(stroke
				(width 0.1524)
				(type default)
			)
			(layer "F.SilkS")
		)
		(fp_line
			(start 35.999928 -10.646156)
			(end 35.999928 -1.908556)
			(stroke
				(width 0.1524)
				(type default)
			)
			(layer "F.SilkS")
		)
		(fp_line
			(start 35.999928 -15.497556)
			(end 35.999928 -12.779756)
			(stroke
				(width 0.1524)
				(type default)
			)
			(layer "F.SilkS")
		)
		(fp_line
			(start 35.999928 -20.348956)
			(end 35.999928 -17.453356)
			(stroke
				(width 0.1524)
				(type default)
			)
			(layer "F.SilkS")
		)
		(fp_line
			(start 35.999928 -25.174956)
			(end 35.999928 -22.177756)
			(stroke
				(width 0.1524)
				(type default)
			)
			(layer "F.SilkS")
		)
		(fp_line
			(start 35.999928 -30.762956)
			(end 35.999928 -27.181556)
			(stroke
				(width 0.1524)
				(type default)
			)
			(layer "F.SilkS")
		)
		(fp_line
			(start 35.999928 -37.69995)
			(end 35.999928 -33.099756)
			(stroke
				(width 0.1524)
				(type default)
			)
			(layer "F.SilkS")
		)
		(fp_line
			(start 27.500072 -40.999918)
			(end 27.500072 -37.69995)
			(stroke
				(width 0.1524)
				(type default)
			)
			(layer "F.SilkS")
		)
		(fp_line
			(start 26.049986 40.999918)
			(end 26.049986 37.69995)
			(stroke
				(width 0.1524)
				(type default)
			)
			(layer "F.SilkS")
		)
		(fp_line
			(start 23.999952 -41.500044)
			(end 26.999946 -41.500044)
			(stroke
				(width 0.1524)
				(type default)
			)
			(layer "F.SilkS")
		)
		(fp_line
			(start 23.50008 -37.69995)
			(end 23.50008 -40.999918)
			(stroke
				(width 0.1524)
				(type default)
			)
			(layer "F.SilkS")
		)
		(fp_line
			(start 22.55012 41.500044)
			(end 25.550114 41.500044)
			(stroke
				(width 0.1524)
				(type default)
			)
			(layer "F.SilkS")
		)
		(fp_line
			(start 22.049994 37.69995)
			(end 22.049994 40.999918)
			(stroke
				(width 0.1524)
				(type default)
			)
			(layer "F.SilkS")
		)
		(fp_line
			(start 17.958054 95.149924)
			(end -12.532106 95.149924)
			(stroke
				(width 0.1524)
				(type default)
			)
			(layer "F.SilkS")
		)
		(fp_line
			(start 13.223494 37.69995)
			(end 6.467094 37.69995)
			(stroke
				(width 0.1524)
				(type default)
			)
			(layer "F.SilkS")
		)
		(fp_line
			(start 9.108694 -37.69995)
			(end 35.999928 -37.69995)
			(stroke
				(width 0.1524)
				(type default)
			)
			(layer "F.SilkS")
		)
		(fp_line
			(start 7.050024 3.999992)
			(end -7.050024 3.999992)
			(stroke
				(width 0.1524)
				(type default)
			)
			(layer "F.SilkS")
		)
		(fp_line
			(start 7.050024 -3.999992)
			(end 7.050024 3.999992)
			(stroke
				(width 0.1524)
				(type default)
			)
			(layer "F.SilkS")
		)
		(fp_line
			(start 6.365494 -37.69995)
			(end 8.143494 -37.69995)
			(stroke
				(width 0.1524)
				(type default)
			)
			(layer "F.SilkS")
		)
		(fp_line
			(start 3.571494 -37.69995)
			(end 5.349494 -37.69995)
			(stroke
				(width 0.1524)
				(type default)
			)
			(layer "F.SilkS")
		)
		(fp_line
			(start 1.844294 37.69995)
			(end -35.999928 37.69995)
			(stroke
				(width 0.1524)
				(type default)
			)
			(layer "F.SilkS")
		)
		(fp_line
			(start 1.158494 -37.69995)
			(end 2.352294 -37.69995)
			(stroke
				(width 0.1524)
				(type default)
			)
			(layer "F.SilkS")
		)
		(fp_line
			(start -7.050024 3.999992)
			(end -7.050024 -3.999992)
			(stroke
				(width 0.1524)
				(type default)
			)
			(layer "F.SilkS")
		)
		(fp_line
			(start -7.050024 -3.999992)
			(end 7.050024 -3.999992)
			(stroke
				(width 0.1524)
				(type default)
			)
			(layer "F.SilkS")
		)
		(fp_line
			(start -14.665706 60.149994)
			(end -46.699932 60.149994)
			(stroke
				(width 0.1524)
				(type default)
			)
			(layer "F.SilkS")
		)
		(fp_line
			(start -16.215106 -37.69995)
			(end -0.263906 -37.69995)
			(stroke
				(width 0.1524)
				(type default)
			)
			(layer "F.SilkS")
		)
		(fp_line
			(start -16.621506 95.149924)
			(end -41.615106 95.149924)
			(stroke
				(width 0.1524)
				(type default)
			)
			(layer "F.SilkS")
		)
		(fp_line
			(start -22.049994 37.69995)
			(end -22.049994 40.999918)
			(stroke
				(width 0.1524)
				(type default)
			)
			(layer "F.SilkS")
		)
		(fp_line
			(start -22.55012 41.500044)
			(end -25.550114 41.500044)
			(stroke
				(width 0.1524)
				(type default)
			)
			(layer "F.SilkS")
		)
		(fp_line
			(start -23.50008 -40.999918)
			(end -23.50008 -37.69995)
			(stroke
				(width 0.1524)
				(type default)
			)
			(layer "F.SilkS")
		)
		(fp_line
			(start -23.631906 -37.69995)
			(end -17.993106 -37.69995)
			(stroke
				(width 0.1524)
				(type default)
			)
			(layer "F.SilkS")
		)
		(fp_line
			(start -24.216106 -41.500044)
			(end -23.999952 -41.500044)
			(stroke
				(width 0.1524)
				(type default)
			)
			(layer "F.SilkS")
		)
		(fp_line
			(start -26.049986 40.999918)
			(end -26.049986 37.69995)
			(stroke
				(width 0.1524)
				(type default)
			)
			(layer "F.SilkS")
		)
		(fp_line
			(start -26.527506 -37.69995)
			(end -25.689306 -37.69995)
			(stroke
				(width 0.1524)
				(type default)
			)
			(layer "F.SilkS")
		)
		(fp_line
			(start -27.500072 -37.69995)
			(end -27.500072 -40.999918)
			(stroke
				(width 0.1524)
				(type default)
			)
			(layer "F.SilkS")
		)
		(fp_line
			(start -29.296106 -37.69995)
			(end -28.483306 -37.69995)
			(stroke
				(width 0.1524)
				(type default)
			)
			(layer "F.SilkS")
		)
		(fp_line
			(start -35.999928 37.69995)
			(end -35.999928 33.067244)
			(stroke
				(width 0.1524)
				(type default)
			)
			(layer "F.SilkS")
		)
		(fp_line
			(start -35.999928 31.213044)
			(end -35.999928 27.987244)
			(stroke
				(width 0.1524)
				(type default)
			)
			(layer "F.SilkS")
		)
		(fp_line
			(start -35.999928 26.285444)
			(end -35.999928 22.831044)
			(stroke
				(width 0.1524)
				(type default)
			)
			(layer "F.SilkS")
		)
		(fp_line
			(start -35.999928 21.129244)
			(end -35.999928 18.309844)
			(stroke
				(width 0.1524)
				(type default)
			)
			(layer "F.SilkS")
		)
		(fp_line
			(start -35.999928 16.404844)
			(end -35.999928 13.229844)
			(stroke
				(width 0.1524)
				(type default)
			)
			(layer "F.SilkS")
		)
		(fp_line
			(start -35.999928 11.426444)
			(end -35.999928 -1.552956)
			(stroke
				(width 0.1524)
				(type default)
			)
			(layer "F.SilkS")
		)
		(fp_line
			(start -35.999928 -2.721356)
			(end -35.999928 -10.823956)
			(stroke
				(width 0.1524)
				(type default)
			)
			(layer "F.SilkS")
		)
		(fp_line
			(start -35.999928 -12.703556)
			(end -35.999928 -15.319756)
			(stroke
				(width 0.1524)
				(type default)
			)
			(layer "F.SilkS")
		)
		(fp_line
			(start -35.999928 -17.300956)
			(end -35.999928 -20.298156)
			(stroke
				(width 0.1524)
				(type default)
			)
			(layer "F.SilkS")
		)
		(fp_line
			(start -35.999928 -22.253956)
			(end -35.999928 -25.124156)
			(stroke
				(width 0.1524)
				(type default)
			)
			(layer "F.SilkS")
		)
		(fp_line
			(start -35.999928 -27.511756)
			(end -35.999928 -31.194756)
			(stroke
				(width 0.1524)
				(type default)
			)
			(layer "F.SilkS")
		)
		(fp_line
			(start -35.999928 -33.810956)
			(end -35.999928 -37.69995)
			(stroke
				(width 0.1524)
				(type default)
			)
			(layer "F.SilkS")
		)
		(fp_line
			(start -35.999928 -37.69995)
			(end -30.464506 -37.69995)
			(stroke
				(width 0.1524)
				(type default)
			)
			(layer "F.SilkS")
		)
		(fp_line
			(start -43.647106 95.149924)
			(end -46.699932 95.149924)
			(stroke
				(width 0.1524)
				(type default)
			)
			(layer "F.SilkS")
		)
		(fp_line
			(start -46.699932 95.149924)
			(end -46.699932 60.149994)
			(stroke
				(width 0.1524)
				(type default)
			)
			(layer "F.SilkS")
		)
		(fp_line
			(start -46.699932 60.149994)
			(end -46.699932 -60.300108)
			(stroke
				(width 0.1524)
				(type default)
			)
			(layer "F.SilkS")
		)
		(fp_line
			(start -46.699932 -60.300108)
			(end 46.699932 -60.300108)
			(stroke
				(width 0.1524)
				(type default)
			)
			(layer "F.SilkS")
		)
		(fp_arc
			(start 26.999946 -41.500044)
			(mid 27.353606 -41.353575)
			(end 27.500072 -40.999918)
			(stroke
				(width 0.1524)
				(type default)
			)
			(layer "F.SilkS")
		)
		(fp_arc
			(start 26.049986 40.999918)
			(mid 25.903658 41.353534)
			(end 25.550114 41.500044)
			(stroke
				(width 0.1524)
				(type default)
			)
			(layer "F.SilkS")
		)
		(fp_arc
			(start 23.50008 -40.999918)
			(mid 23.646461 -41.353491)
			(end 23.999952 -41.500044)
			(stroke
				(width 0.1524)
				(type default)
			)
			(layer "F.SilkS")
		)
		(fp_arc
			(start 22.55012 41.500044)
			(mid 22.19647 41.353568)
			(end 22.049994 40.999918)
			(stroke
				(width 0.1524)
				(type default)
			)
			(layer "F.SilkS")
		)
		(fp_arc
			(start -22.049994 40.999918)
			(mid -22.196411 41.353631)
			(end -22.55012 41.500044)
			(stroke
				(width 0.1524)
				(type default)
			)
			(layer "F.SilkS")
		)
		(fp_arc
			(start -23.999952 -41.500044)
			(mid -23.646364 -41.353562)
			(end -23.50008 -40.999918)
			(stroke
				(width 0.1524)
				(type default)
			)
			(layer "F.SilkS")
		)
		(fp_arc
			(start -25.550114 41.500044)
			(mid -25.903613 41.353485)
			(end -26.049986 40.999918)
			(stroke
				(width 0.1524)
				(type default)
			)
			(layer "F.SilkS")
		)
		(fp_arc
			(start -27.500072 -40.999918)
			(mid -27.444343 -41.229467)
			(end -27.289506 -41.407842)
			(stroke
				(width 0.1524)
				(type default)
			)
			(layer "F.SilkS")
		)
		(fp_poly
			(pts
				(xy -36.761928 -35.189922) (xy -36.761928 -38.46195) (xy -33.219898 -38.46195) (xy -33.219898 -37.69995)
				(xy -35.999928 -37.69995) (xy -35.999928 -35.189922)
			)
			(stroke
				(width 0)
				(type default)
			)
			(fill yes)
			(layer "F.SilkS")
		)
		(fp_line
			(start 49.800002 5.500116)
			(end 49.800002 -5.500116)
			(stroke
				(width 0.1524)
				(type default)
			)
			(layer "B.SilkS")
		)
		(fp_line
			(start 49.800002 -5.500116)
			(end 46.699932 -8.50011)
			(stroke
				(width 0.1524)
				(type default)
			)
			(layer "B.SilkS")
		)
		(fp_line
			(start 46.699932 50.500026)
			(end 46.699932 8.50011)
			(stroke
				(width 0.1524)
				(type default)
			)
			(layer "B.SilkS")
		)
		(fp_line
			(start 46.699932 8.50011)
			(end 49.800002 5.500116)
			(stroke
				(width 0.1524)
				(type default)
			)
			(layer "B.SilkS")
		)
		(fp_line
			(start 46.699932 -8.50011)
			(end 46.699932 -50.500026)
			(stroke
				(width 0.1524)
				(type default)
			)
			(layer "B.SilkS")
		)
		(fp_line
			(start 26.45791 52.999894)
			(end 44.200064 52.999894)
			(stroke
				(width 0.1524)
				(type default)
			)
			(layer "B.SilkS")
		)
		(fp_line
			(start 26.45791 -52.999894)
			(end 44.200064 -52.999894)
			(stroke
				(width 0.1524)
				(type default)
			)
			(layer "B.SilkS")
		)
		(fp_line
			(start 22.900894 43.15206)
			(end 23.981918 50.848006)
			(stroke
				(width 0.1524)
				(type default)
			)
			(layer "B.SilkS")
		)
		(fp_line
			(start 22.900894 -43.15206)
			(end 23.981918 -50.848006)
			(stroke
				(width 0.1524)
				(type default)
			)
			(layer "B.SilkS")
		)
		(fp_line
			(start 20.424902 40.999918)
			(end -20.424902 40.999918)
			(stroke
				(width 0.1524)
				(type default)
			)
			(layer "B.SilkS")
		)
		(fp_line
			(start 20.424902 -40.999918)
			(end 7.305294 -40.999918)
			(stroke
				(width 0.1524)
				(type default)
			)
			(layer "B.SilkS")
		)
		(fp_line
			(start 14.500098 -11.500104)
			(end 14.500098 11.500104)
			(stroke
				(width 0.1524)
				(type default)
			)
			(layer "B.SilkS")
		)
		(fp_line
			(start 2.479294 -40.999918)
			(end -14.691106 -40.999918)
			(stroke
				(width 0.1524)
				(type default)
			)
			(layer "B.SilkS")
		)
		(fp_line
			(start -11.999976 13.999972)
			(end 11.999976 13.999972)
			(stroke
				(width 0.1524)
				(type default)
			)
			(layer "B.SilkS")
		)
		(fp_line
			(start -11.999976 -13.999972)
			(end 11.999976 -13.999972)
			(stroke
				(width 0.1524)
				(type default)
			)
			(layer "B.SilkS")
		)
		(fp_line
			(start -14.500098 11.500104)
			(end -14.500098 -11.500104)
			(stroke
				(width 0.1524)
				(type default)
			)
			(layer "B.SilkS")
		)
		(fp_line
			(start -16.951706 -40.999918)
			(end -20.424902 -40.999918)
			(stroke
				(width 0.1524)
				(type default)
			)
			(layer "B.SilkS")
		)
		(fp_line
			(start -22.900894 43.15206)
			(end -23.981918 50.848006)
			(stroke
				(width 0.1524)
				(type default)
			)
			(layer "B.SilkS")
		)
		(fp_line
			(start -22.900894 -43.15206)
			(end -23.981918 -50.848006)
			(stroke
				(width 0.1524)
				(type default)
			)
			(layer "B.SilkS")
		)
		(fp_line
			(start -26.45791 52.999894)
			(end -44.200064 52.999894)
			(stroke
				(width 0.1524)
				(type default)
			)
			(layer "B.SilkS")
		)
		(fp_line
			(start -26.45791 -52.999894)
			(end -44.200064 -52.999894)
			(stroke
				(width 0.1524)
				(type default)
			)
			(layer "B.SilkS")
		)
		(fp_line
			(start -46.699932 8.50011)
			(end -46.699932 50.500026)
			(stroke
				(width 0.1524)
				(type default)
			)
			(layer "B.SilkS")
		)
		(fp_line
			(start -46.699932 -8.50011)
			(end -49.800002 -5.500116)
			(stroke
				(width 0.1524)
				(type default)
			)
			(layer "B.SilkS")
		)
		(fp_line
			(start -46.699932 -50.500026)
			(end -46.699932 -8.50011)
			(stroke
				(width 0.1524)
				(type default)
			)
			(layer "B.SilkS")
		)
		(fp_line
			(start -49.800002 5.500116)
			(end -46.699932 8.50011)
			(stroke
				(width 0.1524)
				(type default)
			)
			(layer "B.SilkS")
		)
		(fp_line
			(start -49.800002 -5.500116)
			(end -49.800002 5.500116)
			(stroke
				(width 0.1524)
				(type default)
			)
			(layer "B.SilkS")
		)
		(fp_arc
			(start 46.699932 50.500026)
			(mid 45.967742 52.267701)
			(end 44.200064 52.999894)
			(stroke
				(width 0.1524)
				(type default)
			)
			(layer "B.SilkS")
		)
		(fp_arc
			(start 44.200064 -52.999894)
			(mid 45.967746 -52.267708)
			(end 46.699932 -50.500026)
			(stroke
				(width 0.1524)
				(type default)
			)
			(layer "B.SilkS")
		)
		(fp_arc
			(start 26.45791 52.999894)
			(mid 24.817647 52.386804)
			(end 23.981918 50.848006)
			(stroke
				(width 0.1524)
				(type default)
			)
			(layer "B.SilkS")
		)
		(fp_arc
			(start 23.981918 -50.848006)
			(mid 24.817643 -52.386811)
			(end 26.45791 -52.999894)
			(stroke
				(width 0.1524)
				(type default)
			)
			(layer "B.SilkS")
		)
		(fp_arc
			(start 22.900894 -43.15206)
			(mid 22.065263 -41.613081)
			(end 20.424902 -40.999918)
			(stroke
				(width 0.1524)
				(type default)
			)
			(layer "B.SilkS")
		)
		(fp_arc
			(start 20.424902 40.999918)
			(mid 22.065239 41.613101)
			(end 22.900894 43.15206)
			(stroke
				(width 0.1524)
				(type default)
			)
			(layer "B.SilkS")
		)
		(fp_arc
			(start 14.500098 11.500104)
			(mid 13.767736 13.267783)
			(end 11.999976 13.999972)
			(stroke
				(width 0.1524)
				(type default)
			)
			(layer "B.SilkS")
		)
		(fp_arc
			(start 11.999976 -13.999972)
			(mid 13.767749 -13.267799)
			(end 14.500098 -11.500104)
			(stroke
				(width 0.1524)
				(type default)
			)
			(layer "B.SilkS")
		)
		(fp_arc
			(start -11.999976 13.999972)
			(mid -13.767761 13.267804)
			(end -14.500098 11.500104)
			(stroke
				(width 0.1524)
				(type default)
			)
			(layer "B.SilkS")
		)
		(fp_arc
			(start -14.500098 -11.500104)
			(mid -13.76774 -13.267786)
			(end -11.999976 -13.999972)
			(stroke
				(width 0.1524)
				(type default)
			)
			(layer "B.SilkS")
		)
		(fp_arc
			(start -20.424902 -40.999918)
			(mid -22.06525 -41.613096)
			(end -22.900894 -43.15206)
			(stroke
				(width 0.1524)
				(type default)
			)
			(layer "B.SilkS")
		)
		(fp_arc
			(start -22.900894 43.15206)
			(mid -22.065265 41.613079)
			(end -20.424902 40.999918)
			(stroke
				(width 0.1524)
				(type default)
			)
			(layer "B.SilkS")
		)
		(fp_arc
			(start -23.981918 50.848006)
			(mid -24.817625 52.386829)
			(end -26.45791 52.999894)
			(stroke
				(width 0.1524)
				(type default)
			)
			(layer "B.SilkS")
		)
		(fp_arc
			(start -26.45791 -52.999894)
			(mid -24.817657 -52.386799)
			(end -23.981918 -50.848006)
			(stroke
				(width 0.1524)
				(type default)
			)
			(layer "B.SilkS")
		)
		(fp_arc
			(start -44.200064 52.999894)
			(mid -45.967758 52.267713)
			(end -46.699932 50.500026)
			(stroke
				(width 0.1524)
				(type default)
			)
			(layer "B.SilkS")
		)
		(fp_arc
			(start -46.699932 -50.500026)
			(mid -45.967746 -52.267704)
			(end -44.200064 -52.999894)
			(stroke
				(width 0.1524)
				(type default)
			)
			(layer "B.SilkS")
		)
		(fp_line
			(start 49.800002 5.500116)
			(end 49.800002 -5.500116)
			(stroke
				(width 0.1)
				(type default)
			)
			(layer "B.Fab")
		)
		(fp_line
			(start 49.800002 -5.500116)
			(end 46.699932 -8.50011)
			(stroke
				(width 0.1)
				(type default)
			)
			(layer "B.Fab")
		)
		(fp_line
			(start 46.699932 50.500026)
			(end 46.699932 8.50011)
			(stroke
				(width 0.1)
				(type default)
			)
			(layer "B.Fab")
		)
		(fp_line
			(start 46.699932 8.50011)
			(end 49.800002 5.500116)
			(stroke
				(width 0.1)
				(type default)
			)
			(layer "B.Fab")
		)
		(fp_line
			(start 46.699932 -8.50011)
			(end 46.699932 -50.500026)
			(stroke
				(width 0.1)
				(type default)
			)
			(layer "B.Fab")
		)
		(fp_line
			(start 26.45791 52.999894)
			(end 44.200064 52.999894)
			(stroke
				(width 0.1)
				(type default)
			)
			(layer "B.Fab")
		)
		(fp_line
			(start 26.45791 -52.999894)
			(end 44.200064 -52.999894)
			(stroke
				(width 0.1)
				(type default)
			)
			(layer "B.Fab")
		)
		(fp_line
			(start 22.900894 43.15206)
			(end 23.981918 50.848006)
			(stroke
				(width 0.1)
				(type default)
			)
			(layer "B.Fab")
		)
		(fp_line
			(start 22.900894 -43.15206)
			(end 23.981918 -50.848006)
			(stroke
				(width 0.1)
				(type default)
			)
			(layer "B.Fab")
		)
		(fp_line
			(start 20.424902 40.999918)
			(end -20.424902 40.999918)
			(stroke
				(width 0.1)
				(type default)
			)
			(layer "B.Fab")
		)
		(fp_line
			(start 20.424902 -40.999918)
			(end -20.424902 -40.999918)
			(stroke
				(width 0.1)
				(type default)
			)
			(layer "B.Fab")
		)
		(fp_line
			(start 14.500098 -11.500104)
			(end 14.500098 11.500104)
			(stroke
				(width 0.1)
				(type default)
			)
			(layer "B.Fab")
		)
		(fp_line
			(start -11.999976 13.999972)
			(end 11.999976 13.999972)
			(stroke
				(width 0.1)
				(type default)
			)
			(layer "B.Fab")
		)
		(fp_line
			(start -11.999976 -13.999972)
			(end 11.999976 -13.999972)
			(stroke
				(width 0.1)
				(type default)
			)
			(layer "B.Fab")
		)
		(fp_line
			(start -14.500098 11.500104)
			(end -14.500098 -11.500104)
			(stroke
				(width 0.1)
				(type default)
			)
			(layer "B.Fab")
		)
		(fp_line
			(start -22.900894 43.15206)
			(end -23.981918 50.848006)
			(stroke
				(width 0.1)
				(type default)
			)
			(layer "B.Fab")
		)
		(fp_line
			(start -22.900894 -43.15206)
			(end -23.981918 -50.848006)
			(stroke
				(width 0.1)
				(type default)
			)
			(layer "B.Fab")
		)
		(fp_line
			(start -26.45791 52.999894)
			(end -44.200064 52.999894)
			(stroke
				(width 0.1)
				(type default)
			)
			(layer "B.Fab")
		)
		(fp_line
			(start -26.45791 -52.999894)
			(end -44.200064 -52.999894)
			(stroke
				(width 0.1)
				(type default)
			)
			(layer "B.Fab")
		)
		(fp_line
			(start -46.699932 8.50011)
			(end -46.699932 50.500026)
			(stroke
				(width 0.1)
				(type default)
			)
			(layer "B.Fab")
		)
		(fp_line
			(start -46.699932 -8.50011)
			(end -49.800002 -5.500116)
			(stroke
				(width 0.1)
				(type default)
			)
			(layer "B.Fab")
		)
		(fp_line
			(start -46.699932 -50.500026)
			(end -46.699932 -8.50011)
			(stroke
				(width 0.1)
				(type default)
			)
			(layer "B.Fab")
		)
		(fp_line
			(start -49.800002 5.500116)
			(end -46.699932 8.50011)
			(stroke
				(width 0.1)
				(type default)
			)
			(layer "B.Fab")
		)
		(fp_line
			(start -49.800002 -5.500116)
			(end -49.800002 5.500116)
			(stroke
				(width 0.1)
				(type default)
			)
			(layer "B.Fab")
		)
		(fp_arc
			(start 46.699932 50.500026)
			(mid 45.967742 52.267701)
			(end 44.200064 52.999894)
			(stroke
				(width 0.1)
				(type default)
			)
			(layer "B.Fab")
		)
		(fp_arc
			(start 44.200064 -52.999894)
			(mid 45.967746 -52.267708)
			(end 46.699932 -50.500026)
			(stroke
				(width 0.1)
				(type default)
			)
			(layer "B.Fab")
		)
		(fp_arc
			(start 26.45791 52.999894)
			(mid 24.817647 52.386804)
			(end 23.981918 50.848006)
			(stroke
				(width 0.1)
				(type default)
			)
			(layer "B.Fab")
		)
		(fp_arc
			(start 23.981918 -50.848006)
			(mid 24.817643 -52.386811)
			(end 26.45791 -52.999894)
			(stroke
				(width 0.1)
				(type default)
			)
			(layer "B.Fab")
		)
		(fp_arc
			(start 22.900894 -43.15206)
			(mid 22.065263 -41.613081)
			(end 20.424902 -40.999918)
			(stroke
				(width 0.1)
				(type default)
			)
			(layer "B.Fab")
		)
		(fp_arc
			(start 20.424902 40.999918)
			(mid 22.065239 41.613101)
			(end 22.900894 43.15206)
			(stroke
				(width 0.1)
				(type default)
			)
			(layer "B.Fab")
		)
		(fp_arc
			(start 14.500098 11.500104)
			(mid 13.767736 13.267783)
			(end 11.999976 13.999972)
			(stroke
				(width 0.1)
				(type default)
			)
			(layer "B.Fab")
		)
		(fp_arc
			(start 11.999976 -13.999972)
			(mid 13.767749 -13.267799)
			(end 14.500098 -11.500104)
			(stroke
				(width 0.1)
				(type default)
			)
			(layer "B.Fab")
		)
		(fp_arc
			(start -11.999976 13.999972)
			(mid -13.767761 13.267804)
			(end -14.500098 11.500104)
			(stroke
				(width 0.1)
				(type default)
			)
			(layer "B.Fab")
		)
		(fp_arc
			(start -14.500098 -11.500104)
			(mid -13.76774 -13.267786)
			(end -11.999976 -13.999972)
			(stroke
				(width 0.1)
				(type default)
			)
			(layer "B.Fab")
		)
		(fp_arc
			(start -20.424902 -40.999918)
			(mid -22.06525 -41.613096)
			(end -22.900894 -43.15206)
			(stroke
				(width 0.1)
				(type default)
			)
			(layer "B.Fab")
		)
		(fp_arc
			(start -22.900894 43.15206)
			(mid -22.065265 41.613079)
			(end -20.424902 40.999918)
			(stroke
				(width 0.1)
				(type default)
			)
			(layer "B.Fab")
		)
		(fp_arc
			(start -23.981918 50.848006)
			(mid -24.817625 52.386829)
			(end -26.45791 52.999894)
			(stroke
				(width 0.1)
				(type default)
			)
			(layer "B.Fab")
		)
		(fp_arc
			(start -26.45791 -52.999894)
			(mid -24.817657 -52.386799)
			(end -23.981918 -50.848006)
			(stroke
				(width 0.1)
				(type default)
			)
			(layer "B.Fab")
		)
		(fp_arc
			(start -44.200064 52.999894)
			(mid -45.967758 52.267713)
			(end -46.699932 50.500026)
			(stroke
				(width 0.1)
				(type default)
			)
			(layer "B.Fab")
		)
		(fp_arc
			(start -46.699932 -50.500026)
			(mid -45.967746 -52.267704)
			(end -44.200064 -52.999894)
			(stroke
				(width 0.1)
				(type default)
			)
			(layer "B.Fab")
		)
		(fp_line
			(start 46.699932 95.149924)
			(end -46.699932 95.149924)
			(stroke
				(width 0.1)
				(type default)
			)
			(layer "F.Fab")
		)
		(fp_line
			(start 46.699932 60.149994)
			(end -46.699932 60.149994)
			(stroke
				(width 0.1)
				(type default)
			)
			(layer "F.Fab")
		)
		(fp_line
			(start 46.699932 -60.300108)
			(end 46.699932 95.149924)
			(stroke
				(width 0.1)
				(type default)
			)
			(layer "F.Fab")
		)
		(fp_line
			(start 35.999928 37.69995)
			(end -35.999928 37.69995)
			(stroke
				(width 0.1)
				(type default)
			)
			(layer "F.Fab")
		)
		(fp_line
			(start 35.999928 -37.69995)
			(end 35.999928 37.69995)
			(stroke
				(width 0.1)
				(type default)
			)
			(layer "F.Fab")
		)
		(fp_line
			(start 7.050024 3.999992)
			(end -7.050024 3.999992)
			(stroke
				(width 0.1)
				(type default)
			)
			(layer "F.Fab")
		)
		(fp_line
			(start 7.050024 -3.999992)
			(end 7.050024 3.999992)
			(stroke
				(width 0.1)
				(type default)
			)
			(layer "F.Fab")
		)
		(fp_line
			(start -7.050024 3.999992)
			(end -7.050024 -3.999992)
			(stroke
				(width 0.1)
				(type default)
			)
			(layer "F.Fab")
		)
		(fp_line
			(start -7.050024 -3.999992)
			(end 7.050024 -3.999992)
			(stroke
				(width 0.1)
				(type default)
			)
			(layer "F.Fab")
		)
		(fp_line
			(start -35.999928 37.69995)
			(end -35.999928 -37.69995)
			(stroke
				(width 0.1)
				(type default)
			)
			(layer "F.Fab")
		)
		(fp_line
			(start -35.999928 -37.69995)
			(end 35.999928 -37.69995)
			(stroke
				(width 0.1)
				(type default)
			)
			(layer "F.Fab")
		)
		(fp_line
			(start -46.699932 95.149924)
			(end -46.699932 60.149994)
			(stroke
				(width 0.1)
				(type default)
			)
			(layer "F.Fab")
		)
		(fp_line
			(start -46.699932 90.149934)
			(end 46.699932 90.149934)
			(stroke
				(width 0.1)
				(type default)
			)
			(layer "F.Fab")
		)
		(fp_line
			(start -46.699932 85.149944)
			(end 46.699932 85.149944)
			(stroke
				(width 0.1)
				(type default)
			)
			(layer "F.Fab")
		)
		(fp_line
			(start -46.699932 80.149954)
			(end 46.699932 80.149954)
			(stroke
				(width 0.1)
				(type default)
			)
			(layer "F.Fab")
		)
		(fp_line
			(start -46.699932 75.149964)
			(end 46.699932 75.149964)
			(stroke
				(width 0.1)
				(type default)
			)
			(layer "F.Fab")
		)
		(fp_line
			(start -46.699932 70.149974)
			(end 46.699932 70.149974)
			(stroke
				(width 0.1)
				(type default)
			)
			(layer "F.Fab")
		)
		(fp_line
			(start -46.699932 65.149984)
			(end 46.699932 65.149984)
			(stroke
				(width 0.1)
				(type default)
			)
			(layer "F.Fab")
		)
		(fp_line
			(start -46.699932 60.149994)
			(end -46.699932 -60.300108)
			(stroke
				(width 0.1)
				(type default)
			)
			(layer "F.Fab")
		)
		(fp_line
			(start -46.699932 -60.300108)
			(end 46.699932 -60.300108)
			(stroke
				(width 0.1)
				(type default)
			)
			(layer "F.Fab")
		)
		(fp_poly
			(pts
				(xy -36.761928 -35.189922) (xy -36.761928 -38.46195) (xy -33.219898 -38.46195) (xy -33.219898 -37.69995)
				(xy -35.999928 -37.69995) (xy -35.999928 -35.189922)
			)
			(stroke
				(width 0)
				(type default)
			)
			(fill yes)
			(layer "F.Fab")
		)
		(pad "" np_thru_hole circle
			(at -42.099992 0 180)
			(size 4.0132 4.0132)
			(drill 4.0132)
			(layers "*.Cu" "*.Mask")
			(clearance 0.381)
			(thermal_gap 0.381)
		)
		(pad "" np_thru_hole circle
			(at -30.599888 -45.900086 180)
			(size 4.0132 4.0132)
			(drill 4.0132)
			(layers "*.Cu" "*.Mask")
			(clearance 0.381)
			(thermal_gap 0.381)
		)
		(pad "" np_thru_hole circle
			(at -30.599888 45.900086 180)
			(size 4.0132 4.0132)
			(drill 4.0132)
			(layers "*.Cu" "*.Mask")
			(clearance 0.381)
			(thermal_gap 0.381)
		)
		(pad "" np_thru_hole circle
			(at 30.599888 -45.900086 180)
			(size 4.0132 4.0132)
			(drill 4.0132)
			(layers "*.Cu" "*.Mask")
			(clearance 0.381)
			(thermal_gap 0.381)
		)
		(pad "" np_thru_hole circle
			(at 30.599888 45.900086 180)
			(size 4.0132 4.0132)
			(drill 4.0132)
			(layers "*.Cu" "*.Mask")
			(clearance 0.381)
			(thermal_gap 0.381)
		)
		(pad "" np_thru_hole circle
			(at 42.099992 0 180)
			(size 4.0132 4.0132)
			(drill 4.0132)
			(layers "*.Cu" "*.Mask")
			(clearance 0.381)
			(thermal_gap 0.381)
		)
		(pad "A3" smd circle
			(at -32.280098 -36.809934 180)
			(size 0.450088 0.450088)
			(layers "F.Cu" "F.Mask" "F.Paste")
			(net "GND")
		)
		(pad "A4" smd circle
			(at -31.340044 -36.809934 180)
			(size 0.450088 0.450088)
			(layers "F.Cu" "F.Mask" "F.Paste")
			(net "Net_2098")
		)
		(pad "A5" smd circle
			(at -30.39999 -36.809934 180)
			(size 0.450088 0.450088)
			(layers "F.Cu" "F.Mask" "F.Paste")
			(net "I3C_1_SPD_DDRGL_CPU1_R_SDA")
		)
		(pad "A7" smd circle
			(at -28.519882 -36.809934 180)
			(size 0.450088 0.450088)
			(layers "F.Cu" "F.Mask" "F.Paste")
			(net "CLK_100M_CPU1_CLK01_R_DN")
		)
		(pad "A8" smd circle
			(at -27.580082 -36.809934 180)
			(size 0.450088 0.450088)
			(layers "F.Cu" "F.Mask" "F.Paste")
			(net "CLK_100M_CPU1_CLK01_R_DP")
		)
		(pad "A9" smd circle
			(at -26.640028 -36.809934 180)
			(size 0.450088 0.450088)
			(layers "F.Cu" "F.Mask" "F.Paste")
			(net "GND")
		)
		(pad "A10" smd circle
			(at -25.699974 -36.809934 180)
			(size 0.450088 0.450088)
			(layers "F.Cu" "F.Mask" "F.Paste")
			(net "CLK_100M_CPU1_CLK03_R_DP")
		)
		(pad "A11" smd circle
			(at -24.75992 -36.809934 180)
			(size 0.450088 0.450088)
			(layers "F.Cu" "F.Mask" "F.Paste")
			(net "CLK_100M_CPU1_CLK03_R_DN")
		)
		(pad "A13" smd circle
			(at -22.880066 -36.809934 180)
			(size 0.450088 0.450088)
			(layers "F.Cu" "F.Mask" "F.Paste")
			(net "Net_2082")
		)
		(pad "A14" smd circle
			(at -21.940012 -36.809934 180)
			(size 0.450088 0.450088)
			(layers "F.Cu" "F.Mask" "F.Paste")
			(net "Net_2080")
		)
		(pad "A15" smd circle
			(at -20.999958 -36.809934 180)
			(size 0.450088 0.450088)
			(layers "F.Cu" "F.Mask" "F.Paste")
			(net "GND")
		)
		(pad "A16" smd circle
			(at -20.059904 -36.809934 180)
			(size 0.450088 0.450088)
			(layers "F.Cu" "F.Mask" "F.Paste")
			(net "JTAG_CPU1_TMS")
		)
		(pad "A17" smd circle
			(at -19.120104 -36.809934 180)
			(size 0.450088 0.450088)
			(layers "F.Cu" "F.Mask" "F.Paste")
			(net "JTAG_CPU1_TRST_N")
		)
		(pad "A19" smd circle
			(at -17.239996 -36.809934 180)
			(size 0.450088 0.450088)
			(layers "F.Cu" "F.Mask" "F.Paste")
			(net "CLK_100M_REF_IN_DP")
		)
		(pad "A20" smd circle
			(at -16.299942 -36.809934 180)
			(size 0.450088 0.450088)
			(layers "F.Cu" "F.Mask" "F.Paste")
			(net "CLK_100M_REF_IN_DN")
		)
		(pad "A21" smd circle
			(at -15.359888 -36.809934 180)
			(size 0.450088 0.450088)
			(layers "F.Cu" "F.Mask" "F.Paste")
			(net "GND")
		)
		(pad "A22" smd circle
			(at -14.420088 -36.809934 180)
			(size 0.450088 0.450088)
			(layers "F.Cu" "F.Mask" "F.Paste")
			(net "SVID_PVDDCR_CPU0_P1_SVD")
		)
		(pad "A23" smd circle
			(at -13.480034 -36.809934 180)
			(size 0.450088 0.450088)
			(layers "F.Cu" "F.Mask" "F.Paste")
			(net "SVID_PVDDCR_CPU0_P1_SVC")
		)
		(pad "A25" smd circle
			(at -11.599926 -36.809934 180)
			(size 0.450088 0.450088)
			(layers "F.Cu" "F.Mask" "F.Paste")
			(net "NC_CPU1_USB2_USB00_DN")
		)
		(pad "A26" smd circle
			(at -10.659872 -36.809934 180)
			(size 0.450088 0.450088)
			(layers "F.Cu" "F.Mask" "F.Paste")
			(net "NC_CPU1_USB2_USB00_DP")
		)
		(pad "A27" smd circle
			(at -9.720072 -36.809934 180)
			(size 0.450088 0.450088)
			(layers "F.Cu" "F.Mask" "F.Paste")
			(net "GND")
		)
		(pad "A28" smd circle
			(at -8.780018 -36.809934 180)
			(size 0.450088 0.450088)
			(layers "F.Cu" "F.Mask" "F.Paste")
			(net "NC_CPU1_USB2_USB01_DP")
		)
		(pad "A29" smd circle
			(at -7.839964 -36.809934 180)
			(size 0.450088 0.450088)
			(layers "F.Cu" "F.Mask" "F.Paste")
			(net "NC_CPU1_USB2_USB01_DN")
		)
		(pad "A31" smd circle
			(at -5.96011 -36.809934 180)
			(size 0.450088 0.450088)
			(layers "F.Cu" "F.Mask" "F.Paste")
			(net "Net_2121")
		)
		(pad "A32" smd circle
			(at -5.020056 -36.809934 180)
			(size 0.450088 0.450088)
			(layers "F.Cu" "F.Mask" "F.Paste")
			(net "NC_CPU1_AZ_SDOUT")
		)
		(pad "A33" smd circle
			(at -4.080002 -36.809934 180)
			(size 0.450088 0.450088)
			(layers "F.Cu" "F.Mask" "F.Paste")
			(net "NC_CPU1_AZ_SDIN2")
		)
		(pad "A34" smd circle
			(at -3.139948 -36.809934 180)
			(size 0.450088 0.450088)
			(layers "F.Cu" "F.Mask" "F.Paste")
			(net "NC_CPU1_AZ_RST_N")
		)
		(pad "A35" smd circle
			(at -2.199894 -36.809934 180)
			(size 0.450088 0.450088)
			(layers "F.Cu" "F.Mask" "F.Paste")
			(net "Net_2122")
		)
		(pad "A41" smd circle
			(at 2.500122 -36.809934 180)
			(size 0.450088 0.450088)
			(layers "F.Cu" "F.Mask" "F.Paste")
			(net "Net_2123")
		)
		(pad "A42" smd circle
			(at 3.439922 -36.809934 180)
			(size 0.450088 0.450088)
			(layers "F.Cu" "F.Mask" "F.Paste")
			(net "Net_2124")
		)
		(pad "A43" smd circle
			(at 4.379976 -36.809934 180)
			(size 0.450088 0.450088)
			(layers "F.Cu" "F.Mask" "F.Paste")
			(net "GND")
		)
		(pad "A44" smd circle
			(at 5.32003 -36.809934 180)
			(size 0.450088 0.450088)
			(layers "F.Cu" "F.Mask" "F.Paste")
			(net "GND")
		)
		(pad "A45" smd circle
			(at 6.260084 -36.809934 180)
			(size 0.450088 0.450088)
			(layers "F.Cu" "F.Mask" "F.Paste")
			(net "Net_2125")
		)
		(pad "A47" smd circle
			(at 8.139938 -36.809934 180)
			(size 0.450088 0.450088)
			(layers "F.Cu" "F.Mask" "F.Paste")
			(net "GND")
		)
		(pad "A48" smd circle
			(at 9.079992 -36.809934 180)
			(size 0.450088 0.450088)
			(layers "F.Cu" "F.Mask" "F.Paste")
			(net "Net_2126")
		)
		(pad "A49" smd circle
			(at 10.020046 -36.809934 180)
			(size 0.450088 0.450088)
			(layers "F.Cu" "F.Mask" "F.Paste")
			(net "GND")
		)
		(pad "A50" smd circle
			(at 10.9601 -36.809934 180)
			(size 0.450088 0.450088)
			(layers "F.Cu" "F.Mask" "F.Paste")
			(net "Net_2127")
		)
		(pad "A51" smd circle
			(at 11.8999 -36.809934 180)
			(size 0.450088 0.450088)
			(layers "F.Cu" "F.Mask" "F.Paste")
			(net "Net_2128")
		)
		(pad "A53" smd circle
			(at 13.780008 -36.809934 180)
			(size 0.450088 0.450088)
			(layers "F.Cu" "F.Mask" "F.Paste")
			(net "GND")
		)
		(pad "A54" smd circle
			(at 14.720062 -36.809934 180)
			(size 0.450088 0.450088)
			(layers "F.Cu" "F.Mask" "F.Paste")
			(net "Net_2129")
		)
		(pad "A55" smd circle
			(at 15.660116 -36.809934 180)
			(size 0.450088 0.450088)
			(layers "F.Cu" "F.Mask" "F.Paste")
			(net "Net_2130")
		)
		(pad "A56" smd circle
			(at 16.599916 -36.809934 180)
			(size 0.450088 0.450088)
			(layers "F.Cu" "F.Mask" "F.Paste")
			(net "Net_2131")
		)
		(pad "A57" smd circle
			(at 17.53997 -36.809934 180)
			(size 0.450088 0.450088)
			(layers "F.Cu" "F.Mask" "F.Paste")
			(net "Net_2132")
		)
		(pad "A59" smd circle
			(at 19.420078 -36.809934 180)
			(size 0.450088 0.450088)
			(layers "F.Cu" "F.Mask" "F.Paste")
			(net "Net_2133")
		)
		(pad "A60" smd circle
			(at 20.359878 -36.809934 180)
			(size 0.450088 0.450088)
			(layers "F.Cu" "F.Mask" "F.Paste")
			(net "Net_2134")
		)
		(pad "A61" smd circle
			(at 21.299932 -36.809934 180)
			(size 0.450088 0.450088)
			(layers "F.Cu" "F.Mask" "F.Paste")
			(net "GND")
		)
		(pad "A62" smd circle
			(at 22.239986 -36.809934 180)
			(size 0.450088 0.450088)
			(layers "F.Cu" "F.Mask" "F.Paste")
			(net "CPU1_BP3")
		)
		(pad "A63" smd circle
			(at 23.18004 -36.809934 180)
			(size 0.450088 0.450088)
			(layers "F.Cu" "F.Mask" "F.Paste")
			(net "CPU1_BP2")
		)
		(pad "A65" smd circle
			(at 25.059894 -36.809934 180)
			(size 0.450088 0.450088)
			(layers "F.Cu" "F.Mask" "F.Paste")
			(net "CPU1_XTRIG_R2_L7")
		)
		(pad "A66" smd circle
			(at 25.999948 -36.809934 180)
			(size 0.450088 0.450088)
			(layers "F.Cu" "F.Mask" "F.Paste")
			(net "CPU1_XTRIG_R2_L6")
		)
		(pad "A67" smd circle
			(at 26.940002 -36.809934 180)
			(size 0.450088 0.450088)
			(layers "F.Cu" "F.Mask" "F.Paste")
			(net "GND")
		)
		(pad "A68" smd circle
			(at 27.880056 -36.809934 180)
			(size 0.450088 0.450088)
			(layers "F.Cu" "F.Mask" "F.Paste")
			(net "APML_CPU1_ALERT_N")
		)
		(pad "A69" smd circle
			(at 28.82011 -36.809934 180)
			(size 0.450088 0.450088)
			(layers "F.Cu" "F.Mask" "F.Paste")
			(net "CPU1_PROCHOT_N")
		)
		(pad "A71" smd circle
			(at 30.699964 -36.809934 180)
			(size 0.450088 0.450088)
			(layers "F.Cu" "F.Mask" "F.Paste")
			(net "I3C_0_SPD_DDRAF_CPU1_R_SCL")
		)
		(pad "A72" smd circle
			(at 31.640018 -36.809934 180)
			(size 0.450088 0.450088)
			(layers "F.Cu" "F.Mask" "F.Paste")
			(net "GND")
		)
		(pad "A73" smd circle
			(at 32.580072 -36.809934 180)
			(size 0.450088 0.450088)
			(layers "F.Cu" "F.Mask" "F.Paste")
			(net "GND")
		)
		(pad "AA1" smd circle
			(at -34.159952 -20.610068 180)
			(size 0.450088 0.450088)
			(layers "F.Cu" "F.Mask" "F.Paste")
			(net "GND")
		)
		(pad "AA2" smd circle
			(at -33.219898 -20.610068 180)
			(size 0.450088 0.450088)
			(layers "F.Cu" "F.Mask" "F.Paste")
			(net "M_G_CPU1_SA_DQ<20>")
		)
		(pad "AA3" smd circle
			(at -32.280098 -20.610068 180)
			(size 0.450088 0.450088)
			(layers "F.Cu" "F.Mask" "F.Paste")
			(net "M_G_CPU1_SA_DQS_DP<7>")
		)
		(pad "AA4" smd circle
			(at -31.340044 -20.610068 180)
			(size 0.450088 0.450088)
			(layers "F.Cu" "F.Mask" "F.Paste")
			(net "GND")
		)
		(pad "AA5" smd circle
			(at -30.39999 -20.610068 180)
			(size 0.450088 0.450088)
			(layers "F.Cu" "F.Mask" "F.Paste")
			(net "M_K_CPU1_SA_DQ<20>")
		)
		(pad "AA6" smd circle
			(at -29.459936 -20.610068 180)
			(size 0.450088 0.450088)
			(layers "F.Cu" "F.Mask" "F.Paste")
			(net "GND")
		)
		(pad "AA7" smd circle
			(at -28.519882 -20.610068 180)
			(size 0.450088 0.450088)
			(layers "F.Cu" "F.Mask" "F.Paste")
			(net "M_K_CPU1_SA_DQS_DP<7>")
		)
		(pad "AA8" smd circle
			(at -27.580082 -20.610068 180)
			(size 0.450088 0.450088)
			(layers "F.Cu" "F.Mask" "F.Paste")
			(net "GND")
		)
		(pad "AA9" smd circle
			(at -26.640028 -20.610068 180)
			(size 0.450088 0.450088)
			(layers "F.Cu" "F.Mask" "F.Paste")
			(net "M_L_CPU1_SA_DQ<20>")
		)
		(pad "AA10" smd circle
			(at -25.699974 -20.610068 180)
			(size 0.450088 0.450088)
			(layers "F.Cu" "F.Mask" "F.Paste")
			(net "M_L_CPU1_SA_DQS_DP<7>")
		)
		(pad "AA11" smd circle
			(at -24.75992 -20.610068 180)
			(size 0.450088 0.450088)
			(layers "F.Cu" "F.Mask" "F.Paste")
			(net "GND")
		)
		(pad "AA12" smd circle
			(at -23.82012 -20.610068 180)
			(size 0.450088 0.450088)
			(layers "F.Cu" "F.Mask" "F.Paste")
			(net "M_H_CPU1_SA_DQ<20>")
		)
		(pad "AA13" smd circle
			(at -22.880066 -20.610068 180)
			(size 0.450088 0.450088)
			(layers "F.Cu" "F.Mask" "F.Paste")
			(net "GND")
		)
		(pad "AA14" smd circle
			(at -21.940012 -20.610068 180)
			(size 0.450088 0.450088)
			(layers "F.Cu" "F.Mask" "F.Paste")
			(net "M_H_CPU1_SA_DQS_DP<7>")
		)
		(pad "AA15" smd circle
			(at -20.999958 -20.610068 180)
			(size 0.450088 0.450088)
			(layers "F.Cu" "F.Mask" "F.Paste")
			(net "GND")
		)
		(pad "AA16" smd circle
			(at -20.059904 -20.610068 180)
			(size 0.450088 0.450088)
			(layers "F.Cu" "F.Mask" "F.Paste")
			(net "M_J_CPU1_SA_DQ<20>")
		)
		(pad "AA17" smd circle
			(at -19.120104 -20.610068 180)
			(size 0.450088 0.450088)
			(layers "F.Cu" "F.Mask" "F.Paste")
			(net "M_J_CPU1_SA_DQS_DP<7>")
		)
		(pad "AA18" smd circle
			(at -18.18005 -20.610068 180)
			(size 0.450088 0.450088)
			(layers "F.Cu" "F.Mask" "F.Paste")
			(net "GND")
		)
		(pad "AA19" smd circle
			(at -17.239996 -20.610068 180)
			(size 0.450088 0.450088)
			(layers "F.Cu" "F.Mask" "F.Paste")
			(net "M_I_CPU1_SA_DQ<20>")
		)
		(pad "AA20" smd circle
			(at -16.299942 -20.610068 180)
			(size 0.450088 0.450088)
			(layers "F.Cu" "F.Mask" "F.Paste")
			(net "GND")
		)
		(pad "AA21" smd circle
			(at -15.359888 -20.610068 180)
			(size 0.450088 0.450088)
			(layers "F.Cu" "F.Mask" "F.Paste")
			(net "M_I_CPU1_SA_DQS_DP<7>")
		)
		(pad "AA22" smd circle
			(at -14.420088 -20.610068 180)
			(size 0.450088 0.450088)
			(layers "F.Cu" "F.Mask" "F.Paste")
			(net "PVDDCR_SOC_P1")
		)
		(pad "AA23" smd circle
			(at -13.480034 -20.610068 180)
			(size 0.450088 0.450088)
			(layers "F.Cu" "F.Mask" "F.Paste")
			(net "TP_CPU1_TEST6_X3D4")
		)
		(pad "AA24" smd circle
			(at -12.53998 -20.610068 180)
			(size 0.450088 0.450088)
			(layers "F.Cu" "F.Mask" "F.Paste")
			(net "TP_CPU1_TEST5_IOD")
		)
		(pad "AA25" smd circle
			(at -11.599926 -20.610068 180)
			(size 0.450088 0.450088)
			(layers "F.Cu" "F.Mask" "F.Paste")
			(net "TP_CPU1_TEST4_IOD")
		)
		(pad "AA26" smd circle
			(at -10.659872 -20.610068 180)
			(size 0.450088 0.450088)
			(layers "F.Cu" "F.Mask" "F.Paste")
			(net "TP_CPU1_TEST5_CCD7")
		)
		(pad "AA27" smd circle
			(at -9.720072 -20.610068 180)
			(size 0.450088 0.450088)
			(layers "F.Cu" "F.Mask" "F.Paste")
			(net "TP_CPU1_TEST4_CCD7")
		)
		(pad "AA28" smd circle
			(at -8.780018 -20.610068 180)
			(size 0.450088 0.450088)
			(layers "F.Cu" "F.Mask" "F.Paste")
			(net "TP_CPU1_TEST4_CCD11")
		)
		(pad "AA29" smd circle
			(at -7.839964 -20.610068 180)
			(size 0.450088 0.450088)
			(layers "F.Cu" "F.Mask" "F.Paste")
			(net "TP_CPU1_TEST6_X3D2")
		)
		(pad "AA30" smd circle
			(at -6.89991 -20.610068 180)
			(size 0.450088 0.450088)
			(layers "F.Cu" "F.Mask" "F.Paste")
			(net "TP_CPU1_TEST4_CCD3")
		)
		(pad "AA31" smd circle
			(at -5.96011 -20.610068 180)
			(size 0.450088 0.450088)
			(layers "F.Cu" "F.Mask" "F.Paste")
			(net "GND")
		)
		(pad "AA32" smd circle
			(at -5.020056 -20.610068 180)
			(size 0.450088 0.450088)
			(layers "F.Cu" "F.Mask" "F.Paste")
			(net "GMI_CPU0_G0_CPU1_G2_TX_DN<4>")
		)
		(pad "AA33" smd circle
			(at -4.080002 -20.610068 180)
			(size 0.450088 0.450088)
			(layers "F.Cu" "F.Mask" "F.Paste")
			(net "GMI_CPU0_G0_CPU1_G2_TX_DP<4>")
		)
		(pad "AA34" smd circle
			(at -3.139948 -20.610068 180)
			(size 0.450088 0.450088)
			(layers "F.Cu" "F.Mask" "F.Paste")
			(net "GND")
		)
		(pad "AA35" smd circle
			(at -2.199894 -20.610068 180)
			(size 0.450088 0.450088)
			(layers "F.Cu" "F.Mask" "F.Paste")
			(net "GND")
		)
		(pad "AA36" smd circle
			(at -1.260094 -20.610068 180)
			(size 0.450088 0.450088)
			(layers "F.Cu" "F.Mask" "F.Paste")
			(net "GND")
		)
		(pad "AA40" smd circle
			(at 1.560068 -20.610068 180)
			(size 0.450088 0.450088)
			(layers "F.Cu" "F.Mask" "F.Paste")
			(net "GND")
		)
		(pad "AA41" smd circle
			(at 2.500122 -20.610068 180)
			(size 0.450088 0.450088)
			(layers "F.Cu" "F.Mask" "F.Paste")
			(net "GND")
		)
		(pad "AA42" smd circle
			(at 3.439922 -20.610068 180)
			(size 0.450088 0.450088)
			(layers "F.Cu" "F.Mask" "F.Paste")
			(net "GND")
		)
		(pad "AA43" smd circle
			(at 4.379976 -20.610068 180)
			(size 0.450088 0.450088)
			(layers "F.Cu" "F.Mask" "F.Paste")
			(net "GMI_CPU1_G0_CPU0_G2_TX_DP<11>")
		)
		(pad "AA44" smd circle
			(at 5.32003 -20.610068 180)
			(size 0.450088 0.450088)
			(layers "F.Cu" "F.Mask" "F.Paste")
			(net "GMI_CPU1_G0_CPU0_G2_TX_DN<11>")
		)
		(pad "AA45" smd circle
			(at 6.260084 -20.610068 180)
			(size 0.450088 0.450088)
			(layers "F.Cu" "F.Mask" "F.Paste")
			(net "GND")
		)
		(pad "AA46" smd circle
			(at 7.199884 -20.610068 180)
			(size 0.450088 0.450088)
			(layers "F.Cu" "F.Mask" "F.Paste")
			(net "TP_CPU1_TEST6_CCD0")
		)
		(pad "AA47" smd circle
			(at 8.139938 -20.610068 180)
			(size 0.450088 0.450088)
			(layers "F.Cu" "F.Mask" "F.Paste")
			(net "TP_CPU1_TEST6_X3D0")
		)
		(pad "AA48" smd circle
			(at 9.079992 -20.610068 180)
			(size 0.450088 0.450088)
			(layers "F.Cu" "F.Mask" "F.Paste")
			(net "TP_CPU1_TEST4_CCD8")
		)
		(pad "AA49" smd circle
			(at 10.020046 -20.610068 180)
			(size 0.450088 0.450088)
			(layers "F.Cu" "F.Mask" "F.Paste")
			(net "TP_CPU1_TEST6_IOD")
		)
		(pad "AA50" smd circle
			(at 10.9601 -20.610068 180)
			(size 0.450088 0.450088)
			(layers "F.Cu" "F.Mask" "F.Paste")
			(net "TP_CPU1_TEST4_CCD0")
		)
		(pad "AA51" smd circle
			(at 11.8999 -20.610068 180)
			(size 0.450088 0.450088)
			(layers "F.Cu" "F.Mask" "F.Paste")
			(net "TP_CPU1_TEST5_CCD0")
		)
		(pad "AA52" smd circle
			(at 12.839954 -20.610068 180)
			(size 0.450088 0.450088)
			(layers "F.Cu" "F.Mask" "F.Paste")
			(net "TP_CPU1_TEST4_CCD4")
		)
		(pad "AA53" smd circle
			(at 13.780008 -20.610068 180)
			(size 0.450088 0.450088)
			(layers "F.Cu" "F.Mask" "F.Paste")
			(net "TP_CPU1_TEST5_CCD4")
		)
		(pad "AA54" smd circle
			(at 14.720062 -20.610068 180)
			(size 0.450088 0.450088)
			(layers "F.Cu" "F.Mask" "F.Paste")
			(net "PVDDIO_P1")
		)
		(pad "AA55" smd circle
			(at 15.660116 -20.610068 180)
			(size 0.450088 0.450088)
			(layers "F.Cu" "F.Mask" "F.Paste")
			(net "M_C_CPU1_SA_DQS_DP<7>")
		)
		(pad "AA56" smd circle
			(at 16.599916 -20.610068 180)
			(size 0.450088 0.450088)
			(layers "F.Cu" "F.Mask" "F.Paste")
			(net "GND")
		)
		(pad "AA57" smd circle
			(at 17.53997 -20.610068 180)
			(size 0.450088 0.450088)
			(layers "F.Cu" "F.Mask" "F.Paste")
			(net "M_C_CPU1_SA_DQ<20>")
		)
		(pad "AA58" smd circle
			(at 18.480024 -20.610068 180)
			(size 0.450088 0.450088)
			(layers "F.Cu" "F.Mask" "F.Paste")
			(net "GND")
		)
		(pad "AA59" smd circle
			(at 19.420078 -20.610068 180)
			(size 0.450088 0.450088)
			(layers "F.Cu" "F.Mask" "F.Paste")
			(net "M_D_CPU1_SA_DQS_DP<7>")
		)
		(pad "AA60" smd circle
			(at 20.359878 -20.610068 180)
			(size 0.450088 0.450088)
			(layers "F.Cu" "F.Mask" "F.Paste")
			(net "M_D_CPU1_SA_DQ<20>")
		)
		(pad "AA61" smd circle
			(at 21.299932 -20.610068 180)
			(size 0.450088 0.450088)
			(layers "F.Cu" "F.Mask" "F.Paste")
			(net "GND")
		)
		(pad "AA62" smd circle
			(at 22.239986 -20.610068 180)
			(size 0.450088 0.450088)
			(layers "F.Cu" "F.Mask" "F.Paste")
			(net "M_B_CPU1_SA_DQS_DP<7>")
		)
		(pad "AA63" smd circle
			(at 23.18004 -20.610068 180)
			(size 0.450088 0.450088)
			(layers "F.Cu" "F.Mask" "F.Paste")
			(net "GND")
		)
		(pad "AA64" smd circle
			(at 24.120094 -20.610068 180)
			(size 0.450088 0.450088)
			(layers "F.Cu" "F.Mask" "F.Paste")
			(net "M_B_CPU1_SA_DQ<20>")
		)
		(pad "AA65" smd circle
			(at 25.059894 -20.610068 180)
			(size 0.450088 0.450088)
			(layers "F.Cu" "F.Mask" "F.Paste")
			(net "GND")
		)
		(pad "AA66" smd circle
			(at 25.999948 -20.610068 180)
			(size 0.450088 0.450088)
			(layers "F.Cu" "F.Mask" "F.Paste")
			(net "M_F_CPU1_SA_DQS_DP<7>")
		)
		(pad "AA67" smd circle
			(at 26.940002 -20.610068 180)
			(size 0.450088 0.450088)
			(layers "F.Cu" "F.Mask" "F.Paste")
			(net "M_F_CPU1_SA_DQ<20>")
		)
		(pad "AA68" smd circle
			(at 27.880056 -20.610068 180)
			(size 0.450088 0.450088)
			(layers "F.Cu" "F.Mask" "F.Paste")
			(net "GND")
		)
		(pad "AA69" smd circle
			(at 28.82011 -20.610068 180)
			(size 0.450088 0.450088)
			(layers "F.Cu" "F.Mask" "F.Paste")
			(net "M_E_CPU1_SA_DQS_DP<7>")
		)
		(pad "AA70" smd circle
			(at 29.75991 -20.610068 180)
			(size 0.450088 0.450088)
			(layers "F.Cu" "F.Mask" "F.Paste")
			(net "GND")
		)
		(pad "AA71" smd circle
			(at 30.699964 -20.610068 180)
			(size 0.450088 0.450088)
			(layers "F.Cu" "F.Mask" "F.Paste")
			(net "M_E_CPU1_SA_DQ<20>")
		)
		(pad "AA72" smd circle
			(at 31.640018 -20.610068 180)
			(size 0.450088 0.450088)
			(layers "F.Cu" "F.Mask" "F.Paste")
			(net "GND")
		)
		(pad "AA73" smd circle
			(at 32.580072 -20.610068 180)
			(size 0.450088 0.450088)
			(layers "F.Cu" "F.Mask" "F.Paste")
			(net "M_A_CPU1_SA_DQS_DP<7>")
		)
		(pad "AA74" smd circle
			(at 33.519872 -20.610068 180)
			(size 0.450088 0.450088)
			(layers "F.Cu" "F.Mask" "F.Paste")
			(net "M_A_CPU1_SA_DQ<20>")
		)
		(pad "AA75" smd circle
			(at 34.459926 -20.610068 180)
			(size 0.450088 0.450088)
			(layers "F.Cu" "F.Mask" "F.Paste")
			(net "GND")
		)
		(pad "AB2" smd circle
			(at -33.690052 -19.800062 180)
			(size 0.450088 0.450088)
			(layers "F.Cu" "F.Mask" "F.Paste")
			(net "M_G_CPU1_SA_DQ<22>")
		)
		(pad "AB3" smd circle
			(at -32.749998 -19.800062 180)
			(size 0.450088 0.450088)
			(layers "F.Cu" "F.Mask" "F.Paste")
			(net "GND")
		)
		(pad "AB4" smd circle
			(at -31.809944 -19.800062 180)
			(size 0.450088 0.450088)
			(layers "F.Cu" "F.Mask" "F.Paste")
			(net "M_G_CPU1_SA_DQ<21>")
		)
		(pad "AB5" smd circle
			(at -30.86989 -19.800062 180)
			(size 0.450088 0.450088)
			(layers "F.Cu" "F.Mask" "F.Paste")
			(net "GND")
		)
		(pad "AB6" smd circle
			(at -29.93009 -19.800062 180)
			(size 0.450088 0.450088)
			(layers "F.Cu" "F.Mask" "F.Paste")
			(net "M_K_CPU1_SA_DQ<22>")
		)
		(pad "AB7" smd circle
			(at -28.990036 -19.800062 180)
			(size 0.450088 0.450088)
			(layers "F.Cu" "F.Mask" "F.Paste")
			(net "M_K_CPU1_SA_DQ<21>")
		)
		(pad "AB8" smd circle
			(at -28.049982 -19.800062 180)
			(size 0.450088 0.450088)
			(layers "F.Cu" "F.Mask" "F.Paste")
			(net "GND")
		)
		(pad "AB9" smd circle
			(at -27.109928 -19.800062 180)
			(size 0.450088 0.450088)
			(layers "F.Cu" "F.Mask" "F.Paste")
			(net "M_L_CPU1_SA_DQ<22>")
		)
		(pad "AB10" smd circle
			(at -26.170128 -19.800062 180)
			(size 0.450088 0.450088)
			(layers "F.Cu" "F.Mask" "F.Paste")
			(net "GND")
		)
		(pad "AB11" smd circle
			(at -25.230074 -19.800062 180)
			(size 0.450088 0.450088)
			(layers "F.Cu" "F.Mask" "F.Paste")
			(net "M_L_CPU1_SA_DQ<21>")
		)
		(pad "AB12" smd circle
			(at -24.29002 -19.800062 180)
			(size 0.450088 0.450088)
			(layers "F.Cu" "F.Mask" "F.Paste")
			(net "GND")
		)
		(pad "AB13" smd circle
			(at -23.349966 -19.800062 180)
			(size 0.450088 0.450088)
			(layers "F.Cu" "F.Mask" "F.Paste")
			(net "M_H_CPU1_SA_DQ<22>")
		)
		(pad "AB14" smd circle
			(at -22.409912 -19.800062 180)
			(size 0.450088 0.450088)
			(layers "F.Cu" "F.Mask" "F.Paste")
			(net "M_H_CPU1_SA_DQ<21>")
		)
		(pad "AB15" smd circle
			(at -21.470112 -19.800062 180)
			(size 0.450088 0.450088)
			(layers "F.Cu" "F.Mask" "F.Paste")
			(net "GND")
		)
		(pad "AB16" smd circle
			(at -20.530058 -19.800062 180)
			(size 0.450088 0.450088)
			(layers "F.Cu" "F.Mask" "F.Paste")
			(net "M_J_CPU1_SA_DQ<22>")
		)
		(pad "AB17" smd circle
			(at -19.590004 -19.800062 180)
			(size 0.450088 0.450088)
			(layers "F.Cu" "F.Mask" "F.Paste")
			(net "GND")
		)
		(pad "AB18" smd circle
			(at -18.64995 -19.800062 180)
			(size 0.450088 0.450088)
			(layers "F.Cu" "F.Mask" "F.Paste")
			(net "M_J_CPU1_SA_DQ<21>")
		)
		(pad "AB19" smd circle
			(at -17.709896 -19.800062 180)
			(size 0.450088 0.450088)
			(layers "F.Cu" "F.Mask" "F.Paste")
			(net "GND")
		)
		(pad "AB20" smd circle
			(at -16.770096 -19.800062 180)
			(size 0.450088 0.450088)
			(layers "F.Cu" "F.Mask" "F.Paste")
			(net "M_I_CPU1_SA_DQ<22>")
		)
		(pad "AB21" smd circle
			(at -15.830042 -19.800062 180)
			(size 0.450088 0.450088)
			(layers "F.Cu" "F.Mask" "F.Paste")
			(net "M_I_CPU1_SA_DQ<21>")
		)
		(pad "AB22" smd circle
			(at -14.889988 -19.800062 180)
			(size 0.450088 0.450088)
			(layers "F.Cu" "F.Mask" "F.Paste")
			(net "GND")
		)
		(pad "AB23" smd circle
			(at -13.949934 -19.800062 180)
			(size 0.450088 0.450088)
			(layers "F.Cu" "F.Mask" "F.Paste")
			(net "PVDDCR_CPU0_P1")
		)
		(pad "AB24" smd circle
			(at -13.00988 -19.800062 180)
			(size 0.450088 0.450088)
			(layers "F.Cu" "F.Mask" "F.Paste")
			(net "PVDDCR_CPU0_P1")
		)
		(pad "AB25" smd circle
			(at -12.07008 -19.800062 180)
			(size 0.450088 0.450088)
			(layers "F.Cu" "F.Mask" "F.Paste")
			(net "GND")
		)
		(pad "AB26" smd circle
			(at -11.130026 -19.800062 180)
			(size 0.450088 0.450088)
			(layers "F.Cu" "F.Mask" "F.Paste")
			(net "PVDDCR_CPU0_P1")
		)
		(pad "AB27" smd circle
			(at -10.189972 -19.800062 180)
			(size 0.450088 0.450088)
			(layers "F.Cu" "F.Mask" "F.Paste")
			(net "PVDDCR_CPU0_P1")
		)
		(pad "AB28" smd circle
			(at -9.249918 -19.800062 180)
			(size 0.450088 0.450088)
			(layers "F.Cu" "F.Mask" "F.Paste")
			(net "GND")
		)
		(pad "AB29" smd circle
			(at -8.310118 -19.800062 180)
			(size 0.450088 0.450088)
			(layers "F.Cu" "F.Mask" "F.Paste")
			(net "PVDDCR_CPU0_P1")
		)
		(pad "AB30" smd circle
			(at -7.370064 -19.800062 180)
			(size 0.450088 0.450088)
			(layers "F.Cu" "F.Mask" "F.Paste")
			(net "PVDDCR_CPU0_P1")
		)
		(pad "AB31" smd circle
			(at -6.43001 -19.800062 180)
			(size 0.450088 0.450088)
			(layers "F.Cu" "F.Mask" "F.Paste")
			(net "GND")
		)
		(pad "AB32" smd circle
			(at -5.489956 -19.800062 180)
			(size 0.450088 0.450088)
			(layers "F.Cu" "F.Mask" "F.Paste")
			(net "PVDDCR_CPU0_P1")
		)
		(pad "AB33" smd circle
			(at -4.549902 -19.800062 180)
			(size 0.450088 0.450088)
			(layers "F.Cu" "F.Mask" "F.Paste")
			(net "PVDDCR_CPU0_P1")
		)
		(pad "AB34" smd circle
			(at -3.610102 -19.800062 180)
			(size 0.450088 0.450088)
			(layers "F.Cu" "F.Mask" "F.Paste")
			(net "GND")
		)
		(pad "AB35" smd circle
			(at -2.670048 -19.800062 180)
			(size 0.450088 0.450088)
			(layers "F.Cu" "F.Mask" "F.Paste")
			(net "GMI_CPU0_G0_CPU1_G2_TX_DN<2>")
		)
		(pad "AB36" smd circle
			(at -1.729994 -19.800062 180)
			(size 0.450088 0.450088)
			(layers "F.Cu" "F.Mask" "F.Paste")
			(net "GMI_CPU0_G0_CPU1_G2_TX_DP<2>")
		)
		(pad "AB37" smd circle
			(at -0.78994 -19.800062 180)
			(size 0.450088 0.450088)
			(layers "F.Cu" "F.Mask" "F.Paste")
			(net "GND")
		)
		(pad "AB39" smd circle
			(at 1.089914 -19.800062 180)
			(size 0.450088 0.450088)
			(layers "F.Cu" "F.Mask" "F.Paste")
			(net "GND")
		)
		(pad "AB40" smd circle
			(at 2.029968 -19.800062 180)
			(size 0.450088 0.450088)
			(layers "F.Cu" "F.Mask" "F.Paste")
			(net "GMI_CPU1_G0_CPU0_G2_TX_DP<13>")
		)
		(pad "AB41" smd circle
			(at 2.970022 -19.800062 180)
			(size 0.450088 0.450088)
			(layers "F.Cu" "F.Mask" "F.Paste")
			(net "GMI_CPU1_G0_CPU0_G2_TX_DN<13>")
		)
		(pad "AB42" smd circle
			(at 3.910076 -19.800062 180)
			(size 0.450088 0.450088)
			(layers "F.Cu" "F.Mask" "F.Paste")
			(net "GND")
		)
		(pad "AB43" smd circle
			(at 4.849876 -19.800062 180)
			(size 0.450088 0.450088)
			(layers "F.Cu" "F.Mask" "F.Paste")
			(net "PVDDCR_CPU0_P1")
		)
		(pad "AB44" smd circle
			(at 5.78993 -19.800062 180)
			(size 0.450088 0.450088)
			(layers "F.Cu" "F.Mask" "F.Paste")
			(net "PVDDCR_CPU0_P1")
		)
		(pad "AB45" smd circle
			(at 6.729984 -19.800062 180)
			(size 0.450088 0.450088)
			(layers "F.Cu" "F.Mask" "F.Paste")
			(net "GND")
		)
		(pad "AB46" smd circle
			(at 7.670038 -19.800062 180)
			(size 0.450088 0.450088)
			(layers "F.Cu" "F.Mask" "F.Paste")
			(net "PVDDCR_CPU0_P1")
		)
		(pad "AB47" smd circle
			(at 8.610092 -19.800062 180)
			(size 0.450088 0.450088)
			(layers "F.Cu" "F.Mask" "F.Paste")
			(net "PVDDCR_CPU0_P1")
		)
		(pad "AB48" smd circle
			(at 9.549892 -19.800062 180)
			(size 0.450088 0.450088)
			(layers "F.Cu" "F.Mask" "F.Paste")
			(net "GND")
		)
		(pad "AB49" smd circle
			(at 10.489946 -19.800062 180)
			(size 0.450088 0.450088)
			(layers "F.Cu" "F.Mask" "F.Paste")
			(net "PVDDCR_CPU0_P1")
		)
		(pad "AB50" smd circle
			(at 11.43 -19.800062 180)
			(size 0.450088 0.450088)
			(layers "F.Cu" "F.Mask" "F.Paste")
			(net "PVDDCR_CPU0_P1")
		)
		(pad "AB51" smd circle
			(at 12.370054 -19.800062 180)
			(size 0.450088 0.450088)
			(layers "F.Cu" "F.Mask" "F.Paste")
			(net "GND")
		)
		(pad "AB52" smd circle
			(at 13.310108 -19.800062 180)
			(size 0.450088 0.450088)
			(layers "F.Cu" "F.Mask" "F.Paste")
			(net "PVDDCR_CPU0_P1")
		)
		(pad "AB53" smd circle
			(at 14.249908 -19.800062 180)
			(size 0.450088 0.450088)
			(layers "F.Cu" "F.Mask" "F.Paste")
			(net "PVDDCR_CPU0_P1")
		)
		(pad "AB54" smd circle
			(at 15.189962 -19.800062 180)
			(size 0.450088 0.450088)
			(layers "F.Cu" "F.Mask" "F.Paste")
			(net "GND")
		)
		(pad "AB55" smd circle
			(at 16.130016 -19.800062 180)
			(size 0.450088 0.450088)
			(layers "F.Cu" "F.Mask" "F.Paste")
			(net "M_C_CPU1_SA_DQ<21>")
		)
		(pad "AB56" smd circle
			(at 17.07007 -19.800062 180)
			(size 0.450088 0.450088)
			(layers "F.Cu" "F.Mask" "F.Paste")
			(net "M_C_CPU1_SA_DQ<22>")
		)
		(pad "AB57" smd circle
			(at 18.010124 -19.800062 180)
			(size 0.450088 0.450088)
			(layers "F.Cu" "F.Mask" "F.Paste")
			(net "GND")
		)
		(pad "AB58" smd circle
			(at 18.949924 -19.800062 180)
			(size 0.450088 0.450088)
			(layers "F.Cu" "F.Mask" "F.Paste")
			(net "M_D_CPU1_SA_DQ<21>")
		)
		(pad "AB59" smd circle
			(at 19.889978 -19.800062 180)
			(size 0.450088 0.450088)
			(layers "F.Cu" "F.Mask" "F.Paste")
			(net "GND")
		)
		(pad "AB60" smd circle
			(at 20.830032 -19.800062 180)
			(size 0.450088 0.450088)
			(layers "F.Cu" "F.Mask" "F.Paste")
			(net "M_D_CPU1_SA_DQ<22>")
		)
		(pad "AB61" smd circle
			(at 21.770086 -19.800062 180)
			(size 0.450088 0.450088)
			(layers "F.Cu" "F.Mask" "F.Paste")
			(net "GND")
		)
		(pad "AB62" smd circle
			(at 22.709886 -19.800062 180)
			(size 0.450088 0.450088)
			(layers "F.Cu" "F.Mask" "F.Paste")
			(net "M_B_CPU1_SA_DQ<21>")
		)
		(pad "AB63" smd circle
			(at 23.64994 -19.800062 180)
			(size 0.450088 0.450088)
			(layers "F.Cu" "F.Mask" "F.Paste")
			(net "M_B_CPU1_SA_DQ<22>")
		)
		(pad "AB64" smd circle
			(at 24.589994 -19.800062 180)
			(size 0.450088 0.450088)
			(layers "F.Cu" "F.Mask" "F.Paste")
			(net "GND")
		)
		(pad "AB65" smd circle
			(at 25.530048 -19.800062 180)
			(size 0.450088 0.450088)
			(layers "F.Cu" "F.Mask" "F.Paste")
			(net "M_F_CPU1_SA_DQ<21>")
		)
		(pad "AB66" smd circle
			(at 26.470102 -19.800062 180)
			(size 0.450088 0.450088)
			(layers "F.Cu" "F.Mask" "F.Paste")
			(net "GND")
		)
		(pad "AB67" smd circle
			(at 27.409902 -19.800062 180)
			(size 0.450088 0.450088)
			(layers "F.Cu" "F.Mask" "F.Paste")
			(net "M_F_CPU1_SA_DQ<22>")
		)
		(pad "AB68" smd circle
			(at 28.349956 -19.800062 180)
			(size 0.450088 0.450088)
			(layers "F.Cu" "F.Mask" "F.Paste")
			(net "GND")
		)
		(pad "AB69" smd circle
			(at 29.29001 -19.800062 180)
			(size 0.450088 0.450088)
			(layers "F.Cu" "F.Mask" "F.Paste")
			(net "M_E_CPU1_SA_DQ<21>")
		)
		(pad "AB70" smd circle
			(at 30.230064 -19.800062 180)
			(size 0.450088 0.450088)
			(layers "F.Cu" "F.Mask" "F.Paste")
			(net "M_E_CPU1_SA_DQ<22>")
		)
		(pad "AB71" smd circle
			(at 31.170118 -19.800062 180)
			(size 0.450088 0.450088)
			(layers "F.Cu" "F.Mask" "F.Paste")
			(net "GND")
		)
		(pad "AB72" smd circle
			(at 32.109918 -19.800062 180)
			(size 0.450088 0.450088)
			(layers "F.Cu" "F.Mask" "F.Paste")
			(net "M_A_CPU1_SA_DQ<21>")
		)
		(pad "AB73" smd circle
			(at 33.049972 -19.800062 180)
			(size 0.450088 0.450088)
			(layers "F.Cu" "F.Mask" "F.Paste")
			(net "GND")
		)
		(pad "AB74" smd circle
			(at 33.990026 -19.800062 180)
			(size 0.450088 0.450088)
			(layers "F.Cu" "F.Mask" "F.Paste")
			(net "M_A_CPU1_SA_DQ<22>")
		)
		(pad "AC1" smd circle
			(at -34.159952 -18.990056 180)
			(size 0.450088 0.450088)
			(layers "F.Cu" "F.Mask" "F.Paste")
			(net "GND")
		)
		(pad "AC2" smd circle
			(at -33.219898 -18.990056 180)
			(size 0.450088 0.450088)
			(layers "F.Cu" "F.Mask" "F.Paste")
			(net "M_G_CPU1_SA_DQ<24>")
		)
		(pad "AC3" smd circle
			(at -32.280098 -18.990056 180)
			(size 0.450088 0.450088)
			(layers "F.Cu" "F.Mask" "F.Paste")
			(net "M_G_CPU1_SA_DQ<23>")
		)
		(pad "AC4" smd circle
			(at -31.340044 -18.990056 180)
			(size 0.450088 0.450088)
			(layers "F.Cu" "F.Mask" "F.Paste")
			(net "PVDDCR_SOC_P1")
		)
		(pad "AC5" smd circle
			(at -30.39999 -18.990056 180)
			(size 0.450088 0.450088)
			(layers "F.Cu" "F.Mask" "F.Paste")
			(net "M_K_CPU1_SA_DQ<24>")
		)
		(pad "AC6" smd circle
			(at -29.459936 -18.990056 180)
			(size 0.450088 0.450088)
			(layers "F.Cu" "F.Mask" "F.Paste")
			(net "GND")
		)
		(pad "AC7" smd circle
			(at -28.519882 -18.990056 180)
			(size 0.450088 0.450088)
			(layers "F.Cu" "F.Mask" "F.Paste")
			(net "M_K_CPU1_SA_DQ<23>")
		)
		(pad "AC8" smd circle
			(at -27.580082 -18.990056 180)
			(size 0.450088 0.450088)
			(layers "F.Cu" "F.Mask" "F.Paste")
			(net "GND")
		)
		(pad "AC9" smd circle
			(at -26.640028 -18.990056 180)
			(size 0.450088 0.450088)
			(layers "F.Cu" "F.Mask" "F.Paste")
			(net "M_L_CPU1_SA_DQ<24>")
		)
		(pad "AC10" smd circle
			(at -25.699974 -18.990056 180)
			(size 0.450088 0.450088)
			(layers "F.Cu" "F.Mask" "F.Paste")
			(net "M_L_CPU1_SA_DQ<23>")
		)
		(pad "AC11" smd circle
			(at -24.75992 -18.990056 180)
			(size 0.450088 0.450088)
			(layers "F.Cu" "F.Mask" "F.Paste")
			(net "PVDDCR_SOC_P1")
		)
		(pad "AC12" smd circle
			(at -23.82012 -18.990056 180)
			(size 0.450088 0.450088)
			(layers "F.Cu" "F.Mask" "F.Paste")
			(net "M_H_CPU1_SA_DQ<24>")
		)
		(pad "AC13" smd circle
			(at -22.880066 -18.990056 180)
			(size 0.450088 0.450088)
			(layers "F.Cu" "F.Mask" "F.Paste")
			(net "GND")
		)
		(pad "AC14" smd circle
			(at -21.940012 -18.990056 180)
			(size 0.450088 0.450088)
			(layers "F.Cu" "F.Mask" "F.Paste")
			(net "M_H_CPU1_SA_DQ<23>")
		)
		(pad "AC15" smd circle
			(at -20.999958 -18.990056 180)
			(size 0.450088 0.450088)
			(layers "F.Cu" "F.Mask" "F.Paste")
			(net "GND")
		)
		(pad "AC16" smd circle
			(at -20.059904 -18.990056 180)
			(size 0.450088 0.450088)
			(layers "F.Cu" "F.Mask" "F.Paste")
			(net "M_J_CPU1_SA_DQ<24>")
		)
		(pad "AC17" smd circle
			(at -19.120104 -18.990056 180)
			(size 0.450088 0.450088)
			(layers "F.Cu" "F.Mask" "F.Paste")
			(net "M_J_CPU1_SA_DQ<23>")
		)
		(pad "AC18" smd circle
			(at -18.18005 -18.990056 180)
			(size 0.450088 0.450088)
			(layers "F.Cu" "F.Mask" "F.Paste")
			(net "PVDDCR_SOC_P1")
		)
		(pad "AC19" smd circle
			(at -17.239996 -18.990056 180)
			(size 0.450088 0.450088)
			(layers "F.Cu" "F.Mask" "F.Paste")
			(net "M_I_CPU1_SA_DQ<24>")
		)
		(pad "AC20" smd circle
			(at -16.299942 -18.990056 180)
			(size 0.450088 0.450088)
			(layers "F.Cu" "F.Mask" "F.Paste")
			(net "GND")
		)
		(pad "AC21" smd circle
			(at -15.359888 -18.990056 180)
			(size 0.450088 0.450088)
			(layers "F.Cu" "F.Mask" "F.Paste")
			(net "M_I_CPU1_SA_DQ<23>")
		)
		(pad "AC22" smd circle
			(at -14.420088 -18.990056 180)
			(size 0.450088 0.450088)
			(layers "F.Cu" "F.Mask" "F.Paste")
			(net "GND")
		)
		(pad "AC23" smd circle
			(at -13.480034 -18.990056 180)
			(size 0.450088 0.450088)
			(layers "F.Cu" "F.Mask" "F.Paste")
			(net "GMI_CPU0_G0_CPU1_G2_TX_DN<14>")
		)
		(pad "AC24" smd circle
			(at -12.53998 -18.990056 180)
			(size 0.450088 0.450088)
			(layers "F.Cu" "F.Mask" "F.Paste")
			(net "GMI_CPU0_G0_CPU1_G2_TX_DP<14>")
		)
		(pad "AC25" smd circle
			(at -11.599926 -18.990056 180)
			(size 0.450088 0.450088)
			(layers "F.Cu" "F.Mask" "F.Paste")
			(net "GND")
		)
		(pad "AC26" smd circle
			(at -10.659872 -18.990056 180)
			(size 0.450088 0.450088)
			(layers "F.Cu" "F.Mask" "F.Paste")
			(net "GMI_CPU0_G0_CPU1_G2_TX_DN<11>")
		)
		(pad "AC27" smd circle
			(at -9.720072 -18.990056 180)
			(size 0.450088 0.450088)
			(layers "F.Cu" "F.Mask" "F.Paste")
			(net "GMI_CPU0_G0_CPU1_G2_TX_DP<11>")
		)
		(pad "AC28" smd circle
			(at -8.780018 -18.990056 180)
			(size 0.450088 0.450088)
			(layers "F.Cu" "F.Mask" "F.Paste")
			(net "GND")
		)
		(pad "AC29" smd circle
			(at -7.839964 -18.990056 180)
			(size 0.450088 0.450088)
			(layers "F.Cu" "F.Mask" "F.Paste")
			(net "GMI_CPU0_G0_CPU1_G2_TX_DN<8>")
		)
		(pad "AC30" smd circle
			(at -6.89991 -18.990056 180)
			(size 0.450088 0.450088)
			(layers "F.Cu" "F.Mask" "F.Paste")
			(net "GMI_CPU0_G0_CPU1_G2_TX_DP<8>")
		)
		(pad "AC31" smd circle
			(at -5.96011 -18.990056 180)
			(size 0.450088 0.450088)
			(layers "F.Cu" "F.Mask" "F.Paste")
			(net "GND")
		)
		(pad "AC32" smd circle
			(at -5.020056 -18.990056 180)
			(size 0.450088 0.450088)
			(layers "F.Cu" "F.Mask" "F.Paste")
			(net "GMI_CPU0_G0_CPU1_G2_TX_DN<5>")
		)
		(pad "AC33" smd circle
			(at -4.080002 -18.990056 180)
			(size 0.450088 0.450088)
			(layers "F.Cu" "F.Mask" "F.Paste")
			(net "GMI_CPU0_G0_CPU1_G2_TX_DP<5>")
		)
		(pad "AC34" smd circle
			(at -3.139948 -18.990056 180)
			(size 0.450088 0.450088)
			(layers "F.Cu" "F.Mask" "F.Paste")
			(net "GND")
		)
		(pad "AC35" smd circle
			(at -2.199894 -18.990056 180)
			(size 0.450088 0.450088)
			(layers "F.Cu" "F.Mask" "F.Paste")
			(net "PVDDCR_CPU0_P1")
		)
		(pad "AC36" smd circle
			(at -1.260094 -18.990056 180)
			(size 0.450088 0.450088)
			(layers "F.Cu" "F.Mask" "F.Paste")
			(net "PVDDCR_CPU0_P1")
		)
		(pad "AC40" smd circle
			(at 1.560068 -18.990056 180)
			(size 0.450088 0.450088)
			(layers "F.Cu" "F.Mask" "F.Paste")
			(net "PVDDCR_CPU0_P1")
		)
		(pad "AC41" smd circle
			(at 2.500122 -18.990056 180)
			(size 0.450088 0.450088)
			(layers "F.Cu" "F.Mask" "F.Paste")
			(net "PVDDCR_CPU0_P1")
		)
		(pad "AC42" smd circle
			(at 3.439922 -18.990056 180)
			(size 0.450088 0.450088)
			(layers "F.Cu" "F.Mask" "F.Paste")
			(net "GND")
		)
		(pad "AC43" smd circle
			(at 4.379976 -18.990056 180)
			(size 0.450088 0.450088)
			(layers "F.Cu" "F.Mask" "F.Paste")
			(net "GMI_CPU1_G0_CPU0_G2_TX_DP<10>")
		)
		(pad "AC44" smd circle
			(at 5.32003 -18.990056 180)
			(size 0.450088 0.450088)
			(layers "F.Cu" "F.Mask" "F.Paste")
			(net "GMI_CPU1_G0_CPU0_G2_TX_DN<10>")
		)
		(pad "AC45" smd circle
			(at 6.260084 -18.990056 180)
			(size 0.450088 0.450088)
			(layers "F.Cu" "F.Mask" "F.Paste")
			(net "GND")
		)
		(pad "AC46" smd circle
			(at 7.199884 -18.990056 180)
			(size 0.450088 0.450088)
			(layers "F.Cu" "F.Mask" "F.Paste")
			(net "GMI_CPU1_G0_CPU0_G2_TX_DP<7>")
		)
		(pad "AC47" smd circle
			(at 8.139938 -18.990056 180)
			(size 0.450088 0.450088)
			(layers "F.Cu" "F.Mask" "F.Paste")
			(net "GMI_CPU1_G0_CPU0_G2_TX_DN<7>")
		)
		(pad "AC48" smd circle
			(at 9.079992 -18.990056 180)
			(size 0.450088 0.450088)
			(layers "F.Cu" "F.Mask" "F.Paste")
			(net "GND")
		)
		(pad "AC49" smd circle
			(at 10.020046 -18.990056 180)
			(size 0.450088 0.450088)
			(layers "F.Cu" "F.Mask" "F.Paste")
			(net "GMI_CPU1_G0_CPU0_G2_TX_DP<4>")
		)
		(pad "AC50" smd circle
			(at 10.9601 -18.990056 180)
			(size 0.450088 0.450088)
			(layers "F.Cu" "F.Mask" "F.Paste")
			(net "GMI_CPU1_G0_CPU0_G2_TX_DN<4>")
		)
		(pad "AC51" smd circle
			(at 11.8999 -18.990056 180)
			(size 0.450088 0.450088)
			(layers "F.Cu" "F.Mask" "F.Paste")
			(net "GND")
		)
		(pad "AC52" smd circle
			(at 12.839954 -18.990056 180)
			(size 0.450088 0.450088)
			(layers "F.Cu" "F.Mask" "F.Paste")
			(net "GMI_CPU1_G0_CPU0_G2_TX_DP<1>")
		)
		(pad "AC53" smd circle
			(at 13.780008 -18.990056 180)
			(size 0.450088 0.450088)
			(layers "F.Cu" "F.Mask" "F.Paste")
			(net "GMI_CPU1_G0_CPU0_G2_TX_DN<1>")
		)
		(pad "AC54" smd circle
			(at 14.720062 -18.990056 180)
			(size 0.450088 0.450088)
			(layers "F.Cu" "F.Mask" "F.Paste")
			(net "GND")
		)
		(pad "AC55" smd circle
			(at 15.660116 -18.990056 180)
			(size 0.450088 0.450088)
			(layers "F.Cu" "F.Mask" "F.Paste")
			(net "M_C_CPU1_SA_DQ<23>")
		)
		(pad "AC56" smd circle
			(at 16.599916 -18.990056 180)
			(size 0.450088 0.450088)
			(layers "F.Cu" "F.Mask" "F.Paste")
			(net "GND")
		)
		(pad "AC57" smd circle
			(at 17.53997 -18.990056 180)
			(size 0.450088 0.450088)
			(layers "F.Cu" "F.Mask" "F.Paste")
			(net "M_C_CPU1_SA_DQ<24>")
		)
		(pad "AC58" smd circle
			(at 18.480024 -18.990056 180)
			(size 0.450088 0.450088)
			(layers "F.Cu" "F.Mask" "F.Paste")
			(net "PVDDIO_P1")
		)
		(pad "AC59" smd circle
			(at 19.420078 -18.990056 180)
			(size 0.450088 0.450088)
			(layers "F.Cu" "F.Mask" "F.Paste")
			(net "M_D_CPU1_SA_DQ<23>")
		)
		(pad "AC60" smd circle
			(at 20.359878 -18.990056 180)
			(size 0.450088 0.450088)
			(layers "F.Cu" "F.Mask" "F.Paste")
			(net "M_D_CPU1_SA_DQ<24>")
		)
		(pad "AC61" smd circle
			(at 21.299932 -18.990056 180)
			(size 0.450088 0.450088)
			(layers "F.Cu" "F.Mask" "F.Paste")
			(net "GND")
		)
		(pad "AC62" smd circle
			(at 22.239986 -18.990056 180)
			(size 0.450088 0.450088)
			(layers "F.Cu" "F.Mask" "F.Paste")
			(net "M_B_CPU1_SA_DQ<23>")
		)
		(pad "AC63" smd circle
			(at 23.18004 -18.990056 180)
			(size 0.450088 0.450088)
			(layers "F.Cu" "F.Mask" "F.Paste")
			(net "GND")
		)
		(pad "AC64" smd circle
			(at 24.120094 -18.990056 180)
			(size 0.450088 0.450088)
			(layers "F.Cu" "F.Mask" "F.Paste")
			(net "M_B_CPU1_SA_DQ<24>")
		)
		(pad "AC65" smd circle
			(at 25.059894 -18.990056 180)
			(size 0.450088 0.450088)
			(layers "F.Cu" "F.Mask" "F.Paste")
			(net "PVDDIO_P1")
		)
		(pad "AC66" smd circle
			(at 25.999948 -18.990056 180)
			(size 0.450088 0.450088)
			(layers "F.Cu" "F.Mask" "F.Paste")
			(net "M_F_CPU1_SA_DQ<23>")
		)
		(pad "AC67" smd circle
			(at 26.940002 -18.990056 180)
			(size 0.450088 0.450088)
			(layers "F.Cu" "F.Mask" "F.Paste")
			(net "M_F_CPU1_SA_DQ<24>")
		)
		(pad "AC68" smd circle
			(at 27.880056 -18.990056 180)
			(size 0.450088 0.450088)
			(layers "F.Cu" "F.Mask" "F.Paste")
			(net "GND")
		)
		(pad "AC69" smd circle
			(at 28.82011 -18.990056 180)
			(size 0.450088 0.450088)
			(layers "F.Cu" "F.Mask" "F.Paste")
			(net "M_E_CPU1_SA_DQ<23>")
		)
		(pad "AC70" smd circle
			(at 29.75991 -18.990056 180)
			(size 0.450088 0.450088)
			(layers "F.Cu" "F.Mask" "F.Paste")
			(net "GND")
		)
		(pad "AC71" smd circle
			(at 30.699964 -18.990056 180)
			(size 0.450088 0.450088)
			(layers "F.Cu" "F.Mask" "F.Paste")
			(net "M_E_CPU1_SA_DQ<24>")
		)
		(pad "AC72" smd circle
			(at 31.640018 -18.990056 180)
			(size 0.450088 0.450088)
			(layers "F.Cu" "F.Mask" "F.Paste")
			(net "PVDDIO_P1")
		)
		(pad "AC73" smd circle
			(at 32.580072 -18.990056 180)
			(size 0.450088 0.450088)
			(layers "F.Cu" "F.Mask" "F.Paste")
			(net "M_A_CPU1_SA_DQ<23>")
		)
		(pad "AC74" smd circle
			(at 33.519872 -18.990056 180)
			(size 0.450088 0.450088)
			(layers "F.Cu" "F.Mask" "F.Paste")
			(net "M_A_CPU1_SA_DQ<24>")
		)
		(pad "AC75" smd circle
			(at 34.459926 -18.990056 180)
			(size 0.450088 0.450088)
			(layers "F.Cu" "F.Mask" "F.Paste")
			(net "GND")
		)
		(pad "AD2" smd circle
			(at -33.690052 -18.18005 180)
			(size 0.450088 0.450088)
			(layers "F.Cu" "F.Mask" "F.Paste")
			(net "M_G_CPU1_SA_DQ<26>")
		)
		(pad "AD3" smd circle
			(at -32.749998 -18.18005 180)
			(size 0.450088 0.450088)
			(layers "F.Cu" "F.Mask" "F.Paste")
			(net "GND")
		)
		(pad "AD4" smd circle
			(at -31.809944 -18.18005 180)
			(size 0.450088 0.450088)
			(layers "F.Cu" "F.Mask" "F.Paste")
			(net "M_G_CPU1_SA_DQ<25>")
		)
		(pad "AD5" smd circle
			(at -30.86989 -18.18005 180)
			(size 0.450088 0.450088)
			(layers "F.Cu" "F.Mask" "F.Paste")
			(net "GND")
		)
		(pad "AD6" smd circle
			(at -29.93009 -18.18005 180)
			(size 0.450088 0.450088)
			(layers "F.Cu" "F.Mask" "F.Paste")
			(net "M_K_CPU1_SA_DQ<26>")
		)
		(pad "AD7" smd circle
			(at -28.990036 -18.18005 180)
			(size 0.450088 0.450088)
			(layers "F.Cu" "F.Mask" "F.Paste")
			(net "M_K_CPU1_SA_DQ<25>")
		)
		(pad "AD8" smd circle
			(at -28.049982 -18.18005 180)
			(size 0.450088 0.450088)
			(layers "F.Cu" "F.Mask" "F.Paste")
			(net "GND")
		)
		(pad "AD9" smd circle
			(at -27.109928 -18.18005 180)
			(size 0.450088 0.450088)
			(layers "F.Cu" "F.Mask" "F.Paste")
			(net "M_L_CPU1_SA_DQ<26>")
		)
		(pad "AD10" smd circle
			(at -26.170128 -18.18005 180)
			(size 0.450088 0.450088)
			(layers "F.Cu" "F.Mask" "F.Paste")
			(net "GND")
		)
		(pad "AD11" smd circle
			(at -25.230074 -18.18005 180)
			(size 0.450088 0.450088)
			(layers "F.Cu" "F.Mask" "F.Paste")
			(net "M_L_CPU1_SA_DQ<25>")
		)
		(pad "AD12" smd circle
			(at -24.29002 -18.18005 180)
			(size 0.450088 0.450088)
			(layers "F.Cu" "F.Mask" "F.Paste")
			(net "GND")
		)
		(pad "AD13" smd circle
			(at -23.349966 -18.18005 180)
			(size 0.450088 0.450088)
			(layers "F.Cu" "F.Mask" "F.Paste")
			(net "M_H_CPU1_SA_DQ<26>")
		)
		(pad "AD14" smd circle
			(at -22.409912 -18.18005 180)
			(size 0.450088 0.450088)
			(layers "F.Cu" "F.Mask" "F.Paste")
			(net "M_H_CPU1_SA_DQ<25>")
		)
		(pad "AD15" smd circle
			(at -21.470112 -18.18005 180)
			(size 0.450088 0.450088)
			(layers "F.Cu" "F.Mask" "F.Paste")
			(net "GND")
		)
		(pad "AD16" smd circle
			(at -20.530058 -18.18005 180)
			(size 0.450088 0.450088)
			(layers "F.Cu" "F.Mask" "F.Paste")
			(net "M_J_CPU1_SA_DQ<26>")
		)
		(pad "AD17" smd circle
			(at -19.590004 -18.18005 180)
			(size 0.450088 0.450088)
			(layers "F.Cu" "F.Mask" "F.Paste")
			(net "GND")
		)
		(pad "AD18" smd circle
			(at -18.64995 -18.18005 180)
			(size 0.450088 0.450088)
			(layers "F.Cu" "F.Mask" "F.Paste")
			(net "M_J_CPU1_SA_DQ<25>")
		)
		(pad "AD19" smd circle
			(at -17.709896 -18.18005 180)
			(size 0.450088 0.450088)
			(layers "F.Cu" "F.Mask" "F.Paste")
			(net "GND")
		)
		(pad "AD20" smd circle
			(at -16.770096 -18.18005 180)
			(size 0.450088 0.450088)
			(layers "F.Cu" "F.Mask" "F.Paste")
			(net "M_I_CPU1_SA_DQ<26>")
		)
		(pad "AD21" smd circle
			(at -15.830042 -18.18005 180)
			(size 0.450088 0.450088)
			(layers "F.Cu" "F.Mask" "F.Paste")
			(net "M_I_CPU1_SA_DQ<25>")
		)
		(pad "AD22" smd circle
			(at -14.889988 -18.18005 180)
			(size 0.450088 0.450088)
			(layers "F.Cu" "F.Mask" "F.Paste")
			(net "PVDDCR_SOC_P1")
		)
		(pad "AD23" smd circle
			(at -13.949934 -18.18005 180)
			(size 0.450088 0.450088)
			(layers "F.Cu" "F.Mask" "F.Paste")
			(net "GND")
		)
		(pad "AD24" smd circle
			(at -13.00988 -18.18005 180)
			(size 0.450088 0.450088)
			(layers "F.Cu" "F.Mask" "F.Paste")
			(net "GND")
		)
		(pad "AD25" smd circle
			(at -12.07008 -18.18005 180)
			(size 0.450088 0.450088)
			(layers "F.Cu" "F.Mask" "F.Paste")
			(net "GND")
		)
		(pad "AD26" smd circle
			(at -11.130026 -18.18005 180)
			(size 0.450088 0.450088)
			(layers "F.Cu" "F.Mask" "F.Paste")
			(net "GND")
		)
		(pad "AD27" smd circle
			(at -10.189972 -18.18005 180)
			(size 0.450088 0.450088)
			(layers "F.Cu" "F.Mask" "F.Paste")
			(net "GND")
		)
		(pad "AD28" smd circle
			(at -9.249918 -18.18005 180)
			(size 0.450088 0.450088)
			(layers "F.Cu" "F.Mask" "F.Paste")
			(net "GND")
		)
		(pad "AD29" smd circle
			(at -8.310118 -18.18005 180)
			(size 0.450088 0.450088)
			(layers "F.Cu" "F.Mask" "F.Paste")
			(net "GND")
		)
		(pad "AD30" smd circle
			(at -7.370064 -18.18005 180)
			(size 0.450088 0.450088)
			(layers "F.Cu" "F.Mask" "F.Paste")
			(net "GND")
		)
		(pad "AD31" smd circle
			(at -6.43001 -18.18005 180)
			(size 0.450088 0.450088)
			(layers "F.Cu" "F.Mask" "F.Paste")
			(net "GND")
		)
		(pad "AD32" smd circle
			(at -5.489956 -18.18005 180)
			(size 0.450088 0.450088)
			(layers "F.Cu" "F.Mask" "F.Paste")
			(net "GND")
		)
		(pad "AD33" smd circle
			(at -4.549902 -18.18005 180)
			(size 0.450088 0.450088)
			(layers "F.Cu" "F.Mask" "F.Paste")
			(net "GND")
		)
		(pad "AD34" smd circle
			(at -3.610102 -18.18005 180)
			(size 0.450088 0.450088)
			(layers "F.Cu" "F.Mask" "F.Paste")
			(net "GND")
		)
		(pad "AD35" smd circle
			(at -2.670048 -18.18005 180)
			(size 0.450088 0.450088)
			(layers "F.Cu" "F.Mask" "F.Paste")
			(net "GMI_CPU0_G0_CPU1_G2_TX_DN<1>")
		)
		(pad "AD36" smd circle
			(at -1.729994 -18.18005 180)
			(size 0.450088 0.450088)
			(layers "F.Cu" "F.Mask" "F.Paste")
			(net "GMI_CPU0_G0_CPU1_G2_TX_DP<1>")
		)
		(pad "AD37" smd circle
			(at -0.78994 -18.18005 180)
			(size 0.450088 0.450088)
			(layers "F.Cu" "F.Mask" "F.Paste")
			(net "GND")
		)
		(pad "AD39" smd circle
			(at 1.089914 -18.18005 180)
			(size 0.450088 0.450088)
			(layers "F.Cu" "F.Mask" "F.Paste")
			(net "GND")
		)
		(pad "AD40" smd circle
			(at 2.029968 -18.18005 180)
			(size 0.450088 0.450088)
			(layers "F.Cu" "F.Mask" "F.Paste")
			(net "GMI_CPU1_G0_CPU0_G2_TX_DP<14>")
		)
		(pad "AD41" smd circle
			(at 2.970022 -18.18005 180)
			(size 0.450088 0.450088)
			(layers "F.Cu" "F.Mask" "F.Paste")
			(net "GMI_CPU1_G0_CPU0_G2_TX_DN<14>")
		)
		(pad "AD42" smd circle
			(at 3.910076 -18.18005 180)
			(size 0.450088 0.450088)
			(layers "F.Cu" "F.Mask" "F.Paste")
			(net "GND")
		)
		(pad "AD43" smd circle
			(at 4.849876 -18.18005 180)
			(size 0.450088 0.450088)
			(layers "F.Cu" "F.Mask" "F.Paste")
			(net "GND")
		)
		(pad "AD44" smd circle
			(at 5.78993 -18.18005 180)
			(size 0.450088 0.450088)
			(layers "F.Cu" "F.Mask" "F.Paste")
			(net "GND")
		)
		(pad "AD45" smd circle
			(at 6.729984 -18.18005 180)
			(size 0.450088 0.450088)
			(layers "F.Cu" "F.Mask" "F.Paste")
			(net "GND")
		)
		(pad "AD46" smd circle
			(at 7.670038 -18.18005 180)
			(size 0.450088 0.450088)
			(layers "F.Cu" "F.Mask" "F.Paste")
			(net "GND")
		)
		(pad "AD47" smd circle
			(at 8.610092 -18.18005 180)
			(size 0.450088 0.450088)
			(layers "F.Cu" "F.Mask" "F.Paste")
			(net "GND")
		)
		(pad "AD48" smd circle
			(at 9.549892 -18.18005 180)
			(size 0.450088 0.450088)
			(layers "F.Cu" "F.Mask" "F.Paste")
			(net "GND")
		)
		(pad "AD49" smd circle
			(at 10.489946 -18.18005 180)
			(size 0.450088 0.450088)
			(layers "F.Cu" "F.Mask" "F.Paste")
			(net "GND")
		)
		(pad "AD50" smd circle
			(at 11.43 -18.18005 180)
			(size 0.450088 0.450088)
			(layers "F.Cu" "F.Mask" "F.Paste")
			(net "GND")
		)
		(pad "AD51" smd circle
			(at 12.370054 -18.18005 180)
			(size 0.450088 0.450088)
			(layers "F.Cu" "F.Mask" "F.Paste")
			(net "GND")
		)
		(pad "AD52" smd circle
			(at 13.310108 -18.18005 180)
			(size 0.450088 0.450088)
			(layers "F.Cu" "F.Mask" "F.Paste")
			(net "GND")
		)
		(pad "AD53" smd circle
			(at 14.249908 -18.18005 180)
			(size 0.450088 0.450088)
			(layers "F.Cu" "F.Mask" "F.Paste")
			(net "GND")
		)
		(pad "AD54" smd circle
			(at 15.189962 -18.18005 180)
			(size 0.450088 0.450088)
			(layers "F.Cu" "F.Mask" "F.Paste")
			(net "PVDDIO_P1")
		)
		(pad "AD55" smd circle
			(at 16.130016 -18.18005 180)
			(size 0.450088 0.450088)
			(layers "F.Cu" "F.Mask" "F.Paste")
			(net "M_C_CPU1_SA_DQ<25>")
		)
		(pad "AD56" smd circle
			(at 17.07007 -18.18005 180)
			(size 0.450088 0.450088)
			(layers "F.Cu" "F.Mask" "F.Paste")
			(net "M_C_CPU1_SA_DQ<26>")
		)
		(pad "AD57" smd circle
			(at 18.010124 -18.18005 180)
			(size 0.450088 0.450088)
			(layers "F.Cu" "F.Mask" "F.Paste")
			(net "GND")
		)
		(pad "AD58" smd circle
			(at 18.949924 -18.18005 180)
			(size 0.450088 0.450088)
			(layers "F.Cu" "F.Mask" "F.Paste")
			(net "M_D_CPU1_SA_DQ<25>")
		)
		(pad "AD59" smd circle
			(at 19.889978 -18.18005 180)
			(size 0.450088 0.450088)
			(layers "F.Cu" "F.Mask" "F.Paste")
			(net "GND")
		)
		(pad "AD60" smd circle
			(at 20.830032 -18.18005 180)
			(size 0.450088 0.450088)
			(layers "F.Cu" "F.Mask" "F.Paste")
			(net "M_D_CPU1_SA_DQ<26>")
		)
		(pad "AD61" smd circle
			(at 21.770086 -18.18005 180)
			(size 0.450088 0.450088)
			(layers "F.Cu" "F.Mask" "F.Paste")
			(net "GND")
		)
		(pad "AD62" smd circle
			(at 22.709886 -18.18005 180)
			(size 0.450088 0.450088)
			(layers "F.Cu" "F.Mask" "F.Paste")
			(net "M_B_CPU1_SA_DQ<25>")
		)
		(pad "AD63" smd circle
			(at 23.64994 -18.18005 180)
			(size 0.450088 0.450088)
			(layers "F.Cu" "F.Mask" "F.Paste")
			(net "M_B_CPU1_SA_DQ<26>")
		)
		(pad "AD64" smd circle
			(at 24.589994 -18.18005 180)
			(size 0.450088 0.450088)
			(layers "F.Cu" "F.Mask" "F.Paste")
			(net "GND")
		)
		(pad "AD65" smd circle
			(at 25.530048 -18.18005 180)
			(size 0.450088 0.450088)
			(layers "F.Cu" "F.Mask" "F.Paste")
			(net "M_F_CPU1_SA_DQ<25>")
		)
		(pad "AD66" smd circle
			(at 26.470102 -18.18005 180)
			(size 0.450088 0.450088)
			(layers "F.Cu" "F.Mask" "F.Paste")
			(net "GND")
		)
		(pad "AD67" smd circle
			(at 27.409902 -18.18005 180)
			(size 0.450088 0.450088)
			(layers "F.Cu" "F.Mask" "F.Paste")
			(net "M_F_CPU1_SA_DQ<26>")
		)
		(pad "AD68" smd circle
			(at 28.349956 -18.18005 180)
			(size 0.450088 0.450088)
			(layers "F.Cu" "F.Mask" "F.Paste")
			(net "GND")
		)
		(pad "AD69" smd circle
			(at 29.29001 -18.18005 180)
			(size 0.450088 0.450088)
			(layers "F.Cu" "F.Mask" "F.Paste")
			(net "M_E_CPU1_SA_DQ<25>")
		)
		(pad "AD70" smd circle
			(at 30.230064 -18.18005 180)
			(size 0.450088 0.450088)
			(layers "F.Cu" "F.Mask" "F.Paste")
			(net "M_E_CPU1_SA_DQ<26>")
		)
		(pad "AD71" smd circle
			(at 31.170118 -18.18005 180)
			(size 0.450088 0.450088)
			(layers "F.Cu" "F.Mask" "F.Paste")
			(net "GND")
		)
		(pad "AD72" smd circle
			(at 32.109918 -18.18005 180)
			(size 0.450088 0.450088)
			(layers "F.Cu" "F.Mask" "F.Paste")
			(net "M_A_CPU1_SA_DQ<25>")
		)
		(pad "AD73" smd circle
			(at 33.049972 -18.18005 180)
			(size 0.450088 0.450088)
			(layers "F.Cu" "F.Mask" "F.Paste")
			(net "GND")
		)
		(pad "AD74" smd circle
			(at 33.990026 -18.18005 180)
			(size 0.450088 0.450088)
			(layers "F.Cu" "F.Mask" "F.Paste")
			(net "M_A_CPU1_SA_DQ<26>")
		)
		(pad "AE1" smd circle
			(at -34.159952 -17.370044 180)
			(size 0.450088 0.450088)
			(layers "F.Cu" "F.Mask" "F.Paste")
			(net "GND")
		)
		(pad "AE2" smd circle
			(at -33.219898 -17.370044 180)
			(size 0.450088 0.450088)
			(layers "F.Cu" "F.Mask" "F.Paste")
			(net "M_G_CPU1_SA_DQS_DP<3>")
		)
		(pad "AE3" smd circle
			(at -32.280098 -17.370044 180)
			(size 0.450088 0.450088)
			(layers "F.Cu" "F.Mask" "F.Paste")
			(net "M_G_CPU1_SA_DQ<27>")
		)
		(pad "AE4" smd circle
			(at -31.340044 -17.370044 180)
			(size 0.450088 0.450088)
			(layers "F.Cu" "F.Mask" "F.Paste")
			(net "GND")
		)
		(pad "AE5" smd circle
			(at -30.39999 -17.370044 180)
			(size 0.450088 0.450088)
			(layers "F.Cu" "F.Mask" "F.Paste")
			(net "M_K_CPU1_SA_DQS_DP<3>")
		)
		(pad "AE6" smd circle
			(at -29.459936 -17.370044 180)
			(size 0.450088 0.450088)
			(layers "F.Cu" "F.Mask" "F.Paste")
			(net "GND")
		)
		(pad "AE7" smd circle
			(at -28.519882 -17.370044 180)
			(size 0.450088 0.450088)
			(layers "F.Cu" "F.Mask" "F.Paste")
			(net "M_K_CPU1_SA_DQ<27>")
		)
		(pad "AE8" smd circle
			(at -27.580082 -17.370044 180)
			(size 0.450088 0.450088)
			(layers "F.Cu" "F.Mask" "F.Paste")
			(net "GND")
		)
		(pad "AE9" smd circle
			(at -26.640028 -17.370044 180)
			(size 0.450088 0.450088)
			(layers "F.Cu" "F.Mask" "F.Paste")
			(net "M_L_CPU1_SA_DQS_DP<3>")
		)
		(pad "AE10" smd circle
			(at -25.699974 -17.370044 180)
			(size 0.450088 0.450088)
			(layers "F.Cu" "F.Mask" "F.Paste")
			(net "M_L_CPU1_SA_DQ<27>")
		)
		(pad "AE11" smd circle
			(at -24.75992 -17.370044 180)
			(size 0.450088 0.450088)
			(layers "F.Cu" "F.Mask" "F.Paste")
			(net "GND")
		)
		(pad "AE12" smd circle
			(at -23.82012 -17.370044 180)
			(size 0.450088 0.450088)
			(layers "F.Cu" "F.Mask" "F.Paste")
			(net "M_H_CPU1_SA_DQS_DP<3>")
		)
		(pad "AE13" smd circle
			(at -22.880066 -17.370044 180)
			(size 0.450088 0.450088)
			(layers "F.Cu" "F.Mask" "F.Paste")
			(net "GND")
		)
		(pad "AE14" smd circle
			(at -21.940012 -17.370044 180)
			(size 0.450088 0.450088)
			(layers "F.Cu" "F.Mask" "F.Paste")
			(net "M_H_CPU1_SA_DQ<27>")
		)
		(pad "AE15" smd circle
			(at -20.999958 -17.370044 180)
			(size 0.450088 0.450088)
			(layers "F.Cu" "F.Mask" "F.Paste")
			(net "GND")
		)
		(pad "AE16" smd circle
			(at -20.059904 -17.370044 180)
			(size 0.450088 0.450088)
			(layers "F.Cu" "F.Mask" "F.Paste")
			(net "M_J_CPU1_SA_DQS_DP<3>")
		)
		(pad "AE17" smd circle
			(at -19.120104 -17.370044 180)
			(size 0.450088 0.450088)
			(layers "F.Cu" "F.Mask" "F.Paste")
			(net "M_J_CPU1_SA_DQ<27>")
		)
		(pad "AE18" smd circle
			(at -18.18005 -17.370044 180)
			(size 0.450088 0.450088)
			(layers "F.Cu" "F.Mask" "F.Paste")
			(net "GND")
		)
		(pad "AE19" smd circle
			(at -17.239996 -17.370044 180)
			(size 0.450088 0.450088)
			(layers "F.Cu" "F.Mask" "F.Paste")
			(net "M_I_CPU1_SA_DQS_DP<3>")
		)
		(pad "AE20" smd circle
			(at -16.299942 -17.370044 180)
			(size 0.450088 0.450088)
			(layers "F.Cu" "F.Mask" "F.Paste")
			(net "GND")
		)
		(pad "AE21" smd circle
			(at -15.359888 -17.370044 180)
			(size 0.450088 0.450088)
			(layers "F.Cu" "F.Mask" "F.Paste")
			(net "M_I_CPU1_SA_DQ<27>")
		)
		(pad "AE22" smd circle
			(at -14.420088 -17.370044 180)
			(size 0.450088 0.450088)
			(layers "F.Cu" "F.Mask" "F.Paste")
			(net "GND")
		)
		(pad "AE23" smd circle
			(at -13.480034 -17.370044 180)
			(size 0.450088 0.450088)
			(layers "F.Cu" "F.Mask" "F.Paste")
			(net "GMI_CPU0_G0_CPU1_G2_TX_DN<15>")
		)
		(pad "AE24" smd circle
			(at -12.53998 -17.370044 180)
			(size 0.450088 0.450088)
			(layers "F.Cu" "F.Mask" "F.Paste")
			(net "GMI_CPU0_G0_CPU1_G2_TX_DP<15>")
		)
		(pad "AE25" smd circle
			(at -11.599926 -17.370044 180)
			(size 0.450088 0.450088)
			(layers "F.Cu" "F.Mask" "F.Paste")
			(net "GND")
		)
		(pad "AE26" smd circle
			(at -10.659872 -17.370044 180)
			(size 0.450088 0.450088)
			(layers "F.Cu" "F.Mask" "F.Paste")
			(net "GMI_CPU0_G0_CPU1_G2_TX_DN<12>")
		)
		(pad "AE27" smd circle
			(at -9.720072 -17.370044 180)
			(size 0.450088 0.450088)
			(layers "F.Cu" "F.Mask" "F.Paste")
			(net "GMI_CPU0_G0_CPU1_G2_TX_DP<12>")
		)
		(pad "AE28" smd circle
			(at -8.780018 -17.370044 180)
			(size 0.450088 0.450088)
			(layers "F.Cu" "F.Mask" "F.Paste")
			(net "GND")
		)
		(pad "AE29" smd circle
			(at -7.839964 -17.370044 180)
			(size 0.450088 0.450088)
			(layers "F.Cu" "F.Mask" "F.Paste")
			(net "GMI_CPU0_G0_CPU1_G2_TX_DN<9>")
		)
		(pad "AE30" smd circle
			(at -6.89991 -17.370044 180)
			(size 0.450088 0.450088)
			(layers "F.Cu" "F.Mask" "F.Paste")
			(net "GMI_CPU0_G0_CPU1_G2_TX_DP<9>")
		)
		(pad "AE31" smd circle
			(at -5.96011 -17.370044 180)
			(size 0.450088 0.450088)
			(layers "F.Cu" "F.Mask" "F.Paste")
			(net "GND")
		)
		(pad "AE32" smd circle
			(at -5.020056 -17.370044 180)
			(size 0.450088 0.450088)
			(layers "F.Cu" "F.Mask" "F.Paste")
			(net "GMI_CPU0_G0_CPU1_G2_TX_DN<6>")
		)
		(pad "AE33" smd circle
			(at -4.080002 -17.370044 180)
			(size 0.450088 0.450088)
			(layers "F.Cu" "F.Mask" "F.Paste")
			(net "GMI_CPU0_G0_CPU1_G2_TX_DP<6>")
		)
		(pad "AE34" smd circle
			(at -3.139948 -17.370044 180)
			(size 0.450088 0.450088)
			(layers "F.Cu" "F.Mask" "F.Paste")
			(net "GND")
		)
		(pad "AE35" smd circle
			(at -2.199894 -17.370044 180)
			(size 0.450088 0.450088)
			(layers "F.Cu" "F.Mask" "F.Paste")
			(net "GND")
		)
		(pad "AE36" smd circle
			(at -1.260094 -17.370044 180)
			(size 0.450088 0.450088)
			(layers "F.Cu" "F.Mask" "F.Paste")
			(net "GND")
		)
		(pad "AE40" smd circle
			(at 1.560068 -17.370044 180)
			(size 0.450088 0.450088)
			(layers "F.Cu" "F.Mask" "F.Paste")
			(net "GND")
		)
		(pad "AE41" smd circle
			(at 2.500122 -17.370044 180)
			(size 0.450088 0.450088)
			(layers "F.Cu" "F.Mask" "F.Paste")
			(net "GND")
		)
		(pad "AE42" smd circle
			(at 3.439922 -17.370044 180)
			(size 0.450088 0.450088)
			(layers "F.Cu" "F.Mask" "F.Paste")
			(net "GND")
		)
		(pad "AE43" smd circle
			(at 4.379976 -17.370044 180)
			(size 0.450088 0.450088)
			(layers "F.Cu" "F.Mask" "F.Paste")
			(net "GMI_CPU1_G0_CPU0_G2_TX_DP<9>")
		)
		(pad "AE44" smd circle
			(at 5.32003 -17.370044 180)
			(size 0.450088 0.450088)
			(layers "F.Cu" "F.Mask" "F.Paste")
			(net "GMI_CPU1_G0_CPU0_G2_TX_DN<9>")
		)
		(pad "AE45" smd circle
			(at 6.260084 -17.370044 180)
			(size 0.450088 0.450088)
			(layers "F.Cu" "F.Mask" "F.Paste")
			(net "GND")
		)
		(pad "AE46" smd circle
			(at 7.199884 -17.370044 180)
			(size 0.450088 0.450088)
			(layers "F.Cu" "F.Mask" "F.Paste")
			(net "GMI_CPU1_G0_CPU0_G2_TX_DP<6>")
		)
		(pad "AE47" smd circle
			(at 8.139938 -17.370044 180)
			(size 0.450088 0.450088)
			(layers "F.Cu" "F.Mask" "F.Paste")
			(net "GMI_CPU1_G0_CPU0_G2_TX_DN<6>")
		)
		(pad "AE48" smd circle
			(at 9.079992 -17.370044 180)
			(size 0.450088 0.450088)
			(layers "F.Cu" "F.Mask" "F.Paste")
			(net "GND")
		)
		(pad "AE49" smd circle
			(at 10.020046 -17.370044 180)
			(size 0.450088 0.450088)
			(layers "F.Cu" "F.Mask" "F.Paste")
			(net "GMI_CPU1_G0_CPU0_G2_TX_DP<3>")
		)
		(pad "AE50" smd circle
			(at 10.9601 -17.370044 180)
			(size 0.450088 0.450088)
			(layers "F.Cu" "F.Mask" "F.Paste")
			(net "GMI_CPU1_G0_CPU0_G2_TX_DN<3>")
		)
		(pad "AE51" smd circle
			(at 11.8999 -17.370044 180)
			(size 0.450088 0.450088)
			(layers "F.Cu" "F.Mask" "F.Paste")
			(net "GND")
		)
		(pad "AE52" smd circle
			(at 12.839954 -17.370044 180)
			(size 0.450088 0.450088)
			(layers "F.Cu" "F.Mask" "F.Paste")
			(net "GMI_CPU1_G0_CPU0_G2_TX_DP<0>")
		)
		(pad "AE53" smd circle
			(at 13.780008 -17.370044 180)
			(size 0.450088 0.450088)
			(layers "F.Cu" "F.Mask" "F.Paste")
			(net "GMI_CPU1_G0_CPU0_G2_TX_DN<0>")
		)
		(pad "AE54" smd circle
			(at 14.720062 -17.370044 180)
			(size 0.450088 0.450088)
			(layers "F.Cu" "F.Mask" "F.Paste")
			(net "GND")
		)
		(pad "AE55" smd circle
			(at 15.660116 -17.370044 180)
			(size 0.450088 0.450088)
			(layers "F.Cu" "F.Mask" "F.Paste")
			(net "M_C_CPU1_SA_DQ<27>")
		)
		(pad "AE56" smd circle
			(at 16.599916 -17.370044 180)
			(size 0.450088 0.450088)
			(layers "F.Cu" "F.Mask" "F.Paste")
			(net "GND")
		)
		(pad "AE57" smd circle
			(at 17.53997 -17.370044 180)
			(size 0.450088 0.450088)
			(layers "F.Cu" "F.Mask" "F.Paste")
			(net "M_C_CPU1_SA_DQS_DP<3>")
		)
		(pad "AE58" smd circle
			(at 18.480024 -17.370044 180)
			(size 0.450088 0.450088)
			(layers "F.Cu" "F.Mask" "F.Paste")
			(net "GND")
		)
		(pad "AE59" smd circle
			(at 19.420078 -17.370044 180)
			(size 0.450088 0.450088)
			(layers "F.Cu" "F.Mask" "F.Paste")
			(net "M_D_CPU1_SA_DQ<27>")
		)
		(pad "AE60" smd circle
			(at 20.359878 -17.370044 180)
			(size 0.450088 0.450088)
			(layers "F.Cu" "F.Mask" "F.Paste")
			(net "M_D_CPU1_SA_DQS_DP<3>")
		)
		(pad "AE61" smd circle
			(at 21.299932 -17.370044 180)
			(size 0.450088 0.450088)
			(layers "F.Cu" "F.Mask" "F.Paste")
			(net "GND")
		)
		(pad "AE62" smd circle
			(at 22.239986 -17.370044 180)
			(size 0.450088 0.450088)
			(layers "F.Cu" "F.Mask" "F.Paste")
			(net "M_B_CPU1_SA_DQ<27>")
		)
		(pad "AE63" smd circle
			(at 23.18004 -17.370044 180)
			(size 0.450088 0.450088)
			(layers "F.Cu" "F.Mask" "F.Paste")
			(net "GND")
		)
		(pad "AE64" smd circle
			(at 24.120094 -17.370044 180)
			(size 0.450088 0.450088)
			(layers "F.Cu" "F.Mask" "F.Paste")
			(net "M_B_CPU1_SA_DQS_DP<3>")
		)
		(pad "AE65" smd circle
			(at 25.059894 -17.370044 180)
			(size 0.450088 0.450088)
			(layers "F.Cu" "F.Mask" "F.Paste")
			(net "GND")
		)
		(pad "AE66" smd circle
			(at 25.999948 -17.370044 180)
			(size 0.450088 0.450088)
			(layers "F.Cu" "F.Mask" "F.Paste")
			(net "M_F_CPU1_SA_DQ<27>")
		)
		(pad "AE67" smd circle
			(at 26.940002 -17.370044 180)
			(size 0.450088 0.450088)
			(layers "F.Cu" "F.Mask" "F.Paste")
			(net "M_F_CPU1_SA_DQS_DP<3>")
		)
		(pad "AE68" smd circle
			(at 27.880056 -17.370044 180)
			(size 0.450088 0.450088)
			(layers "F.Cu" "F.Mask" "F.Paste")
			(net "GND")
		)
		(pad "AE69" smd circle
			(at 28.82011 -17.370044 180)
			(size 0.450088 0.450088)
			(layers "F.Cu" "F.Mask" "F.Paste")
			(net "M_E_CPU1_SA_DQ<27>")
		)
		(pad "AE70" smd circle
			(at 29.75991 -17.370044 180)
			(size 0.450088 0.450088)
			(layers "F.Cu" "F.Mask" "F.Paste")
			(net "GND")
		)
		(pad "AE71" smd circle
			(at 30.699964 -17.370044 180)
			(size 0.450088 0.450088)
			(layers "F.Cu" "F.Mask" "F.Paste")
			(net "M_E_CPU1_SA_DQS_DP<3>")
		)
		(pad "AE72" smd circle
			(at 31.640018 -17.370044 180)
			(size 0.450088 0.450088)
			(layers "F.Cu" "F.Mask" "F.Paste")
			(net "GND")
		)
		(pad "AE73" smd circle
			(at 32.580072 -17.370044 180)
			(size 0.450088 0.450088)
			(layers "F.Cu" "F.Mask" "F.Paste")
			(net "M_A_CPU1_SA_DQ<27>")
		)
		(pad "AE74" smd circle
			(at 33.519872 -17.370044 180)
			(size 0.450088 0.450088)
			(layers "F.Cu" "F.Mask" "F.Paste")
			(net "M_A_CPU1_SA_DQS_DP<3>")
		)
		(pad "AE75" smd circle
			(at 34.459926 -17.370044 180)
			(size 0.450088 0.450088)
			(layers "F.Cu" "F.Mask" "F.Paste")
			(net "GND")
		)
		(pad "AF2" smd circle
			(at -33.690052 -16.560038 180)
			(size 0.450088 0.450088)
			(layers "F.Cu" "F.Mask" "F.Paste")
			(net "M_G_CPU1_SA_DQS_DN<3>")
		)
		(pad "AF3" smd circle
			(at -32.749998 -16.560038 180)
			(size 0.450088 0.450088)
			(layers "F.Cu" "F.Mask" "F.Paste")
			(net "GND")
		)
		(pad "AF4" smd circle
			(at -31.809944 -16.560038 180)
			(size 0.450088 0.450088)
			(layers "F.Cu" "F.Mask" "F.Paste")
			(net "M_G_CPU1_SA_DQS_DN<8>")
		)
		(pad "AF5" smd circle
			(at -30.86989 -16.560038 180)
			(size 0.450088 0.450088)
			(layers "F.Cu" "F.Mask" "F.Paste")
			(net "PVDDCR_SOC_P1")
		)
		(pad "AF6" smd circle
			(at -29.93009 -16.560038 180)
			(size 0.450088 0.450088)
			(layers "F.Cu" "F.Mask" "F.Paste")
			(net "M_K_CPU1_SA_DQS_DN<3>")
		)
		(pad "AF7" smd circle
			(at -28.990036 -16.560038 180)
			(size 0.450088 0.450088)
			(layers "F.Cu" "F.Mask" "F.Paste")
			(net "M_K_CPU1_SA_DQS_DN<8>")
		)
		(pad "AF8" smd circle
			(at -28.049982 -16.560038 180)
			(size 0.450088 0.450088)
			(layers "F.Cu" "F.Mask" "F.Paste")
			(net "GND")
		)
		(pad "AF9" smd circle
			(at -27.109928 -16.560038 180)
			(size 0.450088 0.450088)
			(layers "F.Cu" "F.Mask" "F.Paste")
			(net "M_L_CPU1_SA_DQS_DN<3>")
		)
		(pad "AF10" smd circle
			(at -26.170128 -16.560038 180)
			(size 0.450088 0.450088)
			(layers "F.Cu" "F.Mask" "F.Paste")
			(net "GND")
		)
		(pad "AF11" smd circle
			(at -25.230074 -16.560038 180)
			(size 0.450088 0.450088)
			(layers "F.Cu" "F.Mask" "F.Paste")
			(net "M_L_CPU1_SA_DQS_DN<8>")
		)
		(pad "AF12" smd circle
			(at -24.29002 -16.560038 180)
			(size 0.450088 0.450088)
			(layers "F.Cu" "F.Mask" "F.Paste")
			(net "PVDDCR_SOC_P1")
		)
		(pad "AF13" smd circle
			(at -23.349966 -16.560038 180)
			(size 0.450088 0.450088)
			(layers "F.Cu" "F.Mask" "F.Paste")
			(net "M_H_CPU1_SA_DQS_DN<3>")
		)
		(pad "AF14" smd circle
			(at -22.409912 -16.560038 180)
			(size 0.450088 0.450088)
			(layers "F.Cu" "F.Mask" "F.Paste")
			(net "M_H_CPU1_SA_DQS_DN<8>")
		)
		(pad "AF15" smd circle
			(at -21.470112 -16.560038 180)
			(size 0.450088 0.450088)
			(layers "F.Cu" "F.Mask" "F.Paste")
			(net "GND")
		)
		(pad "AF16" smd circle
			(at -20.530058 -16.560038 180)
			(size 0.450088 0.450088)
			(layers "F.Cu" "F.Mask" "F.Paste")
			(net "M_J_CPU1_SA_DQS_DN<3>")
		)
		(pad "AF17" smd circle
			(at -19.590004 -16.560038 180)
			(size 0.450088 0.450088)
			(layers "F.Cu" "F.Mask" "F.Paste")
			(net "GND")
		)
		(pad "AF18" smd circle
			(at -18.64995 -16.560038 180)
			(size 0.450088 0.450088)
			(layers "F.Cu" "F.Mask" "F.Paste")
			(net "M_J_CPU1_SA_DQS_DN<8>")
		)
		(pad "AF19" smd circle
			(at -17.709896 -16.560038 180)
			(size 0.450088 0.450088)
			(layers "F.Cu" "F.Mask" "F.Paste")
			(net "PVDDCR_SOC_P1")
		)
		(pad "AF20" smd circle
			(at -16.770096 -16.560038 180)
			(size 0.450088 0.450088)
			(layers "F.Cu" "F.Mask" "F.Paste")
			(net "M_I_CPU1_SA_DQS_DN<3>")
		)
		(pad "AF21" smd circle
			(at -15.830042 -16.560038 180)
			(size 0.450088 0.450088)
			(layers "F.Cu" "F.Mask" "F.Paste")
			(net "M_I_CPU1_SA_DQS_DN<8>")
		)
		(pad "AF22" smd circle
			(at -14.889988 -16.560038 180)
			(size 0.450088 0.450088)
			(layers "F.Cu" "F.Mask" "F.Paste")
			(net "GND")
		)
		(pad "AF23" smd circle
			(at -13.949934 -16.560038 180)
			(size 0.450088 0.450088)
			(layers "F.Cu" "F.Mask" "F.Paste")
			(net "PVDDCR_CPU0_P1")
		)
		(pad "AF24" smd circle
			(at -13.00988 -16.560038 180)
			(size 0.450088 0.450088)
			(layers "F.Cu" "F.Mask" "F.Paste")
			(net "PVDDCR_CPU0_P1")
		)
		(pad "AF25" smd circle
			(at -12.07008 -16.560038 180)
			(size 0.450088 0.450088)
			(layers "F.Cu" "F.Mask" "F.Paste")
			(net "GND")
		)
		(pad "AF26" smd circle
			(at -11.130026 -16.560038 180)
			(size 0.450088 0.450088)
			(layers "F.Cu" "F.Mask" "F.Paste")
			(net "PVDDCR_CPU0_P1")
		)
		(pad "AF27" smd circle
			(at -10.189972 -16.560038 180)
			(size 0.450088 0.450088)
			(layers "F.Cu" "F.Mask" "F.Paste")
			(net "PVDDCR_CPU0_P1")
		)
		(pad "AF28" smd circle
			(at -9.249918 -16.560038 180)
			(size 0.450088 0.450088)
			(layers "F.Cu" "F.Mask" "F.Paste")
			(net "GND")
		)
		(pad "AF29" smd circle
			(at -8.310118 -16.560038 180)
			(size 0.450088 0.450088)
			(layers "F.Cu" "F.Mask" "F.Paste")
			(net "PVDDCR_CPU0_P1")
		)
		(pad "AF30" smd circle
			(at -7.370064 -16.560038 180)
			(size 0.450088 0.450088)
			(layers "F.Cu" "F.Mask" "F.Paste")
			(net "PVDDCR_CPU0_P1")
		)
		(pad "AF31" smd circle
			(at -6.43001 -16.560038 180)
			(size 0.450088 0.450088)
			(layers "F.Cu" "F.Mask" "F.Paste")
			(net "GND")
		)
		(pad "AF32" smd circle
			(at -5.489956 -16.560038 180)
			(size 0.450088 0.450088)
			(layers "F.Cu" "F.Mask" "F.Paste")
			(net "PVDDCR_CPU0_P1")
		)
		(pad "AF33" smd circle
			(at -4.549902 -16.560038 180)
			(size 0.450088 0.450088)
			(layers "F.Cu" "F.Mask" "F.Paste")
			(net "PVDDCR_CPU0_P1")
		)
		(pad "AF34" smd circle
			(at -3.610102 -16.560038 180)
			(size 0.450088 0.450088)
			(layers "F.Cu" "F.Mask" "F.Paste")
			(net "GND")
		)
		(pad "AF35" smd circle
			(at -2.670048 -16.560038 180)
			(size 0.450088 0.450088)
			(layers "F.Cu" "F.Mask" "F.Paste")
			(net "GMI_CPU0_G0_CPU1_G2_TX_DN<0>")
		)
		(pad "AF36" smd circle
			(at -1.729994 -16.560038 180)
			(size 0.450088 0.450088)
			(layers "F.Cu" "F.Mask" "F.Paste")
			(net "GMI_CPU0_G0_CPU1_G2_TX_DP<0>")
		)
		(pad "AF37" smd circle
			(at -0.78994 -16.560038 180)
			(size 0.450088 0.450088)
			(layers "F.Cu" "F.Mask" "F.Paste")
			(net "GND")
		)
		(pad "AF39" smd circle
			(at 1.089914 -16.560038 180)
			(size 0.450088 0.450088)
			(layers "F.Cu" "F.Mask" "F.Paste")
			(net "GND")
		)
		(pad "AF40" smd circle
			(at 2.029968 -16.560038 180)
			(size 0.450088 0.450088)
			(layers "F.Cu" "F.Mask" "F.Paste")
			(net "GMI_CPU1_G0_CPU0_G2_TX_DP<15>")
		)
		(pad "AF41" smd circle
			(at 2.970022 -16.560038 180)
			(size 0.450088 0.450088)
			(layers "F.Cu" "F.Mask" "F.Paste")
			(net "GMI_CPU1_G0_CPU0_G2_TX_DN<15>")
		)
		(pad "AF42" smd circle
			(at 3.910076 -16.560038 180)
			(size 0.450088 0.450088)
			(layers "F.Cu" "F.Mask" "F.Paste")
			(net "GND")
		)
		(pad "AF43" smd circle
			(at 4.849876 -16.560038 180)
			(size 0.450088 0.450088)
			(layers "F.Cu" "F.Mask" "F.Paste")
			(net "PVDDCR_CPU0_P1")
		)
		(pad "AF44" smd circle
			(at 5.78993 -16.560038 180)
			(size 0.450088 0.450088)
			(layers "F.Cu" "F.Mask" "F.Paste")
			(net "PVDDCR_CPU0_P1")
		)
		(pad "AF45" smd circle
			(at 6.729984 -16.560038 180)
			(size 0.450088 0.450088)
			(layers "F.Cu" "F.Mask" "F.Paste")
			(net "GND")
		)
		(pad "AF46" smd circle
			(at 7.670038 -16.560038 180)
			(size 0.450088 0.450088)
			(layers "F.Cu" "F.Mask" "F.Paste")
			(net "PVDDCR_CPU0_P1")
		)
		(pad "AF47" smd circle
			(at 8.610092 -16.560038 180)
			(size 0.450088 0.450088)
			(layers "F.Cu" "F.Mask" "F.Paste")
			(net "PVDDCR_CPU0_P1")
		)
		(pad "AF48" smd circle
			(at 9.549892 -16.560038 180)
			(size 0.450088 0.450088)
			(layers "F.Cu" "F.Mask" "F.Paste")
			(net "GND")
		)
		(pad "AF49" smd circle
			(at 10.489946 -16.560038 180)
			(size 0.450088 0.450088)
			(layers "F.Cu" "F.Mask" "F.Paste")
			(net "PVDDCR_CPU0_P1")
		)
		(pad "AF50" smd circle
			(at 11.43 -16.560038 180)
			(size 0.450088 0.450088)
			(layers "F.Cu" "F.Mask" "F.Paste")
			(net "PVDDCR_CPU0_P1")
		)
		(pad "AF51" smd circle
			(at 12.370054 -16.560038 180)
			(size 0.450088 0.450088)
			(layers "F.Cu" "F.Mask" "F.Paste")
			(net "GND")
		)
		(pad "AF52" smd circle
			(at 13.310108 -16.560038 180)
			(size 0.450088 0.450088)
			(layers "F.Cu" "F.Mask" "F.Paste")
			(net "PVDDCR_CPU0_P1")
		)
		(pad "AF53" smd circle
			(at 14.249908 -16.560038 180)
			(size 0.450088 0.450088)
			(layers "F.Cu" "F.Mask" "F.Paste")
			(net "PVDDCR_CPU0_P1")
		)
		(pad "AF54" smd circle
			(at 15.189962 -16.560038 180)
			(size 0.450088 0.450088)
			(layers "F.Cu" "F.Mask" "F.Paste")
			(net "GND")
		)
		(pad "AF55" smd circle
			(at 16.130016 -16.560038 180)
			(size 0.450088 0.450088)
			(layers "F.Cu" "F.Mask" "F.Paste")
			(net "M_C_CPU1_SA_DQS_DN<8>")
		)
		(pad "AF56" smd circle
			(at 17.07007 -16.560038 180)
			(size 0.450088 0.450088)
			(layers "F.Cu" "F.Mask" "F.Paste")
			(net "M_C_CPU1_SA_DQS_DN<3>")
		)
		(pad "AF57" smd circle
			(at 18.010124 -16.560038 180)
			(size 0.450088 0.450088)
			(layers "F.Cu" "F.Mask" "F.Paste")
			(net "PVDDIO_P1")
		)
		(pad "AF58" smd circle
			(at 18.949924 -16.560038 180)
			(size 0.450088 0.450088)
			(layers "F.Cu" "F.Mask" "F.Paste")
			(net "M_D_CPU1_SA_DQS_DN<8>")
		)
		(pad "AF59" smd circle
			(at 19.889978 -16.560038 180)
			(size 0.450088 0.450088)
			(layers "F.Cu" "F.Mask" "F.Paste")
			(net "GND")
		)
		(pad "AF60" smd circle
			(at 20.830032 -16.560038 180)
			(size 0.450088 0.450088)
			(layers "F.Cu" "F.Mask" "F.Paste")
			(net "M_D_CPU1_SA_DQS_DN<3>")
		)
		(pad "AF61" smd circle
			(at 21.770086 -16.560038 180)
			(size 0.450088 0.450088)
			(layers "F.Cu" "F.Mask" "F.Paste")
			(net "GND")
		)
		(pad "AF62" smd circle
			(at 22.709886 -16.560038 180)
			(size 0.450088 0.450088)
			(layers "F.Cu" "F.Mask" "F.Paste")
			(net "M_B_CPU1_SA_DQS_DN<8>")
		)
		(pad "AF63" smd circle
			(at 23.64994 -16.560038 180)
			(size 0.450088 0.450088)
			(layers "F.Cu" "F.Mask" "F.Paste")
			(net "M_B_CPU1_SA_DQS_DN<3>")
		)
		(pad "AF64" smd circle
			(at 24.589994 -16.560038 180)
			(size 0.450088 0.450088)
			(layers "F.Cu" "F.Mask" "F.Paste")
			(net "PVDDIO_P1")
		)
		(pad "AF65" smd circle
			(at 25.530048 -16.560038 180)
			(size 0.450088 0.450088)
			(layers "F.Cu" "F.Mask" "F.Paste")
			(net "M_F_CPU1_SA_DQS_DN<8>")
		)
		(pad "AF66" smd circle
			(at 26.470102 -16.560038 180)
			(size 0.450088 0.450088)
			(layers "F.Cu" "F.Mask" "F.Paste")
			(net "GND")
		)
		(pad "AF67" smd circle
			(at 27.409902 -16.560038 180)
			(size 0.450088 0.450088)
			(layers "F.Cu" "F.Mask" "F.Paste")
			(net "M_F_CPU1_SA_DQS_DN<3>")
		)
		(pad "AF68" smd circle
			(at 28.349956 -16.560038 180)
			(size 0.450088 0.450088)
			(layers "F.Cu" "F.Mask" "F.Paste")
			(net "GND")
		)
		(pad "AF69" smd circle
			(at 29.29001 -16.560038 180)
			(size 0.450088 0.450088)
			(layers "F.Cu" "F.Mask" "F.Paste")
			(net "M_E_CPU1_SA_DQS_DN<8>")
		)
		(pad "AF70" smd circle
			(at 30.230064 -16.560038 180)
			(size 0.450088 0.450088)
			(layers "F.Cu" "F.Mask" "F.Paste")
			(net "M_E_CPU1_SA_DQS_DN<3>")
		)
		(pad "AF71" smd circle
			(at 31.170118 -16.560038 180)
			(size 0.450088 0.450088)
			(layers "F.Cu" "F.Mask" "F.Paste")
			(net "PVDDIO_P1")
		)
		(pad "AF72" smd circle
			(at 32.109918 -16.560038 180)
			(size 0.450088 0.450088)
			(layers "F.Cu" "F.Mask" "F.Paste")
			(net "M_A_CPU1_SA_DQS_DN<8>")
		)
		(pad "AF73" smd circle
			(at 33.049972 -16.560038 180)
			(size 0.450088 0.450088)
			(layers "F.Cu" "F.Mask" "F.Paste")
			(net "GND")
		)
		(pad "AF74" smd circle
			(at 33.990026 -16.560038 180)
			(size 0.450088 0.450088)
			(layers "F.Cu" "F.Mask" "F.Paste")
			(net "M_A_CPU1_SA_DQS_DN<3>")
		)
		(pad "AG1" smd circle
			(at -34.159952 -15.750032 180)
			(size 0.450088 0.450088)
			(layers "F.Cu" "F.Mask" "F.Paste")
			(net "GND")
		)
		(pad "AG2" smd circle
			(at -33.219898 -15.750032 180)
			(size 0.450088 0.450088)
			(layers "F.Cu" "F.Mask" "F.Paste")
			(net "M_G_CPU1_SA_DQ<28>")
		)
		(pad "AG3" smd circle
			(at -32.280098 -15.750032 180)
			(size 0.450088 0.450088)
			(layers "F.Cu" "F.Mask" "F.Paste")
			(net "M_G_CPU1_SA_DQS_DP<8>")
		)
		(pad "AG4" smd circle
			(at -31.340044 -15.750032 180)
			(size 0.450088 0.450088)
			(layers "F.Cu" "F.Mask" "F.Paste")
			(net "GND")
		)
		(pad "AG5" smd circle
			(at -30.39999 -15.750032 180)
			(size 0.450088 0.450088)
			(layers "F.Cu" "F.Mask" "F.Paste")
			(net "M_K_CPU1_SA_DQ<28>")
		)
		(pad "AG6" smd circle
			(at -29.459936 -15.750032 180)
			(size 0.450088 0.450088)
			(layers "F.Cu" "F.Mask" "F.Paste")
			(net "GND")
		)
		(pad "AG7" smd circle
			(at -28.519882 -15.750032 180)
			(size 0.450088 0.450088)
			(layers "F.Cu" "F.Mask" "F.Paste")
			(net "M_K_CPU1_SA_DQS_DP<8>")
		)
		(pad "AG8" smd circle
			(at -27.580082 -15.750032 180)
			(size 0.450088 0.450088)
			(layers "F.Cu" "F.Mask" "F.Paste")
			(net "GND")
		)
		(pad "AG9" smd circle
			(at -26.640028 -15.750032 180)
			(size 0.450088 0.450088)
			(layers "F.Cu" "F.Mask" "F.Paste")
			(net "M_L_CPU1_SA_DQ<28>")
		)
		(pad "AG10" smd circle
			(at -25.699974 -15.750032 180)
			(size 0.450088 0.450088)
			(layers "F.Cu" "F.Mask" "F.Paste")
			(net "M_L_CPU1_SA_DQS_DP<8>")
		)
		(pad "AG11" smd circle
			(at -24.75992 -15.750032 180)
			(size 0.450088 0.450088)
			(layers "F.Cu" "F.Mask" "F.Paste")
			(net "GND")
		)
		(pad "AG12" smd circle
			(at -23.82012 -15.750032 180)
			(size 0.450088 0.450088)
			(layers "F.Cu" "F.Mask" "F.Paste")
			(net "M_H_CPU1_SA_DQ<28>")
		)
		(pad "AG13" smd circle
			(at -22.880066 -15.750032 180)
			(size 0.450088 0.450088)
			(layers "F.Cu" "F.Mask" "F.Paste")
			(net "GND")
		)
		(pad "AG14" smd circle
			(at -21.940012 -15.750032 180)
			(size 0.450088 0.450088)
			(layers "F.Cu" "F.Mask" "F.Paste")
			(net "M_H_CPU1_SA_DQS_DP<8>")
		)
		(pad "AG15" smd circle
			(at -20.999958 -15.750032 180)
			(size 0.450088 0.450088)
			(layers "F.Cu" "F.Mask" "F.Paste")
			(net "GND")
		)
		(pad "AG16" smd circle
			(at -20.059904 -15.750032 180)
			(size 0.450088 0.450088)
			(layers "F.Cu" "F.Mask" "F.Paste")
			(net "M_J_CPU1_SA_DQ<28>")
		)
		(pad "AG17" smd circle
			(at -19.120104 -15.750032 180)
			(size 0.450088 0.450088)
			(layers "F.Cu" "F.Mask" "F.Paste")
			(net "M_J_CPU1_SA_DQS_DP<8>")
		)
		(pad "AG18" smd circle
			(at -18.18005 -15.750032 180)
			(size 0.450088 0.450088)
			(layers "F.Cu" "F.Mask" "F.Paste")
			(net "GND")
		)
		(pad "AG19" smd circle
			(at -17.239996 -15.750032 180)
			(size 0.450088 0.450088)
			(layers "F.Cu" "F.Mask" "F.Paste")
			(net "M_I_CPU1_SA_DQ<28>")
		)
		(pad "AG20" smd circle
			(at -16.299942 -15.750032 180)
			(size 0.450088 0.450088)
			(layers "F.Cu" "F.Mask" "F.Paste")
			(net "GND")
		)
		(pad "AG21" smd circle
			(at -15.359888 -15.750032 180)
			(size 0.450088 0.450088)
			(layers "F.Cu" "F.Mask" "F.Paste")
			(net "M_I_CPU1_SA_DQS_DP<8>")
		)
		(pad "AG22" smd circle
			(at -14.420088 -15.750032 180)
			(size 0.450088 0.450088)
			(layers "F.Cu" "F.Mask" "F.Paste")
			(net "GND")
		)
		(pad "AG23" smd circle
			(at -13.480034 -15.750032 180)
			(size 0.450088 0.450088)
			(layers "F.Cu" "F.Mask" "F.Paste")
			(net "GMI_CPU0_G0_CPU1_G2_TX_DN<13>")
		)
		(pad "AG24" smd circle
			(at -12.53998 -15.750032 180)
			(size 0.450088 0.450088)
			(layers "F.Cu" "F.Mask" "F.Paste")
			(net "GMI_CPU0_G0_CPU1_G2_TX_DP<13>")
		)
		(pad "AG25" smd circle
			(at -11.599926 -15.750032 180)
			(size 0.450088 0.450088)
			(layers "F.Cu" "F.Mask" "F.Paste")
			(net "GND")
		)
		(pad "AG26" smd circle
			(at -10.659872 -15.750032 180)
			(size 0.450088 0.450088)
			(layers "F.Cu" "F.Mask" "F.Paste")
			(net "GMI_CPU0_G0_CPU1_G2_TX_DN<10>")
		)
		(pad "AG27" smd circle
			(at -9.720072 -15.750032 180)
			(size 0.450088 0.450088)
			(layers "F.Cu" "F.Mask" "F.Paste")
			(net "GMI_CPU0_G0_CPU1_G2_TX_DP<10>")
		)
		(pad "AG28" smd circle
			(at -8.780018 -15.750032 180)
			(size 0.450088 0.450088)
			(layers "F.Cu" "F.Mask" "F.Paste")
			(net "GND")
		)
		(pad "AG29" smd circle
			(at -7.839964 -15.750032 180)
			(size 0.450088 0.450088)
			(layers "F.Cu" "F.Mask" "F.Paste")
			(net "GMI_CPU0_G0_CPU1_G2_TX_DN<7>")
		)
		(pad "AG30" smd circle
			(at -6.89991 -15.750032 180)
			(size 0.450088 0.450088)
			(layers "F.Cu" "F.Mask" "F.Paste")
			(net "GMI_CPU0_G0_CPU1_G2_TX_DP<7>")
		)
		(pad "AG31" smd circle
			(at -5.96011 -15.750032 180)
			(size 0.450088 0.450088)
			(layers "F.Cu" "F.Mask" "F.Paste")
			(net "GND")
		)
		(pad "AG32" smd circle
			(at -5.020056 -15.750032 180)
			(size 0.450088 0.450088)
			(layers "F.Cu" "F.Mask" "F.Paste")
			(net "GMI_CPU0_G0_CPU1_G2_TX_DN<3>")
		)
		(pad "AG33" smd circle
			(at -4.080002 -15.750032 180)
			(size 0.450088 0.450088)
			(layers "F.Cu" "F.Mask" "F.Paste")
			(net "GMI_CPU0_G0_CPU1_G2_TX_DP<3>")
		)
		(pad "AG34" smd circle
			(at -3.139948 -15.750032 180)
			(size 0.450088 0.450088)
			(layers "F.Cu" "F.Mask" "F.Paste")
			(net "GND")
		)
		(pad "AG35" smd circle
			(at -2.199894 -15.750032 180)
			(size 0.450088 0.450088)
			(layers "F.Cu" "F.Mask" "F.Paste")
			(net "PVDDCR_CPU0_P1")
		)
		(pad "AG36" smd circle
			(at -1.260094 -15.750032 180)
			(size 0.450088 0.450088)
			(layers "F.Cu" "F.Mask" "F.Paste")
			(net "PVDDCR_CPU0_P1")
		)
		(pad "AG40" smd circle
			(at 1.560068 -15.750032 180)
			(size 0.450088 0.450088)
			(layers "F.Cu" "F.Mask" "F.Paste")
			(net "PVDDCR_CPU0_P1")
		)
		(pad "AG41" smd circle
			(at 2.500122 -15.750032 180)
			(size 0.450088 0.450088)
			(layers "F.Cu" "F.Mask" "F.Paste")
			(net "PVDDCR_CPU0_P1")
		)
		(pad "AG42" smd circle
			(at 3.439922 -15.750032 180)
			(size 0.450088 0.450088)
			(layers "F.Cu" "F.Mask" "F.Paste")
			(net "GND")
		)
		(pad "AG43" smd circle
			(at 4.379976 -15.750032 180)
			(size 0.450088 0.450088)
			(layers "F.Cu" "F.Mask" "F.Paste")
			(net "GMI_CPU1_G0_CPU0_G2_TX_DP<12>")
		)
		(pad "AG44" smd circle
			(at 5.32003 -15.750032 180)
			(size 0.450088 0.450088)
			(layers "F.Cu" "F.Mask" "F.Paste")
			(net "GMI_CPU1_G0_CPU0_G2_TX_DN<12>")
		)
		(pad "AG45" smd circle
			(at 6.260084 -15.750032 180)
			(size 0.450088 0.450088)
			(layers "F.Cu" "F.Mask" "F.Paste")
			(net "GND")
		)
		(pad "AG46" smd circle
			(at 7.199884 -15.750032 180)
			(size 0.450088 0.450088)
			(layers "F.Cu" "F.Mask" "F.Paste")
			(net "GMI_CPU1_G0_CPU0_G2_TX_DP<8>")
		)
		(pad "AG47" smd circle
			(at 8.139938 -15.750032 180)
			(size 0.450088 0.450088)
			(layers "F.Cu" "F.Mask" "F.Paste")
			(net "GMI_CPU1_G0_CPU0_G2_TX_DN<8>")
		)
		(pad "AG48" smd circle
			(at 9.079992 -15.750032 180)
			(size 0.450088 0.450088)
			(layers "F.Cu" "F.Mask" "F.Paste")
			(net "GND")
		)
		(pad "AG49" smd circle
			(at 10.020046 -15.750032 180)
			(size 0.450088 0.450088)
			(layers "F.Cu" "F.Mask" "F.Paste")
			(net "GMI_CPU1_G0_CPU0_G2_TX_DP<5>")
		)
		(pad "AG50" smd circle
			(at 10.9601 -15.750032 180)
			(size 0.450088 0.450088)
			(layers "F.Cu" "F.Mask" "F.Paste")
			(net "GMI_CPU1_G0_CPU0_G2_TX_DN<5>")
		)
		(pad "AG51" smd circle
			(at 11.8999 -15.750032 180)
			(size 0.450088 0.450088)
			(layers "F.Cu" "F.Mask" "F.Paste")
			(net "GND")
		)
		(pad "AG52" smd circle
			(at 12.839954 -15.750032 180)
			(size 0.450088 0.450088)
			(layers "F.Cu" "F.Mask" "F.Paste")
			(net "GMI_CPU1_G0_CPU0_G2_TX_DP<2>")
		)
		(pad "AG53" smd circle
			(at 13.780008 -15.750032 180)
			(size 0.450088 0.450088)
			(layers "F.Cu" "F.Mask" "F.Paste")
			(net "GMI_CPU1_G0_CPU0_G2_TX_DN<2>")
		)
		(pad "AG54" smd circle
			(at 14.720062 -15.750032 180)
			(size 0.450088 0.450088)
			(layers "F.Cu" "F.Mask" "F.Paste")
			(net "GND")
		)
		(pad "AG55" smd circle
			(at 15.660116 -15.750032 180)
			(size 0.450088 0.450088)
			(layers "F.Cu" "F.Mask" "F.Paste")
			(net "M_C_CPU1_SA_DQS_DP<8>")
		)
		(pad "AG56" smd circle
			(at 16.599916 -15.750032 180)
			(size 0.450088 0.450088)
			(layers "F.Cu" "F.Mask" "F.Paste")
			(net "GND")
		)
		(pad "AG57" smd circle
			(at 17.53997 -15.750032 180)
			(size 0.450088 0.450088)
			(layers "F.Cu" "F.Mask" "F.Paste")
			(net "M_C_CPU1_SA_DQ<28>")
		)
		(pad "AG58" smd circle
			(at 18.480024 -15.750032 180)
			(size 0.450088 0.450088)
			(layers "F.Cu" "F.Mask" "F.Paste")
			(net "GND")
		)
		(pad "AG59" smd circle
			(at 19.420078 -15.750032 180)
			(size 0.450088 0.450088)
			(layers "F.Cu" "F.Mask" "F.Paste")
			(net "M_D_CPU1_SA_DQS_DP<8>")
		)
		(pad "AG60" smd circle
			(at 20.359878 -15.750032 180)
			(size 0.450088 0.450088)
			(layers "F.Cu" "F.Mask" "F.Paste")
			(net "M_D_CPU1_SA_DQ<28>")
		)
		(pad "AG61" smd circle
			(at 21.299932 -15.750032 180)
			(size 0.450088 0.450088)
			(layers "F.Cu" "F.Mask" "F.Paste")
			(net "GND")
		)
		(pad "AG62" smd circle
			(at 22.239986 -15.750032 180)
			(size 0.450088 0.450088)
			(layers "F.Cu" "F.Mask" "F.Paste")
			(net "M_B_CPU1_SA_DQS_DP<8>")
		)
		(pad "AG63" smd circle
			(at 23.18004 -15.750032 180)
			(size 0.450088 0.450088)
			(layers "F.Cu" "F.Mask" "F.Paste")
			(net "GND")
		)
		(pad "AG64" smd circle
			(at 24.120094 -15.750032 180)
			(size 0.450088 0.450088)
			(layers "F.Cu" "F.Mask" "F.Paste")
			(net "M_B_CPU1_SA_DQ<28>")
		)
		(pad "AG65" smd circle
			(at 25.059894 -15.750032 180)
			(size 0.450088 0.450088)
			(layers "F.Cu" "F.Mask" "F.Paste")
			(net "GND")
		)
		(pad "AG66" smd circle
			(at 25.999948 -15.750032 180)
			(size 0.450088 0.450088)
			(layers "F.Cu" "F.Mask" "F.Paste")
			(net "M_F_CPU1_SA_DQS_DP<8>")
		)
		(pad "AG67" smd circle
			(at 26.940002 -15.750032 180)
			(size 0.450088 0.450088)
			(layers "F.Cu" "F.Mask" "F.Paste")
			(net "M_F_CPU1_SA_DQ<28>")
		)
		(pad "AG68" smd circle
			(at 27.880056 -15.750032 180)
			(size 0.450088 0.450088)
			(layers "F.Cu" "F.Mask" "F.Paste")
			(net "GND")
		)
		(pad "AG69" smd circle
			(at 28.82011 -15.750032 180)
			(size 0.450088 0.450088)
			(layers "F.Cu" "F.Mask" "F.Paste")
			(net "M_E_CPU1_SA_DQS_DP<8>")
		)
		(pad "AG70" smd circle
			(at 29.75991 -15.750032 180)
			(size 0.450088 0.450088)
			(layers "F.Cu" "F.Mask" "F.Paste")
			(net "GND")
		)
		(pad "AG71" smd circle
			(at 30.699964 -15.750032 180)
			(size 0.450088 0.450088)
			(layers "F.Cu" "F.Mask" "F.Paste")
			(net "M_E_CPU1_SA_DQ<28>")
		)
		(pad "AG72" smd circle
			(at 31.640018 -15.750032 180)
			(size 0.450088 0.450088)
			(layers "F.Cu" "F.Mask" "F.Paste")
			(net "GND")
		)
		(pad "AG73" smd circle
			(at 32.580072 -15.750032 180)
			(size 0.450088 0.450088)
			(layers "F.Cu" "F.Mask" "F.Paste")
			(net "M_A_CPU1_SA_DQS_DP<8>")
		)
		(pad "AG74" smd circle
			(at 33.519872 -15.750032 180)
			(size 0.450088 0.450088)
			(layers "F.Cu" "F.Mask" "F.Paste")
			(net "M_A_CPU1_SA_DQ<28>")
		)
		(pad "AG75" smd circle
			(at 34.459926 -15.750032 180)
			(size 0.450088 0.450088)
			(layers "F.Cu" "F.Mask" "F.Paste")
			(net "GND")
		)
		(pad "AH2" smd circle
			(at -33.690052 -14.940026 180)
			(size 0.450088 0.450088)
			(layers "F.Cu" "F.Mask" "F.Paste")
			(net "M_G_CPU1_SA_DQ<30>")
		)
		(pad "AH3" smd circle
			(at -32.749998 -14.940026 180)
			(size 0.450088 0.450088)
			(layers "F.Cu" "F.Mask" "F.Paste")
			(net "GND")
		)
		(pad "AH4" smd circle
			(at -31.809944 -14.940026 180)
			(size 0.450088 0.450088)
			(layers "F.Cu" "F.Mask" "F.Paste")
			(net "M_G_CPU1_SA_DQ<29>")
		)
		(pad "AH5" smd circle
			(at -30.86989 -14.940026 180)
			(size 0.450088 0.450088)
			(layers "F.Cu" "F.Mask" "F.Paste")
			(net "GND")
		)
		(pad "AH6" smd circle
			(at -29.93009 -14.940026 180)
			(size 0.450088 0.450088)
			(layers "F.Cu" "F.Mask" "F.Paste")
			(net "M_K_CPU1_SA_DQ<30>")
		)
		(pad "AH7" smd circle
			(at -28.990036 -14.940026 180)
			(size 0.450088 0.450088)
			(layers "F.Cu" "F.Mask" "F.Paste")
			(net "M_K_CPU1_SA_DQ<29>")
		)
		(pad "AH8" smd circle
			(at -28.049982 -14.940026 180)
			(size 0.450088 0.450088)
			(layers "F.Cu" "F.Mask" "F.Paste")
			(net "GND")
		)
		(pad "AH9" smd circle
			(at -27.109928 -14.940026 180)
			(size 0.450088 0.450088)
			(layers "F.Cu" "F.Mask" "F.Paste")
			(net "M_L_CPU1_SA_DQ<30>")
		)
		(pad "AH10" smd circle
			(at -26.170128 -14.940026 180)
			(size 0.450088 0.450088)
			(layers "F.Cu" "F.Mask" "F.Paste")
			(net "GND")
		)
		(pad "AH11" smd circle
			(at -25.230074 -14.940026 180)
			(size 0.450088 0.450088)
			(layers "F.Cu" "F.Mask" "F.Paste")
			(net "M_L_CPU1_SA_DQ<29>")
		)
		(pad "AH12" smd circle
			(at -24.29002 -14.940026 180)
			(size 0.450088 0.450088)
			(layers "F.Cu" "F.Mask" "F.Paste")
			(net "GND")
		)
		(pad "AH13" smd circle
			(at -23.349966 -14.940026 180)
			(size 0.450088 0.450088)
			(layers "F.Cu" "F.Mask" "F.Paste")
			(net "M_H_CPU1_SA_DQ<30>")
		)
		(pad "AH14" smd circle
			(at -22.409912 -14.940026 180)
			(size 0.450088 0.450088)
			(layers "F.Cu" "F.Mask" "F.Paste")
			(net "M_H_CPU1_SA_DQ<29>")
		)
		(pad "AH15" smd circle
			(at -21.470112 -14.940026 180)
			(size 0.450088 0.450088)
			(layers "F.Cu" "F.Mask" "F.Paste")
			(net "GND")
		)
		(pad "AH16" smd circle
			(at -20.530058 -14.940026 180)
			(size 0.450088 0.450088)
			(layers "F.Cu" "F.Mask" "F.Paste")
			(net "M_J_CPU1_SA_DQ<30>")
		)
		(pad "AH17" smd circle
			(at -19.590004 -14.940026 180)
			(size 0.450088 0.450088)
			(layers "F.Cu" "F.Mask" "F.Paste")
			(net "GND")
		)
		(pad "AH18" smd circle
			(at -18.64995 -14.940026 180)
			(size 0.450088 0.450088)
			(layers "F.Cu" "F.Mask" "F.Paste")
			(net "M_J_CPU1_SA_DQ<29>")
		)
		(pad "AH19" smd circle
			(at -17.709896 -14.940026 180)
			(size 0.450088 0.450088)
			(layers "F.Cu" "F.Mask" "F.Paste")
			(net "GND")
		)
		(pad "AH20" smd circle
			(at -16.770096 -14.940026 180)
			(size 0.450088 0.450088)
			(layers "F.Cu" "F.Mask" "F.Paste")
			(net "M_I_CPU1_SA_DQ<30>")
		)
		(pad "AH21" smd circle
			(at -15.830042 -14.940026 180)
			(size 0.450088 0.450088)
			(layers "F.Cu" "F.Mask" "F.Paste")
			(net "M_I_CPU1_SA_DQ<29>")
		)
		(pad "AH22" smd circle
			(at -14.889988 -14.940026 180)
			(size 0.450088 0.450088)
			(layers "F.Cu" "F.Mask" "F.Paste")
			(net "PVDDCR_SOC_P1")
		)
		(pad "AH23" smd circle
			(at -13.949934 -14.940026 180)
			(size 0.450088 0.450088)
			(layers "F.Cu" "F.Mask" "F.Paste")
			(net "GND")
		)
		(pad "AH24" smd circle
			(at -13.00988 -14.940026 180)
			(size 0.450088 0.450088)
			(layers "F.Cu" "F.Mask" "F.Paste")
			(net "GND")
		)
		(pad "AH25" smd circle
			(at -12.07008 -14.940026 180)
			(size 0.450088 0.450088)
			(layers "F.Cu" "F.Mask" "F.Paste")
			(net "GND")
		)
		(pad "AH26" smd circle
			(at -11.130026 -14.940026 180)
			(size 0.450088 0.450088)
			(layers "F.Cu" "F.Mask" "F.Paste")
			(net "GND")
		)
		(pad "AH27" smd circle
			(at -10.189972 -14.940026 180)
			(size 0.450088 0.450088)
			(layers "F.Cu" "F.Mask" "F.Paste")
			(net "GND")
		)
		(pad "AH28" smd circle
			(at -9.249918 -14.940026 180)
			(size 0.450088 0.450088)
			(layers "F.Cu" "F.Mask" "F.Paste")
			(net "GND")
		)
		(pad "AH29" smd circle
			(at -8.310118 -14.940026 180)
			(size 0.450088 0.450088)
			(layers "F.Cu" "F.Mask" "F.Paste")
			(net "GND")
		)
		(pad "AH30" smd circle
			(at -7.370064 -14.940026 180)
			(size 0.450088 0.450088)
			(layers "F.Cu" "F.Mask" "F.Paste")
			(net "GND")
		)
		(pad "AH31" smd circle
			(at -6.43001 -14.940026 180)
			(size 0.450088 0.450088)
			(layers "F.Cu" "F.Mask" "F.Paste")
			(net "GND")
		)
		(pad "AH32" smd circle
			(at -5.489956 -14.940026 180)
			(size 0.450088 0.450088)
			(layers "F.Cu" "F.Mask" "F.Paste")
			(net "GND")
		)
		(pad "AH33" smd circle
			(at -4.549902 -14.940026 180)
			(size 0.450088 0.450088)
			(layers "F.Cu" "F.Mask" "F.Paste")
			(net "GND")
		)
		(pad "AH34" smd circle
			(at -3.610102 -14.940026 180)
			(size 0.450088 0.450088)
			(layers "F.Cu" "F.Mask" "F.Paste")
			(net "GND")
		)
		(pad "AH35" smd circle
			(at -2.670048 -14.940026 180)
			(size 0.450088 0.450088)
			(layers "F.Cu" "F.Mask" "F.Paste")
			(net "GMI_CPU0_G1_CPU1_G3_TX_DN<2>")
		)
		(pad "AH36" smd circle
			(at -1.729994 -14.940026 180)
			(size 0.450088 0.450088)
			(layers "F.Cu" "F.Mask" "F.Paste")
			(net "GMI_CPU0_G1_CPU1_G3_TX_DP<2>")
		)
		(pad "AH37" smd circle
			(at -0.78994 -14.940026 180)
			(size 0.450088 0.450088)
			(layers "F.Cu" "F.Mask" "F.Paste")
			(net "GND")
		)
		(pad "AH39" smd circle
			(at 1.089914 -14.940026 180)
			(size 0.450088 0.450088)
			(layers "F.Cu" "F.Mask" "F.Paste")
			(net "GND")
		)
		(pad "AH40" smd circle
			(at 2.029968 -14.940026 180)
			(size 0.450088 0.450088)
			(layers "F.Cu" "F.Mask" "F.Paste")
			(net "P5E_CPU1_G1_TX_DP<2>")
		)
		(pad "AH41" smd circle
			(at 2.970022 -14.940026 180)
			(size 0.450088 0.450088)
			(layers "F.Cu" "F.Mask" "F.Paste")
			(net "P5E_CPU1_G1_TX_DN<2>")
		)
		(pad "AH42" smd circle
			(at 3.910076 -14.940026 180)
			(size 0.450088 0.450088)
			(layers "F.Cu" "F.Mask" "F.Paste")
			(net "GND")
		)
		(pad "AH43" smd circle
			(at 4.849876 -14.940026 180)
			(size 0.450088 0.450088)
			(layers "F.Cu" "F.Mask" "F.Paste")
			(net "GND")
		)
		(pad "AH44" smd circle
			(at 5.78993 -14.940026 180)
			(size 0.450088 0.450088)
			(layers "F.Cu" "F.Mask" "F.Paste")
			(net "GND")
		)
		(pad "AH45" smd circle
			(at 6.729984 -14.940026 180)
			(size 0.450088 0.450088)
			(layers "F.Cu" "F.Mask" "F.Paste")
			(net "GND")
		)
		(pad "AH46" smd circle
			(at 7.670038 -14.940026 180)
			(size 0.450088 0.450088)
			(layers "F.Cu" "F.Mask" "F.Paste")
			(net "GND")
		)
		(pad "AH47" smd circle
			(at 8.610092 -14.940026 180)
			(size 0.450088 0.450088)
			(layers "F.Cu" "F.Mask" "F.Paste")
			(net "GND")
		)
		(pad "AH48" smd circle
			(at 9.549892 -14.940026 180)
			(size 0.450088 0.450088)
			(layers "F.Cu" "F.Mask" "F.Paste")
			(net "GND")
		)
		(pad "AH49" smd circle
			(at 10.489946 -14.940026 180)
			(size 0.450088 0.450088)
			(layers "F.Cu" "F.Mask" "F.Paste")
			(net "GND")
		)
		(pad "AH50" smd circle
			(at 11.43 -14.940026 180)
			(size 0.450088 0.450088)
			(layers "F.Cu" "F.Mask" "F.Paste")
			(net "GND")
		)
		(pad "AH51" smd circle
			(at 12.370054 -14.940026 180)
			(size 0.450088 0.450088)
			(layers "F.Cu" "F.Mask" "F.Paste")
			(net "GND")
		)
		(pad "AH52" smd circle
			(at 13.310108 -14.940026 180)
			(size 0.450088 0.450088)
			(layers "F.Cu" "F.Mask" "F.Paste")
			(net "GND")
		)
		(pad "AH53" smd circle
			(at 14.249908 -14.940026 180)
			(size 0.450088 0.450088)
			(layers "F.Cu" "F.Mask" "F.Paste")
			(net "GND")
		)
		(pad "AH54" smd circle
			(at 15.189962 -14.940026 180)
			(size 0.450088 0.450088)
			(layers "F.Cu" "F.Mask" "F.Paste")
			(net "PVDDIO_P1")
		)
		(pad "AH55" smd circle
			(at 16.130016 -14.940026 180)
			(size 0.450088 0.450088)
			(layers "F.Cu" "F.Mask" "F.Paste")
			(net "M_C_CPU1_SA_DQ<29>")
		)
		(pad "AH56" smd circle
			(at 17.07007 -14.940026 180)
			(size 0.450088 0.450088)
			(layers "F.Cu" "F.Mask" "F.Paste")
			(net "M_C_CPU1_SA_DQ<30>")
		)
		(pad "AH57" smd circle
			(at 18.010124 -14.940026 180)
			(size 0.450088 0.450088)
			(layers "F.Cu" "F.Mask" "F.Paste")
			(net "GND")
		)
		(pad "AH58" smd circle
			(at 18.949924 -14.940026 180)
			(size 0.450088 0.450088)
			(layers "F.Cu" "F.Mask" "F.Paste")
			(net "M_D_CPU1_SA_DQ<29>")
		)
		(pad "AH59" smd circle
			(at 19.889978 -14.940026 180)
			(size 0.450088 0.450088)
			(layers "F.Cu" "F.Mask" "F.Paste")
			(net "GND")
		)
		(pad "AH60" smd circle
			(at 20.830032 -14.940026 180)
			(size 0.450088 0.450088)
			(layers "F.Cu" "F.Mask" "F.Paste")
			(net "M_D_CPU1_SA_DQ<30>")
		)
		(pad "AH61" smd circle
			(at 21.770086 -14.940026 180)
			(size 0.450088 0.450088)
			(layers "F.Cu" "F.Mask" "F.Paste")
			(net "GND")
		)
		(pad "AH62" smd circle
			(at 22.709886 -14.940026 180)
			(size 0.450088 0.450088)
			(layers "F.Cu" "F.Mask" "F.Paste")
			(net "M_B_CPU1_SA_DQ<29>")
		)
		(pad "AH63" smd circle
			(at 23.64994 -14.940026 180)
			(size 0.450088 0.450088)
			(layers "F.Cu" "F.Mask" "F.Paste")
			(net "M_B_CPU1_SA_DQ<30>")
		)
		(pad "AH64" smd circle
			(at 24.589994 -14.940026 180)
			(size 0.450088 0.450088)
			(layers "F.Cu" "F.Mask" "F.Paste")
			(net "GND")
		)
		(pad "AH65" smd circle
			(at 25.530048 -14.940026 180)
			(size 0.450088 0.450088)
			(layers "F.Cu" "F.Mask" "F.Paste")
			(net "M_F_CPU1_SA_DQ<29>")
		)
		(pad "AH66" smd circle
			(at 26.470102 -14.940026 180)
			(size 0.450088 0.450088)
			(layers "F.Cu" "F.Mask" "F.Paste")
			(net "GND")
		)
		(pad "AH67" smd circle
			(at 27.409902 -14.940026 180)
			(size 0.450088 0.450088)
			(layers "F.Cu" "F.Mask" "F.Paste")
			(net "M_F_CPU1_SA_DQ<30>")
		)
		(pad "AH68" smd circle
			(at 28.349956 -14.940026 180)
			(size 0.450088 0.450088)
			(layers "F.Cu" "F.Mask" "F.Paste")
			(net "GND")
		)
		(pad "AH69" smd circle
			(at 29.29001 -14.940026 180)
			(size 0.450088 0.450088)
			(layers "F.Cu" "F.Mask" "F.Paste")
			(net "M_E_CPU1_SA_DQ<29>")
		)
		(pad "AH70" smd circle
			(at 30.230064 -14.940026 180)
			(size 0.450088 0.450088)
			(layers "F.Cu" "F.Mask" "F.Paste")
			(net "M_E_CPU1_SA_DQ<30>")
		)
		(pad "AH71" smd circle
			(at 31.170118 -14.940026 180)
			(size 0.450088 0.450088)
			(layers "F.Cu" "F.Mask" "F.Paste")
			(net "GND")
		)
		(pad "AH72" smd circle
			(at 32.109918 -14.940026 180)
			(size 0.450088 0.450088)
			(layers "F.Cu" "F.Mask" "F.Paste")
			(net "M_A_CPU1_SA_DQ<29>")
		)
		(pad "AH73" smd circle
			(at 33.049972 -14.940026 180)
			(size 0.450088 0.450088)
			(layers "F.Cu" "F.Mask" "F.Paste")
			(net "GND")
		)
		(pad "AH74" smd circle
			(at 33.990026 -14.940026 180)
			(size 0.450088 0.450088)
			(layers "F.Cu" "F.Mask" "F.Paste")
			(net "M_A_CPU1_SA_DQ<30>")
		)
		(pad "AJ1" smd circle
			(at -34.159952 -14.13002 180)
			(size 0.450088 0.450088)
			(layers "F.Cu" "F.Mask" "F.Paste")
			(net "GND")
		)
		(pad "AJ2" smd circle
			(at -33.219898 -14.13002 180)
			(size 0.450088 0.450088)
			(layers "F.Cu" "F.Mask" "F.Paste")
			(net "M_G_CPU1_SA_CB<0>")
		)
		(pad "AJ3" smd circle
			(at -32.280098 -14.13002 180)
			(size 0.450088 0.450088)
			(layers "F.Cu" "F.Mask" "F.Paste")
			(net "M_G_CPU1_SA_DQ<31>")
		)
		(pad "AJ4" smd circle
			(at -31.340044 -14.13002 180)
			(size 0.450088 0.450088)
			(layers "F.Cu" "F.Mask" "F.Paste")
			(net "PVDDCR_SOC_P1")
		)
		(pad "AJ5" smd circle
			(at -30.39999 -14.13002 180)
			(size 0.450088 0.450088)
			(layers "F.Cu" "F.Mask" "F.Paste")
			(net "M_K_CPU1_SA_CB<0>")
		)
		(pad "AJ6" smd circle
			(at -29.459936 -14.13002 180)
			(size 0.450088 0.450088)
			(layers "F.Cu" "F.Mask" "F.Paste")
			(net "GND")
		)
		(pad "AJ7" smd circle
			(at -28.519882 -14.13002 180)
			(size 0.450088 0.450088)
			(layers "F.Cu" "F.Mask" "F.Paste")
			(net "M_K_CPU1_SA_DQ<31>")
		)
		(pad "AJ8" smd circle
			(at -27.580082 -14.13002 180)
			(size 0.450088 0.450088)
			(layers "F.Cu" "F.Mask" "F.Paste")
			(net "GND")
		)
		(pad "AJ9" smd circle
			(at -26.640028 -14.13002 180)
			(size 0.450088 0.450088)
			(layers "F.Cu" "F.Mask" "F.Paste")
			(net "M_L_CPU1_SA_CB<0>")
		)
		(pad "AJ10" smd circle
			(at -25.699974 -14.13002 180)
			(size 0.450088 0.450088)
			(layers "F.Cu" "F.Mask" "F.Paste")
			(net "M_L_CPU1_SA_DQ<31>")
		)
		(pad "AJ11" smd circle
			(at -24.75992 -14.13002 180)
			(size 0.450088 0.450088)
			(layers "F.Cu" "F.Mask" "F.Paste")
			(net "PVDDCR_SOC_P1")
		)
		(pad "AJ12" smd circle
			(at -23.82012 -14.13002 180)
			(size 0.450088 0.450088)
			(layers "F.Cu" "F.Mask" "F.Paste")
			(net "M_H_CPU1_SA_CB<0>")
		)
		(pad "AJ13" smd circle
			(at -22.880066 -14.13002 180)
			(size 0.450088 0.450088)
			(layers "F.Cu" "F.Mask" "F.Paste")
			(net "GND")
		)
		(pad "AJ14" smd circle
			(at -21.940012 -14.13002 180)
			(size 0.450088 0.450088)
			(layers "F.Cu" "F.Mask" "F.Paste")
			(net "M_H_CPU1_SA_DQ<31>")
		)
		(pad "AJ15" smd circle
			(at -20.999958 -14.13002 180)
			(size 0.450088 0.450088)
			(layers "F.Cu" "F.Mask" "F.Paste")
			(net "GND")
		)
		(pad "AJ16" smd circle
			(at -20.059904 -14.13002 180)
			(size 0.450088 0.450088)
			(layers "F.Cu" "F.Mask" "F.Paste")
			(net "M_J_CPU1_SA_CB<0>")
		)
		(pad "AJ17" smd circle
			(at -19.120104 -14.13002 180)
			(size 0.450088 0.450088)
			(layers "F.Cu" "F.Mask" "F.Paste")
			(net "M_J_CPU1_SA_DQ<31>")
		)
		(pad "AJ18" smd circle
			(at -18.18005 -14.13002 180)
			(size 0.450088 0.450088)
			(layers "F.Cu" "F.Mask" "F.Paste")
			(net "PVDDCR_SOC_P1")
		)
		(pad "AJ19" smd circle
			(at -17.239996 -14.13002 180)
			(size 0.450088 0.450088)
			(layers "F.Cu" "F.Mask" "F.Paste")
			(net "M_I_CPU1_SA_CB<0>")
		)
		(pad "AJ20" smd circle
			(at -16.299942 -14.13002 180)
			(size 0.450088 0.450088)
			(layers "F.Cu" "F.Mask" "F.Paste")
			(net "GND")
		)
		(pad "AJ21" smd circle
			(at -15.359888 -14.13002 180)
			(size 0.450088 0.450088)
			(layers "F.Cu" "F.Mask" "F.Paste")
			(net "M_I_CPU1_SA_DQ<31>")
		)
		(pad "AJ22" smd circle
			(at -14.420088 -14.13002 180)
			(size 0.450088 0.450088)
			(layers "F.Cu" "F.Mask" "F.Paste")
			(net "GND")
		)
		(pad "AJ23" smd circle
			(at -13.480034 -14.13002 180)
			(size 0.450088 0.450088)
			(layers "F.Cu" "F.Mask" "F.Paste")
			(net "GMI_CPU0_G1_CPU1_G3_TX_DN<14>")
		)
		(pad "AJ24" smd circle
			(at -12.53998 -14.13002 180)
			(size 0.450088 0.450088)
			(layers "F.Cu" "F.Mask" "F.Paste")
			(net "GMI_CPU0_G1_CPU1_G3_TX_DP<14>")
		)
		(pad "AJ25" smd circle
			(at -11.599926 -14.13002 180)
			(size 0.450088 0.450088)
			(layers "F.Cu" "F.Mask" "F.Paste")
			(net "GND")
		)
		(pad "AJ26" smd circle
			(at -10.659872 -14.13002 180)
			(size 0.450088 0.450088)
			(layers "F.Cu" "F.Mask" "F.Paste")
			(net "GMI_CPU0_G1_CPU1_G3_TX_DN<11>")
		)
		(pad "AJ27" smd circle
			(at -9.720072 -14.13002 180)
			(size 0.450088 0.450088)
			(layers "F.Cu" "F.Mask" "F.Paste")
			(net "GMI_CPU0_G1_CPU1_G3_TX_DP<11>")
		)
		(pad "AJ28" smd circle
			(at -8.780018 -14.13002 180)
			(size 0.450088 0.450088)
			(layers "F.Cu" "F.Mask" "F.Paste")
			(net "GND")
		)
		(pad "AJ29" smd circle
			(at -7.839964 -14.13002 180)
			(size 0.450088 0.450088)
			(layers "F.Cu" "F.Mask" "F.Paste")
			(net "GMI_CPU0_G1_CPU1_G3_TX_DN<8>")
		)
		(pad "AJ30" smd circle
			(at -6.89991 -14.13002 180)
			(size 0.450088 0.450088)
			(layers "F.Cu" "F.Mask" "F.Paste")
			(net "GMI_CPU0_G1_CPU1_G3_TX_DP<8>")
		)
		(pad "AJ31" smd circle
			(at -5.96011 -14.13002 180)
			(size 0.450088 0.450088)
			(layers "F.Cu" "F.Mask" "F.Paste")
			(net "GND")
		)
		(pad "AJ32" smd circle
			(at -5.020056 -14.13002 180)
			(size 0.450088 0.450088)
			(layers "F.Cu" "F.Mask" "F.Paste")
			(net "GMI_CPU0_G1_CPU1_G3_TX_DN<5>")
		)
		(pad "AJ33" smd circle
			(at -4.080002 -14.13002 180)
			(size 0.450088 0.450088)
			(layers "F.Cu" "F.Mask" "F.Paste")
			(net "GMI_CPU0_G1_CPU1_G3_TX_DP<5>")
		)
		(pad "AJ34" smd circle
			(at -3.139948 -14.13002 180)
			(size 0.450088 0.450088)
			(layers "F.Cu" "F.Mask" "F.Paste")
			(net "GND")
		)
		(pad "AJ35" smd circle
			(at -2.199894 -14.13002 180)
			(size 0.450088 0.450088)
			(layers "F.Cu" "F.Mask" "F.Paste")
			(net "GND")
		)
		(pad "AJ36" smd circle
			(at -1.260094 -14.13002 180)
			(size 0.450088 0.450088)
			(layers "F.Cu" "F.Mask" "F.Paste")
			(net "GND")
		)
		(pad "AJ40" smd circle
			(at 1.560068 -14.13002 180)
			(size 0.450088 0.450088)
			(layers "F.Cu" "F.Mask" "F.Paste")
			(net "GND")
		)
		(pad "AJ41" smd circle
			(at 2.500122 -14.13002 180)
			(size 0.450088 0.450088)
			(layers "F.Cu" "F.Mask" "F.Paste")
			(net "GND")
		)
		(pad "AJ42" smd circle
			(at 3.439922 -14.13002 180)
			(size 0.450088 0.450088)
			(layers "F.Cu" "F.Mask" "F.Paste")
			(net "GND")
		)
		(pad "AJ43" smd circle
			(at 4.379976 -14.13002 180)
			(size 0.450088 0.450088)
			(layers "F.Cu" "F.Mask" "F.Paste")
			(net "P5E_CPU1_G1_TX_DP<5>")
		)
		(pad "AJ44" smd circle
			(at 5.32003 -14.13002 180)
			(size 0.450088 0.450088)
			(layers "F.Cu" "F.Mask" "F.Paste")
			(net "P5E_CPU1_G1_TX_DN<5>")
		)
		(pad "AJ45" smd circle
			(at 6.260084 -14.13002 180)
			(size 0.450088 0.450088)
			(layers "F.Cu" "F.Mask" "F.Paste")
			(net "GND")
		)
		(pad "AJ46" smd circle
			(at 7.199884 -14.13002 180)
			(size 0.450088 0.450088)
			(layers "F.Cu" "F.Mask" "F.Paste")
			(net "P5E_CPU1_G1_TX_DP<8>")
		)
		(pad "AJ47" smd circle
			(at 8.139938 -14.13002 180)
			(size 0.450088 0.450088)
			(layers "F.Cu" "F.Mask" "F.Paste")
			(net "P5E_CPU1_G1_TX_DN<8>")
		)
		(pad "AJ48" smd circle
			(at 9.079992 -14.13002 180)
			(size 0.450088 0.450088)
			(layers "F.Cu" "F.Mask" "F.Paste")
			(net "GND")
		)
		(pad "AJ49" smd circle
			(at 10.020046 -14.13002 180)
			(size 0.450088 0.450088)
			(layers "F.Cu" "F.Mask" "F.Paste")
			(net "P5E_CPU1_G1_TX_DP<11>")
		)
		(pad "AJ50" smd circle
			(at 10.9601 -14.13002 180)
			(size 0.450088 0.450088)
			(layers "F.Cu" "F.Mask" "F.Paste")
			(net "P5E_CPU1_G1_TX_DN<11>")
		)
		(pad "AJ51" smd circle
			(at 11.8999 -14.13002 180)
			(size 0.450088 0.450088)
			(layers "F.Cu" "F.Mask" "F.Paste")
			(net "GND")
		)
		(pad "AJ52" smd circle
			(at 12.839954 -14.13002 180)
			(size 0.450088 0.450088)
			(layers "F.Cu" "F.Mask" "F.Paste")
			(net "P5E_CPU1_G1_TX_DP<14>")
		)
		(pad "AJ53" smd circle
			(at 13.780008 -14.13002 180)
			(size 0.450088 0.450088)
			(layers "F.Cu" "F.Mask" "F.Paste")
			(net "P5E_CPU1_G1_TX_DN<14>")
		)
		(pad "AJ54" smd circle
			(at 14.720062 -14.13002 180)
			(size 0.450088 0.450088)
			(layers "F.Cu" "F.Mask" "F.Paste")
			(net "GND")
		)
		(pad "AJ55" smd circle
			(at 15.660116 -14.13002 180)
			(size 0.450088 0.450088)
			(layers "F.Cu" "F.Mask" "F.Paste")
			(net "M_C_CPU1_SA_DQ<31>")
		)
		(pad "AJ56" smd circle
			(at 16.599916 -14.13002 180)
			(size 0.450088 0.450088)
			(layers "F.Cu" "F.Mask" "F.Paste")
			(net "GND")
		)
		(pad "AJ57" smd circle
			(at 17.53997 -14.13002 180)
			(size 0.450088 0.450088)
			(layers "F.Cu" "F.Mask" "F.Paste")
			(net "M_C_CPU1_SA_CB<0>")
		)
		(pad "AJ58" smd circle
			(at 18.480024 -14.13002 180)
			(size 0.450088 0.450088)
			(layers "F.Cu" "F.Mask" "F.Paste")
			(net "PVDDIO_P1")
		)
		(pad "AJ59" smd circle
			(at 19.420078 -14.13002 180)
			(size 0.450088 0.450088)
			(layers "F.Cu" "F.Mask" "F.Paste")
			(net "M_D_CPU1_SA_DQ<31>")
		)
		(pad "AJ60" smd circle
			(at 20.359878 -14.13002 180)
			(size 0.450088 0.450088)
			(layers "F.Cu" "F.Mask" "F.Paste")
			(net "M_D_CPU1_SA_CB<0>")
		)
		(pad "AJ61" smd circle
			(at 21.299932 -14.13002 180)
			(size 0.450088 0.450088)
			(layers "F.Cu" "F.Mask" "F.Paste")
			(net "GND")
		)
		(pad "AJ62" smd circle
			(at 22.239986 -14.13002 180)
			(size 0.450088 0.450088)
			(layers "F.Cu" "F.Mask" "F.Paste")
			(net "M_B_CPU1_SA_DQ<31>")
		)
		(pad "AJ63" smd circle
			(at 23.18004 -14.13002 180)
			(size 0.450088 0.450088)
			(layers "F.Cu" "F.Mask" "F.Paste")
			(net "GND")
		)
		(pad "AJ64" smd circle
			(at 24.120094 -14.13002 180)
			(size 0.450088 0.450088)
			(layers "F.Cu" "F.Mask" "F.Paste")
			(net "M_B_CPU1_SA_CB<0>")
		)
		(pad "AJ65" smd circle
			(at 25.059894 -14.13002 180)
			(size 0.450088 0.450088)
			(layers "F.Cu" "F.Mask" "F.Paste")
			(net "PVDDIO_P1")
		)
		(pad "AJ66" smd circle
			(at 25.999948 -14.13002 180)
			(size 0.450088 0.450088)
			(layers "F.Cu" "F.Mask" "F.Paste")
			(net "M_F_CPU1_SA_DQ<31>")
		)
		(pad "AJ67" smd circle
			(at 26.940002 -14.13002 180)
			(size 0.450088 0.450088)
			(layers "F.Cu" "F.Mask" "F.Paste")
			(net "M_F_CPU1_SA_CB<0>")
		)
		(pad "AJ68" smd circle
			(at 27.880056 -14.13002 180)
			(size 0.450088 0.450088)
			(layers "F.Cu" "F.Mask" "F.Paste")
			(net "GND")
		)
		(pad "AJ69" smd circle
			(at 28.82011 -14.13002 180)
			(size 0.450088 0.450088)
			(layers "F.Cu" "F.Mask" "F.Paste")
			(net "M_E_CPU1_SA_DQ<31>")
		)
		(pad "AJ70" smd circle
			(at 29.75991 -14.13002 180)
			(size 0.450088 0.450088)
			(layers "F.Cu" "F.Mask" "F.Paste")
			(net "GND")
		)
		(pad "AJ71" smd circle
			(at 30.699964 -14.13002 180)
			(size 0.450088 0.450088)
			(layers "F.Cu" "F.Mask" "F.Paste")
			(net "M_E_CPU1_SA_CB<0>")
		)
		(pad "AJ72" smd circle
			(at 31.640018 -14.13002 180)
			(size 0.450088 0.450088)
			(layers "F.Cu" "F.Mask" "F.Paste")
			(net "PVDDIO_P1")
		)
		(pad "AJ73" smd circle
			(at 32.580072 -14.13002 180)
			(size 0.450088 0.450088)
			(layers "F.Cu" "F.Mask" "F.Paste")
			(net "M_A_CPU1_SA_DQ<31>")
		)
		(pad "AJ74" smd circle
			(at 33.519872 -14.13002 180)
			(size 0.450088 0.450088)
			(layers "F.Cu" "F.Mask" "F.Paste")
			(net "M_A_CPU1_SA_CB<0>")
		)
		(pad "AJ75" smd circle
			(at 34.459926 -14.13002 180)
			(size 0.450088 0.450088)
			(layers "F.Cu" "F.Mask" "F.Paste")
			(net "GND")
		)
		(pad "AK2" smd circle
			(at -33.690052 -13.320014 180)
			(size 0.450088 0.450088)
			(layers "F.Cu" "F.Mask" "F.Paste")
			(net "M_G_CPU1_SA_CB<2>")
		)
		(pad "AK3" smd circle
			(at -32.749998 -13.320014 180)
			(size 0.450088 0.450088)
			(layers "F.Cu" "F.Mask" "F.Paste")
			(net "GND")
		)
		(pad "AK4" smd circle
			(at -31.809944 -13.320014 180)
			(size 0.450088 0.450088)
			(layers "F.Cu" "F.Mask" "F.Paste")
			(net "M_G_CPU1_SA_CB<1>")
		)
		(pad "AK5" smd circle
			(at -30.86989 -13.320014 180)
			(size 0.450088 0.450088)
			(layers "F.Cu" "F.Mask" "F.Paste")
			(net "GND")
		)
		(pad "AK6" smd circle
			(at -29.93009 -13.320014 180)
			(size 0.450088 0.450088)
			(layers "F.Cu" "F.Mask" "F.Paste")
			(net "M_K_CPU1_SA_CB<2>")
		)
		(pad "AK7" smd circle
			(at -28.990036 -13.320014 180)
			(size 0.450088 0.450088)
			(layers "F.Cu" "F.Mask" "F.Paste")
			(net "M_K_CPU1_SA_CB<1>")
		)
		(pad "AK8" smd circle
			(at -28.049982 -13.320014 180)
			(size 0.450088 0.450088)
			(layers "F.Cu" "F.Mask" "F.Paste")
			(net "GND")
		)
		(pad "AK9" smd circle
			(at -27.109928 -13.320014 180)
			(size 0.450088 0.450088)
			(layers "F.Cu" "F.Mask" "F.Paste")
			(net "M_L_CPU1_SA_CB<2>")
		)
		(pad "AK10" smd circle
			(at -26.170128 -13.320014 180)
			(size 0.450088 0.450088)
			(layers "F.Cu" "F.Mask" "F.Paste")
			(net "GND")
		)
		(pad "AK11" smd circle
			(at -25.230074 -13.320014 180)
			(size 0.450088 0.450088)
			(layers "F.Cu" "F.Mask" "F.Paste")
			(net "M_L_CPU1_SA_CB<1>")
		)
		(pad "AK12" smd circle
			(at -24.29002 -13.320014 180)
			(size 0.450088 0.450088)
			(layers "F.Cu" "F.Mask" "F.Paste")
			(net "GND")
		)
		(pad "AK13" smd circle
			(at -23.349966 -13.320014 180)
			(size 0.450088 0.450088)
			(layers "F.Cu" "F.Mask" "F.Paste")
			(net "M_H_CPU1_SA_CB<2>")
		)
		(pad "AK14" smd circle
			(at -22.409912 -13.320014 180)
			(size 0.450088 0.450088)
			(layers "F.Cu" "F.Mask" "F.Paste")
			(net "M_H_CPU1_SA_CB<1>")
		)
		(pad "AK15" smd circle
			(at -21.470112 -13.320014 180)
			(size 0.450088 0.450088)
			(layers "F.Cu" "F.Mask" "F.Paste")
			(net "GND")
		)
		(pad "AK16" smd circle
			(at -20.530058 -13.320014 180)
			(size 0.450088 0.450088)
			(layers "F.Cu" "F.Mask" "F.Paste")
			(net "M_J_CPU1_SA_CB<2>")
		)
		(pad "AK17" smd circle
			(at -19.590004 -13.320014 180)
			(size 0.450088 0.450088)
			(layers "F.Cu" "F.Mask" "F.Paste")
			(net "GND")
		)
		(pad "AK18" smd circle
			(at -18.64995 -13.320014 180)
			(size 0.450088 0.450088)
			(layers "F.Cu" "F.Mask" "F.Paste")
			(net "M_J_CPU1_SA_CB<1>")
		)
		(pad "AK19" smd circle
			(at -17.709896 -13.320014 180)
			(size 0.450088 0.450088)
			(layers "F.Cu" "F.Mask" "F.Paste")
			(net "GND")
		)
		(pad "AK20" smd circle
			(at -16.770096 -13.320014 180)
			(size 0.450088 0.450088)
			(layers "F.Cu" "F.Mask" "F.Paste")
			(net "M_I_CPU1_SA_CB<2>")
		)
		(pad "AK21" smd circle
			(at -15.830042 -13.320014 180)
			(size 0.450088 0.450088)
			(layers "F.Cu" "F.Mask" "F.Paste")
			(net "M_I_CPU1_SA_CB<1>")
		)
		(pad "AK22" smd circle
			(at -14.889988 -13.320014 180)
			(size 0.450088 0.450088)
			(layers "F.Cu" "F.Mask" "F.Paste")
			(net "GND")
		)
		(pad "AK23" smd circle
			(at -13.949934 -13.320014 180)
			(size 0.450088 0.450088)
			(layers "F.Cu" "F.Mask" "F.Paste")
			(net "PVDDCR_CPU0_P1")
		)
		(pad "AK24" smd circle
			(at -13.00988 -13.320014 180)
			(size 0.450088 0.450088)
			(layers "F.Cu" "F.Mask" "F.Paste")
			(net "PVDDCR_CPU0_P1")
		)
		(pad "AK25" smd circle
			(at -12.07008 -13.320014 180)
			(size 0.450088 0.450088)
			(layers "F.Cu" "F.Mask" "F.Paste")
			(net "GND")
		)
		(pad "AK26" smd circle
			(at -11.130026 -13.320014 180)
			(size 0.450088 0.450088)
			(layers "F.Cu" "F.Mask" "F.Paste")
			(net "PVDDCR_CPU0_P1")
		)
		(pad "AK27" smd circle
			(at -10.189972 -13.320014 180)
			(size 0.450088 0.450088)
			(layers "F.Cu" "F.Mask" "F.Paste")
			(net "PVDDCR_CPU0_P1")
		)
		(pad "AK28" smd circle
			(at -9.249918 -13.320014 180)
			(size 0.450088 0.450088)
			(layers "F.Cu" "F.Mask" "F.Paste")
			(net "GND")
		)
		(pad "AK29" smd circle
			(at -8.310118 -13.320014 180)
			(size 0.450088 0.450088)
			(layers "F.Cu" "F.Mask" "F.Paste")
			(net "PVDDCR_CPU0_P1")
		)
		(pad "AK30" smd circle
			(at -7.370064 -13.320014 180)
			(size 0.450088 0.450088)
			(layers "F.Cu" "F.Mask" "F.Paste")
			(net "PVDDCR_CPU0_P1")
		)
		(pad "AK31" smd circle
			(at -6.43001 -13.320014 180)
			(size 0.450088 0.450088)
			(layers "F.Cu" "F.Mask" "F.Paste")
			(net "GND")
		)
		(pad "AK32" smd circle
			(at -5.489956 -13.320014 180)
			(size 0.450088 0.450088)
			(layers "F.Cu" "F.Mask" "F.Paste")
			(net "PVDDCR_CPU0_P1")
		)
		(pad "AK33" smd circle
			(at -4.549902 -13.320014 180)
			(size 0.450088 0.450088)
			(layers "F.Cu" "F.Mask" "F.Paste")
			(net "PVDDCR_CPU0_P1")
		)
		(pad "AK34" smd circle
			(at -3.610102 -13.320014 180)
			(size 0.450088 0.450088)
			(layers "F.Cu" "F.Mask" "F.Paste")
			(net "GND")
		)
		(pad "AK35" smd circle
			(at -2.670048 -13.320014 180)
			(size 0.450088 0.450088)
			(layers "F.Cu" "F.Mask" "F.Paste")
			(net "GMI_CPU0_G1_CPU1_G3_TX_DN<3>")
		)
		(pad "AK36" smd circle
			(at -1.729994 -13.320014 180)
			(size 0.450088 0.450088)
			(layers "F.Cu" "F.Mask" "F.Paste")
			(net "GMI_CPU0_G1_CPU1_G3_TX_DP<3>")
		)
		(pad "AK37" smd circle
			(at -0.78994 -13.320014 180)
			(size 0.450088 0.450088)
			(layers "F.Cu" "F.Mask" "F.Paste")
			(net "GND")
		)
		(pad "AK39" smd circle
			(at 1.089914 -13.320014 180)
			(size 0.450088 0.450088)
			(layers "F.Cu" "F.Mask" "F.Paste")
			(net "GND")
		)
		(pad "AK40" smd circle
			(at 2.029968 -13.320014 180)
			(size 0.450088 0.450088)
			(layers "F.Cu" "F.Mask" "F.Paste")
			(net "P5E_CPU1_G1_TX_DP<3>")
		)
		(pad "AK41" smd circle
			(at 2.970022 -13.320014 180)
			(size 0.450088 0.450088)
			(layers "F.Cu" "F.Mask" "F.Paste")
			(net "P5E_CPU1_G1_TX_DN<3>")
		)
		(pad "AK42" smd circle
			(at 3.910076 -13.320014 180)
			(size 0.450088 0.450088)
			(layers "F.Cu" "F.Mask" "F.Paste")
			(net "GND")
		)
		(pad "AK43" smd circle
			(at 4.849876 -13.320014 180)
			(size 0.450088 0.450088)
			(layers "F.Cu" "F.Mask" "F.Paste")
			(net "PVDDCR_CPU0_P1")
		)
		(pad "AK44" smd circle
			(at 5.78993 -13.320014 180)
			(size 0.450088 0.450088)
			(layers "F.Cu" "F.Mask" "F.Paste")
			(net "PVDDCR_CPU0_P1")
		)
		(pad "AK45" smd circle
			(at 6.729984 -13.320014 180)
			(size 0.450088 0.450088)
			(layers "F.Cu" "F.Mask" "F.Paste")
			(net "GND")
		)
		(pad "AK46" smd circle
			(at 7.670038 -13.320014 180)
			(size 0.450088 0.450088)
			(layers "F.Cu" "F.Mask" "F.Paste")
			(net "PVDDCR_CPU0_P1")
		)
		(pad "AK47" smd circle
			(at 8.610092 -13.320014 180)
			(size 0.450088 0.450088)
			(layers "F.Cu" "F.Mask" "F.Paste")
			(net "PVDDCR_CPU0_P1")
		)
		(pad "AK48" smd circle
			(at 9.549892 -13.320014 180)
			(size 0.450088 0.450088)
			(layers "F.Cu" "F.Mask" "F.Paste")
			(net "GND")
		)
		(pad "AK49" smd circle
			(at 10.489946 -13.320014 180)
			(size 0.450088 0.450088)
			(layers "F.Cu" "F.Mask" "F.Paste")
			(net "PVDDCR_CPU0_P1")
		)
		(pad "AK50" smd circle
			(at 11.43 -13.320014 180)
			(size 0.450088 0.450088)
			(layers "F.Cu" "F.Mask" "F.Paste")
			(net "PVDDCR_CPU0_P1")
		)
		(pad "AK51" smd circle
			(at 12.370054 -13.320014 180)
			(size 0.450088 0.450088)
			(layers "F.Cu" "F.Mask" "F.Paste")
			(net "GND")
		)
		(pad "AK52" smd circle
			(at 13.310108 -13.320014 180)
			(size 0.450088 0.450088)
			(layers "F.Cu" "F.Mask" "F.Paste")
			(net "PVDDCR_CPU0_P1")
		)
		(pad "AK53" smd circle
			(at 14.249908 -13.320014 180)
			(size 0.450088 0.450088)
			(layers "F.Cu" "F.Mask" "F.Paste")
			(net "PVDDCR_CPU0_P1")
		)
		(pad "AK54" smd circle
			(at 15.189962 -13.320014 180)
			(size 0.450088 0.450088)
			(layers "F.Cu" "F.Mask" "F.Paste")
			(net "GND")
		)
		(pad "AK55" smd circle
			(at 16.130016 -13.320014 180)
			(size 0.450088 0.450088)
			(layers "F.Cu" "F.Mask" "F.Paste")
			(net "M_C_CPU1_SA_CB<1>")
		)
		(pad "AK56" smd circle
			(at 17.07007 -13.320014 180)
			(size 0.450088 0.450088)
			(layers "F.Cu" "F.Mask" "F.Paste")
			(net "M_C_CPU1_SA_CB<2>")
		)
		(pad "AK57" smd circle
			(at 18.010124 -13.320014 180)
			(size 0.450088 0.450088)
			(layers "F.Cu" "F.Mask" "F.Paste")
			(net "GND")
		)
		(pad "AK58" smd circle
			(at 18.949924 -13.320014 180)
			(size 0.450088 0.450088)
			(layers "F.Cu" "F.Mask" "F.Paste")
			(net "M_D_CPU1_SA_CB<1>")
		)
		(pad "AK59" smd circle
			(at 19.889978 -13.320014 180)
			(size 0.450088 0.450088)
			(layers "F.Cu" "F.Mask" "F.Paste")
			(net "GND")
		)
		(pad "AK60" smd circle
			(at 20.830032 -13.320014 180)
			(size 0.450088 0.450088)
			(layers "F.Cu" "F.Mask" "F.Paste")
			(net "M_D_CPU1_SA_CB<2>")
		)
		(pad "AK61" smd circle
			(at 21.770086 -13.320014 180)
			(size 0.450088 0.450088)
			(layers "F.Cu" "F.Mask" "F.Paste")
			(net "GND")
		)
		(pad "AK62" smd circle
			(at 22.709886 -13.320014 180)
			(size 0.450088 0.450088)
			(layers "F.Cu" "F.Mask" "F.Paste")
			(net "M_B_CPU1_SA_CB<1>")
		)
		(pad "AK63" smd circle
			(at 23.64994 -13.320014 180)
			(size 0.450088 0.450088)
			(layers "F.Cu" "F.Mask" "F.Paste")
			(net "M_B_CPU1_SA_CB<2>")
		)
		(pad "AK64" smd circle
			(at 24.589994 -13.320014 180)
			(size 0.450088 0.450088)
			(layers "F.Cu" "F.Mask" "F.Paste")
			(net "GND")
		)
		(pad "AK65" smd circle
			(at 25.530048 -13.320014 180)
			(size 0.450088 0.450088)
			(layers "F.Cu" "F.Mask" "F.Paste")
			(net "M_F_CPU1_SA_CB<1>")
		)
		(pad "AK66" smd circle
			(at 26.470102 -13.320014 180)
			(size 0.450088 0.450088)
			(layers "F.Cu" "F.Mask" "F.Paste")
			(net "GND")
		)
		(pad "AK67" smd circle
			(at 27.409902 -13.320014 180)
			(size 0.450088 0.450088)
			(layers "F.Cu" "F.Mask" "F.Paste")
			(net "M_F_CPU1_SA_CB<2>")
		)
		(pad "AK68" smd circle
			(at 28.349956 -13.320014 180)
			(size 0.450088 0.450088)
			(layers "F.Cu" "F.Mask" "F.Paste")
			(net "GND")
		)
		(pad "AK69" smd circle
			(at 29.29001 -13.320014 180)
			(size 0.450088 0.450088)
			(layers "F.Cu" "F.Mask" "F.Paste")
			(net "M_E_CPU1_SA_CB<1>")
		)
		(pad "AK70" smd circle
			(at 30.230064 -13.320014 180)
			(size 0.450088 0.450088)
			(layers "F.Cu" "F.Mask" "F.Paste")
			(net "M_E_CPU1_SA_CB<2>")
		)
		(pad "AK71" smd circle
			(at 31.170118 -13.320014 180)
			(size 0.450088 0.450088)
			(layers "F.Cu" "F.Mask" "F.Paste")
			(net "GND")
		)
		(pad "AK72" smd circle
			(at 32.109918 -13.320014 180)
			(size 0.450088 0.450088)
			(layers "F.Cu" "F.Mask" "F.Paste")
			(net "M_A_CPU1_SA_CB<1>")
		)
		(pad "AK73" smd circle
			(at 33.049972 -13.320014 180)
			(size 0.450088 0.450088)
			(layers "F.Cu" "F.Mask" "F.Paste")
			(net "GND")
		)
		(pad "AK74" smd circle
			(at 33.990026 -13.320014 180)
			(size 0.450088 0.450088)
			(layers "F.Cu" "F.Mask" "F.Paste")
			(net "M_A_CPU1_SA_CB<2>")
		)
		(pad "AL1" smd circle
			(at -34.159952 -12.510008 180)
			(size 0.450088 0.450088)
			(layers "F.Cu" "F.Mask" "F.Paste")
			(net "GND")
		)
		(pad "AL2" smd circle
			(at -33.219898 -12.510008 180)
			(size 0.450088 0.450088)
			(layers "F.Cu" "F.Mask" "F.Paste")
			(net "M_G_CPU1_SA_DQS_DP<4>")
		)
		(pad "AL3" smd circle
			(at -32.280098 -12.510008 180)
			(size 0.450088 0.450088)
			(layers "F.Cu" "F.Mask" "F.Paste")
			(net "M_G_CPU1_SA_CB<3>")
		)
		(pad "AL4" smd circle
			(at -31.340044 -12.510008 180)
			(size 0.450088 0.450088)
			(layers "F.Cu" "F.Mask" "F.Paste")
			(net "GND")
		)
		(pad "AL5" smd circle
			(at -30.39999 -12.510008 180)
			(size 0.450088 0.450088)
			(layers "F.Cu" "F.Mask" "F.Paste")
			(net "M_K_CPU1_SA_DQS_DP<4>")
		)
		(pad "AL6" smd circle
			(at -29.459936 -12.510008 180)
			(size 0.450088 0.450088)
			(layers "F.Cu" "F.Mask" "F.Paste")
			(net "GND")
		)
		(pad "AL7" smd circle
			(at -28.519882 -12.510008 180)
			(size 0.450088 0.450088)
			(layers "F.Cu" "F.Mask" "F.Paste")
			(net "M_K_CPU1_SA_CB<3>")
		)
		(pad "AL8" smd circle
			(at -27.580082 -12.510008 180)
			(size 0.450088 0.450088)
			(layers "F.Cu" "F.Mask" "F.Paste")
			(net "GND")
		)
		(pad "AL9" smd circle
			(at -26.640028 -12.510008 180)
			(size 0.450088 0.450088)
			(layers "F.Cu" "F.Mask" "F.Paste")
			(net "M_L_CPU1_SA_DQS_DP<4>")
		)
		(pad "AL10" smd circle
			(at -25.699974 -12.510008 180)
			(size 0.450088 0.450088)
			(layers "F.Cu" "F.Mask" "F.Paste")
			(net "M_L_CPU1_SA_CB<3>")
		)
		(pad "AL11" smd circle
			(at -24.75992 -12.510008 180)
			(size 0.450088 0.450088)
			(layers "F.Cu" "F.Mask" "F.Paste")
			(net "GND")
		)
		(pad "AL12" smd circle
			(at -23.82012 -12.510008 180)
			(size 0.450088 0.450088)
			(layers "F.Cu" "F.Mask" "F.Paste")
			(net "M_H_CPU1_SA_DQS_DP<4>")
		)
		(pad "AL13" smd circle
			(at -22.880066 -12.510008 180)
			(size 0.450088 0.450088)
			(layers "F.Cu" "F.Mask" "F.Paste")
			(net "GND")
		)
		(pad "AL14" smd circle
			(at -21.940012 -12.510008 180)
			(size 0.450088 0.450088)
			(layers "F.Cu" "F.Mask" "F.Paste")
			(net "M_H_CPU1_SA_CB<3>")
		)
		(pad "AL15" smd circle
			(at -20.999958 -12.510008 180)
			(size 0.450088 0.450088)
			(layers "F.Cu" "F.Mask" "F.Paste")
			(net "GND")
		)
		(pad "AL16" smd circle
			(at -20.059904 -12.510008 180)
			(size 0.450088 0.450088)
			(layers "F.Cu" "F.Mask" "F.Paste")
			(net "M_J_CPU1_SA_DQS_DP<4>")
		)
		(pad "AL17" smd circle
			(at -19.120104 -12.510008 180)
			(size 0.450088 0.450088)
			(layers "F.Cu" "F.Mask" "F.Paste")
			(net "M_J_CPU1_SA_CB<3>")
		)
		(pad "AL18" smd circle
			(at -18.18005 -12.510008 180)
			(size 0.450088 0.450088)
			(layers "F.Cu" "F.Mask" "F.Paste")
			(net "GND")
		)
		(pad "AL19" smd circle
			(at -17.239996 -12.510008 180)
			(size 0.450088 0.450088)
			(layers "F.Cu" "F.Mask" "F.Paste")
			(net "M_I_CPU1_SA_DQS_DP<4>")
		)
		(pad "AL20" smd circle
			(at -16.299942 -12.510008 180)
			(size 0.450088 0.450088)
			(layers "F.Cu" "F.Mask" "F.Paste")
			(net "GND")
		)
		(pad "AL21" smd circle
			(at -15.359888 -12.510008 180)
			(size 0.450088 0.450088)
			(layers "F.Cu" "F.Mask" "F.Paste")
			(net "M_I_CPU1_SA_CB<3>")
		)
		(pad "AL22" smd circle
			(at -14.420088 -12.510008 180)
			(size 0.450088 0.450088)
			(layers "F.Cu" "F.Mask" "F.Paste")
			(net "GND")
		)
		(pad "AL23" smd circle
			(at -13.480034 -12.510008 180)
			(size 0.450088 0.450088)
			(layers "F.Cu" "F.Mask" "F.Paste")
			(net "GMI_CPU0_G1_CPU1_G3_TX_DN<15>")
		)
		(pad "AL24" smd circle
			(at -12.53998 -12.510008 180)
			(size 0.450088 0.450088)
			(layers "F.Cu" "F.Mask" "F.Paste")
			(net "GMI_CPU0_G1_CPU1_G3_TX_DP<15>")
		)
		(pad "AL25" smd circle
			(at -11.599926 -12.510008 180)
			(size 0.450088 0.450088)
			(layers "F.Cu" "F.Mask" "F.Paste")
			(net "GND")
		)
		(pad "AL26" smd circle
			(at -10.659872 -12.510008 180)
			(size 0.450088 0.450088)
			(layers "F.Cu" "F.Mask" "F.Paste")
			(net "GMI_CPU0_G1_CPU1_G3_TX_DN<12>")
		)
		(pad "AL27" smd circle
			(at -9.720072 -12.510008 180)
			(size 0.450088 0.450088)
			(layers "F.Cu" "F.Mask" "F.Paste")
			(net "GMI_CPU0_G1_CPU1_G3_TX_DP<12>")
		)
		(pad "AL28" smd circle
			(at -8.780018 -12.510008 180)
			(size 0.450088 0.450088)
			(layers "F.Cu" "F.Mask" "F.Paste")
			(net "GND")
		)
		(pad "AL29" smd circle
			(at -7.839964 -12.510008 180)
			(size 0.450088 0.450088)
			(layers "F.Cu" "F.Mask" "F.Paste")
			(net "GMI_CPU0_G1_CPU1_G3_TX_DN<9>")
		)
		(pad "AL30" smd circle
			(at -6.89991 -12.510008 180)
			(size 0.450088 0.450088)
			(layers "F.Cu" "F.Mask" "F.Paste")
			(net "GMI_CPU0_G1_CPU1_G3_TX_DP<9>")
		)
		(pad "AL31" smd circle
			(at -5.96011 -12.510008 180)
			(size 0.450088 0.450088)
			(layers "F.Cu" "F.Mask" "F.Paste")
			(net "GND")
		)
		(pad "AL32" smd circle
			(at -5.020056 -12.510008 180)
			(size 0.450088 0.450088)
			(layers "F.Cu" "F.Mask" "F.Paste")
			(net "GMI_CPU0_G1_CPU1_G3_TX_DN<6>")
		)
		(pad "AL33" smd circle
			(at -4.080002 -12.510008 180)
			(size 0.450088 0.450088)
			(layers "F.Cu" "F.Mask" "F.Paste")
			(net "GMI_CPU0_G1_CPU1_G3_TX_DP<6>")
		)
		(pad "AL34" smd circle
			(at -3.139948 -12.510008 180)
			(size 0.450088 0.450088)
			(layers "F.Cu" "F.Mask" "F.Paste")
			(net "GND")
		)
		(pad "AL35" smd circle
			(at -2.199894 -12.510008 180)
			(size 0.450088 0.450088)
			(layers "F.Cu" "F.Mask" "F.Paste")
			(net "PVDDCR_CPU0_P1")
		)
		(pad "AL36" smd circle
			(at -1.260094 -12.510008 180)
			(size 0.450088 0.450088)
			(layers "F.Cu" "F.Mask" "F.Paste")
			(net "PVDDCR_CPU0_P1")
		)
		(pad "AL40" smd circle
			(at 1.560068 -12.510008 180)
			(size 0.450088 0.450088)
			(layers "F.Cu" "F.Mask" "F.Paste")
			(net "PVDDCR_CPU0_P1")
		)
		(pad "AL41" smd circle
			(at 2.500122 -12.510008 180)
			(size 0.450088 0.450088)
			(layers "F.Cu" "F.Mask" "F.Paste")
			(net "PVDDCR_CPU0_P1")
		)
		(pad "AL42" smd circle
			(at 3.439922 -12.510008 180)
			(size 0.450088 0.450088)
			(layers "F.Cu" "F.Mask" "F.Paste")
			(net "GND")
		)
		(pad "AL43" smd circle
			(at 4.379976 -12.510008 180)
			(size 0.450088 0.450088)
			(layers "F.Cu" "F.Mask" "F.Paste")
			(net "P5E_CPU1_G1_TX_DP<6>")
		)
		(pad "AL44" smd circle
			(at 5.32003 -12.510008 180)
			(size 0.450088 0.450088)
			(layers "F.Cu" "F.Mask" "F.Paste")
			(net "P5E_CPU1_G1_TX_DN<6>")
		)
		(pad "AL45" smd circle
			(at 6.260084 -12.510008 180)
			(size 0.450088 0.450088)
			(layers "F.Cu" "F.Mask" "F.Paste")
			(net "GND")
		)
		(pad "AL46" smd circle
			(at 7.199884 -12.510008 180)
			(size 0.450088 0.450088)
			(layers "F.Cu" "F.Mask" "F.Paste")
			(net "P5E_CPU1_G1_TX_DP<9>")
		)
		(pad "AL47" smd circle
			(at 8.139938 -12.510008 180)
			(size 0.450088 0.450088)
			(layers "F.Cu" "F.Mask" "F.Paste")
			(net "P5E_CPU1_G1_TX_DN<9>")
		)
		(pad "AL48" smd circle
			(at 9.079992 -12.510008 180)
			(size 0.450088 0.450088)
			(layers "F.Cu" "F.Mask" "F.Paste")
			(net "GND")
		)
		(pad "AL49" smd circle
			(at 10.020046 -12.510008 180)
			(size 0.450088 0.450088)
			(layers "F.Cu" "F.Mask" "F.Paste")
			(net "P5E_CPU1_G1_TX_DP<12>")
		)
		(pad "AL50" smd circle
			(at 10.9601 -12.510008 180)
			(size 0.450088 0.450088)
			(layers "F.Cu" "F.Mask" "F.Paste")
			(net "P5E_CPU1_G1_TX_DN<12>")
		)
		(pad "AL51" smd circle
			(at 11.8999 -12.510008 180)
			(size 0.450088 0.450088)
			(layers "F.Cu" "F.Mask" "F.Paste")
			(net "GND")
		)
		(pad "AL52" smd circle
			(at 12.839954 -12.510008 180)
			(size 0.450088 0.450088)
			(layers "F.Cu" "F.Mask" "F.Paste")
			(net "P5E_CPU1_G1_TX_DP<15>")
		)
		(pad "AL53" smd circle
			(at 13.780008 -12.510008 180)
			(size 0.450088 0.450088)
			(layers "F.Cu" "F.Mask" "F.Paste")
			(net "P5E_CPU1_G1_TX_DN<15>")
		)
		(pad "AL54" smd circle
			(at 14.720062 -12.510008 180)
			(size 0.450088 0.450088)
			(layers "F.Cu" "F.Mask" "F.Paste")
			(net "GND")
		)
		(pad "AL55" smd circle
			(at 15.660116 -12.510008 180)
			(size 0.450088 0.450088)
			(layers "F.Cu" "F.Mask" "F.Paste")
			(net "M_C_CPU1_SA_CB<3>")
		)
		(pad "AL56" smd circle
			(at 16.599916 -12.510008 180)
			(size 0.450088 0.450088)
			(layers "F.Cu" "F.Mask" "F.Paste")
			(net "GND")
		)
		(pad "AL57" smd circle
			(at 17.53997 -12.510008 180)
			(size 0.450088 0.450088)
			(layers "F.Cu" "F.Mask" "F.Paste")
			(net "M_C_CPU1_SA_DQS_DP<4>")
		)
		(pad "AL58" smd circle
			(at 18.480024 -12.510008 180)
			(size 0.450088 0.450088)
			(layers "F.Cu" "F.Mask" "F.Paste")
			(net "GND")
		)
		(pad "AL59" smd circle
			(at 19.420078 -12.510008 180)
			(size 0.450088 0.450088)
			(layers "F.Cu" "F.Mask" "F.Paste")
			(net "M_D_CPU1_SA_CB<3>")
		)
		(pad "AL60" smd circle
			(at 20.359878 -12.510008 180)
			(size 0.450088 0.450088)
			(layers "F.Cu" "F.Mask" "F.Paste")
			(net "M_D_CPU1_SA_DQS_DP<4>")
		)
		(pad "AL61" smd circle
			(at 21.299932 -12.510008 180)
			(size 0.450088 0.450088)
			(layers "F.Cu" "F.Mask" "F.Paste")
			(net "GND")
		)
		(pad "AL62" smd circle
			(at 22.239986 -12.510008 180)
			(size 0.450088 0.450088)
			(layers "F.Cu" "F.Mask" "F.Paste")
			(net "M_B_CPU1_SA_CB<3>")
		)
		(pad "AL63" smd circle
			(at 23.18004 -12.510008 180)
			(size 0.450088 0.450088)
			(layers "F.Cu" "F.Mask" "F.Paste")
			(net "GND")
		)
		(pad "AL64" smd circle
			(at 24.120094 -12.510008 180)
			(size 0.450088 0.450088)
			(layers "F.Cu" "F.Mask" "F.Paste")
			(net "M_B_CPU1_SA_DQS_DP<4>")
		)
		(pad "AL65" smd circle
			(at 25.059894 -12.510008 180)
			(size 0.450088 0.450088)
			(layers "F.Cu" "F.Mask" "F.Paste")
			(net "GND")
		)
		(pad "AL66" smd circle
			(at 25.999948 -12.510008 180)
			(size 0.450088 0.450088)
			(layers "F.Cu" "F.Mask" "F.Paste")
			(net "M_F_CPU1_SA_CB<3>")
		)
		(pad "AL67" smd circle
			(at 26.940002 -12.510008 180)
			(size 0.450088 0.450088)
			(layers "F.Cu" "F.Mask" "F.Paste")
			(net "M_F_CPU1_SA_DQS_DP<4>")
		)
		(pad "AL68" smd circle
			(at 27.880056 -12.510008 180)
			(size 0.450088 0.450088)
			(layers "F.Cu" "F.Mask" "F.Paste")
			(net "GND")
		)
		(pad "AL69" smd circle
			(at 28.82011 -12.510008 180)
			(size 0.450088 0.450088)
			(layers "F.Cu" "F.Mask" "F.Paste")
			(net "M_E_CPU1_SA_CB<3>")
		)
		(pad "AL70" smd circle
			(at 29.75991 -12.510008 180)
			(size 0.450088 0.450088)
			(layers "F.Cu" "F.Mask" "F.Paste")
			(net "GND")
		)
		(pad "AL71" smd circle
			(at 30.699964 -12.510008 180)
			(size 0.450088 0.450088)
			(layers "F.Cu" "F.Mask" "F.Paste")
			(net "M_E_CPU1_SA_DQS_DP<4>")
		)
		(pad "AL72" smd circle
			(at 31.640018 -12.510008 180)
			(size 0.450088 0.450088)
			(layers "F.Cu" "F.Mask" "F.Paste")
			(net "GND")
		)
		(pad "AL73" smd circle
			(at 32.580072 -12.510008 180)
			(size 0.450088 0.450088)
			(layers "F.Cu" "F.Mask" "F.Paste")
			(net "M_A_CPU1_SA_CB<3>")
		)
		(pad "AL74" smd circle
			(at 33.519872 -12.510008 180)
			(size 0.450088 0.450088)
			(layers "F.Cu" "F.Mask" "F.Paste")
			(net "M_A_CPU1_SA_DQS_DP<4>")
		)
		(pad "AL75" smd circle
			(at 34.459926 -12.510008 180)
			(size 0.450088 0.450088)
			(layers "F.Cu" "F.Mask" "F.Paste")
			(net "GND")
		)
		(pad "AM2" smd circle
			(at -33.690052 -11.700002 180)
			(size 0.450088 0.450088)
			(layers "F.Cu" "F.Mask" "F.Paste")
			(net "M_G_CPU1_SA_DQS_DN<4>")
		)
		(pad "AM3" smd circle
			(at -32.749998 -11.700002 180)
			(size 0.450088 0.450088)
			(layers "F.Cu" "F.Mask" "F.Paste")
			(net "GND")
		)
		(pad "AM4" smd circle
			(at -31.809944 -11.700002 180)
			(size 0.450088 0.450088)
			(layers "F.Cu" "F.Mask" "F.Paste")
			(net "M_G_CPU1_SA_DQS_DN<9>")
		)
		(pad "AM5" smd circle
			(at -30.86989 -11.700002 180)
			(size 0.450088 0.450088)
			(layers "F.Cu" "F.Mask" "F.Paste")
			(net "PVDDCR_SOC_P1")
		)
		(pad "AM6" smd circle
			(at -29.93009 -11.700002 180)
			(size 0.450088 0.450088)
			(layers "F.Cu" "F.Mask" "F.Paste")
			(net "M_K_CPU1_SA_DQS_DN<4>")
		)
		(pad "AM7" smd circle
			(at -28.990036 -11.700002 180)
			(size 0.450088 0.450088)
			(layers "F.Cu" "F.Mask" "F.Paste")
			(net "M_K_CPU1_SA_DQS_DN<9>")
		)
		(pad "AM8" smd circle
			(at -28.049982 -11.700002 180)
			(size 0.450088 0.450088)
			(layers "F.Cu" "F.Mask" "F.Paste")
			(net "GND")
		)
		(pad "AM9" smd circle
			(at -27.109928 -11.700002 180)
			(size 0.450088 0.450088)
			(layers "F.Cu" "F.Mask" "F.Paste")
			(net "M_L_CPU1_SA_DQS_DN<4>")
		)
		(pad "AM10" smd circle
			(at -26.170128 -11.700002 180)
			(size 0.450088 0.450088)
			(layers "F.Cu" "F.Mask" "F.Paste")
			(net "GND")
		)
		(pad "AM11" smd circle
			(at -25.230074 -11.700002 180)
			(size 0.450088 0.450088)
			(layers "F.Cu" "F.Mask" "F.Paste")
			(net "M_L_CPU1_SA_DQS_DN<9>")
		)
		(pad "AM12" smd circle
			(at -24.29002 -11.700002 180)
			(size 0.450088 0.450088)
			(layers "F.Cu" "F.Mask" "F.Paste")
			(net "PVDDCR_SOC_P1")
		)
		(pad "AM13" smd circle
			(at -23.349966 -11.700002 180)
			(size 0.450088 0.450088)
			(layers "F.Cu" "F.Mask" "F.Paste")
			(net "M_H_CPU1_SA_DQS_DN<4>")
		)
		(pad "AM14" smd circle
			(at -22.409912 -11.700002 180)
			(size 0.450088 0.450088)
			(layers "F.Cu" "F.Mask" "F.Paste")
			(net "M_H_CPU1_SA_DQS_DN<9>")
		)
		(pad "AM15" smd circle
			(at -21.470112 -11.700002 180)
			(size 0.450088 0.450088)
			(layers "F.Cu" "F.Mask" "F.Paste")
			(net "GND")
		)
		(pad "AM16" smd circle
			(at -20.530058 -11.700002 180)
			(size 0.450088 0.450088)
			(layers "F.Cu" "F.Mask" "F.Paste")
			(net "M_J_CPU1_SA_DQS_DN<4>")
		)
		(pad "AM17" smd circle
			(at -19.590004 -11.700002 180)
			(size 0.450088 0.450088)
			(layers "F.Cu" "F.Mask" "F.Paste")
			(net "GND")
		)
		(pad "AM18" smd circle
			(at -18.64995 -11.700002 180)
			(size 0.450088 0.450088)
			(layers "F.Cu" "F.Mask" "F.Paste")
			(net "M_J_CPU1_SA_DQS_DN<9>")
		)
		(pad "AM19" smd circle
			(at -17.709896 -11.700002 180)
			(size 0.450088 0.450088)
			(layers "F.Cu" "F.Mask" "F.Paste")
			(net "PVDDCR_SOC_P1")
		)
		(pad "AM20" smd circle
			(at -16.770096 -11.700002 180)
			(size 0.450088 0.450088)
			(layers "F.Cu" "F.Mask" "F.Paste")
			(net "M_I_CPU1_SA_DQS_DN<4>")
		)
		(pad "AM21" smd circle
			(at -15.830042 -11.700002 180)
			(size 0.450088 0.450088)
			(layers "F.Cu" "F.Mask" "F.Paste")
			(net "M_I_CPU1_SA_DQS_DN<9>")
		)
		(pad "AM22" smd circle
			(at -14.889988 -11.700002 180)
			(size 0.450088 0.450088)
			(layers "F.Cu" "F.Mask" "F.Paste")
			(net "PVDDCR_SOC_P1")
		)
		(pad "AM23" smd circle
			(at -13.949934 -11.700002 180)
			(size 0.450088 0.450088)
			(layers "F.Cu" "F.Mask" "F.Paste")
			(net "GND")
		)
		(pad "AM24" smd circle
			(at -13.00988 -11.700002 180)
			(size 0.450088 0.450088)
			(layers "F.Cu" "F.Mask" "F.Paste")
			(net "GND")
		)
		(pad "AM25" smd circle
			(at -12.07008 -11.700002 180)
			(size 0.450088 0.450088)
			(layers "F.Cu" "F.Mask" "F.Paste")
			(net "GND")
		)
		(pad "AM26" smd circle
			(at -11.130026 -11.700002 180)
			(size 0.450088 0.450088)
			(layers "F.Cu" "F.Mask" "F.Paste")
			(net "GND")
		)
		(pad "AM27" smd circle
			(at -10.189972 -11.700002 180)
			(size 0.450088 0.450088)
			(layers "F.Cu" "F.Mask" "F.Paste")
			(net "GND")
		)
		(pad "AM28" smd circle
			(at -9.249918 -11.700002 180)
			(size 0.450088 0.450088)
			(layers "F.Cu" "F.Mask" "F.Paste")
			(net "GND")
		)
		(pad "AM29" smd circle
			(at -8.310118 -11.700002 180)
			(size 0.450088 0.450088)
			(layers "F.Cu" "F.Mask" "F.Paste")
			(net "GND")
		)
		(pad "AM30" smd circle
			(at -7.370064 -11.700002 180)
			(size 0.450088 0.450088)
			(layers "F.Cu" "F.Mask" "F.Paste")
			(net "GND")
		)
		(pad "AM31" smd circle
			(at -6.43001 -11.700002 180)
			(size 0.450088 0.450088)
			(layers "F.Cu" "F.Mask" "F.Paste")
			(net "GND")
		)
		(pad "AM32" smd circle
			(at -5.489956 -11.700002 180)
			(size 0.450088 0.450088)
			(layers "F.Cu" "F.Mask" "F.Paste")
			(net "GND")
		)
		(pad "AM33" smd circle
			(at -4.549902 -11.700002 180)
			(size 0.450088 0.450088)
			(layers "F.Cu" "F.Mask" "F.Paste")
			(net "GND")
		)
		(pad "AM34" smd circle
			(at -3.610102 -11.700002 180)
			(size 0.450088 0.450088)
			(layers "F.Cu" "F.Mask" "F.Paste")
			(net "GND")
		)
		(pad "AM35" smd circle
			(at -2.670048 -11.700002 180)
			(size 0.450088 0.450088)
			(layers "F.Cu" "F.Mask" "F.Paste")
			(net "GMI_CPU0_G1_CPU1_G3_TX_DN<1>")
		)
		(pad "AM36" smd circle
			(at -1.729994 -11.700002 180)
			(size 0.450088 0.450088)
			(layers "F.Cu" "F.Mask" "F.Paste")
			(net "GMI_CPU0_G1_CPU1_G3_TX_DP<1>")
		)
		(pad "AM37" smd circle
			(at -0.78994 -11.700002 180)
			(size 0.450088 0.450088)
			(layers "F.Cu" "F.Mask" "F.Paste")
			(net "GND")
		)
		(pad "AM39" smd circle
			(at 1.089914 -11.700002 180)
			(size 0.450088 0.450088)
			(layers "F.Cu" "F.Mask" "F.Paste")
			(net "GND")
		)
		(pad "AM40" smd circle
			(at 2.029968 -11.700002 180)
			(size 0.450088 0.450088)
			(layers "F.Cu" "F.Mask" "F.Paste")
			(net "P5E_CPU1_G1_TX_DP<1>")
		)
		(pad "AM41" smd circle
			(at 2.970022 -11.700002 180)
			(size 0.450088 0.450088)
			(layers "F.Cu" "F.Mask" "F.Paste")
			(net "P5E_CPU1_G1_TX_DN<1>")
		)
		(pad "AM42" smd circle
			(at 3.910076 -11.700002 180)
			(size 0.450088 0.450088)
			(layers "F.Cu" "F.Mask" "F.Paste")
			(net "GND")
		)
		(pad "AM43" smd circle
			(at 4.849876 -11.700002 180)
			(size 0.450088 0.450088)
			(layers "F.Cu" "F.Mask" "F.Paste")
			(net "GND")
		)
		(pad "AM44" smd circle
			(at 5.78993 -11.700002 180)
			(size 0.450088 0.450088)
			(layers "F.Cu" "F.Mask" "F.Paste")
			(net "GND")
		)
		(pad "AM45" smd circle
			(at 6.729984 -11.700002 180)
			(size 0.450088 0.450088)
			(layers "F.Cu" "F.Mask" "F.Paste")
			(net "GND")
		)
		(pad "AM46" smd circle
			(at 7.670038 -11.700002 180)
			(size 0.450088 0.450088)
			(layers "F.Cu" "F.Mask" "F.Paste")
			(net "GND")
		)
		(pad "AM47" smd circle
			(at 8.610092 -11.700002 180)
			(size 0.450088 0.450088)
			(layers "F.Cu" "F.Mask" "F.Paste")
			(net "GND")
		)
		(pad "AM48" smd circle
			(at 9.549892 -11.700002 180)
			(size 0.450088 0.450088)
			(layers "F.Cu" "F.Mask" "F.Paste")
			(net "GND")
		)
		(pad "AM49" smd circle
			(at 10.489946 -11.700002 180)
			(size 0.450088 0.450088)
			(layers "F.Cu" "F.Mask" "F.Paste")
			(net "GND")
		)
		(pad "AM50" smd circle
			(at 11.43 -11.700002 180)
			(size 0.450088 0.450088)
			(layers "F.Cu" "F.Mask" "F.Paste")
			(net "GND")
		)
		(pad "AM51" smd circle
			(at 12.370054 -11.700002 180)
			(size 0.450088 0.450088)
			(layers "F.Cu" "F.Mask" "F.Paste")
			(net "GND")
		)
		(pad "AM52" smd circle
			(at 13.310108 -11.700002 180)
			(size 0.450088 0.450088)
			(layers "F.Cu" "F.Mask" "F.Paste")
			(net "GND")
		)
		(pad "AM53" smd circle
			(at 14.249908 -11.700002 180)
			(size 0.450088 0.450088)
			(layers "F.Cu" "F.Mask" "F.Paste")
			(net "GND")
		)
		(pad "AM54" smd circle
			(at 15.189962 -11.700002 180)
			(size 0.450088 0.450088)
			(layers "F.Cu" "F.Mask" "F.Paste")
			(net "PVDDIO_P1")
		)
		(pad "AM55" smd circle
			(at 16.130016 -11.700002 180)
			(size 0.450088 0.450088)
			(layers "F.Cu" "F.Mask" "F.Paste")
			(net "M_C_CPU1_SA_DQS_DN<9>")
		)
		(pad "AM56" smd circle
			(at 17.07007 -11.700002 180)
			(size 0.450088 0.450088)
			(layers "F.Cu" "F.Mask" "F.Paste")
			(net "M_C_CPU1_SA_DQS_DN<4>")
		)
		(pad "AM57" smd circle
			(at 18.010124 -11.700002 180)
			(size 0.450088 0.450088)
			(layers "F.Cu" "F.Mask" "F.Paste")
			(net "PVDDIO_P1")
		)
		(pad "AM58" smd circle
			(at 18.949924 -11.700002 180)
			(size 0.450088 0.450088)
			(layers "F.Cu" "F.Mask" "F.Paste")
			(net "M_D_CPU1_SA_DQS_DN<9>")
		)
		(pad "AM59" smd circle
			(at 19.889978 -11.700002 180)
			(size 0.450088 0.450088)
			(layers "F.Cu" "F.Mask" "F.Paste")
			(net "GND")
		)
		(pad "AM60" smd circle
			(at 20.830032 -11.700002 180)
			(size 0.450088 0.450088)
			(layers "F.Cu" "F.Mask" "F.Paste")
			(net "M_D_CPU1_SA_DQS_DN<4>")
		)
		(pad "AM61" smd circle
			(at 21.770086 -11.700002 180)
			(size 0.450088 0.450088)
			(layers "F.Cu" "F.Mask" "F.Paste")
			(net "GND")
		)
		(pad "AM62" smd circle
			(at 22.709886 -11.700002 180)
			(size 0.450088 0.450088)
			(layers "F.Cu" "F.Mask" "F.Paste")
			(net "M_B_CPU1_SA_DQS_DN<9>")
		)
		(pad "AM63" smd circle
			(at 23.64994 -11.700002 180)
			(size 0.450088 0.450088)
			(layers "F.Cu" "F.Mask" "F.Paste")
			(net "M_B_CPU1_SA_DQS_DN<4>")
		)
		(pad "AM64" smd circle
			(at 24.589994 -11.700002 180)
			(size 0.450088 0.450088)
			(layers "F.Cu" "F.Mask" "F.Paste")
			(net "PVDDIO_P1")
		)
		(pad "AM65" smd circle
			(at 25.530048 -11.700002 180)
			(size 0.450088 0.450088)
			(layers "F.Cu" "F.Mask" "F.Paste")
			(net "M_F_CPU1_SA_DQS_DN<9>")
		)
		(pad "AM66" smd circle
			(at 26.470102 -11.700002 180)
			(size 0.450088 0.450088)
			(layers "F.Cu" "F.Mask" "F.Paste")
			(net "GND")
		)
		(pad "AM67" smd circle
			(at 27.409902 -11.700002 180)
			(size 0.450088 0.450088)
			(layers "F.Cu" "F.Mask" "F.Paste")
			(net "M_F_CPU1_SA_DQS_DN<4>")
		)
		(pad "AM68" smd circle
			(at 28.349956 -11.700002 180)
			(size 0.450088 0.450088)
			(layers "F.Cu" "F.Mask" "F.Paste")
			(net "GND")
		)
		(pad "AM69" smd circle
			(at 29.29001 -11.700002 180)
			(size 0.450088 0.450088)
			(layers "F.Cu" "F.Mask" "F.Paste")
			(net "M_E_CPU1_SA_DQS_DN<9>")
		)
		(pad "AM70" smd circle
			(at 30.230064 -11.700002 180)
			(size 0.450088 0.450088)
			(layers "F.Cu" "F.Mask" "F.Paste")
			(net "M_E_CPU1_SA_DQS_DN<4>")
		)
		(pad "AM71" smd circle
			(at 31.170118 -11.700002 180)
			(size 0.450088 0.450088)
			(layers "F.Cu" "F.Mask" "F.Paste")
			(net "PVDDIO_P1")
		)
		(pad "AM72" smd circle
			(at 32.109918 -11.700002 180)
			(size 0.450088 0.450088)
			(layers "F.Cu" "F.Mask" "F.Paste")
			(net "M_A_CPU1_SA_DQS_DN<9>")
		)
		(pad "AM73" smd circle
			(at 33.049972 -11.700002 180)
			(size 0.450088 0.450088)
			(layers "F.Cu" "F.Mask" "F.Paste")
			(net "GND")
		)
		(pad "AM74" smd circle
			(at 33.990026 -11.700002 180)
			(size 0.450088 0.450088)
			(layers "F.Cu" "F.Mask" "F.Paste")
			(net "M_A_CPU1_SA_DQS_DN<4>")
		)
		(pad "AN1" smd circle
			(at -34.159952 -10.889996 180)
			(size 0.450088 0.450088)
			(layers "F.Cu" "F.Mask" "F.Paste")
			(net "GND")
		)
		(pad "AN2" smd circle
			(at -33.219898 -10.889996 180)
			(size 0.450088 0.450088)
			(layers "F.Cu" "F.Mask" "F.Paste")
			(net "M_G_CPU1_SA_CB<4>")
		)
		(pad "AN3" smd circle
			(at -32.280098 -10.889996 180)
			(size 0.450088 0.450088)
			(layers "F.Cu" "F.Mask" "F.Paste")
			(net "M_G_CPU1_SA_DQS_DP<9>")
		)
		(pad "AN4" smd circle
			(at -31.340044 -10.889996 180)
			(size 0.450088 0.450088)
			(layers "F.Cu" "F.Mask" "F.Paste")
			(net "GND")
		)
		(pad "AN5" smd circle
			(at -30.39999 -10.889996 180)
			(size 0.450088 0.450088)
			(layers "F.Cu" "F.Mask" "F.Paste")
			(net "M_K_CPU1_SA_CB<4>")
		)
		(pad "AN6" smd circle
			(at -29.459936 -10.889996 180)
			(size 0.450088 0.450088)
			(layers "F.Cu" "F.Mask" "F.Paste")
			(net "GND")
		)
		(pad "AN7" smd circle
			(at -28.519882 -10.889996 180)
			(size 0.450088 0.450088)
			(layers "F.Cu" "F.Mask" "F.Paste")
			(net "M_K_CPU1_SA_DQS_DP<9>")
		)
		(pad "AN8" smd circle
			(at -27.580082 -10.889996 180)
			(size 0.450088 0.450088)
			(layers "F.Cu" "F.Mask" "F.Paste")
			(net "GND")
		)
		(pad "AN9" smd circle
			(at -26.640028 -10.889996 180)
			(size 0.450088 0.450088)
			(layers "F.Cu" "F.Mask" "F.Paste")
			(net "M_L_CPU1_SA_CB<4>")
		)
		(pad "AN10" smd circle
			(at -25.699974 -10.889996 180)
			(size 0.450088 0.450088)
			(layers "F.Cu" "F.Mask" "F.Paste")
			(net "M_L_CPU1_SA_DQS_DP<9>")
		)
		(pad "AN11" smd circle
			(at -24.75992 -10.889996 180)
			(size 0.450088 0.450088)
			(layers "F.Cu" "F.Mask" "F.Paste")
			(net "GND")
		)
		(pad "AN12" smd circle
			(at -23.82012 -10.889996 180)
			(size 0.450088 0.450088)
			(layers "F.Cu" "F.Mask" "F.Paste")
			(net "M_H_CPU1_SA_CB<4>")
		)
		(pad "AN13" smd circle
			(at -22.880066 -10.889996 180)
			(size 0.450088 0.450088)
			(layers "F.Cu" "F.Mask" "F.Paste")
			(net "GND")
		)
		(pad "AN14" smd circle
			(at -21.940012 -10.889996 180)
			(size 0.450088 0.450088)
			(layers "F.Cu" "F.Mask" "F.Paste")
			(net "M_H_CPU1_SA_DQS_DP<9>")
		)
		(pad "AN15" smd circle
			(at -20.999958 -10.889996 180)
			(size 0.450088 0.450088)
			(layers "F.Cu" "F.Mask" "F.Paste")
			(net "GND")
		)
		(pad "AN16" smd circle
			(at -20.059904 -10.889996 180)
			(size 0.450088 0.450088)
			(layers "F.Cu" "F.Mask" "F.Paste")
			(net "M_J_CPU1_SA_CB<4>")
		)
		(pad "AN17" smd circle
			(at -19.120104 -10.889996 180)
			(size 0.450088 0.450088)
			(layers "F.Cu" "F.Mask" "F.Paste")
			(net "M_J_CPU1_SA_DQS_DP<9>")
		)
		(pad "AN18" smd circle
			(at -18.18005 -10.889996 180)
			(size 0.450088 0.450088)
			(layers "F.Cu" "F.Mask" "F.Paste")
			(net "GND")
		)
		(pad "AN19" smd circle
			(at -17.239996 -10.889996 180)
			(size 0.450088 0.450088)
			(layers "F.Cu" "F.Mask" "F.Paste")
			(net "M_I_CPU1_SA_CB<4>")
		)
		(pad "AN20" smd circle
			(at -16.299942 -10.889996 180)
			(size 0.450088 0.450088)
			(layers "F.Cu" "F.Mask" "F.Paste")
			(net "GND")
		)
		(pad "AN21" smd circle
			(at -15.359888 -10.889996 180)
			(size 0.450088 0.450088)
			(layers "F.Cu" "F.Mask" "F.Paste")
			(net "M_I_CPU1_SA_DQS_DP<9>")
		)
		(pad "AN22" smd circle
			(at -14.420088 -10.889996 180)
			(size 0.450088 0.450088)
			(layers "F.Cu" "F.Mask" "F.Paste")
			(net "GND")
		)
		(pad "AN23" smd circle
			(at -13.480034 -10.889996 180)
			(size 0.450088 0.450088)
			(layers "F.Cu" "F.Mask" "F.Paste")
			(net "GMI_CPU0_G1_CPU1_G3_TX_DN<13>")
		)
		(pad "AN24" smd circle
			(at -12.53998 -10.889996 180)
			(size 0.450088 0.450088)
			(layers "F.Cu" "F.Mask" "F.Paste")
			(net "GMI_CPU0_G1_CPU1_G3_TX_DP<13>")
		)
		(pad "AN25" smd circle
			(at -11.599926 -10.889996 180)
			(size 0.450088 0.450088)
			(layers "F.Cu" "F.Mask" "F.Paste")
			(net "GND")
		)
		(pad "AN26" smd circle
			(at -10.659872 -10.889996 180)
			(size 0.450088 0.450088)
			(layers "F.Cu" "F.Mask" "F.Paste")
			(net "GMI_CPU0_G1_CPU1_G3_TX_DN<10>")
		)
		(pad "AN27" smd circle
			(at -9.720072 -10.889996 180)
			(size 0.450088 0.450088)
			(layers "F.Cu" "F.Mask" "F.Paste")
			(net "GMI_CPU0_G1_CPU1_G3_TX_DP<10>")
		)
		(pad "AN28" smd circle
			(at -8.780018 -10.889996 180)
			(size 0.450088 0.450088)
			(layers "F.Cu" "F.Mask" "F.Paste")
			(net "GND")
		)
		(pad "AN29" smd circle
			(at -7.839964 -10.889996 180)
			(size 0.450088 0.450088)
			(layers "F.Cu" "F.Mask" "F.Paste")
			(net "GMI_CPU0_G1_CPU1_G3_TX_DN<7>")
		)
		(pad "AN30" smd circle
			(at -6.89991 -10.889996 180)
			(size 0.450088 0.450088)
			(layers "F.Cu" "F.Mask" "F.Paste")
			(net "GMI_CPU0_G1_CPU1_G3_TX_DP<7>")
		)
		(pad "AN31" smd circle
			(at -5.96011 -10.889996 180)
			(size 0.450088 0.450088)
			(layers "F.Cu" "F.Mask" "F.Paste")
			(net "GND")
		)
		(pad "AN32" smd circle
			(at -5.020056 -10.889996 180)
			(size 0.450088 0.450088)
			(layers "F.Cu" "F.Mask" "F.Paste")
			(net "GMI_CPU0_G1_CPU1_G3_TX_DN<4>")
		)
		(pad "AN33" smd circle
			(at -4.080002 -10.889996 180)
			(size 0.450088 0.450088)
			(layers "F.Cu" "F.Mask" "F.Paste")
			(net "GMI_CPU0_G1_CPU1_G3_TX_DP<4>")
		)
		(pad "AN34" smd circle
			(at -3.139948 -10.889996 180)
			(size 0.450088 0.450088)
			(layers "F.Cu" "F.Mask" "F.Paste")
			(net "GND")
		)
		(pad "AN35" smd circle
			(at -2.199894 -10.889996 180)
			(size 0.450088 0.450088)
			(layers "F.Cu" "F.Mask" "F.Paste")
			(net "GND")
		)
		(pad "AN36" smd circle
			(at -1.260094 -10.889996 180)
			(size 0.450088 0.450088)
			(layers "F.Cu" "F.Mask" "F.Paste")
			(net "GND")
		)
		(pad "AN40" smd circle
			(at 1.560068 -10.889996 180)
			(size 0.450088 0.450088)
			(layers "F.Cu" "F.Mask" "F.Paste")
			(net "GND")
		)
		(pad "AN41" smd circle
			(at 2.500122 -10.889996 180)
			(size 0.450088 0.450088)
			(layers "F.Cu" "F.Mask" "F.Paste")
			(net "GND")
		)
		(pad "AN42" smd circle
			(at 3.439922 -10.889996 180)
			(size 0.450088 0.450088)
			(layers "F.Cu" "F.Mask" "F.Paste")
			(net "GND")
		)
		(pad "AN43" smd circle
			(at 4.379976 -10.889996 180)
			(size 0.450088 0.450088)
			(layers "F.Cu" "F.Mask" "F.Paste")
			(net "P5E_CPU1_G1_TX_DP<4>")
		)
		(pad "AN44" smd circle
			(at 5.32003 -10.889996 180)
			(size 0.450088 0.450088)
			(layers "F.Cu" "F.Mask" "F.Paste")
			(net "P5E_CPU1_G1_TX_DN<4>")
		)
		(pad "AN45" smd circle
			(at 6.260084 -10.889996 180)
			(size 0.450088 0.450088)
			(layers "F.Cu" "F.Mask" "F.Paste")
			(net "GND")
		)
		(pad "AN46" smd circle
			(at 7.199884 -10.889996 180)
			(size 0.450088 0.450088)
			(layers "F.Cu" "F.Mask" "F.Paste")
			(net "P5E_CPU1_G1_TX_DP<7>")
		)
		(pad "AN47" smd circle
			(at 8.139938 -10.889996 180)
			(size 0.450088 0.450088)
			(layers "F.Cu" "F.Mask" "F.Paste")
			(net "P5E_CPU1_G1_TX_DN<7>")
		)
		(pad "AN48" smd circle
			(at 9.079992 -10.889996 180)
			(size 0.450088 0.450088)
			(layers "F.Cu" "F.Mask" "F.Paste")
			(net "GND")
		)
		(pad "AN49" smd circle
			(at 10.020046 -10.889996 180)
			(size 0.450088 0.450088)
			(layers "F.Cu" "F.Mask" "F.Paste")
			(net "P5E_CPU1_G1_TX_DP<10>")
		)
		(pad "AN50" smd circle
			(at 10.9601 -10.889996 180)
			(size 0.450088 0.450088)
			(layers "F.Cu" "F.Mask" "F.Paste")
			(net "P5E_CPU1_G1_TX_DN<10>")
		)
		(pad "AN51" smd circle
			(at 11.8999 -10.889996 180)
			(size 0.450088 0.450088)
			(layers "F.Cu" "F.Mask" "F.Paste")
			(net "GND")
		)
		(pad "AN52" smd circle
			(at 12.839954 -10.889996 180)
			(size 0.450088 0.450088)
			(layers "F.Cu" "F.Mask" "F.Paste")
			(net "P5E_CPU1_G1_TX_DP<13>")
		)
		(pad "AN53" smd circle
			(at 13.780008 -10.889996 180)
			(size 0.450088 0.450088)
			(layers "F.Cu" "F.Mask" "F.Paste")
			(net "P5E_CPU1_G1_TX_DN<13>")
		)
		(pad "AN54" smd circle
			(at 14.720062 -10.889996 180)
			(size 0.450088 0.450088)
			(layers "F.Cu" "F.Mask" "F.Paste")
			(net "GND")
		)
		(pad "AN55" smd circle
			(at 15.660116 -10.889996 180)
			(size 0.450088 0.450088)
			(layers "F.Cu" "F.Mask" "F.Paste")
			(net "M_C_CPU1_SA_DQS_DP<9>")
		)
		(pad "AN56" smd circle
			(at 16.599916 -10.889996 180)
			(size 0.450088 0.450088)
			(layers "F.Cu" "F.Mask" "F.Paste")
			(net "GND")
		)
		(pad "AN57" smd circle
			(at 17.53997 -10.889996 180)
			(size 0.450088 0.450088)
			(layers "F.Cu" "F.Mask" "F.Paste")
			(net "M_C_CPU1_SA_CB<4>")
		)
		(pad "AN58" smd circle
			(at 18.480024 -10.889996 180)
			(size 0.450088 0.450088)
			(layers "F.Cu" "F.Mask" "F.Paste")
			(net "GND")
		)
		(pad "AN59" smd circle
			(at 19.420078 -10.889996 180)
			(size 0.450088 0.450088)
			(layers "F.Cu" "F.Mask" "F.Paste")
			(net "M_D_CPU1_SA_DQS_DP<9>")
		)
		(pad "AN60" smd circle
			(at 20.359878 -10.889996 180)
			(size 0.450088 0.450088)
			(layers "F.Cu" "F.Mask" "F.Paste")
			(net "M_D_CPU1_SA_CB<4>")
		)
		(pad "AN61" smd circle
			(at 21.299932 -10.889996 180)
			(size 0.450088 0.450088)
			(layers "F.Cu" "F.Mask" "F.Paste")
			(net "GND")
		)
		(pad "AN62" smd circle
			(at 22.239986 -10.889996 180)
			(size 0.450088 0.450088)
			(layers "F.Cu" "F.Mask" "F.Paste")
			(net "M_B_CPU1_SA_DQS_DP<9>")
		)
		(pad "AN63" smd circle
			(at 23.18004 -10.889996 180)
			(size 0.450088 0.450088)
			(layers "F.Cu" "F.Mask" "F.Paste")
			(net "GND")
		)
		(pad "AN64" smd circle
			(at 24.120094 -10.889996 180)
			(size 0.450088 0.450088)
			(layers "F.Cu" "F.Mask" "F.Paste")
			(net "M_B_CPU1_SA_CB<4>")
		)
		(pad "AN65" smd circle
			(at 25.059894 -10.889996 180)
			(size 0.450088 0.450088)
			(layers "F.Cu" "F.Mask" "F.Paste")
			(net "GND")
		)
		(pad "AN66" smd circle
			(at 25.999948 -10.889996 180)
			(size 0.450088 0.450088)
			(layers "F.Cu" "F.Mask" "F.Paste")
			(net "M_F_CPU1_SA_DQS_DP<9>")
		)
		(pad "AN67" smd circle
			(at 26.940002 -10.889996 180)
			(size 0.450088 0.450088)
			(layers "F.Cu" "F.Mask" "F.Paste")
			(net "M_F_CPU1_SA_CB<4>")
		)
		(pad "AN68" smd circle
			(at 27.880056 -10.889996 180)
			(size 0.450088 0.450088)
			(layers "F.Cu" "F.Mask" "F.Paste")
			(net "GND")
		)
		(pad "AN69" smd circle
			(at 28.82011 -10.889996 180)
			(size 0.450088 0.450088)
			(layers "F.Cu" "F.Mask" "F.Paste")
			(net "M_E_CPU1_SA_DQS_DP<9>")
		)
		(pad "AN70" smd circle
			(at 29.75991 -10.889996 180)
			(size 0.450088 0.450088)
			(layers "F.Cu" "F.Mask" "F.Paste")
			(net "GND")
		)
		(pad "AN71" smd circle
			(at 30.699964 -10.889996 180)
			(size 0.450088 0.450088)
			(layers "F.Cu" "F.Mask" "F.Paste")
			(net "M_E_CPU1_SA_CB<4>")
		)
		(pad "AN72" smd circle
			(at 31.640018 -10.889996 180)
			(size 0.450088 0.450088)
			(layers "F.Cu" "F.Mask" "F.Paste")
			(net "GND")
		)
		(pad "AN73" smd circle
			(at 32.580072 -10.889996 180)
			(size 0.450088 0.450088)
			(layers "F.Cu" "F.Mask" "F.Paste")
			(net "M_A_CPU1_SA_DQS_DP<9>")
		)
		(pad "AN74" smd circle
			(at 33.519872 -10.889996 180)
			(size 0.450088 0.450088)
			(layers "F.Cu" "F.Mask" "F.Paste")
			(net "M_A_CPU1_SA_CB<4>")
		)
		(pad "AN75" smd circle
			(at 34.459926 -10.889996 180)
			(size 0.450088 0.450088)
			(layers "F.Cu" "F.Mask" "F.Paste")
			(net "GND")
		)
		(pad "AP2" smd circle
			(at -33.690052 -10.07999 180)
			(size 0.450088 0.450088)
			(layers "F.Cu" "F.Mask" "F.Paste")
			(net "M_G_CPU1_SA_CB<6>")
		)
		(pad "AP3" smd circle
			(at -32.749998 -10.07999 180)
			(size 0.450088 0.450088)
			(layers "F.Cu" "F.Mask" "F.Paste")
			(net "GND")
		)
		(pad "AP4" smd circle
			(at -31.809944 -10.07999 180)
			(size 0.450088 0.450088)
			(layers "F.Cu" "F.Mask" "F.Paste")
			(net "M_G_CPU1_SA_CB<5>")
		)
		(pad "AP5" smd circle
			(at -30.86989 -10.07999 180)
			(size 0.450088 0.450088)
			(layers "F.Cu" "F.Mask" "F.Paste")
			(net "GND")
		)
		(pad "AP6" smd circle
			(at -29.93009 -10.07999 180)
			(size 0.450088 0.450088)
			(layers "F.Cu" "F.Mask" "F.Paste")
			(net "M_K_CPU1_SA_CB<6>")
		)
		(pad "AP7" smd circle
			(at -28.990036 -10.07999 180)
			(size 0.450088 0.450088)
			(layers "F.Cu" "F.Mask" "F.Paste")
			(net "M_K_CPU1_SA_CB<5>")
		)
		(pad "AP8" smd circle
			(at -28.049982 -10.07999 180)
			(size 0.450088 0.450088)
			(layers "F.Cu" "F.Mask" "F.Paste")
			(net "GND")
		)
		(pad "AP9" smd circle
			(at -27.109928 -10.07999 180)
			(size 0.450088 0.450088)
			(layers "F.Cu" "F.Mask" "F.Paste")
			(net "M_L_CPU1_SA_CB<6>")
		)
		(pad "AP10" smd circle
			(at -26.170128 -10.07999 180)
			(size 0.450088 0.450088)
			(layers "F.Cu" "F.Mask" "F.Paste")
			(net "GND")
		)
		(pad "AP11" smd circle
			(at -25.230074 -10.07999 180)
			(size 0.450088 0.450088)
			(layers "F.Cu" "F.Mask" "F.Paste")
			(net "M_L_CPU1_SA_CB<5>")
		)
		(pad "AP12" smd circle
			(at -24.29002 -10.07999 180)
			(size 0.450088 0.450088)
			(layers "F.Cu" "F.Mask" "F.Paste")
			(net "GND")
		)
		(pad "AP13" smd circle
			(at -23.349966 -10.07999 180)
			(size 0.450088 0.450088)
			(layers "F.Cu" "F.Mask" "F.Paste")
			(net "M_H_CPU1_SA_CB<6>")
		)
		(pad "AP14" smd circle
			(at -22.409912 -10.07999 180)
			(size 0.450088 0.450088)
			(layers "F.Cu" "F.Mask" "F.Paste")
			(net "M_H_CPU1_SA_CB<5>")
		)
		(pad "AP15" smd circle
			(at -21.470112 -10.07999 180)
			(size 0.450088 0.450088)
			(layers "F.Cu" "F.Mask" "F.Paste")
			(net "GND")
		)
		(pad "AP16" smd circle
			(at -20.530058 -10.07999 180)
			(size 0.450088 0.450088)
			(layers "F.Cu" "F.Mask" "F.Paste")
			(net "M_J_CPU1_SA_CB<6>")
		)
		(pad "AP17" smd circle
			(at -19.590004 -10.07999 180)
			(size 0.450088 0.450088)
			(layers "F.Cu" "F.Mask" "F.Paste")
			(net "GND")
		)
		(pad "AP18" smd circle
			(at -18.64995 -10.07999 180)
			(size 0.450088 0.450088)
			(layers "F.Cu" "F.Mask" "F.Paste")
			(net "M_J_CPU1_SA_CB<5>")
		)
		(pad "AP19" smd circle
			(at -17.709896 -10.07999 180)
			(size 0.450088 0.450088)
			(layers "F.Cu" "F.Mask" "F.Paste")
			(net "GND")
		)
		(pad "AP20" smd circle
			(at -16.770096 -10.07999 180)
			(size 0.450088 0.450088)
			(layers "F.Cu" "F.Mask" "F.Paste")
			(net "M_I_CPU1_SA_CB<6>")
		)
		(pad "AP21" smd circle
			(at -15.830042 -10.07999 180)
			(size 0.450088 0.450088)
			(layers "F.Cu" "F.Mask" "F.Paste")
			(net "M_I_CPU1_SA_CB<5>")
		)
		(pad "AP22" smd circle
			(at -14.889988 -10.07999 180)
			(size 0.450088 0.450088)
			(layers "F.Cu" "F.Mask" "F.Paste")
			(net "GND")
		)
		(pad "AP23" smd circle
			(at -13.949934 -10.07999 180)
			(size 0.450088 0.450088)
			(layers "F.Cu" "F.Mask" "F.Paste")
			(net "PVDDCR_CPU0_P1")
		)
		(pad "AP24" smd circle
			(at -13.00988 -10.07999 180)
			(size 0.450088 0.450088)
			(layers "F.Cu" "F.Mask" "F.Paste")
			(net "PVDDCR_CPU0_P1")
		)
		(pad "AP25" smd circle
			(at -12.07008 -10.07999 180)
			(size 0.450088 0.450088)
			(layers "F.Cu" "F.Mask" "F.Paste")
			(net "GND")
		)
		(pad "AP26" smd circle
			(at -11.130026 -10.07999 180)
			(size 0.450088 0.450088)
			(layers "F.Cu" "F.Mask" "F.Paste")
			(net "PVDDCR_CPU0_P1")
		)
		(pad "AP27" smd circle
			(at -10.189972 -10.07999 180)
			(size 0.450088 0.450088)
			(layers "F.Cu" "F.Mask" "F.Paste")
			(net "PVDDCR_CPU0_P1")
		)
		(pad "AP28" smd circle
			(at -9.249918 -10.07999 180)
			(size 0.450088 0.450088)
			(layers "F.Cu" "F.Mask" "F.Paste")
			(net "GND")
		)
		(pad "AP29" smd circle
			(at -8.310118 -10.07999 180)
			(size 0.450088 0.450088)
			(layers "F.Cu" "F.Mask" "F.Paste")
			(net "PVDDCR_CPU0_P1")
		)
		(pad "AP30" smd circle
			(at -7.370064 -10.07999 180)
			(size 0.450088 0.450088)
			(layers "F.Cu" "F.Mask" "F.Paste")
			(net "PVDDCR_CPU0_P1")
		)
		(pad "AP31" smd circle
			(at -6.43001 -10.07999 180)
			(size 0.450088 0.450088)
			(layers "F.Cu" "F.Mask" "F.Paste")
			(net "GND")
		)
		(pad "AP32" smd circle
			(at -5.489956 -10.07999 180)
			(size 0.450088 0.450088)
			(layers "F.Cu" "F.Mask" "F.Paste")
			(net "PVDDCR_CPU0_P1")
		)
		(pad "AP33" smd circle
			(at -4.549902 -10.07999 180)
			(size 0.450088 0.450088)
			(layers "F.Cu" "F.Mask" "F.Paste")
			(net "PVDDCR_CPU0_P1")
		)
		(pad "AP34" smd circle
			(at -3.610102 -10.07999 180)
			(size 0.450088 0.450088)
			(layers "F.Cu" "F.Mask" "F.Paste")
			(net "GND")
		)
		(pad "AP35" smd circle
			(at -2.670048 -10.07999 180)
			(size 0.450088 0.450088)
			(layers "F.Cu" "F.Mask" "F.Paste")
			(net "GMI_CPU0_G1_CPU1_G3_TX_DN<0>")
		)
		(pad "AP36" smd circle
			(at -1.729994 -10.07999 180)
			(size 0.450088 0.450088)
			(layers "F.Cu" "F.Mask" "F.Paste")
			(net "GMI_CPU0_G1_CPU1_G3_TX_DP<0>")
		)
		(pad "AP37" smd circle
			(at -0.78994 -10.07999 180)
			(size 0.450088 0.450088)
			(layers "F.Cu" "F.Mask" "F.Paste")
			(net "GND")
		)
		(pad "AP39" smd circle
			(at 1.089914 -10.07999 180)
			(size 0.450088 0.450088)
			(layers "F.Cu" "F.Mask" "F.Paste")
			(net "GND")
		)
		(pad "AP40" smd circle
			(at 2.029968 -10.07999 180)
			(size 0.450088 0.450088)
			(layers "F.Cu" "F.Mask" "F.Paste")
			(net "P5E_CPU1_G1_TX_DP<0>")
		)
		(pad "AP41" smd circle
			(at 2.970022 -10.07999 180)
			(size 0.450088 0.450088)
			(layers "F.Cu" "F.Mask" "F.Paste")
			(net "P5E_CPU1_G1_TX_DN<0>")
		)
		(pad "AP42" smd circle
			(at 3.910076 -10.07999 180)
			(size 0.450088 0.450088)
			(layers "F.Cu" "F.Mask" "F.Paste")
			(net "GND")
		)
		(pad "AP43" smd circle
			(at 4.849876 -10.07999 180)
			(size 0.450088 0.450088)
			(layers "F.Cu" "F.Mask" "F.Paste")
			(net "PVDDCR_CPU0_P1")
		)
		(pad "AP44" smd circle
			(at 5.78993 -10.07999 180)
			(size 0.450088 0.450088)
			(layers "F.Cu" "F.Mask" "F.Paste")
			(net "PVDDCR_CPU0_P1")
		)
		(pad "AP45" smd circle
			(at 6.729984 -10.07999 180)
			(size 0.450088 0.450088)
			(layers "F.Cu" "F.Mask" "F.Paste")
			(net "GND")
		)
		(pad "AP46" smd circle
			(at 7.670038 -10.07999 180)
			(size 0.450088 0.450088)
			(layers "F.Cu" "F.Mask" "F.Paste")
			(net "PVDDCR_CPU0_P1")
		)
		(pad "AP47" smd circle
			(at 8.610092 -10.07999 180)
			(size 0.450088 0.450088)
			(layers "F.Cu" "F.Mask" "F.Paste")
			(net "PVDDCR_CPU0_P1")
		)
		(pad "AP48" smd circle
			(at 9.549892 -10.07999 180)
			(size 0.450088 0.450088)
			(layers "F.Cu" "F.Mask" "F.Paste")
			(net "GND")
		)
		(pad "AP49" smd circle
			(at 10.489946 -10.07999 180)
			(size 0.450088 0.450088)
			(layers "F.Cu" "F.Mask" "F.Paste")
			(net "PVDDCR_CPU0_P1")
		)
		(pad "AP50" smd circle
			(at 11.43 -10.07999 180)
			(size 0.450088 0.450088)
			(layers "F.Cu" "F.Mask" "F.Paste")
			(net "PVDDCR_CPU0_P1")
		)
		(pad "AP51" smd circle
			(at 12.370054 -10.07999 180)
			(size 0.450088 0.450088)
			(layers "F.Cu" "F.Mask" "F.Paste")
			(net "GND")
		)
		(pad "AP52" smd circle
			(at 13.310108 -10.07999 180)
			(size 0.450088 0.450088)
			(layers "F.Cu" "F.Mask" "F.Paste")
			(net "PVDDCR_CPU0_P1")
		)
		(pad "AP53" smd circle
			(at 14.249908 -10.07999 180)
			(size 0.450088 0.450088)
			(layers "F.Cu" "F.Mask" "F.Paste")
			(net "PVDDCR_CPU0_P1")
		)
		(pad "AP54" smd circle
			(at 15.189962 -10.07999 180)
			(size 0.450088 0.450088)
			(layers "F.Cu" "F.Mask" "F.Paste")
			(net "GND")
		)
		(pad "AP55" smd circle
			(at 16.130016 -10.07999 180)
			(size 0.450088 0.450088)
			(layers "F.Cu" "F.Mask" "F.Paste")
			(net "M_C_CPU1_SA_CB<5>")
		)
		(pad "AP56" smd circle
			(at 17.07007 -10.07999 180)
			(size 0.450088 0.450088)
			(layers "F.Cu" "F.Mask" "F.Paste")
			(net "M_C_CPU1_SA_CB<6>")
		)
		(pad "AP57" smd circle
			(at 18.010124 -10.07999 180)
			(size 0.450088 0.450088)
			(layers "F.Cu" "F.Mask" "F.Paste")
			(net "GND")
		)
		(pad "AP58" smd circle
			(at 18.949924 -10.07999 180)
			(size 0.450088 0.450088)
			(layers "F.Cu" "F.Mask" "F.Paste")
			(net "M_D_CPU1_SA_CB<5>")
		)
		(pad "AP59" smd circle
			(at 19.889978 -10.07999 180)
			(size 0.450088 0.450088)
			(layers "F.Cu" "F.Mask" "F.Paste")
			(net "GND")
		)
		(pad "AP60" smd circle
			(at 20.830032 -10.07999 180)
			(size 0.450088 0.450088)
			(layers "F.Cu" "F.Mask" "F.Paste")
			(net "M_D_CPU1_SA_CB<6>")
		)
		(pad "AP61" smd circle
			(at 21.770086 -10.07999 180)
			(size 0.450088 0.450088)
			(layers "F.Cu" "F.Mask" "F.Paste")
			(net "GND")
		)
		(pad "AP62" smd circle
			(at 22.709886 -10.07999 180)
			(size 0.450088 0.450088)
			(layers "F.Cu" "F.Mask" "F.Paste")
			(net "M_B_CPU1_SA_CB<5>")
		)
		(pad "AP63" smd circle
			(at 23.64994 -10.07999 180)
			(size 0.450088 0.450088)
			(layers "F.Cu" "F.Mask" "F.Paste")
			(net "M_B_CPU1_SA_CB<6>")
		)
		(pad "AP64" smd circle
			(at 24.589994 -10.07999 180)
			(size 0.450088 0.450088)
			(layers "F.Cu" "F.Mask" "F.Paste")
			(net "GND")
		)
		(pad "AP65" smd circle
			(at 25.530048 -10.07999 180)
			(size 0.450088 0.450088)
			(layers "F.Cu" "F.Mask" "F.Paste")
			(net "M_F_CPU1_SA_CB<5>")
		)
		(pad "AP66" smd circle
			(at 26.470102 -10.07999 180)
			(size 0.450088 0.450088)
			(layers "F.Cu" "F.Mask" "F.Paste")
			(net "GND")
		)
		(pad "AP67" smd circle
			(at 27.409902 -10.07999 180)
			(size 0.450088 0.450088)
			(layers "F.Cu" "F.Mask" "F.Paste")
			(net "M_F_CPU1_SA_CB<6>")
		)
		(pad "AP68" smd circle
			(at 28.349956 -10.07999 180)
			(size 0.450088 0.450088)
			(layers "F.Cu" "F.Mask" "F.Paste")
			(net "GND")
		)
		(pad "AP69" smd circle
			(at 29.29001 -10.07999 180)
			(size 0.450088 0.450088)
			(layers "F.Cu" "F.Mask" "F.Paste")
			(net "M_E_CPU1_SA_CB<5>")
		)
		(pad "AP70" smd circle
			(at 30.230064 -10.07999 180)
			(size 0.450088 0.450088)
			(layers "F.Cu" "F.Mask" "F.Paste")
			(net "M_E_CPU1_SA_CB<6>")
		)
		(pad "AP71" smd circle
			(at 31.170118 -10.07999 180)
			(size 0.450088 0.450088)
			(layers "F.Cu" "F.Mask" "F.Paste")
			(net "GND")
		)
		(pad "AP72" smd circle
			(at 32.109918 -10.07999 180)
			(size 0.450088 0.450088)
			(layers "F.Cu" "F.Mask" "F.Paste")
			(net "M_A_CPU1_SA_CB<5>")
		)
		(pad "AP73" smd circle
			(at 33.049972 -10.07999 180)
			(size 0.450088 0.450088)
			(layers "F.Cu" "F.Mask" "F.Paste")
			(net "GND")
		)
		(pad "AP74" smd circle
			(at 33.990026 -10.07999 180)
			(size 0.450088 0.450088)
			(layers "F.Cu" "F.Mask" "F.Paste")
			(net "M_A_CPU1_SA_CB<6>")
		)
		(pad "AR1" smd circle
			(at -34.159952 -9.269984 180)
			(size 0.450088 0.450088)
			(layers "F.Cu" "F.Mask" "F.Paste")
			(net "GND")
		)
		(pad "AR2" smd circle
			(at -33.219898 -9.269984 180)
			(size 0.450088 0.450088)
			(layers "F.Cu" "F.Mask" "F.Paste")
			(net "M_G_CPU1_ALERT_R_N")
		)
		(pad "AR3" smd circle
			(at -32.280098 -9.269984 180)
			(size 0.450088 0.450088)
			(layers "F.Cu" "F.Mask" "F.Paste")
			(net "M_G_CPU1_SA_CB<7>")
		)
		(pad "AR4" smd circle
			(at -31.340044 -9.269984 180)
			(size 0.450088 0.450088)
			(layers "F.Cu" "F.Mask" "F.Paste")
			(net "PVDDCR_SOC_P1")
		)
		(pad "AR5" smd circle
			(at -30.39999 -9.269984 180)
			(size 0.450088 0.450088)
			(layers "F.Cu" "F.Mask" "F.Paste")
			(net "GND")
		)
		(pad "AR6" smd circle
			(at -29.459936 -9.269984 180)
			(size 0.450088 0.450088)
			(layers "F.Cu" "F.Mask" "F.Paste")
			(net "GND")
		)
		(pad "AR7" smd circle
			(at -28.519882 -9.269984 180)
			(size 0.450088 0.450088)
			(layers "F.Cu" "F.Mask" "F.Paste")
			(net "M_K_CPU1_SA_CB<7>")
		)
		(pad "AR8" smd circle
			(at -27.580082 -9.269984 180)
			(size 0.450088 0.450088)
			(layers "F.Cu" "F.Mask" "F.Paste")
			(net "GND")
		)
		(pad "AR9" smd circle
			(at -26.640028 -9.269984 180)
			(size 0.450088 0.450088)
			(layers "F.Cu" "F.Mask" "F.Paste")
			(net "GND")
		)
		(pad "AR10" smd circle
			(at -25.699974 -9.269984 180)
			(size 0.450088 0.450088)
			(layers "F.Cu" "F.Mask" "F.Paste")
			(net "M_L_CPU1_SA_CB<7>")
		)
		(pad "AR11" smd circle
			(at -24.75992 -9.269984 180)
			(size 0.450088 0.450088)
			(layers "F.Cu" "F.Mask" "F.Paste")
			(net "PVDDCR_SOC_P1")
		)
		(pad "AR12" smd circle
			(at -23.82012 -9.269984 180)
			(size 0.450088 0.450088)
			(layers "F.Cu" "F.Mask" "F.Paste")
			(net "GND")
		)
		(pad "AR13" smd circle
			(at -22.880066 -9.269984 180)
			(size 0.450088 0.450088)
			(layers "F.Cu" "F.Mask" "F.Paste")
			(net "GND")
		)
		(pad "AR14" smd circle
			(at -21.940012 -9.269984 180)
			(size 0.450088 0.450088)
			(layers "F.Cu" "F.Mask" "F.Paste")
			(net "M_H_CPU1_SA_CB<7>")
		)
		(pad "AR15" smd circle
			(at -20.999958 -9.269984 180)
			(size 0.450088 0.450088)
			(layers "F.Cu" "F.Mask" "F.Paste")
			(net "GND")
		)
		(pad "AR16" smd circle
			(at -20.059904 -9.269984 180)
			(size 0.450088 0.450088)
			(layers "F.Cu" "F.Mask" "F.Paste")
			(net "GND")
		)
		(pad "AR17" smd circle
			(at -19.120104 -9.269984 180)
			(size 0.450088 0.450088)
			(layers "F.Cu" "F.Mask" "F.Paste")
			(net "M_J_CPU1_SA_CB<7>")
		)
		(pad "AR18" smd circle
			(at -18.18005 -9.269984 180)
			(size 0.450088 0.450088)
			(layers "F.Cu" "F.Mask" "F.Paste")
			(net "PVDDCR_SOC_P1")
		)
		(pad "AR19" smd circle
			(at -17.239996 -9.269984 180)
			(size 0.450088 0.450088)
			(layers "F.Cu" "F.Mask" "F.Paste")
			(net "GND")
		)
		(pad "AR20" smd circle
			(at -16.299942 -9.269984 180)
			(size 0.450088 0.450088)
			(layers "F.Cu" "F.Mask" "F.Paste")
			(net "GND")
		)
		(pad "AR21" smd circle
			(at -15.359888 -9.269984 180)
			(size 0.450088 0.450088)
			(layers "F.Cu" "F.Mask" "F.Paste")
			(net "M_I_CPU1_SA_CB<7>")
		)
		(pad "AR22" smd circle
			(at -14.420088 -9.269984 180)
			(size 0.450088 0.450088)
			(layers "F.Cu" "F.Mask" "F.Paste")
			(net "GND")
		)
		(pad "AR23" smd circle
			(at -13.480034 -9.269984 180)
			(size 0.450088 0.450088)
			(layers "F.Cu" "F.Mask" "F.Paste")
			(net "PVDDCR_CPU0_P1")
		)
		(pad "AR24" smd circle
			(at -12.53998 -9.269984 180)
			(size 0.450088 0.450088)
			(layers "F.Cu" "F.Mask" "F.Paste")
			(net "GND")
		)
		(pad "AR25" smd circle
			(at -11.599926 -9.269984 180)
			(size 0.450088 0.450088)
			(layers "F.Cu" "F.Mask" "F.Paste")
			(net "PVDDCR_CPU0_P1")
		)
		(pad "AR26" smd circle
			(at -10.659872 -9.269984 180)
			(size 0.450088 0.450088)
			(layers "F.Cu" "F.Mask" "F.Paste")
			(net "GND")
		)
		(pad "AR27" smd circle
			(at -9.720072 -9.269984 180)
			(size 0.450088 0.450088)
			(layers "F.Cu" "F.Mask" "F.Paste")
			(net "PVDDCR_CPU0_P1")
		)
		(pad "AR28" smd circle
			(at -8.780018 -9.269984 180)
			(size 0.450088 0.450088)
			(layers "F.Cu" "F.Mask" "F.Paste")
			(net "GND")
		)
		(pad "AR29" smd circle
			(at -7.839964 -9.269984 180)
			(size 0.450088 0.450088)
			(layers "F.Cu" "F.Mask" "F.Paste")
			(net "PVDDCR_CPU0_P1")
		)
		(pad "AR30" smd circle
			(at -6.89991 -9.269984 180)
			(size 0.450088 0.450088)
			(layers "F.Cu" "F.Mask" "F.Paste")
			(net "GND")
		)
		(pad "AR31" smd circle
			(at -5.96011 -9.269984 180)
			(size 0.450088 0.450088)
			(layers "F.Cu" "F.Mask" "F.Paste")
			(net "PVDDCR_CPU0_P1")
		)
		(pad "AR32" smd circle
			(at -5.020056 -9.269984 180)
			(size 0.450088 0.450088)
			(layers "F.Cu" "F.Mask" "F.Paste")
			(net "GND")
		)
		(pad "AR33" smd circle
			(at -4.080002 -9.269984 180)
			(size 0.450088 0.450088)
			(layers "F.Cu" "F.Mask" "F.Paste")
			(net "PVDDCR_CPU0_P1")
		)
		(pad "AR34" smd circle
			(at -3.139948 -9.269984 180)
			(size 0.450088 0.450088)
			(layers "F.Cu" "F.Mask" "F.Paste")
			(net "GND")
		)
		(pad "AR35" smd circle
			(at -2.199894 -9.269984 180)
			(size 0.450088 0.450088)
			(layers "F.Cu" "F.Mask" "F.Paste")
			(net "PVDDCR_CPU0_P1")
		)
		(pad "AR36" smd circle
			(at -1.260094 -9.269984 180)
			(size 0.450088 0.450088)
			(layers "F.Cu" "F.Mask" "F.Paste")
			(net "GND")
		)
		(pad "AR40" smd circle
			(at 1.560068 -9.269984 180)
			(size 0.450088 0.450088)
			(layers "F.Cu" "F.Mask" "F.Paste")
			(net "PVDDCR_CPU0_P1")
		)
		(pad "AR41" smd circle
			(at 2.500122 -9.269984 180)
			(size 0.450088 0.450088)
			(layers "F.Cu" "F.Mask" "F.Paste")
			(net "GND")
		)
		(pad "AR42" smd circle
			(at 3.439922 -9.269984 180)
			(size 0.450088 0.450088)
			(layers "F.Cu" "F.Mask" "F.Paste")
			(net "PVDDCR_CPU0_P1")
		)
		(pad "AR43" smd circle
			(at 4.379976 -9.269984 180)
			(size 0.450088 0.450088)
			(layers "F.Cu" "F.Mask" "F.Paste")
			(net "GND")
		)
		(pad "AR44" smd circle
			(at 5.32003 -9.269984 180)
			(size 0.450088 0.450088)
			(layers "F.Cu" "F.Mask" "F.Paste")
			(net "PVDDCR_CPU0_P1")
		)
		(pad "AR45" smd circle
			(at 6.260084 -9.269984 180)
			(size 0.450088 0.450088)
			(layers "F.Cu" "F.Mask" "F.Paste")
			(net "GND")
		)
		(pad "AR46" smd circle
			(at 7.199884 -9.269984 180)
			(size 0.450088 0.450088)
			(layers "F.Cu" "F.Mask" "F.Paste")
			(net "PVDDCR_CPU0_P1")
		)
		(pad "AR47" smd circle
			(at 8.139938 -9.269984 180)
			(size 0.450088 0.450088)
			(layers "F.Cu" "F.Mask" "F.Paste")
			(net "GND")
		)
		(pad "AR48" smd circle
			(at 9.079992 -9.269984 180)
			(size 0.450088 0.450088)
			(layers "F.Cu" "F.Mask" "F.Paste")
			(net "PVDDCR_CPU0_P1")
		)
		(pad "AR49" smd circle
			(at 10.020046 -9.269984 180)
			(size 0.450088 0.450088)
			(layers "F.Cu" "F.Mask" "F.Paste")
			(net "GND")
		)
		(pad "AR50" smd circle
			(at 10.9601 -9.269984 180)
			(size 0.450088 0.450088)
			(layers "F.Cu" "F.Mask" "F.Paste")
			(net "PVDDCR_CPU0_P1")
		)
		(pad "AR51" smd circle
			(at 11.8999 -9.269984 180)
			(size 0.450088 0.450088)
			(layers "F.Cu" "F.Mask" "F.Paste")
			(net "GND")
		)
		(pad "AR52" smd circle
			(at 12.839954 -9.269984 180)
			(size 0.450088 0.450088)
			(layers "F.Cu" "F.Mask" "F.Paste")
			(net "PVDD18_S5_P1")
		)
		(pad "AR53" smd circle
			(at 13.780008 -9.269984 180)
			(size 0.450088 0.450088)
			(layers "F.Cu" "F.Mask" "F.Paste")
			(net "GND")
		)
		(pad "AR54" smd circle
			(at 14.720062 -9.269984 180)
			(size 0.450088 0.450088)
			(layers "F.Cu" "F.Mask" "F.Paste")
			(net "PVDD18_S5_P1")
		)
		(pad "AR55" smd circle
			(at 15.660116 -9.269984 180)
			(size 0.450088 0.450088)
			(layers "F.Cu" "F.Mask" "F.Paste")
			(net "M_C_CPU1_SA_CB<7>")
		)
		(pad "AR56" smd circle
			(at 16.599916 -9.269984 180)
			(size 0.450088 0.450088)
			(layers "F.Cu" "F.Mask" "F.Paste")
			(net "GND")
		)
		(pad "AR57" smd circle
			(at 17.53997 -9.269984 180)
			(size 0.450088 0.450088)
			(layers "F.Cu" "F.Mask" "F.Paste")
			(net "GND")
		)
		(pad "AR58" smd circle
			(at 18.480024 -9.269984 180)
			(size 0.450088 0.450088)
			(layers "F.Cu" "F.Mask" "F.Paste")
			(net "PVDDIO_P1")
		)
		(pad "AR59" smd circle
			(at 19.420078 -9.269984 180)
			(size 0.450088 0.450088)
			(layers "F.Cu" "F.Mask" "F.Paste")
			(net "M_D_CPU1_SA_CB<7>")
		)
		(pad "AR60" smd circle
			(at 20.359878 -9.269984 180)
			(size 0.450088 0.450088)
			(layers "F.Cu" "F.Mask" "F.Paste")
			(net "GND")
		)
		(pad "AR61" smd circle
			(at 21.299932 -9.269984 180)
			(size 0.450088 0.450088)
			(layers "F.Cu" "F.Mask" "F.Paste")
			(net "GND")
		)
		(pad "AR62" smd circle
			(at 22.239986 -9.269984 180)
			(size 0.450088 0.450088)
			(layers "F.Cu" "F.Mask" "F.Paste")
			(net "M_B_CPU1_SA_CB<7>")
		)
		(pad "AR63" smd circle
			(at 23.18004 -9.269984 180)
			(size 0.450088 0.450088)
			(layers "F.Cu" "F.Mask" "F.Paste")
			(net "GND")
		)
		(pad "AR64" smd circle
			(at 24.120094 -9.269984 180)
			(size 0.450088 0.450088)
			(layers "F.Cu" "F.Mask" "F.Paste")
			(net "GND")
		)
		(pad "AR65" smd circle
			(at 25.059894 -9.269984 180)
			(size 0.450088 0.450088)
			(layers "F.Cu" "F.Mask" "F.Paste")
			(net "PVDDIO_P1")
		)
		(pad "AR66" smd circle
			(at 25.999948 -9.269984 180)
			(size 0.450088 0.450088)
			(layers "F.Cu" "F.Mask" "F.Paste")
			(net "M_F_CPU1_SA_CB<7>")
		)
		(pad "AR67" smd circle
			(at 26.940002 -9.269984 180)
			(size 0.450088 0.450088)
			(layers "F.Cu" "F.Mask" "F.Paste")
			(net "GND")
		)
		(pad "AR68" smd circle
			(at 27.880056 -9.269984 180)
			(size 0.450088 0.450088)
			(layers "F.Cu" "F.Mask" "F.Paste")
			(net "GND")
		)
		(pad "AR69" smd circle
			(at 28.82011 -9.269984 180)
			(size 0.450088 0.450088)
			(layers "F.Cu" "F.Mask" "F.Paste")
			(net "M_E_CPU1_SA_CB<7>")
		)
		(pad "AR70" smd circle
			(at 29.75991 -9.269984 180)
			(size 0.450088 0.450088)
			(layers "F.Cu" "F.Mask" "F.Paste")
			(net "GND")
		)
		(pad "AR71" smd circle
			(at 30.699964 -9.269984 180)
			(size 0.450088 0.450088)
			(layers "F.Cu" "F.Mask" "F.Paste")
			(net "GND")
		)
		(pad "AR72" smd circle
			(at 31.640018 -9.269984 180)
			(size 0.450088 0.450088)
			(layers "F.Cu" "F.Mask" "F.Paste")
			(net "PVDDIO_P1")
		)
		(pad "AR73" smd circle
			(at 32.580072 -9.269984 180)
			(size 0.450088 0.450088)
			(layers "F.Cu" "F.Mask" "F.Paste")
			(net "M_A_CPU1_SA_CB<7>")
		)
		(pad "AR74" smd circle
			(at 33.519872 -9.269984 180)
			(size 0.450088 0.450088)
			(layers "F.Cu" "F.Mask" "F.Paste")
			(net "M_A_CPU1_ALERT_R_N")
		)
		(pad "AR75" smd circle
			(at 34.459926 -9.269984 180)
			(size 0.450088 0.450088)
			(layers "F.Cu" "F.Mask" "F.Paste")
			(net "GND")
		)
		(pad "AT2" smd circle
			(at -33.690052 -8.459978 180)
			(size 0.450088 0.450088)
			(layers "F.Cu" "F.Mask" "F.Paste")
			(net "M_G_CPU1_RESET_N")
		)
		(pad "AT3" smd circle
			(at -32.749998 -8.459978 180)
			(size 0.450088 0.450088)
			(layers "F.Cu" "F.Mask" "F.Paste")
			(net "GND")
		)
		(pad "AT4" smd circle
			(at -31.809944 -8.459978 180)
			(size 0.450088 0.450088)
			(layers "F.Cu" "F.Mask" "F.Paste")
			(net "GND")
		)
		(pad "AT5" smd circle
			(at -30.86989 -8.459978 180)
			(size 0.450088 0.450088)
			(layers "F.Cu" "F.Mask" "F.Paste")
			(net "GND")
		)
		(pad "AT6" smd circle
			(at -29.93009 -8.459978 180)
			(size 0.450088 0.450088)
			(layers "F.Cu" "F.Mask" "F.Paste")
			(net "GND")
		)
		(pad "AT7" smd circle
			(at -28.990036 -8.459978 180)
			(size 0.450088 0.450088)
			(layers "F.Cu" "F.Mask" "F.Paste")
			(net "M_K_CPU1_ALERT_R_N")
		)
		(pad "AT8" smd circle
			(at -28.049982 -8.459978 180)
			(size 0.450088 0.450088)
			(layers "F.Cu" "F.Mask" "F.Paste")
			(net "GND")
		)
		(pad "AT9" smd circle
			(at -27.109928 -8.459978 180)
			(size 0.450088 0.450088)
			(layers "F.Cu" "F.Mask" "F.Paste")
			(net "GND")
		)
		(pad "AT10" smd circle
			(at -26.170128 -8.459978 180)
			(size 0.450088 0.450088)
			(layers "F.Cu" "F.Mask" "F.Paste")
			(net "GND")
		)
		(pad "AT11" smd circle
			(at -25.230074 -8.459978 180)
			(size 0.450088 0.450088)
			(layers "F.Cu" "F.Mask" "F.Paste")
			(net "M_L_CPU1_ALERT_R_N")
		)
		(pad "AT12" smd circle
			(at -24.29002 -8.459978 180)
			(size 0.450088 0.450088)
			(layers "F.Cu" "F.Mask" "F.Paste")
			(net "GND")
		)
		(pad "AT13" smd circle
			(at -23.349966 -8.459978 180)
			(size 0.450088 0.450088)
			(layers "F.Cu" "F.Mask" "F.Paste")
			(net "GND")
		)
		(pad "AT14" smd circle
			(at -22.409912 -8.459978 180)
			(size 0.450088 0.450088)
			(layers "F.Cu" "F.Mask" "F.Paste")
			(net "M_H_CPU1_ALERT_R_N")
		)
		(pad "AT15" smd circle
			(at -21.470112 -8.459978 180)
			(size 0.450088 0.450088)
			(layers "F.Cu" "F.Mask" "F.Paste")
			(net "GND")
		)
		(pad "AT16" smd circle
			(at -20.530058 -8.459978 180)
			(size 0.450088 0.450088)
			(layers "F.Cu" "F.Mask" "F.Paste")
			(net "GND")
		)
		(pad "AT17" smd circle
			(at -19.590004 -8.459978 180)
			(size 0.450088 0.450088)
			(layers "F.Cu" "F.Mask" "F.Paste")
			(net "GND")
		)
		(pad "AT18" smd circle
			(at -18.64995 -8.459978 180)
			(size 0.450088 0.450088)
			(layers "F.Cu" "F.Mask" "F.Paste")
			(net "M_J_CPU1_ALERT_R_N")
		)
		(pad "AT19" smd circle
			(at -17.709896 -8.459978 180)
			(size 0.450088 0.450088)
			(layers "F.Cu" "F.Mask" "F.Paste")
			(net "GND")
		)
		(pad "AT20" smd circle
			(at -16.770096 -8.459978 180)
			(size 0.450088 0.450088)
			(layers "F.Cu" "F.Mask" "F.Paste")
			(net "GND")
		)
		(pad "AT21" smd circle
			(at -15.830042 -8.459978 180)
			(size 0.450088 0.450088)
			(layers "F.Cu" "F.Mask" "F.Paste")
			(net "M_I_CPU1_ALERT_R_N")
		)
		(pad "AT22" smd circle
			(at -14.889988 -8.459978 180)
			(size 0.450088 0.450088)
			(layers "F.Cu" "F.Mask" "F.Paste")
			(net "PVDDCR_SOC_P1")
		)
		(pad "AT23" smd circle
			(at -13.949934 -8.459978 180)
			(size 0.450088 0.450088)
			(layers "F.Cu" "F.Mask" "F.Paste")
			(net "GND")
		)
		(pad "AT24" smd circle
			(at -13.00988 -8.459978 180)
			(size 0.450088 0.450088)
			(layers "F.Cu" "F.Mask" "F.Paste")
			(net "PVDDCR_CPU0_P1")
		)
		(pad "AT25" smd circle
			(at -12.07008 -8.459978 180)
			(size 0.450088 0.450088)
			(layers "F.Cu" "F.Mask" "F.Paste")
			(net "GND")
		)
		(pad "AT26" smd circle
			(at -11.130026 -8.459978 180)
			(size 0.450088 0.450088)
			(layers "F.Cu" "F.Mask" "F.Paste")
			(net "PVDDCR_CPU0_P1")
		)
		(pad "AT27" smd circle
			(at -10.189972 -8.459978 180)
			(size 0.450088 0.450088)
			(layers "F.Cu" "F.Mask" "F.Paste")
			(net "GND")
		)
		(pad "AT28" smd circle
			(at -9.249918 -8.459978 180)
			(size 0.450088 0.450088)
			(layers "F.Cu" "F.Mask" "F.Paste")
			(net "PVDDCR_CPU0_P1")
		)
		(pad "AT29" smd circle
			(at -8.310118 -8.459978 180)
			(size 0.450088 0.450088)
			(layers "F.Cu" "F.Mask" "F.Paste")
			(net "GND")
		)
		(pad "AT30" smd circle
			(at -7.370064 -8.459978 180)
			(size 0.450088 0.450088)
			(layers "F.Cu" "F.Mask" "F.Paste")
			(net "PVDDCR_CPU0_P1")
		)
		(pad "AT31" smd circle
			(at -6.43001 -8.459978 180)
			(size 0.450088 0.450088)
			(layers "F.Cu" "F.Mask" "F.Paste")
			(net "GND")
		)
		(pad "AT32" smd circle
			(at -5.489956 -8.459978 180)
			(size 0.450088 0.450088)
			(layers "F.Cu" "F.Mask" "F.Paste")
			(net "PVDDCR_CPU0_P1")
		)
		(pad "AT33" smd circle
			(at -4.549902 -8.459978 180)
			(size 0.450088 0.450088)
			(layers "F.Cu" "F.Mask" "F.Paste")
			(net "GND")
		)
		(pad "AT34" smd circle
			(at -3.610102 -8.459978 180)
			(size 0.450088 0.450088)
			(layers "F.Cu" "F.Mask" "F.Paste")
			(net "PVDDCR_CPU0_P1")
		)
		(pad "AT35" smd circle
			(at -2.670048 -8.459978 180)
			(size 0.450088 0.450088)
			(layers "F.Cu" "F.Mask" "F.Paste")
			(net "GND")
		)
		(pad "AT36" smd circle
			(at -1.729994 -8.459978 180)
			(size 0.450088 0.450088)
			(layers "F.Cu" "F.Mask" "F.Paste")
			(net "PVDDCR_CPU0_P1")
		)
		(pad "AT37" smd circle
			(at -0.78994 -8.459978 180)
			(size 0.450088 0.450088)
			(layers "F.Cu" "F.Mask" "F.Paste")
			(net "GND")
		)
		(pad "AT39" smd circle
			(at 1.089914 -8.459978 180)
			(size 0.450088 0.450088)
			(layers "F.Cu" "F.Mask" "F.Paste")
			(net "PVDDCR_CPU0_P1")
		)
		(pad "AT40" smd circle
			(at 2.029968 -8.459978 180)
			(size 0.450088 0.450088)
			(layers "F.Cu" "F.Mask" "F.Paste")
			(net "GND")
		)
		(pad "AT41" smd circle
			(at 2.970022 -8.459978 180)
			(size 0.450088 0.450088)
			(layers "F.Cu" "F.Mask" "F.Paste")
			(net "PVDDCR_CPU0_P1")
		)
		(pad "AT42" smd circle
			(at 3.910076 -8.459978 180)
			(size 0.450088 0.450088)
			(layers "F.Cu" "F.Mask" "F.Paste")
			(net "GND")
		)
		(pad "AT43" smd circle
			(at 4.849876 -8.459978 180)
			(size 0.450088 0.450088)
			(layers "F.Cu" "F.Mask" "F.Paste")
			(net "PVDDCR_CPU0_P1")
		)
		(pad "AT44" smd circle
			(at 5.78993 -8.459978 180)
			(size 0.450088 0.450088)
			(layers "F.Cu" "F.Mask" "F.Paste")
			(net "GND")
		)
		(pad "AT45" smd circle
			(at 6.729984 -8.459978 180)
			(size 0.450088 0.450088)
			(layers "F.Cu" "F.Mask" "F.Paste")
			(net "PVDDCR_CPU0_P1")
		)
		(pad "AT46" smd circle
			(at 7.670038 -8.459978 180)
			(size 0.450088 0.450088)
			(layers "F.Cu" "F.Mask" "F.Paste")
			(net "GND")
		)
		(pad "AT47" smd circle
			(at 8.610092 -8.459978 180)
			(size 0.450088 0.450088)
			(layers "F.Cu" "F.Mask" "F.Paste")
			(net "PVDDCR_CPU0_P1")
		)
		(pad "AT48" smd circle
			(at 9.549892 -8.459978 180)
			(size 0.450088 0.450088)
			(layers "F.Cu" "F.Mask" "F.Paste")
			(net "GND")
		)
		(pad "AT49" smd circle
			(at 10.489946 -8.459978 180)
			(size 0.450088 0.450088)
			(layers "F.Cu" "F.Mask" "F.Paste")
			(net "PVDDCR_CPU0_P1")
		)
		(pad "AT50" smd circle
			(at 11.43 -8.459978 180)
			(size 0.450088 0.450088)
			(layers "F.Cu" "F.Mask" "F.Paste")
			(net "GND")
		)
		(pad "AT51" smd circle
			(at 12.370054 -8.459978 180)
			(size 0.450088 0.450088)
			(layers "F.Cu" "F.Mask" "F.Paste")
			(net "PVDD18_S5_P1")
		)
		(pad "AT52" smd circle
			(at 13.310108 -8.459978 180)
			(size 0.450088 0.450088)
			(layers "F.Cu" "F.Mask" "F.Paste")
			(net "GND")
		)
		(pad "AT53" smd circle
			(at 14.249908 -8.459978 180)
			(size 0.450088 0.450088)
			(layers "F.Cu" "F.Mask" "F.Paste")
			(net "PVDD18_S5_P1")
		)
		(pad "AT54" smd circle
			(at 15.189962 -8.459978 180)
			(size 0.450088 0.450088)
			(layers "F.Cu" "F.Mask" "F.Paste")
			(net "GND")
		)
		(pad "AT55" smd circle
			(at 16.130016 -8.459978 180)
			(size 0.450088 0.450088)
			(layers "F.Cu" "F.Mask" "F.Paste")
			(net "M_C_CPU1_ALERT_R_N")
		)
		(pad "AT56" smd circle
			(at 17.07007 -8.459978 180)
			(size 0.450088 0.450088)
			(layers "F.Cu" "F.Mask" "F.Paste")
			(net "GND")
		)
		(pad "AT57" smd circle
			(at 18.010124 -8.459978 180)
			(size 0.450088 0.450088)
			(layers "F.Cu" "F.Mask" "F.Paste")
			(net "GND")
		)
		(pad "AT58" smd circle
			(at 18.949924 -8.459978 180)
			(size 0.450088 0.450088)
			(layers "F.Cu" "F.Mask" "F.Paste")
			(net "M_D_CPU1_ALERT_R_N")
		)
		(pad "AT59" smd circle
			(at 19.889978 -8.459978 180)
			(size 0.450088 0.450088)
			(layers "F.Cu" "F.Mask" "F.Paste")
			(net "GND")
		)
		(pad "AT60" smd circle
			(at 20.830032 -8.459978 180)
			(size 0.450088 0.450088)
			(layers "F.Cu" "F.Mask" "F.Paste")
			(net "GND")
		)
		(pad "AT61" smd circle
			(at 21.770086 -8.459978 180)
			(size 0.450088 0.450088)
			(layers "F.Cu" "F.Mask" "F.Paste")
			(net "GND")
		)
		(pad "AT62" smd circle
			(at 22.709886 -8.459978 180)
			(size 0.450088 0.450088)
			(layers "F.Cu" "F.Mask" "F.Paste")
			(net "M_B_CPU1_ALERT_R_N")
		)
		(pad "AT63" smd circle
			(at 23.64994 -8.459978 180)
			(size 0.450088 0.450088)
			(layers "F.Cu" "F.Mask" "F.Paste")
			(net "GND")
		)
		(pad "AT64" smd circle
			(at 24.589994 -8.459978 180)
			(size 0.450088 0.450088)
			(layers "F.Cu" "F.Mask" "F.Paste")
			(net "GND")
		)
		(pad "AT65" smd circle
			(at 25.530048 -8.459978 180)
			(size 0.450088 0.450088)
			(layers "F.Cu" "F.Mask" "F.Paste")
			(net "M_F_CPU1_ALERT_R_N")
		)
		(pad "AT66" smd circle
			(at 26.470102 -8.459978 180)
			(size 0.450088 0.450088)
			(layers "F.Cu" "F.Mask" "F.Paste")
			(net "GND")
		)
		(pad "AT67" smd circle
			(at 27.409902 -8.459978 180)
			(size 0.450088 0.450088)
			(layers "F.Cu" "F.Mask" "F.Paste")
			(net "GND")
		)
		(pad "AT68" smd circle
			(at 28.349956 -8.459978 180)
			(size 0.450088 0.450088)
			(layers "F.Cu" "F.Mask" "F.Paste")
			(net "GND")
		)
		(pad "AT69" smd circle
			(at 29.29001 -8.459978 180)
			(size 0.450088 0.450088)
			(layers "F.Cu" "F.Mask" "F.Paste")
			(net "M_E_CPU1_ALERT_R_N")
		)
		(pad "AT70" smd circle
			(at 30.230064 -8.459978 180)
			(size 0.450088 0.450088)
			(layers "F.Cu" "F.Mask" "F.Paste")
			(net "GND")
		)
		(pad "AT71" smd circle
			(at 31.170118 -8.459978 180)
			(size 0.450088 0.450088)
			(layers "F.Cu" "F.Mask" "F.Paste")
			(net "GND")
		)
		(pad "AT72" smd circle
			(at 32.109918 -8.459978 180)
			(size 0.450088 0.450088)
			(layers "F.Cu" "F.Mask" "F.Paste")
			(net "GND")
		)
		(pad "AT73" smd circle
			(at 33.049972 -8.459978 180)
			(size 0.450088 0.450088)
			(layers "F.Cu" "F.Mask" "F.Paste")
			(net "GND")
		)
		(pad "AT74" smd circle
			(at 33.990026 -8.459978 180)
			(size 0.450088 0.450088)
			(layers "F.Cu" "F.Mask" "F.Paste")
			(net "M_A_CPU1_RESET_N")
		)
		(pad "AU1" smd circle
			(at -34.159952 -7.649972 180)
			(size 0.450088 0.450088)
			(layers "F.Cu" "F.Mask" "F.Paste")
			(net "GND")
		)
		(pad "AU2" smd circle
			(at -33.219898 -7.649972 180)
			(size 0.450088 0.450088)
			(layers "F.Cu" "F.Mask" "F.Paste")
			(net "M_G_CPU1_SA_CS_N<0>")
		)
		(pad "AU3" smd circle
			(at -32.280098 -7.649972 180)
			(size 0.450088 0.450088)
			(layers "F.Cu" "F.Mask" "F.Paste")
			(net "GND")
		)
		(pad "AU4" smd circle
			(at -31.340044 -7.649972 180)
			(size 0.450088 0.450088)
			(layers "F.Cu" "F.Mask" "F.Paste")
			(net "GND")
		)
		(pad "AU5" smd circle
			(at -30.39999 -7.649972 180)
			(size 0.450088 0.450088)
			(layers "F.Cu" "F.Mask" "F.Paste")
			(net "M_K_CPU1_SA_CS_N<0>")
		)
		(pad "AU6" smd circle
			(at -29.459936 -7.649972 180)
			(size 0.450088 0.450088)
			(layers "F.Cu" "F.Mask" "F.Paste")
			(net "GND")
		)
		(pad "AU7" smd circle
			(at -28.519882 -7.649972 180)
			(size 0.450088 0.450088)
			(layers "F.Cu" "F.Mask" "F.Paste")
			(net "M_K_CPU1_RESET_N")
		)
		(pad "AU8" smd circle
			(at -27.580082 -7.649972 180)
			(size 0.450088 0.450088)
			(layers "F.Cu" "F.Mask" "F.Paste")
			(net "GND")
		)
		(pad "AU9" smd circle
			(at -26.640028 -7.649972 180)
			(size 0.450088 0.450088)
			(layers "F.Cu" "F.Mask" "F.Paste")
			(net "M_L_CPU1_SA_CS_N<0>")
		)
		(pad "AU10" smd circle
			(at -25.699974 -7.649972 180)
			(size 0.450088 0.450088)
			(layers "F.Cu" "F.Mask" "F.Paste")
			(net "M_L_CPU1_RESET_N")
		)
		(pad "AU11" smd circle
			(at -24.75992 -7.649972 180)
			(size 0.450088 0.450088)
			(layers "F.Cu" "F.Mask" "F.Paste")
			(net "GND")
		)
		(pad "AU12" smd circle
			(at -23.82012 -7.649972 180)
			(size 0.450088 0.450088)
			(layers "F.Cu" "F.Mask" "F.Paste")
			(net "M_H_CPU1_SA_CS_N<0>")
		)
		(pad "AU13" smd circle
			(at -22.880066 -7.649972 180)
			(size 0.450088 0.450088)
			(layers "F.Cu" "F.Mask" "F.Paste")
			(net "GND")
		)
		(pad "AU14" smd circle
			(at -21.940012 -7.649972 180)
			(size 0.450088 0.450088)
			(layers "F.Cu" "F.Mask" "F.Paste")
			(net "M_H_CPU1_RESET_N")
		)
		(pad "AU15" smd circle
			(at -20.999958 -7.649972 180)
			(size 0.450088 0.450088)
			(layers "F.Cu" "F.Mask" "F.Paste")
			(net "GND")
		)
		(pad "AU16" smd circle
			(at -20.059904 -7.649972 180)
			(size 0.450088 0.450088)
			(layers "F.Cu" "F.Mask" "F.Paste")
			(net "M_J_CPU1_SA_CS_N<0>")
		)
		(pad "AU17" smd circle
			(at -19.120104 -7.649972 180)
			(size 0.450088 0.450088)
			(layers "F.Cu" "F.Mask" "F.Paste")
			(net "M_J_CPU1_RESET_N")
		)
		(pad "AU18" smd circle
			(at -18.18005 -7.649972 180)
			(size 0.450088 0.450088)
			(layers "F.Cu" "F.Mask" "F.Paste")
			(net "GND")
		)
		(pad "AU19" smd circle
			(at -17.239996 -7.649972 180)
			(size 0.450088 0.450088)
			(layers "F.Cu" "F.Mask" "F.Paste")
			(net "M_I_CPU1_SA_CS_N<0>")
		)
		(pad "AU20" smd circle
			(at -16.299942 -7.649972 180)
			(size 0.450088 0.450088)
			(layers "F.Cu" "F.Mask" "F.Paste")
			(net "GND")
		)
		(pad "AU21" smd circle
			(at -15.359888 -7.649972 180)
			(size 0.450088 0.450088)
			(layers "F.Cu" "F.Mask" "F.Paste")
			(net "M_I_CPU1_RESET_N")
		)
		(pad "AU22" smd circle
			(at -14.420088 -7.649972 180)
			(size 0.450088 0.450088)
			(layers "F.Cu" "F.Mask" "F.Paste")
			(net "GND")
		)
		(pad "AU23" smd circle
			(at -13.480034 -7.649972 180)
			(size 0.450088 0.450088)
			(layers "F.Cu" "F.Mask" "F.Paste")
			(net "PVDDCR_SOC_P1")
		)
		(pad "AU24" smd circle
			(at -12.53998 -7.649972 180)
			(size 0.450088 0.450088)
			(layers "F.Cu" "F.Mask" "F.Paste")
			(net "GND")
		)
		(pad "AU25" smd circle
			(at -11.599926 -7.649972 180)
			(size 0.450088 0.450088)
			(layers "F.Cu" "F.Mask" "F.Paste")
			(net "PVDDCR_CPU0_P1")
		)
		(pad "AU26" smd circle
			(at -10.659872 -7.649972 180)
			(size 0.450088 0.450088)
			(layers "F.Cu" "F.Mask" "F.Paste")
			(net "GND")
		)
		(pad "AU27" smd circle
			(at -9.720072 -7.649972 180)
			(size 0.450088 0.450088)
			(layers "F.Cu" "F.Mask" "F.Paste")
			(net "PVDDCR_SOC_P1")
		)
		(pad "AU28" smd circle
			(at -8.780018 -7.649972 180)
			(size 0.450088 0.450088)
			(layers "F.Cu" "F.Mask" "F.Paste")
			(net "GND")
		)
		(pad "AU29" smd circle
			(at -7.839964 -7.649972 180)
			(size 0.450088 0.450088)
			(layers "F.Cu" "F.Mask" "F.Paste")
			(net "PVDDCR_CPU0_P1")
		)
		(pad "AU30" smd circle
			(at -6.89991 -7.649972 180)
			(size 0.450088 0.450088)
			(layers "F.Cu" "F.Mask" "F.Paste")
			(net "GND")
		)
		(pad "AU31" smd circle
			(at -5.96011 -7.649972 180)
			(size 0.450088 0.450088)
			(layers "F.Cu" "F.Mask" "F.Paste")
			(net "PVDDCR_SOC_P1")
		)
		(pad "AU32" smd circle
			(at -5.020056 -7.649972 180)
			(size 0.450088 0.450088)
			(layers "F.Cu" "F.Mask" "F.Paste")
			(net "GND")
		)
		(pad "AU33" smd circle
			(at -4.080002 -7.649972 180)
			(size 0.450088 0.450088)
			(layers "F.Cu" "F.Mask" "F.Paste")
			(net "PVDDCR_CPU0_P1")
		)
		(pad "AU34" smd circle
			(at -3.139948 -7.649972 180)
			(size 0.450088 0.450088)
			(layers "F.Cu" "F.Mask" "F.Paste")
			(net "GND")
		)
		(pad "AU35" smd circle
			(at -2.199894 -7.649972 180)
			(size 0.450088 0.450088)
			(layers "F.Cu" "F.Mask" "F.Paste")
			(net "PVDDCR_SOC_P1")
		)
		(pad "AU36" smd circle
			(at -1.260094 -7.649972 180)
			(size 0.450088 0.450088)
			(layers "F.Cu" "F.Mask" "F.Paste")
			(net "GND")
		)
		(pad "AU40" smd circle
			(at 1.560068 -7.649972 180)
			(size 0.450088 0.450088)
			(layers "F.Cu" "F.Mask" "F.Paste")
			(net "PVDDCR_SOC_P1")
		)
		(pad "AU41" smd circle
			(at 2.500122 -7.649972 180)
			(size 0.450088 0.450088)
			(layers "F.Cu" "F.Mask" "F.Paste")
			(net "GND")
		)
		(pad "AU42" smd circle
			(at 3.439922 -7.649972 180)
			(size 0.450088 0.450088)
			(layers "F.Cu" "F.Mask" "F.Paste")
			(net "PVDDCR_CPU0_P1")
		)
		(pad "AU43" smd circle
			(at 4.379976 -7.649972 180)
			(size 0.450088 0.450088)
			(layers "F.Cu" "F.Mask" "F.Paste")
			(net "GND")
		)
		(pad "AU44" smd circle
			(at 5.32003 -7.649972 180)
			(size 0.450088 0.450088)
			(layers "F.Cu" "F.Mask" "F.Paste")
			(net "PVDDCR_CPU0_P1")
		)
		(pad "AU45" smd circle
			(at 6.260084 -7.649972 180)
			(size 0.450088 0.450088)
			(layers "F.Cu" "F.Mask" "F.Paste")
			(net "GND")
		)
		(pad "AU46" smd circle
			(at 7.199884 -7.649972 180)
			(size 0.450088 0.450088)
			(layers "F.Cu" "F.Mask" "F.Paste")
			(net "PVDDCR_CPU0_P1")
		)
		(pad "AU47" smd circle
			(at 8.139938 -7.649972 180)
			(size 0.450088 0.450088)
			(layers "F.Cu" "F.Mask" "F.Paste")
			(net "GND")
		)
		(pad "AU48" smd circle
			(at 9.079992 -7.649972 180)
			(size 0.450088 0.450088)
			(layers "F.Cu" "F.Mask" "F.Paste")
			(net "PVDDCR_CPU0_P1")
		)
		(pad "AU49" smd circle
			(at 10.020046 -7.649972 180)
			(size 0.450088 0.450088)
			(layers "F.Cu" "F.Mask" "F.Paste")
			(net "GND")
		)
		(pad "AU50" smd circle
			(at 10.9601 -7.649972 180)
			(size 0.450088 0.450088)
			(layers "F.Cu" "F.Mask" "F.Paste")
			(net "PVDD18_S5_P1")
		)
		(pad "AU51" smd circle
			(at 11.8999 -7.649972 180)
			(size 0.450088 0.450088)
			(layers "F.Cu" "F.Mask" "F.Paste")
			(net "GND")
		)
		(pad "AU52" smd circle
			(at 12.839954 -7.649972 180)
			(size 0.450088 0.450088)
			(layers "F.Cu" "F.Mask" "F.Paste")
			(net "PVDD18_S5_P1")
		)
		(pad "AU53" smd circle
			(at 13.780008 -7.649972 180)
			(size 0.450088 0.450088)
			(layers "F.Cu" "F.Mask" "F.Paste")
			(net "GND")
		)
		(pad "AU54" smd circle
			(at 14.720062 -7.649972 180)
			(size 0.450088 0.450088)
			(layers "F.Cu" "F.Mask" "F.Paste")
			(net "PVDD18_S5_P1")
		)
		(pad "AU55" smd circle
			(at 15.660116 -7.649972 180)
			(size 0.450088 0.450088)
			(layers "F.Cu" "F.Mask" "F.Paste")
			(net "M_C_CPU1_RESET_N")
		)
		(pad "AU56" smd circle
			(at 16.599916 -7.649972 180)
			(size 0.450088 0.450088)
			(layers "F.Cu" "F.Mask" "F.Paste")
			(net "GND")
		)
		(pad "AU57" smd circle
			(at 17.53997 -7.649972 180)
			(size 0.450088 0.450088)
			(layers "F.Cu" "F.Mask" "F.Paste")
			(net "Net_2008")
		)
		(pad "AU58" smd circle
			(at 18.480024 -7.649972 180)
			(size 0.450088 0.450088)
			(layers "F.Cu" "F.Mask" "F.Paste")
			(net "GND")
		)
		(pad "AU59" smd circle
			(at 19.420078 -7.649972 180)
			(size 0.450088 0.450088)
			(layers "F.Cu" "F.Mask" "F.Paste")
			(net "M_D_CPU1_RESET_N")
		)
		(pad "AU60" smd circle
			(at 20.359878 -7.649972 180)
			(size 0.450088 0.450088)
			(layers "F.Cu" "F.Mask" "F.Paste")
			(net "Net_2016")
		)
		(pad "AU61" smd circle
			(at 21.299932 -7.649972 180)
			(size 0.450088 0.450088)
			(layers "F.Cu" "F.Mask" "F.Paste")
			(net "GND")
		)
		(pad "AU62" smd circle
			(at 22.239986 -7.649972 180)
			(size 0.450088 0.450088)
			(layers "F.Cu" "F.Mask" "F.Paste")
			(net "M_B_CPU1_RESET_N")
		)
		(pad "AU63" smd circle
			(at 23.18004 -7.649972 180)
			(size 0.450088 0.450088)
			(layers "F.Cu" "F.Mask" "F.Paste")
			(net "GND")
		)
		(pad "AU64" smd circle
			(at 24.120094 -7.649972 180)
			(size 0.450088 0.450088)
			(layers "F.Cu" "F.Mask" "F.Paste")
			(net "Net_2000")
		)
		(pad "AU65" smd circle
			(at 25.059894 -7.649972 180)
			(size 0.450088 0.450088)
			(layers "F.Cu" "F.Mask" "F.Paste")
			(net "GND")
		)
		(pad "AU66" smd circle
			(at 25.999948 -7.649972 180)
			(size 0.450088 0.450088)
			(layers "F.Cu" "F.Mask" "F.Paste")
			(net "M_F_CPU1_RESET_N")
		)
		(pad "AU67" smd circle
			(at 26.940002 -7.649972 180)
			(size 0.450088 0.450088)
			(layers "F.Cu" "F.Mask" "F.Paste")
			(net "Net_2032")
		)
		(pad "AU68" smd circle
			(at 27.880056 -7.649972 180)
			(size 0.450088 0.450088)
			(layers "F.Cu" "F.Mask" "F.Paste")
			(net "GND")
		)
		(pad "AU69" smd circle
			(at 28.82011 -7.649972 180)
			(size 0.450088 0.450088)
			(layers "F.Cu" "F.Mask" "F.Paste")
			(net "M_E_CPU1_RESET_N")
		)
		(pad "AU70" smd circle
			(at 29.75991 -7.649972 180)
			(size 0.450088 0.450088)
			(layers "F.Cu" "F.Mask" "F.Paste")
			(net "GND")
		)
		(pad "AU71" smd circle
			(at 30.699964 -7.649972 180)
			(size 0.450088 0.450088)
			(layers "F.Cu" "F.Mask" "F.Paste")
			(net "Net_2024")
		)
		(pad "AU72" smd circle
			(at 31.640018 -7.649972 180)
			(size 0.450088 0.450088)
			(layers "F.Cu" "F.Mask" "F.Paste")
			(net "GND")
		)
		(pad "AU73" smd circle
			(at 32.580072 -7.649972 180)
			(size 0.450088 0.450088)
			(layers "F.Cu" "F.Mask" "F.Paste")
			(net "GND")
		)
		(pad "AU74" smd circle
			(at 33.519872 -7.649972 180)
			(size 0.450088 0.450088)
			(layers "F.Cu" "F.Mask" "F.Paste")
			(net "Net_1992")
		)
		(pad "AU75" smd circle
			(at 34.459926 -7.649972 180)
			(size 0.450088 0.450088)
			(layers "F.Cu" "F.Mask" "F.Paste")
			(net "GND")
		)
		(pad "AV2" smd circle
			(at -33.690052 -6.839966 180)
			(size 0.450088 0.450088)
			(layers "F.Cu" "F.Mask" "F.Paste")
			(net "Net_2040")
		)
		(pad "AV3" smd circle
			(at -32.749998 -6.839966 180)
			(size 0.450088 0.450088)
			(layers "F.Cu" "F.Mask" "F.Paste")
			(net "GND")
		)
		(pad "AV4" smd circle
			(at -31.809944 -6.839966 180)
			(size 0.450088 0.450088)
			(layers "F.Cu" "F.Mask" "F.Paste")
			(net "M_G_CPU1_SA_CS_N<1>")
		)
		(pad "AV5" smd circle
			(at -30.86989 -6.839966 180)
			(size 0.450088 0.450088)
			(layers "F.Cu" "F.Mask" "F.Paste")
			(net "PVDDCR_SOC_P1")
		)
		(pad "AV6" smd circle
			(at -29.93009 -6.839966 180)
			(size 0.450088 0.450088)
			(layers "F.Cu" "F.Mask" "F.Paste")
			(net "Net_2189")
		)
		(pad "AV7" smd circle
			(at -28.990036 -6.839966 180)
			(size 0.450088 0.450088)
			(layers "F.Cu" "F.Mask" "F.Paste")
			(net "M_K_CPU1_SA_CS_N<1>")
		)
		(pad "AV8" smd circle
			(at -28.049982 -6.839966 180)
			(size 0.450088 0.450088)
			(layers "F.Cu" "F.Mask" "F.Paste")
			(net "GND")
		)
		(pad "AV9" smd circle
			(at -27.109928 -6.839966 180)
			(size 0.450088 0.450088)
			(layers "F.Cu" "F.Mask" "F.Paste")
			(net "Net_2181")
		)
		(pad "AV10" smd circle
			(at -26.170128 -6.839966 180)
			(size 0.450088 0.450088)
			(layers "F.Cu" "F.Mask" "F.Paste")
			(net "GND")
		)
		(pad "AV11" smd circle
			(at -25.230074 -6.839966 180)
			(size 0.450088 0.450088)
			(layers "F.Cu" "F.Mask" "F.Paste")
			(net "M_L_CPU1_SA_CS_N<1>")
		)
		(pad "AV12" smd circle
			(at -24.29002 -6.839966 180)
			(size 0.450088 0.450088)
			(layers "F.Cu" "F.Mask" "F.Paste")
			(net "PVDDCR_SOC_P1")
		)
		(pad "AV13" smd circle
			(at -23.349966 -6.839966 180)
			(size 0.450088 0.450088)
			(layers "F.Cu" "F.Mask" "F.Paste")
			(net "Net_2048")
		)
		(pad "AV14" smd circle
			(at -22.409912 -6.839966 180)
			(size 0.450088 0.450088)
			(layers "F.Cu" "F.Mask" "F.Paste")
			(net "M_H_CPU1_SA_CS_N<1>")
		)
		(pad "AV15" smd circle
			(at -21.470112 -6.839966 180)
			(size 0.450088 0.450088)
			(layers "F.Cu" "F.Mask" "F.Paste")
			(net "GND")
		)
		(pad "AV16" smd circle
			(at -20.530058 -6.839966 180)
			(size 0.450088 0.450088)
			(layers "F.Cu" "F.Mask" "F.Paste")
			(net "Net_2064")
		)
		(pad "AV17" smd circle
			(at -19.590004 -6.839966 180)
			(size 0.450088 0.450088)
			(layers "F.Cu" "F.Mask" "F.Paste")
			(net "GND")
		)
		(pad "AV18" smd circle
			(at -18.64995 -6.839966 180)
			(size 0.450088 0.450088)
			(layers "F.Cu" "F.Mask" "F.Paste")
			(net "M_J_CPU1_SA_CS_N<1>")
		)
		(pad "AV19" smd circle
			(at -17.709896 -6.839966 180)
			(size 0.450088 0.450088)
			(layers "F.Cu" "F.Mask" "F.Paste")
			(net "PVDDCR_SOC_P1")
		)
		(pad "AV20" smd circle
			(at -16.770096 -6.839966 180)
			(size 0.450088 0.450088)
			(layers "F.Cu" "F.Mask" "F.Paste")
			(net "Net_2056")
		)
		(pad "AV21" smd circle
			(at -15.830042 -6.839966 180)
			(size 0.450088 0.450088)
			(layers "F.Cu" "F.Mask" "F.Paste")
			(net "M_I_CPU1_SA_CS_N<1>")
		)
		(pad "AV22" smd circle
			(at -14.889988 -6.839966 180)
			(size 0.450088 0.450088)
			(layers "F.Cu" "F.Mask" "F.Paste")
			(net "PVDDCR_SOC_P1")
		)
		(pad "AV23" smd circle
			(at -13.949934 -6.839966 180)
			(size 0.450088 0.450088)
			(layers "F.Cu" "F.Mask" "F.Paste")
			(net "GND")
		)
		(pad "AV24" smd circle
			(at -13.00988 -6.839966 180)
			(size 0.450088 0.450088)
			(layers "F.Cu" "F.Mask" "F.Paste")
			(net "PVDDCR_SOC_P1")
		)
		(pad "AV25" smd circle
			(at -12.07008 -6.839966 180)
			(size 0.450088 0.450088)
			(layers "F.Cu" "F.Mask" "F.Paste")
			(net "GND")
		)
		(pad "AV26" smd circle
			(at -11.130026 -6.839966 180)
			(size 0.450088 0.450088)
			(layers "F.Cu" "F.Mask" "F.Paste")
			(net "PVDDCR_SOC_P1")
		)
		(pad "AV27" smd circle
			(at -10.189972 -6.839966 180)
			(size 0.450088 0.450088)
			(layers "F.Cu" "F.Mask" "F.Paste")
			(net "GND")
		)
		(pad "AV28" smd circle
			(at -9.249918 -6.839966 180)
			(size 0.450088 0.450088)
			(layers "F.Cu" "F.Mask" "F.Paste")
			(net "PVDDCR_SOC_P1")
		)
		(pad "AV29" smd circle
			(at -8.310118 -6.839966 180)
			(size 0.450088 0.450088)
			(layers "F.Cu" "F.Mask" "F.Paste")
			(net "GND")
		)
		(pad "AV30" smd circle
			(at -7.370064 -6.839966 180)
			(size 0.450088 0.450088)
			(layers "F.Cu" "F.Mask" "F.Paste")
			(net "PVDDCR_SOC_P1")
		)
		(pad "AV31" smd circle
			(at -6.43001 -6.839966 180)
			(size 0.450088 0.450088)
			(layers "F.Cu" "F.Mask" "F.Paste")
			(net "GND")
		)
		(pad "AV32" smd circle
			(at -5.489956 -6.839966 180)
			(size 0.450088 0.450088)
			(layers "F.Cu" "F.Mask" "F.Paste")
			(net "PVDDCR_SOC_P1")
		)
		(pad "AV33" smd circle
			(at -4.549902 -6.839966 180)
			(size 0.450088 0.450088)
			(layers "F.Cu" "F.Mask" "F.Paste")
			(net "GND")
		)
		(pad "AV34" smd circle
			(at -3.610102 -6.839966 180)
			(size 0.450088 0.450088)
			(layers "F.Cu" "F.Mask" "F.Paste")
			(net "PVDDCR_SOC_P1")
		)
		(pad "AV35" smd circle
			(at -2.670048 -6.839966 180)
			(size 0.450088 0.450088)
			(layers "F.Cu" "F.Mask" "F.Paste")
			(net "GND")
		)
		(pad "AV36" smd circle
			(at -1.729994 -6.839966 180)
			(size 0.450088 0.450088)
			(layers "F.Cu" "F.Mask" "F.Paste")
			(net "PVDDCR_SOC_P1")
		)
		(pad "AV37" smd circle
			(at -0.78994 -6.839966 180)
			(size 0.450088 0.450088)
			(layers "F.Cu" "F.Mask" "F.Paste")
			(net "GND")
		)
		(pad "AV39" smd circle
			(at 1.089914 -6.839966 180)
			(size 0.450088 0.450088)
			(layers "F.Cu" "F.Mask" "F.Paste")
			(net "PVDDCR_SOC_P1")
		)
		(pad "AV40" smd circle
			(at 2.029968 -6.839966 180)
			(size 0.450088 0.450088)
			(layers "F.Cu" "F.Mask" "F.Paste")
			(net "GND")
		)
		(pad "AV41" smd circle
			(at 2.970022 -6.839966 180)
			(size 0.450088 0.450088)
			(layers "F.Cu" "F.Mask" "F.Paste")
			(net "PVDDCR_SOC_P1")
		)
		(pad "AV42" smd circle
			(at 3.910076 -6.839966 180)
			(size 0.450088 0.450088)
			(layers "F.Cu" "F.Mask" "F.Paste")
			(net "GND")
		)
		(pad "AV43" smd circle
			(at 4.849876 -6.839966 180)
			(size 0.450088 0.450088)
			(layers "F.Cu" "F.Mask" "F.Paste")
			(net "PVDDCR_SOC_P1")
		)
		(pad "AV44" smd circle
			(at 5.78993 -6.839966 180)
			(size 0.450088 0.450088)
			(layers "F.Cu" "F.Mask" "F.Paste")
			(net "GND")
		)
		(pad "AV45" smd circle
			(at 6.729984 -6.839966 180)
			(size 0.450088 0.450088)
			(layers "F.Cu" "F.Mask" "F.Paste")
			(net "PVDDCR_SOC_P1")
		)
		(pad "AV46" smd circle
			(at 7.670038 -6.839966 180)
			(size 0.450088 0.450088)
			(layers "F.Cu" "F.Mask" "F.Paste")
			(net "GND")
		)
		(pad "AV47" smd circle
			(at 8.610092 -6.839966 180)
			(size 0.450088 0.450088)
			(layers "F.Cu" "F.Mask" "F.Paste")
			(net "PVDDCR_SOC_P1")
		)
		(pad "AV48" smd circle
			(at 9.549892 -6.839966 180)
			(size 0.450088 0.450088)
			(layers "F.Cu" "F.Mask" "F.Paste")
			(net "GND")
		)
		(pad "AV49" smd circle
			(at 10.489946 -6.839966 180)
			(size 0.450088 0.450088)
			(layers "F.Cu" "F.Mask" "F.Paste")
			(net "PVDD18_S5_P1")
		)
		(pad "AV50" smd circle
			(at 11.43 -6.839966 180)
			(size 0.450088 0.450088)
			(layers "F.Cu" "F.Mask" "F.Paste")
			(net "GND")
		)
		(pad "AV51" smd circle
			(at 12.370054 -6.839966 180)
			(size 0.450088 0.450088)
			(layers "F.Cu" "F.Mask" "F.Paste")
			(net "PVDD18_S5_P1")
		)
		(pad "AV52" smd circle
			(at 13.310108 -6.839966 180)
			(size 0.450088 0.450088)
			(layers "F.Cu" "F.Mask" "F.Paste")
			(net "GND")
		)
		(pad "AV53" smd circle
			(at 14.249908 -6.839966 180)
			(size 0.450088 0.450088)
			(layers "F.Cu" "F.Mask" "F.Paste")
			(net "PVDD18_S5_P1")
		)
		(pad "AV54" smd circle
			(at 15.189962 -6.839966 180)
			(size 0.450088 0.450088)
			(layers "F.Cu" "F.Mask" "F.Paste")
			(net "GND")
		)
		(pad "AV55" smd circle
			(at 16.130016 -6.839966 180)
			(size 0.450088 0.450088)
			(layers "F.Cu" "F.Mask" "F.Paste")
			(net "Net_2009")
		)
		(pad "AV56" smd circle
			(at 17.07007 -6.839966 180)
			(size 0.450088 0.450088)
			(layers "F.Cu" "F.Mask" "F.Paste")
			(net "M_C_CPU1_SA_CS_N<0>")
		)
		(pad "AV57" smd circle
			(at 18.010124 -6.839966 180)
			(size 0.450088 0.450088)
			(layers "F.Cu" "F.Mask" "F.Paste")
			(net "PVDDIO_P1")
		)
		(pad "AV58" smd circle
			(at 18.949924 -6.839966 180)
			(size 0.450088 0.450088)
			(layers "F.Cu" "F.Mask" "F.Paste")
			(net "Net_2017")
		)
		(pad "AV59" smd circle
			(at 19.889978 -6.839966 180)
			(size 0.450088 0.450088)
			(layers "F.Cu" "F.Mask" "F.Paste")
			(net "GND")
		)
		(pad "AV60" smd circle
			(at 20.830032 -6.839966 180)
			(size 0.450088 0.450088)
			(layers "F.Cu" "F.Mask" "F.Paste")
			(net "M_D_CPU1_SA_CS_N<0>")
		)
		(pad "AV61" smd circle
			(at 21.770086 -6.839966 180)
			(size 0.450088 0.450088)
			(layers "F.Cu" "F.Mask" "F.Paste")
			(net "GND")
		)
		(pad "AV62" smd circle
			(at 22.709886 -6.839966 180)
			(size 0.450088 0.450088)
			(layers "F.Cu" "F.Mask" "F.Paste")
			(net "Net_2001")
		)
		(pad "AV63" smd circle
			(at 23.64994 -6.839966 180)
			(size 0.450088 0.450088)
			(layers "F.Cu" "F.Mask" "F.Paste")
			(net "M_B_CPU1_SA_CS_N<0>")
		)
		(pad "AV64" smd circle
			(at 24.589994 -6.839966 180)
			(size 0.450088 0.450088)
			(layers "F.Cu" "F.Mask" "F.Paste")
			(net "PVDDIO_P1")
		)
		(pad "AV65" smd circle
			(at 25.530048 -6.839966 180)
			(size 0.450088 0.450088)
			(layers "F.Cu" "F.Mask" "F.Paste")
			(net "Net_2033")
		)
		(pad "AV66" smd circle
			(at 26.470102 -6.839966 180)
			(size 0.450088 0.450088)
			(layers "F.Cu" "F.Mask" "F.Paste")
			(net "GND")
		)
		(pad "AV67" smd circle
			(at 27.409902 -6.839966 180)
			(size 0.450088 0.450088)
			(layers "F.Cu" "F.Mask" "F.Paste")
			(net "M_F_CPU1_SA_CS_N<0>")
		)
		(pad "AV68" smd circle
			(at 28.349956 -6.839966 180)
			(size 0.450088 0.450088)
			(layers "F.Cu" "F.Mask" "F.Paste")
			(net "GND")
		)
		(pad "AV69" smd circle
			(at 29.29001 -6.839966 180)
			(size 0.450088 0.450088)
			(layers "F.Cu" "F.Mask" "F.Paste")
			(net "Net_2025")
		)
		(pad "AV70" smd circle
			(at 30.230064 -6.839966 180)
			(size 0.450088 0.450088)
			(layers "F.Cu" "F.Mask" "F.Paste")
			(net "M_E_CPU1_SA_CS_N<0>")
		)
		(pad "AV71" smd circle
			(at 31.170118 -6.839966 180)
			(size 0.450088 0.450088)
			(layers "F.Cu" "F.Mask" "F.Paste")
			(net "PVDDIO_P1")
		)
		(pad "AV72" smd circle
			(at 32.109918 -6.839966 180)
			(size 0.450088 0.450088)
			(layers "F.Cu" "F.Mask" "F.Paste")
			(net "Net_1993")
		)
		(pad "AV73" smd circle
			(at 33.049972 -6.839966 180)
			(size 0.450088 0.450088)
			(layers "F.Cu" "F.Mask" "F.Paste")
			(net "GND")
		)
		(pad "AV74" smd circle
			(at 33.990026 -6.839966 180)
			(size 0.450088 0.450088)
			(layers "F.Cu" "F.Mask" "F.Paste")
			(net "M_A_CPU1_SA_CS_N<0>")
		)
		(pad "AW1" smd circle
			(at -34.159952 -6.02996 180)
			(size 0.450088 0.450088)
			(layers "F.Cu" "F.Mask" "F.Paste")
			(net "GND")
		)
		(pad "AW2" smd circle
			(at -33.219898 -6.02996 180)
			(size 0.450088 0.450088)
			(layers "F.Cu" "F.Mask" "F.Paste")
			(net "M_G_CPU1_SA_CA<0>")
		)
		(pad "AW3" smd circle
			(at -32.280098 -6.02996 180)
			(size 0.450088 0.450088)
			(layers "F.Cu" "F.Mask" "F.Paste")
			(net "Net_2041")
		)
		(pad "AW4" smd circle
			(at -31.340044 -6.02996 180)
			(size 0.450088 0.450088)
			(layers "F.Cu" "F.Mask" "F.Paste")
			(net "GND")
		)
		(pad "AW5" smd circle
			(at -30.39999 -6.02996 180)
			(size 0.450088 0.450088)
			(layers "F.Cu" "F.Mask" "F.Paste")
			(net "M_K_CPU1_SA_CA<0>")
		)
		(pad "AW6" smd circle
			(at -29.459936 -6.02996 180)
			(size 0.450088 0.450088)
			(layers "F.Cu" "F.Mask" "F.Paste")
			(net "GND")
		)
		(pad "AW7" smd circle
			(at -28.519882 -6.02996 180)
			(size 0.450088 0.450088)
			(layers "F.Cu" "F.Mask" "F.Paste")
			(net "Net_2190")
		)
		(pad "AW8" smd circle
			(at -27.580082 -6.02996 180)
			(size 0.450088 0.450088)
			(layers "F.Cu" "F.Mask" "F.Paste")
			(net "GND")
		)
		(pad "AW9" smd circle
			(at -26.640028 -6.02996 180)
			(size 0.450088 0.450088)
			(layers "F.Cu" "F.Mask" "F.Paste")
			(net "M_L_CPU1_SA_CA<0>")
		)
		(pad "AW10" smd circle
			(at -25.699974 -6.02996 180)
			(size 0.450088 0.450088)
			(layers "F.Cu" "F.Mask" "F.Paste")
			(net "Net_2182")
		)
		(pad "AW11" smd circle
			(at -24.75992 -6.02996 180)
			(size 0.450088 0.450088)
			(layers "F.Cu" "F.Mask" "F.Paste")
			(net "GND")
		)
		(pad "AW12" smd circle
			(at -23.82012 -6.02996 180)
			(size 0.450088 0.450088)
			(layers "F.Cu" "F.Mask" "F.Paste")
			(net "M_H_CPU1_SA_CA<0>")
		)
		(pad "AW13" smd circle
			(at -22.880066 -6.02996 180)
			(size 0.450088 0.450088)
			(layers "F.Cu" "F.Mask" "F.Paste")
			(net "GND")
		)
		(pad "AW14" smd circle
			(at -21.940012 -6.02996 180)
			(size 0.450088 0.450088)
			(layers "F.Cu" "F.Mask" "F.Paste")
			(net "Net_2049")
		)
		(pad "AW15" smd circle
			(at -20.999958 -6.02996 180)
			(size 0.450088 0.450088)
			(layers "F.Cu" "F.Mask" "F.Paste")
			(net "GND")
		)
		(pad "AW16" smd circle
			(at -20.059904 -6.02996 180)
			(size 0.450088 0.450088)
			(layers "F.Cu" "F.Mask" "F.Paste")
			(net "M_J_CPU1_SA_CA<0>")
		)
		(pad "AW17" smd circle
			(at -19.120104 -6.02996 180)
			(size 0.450088 0.450088)
			(layers "F.Cu" "F.Mask" "F.Paste")
			(net "Net_2065")
		)
		(pad "AW18" smd circle
			(at -18.18005 -6.02996 180)
			(size 0.450088 0.450088)
			(layers "F.Cu" "F.Mask" "F.Paste")
			(net "GND")
		)
		(pad "AW19" smd circle
			(at -17.239996 -6.02996 180)
			(size 0.450088 0.450088)
			(layers "F.Cu" "F.Mask" "F.Paste")
			(net "M_I_CPU1_SA_CA<0>")
		)
		(pad "AW20" smd circle
			(at -16.299942 -6.02996 180)
			(size 0.450088 0.450088)
			(layers "F.Cu" "F.Mask" "F.Paste")
			(net "GND")
		)
		(pad "AW21" smd circle
			(at -15.359888 -6.02996 180)
			(size 0.450088 0.450088)
			(layers "F.Cu" "F.Mask" "F.Paste")
			(net "Net_2057")
		)
		(pad "AW22" smd circle
			(at -14.420088 -6.02996 180)
			(size 0.450088 0.450088)
			(layers "F.Cu" "F.Mask" "F.Paste")
			(net "GND")
		)
		(pad "AW23" smd circle
			(at -13.480034 -6.02996 180)
			(size 0.450088 0.450088)
			(layers "F.Cu" "F.Mask" "F.Paste")
			(net "PVDDCR_SOC_P1")
		)
		(pad "AW24" smd circle
			(at -12.53998 -6.02996 180)
			(size 0.450088 0.450088)
			(layers "F.Cu" "F.Mask" "F.Paste")
			(net "GND")
		)
		(pad "AW25" smd circle
			(at -11.599926 -6.02996 180)
			(size 0.450088 0.450088)
			(layers "F.Cu" "F.Mask" "F.Paste")
			(net "PVDDCR_SOC_P1")
		)
		(pad "AW26" smd circle
			(at -10.659872 -6.02996 180)
			(size 0.450088 0.450088)
			(layers "F.Cu" "F.Mask" "F.Paste")
			(net "GND")
		)
		(pad "AW27" smd circle
			(at -9.720072 -6.02996 180)
			(size 0.450088 0.450088)
			(layers "F.Cu" "F.Mask" "F.Paste")
			(net "PVDDCR_SOC_P1")
		)
		(pad "AW28" smd circle
			(at -8.780018 -6.02996 180)
			(size 0.450088 0.450088)
			(layers "F.Cu" "F.Mask" "F.Paste")
			(net "GND")
		)
		(pad "AW48" smd circle
			(at 9.079992 -6.02996 180)
			(size 0.450088 0.450088)
			(layers "F.Cu" "F.Mask" "F.Paste")
			(net "PVDDCR_SOC_P1")
		)
		(pad "AW49" smd circle
			(at 10.020046 -6.02996 180)
			(size 0.450088 0.450088)
			(layers "F.Cu" "F.Mask" "F.Paste")
			(net "GND")
		)
		(pad "AW50" smd circle
			(at 10.9601 -6.02996 180)
			(size 0.450088 0.450088)
			(layers "F.Cu" "F.Mask" "F.Paste")
			(net "PVDD18_S5_P1")
		)
		(pad "AW51" smd circle
			(at 11.8999 -6.02996 180)
			(size 0.450088 0.450088)
			(layers "F.Cu" "F.Mask" "F.Paste")
			(net "GND")
		)
		(pad "AW52" smd circle
			(at 12.839954 -6.02996 180)
			(size 0.450088 0.450088)
			(layers "F.Cu" "F.Mask" "F.Paste")
			(net "PVDD18_S5_P1")
		)
		(pad "AW53" smd circle
			(at 13.780008 -6.02996 180)
			(size 0.450088 0.450088)
			(layers "F.Cu" "F.Mask" "F.Paste")
			(net "GND")
		)
		(pad "AW54" smd circle
			(at 14.720062 -6.02996 180)
			(size 0.450088 0.450088)
			(layers "F.Cu" "F.Mask" "F.Paste")
			(net "PVDD18_S5_P1")
		)
		(pad "AW55" smd circle
			(at 15.660116 -6.02996 180)
			(size 0.450088 0.450088)
			(layers "F.Cu" "F.Mask" "F.Paste")
			(net "M_C_CPU1_SA_CS_N<1>")
		)
		(pad "AW56" smd circle
			(at 16.599916 -6.02996 180)
			(size 0.450088 0.450088)
			(layers "F.Cu" "F.Mask" "F.Paste")
			(net "GND")
		)
		(pad "AW57" smd circle
			(at 17.53997 -6.02996 180)
			(size 0.450088 0.450088)
			(layers "F.Cu" "F.Mask" "F.Paste")
			(net "M_C_CPU1_SA_CA<0>")
		)
		(pad "AW58" smd circle
			(at 18.480024 -6.02996 180)
			(size 0.450088 0.450088)
			(layers "F.Cu" "F.Mask" "F.Paste")
			(net "GND")
		)
		(pad "AW59" smd circle
			(at 19.420078 -6.02996 180)
			(size 0.450088 0.450088)
			(layers "F.Cu" "F.Mask" "F.Paste")
			(net "M_D_CPU1_SA_CS_N<1>")
		)
		(pad "AW60" smd circle
			(at 20.359878 -6.02996 180)
			(size 0.450088 0.450088)
			(layers "F.Cu" "F.Mask" "F.Paste")
			(net "M_D_CPU1_SA_CA<0>")
		)
		(pad "AW61" smd circle
			(at 21.299932 -6.02996 180)
			(size 0.450088 0.450088)
			(layers "F.Cu" "F.Mask" "F.Paste")
			(net "GND")
		)
		(pad "AW62" smd circle
			(at 22.239986 -6.02996 180)
			(size 0.450088 0.450088)
			(layers "F.Cu" "F.Mask" "F.Paste")
			(net "M_B_CPU1_SA_CS_N<1>")
		)
		(pad "AW63" smd circle
			(at 23.18004 -6.02996 180)
			(size 0.450088 0.450088)
			(layers "F.Cu" "F.Mask" "F.Paste")
			(net "GND")
		)
		(pad "AW64" smd circle
			(at 24.120094 -6.02996 180)
			(size 0.450088 0.450088)
			(layers "F.Cu" "F.Mask" "F.Paste")
			(net "M_B_CPU1_SA_CA<0>")
		)
		(pad "AW65" smd circle
			(at 25.059894 -6.02996 180)
			(size 0.450088 0.450088)
			(layers "F.Cu" "F.Mask" "F.Paste")
			(net "GND")
		)
		(pad "AW66" smd circle
			(at 25.999948 -6.02996 180)
			(size 0.450088 0.450088)
			(layers "F.Cu" "F.Mask" "F.Paste")
			(net "M_F_CPU1_SA_CS_N<1>")
		)
		(pad "AW67" smd circle
			(at 26.940002 -6.02996 180)
			(size 0.450088 0.450088)
			(layers "F.Cu" "F.Mask" "F.Paste")
			(net "M_F_CPU1_SA_CA<0>")
		)
		(pad "AW68" smd circle
			(at 27.880056 -6.02996 180)
			(size 0.450088 0.450088)
			(layers "F.Cu" "F.Mask" "F.Paste")
			(net "GND")
		)
		(pad "AW69" smd circle
			(at 28.82011 -6.02996 180)
			(size 0.450088 0.450088)
			(layers "F.Cu" "F.Mask" "F.Paste")
			(net "M_E_CPU1_SA_CS_N<1>")
		)
		(pad "AW70" smd circle
			(at 29.75991 -6.02996 180)
			(size 0.450088 0.450088)
			(layers "F.Cu" "F.Mask" "F.Paste")
			(net "GND")
		)
		(pad "AW71" smd circle
			(at 30.699964 -6.02996 180)
			(size 0.450088 0.450088)
			(layers "F.Cu" "F.Mask" "F.Paste")
			(net "M_E_CPU1_SA_CA<0>")
		)
		(pad "AW72" smd circle
			(at 31.640018 -6.02996 180)
			(size 0.450088 0.450088)
			(layers "F.Cu" "F.Mask" "F.Paste")
			(net "GND")
		)
		(pad "AW73" smd circle
			(at 32.580072 -6.02996 180)
			(size 0.450088 0.450088)
			(layers "F.Cu" "F.Mask" "F.Paste")
			(net "M_A_CPU1_SA_CS_N<1>")
		)
		(pad "AW74" smd circle
			(at 33.519872 -6.02996 180)
			(size 0.450088 0.450088)
			(layers "F.Cu" "F.Mask" "F.Paste")
			(net "M_A_CPU1_SA_CA<0>")
		)
		(pad "AW75" smd circle
			(at 34.459926 -6.02996 180)
			(size 0.450088 0.450088)
			(layers "F.Cu" "F.Mask" "F.Paste")
			(net "GND")
		)
		(pad "AY2" smd circle
			(at -33.690052 -5.219954 180)
			(size 0.450088 0.450088)
			(layers "F.Cu" "F.Mask" "F.Paste")
			(net "M_G_CPU1_SA_CA<1>")
		)
		(pad "AY3" smd circle
			(at -32.749998 -5.219954 180)
			(size 0.450088 0.450088)
			(layers "F.Cu" "F.Mask" "F.Paste")
			(net "GND")
		)
		(pad "AY4" smd circle
			(at -31.809944 -5.219954 180)
			(size 0.450088 0.450088)
			(layers "F.Cu" "F.Mask" "F.Paste")
			(net "M_G_CPU1_SA_CA<2>")
		)
		(pad "AY5" smd circle
			(at -30.86989 -5.219954 180)
			(size 0.450088 0.450088)
			(layers "F.Cu" "F.Mask" "F.Paste")
			(net "GND")
		)
		(pad "AY6" smd circle
			(at -29.93009 -5.219954 180)
			(size 0.450088 0.450088)
			(layers "F.Cu" "F.Mask" "F.Paste")
			(net "M_K_CPU1_SA_CA<1>")
		)
		(pad "AY7" smd circle
			(at -28.990036 -5.219954 180)
			(size 0.450088 0.450088)
			(layers "F.Cu" "F.Mask" "F.Paste")
			(net "M_K_CPU1_SA_CA<2>")
		)
		(pad "AY8" smd circle
			(at -28.049982 -5.219954 180)
			(size 0.450088 0.450088)
			(layers "F.Cu" "F.Mask" "F.Paste")
			(net "GND")
		)
		(pad "AY9" smd circle
			(at -27.109928 -5.219954 180)
			(size 0.450088 0.450088)
			(layers "F.Cu" "F.Mask" "F.Paste")
			(net "M_L_CPU1_SA_CA<1>")
		)
		(pad "AY10" smd circle
			(at -26.170128 -5.219954 180)
			(size 0.450088 0.450088)
			(layers "F.Cu" "F.Mask" "F.Paste")
			(net "GND")
		)
		(pad "AY11" smd circle
			(at -25.230074 -5.219954 180)
			(size 0.450088 0.450088)
			(layers "F.Cu" "F.Mask" "F.Paste")
			(net "M_L_CPU1_SA_CA<2>")
		)
		(pad "AY12" smd circle
			(at -24.29002 -5.219954 180)
			(size 0.450088 0.450088)
			(layers "F.Cu" "F.Mask" "F.Paste")
			(net "GND")
		)
		(pad "AY13" smd circle
			(at -23.349966 -5.219954 180)
			(size 0.450088 0.450088)
			(layers "F.Cu" "F.Mask" "F.Paste")
			(net "M_H_CPU1_SA_CA<1>")
		)
		(pad "AY14" smd circle
			(at -22.409912 -5.219954 180)
			(size 0.450088 0.450088)
			(layers "F.Cu" "F.Mask" "F.Paste")
			(net "M_H_CPU1_SA_CA<2>")
		)
		(pad "AY15" smd circle
			(at -21.470112 -5.219954 180)
			(size 0.450088 0.450088)
			(layers "F.Cu" "F.Mask" "F.Paste")
			(net "GND")
		)
		(pad "AY16" smd circle
			(at -20.530058 -5.219954 180)
			(size 0.450088 0.450088)
			(layers "F.Cu" "F.Mask" "F.Paste")
			(net "M_J_CPU1_SA_CA<1>")
		)
		(pad "AY17" smd circle
			(at -19.590004 -5.219954 180)
			(size 0.450088 0.450088)
			(layers "F.Cu" "F.Mask" "F.Paste")
			(net "GND")
		)
		(pad "AY18" smd circle
			(at -18.64995 -5.219954 180)
			(size 0.450088 0.450088)
			(layers "F.Cu" "F.Mask" "F.Paste")
			(net "M_J_CPU1_SA_CA<2>")
		)
		(pad "AY19" smd circle
			(at -17.709896 -5.219954 180)
			(size 0.450088 0.450088)
			(layers "F.Cu" "F.Mask" "F.Paste")
			(net "GND")
		)
		(pad "AY20" smd circle
			(at -16.770096 -5.219954 180)
			(size 0.450088 0.450088)
			(layers "F.Cu" "F.Mask" "F.Paste")
			(net "M_I_CPU1_SA_CA<1>")
		)
		(pad "AY21" smd circle
			(at -15.830042 -5.219954 180)
			(size 0.450088 0.450088)
			(layers "F.Cu" "F.Mask" "F.Paste")
			(net "M_I_CPU1_SA_CA<2>")
		)
		(pad "AY22" smd circle
			(at -14.889988 -5.219954 180)
			(size 0.450088 0.450088)
			(layers "F.Cu" "F.Mask" "F.Paste")
			(net "PVDDCR_SOC_P1")
		)
		(pad "AY23" smd circle
			(at -13.949934 -5.219954 180)
			(size 0.450088 0.450088)
			(layers "F.Cu" "F.Mask" "F.Paste")
			(net "GND")
		)
		(pad "AY24" smd circle
			(at -13.00988 -5.219954 180)
			(size 0.450088 0.450088)
			(layers "F.Cu" "F.Mask" "F.Paste")
			(net "PVDDCR_SOC_P1")
		)
		(pad "AY25" smd circle
			(at -12.07008 -5.219954 180)
			(size 0.450088 0.450088)
			(layers "F.Cu" "F.Mask" "F.Paste")
			(net "GND")
		)
		(pad "AY26" smd circle
			(at -11.130026 -5.219954 180)
			(size 0.450088 0.450088)
			(layers "F.Cu" "F.Mask" "F.Paste")
			(net "PVDDCR_SOC_P1")
		)
		(pad "AY27" smd circle
			(at -10.189972 -5.219954 180)
			(size 0.450088 0.450088)
			(layers "F.Cu" "F.Mask" "F.Paste")
			(net "GND")
		)
		(pad "AY28" smd circle
			(at -9.249918 -5.219954 180)
			(size 0.450088 0.450088)
			(layers "F.Cu" "F.Mask" "F.Paste")
			(net "PVDDCR_SOC_P1")
		)
		(pad "AY48" smd circle
			(at 9.549892 -5.219954 180)
			(size 0.450088 0.450088)
			(layers "F.Cu" "F.Mask" "F.Paste")
			(net "GND")
		)
		(pad "AY49" smd circle
			(at 10.489946 -5.219954 180)
			(size 0.450088 0.450088)
			(layers "F.Cu" "F.Mask" "F.Paste")
			(net "PVDDCR_SOC_P1")
		)
		(pad "AY50" smd circle
			(at 11.43 -5.219954 180)
			(size 0.450088 0.450088)
			(layers "F.Cu" "F.Mask" "F.Paste")
			(net "GND")
		)
		(pad "AY51" smd circle
			(at 12.370054 -5.219954 180)
			(size 0.450088 0.450088)
			(layers "F.Cu" "F.Mask" "F.Paste")
			(net "PVDD18_S5_P1")
		)
		(pad "AY52" smd circle
			(at 13.310108 -5.219954 180)
			(size 0.450088 0.450088)
			(layers "F.Cu" "F.Mask" "F.Paste")
			(net "GND")
		)
		(pad "AY53" smd circle
			(at 14.249908 -5.219954 180)
			(size 0.450088 0.450088)
			(layers "F.Cu" "F.Mask" "F.Paste")
			(net "PVDD18_S5_P1")
		)
		(pad "AY54" smd circle
			(at 15.189962 -5.219954 180)
			(size 0.450088 0.450088)
			(layers "F.Cu" "F.Mask" "F.Paste")
			(net "GND")
		)
		(pad "AY55" smd circle
			(at 16.130016 -5.219954 180)
			(size 0.450088 0.450088)
			(layers "F.Cu" "F.Mask" "F.Paste")
			(net "M_C_CPU1_SA_CA<2>")
		)
		(pad "AY56" smd circle
			(at 17.07007 -5.219954 180)
			(size 0.450088 0.450088)
			(layers "F.Cu" "F.Mask" "F.Paste")
			(net "M_C_CPU1_SA_CA<1>")
		)
		(pad "AY57" smd circle
			(at 18.010124 -5.219954 180)
			(size 0.450088 0.450088)
			(layers "F.Cu" "F.Mask" "F.Paste")
			(net "GND")
		)
		(pad "AY58" smd circle
			(at 18.949924 -5.219954 180)
			(size 0.450088 0.450088)
			(layers "F.Cu" "F.Mask" "F.Paste")
			(net "M_D_CPU1_SA_CA<2>")
		)
		(pad "AY59" smd circle
			(at 19.889978 -5.219954 180)
			(size 0.450088 0.450088)
			(layers "F.Cu" "F.Mask" "F.Paste")
			(net "GND")
		)
		(pad "AY60" smd circle
			(at 20.830032 -5.219954 180)
			(size 0.450088 0.450088)
			(layers "F.Cu" "F.Mask" "F.Paste")
			(net "M_D_CPU1_SA_CA<1>")
		)
		(pad "AY61" smd circle
			(at 21.770086 -5.219954 180)
			(size 0.450088 0.450088)
			(layers "F.Cu" "F.Mask" "F.Paste")
			(net "GND")
		)
		(pad "AY62" smd circle
			(at 22.709886 -5.219954 180)
			(size 0.450088 0.450088)
			(layers "F.Cu" "F.Mask" "F.Paste")
			(net "M_B_CPU1_SA_CA<2>")
		)
		(pad "AY63" smd circle
			(at 23.64994 -5.219954 180)
			(size 0.450088 0.450088)
			(layers "F.Cu" "F.Mask" "F.Paste")
			(net "M_B_CPU1_SA_CA<1>")
		)
		(pad "AY64" smd circle
			(at 24.589994 -5.219954 180)
			(size 0.450088 0.450088)
			(layers "F.Cu" "F.Mask" "F.Paste")
			(net "GND")
		)
		(pad "AY65" smd circle
			(at 25.530048 -5.219954 180)
			(size 0.450088 0.450088)
			(layers "F.Cu" "F.Mask" "F.Paste")
			(net "M_F_CPU1_SA_CA<2>")
		)
		(pad "AY66" smd circle
			(at 26.470102 -5.219954 180)
			(size 0.450088 0.450088)
			(layers "F.Cu" "F.Mask" "F.Paste")
			(net "GND")
		)
		(pad "AY67" smd circle
			(at 27.409902 -5.219954 180)
			(size 0.450088 0.450088)
			(layers "F.Cu" "F.Mask" "F.Paste")
			(net "M_F_CPU1_SA_CA<1>")
		)
		(pad "AY68" smd circle
			(at 28.349956 -5.219954 180)
			(size 0.450088 0.450088)
			(layers "F.Cu" "F.Mask" "F.Paste")
			(net "GND")
		)
		(pad "AY69" smd circle
			(at 29.29001 -5.219954 180)
			(size 0.450088 0.450088)
			(layers "F.Cu" "F.Mask" "F.Paste")
			(net "M_E_CPU1_SA_CA<2>")
		)
		(pad "AY70" smd circle
			(at 30.230064 -5.219954 180)
			(size 0.450088 0.450088)
			(layers "F.Cu" "F.Mask" "F.Paste")
			(net "M_E_CPU1_SA_CA<1>")
		)
		(pad "AY71" smd circle
			(at 31.170118 -5.219954 180)
			(size 0.450088 0.450088)
			(layers "F.Cu" "F.Mask" "F.Paste")
			(net "GND")
		)
		(pad "AY72" smd circle
			(at 32.109918 -5.219954 180)
			(size 0.450088 0.450088)
			(layers "F.Cu" "F.Mask" "F.Paste")
			(net "M_A_CPU1_SA_CA<2>")
		)
		(pad "AY73" smd circle
			(at 33.049972 -5.219954 180)
			(size 0.450088 0.450088)
			(layers "F.Cu" "F.Mask" "F.Paste")
			(net "GND")
		)
		(pad "AY74" smd circle
			(at 33.990026 -5.219954 180)
			(size 0.450088 0.450088)
			(layers "F.Cu" "F.Mask" "F.Paste")
			(net "M_A_CPU1_SA_CA<1>")
		)
		(pad "B3" smd circle
			(at -32.749998 -35.999928 180)
			(size 0.450088 0.450088)
			(layers "F.Cu" "F.Mask" "F.Paste")
			(net "VSENSE_PVDDCR_SOC_P1_DP")
		)
		(pad "B4" smd circle
			(at -31.809944 -35.999928 180)
			(size 0.450088 0.450088)
			(layers "F.Cu" "F.Mask" "F.Paste")
			(net "Net_2099")
		)
		(pad "B5" smd circle
			(at -30.86989 -35.999928 180)
			(size 0.450088 0.450088)
			(layers "F.Cu" "F.Mask" "F.Paste")
			(net "PVDDCR_SOC_P1")
		)
		(pad "B6" smd circle
			(at -29.93009 -35.999928 180)
			(size 0.450088 0.450088)
			(layers "F.Cu" "F.Mask" "F.Paste")
			(net "CLK_100M_CPU1_CLK02_R_DP")
		)
		(pad "B7" smd circle
			(at -28.990036 -35.999928 180)
			(size 0.450088 0.450088)
			(layers "F.Cu" "F.Mask" "F.Paste")
			(net "GND")
		)
		(pad "B8" smd circle
			(at -28.049982 -35.999928 180)
			(size 0.450088 0.450088)
			(layers "F.Cu" "F.Mask" "F.Paste")
			(net "GND")
		)
		(pad "B9" smd circle
			(at -27.109928 -35.999928 180)
			(size 0.450088 0.450088)
			(layers "F.Cu" "F.Mask" "F.Paste")
			(net "CLK_100M_CPU1_CLK05_R_DP")
		)
		(pad "B10" smd circle
			(at -26.170128 -35.999928 180)
			(size 0.450088 0.450088)
			(layers "F.Cu" "F.Mask" "F.Paste")
			(net "GND")
		)
		(pad "B11" smd circle
			(at -25.230074 -35.999928 180)
			(size 0.450088 0.450088)
			(layers "F.Cu" "F.Mask" "F.Paste")
			(net "GND")
		)
		(pad "B12" smd circle
			(at -24.29002 -35.999928 180)
			(size 0.450088 0.450088)
			(layers "F.Cu" "F.Mask" "F.Paste")
			(net "CLK_100M_CPU1_CLK04_R_DP")
		)
		(pad "B13" smd circle
			(at -23.349966 -35.999928 180)
			(size 0.450088 0.450088)
			(layers "F.Cu" "F.Mask" "F.Paste")
			(net "GND")
		)
		(pad "B14" smd circle
			(at -22.409912 -35.999928 180)
			(size 0.450088 0.450088)
			(layers "F.Cu" "F.Mask" "F.Paste")
			(net "SMB_CPU1_SEC_SCL")
		)
		(pad "B15" smd circle
			(at -21.470112 -35.999928 180)
			(size 0.450088 0.450088)
			(layers "F.Cu" "F.Mask" "F.Paste")
			(net "Net_2101")
		)
		(pad "B16" smd circle
			(at -20.530058 -35.999928 180)
			(size 0.450088 0.450088)
			(layers "F.Cu" "F.Mask" "F.Paste")
			(net "Net_2083")
		)
		(pad "B17" smd circle
			(at -19.590004 -35.999928 180)
			(size 0.450088 0.450088)
			(layers "F.Cu" "F.Mask" "F.Paste")
			(net "JTAG_CPU1_TCK")
		)
		(pad "B18" smd circle
			(at -18.64995 -35.999928 180)
			(size 0.450088 0.450088)
			(layers "F.Cu" "F.Mask" "F.Paste")
			(net "GND")
		)
		(pad "B19" smd circle
			(at -17.709896 -35.999928 180)
			(size 0.450088 0.450088)
			(layers "F.Cu" "F.Mask" "F.Paste")
			(net "PVDDCR_CPU0_P1")
		)
		(pad "B20" smd circle
			(at -16.770096 -35.999928 180)
			(size 0.450088 0.450088)
			(layers "F.Cu" "F.Mask" "F.Paste")
			(net "PVDDCR_CPU0_P1")
		)
		(pad "B21" smd circle
			(at -15.830042 -35.999928 180)
			(size 0.450088 0.450088)
			(layers "F.Cu" "F.Mask" "F.Paste")
			(net "SVID_PVDDCR_CPU0_P1_SVTO")
		)
		(pad "B22" smd circle
			(at -14.889988 -35.999928 180)
			(size 0.450088 0.450088)
			(layers "F.Cu" "F.Mask" "F.Paste")
			(net "PVDDCR_CPU0_P1")
		)
		(pad "B23" smd circle
			(at -13.949934 -35.999928 180)
			(size 0.450088 0.450088)
			(layers "F.Cu" "F.Mask" "F.Paste")
			(net "PVDDCR_CPU0_P1")
		)
		(pad "B24" smd circle
			(at -13.00988 -35.999928 180)
			(size 0.450088 0.450088)
			(layers "F.Cu" "F.Mask" "F.Paste")
			(net "GND")
		)
		(pad "B25" smd circle
			(at -12.07008 -35.999928 180)
			(size 0.450088 0.450088)
			(layers "F.Cu" "F.Mask" "F.Paste")
			(net "PVDDCR_CPU0_P1")
		)
		(pad "B26" smd circle
			(at -11.130026 -35.999928 180)
			(size 0.450088 0.450088)
			(layers "F.Cu" "F.Mask" "F.Paste")
			(net "PVDDCR_CPU0_P1")
		)
		(pad "B27" smd circle
			(at -10.189972 -35.999928 180)
			(size 0.450088 0.450088)
			(layers "F.Cu" "F.Mask" "F.Paste")
			(net "GND")
		)
		(pad "B28" smd circle
			(at -9.249918 -35.999928 180)
			(size 0.450088 0.450088)
			(layers "F.Cu" "F.Mask" "F.Paste")
			(net "PVDDCR_CPU0_P1")
		)
		(pad "B29" smd circle
			(at -8.310118 -35.999928 180)
			(size 0.450088 0.450088)
			(layers "F.Cu" "F.Mask" "F.Paste")
			(net "PVDDCR_CPU0_P1")
		)
		(pad "B30" smd circle
			(at -7.370064 -35.999928 180)
			(size 0.450088 0.450088)
			(layers "F.Cu" "F.Mask" "F.Paste")
			(net "GND")
		)
		(pad "B31" smd circle
			(at -6.43001 -35.999928 180)
			(size 0.450088 0.450088)
			(layers "F.Cu" "F.Mask" "F.Paste")
			(net "PVDDCR_CPU0_P1")
		)
		(pad "B32" smd circle
			(at -5.489956 -35.999928 180)
			(size 0.450088 0.450088)
			(layers "F.Cu" "F.Mask" "F.Paste")
			(net "PVDDCR_CPU0_P1")
		)
		(pad "B33" smd circle
			(at -4.549902 -35.999928 180)
			(size 0.450088 0.450088)
			(layers "F.Cu" "F.Mask" "F.Paste")
			(net "GND")
		)
		(pad "B34" smd circle
			(at -3.610102 -35.999928 180)
			(size 0.450088 0.450088)
			(layers "F.Cu" "F.Mask" "F.Paste")
			(net "PVDDCR_CPU0_P1")
		)
		(pad "B35" smd circle
			(at -2.670048 -35.999928 180)
			(size 0.450088 0.450088)
			(layers "F.Cu" "F.Mask" "F.Paste")
			(net "PVDDCR_CPU0_P1")
		)
		(pad "B36" smd circle
			(at -1.729994 -35.999928 180)
			(size 0.450088 0.450088)
			(layers "F.Cu" "F.Mask" "F.Paste")
			(net "Net_2177")
		)
		(pad "B37" smd circle
			(at -0.78994 -35.999928 180)
			(size 0.450088 0.450088)
			(layers "F.Cu" "F.Mask" "F.Paste")
			(net "GND")
		)
		(pad "B39" smd circle
			(at 1.089914 -35.999928 180)
			(size 0.450088 0.450088)
			(layers "F.Cu" "F.Mask" "F.Paste")
			(net "GND")
		)
		(pad "B40" smd circle
			(at 2.029968 -35.999928 180)
			(size 0.450088 0.450088)
			(layers "F.Cu" "F.Mask" "F.Paste")
			(net "Net_2135")
		)
		(pad "B41" smd circle
			(at 2.970022 -35.999928 180)
			(size 0.450088 0.450088)
			(layers "F.Cu" "F.Mask" "F.Paste")
			(net "PVDDCR_CPU0_P1")
		)
		(pad "B42" smd circle
			(at 3.910076 -35.999928 180)
			(size 0.450088 0.450088)
			(layers "F.Cu" "F.Mask" "F.Paste")
			(net "PVDDCR_CPU0_P1")
		)
		(pad "B43" smd circle
			(at 4.849876 -35.999928 180)
			(size 0.450088 0.450088)
			(layers "F.Cu" "F.Mask" "F.Paste")
			(net "GND")
		)
		(pad "B44" smd circle
			(at 5.78993 -35.999928 180)
			(size 0.450088 0.450088)
			(layers "F.Cu" "F.Mask" "F.Paste")
			(net "PVDDCR_CPU0_P1")
		)
		(pad "B45" smd circle
			(at 6.729984 -35.999928 180)
			(size 0.450088 0.450088)
			(layers "F.Cu" "F.Mask" "F.Paste")
			(net "PVDDCR_CPU0_P1")
		)
		(pad "B46" smd circle
			(at 7.670038 -35.999928 180)
			(size 0.450088 0.450088)
			(layers "F.Cu" "F.Mask" "F.Paste")
			(net "GND")
		)
		(pad "B47" smd circle
			(at 8.610092 -35.999928 180)
			(size 0.450088 0.450088)
			(layers "F.Cu" "F.Mask" "F.Paste")
			(net "PVDDCR_CPU0_P1")
		)
		(pad "B48" smd circle
			(at 9.549892 -35.999928 180)
			(size 0.450088 0.450088)
			(layers "F.Cu" "F.Mask" "F.Paste")
			(net "PVDDCR_CPU0_P1")
		)
		(pad "B49" smd circle
			(at 10.489946 -35.999928 180)
			(size 0.450088 0.450088)
			(layers "F.Cu" "F.Mask" "F.Paste")
			(net "GND")
		)
		(pad "B50" smd circle
			(at 11.43 -35.999928 180)
			(size 0.450088 0.450088)
			(layers "F.Cu" "F.Mask" "F.Paste")
			(net "PVDDCR_CPU0_P1")
		)
		(pad "B51" smd circle
			(at 12.370054 -35.999928 180)
			(size 0.450088 0.450088)
			(layers "F.Cu" "F.Mask" "F.Paste")
			(net "PVDDCR_CPU0_P1")
		)
		(pad "B52" smd circle
			(at 13.310108 -35.999928 180)
			(size 0.450088 0.450088)
			(layers "F.Cu" "F.Mask" "F.Paste")
			(net "GND")
		)
		(pad "B53" smd circle
			(at 14.249908 -35.999928 180)
			(size 0.450088 0.450088)
			(layers "F.Cu" "F.Mask" "F.Paste")
			(net "PVDDCR_CPU0_P1")
		)
		(pad "B54" smd circle
			(at 15.189962 -35.999928 180)
			(size 0.450088 0.450088)
			(layers "F.Cu" "F.Mask" "F.Paste")
			(net "PVDDCR_CPU0_P1")
		)
		(pad "B55" smd circle
			(at 16.130016 -35.999928 180)
			(size 0.450088 0.450088)
			(layers "F.Cu" "F.Mask" "F.Paste")
			(net "GND")
		)
		(pad "B56" smd circle
			(at 17.07007 -35.999928 180)
			(size 0.450088 0.450088)
			(layers "F.Cu" "F.Mask" "F.Paste")
			(net "PVDDCR_CPU0_P1")
		)
		(pad "B57" smd circle
			(at 18.010124 -35.999928 180)
			(size 0.450088 0.450088)
			(layers "F.Cu" "F.Mask" "F.Paste")
			(net "PVDDCR_CPU0_P1")
		)
		(pad "B58" smd circle
			(at 18.949924 -35.999928 180)
			(size 0.450088 0.450088)
			(layers "F.Cu" "F.Mask" "F.Paste")
			(net "TP_CPU1_TEST47_IOD0")
		)
		(pad "B59" smd circle
			(at 19.889978 -35.999928 180)
			(size 0.450088 0.450088)
			(layers "F.Cu" "F.Mask" "F.Paste")
			(net "GND")
		)
		(pad "B60" smd circle
			(at 20.830032 -35.999928 180)
			(size 0.450088 0.450088)
			(layers "F.Cu" "F.Mask" "F.Paste")
			(net "TP_CPU1_TEST47_CCD0")
		)
		(pad "B61" smd circle
			(at 21.770086 -35.999928 180)
			(size 0.450088 0.450088)
			(layers "F.Cu" "F.Mask" "F.Paste")
			(net "TP_CPU1_TEST50_IOD")
		)
		(pad "B62" smd circle
			(at 22.709886 -35.999928 180)
			(size 0.450088 0.450088)
			(layers "F.Cu" "F.Mask" "F.Paste")
			(net "GND")
		)
		(pad "B63" smd circle
			(at 23.64994 -35.999928 180)
			(size 0.450088 0.450088)
			(layers "F.Cu" "F.Mask" "F.Paste")
			(net "CPU1_FORCE_SELFREFRESH")
		)
		(pad "B64" smd circle
			(at 24.589994 -35.999928 180)
			(size 0.450088 0.450088)
			(layers "F.Cu" "F.Mask" "F.Paste")
			(net "CPU1_NV_SAVE_N")
		)
		(pad "B65" smd circle
			(at 25.530048 -35.999928 180)
			(size 0.450088 0.450088)
			(layers "F.Cu" "F.Mask" "F.Paste")
			(net "GND")
		)
		(pad "B66" smd circle
			(at 26.470102 -35.999928 180)
			(size 0.450088 0.450088)
			(layers "F.Cu" "F.Mask" "F.Paste")
			(net "PRSNT_CPU1_N")
		)
		(pad "B67" smd circle
			(at 27.409902 -35.999928 180)
			(size 0.450088 0.450088)
			(layers "F.Cu" "F.Mask" "F.Paste")
			(net "RST_CPU1_RESETL_N")
		)
		(pad "B68" smd circle
			(at 28.349956 -35.999928 180)
			(size 0.450088 0.450088)
			(layers "F.Cu" "F.Mask" "F.Paste")
			(net "GND")
		)
		(pad "B69" smd circle
			(at 29.29001 -35.999928 180)
			(size 0.450088 0.450088)
			(layers "F.Cu" "F.Mask" "F.Paste")
			(net "CPU1_CORETYPE1")
		)
		(pad "B70" smd circle
			(at 30.230064 -35.999928 180)
			(size 0.450088 0.450088)
			(layers "F.Cu" "F.Mask" "F.Paste")
			(net "GND")
		)
		(pad "B71" smd circle
			(at 31.170118 -35.999928 180)
			(size 0.450088 0.450088)
			(layers "F.Cu" "F.Mask" "F.Paste")
			(net "I3C_0_SPD_DDRAF_CPU1_R_SDA")
		)
		(pad "B72" smd circle
			(at 32.109918 -35.999928 180)
			(size 0.450088 0.450088)
			(layers "F.Cu" "F.Mask" "F.Paste")
			(net "Net_2097")
		)
		(pad "B73" smd circle
			(at 33.049972 -35.999928 180)
			(size 0.450088 0.450088)
			(layers "F.Cu" "F.Mask" "F.Paste")
			(net "VSENSE_PVDD18_S5_P1_DN")
		)
		(pad "BA1" smd circle
			(at -34.159952 -4.409948 180)
			(size 0.450088 0.450088)
			(layers "F.Cu" "F.Mask" "F.Paste")
			(net "GND")
		)
		(pad "BA2" smd circle
			(at -33.219898 -4.409948 180)
			(size 0.450088 0.450088)
			(layers "F.Cu" "F.Mask" "F.Paste")
			(net "M_G_CPU1_SA_CA<4>")
		)
		(pad "BA3" smd circle
			(at -32.280098 -4.409948 180)
			(size 0.450088 0.450088)
			(layers "F.Cu" "F.Mask" "F.Paste")
			(net "M_G_CPU1_SA_CA<3>")
		)
		(pad "BA4" smd circle
			(at -31.340044 -4.409948 180)
			(size 0.450088 0.450088)
			(layers "F.Cu" "F.Mask" "F.Paste")
			(net "PVDDCR_SOC_P1")
		)
		(pad "BA5" smd circle
			(at -30.39999 -4.409948 180)
			(size 0.450088 0.450088)
			(layers "F.Cu" "F.Mask" "F.Paste")
			(net "M_K_CPU1_SA_CA<4>")
		)
		(pad "BA6" smd circle
			(at -29.459936 -4.409948 180)
			(size 0.450088 0.450088)
			(layers "F.Cu" "F.Mask" "F.Paste")
			(net "GND")
		)
		(pad "BA7" smd circle
			(at -28.519882 -4.409948 180)
			(size 0.450088 0.450088)
			(layers "F.Cu" "F.Mask" "F.Paste")
			(net "M_K_CPU1_SA_CA<3>")
		)
		(pad "BA8" smd circle
			(at -27.580082 -4.409948 180)
			(size 0.450088 0.450088)
			(layers "F.Cu" "F.Mask" "F.Paste")
			(net "GND")
		)
		(pad "BA9" smd circle
			(at -26.640028 -4.409948 180)
			(size 0.450088 0.450088)
			(layers "F.Cu" "F.Mask" "F.Paste")
			(net "M_L_CPU1_SA_CA<4>")
		)
		(pad "BA10" smd circle
			(at -25.699974 -4.409948 180)
			(size 0.450088 0.450088)
			(layers "F.Cu" "F.Mask" "F.Paste")
			(net "M_L_CPU1_SA_CA<3>")
		)
		(pad "BA11" smd circle
			(at -24.75992 -4.409948 180)
			(size 0.450088 0.450088)
			(layers "F.Cu" "F.Mask" "F.Paste")
			(net "PVDDCR_SOC_P1")
		)
		(pad "BA12" smd circle
			(at -23.82012 -4.409948 180)
			(size 0.450088 0.450088)
			(layers "F.Cu" "F.Mask" "F.Paste")
			(net "M_H_CPU1_SA_CA<4>")
		)
		(pad "BA13" smd circle
			(at -22.880066 -4.409948 180)
			(size 0.450088 0.450088)
			(layers "F.Cu" "F.Mask" "F.Paste")
			(net "GND")
		)
		(pad "BA14" smd circle
			(at -21.940012 -4.409948 180)
			(size 0.450088 0.450088)
			(layers "F.Cu" "F.Mask" "F.Paste")
			(net "M_H_CPU1_SA_CA<3>")
		)
		(pad "BA15" smd circle
			(at -20.999958 -4.409948 180)
			(size 0.450088 0.450088)
			(layers "F.Cu" "F.Mask" "F.Paste")
			(net "GND")
		)
		(pad "BA16" smd circle
			(at -20.059904 -4.409948 180)
			(size 0.450088 0.450088)
			(layers "F.Cu" "F.Mask" "F.Paste")
			(net "M_J_CPU1_SA_CA<4>")
		)
		(pad "BA17" smd circle
			(at -19.120104 -4.409948 180)
			(size 0.450088 0.450088)
			(layers "F.Cu" "F.Mask" "F.Paste")
			(net "M_J_CPU1_SA_CA<3>")
		)
		(pad "BA18" smd circle
			(at -18.18005 -4.409948 180)
			(size 0.450088 0.450088)
			(layers "F.Cu" "F.Mask" "F.Paste")
			(net "PVDDCR_SOC_P1")
		)
		(pad "BA19" smd circle
			(at -17.239996 -4.409948 180)
			(size 0.450088 0.450088)
			(layers "F.Cu" "F.Mask" "F.Paste")
			(net "M_I_CPU1_SA_CA<4>")
		)
		(pad "BA20" smd circle
			(at -16.299942 -4.409948 180)
			(size 0.450088 0.450088)
			(layers "F.Cu" "F.Mask" "F.Paste")
			(net "GND")
		)
		(pad "BA21" smd circle
			(at -15.359888 -4.409948 180)
			(size 0.450088 0.450088)
			(layers "F.Cu" "F.Mask" "F.Paste")
			(net "M_I_CPU1_SA_CA<3>")
		)
		(pad "BA22" smd circle
			(at -14.420088 -4.409948 180)
			(size 0.450088 0.450088)
			(layers "F.Cu" "F.Mask" "F.Paste")
			(net "GND")
		)
		(pad "BA23" smd circle
			(at -13.480034 -4.409948 180)
			(size 0.450088 0.450088)
			(layers "F.Cu" "F.Mask" "F.Paste")
			(net "PVDDCR_SOC_P1")
		)
		(pad "BA24" smd circle
			(at -12.53998 -4.409948 180)
			(size 0.450088 0.450088)
			(layers "F.Cu" "F.Mask" "F.Paste")
			(net "GND")
		)
		(pad "BA25" smd circle
			(at -11.599926 -4.409948 180)
			(size 0.450088 0.450088)
			(layers "F.Cu" "F.Mask" "F.Paste")
			(net "PVDDCR_SOC_P1")
		)
		(pad "BA26" smd circle
			(at -10.659872 -4.409948 180)
			(size 0.450088 0.450088)
			(layers "F.Cu" "F.Mask" "F.Paste")
			(net "GND")
		)
		(pad "BA27" smd circle
			(at -9.720072 -4.409948 180)
			(size 0.450088 0.450088)
			(layers "F.Cu" "F.Mask" "F.Paste")
			(net "PVDDCR_SOC_P1")
		)
		(pad "BA28" smd circle
			(at -8.780018 -4.409948 180)
			(size 0.450088 0.450088)
			(layers "F.Cu" "F.Mask" "F.Paste")
			(net "GND")
		)
		(pad "BA48" smd circle
			(at 9.079992 -4.409948 180)
			(size 0.450088 0.450088)
			(layers "F.Cu" "F.Mask" "F.Paste")
			(net "PVDDCR_SOC_P1")
		)
		(pad "BA49" smd circle
			(at 10.020046 -4.409948 180)
			(size 0.450088 0.450088)
			(layers "F.Cu" "F.Mask" "F.Paste")
			(net "GND")
		)
		(pad "BA50" smd circle
			(at 10.9601 -4.409948 180)
			(size 0.450088 0.450088)
			(layers "F.Cu" "F.Mask" "F.Paste")
			(net "PVDD18_S5_P1")
		)
		(pad "BA51" smd circle
			(at 11.8999 -4.409948 180)
			(size 0.450088 0.450088)
			(layers "F.Cu" "F.Mask" "F.Paste")
			(net "GND")
		)
		(pad "BA52" smd circle
			(at 12.839954 -4.409948 180)
			(size 0.450088 0.450088)
			(layers "F.Cu" "F.Mask" "F.Paste")
			(net "PVDD18_S5_P1")
		)
		(pad "BA53" smd circle
			(at 13.780008 -4.409948 180)
			(size 0.450088 0.450088)
			(layers "F.Cu" "F.Mask" "F.Paste")
			(net "GND")
		)
		(pad "BA54" smd circle
			(at 14.720062 -4.409948 180)
			(size 0.450088 0.450088)
			(layers "F.Cu" "F.Mask" "F.Paste")
			(net "PVDD18_S5_P1")
		)
		(pad "BA55" smd circle
			(at 15.660116 -4.409948 180)
			(size 0.450088 0.450088)
			(layers "F.Cu" "F.Mask" "F.Paste")
			(net "M_C_CPU1_SA_CA<3>")
		)
		(pad "BA56" smd circle
			(at 16.599916 -4.409948 180)
			(size 0.450088 0.450088)
			(layers "F.Cu" "F.Mask" "F.Paste")
			(net "GND")
		)
		(pad "BA57" smd circle
			(at 17.53997 -4.409948 180)
			(size 0.450088 0.450088)
			(layers "F.Cu" "F.Mask" "F.Paste")
			(net "M_C_CPU1_SA_CA<4>")
		)
		(pad "BA58" smd circle
			(at 18.480024 -4.409948 180)
			(size 0.450088 0.450088)
			(layers "F.Cu" "F.Mask" "F.Paste")
			(net "PVDDIO_P1")
		)
		(pad "BA59" smd circle
			(at 19.420078 -4.409948 180)
			(size 0.450088 0.450088)
			(layers "F.Cu" "F.Mask" "F.Paste")
			(net "M_D_CPU1_SA_CA<3>")
		)
		(pad "BA60" smd circle
			(at 20.359878 -4.409948 180)
			(size 0.450088 0.450088)
			(layers "F.Cu" "F.Mask" "F.Paste")
			(net "M_D_CPU1_SA_CA<4>")
		)
		(pad "BA61" smd circle
			(at 21.299932 -4.409948 180)
			(size 0.450088 0.450088)
			(layers "F.Cu" "F.Mask" "F.Paste")
			(net "GND")
		)
		(pad "BA62" smd circle
			(at 22.239986 -4.409948 180)
			(size 0.450088 0.450088)
			(layers "F.Cu" "F.Mask" "F.Paste")
			(net "M_B_CPU1_SA_CA<3>")
		)
		(pad "BA63" smd circle
			(at 23.18004 -4.409948 180)
			(size 0.450088 0.450088)
			(layers "F.Cu" "F.Mask" "F.Paste")
			(net "GND")
		)
		(pad "BA64" smd circle
			(at 24.120094 -4.409948 180)
			(size 0.450088 0.450088)
			(layers "F.Cu" "F.Mask" "F.Paste")
			(net "M_B_CPU1_SA_CA<4>")
		)
		(pad "BA65" smd circle
			(at 25.059894 -4.409948 180)
			(size 0.450088 0.450088)
			(layers "F.Cu" "F.Mask" "F.Paste")
			(net "PVDDIO_P1")
		)
		(pad "BA66" smd circle
			(at 25.999948 -4.409948 180)
			(size 0.450088 0.450088)
			(layers "F.Cu" "F.Mask" "F.Paste")
			(net "M_F_CPU1_SA_CA<3>")
		)
		(pad "BA67" smd circle
			(at 26.940002 -4.409948 180)
			(size 0.450088 0.450088)
			(layers "F.Cu" "F.Mask" "F.Paste")
			(net "M_F_CPU1_SA_CA<4>")
		)
		(pad "BA68" smd circle
			(at 27.880056 -4.409948 180)
			(size 0.450088 0.450088)
			(layers "F.Cu" "F.Mask" "F.Paste")
			(net "GND")
		)
		(pad "BA69" smd circle
			(at 28.82011 -4.409948 180)
			(size 0.450088 0.450088)
			(layers "F.Cu" "F.Mask" "F.Paste")
			(net "M_E_CPU1_SA_CA<3>")
		)
		(pad "BA70" smd circle
			(at 29.75991 -4.409948 180)
			(size 0.450088 0.450088)
			(layers "F.Cu" "F.Mask" "F.Paste")
			(net "GND")
		)
		(pad "BA71" smd circle
			(at 30.699964 -4.409948 180)
			(size 0.450088 0.450088)
			(layers "F.Cu" "F.Mask" "F.Paste")
			(net "M_E_CPU1_SA_CA<4>")
		)
		(pad "BA72" smd circle
			(at 31.640018 -4.409948 180)
			(size 0.450088 0.450088)
			(layers "F.Cu" "F.Mask" "F.Paste")
			(net "PVDDIO_P1")
		)
		(pad "BA73" smd circle
			(at 32.580072 -4.409948 180)
			(size 0.450088 0.450088)
			(layers "F.Cu" "F.Mask" "F.Paste")
			(net "M_A_CPU1_SA_CA<3>")
		)
		(pad "BA74" smd circle
			(at 33.519872 -4.409948 180)
			(size 0.450088 0.450088)
			(layers "F.Cu" "F.Mask" "F.Paste")
			(net "M_A_CPU1_SA_CA<4>")
		)
		(pad "BA75" smd circle
			(at 34.459926 -4.409948 180)
			(size 0.450088 0.450088)
			(layers "F.Cu" "F.Mask" "F.Paste")
			(net "GND")
		)
		(pad "BB2" smd circle
			(at -33.690052 -3.599942 180)
			(size 0.450088 0.450088)
			(layers "F.Cu" "F.Mask" "F.Paste")
			(net "M_G_CPU1_SA_CA<5>")
		)
		(pad "BB3" smd circle
			(at -32.749998 -3.599942 180)
			(size 0.450088 0.450088)
			(layers "F.Cu" "F.Mask" "F.Paste")
			(net "GND")
		)
		(pad "BB4" smd circle
			(at -31.809944 -3.599942 180)
			(size 0.450088 0.450088)
			(layers "F.Cu" "F.Mask" "F.Paste")
			(net "M_G_CPU1_SA_CA<6>")
		)
		(pad "BB5" smd circle
			(at -30.86989 -3.599942 180)
			(size 0.450088 0.450088)
			(layers "F.Cu" "F.Mask" "F.Paste")
			(net "GND")
		)
		(pad "BB6" smd circle
			(at -29.93009 -3.599942 180)
			(size 0.450088 0.450088)
			(layers "F.Cu" "F.Mask" "F.Paste")
			(net "M_K_CPU1_SA_CA<5>")
		)
		(pad "BB7" smd circle
			(at -28.990036 -3.599942 180)
			(size 0.450088 0.450088)
			(layers "F.Cu" "F.Mask" "F.Paste")
			(net "M_K_CPU1_SA_CA<6>")
		)
		(pad "BB8" smd circle
			(at -28.049982 -3.599942 180)
			(size 0.450088 0.450088)
			(layers "F.Cu" "F.Mask" "F.Paste")
			(net "GND")
		)
		(pad "BB9" smd circle
			(at -27.109928 -3.599942 180)
			(size 0.450088 0.450088)
			(layers "F.Cu" "F.Mask" "F.Paste")
			(net "M_L_CPU1_SA_CA<5>")
		)
		(pad "BB10" smd circle
			(at -26.170128 -3.599942 180)
			(size 0.450088 0.450088)
			(layers "F.Cu" "F.Mask" "F.Paste")
			(net "GND")
		)
		(pad "BB11" smd circle
			(at -25.230074 -3.599942 180)
			(size 0.450088 0.450088)
			(layers "F.Cu" "F.Mask" "F.Paste")
			(net "M_L_CPU1_SA_CA<6>")
		)
		(pad "BB12" smd circle
			(at -24.29002 -3.599942 180)
			(size 0.450088 0.450088)
			(layers "F.Cu" "F.Mask" "F.Paste")
			(net "GND")
		)
		(pad "BB13" smd circle
			(at -23.349966 -3.599942 180)
			(size 0.450088 0.450088)
			(layers "F.Cu" "F.Mask" "F.Paste")
			(net "M_H_CPU1_SA_CA<5>")
		)
		(pad "BB14" smd circle
			(at -22.409912 -3.599942 180)
			(size 0.450088 0.450088)
			(layers "F.Cu" "F.Mask" "F.Paste")
			(net "M_H_CPU1_SA_CA<6>")
		)
		(pad "BB15" smd circle
			(at -21.470112 -3.599942 180)
			(size 0.450088 0.450088)
			(layers "F.Cu" "F.Mask" "F.Paste")
			(net "GND")
		)
		(pad "BB16" smd circle
			(at -20.530058 -3.599942 180)
			(size 0.450088 0.450088)
			(layers "F.Cu" "F.Mask" "F.Paste")
			(net "M_J_CPU1_SA_CA<5>")
		)
		(pad "BB17" smd circle
			(at -19.590004 -3.599942 180)
			(size 0.450088 0.450088)
			(layers "F.Cu" "F.Mask" "F.Paste")
			(net "GND")
		)
		(pad "BB18" smd circle
			(at -18.64995 -3.599942 180)
			(size 0.450088 0.450088)
			(layers "F.Cu" "F.Mask" "F.Paste")
			(net "M_J_CPU1_SA_CA<6>")
		)
		(pad "BB19" smd circle
			(at -17.709896 -3.599942 180)
			(size 0.450088 0.450088)
			(layers "F.Cu" "F.Mask" "F.Paste")
			(net "GND")
		)
		(pad "BB20" smd circle
			(at -16.770096 -3.599942 180)
			(size 0.450088 0.450088)
			(layers "F.Cu" "F.Mask" "F.Paste")
			(net "M_I_CPU1_SA_CA<5>")
		)
		(pad "BB21" smd circle
			(at -15.830042 -3.599942 180)
			(size 0.450088 0.450088)
			(layers "F.Cu" "F.Mask" "F.Paste")
			(net "M_I_CPU1_SA_CA<6>")
		)
		(pad "BB22" smd circle
			(at -14.889988 -3.599942 180)
			(size 0.450088 0.450088)
			(layers "F.Cu" "F.Mask" "F.Paste")
			(net "PVDDCR_SOC_P1")
		)
		(pad "BB23" smd circle
			(at -13.949934 -3.599942 180)
			(size 0.450088 0.450088)
			(layers "F.Cu" "F.Mask" "F.Paste")
			(net "GND")
		)
		(pad "BB24" smd circle
			(at -13.00988 -3.599942 180)
			(size 0.450088 0.450088)
			(layers "F.Cu" "F.Mask" "F.Paste")
			(net "PVDDCR_SOC_P1")
		)
		(pad "BB25" smd circle
			(at -12.07008 -3.599942 180)
			(size 0.450088 0.450088)
			(layers "F.Cu" "F.Mask" "F.Paste")
			(net "GND")
		)
		(pad "BB26" smd circle
			(at -11.130026 -3.599942 180)
			(size 0.450088 0.450088)
			(layers "F.Cu" "F.Mask" "F.Paste")
			(net "PVDDCR_SOC_P1")
		)
		(pad "BB27" smd circle
			(at -10.189972 -3.599942 180)
			(size 0.450088 0.450088)
			(layers "F.Cu" "F.Mask" "F.Paste")
			(net "GND")
		)
		(pad "BB28" smd circle
			(at -9.249918 -3.599942 180)
			(size 0.450088 0.450088)
			(layers "F.Cu" "F.Mask" "F.Paste")
			(net "PVDDCR_SOC_P1")
		)
		(pad "BB48" smd circle
			(at 9.549892 -3.599942 180)
			(size 0.450088 0.450088)
			(layers "F.Cu" "F.Mask" "F.Paste")
			(net "GND")
		)
		(pad "BB49" smd circle
			(at 10.489946 -3.599942 180)
			(size 0.450088 0.450088)
			(layers "F.Cu" "F.Mask" "F.Paste")
			(net "PVDDCR_SOC_P1")
		)
		(pad "BB50" smd circle
			(at 11.43 -3.599942 180)
			(size 0.450088 0.450088)
			(layers "F.Cu" "F.Mask" "F.Paste")
			(net "GND")
		)
		(pad "BB51" smd circle
			(at 12.370054 -3.599942 180)
			(size 0.450088 0.450088)
			(layers "F.Cu" "F.Mask" "F.Paste")
			(net "PVDD18_S5_P1")
		)
		(pad "BB52" smd circle
			(at 13.310108 -3.599942 180)
			(size 0.450088 0.450088)
			(layers "F.Cu" "F.Mask" "F.Paste")
			(net "GND")
		)
		(pad "BB53" smd circle
			(at 14.249908 -3.599942 180)
			(size 0.450088 0.450088)
			(layers "F.Cu" "F.Mask" "F.Paste")
			(net "PVDD18_S5_P1")
		)
		(pad "BB54" smd circle
			(at 15.189962 -3.599942 180)
			(size 0.450088 0.450088)
			(layers "F.Cu" "F.Mask" "F.Paste")
			(net "GND")
		)
		(pad "BB55" smd circle
			(at 16.130016 -3.599942 180)
			(size 0.450088 0.450088)
			(layers "F.Cu" "F.Mask" "F.Paste")
			(net "M_C_CPU1_SA_CA<6>")
		)
		(pad "BB56" smd circle
			(at 17.07007 -3.599942 180)
			(size 0.450088 0.450088)
			(layers "F.Cu" "F.Mask" "F.Paste")
			(net "M_C_CPU1_SA_CA<5>")
		)
		(pad "BB57" smd circle
			(at 18.010124 -3.599942 180)
			(size 0.450088 0.450088)
			(layers "F.Cu" "F.Mask" "F.Paste")
			(net "GND")
		)
		(pad "BB58" smd circle
			(at 18.949924 -3.599942 180)
			(size 0.450088 0.450088)
			(layers "F.Cu" "F.Mask" "F.Paste")
			(net "M_D_CPU1_SA_CA<6>")
		)
		(pad "BB59" smd circle
			(at 19.889978 -3.599942 180)
			(size 0.450088 0.450088)
			(layers "F.Cu" "F.Mask" "F.Paste")
			(net "GND")
		)
		(pad "BB60" smd circle
			(at 20.830032 -3.599942 180)
			(size 0.450088 0.450088)
			(layers "F.Cu" "F.Mask" "F.Paste")
			(net "M_D_CPU1_SA_CA<5>")
		)
		(pad "BB61" smd circle
			(at 21.770086 -3.599942 180)
			(size 0.450088 0.450088)
			(layers "F.Cu" "F.Mask" "F.Paste")
			(net "GND")
		)
		(pad "BB62" smd circle
			(at 22.709886 -3.599942 180)
			(size 0.450088 0.450088)
			(layers "F.Cu" "F.Mask" "F.Paste")
			(net "M_B_CPU1_SA_CA<6>")
		)
		(pad "BB63" smd circle
			(at 23.64994 -3.599942 180)
			(size 0.450088 0.450088)
			(layers "F.Cu" "F.Mask" "F.Paste")
			(net "M_B_CPU1_SA_CA<5>")
		)
		(pad "BB64" smd circle
			(at 24.589994 -3.599942 180)
			(size 0.450088 0.450088)
			(layers "F.Cu" "F.Mask" "F.Paste")
			(net "GND")
		)
		(pad "BB65" smd circle
			(at 25.530048 -3.599942 180)
			(size 0.450088 0.450088)
			(layers "F.Cu" "F.Mask" "F.Paste")
			(net "M_F_CPU1_SA_CA<6>")
		)
		(pad "BB66" smd circle
			(at 26.470102 -3.599942 180)
			(size 0.450088 0.450088)
			(layers "F.Cu" "F.Mask" "F.Paste")
			(net "GND")
		)
		(pad "BB67" smd circle
			(at 27.409902 -3.599942 180)
			(size 0.450088 0.450088)
			(layers "F.Cu" "F.Mask" "F.Paste")
			(net "M_F_CPU1_SA_CA<5>")
		)
		(pad "BB68" smd circle
			(at 28.349956 -3.599942 180)
			(size 0.450088 0.450088)
			(layers "F.Cu" "F.Mask" "F.Paste")
			(net "GND")
		)
		(pad "BB69" smd circle
			(at 29.29001 -3.599942 180)
			(size 0.450088 0.450088)
			(layers "F.Cu" "F.Mask" "F.Paste")
			(net "M_E_CPU1_SA_CA<6>")
		)
		(pad "BB70" smd circle
			(at 30.230064 -3.599942 180)
			(size 0.450088 0.450088)
			(layers "F.Cu" "F.Mask" "F.Paste")
			(net "M_E_CPU1_SA_CA<5>")
		)
		(pad "BB71" smd circle
			(at 31.170118 -3.599942 180)
			(size 0.450088 0.450088)
			(layers "F.Cu" "F.Mask" "F.Paste")
			(net "GND")
		)
		(pad "BB72" smd circle
			(at 32.109918 -3.599942 180)
			(size 0.450088 0.450088)
			(layers "F.Cu" "F.Mask" "F.Paste")
			(net "M_A_CPU1_SA_CA<6>")
		)
		(pad "BB73" smd circle
			(at 33.049972 -3.599942 180)
			(size 0.450088 0.450088)
			(layers "F.Cu" "F.Mask" "F.Paste")
			(net "GND")
		)
		(pad "BB74" smd circle
			(at 33.990026 -3.599942 180)
			(size 0.450088 0.450088)
			(layers "F.Cu" "F.Mask" "F.Paste")
			(net "M_A_CPU1_SA_CA<5>")
		)
		(pad "BC1" smd circle
			(at -34.159952 -2.789936 180)
			(size 0.450088 0.450088)
			(layers "F.Cu" "F.Mask" "F.Paste")
			(net "GND")
		)
		(pad "BC2" smd circle
			(at -33.219898 -2.789936 180)
			(size 0.450088 0.450088)
			(layers "F.Cu" "F.Mask" "F.Paste")
			(net "M_G_CPU1_CLK_DP<0>")
		)
		(pad "BC3" smd circle
			(at -32.280098 -2.789936 180)
			(size 0.450088 0.450088)
			(layers "F.Cu" "F.Mask" "F.Paste")
			(net "M_G_CPU1_SA_PAR")
		)
		(pad "BC4" smd circle
			(at -31.340044 -2.789936 180)
			(size 0.450088 0.450088)
			(layers "F.Cu" "F.Mask" "F.Paste")
			(net "GND")
		)
		(pad "BC5" smd circle
			(at -30.39999 -2.789936 180)
			(size 0.450088 0.450088)
			(layers "F.Cu" "F.Mask" "F.Paste")
			(net "M_K_CPU1_CLK_DP<0>")
		)
		(pad "BC6" smd circle
			(at -29.459936 -2.789936 180)
			(size 0.450088 0.450088)
			(layers "F.Cu" "F.Mask" "F.Paste")
			(net "GND")
		)
		(pad "BC7" smd circle
			(at -28.519882 -2.789936 180)
			(size 0.450088 0.450088)
			(layers "F.Cu" "F.Mask" "F.Paste")
			(net "M_K_CPU1_SA_PAR")
		)
		(pad "BC8" smd circle
			(at -27.580082 -2.789936 180)
			(size 0.450088 0.450088)
			(layers "F.Cu" "F.Mask" "F.Paste")
			(net "GND")
		)
		(pad "BC9" smd circle
			(at -26.640028 -2.789936 180)
			(size 0.450088 0.450088)
			(layers "F.Cu" "F.Mask" "F.Paste")
			(net "M_L_CPU1_CLK_DP<0>")
		)
		(pad "BC10" smd circle
			(at -25.699974 -2.789936 180)
			(size 0.450088 0.450088)
			(layers "F.Cu" "F.Mask" "F.Paste")
			(net "M_L_CPU1_SA_PAR")
		)
		(pad "BC11" smd circle
			(at -24.75992 -2.789936 180)
			(size 0.450088 0.450088)
			(layers "F.Cu" "F.Mask" "F.Paste")
			(net "GND")
		)
		(pad "BC12" smd circle
			(at -23.82012 -2.789936 180)
			(size 0.450088 0.450088)
			(layers "F.Cu" "F.Mask" "F.Paste")
			(net "M_H_CPU1_CLK_DP<0>")
		)
		(pad "BC13" smd circle
			(at -22.880066 -2.789936 180)
			(size 0.450088 0.450088)
			(layers "F.Cu" "F.Mask" "F.Paste")
			(net "GND")
		)
		(pad "BC14" smd circle
			(at -21.940012 -2.789936 180)
			(size 0.450088 0.450088)
			(layers "F.Cu" "F.Mask" "F.Paste")
			(net "M_H_CPU1_SA_PAR")
		)
		(pad "BC15" smd circle
			(at -20.999958 -2.789936 180)
			(size 0.450088 0.450088)
			(layers "F.Cu" "F.Mask" "F.Paste")
			(net "GND")
		)
		(pad "BC16" smd circle
			(at -20.059904 -2.789936 180)
			(size 0.450088 0.450088)
			(layers "F.Cu" "F.Mask" "F.Paste")
			(net "M_J_CPU1_CLK_DP<0>")
		)
		(pad "BC17" smd circle
			(at -19.120104 -2.789936 180)
			(size 0.450088 0.450088)
			(layers "F.Cu" "F.Mask" "F.Paste")
			(net "M_J_CPU1_SA_PAR")
		)
		(pad "BC18" smd circle
			(at -18.18005 -2.789936 180)
			(size 0.450088 0.450088)
			(layers "F.Cu" "F.Mask" "F.Paste")
			(net "GND")
		)
		(pad "BC19" smd circle
			(at -17.239996 -2.789936 180)
			(size 0.450088 0.450088)
			(layers "F.Cu" "F.Mask" "F.Paste")
			(net "M_I_CPU1_CLK_DP<0>")
		)
		(pad "BC20" smd circle
			(at -16.299942 -2.789936 180)
			(size 0.450088 0.450088)
			(layers "F.Cu" "F.Mask" "F.Paste")
			(net "GND")
		)
		(pad "BC21" smd circle
			(at -15.359888 -2.789936 180)
			(size 0.450088 0.450088)
			(layers "F.Cu" "F.Mask" "F.Paste")
			(net "M_I_CPU1_SA_PAR")
		)
		(pad "BC22" smd circle
			(at -14.420088 -2.789936 180)
			(size 0.450088 0.450088)
			(layers "F.Cu" "F.Mask" "F.Paste")
			(net "GND")
		)
		(pad "BC23" smd circle
			(at -13.480034 -2.789936 180)
			(size 0.450088 0.450088)
			(layers "F.Cu" "F.Mask" "F.Paste")
			(net "PVDDCR_SOC_P1")
		)
		(pad "BC24" smd circle
			(at -12.53998 -2.789936 180)
			(size 0.450088 0.450088)
			(layers "F.Cu" "F.Mask" "F.Paste")
			(net "GND")
		)
		(pad "BC25" smd circle
			(at -11.599926 -2.789936 180)
			(size 0.450088 0.450088)
			(layers "F.Cu" "F.Mask" "F.Paste")
			(net "PVDDCR_SOC_P1")
		)
		(pad "BC26" smd circle
			(at -10.659872 -2.789936 180)
			(size 0.450088 0.450088)
			(layers "F.Cu" "F.Mask" "F.Paste")
			(net "GND")
		)
		(pad "BC27" smd circle
			(at -9.720072 -2.789936 180)
			(size 0.450088 0.450088)
			(layers "F.Cu" "F.Mask" "F.Paste")
			(net "PVDDCR_SOC_P1")
		)
		(pad "BC28" smd circle
			(at -8.780018 -2.789936 180)
			(size 0.450088 0.450088)
			(layers "F.Cu" "F.Mask" "F.Paste")
			(net "GND")
		)
		(pad "BC48" smd circle
			(at 9.079992 -2.789936 180)
			(size 0.450088 0.450088)
			(layers "F.Cu" "F.Mask" "F.Paste")
			(net "PVDDCR_SOC_P1")
		)
		(pad "BC49" smd circle
			(at 10.020046 -2.789936 180)
			(size 0.450088 0.450088)
			(layers "F.Cu" "F.Mask" "F.Paste")
			(net "GND")
		)
		(pad "BC50" smd circle
			(at 10.9601 -2.789936 180)
			(size 0.450088 0.450088)
			(layers "F.Cu" "F.Mask" "F.Paste")
			(net "GND")
		)
		(pad "BC51" smd circle
			(at 11.8999 -2.789936 180)
			(size 0.450088 0.450088)
			(layers "F.Cu" "F.Mask" "F.Paste")
			(net "GND")
		)
		(pad "BC52" smd circle
			(at 12.839954 -2.789936 180)
			(size 0.450088 0.450088)
			(layers "F.Cu" "F.Mask" "F.Paste")
			(net "PVDD18_S5_P1")
		)
		(pad "BC53" smd circle
			(at 13.780008 -2.789936 180)
			(size 0.450088 0.450088)
			(layers "F.Cu" "F.Mask" "F.Paste")
			(net "GND")
		)
		(pad "BC54" smd circle
			(at 14.720062 -2.789936 180)
			(size 0.450088 0.450088)
			(layers "F.Cu" "F.Mask" "F.Paste")
			(net "PVDD18_S5_P1")
		)
		(pad "BC55" smd circle
			(at 15.660116 -2.789936 180)
			(size 0.450088 0.450088)
			(layers "F.Cu" "F.Mask" "F.Paste")
			(net "M_C_CPU1_SA_PAR")
		)
		(pad "BC56" smd circle
			(at 16.599916 -2.789936 180)
			(size 0.450088 0.450088)
			(layers "F.Cu" "F.Mask" "F.Paste")
			(net "GND")
		)
		(pad "BC57" smd circle
			(at 17.53997 -2.789936 180)
			(size 0.450088 0.450088)
			(layers "F.Cu" "F.Mask" "F.Paste")
			(net "M_C_CPU1_CLK_DP<0>")
		)
		(pad "BC58" smd circle
			(at 18.480024 -2.789936 180)
			(size 0.450088 0.450088)
			(layers "F.Cu" "F.Mask" "F.Paste")
			(net "GND")
		)
		(pad "BC59" smd circle
			(at 19.420078 -2.789936 180)
			(size 0.450088 0.450088)
			(layers "F.Cu" "F.Mask" "F.Paste")
			(net "M_D_CPU1_SA_PAR")
		)
		(pad "BC60" smd circle
			(at 20.359878 -2.789936 180)
			(size 0.450088 0.450088)
			(layers "F.Cu" "F.Mask" "F.Paste")
			(net "M_D_CPU1_CLK_DP<0>")
		)
		(pad "BC61" smd circle
			(at 21.299932 -2.789936 180)
			(size 0.450088 0.450088)
			(layers "F.Cu" "F.Mask" "F.Paste")
			(net "GND")
		)
		(pad "BC62" smd circle
			(at 22.239986 -2.789936 180)
			(size 0.450088 0.450088)
			(layers "F.Cu" "F.Mask" "F.Paste")
			(net "M_B_CPU1_SA_PAR")
		)
		(pad "BC63" smd circle
			(at 23.18004 -2.789936 180)
			(size 0.450088 0.450088)
			(layers "F.Cu" "F.Mask" "F.Paste")
			(net "GND")
		)
		(pad "BC64" smd circle
			(at 24.120094 -2.789936 180)
			(size 0.450088 0.450088)
			(layers "F.Cu" "F.Mask" "F.Paste")
			(net "M_B_CPU1_CLK_DP<0>")
		)
		(pad "BC65" smd circle
			(at 25.059894 -2.789936 180)
			(size 0.450088 0.450088)
			(layers "F.Cu" "F.Mask" "F.Paste")
			(net "GND")
		)
		(pad "BC66" smd circle
			(at 25.999948 -2.789936 180)
			(size 0.450088 0.450088)
			(layers "F.Cu" "F.Mask" "F.Paste")
			(net "M_F_CPU1_SA_PAR")
		)
		(pad "BC67" smd circle
			(at 26.940002 -2.789936 180)
			(size 0.450088 0.450088)
			(layers "F.Cu" "F.Mask" "F.Paste")
			(net "M_F_CPU1_CLK_DP<0>")
		)
		(pad "BC68" smd circle
			(at 27.880056 -2.789936 180)
			(size 0.450088 0.450088)
			(layers "F.Cu" "F.Mask" "F.Paste")
			(net "GND")
		)
		(pad "BC69" smd circle
			(at 28.82011 -2.789936 180)
			(size 0.450088 0.450088)
			(layers "F.Cu" "F.Mask" "F.Paste")
			(net "M_E_CPU1_SA_PAR")
		)
		(pad "BC70" smd circle
			(at 29.75991 -2.789936 180)
			(size 0.450088 0.450088)
			(layers "F.Cu" "F.Mask" "F.Paste")
			(net "GND")
		)
		(pad "BC71" smd circle
			(at 30.699964 -2.789936 180)
			(size 0.450088 0.450088)
			(layers "F.Cu" "F.Mask" "F.Paste")
			(net "M_E_CPU1_CLK_DP<0>")
		)
		(pad "BC72" smd circle
			(at 31.640018 -2.789936 180)
			(size 0.450088 0.450088)
			(layers "F.Cu" "F.Mask" "F.Paste")
			(net "GND")
		)
		(pad "BC73" smd circle
			(at 32.580072 -2.789936 180)
			(size 0.450088 0.450088)
			(layers "F.Cu" "F.Mask" "F.Paste")
			(net "M_A_CPU1_SA_PAR")
		)
		(pad "BC74" smd circle
			(at 33.519872 -2.789936 180)
			(size 0.450088 0.450088)
			(layers "F.Cu" "F.Mask" "F.Paste")
			(net "M_A_CPU1_CLK_DP<0>")
		)
		(pad "BC75" smd circle
			(at 34.459926 -2.789936 180)
			(size 0.450088 0.450088)
			(layers "F.Cu" "F.Mask" "F.Paste")
			(net "GND")
		)
		(pad "BD2" smd circle
			(at -33.690052 -1.97993 180)
			(size 0.450088 0.450088)
			(layers "F.Cu" "F.Mask" "F.Paste")
			(net "M_G_CPU1_CLK_DN<0>")
		)
		(pad "BD3" smd circle
			(at -32.749998 -1.97993 180)
			(size 0.450088 0.450088)
			(layers "F.Cu" "F.Mask" "F.Paste")
			(net "GND")
		)
		(pad "BD4" smd circle
			(at -31.809944 -1.97993 180)
			(size 0.450088 0.450088)
			(layers "F.Cu" "F.Mask" "F.Paste")
			(net "Net_2140")
		)
		(pad "BD5" smd circle
			(at -30.86989 -1.97993 180)
			(size 0.450088 0.450088)
			(layers "F.Cu" "F.Mask" "F.Paste")
			(net "PVDDCR_SOC_P1")
		)
		(pad "BD6" smd circle
			(at -29.93009 -1.97993 180)
			(size 0.450088 0.450088)
			(layers "F.Cu" "F.Mask" "F.Paste")
			(net "M_K_CPU1_CLK_DN<0>")
		)
		(pad "BD7" smd circle
			(at -28.990036 -1.97993 180)
			(size 0.450088 0.450088)
			(layers "F.Cu" "F.Mask" "F.Paste")
			(net "Net_2146")
		)
		(pad "BD8" smd circle
			(at -28.049982 -1.97993 180)
			(size 0.450088 0.450088)
			(layers "F.Cu" "F.Mask" "F.Paste")
			(net "GND")
		)
		(pad "BD9" smd circle
			(at -27.109928 -1.97993 180)
			(size 0.450088 0.450088)
			(layers "F.Cu" "F.Mask" "F.Paste")
			(net "M_L_CPU1_CLK_DN<0>")
		)
		(pad "BD10" smd circle
			(at -26.170128 -1.97993 180)
			(size 0.450088 0.450088)
			(layers "F.Cu" "F.Mask" "F.Paste")
			(net "GND")
		)
		(pad "BD11" smd circle
			(at -25.230074 -1.97993 180)
			(size 0.450088 0.450088)
			(layers "F.Cu" "F.Mask" "F.Paste")
			(net "Net_2136")
		)
		(pad "BD12" smd circle
			(at -24.29002 -1.97993 180)
			(size 0.450088 0.450088)
			(layers "F.Cu" "F.Mask" "F.Paste")
			(net "PVDDCR_SOC_P1")
		)
		(pad "BD13" smd circle
			(at -23.349966 -1.97993 180)
			(size 0.450088 0.450088)
			(layers "F.Cu" "F.Mask" "F.Paste")
			(net "M_H_CPU1_CLK_DN<0>")
		)
		(pad "BD14" smd circle
			(at -22.409912 -1.97993 180)
			(size 0.450088 0.450088)
			(layers "F.Cu" "F.Mask" "F.Paste")
			(net "Net_2137")
		)
		(pad "BD15" smd circle
			(at -21.470112 -1.97993 180)
			(size 0.450088 0.450088)
			(layers "F.Cu" "F.Mask" "F.Paste")
			(net "GND")
		)
		(pad "BD16" smd circle
			(at -20.530058 -1.97993 180)
			(size 0.450088 0.450088)
			(layers "F.Cu" "F.Mask" "F.Paste")
			(net "M_J_CPU1_CLK_DN<0>")
		)
		(pad "BD17" smd circle
			(at -19.590004 -1.97993 180)
			(size 0.450088 0.450088)
			(layers "F.Cu" "F.Mask" "F.Paste")
			(net "GND")
		)
		(pad "BD18" smd circle
			(at -18.64995 -1.97993 180)
			(size 0.450088 0.450088)
			(layers "F.Cu" "F.Mask" "F.Paste")
			(net "Net_2138")
		)
		(pad "BD19" smd circle
			(at -17.709896 -1.97993 180)
			(size 0.450088 0.450088)
			(layers "F.Cu" "F.Mask" "F.Paste")
			(net "PVDDCR_SOC_P1")
		)
		(pad "BD20" smd circle
			(at -16.770096 -1.97993 180)
			(size 0.450088 0.450088)
			(layers "F.Cu" "F.Mask" "F.Paste")
			(net "M_I_CPU1_CLK_DN<0>")
		)
		(pad "BD21" smd circle
			(at -15.830042 -1.97993 180)
			(size 0.450088 0.450088)
			(layers "F.Cu" "F.Mask" "F.Paste")
			(net "Net_2139")
		)
		(pad "BD22" smd circle
			(at -14.889988 -1.97993 180)
			(size 0.450088 0.450088)
			(layers "F.Cu" "F.Mask" "F.Paste")
			(net "PVDDCR_SOC_P1")
		)
		(pad "BD23" smd circle
			(at -13.949934 -1.97993 180)
			(size 0.450088 0.450088)
			(layers "F.Cu" "F.Mask" "F.Paste")
			(net "GND")
		)
		(pad "BD24" smd circle
			(at -13.00988 -1.97993 180)
			(size 0.450088 0.450088)
			(layers "F.Cu" "F.Mask" "F.Paste")
			(net "PVDDCR_SOC_P1")
		)
		(pad "BD25" smd circle
			(at -12.07008 -1.97993 180)
			(size 0.450088 0.450088)
			(layers "F.Cu" "F.Mask" "F.Paste")
			(net "GND")
		)
		(pad "BD26" smd circle
			(at -11.130026 -1.97993 180)
			(size 0.450088 0.450088)
			(layers "F.Cu" "F.Mask" "F.Paste")
			(net "PVDDCR_SOC_P1")
		)
		(pad "BD27" smd circle
			(at -10.189972 -1.97993 180)
			(size 0.450088 0.450088)
			(layers "F.Cu" "F.Mask" "F.Paste")
			(net "GND")
		)
		(pad "BD28" smd circle
			(at -9.249918 -1.97993 180)
			(size 0.450088 0.450088)
			(layers "F.Cu" "F.Mask" "F.Paste")
			(net "PVDDCR_SOC_P1")
		)
		(pad "BD48" smd circle
			(at 9.549892 -1.97993 180)
			(size 0.450088 0.450088)
			(layers "F.Cu" "F.Mask" "F.Paste")
			(net "PVDDCR_SOC_P1")
		)
		(pad "BD49" smd circle
			(at 10.489946 -1.97993 180)
			(size 0.450088 0.450088)
			(layers "F.Cu" "F.Mask" "F.Paste")
			(net "GND")
		)
		(pad "BD50" smd circle
			(at 11.43 -1.97993 180)
			(size 0.450088 0.450088)
			(layers "F.Cu" "F.Mask" "F.Paste")
			(net "PVDDIO_P1")
		)
		(pad "BD51" smd circle
			(at 12.370054 -1.97993 180)
			(size 0.450088 0.450088)
			(layers "F.Cu" "F.Mask" "F.Paste")
			(net "GND")
		)
		(pad "BD52" smd circle
			(at 13.310108 -1.97993 180)
			(size 0.450088 0.450088)
			(layers "F.Cu" "F.Mask" "F.Paste")
			(net "PVDDIO_P1")
		)
		(pad "BD53" smd circle
			(at 14.249908 -1.97993 180)
			(size 0.450088 0.450088)
			(layers "F.Cu" "F.Mask" "F.Paste")
			(net "GND")
		)
		(pad "BD54" smd circle
			(at 15.189962 -1.97993 180)
			(size 0.450088 0.450088)
			(layers "F.Cu" "F.Mask" "F.Paste")
			(net "PVDDIO_P1")
		)
		(pad "BD55" smd circle
			(at 16.130016 -1.97993 180)
			(size 0.450088 0.450088)
			(layers "F.Cu" "F.Mask" "F.Paste")
			(net "Net_2141")
		)
		(pad "BD56" smd circle
			(at 17.07007 -1.97993 180)
			(size 0.450088 0.450088)
			(layers "F.Cu" "F.Mask" "F.Paste")
			(net "M_C_CPU1_CLK_DN<0>")
		)
		(pad "BD57" smd circle
			(at 18.010124 -1.97993 180)
			(size 0.450088 0.450088)
			(layers "F.Cu" "F.Mask" "F.Paste")
			(net "GND")
		)
		(pad "BD58" smd circle
			(at 18.949924 -1.97993 180)
			(size 0.450088 0.450088)
			(layers "F.Cu" "F.Mask" "F.Paste")
			(net "Net_2142")
		)
		(pad "BD59" smd circle
			(at 19.889978 -1.97993 180)
			(size 0.450088 0.450088)
			(layers "F.Cu" "F.Mask" "F.Paste")
			(net "GND")
		)
		(pad "BD60" smd circle
			(at 20.830032 -1.97993 180)
			(size 0.450088 0.450088)
			(layers "F.Cu" "F.Mask" "F.Paste")
			(net "M_D_CPU1_CLK_DN<0>")
		)
		(pad "BD61" smd circle
			(at 21.770086 -1.97993 180)
			(size 0.450088 0.450088)
			(layers "F.Cu" "F.Mask" "F.Paste")
			(net "GND")
		)
		(pad "BD62" smd circle
			(at 22.709886 -1.97993 180)
			(size 0.450088 0.450088)
			(layers "F.Cu" "F.Mask" "F.Paste")
			(net "Net_2143")
		)
		(pad "BD63" smd circle
			(at 23.64994 -1.97993 180)
			(size 0.450088 0.450088)
			(layers "F.Cu" "F.Mask" "F.Paste")
			(net "M_B_CPU1_CLK_DN<0>")
		)
		(pad "BD64" smd circle
			(at 24.589994 -1.97993 180)
			(size 0.450088 0.450088)
			(layers "F.Cu" "F.Mask" "F.Paste")
			(net "GND")
		)
		(pad "BD65" smd circle
			(at 25.530048 -1.97993 180)
			(size 0.450088 0.450088)
			(layers "F.Cu" "F.Mask" "F.Paste")
			(net "Net_2144")
		)
		(pad "BD66" smd circle
			(at 26.470102 -1.97993 180)
			(size 0.450088 0.450088)
			(layers "F.Cu" "F.Mask" "F.Paste")
			(net "GND")
		)
		(pad "BD67" smd circle
			(at 27.409902 -1.97993 180)
			(size 0.450088 0.450088)
			(layers "F.Cu" "F.Mask" "F.Paste")
			(net "M_F_CPU1_CLK_DN<0>")
		)
		(pad "BD68" smd circle
			(at 28.349956 -1.97993 180)
			(size 0.450088 0.450088)
			(layers "F.Cu" "F.Mask" "F.Paste")
			(net "GND")
		)
		(pad "BD69" smd circle
			(at 29.29001 -1.97993 180)
			(size 0.450088 0.450088)
			(layers "F.Cu" "F.Mask" "F.Paste")
			(net "Net_2145")
		)
		(pad "BD70" smd circle
			(at 30.230064 -1.97993 180)
			(size 0.450088 0.450088)
			(layers "F.Cu" "F.Mask" "F.Paste")
			(net "M_E_CPU1_CLK_DN<0>")
		)
		(pad "BD71" smd circle
			(at 31.170118 -1.97993 180)
			(size 0.450088 0.450088)
			(layers "F.Cu" "F.Mask" "F.Paste")
			(net "GND")
		)
		(pad "BD72" smd circle
			(at 32.109918 -1.97993 180)
			(size 0.450088 0.450088)
			(layers "F.Cu" "F.Mask" "F.Paste")
			(net "Net_2147")
		)
		(pad "BD73" smd circle
			(at 33.049972 -1.97993 180)
			(size 0.450088 0.450088)
			(layers "F.Cu" "F.Mask" "F.Paste")
			(net "GND")
		)
		(pad "BD74" smd circle
			(at 33.990026 -1.97993 180)
			(size 0.450088 0.450088)
			(layers "F.Cu" "F.Mask" "F.Paste")
			(net "M_A_CPU1_CLK_DN<0>")
		)
		(pad "BF2" smd circle
			(at -33.990026 1.97993 180)
			(size 0.450088 0.450088)
			(layers "F.Cu" "F.Mask" "F.Paste")
			(net "Net_2038")
		)
		(pad "BF3" smd circle
			(at -33.049972 1.97993 180)
			(size 0.450088 0.450088)
			(layers "F.Cu" "F.Mask" "F.Paste")
			(net "GND")
		)
		(pad "BF4" smd circle
			(at -32.109918 1.97993 180)
			(size 0.450088 0.450088)
			(layers "F.Cu" "F.Mask" "F.Paste")
			(net "TP_M_G_CPU1_SA_TEST39G")
		)
		(pad "BF5" smd circle
			(at -31.170118 1.97993 180)
			(size 0.450088 0.450088)
			(layers "F.Cu" "F.Mask" "F.Paste")
			(net "GND")
		)
		(pad "BF6" smd circle
			(at -30.230064 1.97993 180)
			(size 0.450088 0.450088)
			(layers "F.Cu" "F.Mask" "F.Paste")
			(net "Net_2187")
		)
		(pad "BF7" smd circle
			(at -29.29001 1.97993 180)
			(size 0.450088 0.450088)
			(layers "F.Cu" "F.Mask" "F.Paste")
			(net "TP_M_K_CPU1_SA_TEST39K")
		)
		(pad "BF8" smd circle
			(at -28.349956 1.97993 180)
			(size 0.450088 0.450088)
			(layers "F.Cu" "F.Mask" "F.Paste")
			(net "GND")
		)
		(pad "BF9" smd circle
			(at -27.409902 1.97993 180)
			(size 0.450088 0.450088)
			(layers "F.Cu" "F.Mask" "F.Paste")
			(net "Net_2179")
		)
		(pad "BF10" smd circle
			(at -26.470102 1.97993 180)
			(size 0.450088 0.450088)
			(layers "F.Cu" "F.Mask" "F.Paste")
			(net "GND")
		)
		(pad "BF11" smd circle
			(at -25.530048 1.97993 180)
			(size 0.450088 0.450088)
			(layers "F.Cu" "F.Mask" "F.Paste")
			(net "TP_M_L_CPU1_SA_TEST39L")
		)
		(pad "BF12" smd circle
			(at -24.589994 1.97993 180)
			(size 0.450088 0.450088)
			(layers "F.Cu" "F.Mask" "F.Paste")
			(net "GND")
		)
		(pad "BF13" smd circle
			(at -23.64994 1.97993 180)
			(size 0.450088 0.450088)
			(layers "F.Cu" "F.Mask" "F.Paste")
			(net "Net_2046")
		)
		(pad "BF14" smd circle
			(at -22.709886 1.97993 180)
			(size 0.450088 0.450088)
			(layers "F.Cu" "F.Mask" "F.Paste")
			(net "TP_M_H_CPU1_SA_TEST39H")
		)
		(pad "BF15" smd circle
			(at -21.770086 1.97993 180)
			(size 0.450088 0.450088)
			(layers "F.Cu" "F.Mask" "F.Paste")
			(net "GND")
		)
		(pad "BF16" smd circle
			(at -20.830032 1.97993 180)
			(size 0.450088 0.450088)
			(layers "F.Cu" "F.Mask" "F.Paste")
			(net "Net_2062")
		)
		(pad "BF17" smd circle
			(at -19.889978 1.97993 180)
			(size 0.450088 0.450088)
			(layers "F.Cu" "F.Mask" "F.Paste")
			(net "GND")
		)
		(pad "BF18" smd circle
			(at -18.949924 1.97993 180)
			(size 0.450088 0.450088)
			(layers "F.Cu" "F.Mask" "F.Paste")
			(net "TP_M_J_CPU1_SA_TEST39J")
		)
		(pad "BF19" smd circle
			(at -18.010124 1.97993 180)
			(size 0.450088 0.450088)
			(layers "F.Cu" "F.Mask" "F.Paste")
			(net "GND")
		)
		(pad "BF20" smd circle
			(at -17.07007 1.97993 180)
			(size 0.450088 0.450088)
			(layers "F.Cu" "F.Mask" "F.Paste")
			(net "Net_2054")
		)
		(pad "BF21" smd circle
			(at -16.130016 1.97993 180)
			(size 0.450088 0.450088)
			(layers "F.Cu" "F.Mask" "F.Paste")
			(net "TP_M_I_CPU1_SA_TEST39I")
		)
		(pad "BF22" smd circle
			(at -15.189962 1.97993 180)
			(size 0.450088 0.450088)
			(layers "F.Cu" "F.Mask" "F.Paste")
			(net "GND")
		)
		(pad "BF23" smd circle
			(at -14.249908 1.97993 180)
			(size 0.450088 0.450088)
			(layers "F.Cu" "F.Mask" "F.Paste")
			(net "PVDDCR_SOC_P1")
		)
		(pad "BF24" smd circle
			(at -13.310108 1.97993 180)
			(size 0.450088 0.450088)
			(layers "F.Cu" "F.Mask" "F.Paste")
			(net "GND")
		)
		(pad "BF25" smd circle
			(at -12.370054 1.97993 180)
			(size 0.450088 0.450088)
			(layers "F.Cu" "F.Mask" "F.Paste")
			(net "PVDDCR_SOC_P1")
		)
		(pad "BF26" smd circle
			(at -11.43 1.97993 180)
			(size 0.450088 0.450088)
			(layers "F.Cu" "F.Mask" "F.Paste")
			(net "GND")
		)
		(pad "BF27" smd circle
			(at -10.489946 1.97993 180)
			(size 0.450088 0.450088)
			(layers "F.Cu" "F.Mask" "F.Paste")
			(net "PVDDCR_SOC_P1")
		)
		(pad "BF28" smd circle
			(at -9.549892 1.97993 180)
			(size 0.450088 0.450088)
			(layers "F.Cu" "F.Mask" "F.Paste")
			(net "GND")
		)
		(pad "BF48" smd circle
			(at 9.249918 1.97993 180)
			(size 0.450088 0.450088)
			(layers "F.Cu" "F.Mask" "F.Paste")
			(net "PVDDCR_SOC_P1")
		)
		(pad "BF49" smd circle
			(at 10.189972 1.97993 180)
			(size 0.450088 0.450088)
			(layers "F.Cu" "F.Mask" "F.Paste")
			(net "GND")
		)
		(pad "BF50" smd circle
			(at 11.130026 1.97993 180)
			(size 0.450088 0.450088)
			(layers "F.Cu" "F.Mask" "F.Paste")
			(net "GND")
		)
		(pad "BF51" smd circle
			(at 12.07008 1.97993 180)
			(size 0.450088 0.450088)
			(layers "F.Cu" "F.Mask" "F.Paste")
			(net "PVDDIO_P1")
		)
		(pad "BF52" smd circle
			(at 13.00988 1.97993 180)
			(size 0.450088 0.450088)
			(layers "F.Cu" "F.Mask" "F.Paste")
			(net "GND")
		)
		(pad "BF53" smd circle
			(at 13.949934 1.97993 180)
			(size 0.450088 0.450088)
			(layers "F.Cu" "F.Mask" "F.Paste")
			(net "PVDDIO_P1")
		)
		(pad "BF54" smd circle
			(at 14.889988 1.97993 180)
			(size 0.450088 0.450088)
			(layers "F.Cu" "F.Mask" "F.Paste")
			(net "GND")
		)
		(pad "BF55" smd circle
			(at 15.830042 1.97993 180)
			(size 0.450088 0.450088)
			(layers "F.Cu" "F.Mask" "F.Paste")
			(net "TP_M_C_CPU1_SA_TEST39C")
		)
		(pad "BF56" smd circle
			(at 16.770096 1.97993 180)
			(size 0.450088 0.450088)
			(layers "F.Cu" "F.Mask" "F.Paste")
			(net "Net_2006")
		)
		(pad "BF57" smd circle
			(at 17.709896 1.97993 180)
			(size 0.450088 0.450088)
			(layers "F.Cu" "F.Mask" "F.Paste")
			(net "PVDDIO_P1")
		)
		(pad "BF58" smd circle
			(at 18.64995 1.97993 180)
			(size 0.450088 0.450088)
			(layers "F.Cu" "F.Mask" "F.Paste")
			(net "TP_M_D_CPU1_SA_TEST39D")
		)
		(pad "BF59" smd circle
			(at 19.590004 1.97993 180)
			(size 0.450088 0.450088)
			(layers "F.Cu" "F.Mask" "F.Paste")
			(net "GND")
		)
		(pad "BF60" smd circle
			(at 20.530058 1.97993 180)
			(size 0.450088 0.450088)
			(layers "F.Cu" "F.Mask" "F.Paste")
			(net "Net_2014")
		)
		(pad "BF61" smd circle
			(at 21.470112 1.97993 180)
			(size 0.450088 0.450088)
			(layers "F.Cu" "F.Mask" "F.Paste")
			(net "GND")
		)
		(pad "BF62" smd circle
			(at 22.409912 1.97993 180)
			(size 0.450088 0.450088)
			(layers "F.Cu" "F.Mask" "F.Paste")
			(net "TP_M_B_CPU1_SA_TEST39B")
		)
		(pad "BF63" smd circle
			(at 23.349966 1.97993 180)
			(size 0.450088 0.450088)
			(layers "F.Cu" "F.Mask" "F.Paste")
			(net "Net_1998")
		)
		(pad "BF64" smd circle
			(at 24.29002 1.97993 180)
			(size 0.450088 0.450088)
			(layers "F.Cu" "F.Mask" "F.Paste")
			(net "PVDDIO_P1")
		)
		(pad "BF65" smd circle
			(at 25.230074 1.97993 180)
			(size 0.450088 0.450088)
			(layers "F.Cu" "F.Mask" "F.Paste")
			(net "TP_M_F_CPU1_SA_TEST39F")
		)
		(pad "BF66" smd circle
			(at 26.170128 1.97993 180)
			(size 0.450088 0.450088)
			(layers "F.Cu" "F.Mask" "F.Paste")
			(net "GND")
		)
		(pad "BF67" smd circle
			(at 27.109928 1.97993 180)
			(size 0.450088 0.450088)
			(layers "F.Cu" "F.Mask" "F.Paste")
			(net "Net_2030")
		)
		(pad "BF68" smd circle
			(at 28.049982 1.97993 180)
			(size 0.450088 0.450088)
			(layers "F.Cu" "F.Mask" "F.Paste")
			(net "GND")
		)
		(pad "BF69" smd circle
			(at 28.990036 1.97993 180)
			(size 0.450088 0.450088)
			(layers "F.Cu" "F.Mask" "F.Paste")
			(net "TP_M_E_CPU1_SA_TEST39E")
		)
		(pad "BF70" smd circle
			(at 29.93009 1.97993 180)
			(size 0.450088 0.450088)
			(layers "F.Cu" "F.Mask" "F.Paste")
			(net "Net_2022")
		)
		(pad "BF71" smd circle
			(at 30.86989 1.97993 180)
			(size 0.450088 0.450088)
			(layers "F.Cu" "F.Mask" "F.Paste")
			(net "PVDDIO_P1")
		)
		(pad "BF72" smd circle
			(at 31.809944 1.97993 180)
			(size 0.450088 0.450088)
			(layers "F.Cu" "F.Mask" "F.Paste")
			(net "TP_M_A_CPU1_SA_TEST39A")
		)
		(pad "BF73" smd circle
			(at 32.749998 1.97993 180)
			(size 0.450088 0.450088)
			(layers "F.Cu" "F.Mask" "F.Paste")
			(net "GND")
		)
		(pad "BF74" smd circle
			(at 33.690052 1.97993 180)
			(size 0.450088 0.450088)
			(layers "F.Cu" "F.Mask" "F.Paste")
			(net "Net_1990")
		)
		(pad "BG1" smd circle
			(at -34.459926 2.789936 180)
			(size 0.450088 0.450088)
			(layers "F.Cu" "F.Mask" "F.Paste")
			(net "GND")
		)
		(pad "BG2" smd circle
			(at -33.519872 2.789936 180)
			(size 0.450088 0.450088)
			(layers "F.Cu" "F.Mask" "F.Paste")
			(net "Net_2039")
		)
		(pad "BG3" smd circle
			(at -32.580072 2.789936 180)
			(size 0.450088 0.450088)
			(layers "F.Cu" "F.Mask" "F.Paste")
			(net "M_G_CPU1_SB_CA<0>")
		)
		(pad "BG4" smd circle
			(at -31.640018 2.789936 180)
			(size 0.450088 0.450088)
			(layers "F.Cu" "F.Mask" "F.Paste")
			(net "GND")
		)
		(pad "BG5" smd circle
			(at -30.699964 2.789936 180)
			(size 0.450088 0.450088)
			(layers "F.Cu" "F.Mask" "F.Paste")
			(net "Net_2188")
		)
		(pad "BG6" smd circle
			(at -29.75991 2.789936 180)
			(size 0.450088 0.450088)
			(layers "F.Cu" "F.Mask" "F.Paste")
			(net "GND")
		)
		(pad "BG7" smd circle
			(at -28.82011 2.789936 180)
			(size 0.450088 0.450088)
			(layers "F.Cu" "F.Mask" "F.Paste")
			(net "M_K_CPU1_SB_CA<0>")
		)
		(pad "BG8" smd circle
			(at -27.880056 2.789936 180)
			(size 0.450088 0.450088)
			(layers "F.Cu" "F.Mask" "F.Paste")
			(net "GND")
		)
		(pad "BG9" smd circle
			(at -26.940002 2.789936 180)
			(size 0.450088 0.450088)
			(layers "F.Cu" "F.Mask" "F.Paste")
			(net "Net_2180")
		)
		(pad "BG10" smd circle
			(at -25.999948 2.789936 180)
			(size 0.450088 0.450088)
			(layers "F.Cu" "F.Mask" "F.Paste")
			(net "M_L_CPU1_SB_CA<0>")
		)
		(pad "BG11" smd circle
			(at -25.059894 2.789936 180)
			(size 0.450088 0.450088)
			(layers "F.Cu" "F.Mask" "F.Paste")
			(net "GND")
		)
		(pad "BG12" smd circle
			(at -24.120094 2.789936 180)
			(size 0.450088 0.450088)
			(layers "F.Cu" "F.Mask" "F.Paste")
			(net "Net_2047")
		)
		(pad "BG13" smd circle
			(at -23.18004 2.789936 180)
			(size 0.450088 0.450088)
			(layers "F.Cu" "F.Mask" "F.Paste")
			(net "GND")
		)
		(pad "BG14" smd circle
			(at -22.239986 2.789936 180)
			(size 0.450088 0.450088)
			(layers "F.Cu" "F.Mask" "F.Paste")
			(net "M_H_CPU1_SB_CA<0>")
		)
		(pad "BG15" smd circle
			(at -21.299932 2.789936 180)
			(size 0.450088 0.450088)
			(layers "F.Cu" "F.Mask" "F.Paste")
			(net "GND")
		)
		(pad "BG16" smd circle
			(at -20.359878 2.789936 180)
			(size 0.450088 0.450088)
			(layers "F.Cu" "F.Mask" "F.Paste")
			(net "Net_2063")
		)
		(pad "BG17" smd circle
			(at -19.420078 2.789936 180)
			(size 0.450088 0.450088)
			(layers "F.Cu" "F.Mask" "F.Paste")
			(net "M_J_CPU1_SB_CA<0>")
		)
		(pad "BG18" smd circle
			(at -18.480024 2.789936 180)
			(size 0.450088 0.450088)
			(layers "F.Cu" "F.Mask" "F.Paste")
			(net "GND")
		)
		(pad "BG19" smd circle
			(at -17.53997 2.789936 180)
			(size 0.450088 0.450088)
			(layers "F.Cu" "F.Mask" "F.Paste")
			(net "Net_2055")
		)
		(pad "BG20" smd circle
			(at -16.599916 2.789936 180)
			(size 0.450088 0.450088)
			(layers "F.Cu" "F.Mask" "F.Paste")
			(net "GND")
		)
		(pad "BG21" smd circle
			(at -15.660116 2.789936 180)
			(size 0.450088 0.450088)
			(layers "F.Cu" "F.Mask" "F.Paste")
			(net "M_I_CPU1_SB_CA<0>")
		)
		(pad "BG22" smd circle
			(at -14.720062 2.789936 180)
			(size 0.450088 0.450088)
			(layers "F.Cu" "F.Mask" "F.Paste")
			(net "PVDDCR_SOC_P1")
		)
		(pad "BG23" smd circle
			(at -13.780008 2.789936 180)
			(size 0.450088 0.450088)
			(layers "F.Cu" "F.Mask" "F.Paste")
			(net "GND")
		)
		(pad "BG24" smd circle
			(at -12.839954 2.789936 180)
			(size 0.450088 0.450088)
			(layers "F.Cu" "F.Mask" "F.Paste")
			(net "PVDDCR_SOC_P1")
		)
		(pad "BG25" smd circle
			(at -11.8999 2.789936 180)
			(size 0.450088 0.450088)
			(layers "F.Cu" "F.Mask" "F.Paste")
			(net "GND")
		)
		(pad "BG26" smd circle
			(at -10.9601 2.789936 180)
			(size 0.450088 0.450088)
			(layers "F.Cu" "F.Mask" "F.Paste")
			(net "PVDDCR_SOC_P1")
		)
		(pad "BG27" smd circle
			(at -10.020046 2.789936 180)
			(size 0.450088 0.450088)
			(layers "F.Cu" "F.Mask" "F.Paste")
			(net "GND")
		)
		(pad "BG28" smd circle
			(at -9.079992 2.789936 180)
			(size 0.450088 0.450088)
			(layers "F.Cu" "F.Mask" "F.Paste")
			(net "PVDDCR_SOC_P1")
		)
		(pad "BG48" smd circle
			(at 8.780018 2.789936 180)
			(size 0.450088 0.450088)
			(layers "F.Cu" "F.Mask" "F.Paste")
			(net "PVDDCR_SOC_P1")
		)
		(pad "BG49" smd circle
			(at 9.720072 2.789936 180)
			(size 0.450088 0.450088)
			(layers "F.Cu" "F.Mask" "F.Paste")
			(net "GND")
		)
		(pad "BG50" smd circle
			(at 10.659872 2.789936 180)
			(size 0.450088 0.450088)
			(layers "F.Cu" "F.Mask" "F.Paste")
			(net "PVDDIO_P1")
		)
		(pad "BG51" smd circle
			(at 11.599926 2.789936 180)
			(size 0.450088 0.450088)
			(layers "F.Cu" "F.Mask" "F.Paste")
			(net "GND")
		)
		(pad "BG52" smd circle
			(at 12.53998 2.789936 180)
			(size 0.450088 0.450088)
			(layers "F.Cu" "F.Mask" "F.Paste")
			(net "PVDDIO_P1")
		)
		(pad "BG53" smd circle
			(at 13.480034 2.789936 180)
			(size 0.450088 0.450088)
			(layers "F.Cu" "F.Mask" "F.Paste")
			(net "GND")
		)
		(pad "BG54" smd circle
			(at 14.420088 2.789936 180)
			(size 0.450088 0.450088)
			(layers "F.Cu" "F.Mask" "F.Paste")
			(net "PVDDIO_P1")
		)
		(pad "BG55" smd circle
			(at 15.359888 2.789936 180)
			(size 0.450088 0.450088)
			(layers "F.Cu" "F.Mask" "F.Paste")
			(net "M_C_CPU1_SB_CA<0>")
		)
		(pad "BG56" smd circle
			(at 16.299942 2.789936 180)
			(size 0.450088 0.450088)
			(layers "F.Cu" "F.Mask" "F.Paste")
			(net "GND")
		)
		(pad "BG57" smd circle
			(at 17.239996 2.789936 180)
			(size 0.450088 0.450088)
			(layers "F.Cu" "F.Mask" "F.Paste")
			(net "Net_2007")
		)
		(pad "BG58" smd circle
			(at 18.18005 2.789936 180)
			(size 0.450088 0.450088)
			(layers "F.Cu" "F.Mask" "F.Paste")
			(net "GND")
		)
		(pad "BG59" smd circle
			(at 19.120104 2.789936 180)
			(size 0.450088 0.450088)
			(layers "F.Cu" "F.Mask" "F.Paste")
			(net "M_D_CPU1_SB_CA<0>")
		)
		(pad "BG60" smd circle
			(at 20.059904 2.789936 180)
			(size 0.450088 0.450088)
			(layers "F.Cu" "F.Mask" "F.Paste")
			(net "Net_2015")
		)
		(pad "BG61" smd circle
			(at 20.999958 2.789936 180)
			(size 0.450088 0.450088)
			(layers "F.Cu" "F.Mask" "F.Paste")
			(net "GND")
		)
		(pad "BG62" smd circle
			(at 21.940012 2.789936 180)
			(size 0.450088 0.450088)
			(layers "F.Cu" "F.Mask" "F.Paste")
			(net "M_B_CPU1_SB_CA<0>")
		)
		(pad "BG63" smd circle
			(at 22.880066 2.789936 180)
			(size 0.450088 0.450088)
			(layers "F.Cu" "F.Mask" "F.Paste")
			(net "GND")
		)
		(pad "BG64" smd circle
			(at 23.82012 2.789936 180)
			(size 0.450088 0.450088)
			(layers "F.Cu" "F.Mask" "F.Paste")
			(net "Net_1999")
		)
		(pad "BG65" smd circle
			(at 24.75992 2.789936 180)
			(size 0.450088 0.450088)
			(layers "F.Cu" "F.Mask" "F.Paste")
			(net "GND")
		)
		(pad "BG66" smd circle
			(at 25.699974 2.789936 180)
			(size 0.450088 0.450088)
			(layers "F.Cu" "F.Mask" "F.Paste")
			(net "M_F_CPU1_SB_CA<0>")
		)
		(pad "BG67" smd circle
			(at 26.640028 2.789936 180)
			(size 0.450088 0.450088)
			(layers "F.Cu" "F.Mask" "F.Paste")
			(net "Net_2031")
		)
		(pad "BG68" smd circle
			(at 27.580082 2.789936 180)
			(size 0.450088 0.450088)
			(layers "F.Cu" "F.Mask" "F.Paste")
			(net "GND")
		)
		(pad "BG69" smd circle
			(at 28.519882 2.789936 180)
			(size 0.450088 0.450088)
			(layers "F.Cu" "F.Mask" "F.Paste")
			(net "M_E_CPU1_SB_CA<0>")
		)
		(pad "BG70" smd circle
			(at 29.459936 2.789936 180)
			(size 0.450088 0.450088)
			(layers "F.Cu" "F.Mask" "F.Paste")
			(net "GND")
		)
		(pad "BG71" smd circle
			(at 30.39999 2.789936 180)
			(size 0.450088 0.450088)
			(layers "F.Cu" "F.Mask" "F.Paste")
			(net "Net_2023")
		)
		(pad "BG72" smd circle
			(at 31.340044 2.789936 180)
			(size 0.450088 0.450088)
			(layers "F.Cu" "F.Mask" "F.Paste")
			(net "GND")
		)
		(pad "BG73" smd circle
			(at 32.280098 2.789936 180)
			(size 0.450088 0.450088)
			(layers "F.Cu" "F.Mask" "F.Paste")
			(net "M_A_CPU1_SB_CA<0>")
		)
		(pad "BG74" smd circle
			(at 33.219898 2.789936 180)
			(size 0.450088 0.450088)
			(layers "F.Cu" "F.Mask" "F.Paste")
			(net "Net_1991")
		)
		(pad "BG75" smd circle
			(at 34.159952 2.789936 180)
			(size 0.450088 0.450088)
			(layers "F.Cu" "F.Mask" "F.Paste")
			(net "GND")
		)
		(pad "BH2" smd circle
			(at -33.990026 3.599942 180)
			(size 0.450088 0.450088)
			(layers "F.Cu" "F.Mask" "F.Paste")
			(net "M_G_CPU1_SB_CA<2>")
		)
		(pad "BH3" smd circle
			(at -33.049972 3.599942 180)
			(size 0.450088 0.450088)
			(layers "F.Cu" "F.Mask" "F.Paste")
			(net "GND")
		)
		(pad "BH4" smd circle
			(at -32.109918 3.599942 180)
			(size 0.450088 0.450088)
			(layers "F.Cu" "F.Mask" "F.Paste")
			(net "M_G_CPU1_SB_CA<1>")
		)
		(pad "BH5" smd circle
			(at -31.170118 3.599942 180)
			(size 0.450088 0.450088)
			(layers "F.Cu" "F.Mask" "F.Paste")
			(net "GND")
		)
		(pad "BH6" smd circle
			(at -30.230064 3.599942 180)
			(size 0.450088 0.450088)
			(layers "F.Cu" "F.Mask" "F.Paste")
			(net "M_K_CPU1_SB_CA<2>")
		)
		(pad "BH7" smd circle
			(at -29.29001 3.599942 180)
			(size 0.450088 0.450088)
			(layers "F.Cu" "F.Mask" "F.Paste")
			(net "M_K_CPU1_SB_CA<1>")
		)
		(pad "BH8" smd circle
			(at -28.349956 3.599942 180)
			(size 0.450088 0.450088)
			(layers "F.Cu" "F.Mask" "F.Paste")
			(net "GND")
		)
		(pad "BH9" smd circle
			(at -27.409902 3.599942 180)
			(size 0.450088 0.450088)
			(layers "F.Cu" "F.Mask" "F.Paste")
			(net "M_L_CPU1_SB_CA<2>")
		)
		(pad "BH10" smd circle
			(at -26.470102 3.599942 180)
			(size 0.450088 0.450088)
			(layers "F.Cu" "F.Mask" "F.Paste")
			(net "GND")
		)
		(pad "BH11" smd circle
			(at -25.530048 3.599942 180)
			(size 0.450088 0.450088)
			(layers "F.Cu" "F.Mask" "F.Paste")
			(net "M_L_CPU1_SB_CA<1>")
		)
		(pad "BH12" smd circle
			(at -24.589994 3.599942 180)
			(size 0.450088 0.450088)
			(layers "F.Cu" "F.Mask" "F.Paste")
			(net "GND")
		)
		(pad "BH13" smd circle
			(at -23.64994 3.599942 180)
			(size 0.450088 0.450088)
			(layers "F.Cu" "F.Mask" "F.Paste")
			(net "M_H_CPU1_SB_CA<2>")
		)
		(pad "BH14" smd circle
			(at -22.709886 3.599942 180)
			(size 0.450088 0.450088)
			(layers "F.Cu" "F.Mask" "F.Paste")
			(net "M_H_CPU1_SB_CA<1>")
		)
		(pad "BH15" smd circle
			(at -21.770086 3.599942 180)
			(size 0.450088 0.450088)
			(layers "F.Cu" "F.Mask" "F.Paste")
			(net "GND")
		)
		(pad "BH16" smd circle
			(at -20.830032 3.599942 180)
			(size 0.450088 0.450088)
			(layers "F.Cu" "F.Mask" "F.Paste")
			(net "M_J_CPU1_SB_CA<2>")
		)
		(pad "BH17" smd circle
			(at -19.889978 3.599942 180)
			(size 0.450088 0.450088)
			(layers "F.Cu" "F.Mask" "F.Paste")
			(net "GND")
		)
		(pad "BH18" smd circle
			(at -18.949924 3.599942 180)
			(size 0.450088 0.450088)
			(layers "F.Cu" "F.Mask" "F.Paste")
			(net "M_J_CPU1_SB_CA<1>")
		)
		(pad "BH19" smd circle
			(at -18.010124 3.599942 180)
			(size 0.450088 0.450088)
			(layers "F.Cu" "F.Mask" "F.Paste")
			(net "GND")
		)
		(pad "BH20" smd circle
			(at -17.07007 3.599942 180)
			(size 0.450088 0.450088)
			(layers "F.Cu" "F.Mask" "F.Paste")
			(net "M_I_CPU1_SB_CA<2>")
		)
		(pad "BH21" smd circle
			(at -16.130016 3.599942 180)
			(size 0.450088 0.450088)
			(layers "F.Cu" "F.Mask" "F.Paste")
			(net "M_I_CPU1_SB_CA<1>")
		)
		(pad "BH22" smd circle
			(at -15.189962 3.599942 180)
			(size 0.450088 0.450088)
			(layers "F.Cu" "F.Mask" "F.Paste")
			(net "GND")
		)
		(pad "BH23" smd circle
			(at -14.249908 3.599942 180)
			(size 0.450088 0.450088)
			(layers "F.Cu" "F.Mask" "F.Paste")
			(net "PVDDCR_SOC_P1")
		)
		(pad "BH24" smd circle
			(at -13.310108 3.599942 180)
			(size 0.450088 0.450088)
			(layers "F.Cu" "F.Mask" "F.Paste")
			(net "GND")
		)
		(pad "BH25" smd circle
			(at -12.370054 3.599942 180)
			(size 0.450088 0.450088)
			(layers "F.Cu" "F.Mask" "F.Paste")
			(net "PVDDCR_SOC_P1")
		)
		(pad "BH26" smd circle
			(at -11.43 3.599942 180)
			(size 0.450088 0.450088)
			(layers "F.Cu" "F.Mask" "F.Paste")
			(net "GND")
		)
		(pad "BH27" smd circle
			(at -10.489946 3.599942 180)
			(size 0.450088 0.450088)
			(layers "F.Cu" "F.Mask" "F.Paste")
			(net "PVDD18_S5_P1")
		)
		(pad "BH28" smd circle
			(at -9.549892 3.599942 180)
			(size 0.450088 0.450088)
			(layers "F.Cu" "F.Mask" "F.Paste")
			(net "GND")
		)
		(pad "BH48" smd circle
			(at 9.249918 3.599942 180)
			(size 0.450088 0.450088)
			(layers "F.Cu" "F.Mask" "F.Paste")
			(net "PVDDCR_SOC_P1")
		)
		(pad "BH49" smd circle
			(at 10.189972 3.599942 180)
			(size 0.450088 0.450088)
			(layers "F.Cu" "F.Mask" "F.Paste")
			(net "GND")
		)
		(pad "BH50" smd circle
			(at 11.130026 3.599942 180)
			(size 0.450088 0.450088)
			(layers "F.Cu" "F.Mask" "F.Paste")
			(net "GND")
		)
		(pad "BH51" smd circle
			(at 12.07008 3.599942 180)
			(size 0.450088 0.450088)
			(layers "F.Cu" "F.Mask" "F.Paste")
			(net "PVDDIO_P1")
		)
		(pad "BH52" smd circle
			(at 13.00988 3.599942 180)
			(size 0.450088 0.450088)
			(layers "F.Cu" "F.Mask" "F.Paste")
			(net "GND")
		)
		(pad "BH53" smd circle
			(at 13.949934 3.599942 180)
			(size 0.450088 0.450088)
			(layers "F.Cu" "F.Mask" "F.Paste")
			(net "PVDDIO_P1")
		)
		(pad "BH54" smd circle
			(at 14.889988 3.599942 180)
			(size 0.450088 0.450088)
			(layers "F.Cu" "F.Mask" "F.Paste")
			(net "GND")
		)
		(pad "BH55" smd circle
			(at 15.830042 3.599942 180)
			(size 0.450088 0.450088)
			(layers "F.Cu" "F.Mask" "F.Paste")
			(net "M_C_CPU1_SB_CA<1>")
		)
		(pad "BH56" smd circle
			(at 16.770096 3.599942 180)
			(size 0.450088 0.450088)
			(layers "F.Cu" "F.Mask" "F.Paste")
			(net "M_C_CPU1_SB_CA<2>")
		)
		(pad "BH57" smd circle
			(at 17.709896 3.599942 180)
			(size 0.450088 0.450088)
			(layers "F.Cu" "F.Mask" "F.Paste")
			(net "GND")
		)
		(pad "BH58" smd circle
			(at 18.64995 3.599942 180)
			(size 0.450088 0.450088)
			(layers "F.Cu" "F.Mask" "F.Paste")
			(net "M_D_CPU1_SB_CA<1>")
		)
		(pad "BH59" smd circle
			(at 19.590004 3.599942 180)
			(size 0.450088 0.450088)
			(layers "F.Cu" "F.Mask" "F.Paste")
			(net "GND")
		)
		(pad "BH60" smd circle
			(at 20.530058 3.599942 180)
			(size 0.450088 0.450088)
			(layers "F.Cu" "F.Mask" "F.Paste")
			(net "M_D_CPU1_SB_CA<2>")
		)
		(pad "BH61" smd circle
			(at 21.470112 3.599942 180)
			(size 0.450088 0.450088)
			(layers "F.Cu" "F.Mask" "F.Paste")
			(net "GND")
		)
		(pad "BH62" smd circle
			(at 22.409912 3.599942 180)
			(size 0.450088 0.450088)
			(layers "F.Cu" "F.Mask" "F.Paste")
			(net "M_B_CPU1_SB_CA<1>")
		)
		(pad "BH63" smd circle
			(at 23.349966 3.599942 180)
			(size 0.450088 0.450088)
			(layers "F.Cu" "F.Mask" "F.Paste")
			(net "M_B_CPU1_SB_CA<2>")
		)
		(pad "BH64" smd circle
			(at 24.29002 3.599942 180)
			(size 0.450088 0.450088)
			(layers "F.Cu" "F.Mask" "F.Paste")
			(net "GND")
		)
		(pad "BH65" smd circle
			(at 25.230074 3.599942 180)
			(size 0.450088 0.450088)
			(layers "F.Cu" "F.Mask" "F.Paste")
			(net "M_F_CPU1_SB_CA<1>")
		)
		(pad "BH66" smd circle
			(at 26.170128 3.599942 180)
			(size 0.450088 0.450088)
			(layers "F.Cu" "F.Mask" "F.Paste")
			(net "GND")
		)
		(pad "BH67" smd circle
			(at 27.109928 3.599942 180)
			(size 0.450088 0.450088)
			(layers "F.Cu" "F.Mask" "F.Paste")
			(net "M_F_CPU1_SB_CA<2>")
		)
		(pad "BH68" smd circle
			(at 28.049982 3.599942 180)
			(size 0.450088 0.450088)
			(layers "F.Cu" "F.Mask" "F.Paste")
			(net "GND")
		)
		(pad "BH69" smd circle
			(at 28.990036 3.599942 180)
			(size 0.450088 0.450088)
			(layers "F.Cu" "F.Mask" "F.Paste")
			(net "M_E_CPU1_SB_CA<1>")
		)
		(pad "BH70" smd circle
			(at 29.93009 3.599942 180)
			(size 0.450088 0.450088)
			(layers "F.Cu" "F.Mask" "F.Paste")
			(net "M_E_CPU1_SB_CA<2>")
		)
		(pad "BH71" smd circle
			(at 30.86989 3.599942 180)
			(size 0.450088 0.450088)
			(layers "F.Cu" "F.Mask" "F.Paste")
			(net "GND")
		)
		(pad "BH72" smd circle
			(at 31.809944 3.599942 180)
			(size 0.450088 0.450088)
			(layers "F.Cu" "F.Mask" "F.Paste")
			(net "M_A_CPU1_SB_CA<1>")
		)
		(pad "BH73" smd circle
			(at 32.749998 3.599942 180)
			(size 0.450088 0.450088)
			(layers "F.Cu" "F.Mask" "F.Paste")
			(net "GND")
		)
		(pad "BH74" smd circle
			(at 33.690052 3.599942 180)
			(size 0.450088 0.450088)
			(layers "F.Cu" "F.Mask" "F.Paste")
			(net "M_A_CPU1_SB_CA<2>")
		)
		(pad "BJ1" smd circle
			(at -34.459926 4.409948 180)
			(size 0.450088 0.450088)
			(layers "F.Cu" "F.Mask" "F.Paste")
			(net "GND")
		)
		(pad "BJ2" smd circle
			(at -33.519872 4.409948 180)
			(size 0.450088 0.450088)
			(layers "F.Cu" "F.Mask" "F.Paste")
			(net "M_G_CPU1_SB_CA<3>")
		)
		(pad "BJ3" smd circle
			(at -32.580072 4.409948 180)
			(size 0.450088 0.450088)
			(layers "F.Cu" "F.Mask" "F.Paste")
			(net "M_G_CPU1_SB_CA<4>")
		)
		(pad "BJ4" smd circle
			(at -31.640018 4.409948 180)
			(size 0.450088 0.450088)
			(layers "F.Cu" "F.Mask" "F.Paste")
			(net "PVDDCR_SOC_P1")
		)
		(pad "BJ5" smd circle
			(at -30.699964 4.409948 180)
			(size 0.450088 0.450088)
			(layers "F.Cu" "F.Mask" "F.Paste")
			(net "M_K_CPU1_SB_CA<3>")
		)
		(pad "BJ6" smd circle
			(at -29.75991 4.409948 180)
			(size 0.450088 0.450088)
			(layers "F.Cu" "F.Mask" "F.Paste")
			(net "GND")
		)
		(pad "BJ7" smd circle
			(at -28.82011 4.409948 180)
			(size 0.450088 0.450088)
			(layers "F.Cu" "F.Mask" "F.Paste")
			(net "M_K_CPU1_SB_CA<4>")
		)
		(pad "BJ8" smd circle
			(at -27.880056 4.409948 180)
			(size 0.450088 0.450088)
			(layers "F.Cu" "F.Mask" "F.Paste")
			(net "GND")
		)
		(pad "BJ9" smd circle
			(at -26.940002 4.409948 180)
			(size 0.450088 0.450088)
			(layers "F.Cu" "F.Mask" "F.Paste")
			(net "M_L_CPU1_SB_CA<3>")
		)
		(pad "BJ10" smd circle
			(at -25.999948 4.409948 180)
			(size 0.450088 0.450088)
			(layers "F.Cu" "F.Mask" "F.Paste")
			(net "M_L_CPU1_SB_CA<4>")
		)
		(pad "BJ11" smd circle
			(at -25.059894 4.409948 180)
			(size 0.450088 0.450088)
			(layers "F.Cu" "F.Mask" "F.Paste")
			(net "PVDDCR_SOC_P1")
		)
		(pad "BJ12" smd circle
			(at -24.120094 4.409948 180)
			(size 0.450088 0.450088)
			(layers "F.Cu" "F.Mask" "F.Paste")
			(net "M_H_CPU1_SB_CA<3>")
		)
		(pad "BJ13" smd circle
			(at -23.18004 4.409948 180)
			(size 0.450088 0.450088)
			(layers "F.Cu" "F.Mask" "F.Paste")
			(net "GND")
		)
		(pad "BJ14" smd circle
			(at -22.239986 4.409948 180)
			(size 0.450088 0.450088)
			(layers "F.Cu" "F.Mask" "F.Paste")
			(net "M_H_CPU1_SB_CA<4>")
		)
		(pad "BJ15" smd circle
			(at -21.299932 4.409948 180)
			(size 0.450088 0.450088)
			(layers "F.Cu" "F.Mask" "F.Paste")
			(net "GND")
		)
		(pad "BJ16" smd circle
			(at -20.359878 4.409948 180)
			(size 0.450088 0.450088)
			(layers "F.Cu" "F.Mask" "F.Paste")
			(net "M_J_CPU1_SB_CA<3>")
		)
		(pad "BJ17" smd circle
			(at -19.420078 4.409948 180)
			(size 0.450088 0.450088)
			(layers "F.Cu" "F.Mask" "F.Paste")
			(net "M_J_CPU1_SB_CA<4>")
		)
		(pad "BJ18" smd circle
			(at -18.480024 4.409948 180)
			(size 0.450088 0.450088)
			(layers "F.Cu" "F.Mask" "F.Paste")
			(net "PVDD11_S3_P1")
		)
		(pad "BJ19" smd circle
			(at -17.53997 4.409948 180)
			(size 0.450088 0.450088)
			(layers "F.Cu" "F.Mask" "F.Paste")
			(net "M_I_CPU1_SB_CA<3>")
		)
		(pad "BJ20" smd circle
			(at -16.599916 4.409948 180)
			(size 0.450088 0.450088)
			(layers "F.Cu" "F.Mask" "F.Paste")
			(net "GND")
		)
		(pad "BJ21" smd circle
			(at -15.660116 4.409948 180)
			(size 0.450088 0.450088)
			(layers "F.Cu" "F.Mask" "F.Paste")
			(net "M_I_CPU1_SB_CA<4>")
		)
		(pad "BJ22" smd circle
			(at -14.720062 4.409948 180)
			(size 0.450088 0.450088)
			(layers "F.Cu" "F.Mask" "F.Paste")
			(net "GND")
		)
		(pad "BJ23" smd circle
			(at -13.780008 4.409948 180)
			(size 0.450088 0.450088)
			(layers "F.Cu" "F.Mask" "F.Paste")
			(net "PVDD11_S3_P1")
		)
		(pad "BJ24" smd circle
			(at -12.839954 4.409948 180)
			(size 0.450088 0.450088)
			(layers "F.Cu" "F.Mask" "F.Paste")
			(net "GND")
		)
		(pad "BJ25" smd circle
			(at -11.8999 4.409948 180)
			(size 0.450088 0.450088)
			(layers "F.Cu" "F.Mask" "F.Paste")
			(net "PVDD11_S3_P1")
		)
		(pad "BJ26" smd circle
			(at -10.9601 4.409948 180)
			(size 0.450088 0.450088)
			(layers "F.Cu" "F.Mask" "F.Paste")
			(net "GND")
		)
		(pad "BJ27" smd circle
			(at -10.020046 4.409948 180)
			(size 0.450088 0.450088)
			(layers "F.Cu" "F.Mask" "F.Paste")
			(net "PVDD11_S3_P1")
		)
		(pad "BJ28" smd circle
			(at -9.079992 4.409948 180)
			(size 0.450088 0.450088)
			(layers "F.Cu" "F.Mask" "F.Paste")
			(net "GND")
		)
		(pad "BJ48" smd circle
			(at 8.780018 4.409948 180)
			(size 0.450088 0.450088)
			(layers "F.Cu" "F.Mask" "F.Paste")
			(net "PVDDCR_SOC_P1")
		)
		(pad "BJ49" smd circle
			(at 9.720072 4.409948 180)
			(size 0.450088 0.450088)
			(layers "F.Cu" "F.Mask" "F.Paste")
			(net "GND")
		)
		(pad "BJ50" smd circle
			(at 10.659872 4.409948 180)
			(size 0.450088 0.450088)
			(layers "F.Cu" "F.Mask" "F.Paste")
			(net "PVDDIO_P1")
		)
		(pad "BJ51" smd circle
			(at 11.599926 4.409948 180)
			(size 0.450088 0.450088)
			(layers "F.Cu" "F.Mask" "F.Paste")
			(net "GND")
		)
		(pad "BJ52" smd circle
			(at 12.53998 4.409948 180)
			(size 0.450088 0.450088)
			(layers "F.Cu" "F.Mask" "F.Paste")
			(net "PVDDIO_P1")
		)
		(pad "BJ53" smd circle
			(at 13.480034 4.409948 180)
			(size 0.450088 0.450088)
			(layers "F.Cu" "F.Mask" "F.Paste")
			(net "GND")
		)
		(pad "BJ54" smd circle
			(at 14.420088 4.409948 180)
			(size 0.450088 0.450088)
			(layers "F.Cu" "F.Mask" "F.Paste")
			(net "PVDDIO_P1")
		)
		(pad "BJ55" smd circle
			(at 15.359888 4.409948 180)
			(size 0.450088 0.450088)
			(layers "F.Cu" "F.Mask" "F.Paste")
			(net "M_C_CPU1_SB_CA<4>")
		)
		(pad "BJ56" smd circle
			(at 16.299942 4.409948 180)
			(size 0.450088 0.450088)
			(layers "F.Cu" "F.Mask" "F.Paste")
			(net "GND")
		)
		(pad "BJ57" smd circle
			(at 17.239996 4.409948 180)
			(size 0.450088 0.450088)
			(layers "F.Cu" "F.Mask" "F.Paste")
			(net "M_C_CPU1_SB_CA<3>")
		)
		(pad "BJ58" smd circle
			(at 18.18005 4.409948 180)
			(size 0.450088 0.450088)
			(layers "F.Cu" "F.Mask" "F.Paste")
			(net "PVDDIO_P1")
		)
		(pad "BJ59" smd circle
			(at 19.120104 4.409948 180)
			(size 0.450088 0.450088)
			(layers "F.Cu" "F.Mask" "F.Paste")
			(net "M_D_CPU1_SB_CA<4>")
		)
		(pad "BJ60" smd circle
			(at 20.059904 4.409948 180)
			(size 0.450088 0.450088)
			(layers "F.Cu" "F.Mask" "F.Paste")
			(net "M_D_CPU1_SB_CA<3>")
		)
		(pad "BJ61" smd circle
			(at 20.999958 4.409948 180)
			(size 0.450088 0.450088)
			(layers "F.Cu" "F.Mask" "F.Paste")
			(net "GND")
		)
		(pad "BJ62" smd circle
			(at 21.940012 4.409948 180)
			(size 0.450088 0.450088)
			(layers "F.Cu" "F.Mask" "F.Paste")
			(net "M_B_CPU1_SB_CA<4>")
		)
		(pad "BJ63" smd circle
			(at 22.880066 4.409948 180)
			(size 0.450088 0.450088)
			(layers "F.Cu" "F.Mask" "F.Paste")
			(net "GND")
		)
		(pad "BJ64" smd circle
			(at 23.82012 4.409948 180)
			(size 0.450088 0.450088)
			(layers "F.Cu" "F.Mask" "F.Paste")
			(net "M_B_CPU1_SB_CA<3>")
		)
		(pad "BJ65" smd circle
			(at 24.75992 4.409948 180)
			(size 0.450088 0.450088)
			(layers "F.Cu" "F.Mask" "F.Paste")
			(net "PVDDIO_P1")
		)
		(pad "BJ66" smd circle
			(at 25.699974 4.409948 180)
			(size 0.450088 0.450088)
			(layers "F.Cu" "F.Mask" "F.Paste")
			(net "M_F_CPU1_SB_CA<4>")
		)
		(pad "BJ67" smd circle
			(at 26.640028 4.409948 180)
			(size 0.450088 0.450088)
			(layers "F.Cu" "F.Mask" "F.Paste")
			(net "M_F_CPU1_SB_CA<3>")
		)
		(pad "BJ68" smd circle
			(at 27.580082 4.409948 180)
			(size 0.450088 0.450088)
			(layers "F.Cu" "F.Mask" "F.Paste")
			(net "GND")
		)
		(pad "BJ69" smd circle
			(at 28.519882 4.409948 180)
			(size 0.450088 0.450088)
			(layers "F.Cu" "F.Mask" "F.Paste")
			(net "M_E_CPU1_SB_CA<4>")
		)
		(pad "BJ70" smd circle
			(at 29.459936 4.409948 180)
			(size 0.450088 0.450088)
			(layers "F.Cu" "F.Mask" "F.Paste")
			(net "GND")
		)
		(pad "BJ71" smd circle
			(at 30.39999 4.409948 180)
			(size 0.450088 0.450088)
			(layers "F.Cu" "F.Mask" "F.Paste")
			(net "M_E_CPU1_SB_CA<3>")
		)
		(pad "BJ72" smd circle
			(at 31.340044 4.409948 180)
			(size 0.450088 0.450088)
			(layers "F.Cu" "F.Mask" "F.Paste")
			(net "PVDDIO_P1")
		)
		(pad "BJ73" smd circle
			(at 32.280098 4.409948 180)
			(size 0.450088 0.450088)
			(layers "F.Cu" "F.Mask" "F.Paste")
			(net "M_A_CPU1_SB_CA<4>")
		)
		(pad "BJ74" smd circle
			(at 33.219898 4.409948 180)
			(size 0.450088 0.450088)
			(layers "F.Cu" "F.Mask" "F.Paste")
			(net "M_A_CPU1_SB_CA<3>")
		)
		(pad "BJ75" smd circle
			(at 34.159952 4.409948 180)
			(size 0.450088 0.450088)
			(layers "F.Cu" "F.Mask" "F.Paste")
			(net "GND")
		)
		(pad "BK2" smd circle
			(at -33.990026 5.219954 180)
			(size 0.450088 0.450088)
			(layers "F.Cu" "F.Mask" "F.Paste")
			(net "M_G_CPU1_SB_CA<6>")
		)
		(pad "BK3" smd circle
			(at -33.049972 5.219954 180)
			(size 0.450088 0.450088)
			(layers "F.Cu" "F.Mask" "F.Paste")
			(net "GND")
		)
		(pad "BK4" smd circle
			(at -32.109918 5.219954 180)
			(size 0.450088 0.450088)
			(layers "F.Cu" "F.Mask" "F.Paste")
			(net "M_G_CPU1_SB_CA<5>")
		)
		(pad "BK5" smd circle
			(at -31.170118 5.219954 180)
			(size 0.450088 0.450088)
			(layers "F.Cu" "F.Mask" "F.Paste")
			(net "GND")
		)
		(pad "BK6" smd circle
			(at -30.230064 5.219954 180)
			(size 0.450088 0.450088)
			(layers "F.Cu" "F.Mask" "F.Paste")
			(net "M_K_CPU1_SB_CA<6>")
		)
		(pad "BK7" smd circle
			(at -29.29001 5.219954 180)
			(size 0.450088 0.450088)
			(layers "F.Cu" "F.Mask" "F.Paste")
			(net "M_K_CPU1_SB_CA<5>")
		)
		(pad "BK8" smd circle
			(at -28.349956 5.219954 180)
			(size 0.450088 0.450088)
			(layers "F.Cu" "F.Mask" "F.Paste")
			(net "GND")
		)
		(pad "BK9" smd circle
			(at -27.409902 5.219954 180)
			(size 0.450088 0.450088)
			(layers "F.Cu" "F.Mask" "F.Paste")
			(net "M_L_CPU1_SB_CA<6>")
		)
		(pad "BK10" smd circle
			(at -26.470102 5.219954 180)
			(size 0.450088 0.450088)
			(layers "F.Cu" "F.Mask" "F.Paste")
			(net "GND")
		)
		(pad "BK11" smd circle
			(at -25.530048 5.219954 180)
			(size 0.450088 0.450088)
			(layers "F.Cu" "F.Mask" "F.Paste")
			(net "M_L_CPU1_SB_CA<5>")
		)
		(pad "BK12" smd circle
			(at -24.589994 5.219954 180)
			(size 0.450088 0.450088)
			(layers "F.Cu" "F.Mask" "F.Paste")
			(net "GND")
		)
		(pad "BK13" smd circle
			(at -23.64994 5.219954 180)
			(size 0.450088 0.450088)
			(layers "F.Cu" "F.Mask" "F.Paste")
			(net "M_H_CPU1_SB_CA<6>")
		)
		(pad "BK14" smd circle
			(at -22.709886 5.219954 180)
			(size 0.450088 0.450088)
			(layers "F.Cu" "F.Mask" "F.Paste")
			(net "M_H_CPU1_SB_CA<5>")
		)
		(pad "BK15" smd circle
			(at -21.770086 5.219954 180)
			(size 0.450088 0.450088)
			(layers "F.Cu" "F.Mask" "F.Paste")
			(net "GND")
		)
		(pad "BK16" smd circle
			(at -20.830032 5.219954 180)
			(size 0.450088 0.450088)
			(layers "F.Cu" "F.Mask" "F.Paste")
			(net "M_J_CPU1_SB_CA<6>")
		)
		(pad "BK17" smd circle
			(at -19.889978 5.219954 180)
			(size 0.450088 0.450088)
			(layers "F.Cu" "F.Mask" "F.Paste")
			(net "GND")
		)
		(pad "BK18" smd circle
			(at -18.949924 5.219954 180)
			(size 0.450088 0.450088)
			(layers "F.Cu" "F.Mask" "F.Paste")
			(net "M_J_CPU1_SB_CA<5>")
		)
		(pad "BK19" smd circle
			(at -18.010124 5.219954 180)
			(size 0.450088 0.450088)
			(layers "F.Cu" "F.Mask" "F.Paste")
			(net "GND")
		)
		(pad "BK20" smd circle
			(at -17.07007 5.219954 180)
			(size 0.450088 0.450088)
			(layers "F.Cu" "F.Mask" "F.Paste")
			(net "M_I_CPU1_SB_CA<6>")
		)
		(pad "BK21" smd circle
			(at -16.130016 5.219954 180)
			(size 0.450088 0.450088)
			(layers "F.Cu" "F.Mask" "F.Paste")
			(net "M_I_CPU1_SB_CA<5>")
		)
		(pad "BK22" smd circle
			(at -15.189962 5.219954 180)
			(size 0.450088 0.450088)
			(layers "F.Cu" "F.Mask" "F.Paste")
			(net "PVDD11_S3_P1")
		)
		(pad "BK23" smd circle
			(at -14.249908 5.219954 180)
			(size 0.450088 0.450088)
			(layers "F.Cu" "F.Mask" "F.Paste")
			(net "GND")
		)
		(pad "BK24" smd circle
			(at -13.310108 5.219954 180)
			(size 0.450088 0.450088)
			(layers "F.Cu" "F.Mask" "F.Paste")
			(net "PVDD11_S3_P1")
		)
		(pad "BK25" smd circle
			(at -12.370054 5.219954 180)
			(size 0.450088 0.450088)
			(layers "F.Cu" "F.Mask" "F.Paste")
			(net "GND")
		)
		(pad "BK26" smd circle
			(at -11.43 5.219954 180)
			(size 0.450088 0.450088)
			(layers "F.Cu" "F.Mask" "F.Paste")
			(net "PVDD11_S3_P1")
		)
		(pad "BK27" smd circle
			(at -10.489946 5.219954 180)
			(size 0.450088 0.450088)
			(layers "F.Cu" "F.Mask" "F.Paste")
			(net "GND")
		)
		(pad "BK28" smd circle
			(at -9.549892 5.219954 180)
			(size 0.450088 0.450088)
			(layers "F.Cu" "F.Mask" "F.Paste")
			(net "PVDD11_S3_P1")
		)
		(pad "BK48" smd circle
			(at 9.249918 5.219954 180)
			(size 0.450088 0.450088)
			(layers "F.Cu" "F.Mask" "F.Paste")
			(net "GND")
		)
		(pad "BK49" smd circle
			(at 10.189972 5.219954 180)
			(size 0.450088 0.450088)
			(layers "F.Cu" "F.Mask" "F.Paste")
			(net "PVDD11_S3_P1")
		)
		(pad "BK50" smd circle
			(at 11.130026 5.219954 180)
			(size 0.450088 0.450088)
			(layers "F.Cu" "F.Mask" "F.Paste")
			(net "GND")
		)
		(pad "BK51" smd circle
			(at 12.07008 5.219954 180)
			(size 0.450088 0.450088)
			(layers "F.Cu" "F.Mask" "F.Paste")
			(net "PVDDIO_P1")
		)
		(pad "BK52" smd circle
			(at 13.00988 5.219954 180)
			(size 0.450088 0.450088)
			(layers "F.Cu" "F.Mask" "F.Paste")
			(net "GND")
		)
		(pad "BK53" smd circle
			(at 13.949934 5.219954 180)
			(size 0.450088 0.450088)
			(layers "F.Cu" "F.Mask" "F.Paste")
			(net "PVDDIO_P1")
		)
		(pad "BK54" smd circle
			(at 14.889988 5.219954 180)
			(size 0.450088 0.450088)
			(layers "F.Cu" "F.Mask" "F.Paste")
			(net "GND")
		)
		(pad "BK55" smd circle
			(at 15.830042 5.219954 180)
			(size 0.450088 0.450088)
			(layers "F.Cu" "F.Mask" "F.Paste")
			(net "M_C_CPU1_SB_CA<5>")
		)
		(pad "BK56" smd circle
			(at 16.770096 5.219954 180)
			(size 0.450088 0.450088)
			(layers "F.Cu" "F.Mask" "F.Paste")
			(net "M_C_CPU1_SB_CA<6>")
		)
		(pad "BK57" smd circle
			(at 17.709896 5.219954 180)
			(size 0.450088 0.450088)
			(layers "F.Cu" "F.Mask" "F.Paste")
			(net "GND")
		)
		(pad "BK58" smd circle
			(at 18.64995 5.219954 180)
			(size 0.450088 0.450088)
			(layers "F.Cu" "F.Mask" "F.Paste")
			(net "M_D_CPU1_SB_CA<5>")
		)
		(pad "BK59" smd circle
			(at 19.590004 5.219954 180)
			(size 0.450088 0.450088)
			(layers "F.Cu" "F.Mask" "F.Paste")
			(net "GND")
		)
		(pad "BK60" smd circle
			(at 20.530058 5.219954 180)
			(size 0.450088 0.450088)
			(layers "F.Cu" "F.Mask" "F.Paste")
			(net "M_D_CPU1_SB_CA<6>")
		)
		(pad "BK61" smd circle
			(at 21.470112 5.219954 180)
			(size 0.450088 0.450088)
			(layers "F.Cu" "F.Mask" "F.Paste")
			(net "GND")
		)
		(pad "BK62" smd circle
			(at 22.409912 5.219954 180)
			(size 0.450088 0.450088)
			(layers "F.Cu" "F.Mask" "F.Paste")
			(net "M_B_CPU1_SB_CA<5>")
		)
		(pad "BK63" smd circle
			(at 23.349966 5.219954 180)
			(size 0.450088 0.450088)
			(layers "F.Cu" "F.Mask" "F.Paste")
			(net "M_B_CPU1_SB_CA<6>")
		)
		(pad "BK64" smd circle
			(at 24.29002 5.219954 180)
			(size 0.450088 0.450088)
			(layers "F.Cu" "F.Mask" "F.Paste")
			(net "GND")
		)
		(pad "BK65" smd circle
			(at 25.230074 5.219954 180)
			(size 0.450088 0.450088)
			(layers "F.Cu" "F.Mask" "F.Paste")
			(net "M_F_CPU1_SB_CA<5>")
		)
		(pad "BK66" smd circle
			(at 26.170128 5.219954 180)
			(size 0.450088 0.450088)
			(layers "F.Cu" "F.Mask" "F.Paste")
			(net "GND")
		)
		(pad "BK67" smd circle
			(at 27.109928 5.219954 180)
			(size 0.450088 0.450088)
			(layers "F.Cu" "F.Mask" "F.Paste")
			(net "M_F_CPU1_SB_CA<6>")
		)
		(pad "BK68" smd circle
			(at 28.049982 5.219954 180)
			(size 0.450088 0.450088)
			(layers "F.Cu" "F.Mask" "F.Paste")
			(net "GND")
		)
		(pad "BK69" smd circle
			(at 28.990036 5.219954 180)
			(size 0.450088 0.450088)
			(layers "F.Cu" "F.Mask" "F.Paste")
			(net "M_E_CPU1_SB_CA<5>")
		)
		(pad "BK70" smd circle
			(at 29.93009 5.219954 180)
			(size 0.450088 0.450088)
			(layers "F.Cu" "F.Mask" "F.Paste")
			(net "M_E_CPU1_SB_CA<6>")
		)
		(pad "BK71" smd circle
			(at 30.86989 5.219954 180)
			(size 0.450088 0.450088)
			(layers "F.Cu" "F.Mask" "F.Paste")
			(net "GND")
		)
		(pad "BK72" smd circle
			(at 31.809944 5.219954 180)
			(size 0.450088 0.450088)
			(layers "F.Cu" "F.Mask" "F.Paste")
			(net "M_A_CPU1_SB_CA<5>")
		)
		(pad "BK73" smd circle
			(at 32.749998 5.219954 180)
			(size 0.450088 0.450088)
			(layers "F.Cu" "F.Mask" "F.Paste")
			(net "GND")
		)
		(pad "BK74" smd circle
			(at 33.690052 5.219954 180)
			(size 0.450088 0.450088)
			(layers "F.Cu" "F.Mask" "F.Paste")
			(net "M_A_CPU1_SB_CA<6>")
		)
		(pad "BL1" smd circle
			(at -34.459926 6.02996 180)
			(size 0.450088 0.450088)
			(layers "F.Cu" "F.Mask" "F.Paste")
			(net "GND")
		)
		(pad "BL2" smd circle
			(at -33.519872 6.02996 180)
			(size 0.450088 0.450088)
			(layers "F.Cu" "F.Mask" "F.Paste")
			(net "Net_2043")
		)
		(pad "BL3" smd circle
			(at -32.580072 6.02996 180)
			(size 0.450088 0.450088)
			(layers "F.Cu" "F.Mask" "F.Paste")
			(net "M_G_CPU1_SB_PAR")
		)
		(pad "BL4" smd circle
			(at -31.640018 6.02996 180)
			(size 0.450088 0.450088)
			(layers "F.Cu" "F.Mask" "F.Paste")
			(net "GND")
		)
		(pad "BL5" smd circle
			(at -30.699964 6.02996 180)
			(size 0.450088 0.450088)
			(layers "F.Cu" "F.Mask" "F.Paste")
			(net "Net_2192")
		)
		(pad "BL6" smd circle
			(at -29.75991 6.02996 180)
			(size 0.450088 0.450088)
			(layers "F.Cu" "F.Mask" "F.Paste")
			(net "GND")
		)
		(pad "BL7" smd circle
			(at -28.82011 6.02996 180)
			(size 0.450088 0.450088)
			(layers "F.Cu" "F.Mask" "F.Paste")
			(net "M_K_CPU1_SB_PAR")
		)
		(pad "BL8" smd circle
			(at -27.880056 6.02996 180)
			(size 0.450088 0.450088)
			(layers "F.Cu" "F.Mask" "F.Paste")
			(net "GND")
		)
		(pad "BL9" smd circle
			(at -26.940002 6.02996 180)
			(size 0.450088 0.450088)
			(layers "F.Cu" "F.Mask" "F.Paste")
			(net "Net_2184")
		)
		(pad "BL10" smd circle
			(at -25.999948 6.02996 180)
			(size 0.450088 0.450088)
			(layers "F.Cu" "F.Mask" "F.Paste")
			(net "M_L_CPU1_SB_PAR")
		)
		(pad "BL11" smd circle
			(at -25.059894 6.02996 180)
			(size 0.450088 0.450088)
			(layers "F.Cu" "F.Mask" "F.Paste")
			(net "GND")
		)
		(pad "BL12" smd circle
			(at -24.120094 6.02996 180)
			(size 0.450088 0.450088)
			(layers "F.Cu" "F.Mask" "F.Paste")
			(net "Net_2051")
		)
		(pad "BL13" smd circle
			(at -23.18004 6.02996 180)
			(size 0.450088 0.450088)
			(layers "F.Cu" "F.Mask" "F.Paste")
			(net "GND")
		)
		(pad "BL14" smd circle
			(at -22.239986 6.02996 180)
			(size 0.450088 0.450088)
			(layers "F.Cu" "F.Mask" "F.Paste")
			(net "M_H_CPU1_SB_PAR")
		)
		(pad "BL15" smd circle
			(at -21.299932 6.02996 180)
			(size 0.450088 0.450088)
			(layers "F.Cu" "F.Mask" "F.Paste")
			(net "GND")
		)
		(pad "BL16" smd circle
			(at -20.359878 6.02996 180)
			(size 0.450088 0.450088)
			(layers "F.Cu" "F.Mask" "F.Paste")
			(net "Net_2067")
		)
		(pad "BL17" smd circle
			(at -19.420078 6.02996 180)
			(size 0.450088 0.450088)
			(layers "F.Cu" "F.Mask" "F.Paste")
			(net "M_J_CPU1_SB_PAR")
		)
		(pad "BL18" smd circle
			(at -18.480024 6.02996 180)
			(size 0.450088 0.450088)
			(layers "F.Cu" "F.Mask" "F.Paste")
			(net "GND")
		)
		(pad "BL19" smd circle
			(at -17.53997 6.02996 180)
			(size 0.450088 0.450088)
			(layers "F.Cu" "F.Mask" "F.Paste")
			(net "Net_2059")
		)
		(pad "BL20" smd circle
			(at -16.599916 6.02996 180)
			(size 0.450088 0.450088)
			(layers "F.Cu" "F.Mask" "F.Paste")
			(net "GND")
		)
		(pad "BL21" smd circle
			(at -15.660116 6.02996 180)
			(size 0.450088 0.450088)
			(layers "F.Cu" "F.Mask" "F.Paste")
			(net "M_I_CPU1_SB_PAR")
		)
		(pad "BL22" smd circle
			(at -14.720062 6.02996 180)
			(size 0.450088 0.450088)
			(layers "F.Cu" "F.Mask" "F.Paste")
			(net "GND")
		)
		(pad "BL23" smd circle
			(at -13.780008 6.02996 180)
			(size 0.450088 0.450088)
			(layers "F.Cu" "F.Mask" "F.Paste")
			(net "PVDD11_S3_P1")
		)
		(pad "BL24" smd circle
			(at -12.839954 6.02996 180)
			(size 0.450088 0.450088)
			(layers "F.Cu" "F.Mask" "F.Paste")
			(net "GND")
		)
		(pad "BL25" smd circle
			(at -11.8999 6.02996 180)
			(size 0.450088 0.450088)
			(layers "F.Cu" "F.Mask" "F.Paste")
			(net "PVDD11_S3_P1")
		)
		(pad "BL26" smd circle
			(at -10.9601 6.02996 180)
			(size 0.450088 0.450088)
			(layers "F.Cu" "F.Mask" "F.Paste")
			(net "GND")
		)
		(pad "BL27" smd circle
			(at -10.020046 6.02996 180)
			(size 0.450088 0.450088)
			(layers "F.Cu" "F.Mask" "F.Paste")
			(net "PVDD11_S3_P1")
		)
		(pad "BL28" smd circle
			(at -9.079992 6.02996 180)
			(size 0.450088 0.450088)
			(layers "F.Cu" "F.Mask" "F.Paste")
			(net "GND")
		)
		(pad "BL48" smd circle
			(at 8.780018 6.02996 180)
			(size 0.450088 0.450088)
			(layers "F.Cu" "F.Mask" "F.Paste")
			(net "PVDD11_S3_P1")
		)
		(pad "BL49" smd circle
			(at 9.720072 6.02996 180)
			(size 0.450088 0.450088)
			(layers "F.Cu" "F.Mask" "F.Paste")
			(net "GND")
		)
		(pad "BL50" smd circle
			(at 10.659872 6.02996 180)
			(size 0.450088 0.450088)
			(layers "F.Cu" "F.Mask" "F.Paste")
			(net "PVDDIO_P1")
		)
		(pad "BL51" smd circle
			(at 11.599926 6.02996 180)
			(size 0.450088 0.450088)
			(layers "F.Cu" "F.Mask" "F.Paste")
			(net "GND")
		)
		(pad "BL52" smd circle
			(at 12.53998 6.02996 180)
			(size 0.450088 0.450088)
			(layers "F.Cu" "F.Mask" "F.Paste")
			(net "PVDDIO_P1")
		)
		(pad "BL53" smd circle
			(at 13.480034 6.02996 180)
			(size 0.450088 0.450088)
			(layers "F.Cu" "F.Mask" "F.Paste")
			(net "GND")
		)
		(pad "BL54" smd circle
			(at 14.420088 6.02996 180)
			(size 0.450088 0.450088)
			(layers "F.Cu" "F.Mask" "F.Paste")
			(net "PVDDIO_P1")
		)
		(pad "BL55" smd circle
			(at 15.359888 6.02996 180)
			(size 0.450088 0.450088)
			(layers "F.Cu" "F.Mask" "F.Paste")
			(net "Net_2011")
		)
		(pad "BL56" smd circle
			(at 16.299942 6.02996 180)
			(size 0.450088 0.450088)
			(layers "F.Cu" "F.Mask" "F.Paste")
			(net "GND")
		)
		(pad "BL57" smd circle
			(at 17.239996 6.02996 180)
			(size 0.450088 0.450088)
			(layers "F.Cu" "F.Mask" "F.Paste")
			(net "M_C_CPU1_SB_PAR")
		)
		(pad "BL58" smd circle
			(at 18.18005 6.02996 180)
			(size 0.450088 0.450088)
			(layers "F.Cu" "F.Mask" "F.Paste")
			(net "GND")
		)
		(pad "BL59" smd circle
			(at 19.120104 6.02996 180)
			(size 0.450088 0.450088)
			(layers "F.Cu" "F.Mask" "F.Paste")
			(net "Net_2019")
		)
		(pad "BL60" smd circle
			(at 20.059904 6.02996 180)
			(size 0.450088 0.450088)
			(layers "F.Cu" "F.Mask" "F.Paste")
			(net "M_D_CPU1_SB_PAR")
		)
		(pad "BL61" smd circle
			(at 20.999958 6.02996 180)
			(size 0.450088 0.450088)
			(layers "F.Cu" "F.Mask" "F.Paste")
			(net "GND")
		)
		(pad "BL62" smd circle
			(at 21.940012 6.02996 180)
			(size 0.450088 0.450088)
			(layers "F.Cu" "F.Mask" "F.Paste")
			(net "Net_2003")
		)
		(pad "BL63" smd circle
			(at 22.880066 6.02996 180)
			(size 0.450088 0.450088)
			(layers "F.Cu" "F.Mask" "F.Paste")
			(net "GND")
		)
		(pad "BL64" smd circle
			(at 23.82012 6.02996 180)
			(size 0.450088 0.450088)
			(layers "F.Cu" "F.Mask" "F.Paste")
			(net "M_B_CPU1_SB_PAR")
		)
		(pad "BL65" smd circle
			(at 24.75992 6.02996 180)
			(size 0.450088 0.450088)
			(layers "F.Cu" "F.Mask" "F.Paste")
			(net "GND")
		)
		(pad "BL66" smd circle
			(at 25.699974 6.02996 180)
			(size 0.450088 0.450088)
			(layers "F.Cu" "F.Mask" "F.Paste")
			(net "Net_2035")
		)
		(pad "BL67" smd circle
			(at 26.640028 6.02996 180)
			(size 0.450088 0.450088)
			(layers "F.Cu" "F.Mask" "F.Paste")
			(net "M_F_CPU1_SB_PAR")
		)
		(pad "BL68" smd circle
			(at 27.580082 6.02996 180)
			(size 0.450088 0.450088)
			(layers "F.Cu" "F.Mask" "F.Paste")
			(net "GND")
		)
		(pad "BL69" smd circle
			(at 28.519882 6.02996 180)
			(size 0.450088 0.450088)
			(layers "F.Cu" "F.Mask" "F.Paste")
			(net "Net_2027")
		)
		(pad "BL70" smd circle
			(at 29.459936 6.02996 180)
			(size 0.450088 0.450088)
			(layers "F.Cu" "F.Mask" "F.Paste")
			(net "GND")
		)
		(pad "BL71" smd circle
			(at 30.39999 6.02996 180)
			(size 0.450088 0.450088)
			(layers "F.Cu" "F.Mask" "F.Paste")
			(net "M_E_CPU1_SB_PAR")
		)
		(pad "BL72" smd circle
			(at 31.340044 6.02996 180)
			(size 0.450088 0.450088)
			(layers "F.Cu" "F.Mask" "F.Paste")
			(net "GND")
		)
		(pad "BL73" smd circle
			(at 32.280098 6.02996 180)
			(size 0.450088 0.450088)
			(layers "F.Cu" "F.Mask" "F.Paste")
			(net "Net_1995")
		)
		(pad "BL74" smd circle
			(at 33.219898 6.02996 180)
			(size 0.450088 0.450088)
			(layers "F.Cu" "F.Mask" "F.Paste")
			(net "M_A_CPU1_SB_PAR")
		)
		(pad "BL75" smd circle
			(at 34.159952 6.02996 180)
			(size 0.450088 0.450088)
			(layers "F.Cu" "F.Mask" "F.Paste")
			(net "GND")
		)
		(pad "BM2" smd circle
			(at -33.990026 6.839966 180)
			(size 0.450088 0.450088)
			(layers "F.Cu" "F.Mask" "F.Paste")
			(net "Net_2044")
		)
		(pad "BM3" smd circle
			(at -33.049972 6.839966 180)
			(size 0.450088 0.450088)
			(layers "F.Cu" "F.Mask" "F.Paste")
			(net "GND")
		)
		(pad "BM4" smd circle
			(at -32.109918 6.839966 180)
			(size 0.450088 0.450088)
			(layers "F.Cu" "F.Mask" "F.Paste")
			(net "M_G_CPU1_SB_CS_N<0>")
		)
		(pad "BM5" smd circle
			(at -31.170118 6.839966 180)
			(size 0.450088 0.450088)
			(layers "F.Cu" "F.Mask" "F.Paste")
			(net "PVDDCR_SOC_P1")
		)
		(pad "BM6" smd circle
			(at -30.230064 6.839966 180)
			(size 0.450088 0.450088)
			(layers "F.Cu" "F.Mask" "F.Paste")
			(net "Net_2193")
		)
		(pad "BM7" smd circle
			(at -29.29001 6.839966 180)
			(size 0.450088 0.450088)
			(layers "F.Cu" "F.Mask" "F.Paste")
			(net "M_K_CPU1_SB_CS_N<0>")
		)
		(pad "BM8" smd circle
			(at -28.349956 6.839966 180)
			(size 0.450088 0.450088)
			(layers "F.Cu" "F.Mask" "F.Paste")
			(net "GND")
		)
		(pad "BM9" smd circle
			(at -27.409902 6.839966 180)
			(size 0.450088 0.450088)
			(layers "F.Cu" "F.Mask" "F.Paste")
			(net "Net_2185")
		)
		(pad "BM10" smd circle
			(at -26.470102 6.839966 180)
			(size 0.450088 0.450088)
			(layers "F.Cu" "F.Mask" "F.Paste")
			(net "GND")
		)
		(pad "BM11" smd circle
			(at -25.530048 6.839966 180)
			(size 0.450088 0.450088)
			(layers "F.Cu" "F.Mask" "F.Paste")
			(net "M_L_CPU1_SB_CS_N<0>")
		)
		(pad "BM12" smd circle
			(at -24.589994 6.839966 180)
			(size 0.450088 0.450088)
			(layers "F.Cu" "F.Mask" "F.Paste")
			(net "PVDD11_S3_P1")
		)
		(pad "BM13" smd circle
			(at -23.64994 6.839966 180)
			(size 0.450088 0.450088)
			(layers "F.Cu" "F.Mask" "F.Paste")
			(net "Net_2052")
		)
		(pad "BM14" smd circle
			(at -22.709886 6.839966 180)
			(size 0.450088 0.450088)
			(layers "F.Cu" "F.Mask" "F.Paste")
			(net "M_H_CPU1_SB_CS_N<0>")
		)
		(pad "BM15" smd circle
			(at -21.770086 6.839966 180)
			(size 0.450088 0.450088)
			(layers "F.Cu" "F.Mask" "F.Paste")
			(net "GND")
		)
		(pad "BM16" smd circle
			(at -20.830032 6.839966 180)
			(size 0.450088 0.450088)
			(layers "F.Cu" "F.Mask" "F.Paste")
			(net "Net_2068")
		)
		(pad "BM17" smd circle
			(at -19.889978 6.839966 180)
			(size 0.450088 0.450088)
			(layers "F.Cu" "F.Mask" "F.Paste")
			(net "GND")
		)
		(pad "BM18" smd circle
			(at -18.949924 6.839966 180)
			(size 0.450088 0.450088)
			(layers "F.Cu" "F.Mask" "F.Paste")
			(net "M_J_CPU1_SB_CS_N<0>")
		)
		(pad "BM19" smd circle
			(at -18.010124 6.839966 180)
			(size 0.450088 0.450088)
			(layers "F.Cu" "F.Mask" "F.Paste")
			(net "PVDD11_S3_P1")
		)
		(pad "BM20" smd circle
			(at -17.07007 6.839966 180)
			(size 0.450088 0.450088)
			(layers "F.Cu" "F.Mask" "F.Paste")
			(net "Net_2060")
		)
		(pad "BM21" smd circle
			(at -16.130016 6.839966 180)
			(size 0.450088 0.450088)
			(layers "F.Cu" "F.Mask" "F.Paste")
			(net "M_I_CPU1_SB_CS_N<0>")
		)
		(pad "BM22" smd circle
			(at -15.189962 6.839966 180)
			(size 0.450088 0.450088)
			(layers "F.Cu" "F.Mask" "F.Paste")
			(net "PVDD11_S3_P1")
		)
		(pad "BM23" smd circle
			(at -14.249908 6.839966 180)
			(size 0.450088 0.450088)
			(layers "F.Cu" "F.Mask" "F.Paste")
			(net "GND")
		)
		(pad "BM24" smd circle
			(at -13.310108 6.839966 180)
			(size 0.450088 0.450088)
			(layers "F.Cu" "F.Mask" "F.Paste")
			(net "PVDD11_S3_P1")
		)
		(pad "BM25" smd circle
			(at -12.370054 6.839966 180)
			(size 0.450088 0.450088)
			(layers "F.Cu" "F.Mask" "F.Paste")
			(net "GND")
		)
		(pad "BM26" smd circle
			(at -11.43 6.839966 180)
			(size 0.450088 0.450088)
			(layers "F.Cu" "F.Mask" "F.Paste")
			(net "PVDD11_S3_P1")
		)
		(pad "BM27" smd circle
			(at -10.489946 6.839966 180)
			(size 0.450088 0.450088)
			(layers "F.Cu" "F.Mask" "F.Paste")
			(net "GND")
		)
		(pad "BM28" smd circle
			(at -9.549892 6.839966 180)
			(size 0.450088 0.450088)
			(layers "F.Cu" "F.Mask" "F.Paste")
			(net "PVDD11_S3_P1")
		)
		(pad "BM29" smd circle
			(at -8.610092 6.839966 180)
			(size 0.450088 0.450088)
			(layers "F.Cu" "F.Mask" "F.Paste")
			(net "GND")
		)
		(pad "BM30" smd circle
			(at -7.670038 6.839966 180)
			(size 0.450088 0.450088)
			(layers "F.Cu" "F.Mask" "F.Paste")
			(net "PVDD11_S3_P1")
		)
		(pad "BM31" smd circle
			(at -6.729984 6.839966 180)
			(size 0.450088 0.450088)
			(layers "F.Cu" "F.Mask" "F.Paste")
			(net "GND")
		)
		(pad "BM32" smd circle
			(at -5.78993 6.839966 180)
			(size 0.450088 0.450088)
			(layers "F.Cu" "F.Mask" "F.Paste")
			(net "PVDD11_S3_P1")
		)
		(pad "BM33" smd circle
			(at -4.849876 6.839966 180)
			(size 0.450088 0.450088)
			(layers "F.Cu" "F.Mask" "F.Paste")
			(net "GND")
		)
		(pad "BM34" smd circle
			(at -3.910076 6.839966 180)
			(size 0.450088 0.450088)
			(layers "F.Cu" "F.Mask" "F.Paste")
			(net "PVDD11_S3_P1")
		)
		(pad "BM35" smd circle
			(at -2.970022 6.839966 180)
			(size 0.450088 0.450088)
			(layers "F.Cu" "F.Mask" "F.Paste")
			(net "GND")
		)
		(pad "BM36" smd circle
			(at -2.029968 6.839966 180)
			(size 0.450088 0.450088)
			(layers "F.Cu" "F.Mask" "F.Paste")
			(net "PVDD11_S3_P1")
		)
		(pad "BM37" smd circle
			(at -1.089914 6.839966 180)
			(size 0.450088 0.450088)
			(layers "F.Cu" "F.Mask" "F.Paste")
			(net "GND")
		)
		(pad "BM39" smd circle
			(at 0.78994 6.839966 180)
			(size 0.450088 0.450088)
			(layers "F.Cu" "F.Mask" "F.Paste")
			(net "PVDD11_S3_P1")
		)
		(pad "BM40" smd circle
			(at 1.729994 6.839966 180)
			(size 0.450088 0.450088)
			(layers "F.Cu" "F.Mask" "F.Paste")
			(net "GND")
		)
		(pad "BM41" smd circle
			(at 2.670048 6.839966 180)
			(size 0.450088 0.450088)
			(layers "F.Cu" "F.Mask" "F.Paste")
			(net "PVDD11_S3_P1")
		)
		(pad "BM42" smd circle
			(at 3.610102 6.839966 180)
			(size 0.450088 0.450088)
			(layers "F.Cu" "F.Mask" "F.Paste")
			(net "GND")
		)
		(pad "BM43" smd circle
			(at 4.549902 6.839966 180)
			(size 0.450088 0.450088)
			(layers "F.Cu" "F.Mask" "F.Paste")
			(net "PVDD11_S3_P1")
		)
		(pad "BM44" smd circle
			(at 5.489956 6.839966 180)
			(size 0.450088 0.450088)
			(layers "F.Cu" "F.Mask" "F.Paste")
			(net "GND")
		)
		(pad "BM45" smd circle
			(at 6.43001 6.839966 180)
			(size 0.450088 0.450088)
			(layers "F.Cu" "F.Mask" "F.Paste")
			(net "PVDD11_S3_P1")
		)
		(pad "BM46" smd circle
			(at 7.370064 6.839966 180)
			(size 0.450088 0.450088)
			(layers "F.Cu" "F.Mask" "F.Paste")
			(net "GND")
		)
		(pad "BM47" smd circle
			(at 8.310118 6.839966 180)
			(size 0.450088 0.450088)
			(layers "F.Cu" "F.Mask" "F.Paste")
			(net "PVDD11_S3_P1")
		)
		(pad "BM48" smd circle
			(at 9.249918 6.839966 180)
			(size 0.450088 0.450088)
			(layers "F.Cu" "F.Mask" "F.Paste")
			(net "GND")
		)
		(pad "BM49" smd circle
			(at 10.189972 6.839966 180)
			(size 0.450088 0.450088)
			(layers "F.Cu" "F.Mask" "F.Paste")
			(net "PVDD11_S3_P1")
		)
		(pad "BM50" smd circle
			(at 11.130026 6.839966 180)
			(size 0.450088 0.450088)
			(layers "F.Cu" "F.Mask" "F.Paste")
			(net "GND")
		)
		(pad "BM51" smd circle
			(at 12.07008 6.839966 180)
			(size 0.450088 0.450088)
			(layers "F.Cu" "F.Mask" "F.Paste")
			(net "PVDDIO_P1")
		)
		(pad "BM52" smd circle
			(at 13.00988 6.839966 180)
			(size 0.450088 0.450088)
			(layers "F.Cu" "F.Mask" "F.Paste")
			(net "GND")
		)
		(pad "BM53" smd circle
			(at 13.949934 6.839966 180)
			(size 0.450088 0.450088)
			(layers "F.Cu" "F.Mask" "F.Paste")
			(net "PVDDIO_P1")
		)
		(pad "BM54" smd circle
			(at 14.889988 6.839966 180)
			(size 0.450088 0.450088)
			(layers "F.Cu" "F.Mask" "F.Paste")
			(net "GND")
		)
		(pad "BM55" smd circle
			(at 15.830042 6.839966 180)
			(size 0.450088 0.450088)
			(layers "F.Cu" "F.Mask" "F.Paste")
			(net "M_C_CPU1_SB_CS_N<0>")
		)
		(pad "BM56" smd circle
			(at 16.770096 6.839966 180)
			(size 0.450088 0.450088)
			(layers "F.Cu" "F.Mask" "F.Paste")
			(net "Net_2012")
		)
		(pad "BM57" smd circle
			(at 17.709896 6.839966 180)
			(size 0.450088 0.450088)
			(layers "F.Cu" "F.Mask" "F.Paste")
			(net "PVDDIO_P1")
		)
		(pad "BM58" smd circle
			(at 18.64995 6.839966 180)
			(size 0.450088 0.450088)
			(layers "F.Cu" "F.Mask" "F.Paste")
			(net "M_D_CPU1_SB_CS_N<0>")
		)
		(pad "BM59" smd circle
			(at 19.590004 6.839966 180)
			(size 0.450088 0.450088)
			(layers "F.Cu" "F.Mask" "F.Paste")
			(net "GND")
		)
		(pad "BM60" smd circle
			(at 20.530058 6.839966 180)
			(size 0.450088 0.450088)
			(layers "F.Cu" "F.Mask" "F.Paste")
			(net "Net_2020")
		)
		(pad "BM61" smd circle
			(at 21.470112 6.839966 180)
			(size 0.450088 0.450088)
			(layers "F.Cu" "F.Mask" "F.Paste")
			(net "GND")
		)
		(pad "BM62" smd circle
			(at 22.409912 6.839966 180)
			(size 0.450088 0.450088)
			(layers "F.Cu" "F.Mask" "F.Paste")
			(net "M_B_CPU1_SB_CS_N<0>")
		)
		(pad "BM63" smd circle
			(at 23.349966 6.839966 180)
			(size 0.450088 0.450088)
			(layers "F.Cu" "F.Mask" "F.Paste")
			(net "Net_2004")
		)
		(pad "BM64" smd circle
			(at 24.29002 6.839966 180)
			(size 0.450088 0.450088)
			(layers "F.Cu" "F.Mask" "F.Paste")
			(net "PVDDIO_P1")
		)
		(pad "BM65" smd circle
			(at 25.230074 6.839966 180)
			(size 0.450088 0.450088)
			(layers "F.Cu" "F.Mask" "F.Paste")
			(net "M_F_CPU1_SB_CS_N<0>")
		)
		(pad "BM66" smd circle
			(at 26.170128 6.839966 180)
			(size 0.450088 0.450088)
			(layers "F.Cu" "F.Mask" "F.Paste")
			(net "GND")
		)
		(pad "BM67" smd circle
			(at 27.109928 6.839966 180)
			(size 0.450088 0.450088)
			(layers "F.Cu" "F.Mask" "F.Paste")
			(net "Net_2036")
		)
		(pad "BM68" smd circle
			(at 28.049982 6.839966 180)
			(size 0.450088 0.450088)
			(layers "F.Cu" "F.Mask" "F.Paste")
			(net "GND")
		)
		(pad "BM69" smd circle
			(at 28.990036 6.839966 180)
			(size 0.450088 0.450088)
			(layers "F.Cu" "F.Mask" "F.Paste")
			(net "M_E_CPU1_SB_CS_N<0>")
		)
		(pad "BM70" smd circle
			(at 29.93009 6.839966 180)
			(size 0.450088 0.450088)
			(layers "F.Cu" "F.Mask" "F.Paste")
			(net "Net_2028")
		)
		(pad "BM71" smd circle
			(at 30.86989 6.839966 180)
			(size 0.450088 0.450088)
			(layers "F.Cu" "F.Mask" "F.Paste")
			(net "PVDDIO_P1")
		)
		(pad "BM72" smd circle
			(at 31.809944 6.839966 180)
			(size 0.450088 0.450088)
			(layers "F.Cu" "F.Mask" "F.Paste")
			(net "M_A_CPU1_SB_CS_N<0>")
		)
		(pad "BM73" smd circle
			(at 32.749998 6.839966 180)
			(size 0.450088 0.450088)
			(layers "F.Cu" "F.Mask" "F.Paste")
			(net "GND")
		)
		(pad "BM74" smd circle
			(at 33.690052 6.839966 180)
			(size 0.450088 0.450088)
			(layers "F.Cu" "F.Mask" "F.Paste")
			(net "Net_1996")
		)
		(pad "BN1" smd circle
			(at -34.459926 7.649972 180)
			(size 0.450088 0.450088)
			(layers "F.Cu" "F.Mask" "F.Paste")
			(net "GND")
		)
		(pad "BN2" smd circle
			(at -33.519872 7.649972 180)
			(size 0.450088 0.450088)
			(layers "F.Cu" "F.Mask" "F.Paste")
			(net "M_G_CPU1_SB_CS_N<1>")
		)
		(pad "BN3" smd circle
			(at -32.580072 7.649972 180)
			(size 0.450088 0.450088)
			(layers "F.Cu" "F.Mask" "F.Paste")
			(net "M_G_CPU1_SA_RSP<0>")
		)
		(pad "BN4" smd circle
			(at -31.640018 7.649972 180)
			(size 0.450088 0.450088)
			(layers "F.Cu" "F.Mask" "F.Paste")
			(net "GND")
		)
		(pad "BN5" smd circle
			(at -30.699964 7.649972 180)
			(size 0.450088 0.450088)
			(layers "F.Cu" "F.Mask" "F.Paste")
			(net "M_K_CPU1_SB_CS_N<1>")
		)
		(pad "BN6" smd circle
			(at -29.75991 7.649972 180)
			(size 0.450088 0.450088)
			(layers "F.Cu" "F.Mask" "F.Paste")
			(net "GND")
		)
		(pad "BN7" smd circle
			(at -28.82011 7.649972 180)
			(size 0.450088 0.450088)
			(layers "F.Cu" "F.Mask" "F.Paste")
			(net "M_K_CPU1_SA_RSP<0>")
		)
		(pad "BN8" smd circle
			(at -27.880056 7.649972 180)
			(size 0.450088 0.450088)
			(layers "F.Cu" "F.Mask" "F.Paste")
			(net "GND")
		)
		(pad "BN9" smd circle
			(at -26.940002 7.649972 180)
			(size 0.450088 0.450088)
			(layers "F.Cu" "F.Mask" "F.Paste")
			(net "M_L_CPU1_SB_CS_N<1>")
		)
		(pad "BN10" smd circle
			(at -25.999948 7.649972 180)
			(size 0.450088 0.450088)
			(layers "F.Cu" "F.Mask" "F.Paste")
			(net "M_L_CPU1_SA_RSP<0>")
		)
		(pad "BN11" smd circle
			(at -25.059894 7.649972 180)
			(size 0.450088 0.450088)
			(layers "F.Cu" "F.Mask" "F.Paste")
			(net "GND")
		)
		(pad "BN12" smd circle
			(at -24.120094 7.649972 180)
			(size 0.450088 0.450088)
			(layers "F.Cu" "F.Mask" "F.Paste")
			(net "M_H_CPU1_SB_CS_N<1>")
		)
		(pad "BN13" smd circle
			(at -23.18004 7.649972 180)
			(size 0.450088 0.450088)
			(layers "F.Cu" "F.Mask" "F.Paste")
			(net "GND")
		)
		(pad "BN14" smd circle
			(at -22.239986 7.649972 180)
			(size 0.450088 0.450088)
			(layers "F.Cu" "F.Mask" "F.Paste")
			(net "M_H_CPU1_SA_RSP<0>")
		)
		(pad "BN15" smd circle
			(at -21.299932 7.649972 180)
			(size 0.450088 0.450088)
			(layers "F.Cu" "F.Mask" "F.Paste")
			(net "GND")
		)
		(pad "BN16" smd circle
			(at -20.359878 7.649972 180)
			(size 0.450088 0.450088)
			(layers "F.Cu" "F.Mask" "F.Paste")
			(net "M_J_CPU1_SB_CS_N<1>")
		)
		(pad "BN17" smd circle
			(at -19.420078 7.649972 180)
			(size 0.450088 0.450088)
			(layers "F.Cu" "F.Mask" "F.Paste")
			(net "M_J_CPU1_SA_RSP<0>")
		)
		(pad "BN18" smd circle
			(at -18.480024 7.649972 180)
			(size 0.450088 0.450088)
			(layers "F.Cu" "F.Mask" "F.Paste")
			(net "GND")
		)
		(pad "BN19" smd circle
			(at -17.53997 7.649972 180)
			(size 0.450088 0.450088)
			(layers "F.Cu" "F.Mask" "F.Paste")
			(net "M_I_CPU1_SB_CS_N<1>")
		)
		(pad "BN20" smd circle
			(at -16.599916 7.649972 180)
			(size 0.450088 0.450088)
			(layers "F.Cu" "F.Mask" "F.Paste")
			(net "GND")
		)
		(pad "BN21" smd circle
			(at -15.660116 7.649972 180)
			(size 0.450088 0.450088)
			(layers "F.Cu" "F.Mask" "F.Paste")
			(net "M_I_CPU1_SA_RSP<0>")
		)
		(pad "BN22" smd circle
			(at -14.720062 7.649972 180)
			(size 0.450088 0.450088)
			(layers "F.Cu" "F.Mask" "F.Paste")
			(net "GND")
		)
		(pad "BN23" smd circle
			(at -13.780008 7.649972 180)
			(size 0.450088 0.450088)
			(layers "F.Cu" "F.Mask" "F.Paste")
			(net "CPU1_VDDBT_RTC_G")
		)
		(pad "BN24" smd circle
			(at -12.839954 7.649972 180)
			(size 0.450088 0.450088)
			(layers "F.Cu" "F.Mask" "F.Paste")
			(net "GND")
		)
		(pad "BN25" smd circle
			(at -11.8999 7.649972 180)
			(size 0.450088 0.450088)
			(layers "F.Cu" "F.Mask" "F.Paste")
			(net "PVDD11_S3_P1")
		)
		(pad "BN26" smd circle
			(at -10.9601 7.649972 180)
			(size 0.450088 0.450088)
			(layers "F.Cu" "F.Mask" "F.Paste")
			(net "GND")
		)
		(pad "BN27" smd circle
			(at -10.020046 7.649972 180)
			(size 0.450088 0.450088)
			(layers "F.Cu" "F.Mask" "F.Paste")
			(net "PVDDCR_CPU1_P1")
		)
		(pad "BN28" smd circle
			(at -9.079992 7.649972 180)
			(size 0.450088 0.450088)
			(layers "F.Cu" "F.Mask" "F.Paste")
			(net "GND")
		)
		(pad "BN29" smd circle
			(at -8.139938 7.649972 180)
			(size 0.450088 0.450088)
			(layers "F.Cu" "F.Mask" "F.Paste")
			(net "PVDD11_S3_P1")
		)
		(pad "BN30" smd circle
			(at -7.199884 7.649972 180)
			(size 0.450088 0.450088)
			(layers "F.Cu" "F.Mask" "F.Paste")
			(net "GND")
		)
		(pad "BN31" smd circle
			(at -6.260084 7.649972 180)
			(size 0.450088 0.450088)
			(layers "F.Cu" "F.Mask" "F.Paste")
			(net "PVDDCR_CPU1_P1")
		)
		(pad "BN32" smd circle
			(at -5.32003 7.649972 180)
			(size 0.450088 0.450088)
			(layers "F.Cu" "F.Mask" "F.Paste")
			(net "GND")
		)
		(pad "BN33" smd circle
			(at -4.379976 7.649972 180)
			(size 0.450088 0.450088)
			(layers "F.Cu" "F.Mask" "F.Paste")
			(net "PVDD11_S3_P1")
		)
		(pad "BN34" smd circle
			(at -3.439922 7.649972 180)
			(size 0.450088 0.450088)
			(layers "F.Cu" "F.Mask" "F.Paste")
			(net "GND")
		)
		(pad "BN35" smd circle
			(at -2.500122 7.649972 180)
			(size 0.450088 0.450088)
			(layers "F.Cu" "F.Mask" "F.Paste")
			(net "PVDDCR_CPU1_P1")
		)
		(pad "BN36" smd circle
			(at -1.560068 7.649972 180)
			(size 0.450088 0.450088)
			(layers "F.Cu" "F.Mask" "F.Paste")
			(net "GND")
		)
		(pad "BN40" smd circle
			(at 1.260094 7.649972 180)
			(size 0.450088 0.450088)
			(layers "F.Cu" "F.Mask" "F.Paste")
			(net "PVDD11_S3_P1")
		)
		(pad "BN41" smd circle
			(at 2.199894 7.649972 180)
			(size 0.450088 0.450088)
			(layers "F.Cu" "F.Mask" "F.Paste")
			(net "GND")
		)
		(pad "BN42" smd circle
			(at 3.139948 7.649972 180)
			(size 0.450088 0.450088)
			(layers "F.Cu" "F.Mask" "F.Paste")
			(net "PVDDCR_CPU1_P1")
		)
		(pad "BN43" smd circle
			(at 4.080002 7.649972 180)
			(size 0.450088 0.450088)
			(layers "F.Cu" "F.Mask" "F.Paste")
			(net "GND")
		)
		(pad "BN44" smd circle
			(at 5.020056 7.649972 180)
			(size 0.450088 0.450088)
			(layers "F.Cu" "F.Mask" "F.Paste")
			(net "PVDD11_S3_P1")
		)
		(pad "BN45" smd circle
			(at 5.96011 7.649972 180)
			(size 0.450088 0.450088)
			(layers "F.Cu" "F.Mask" "F.Paste")
			(net "GND")
		)
		(pad "BN46" smd circle
			(at 6.89991 7.649972 180)
			(size 0.450088 0.450088)
			(layers "F.Cu" "F.Mask" "F.Paste")
			(net "PVDDCR_CPU1_P1")
		)
		(pad "BN47" smd circle
			(at 7.839964 7.649972 180)
			(size 0.450088 0.450088)
			(layers "F.Cu" "F.Mask" "F.Paste")
			(net "GND")
		)
		(pad "BN48" smd circle
			(at 8.780018 7.649972 180)
			(size 0.450088 0.450088)
			(layers "F.Cu" "F.Mask" "F.Paste")
			(net "PVDD11_S3_P1")
		)
		(pad "BN49" smd circle
			(at 9.720072 7.649972 180)
			(size 0.450088 0.450088)
			(layers "F.Cu" "F.Mask" "F.Paste")
			(net "GND")
		)
		(pad "BN50" smd circle
			(at 10.659872 7.649972 180)
			(size 0.450088 0.450088)
			(layers "F.Cu" "F.Mask" "F.Paste")
			(net "PVDDCR_CPU1_P1")
		)
		(pad "BN51" smd circle
			(at 11.599926 7.649972 180)
			(size 0.450088 0.450088)
			(layers "F.Cu" "F.Mask" "F.Paste")
			(net "GND")
		)
		(pad "BN52" smd circle
			(at 12.53998 7.649972 180)
			(size 0.450088 0.450088)
			(layers "F.Cu" "F.Mask" "F.Paste")
			(net "PVDD_33_S5")
		)
		(pad "BN53" smd circle
			(at 13.480034 7.649972 180)
			(size 0.450088 0.450088)
			(layers "F.Cu" "F.Mask" "F.Paste")
			(net "GND")
		)
		(pad "BN54" smd circle
			(at 14.420088 7.649972 180)
			(size 0.450088 0.450088)
			(layers "F.Cu" "F.Mask" "F.Paste")
			(net "PVDDIO_P1")
		)
		(pad "BN55" smd circle
			(at 15.359888 7.649972 180)
			(size 0.450088 0.450088)
			(layers "F.Cu" "F.Mask" "F.Paste")
			(net "M_C_CPU1_SA_RSP<0>")
		)
		(pad "BN56" smd circle
			(at 16.299942 7.649972 180)
			(size 0.450088 0.450088)
			(layers "F.Cu" "F.Mask" "F.Paste")
			(net "GND")
		)
		(pad "BN57" smd circle
			(at 17.239996 7.649972 180)
			(size 0.450088 0.450088)
			(layers "F.Cu" "F.Mask" "F.Paste")
			(net "M_C_CPU1_SB_CS_N<1>")
		)
		(pad "BN58" smd circle
			(at 18.18005 7.649972 180)
			(size 0.450088 0.450088)
			(layers "F.Cu" "F.Mask" "F.Paste")
			(net "GND")
		)
		(pad "BN59" smd circle
			(at 19.120104 7.649972 180)
			(size 0.450088 0.450088)
			(layers "F.Cu" "F.Mask" "F.Paste")
			(net "M_D_CPU1_SA_RSP<0>")
		)
		(pad "BN60" smd circle
			(at 20.059904 7.649972 180)
			(size 0.450088 0.450088)
			(layers "F.Cu" "F.Mask" "F.Paste")
			(net "M_D_CPU1_SB_CS_N<1>")
		)
		(pad "BN61" smd circle
			(at 20.999958 7.649972 180)
			(size 0.450088 0.450088)
			(layers "F.Cu" "F.Mask" "F.Paste")
			(net "GND")
		)
		(pad "BN62" smd circle
			(at 21.940012 7.649972 180)
			(size 0.450088 0.450088)
			(layers "F.Cu" "F.Mask" "F.Paste")
			(net "M_B_CPU1_SA_RSP<0>")
		)
		(pad "BN63" smd circle
			(at 22.880066 7.649972 180)
			(size 0.450088 0.450088)
			(layers "F.Cu" "F.Mask" "F.Paste")
			(net "GND")
		)
		(pad "BN64" smd circle
			(at 23.82012 7.649972 180)
			(size 0.450088 0.450088)
			(layers "F.Cu" "F.Mask" "F.Paste")
			(net "M_B_CPU1_SB_CS_N<1>")
		)
		(pad "BN65" smd circle
			(at 24.75992 7.649972 180)
			(size 0.450088 0.450088)
			(layers "F.Cu" "F.Mask" "F.Paste")
			(net "GND")
		)
		(pad "BN66" smd circle
			(at 25.699974 7.649972 180)
			(size 0.450088 0.450088)
			(layers "F.Cu" "F.Mask" "F.Paste")
			(net "M_F_CPU1_SA_RSP<0>")
		)
		(pad "BN67" smd circle
			(at 26.640028 7.649972 180)
			(size 0.450088 0.450088)
			(layers "F.Cu" "F.Mask" "F.Paste")
			(net "M_F_CPU1_SB_CS_N<1>")
		)
		(pad "BN68" smd circle
			(at 27.580082 7.649972 180)
			(size 0.450088 0.450088)
			(layers "F.Cu" "F.Mask" "F.Paste")
			(net "GND")
		)
		(pad "BN69" smd circle
			(at 28.519882 7.649972 180)
			(size 0.450088 0.450088)
			(layers "F.Cu" "F.Mask" "F.Paste")
			(net "M_E_CPU1_SA_RSP<0>")
		)
		(pad "BN70" smd circle
			(at 29.459936 7.649972 180)
			(size 0.450088 0.450088)
			(layers "F.Cu" "F.Mask" "F.Paste")
			(net "GND")
		)
		(pad "BN71" smd circle
			(at 30.39999 7.649972 180)
			(size 0.450088 0.450088)
			(layers "F.Cu" "F.Mask" "F.Paste")
			(net "M_E_CPU1_SB_CS_N<1>")
		)
		(pad "BN72" smd circle
			(at 31.340044 7.649972 180)
			(size 0.450088 0.450088)
			(layers "F.Cu" "F.Mask" "F.Paste")
			(net "GND")
		)
		(pad "BN73" smd circle
			(at 32.280098 7.649972 180)
			(size 0.450088 0.450088)
			(layers "F.Cu" "F.Mask" "F.Paste")
			(net "M_A_CPU1_SA_RSP<0>")
		)
		(pad "BN74" smd circle
			(at 33.219898 7.649972 180)
			(size 0.450088 0.450088)
			(layers "F.Cu" "F.Mask" "F.Paste")
			(net "M_A_CPU1_SB_CS_N<1>")
		)
		(pad "BN75" smd circle
			(at 34.159952 7.649972 180)
			(size 0.450088 0.450088)
			(layers "F.Cu" "F.Mask" "F.Paste")
			(net "GND")
		)
		(pad "BP2" smd circle
			(at -33.990026 8.459978 180)
			(size 0.450088 0.450088)
			(layers "F.Cu" "F.Mask" "F.Paste")
			(net "M_G_CPU1_SB_RSP<0>")
		)
		(pad "BP3" smd circle
			(at -33.049972 8.459978 180)
			(size 0.450088 0.450088)
			(layers "F.Cu" "F.Mask" "F.Paste")
			(net "GND")
		)
		(pad "BP4" smd circle
			(at -32.109918 8.459978 180)
			(size 0.450088 0.450088)
			(layers "F.Cu" "F.Mask" "F.Paste")
			(net "Net_2042")
		)
		(pad "BP5" smd circle
			(at -31.170118 8.459978 180)
			(size 0.450088 0.450088)
			(layers "F.Cu" "F.Mask" "F.Paste")
			(net "GND")
		)
		(pad "BP6" smd circle
			(at -30.230064 8.459978 180)
			(size 0.450088 0.450088)
			(layers "F.Cu" "F.Mask" "F.Paste")
			(net "M_K_CPU1_SB_RSP<0>")
		)
		(pad "BP7" smd circle
			(at -29.29001 8.459978 180)
			(size 0.450088 0.450088)
			(layers "F.Cu" "F.Mask" "F.Paste")
			(net "Net_2191")
		)
		(pad "BP8" smd circle
			(at -28.349956 8.459978 180)
			(size 0.450088 0.450088)
			(layers "F.Cu" "F.Mask" "F.Paste")
			(net "GND")
		)
		(pad "BP9" smd circle
			(at -27.409902 8.459978 180)
			(size 0.450088 0.450088)
			(layers "F.Cu" "F.Mask" "F.Paste")
			(net "M_L_CPU1_SB_RSP<0>")
		)
		(pad "BP10" smd circle
			(at -26.470102 8.459978 180)
			(size 0.450088 0.450088)
			(layers "F.Cu" "F.Mask" "F.Paste")
			(net "GND")
		)
		(pad "BP11" smd circle
			(at -25.530048 8.459978 180)
			(size 0.450088 0.450088)
			(layers "F.Cu" "F.Mask" "F.Paste")
			(net "Net_2183")
		)
		(pad "BP12" smd circle
			(at -24.589994 8.459978 180)
			(size 0.450088 0.450088)
			(layers "F.Cu" "F.Mask" "F.Paste")
			(net "GND")
		)
		(pad "BP13" smd circle
			(at -23.64994 8.459978 180)
			(size 0.450088 0.450088)
			(layers "F.Cu" "F.Mask" "F.Paste")
			(net "M_H_CPU1_SB_RSP<0>")
		)
		(pad "BP14" smd circle
			(at -22.709886 8.459978 180)
			(size 0.450088 0.450088)
			(layers "F.Cu" "F.Mask" "F.Paste")
			(net "Net_2050")
		)
		(pad "BP15" smd circle
			(at -21.770086 8.459978 180)
			(size 0.450088 0.450088)
			(layers "F.Cu" "F.Mask" "F.Paste")
			(net "GND")
		)
		(pad "BP16" smd circle
			(at -20.830032 8.459978 180)
			(size 0.450088 0.450088)
			(layers "F.Cu" "F.Mask" "F.Paste")
			(net "M_J_CPU1_SB_RSP<0>")
		)
		(pad "BP17" smd circle
			(at -19.889978 8.459978 180)
			(size 0.450088 0.450088)
			(layers "F.Cu" "F.Mask" "F.Paste")
			(net "GND")
		)
		(pad "BP18" smd circle
			(at -18.949924 8.459978 180)
			(size 0.450088 0.450088)
			(layers "F.Cu" "F.Mask" "F.Paste")
			(net "Net_2066")
		)
		(pad "BP19" smd circle
			(at -18.010124 8.459978 180)
			(size 0.450088 0.450088)
			(layers "F.Cu" "F.Mask" "F.Paste")
			(net "GND")
		)
		(pad "BP20" smd circle
			(at -17.07007 8.459978 180)
			(size 0.450088 0.450088)
			(layers "F.Cu" "F.Mask" "F.Paste")
			(net "M_I_CPU1_SB_RSP<0>")
		)
		(pad "BP21" smd circle
			(at -16.130016 8.459978 180)
			(size 0.450088 0.450088)
			(layers "F.Cu" "F.Mask" "F.Paste")
			(net "Net_2058")
		)
		(pad "BP22" smd circle
			(at -15.189962 8.459978 180)
			(size 0.450088 0.450088)
			(layers "F.Cu" "F.Mask" "F.Paste")
			(net "PVDD11_S3_P1")
		)
		(pad "BP23" smd circle
			(at -14.249908 8.459978 180)
			(size 0.450088 0.450088)
			(layers "F.Cu" "F.Mask" "F.Paste")
			(net "GND")
		)
		(pad "BP24" smd circle
			(at -13.310108 8.459978 180)
			(size 0.450088 0.450088)
			(layers "F.Cu" "F.Mask" "F.Paste")
			(net "PVDDCR_CPU1_P1")
		)
		(pad "BP25" smd circle
			(at -12.370054 8.459978 180)
			(size 0.450088 0.450088)
			(layers "F.Cu" "F.Mask" "F.Paste")
			(net "GND")
		)
		(pad "BP26" smd circle
			(at -11.43 8.459978 180)
			(size 0.450088 0.450088)
			(layers "F.Cu" "F.Mask" "F.Paste")
			(net "PVDDCR_CPU1_P1")
		)
		(pad "BP27" smd circle
			(at -10.489946 8.459978 180)
			(size 0.450088 0.450088)
			(layers "F.Cu" "F.Mask" "F.Paste")
			(net "GND")
		)
		(pad "BP28" smd circle
			(at -9.549892 8.459978 180)
			(size 0.450088 0.450088)
			(layers "F.Cu" "F.Mask" "F.Paste")
			(net "PVDDCR_CPU1_P1")
		)
		(pad "BP29" smd circle
			(at -8.610092 8.459978 180)
			(size 0.450088 0.450088)
			(layers "F.Cu" "F.Mask" "F.Paste")
			(net "GND")
		)
		(pad "BP30" smd circle
			(at -7.670038 8.459978 180)
			(size 0.450088 0.450088)
			(layers "F.Cu" "F.Mask" "F.Paste")
			(net "PVDDCR_CPU1_P1")
		)
		(pad "BP31" smd circle
			(at -6.729984 8.459978 180)
			(size 0.450088 0.450088)
			(layers "F.Cu" "F.Mask" "F.Paste")
			(net "GND")
		)
		(pad "BP32" smd circle
			(at -5.78993 8.459978 180)
			(size 0.450088 0.450088)
			(layers "F.Cu" "F.Mask" "F.Paste")
			(net "PVDDCR_CPU1_P1")
		)
		(pad "BP33" smd circle
			(at -4.849876 8.459978 180)
			(size 0.450088 0.450088)
			(layers "F.Cu" "F.Mask" "F.Paste")
			(net "GND")
		)
		(pad "BP34" smd circle
			(at -3.910076 8.459978 180)
			(size 0.450088 0.450088)
			(layers "F.Cu" "F.Mask" "F.Paste")
			(net "PVDDCR_CPU1_P1")
		)
		(pad "BP35" smd circle
			(at -2.970022 8.459978 180)
			(size 0.450088 0.450088)
			(layers "F.Cu" "F.Mask" "F.Paste")
			(net "GND")
		)
		(pad "BP36" smd circle
			(at -2.029968 8.459978 180)
			(size 0.450088 0.450088)
			(layers "F.Cu" "F.Mask" "F.Paste")
			(net "PVDDCR_CPU1_P1")
		)
		(pad "BP37" smd circle
			(at -1.089914 8.459978 180)
			(size 0.450088 0.450088)
			(layers "F.Cu" "F.Mask" "F.Paste")
			(net "GND")
		)
		(pad "BP39" smd circle
			(at 0.78994 8.459978 180)
			(size 0.450088 0.450088)
			(layers "F.Cu" "F.Mask" "F.Paste")
			(net "PVDDCR_CPU1_P1")
		)
		(pad "BP40" smd circle
			(at 1.729994 8.459978 180)
			(size 0.450088 0.450088)
			(layers "F.Cu" "F.Mask" "F.Paste")
			(net "GND")
		)
		(pad "BP41" smd circle
			(at 2.670048 8.459978 180)
			(size 0.450088 0.450088)
			(layers "F.Cu" "F.Mask" "F.Paste")
			(net "PVDDCR_CPU1_P1")
		)
		(pad "BP42" smd circle
			(at 3.610102 8.459978 180)
			(size 0.450088 0.450088)
			(layers "F.Cu" "F.Mask" "F.Paste")
			(net "GND")
		)
		(pad "BP43" smd circle
			(at 4.549902 8.459978 180)
			(size 0.450088 0.450088)
			(layers "F.Cu" "F.Mask" "F.Paste")
			(net "PVDDCR_CPU1_P1")
		)
		(pad "BP44" smd circle
			(at 5.489956 8.459978 180)
			(size 0.450088 0.450088)
			(layers "F.Cu" "F.Mask" "F.Paste")
			(net "GND")
		)
		(pad "BP45" smd circle
			(at 6.43001 8.459978 180)
			(size 0.450088 0.450088)
			(layers "F.Cu" "F.Mask" "F.Paste")
			(net "PVDDCR_CPU1_P1")
		)
		(pad "BP46" smd circle
			(at 7.370064 8.459978 180)
			(size 0.450088 0.450088)
			(layers "F.Cu" "F.Mask" "F.Paste")
			(net "GND")
		)
		(pad "BP47" smd circle
			(at 8.310118 8.459978 180)
			(size 0.450088 0.450088)
			(layers "F.Cu" "F.Mask" "F.Paste")
			(net "PVDDCR_CPU1_P1")
		)
		(pad "BP48" smd circle
			(at 9.249918 8.459978 180)
			(size 0.450088 0.450088)
			(layers "F.Cu" "F.Mask" "F.Paste")
			(net "GND")
		)
		(pad "BP49" smd circle
			(at 10.189972 8.459978 180)
			(size 0.450088 0.450088)
			(layers "F.Cu" "F.Mask" "F.Paste")
			(net "PVDDCR_CPU1_P1")
		)
		(pad "BP50" smd circle
			(at 11.130026 8.459978 180)
			(size 0.450088 0.450088)
			(layers "F.Cu" "F.Mask" "F.Paste")
			(net "GND")
		)
		(pad "BP51" smd circle
			(at 12.07008 8.459978 180)
			(size 0.450088 0.450088)
			(layers "F.Cu" "F.Mask" "F.Paste")
			(net "PVDD_33_S5")
		)
		(pad "BP52" smd circle
			(at 13.00988 8.459978 180)
			(size 0.450088 0.450088)
			(layers "F.Cu" "F.Mask" "F.Paste")
			(net "GND")
		)
		(pad "BP53" smd circle
			(at 13.949934 8.459978 180)
			(size 0.450088 0.450088)
			(layers "F.Cu" "F.Mask" "F.Paste")
			(net "TP_VSENSE_PVDD33_S5_P1")
		)
		(pad "BP54" smd circle
			(at 14.889988 8.459978 180)
			(size 0.450088 0.450088)
			(layers "F.Cu" "F.Mask" "F.Paste")
			(net "GND")
		)
		(pad "BP55" smd circle
			(at 15.830042 8.459978 180)
			(size 0.450088 0.450088)
			(layers "F.Cu" "F.Mask" "F.Paste")
			(net "Net_2010")
		)
		(pad "BP56" smd circle
			(at 16.770096 8.459978 180)
			(size 0.450088 0.450088)
			(layers "F.Cu" "F.Mask" "F.Paste")
			(net "M_C_CPU1_SB_RSP<0>")
		)
		(pad "BP57" smd circle
			(at 17.709896 8.459978 180)
			(size 0.450088 0.450088)
			(layers "F.Cu" "F.Mask" "F.Paste")
			(net "GND")
		)
		(pad "BP58" smd circle
			(at 18.64995 8.459978 180)
			(size 0.450088 0.450088)
			(layers "F.Cu" "F.Mask" "F.Paste")
			(net "Net_2018")
		)
		(pad "BP59" smd circle
			(at 19.590004 8.459978 180)
			(size 0.450088 0.450088)
			(layers "F.Cu" "F.Mask" "F.Paste")
			(net "GND")
		)
		(pad "BP60" smd circle
			(at 20.530058 8.459978 180)
			(size 0.450088 0.450088)
			(layers "F.Cu" "F.Mask" "F.Paste")
			(net "M_D_CPU1_SB_RSP<0>")
		)
		(pad "BP61" smd circle
			(at 21.470112 8.459978 180)
			(size 0.450088 0.450088)
			(layers "F.Cu" "F.Mask" "F.Paste")
			(net "GND")
		)
		(pad "BP62" smd circle
			(at 22.409912 8.459978 180)
			(size 0.450088 0.450088)
			(layers "F.Cu" "F.Mask" "F.Paste")
			(net "Net_2002")
		)
		(pad "BP63" smd circle
			(at 23.349966 8.459978 180)
			(size 0.450088 0.450088)
			(layers "F.Cu" "F.Mask" "F.Paste")
			(net "M_B_CPU1_SB_RSP<0>")
		)
		(pad "BP64" smd circle
			(at 24.29002 8.459978 180)
			(size 0.450088 0.450088)
			(layers "F.Cu" "F.Mask" "F.Paste")
			(net "GND")
		)
		(pad "BP65" smd circle
			(at 25.230074 8.459978 180)
			(size 0.450088 0.450088)
			(layers "F.Cu" "F.Mask" "F.Paste")
			(net "Net_2034")
		)
		(pad "BP66" smd circle
			(at 26.170128 8.459978 180)
			(size 0.450088 0.450088)
			(layers "F.Cu" "F.Mask" "F.Paste")
			(net "GND")
		)
		(pad "BP67" smd circle
			(at 27.109928 8.459978 180)
			(size 0.450088 0.450088)
			(layers "F.Cu" "F.Mask" "F.Paste")
			(net "M_F_CPU1_SB_RSP<0>")
		)
		(pad "BP68" smd circle
			(at 28.049982 8.459978 180)
			(size 0.450088 0.450088)
			(layers "F.Cu" "F.Mask" "F.Paste")
			(net "GND")
		)
		(pad "BP69" smd circle
			(at 28.990036 8.459978 180)
			(size 0.450088 0.450088)
			(layers "F.Cu" "F.Mask" "F.Paste")
			(net "Net_2026")
		)
		(pad "BP70" smd circle
			(at 29.93009 8.459978 180)
			(size 0.450088 0.450088)
			(layers "F.Cu" "F.Mask" "F.Paste")
			(net "M_E_CPU1_SB_RSP<0>")
		)
		(pad "BP71" smd circle
			(at 30.86989 8.459978 180)
			(size 0.450088 0.450088)
			(layers "F.Cu" "F.Mask" "F.Paste")
			(net "GND")
		)
		(pad "BP72" smd circle
			(at 31.809944 8.459978 180)
			(size 0.450088 0.450088)
			(layers "F.Cu" "F.Mask" "F.Paste")
			(net "Net_1994")
		)
		(pad "BP73" smd circle
			(at 32.749998 8.459978 180)
			(size 0.450088 0.450088)
			(layers "F.Cu" "F.Mask" "F.Paste")
			(net "GND")
		)
		(pad "BP74" smd circle
			(at 33.690052 8.459978 180)
			(size 0.450088 0.450088)
			(layers "F.Cu" "F.Mask" "F.Paste")
			(net "M_A_CPU1_SB_RSP<0>")
		)
		(pad "BR1" smd circle
			(at -34.459926 9.269984 180)
			(size 0.450088 0.450088)
			(layers "F.Cu" "F.Mask" "F.Paste")
			(net "GND")
		)
		(pad "BR2" smd circle
			(at -33.519872 9.269984 180)
			(size 0.450088 0.450088)
			(layers "F.Cu" "F.Mask" "F.Paste")
			(net "Net_2045")
		)
		(pad "BR3" smd circle
			(at -32.580072 9.269984 180)
			(size 0.450088 0.450088)
			(layers "F.Cu" "F.Mask" "F.Paste")
			(net "GND")
		)
		(pad "BR4" smd circle
			(at -31.640018 9.269984 180)
			(size 0.450088 0.450088)
			(layers "F.Cu" "F.Mask" "F.Paste")
			(net "PVDD11_S3_P1")
		)
		(pad "BR5" smd circle
			(at -30.699964 9.269984 180)
			(size 0.450088 0.450088)
			(layers "F.Cu" "F.Mask" "F.Paste")
			(net "Net_2194")
		)
		(pad "BR6" smd circle
			(at -29.75991 9.269984 180)
			(size 0.450088 0.450088)
			(layers "F.Cu" "F.Mask" "F.Paste")
			(net "GND")
		)
		(pad "BR7" smd circle
			(at -28.82011 9.269984 180)
			(size 0.450088 0.450088)
			(layers "F.Cu" "F.Mask" "F.Paste")
			(net "GND")
		)
		(pad "BR8" smd circle
			(at -27.880056 9.269984 180)
			(size 0.450088 0.450088)
			(layers "F.Cu" "F.Mask" "F.Paste")
			(net "GND")
		)
		(pad "BR9" smd circle
			(at -26.940002 9.269984 180)
			(size 0.450088 0.450088)
			(layers "F.Cu" "F.Mask" "F.Paste")
			(net "Net_2186")
		)
		(pad "BR10" smd circle
			(at -25.999948 9.269984 180)
			(size 0.450088 0.450088)
			(layers "F.Cu" "F.Mask" "F.Paste")
			(net "GND")
		)
		(pad "BR11" smd circle
			(at -25.059894 9.269984 180)
			(size 0.450088 0.450088)
			(layers "F.Cu" "F.Mask" "F.Paste")
			(net "PVDD11_S3_P1")
		)
		(pad "BR12" smd circle
			(at -24.120094 9.269984 180)
			(size 0.450088 0.450088)
			(layers "F.Cu" "F.Mask" "F.Paste")
			(net "Net_2053")
		)
		(pad "BR13" smd circle
			(at -23.18004 9.269984 180)
			(size 0.450088 0.450088)
			(layers "F.Cu" "F.Mask" "F.Paste")
			(net "GND")
		)
		(pad "BR14" smd circle
			(at -22.239986 9.269984 180)
			(size 0.450088 0.450088)
			(layers "F.Cu" "F.Mask" "F.Paste")
			(net "GND")
		)
		(pad "BR15" smd circle
			(at -21.299932 9.269984 180)
			(size 0.450088 0.450088)
			(layers "F.Cu" "F.Mask" "F.Paste")
			(net "GND")
		)
		(pad "BR16" smd circle
			(at -20.359878 9.269984 180)
			(size 0.450088 0.450088)
			(layers "F.Cu" "F.Mask" "F.Paste")
			(net "Net_2069")
		)
		(pad "BR17" smd circle
			(at -19.420078 9.269984 180)
			(size 0.450088 0.450088)
			(layers "F.Cu" "F.Mask" "F.Paste")
			(net "GND")
		)
		(pad "BR18" smd circle
			(at -18.480024 9.269984 180)
			(size 0.450088 0.450088)
			(layers "F.Cu" "F.Mask" "F.Paste")
			(net "PVDD11_S3_P1")
		)
		(pad "BR19" smd circle
			(at -17.53997 9.269984 180)
			(size 0.450088 0.450088)
			(layers "F.Cu" "F.Mask" "F.Paste")
			(net "Net_2061")
		)
		(pad "BR20" smd circle
			(at -16.599916 9.269984 180)
			(size 0.450088 0.450088)
			(layers "F.Cu" "F.Mask" "F.Paste")
			(net "GND")
		)
		(pad "BR21" smd circle
			(at -15.660116 9.269984 180)
			(size 0.450088 0.450088)
			(layers "F.Cu" "F.Mask" "F.Paste")
			(net "GND")
		)
		(pad "BR22" smd circle
			(at -14.720062 9.269984 180)
			(size 0.450088 0.450088)
			(layers "F.Cu" "F.Mask" "F.Paste")
			(net "GND")
		)
		(pad "BR23" smd circle
			(at -13.780008 9.269984 180)
			(size 0.450088 0.450088)
			(layers "F.Cu" "F.Mask" "F.Paste")
			(net "PVDDCR_CPU1_P1")
		)
		(pad "BR24" smd circle
			(at -12.839954 9.269984 180)
			(size 0.450088 0.450088)
			(layers "F.Cu" "F.Mask" "F.Paste")
			(net "GND")
		)
		(pad "BR25" smd circle
			(at -11.8999 9.269984 180)
			(size 0.450088 0.450088)
			(layers "F.Cu" "F.Mask" "F.Paste")
			(net "PVDDCR_CPU1_P1")
		)
		(pad "BR26" smd circle
			(at -10.9601 9.269984 180)
			(size 0.450088 0.450088)
			(layers "F.Cu" "F.Mask" "F.Paste")
			(net "GND")
		)
		(pad "BR27" smd circle
			(at -10.020046 9.269984 180)
			(size 0.450088 0.450088)
			(layers "F.Cu" "F.Mask" "F.Paste")
			(net "PVDDCR_CPU1_P1")
		)
		(pad "BR28" smd circle
			(at -9.079992 9.269984 180)
			(size 0.450088 0.450088)
			(layers "F.Cu" "F.Mask" "F.Paste")
			(net "GND")
		)
		(pad "BR29" smd circle
			(at -8.139938 9.269984 180)
			(size 0.450088 0.450088)
			(layers "F.Cu" "F.Mask" "F.Paste")
			(net "PVDDCR_CPU1_P1")
		)
		(pad "BR30" smd circle
			(at -7.199884 9.269984 180)
			(size 0.450088 0.450088)
			(layers "F.Cu" "F.Mask" "F.Paste")
			(net "GND")
		)
		(pad "BR31" smd circle
			(at -6.260084 9.269984 180)
			(size 0.450088 0.450088)
			(layers "F.Cu" "F.Mask" "F.Paste")
			(net "PVDDCR_CPU1_P1")
		)
		(pad "BR32" smd circle
			(at -5.32003 9.269984 180)
			(size 0.450088 0.450088)
			(layers "F.Cu" "F.Mask" "F.Paste")
			(net "GND")
		)
		(pad "BR33" smd circle
			(at -4.379976 9.269984 180)
			(size 0.450088 0.450088)
			(layers "F.Cu" "F.Mask" "F.Paste")
			(net "PVDDCR_CPU1_P1")
		)
		(pad "BR34" smd circle
			(at -3.439922 9.269984 180)
			(size 0.450088 0.450088)
			(layers "F.Cu" "F.Mask" "F.Paste")
			(net "GND")
		)
		(pad "BR35" smd circle
			(at -2.500122 9.269984 180)
			(size 0.450088 0.450088)
			(layers "F.Cu" "F.Mask" "F.Paste")
			(net "PVDDCR_CPU1_P1")
		)
		(pad "BR36" smd circle
			(at -1.560068 9.269984 180)
			(size 0.450088 0.450088)
			(layers "F.Cu" "F.Mask" "F.Paste")
			(net "GND")
		)
		(pad "BR40" smd circle
			(at 1.260094 9.269984 180)
			(size 0.450088 0.450088)
			(layers "F.Cu" "F.Mask" "F.Paste")
			(net "PVDDCR_CPU1_P1")
		)
		(pad "BR41" smd circle
			(at 2.199894 9.269984 180)
			(size 0.450088 0.450088)
			(layers "F.Cu" "F.Mask" "F.Paste")
			(net "GND")
		)
		(pad "BR42" smd circle
			(at 3.139948 9.269984 180)
			(size 0.450088 0.450088)
			(layers "F.Cu" "F.Mask" "F.Paste")
			(net "PVDDCR_CPU1_P1")
		)
		(pad "BR43" smd circle
			(at 4.080002 9.269984 180)
			(size 0.450088 0.450088)
			(layers "F.Cu" "F.Mask" "F.Paste")
			(net "GND")
		)
		(pad "BR44" smd circle
			(at 5.020056 9.269984 180)
			(size 0.450088 0.450088)
			(layers "F.Cu" "F.Mask" "F.Paste")
			(net "PVDDCR_CPU1_P1")
		)
		(pad "BR45" smd circle
			(at 5.96011 9.269984 180)
			(size 0.450088 0.450088)
			(layers "F.Cu" "F.Mask" "F.Paste")
			(net "GND")
		)
		(pad "BR46" smd circle
			(at 6.89991 9.269984 180)
			(size 0.450088 0.450088)
			(layers "F.Cu" "F.Mask" "F.Paste")
			(net "PVDDCR_CPU1_P1")
		)
		(pad "BR47" smd circle
			(at 7.839964 9.269984 180)
			(size 0.450088 0.450088)
			(layers "F.Cu" "F.Mask" "F.Paste")
			(net "GND")
		)
		(pad "BR48" smd circle
			(at 8.780018 9.269984 180)
			(size 0.450088 0.450088)
			(layers "F.Cu" "F.Mask" "F.Paste")
			(net "PVDDCR_CPU1_P1")
		)
		(pad "BR49" smd circle
			(at 9.720072 9.269984 180)
			(size 0.450088 0.450088)
			(layers "F.Cu" "F.Mask" "F.Paste")
			(net "GND")
		)
		(pad "BR50" smd circle
			(at 10.659872 9.269984 180)
			(size 0.450088 0.450088)
			(layers "F.Cu" "F.Mask" "F.Paste")
			(net "PVDDCR_CPU1_P1")
		)
		(pad "BR51" smd circle
			(at 11.599926 9.269984 180)
			(size 0.450088 0.450088)
			(layers "F.Cu" "F.Mask" "F.Paste")
			(net "GND")
		)
		(pad "BR52" smd circle
			(at 12.53998 9.269984 180)
			(size 0.450088 0.450088)
			(layers "F.Cu" "F.Mask" "F.Paste")
			(net "PVDDCR_CPU1_P1")
		)
		(pad "BR53" smd circle
			(at 13.480034 9.269984 180)
			(size 0.450088 0.450088)
			(layers "F.Cu" "F.Mask" "F.Paste")
			(net "VSENSE_PVDDIO_P1_DP")
		)
		(pad "BR54" smd circle
			(at 14.420088 9.269984 180)
			(size 0.450088 0.450088)
			(layers "F.Cu" "F.Mask" "F.Paste")
			(net "VSENSE_VSS_SENSE_B_P1")
		)
		(pad "BR55" smd circle
			(at 15.359888 9.269984 180)
			(size 0.450088 0.450088)
			(layers "F.Cu" "F.Mask" "F.Paste")
			(net "GND")
		)
		(pad "BR56" smd circle
			(at 16.299942 9.269984 180)
			(size 0.450088 0.450088)
			(layers "F.Cu" "F.Mask" "F.Paste")
			(net "GND")
		)
		(pad "BR57" smd circle
			(at 17.239996 9.269984 180)
			(size 0.450088 0.450088)
			(layers "F.Cu" "F.Mask" "F.Paste")
			(net "Net_2013")
		)
		(pad "BR58" smd circle
			(at 18.18005 9.269984 180)
			(size 0.450088 0.450088)
			(layers "F.Cu" "F.Mask" "F.Paste")
			(net "PVDDIO_P1")
		)
		(pad "BR59" smd circle
			(at 19.120104 9.269984 180)
			(size 0.450088 0.450088)
			(layers "F.Cu" "F.Mask" "F.Paste")
			(net "GND")
		)
		(pad "BR60" smd circle
			(at 20.059904 9.269984 180)
			(size 0.450088 0.450088)
			(layers "F.Cu" "F.Mask" "F.Paste")
			(net "Net_2021")
		)
		(pad "BR61" smd circle
			(at 20.999958 9.269984 180)
			(size 0.450088 0.450088)
			(layers "F.Cu" "F.Mask" "F.Paste")
			(net "GND")
		)
		(pad "BR62" smd circle
			(at 21.940012 9.269984 180)
			(size 0.450088 0.450088)
			(layers "F.Cu" "F.Mask" "F.Paste")
			(net "GND")
		)
		(pad "BR63" smd circle
			(at 22.880066 9.269984 180)
			(size 0.450088 0.450088)
			(layers "F.Cu" "F.Mask" "F.Paste")
			(net "GND")
		)
		(pad "BR64" smd circle
			(at 23.82012 9.269984 180)
			(size 0.450088 0.450088)
			(layers "F.Cu" "F.Mask" "F.Paste")
			(net "Net_2005")
		)
		(pad "BR65" smd circle
			(at 24.75992 9.269984 180)
			(size 0.450088 0.450088)
			(layers "F.Cu" "F.Mask" "F.Paste")
			(net "PVDDIO_P1")
		)
		(pad "BR66" smd circle
			(at 25.699974 9.269984 180)
			(size 0.450088 0.450088)
			(layers "F.Cu" "F.Mask" "F.Paste")
			(net "GND")
		)
		(pad "BR67" smd circle
			(at 26.640028 9.269984 180)
			(size 0.450088 0.450088)
			(layers "F.Cu" "F.Mask" "F.Paste")
			(net "Net_2037")
		)
		(pad "BR68" smd circle
			(at 27.580082 9.269984 180)
			(size 0.450088 0.450088)
			(layers "F.Cu" "F.Mask" "F.Paste")
			(net "GND")
		)
		(pad "BR69" smd circle
			(at 28.519882 9.269984 180)
			(size 0.450088 0.450088)
			(layers "F.Cu" "F.Mask" "F.Paste")
			(net "GND")
		)
		(pad "BR70" smd circle
			(at 29.459936 9.269984 180)
			(size 0.450088 0.450088)
			(layers "F.Cu" "F.Mask" "F.Paste")
			(net "GND")
		)
		(pad "BR71" smd circle
			(at 30.39999 9.269984 180)
			(size 0.450088 0.450088)
			(layers "F.Cu" "F.Mask" "F.Paste")
			(net "Net_2029")
		)
		(pad "BR72" smd circle
			(at 31.340044 9.269984 180)
			(size 0.450088 0.450088)
			(layers "F.Cu" "F.Mask" "F.Paste")
			(net "PVDDIO_P1")
		)
		(pad "BR73" smd circle
			(at 32.280098 9.269984 180)
			(size 0.450088 0.450088)
			(layers "F.Cu" "F.Mask" "F.Paste")
			(net "GND")
		)
		(pad "BR74" smd circle
			(at 33.219898 9.269984 180)
			(size 0.450088 0.450088)
			(layers "F.Cu" "F.Mask" "F.Paste")
			(net "Net_1997")
		)
		(pad "BR75" smd circle
			(at 34.159952 9.269984 180)
			(size 0.450088 0.450088)
			(layers "F.Cu" "F.Mask" "F.Paste")
			(net "GND")
		)
		(pad "BT2" smd circle
			(at -33.990026 10.07999 180)
			(size 0.450088 0.450088)
			(layers "F.Cu" "F.Mask" "F.Paste")
			(net "M_G_CPU1_SB_CB<4>")
		)
		(pad "BT3" smd circle
			(at -33.049972 10.07999 180)
			(size 0.450088 0.450088)
			(layers "F.Cu" "F.Mask" "F.Paste")
			(net "GND")
		)
		(pad "BT4" smd circle
			(at -32.109918 10.07999 180)
			(size 0.450088 0.450088)
			(layers "F.Cu" "F.Mask" "F.Paste")
			(net "GND")
		)
		(pad "BT5" smd circle
			(at -31.170118 10.07999 180)
			(size 0.450088 0.450088)
			(layers "F.Cu" "F.Mask" "F.Paste")
			(net "GND")
		)
		(pad "BT6" smd circle
			(at -30.230064 10.07999 180)
			(size 0.450088 0.450088)
			(layers "F.Cu" "F.Mask" "F.Paste")
			(net "M_K_CPU1_SB_CB<4>")
		)
		(pad "BT7" smd circle
			(at -29.29001 10.07999 180)
			(size 0.450088 0.450088)
			(layers "F.Cu" "F.Mask" "F.Paste")
			(net "GND")
		)
		(pad "BT8" smd circle
			(at -28.349956 10.07999 180)
			(size 0.450088 0.450088)
			(layers "F.Cu" "F.Mask" "F.Paste")
			(net "GND")
		)
		(pad "BT9" smd circle
			(at -27.409902 10.07999 180)
			(size 0.450088 0.450088)
			(layers "F.Cu" "F.Mask" "F.Paste")
			(net "M_L_CPU1_SB_CB<4>")
		)
		(pad "BT10" smd circle
			(at -26.470102 10.07999 180)
			(size 0.450088 0.450088)
			(layers "F.Cu" "F.Mask" "F.Paste")
			(net "GND")
		)
		(pad "BT11" smd circle
			(at -25.530048 10.07999 180)
			(size 0.450088 0.450088)
			(layers "F.Cu" "F.Mask" "F.Paste")
			(net "GND")
		)
		(pad "BT12" smd circle
			(at -24.589994 10.07999 180)
			(size 0.450088 0.450088)
			(layers "F.Cu" "F.Mask" "F.Paste")
			(net "GND")
		)
		(pad "BT13" smd circle
			(at -23.64994 10.07999 180)
			(size 0.450088 0.450088)
			(layers "F.Cu" "F.Mask" "F.Paste")
			(net "M_H_CPU1_SB_CB<4>")
		)
		(pad "BT14" smd circle
			(at -22.709886 10.07999 180)
			(size 0.450088 0.450088)
			(layers "F.Cu" "F.Mask" "F.Paste")
			(net "GND")
		)
		(pad "BT15" smd circle
			(at -21.770086 10.07999 180)
			(size 0.450088 0.450088)
			(layers "F.Cu" "F.Mask" "F.Paste")
			(net "GND")
		)
		(pad "BT16" smd circle
			(at -20.830032 10.07999 180)
			(size 0.450088 0.450088)
			(layers "F.Cu" "F.Mask" "F.Paste")
			(net "M_J_CPU1_SB_CB<4>")
		)
		(pad "BT17" smd circle
			(at -19.889978 10.07999 180)
			(size 0.450088 0.450088)
			(layers "F.Cu" "F.Mask" "F.Paste")
			(net "GND")
		)
		(pad "BT18" smd circle
			(at -18.949924 10.07999 180)
			(size 0.450088 0.450088)
			(layers "F.Cu" "F.Mask" "F.Paste")
			(net "GND")
		)
		(pad "BT19" smd circle
			(at -18.010124 10.07999 180)
			(size 0.450088 0.450088)
			(layers "F.Cu" "F.Mask" "F.Paste")
			(net "GND")
		)
		(pad "BT20" smd circle
			(at -17.07007 10.07999 180)
			(size 0.450088 0.450088)
			(layers "F.Cu" "F.Mask" "F.Paste")
			(net "M_I_CPU1_SB_CB<4>")
		)
		(pad "BT21" smd circle
			(at -16.130016 10.07999 180)
			(size 0.450088 0.450088)
			(layers "F.Cu" "F.Mask" "F.Paste")
			(net "GND")
		)
		(pad "BT22" smd circle
			(at -15.189962 10.07999 180)
			(size 0.450088 0.450088)
			(layers "F.Cu" "F.Mask" "F.Paste")
			(net "GND")
		)
		(pad "BT23" smd circle
			(at -14.249908 10.07999 180)
			(size 0.450088 0.450088)
			(layers "F.Cu" "F.Mask" "F.Paste")
			(net "PVDDCR_CPU1_P1")
		)
		(pad "BT24" smd circle
			(at -13.310108 10.07999 180)
			(size 0.450088 0.450088)
			(layers "F.Cu" "F.Mask" "F.Paste")
			(net "PVDDCR_CPU1_P1")
		)
		(pad "BT25" smd circle
			(at -12.370054 10.07999 180)
			(size 0.450088 0.450088)
			(layers "F.Cu" "F.Mask" "F.Paste")
			(net "GND")
		)
		(pad "BT26" smd circle
			(at -11.43 10.07999 180)
			(size 0.450088 0.450088)
			(layers "F.Cu" "F.Mask" "F.Paste")
			(net "PVDDCR_CPU1_P1")
		)
		(pad "BT27" smd circle
			(at -10.489946 10.07999 180)
			(size 0.450088 0.450088)
			(layers "F.Cu" "F.Mask" "F.Paste")
			(net "PVDDCR_CPU1_P1")
		)
		(pad "BT28" smd circle
			(at -9.549892 10.07999 180)
			(size 0.450088 0.450088)
			(layers "F.Cu" "F.Mask" "F.Paste")
			(net "GND")
		)
		(pad "BT29" smd circle
			(at -8.610092 10.07999 180)
			(size 0.450088 0.450088)
			(layers "F.Cu" "F.Mask" "F.Paste")
			(net "PVDDCR_CPU1_P1")
		)
		(pad "BT30" smd circle
			(at -7.670038 10.07999 180)
			(size 0.450088 0.450088)
			(layers "F.Cu" "F.Mask" "F.Paste")
			(net "PVDDCR_CPU1_P1")
		)
		(pad "BT31" smd circle
			(at -6.729984 10.07999 180)
			(size 0.450088 0.450088)
			(layers "F.Cu" "F.Mask" "F.Paste")
			(net "GND")
		)
		(pad "BT32" smd circle
			(at -5.78993 10.07999 180)
			(size 0.450088 0.450088)
			(layers "F.Cu" "F.Mask" "F.Paste")
			(net "PVDDCR_CPU1_P1")
		)
		(pad "BT33" smd circle
			(at -4.849876 10.07999 180)
			(size 0.450088 0.450088)
			(layers "F.Cu" "F.Mask" "F.Paste")
			(net "PVDDCR_CPU1_P1")
		)
		(pad "BT34" smd circle
			(at -3.910076 10.07999 180)
			(size 0.450088 0.450088)
			(layers "F.Cu" "F.Mask" "F.Paste")
			(net "GND")
		)
		(pad "BT35" smd circle
			(at -2.970022 10.07999 180)
			(size 0.450088 0.450088)
			(layers "F.Cu" "F.Mask" "F.Paste")
			(net "P5E_CPU1_P2_TX_DN<0>")
		)
		(pad "BT36" smd circle
			(at -2.029968 10.07999 180)
			(size 0.450088 0.450088)
			(layers "F.Cu" "F.Mask" "F.Paste")
			(net "P5E_CPU1_P2_TX_DP<0>")
		)
		(pad "BT37" smd circle
			(at -1.089914 10.07999 180)
			(size 0.450088 0.450088)
			(layers "F.Cu" "F.Mask" "F.Paste")
			(net "GND")
		)
		(pad "BT39" smd circle
			(at 0.78994 10.07999 180)
			(size 0.450088 0.450088)
			(layers "F.Cu" "F.Mask" "F.Paste")
			(net "GND")
		)
		(pad "BT40" smd circle
			(at 1.729994 10.07999 180)
			(size 0.450088 0.450088)
			(layers "F.Cu" "F.Mask" "F.Paste")
			(net "P5E_CPU1_P0_RX_DP<15>")
		)
		(pad "BT41" smd circle
			(at 2.670048 10.07999 180)
			(size 0.450088 0.450088)
			(layers "F.Cu" "F.Mask" "F.Paste")
			(net "P5E_CPU1_P0_RX_DN<15>")
		)
		(pad "BT42" smd circle
			(at 3.610102 10.07999 180)
			(size 0.450088 0.450088)
			(layers "F.Cu" "F.Mask" "F.Paste")
			(net "GND")
		)
		(pad "BT43" smd circle
			(at 4.549902 10.07999 180)
			(size 0.450088 0.450088)
			(layers "F.Cu" "F.Mask" "F.Paste")
			(net "PVDDCR_CPU1_P1")
		)
		(pad "BT44" smd circle
			(at 5.489956 10.07999 180)
			(size 0.450088 0.450088)
			(layers "F.Cu" "F.Mask" "F.Paste")
			(net "PVDDCR_CPU1_P1")
		)
		(pad "BT45" smd circle
			(at 6.43001 10.07999 180)
			(size 0.450088 0.450088)
			(layers "F.Cu" "F.Mask" "F.Paste")
			(net "GND")
		)
		(pad "BT46" smd circle
			(at 7.370064 10.07999 180)
			(size 0.450088 0.450088)
			(layers "F.Cu" "F.Mask" "F.Paste")
			(net "PVDDCR_CPU1_P1")
		)
		(pad "BT47" smd circle
			(at 8.310118 10.07999 180)
			(size 0.450088 0.450088)
			(layers "F.Cu" "F.Mask" "F.Paste")
			(net "PVDDCR_CPU1_P1")
		)
		(pad "BT48" smd circle
			(at 9.249918 10.07999 180)
			(size 0.450088 0.450088)
			(layers "F.Cu" "F.Mask" "F.Paste")
			(net "GND")
		)
		(pad "BT49" smd circle
			(at 10.189972 10.07999 180)
			(size 0.450088 0.450088)
			(layers "F.Cu" "F.Mask" "F.Paste")
			(net "PVDDCR_CPU1_P1")
		)
		(pad "BT50" smd circle
			(at 11.130026 10.07999 180)
			(size 0.450088 0.450088)
			(layers "F.Cu" "F.Mask" "F.Paste")
			(net "PVDDCR_CPU1_P1")
		)
		(pad "BT51" smd circle
			(at 12.07008 10.07999 180)
			(size 0.450088 0.450088)
			(layers "F.Cu" "F.Mask" "F.Paste")
			(net "GND")
		)
		(pad "BT52" smd circle
			(at 13.00988 10.07999 180)
			(size 0.450088 0.450088)
			(layers "F.Cu" "F.Mask" "F.Paste")
			(net "PVDDCR_CPU1_P1")
		)
		(pad "BT53" smd circle
			(at 13.949934 10.07999 180)
			(size 0.450088 0.450088)
			(layers "F.Cu" "F.Mask" "F.Paste")
			(net "PVDDCR_CPU1_P1")
		)
		(pad "BT54" smd circle
			(at 14.889988 10.07999 180)
			(size 0.450088 0.450088)
			(layers "F.Cu" "F.Mask" "F.Paste")
			(net "GND")
		)
		(pad "BT55" smd circle
			(at 15.830042 10.07999 180)
			(size 0.450088 0.450088)
			(layers "F.Cu" "F.Mask" "F.Paste")
			(net "GND")
		)
		(pad "BT56" smd circle
			(at 16.770096 10.07999 180)
			(size 0.450088 0.450088)
			(layers "F.Cu" "F.Mask" "F.Paste")
			(net "M_C_CPU1_SB_CB<4>")
		)
		(pad "BT57" smd circle
			(at 17.709896 10.07999 180)
			(size 0.450088 0.450088)
			(layers "F.Cu" "F.Mask" "F.Paste")
			(net "GND")
		)
		(pad "BT58" smd circle
			(at 18.64995 10.07999 180)
			(size 0.450088 0.450088)
			(layers "F.Cu" "F.Mask" "F.Paste")
			(net "GND")
		)
		(pad "BT59" smd circle
			(at 19.590004 10.07999 180)
			(size 0.450088 0.450088)
			(layers "F.Cu" "F.Mask" "F.Paste")
			(net "GND")
		)
		(pad "BT60" smd circle
			(at 20.530058 10.07999 180)
			(size 0.450088 0.450088)
			(layers "F.Cu" "F.Mask" "F.Paste")
			(net "M_D_CPU1_SB_CB<4>")
		)
		(pad "BT61" smd circle
			(at 21.470112 10.07999 180)
			(size 0.450088 0.450088)
			(layers "F.Cu" "F.Mask" "F.Paste")
			(net "GND")
		)
		(pad "BT62" smd circle
			(at 22.409912 10.07999 180)
			(size 0.450088 0.450088)
			(layers "F.Cu" "F.Mask" "F.Paste")
			(net "GND")
		)
		(pad "BT63" smd circle
			(at 23.349966 10.07999 180)
			(size 0.450088 0.450088)
			(layers "F.Cu" "F.Mask" "F.Paste")
			(net "M_B_CPU1_SB_CB<4>")
		)
		(pad "BT64" smd circle
			(at 24.29002 10.07999 180)
			(size 0.450088 0.450088)
			(layers "F.Cu" "F.Mask" "F.Paste")
			(net "GND")
		)
		(pad "BT65" smd circle
			(at 25.230074 10.07999 180)
			(size 0.450088 0.450088)
			(layers "F.Cu" "F.Mask" "F.Paste")
			(net "GND")
		)
		(pad "BT66" smd circle
			(at 26.170128 10.07999 180)
			(size 0.450088 0.450088)
			(layers "F.Cu" "F.Mask" "F.Paste")
			(net "GND")
		)
		(pad "BT67" smd circle
			(at 27.109928 10.07999 180)
			(size 0.450088 0.450088)
			(layers "F.Cu" "F.Mask" "F.Paste")
			(net "M_F_CPU1_SB_CB<4>")
		)
		(pad "BT68" smd circle
			(at 28.049982 10.07999 180)
			(size 0.450088 0.450088)
			(layers "F.Cu" "F.Mask" "F.Paste")
			(net "GND")
		)
		(pad "BT69" smd circle
			(at 28.990036 10.07999 180)
			(size 0.450088 0.450088)
			(layers "F.Cu" "F.Mask" "F.Paste")
			(net "GND")
		)
		(pad "BT70" smd circle
			(at 29.93009 10.07999 180)
			(size 0.450088 0.450088)
			(layers "F.Cu" "F.Mask" "F.Paste")
			(net "M_E_CPU1_SB_CB<4>")
		)
		(pad "BT71" smd circle
			(at 30.86989 10.07999 180)
			(size 0.450088 0.450088)
			(layers "F.Cu" "F.Mask" "F.Paste")
			(net "GND")
		)
		(pad "BT72" smd circle
			(at 31.809944 10.07999 180)
			(size 0.450088 0.450088)
			(layers "F.Cu" "F.Mask" "F.Paste")
			(net "GND")
		)
		(pad "BT73" smd circle
			(at 32.749998 10.07999 180)
			(size 0.450088 0.450088)
			(layers "F.Cu" "F.Mask" "F.Paste")
			(net "GND")
		)
		(pad "BT74" smd circle
			(at 33.690052 10.07999 180)
			(size 0.450088 0.450088)
			(layers "F.Cu" "F.Mask" "F.Paste")
			(net "M_A_CPU1_SB_CB<4>")
		)
		(pad "BU1" smd circle
			(at -34.459926 10.889996 180)
			(size 0.450088 0.450088)
			(layers "F.Cu" "F.Mask" "F.Paste")
			(net "GND")
		)
		(pad "BU2" smd circle
			(at -33.519872 10.889996 180)
			(size 0.450088 0.450088)
			(layers "F.Cu" "F.Mask" "F.Paste")
			(net "M_G_CPU1_SB_CB<6>")
		)
		(pad "BU3" smd circle
			(at -32.580072 10.889996 180)
			(size 0.450088 0.450088)
			(layers "F.Cu" "F.Mask" "F.Paste")
			(net "M_G_CPU1_SB_CB<5>")
		)
		(pad "BU4" smd circle
			(at -31.640018 10.889996 180)
			(size 0.450088 0.450088)
			(layers "F.Cu" "F.Mask" "F.Paste")
			(net "GND")
		)
		(pad "BU5" smd circle
			(at -30.699964 10.889996 180)
			(size 0.450088 0.450088)
			(layers "F.Cu" "F.Mask" "F.Paste")
			(net "M_K_CPU1_SB_CB<6>")
		)
		(pad "BU6" smd circle
			(at -29.75991 10.889996 180)
			(size 0.450088 0.450088)
			(layers "F.Cu" "F.Mask" "F.Paste")
			(net "GND")
		)
		(pad "BU7" smd circle
			(at -28.82011 10.889996 180)
			(size 0.450088 0.450088)
			(layers "F.Cu" "F.Mask" "F.Paste")
			(net "M_K_CPU1_SB_CB<5>")
		)
		(pad "BU8" smd circle
			(at -27.880056 10.889996 180)
			(size 0.450088 0.450088)
			(layers "F.Cu" "F.Mask" "F.Paste")
			(net "GND")
		)
		(pad "BU9" smd circle
			(at -26.940002 10.889996 180)
			(size 0.450088 0.450088)
			(layers "F.Cu" "F.Mask" "F.Paste")
			(net "M_L_CPU1_SB_CB<6>")
		)
		(pad "BU10" smd circle
			(at -25.999948 10.889996 180)
			(size 0.450088 0.450088)
			(layers "F.Cu" "F.Mask" "F.Paste")
			(net "M_L_CPU1_SB_CB<5>")
		)
		(pad "BU11" smd circle
			(at -25.059894 10.889996 180)
			(size 0.450088 0.450088)
			(layers "F.Cu" "F.Mask" "F.Paste")
			(net "GND")
		)
		(pad "BU12" smd circle
			(at -24.120094 10.889996 180)
			(size 0.450088 0.450088)
			(layers "F.Cu" "F.Mask" "F.Paste")
			(net "M_H_CPU1_SB_CB<6>")
		)
		(pad "BU13" smd circle
			(at -23.18004 10.889996 180)
			(size 0.450088 0.450088)
			(layers "F.Cu" "F.Mask" "F.Paste")
			(net "GND")
		)
		(pad "BU14" smd circle
			(at -22.239986 10.889996 180)
			(size 0.450088 0.450088)
			(layers "F.Cu" "F.Mask" "F.Paste")
			(net "M_H_CPU1_SB_CB<5>")
		)
		(pad "BU15" smd circle
			(at -21.299932 10.889996 180)
			(size 0.450088 0.450088)
			(layers "F.Cu" "F.Mask" "F.Paste")
			(net "GND")
		)
		(pad "BU16" smd circle
			(at -20.359878 10.889996 180)
			(size 0.450088 0.450088)
			(layers "F.Cu" "F.Mask" "F.Paste")
			(net "M_J_CPU1_SB_CB<6>")
		)
		(pad "BU17" smd circle
			(at -19.420078 10.889996 180)
			(size 0.450088 0.450088)
			(layers "F.Cu" "F.Mask" "F.Paste")
			(net "M_J_CPU1_SB_CB<5>")
		)
		(pad "BU18" smd circle
			(at -18.480024 10.889996 180)
			(size 0.450088 0.450088)
			(layers "F.Cu" "F.Mask" "F.Paste")
			(net "GND")
		)
		(pad "BU19" smd circle
			(at -17.53997 10.889996 180)
			(size 0.450088 0.450088)
			(layers "F.Cu" "F.Mask" "F.Paste")
			(net "M_I_CPU1_SB_CB<6>")
		)
		(pad "BU20" smd circle
			(at -16.599916 10.889996 180)
			(size 0.450088 0.450088)
			(layers "F.Cu" "F.Mask" "F.Paste")
			(net "GND")
		)
		(pad "BU21" smd circle
			(at -15.660116 10.889996 180)
			(size 0.450088 0.450088)
			(layers "F.Cu" "F.Mask" "F.Paste")
			(net "M_I_CPU1_SB_CB<5>")
		)
		(pad "BU22" smd circle
			(at -14.720062 10.889996 180)
			(size 0.450088 0.450088)
			(layers "F.Cu" "F.Mask" "F.Paste")
			(net "GND")
		)
		(pad "BU23" smd circle
			(at -13.780008 10.889996 180)
			(size 0.450088 0.450088)
			(layers "F.Cu" "F.Mask" "F.Paste")
			(net "P5E_CPU1_P2_TX_DN<13>")
		)
		(pad "BU24" smd circle
			(at -12.839954 10.889996 180)
			(size 0.450088 0.450088)
			(layers "F.Cu" "F.Mask" "F.Paste")
			(net "P5E_CPU1_P2_TX_DP<13>")
		)
		(pad "BU25" smd circle
			(at -11.8999 10.889996 180)
			(size 0.450088 0.450088)
			(layers "F.Cu" "F.Mask" "F.Paste")
			(net "GND")
		)
		(pad "BU26" smd circle
			(at -10.9601 10.889996 180)
			(size 0.450088 0.450088)
			(layers "F.Cu" "F.Mask" "F.Paste")
			(net "P5E_CPU1_P2_TX_DN<10>")
		)
		(pad "BU27" smd circle
			(at -10.020046 10.889996 180)
			(size 0.450088 0.450088)
			(layers "F.Cu" "F.Mask" "F.Paste")
			(net "P5E_CPU1_P2_TX_DP<10>")
		)
		(pad "BU28" smd circle
			(at -9.079992 10.889996 180)
			(size 0.450088 0.450088)
			(layers "F.Cu" "F.Mask" "F.Paste")
			(net "GND")
		)
		(pad "BU29" smd circle
			(at -8.139938 10.889996 180)
			(size 0.450088 0.450088)
			(layers "F.Cu" "F.Mask" "F.Paste")
			(net "P5E_CPU1_P2_TX_DN<7>")
		)
		(pad "BU30" smd circle
			(at -7.199884 10.889996 180)
			(size 0.450088 0.450088)
			(layers "F.Cu" "F.Mask" "F.Paste")
			(net "P5E_CPU1_P2_TX_DP<7>")
		)
		(pad "BU31" smd circle
			(at -6.260084 10.889996 180)
			(size 0.450088 0.450088)
			(layers "F.Cu" "F.Mask" "F.Paste")
			(net "GND")
		)
		(pad "BU32" smd circle
			(at -5.32003 10.889996 180)
			(size 0.450088 0.450088)
			(layers "F.Cu" "F.Mask" "F.Paste")
			(net "P5E_CPU1_P2_TX_DN<4>")
		)
		(pad "BU33" smd circle
			(at -4.379976 10.889996 180)
			(size 0.450088 0.450088)
			(layers "F.Cu" "F.Mask" "F.Paste")
			(net "P5E_CPU1_P2_TX_DP<4>")
		)
		(pad "BU34" smd circle
			(at -3.439922 10.889996 180)
			(size 0.450088 0.450088)
			(layers "F.Cu" "F.Mask" "F.Paste")
			(net "GND")
		)
		(pad "BU35" smd circle
			(at -2.500122 10.889996 180)
			(size 0.450088 0.450088)
			(layers "F.Cu" "F.Mask" "F.Paste")
			(net "GND")
		)
		(pad "BU36" smd circle
			(at -1.560068 10.889996 180)
			(size 0.450088 0.450088)
			(layers "F.Cu" "F.Mask" "F.Paste")
			(net "GND")
		)
		(pad "BU40" smd circle
			(at 1.260094 10.889996 180)
			(size 0.450088 0.450088)
			(layers "F.Cu" "F.Mask" "F.Paste")
			(net "GND")
		)
		(pad "BU41" smd circle
			(at 2.199894 10.889996 180)
			(size 0.450088 0.450088)
			(layers "F.Cu" "F.Mask" "F.Paste")
			(net "GND")
		)
		(pad "BU42" smd circle
			(at 3.139948 10.889996 180)
			(size 0.450088 0.450088)
			(layers "F.Cu" "F.Mask" "F.Paste")
			(net "GND")
		)
		(pad "BU43" smd circle
			(at 4.080002 10.889996 180)
			(size 0.450088 0.450088)
			(layers "F.Cu" "F.Mask" "F.Paste")
			(net "P5E_CPU1_P0_RX_DP<11>")
		)
		(pad "BU44" smd circle
			(at 5.020056 10.889996 180)
			(size 0.450088 0.450088)
			(layers "F.Cu" "F.Mask" "F.Paste")
			(net "P5E_CPU1_P0_RX_DN<11>")
		)
		(pad "BU45" smd circle
			(at 5.96011 10.889996 180)
			(size 0.450088 0.450088)
			(layers "F.Cu" "F.Mask" "F.Paste")
			(net "GND")
		)
		(pad "BU46" smd circle
			(at 6.89991 10.889996 180)
			(size 0.450088 0.450088)
			(layers "F.Cu" "F.Mask" "F.Paste")
			(net "P5E_CPU1_P0_RX_DP<8>")
		)
		(pad "BU47" smd circle
			(at 7.839964 10.889996 180)
			(size 0.450088 0.450088)
			(layers "F.Cu" "F.Mask" "F.Paste")
			(net "P5E_CPU1_P0_RX_DN<8>")
		)
		(pad "BU48" smd circle
			(at 8.780018 10.889996 180)
			(size 0.450088 0.450088)
			(layers "F.Cu" "F.Mask" "F.Paste")
			(net "GND")
		)
		(pad "BU49" smd circle
			(at 9.720072 10.889996 180)
			(size 0.450088 0.450088)
			(layers "F.Cu" "F.Mask" "F.Paste")
			(net "P5E_CPU1_P0_RX_DP<5>")
		)
		(pad "BU50" smd circle
			(at 10.659872 10.889996 180)
			(size 0.450088 0.450088)
			(layers "F.Cu" "F.Mask" "F.Paste")
			(net "P5E_CPU1_P0_RX_DN<5>")
		)
		(pad "BU51" smd circle
			(at 11.599926 10.889996 180)
			(size 0.450088 0.450088)
			(layers "F.Cu" "F.Mask" "F.Paste")
			(net "GND")
		)
		(pad "BU52" smd circle
			(at 12.53998 10.889996 180)
			(size 0.450088 0.450088)
			(layers "F.Cu" "F.Mask" "F.Paste")
			(net "P5E_CPU1_P0_RX_DP<2>")
		)
		(pad "BU53" smd circle
			(at 13.480034 10.889996 180)
			(size 0.450088 0.450088)
			(layers "F.Cu" "F.Mask" "F.Paste")
			(net "P5E_CPU1_P0_RX_DN<2>")
		)
		(pad "BU54" smd circle
			(at 14.420088 10.889996 180)
			(size 0.450088 0.450088)
			(layers "F.Cu" "F.Mask" "F.Paste")
			(net "GND")
		)
		(pad "BU55" smd circle
			(at 15.359888 10.889996 180)
			(size 0.450088 0.450088)
			(layers "F.Cu" "F.Mask" "F.Paste")
			(net "M_C_CPU1_SB_CB<5>")
		)
		(pad "BU56" smd circle
			(at 16.299942 10.889996 180)
			(size 0.450088 0.450088)
			(layers "F.Cu" "F.Mask" "F.Paste")
			(net "GND")
		)
		(pad "BU57" smd circle
			(at 17.239996 10.889996 180)
			(size 0.450088 0.450088)
			(layers "F.Cu" "F.Mask" "F.Paste")
			(net "M_C_CPU1_SB_CB<6>")
		)
		(pad "BU58" smd circle
			(at 18.18005 10.889996 180)
			(size 0.450088 0.450088)
			(layers "F.Cu" "F.Mask" "F.Paste")
			(net "GND")
		)
		(pad "BU59" smd circle
			(at 19.120104 10.889996 180)
			(size 0.450088 0.450088)
			(layers "F.Cu" "F.Mask" "F.Paste")
			(net "M_D_CPU1_SB_CB<5>")
		)
		(pad "BU60" smd circle
			(at 20.059904 10.889996 180)
			(size 0.450088 0.450088)
			(layers "F.Cu" "F.Mask" "F.Paste")
			(net "M_D_CPU1_SB_CB<6>")
		)
		(pad "BU61" smd circle
			(at 20.999958 10.889996 180)
			(size 0.450088 0.450088)
			(layers "F.Cu" "F.Mask" "F.Paste")
			(net "GND")
		)
		(pad "BU62" smd circle
			(at 21.940012 10.889996 180)
			(size 0.450088 0.450088)
			(layers "F.Cu" "F.Mask" "F.Paste")
			(net "M_B_CPU1_SB_CB<5>")
		)
		(pad "BU63" smd circle
			(at 22.880066 10.889996 180)
			(size 0.450088 0.450088)
			(layers "F.Cu" "F.Mask" "F.Paste")
			(net "GND")
		)
		(pad "BU64" smd circle
			(at 23.82012 10.889996 180)
			(size 0.450088 0.450088)
			(layers "F.Cu" "F.Mask" "F.Paste")
			(net "M_B_CPU1_SB_CB<6>")
		)
		(pad "BU65" smd circle
			(at 24.75992 10.889996 180)
			(size 0.450088 0.450088)
			(layers "F.Cu" "F.Mask" "F.Paste")
			(net "GND")
		)
		(pad "BU66" smd circle
			(at 25.699974 10.889996 180)
			(size 0.450088 0.450088)
			(layers "F.Cu" "F.Mask" "F.Paste")
			(net "M_F_CPU1_SB_CB<5>")
		)
		(pad "BU67" smd circle
			(at 26.640028 10.889996 180)
			(size 0.450088 0.450088)
			(layers "F.Cu" "F.Mask" "F.Paste")
			(net "M_F_CPU1_SB_CB<6>")
		)
		(pad "BU68" smd circle
			(at 27.580082 10.889996 180)
			(size 0.450088 0.450088)
			(layers "F.Cu" "F.Mask" "F.Paste")
			(net "GND")
		)
		(pad "BU69" smd circle
			(at 28.519882 10.889996 180)
			(size 0.450088 0.450088)
			(layers "F.Cu" "F.Mask" "F.Paste")
			(net "M_E_CPU1_SB_CB<5>")
		)
		(pad "BU70" smd circle
			(at 29.459936 10.889996 180)
			(size 0.450088 0.450088)
			(layers "F.Cu" "F.Mask" "F.Paste")
			(net "GND")
		)
		(pad "BU71" smd circle
			(at 30.39999 10.889996 180)
			(size 0.450088 0.450088)
			(layers "F.Cu" "F.Mask" "F.Paste")
			(net "M_E_CPU1_SB_CB<6>")
		)
		(pad "BU72" smd circle
			(at 31.340044 10.889996 180)
			(size 0.450088 0.450088)
			(layers "F.Cu" "F.Mask" "F.Paste")
			(net "GND")
		)
		(pad "BU73" smd circle
			(at 32.280098 10.889996 180)
			(size 0.450088 0.450088)
			(layers "F.Cu" "F.Mask" "F.Paste")
			(net "M_A_CPU1_SB_CB<5>")
		)
		(pad "BU74" smd circle
			(at 33.219898 10.889996 180)
			(size 0.450088 0.450088)
			(layers "F.Cu" "F.Mask" "F.Paste")
			(net "M_A_CPU1_SB_CB<6>")
		)
		(pad "BU75" smd circle
			(at 34.159952 10.889996 180)
			(size 0.450088 0.450088)
			(layers "F.Cu" "F.Mask" "F.Paste")
			(net "GND")
		)
		(pad "BV2" smd circle
			(at -33.990026 11.700002 180)
			(size 0.450088 0.450088)
			(layers "F.Cu" "F.Mask" "F.Paste")
			(net "M_G_CPU1_SB_DQS_DP<9>")
		)
		(pad "BV3" smd circle
			(at -33.049972 11.700002 180)
			(size 0.450088 0.450088)
			(layers "F.Cu" "F.Mask" "F.Paste")
			(net "GND")
		)
		(pad "BV4" smd circle
			(at -32.109918 11.700002 180)
			(size 0.450088 0.450088)
			(layers "F.Cu" "F.Mask" "F.Paste")
			(net "M_G_CPU1_SB_CB<7>")
		)
		(pad "BV5" smd circle
			(at -31.170118 11.700002 180)
			(size 0.450088 0.450088)
			(layers "F.Cu" "F.Mask" "F.Paste")
			(net "PVDD11_S3_P1")
		)
		(pad "BV6" smd circle
			(at -30.230064 11.700002 180)
			(size 0.450088 0.450088)
			(layers "F.Cu" "F.Mask" "F.Paste")
			(net "M_K_CPU1_SB_DQS_DP<9>")
		)
		(pad "BV7" smd circle
			(at -29.29001 11.700002 180)
			(size 0.450088 0.450088)
			(layers "F.Cu" "F.Mask" "F.Paste")
			(net "M_K_CPU1_SB_CB<7>")
		)
		(pad "BV8" smd circle
			(at -28.349956 11.700002 180)
			(size 0.450088 0.450088)
			(layers "F.Cu" "F.Mask" "F.Paste")
			(net "GND")
		)
		(pad "BV9" smd circle
			(at -27.409902 11.700002 180)
			(size 0.450088 0.450088)
			(layers "F.Cu" "F.Mask" "F.Paste")
			(net "M_L_CPU1_SB_DQS_DP<9>")
		)
		(pad "BV10" smd circle
			(at -26.470102 11.700002 180)
			(size 0.450088 0.450088)
			(layers "F.Cu" "F.Mask" "F.Paste")
			(net "GND")
		)
		(pad "BV11" smd circle
			(at -25.530048 11.700002 180)
			(size 0.450088 0.450088)
			(layers "F.Cu" "F.Mask" "F.Paste")
			(net "M_L_CPU1_SB_CB<7>")
		)
		(pad "BV12" smd circle
			(at -24.589994 11.700002 180)
			(size 0.450088 0.450088)
			(layers "F.Cu" "F.Mask" "F.Paste")
			(net "PVDD11_S3_P1")
		)
		(pad "BV13" smd circle
			(at -23.64994 11.700002 180)
			(size 0.450088 0.450088)
			(layers "F.Cu" "F.Mask" "F.Paste")
			(net "M_H_CPU1_SB_DQS_DP<9>")
		)
		(pad "BV14" smd circle
			(at -22.709886 11.700002 180)
			(size 0.450088 0.450088)
			(layers "F.Cu" "F.Mask" "F.Paste")
			(net "M_H_CPU1_SB_CB<7>")
		)
		(pad "BV15" smd circle
			(at -21.770086 11.700002 180)
			(size 0.450088 0.450088)
			(layers "F.Cu" "F.Mask" "F.Paste")
			(net "GND")
		)
		(pad "BV16" smd circle
			(at -20.830032 11.700002 180)
			(size 0.450088 0.450088)
			(layers "F.Cu" "F.Mask" "F.Paste")
			(net "M_J_CPU1_SB_DQS_DP<9>")
		)
		(pad "BV17" smd circle
			(at -19.889978 11.700002 180)
			(size 0.450088 0.450088)
			(layers "F.Cu" "F.Mask" "F.Paste")
			(net "GND")
		)
		(pad "BV18" smd circle
			(at -18.949924 11.700002 180)
			(size 0.450088 0.450088)
			(layers "F.Cu" "F.Mask" "F.Paste")
			(net "M_J_CPU1_SB_CB<7>")
		)
		(pad "BV19" smd circle
			(at -18.010124 11.700002 180)
			(size 0.450088 0.450088)
			(layers "F.Cu" "F.Mask" "F.Paste")
			(net "PVDD11_S3_P1")
		)
		(pad "BV20" smd circle
			(at -17.07007 11.700002 180)
			(size 0.450088 0.450088)
			(layers "F.Cu" "F.Mask" "F.Paste")
			(net "M_I_CPU1_SB_DQS_DP<9>")
		)
		(pad "BV21" smd circle
			(at -16.130016 11.700002 180)
			(size 0.450088 0.450088)
			(layers "F.Cu" "F.Mask" "F.Paste")
			(net "M_I_CPU1_SB_CB<7>")
		)
		(pad "BV22" smd circle
			(at -15.189962 11.700002 180)
			(size 0.450088 0.450088)
			(layers "F.Cu" "F.Mask" "F.Paste")
			(net "PVDD11_S3_P1")
		)
		(pad "BV23" smd circle
			(at -14.249908 11.700002 180)
			(size 0.450088 0.450088)
			(layers "F.Cu" "F.Mask" "F.Paste")
			(net "GND")
		)
		(pad "BV24" smd circle
			(at -13.310108 11.700002 180)
			(size 0.450088 0.450088)
			(layers "F.Cu" "F.Mask" "F.Paste")
			(net "GND")
		)
		(pad "BV25" smd circle
			(at -12.370054 11.700002 180)
			(size 0.450088 0.450088)
			(layers "F.Cu" "F.Mask" "F.Paste")
			(net "GND")
		)
		(pad "BV26" smd circle
			(at -11.43 11.700002 180)
			(size 0.450088 0.450088)
			(layers "F.Cu" "F.Mask" "F.Paste")
			(net "GND")
		)
		(pad "BV27" smd circle
			(at -10.489946 11.700002 180)
			(size 0.450088 0.450088)
			(layers "F.Cu" "F.Mask" "F.Paste")
			(net "GND")
		)
		(pad "BV28" smd circle
			(at -9.549892 11.700002 180)
			(size 0.450088 0.450088)
			(layers "F.Cu" "F.Mask" "F.Paste")
			(net "GND")
		)
		(pad "BV29" smd circle
			(at -8.610092 11.700002 180)
			(size 0.450088 0.450088)
			(layers "F.Cu" "F.Mask" "F.Paste")
			(net "GND")
		)
		(pad "BV30" smd circle
			(at -7.670038 11.700002 180)
			(size 0.450088 0.450088)
			(layers "F.Cu" "F.Mask" "F.Paste")
			(net "GND")
		)
		(pad "BV31" smd circle
			(at -6.729984 11.700002 180)
			(size 0.450088 0.450088)
			(layers "F.Cu" "F.Mask" "F.Paste")
			(net "GND")
		)
		(pad "BV32" smd circle
			(at -5.78993 11.700002 180)
			(size 0.450088 0.450088)
			(layers "F.Cu" "F.Mask" "F.Paste")
			(net "GND")
		)
		(pad "BV33" smd circle
			(at -4.849876 11.700002 180)
			(size 0.450088 0.450088)
			(layers "F.Cu" "F.Mask" "F.Paste")
			(net "GND")
		)
		(pad "BV34" smd circle
			(at -3.910076 11.700002 180)
			(size 0.450088 0.450088)
			(layers "F.Cu" "F.Mask" "F.Paste")
			(net "GND")
		)
		(pad "BV35" smd circle
			(at -2.970022 11.700002 180)
			(size 0.450088 0.450088)
			(layers "F.Cu" "F.Mask" "F.Paste")
			(net "P5E_CPU1_P2_TX_DN<1>")
		)
		(pad "BV36" smd circle
			(at -2.029968 11.700002 180)
			(size 0.450088 0.450088)
			(layers "F.Cu" "F.Mask" "F.Paste")
			(net "P5E_CPU1_P2_TX_DP<1>")
		)
		(pad "BV37" smd circle
			(at -1.089914 11.700002 180)
			(size 0.450088 0.450088)
			(layers "F.Cu" "F.Mask" "F.Paste")
			(net "GND")
		)
		(pad "BV39" smd circle
			(at 0.78994 11.700002 180)
			(size 0.450088 0.450088)
			(layers "F.Cu" "F.Mask" "F.Paste")
			(net "GND")
		)
		(pad "BV40" smd circle
			(at 1.729994 11.700002 180)
			(size 0.450088 0.450088)
			(layers "F.Cu" "F.Mask" "F.Paste")
			(net "P5E_CPU1_P0_RX_DP<14>")
		)
		(pad "BV41" smd circle
			(at 2.670048 11.700002 180)
			(size 0.450088 0.450088)
			(layers "F.Cu" "F.Mask" "F.Paste")
			(net "P5E_CPU1_P0_RX_DN<14>")
		)
		(pad "BV42" smd circle
			(at 3.610102 11.700002 180)
			(size 0.450088 0.450088)
			(layers "F.Cu" "F.Mask" "F.Paste")
			(net "GND")
		)
		(pad "BV43" smd circle
			(at 4.549902 11.700002 180)
			(size 0.450088 0.450088)
			(layers "F.Cu" "F.Mask" "F.Paste")
			(net "GND")
		)
		(pad "BV44" smd circle
			(at 5.489956 11.700002 180)
			(size 0.450088 0.450088)
			(layers "F.Cu" "F.Mask" "F.Paste")
			(net "GND")
		)
		(pad "BV45" smd circle
			(at 6.43001 11.700002 180)
			(size 0.450088 0.450088)
			(layers "F.Cu" "F.Mask" "F.Paste")
			(net "GND")
		)
		(pad "BV46" smd circle
			(at 7.370064 11.700002 180)
			(size 0.450088 0.450088)
			(layers "F.Cu" "F.Mask" "F.Paste")
			(net "GND")
		)
		(pad "BV47" smd circle
			(at 8.310118 11.700002 180)
			(size 0.450088 0.450088)
			(layers "F.Cu" "F.Mask" "F.Paste")
			(net "GND")
		)
		(pad "BV48" smd circle
			(at 9.249918 11.700002 180)
			(size 0.450088 0.450088)
			(layers "F.Cu" "F.Mask" "F.Paste")
			(net "GND")
		)
		(pad "BV49" smd circle
			(at 10.189972 11.700002 180)
			(size 0.450088 0.450088)
			(layers "F.Cu" "F.Mask" "F.Paste")
			(net "GND")
		)
		(pad "BV50" smd circle
			(at 11.130026 11.700002 180)
			(size 0.450088 0.450088)
			(layers "F.Cu" "F.Mask" "F.Paste")
			(net "GND")
		)
		(pad "BV51" smd circle
			(at 12.07008 11.700002 180)
			(size 0.450088 0.450088)
			(layers "F.Cu" "F.Mask" "F.Paste")
			(net "GND")
		)
		(pad "BV52" smd circle
			(at 13.00988 11.700002 180)
			(size 0.450088 0.450088)
			(layers "F.Cu" "F.Mask" "F.Paste")
			(net "GND")
		)
		(pad "BV53" smd circle
			(at 13.949934 11.700002 180)
			(size 0.450088 0.450088)
			(layers "F.Cu" "F.Mask" "F.Paste")
			(net "GND")
		)
		(pad "BV54" smd circle
			(at 14.889988 11.700002 180)
			(size 0.450088 0.450088)
			(layers "F.Cu" "F.Mask" "F.Paste")
			(net "PVDDIO_P1")
		)
		(pad "BV55" smd circle
			(at 15.830042 11.700002 180)
			(size 0.450088 0.450088)
			(layers "F.Cu" "F.Mask" "F.Paste")
			(net "M_C_CPU1_SB_CB<7>")
		)
		(pad "BV56" smd circle
			(at 16.770096 11.700002 180)
			(size 0.450088 0.450088)
			(layers "F.Cu" "F.Mask" "F.Paste")
			(net "M_C_CPU1_SB_DQS_DP<9>")
		)
		(pad "BV57" smd circle
			(at 17.709896 11.700002 180)
			(size 0.450088 0.450088)
			(layers "F.Cu" "F.Mask" "F.Paste")
			(net "PVDDIO_P1")
		)
		(pad "BV58" smd circle
			(at 18.64995 11.700002 180)
			(size 0.450088 0.450088)
			(layers "F.Cu" "F.Mask" "F.Paste")
			(net "M_D_CPU1_SB_CB<7>")
		)
		(pad "BV59" smd circle
			(at 19.590004 11.700002 180)
			(size 0.450088 0.450088)
			(layers "F.Cu" "F.Mask" "F.Paste")
			(net "GND")
		)
		(pad "BV60" smd circle
			(at 20.530058 11.700002 180)
			(size 0.450088 0.450088)
			(layers "F.Cu" "F.Mask" "F.Paste")
			(net "M_D_CPU1_SB_DQS_DP<9>")
		)
		(pad "BV61" smd circle
			(at 21.470112 11.700002 180)
			(size 0.450088 0.450088)
			(layers "F.Cu" "F.Mask" "F.Paste")
			(net "GND")
		)
		(pad "BV62" smd circle
			(at 22.409912 11.700002 180)
			(size 0.450088 0.450088)
			(layers "F.Cu" "F.Mask" "F.Paste")
			(net "M_B_CPU1_SB_CB<7>")
		)
		(pad "BV63" smd circle
			(at 23.349966 11.700002 180)
			(size 0.450088 0.450088)
			(layers "F.Cu" "F.Mask" "F.Paste")
			(net "M_B_CPU1_SB_DQS_DP<9>")
		)
		(pad "BV64" smd circle
			(at 24.29002 11.700002 180)
			(size 0.450088 0.450088)
			(layers "F.Cu" "F.Mask" "F.Paste")
			(net "PVDDIO_P1")
		)
		(pad "BV65" smd circle
			(at 25.230074 11.700002 180)
			(size 0.450088 0.450088)
			(layers "F.Cu" "F.Mask" "F.Paste")
			(net "M_F_CPU1_SB_CB<7>")
		)
		(pad "BV66" smd circle
			(at 26.170128 11.700002 180)
			(size 0.450088 0.450088)
			(layers "F.Cu" "F.Mask" "F.Paste")
			(net "GND")
		)
		(pad "BV67" smd circle
			(at 27.109928 11.700002 180)
			(size 0.450088 0.450088)
			(layers "F.Cu" "F.Mask" "F.Paste")
			(net "M_F_CPU1_SB_DQS_DP<9>")
		)
		(pad "BV68" smd circle
			(at 28.049982 11.700002 180)
			(size 0.450088 0.450088)
			(layers "F.Cu" "F.Mask" "F.Paste")
			(net "GND")
		)
		(pad "BV69" smd circle
			(at 28.990036 11.700002 180)
			(size 0.450088 0.450088)
			(layers "F.Cu" "F.Mask" "F.Paste")
			(net "M_E_CPU1_SB_CB<7>")
		)
		(pad "BV70" smd circle
			(at 29.93009 11.700002 180)
			(size 0.450088 0.450088)
			(layers "F.Cu" "F.Mask" "F.Paste")
			(net "M_E_CPU1_SB_DQS_DP<9>")
		)
		(pad "BV71" smd circle
			(at 30.86989 11.700002 180)
			(size 0.450088 0.450088)
			(layers "F.Cu" "F.Mask" "F.Paste")
			(net "PVDDIO_P1")
		)
		(pad "BV72" smd circle
			(at 31.809944 11.700002 180)
			(size 0.450088 0.450088)
			(layers "F.Cu" "F.Mask" "F.Paste")
			(net "M_A_CPU1_SB_CB<7>")
		)
		(pad "BV73" smd circle
			(at 32.749998 11.700002 180)
			(size 0.450088 0.450088)
			(layers "F.Cu" "F.Mask" "F.Paste")
			(net "GND")
		)
		(pad "BV74" smd circle
			(at 33.690052 11.700002 180)
			(size 0.450088 0.450088)
			(layers "F.Cu" "F.Mask" "F.Paste")
			(net "M_A_CPU1_SB_DQS_DP<9>")
		)
		(pad "BW1" smd circle
			(at -34.459926 12.510008 180)
			(size 0.450088 0.450088)
			(layers "F.Cu" "F.Mask" "F.Paste")
			(net "GND")
		)
		(pad "BW2" smd circle
			(at -33.519872 12.510008 180)
			(size 0.450088 0.450088)
			(layers "F.Cu" "F.Mask" "F.Paste")
			(net "M_G_CPU1_SB_DQS_DN<9>")
		)
		(pad "BW3" smd circle
			(at -32.580072 12.510008 180)
			(size 0.450088 0.450088)
			(layers "F.Cu" "F.Mask" "F.Paste")
			(net "M_G_CPU1_SB_DQS_DN<4>")
		)
		(pad "BW4" smd circle
			(at -31.640018 12.510008 180)
			(size 0.450088 0.450088)
			(layers "F.Cu" "F.Mask" "F.Paste")
			(net "GND")
		)
		(pad "BW5" smd circle
			(at -30.699964 12.510008 180)
			(size 0.450088 0.450088)
			(layers "F.Cu" "F.Mask" "F.Paste")
			(net "M_K_CPU1_SB_DQS_DN<9>")
		)
		(pad "BW6" smd circle
			(at -29.75991 12.510008 180)
			(size 0.450088 0.450088)
			(layers "F.Cu" "F.Mask" "F.Paste")
			(net "GND")
		)
		(pad "BW7" smd circle
			(at -28.82011 12.510008 180)
			(size 0.450088 0.450088)
			(layers "F.Cu" "F.Mask" "F.Paste")
			(net "M_K_CPU1_SB_DQS_DN<4>")
		)
		(pad "BW8" smd circle
			(at -27.880056 12.510008 180)
			(size 0.450088 0.450088)
			(layers "F.Cu" "F.Mask" "F.Paste")
			(net "GND")
		)
		(pad "BW9" smd circle
			(at -26.940002 12.510008 180)
			(size 0.450088 0.450088)
			(layers "F.Cu" "F.Mask" "F.Paste")
			(net "M_L_CPU1_SB_DQS_DN<9>")
		)
		(pad "BW10" smd circle
			(at -25.999948 12.510008 180)
			(size 0.450088 0.450088)
			(layers "F.Cu" "F.Mask" "F.Paste")
			(net "M_L_CPU1_SB_DQS_DN<4>")
		)
		(pad "BW11" smd circle
			(at -25.059894 12.510008 180)
			(size 0.450088 0.450088)
			(layers "F.Cu" "F.Mask" "F.Paste")
			(net "GND")
		)
		(pad "BW12" smd circle
			(at -24.120094 12.510008 180)
			(size 0.450088 0.450088)
			(layers "F.Cu" "F.Mask" "F.Paste")
			(net "M_H_CPU1_SB_DQS_DN<9>")
		)
		(pad "BW13" smd circle
			(at -23.18004 12.510008 180)
			(size 0.450088 0.450088)
			(layers "F.Cu" "F.Mask" "F.Paste")
			(net "GND")
		)
		(pad "BW14" smd circle
			(at -22.239986 12.510008 180)
			(size 0.450088 0.450088)
			(layers "F.Cu" "F.Mask" "F.Paste")
			(net "M_H_CPU1_SB_DQS_DN<4>")
		)
		(pad "BW15" smd circle
			(at -21.299932 12.510008 180)
			(size 0.450088 0.450088)
			(layers "F.Cu" "F.Mask" "F.Paste")
			(net "GND")
		)
		(pad "BW16" smd circle
			(at -20.359878 12.510008 180)
			(size 0.450088 0.450088)
			(layers "F.Cu" "F.Mask" "F.Paste")
			(net "M_J_CPU1_SB_DQS_DN<9>")
		)
		(pad "BW17" smd circle
			(at -19.420078 12.510008 180)
			(size 0.450088 0.450088)
			(layers "F.Cu" "F.Mask" "F.Paste")
			(net "M_J_CPU1_SB_DQS_DN<4>")
		)
		(pad "BW18" smd circle
			(at -18.480024 12.510008 180)
			(size 0.450088 0.450088)
			(layers "F.Cu" "F.Mask" "F.Paste")
			(net "GND")
		)
		(pad "BW19" smd circle
			(at -17.53997 12.510008 180)
			(size 0.450088 0.450088)
			(layers "F.Cu" "F.Mask" "F.Paste")
			(net "M_I_CPU1_SB_DQS_DN<9>")
		)
		(pad "BW20" smd circle
			(at -16.599916 12.510008 180)
			(size 0.450088 0.450088)
			(layers "F.Cu" "F.Mask" "F.Paste")
			(net "GND")
		)
		(pad "BW21" smd circle
			(at -15.660116 12.510008 180)
			(size 0.450088 0.450088)
			(layers "F.Cu" "F.Mask" "F.Paste")
			(net "M_I_CPU1_SB_DQS_DN<4>")
		)
		(pad "BW22" smd circle
			(at -14.720062 12.510008 180)
			(size 0.450088 0.450088)
			(layers "F.Cu" "F.Mask" "F.Paste")
			(net "GND")
		)
		(pad "BW23" smd circle
			(at -13.780008 12.510008 180)
			(size 0.450088 0.450088)
			(layers "F.Cu" "F.Mask" "F.Paste")
			(net "P5E_CPU1_P2_TX_DN<15>")
		)
		(pad "BW24" smd circle
			(at -12.839954 12.510008 180)
			(size 0.450088 0.450088)
			(layers "F.Cu" "F.Mask" "F.Paste")
			(net "P5E_CPU1_P2_TX_DP<15>")
		)
		(pad "BW25" smd circle
			(at -11.8999 12.510008 180)
			(size 0.450088 0.450088)
			(layers "F.Cu" "F.Mask" "F.Paste")
			(net "GND")
		)
		(pad "BW26" smd circle
			(at -10.9601 12.510008 180)
			(size 0.450088 0.450088)
			(layers "F.Cu" "F.Mask" "F.Paste")
			(net "P5E_CPU1_P2_TX_DN<12>")
		)
		(pad "BW27" smd circle
			(at -10.020046 12.510008 180)
			(size 0.450088 0.450088)
			(layers "F.Cu" "F.Mask" "F.Paste")
			(net "P5E_CPU1_P2_TX_DP<12>")
		)
		(pad "BW28" smd circle
			(at -9.079992 12.510008 180)
			(size 0.450088 0.450088)
			(layers "F.Cu" "F.Mask" "F.Paste")
			(net "GND")
		)
		(pad "BW29" smd circle
			(at -8.139938 12.510008 180)
			(size 0.450088 0.450088)
			(layers "F.Cu" "F.Mask" "F.Paste")
			(net "P5E_CPU1_P2_TX_DN<9>")
		)
		(pad "BW30" smd circle
			(at -7.199884 12.510008 180)
			(size 0.450088 0.450088)
			(layers "F.Cu" "F.Mask" "F.Paste")
			(net "P5E_CPU1_P2_TX_DP<9>")
		)
		(pad "BW31" smd circle
			(at -6.260084 12.510008 180)
			(size 0.450088 0.450088)
			(layers "F.Cu" "F.Mask" "F.Paste")
			(net "GND")
		)
		(pad "BW32" smd circle
			(at -5.32003 12.510008 180)
			(size 0.450088 0.450088)
			(layers "F.Cu" "F.Mask" "F.Paste")
			(net "P5E_CPU1_P2_TX_DN<6>")
		)
		(pad "BW33" smd circle
			(at -4.379976 12.510008 180)
			(size 0.450088 0.450088)
			(layers "F.Cu" "F.Mask" "F.Paste")
			(net "P5E_CPU1_P2_TX_DP<6>")
		)
		(pad "BW34" smd circle
			(at -3.439922 12.510008 180)
			(size 0.450088 0.450088)
			(layers "F.Cu" "F.Mask" "F.Paste")
			(net "GND")
		)
		(pad "BW35" smd circle
			(at -2.500122 12.510008 180)
			(size 0.450088 0.450088)
			(layers "F.Cu" "F.Mask" "F.Paste")
			(net "PVDDCR_CPU1_P1")
		)
		(pad "BW36" smd circle
			(at -1.560068 12.510008 180)
			(size 0.450088 0.450088)
			(layers "F.Cu" "F.Mask" "F.Paste")
			(net "PVDDCR_CPU1_P1")
		)
		(pad "BW40" smd circle
			(at 1.260094 12.510008 180)
			(size 0.450088 0.450088)
			(layers "F.Cu" "F.Mask" "F.Paste")
			(net "PVDDCR_CPU1_P1")
		)
		(pad "BW41" smd circle
			(at 2.199894 12.510008 180)
			(size 0.450088 0.450088)
			(layers "F.Cu" "F.Mask" "F.Paste")
			(net "PVDDCR_CPU1_P1")
		)
		(pad "BW42" smd circle
			(at 3.139948 12.510008 180)
			(size 0.450088 0.450088)
			(layers "F.Cu" "F.Mask" "F.Paste")
			(net "GND")
		)
		(pad "BW43" smd circle
			(at 4.080002 12.510008 180)
			(size 0.450088 0.450088)
			(layers "F.Cu" "F.Mask" "F.Paste")
			(net "P5E_CPU1_P0_RX_DP<9>")
		)
		(pad "BW44" smd circle
			(at 5.020056 12.510008 180)
			(size 0.450088 0.450088)
			(layers "F.Cu" "F.Mask" "F.Paste")
			(net "P5E_CPU1_P0_RX_DN<9>")
		)
		(pad "BW45" smd circle
			(at 5.96011 12.510008 180)
			(size 0.450088 0.450088)
			(layers "F.Cu" "F.Mask" "F.Paste")
			(net "GND")
		)
		(pad "BW46" smd circle
			(at 6.89991 12.510008 180)
			(size 0.450088 0.450088)
			(layers "F.Cu" "F.Mask" "F.Paste")
			(net "P5E_CPU1_P0_RX_DP<6>")
		)
		(pad "BW47" smd circle
			(at 7.839964 12.510008 180)
			(size 0.450088 0.450088)
			(layers "F.Cu" "F.Mask" "F.Paste")
			(net "P5E_CPU1_P0_RX_DN<6>")
		)
		(pad "BW48" smd circle
			(at 8.780018 12.510008 180)
			(size 0.450088 0.450088)
			(layers "F.Cu" "F.Mask" "F.Paste")
			(net "GND")
		)
		(pad "BW49" smd circle
			(at 9.720072 12.510008 180)
			(size 0.450088 0.450088)
			(layers "F.Cu" "F.Mask" "F.Paste")
			(net "P5E_CPU1_P0_RX_DP<3>")
		)
		(pad "BW50" smd circle
			(at 10.659872 12.510008 180)
			(size 0.450088 0.450088)
			(layers "F.Cu" "F.Mask" "F.Paste")
			(net "P5E_CPU1_P0_RX_DN<3>")
		)
		(pad "BW51" smd circle
			(at 11.599926 12.510008 180)
			(size 0.450088 0.450088)
			(layers "F.Cu" "F.Mask" "F.Paste")
			(net "GND")
		)
		(pad "BW52" smd circle
			(at 12.53998 12.510008 180)
			(size 0.450088 0.450088)
			(layers "F.Cu" "F.Mask" "F.Paste")
			(net "P5E_CPU1_P0_RX_DP<0>")
		)
		(pad "BW53" smd circle
			(at 13.480034 12.510008 180)
			(size 0.450088 0.450088)
			(layers "F.Cu" "F.Mask" "F.Paste")
			(net "P5E_CPU1_P0_RX_DN<0>")
		)
		(pad "BW54" smd circle
			(at 14.420088 12.510008 180)
			(size 0.450088 0.450088)
			(layers "F.Cu" "F.Mask" "F.Paste")
			(net "GND")
		)
		(pad "BW55" smd circle
			(at 15.359888 12.510008 180)
			(size 0.450088 0.450088)
			(layers "F.Cu" "F.Mask" "F.Paste")
			(net "M_C_CPU1_SB_DQS_DN<4>")
		)
		(pad "BW56" smd circle
			(at 16.299942 12.510008 180)
			(size 0.450088 0.450088)
			(layers "F.Cu" "F.Mask" "F.Paste")
			(net "GND")
		)
		(pad "BW57" smd circle
			(at 17.239996 12.510008 180)
			(size 0.450088 0.450088)
			(layers "F.Cu" "F.Mask" "F.Paste")
			(net "M_C_CPU1_SB_DQS_DN<9>")
		)
		(pad "BW58" smd circle
			(at 18.18005 12.510008 180)
			(size 0.450088 0.450088)
			(layers "F.Cu" "F.Mask" "F.Paste")
			(net "GND")
		)
		(pad "BW59" smd circle
			(at 19.120104 12.510008 180)
			(size 0.450088 0.450088)
			(layers "F.Cu" "F.Mask" "F.Paste")
			(net "M_D_CPU1_SB_DQS_DN<4>")
		)
		(pad "BW60" smd circle
			(at 20.059904 12.510008 180)
			(size 0.450088 0.450088)
			(layers "F.Cu" "F.Mask" "F.Paste")
			(net "M_D_CPU1_SB_DQS_DN<9>")
		)
		(pad "BW61" smd circle
			(at 20.999958 12.510008 180)
			(size 0.450088 0.450088)
			(layers "F.Cu" "F.Mask" "F.Paste")
			(net "GND")
		)
		(pad "BW62" smd circle
			(at 21.940012 12.510008 180)
			(size 0.450088 0.450088)
			(layers "F.Cu" "F.Mask" "F.Paste")
			(net "M_B_CPU1_SB_DQS_DN<4>")
		)
		(pad "BW63" smd circle
			(at 22.880066 12.510008 180)
			(size 0.450088 0.450088)
			(layers "F.Cu" "F.Mask" "F.Paste")
			(net "GND")
		)
		(pad "BW64" smd circle
			(at 23.82012 12.510008 180)
			(size 0.450088 0.450088)
			(layers "F.Cu" "F.Mask" "F.Paste")
			(net "M_B_CPU1_SB_DQS_DN<9>")
		)
		(pad "BW65" smd circle
			(at 24.75992 12.510008 180)
			(size 0.450088 0.450088)
			(layers "F.Cu" "F.Mask" "F.Paste")
			(net "GND")
		)
		(pad "BW66" smd circle
			(at 25.699974 12.510008 180)
			(size 0.450088 0.450088)
			(layers "F.Cu" "F.Mask" "F.Paste")
			(net "M_F_CPU1_SB_DQS_DN<4>")
		)
		(pad "BW67" smd circle
			(at 26.640028 12.510008 180)
			(size 0.450088 0.450088)
			(layers "F.Cu" "F.Mask" "F.Paste")
			(net "M_F_CPU1_SB_DQS_DN<9>")
		)
		(pad "BW68" smd circle
			(at 27.580082 12.510008 180)
			(size 0.450088 0.450088)
			(layers "F.Cu" "F.Mask" "F.Paste")
			(net "GND")
		)
		(pad "BW69" smd circle
			(at 28.519882 12.510008 180)
			(size 0.450088 0.450088)
			(layers "F.Cu" "F.Mask" "F.Paste")
			(net "M_E_CPU1_SB_DQS_DN<4>")
		)
		(pad "BW70" smd circle
			(at 29.459936 12.510008 180)
			(size 0.450088 0.450088)
			(layers "F.Cu" "F.Mask" "F.Paste")
			(net "GND")
		)
		(pad "BW71" smd circle
			(at 30.39999 12.510008 180)
			(size 0.450088 0.450088)
			(layers "F.Cu" "F.Mask" "F.Paste")
			(net "M_E_CPU1_SB_DQS_DN<9>")
		)
		(pad "BW72" smd circle
			(at 31.340044 12.510008 180)
			(size 0.450088 0.450088)
			(layers "F.Cu" "F.Mask" "F.Paste")
			(net "GND")
		)
		(pad "BW73" smd circle
			(at 32.280098 12.510008 180)
			(size 0.450088 0.450088)
			(layers "F.Cu" "F.Mask" "F.Paste")
			(net "M_A_CPU1_SB_DQS_DN<4>")
		)
		(pad "BW74" smd circle
			(at 33.219898 12.510008 180)
			(size 0.450088 0.450088)
			(layers "F.Cu" "F.Mask" "F.Paste")
			(net "M_A_CPU1_SB_DQS_DN<9>")
		)
		(pad "BW75" smd circle
			(at 34.159952 12.510008 180)
			(size 0.450088 0.450088)
			(layers "F.Cu" "F.Mask" "F.Paste")
			(net "GND")
		)
		(pad "BY2" smd circle
			(at -33.990026 13.320014 180)
			(size 0.450088 0.450088)
			(layers "F.Cu" "F.Mask" "F.Paste")
			(net "M_G_CPU1_SB_CB<0>")
		)
		(pad "BY3" smd circle
			(at -33.049972 13.320014 180)
			(size 0.450088 0.450088)
			(layers "F.Cu" "F.Mask" "F.Paste")
			(net "GND")
		)
		(pad "BY4" smd circle
			(at -32.109918 13.320014 180)
			(size 0.450088 0.450088)
			(layers "F.Cu" "F.Mask" "F.Paste")
			(net "M_G_CPU1_SB_DQS_DP<4>")
		)
		(pad "BY5" smd circle
			(at -31.170118 13.320014 180)
			(size 0.450088 0.450088)
			(layers "F.Cu" "F.Mask" "F.Paste")
			(net "GND")
		)
		(pad "BY6" smd circle
			(at -30.230064 13.320014 180)
			(size 0.450088 0.450088)
			(layers "F.Cu" "F.Mask" "F.Paste")
			(net "M_K_CPU1_SB_CB<0>")
		)
		(pad "BY7" smd circle
			(at -29.29001 13.320014 180)
			(size 0.450088 0.450088)
			(layers "F.Cu" "F.Mask" "F.Paste")
			(net "M_K_CPU1_SB_DQS_DP<4>")
		)
		(pad "BY8" smd circle
			(at -28.349956 13.320014 180)
			(size 0.450088 0.450088)
			(layers "F.Cu" "F.Mask" "F.Paste")
			(net "GND")
		)
		(pad "BY9" smd circle
			(at -27.409902 13.320014 180)
			(size 0.450088 0.450088)
			(layers "F.Cu" "F.Mask" "F.Paste")
			(net "M_L_CPU1_SB_CB<0>")
		)
		(pad "BY10" smd circle
			(at -26.470102 13.320014 180)
			(size 0.450088 0.450088)
			(layers "F.Cu" "F.Mask" "F.Paste")
			(net "GND")
		)
		(pad "BY11" smd circle
			(at -25.530048 13.320014 180)
			(size 0.450088 0.450088)
			(layers "F.Cu" "F.Mask" "F.Paste")
			(net "M_L_CPU1_SB_DQS_DP<4>")
		)
		(pad "BY12" smd circle
			(at -24.589994 13.320014 180)
			(size 0.450088 0.450088)
			(layers "F.Cu" "F.Mask" "F.Paste")
			(net "GND")
		)
		(pad "BY13" smd circle
			(at -23.64994 13.320014 180)
			(size 0.450088 0.450088)
			(layers "F.Cu" "F.Mask" "F.Paste")
			(net "M_H_CPU1_SB_CB<0>")
		)
		(pad "BY14" smd circle
			(at -22.709886 13.320014 180)
			(size 0.450088 0.450088)
			(layers "F.Cu" "F.Mask" "F.Paste")
			(net "M_H_CPU1_SB_DQS_DP<4>")
		)
		(pad "BY15" smd circle
			(at -21.770086 13.320014 180)
			(size 0.450088 0.450088)
			(layers "F.Cu" "F.Mask" "F.Paste")
			(net "GND")
		)
		(pad "BY16" smd circle
			(at -20.830032 13.320014 180)
			(size 0.450088 0.450088)
			(layers "F.Cu" "F.Mask" "F.Paste")
			(net "M_J_CPU1_SB_CB<0>")
		)
		(pad "BY17" smd circle
			(at -19.889978 13.320014 180)
			(size 0.450088 0.450088)
			(layers "F.Cu" "F.Mask" "F.Paste")
			(net "GND")
		)
		(pad "BY18" smd circle
			(at -18.949924 13.320014 180)
			(size 0.450088 0.450088)
			(layers "F.Cu" "F.Mask" "F.Paste")
			(net "M_J_CPU1_SB_DQS_DP<4>")
		)
		(pad "BY19" smd circle
			(at -18.010124 13.320014 180)
			(size 0.450088 0.450088)
			(layers "F.Cu" "F.Mask" "F.Paste")
			(net "GND")
		)
		(pad "BY20" smd circle
			(at -17.07007 13.320014 180)
			(size 0.450088 0.450088)
			(layers "F.Cu" "F.Mask" "F.Paste")
			(net "M_I_CPU1_SB_CB<0>")
		)
		(pad "BY21" smd circle
			(at -16.130016 13.320014 180)
			(size 0.450088 0.450088)
			(layers "F.Cu" "F.Mask" "F.Paste")
			(net "M_I_CPU1_SB_DQS_DP<4>")
		)
		(pad "BY22" smd circle
			(at -15.189962 13.320014 180)
			(size 0.450088 0.450088)
			(layers "F.Cu" "F.Mask" "F.Paste")
			(net "GND")
		)
		(pad "BY23" smd circle
			(at -14.249908 13.320014 180)
			(size 0.450088 0.450088)
			(layers "F.Cu" "F.Mask" "F.Paste")
			(net "PVDDCR_CPU1_P1")
		)
		(pad "BY24" smd circle
			(at -13.310108 13.320014 180)
			(size 0.450088 0.450088)
			(layers "F.Cu" "F.Mask" "F.Paste")
			(net "PVDDCR_CPU1_P1")
		)
		(pad "BY25" smd circle
			(at -12.370054 13.320014 180)
			(size 0.450088 0.450088)
			(layers "F.Cu" "F.Mask" "F.Paste")
			(net "GND")
		)
		(pad "BY26" smd circle
			(at -11.43 13.320014 180)
			(size 0.450088 0.450088)
			(layers "F.Cu" "F.Mask" "F.Paste")
			(net "PVDDCR_CPU1_P1")
		)
		(pad "BY27" smd circle
			(at -10.489946 13.320014 180)
			(size 0.450088 0.450088)
			(layers "F.Cu" "F.Mask" "F.Paste")
			(net "PVDDCR_CPU1_P1")
		)
		(pad "BY28" smd circle
			(at -9.549892 13.320014 180)
			(size 0.450088 0.450088)
			(layers "F.Cu" "F.Mask" "F.Paste")
			(net "GND")
		)
		(pad "BY29" smd circle
			(at -8.610092 13.320014 180)
			(size 0.450088 0.450088)
			(layers "F.Cu" "F.Mask" "F.Paste")
			(net "PVDDCR_CPU1_P1")
		)
		(pad "BY30" smd circle
			(at -7.670038 13.320014 180)
			(size 0.450088 0.450088)
			(layers "F.Cu" "F.Mask" "F.Paste")
			(net "PVDDCR_CPU1_P1")
		)
		(pad "BY31" smd circle
			(at -6.729984 13.320014 180)
			(size 0.450088 0.450088)
			(layers "F.Cu" "F.Mask" "F.Paste")
			(net "GND")
		)
		(pad "BY32" smd circle
			(at -5.78993 13.320014 180)
			(size 0.450088 0.450088)
			(layers "F.Cu" "F.Mask" "F.Paste")
			(net "PVDDCR_CPU1_P1")
		)
		(pad "BY33" smd circle
			(at -4.849876 13.320014 180)
			(size 0.450088 0.450088)
			(layers "F.Cu" "F.Mask" "F.Paste")
			(net "PVDDCR_CPU1_P1")
		)
		(pad "BY34" smd circle
			(at -3.910076 13.320014 180)
			(size 0.450088 0.450088)
			(layers "F.Cu" "F.Mask" "F.Paste")
			(net "GND")
		)
		(pad "BY35" smd circle
			(at -2.970022 13.320014 180)
			(size 0.450088 0.450088)
			(layers "F.Cu" "F.Mask" "F.Paste")
			(net "P5E_CPU1_P2_TX_DN<3>")
		)
		(pad "BY36" smd circle
			(at -2.029968 13.320014 180)
			(size 0.450088 0.450088)
			(layers "F.Cu" "F.Mask" "F.Paste")
			(net "P5E_CPU1_P2_TX_DP<3>")
		)
		(pad "BY37" smd circle
			(at -1.089914 13.320014 180)
			(size 0.450088 0.450088)
			(layers "F.Cu" "F.Mask" "F.Paste")
			(net "GND")
		)
		(pad "BY39" smd circle
			(at 0.78994 13.320014 180)
			(size 0.450088 0.450088)
			(layers "F.Cu" "F.Mask" "F.Paste")
			(net "GND")
		)
		(pad "BY40" smd circle
			(at 1.729994 13.320014 180)
			(size 0.450088 0.450088)
			(layers "F.Cu" "F.Mask" "F.Paste")
			(net "P5E_CPU1_P0_RX_DP<12>")
		)
		(pad "BY41" smd circle
			(at 2.670048 13.320014 180)
			(size 0.450088 0.450088)
			(layers "F.Cu" "F.Mask" "F.Paste")
			(net "P5E_CPU1_P0_RX_DN<12>")
		)
		(pad "BY42" smd circle
			(at 3.610102 13.320014 180)
			(size 0.450088 0.450088)
			(layers "F.Cu" "F.Mask" "F.Paste")
			(net "GND")
		)
		(pad "BY43" smd circle
			(at 4.549902 13.320014 180)
			(size 0.450088 0.450088)
			(layers "F.Cu" "F.Mask" "F.Paste")
			(net "PVDDCR_CPU1_P1")
		)
		(pad "BY44" smd circle
			(at 5.489956 13.320014 180)
			(size 0.450088 0.450088)
			(layers "F.Cu" "F.Mask" "F.Paste")
			(net "PVDDCR_CPU1_P1")
		)
		(pad "BY45" smd circle
			(at 6.43001 13.320014 180)
			(size 0.450088 0.450088)
			(layers "F.Cu" "F.Mask" "F.Paste")
			(net "GND")
		)
		(pad "BY46" smd circle
			(at 7.370064 13.320014 180)
			(size 0.450088 0.450088)
			(layers "F.Cu" "F.Mask" "F.Paste")
			(net "PVDDCR_CPU1_P1")
		)
		(pad "BY47" smd circle
			(at 8.310118 13.320014 180)
			(size 0.450088 0.450088)
			(layers "F.Cu" "F.Mask" "F.Paste")
			(net "PVDDCR_CPU1_P1")
		)
		(pad "BY48" smd circle
			(at 9.249918 13.320014 180)
			(size 0.450088 0.450088)
			(layers "F.Cu" "F.Mask" "F.Paste")
			(net "GND")
		)
		(pad "BY49" smd circle
			(at 10.189972 13.320014 180)
			(size 0.450088 0.450088)
			(layers "F.Cu" "F.Mask" "F.Paste")
			(net "PVDDCR_CPU1_P1")
		)
		(pad "BY50" smd circle
			(at 11.130026 13.320014 180)
			(size 0.450088 0.450088)
			(layers "F.Cu" "F.Mask" "F.Paste")
			(net "PVDDCR_CPU1_P1")
		)
		(pad "BY51" smd circle
			(at 12.07008 13.320014 180)
			(size 0.450088 0.450088)
			(layers "F.Cu" "F.Mask" "F.Paste")
			(net "GND")
		)
		(pad "BY52" smd circle
			(at 13.00988 13.320014 180)
			(size 0.450088 0.450088)
			(layers "F.Cu" "F.Mask" "F.Paste")
			(net "PVDDCR_CPU1_P1")
		)
		(pad "BY53" smd circle
			(at 13.949934 13.320014 180)
			(size 0.450088 0.450088)
			(layers "F.Cu" "F.Mask" "F.Paste")
			(net "PVDDCR_CPU1_P1")
		)
		(pad "BY54" smd circle
			(at 14.889988 13.320014 180)
			(size 0.450088 0.450088)
			(layers "F.Cu" "F.Mask" "F.Paste")
			(net "GND")
		)
		(pad "BY55" smd circle
			(at 15.830042 13.320014 180)
			(size 0.450088 0.450088)
			(layers "F.Cu" "F.Mask" "F.Paste")
			(net "M_C_CPU1_SB_DQS_DP<4>")
		)
		(pad "BY56" smd circle
			(at 16.770096 13.320014 180)
			(size 0.450088 0.450088)
			(layers "F.Cu" "F.Mask" "F.Paste")
			(net "M_C_CPU1_SB_CB<0>")
		)
		(pad "BY57" smd circle
			(at 17.709896 13.320014 180)
			(size 0.450088 0.450088)
			(layers "F.Cu" "F.Mask" "F.Paste")
			(net "GND")
		)
		(pad "BY58" smd circle
			(at 18.64995 13.320014 180)
			(size 0.450088 0.450088)
			(layers "F.Cu" "F.Mask" "F.Paste")
			(net "M_D_CPU1_SB_DQS_DP<4>")
		)
		(pad "BY59" smd circle
			(at 19.590004 13.320014 180)
			(size 0.450088 0.450088)
			(layers "F.Cu" "F.Mask" "F.Paste")
			(net "GND")
		)
		(pad "BY60" smd circle
			(at 20.530058 13.320014 180)
			(size 0.450088 0.450088)
			(layers "F.Cu" "F.Mask" "F.Paste")
			(net "M_D_CPU1_SB_CB<0>")
		)
		(pad "BY61" smd circle
			(at 21.470112 13.320014 180)
			(size 0.450088 0.450088)
			(layers "F.Cu" "F.Mask" "F.Paste")
			(net "GND")
		)
		(pad "BY62" smd circle
			(at 22.409912 13.320014 180)
			(size 0.450088 0.450088)
			(layers "F.Cu" "F.Mask" "F.Paste")
			(net "M_B_CPU1_SB_DQS_DP<4>")
		)
		(pad "BY63" smd circle
			(at 23.349966 13.320014 180)
			(size 0.450088 0.450088)
			(layers "F.Cu" "F.Mask" "F.Paste")
			(net "M_B_CPU1_SB_CB<0>")
		)
		(pad "BY64" smd circle
			(at 24.29002 13.320014 180)
			(size 0.450088 0.450088)
			(layers "F.Cu" "F.Mask" "F.Paste")
			(net "GND")
		)
		(pad "BY65" smd circle
			(at 25.230074 13.320014 180)
			(size 0.450088 0.450088)
			(layers "F.Cu" "F.Mask" "F.Paste")
			(net "M_F_CPU1_SB_DQS_DP<4>")
		)
		(pad "BY66" smd circle
			(at 26.170128 13.320014 180)
			(size 0.450088 0.450088)
			(layers "F.Cu" "F.Mask" "F.Paste")
			(net "GND")
		)
		(pad "BY67" smd circle
			(at 27.109928 13.320014 180)
			(size 0.450088 0.450088)
			(layers "F.Cu" "F.Mask" "F.Paste")
			(net "M_F_CPU1_SB_CB<0>")
		)
		(pad "BY68" smd circle
			(at 28.049982 13.320014 180)
			(size 0.450088 0.450088)
			(layers "F.Cu" "F.Mask" "F.Paste")
			(net "GND")
		)
		(pad "BY69" smd circle
			(at 28.990036 13.320014 180)
			(size 0.450088 0.450088)
			(layers "F.Cu" "F.Mask" "F.Paste")
			(net "M_E_CPU1_SB_DQS_DP<4>")
		)
		(pad "BY70" smd circle
			(at 29.93009 13.320014 180)
			(size 0.450088 0.450088)
			(layers "F.Cu" "F.Mask" "F.Paste")
			(net "M_E_CPU1_SB_CB<0>")
		)
		(pad "BY71" smd circle
			(at 30.86989 13.320014 180)
			(size 0.450088 0.450088)
			(layers "F.Cu" "F.Mask" "F.Paste")
			(net "GND")
		)
		(pad "BY72" smd circle
			(at 31.809944 13.320014 180)
			(size 0.450088 0.450088)
			(layers "F.Cu" "F.Mask" "F.Paste")
			(net "M_A_CPU1_SB_DQS_DP<4>")
		)
		(pad "BY73" smd circle
			(at 32.749998 13.320014 180)
			(size 0.450088 0.450088)
			(layers "F.Cu" "F.Mask" "F.Paste")
			(net "GND")
		)
		(pad "BY74" smd circle
			(at 33.690052 13.320014 180)
			(size 0.450088 0.450088)
			(layers "F.Cu" "F.Mask" "F.Paste")
			(net "M_A_CPU1_SB_CB<0>")
		)
		(pad "C1" smd circle
			(at -34.159952 -35.189922 180)
			(size 0.450088 0.450088)
			(layers "F.Cu" "F.Mask" "F.Paste")
			(net "GND")
		)
		(pad "C2" smd circle
			(at -33.219898 -35.189922 180)
			(size 0.450088 0.450088)
			(layers "F.Cu" "F.Mask" "F.Paste")
			(net "VSENSE_PVDDCR_CPU0_P1_DP")
		)
		(pad "C3" smd circle
			(at -32.280098 -35.189922 180)
			(size 0.450088 0.450088)
			(layers "F.Cu" "F.Mask" "F.Paste")
			(net "VSENSE_VSS_SENSE_A_P1")
		)
		(pad "C4" smd circle
			(at -31.340044 -35.189922 180)
			(size 0.450088 0.450088)
			(layers "F.Cu" "F.Mask" "F.Paste")
			(net "PVDDCR_SOC_P1")
		)
		(pad "C5" smd circle
			(at -30.39999 -35.189922 180)
			(size 0.450088 0.450088)
			(layers "F.Cu" "F.Mask" "F.Paste")
			(net "GND")
		)
		(pad "C6" smd circle
			(at -29.459936 -35.189922 180)
			(size 0.450088 0.450088)
			(layers "F.Cu" "F.Mask" "F.Paste")
			(net "CLK_100M_CPU1_CLK02_R_DN")
		)
		(pad "C7" smd circle
			(at -28.519882 -35.189922 180)
			(size 0.450088 0.450088)
			(layers "F.Cu" "F.Mask" "F.Paste")
			(net "I3C_1_SPD_DDRGL_CPU1_R_SCL")
		)
		(pad "C8" smd circle
			(at -27.580082 -35.189922 180)
			(size 0.450088 0.450088)
			(layers "F.Cu" "F.Mask" "F.Paste")
			(net "GND")
		)
		(pad "C9" smd circle
			(at -26.640028 -35.189922 180)
			(size 0.450088 0.450088)
			(layers "F.Cu" "F.Mask" "F.Paste")
			(net "CLK_100M_CPU1_CLK05_R_DN")
		)
		(pad "C10" smd circle
			(at -25.699974 -35.189922 180)
			(size 0.450088 0.450088)
			(layers "F.Cu" "F.Mask" "F.Paste")
			(net "GND")
		)
		(pad "C11" smd circle
			(at -24.75992 -35.189922 180)
			(size 0.450088 0.450088)
			(layers "F.Cu" "F.Mask" "F.Paste")
			(net "GND")
		)
		(pad "C12" smd circle
			(at -23.82012 -35.189922 180)
			(size 0.450088 0.450088)
			(layers "F.Cu" "F.Mask" "F.Paste")
			(net "CLK_100M_CPU1_CLK04_R_DN")
		)
		(pad "C13" smd circle
			(at -22.880066 -35.189922 180)
			(size 0.450088 0.450088)
			(layers "F.Cu" "F.Mask" "F.Paste")
			(net "GND")
		)
		(pad "C14" smd circle
			(at -21.940012 -35.189922 180)
			(size 0.450088 0.450088)
			(layers "F.Cu" "F.Mask" "F.Paste")
			(net "Net_2081")
		)
		(pad "C15" smd circle
			(at -20.999958 -35.189922 180)
			(size 0.450088 0.450088)
			(layers "F.Cu" "F.Mask" "F.Paste")
			(net "GND")
		)
		(pad "C16" smd circle
			(at -20.059904 -35.189922 180)
			(size 0.450088 0.450088)
			(layers "F.Cu" "F.Mask" "F.Paste")
			(net "JTAG_CPU1_DBREQ_N")
		)
		(pad "C17" smd circle
			(at -19.120104 -35.189922 180)
			(size 0.450088 0.450088)
			(layers "F.Cu" "F.Mask" "F.Paste")
			(net "JTAG_CPU1_TDI")
		)
		(pad "C18" smd circle
			(at -18.18005 -35.189922 180)
			(size 0.450088 0.450088)
			(layers "F.Cu" "F.Mask" "F.Paste")
			(net "JTAG_CPU1_R_TDO")
		)
		(pad "C19" smd circle
			(at -17.239996 -35.189922 180)
			(size 0.450088 0.450088)
			(layers "F.Cu" "F.Mask" "F.Paste")
			(net "CPU1_SP5R1")
		)
		(pad "C20" smd circle
			(at -16.299942 -35.189922 180)
			(size 0.450088 0.450088)
			(layers "F.Cu" "F.Mask" "F.Paste")
			(net "PVDDCR_CPU0_P1")
		)
		(pad "C21" smd circle
			(at -15.359888 -35.189922 180)
			(size 0.450088 0.450088)
			(layers "F.Cu" "F.Mask" "F.Paste")
			(net "GND")
		)
		(pad "C22" smd circle
			(at -14.420088 -35.189922 180)
			(size 0.450088 0.450088)
			(layers "F.Cu" "F.Mask" "F.Paste")
			(net "FM_P1_PCC0_N")
		)
		(pad "C23" smd circle
			(at -13.480034 -35.189922 180)
			(size 0.450088 0.450088)
			(layers "F.Cu" "F.Mask" "F.Paste")
			(net "Net_2172")
		)
		(pad "C24" smd circle
			(at -12.53998 -35.189922 180)
			(size 0.450088 0.450088)
			(layers "F.Cu" "F.Mask" "F.Paste")
			(net "GND")
		)
		(pad "C25" smd circle
			(at -11.599926 -35.189922 180)
			(size 0.450088 0.450088)
			(layers "F.Cu" "F.Mask" "F.Paste")
			(net "NC_CPU1_USB3_USB00_TXN")
		)
		(pad "C26" smd circle
			(at -10.659872 -35.189922 180)
			(size 0.450088 0.450088)
			(layers "F.Cu" "F.Mask" "F.Paste")
			(net "NC_CPU1_USB3_USB00_TXP")
		)
		(pad "C27" smd circle
			(at -9.720072 -35.189922 180)
			(size 0.450088 0.450088)
			(layers "F.Cu" "F.Mask" "F.Paste")
			(net "GND")
		)
		(pad "C28" smd circle
			(at -8.780018 -35.189922 180)
			(size 0.450088 0.450088)
			(layers "F.Cu" "F.Mask" "F.Paste")
			(net "NC_CPU1_USB3_USB01_RXN")
		)
		(pad "C29" smd circle
			(at -7.839964 -35.189922 180)
			(size 0.450088 0.450088)
			(layers "F.Cu" "F.Mask" "F.Paste")
			(net "NC_CPU1_USB3_USB01_RXP")
		)
		(pad "C30" smd circle
			(at -6.89991 -35.189922 180)
			(size 0.450088 0.450088)
			(layers "F.Cu" "F.Mask" "F.Paste")
			(net "GND")
		)
		(pad "C31" smd circle
			(at -5.96011 -35.189922 180)
			(size 0.450088 0.450088)
			(layers "F.Cu" "F.Mask" "F.Paste")
			(net "Net_2148")
		)
		(pad "C32" smd circle
			(at -5.020056 -35.189922 180)
			(size 0.450088 0.450088)
			(layers "F.Cu" "F.Mask" "F.Paste")
			(net "NC_CPU1_AZ_BITCLK")
		)
		(pad "C33" smd circle
			(at -4.080002 -35.189922 180)
			(size 0.450088 0.450088)
			(layers "F.Cu" "F.Mask" "F.Paste")
			(net "NC_CPU1_AZ_SDIN0")
		)
		(pad "C34" smd circle
			(at -3.139948 -35.189922 180)
			(size 0.450088 0.450088)
			(layers "F.Cu" "F.Mask" "F.Paste")
			(net "Net_2149")
		)
		(pad "C35" smd circle
			(at -2.199894 -35.189922 180)
			(size 0.450088 0.450088)
			(layers "F.Cu" "F.Mask" "F.Paste")
			(net "Net_2150")
		)
		(pad "C36" smd circle
			(at -1.260094 -35.189922 180)
			(size 0.450088 0.450088)
			(layers "F.Cu" "F.Mask" "F.Paste")
			(net "GND")
		)
		(pad "C40" smd circle
			(at 1.560068 -35.189922 180)
			(size 0.450088 0.450088)
			(layers "F.Cu" "F.Mask" "F.Paste")
			(net "GND")
		)
		(pad "C41" smd circle
			(at 2.500122 -35.189922 180)
			(size 0.450088 0.450088)
			(layers "F.Cu" "F.Mask" "F.Paste")
			(net "P3E_CPU1_P5_TX_DP<1>")
		)
		(pad "C42" smd circle
			(at 3.439922 -35.189922 180)
			(size 0.450088 0.450088)
			(layers "F.Cu" "F.Mask" "F.Paste")
			(net "P3E_CPU1_P5_TX_DN<1>")
		)
		(pad "C43" smd circle
			(at 4.379976 -35.189922 180)
			(size 0.450088 0.450088)
			(layers "F.Cu" "F.Mask" "F.Paste")
			(net "GND")
		)
		(pad "C44" smd circle
			(at 5.32003 -35.189922 180)
			(size 0.450088 0.450088)
			(layers "F.Cu" "F.Mask" "F.Paste")
			(net "P3E_CPU1_P5_TX_DP<0>")
		)
		(pad "C45" smd circle
			(at 6.260084 -35.189922 180)
			(size 0.450088 0.450088)
			(layers "F.Cu" "F.Mask" "F.Paste")
			(net "P3E_CPU1_P5_TX_DN<0>")
		)
		(pad "C46" smd circle
			(at 7.199884 -35.189922 180)
			(size 0.450088 0.450088)
			(layers "F.Cu" "F.Mask" "F.Paste")
			(net "GND")
		)
		(pad "C47" smd circle
			(at 8.139938 -35.189922 180)
			(size 0.450088 0.450088)
			(layers "F.Cu" "F.Mask" "F.Paste")
			(net "WAFL_CPU1_TX1_CPU0_RX0_DP")
		)
		(pad "C48" smd circle
			(at 9.079992 -35.189922 180)
			(size 0.450088 0.450088)
			(layers "F.Cu" "F.Mask" "F.Paste")
			(net "WAFL_CPU1_TX1_CPU0_RX0_DN")
		)
		(pad "C49" smd circle
			(at 10.020046 -35.189922 180)
			(size 0.450088 0.450088)
			(layers "F.Cu" "F.Mask" "F.Paste")
			(net "GND")
		)
		(pad "C50" smd circle
			(at 10.9601 -35.189922 180)
			(size 0.450088 0.450088)
			(layers "F.Cu" "F.Mask" "F.Paste")
			(net "Net_2073")
		)
		(pad "C51" smd circle
			(at 11.8999 -35.189922 180)
			(size 0.450088 0.450088)
			(layers "F.Cu" "F.Mask" "F.Paste")
			(net "Net_2072")
		)
		(pad "C52" smd circle
			(at 12.839954 -35.189922 180)
			(size 0.450088 0.450088)
			(layers "F.Cu" "F.Mask" "F.Paste")
			(net "GND")
		)
		(pad "C53" smd circle
			(at 13.780008 -35.189922 180)
			(size 0.450088 0.450088)
			(layers "F.Cu" "F.Mask" "F.Paste")
			(net "Net_2151")
		)
		(pad "C54" smd circle
			(at 14.720062 -35.189922 180)
			(size 0.450088 0.450088)
			(layers "F.Cu" "F.Mask" "F.Paste")
			(net "Net_2152")
		)
		(pad "C55" smd circle
			(at 15.660116 -35.189922 180)
			(size 0.450088 0.450088)
			(layers "F.Cu" "F.Mask" "F.Paste")
			(net "GND")
		)
		(pad "C56" smd circle
			(at 16.599916 -35.189922 180)
			(size 0.450088 0.450088)
			(layers "F.Cu" "F.Mask" "F.Paste")
			(net "GND")
		)
		(pad "C57" smd circle
			(at 17.53997 -35.189922 180)
			(size 0.450088 0.450088)
			(layers "F.Cu" "F.Mask" "F.Paste")
			(net "GND")
		)
		(pad "C58" smd circle
			(at 18.480024 -35.189922 180)
			(size 0.450088 0.450088)
			(layers "F.Cu" "F.Mask" "F.Paste")
			(net "Net_2169")
		)
		(pad "C59" smd circle
			(at 19.420078 -35.189922 180)
			(size 0.450088 0.450088)
			(layers "F.Cu" "F.Mask" "F.Paste")
			(net "Net_2173")
		)
		(pad "C60" smd circle
			(at 20.359878 -35.189922 180)
			(size 0.450088 0.450088)
			(layers "F.Cu" "F.Mask" "F.Paste")
			(net "TP_M_A_CPU1_SA_TEST40")
		)
		(pad "C61" smd circle
			(at 21.299932 -35.189922 180)
			(size 0.450088 0.450088)
			(layers "F.Cu" "F.Mask" "F.Paste")
			(net "GND")
		)
		(pad "C62" smd circle
			(at 22.239986 -35.189922 180)
			(size 0.450088 0.450088)
			(layers "F.Cu" "F.Mask" "F.Paste")
			(net "CPU1_BP1")
		)
		(pad "C63" smd circle
			(at 23.18004 -35.189922 180)
			(size 0.450088 0.450088)
			(layers "F.Cu" "F.Mask" "F.Paste")
			(net "CPU1_BP0")
		)
		(pad "C64" smd circle
			(at 24.120094 -35.189922 180)
			(size 0.450088 0.450088)
			(layers "F.Cu" "F.Mask" "F.Paste")
			(net "GND")
		)
		(pad "C65" smd circle
			(at 25.059894 -35.189922 180)
			(size 0.450088 0.450088)
			(layers "F.Cu" "F.Mask" "F.Paste")
			(net "CPU1_XTRIG_R2_L5")
		)
		(pad "C66" smd circle
			(at 25.999948 -35.189922 180)
			(size 0.450088 0.450088)
			(layers "F.Cu" "F.Mask" "F.Paste")
			(net "CPU1_XTRIG_R2_L4")
		)
		(pad "C67" smd circle
			(at 26.940002 -35.189922 180)
			(size 0.450088 0.450088)
			(layers "F.Cu" "F.Mask" "F.Paste")
			(net "GND")
		)
		(pad "C68" smd circle
			(at 27.880056 -35.189922 180)
			(size 0.450088 0.450088)
			(layers "F.Cu" "F.Mask" "F.Paste")
			(net "CPU1_SP5R2")
		)
		(pad "C69" smd circle
			(at 28.82011 -35.189922 180)
			(size 0.450088 0.450088)
			(layers "F.Cu" "F.Mask" "F.Paste")
			(net "GND")
		)
		(pad "C70" smd circle
			(at 29.75991 -35.189922 180)
			(size 0.450088 0.450088)
			(layers "F.Cu" "F.Mask" "F.Paste")
			(net "CPU1_CORETYPE0")
		)
		(pad "C71" smd circle
			(at 30.699964 -35.189922 180)
			(size 0.450088 0.450088)
			(layers "F.Cu" "F.Mask" "F.Paste")
			(net "GND")
		)
		(pad "C72" smd circle
			(at 31.640018 -35.189922 180)
			(size 0.450088 0.450088)
			(layers "F.Cu" "F.Mask" "F.Paste")
			(net "Net_2096")
		)
		(pad "C73" smd circle
			(at 32.580072 -35.189922 180)
			(size 0.450088 0.450088)
			(layers "F.Cu" "F.Mask" "F.Paste")
			(net "GND")
		)
		(pad "C74" smd circle
			(at 33.519872 -35.189922 180)
			(size 0.450088 0.450088)
			(layers "F.Cu" "F.Mask" "F.Paste")
			(net "VSENSE_PVDD18_S5_P1_DP")
		)
		(pad "C75" smd circle
			(at 34.459926 -35.189922 180)
			(size 0.450088 0.450088)
			(layers "F.Cu" "F.Mask" "F.Paste")
			(net "GND")
		)
		(pad "CA1" smd circle
			(at -34.459926 14.13002 180)
			(size 0.450088 0.450088)
			(layers "F.Cu" "F.Mask" "F.Paste")
			(net "GND")
		)
		(pad "CA2" smd circle
			(at -33.519872 14.13002 180)
			(size 0.450088 0.450088)
			(layers "F.Cu" "F.Mask" "F.Paste")
			(net "M_G_CPU1_SB_CB<2>")
		)
		(pad "CA3" smd circle
			(at -32.580072 14.13002 180)
			(size 0.450088 0.450088)
			(layers "F.Cu" "F.Mask" "F.Paste")
			(net "M_G_CPU1_SB_CB<1>")
		)
		(pad "CA4" smd circle
			(at -31.640018 14.13002 180)
			(size 0.450088 0.450088)
			(layers "F.Cu" "F.Mask" "F.Paste")
			(net "PVDD11_S3_P1")
		)
		(pad "CA5" smd circle
			(at -30.699964 14.13002 180)
			(size 0.450088 0.450088)
			(layers "F.Cu" "F.Mask" "F.Paste")
			(net "M_K_CPU1_SB_CB<2>")
		)
		(pad "CA6" smd circle
			(at -29.75991 14.13002 180)
			(size 0.450088 0.450088)
			(layers "F.Cu" "F.Mask" "F.Paste")
			(net "GND")
		)
		(pad "CA7" smd circle
			(at -28.82011 14.13002 180)
			(size 0.450088 0.450088)
			(layers "F.Cu" "F.Mask" "F.Paste")
			(net "M_K_CPU1_SB_CB<1>")
		)
		(pad "CA8" smd circle
			(at -27.880056 14.13002 180)
			(size 0.450088 0.450088)
			(layers "F.Cu" "F.Mask" "F.Paste")
			(net "GND")
		)
		(pad "CA9" smd circle
			(at -26.940002 14.13002 180)
			(size 0.450088 0.450088)
			(layers "F.Cu" "F.Mask" "F.Paste")
			(net "M_L_CPU1_SB_CB<2>")
		)
		(pad "CA10" smd circle
			(at -25.999948 14.13002 180)
			(size 0.450088 0.450088)
			(layers "F.Cu" "F.Mask" "F.Paste")
			(net "M_L_CPU1_SB_CB<1>")
		)
		(pad "CA11" smd circle
			(at -25.059894 14.13002 180)
			(size 0.450088 0.450088)
			(layers "F.Cu" "F.Mask" "F.Paste")
			(net "PVDD11_S3_P1")
		)
		(pad "CA12" smd circle
			(at -24.120094 14.13002 180)
			(size 0.450088 0.450088)
			(layers "F.Cu" "F.Mask" "F.Paste")
			(net "M_H_CPU1_SB_CB<2>")
		)
		(pad "CA13" smd circle
			(at -23.18004 14.13002 180)
			(size 0.450088 0.450088)
			(layers "F.Cu" "F.Mask" "F.Paste")
			(net "GND")
		)
		(pad "CA14" smd circle
			(at -22.239986 14.13002 180)
			(size 0.450088 0.450088)
			(layers "F.Cu" "F.Mask" "F.Paste")
			(net "M_H_CPU1_SB_CB<1>")
		)
		(pad "CA15" smd circle
			(at -21.299932 14.13002 180)
			(size 0.450088 0.450088)
			(layers "F.Cu" "F.Mask" "F.Paste")
			(net "GND")
		)
		(pad "CA16" smd circle
			(at -20.359878 14.13002 180)
			(size 0.450088 0.450088)
			(layers "F.Cu" "F.Mask" "F.Paste")
			(net "M_J_CPU1_SB_CB<2>")
		)
		(pad "CA17" smd circle
			(at -19.420078 14.13002 180)
			(size 0.450088 0.450088)
			(layers "F.Cu" "F.Mask" "F.Paste")
			(net "M_J_CPU1_SB_CB<1>")
		)
		(pad "CA18" smd circle
			(at -18.480024 14.13002 180)
			(size 0.450088 0.450088)
			(layers "F.Cu" "F.Mask" "F.Paste")
			(net "PVDD11_S3_P1")
		)
		(pad "CA19" smd circle
			(at -17.53997 14.13002 180)
			(size 0.450088 0.450088)
			(layers "F.Cu" "F.Mask" "F.Paste")
			(net "M_I_CPU1_SB_CB<2>")
		)
		(pad "CA20" smd circle
			(at -16.599916 14.13002 180)
			(size 0.450088 0.450088)
			(layers "F.Cu" "F.Mask" "F.Paste")
			(net "GND")
		)
		(pad "CA21" smd circle
			(at -15.660116 14.13002 180)
			(size 0.450088 0.450088)
			(layers "F.Cu" "F.Mask" "F.Paste")
			(net "M_I_CPU1_SB_CB<1>")
		)
		(pad "CA22" smd circle
			(at -14.720062 14.13002 180)
			(size 0.450088 0.450088)
			(layers "F.Cu" "F.Mask" "F.Paste")
			(net "GND")
		)
		(pad "CA23" smd circle
			(at -13.780008 14.13002 180)
			(size 0.450088 0.450088)
			(layers "F.Cu" "F.Mask" "F.Paste")
			(net "P5E_CPU1_P2_TX_DN<14>")
		)
		(pad "CA24" smd circle
			(at -12.839954 14.13002 180)
			(size 0.450088 0.450088)
			(layers "F.Cu" "F.Mask" "F.Paste")
			(net "P5E_CPU1_P2_TX_DP<14>")
		)
		(pad "CA25" smd circle
			(at -11.8999 14.13002 180)
			(size 0.450088 0.450088)
			(layers "F.Cu" "F.Mask" "F.Paste")
			(net "GND")
		)
		(pad "CA26" smd circle
			(at -10.9601 14.13002 180)
			(size 0.450088 0.450088)
			(layers "F.Cu" "F.Mask" "F.Paste")
			(net "P5E_CPU1_P2_TX_DN<11>")
		)
		(pad "CA27" smd circle
			(at -10.020046 14.13002 180)
			(size 0.450088 0.450088)
			(layers "F.Cu" "F.Mask" "F.Paste")
			(net "P5E_CPU1_P2_TX_DP<11>")
		)
		(pad "CA28" smd circle
			(at -9.079992 14.13002 180)
			(size 0.450088 0.450088)
			(layers "F.Cu" "F.Mask" "F.Paste")
			(net "GND")
		)
		(pad "CA29" smd circle
			(at -8.139938 14.13002 180)
			(size 0.450088 0.450088)
			(layers "F.Cu" "F.Mask" "F.Paste")
			(net "P5E_CPU1_P2_TX_DN<8>")
		)
		(pad "CA30" smd circle
			(at -7.199884 14.13002 180)
			(size 0.450088 0.450088)
			(layers "F.Cu" "F.Mask" "F.Paste")
			(net "P5E_CPU1_P2_TX_DP<8>")
		)
		(pad "CA31" smd circle
			(at -6.260084 14.13002 180)
			(size 0.450088 0.450088)
			(layers "F.Cu" "F.Mask" "F.Paste")
			(net "GND")
		)
		(pad "CA32" smd circle
			(at -5.32003 14.13002 180)
			(size 0.450088 0.450088)
			(layers "F.Cu" "F.Mask" "F.Paste")
			(net "P5E_CPU1_P2_TX_DN<5>")
		)
		(pad "CA33" smd circle
			(at -4.379976 14.13002 180)
			(size 0.450088 0.450088)
			(layers "F.Cu" "F.Mask" "F.Paste")
			(net "P5E_CPU1_P2_TX_DP<5>")
		)
		(pad "CA34" smd circle
			(at -3.439922 14.13002 180)
			(size 0.450088 0.450088)
			(layers "F.Cu" "F.Mask" "F.Paste")
			(net "GND")
		)
		(pad "CA35" smd circle
			(at -2.500122 14.13002 180)
			(size 0.450088 0.450088)
			(layers "F.Cu" "F.Mask" "F.Paste")
			(net "GND")
		)
		(pad "CA36" smd circle
			(at -1.560068 14.13002 180)
			(size 0.450088 0.450088)
			(layers "F.Cu" "F.Mask" "F.Paste")
			(net "GND")
		)
		(pad "CA40" smd circle
			(at 1.260094 14.13002 180)
			(size 0.450088 0.450088)
			(layers "F.Cu" "F.Mask" "F.Paste")
			(net "GND")
		)
		(pad "CA41" smd circle
			(at 2.199894 14.13002 180)
			(size 0.450088 0.450088)
			(layers "F.Cu" "F.Mask" "F.Paste")
			(net "GND")
		)
		(pad "CA42" smd circle
			(at 3.139948 14.13002 180)
			(size 0.450088 0.450088)
			(layers "F.Cu" "F.Mask" "F.Paste")
			(net "GND")
		)
		(pad "CA43" smd circle
			(at 4.080002 14.13002 180)
			(size 0.450088 0.450088)
			(layers "F.Cu" "F.Mask" "F.Paste")
			(net "P5E_CPU1_P0_RX_DP<10>")
		)
		(pad "CA44" smd circle
			(at 5.020056 14.13002 180)
			(size 0.450088 0.450088)
			(layers "F.Cu" "F.Mask" "F.Paste")
			(net "P5E_CPU1_P0_RX_DN<10>")
		)
		(pad "CA45" smd circle
			(at 5.96011 14.13002 180)
			(size 0.450088 0.450088)
			(layers "F.Cu" "F.Mask" "F.Paste")
			(net "GND")
		)
		(pad "CA46" smd circle
			(at 6.89991 14.13002 180)
			(size 0.450088 0.450088)
			(layers "F.Cu" "F.Mask" "F.Paste")
			(net "P5E_CPU1_P0_RX_DP<7>")
		)
		(pad "CA47" smd circle
			(at 7.839964 14.13002 180)
			(size 0.450088 0.450088)
			(layers "F.Cu" "F.Mask" "F.Paste")
			(net "P5E_CPU1_P0_RX_DN<7>")
		)
		(pad "CA48" smd circle
			(at 8.780018 14.13002 180)
			(size 0.450088 0.450088)
			(layers "F.Cu" "F.Mask" "F.Paste")
			(net "GND")
		)
		(pad "CA49" smd circle
			(at 9.720072 14.13002 180)
			(size 0.450088 0.450088)
			(layers "F.Cu" "F.Mask" "F.Paste")
			(net "P5E_CPU1_P0_RX_DP<4>")
		)
		(pad "CA50" smd circle
			(at 10.659872 14.13002 180)
			(size 0.450088 0.450088)
			(layers "F.Cu" "F.Mask" "F.Paste")
			(net "P5E_CPU1_P0_RX_DN<4>")
		)
		(pad "CA51" smd circle
			(at 11.599926 14.13002 180)
			(size 0.450088 0.450088)
			(layers "F.Cu" "F.Mask" "F.Paste")
			(net "GND")
		)
		(pad "CA52" smd circle
			(at 12.53998 14.13002 180)
			(size 0.450088 0.450088)
			(layers "F.Cu" "F.Mask" "F.Paste")
			(net "P5E_CPU1_P0_RX_DP<1>")
		)
		(pad "CA53" smd circle
			(at 13.480034 14.13002 180)
			(size 0.450088 0.450088)
			(layers "F.Cu" "F.Mask" "F.Paste")
			(net "P5E_CPU1_P0_RX_DN<1>")
		)
		(pad "CA54" smd circle
			(at 14.420088 14.13002 180)
			(size 0.450088 0.450088)
			(layers "F.Cu" "F.Mask" "F.Paste")
			(net "GND")
		)
		(pad "CA55" smd circle
			(at 15.359888 14.13002 180)
			(size 0.450088 0.450088)
			(layers "F.Cu" "F.Mask" "F.Paste")
			(net "M_C_CPU1_SB_CB<1>")
		)
		(pad "CA56" smd circle
			(at 16.299942 14.13002 180)
			(size 0.450088 0.450088)
			(layers "F.Cu" "F.Mask" "F.Paste")
			(net "GND")
		)
		(pad "CA57" smd circle
			(at 17.239996 14.13002 180)
			(size 0.450088 0.450088)
			(layers "F.Cu" "F.Mask" "F.Paste")
			(net "M_C_CPU1_SB_CB<2>")
		)
		(pad "CA58" smd circle
			(at 18.18005 14.13002 180)
			(size 0.450088 0.450088)
			(layers "F.Cu" "F.Mask" "F.Paste")
			(net "PVDDIO_P1")
		)
		(pad "CA59" smd circle
			(at 19.120104 14.13002 180)
			(size 0.450088 0.450088)
			(layers "F.Cu" "F.Mask" "F.Paste")
			(net "M_D_CPU1_SB_CB<1>")
		)
		(pad "CA60" smd circle
			(at 20.059904 14.13002 180)
			(size 0.450088 0.450088)
			(layers "F.Cu" "F.Mask" "F.Paste")
			(net "M_D_CPU1_SB_CB<2>")
		)
		(pad "CA61" smd circle
			(at 20.999958 14.13002 180)
			(size 0.450088 0.450088)
			(layers "F.Cu" "F.Mask" "F.Paste")
			(net "GND")
		)
		(pad "CA62" smd circle
			(at 21.940012 14.13002 180)
			(size 0.450088 0.450088)
			(layers "F.Cu" "F.Mask" "F.Paste")
			(net "M_B_CPU1_SB_CB<1>")
		)
		(pad "CA63" smd circle
			(at 22.880066 14.13002 180)
			(size 0.450088 0.450088)
			(layers "F.Cu" "F.Mask" "F.Paste")
			(net "GND")
		)
		(pad "CA64" smd circle
			(at 23.82012 14.13002 180)
			(size 0.450088 0.450088)
			(layers "F.Cu" "F.Mask" "F.Paste")
			(net "M_B_CPU1_SB_CB<2>")
		)
		(pad "CA65" smd circle
			(at 24.75992 14.13002 180)
			(size 0.450088 0.450088)
			(layers "F.Cu" "F.Mask" "F.Paste")
			(net "PVDDIO_P1")
		)
		(pad "CA66" smd circle
			(at 25.699974 14.13002 180)
			(size 0.450088 0.450088)
			(layers "F.Cu" "F.Mask" "F.Paste")
			(net "M_F_CPU1_SB_CB<1>")
		)
		(pad "CA67" smd circle
			(at 26.640028 14.13002 180)
			(size 0.450088 0.450088)
			(layers "F.Cu" "F.Mask" "F.Paste")
			(net "M_F_CPU1_SB_CB<2>")
		)
		(pad "CA68" smd circle
			(at 27.580082 14.13002 180)
			(size 0.450088 0.450088)
			(layers "F.Cu" "F.Mask" "F.Paste")
			(net "GND")
		)
		(pad "CA69" smd circle
			(at 28.519882 14.13002 180)
			(size 0.450088 0.450088)
			(layers "F.Cu" "F.Mask" "F.Paste")
			(net "M_E_CPU1_SB_CB<1>")
		)
		(pad "CA70" smd circle
			(at 29.459936 14.13002 180)
			(size 0.450088 0.450088)
			(layers "F.Cu" "F.Mask" "F.Paste")
			(net "GND")
		)
		(pad "CA71" smd circle
			(at 30.39999 14.13002 180)
			(size 0.450088 0.450088)
			(layers "F.Cu" "F.Mask" "F.Paste")
			(net "M_E_CPU1_SB_CB<2>")
		)
		(pad "CA72" smd circle
			(at 31.340044 14.13002 180)
			(size 0.450088 0.450088)
			(layers "F.Cu" "F.Mask" "F.Paste")
			(net "PVDDIO_P1")
		)
		(pad "CA73" smd circle
			(at 32.280098 14.13002 180)
			(size 0.450088 0.450088)
			(layers "F.Cu" "F.Mask" "F.Paste")
			(net "M_A_CPU1_SB_CB<1>")
		)
		(pad "CA74" smd circle
			(at 33.219898 14.13002 180)
			(size 0.450088 0.450088)
			(layers "F.Cu" "F.Mask" "F.Paste")
			(net "M_A_CPU1_SB_CB<2>")
		)
		(pad "CA75" smd circle
			(at 34.159952 14.13002 180)
			(size 0.450088 0.450088)
			(layers "F.Cu" "F.Mask" "F.Paste")
			(net "GND")
		)
		(pad "CB2" smd circle
			(at -33.990026 14.940026 180)
			(size 0.450088 0.450088)
			(layers "F.Cu" "F.Mask" "F.Paste")
			(net "M_G_CPU1_SB_DQ<0>")
		)
		(pad "CB3" smd circle
			(at -33.049972 14.940026 180)
			(size 0.450088 0.450088)
			(layers "F.Cu" "F.Mask" "F.Paste")
			(net "GND")
		)
		(pad "CB4" smd circle
			(at -32.109918 14.940026 180)
			(size 0.450088 0.450088)
			(layers "F.Cu" "F.Mask" "F.Paste")
			(net "M_G_CPU1_SB_CB<3>")
		)
		(pad "CB5" smd circle
			(at -31.170118 14.940026 180)
			(size 0.450088 0.450088)
			(layers "F.Cu" "F.Mask" "F.Paste")
			(net "GND")
		)
		(pad "CB6" smd circle
			(at -30.230064 14.940026 180)
			(size 0.450088 0.450088)
			(layers "F.Cu" "F.Mask" "F.Paste")
			(net "M_K_CPU1_SB_DQ<0>")
		)
		(pad "CB7" smd circle
			(at -29.29001 14.940026 180)
			(size 0.450088 0.450088)
			(layers "F.Cu" "F.Mask" "F.Paste")
			(net "M_K_CPU1_SB_CB<3>")
		)
		(pad "CB8" smd circle
			(at -28.349956 14.940026 180)
			(size 0.450088 0.450088)
			(layers "F.Cu" "F.Mask" "F.Paste")
			(net "GND")
		)
		(pad "CB9" smd circle
			(at -27.409902 14.940026 180)
			(size 0.450088 0.450088)
			(layers "F.Cu" "F.Mask" "F.Paste")
			(net "M_L_CPU1_SB_DQ<0>")
		)
		(pad "CB10" smd circle
			(at -26.470102 14.940026 180)
			(size 0.450088 0.450088)
			(layers "F.Cu" "F.Mask" "F.Paste")
			(net "GND")
		)
		(pad "CB11" smd circle
			(at -25.530048 14.940026 180)
			(size 0.450088 0.450088)
			(layers "F.Cu" "F.Mask" "F.Paste")
			(net "M_L_CPU1_SB_CB<3>")
		)
		(pad "CB12" smd circle
			(at -24.589994 14.940026 180)
			(size 0.450088 0.450088)
			(layers "F.Cu" "F.Mask" "F.Paste")
			(net "GND")
		)
		(pad "CB13" smd circle
			(at -23.64994 14.940026 180)
			(size 0.450088 0.450088)
			(layers "F.Cu" "F.Mask" "F.Paste")
			(net "M_H_CPU1_SB_DQ<0>")
		)
		(pad "CB14" smd circle
			(at -22.709886 14.940026 180)
			(size 0.450088 0.450088)
			(layers "F.Cu" "F.Mask" "F.Paste")
			(net "M_H_CPU1_SB_CB<3>")
		)
		(pad "CB15" smd circle
			(at -21.770086 14.940026 180)
			(size 0.450088 0.450088)
			(layers "F.Cu" "F.Mask" "F.Paste")
			(net "GND")
		)
		(pad "CB16" smd circle
			(at -20.830032 14.940026 180)
			(size 0.450088 0.450088)
			(layers "F.Cu" "F.Mask" "F.Paste")
			(net "M_J_CPU1_SB_DQ<0>")
		)
		(pad "CB17" smd circle
			(at -19.889978 14.940026 180)
			(size 0.450088 0.450088)
			(layers "F.Cu" "F.Mask" "F.Paste")
			(net "GND")
		)
		(pad "CB18" smd circle
			(at -18.949924 14.940026 180)
			(size 0.450088 0.450088)
			(layers "F.Cu" "F.Mask" "F.Paste")
			(net "M_J_CPU1_SB_CB<3>")
		)
		(pad "CB19" smd circle
			(at -18.010124 14.940026 180)
			(size 0.450088 0.450088)
			(layers "F.Cu" "F.Mask" "F.Paste")
			(net "GND")
		)
		(pad "CB20" smd circle
			(at -17.07007 14.940026 180)
			(size 0.450088 0.450088)
			(layers "F.Cu" "F.Mask" "F.Paste")
			(net "M_I_CPU1_SB_DQ<0>")
		)
		(pad "CB21" smd circle
			(at -16.130016 14.940026 180)
			(size 0.450088 0.450088)
			(layers "F.Cu" "F.Mask" "F.Paste")
			(net "M_I_CPU1_SB_CB<3>")
		)
		(pad "CB22" smd circle
			(at -15.189962 14.940026 180)
			(size 0.450088 0.450088)
			(layers "F.Cu" "F.Mask" "F.Paste")
			(net "PVDD11_S3_P1")
		)
		(pad "CB23" smd circle
			(at -14.249908 14.940026 180)
			(size 0.450088 0.450088)
			(layers "F.Cu" "F.Mask" "F.Paste")
			(net "GND")
		)
		(pad "CB24" smd circle
			(at -13.310108 14.940026 180)
			(size 0.450088 0.450088)
			(layers "F.Cu" "F.Mask" "F.Paste")
			(net "GND")
		)
		(pad "CB25" smd circle
			(at -12.370054 14.940026 180)
			(size 0.450088 0.450088)
			(layers "F.Cu" "F.Mask" "F.Paste")
			(net "GND")
		)
		(pad "CB26" smd circle
			(at -11.43 14.940026 180)
			(size 0.450088 0.450088)
			(layers "F.Cu" "F.Mask" "F.Paste")
			(net "GND")
		)
		(pad "CB27" smd circle
			(at -10.489946 14.940026 180)
			(size 0.450088 0.450088)
			(layers "F.Cu" "F.Mask" "F.Paste")
			(net "GND")
		)
		(pad "CB28" smd circle
			(at -9.549892 14.940026 180)
			(size 0.450088 0.450088)
			(layers "F.Cu" "F.Mask" "F.Paste")
			(net "GND")
		)
		(pad "CB29" smd circle
			(at -8.610092 14.940026 180)
			(size 0.450088 0.450088)
			(layers "F.Cu" "F.Mask" "F.Paste")
			(net "GND")
		)
		(pad "CB30" smd circle
			(at -7.670038 14.940026 180)
			(size 0.450088 0.450088)
			(layers "F.Cu" "F.Mask" "F.Paste")
			(net "GND")
		)
		(pad "CB31" smd circle
			(at -6.729984 14.940026 180)
			(size 0.450088 0.450088)
			(layers "F.Cu" "F.Mask" "F.Paste")
			(net "GND")
		)
		(pad "CB32" smd circle
			(at -5.78993 14.940026 180)
			(size 0.450088 0.450088)
			(layers "F.Cu" "F.Mask" "F.Paste")
			(net "GND")
		)
		(pad "CB33" smd circle
			(at -4.849876 14.940026 180)
			(size 0.450088 0.450088)
			(layers "F.Cu" "F.Mask" "F.Paste")
			(net "GND")
		)
		(pad "CB34" smd circle
			(at -3.910076 14.940026 180)
			(size 0.450088 0.450088)
			(layers "F.Cu" "F.Mask" "F.Paste")
			(net "GND")
		)
		(pad "CB35" smd circle
			(at -2.970022 14.940026 180)
			(size 0.450088 0.450088)
			(layers "F.Cu" "F.Mask" "F.Paste")
			(net "P5E_CPU1_P2_TX_DN<2>")
		)
		(pad "CB36" smd circle
			(at -2.029968 14.940026 180)
			(size 0.450088 0.450088)
			(layers "F.Cu" "F.Mask" "F.Paste")
			(net "P5E_CPU1_P2_TX_DP<2>")
		)
		(pad "CB37" smd circle
			(at -1.089914 14.940026 180)
			(size 0.450088 0.450088)
			(layers "F.Cu" "F.Mask" "F.Paste")
			(net "GND")
		)
		(pad "CB39" smd circle
			(at 0.78994 14.940026 180)
			(size 0.450088 0.450088)
			(layers "F.Cu" "F.Mask" "F.Paste")
			(net "GND")
		)
		(pad "CB40" smd circle
			(at 1.729994 14.940026 180)
			(size 0.450088 0.450088)
			(layers "F.Cu" "F.Mask" "F.Paste")
			(net "P5E_CPU1_P0_RX_DP<13>")
		)
		(pad "CB41" smd circle
			(at 2.670048 14.940026 180)
			(size 0.450088 0.450088)
			(layers "F.Cu" "F.Mask" "F.Paste")
			(net "P5E_CPU1_P0_RX_DN<13>")
		)
		(pad "CB42" smd circle
			(at 3.610102 14.940026 180)
			(size 0.450088 0.450088)
			(layers "F.Cu" "F.Mask" "F.Paste")
			(net "GND")
		)
		(pad "CB43" smd circle
			(at 4.549902 14.940026 180)
			(size 0.450088 0.450088)
			(layers "F.Cu" "F.Mask" "F.Paste")
			(net "GND")
		)
		(pad "CB44" smd circle
			(at 5.489956 14.940026 180)
			(size 0.450088 0.450088)
			(layers "F.Cu" "F.Mask" "F.Paste")
			(net "GND")
		)
		(pad "CB45" smd circle
			(at 6.43001 14.940026 180)
			(size 0.450088 0.450088)
			(layers "F.Cu" "F.Mask" "F.Paste")
			(net "GND")
		)
		(pad "CB46" smd circle
			(at 7.370064 14.940026 180)
			(size 0.450088 0.450088)
			(layers "F.Cu" "F.Mask" "F.Paste")
			(net "GND")
		)
		(pad "CB47" smd circle
			(at 8.310118 14.940026 180)
			(size 0.450088 0.450088)
			(layers "F.Cu" "F.Mask" "F.Paste")
			(net "GND")
		)
		(pad "CB48" smd circle
			(at 9.249918 14.940026 180)
			(size 0.450088 0.450088)
			(layers "F.Cu" "F.Mask" "F.Paste")
			(net "GND")
		)
		(pad "CB49" smd circle
			(at 10.189972 14.940026 180)
			(size 0.450088 0.450088)
			(layers "F.Cu" "F.Mask" "F.Paste")
			(net "GND")
		)
		(pad "CB50" smd circle
			(at 11.130026 14.940026 180)
			(size 0.450088 0.450088)
			(layers "F.Cu" "F.Mask" "F.Paste")
			(net "GND")
		)
		(pad "CB51" smd circle
			(at 12.07008 14.940026 180)
			(size 0.450088 0.450088)
			(layers "F.Cu" "F.Mask" "F.Paste")
			(net "GND")
		)
		(pad "CB52" smd circle
			(at 13.00988 14.940026 180)
			(size 0.450088 0.450088)
			(layers "F.Cu" "F.Mask" "F.Paste")
			(net "GND")
		)
		(pad "CB53" smd circle
			(at 13.949934 14.940026 180)
			(size 0.450088 0.450088)
			(layers "F.Cu" "F.Mask" "F.Paste")
			(net "GND")
		)
		(pad "CB54" smd circle
			(at 14.889988 14.940026 180)
			(size 0.450088 0.450088)
			(layers "F.Cu" "F.Mask" "F.Paste")
			(net "PVDDIO_P1")
		)
		(pad "CB55" smd circle
			(at 15.830042 14.940026 180)
			(size 0.450088 0.450088)
			(layers "F.Cu" "F.Mask" "F.Paste")
			(net "M_C_CPU1_SB_CB<3>")
		)
		(pad "CB56" smd circle
			(at 16.770096 14.940026 180)
			(size 0.450088 0.450088)
			(layers "F.Cu" "F.Mask" "F.Paste")
			(net "M_C_CPU1_SB_DQ<0>")
		)
		(pad "CB57" smd circle
			(at 17.709896 14.940026 180)
			(size 0.450088 0.450088)
			(layers "F.Cu" "F.Mask" "F.Paste")
			(net "GND")
		)
		(pad "CB58" smd circle
			(at 18.64995 14.940026 180)
			(size 0.450088 0.450088)
			(layers "F.Cu" "F.Mask" "F.Paste")
			(net "M_D_CPU1_SB_CB<3>")
		)
		(pad "CB59" smd circle
			(at 19.590004 14.940026 180)
			(size 0.450088 0.450088)
			(layers "F.Cu" "F.Mask" "F.Paste")
			(net "GND")
		)
		(pad "CB60" smd circle
			(at 20.530058 14.940026 180)
			(size 0.450088 0.450088)
			(layers "F.Cu" "F.Mask" "F.Paste")
			(net "M_D_CPU1_SB_DQ<0>")
		)
		(pad "CB61" smd circle
			(at 21.470112 14.940026 180)
			(size 0.450088 0.450088)
			(layers "F.Cu" "F.Mask" "F.Paste")
			(net "GND")
		)
		(pad "CB62" smd circle
			(at 22.409912 14.940026 180)
			(size 0.450088 0.450088)
			(layers "F.Cu" "F.Mask" "F.Paste")
			(net "M_B_CPU1_SB_CB<3>")
		)
		(pad "CB63" smd circle
			(at 23.349966 14.940026 180)
			(size 0.450088 0.450088)
			(layers "F.Cu" "F.Mask" "F.Paste")
			(net "M_B_CPU1_SB_DQ<0>")
		)
		(pad "CB64" smd circle
			(at 24.29002 14.940026 180)
			(size 0.450088 0.450088)
			(layers "F.Cu" "F.Mask" "F.Paste")
			(net "GND")
		)
		(pad "CB65" smd circle
			(at 25.230074 14.940026 180)
			(size 0.450088 0.450088)
			(layers "F.Cu" "F.Mask" "F.Paste")
			(net "M_F_CPU1_SB_CB<3>")
		)
		(pad "CB66" smd circle
			(at 26.170128 14.940026 180)
			(size 0.450088 0.450088)
			(layers "F.Cu" "F.Mask" "F.Paste")
			(net "GND")
		)
		(pad "CB67" smd circle
			(at 27.109928 14.940026 180)
			(size 0.450088 0.450088)
			(layers "F.Cu" "F.Mask" "F.Paste")
			(net "M_F_CPU1_SB_DQ<0>")
		)
		(pad "CB68" smd circle
			(at 28.049982 14.940026 180)
			(size 0.450088 0.450088)
			(layers "F.Cu" "F.Mask" "F.Paste")
			(net "GND")
		)
		(pad "CB69" smd circle
			(at 28.990036 14.940026 180)
			(size 0.450088 0.450088)
			(layers "F.Cu" "F.Mask" "F.Paste")
			(net "M_E_CPU1_SB_CB<3>")
		)
		(pad "CB70" smd circle
			(at 29.93009 14.940026 180)
			(size 0.450088 0.450088)
			(layers "F.Cu" "F.Mask" "F.Paste")
			(net "M_E_CPU1_SB_DQ<0>")
		)
		(pad "CB71" smd circle
			(at 30.86989 14.940026 180)
			(size 0.450088 0.450088)
			(layers "F.Cu" "F.Mask" "F.Paste")
			(net "GND")
		)
		(pad "CB72" smd circle
			(at 31.809944 14.940026 180)
			(size 0.450088 0.450088)
			(layers "F.Cu" "F.Mask" "F.Paste")
			(net "M_A_CPU1_SB_CB<3>")
		)
		(pad "CB73" smd circle
			(at 32.749998 14.940026 180)
			(size 0.450088 0.450088)
			(layers "F.Cu" "F.Mask" "F.Paste")
			(net "GND")
		)
		(pad "CB74" smd circle
			(at 33.690052 14.940026 180)
			(size 0.450088 0.450088)
			(layers "F.Cu" "F.Mask" "F.Paste")
			(net "M_A_CPU1_SB_DQ<0>")
		)
		(pad "CC1" smd circle
			(at -34.459926 15.750032 180)
			(size 0.450088 0.450088)
			(layers "F.Cu" "F.Mask" "F.Paste")
			(net "GND")
		)
		(pad "CC2" smd circle
			(at -33.519872 15.750032 180)
			(size 0.450088 0.450088)
			(layers "F.Cu" "F.Mask" "F.Paste")
			(net "M_G_CPU1_SB_DQ<2>")
		)
		(pad "CC3" smd circle
			(at -32.580072 15.750032 180)
			(size 0.450088 0.450088)
			(layers "F.Cu" "F.Mask" "F.Paste")
			(net "M_G_CPU1_SB_DQ<1>")
		)
		(pad "CC4" smd circle
			(at -31.640018 15.750032 180)
			(size 0.450088 0.450088)
			(layers "F.Cu" "F.Mask" "F.Paste")
			(net "GND")
		)
		(pad "CC5" smd circle
			(at -30.699964 15.750032 180)
			(size 0.450088 0.450088)
			(layers "F.Cu" "F.Mask" "F.Paste")
			(net "M_K_CPU1_SB_DQ<2>")
		)
		(pad "CC6" smd circle
			(at -29.75991 15.750032 180)
			(size 0.450088 0.450088)
			(layers "F.Cu" "F.Mask" "F.Paste")
			(net "GND")
		)
		(pad "CC7" smd circle
			(at -28.82011 15.750032 180)
			(size 0.450088 0.450088)
			(layers "F.Cu" "F.Mask" "F.Paste")
			(net "M_K_CPU1_SB_DQ<1>")
		)
		(pad "CC8" smd circle
			(at -27.880056 15.750032 180)
			(size 0.450088 0.450088)
			(layers "F.Cu" "F.Mask" "F.Paste")
			(net "GND")
		)
		(pad "CC9" smd circle
			(at -26.940002 15.750032 180)
			(size 0.450088 0.450088)
			(layers "F.Cu" "F.Mask" "F.Paste")
			(net "M_L_CPU1_SB_DQ<2>")
		)
		(pad "CC10" smd circle
			(at -25.999948 15.750032 180)
			(size 0.450088 0.450088)
			(layers "F.Cu" "F.Mask" "F.Paste")
			(net "M_L_CPU1_SB_DQ<1>")
		)
		(pad "CC11" smd circle
			(at -25.059894 15.750032 180)
			(size 0.450088 0.450088)
			(layers "F.Cu" "F.Mask" "F.Paste")
			(net "GND")
		)
		(pad "CC12" smd circle
			(at -24.120094 15.750032 180)
			(size 0.450088 0.450088)
			(layers "F.Cu" "F.Mask" "F.Paste")
			(net "M_H_CPU1_SB_DQ<2>")
		)
		(pad "CC13" smd circle
			(at -23.18004 15.750032 180)
			(size 0.450088 0.450088)
			(layers "F.Cu" "F.Mask" "F.Paste")
			(net "GND")
		)
		(pad "CC14" smd circle
			(at -22.239986 15.750032 180)
			(size 0.450088 0.450088)
			(layers "F.Cu" "F.Mask" "F.Paste")
			(net "M_H_CPU1_SB_DQ<1>")
		)
		(pad "CC15" smd circle
			(at -21.299932 15.750032 180)
			(size 0.450088 0.450088)
			(layers "F.Cu" "F.Mask" "F.Paste")
			(net "GND")
		)
		(pad "CC16" smd circle
			(at -20.359878 15.750032 180)
			(size 0.450088 0.450088)
			(layers "F.Cu" "F.Mask" "F.Paste")
			(net "M_J_CPU1_SB_DQ<2>")
		)
		(pad "CC17" smd circle
			(at -19.420078 15.750032 180)
			(size 0.450088 0.450088)
			(layers "F.Cu" "F.Mask" "F.Paste")
			(net "M_J_CPU1_SB_DQ<1>")
		)
		(pad "CC18" smd circle
			(at -18.480024 15.750032 180)
			(size 0.450088 0.450088)
			(layers "F.Cu" "F.Mask" "F.Paste")
			(net "GND")
		)
		(pad "CC19" smd circle
			(at -17.53997 15.750032 180)
			(size 0.450088 0.450088)
			(layers "F.Cu" "F.Mask" "F.Paste")
			(net "M_I_CPU1_SB_DQ<2>")
		)
		(pad "CC20" smd circle
			(at -16.599916 15.750032 180)
			(size 0.450088 0.450088)
			(layers "F.Cu" "F.Mask" "F.Paste")
			(net "GND")
		)
		(pad "CC21" smd circle
			(at -15.660116 15.750032 180)
			(size 0.450088 0.450088)
			(layers "F.Cu" "F.Mask" "F.Paste")
			(net "M_I_CPU1_SB_DQ<1>")
		)
		(pad "CC22" smd circle
			(at -14.720062 15.750032 180)
			(size 0.450088 0.450088)
			(layers "F.Cu" "F.Mask" "F.Paste")
			(net "GND")
		)
		(pad "CC23" smd circle
			(at -13.780008 15.750032 180)
			(size 0.450088 0.450088)
			(layers "F.Cu" "F.Mask" "F.Paste")
			(net "P5E_CPU1_P3_TX_DN<13>")
		)
		(pad "CC24" smd circle
			(at -12.839954 15.750032 180)
			(size 0.450088 0.450088)
			(layers "F.Cu" "F.Mask" "F.Paste")
			(net "P5E_CPU1_P3_TX_DP<13>")
		)
		(pad "CC25" smd circle
			(at -11.8999 15.750032 180)
			(size 0.450088 0.450088)
			(layers "F.Cu" "F.Mask" "F.Paste")
			(net "GND")
		)
		(pad "CC26" smd circle
			(at -10.9601 15.750032 180)
			(size 0.450088 0.450088)
			(layers "F.Cu" "F.Mask" "F.Paste")
			(net "P5E_CPU1_P3_TX_DN<10>")
		)
		(pad "CC27" smd circle
			(at -10.020046 15.750032 180)
			(size 0.450088 0.450088)
			(layers "F.Cu" "F.Mask" "F.Paste")
			(net "P5E_CPU1_P3_TX_DP<10>")
		)
		(pad "CC28" smd circle
			(at -9.079992 15.750032 180)
			(size 0.450088 0.450088)
			(layers "F.Cu" "F.Mask" "F.Paste")
			(net "GND")
		)
		(pad "CC29" smd circle
			(at -8.139938 15.750032 180)
			(size 0.450088 0.450088)
			(layers "F.Cu" "F.Mask" "F.Paste")
			(net "P5E_CPU1_P3_TX_DN<7>")
		)
		(pad "CC30" smd circle
			(at -7.199884 15.750032 180)
			(size 0.450088 0.450088)
			(layers "F.Cu" "F.Mask" "F.Paste")
			(net "P5E_CPU1_P3_TX_DP<7>")
		)
		(pad "CC31" smd circle
			(at -6.260084 15.750032 180)
			(size 0.450088 0.450088)
			(layers "F.Cu" "F.Mask" "F.Paste")
			(net "GND")
		)
		(pad "CC32" smd circle
			(at -5.32003 15.750032 180)
			(size 0.450088 0.450088)
			(layers "F.Cu" "F.Mask" "F.Paste")
			(net "P5E_CPU1_P3_TX_DN<3>")
		)
		(pad "CC33" smd circle
			(at -4.379976 15.750032 180)
			(size 0.450088 0.450088)
			(layers "F.Cu" "F.Mask" "F.Paste")
			(net "P5E_CPU1_P3_TX_DP<3>")
		)
		(pad "CC34" smd circle
			(at -3.439922 15.750032 180)
			(size 0.450088 0.450088)
			(layers "F.Cu" "F.Mask" "F.Paste")
			(net "GND")
		)
		(pad "CC35" smd circle
			(at -2.500122 15.750032 180)
			(size 0.450088 0.450088)
			(layers "F.Cu" "F.Mask" "F.Paste")
			(net "PVDDCR_CPU1_P1")
		)
		(pad "CC36" smd circle
			(at -1.560068 15.750032 180)
			(size 0.450088 0.450088)
			(layers "F.Cu" "F.Mask" "F.Paste")
			(net "PVDDCR_CPU1_P1")
		)
		(pad "CC40" smd circle
			(at 1.260094 15.750032 180)
			(size 0.450088 0.450088)
			(layers "F.Cu" "F.Mask" "F.Paste")
			(net "PVDDCR_CPU1_P1")
		)
		(pad "CC41" smd circle
			(at 2.199894 15.750032 180)
			(size 0.450088 0.450088)
			(layers "F.Cu" "F.Mask" "F.Paste")
			(net "PVDDCR_CPU1_P1")
		)
		(pad "CC42" smd circle
			(at 3.139948 15.750032 180)
			(size 0.450088 0.450088)
			(layers "F.Cu" "F.Mask" "F.Paste")
			(net "GND")
		)
		(pad "CC43" smd circle
			(at 4.080002 15.750032 180)
			(size 0.450088 0.450088)
			(layers "F.Cu" "F.Mask" "F.Paste")
			(net "P5E_CPU1_P1_RX_DP<12>")
		)
		(pad "CC44" smd circle
			(at 5.020056 15.750032 180)
			(size 0.450088 0.450088)
			(layers "F.Cu" "F.Mask" "F.Paste")
			(net "P5E_CPU1_P1_RX_DN<12>")
		)
		(pad "CC45" smd circle
			(at 5.96011 15.750032 180)
			(size 0.450088 0.450088)
			(layers "F.Cu" "F.Mask" "F.Paste")
			(net "GND")
		)
		(pad "CC46" smd circle
			(at 6.89991 15.750032 180)
			(size 0.450088 0.450088)
			(layers "F.Cu" "F.Mask" "F.Paste")
			(net "P5E_CPU1_P1_RX_DP<8>")
		)
		(pad "CC47" smd circle
			(at 7.839964 15.750032 180)
			(size 0.450088 0.450088)
			(layers "F.Cu" "F.Mask" "F.Paste")
			(net "P5E_CPU1_P1_RX_DN<8>")
		)
		(pad "CC48" smd circle
			(at 8.780018 15.750032 180)
			(size 0.450088 0.450088)
			(layers "F.Cu" "F.Mask" "F.Paste")
			(net "GND")
		)
		(pad "CC49" smd circle
			(at 9.720072 15.750032 180)
			(size 0.450088 0.450088)
			(layers "F.Cu" "F.Mask" "F.Paste")
			(net "P5E_CPU1_P1_RX_DP<5>")
		)
		(pad "CC50" smd circle
			(at 10.659872 15.750032 180)
			(size 0.450088 0.450088)
			(layers "F.Cu" "F.Mask" "F.Paste")
			(net "P5E_CPU1_P1_RX_DN<5>")
		)
		(pad "CC51" smd circle
			(at 11.599926 15.750032 180)
			(size 0.450088 0.450088)
			(layers "F.Cu" "F.Mask" "F.Paste")
			(net "GND")
		)
		(pad "CC52" smd circle
			(at 12.53998 15.750032 180)
			(size 0.450088 0.450088)
			(layers "F.Cu" "F.Mask" "F.Paste")
			(net "P5E_CPU1_P1_RX_DP<2>")
		)
		(pad "CC53" smd circle
			(at 13.480034 15.750032 180)
			(size 0.450088 0.450088)
			(layers "F.Cu" "F.Mask" "F.Paste")
			(net "P5E_CPU1_P1_RX_DN<2>")
		)
		(pad "CC54" smd circle
			(at 14.420088 15.750032 180)
			(size 0.450088 0.450088)
			(layers "F.Cu" "F.Mask" "F.Paste")
			(net "GND")
		)
		(pad "CC55" smd circle
			(at 15.359888 15.750032 180)
			(size 0.450088 0.450088)
			(layers "F.Cu" "F.Mask" "F.Paste")
			(net "M_C_CPU1_SB_DQ<1>")
		)
		(pad "CC56" smd circle
			(at 16.299942 15.750032 180)
			(size 0.450088 0.450088)
			(layers "F.Cu" "F.Mask" "F.Paste")
			(net "GND")
		)
		(pad "CC57" smd circle
			(at 17.239996 15.750032 180)
			(size 0.450088 0.450088)
			(layers "F.Cu" "F.Mask" "F.Paste")
			(net "M_C_CPU1_SB_DQ<2>")
		)
		(pad "CC58" smd circle
			(at 18.18005 15.750032 180)
			(size 0.450088 0.450088)
			(layers "F.Cu" "F.Mask" "F.Paste")
			(net "GND")
		)
		(pad "CC59" smd circle
			(at 19.120104 15.750032 180)
			(size 0.450088 0.450088)
			(layers "F.Cu" "F.Mask" "F.Paste")
			(net "M_D_CPU1_SB_DQ<1>")
		)
		(pad "CC60" smd circle
			(at 20.059904 15.750032 180)
			(size 0.450088 0.450088)
			(layers "F.Cu" "F.Mask" "F.Paste")
			(net "M_D_CPU1_SB_DQ<2>")
		)
		(pad "CC61" smd circle
			(at 20.999958 15.750032 180)
			(size 0.450088 0.450088)
			(layers "F.Cu" "F.Mask" "F.Paste")
			(net "GND")
		)
		(pad "CC62" smd circle
			(at 21.940012 15.750032 180)
			(size 0.450088 0.450088)
			(layers "F.Cu" "F.Mask" "F.Paste")
			(net "M_B_CPU1_SB_DQ<1>")
		)
		(pad "CC63" smd circle
			(at 22.880066 15.750032 180)
			(size 0.450088 0.450088)
			(layers "F.Cu" "F.Mask" "F.Paste")
			(net "GND")
		)
		(pad "CC64" smd circle
			(at 23.82012 15.750032 180)
			(size 0.450088 0.450088)
			(layers "F.Cu" "F.Mask" "F.Paste")
			(net "M_B_CPU1_SB_DQ<2>")
		)
		(pad "CC65" smd circle
			(at 24.75992 15.750032 180)
			(size 0.450088 0.450088)
			(layers "F.Cu" "F.Mask" "F.Paste")
			(net "GND")
		)
		(pad "CC66" smd circle
			(at 25.699974 15.750032 180)
			(size 0.450088 0.450088)
			(layers "F.Cu" "F.Mask" "F.Paste")
			(net "M_F_CPU1_SB_DQ<1>")
		)
		(pad "CC67" smd circle
			(at 26.640028 15.750032 180)
			(size 0.450088 0.450088)
			(layers "F.Cu" "F.Mask" "F.Paste")
			(net "M_F_CPU1_SB_DQ<2>")
		)
		(pad "CC68" smd circle
			(at 27.580082 15.750032 180)
			(size 0.450088 0.450088)
			(layers "F.Cu" "F.Mask" "F.Paste")
			(net "GND")
		)
		(pad "CC69" smd circle
			(at 28.519882 15.750032 180)
			(size 0.450088 0.450088)
			(layers "F.Cu" "F.Mask" "F.Paste")
			(net "M_E_CPU1_SB_DQ<1>")
		)
		(pad "CC70" smd circle
			(at 29.459936 15.750032 180)
			(size 0.450088 0.450088)
			(layers "F.Cu" "F.Mask" "F.Paste")
			(net "GND")
		)
		(pad "CC71" smd circle
			(at 30.39999 15.750032 180)
			(size 0.450088 0.450088)
			(layers "F.Cu" "F.Mask" "F.Paste")
			(net "M_E_CPU1_SB_DQ<2>")
		)
		(pad "CC72" smd circle
			(at 31.340044 15.750032 180)
			(size 0.450088 0.450088)
			(layers "F.Cu" "F.Mask" "F.Paste")
			(net "GND")
		)
		(pad "CC73" smd circle
			(at 32.280098 15.750032 180)
			(size 0.450088 0.450088)
			(layers "F.Cu" "F.Mask" "F.Paste")
			(net "M_A_CPU1_SB_DQ<1>")
		)
		(pad "CC74" smd circle
			(at 33.219898 15.750032 180)
			(size 0.450088 0.450088)
			(layers "F.Cu" "F.Mask" "F.Paste")
			(net "M_A_CPU1_SB_DQ<2>")
		)
		(pad "CC75" smd circle
			(at 34.159952 15.750032 180)
			(size 0.450088 0.450088)
			(layers "F.Cu" "F.Mask" "F.Paste")
			(net "GND")
		)
		(pad "CD2" smd circle
			(at -33.990026 16.560038 180)
			(size 0.450088 0.450088)
			(layers "F.Cu" "F.Mask" "F.Paste")
			(net "M_G_CPU1_SB_DQS_DP<0>")
		)
		(pad "CD3" smd circle
			(at -33.049972 16.560038 180)
			(size 0.450088 0.450088)
			(layers "F.Cu" "F.Mask" "F.Paste")
			(net "GND")
		)
		(pad "CD4" smd circle
			(at -32.109918 16.560038 180)
			(size 0.450088 0.450088)
			(layers "F.Cu" "F.Mask" "F.Paste")
			(net "M_G_CPU1_SB_DQ<3>")
		)
		(pad "CD5" smd circle
			(at -31.170118 16.560038 180)
			(size 0.450088 0.450088)
			(layers "F.Cu" "F.Mask" "F.Paste")
			(net "PVDD11_S3_P1")
		)
		(pad "CD6" smd circle
			(at -30.230064 16.560038 180)
			(size 0.450088 0.450088)
			(layers "F.Cu" "F.Mask" "F.Paste")
			(net "M_K_CPU1_SB_DQS_DP<0>")
		)
		(pad "CD7" smd circle
			(at -29.29001 16.560038 180)
			(size 0.450088 0.450088)
			(layers "F.Cu" "F.Mask" "F.Paste")
			(net "M_K_CPU1_SB_DQ<3>")
		)
		(pad "CD8" smd circle
			(at -28.349956 16.560038 180)
			(size 0.450088 0.450088)
			(layers "F.Cu" "F.Mask" "F.Paste")
			(net "GND")
		)
		(pad "CD9" smd circle
			(at -27.409902 16.560038 180)
			(size 0.450088 0.450088)
			(layers "F.Cu" "F.Mask" "F.Paste")
			(net "M_L_CPU1_SB_DQS_DP<0>")
		)
		(pad "CD10" smd circle
			(at -26.470102 16.560038 180)
			(size 0.450088 0.450088)
			(layers "F.Cu" "F.Mask" "F.Paste")
			(net "GND")
		)
		(pad "CD11" smd circle
			(at -25.530048 16.560038 180)
			(size 0.450088 0.450088)
			(layers "F.Cu" "F.Mask" "F.Paste")
			(net "M_L_CPU1_SB_DQ<3>")
		)
		(pad "CD12" smd circle
			(at -24.589994 16.560038 180)
			(size 0.450088 0.450088)
			(layers "F.Cu" "F.Mask" "F.Paste")
			(net "PVDD11_S3_P1")
		)
		(pad "CD13" smd circle
			(at -23.64994 16.560038 180)
			(size 0.450088 0.450088)
			(layers "F.Cu" "F.Mask" "F.Paste")
			(net "M_H_CPU1_SB_DQS_DP<0>")
		)
		(pad "CD14" smd circle
			(at -22.709886 16.560038 180)
			(size 0.450088 0.450088)
			(layers "F.Cu" "F.Mask" "F.Paste")
			(net "M_H_CPU1_SB_DQ<3>")
		)
		(pad "CD15" smd circle
			(at -21.770086 16.560038 180)
			(size 0.450088 0.450088)
			(layers "F.Cu" "F.Mask" "F.Paste")
			(net "GND")
		)
		(pad "CD16" smd circle
			(at -20.830032 16.560038 180)
			(size 0.450088 0.450088)
			(layers "F.Cu" "F.Mask" "F.Paste")
			(net "M_J_CPU1_SB_DQS_DP<0>")
		)
		(pad "CD17" smd circle
			(at -19.889978 16.560038 180)
			(size 0.450088 0.450088)
			(layers "F.Cu" "F.Mask" "F.Paste")
			(net "GND")
		)
		(pad "CD18" smd circle
			(at -18.949924 16.560038 180)
			(size 0.450088 0.450088)
			(layers "F.Cu" "F.Mask" "F.Paste")
			(net "M_J_CPU1_SB_DQ<3>")
		)
		(pad "CD19" smd circle
			(at -18.010124 16.560038 180)
			(size 0.450088 0.450088)
			(layers "F.Cu" "F.Mask" "F.Paste")
			(net "PVDD11_S3_P1")
		)
		(pad "CD20" smd circle
			(at -17.07007 16.560038 180)
			(size 0.450088 0.450088)
			(layers "F.Cu" "F.Mask" "F.Paste")
			(net "M_I_CPU1_SB_DQS_DP<0>")
		)
		(pad "CD21" smd circle
			(at -16.130016 16.560038 180)
			(size 0.450088 0.450088)
			(layers "F.Cu" "F.Mask" "F.Paste")
			(net "M_I_CPU1_SB_DQ<3>")
		)
		(pad "CD22" smd circle
			(at -15.189962 16.560038 180)
			(size 0.450088 0.450088)
			(layers "F.Cu" "F.Mask" "F.Paste")
			(net "GND")
		)
		(pad "CD23" smd circle
			(at -14.249908 16.560038 180)
			(size 0.450088 0.450088)
			(layers "F.Cu" "F.Mask" "F.Paste")
			(net "PVDDCR_CPU1_P1")
		)
		(pad "CD24" smd circle
			(at -13.310108 16.560038 180)
			(size 0.450088 0.450088)
			(layers "F.Cu" "F.Mask" "F.Paste")
			(net "PVDDCR_CPU1_P1")
		)
		(pad "CD25" smd circle
			(at -12.370054 16.560038 180)
			(size 0.450088 0.450088)
			(layers "F.Cu" "F.Mask" "F.Paste")
			(net "GND")
		)
		(pad "CD26" smd circle
			(at -11.43 16.560038 180)
			(size 0.450088 0.450088)
			(layers "F.Cu" "F.Mask" "F.Paste")
			(net "PVDDCR_CPU1_P1")
		)
		(pad "CD27" smd circle
			(at -10.489946 16.560038 180)
			(size 0.450088 0.450088)
			(layers "F.Cu" "F.Mask" "F.Paste")
			(net "PVDDCR_CPU1_P1")
		)
		(pad "CD28" smd circle
			(at -9.549892 16.560038 180)
			(size 0.450088 0.450088)
			(layers "F.Cu" "F.Mask" "F.Paste")
			(net "GND")
		)
		(pad "CD29" smd circle
			(at -8.610092 16.560038 180)
			(size 0.450088 0.450088)
			(layers "F.Cu" "F.Mask" "F.Paste")
			(net "PVDDCR_CPU1_P1")
		)
		(pad "CD30" smd circle
			(at -7.670038 16.560038 180)
			(size 0.450088 0.450088)
			(layers "F.Cu" "F.Mask" "F.Paste")
			(net "PVDDCR_CPU1_P1")
		)
		(pad "CD31" smd circle
			(at -6.729984 16.560038 180)
			(size 0.450088 0.450088)
			(layers "F.Cu" "F.Mask" "F.Paste")
			(net "GND")
		)
		(pad "CD32" smd circle
			(at -5.78993 16.560038 180)
			(size 0.450088 0.450088)
			(layers "F.Cu" "F.Mask" "F.Paste")
			(net "PVDDCR_CPU1_P1")
		)
		(pad "CD33" smd circle
			(at -4.849876 16.560038 180)
			(size 0.450088 0.450088)
			(layers "F.Cu" "F.Mask" "F.Paste")
			(net "PVDDCR_CPU1_P1")
		)
		(pad "CD34" smd circle
			(at -3.910076 16.560038 180)
			(size 0.450088 0.450088)
			(layers "F.Cu" "F.Mask" "F.Paste")
			(net "GND")
		)
		(pad "CD35" smd circle
			(at -2.970022 16.560038 180)
			(size 0.450088 0.450088)
			(layers "F.Cu" "F.Mask" "F.Paste")
			(net "P5E_CPU1_P3_TX_DN<0>")
		)
		(pad "CD36" smd circle
			(at -2.029968 16.560038 180)
			(size 0.450088 0.450088)
			(layers "F.Cu" "F.Mask" "F.Paste")
			(net "P5E_CPU1_P3_TX_DP<0>")
		)
		(pad "CD37" smd circle
			(at -1.089914 16.560038 180)
			(size 0.450088 0.450088)
			(layers "F.Cu" "F.Mask" "F.Paste")
			(net "GND")
		)
		(pad "CD39" smd circle
			(at 0.78994 16.560038 180)
			(size 0.450088 0.450088)
			(layers "F.Cu" "F.Mask" "F.Paste")
			(net "GND")
		)
		(pad "CD40" smd circle
			(at 1.729994 16.560038 180)
			(size 0.450088 0.450088)
			(layers "F.Cu" "F.Mask" "F.Paste")
			(net "P5E_CPU1_P1_RX_DP<15>")
		)
		(pad "CD41" smd circle
			(at 2.670048 16.560038 180)
			(size 0.450088 0.450088)
			(layers "F.Cu" "F.Mask" "F.Paste")
			(net "P5E_CPU1_P1_RX_DN<15>")
		)
		(pad "CD42" smd circle
			(at 3.610102 16.560038 180)
			(size 0.450088 0.450088)
			(layers "F.Cu" "F.Mask" "F.Paste")
			(net "GND")
		)
		(pad "CD43" smd circle
			(at 4.549902 16.560038 180)
			(size 0.450088 0.450088)
			(layers "F.Cu" "F.Mask" "F.Paste")
			(net "PVDDCR_CPU1_P1")
		)
		(pad "CD44" smd circle
			(at 5.489956 16.560038 180)
			(size 0.450088 0.450088)
			(layers "F.Cu" "F.Mask" "F.Paste")
			(net "PVDDCR_CPU1_P1")
		)
		(pad "CD45" smd circle
			(at 6.43001 16.560038 180)
			(size 0.450088 0.450088)
			(layers "F.Cu" "F.Mask" "F.Paste")
			(net "GND")
		)
		(pad "CD46" smd circle
			(at 7.370064 16.560038 180)
			(size 0.450088 0.450088)
			(layers "F.Cu" "F.Mask" "F.Paste")
			(net "PVDDCR_CPU1_P1")
		)
		(pad "CD47" smd circle
			(at 8.310118 16.560038 180)
			(size 0.450088 0.450088)
			(layers "F.Cu" "F.Mask" "F.Paste")
			(net "PVDDCR_CPU1_P1")
		)
		(pad "CD48" smd circle
			(at 9.249918 16.560038 180)
			(size 0.450088 0.450088)
			(layers "F.Cu" "F.Mask" "F.Paste")
			(net "GND")
		)
		(pad "CD49" smd circle
			(at 10.189972 16.560038 180)
			(size 0.450088 0.450088)
			(layers "F.Cu" "F.Mask" "F.Paste")
			(net "PVDDCR_CPU1_P1")
		)
		(pad "CD50" smd circle
			(at 11.130026 16.560038 180)
			(size 0.450088 0.450088)
			(layers "F.Cu" "F.Mask" "F.Paste")
			(net "PVDDCR_CPU1_P1")
		)
		(pad "CD51" smd circle
			(at 12.07008 16.560038 180)
			(size 0.450088 0.450088)
			(layers "F.Cu" "F.Mask" "F.Paste")
			(net "GND")
		)
		(pad "CD52" smd circle
			(at 13.00988 16.560038 180)
			(size 0.450088 0.450088)
			(layers "F.Cu" "F.Mask" "F.Paste")
			(net "PVDDCR_CPU1_P1")
		)
		(pad "CD53" smd circle
			(at 13.949934 16.560038 180)
			(size 0.450088 0.450088)
			(layers "F.Cu" "F.Mask" "F.Paste")
			(net "PVDDCR_CPU1_P1")
		)
		(pad "CD54" smd circle
			(at 14.889988 16.560038 180)
			(size 0.450088 0.450088)
			(layers "F.Cu" "F.Mask" "F.Paste")
			(net "GND")
		)
		(pad "CD55" smd circle
			(at 15.830042 16.560038 180)
			(size 0.450088 0.450088)
			(layers "F.Cu" "F.Mask" "F.Paste")
			(net "M_C_CPU1_SB_DQ<3>")
		)
		(pad "CD56" smd circle
			(at 16.770096 16.560038 180)
			(size 0.450088 0.450088)
			(layers "F.Cu" "F.Mask" "F.Paste")
			(net "M_C_CPU1_SB_DQS_DP<0>")
		)
		(pad "CD57" smd circle
			(at 17.709896 16.560038 180)
			(size 0.450088 0.450088)
			(layers "F.Cu" "F.Mask" "F.Paste")
			(net "PVDDIO_P1")
		)
		(pad "CD58" smd circle
			(at 18.64995 16.560038 180)
			(size 0.450088 0.450088)
			(layers "F.Cu" "F.Mask" "F.Paste")
			(net "M_D_CPU1_SB_DQ<3>")
		)
		(pad "CD59" smd circle
			(at 19.590004 16.560038 180)
			(size 0.450088 0.450088)
			(layers "F.Cu" "F.Mask" "F.Paste")
			(net "GND")
		)
		(pad "CD60" smd circle
			(at 20.530058 16.560038 180)
			(size 0.450088 0.450088)
			(layers "F.Cu" "F.Mask" "F.Paste")
			(net "M_D_CPU1_SB_DQS_DP<0>")
		)
		(pad "CD61" smd circle
			(at 21.470112 16.560038 180)
			(size 0.450088 0.450088)
			(layers "F.Cu" "F.Mask" "F.Paste")
			(net "GND")
		)
		(pad "CD62" smd circle
			(at 22.409912 16.560038 180)
			(size 0.450088 0.450088)
			(layers "F.Cu" "F.Mask" "F.Paste")
			(net "M_B_CPU1_SB_DQ<3>")
		)
		(pad "CD63" smd circle
			(at 23.349966 16.560038 180)
			(size 0.450088 0.450088)
			(layers "F.Cu" "F.Mask" "F.Paste")
			(net "M_B_CPU1_SB_DQS_DP<0>")
		)
		(pad "CD64" smd circle
			(at 24.29002 16.560038 180)
			(size 0.450088 0.450088)
			(layers "F.Cu" "F.Mask" "F.Paste")
			(net "PVDDIO_P1")
		)
		(pad "CD65" smd circle
			(at 25.230074 16.560038 180)
			(size 0.450088 0.450088)
			(layers "F.Cu" "F.Mask" "F.Paste")
			(net "M_F_CPU1_SB_DQ<3>")
		)
		(pad "CD66" smd circle
			(at 26.170128 16.560038 180)
			(size 0.450088 0.450088)
			(layers "F.Cu" "F.Mask" "F.Paste")
			(net "GND")
		)
		(pad "CD67" smd circle
			(at 27.109928 16.560038 180)
			(size 0.450088 0.450088)
			(layers "F.Cu" "F.Mask" "F.Paste")
			(net "M_F_CPU1_SB_DQS_DP<0>")
		)
		(pad "CD68" smd circle
			(at 28.049982 16.560038 180)
			(size 0.450088 0.450088)
			(layers "F.Cu" "F.Mask" "F.Paste")
			(net "GND")
		)
		(pad "CD69" smd circle
			(at 28.990036 16.560038 180)
			(size 0.450088 0.450088)
			(layers "F.Cu" "F.Mask" "F.Paste")
			(net "M_E_CPU1_SB_DQ<3>")
		)
		(pad "CD70" smd circle
			(at 29.93009 16.560038 180)
			(size 0.450088 0.450088)
			(layers "F.Cu" "F.Mask" "F.Paste")
			(net "M_E_CPU1_SB_DQS_DP<0>")
		)
		(pad "CD71" smd circle
			(at 30.86989 16.560038 180)
			(size 0.450088 0.450088)
			(layers "F.Cu" "F.Mask" "F.Paste")
			(net "PVDDIO_P1")
		)
		(pad "CD72" smd circle
			(at 31.809944 16.560038 180)
			(size 0.450088 0.450088)
			(layers "F.Cu" "F.Mask" "F.Paste")
			(net "M_A_CPU1_SB_DQ<3>")
		)
		(pad "CD73" smd circle
			(at 32.749998 16.560038 180)
			(size 0.450088 0.450088)
			(layers "F.Cu" "F.Mask" "F.Paste")
			(net "GND")
		)
		(pad "CD74" smd circle
			(at 33.690052 16.560038 180)
			(size 0.450088 0.450088)
			(layers "F.Cu" "F.Mask" "F.Paste")
			(net "M_A_CPU1_SB_DQS_DP<0>")
		)
		(pad "CE1" smd circle
			(at -34.459926 17.370044 180)
			(size 0.450088 0.450088)
			(layers "F.Cu" "F.Mask" "F.Paste")
			(net "GND")
		)
		(pad "CE2" smd circle
			(at -33.519872 17.370044 180)
			(size 0.450088 0.450088)
			(layers "F.Cu" "F.Mask" "F.Paste")
			(net "M_G_CPU1_SB_DQS_DN<0>")
		)
		(pad "CE3" smd circle
			(at -32.580072 17.370044 180)
			(size 0.450088 0.450088)
			(layers "F.Cu" "F.Mask" "F.Paste")
			(net "M_G_CPU1_SB_DQS_DN<5>")
		)
		(pad "CE4" smd circle
			(at -31.640018 17.370044 180)
			(size 0.450088 0.450088)
			(layers "F.Cu" "F.Mask" "F.Paste")
			(net "GND")
		)
		(pad "CE5" smd circle
			(at -30.699964 17.370044 180)
			(size 0.450088 0.450088)
			(layers "F.Cu" "F.Mask" "F.Paste")
			(net "M_K_CPU1_SB_DQS_DN<0>")
		)
		(pad "CE6" smd circle
			(at -29.75991 17.370044 180)
			(size 0.450088 0.450088)
			(layers "F.Cu" "F.Mask" "F.Paste")
			(net "GND")
		)
		(pad "CE7" smd circle
			(at -28.82011 17.370044 180)
			(size 0.450088 0.450088)
			(layers "F.Cu" "F.Mask" "F.Paste")
			(net "M_K_CPU1_SB_DQS_DN<5>")
		)
		(pad "CE8" smd circle
			(at -27.880056 17.370044 180)
			(size 0.450088 0.450088)
			(layers "F.Cu" "F.Mask" "F.Paste")
			(net "GND")
		)
		(pad "CE9" smd circle
			(at -26.940002 17.370044 180)
			(size 0.450088 0.450088)
			(layers "F.Cu" "F.Mask" "F.Paste")
			(net "M_L_CPU1_SB_DQS_DN<0>")
		)
		(pad "CE10" smd circle
			(at -25.999948 17.370044 180)
			(size 0.450088 0.450088)
			(layers "F.Cu" "F.Mask" "F.Paste")
			(net "M_L_CPU1_SB_DQS_DN<5>")
		)
		(pad "CE11" smd circle
			(at -25.059894 17.370044 180)
			(size 0.450088 0.450088)
			(layers "F.Cu" "F.Mask" "F.Paste")
			(net "GND")
		)
		(pad "CE12" smd circle
			(at -24.120094 17.370044 180)
			(size 0.450088 0.450088)
			(layers "F.Cu" "F.Mask" "F.Paste")
			(net "M_H_CPU1_SB_DQS_DN<0>")
		)
		(pad "CE13" smd circle
			(at -23.18004 17.370044 180)
			(size 0.450088 0.450088)
			(layers "F.Cu" "F.Mask" "F.Paste")
			(net "GND")
		)
		(pad "CE14" smd circle
			(at -22.239986 17.370044 180)
			(size 0.450088 0.450088)
			(layers "F.Cu" "F.Mask" "F.Paste")
			(net "M_H_CPU1_SB_DQS_DN<5>")
		)
		(pad "CE15" smd circle
			(at -21.299932 17.370044 180)
			(size 0.450088 0.450088)
			(layers "F.Cu" "F.Mask" "F.Paste")
			(net "GND")
		)
		(pad "CE16" smd circle
			(at -20.359878 17.370044 180)
			(size 0.450088 0.450088)
			(layers "F.Cu" "F.Mask" "F.Paste")
			(net "M_J_CPU1_SB_DQS_DN<0>")
		)
		(pad "CE17" smd circle
			(at -19.420078 17.370044 180)
			(size 0.450088 0.450088)
			(layers "F.Cu" "F.Mask" "F.Paste")
			(net "M_J_CPU1_SB_DQS_DN<5>")
		)
		(pad "CE18" smd circle
			(at -18.480024 17.370044 180)
			(size 0.450088 0.450088)
			(layers "F.Cu" "F.Mask" "F.Paste")
			(net "GND")
		)
		(pad "CE19" smd circle
			(at -17.53997 17.370044 180)
			(size 0.450088 0.450088)
			(layers "F.Cu" "F.Mask" "F.Paste")
			(net "M_I_CPU1_SB_DQS_DN<0>")
		)
		(pad "CE20" smd circle
			(at -16.599916 17.370044 180)
			(size 0.450088 0.450088)
			(layers "F.Cu" "F.Mask" "F.Paste")
			(net "GND")
		)
		(pad "CE21" smd circle
			(at -15.660116 17.370044 180)
			(size 0.450088 0.450088)
			(layers "F.Cu" "F.Mask" "F.Paste")
			(net "M_I_CPU1_SB_DQS_DN<5>")
		)
		(pad "CE22" smd circle
			(at -14.720062 17.370044 180)
			(size 0.450088 0.450088)
			(layers "F.Cu" "F.Mask" "F.Paste")
			(net "GND")
		)
		(pad "CE23" smd circle
			(at -13.780008 17.370044 180)
			(size 0.450088 0.450088)
			(layers "F.Cu" "F.Mask" "F.Paste")
			(net "P5E_CPU1_P3_TX_DN<15>")
		)
		(pad "CE24" smd circle
			(at -12.839954 17.370044 180)
			(size 0.450088 0.450088)
			(layers "F.Cu" "F.Mask" "F.Paste")
			(net "P5E_CPU1_P3_TX_DP<15>")
		)
		(pad "CE25" smd circle
			(at -11.8999 17.370044 180)
			(size 0.450088 0.450088)
			(layers "F.Cu" "F.Mask" "F.Paste")
			(net "GND")
		)
		(pad "CE26" smd circle
			(at -10.9601 17.370044 180)
			(size 0.450088 0.450088)
			(layers "F.Cu" "F.Mask" "F.Paste")
			(net "P5E_CPU1_P3_TX_DN<12>")
		)
		(pad "CE27" smd circle
			(at -10.020046 17.370044 180)
			(size 0.450088 0.450088)
			(layers "F.Cu" "F.Mask" "F.Paste")
			(net "P5E_CPU1_P3_TX_DP<12>")
		)
		(pad "CE28" smd circle
			(at -9.079992 17.370044 180)
			(size 0.450088 0.450088)
			(layers "F.Cu" "F.Mask" "F.Paste")
			(net "GND")
		)
		(pad "CE29" smd circle
			(at -8.139938 17.370044 180)
			(size 0.450088 0.450088)
			(layers "F.Cu" "F.Mask" "F.Paste")
			(net "P5E_CPU1_P3_TX_DN<9>")
		)
		(pad "CE30" smd circle
			(at -7.199884 17.370044 180)
			(size 0.450088 0.450088)
			(layers "F.Cu" "F.Mask" "F.Paste")
			(net "P5E_CPU1_P3_TX_DP<9>")
		)
		(pad "CE31" smd circle
			(at -6.260084 17.370044 180)
			(size 0.450088 0.450088)
			(layers "F.Cu" "F.Mask" "F.Paste")
			(net "GND")
		)
		(pad "CE32" smd circle
			(at -5.32003 17.370044 180)
			(size 0.450088 0.450088)
			(layers "F.Cu" "F.Mask" "F.Paste")
			(net "P5E_CPU1_P3_TX_DN<6>")
		)
		(pad "CE33" smd circle
			(at -4.379976 17.370044 180)
			(size 0.450088 0.450088)
			(layers "F.Cu" "F.Mask" "F.Paste")
			(net "P5E_CPU1_P3_TX_DP<6>")
		)
		(pad "CE34" smd circle
			(at -3.439922 17.370044 180)
			(size 0.450088 0.450088)
			(layers "F.Cu" "F.Mask" "F.Paste")
			(net "GND")
		)
		(pad "CE35" smd circle
			(at -2.500122 17.370044 180)
			(size 0.450088 0.450088)
			(layers "F.Cu" "F.Mask" "F.Paste")
			(net "GND")
		)
		(pad "CE36" smd circle
			(at -1.560068 17.370044 180)
			(size 0.450088 0.450088)
			(layers "F.Cu" "F.Mask" "F.Paste")
			(net "GND")
		)
		(pad "CE40" smd circle
			(at 1.260094 17.370044 180)
			(size 0.450088 0.450088)
			(layers "F.Cu" "F.Mask" "F.Paste")
			(net "GND")
		)
		(pad "CE41" smd circle
			(at 2.199894 17.370044 180)
			(size 0.450088 0.450088)
			(layers "F.Cu" "F.Mask" "F.Paste")
			(net "GND")
		)
		(pad "CE42" smd circle
			(at 3.139948 17.370044 180)
			(size 0.450088 0.450088)
			(layers "F.Cu" "F.Mask" "F.Paste")
			(net "GND")
		)
		(pad "CE43" smd circle
			(at 4.080002 17.370044 180)
			(size 0.450088 0.450088)
			(layers "F.Cu" "F.Mask" "F.Paste")
			(net "P5E_CPU1_P1_RX_DP<9>")
		)
		(pad "CE44" smd circle
			(at 5.020056 17.370044 180)
			(size 0.450088 0.450088)
			(layers "F.Cu" "F.Mask" "F.Paste")
			(net "P5E_CPU1_P1_RX_DN<9>")
		)
		(pad "CE45" smd circle
			(at 5.96011 17.370044 180)
			(size 0.450088 0.450088)
			(layers "F.Cu" "F.Mask" "F.Paste")
			(net "GND")
		)
		(pad "CE46" smd circle
			(at 6.89991 17.370044 180)
			(size 0.450088 0.450088)
			(layers "F.Cu" "F.Mask" "F.Paste")
			(net "P5E_CPU1_P1_RX_DP<6>")
		)
		(pad "CE47" smd circle
			(at 7.839964 17.370044 180)
			(size 0.450088 0.450088)
			(layers "F.Cu" "F.Mask" "F.Paste")
			(net "P5E_CPU1_P1_RX_DN<6>")
		)
		(pad "CE48" smd circle
			(at 8.780018 17.370044 180)
			(size 0.450088 0.450088)
			(layers "F.Cu" "F.Mask" "F.Paste")
			(net "GND")
		)
		(pad "CE49" smd circle
			(at 9.720072 17.370044 180)
			(size 0.450088 0.450088)
			(layers "F.Cu" "F.Mask" "F.Paste")
			(net "P5E_CPU1_P1_RX_DP<3>")
		)
		(pad "CE50" smd circle
			(at 10.659872 17.370044 180)
			(size 0.450088 0.450088)
			(layers "F.Cu" "F.Mask" "F.Paste")
			(net "P5E_CPU1_P1_RX_DN<3>")
		)
		(pad "CE51" smd circle
			(at 11.599926 17.370044 180)
			(size 0.450088 0.450088)
			(layers "F.Cu" "F.Mask" "F.Paste")
			(net "GND")
		)
		(pad "CE52" smd circle
			(at 12.53998 17.370044 180)
			(size 0.450088 0.450088)
			(layers "F.Cu" "F.Mask" "F.Paste")
			(net "P5E_CPU1_P1_RX_DP<0>")
		)
		(pad "CE53" smd circle
			(at 13.480034 17.370044 180)
			(size 0.450088 0.450088)
			(layers "F.Cu" "F.Mask" "F.Paste")
			(net "P5E_CPU1_P1_RX_DN<0>")
		)
		(pad "CE54" smd circle
			(at 14.420088 17.370044 180)
			(size 0.450088 0.450088)
			(layers "F.Cu" "F.Mask" "F.Paste")
			(net "GND")
		)
		(pad "CE55" smd circle
			(at 15.359888 17.370044 180)
			(size 0.450088 0.450088)
			(layers "F.Cu" "F.Mask" "F.Paste")
			(net "M_C_CPU1_SB_DQS_DN<5>")
		)
		(pad "CE56" smd circle
			(at 16.299942 17.370044 180)
			(size 0.450088 0.450088)
			(layers "F.Cu" "F.Mask" "F.Paste")
			(net "GND")
		)
		(pad "CE57" smd circle
			(at 17.239996 17.370044 180)
			(size 0.450088 0.450088)
			(layers "F.Cu" "F.Mask" "F.Paste")
			(net "M_C_CPU1_SB_DQS_DN<0>")
		)
		(pad "CE58" smd circle
			(at 18.18005 17.370044 180)
			(size 0.450088 0.450088)
			(layers "F.Cu" "F.Mask" "F.Paste")
			(net "GND")
		)
		(pad "CE59" smd circle
			(at 19.120104 17.370044 180)
			(size 0.450088 0.450088)
			(layers "F.Cu" "F.Mask" "F.Paste")
			(net "M_D_CPU1_SB_DQS_DN<5>")
		)
		(pad "CE60" smd circle
			(at 20.059904 17.370044 180)
			(size 0.450088 0.450088)
			(layers "F.Cu" "F.Mask" "F.Paste")
			(net "M_D_CPU1_SB_DQS_DN<0>")
		)
		(pad "CE61" smd circle
			(at 20.999958 17.370044 180)
			(size 0.450088 0.450088)
			(layers "F.Cu" "F.Mask" "F.Paste")
			(net "GND")
		)
		(pad "CE62" smd circle
			(at 21.940012 17.370044 180)
			(size 0.450088 0.450088)
			(layers "F.Cu" "F.Mask" "F.Paste")
			(net "M_B_CPU1_SB_DQS_DN<5>")
		)
		(pad "CE63" smd circle
			(at 22.880066 17.370044 180)
			(size 0.450088 0.450088)
			(layers "F.Cu" "F.Mask" "F.Paste")
			(net "GND")
		)
		(pad "CE64" smd circle
			(at 23.82012 17.370044 180)
			(size 0.450088 0.450088)
			(layers "F.Cu" "F.Mask" "F.Paste")
			(net "M_B_CPU1_SB_DQS_DN<0>")
		)
		(pad "CE65" smd circle
			(at 24.75992 17.370044 180)
			(size 0.450088 0.450088)
			(layers "F.Cu" "F.Mask" "F.Paste")
			(net "GND")
		)
		(pad "CE66" smd circle
			(at 25.699974 17.370044 180)
			(size 0.450088 0.450088)
			(layers "F.Cu" "F.Mask" "F.Paste")
			(net "M_F_CPU1_SB_DQS_DN<5>")
		)
		(pad "CE67" smd circle
			(at 26.640028 17.370044 180)
			(size 0.450088 0.450088)
			(layers "F.Cu" "F.Mask" "F.Paste")
			(net "M_F_CPU1_SB_DQS_DN<0>")
		)
		(pad "CE68" smd circle
			(at 27.580082 17.370044 180)
			(size 0.450088 0.450088)
			(layers "F.Cu" "F.Mask" "F.Paste")
			(net "GND")
		)
		(pad "CE69" smd circle
			(at 28.519882 17.370044 180)
			(size 0.450088 0.450088)
			(layers "F.Cu" "F.Mask" "F.Paste")
			(net "M_E_CPU1_SB_DQS_DN<5>")
		)
		(pad "CE70" smd circle
			(at 29.459936 17.370044 180)
			(size 0.450088 0.450088)
			(layers "F.Cu" "F.Mask" "F.Paste")
			(net "GND")
		)
		(pad "CE71" smd circle
			(at 30.39999 17.370044 180)
			(size 0.450088 0.450088)
			(layers "F.Cu" "F.Mask" "F.Paste")
			(net "M_E_CPU1_SB_DQS_DN<0>")
		)
		(pad "CE72" smd circle
			(at 31.340044 17.370044 180)
			(size 0.450088 0.450088)
			(layers "F.Cu" "F.Mask" "F.Paste")
			(net "GND")
		)
		(pad "CE73" smd circle
			(at 32.280098 17.370044 180)
			(size 0.450088 0.450088)
			(layers "F.Cu" "F.Mask" "F.Paste")
			(net "M_A_CPU1_SB_DQS_DN<5>")
		)
		(pad "CE74" smd circle
			(at 33.219898 17.370044 180)
			(size 0.450088 0.450088)
			(layers "F.Cu" "F.Mask" "F.Paste")
			(net "M_A_CPU1_SB_DQS_DN<0>")
		)
		(pad "CE75" smd circle
			(at 34.159952 17.370044 180)
			(size 0.450088 0.450088)
			(layers "F.Cu" "F.Mask" "F.Paste")
			(net "GND")
		)
		(pad "CF2" smd circle
			(at -33.990026 18.18005 180)
			(size 0.450088 0.450088)
			(layers "F.Cu" "F.Mask" "F.Paste")
			(net "M_G_CPU1_SB_DQ<4>")
		)
		(pad "CF3" smd circle
			(at -33.049972 18.18005 180)
			(size 0.450088 0.450088)
			(layers "F.Cu" "F.Mask" "F.Paste")
			(net "GND")
		)
		(pad "CF4" smd circle
			(at -32.109918 18.18005 180)
			(size 0.450088 0.450088)
			(layers "F.Cu" "F.Mask" "F.Paste")
			(net "M_G_CPU1_SB_DQS_DP<5>")
		)
		(pad "CF5" smd circle
			(at -31.170118 18.18005 180)
			(size 0.450088 0.450088)
			(layers "F.Cu" "F.Mask" "F.Paste")
			(net "GND")
		)
		(pad "CF6" smd circle
			(at -30.230064 18.18005 180)
			(size 0.450088 0.450088)
			(layers "F.Cu" "F.Mask" "F.Paste")
			(net "M_K_CPU1_SB_DQ<4>")
		)
		(pad "CF7" smd circle
			(at -29.29001 18.18005 180)
			(size 0.450088 0.450088)
			(layers "F.Cu" "F.Mask" "F.Paste")
			(net "M_K_CPU1_SB_DQS_DP<5>")
		)
		(pad "CF8" smd circle
			(at -28.349956 18.18005 180)
			(size 0.450088 0.450088)
			(layers "F.Cu" "F.Mask" "F.Paste")
			(net "GND")
		)
		(pad "CF9" smd circle
			(at -27.409902 18.18005 180)
			(size 0.450088 0.450088)
			(layers "F.Cu" "F.Mask" "F.Paste")
			(net "M_L_CPU1_SB_DQ<4>")
		)
		(pad "CF10" smd circle
			(at -26.470102 18.18005 180)
			(size 0.450088 0.450088)
			(layers "F.Cu" "F.Mask" "F.Paste")
			(net "GND")
		)
		(pad "CF11" smd circle
			(at -25.530048 18.18005 180)
			(size 0.450088 0.450088)
			(layers "F.Cu" "F.Mask" "F.Paste")
			(net "M_L_CPU1_SB_DQS_DP<5>")
		)
		(pad "CF12" smd circle
			(at -24.589994 18.18005 180)
			(size 0.450088 0.450088)
			(layers "F.Cu" "F.Mask" "F.Paste")
			(net "GND")
		)
		(pad "CF13" smd circle
			(at -23.64994 18.18005 180)
			(size 0.450088 0.450088)
			(layers "F.Cu" "F.Mask" "F.Paste")
			(net "M_H_CPU1_SB_DQ<4>")
		)
		(pad "CF14" smd circle
			(at -22.709886 18.18005 180)
			(size 0.450088 0.450088)
			(layers "F.Cu" "F.Mask" "F.Paste")
			(net "M_H_CPU1_SB_DQS_DP<5>")
		)
		(pad "CF15" smd circle
			(at -21.770086 18.18005 180)
			(size 0.450088 0.450088)
			(layers "F.Cu" "F.Mask" "F.Paste")
			(net "GND")
		)
		(pad "CF16" smd circle
			(at -20.830032 18.18005 180)
			(size 0.450088 0.450088)
			(layers "F.Cu" "F.Mask" "F.Paste")
			(net "M_J_CPU1_SB_DQ<4>")
		)
		(pad "CF17" smd circle
			(at -19.889978 18.18005 180)
			(size 0.450088 0.450088)
			(layers "F.Cu" "F.Mask" "F.Paste")
			(net "GND")
		)
		(pad "CF18" smd circle
			(at -18.949924 18.18005 180)
			(size 0.450088 0.450088)
			(layers "F.Cu" "F.Mask" "F.Paste")
			(net "M_J_CPU1_SB_DQS_DP<5>")
		)
		(pad "CF19" smd circle
			(at -18.010124 18.18005 180)
			(size 0.450088 0.450088)
			(layers "F.Cu" "F.Mask" "F.Paste")
			(net "GND")
		)
		(pad "CF20" smd circle
			(at -17.07007 18.18005 180)
			(size 0.450088 0.450088)
			(layers "F.Cu" "F.Mask" "F.Paste")
			(net "M_I_CPU1_SB_DQ<4>")
		)
		(pad "CF21" smd circle
			(at -16.130016 18.18005 180)
			(size 0.450088 0.450088)
			(layers "F.Cu" "F.Mask" "F.Paste")
			(net "M_I_CPU1_SB_DQS_DP<5>")
		)
		(pad "CF22" smd circle
			(at -15.189962 18.18005 180)
			(size 0.450088 0.450088)
			(layers "F.Cu" "F.Mask" "F.Paste")
			(net "PVDD11_S3_P1")
		)
		(pad "CF23" smd circle
			(at -14.249908 18.18005 180)
			(size 0.450088 0.450088)
			(layers "F.Cu" "F.Mask" "F.Paste")
			(net "GND")
		)
		(pad "CF24" smd circle
			(at -13.310108 18.18005 180)
			(size 0.450088 0.450088)
			(layers "F.Cu" "F.Mask" "F.Paste")
			(net "GND")
		)
		(pad "CF25" smd circle
			(at -12.370054 18.18005 180)
			(size 0.450088 0.450088)
			(layers "F.Cu" "F.Mask" "F.Paste")
			(net "GND")
		)
		(pad "CF26" smd circle
			(at -11.43 18.18005 180)
			(size 0.450088 0.450088)
			(layers "F.Cu" "F.Mask" "F.Paste")
			(net "GND")
		)
		(pad "CF27" smd circle
			(at -10.489946 18.18005 180)
			(size 0.450088 0.450088)
			(layers "F.Cu" "F.Mask" "F.Paste")
			(net "GND")
		)
		(pad "CF28" smd circle
			(at -9.549892 18.18005 180)
			(size 0.450088 0.450088)
			(layers "F.Cu" "F.Mask" "F.Paste")
			(net "GND")
		)
		(pad "CF29" smd circle
			(at -8.610092 18.18005 180)
			(size 0.450088 0.450088)
			(layers "F.Cu" "F.Mask" "F.Paste")
			(net "GND")
		)
		(pad "CF30" smd circle
			(at -7.670038 18.18005 180)
			(size 0.450088 0.450088)
			(layers "F.Cu" "F.Mask" "F.Paste")
			(net "GND")
		)
		(pad "CF31" smd circle
			(at -6.729984 18.18005 180)
			(size 0.450088 0.450088)
			(layers "F.Cu" "F.Mask" "F.Paste")
			(net "GND")
		)
		(pad "CF32" smd circle
			(at -5.78993 18.18005 180)
			(size 0.450088 0.450088)
			(layers "F.Cu" "F.Mask" "F.Paste")
			(net "GND")
		)
		(pad "CF33" smd circle
			(at -4.849876 18.18005 180)
			(size 0.450088 0.450088)
			(layers "F.Cu" "F.Mask" "F.Paste")
			(net "GND")
		)
		(pad "CF34" smd circle
			(at -3.910076 18.18005 180)
			(size 0.450088 0.450088)
			(layers "F.Cu" "F.Mask" "F.Paste")
			(net "GND")
		)
		(pad "CF35" smd circle
			(at -2.970022 18.18005 180)
			(size 0.450088 0.450088)
			(layers "F.Cu" "F.Mask" "F.Paste")
			(net "P5E_CPU1_P3_TX_DN<1>")
		)
		(pad "CF36" smd circle
			(at -2.029968 18.18005 180)
			(size 0.450088 0.450088)
			(layers "F.Cu" "F.Mask" "F.Paste")
			(net "P5E_CPU1_P3_TX_DP<1>")
		)
		(pad "CF37" smd circle
			(at -1.089914 18.18005 180)
			(size 0.450088 0.450088)
			(layers "F.Cu" "F.Mask" "F.Paste")
			(net "GND")
		)
		(pad "CF39" smd circle
			(at 0.78994 18.18005 180)
			(size 0.450088 0.450088)
			(layers "F.Cu" "F.Mask" "F.Paste")
			(net "GND")
		)
		(pad "CF40" smd circle
			(at 1.729994 18.18005 180)
			(size 0.450088 0.450088)
			(layers "F.Cu" "F.Mask" "F.Paste")
			(net "P5E_CPU1_P1_RX_DP<14>")
		)
		(pad "CF41" smd circle
			(at 2.670048 18.18005 180)
			(size 0.450088 0.450088)
			(layers "F.Cu" "F.Mask" "F.Paste")
			(net "P5E_CPU1_P1_RX_DN<14>")
		)
		(pad "CF42" smd circle
			(at 3.610102 18.18005 180)
			(size 0.450088 0.450088)
			(layers "F.Cu" "F.Mask" "F.Paste")
			(net "GND")
		)
		(pad "CF43" smd circle
			(at 4.549902 18.18005 180)
			(size 0.450088 0.450088)
			(layers "F.Cu" "F.Mask" "F.Paste")
			(net "GND")
		)
		(pad "CF44" smd circle
			(at 5.489956 18.18005 180)
			(size 0.450088 0.450088)
			(layers "F.Cu" "F.Mask" "F.Paste")
			(net "GND")
		)
		(pad "CF45" smd circle
			(at 6.43001 18.18005 180)
			(size 0.450088 0.450088)
			(layers "F.Cu" "F.Mask" "F.Paste")
			(net "GND")
		)
		(pad "CF46" smd circle
			(at 7.370064 18.18005 180)
			(size 0.450088 0.450088)
			(layers "F.Cu" "F.Mask" "F.Paste")
			(net "GND")
		)
		(pad "CF47" smd circle
			(at 8.310118 18.18005 180)
			(size 0.450088 0.450088)
			(layers "F.Cu" "F.Mask" "F.Paste")
			(net "GND")
		)
		(pad "CF48" smd circle
			(at 9.249918 18.18005 180)
			(size 0.450088 0.450088)
			(layers "F.Cu" "F.Mask" "F.Paste")
			(net "GND")
		)
		(pad "CF49" smd circle
			(at 10.189972 18.18005 180)
			(size 0.450088 0.450088)
			(layers "F.Cu" "F.Mask" "F.Paste")
			(net "GND")
		)
		(pad "CF50" smd circle
			(at 11.130026 18.18005 180)
			(size 0.450088 0.450088)
			(layers "F.Cu" "F.Mask" "F.Paste")
			(net "GND")
		)
		(pad "CF51" smd circle
			(at 12.07008 18.18005 180)
			(size 0.450088 0.450088)
			(layers "F.Cu" "F.Mask" "F.Paste")
			(net "GND")
		)
		(pad "CF52" smd circle
			(at 13.00988 18.18005 180)
			(size 0.450088 0.450088)
			(layers "F.Cu" "F.Mask" "F.Paste")
			(net "GND")
		)
		(pad "CF53" smd circle
			(at 13.949934 18.18005 180)
			(size 0.450088 0.450088)
			(layers "F.Cu" "F.Mask" "F.Paste")
			(net "GND")
		)
		(pad "CF54" smd circle
			(at 14.889988 18.18005 180)
			(size 0.450088 0.450088)
			(layers "F.Cu" "F.Mask" "F.Paste")
			(net "PVDDIO_P1")
		)
		(pad "CF55" smd circle
			(at 15.830042 18.18005 180)
			(size 0.450088 0.450088)
			(layers "F.Cu" "F.Mask" "F.Paste")
			(net "M_C_CPU1_SB_DQS_DP<5>")
		)
		(pad "CF56" smd circle
			(at 16.770096 18.18005 180)
			(size 0.450088 0.450088)
			(layers "F.Cu" "F.Mask" "F.Paste")
			(net "M_C_CPU1_SB_DQ<4>")
		)
		(pad "CF57" smd circle
			(at 17.709896 18.18005 180)
			(size 0.450088 0.450088)
			(layers "F.Cu" "F.Mask" "F.Paste")
			(net "GND")
		)
		(pad "CF58" smd circle
			(at 18.64995 18.18005 180)
			(size 0.450088 0.450088)
			(layers "F.Cu" "F.Mask" "F.Paste")
			(net "M_D_CPU1_SB_DQS_DP<5>")
		)
		(pad "CF59" smd circle
			(at 19.590004 18.18005 180)
			(size 0.450088 0.450088)
			(layers "F.Cu" "F.Mask" "F.Paste")
			(net "GND")
		)
		(pad "CF60" smd circle
			(at 20.530058 18.18005 180)
			(size 0.450088 0.450088)
			(layers "F.Cu" "F.Mask" "F.Paste")
			(net "M_D_CPU1_SB_DQ<4>")
		)
		(pad "CF61" smd circle
			(at 21.470112 18.18005 180)
			(size 0.450088 0.450088)
			(layers "F.Cu" "F.Mask" "F.Paste")
			(net "GND")
		)
		(pad "CF62" smd circle
			(at 22.409912 18.18005 180)
			(size 0.450088 0.450088)
			(layers "F.Cu" "F.Mask" "F.Paste")
			(net "M_B_CPU1_SB_DQS_DP<5>")
		)
		(pad "CF63" smd circle
			(at 23.349966 18.18005 180)
			(size 0.450088 0.450088)
			(layers "F.Cu" "F.Mask" "F.Paste")
			(net "M_B_CPU1_SB_DQ<4>")
		)
		(pad "CF64" smd circle
			(at 24.29002 18.18005 180)
			(size 0.450088 0.450088)
			(layers "F.Cu" "F.Mask" "F.Paste")
			(net "GND")
		)
		(pad "CF65" smd circle
			(at 25.230074 18.18005 180)
			(size 0.450088 0.450088)
			(layers "F.Cu" "F.Mask" "F.Paste")
			(net "M_F_CPU1_SB_DQS_DP<5>")
		)
		(pad "CF66" smd circle
			(at 26.170128 18.18005 180)
			(size 0.450088 0.450088)
			(layers "F.Cu" "F.Mask" "F.Paste")
			(net "GND")
		)
		(pad "CF67" smd circle
			(at 27.109928 18.18005 180)
			(size 0.450088 0.450088)
			(layers "F.Cu" "F.Mask" "F.Paste")
			(net "M_F_CPU1_SB_DQ<4>")
		)
		(pad "CF68" smd circle
			(at 28.049982 18.18005 180)
			(size 0.450088 0.450088)
			(layers "F.Cu" "F.Mask" "F.Paste")
			(net "GND")
		)
		(pad "CF69" smd circle
			(at 28.990036 18.18005 180)
			(size 0.450088 0.450088)
			(layers "F.Cu" "F.Mask" "F.Paste")
			(net "M_E_CPU1_SB_DQS_DP<5>")
		)
		(pad "CF70" smd circle
			(at 29.93009 18.18005 180)
			(size 0.450088 0.450088)
			(layers "F.Cu" "F.Mask" "F.Paste")
			(net "M_E_CPU1_SB_DQ<4>")
		)
		(pad "CF71" smd circle
			(at 30.86989 18.18005 180)
			(size 0.450088 0.450088)
			(layers "F.Cu" "F.Mask" "F.Paste")
			(net "GND")
		)
		(pad "CF72" smd circle
			(at 31.809944 18.18005 180)
			(size 0.450088 0.450088)
			(layers "F.Cu" "F.Mask" "F.Paste")
			(net "M_A_CPU1_SB_DQS_DP<5>")
		)
		(pad "CF73" smd circle
			(at 32.749998 18.18005 180)
			(size 0.450088 0.450088)
			(layers "F.Cu" "F.Mask" "F.Paste")
			(net "GND")
		)
		(pad "CF74" smd circle
			(at 33.690052 18.18005 180)
			(size 0.450088 0.450088)
			(layers "F.Cu" "F.Mask" "F.Paste")
			(net "M_A_CPU1_SB_DQ<4>")
		)
		(pad "CG1" smd circle
			(at -34.459926 18.990056 180)
			(size 0.450088 0.450088)
			(layers "F.Cu" "F.Mask" "F.Paste")
			(net "GND")
		)
		(pad "CG2" smd circle
			(at -33.519872 18.990056 180)
			(size 0.450088 0.450088)
			(layers "F.Cu" "F.Mask" "F.Paste")
			(net "M_G_CPU1_SB_DQ<6>")
		)
		(pad "CG3" smd circle
			(at -32.580072 18.990056 180)
			(size 0.450088 0.450088)
			(layers "F.Cu" "F.Mask" "F.Paste")
			(net "M_G_CPU1_SB_DQ<5>")
		)
		(pad "CG4" smd circle
			(at -31.640018 18.990056 180)
			(size 0.450088 0.450088)
			(layers "F.Cu" "F.Mask" "F.Paste")
			(net "PVDD11_S3_P1")
		)
		(pad "CG5" smd circle
			(at -30.699964 18.990056 180)
			(size 0.450088 0.450088)
			(layers "F.Cu" "F.Mask" "F.Paste")
			(net "M_K_CPU1_SB_DQ<6>")
		)
		(pad "CG6" smd circle
			(at -29.75991 18.990056 180)
			(size 0.450088 0.450088)
			(layers "F.Cu" "F.Mask" "F.Paste")
			(net "GND")
		)
		(pad "CG7" smd circle
			(at -28.82011 18.990056 180)
			(size 0.450088 0.450088)
			(layers "F.Cu" "F.Mask" "F.Paste")
			(net "M_K_CPU1_SB_DQ<5>")
		)
		(pad "CG8" smd circle
			(at -27.880056 18.990056 180)
			(size 0.450088 0.450088)
			(layers "F.Cu" "F.Mask" "F.Paste")
			(net "GND")
		)
		(pad "CG9" smd circle
			(at -26.940002 18.990056 180)
			(size 0.450088 0.450088)
			(layers "F.Cu" "F.Mask" "F.Paste")
			(net "M_L_CPU1_SB_DQ<6>")
		)
		(pad "CG10" smd circle
			(at -25.999948 18.990056 180)
			(size 0.450088 0.450088)
			(layers "F.Cu" "F.Mask" "F.Paste")
			(net "M_L_CPU1_SB_DQ<5>")
		)
		(pad "CG11" smd circle
			(at -25.059894 18.990056 180)
			(size 0.450088 0.450088)
			(layers "F.Cu" "F.Mask" "F.Paste")
			(net "PVDD11_S3_P1")
		)
		(pad "CG12" smd circle
			(at -24.120094 18.990056 180)
			(size 0.450088 0.450088)
			(layers "F.Cu" "F.Mask" "F.Paste")
			(net "M_H_CPU1_SB_DQ<6>")
		)
		(pad "CG13" smd circle
			(at -23.18004 18.990056 180)
			(size 0.450088 0.450088)
			(layers "F.Cu" "F.Mask" "F.Paste")
			(net "GND")
		)
		(pad "CG14" smd circle
			(at -22.239986 18.990056 180)
			(size 0.450088 0.450088)
			(layers "F.Cu" "F.Mask" "F.Paste")
			(net "M_H_CPU1_SB_DQ<5>")
		)
		(pad "CG15" smd circle
			(at -21.299932 18.990056 180)
			(size 0.450088 0.450088)
			(layers "F.Cu" "F.Mask" "F.Paste")
			(net "GND")
		)
		(pad "CG16" smd circle
			(at -20.359878 18.990056 180)
			(size 0.450088 0.450088)
			(layers "F.Cu" "F.Mask" "F.Paste")
			(net "M_J_CPU1_SB_DQ<6>")
		)
		(pad "CG17" smd circle
			(at -19.420078 18.990056 180)
			(size 0.450088 0.450088)
			(layers "F.Cu" "F.Mask" "F.Paste")
			(net "M_J_CPU1_SB_DQ<5>")
		)
		(pad "CG18" smd circle
			(at -18.480024 18.990056 180)
			(size 0.450088 0.450088)
			(layers "F.Cu" "F.Mask" "F.Paste")
			(net "PVDD11_S3_P1")
		)
		(pad "CG19" smd circle
			(at -17.53997 18.990056 180)
			(size 0.450088 0.450088)
			(layers "F.Cu" "F.Mask" "F.Paste")
			(net "M_I_CPU1_SB_DQ<6>")
		)
		(pad "CG20" smd circle
			(at -16.599916 18.990056 180)
			(size 0.450088 0.450088)
			(layers "F.Cu" "F.Mask" "F.Paste")
			(net "GND")
		)
		(pad "CG21" smd circle
			(at -15.660116 18.990056 180)
			(size 0.450088 0.450088)
			(layers "F.Cu" "F.Mask" "F.Paste")
			(net "M_I_CPU1_SB_DQ<5>")
		)
		(pad "CG22" smd circle
			(at -14.720062 18.990056 180)
			(size 0.450088 0.450088)
			(layers "F.Cu" "F.Mask" "F.Paste")
			(net "GND")
		)
		(pad "CG23" smd circle
			(at -13.780008 18.990056 180)
			(size 0.450088 0.450088)
			(layers "F.Cu" "F.Mask" "F.Paste")
			(net "P5E_CPU1_P3_TX_DN<14>")
		)
		(pad "CG24" smd circle
			(at -12.839954 18.990056 180)
			(size 0.450088 0.450088)
			(layers "F.Cu" "F.Mask" "F.Paste")
			(net "P5E_CPU1_P3_TX_DP<14>")
		)
		(pad "CG25" smd circle
			(at -11.8999 18.990056 180)
			(size 0.450088 0.450088)
			(layers "F.Cu" "F.Mask" "F.Paste")
			(net "GND")
		)
		(pad "CG26" smd circle
			(at -10.9601 18.990056 180)
			(size 0.450088 0.450088)
			(layers "F.Cu" "F.Mask" "F.Paste")
			(net "P5E_CPU1_P3_TX_DN<11>")
		)
		(pad "CG27" smd circle
			(at -10.020046 18.990056 180)
			(size 0.450088 0.450088)
			(layers "F.Cu" "F.Mask" "F.Paste")
			(net "P5E_CPU1_P3_TX_DP<11>")
		)
		(pad "CG28" smd circle
			(at -9.079992 18.990056 180)
			(size 0.450088 0.450088)
			(layers "F.Cu" "F.Mask" "F.Paste")
			(net "GND")
		)
		(pad "CG29" smd circle
			(at -8.139938 18.990056 180)
			(size 0.450088 0.450088)
			(layers "F.Cu" "F.Mask" "F.Paste")
			(net "P5E_CPU1_P3_TX_DN<8>")
		)
		(pad "CG30" smd circle
			(at -7.199884 18.990056 180)
			(size 0.450088 0.450088)
			(layers "F.Cu" "F.Mask" "F.Paste")
			(net "P5E_CPU1_P3_TX_DP<8>")
		)
		(pad "CG31" smd circle
			(at -6.260084 18.990056 180)
			(size 0.450088 0.450088)
			(layers "F.Cu" "F.Mask" "F.Paste")
			(net "GND")
		)
		(pad "CG32" smd circle
			(at -5.32003 18.990056 180)
			(size 0.450088 0.450088)
			(layers "F.Cu" "F.Mask" "F.Paste")
			(net "P5E_CPU1_P3_TX_DN<5>")
		)
		(pad "CG33" smd circle
			(at -4.379976 18.990056 180)
			(size 0.450088 0.450088)
			(layers "F.Cu" "F.Mask" "F.Paste")
			(net "P5E_CPU1_P3_TX_DP<5>")
		)
		(pad "CG34" smd circle
			(at -3.439922 18.990056 180)
			(size 0.450088 0.450088)
			(layers "F.Cu" "F.Mask" "F.Paste")
			(net "GND")
		)
		(pad "CG35" smd circle
			(at -2.500122 18.990056 180)
			(size 0.450088 0.450088)
			(layers "F.Cu" "F.Mask" "F.Paste")
			(net "PVDDCR_CPU1_P1")
		)
		(pad "CG36" smd circle
			(at -1.560068 18.990056 180)
			(size 0.450088 0.450088)
			(layers "F.Cu" "F.Mask" "F.Paste")
			(net "PVDDCR_CPU1_P1")
		)
		(pad "CG40" smd circle
			(at 1.260094 18.990056 180)
			(size 0.450088 0.450088)
			(layers "F.Cu" "F.Mask" "F.Paste")
			(net "PVDDCR_CPU1_P1")
		)
		(pad "CG41" smd circle
			(at 2.199894 18.990056 180)
			(size 0.450088 0.450088)
			(layers "F.Cu" "F.Mask" "F.Paste")
			(net "PVDDCR_CPU1_P1")
		)
		(pad "CG42" smd circle
			(at 3.139948 18.990056 180)
			(size 0.450088 0.450088)
			(layers "F.Cu" "F.Mask" "F.Paste")
			(net "GND")
		)
		(pad "CG43" smd circle
			(at 4.080002 18.990056 180)
			(size 0.450088 0.450088)
			(layers "F.Cu" "F.Mask" "F.Paste")
			(net "P5E_CPU1_P1_RX_DP<10>")
		)
		(pad "CG44" smd circle
			(at 5.020056 18.990056 180)
			(size 0.450088 0.450088)
			(layers "F.Cu" "F.Mask" "F.Paste")
			(net "P5E_CPU1_P1_RX_DN<10>")
		)
		(pad "CG45" smd circle
			(at 5.96011 18.990056 180)
			(size 0.450088 0.450088)
			(layers "F.Cu" "F.Mask" "F.Paste")
			(net "GND")
		)
		(pad "CG46" smd circle
			(at 6.89991 18.990056 180)
			(size 0.450088 0.450088)
			(layers "F.Cu" "F.Mask" "F.Paste")
			(net "P5E_CPU1_P1_RX_DP<7>")
		)
		(pad "CG47" smd circle
			(at 7.839964 18.990056 180)
			(size 0.450088 0.450088)
			(layers "F.Cu" "F.Mask" "F.Paste")
			(net "P5E_CPU1_P1_RX_DN<7>")
		)
		(pad "CG48" smd circle
			(at 8.780018 18.990056 180)
			(size 0.450088 0.450088)
			(layers "F.Cu" "F.Mask" "F.Paste")
			(net "GND")
		)
		(pad "CG49" smd circle
			(at 9.720072 18.990056 180)
			(size 0.450088 0.450088)
			(layers "F.Cu" "F.Mask" "F.Paste")
			(net "P5E_CPU1_P1_RX_DP<4>")
		)
		(pad "CG50" smd circle
			(at 10.659872 18.990056 180)
			(size 0.450088 0.450088)
			(layers "F.Cu" "F.Mask" "F.Paste")
			(net "P5E_CPU1_P1_RX_DN<4>")
		)
		(pad "CG51" smd circle
			(at 11.599926 18.990056 180)
			(size 0.450088 0.450088)
			(layers "F.Cu" "F.Mask" "F.Paste")
			(net "GND")
		)
		(pad "CG52" smd circle
			(at 12.53998 18.990056 180)
			(size 0.450088 0.450088)
			(layers "F.Cu" "F.Mask" "F.Paste")
			(net "P5E_CPU1_P1_RX_DP<1>")
		)
		(pad "CG53" smd circle
			(at 13.480034 18.990056 180)
			(size 0.450088 0.450088)
			(layers "F.Cu" "F.Mask" "F.Paste")
			(net "P5E_CPU1_P1_RX_DN<1>")
		)
		(pad "CG54" smd circle
			(at 14.420088 18.990056 180)
			(size 0.450088 0.450088)
			(layers "F.Cu" "F.Mask" "F.Paste")
			(net "GND")
		)
		(pad "CG55" smd circle
			(at 15.359888 18.990056 180)
			(size 0.450088 0.450088)
			(layers "F.Cu" "F.Mask" "F.Paste")
			(net "M_C_CPU1_SB_DQ<5>")
		)
		(pad "CG56" smd circle
			(at 16.299942 18.990056 180)
			(size 0.450088 0.450088)
			(layers "F.Cu" "F.Mask" "F.Paste")
			(net "GND")
		)
		(pad "CG57" smd circle
			(at 17.239996 18.990056 180)
			(size 0.450088 0.450088)
			(layers "F.Cu" "F.Mask" "F.Paste")
			(net "M_C_CPU1_SB_DQ<6>")
		)
		(pad "CG58" smd circle
			(at 18.18005 18.990056 180)
			(size 0.450088 0.450088)
			(layers "F.Cu" "F.Mask" "F.Paste")
			(net "PVDDIO_P1")
		)
		(pad "CG59" smd circle
			(at 19.120104 18.990056 180)
			(size 0.450088 0.450088)
			(layers "F.Cu" "F.Mask" "F.Paste")
			(net "M_D_CPU1_SB_DQ<5>")
		)
		(pad "CG60" smd circle
			(at 20.059904 18.990056 180)
			(size 0.450088 0.450088)
			(layers "F.Cu" "F.Mask" "F.Paste")
			(net "M_D_CPU1_SB_DQ<6>")
		)
		(pad "CG61" smd circle
			(at 20.999958 18.990056 180)
			(size 0.450088 0.450088)
			(layers "F.Cu" "F.Mask" "F.Paste")
			(net "GND")
		)
		(pad "CG62" smd circle
			(at 21.940012 18.990056 180)
			(size 0.450088 0.450088)
			(layers "F.Cu" "F.Mask" "F.Paste")
			(net "M_B_CPU1_SB_DQ<5>")
		)
		(pad "CG63" smd circle
			(at 22.880066 18.990056 180)
			(size 0.450088 0.450088)
			(layers "F.Cu" "F.Mask" "F.Paste")
			(net "GND")
		)
		(pad "CG64" smd circle
			(at 23.82012 18.990056 180)
			(size 0.450088 0.450088)
			(layers "F.Cu" "F.Mask" "F.Paste")
			(net "M_B_CPU1_SB_DQ<6>")
		)
		(pad "CG65" smd circle
			(at 24.75992 18.990056 180)
			(size 0.450088 0.450088)
			(layers "F.Cu" "F.Mask" "F.Paste")
			(net "PVDDIO_P1")
		)
		(pad "CG66" smd circle
			(at 25.699974 18.990056 180)
			(size 0.450088 0.450088)
			(layers "F.Cu" "F.Mask" "F.Paste")
			(net "M_F_CPU1_SB_DQ<5>")
		)
		(pad "CG67" smd circle
			(at 26.640028 18.990056 180)
			(size 0.450088 0.450088)
			(layers "F.Cu" "F.Mask" "F.Paste")
			(net "M_F_CPU1_SB_DQ<6>")
		)
		(pad "CG68" smd circle
			(at 27.580082 18.990056 180)
			(size 0.450088 0.450088)
			(layers "F.Cu" "F.Mask" "F.Paste")
			(net "GND")
		)
		(pad "CG69" smd circle
			(at 28.519882 18.990056 180)
			(size 0.450088 0.450088)
			(layers "F.Cu" "F.Mask" "F.Paste")
			(net "M_E_CPU1_SB_DQ<5>")
		)
		(pad "CG70" smd circle
			(at 29.459936 18.990056 180)
			(size 0.450088 0.450088)
			(layers "F.Cu" "F.Mask" "F.Paste")
			(net "GND")
		)
		(pad "CG71" smd circle
			(at 30.39999 18.990056 180)
			(size 0.450088 0.450088)
			(layers "F.Cu" "F.Mask" "F.Paste")
			(net "M_E_CPU1_SB_DQ<6>")
		)
		(pad "CG72" smd circle
			(at 31.340044 18.990056 180)
			(size 0.450088 0.450088)
			(layers "F.Cu" "F.Mask" "F.Paste")
			(net "PVDDIO_P1")
		)
		(pad "CG73" smd circle
			(at 32.280098 18.990056 180)
			(size 0.450088 0.450088)
			(layers "F.Cu" "F.Mask" "F.Paste")
			(net "M_A_CPU1_SB_DQ<5>")
		)
		(pad "CG74" smd circle
			(at 33.219898 18.990056 180)
			(size 0.450088 0.450088)
			(layers "F.Cu" "F.Mask" "F.Paste")
			(net "M_A_CPU1_SB_DQ<6>")
		)
		(pad "CG75" smd circle
			(at 34.159952 18.990056 180)
			(size 0.450088 0.450088)
			(layers "F.Cu" "F.Mask" "F.Paste")
			(net "GND")
		)
		(pad "CH2" smd circle
			(at -33.990026 19.800062 180)
			(size 0.450088 0.450088)
			(layers "F.Cu" "F.Mask" "F.Paste")
			(net "M_G_CPU1_SB_DQ<8>")
		)
		(pad "CH3" smd circle
			(at -33.049972 19.800062 180)
			(size 0.450088 0.450088)
			(layers "F.Cu" "F.Mask" "F.Paste")
			(net "GND")
		)
		(pad "CH4" smd circle
			(at -32.109918 19.800062 180)
			(size 0.450088 0.450088)
			(layers "F.Cu" "F.Mask" "F.Paste")
			(net "M_G_CPU1_SB_DQ<7>")
		)
		(pad "CH5" smd circle
			(at -31.170118 19.800062 180)
			(size 0.450088 0.450088)
			(layers "F.Cu" "F.Mask" "F.Paste")
			(net "GND")
		)
		(pad "CH6" smd circle
			(at -30.230064 19.800062 180)
			(size 0.450088 0.450088)
			(layers "F.Cu" "F.Mask" "F.Paste")
			(net "M_K_CPU1_SB_DQ<8>")
		)
		(pad "CH7" smd circle
			(at -29.29001 19.800062 180)
			(size 0.450088 0.450088)
			(layers "F.Cu" "F.Mask" "F.Paste")
			(net "M_K_CPU1_SB_DQ<7>")
		)
		(pad "CH8" smd circle
			(at -28.349956 19.800062 180)
			(size 0.450088 0.450088)
			(layers "F.Cu" "F.Mask" "F.Paste")
			(net "GND")
		)
		(pad "CH9" smd circle
			(at -27.409902 19.800062 180)
			(size 0.450088 0.450088)
			(layers "F.Cu" "F.Mask" "F.Paste")
			(net "M_L_CPU1_SB_DQ<8>")
		)
		(pad "CH10" smd circle
			(at -26.470102 19.800062 180)
			(size 0.450088 0.450088)
			(layers "F.Cu" "F.Mask" "F.Paste")
			(net "GND")
		)
		(pad "CH11" smd circle
			(at -25.530048 19.800062 180)
			(size 0.450088 0.450088)
			(layers "F.Cu" "F.Mask" "F.Paste")
			(net "M_L_CPU1_SB_DQ<7>")
		)
		(pad "CH12" smd circle
			(at -24.589994 19.800062 180)
			(size 0.450088 0.450088)
			(layers "F.Cu" "F.Mask" "F.Paste")
			(net "GND")
		)
		(pad "CH13" smd circle
			(at -23.64994 19.800062 180)
			(size 0.450088 0.450088)
			(layers "F.Cu" "F.Mask" "F.Paste")
			(net "M_H_CPU1_SB_DQ<8>")
		)
		(pad "CH14" smd circle
			(at -22.709886 19.800062 180)
			(size 0.450088 0.450088)
			(layers "F.Cu" "F.Mask" "F.Paste")
			(net "M_H_CPU1_SB_DQ<7>")
		)
		(pad "CH15" smd circle
			(at -21.770086 19.800062 180)
			(size 0.450088 0.450088)
			(layers "F.Cu" "F.Mask" "F.Paste")
			(net "GND")
		)
		(pad "CH16" smd circle
			(at -20.830032 19.800062 180)
			(size 0.450088 0.450088)
			(layers "F.Cu" "F.Mask" "F.Paste")
			(net "M_J_CPU1_SB_DQ<8>")
		)
		(pad "CH17" smd circle
			(at -19.889978 19.800062 180)
			(size 0.450088 0.450088)
			(layers "F.Cu" "F.Mask" "F.Paste")
			(net "GND")
		)
		(pad "CH18" smd circle
			(at -18.949924 19.800062 180)
			(size 0.450088 0.450088)
			(layers "F.Cu" "F.Mask" "F.Paste")
			(net "M_J_CPU1_SB_DQ<7>")
		)
		(pad "CH19" smd circle
			(at -18.010124 19.800062 180)
			(size 0.450088 0.450088)
			(layers "F.Cu" "F.Mask" "F.Paste")
			(net "GND")
		)
		(pad "CH20" smd circle
			(at -17.07007 19.800062 180)
			(size 0.450088 0.450088)
			(layers "F.Cu" "F.Mask" "F.Paste")
			(net "M_I_CPU1_SB_DQ<8>")
		)
		(pad "CH21" smd circle
			(at -16.130016 19.800062 180)
			(size 0.450088 0.450088)
			(layers "F.Cu" "F.Mask" "F.Paste")
			(net "M_I_CPU1_SB_DQ<7>")
		)
		(pad "CH22" smd circle
			(at -15.189962 19.800062 180)
			(size 0.450088 0.450088)
			(layers "F.Cu" "F.Mask" "F.Paste")
			(net "GND")
		)
		(pad "CH23" smd circle
			(at -14.249908 19.800062 180)
			(size 0.450088 0.450088)
			(layers "F.Cu" "F.Mask" "F.Paste")
			(net "PVDDCR_CPU1_P1")
		)
		(pad "CH24" smd circle
			(at -13.310108 19.800062 180)
			(size 0.450088 0.450088)
			(layers "F.Cu" "F.Mask" "F.Paste")
			(net "PVDDCR_CPU1_P1")
		)
		(pad "CH25" smd circle
			(at -12.370054 19.800062 180)
			(size 0.450088 0.450088)
			(layers "F.Cu" "F.Mask" "F.Paste")
			(net "GND")
		)
		(pad "CH26" smd circle
			(at -11.43 19.800062 180)
			(size 0.450088 0.450088)
			(layers "F.Cu" "F.Mask" "F.Paste")
			(net "PVDDCR_CPU1_P1")
		)
		(pad "CH27" smd circle
			(at -10.489946 19.800062 180)
			(size 0.450088 0.450088)
			(layers "F.Cu" "F.Mask" "F.Paste")
			(net "PVDDCR_CPU1_P1")
		)
		(pad "CH28" smd circle
			(at -9.549892 19.800062 180)
			(size 0.450088 0.450088)
			(layers "F.Cu" "F.Mask" "F.Paste")
			(net "GND")
		)
		(pad "CH29" smd circle
			(at -8.610092 19.800062 180)
			(size 0.450088 0.450088)
			(layers "F.Cu" "F.Mask" "F.Paste")
			(net "PVDDCR_CPU1_P1")
		)
		(pad "CH30" smd circle
			(at -7.670038 19.800062 180)
			(size 0.450088 0.450088)
			(layers "F.Cu" "F.Mask" "F.Paste")
			(net "PVDDCR_CPU1_P1")
		)
		(pad "CH31" smd circle
			(at -6.729984 19.800062 180)
			(size 0.450088 0.450088)
			(layers "F.Cu" "F.Mask" "F.Paste")
			(net "GND")
		)
		(pad "CH32" smd circle
			(at -5.78993 19.800062 180)
			(size 0.450088 0.450088)
			(layers "F.Cu" "F.Mask" "F.Paste")
			(net "PVDDCR_CPU1_P1")
		)
		(pad "CH33" smd circle
			(at -4.849876 19.800062 180)
			(size 0.450088 0.450088)
			(layers "F.Cu" "F.Mask" "F.Paste")
			(net "PVDDCR_CPU1_P1")
		)
		(pad "CH34" smd circle
			(at -3.910076 19.800062 180)
			(size 0.450088 0.450088)
			(layers "F.Cu" "F.Mask" "F.Paste")
			(net "GND")
		)
		(pad "CH35" smd circle
			(at -2.970022 19.800062 180)
			(size 0.450088 0.450088)
			(layers "F.Cu" "F.Mask" "F.Paste")
			(net "P5E_CPU1_P3_TX_DN<2>")
		)
		(pad "CH36" smd circle
			(at -2.029968 19.800062 180)
			(size 0.450088 0.450088)
			(layers "F.Cu" "F.Mask" "F.Paste")
			(net "P5E_CPU1_P3_TX_DP<2>")
		)
		(pad "CH37" smd circle
			(at -1.089914 19.800062 180)
			(size 0.450088 0.450088)
			(layers "F.Cu" "F.Mask" "F.Paste")
			(net "GND")
		)
		(pad "CH39" smd circle
			(at 0.78994 19.800062 180)
			(size 0.450088 0.450088)
			(layers "F.Cu" "F.Mask" "F.Paste")
			(net "GND")
		)
		(pad "CH40" smd circle
			(at 1.729994 19.800062 180)
			(size 0.450088 0.450088)
			(layers "F.Cu" "F.Mask" "F.Paste")
			(net "P5E_CPU1_P1_RX_DP<13>")
		)
		(pad "CH41" smd circle
			(at 2.670048 19.800062 180)
			(size 0.450088 0.450088)
			(layers "F.Cu" "F.Mask" "F.Paste")
			(net "P5E_CPU1_P1_RX_DN<13>")
		)
		(pad "CH42" smd circle
			(at 3.610102 19.800062 180)
			(size 0.450088 0.450088)
			(layers "F.Cu" "F.Mask" "F.Paste")
			(net "GND")
		)
		(pad "CH43" smd circle
			(at 4.549902 19.800062 180)
			(size 0.450088 0.450088)
			(layers "F.Cu" "F.Mask" "F.Paste")
			(net "PVDDCR_CPU1_P1")
		)
		(pad "CH44" smd circle
			(at 5.489956 19.800062 180)
			(size 0.450088 0.450088)
			(layers "F.Cu" "F.Mask" "F.Paste")
			(net "PVDDCR_CPU1_P1")
		)
		(pad "CH45" smd circle
			(at 6.43001 19.800062 180)
			(size 0.450088 0.450088)
			(layers "F.Cu" "F.Mask" "F.Paste")
			(net "GND")
		)
		(pad "CH46" smd circle
			(at 7.370064 19.800062 180)
			(size 0.450088 0.450088)
			(layers "F.Cu" "F.Mask" "F.Paste")
			(net "PVDDCR_CPU1_P1")
		)
		(pad "CH47" smd circle
			(at 8.310118 19.800062 180)
			(size 0.450088 0.450088)
			(layers "F.Cu" "F.Mask" "F.Paste")
			(net "PVDDCR_CPU1_P1")
		)
		(pad "CH48" smd circle
			(at 9.249918 19.800062 180)
			(size 0.450088 0.450088)
			(layers "F.Cu" "F.Mask" "F.Paste")
			(net "GND")
		)
		(pad "CH49" smd circle
			(at 10.189972 19.800062 180)
			(size 0.450088 0.450088)
			(layers "F.Cu" "F.Mask" "F.Paste")
			(net "PVDDCR_CPU1_P1")
		)
		(pad "CH50" smd circle
			(at 11.130026 19.800062 180)
			(size 0.450088 0.450088)
			(layers "F.Cu" "F.Mask" "F.Paste")
			(net "PVDDCR_CPU1_P1")
		)
		(pad "CH51" smd circle
			(at 12.07008 19.800062 180)
			(size 0.450088 0.450088)
			(layers "F.Cu" "F.Mask" "F.Paste")
			(net "GND")
		)
		(pad "CH52" smd circle
			(at 13.00988 19.800062 180)
			(size 0.450088 0.450088)
			(layers "F.Cu" "F.Mask" "F.Paste")
			(net "PVDDCR_CPU1_P1")
		)
		(pad "CH53" smd circle
			(at 13.949934 19.800062 180)
			(size 0.450088 0.450088)
			(layers "F.Cu" "F.Mask" "F.Paste")
			(net "PVDDCR_CPU1_P1")
		)
		(pad "CH54" smd circle
			(at 14.889988 19.800062 180)
			(size 0.450088 0.450088)
			(layers "F.Cu" "F.Mask" "F.Paste")
			(net "GND")
		)
		(pad "CH55" smd circle
			(at 15.830042 19.800062 180)
			(size 0.450088 0.450088)
			(layers "F.Cu" "F.Mask" "F.Paste")
			(net "M_C_CPU1_SB_DQ<7>")
		)
		(pad "CH56" smd circle
			(at 16.770096 19.800062 180)
			(size 0.450088 0.450088)
			(layers "F.Cu" "F.Mask" "F.Paste")
			(net "M_C_CPU1_SB_DQ<8>")
		)
		(pad "CH57" smd circle
			(at 17.709896 19.800062 180)
			(size 0.450088 0.450088)
			(layers "F.Cu" "F.Mask" "F.Paste")
			(net "GND")
		)
		(pad "CH58" smd circle
			(at 18.64995 19.800062 180)
			(size 0.450088 0.450088)
			(layers "F.Cu" "F.Mask" "F.Paste")
			(net "M_D_CPU1_SB_DQ<7>")
		)
		(pad "CH59" smd circle
			(at 19.590004 19.800062 180)
			(size 0.450088 0.450088)
			(layers "F.Cu" "F.Mask" "F.Paste")
			(net "GND")
		)
		(pad "CH60" smd circle
			(at 20.530058 19.800062 180)
			(size 0.450088 0.450088)
			(layers "F.Cu" "F.Mask" "F.Paste")
			(net "M_D_CPU1_SB_DQ<8>")
		)
		(pad "CH61" smd circle
			(at 21.470112 19.800062 180)
			(size 0.450088 0.450088)
			(layers "F.Cu" "F.Mask" "F.Paste")
			(net "GND")
		)
		(pad "CH62" smd circle
			(at 22.409912 19.800062 180)
			(size 0.450088 0.450088)
			(layers "F.Cu" "F.Mask" "F.Paste")
			(net "M_B_CPU1_SB_DQ<7>")
		)
		(pad "CH63" smd circle
			(at 23.349966 19.800062 180)
			(size 0.450088 0.450088)
			(layers "F.Cu" "F.Mask" "F.Paste")
			(net "M_B_CPU1_SB_DQ<8>")
		)
		(pad "CH64" smd circle
			(at 24.29002 19.800062 180)
			(size 0.450088 0.450088)
			(layers "F.Cu" "F.Mask" "F.Paste")
			(net "GND")
		)
		(pad "CH65" smd circle
			(at 25.230074 19.800062 180)
			(size 0.450088 0.450088)
			(layers "F.Cu" "F.Mask" "F.Paste")
			(net "M_F_CPU1_SB_DQ<7>")
		)
		(pad "CH66" smd circle
			(at 26.170128 19.800062 180)
			(size 0.450088 0.450088)
			(layers "F.Cu" "F.Mask" "F.Paste")
			(net "GND")
		)
		(pad "CH67" smd circle
			(at 27.109928 19.800062 180)
			(size 0.450088 0.450088)
			(layers "F.Cu" "F.Mask" "F.Paste")
			(net "M_F_CPU1_SB_DQ<8>")
		)
		(pad "CH68" smd circle
			(at 28.049982 19.800062 180)
			(size 0.450088 0.450088)
			(layers "F.Cu" "F.Mask" "F.Paste")
			(net "GND")
		)
		(pad "CH69" smd circle
			(at 28.990036 19.800062 180)
			(size 0.450088 0.450088)
			(layers "F.Cu" "F.Mask" "F.Paste")
			(net "M_E_CPU1_SB_DQ<7>")
		)
		(pad "CH70" smd circle
			(at 29.93009 19.800062 180)
			(size 0.450088 0.450088)
			(layers "F.Cu" "F.Mask" "F.Paste")
			(net "M_E_CPU1_SB_DQ<8>")
		)
		(pad "CH71" smd circle
			(at 30.86989 19.800062 180)
			(size 0.450088 0.450088)
			(layers "F.Cu" "F.Mask" "F.Paste")
			(net "GND")
		)
		(pad "CH72" smd circle
			(at 31.809944 19.800062 180)
			(size 0.450088 0.450088)
			(layers "F.Cu" "F.Mask" "F.Paste")
			(net "M_A_CPU1_SB_DQ<7>")
		)
		(pad "CH73" smd circle
			(at 32.749998 19.800062 180)
			(size 0.450088 0.450088)
			(layers "F.Cu" "F.Mask" "F.Paste")
			(net "GND")
		)
		(pad "CH74" smd circle
			(at 33.690052 19.800062 180)
			(size 0.450088 0.450088)
			(layers "F.Cu" "F.Mask" "F.Paste")
			(net "M_A_CPU1_SB_DQ<8>")
		)
		(pad "CJ1" smd circle
			(at -34.459926 20.610068 180)
			(size 0.450088 0.450088)
			(layers "F.Cu" "F.Mask" "F.Paste")
			(net "GND")
		)
		(pad "CJ2" smd circle
			(at -33.519872 20.610068 180)
			(size 0.450088 0.450088)
			(layers "F.Cu" "F.Mask" "F.Paste")
			(net "M_G_CPU1_SB_DQ<10>")
		)
		(pad "CJ3" smd circle
			(at -32.580072 20.610068 180)
			(size 0.450088 0.450088)
			(layers "F.Cu" "F.Mask" "F.Paste")
			(net "M_G_CPU1_SB_DQ<9>")
		)
		(pad "CJ4" smd circle
			(at -31.640018 20.610068 180)
			(size 0.450088 0.450088)
			(layers "F.Cu" "F.Mask" "F.Paste")
			(net "GND")
		)
		(pad "CJ5" smd circle
			(at -30.699964 20.610068 180)
			(size 0.450088 0.450088)
			(layers "F.Cu" "F.Mask" "F.Paste")
			(net "M_K_CPU1_SB_DQ<10>")
		)
		(pad "CJ6" smd circle
			(at -29.75991 20.610068 180)
			(size 0.450088 0.450088)
			(layers "F.Cu" "F.Mask" "F.Paste")
			(net "GND")
		)
		(pad "CJ7" smd circle
			(at -28.82011 20.610068 180)
			(size 0.450088 0.450088)
			(layers "F.Cu" "F.Mask" "F.Paste")
			(net "M_K_CPU1_SB_DQ<9>")
		)
		(pad "CJ8" smd circle
			(at -27.880056 20.610068 180)
			(size 0.450088 0.450088)
			(layers "F.Cu" "F.Mask" "F.Paste")
			(net "GND")
		)
		(pad "CJ9" smd circle
			(at -26.940002 20.610068 180)
			(size 0.450088 0.450088)
			(layers "F.Cu" "F.Mask" "F.Paste")
			(net "M_L_CPU1_SB_DQ<10>")
		)
		(pad "CJ10" smd circle
			(at -25.999948 20.610068 180)
			(size 0.450088 0.450088)
			(layers "F.Cu" "F.Mask" "F.Paste")
			(net "M_L_CPU1_SB_DQ<9>")
		)
		(pad "CJ11" smd circle
			(at -25.059894 20.610068 180)
			(size 0.450088 0.450088)
			(layers "F.Cu" "F.Mask" "F.Paste")
			(net "GND")
		)
		(pad "CJ12" smd circle
			(at -24.120094 20.610068 180)
			(size 0.450088 0.450088)
			(layers "F.Cu" "F.Mask" "F.Paste")
			(net "M_H_CPU1_SB_DQ<10>")
		)
		(pad "CJ13" smd circle
			(at -23.18004 20.610068 180)
			(size 0.450088 0.450088)
			(layers "F.Cu" "F.Mask" "F.Paste")
			(net "GND")
		)
		(pad "CJ14" smd circle
			(at -22.239986 20.610068 180)
			(size 0.450088 0.450088)
			(layers "F.Cu" "F.Mask" "F.Paste")
			(net "M_H_CPU1_SB_DQ<9>")
		)
		(pad "CJ15" smd circle
			(at -21.299932 20.610068 180)
			(size 0.450088 0.450088)
			(layers "F.Cu" "F.Mask" "F.Paste")
			(net "GND")
		)
		(pad "CJ16" smd circle
			(at -20.359878 20.610068 180)
			(size 0.450088 0.450088)
			(layers "F.Cu" "F.Mask" "F.Paste")
			(net "M_J_CPU1_SB_DQ<10>")
		)
		(pad "CJ17" smd circle
			(at -19.420078 20.610068 180)
			(size 0.450088 0.450088)
			(layers "F.Cu" "F.Mask" "F.Paste")
			(net "M_J_CPU1_SB_DQ<9>")
		)
		(pad "CJ18" smd circle
			(at -18.480024 20.610068 180)
			(size 0.450088 0.450088)
			(layers "F.Cu" "F.Mask" "F.Paste")
			(net "GND")
		)
		(pad "CJ19" smd circle
			(at -17.53997 20.610068 180)
			(size 0.450088 0.450088)
			(layers "F.Cu" "F.Mask" "F.Paste")
			(net "M_I_CPU1_SB_DQ<10>")
		)
		(pad "CJ20" smd circle
			(at -16.599916 20.610068 180)
			(size 0.450088 0.450088)
			(layers "F.Cu" "F.Mask" "F.Paste")
			(net "GND")
		)
		(pad "CJ21" smd circle
			(at -15.660116 20.610068 180)
			(size 0.450088 0.450088)
			(layers "F.Cu" "F.Mask" "F.Paste")
			(net "M_I_CPU1_SB_DQ<9>")
		)
		(pad "CJ22" smd circle
			(at -14.720062 20.610068 180)
			(size 0.450088 0.450088)
			(layers "F.Cu" "F.Mask" "F.Paste")
			(net "PVDD11_S3_P1")
		)
		(pad "CJ23" smd circle
			(at -13.780008 20.610068 180)
			(size 0.450088 0.450088)
			(layers "F.Cu" "F.Mask" "F.Paste")
			(net "GND")
		)
		(pad "CJ24" smd circle
			(at -12.839954 20.610068 180)
			(size 0.450088 0.450088)
			(layers "F.Cu" "F.Mask" "F.Paste")
			(net "TP_CPU1_TEST47_CCD1")
		)
		(pad "CJ25" smd circle
			(at -11.8999 20.610068 180)
			(size 0.450088 0.450088)
			(layers "F.Cu" "F.Mask" "F.Paste")
			(net "TP_CPU1_TEST5_CCD5")
		)
		(pad "CJ26" smd circle
			(at -10.9601 20.610068 180)
			(size 0.450088 0.450088)
			(layers "F.Cu" "F.Mask" "F.Paste")
			(net "TP_CPU1_TEST4_CCD5")
		)
		(pad "CJ27" smd circle
			(at -10.020046 20.610068 180)
			(size 0.450088 0.450088)
			(layers "F.Cu" "F.Mask" "F.Paste")
			(net "TP_CPU1_TEST5_CCD1")
		)
		(pad "CJ28" smd circle
			(at -9.079992 20.610068 180)
			(size 0.450088 0.450088)
			(layers "F.Cu" "F.Mask" "F.Paste")
			(net "TP_CPU1_TEST4_CCD1")
		)
		(pad "CJ29" smd circle
			(at -8.139938 20.610068 180)
			(size 0.450088 0.450088)
			(layers "F.Cu" "F.Mask" "F.Paste")
			(net "TP_CPU1_TEST6_X3D1")
		)
		(pad "CJ30" smd circle
			(at -7.199884 20.610068 180)
			(size 0.450088 0.450088)
			(layers "F.Cu" "F.Mask" "F.Paste")
			(net "TP_CPU1_TEST6_CCD1")
		)
		(pad "CJ31" smd circle
			(at -6.260084 20.610068 180)
			(size 0.450088 0.450088)
			(layers "F.Cu" "F.Mask" "F.Paste")
			(net "GND")
		)
		(pad "CJ32" smd circle
			(at -5.32003 20.610068 180)
			(size 0.450088 0.450088)
			(layers "F.Cu" "F.Mask" "F.Paste")
			(net "P5E_CPU1_P3_TX_DN<4>")
		)
		(pad "CJ33" smd circle
			(at -4.379976 20.610068 180)
			(size 0.450088 0.450088)
			(layers "F.Cu" "F.Mask" "F.Paste")
			(net "P5E_CPU1_P3_TX_DP<4>")
		)
		(pad "CJ34" smd circle
			(at -3.439922 20.610068 180)
			(size 0.450088 0.450088)
			(layers "F.Cu" "F.Mask" "F.Paste")
			(net "GND")
		)
		(pad "CJ35" smd circle
			(at -2.500122 20.610068 180)
			(size 0.450088 0.450088)
			(layers "F.Cu" "F.Mask" "F.Paste")
			(net "GND")
		)
		(pad "CJ36" smd circle
			(at -1.560068 20.610068 180)
			(size 0.450088 0.450088)
			(layers "F.Cu" "F.Mask" "F.Paste")
			(net "GND")
		)
		(pad "CJ40" smd circle
			(at 1.260094 20.610068 180)
			(size 0.450088 0.450088)
			(layers "F.Cu" "F.Mask" "F.Paste")
			(net "GND")
		)
		(pad "CJ41" smd circle
			(at 2.199894 20.610068 180)
			(size 0.450088 0.450088)
			(layers "F.Cu" "F.Mask" "F.Paste")
			(net "GND")
		)
		(pad "CJ42" smd circle
			(at 3.139948 20.610068 180)
			(size 0.450088 0.450088)
			(layers "F.Cu" "F.Mask" "F.Paste")
			(net "GND")
		)
		(pad "CJ43" smd circle
			(at 4.080002 20.610068 180)
			(size 0.450088 0.450088)
			(layers "F.Cu" "F.Mask" "F.Paste")
			(net "P5E_CPU1_P1_RX_DP<11>")
		)
		(pad "CJ44" smd circle
			(at 5.020056 20.610068 180)
			(size 0.450088 0.450088)
			(layers "F.Cu" "F.Mask" "F.Paste")
			(net "P5E_CPU1_P1_RX_DN<11>")
		)
		(pad "CJ45" smd circle
			(at 5.96011 20.610068 180)
			(size 0.450088 0.450088)
			(layers "F.Cu" "F.Mask" "F.Paste")
			(net "GND")
		)
		(pad "CJ46" smd circle
			(at 6.89991 20.610068 180)
			(size 0.450088 0.450088)
			(layers "F.Cu" "F.Mask" "F.Paste")
			(net "TP_CPU1_TEST6_CCD2")
		)
		(pad "CJ47" smd circle
			(at 7.839964 20.610068 180)
			(size 0.450088 0.450088)
			(layers "F.Cu" "F.Mask" "F.Paste")
			(net "TP_CPU1_TEST4_CCD10")
		)
		(pad "CJ48" smd circle
			(at 8.780018 20.610068 180)
			(size 0.450088 0.450088)
			(layers "F.Cu" "F.Mask" "F.Paste")
			(net "TP_CPU1_TEST4_CCD2")
		)
		(pad "CJ49" smd circle
			(at 9.720072 20.610068 180)
			(size 0.450088 0.450088)
			(layers "F.Cu" "F.Mask" "F.Paste")
			(net "TP_CPU1_TEST5_CCD2")
		)
		(pad "CJ50" smd circle
			(at 10.659872 20.610068 180)
			(size 0.450088 0.450088)
			(layers "F.Cu" "F.Mask" "F.Paste")
			(net "TP_CPU1_TEST4_CCD6")
		)
		(pad "CJ51" smd circle
			(at 11.599926 20.610068 180)
			(size 0.450088 0.450088)
			(layers "F.Cu" "F.Mask" "F.Paste")
			(net "TP_CPU1_TEST5_CCD6")
		)
		(pad "CJ52" smd circle
			(at 12.53998 20.610068 180)
			(size 0.450088 0.450088)
			(layers "F.Cu" "F.Mask" "F.Paste")
			(net "TP_CPU1_TEST6_X3D3")
		)
		(pad "CJ53" smd circle
			(at 13.480034 20.610068 180)
			(size 0.450088 0.450088)
			(layers "F.Cu" "F.Mask" "F.Paste")
			(net "TP_CPU1_TEST6_X3D5")
		)
		(pad "CJ54" smd circle
			(at 14.420088 20.610068 180)
			(size 0.450088 0.450088)
			(layers "F.Cu" "F.Mask" "F.Paste")
			(net "PVDDIO_P1")
		)
		(pad "CJ55" smd circle
			(at 15.359888 20.610068 180)
			(size 0.450088 0.450088)
			(layers "F.Cu" "F.Mask" "F.Paste")
			(net "M_C_CPU1_SB_DQ<9>")
		)
		(pad "CJ56" smd circle
			(at 16.299942 20.610068 180)
			(size 0.450088 0.450088)
			(layers "F.Cu" "F.Mask" "F.Paste")
			(net "GND")
		)
		(pad "CJ57" smd circle
			(at 17.239996 20.610068 180)
			(size 0.450088 0.450088)
			(layers "F.Cu" "F.Mask" "F.Paste")
			(net "M_C_CPU1_SB_DQ<10>")
		)
		(pad "CJ58" smd circle
			(at 18.18005 20.610068 180)
			(size 0.450088 0.450088)
			(layers "F.Cu" "F.Mask" "F.Paste")
			(net "GND")
		)
		(pad "CJ59" smd circle
			(at 19.120104 20.610068 180)
			(size 0.450088 0.450088)
			(layers "F.Cu" "F.Mask" "F.Paste")
			(net "M_D_CPU1_SB_DQ<9>")
		)
		(pad "CJ60" smd circle
			(at 20.059904 20.610068 180)
			(size 0.450088 0.450088)
			(layers "F.Cu" "F.Mask" "F.Paste")
			(net "M_D_CPU1_SB_DQ<10>")
		)
		(pad "CJ61" smd circle
			(at 20.999958 20.610068 180)
			(size 0.450088 0.450088)
			(layers "F.Cu" "F.Mask" "F.Paste")
			(net "GND")
		)
		(pad "CJ62" smd circle
			(at 21.940012 20.610068 180)
			(size 0.450088 0.450088)
			(layers "F.Cu" "F.Mask" "F.Paste")
			(net "M_B_CPU1_SB_DQ<9>")
		)
		(pad "CJ63" smd circle
			(at 22.880066 20.610068 180)
			(size 0.450088 0.450088)
			(layers "F.Cu" "F.Mask" "F.Paste")
			(net "GND")
		)
		(pad "CJ64" smd circle
			(at 23.82012 20.610068 180)
			(size 0.450088 0.450088)
			(layers "F.Cu" "F.Mask" "F.Paste")
			(net "M_B_CPU1_SB_DQ<10>")
		)
		(pad "CJ65" smd circle
			(at 24.75992 20.610068 180)
			(size 0.450088 0.450088)
			(layers "F.Cu" "F.Mask" "F.Paste")
			(net "GND")
		)
		(pad "CJ66" smd circle
			(at 25.699974 20.610068 180)
			(size 0.450088 0.450088)
			(layers "F.Cu" "F.Mask" "F.Paste")
			(net "M_F_CPU1_SB_DQ<9>")
		)
		(pad "CJ67" smd circle
			(at 26.640028 20.610068 180)
			(size 0.450088 0.450088)
			(layers "F.Cu" "F.Mask" "F.Paste")
			(net "M_F_CPU1_SB_DQ<10>")
		)
		(pad "CJ68" smd circle
			(at 27.580082 20.610068 180)
			(size 0.450088 0.450088)
			(layers "F.Cu" "F.Mask" "F.Paste")
			(net "GND")
		)
		(pad "CJ69" smd circle
			(at 28.519882 20.610068 180)
			(size 0.450088 0.450088)
			(layers "F.Cu" "F.Mask" "F.Paste")
			(net "M_E_CPU1_SB_DQ<9>")
		)
		(pad "CJ70" smd circle
			(at 29.459936 20.610068 180)
			(size 0.450088 0.450088)
			(layers "F.Cu" "F.Mask" "F.Paste")
			(net "GND")
		)
		(pad "CJ71" smd circle
			(at 30.39999 20.610068 180)
			(size 0.450088 0.450088)
			(layers "F.Cu" "F.Mask" "F.Paste")
			(net "M_E_CPU1_SB_DQ<10>")
		)
		(pad "CJ72" smd circle
			(at 31.340044 20.610068 180)
			(size 0.450088 0.450088)
			(layers "F.Cu" "F.Mask" "F.Paste")
			(net "GND")
		)
		(pad "CJ73" smd circle
			(at 32.280098 20.610068 180)
			(size 0.450088 0.450088)
			(layers "F.Cu" "F.Mask" "F.Paste")
			(net "M_A_CPU1_SB_DQ<9>")
		)
		(pad "CJ74" smd circle
			(at 33.219898 20.610068 180)
			(size 0.450088 0.450088)
			(layers "F.Cu" "F.Mask" "F.Paste")
			(net "M_A_CPU1_SB_DQ<10>")
		)
		(pad "CJ75" smd circle
			(at 34.159952 20.610068 180)
			(size 0.450088 0.450088)
			(layers "F.Cu" "F.Mask" "F.Paste")
			(net "GND")
		)
		(pad "CK2" smd circle
			(at -33.990026 21.420074 180)
			(size 0.450088 0.450088)
			(layers "F.Cu" "F.Mask" "F.Paste")
			(net "M_G_CPU1_SB_DQS_DP<1>")
		)
		(pad "CK3" smd circle
			(at -33.049972 21.420074 180)
			(size 0.450088 0.450088)
			(layers "F.Cu" "F.Mask" "F.Paste")
			(net "GND")
		)
		(pad "CK4" smd circle
			(at -32.109918 21.420074 180)
			(size 0.450088 0.450088)
			(layers "F.Cu" "F.Mask" "F.Paste")
			(net "M_G_CPU1_SB_DQ<11>")
		)
		(pad "CK5" smd circle
			(at -31.170118 21.420074 180)
			(size 0.450088 0.450088)
			(layers "F.Cu" "F.Mask" "F.Paste")
			(net "PVDD11_S3_P1")
		)
		(pad "CK6" smd circle
			(at -30.230064 21.420074 180)
			(size 0.450088 0.450088)
			(layers "F.Cu" "F.Mask" "F.Paste")
			(net "M_K_CPU1_SB_DQS_DP<1>")
		)
		(pad "CK7" smd circle
			(at -29.29001 21.420074 180)
			(size 0.450088 0.450088)
			(layers "F.Cu" "F.Mask" "F.Paste")
			(net "M_K_CPU1_SB_DQ<11>")
		)
		(pad "CK8" smd circle
			(at -28.349956 21.420074 180)
			(size 0.450088 0.450088)
			(layers "F.Cu" "F.Mask" "F.Paste")
			(net "GND")
		)
		(pad "CK9" smd circle
			(at -27.409902 21.420074 180)
			(size 0.450088 0.450088)
			(layers "F.Cu" "F.Mask" "F.Paste")
			(net "M_L_CPU1_SB_DQS_DP<1>")
		)
		(pad "CK10" smd circle
			(at -26.470102 21.420074 180)
			(size 0.450088 0.450088)
			(layers "F.Cu" "F.Mask" "F.Paste")
			(net "GND")
		)
		(pad "CK11" smd circle
			(at -25.530048 21.420074 180)
			(size 0.450088 0.450088)
			(layers "F.Cu" "F.Mask" "F.Paste")
			(net "M_L_CPU1_SB_DQ<11>")
		)
		(pad "CK12" smd circle
			(at -24.589994 21.420074 180)
			(size 0.450088 0.450088)
			(layers "F.Cu" "F.Mask" "F.Paste")
			(net "PVDD11_S3_P1")
		)
		(pad "CK13" smd circle
			(at -23.64994 21.420074 180)
			(size 0.450088 0.450088)
			(layers "F.Cu" "F.Mask" "F.Paste")
			(net "M_H_CPU1_SB_DQS_DP<1>")
		)
		(pad "CK14" smd circle
			(at -22.709886 21.420074 180)
			(size 0.450088 0.450088)
			(layers "F.Cu" "F.Mask" "F.Paste")
			(net "M_H_CPU1_SB_DQ<11>")
		)
		(pad "CK15" smd circle
			(at -21.770086 21.420074 180)
			(size 0.450088 0.450088)
			(layers "F.Cu" "F.Mask" "F.Paste")
			(net "GND")
		)
		(pad "CK16" smd circle
			(at -20.830032 21.420074 180)
			(size 0.450088 0.450088)
			(layers "F.Cu" "F.Mask" "F.Paste")
			(net "M_J_CPU1_SB_DQS_DP<1>")
		)
		(pad "CK17" smd circle
			(at -19.889978 21.420074 180)
			(size 0.450088 0.450088)
			(layers "F.Cu" "F.Mask" "F.Paste")
			(net "GND")
		)
		(pad "CK18" smd circle
			(at -18.949924 21.420074 180)
			(size 0.450088 0.450088)
			(layers "F.Cu" "F.Mask" "F.Paste")
			(net "M_J_CPU1_SB_DQ<11>")
		)
		(pad "CK19" smd circle
			(at -18.010124 21.420074 180)
			(size 0.450088 0.450088)
			(layers "F.Cu" "F.Mask" "F.Paste")
			(net "PVDD11_S3_P1")
		)
		(pad "CK20" smd circle
			(at -17.07007 21.420074 180)
			(size 0.450088 0.450088)
			(layers "F.Cu" "F.Mask" "F.Paste")
			(net "M_I_CPU1_SB_DQS_DP<1>")
		)
		(pad "CK21" smd circle
			(at -16.130016 21.420074 180)
			(size 0.450088 0.450088)
			(layers "F.Cu" "F.Mask" "F.Paste")
			(net "M_I_CPU1_SB_DQ<11>")
		)
		(pad "CK22" smd circle
			(at -15.189962 21.420074 180)
			(size 0.450088 0.450088)
			(layers "F.Cu" "F.Mask" "F.Paste")
			(net "GND")
		)
		(pad "CK23" smd circle
			(at -14.249908 21.420074 180)
			(size 0.450088 0.450088)
			(layers "F.Cu" "F.Mask" "F.Paste")
			(net "GND")
		)
		(pad "CK24" smd circle
			(at -13.310108 21.420074 180)
			(size 0.450088 0.450088)
			(layers "F.Cu" "F.Mask" "F.Paste")
			(net "GND")
		)
		(pad "CK25" smd circle
			(at -12.370054 21.420074 180)
			(size 0.450088 0.450088)
			(layers "F.Cu" "F.Mask" "F.Paste")
			(net "GND")
		)
		(pad "CK26" smd circle
			(at -11.43 21.420074 180)
			(size 0.450088 0.450088)
			(layers "F.Cu" "F.Mask" "F.Paste")
			(net "GND")
		)
		(pad "CK27" smd circle
			(at -10.489946 21.420074 180)
			(size 0.450088 0.450088)
			(layers "F.Cu" "F.Mask" "F.Paste")
			(net "GND")
		)
		(pad "CK28" smd circle
			(at -9.549892 21.420074 180)
			(size 0.450088 0.450088)
			(layers "F.Cu" "F.Mask" "F.Paste")
			(net "GND")
		)
		(pad "CK29" smd circle
			(at -8.610092 21.420074 180)
			(size 0.450088 0.450088)
			(layers "F.Cu" "F.Mask" "F.Paste")
			(net "TP_CPU1_TEST5_CCD9")
		)
		(pad "CK30" smd circle
			(at -7.670038 21.420074 180)
			(size 0.450088 0.450088)
			(layers "F.Cu" "F.Mask" "F.Paste")
			(net "TP_CPU1_TEST4_CCD9")
		)
		(pad "CK31" smd circle
			(at -6.729984 21.420074 180)
			(size 0.450088 0.450088)
			(layers "F.Cu" "F.Mask" "F.Paste")
			(net "GND")
		)
		(pad "CK32" smd circle
			(at -5.78993 21.420074 180)
			(size 0.450088 0.450088)
			(layers "F.Cu" "F.Mask" "F.Paste")
			(net "GND")
		)
		(pad "CK33" smd circle
			(at -4.849876 21.420074 180)
			(size 0.450088 0.450088)
			(layers "F.Cu" "F.Mask" "F.Paste")
			(net "GND")
		)
		(pad "CK34" smd circle
			(at -3.910076 21.420074 180)
			(size 0.450088 0.450088)
			(layers "F.Cu" "F.Mask" "F.Paste")
			(net "GND")
		)
		(pad "CK35" smd circle
			(at -2.970022 21.420074 180)
			(size 0.450088 0.450088)
			(layers "F.Cu" "F.Mask" "F.Paste")
			(net "PVDDCR_CPU1_P1")
		)
		(pad "CK36" smd circle
			(at -2.029968 21.420074 180)
			(size 0.450088 0.450088)
			(layers "F.Cu" "F.Mask" "F.Paste")
			(net "PVDDCR_CPU1_P1")
		)
		(pad "CK37" smd circle
			(at -1.089914 21.420074 180)
			(size 0.450088 0.450088)
			(layers "F.Cu" "F.Mask" "F.Paste")
			(net "GND")
		)
		(pad "CK39" smd circle
			(at 0.78994 21.420074 180)
			(size 0.450088 0.450088)
			(layers "F.Cu" "F.Mask" "F.Paste")
			(net "GND")
		)
		(pad "CK40" smd circle
			(at 1.729994 21.420074 180)
			(size 0.450088 0.450088)
			(layers "F.Cu" "F.Mask" "F.Paste")
			(net "PVDDCR_CPU1_P1")
		)
		(pad "CK41" smd circle
			(at 2.670048 21.420074 180)
			(size 0.450088 0.450088)
			(layers "F.Cu" "F.Mask" "F.Paste")
			(net "PVDDCR_CPU1_P1")
		)
		(pad "CK42" smd circle
			(at 3.610102 21.420074 180)
			(size 0.450088 0.450088)
			(layers "F.Cu" "F.Mask" "F.Paste")
			(net "GND")
		)
		(pad "CK43" smd circle
			(at 4.549902 21.420074 180)
			(size 0.450088 0.450088)
			(layers "F.Cu" "F.Mask" "F.Paste")
			(net "GND")
		)
		(pad "CK44" smd circle
			(at 5.489956 21.420074 180)
			(size 0.450088 0.450088)
			(layers "F.Cu" "F.Mask" "F.Paste")
			(net "GND")
		)
		(pad "CK45" smd circle
			(at 6.43001 21.420074 180)
			(size 0.450088 0.450088)
			(layers "F.Cu" "F.Mask" "F.Paste")
			(net "GND")
		)
		(pad "CK46" smd circle
			(at 7.370064 21.420074 180)
			(size 0.450088 0.450088)
			(layers "F.Cu" "F.Mask" "F.Paste")
			(net "TP_CPU1_TEST47_CCD2")
		)
		(pad "CK47" smd circle
			(at 8.310118 21.420074 180)
			(size 0.450088 0.450088)
			(layers "F.Cu" "F.Mask" "F.Paste")
			(net "TP_CPU1_TEST5_CCD10")
		)
		(pad "CK48" smd circle
			(at 9.249918 21.420074 180)
			(size 0.450088 0.450088)
			(layers "F.Cu" "F.Mask" "F.Paste")
			(net "GND")
		)
		(pad "CK49" smd circle
			(at 10.189972 21.420074 180)
			(size 0.450088 0.450088)
			(layers "F.Cu" "F.Mask" "F.Paste")
			(net "GND")
		)
		(pad "CK50" smd circle
			(at 11.130026 21.420074 180)
			(size 0.450088 0.450088)
			(layers "F.Cu" "F.Mask" "F.Paste")
			(net "GND")
		)
		(pad "CK51" smd circle
			(at 12.07008 21.420074 180)
			(size 0.450088 0.450088)
			(layers "F.Cu" "F.Mask" "F.Paste")
			(net "GND")
		)
		(pad "CK52" smd circle
			(at 13.00988 21.420074 180)
			(size 0.450088 0.450088)
			(layers "F.Cu" "F.Mask" "F.Paste")
			(net "GND")
		)
		(pad "CK53" smd circle
			(at 13.949934 21.420074 180)
			(size 0.450088 0.450088)
			(layers "F.Cu" "F.Mask" "F.Paste")
			(net "GND")
		)
		(pad "CK54" smd circle
			(at 14.889988 21.420074 180)
			(size 0.450088 0.450088)
			(layers "F.Cu" "F.Mask" "F.Paste")
			(net "GND")
		)
		(pad "CK55" smd circle
			(at 15.830042 21.420074 180)
			(size 0.450088 0.450088)
			(layers "F.Cu" "F.Mask" "F.Paste")
			(net "M_C_CPU1_SB_DQ<11>")
		)
		(pad "CK56" smd circle
			(at 16.770096 21.420074 180)
			(size 0.450088 0.450088)
			(layers "F.Cu" "F.Mask" "F.Paste")
			(net "M_C_CPU1_SB_DQS_DP<1>")
		)
		(pad "CK57" smd circle
			(at 17.709896 21.420074 180)
			(size 0.450088 0.450088)
			(layers "F.Cu" "F.Mask" "F.Paste")
			(net "PVDDIO_P1")
		)
		(pad "CK58" smd circle
			(at 18.64995 21.420074 180)
			(size 0.450088 0.450088)
			(layers "F.Cu" "F.Mask" "F.Paste")
			(net "M_D_CPU1_SB_DQ<11>")
		)
		(pad "CK59" smd circle
			(at 19.590004 21.420074 180)
			(size 0.450088 0.450088)
			(layers "F.Cu" "F.Mask" "F.Paste")
			(net "GND")
		)
		(pad "CK60" smd circle
			(at 20.530058 21.420074 180)
			(size 0.450088 0.450088)
			(layers "F.Cu" "F.Mask" "F.Paste")
			(net "M_D_CPU1_SB_DQS_DP<1>")
		)
		(pad "CK61" smd circle
			(at 21.470112 21.420074 180)
			(size 0.450088 0.450088)
			(layers "F.Cu" "F.Mask" "F.Paste")
			(net "GND")
		)
		(pad "CK62" smd circle
			(at 22.409912 21.420074 180)
			(size 0.450088 0.450088)
			(layers "F.Cu" "F.Mask" "F.Paste")
			(net "M_B_CPU1_SB_DQ<11>")
		)
		(pad "CK63" smd circle
			(at 23.349966 21.420074 180)
			(size 0.450088 0.450088)
			(layers "F.Cu" "F.Mask" "F.Paste")
			(net "M_B_CPU1_SB_DQS_DP<1>")
		)
		(pad "CK64" smd circle
			(at 24.29002 21.420074 180)
			(size 0.450088 0.450088)
			(layers "F.Cu" "F.Mask" "F.Paste")
			(net "PVDDIO_P1")
		)
		(pad "CK65" smd circle
			(at 25.230074 21.420074 180)
			(size 0.450088 0.450088)
			(layers "F.Cu" "F.Mask" "F.Paste")
			(net "M_F_CPU1_SB_DQ<11>")
		)
		(pad "CK66" smd circle
			(at 26.170128 21.420074 180)
			(size 0.450088 0.450088)
			(layers "F.Cu" "F.Mask" "F.Paste")
			(net "GND")
		)
		(pad "CK67" smd circle
			(at 27.109928 21.420074 180)
			(size 0.450088 0.450088)
			(layers "F.Cu" "F.Mask" "F.Paste")
			(net "M_F_CPU1_SB_DQS_DP<1>")
		)
		(pad "CK68" smd circle
			(at 28.049982 21.420074 180)
			(size 0.450088 0.450088)
			(layers "F.Cu" "F.Mask" "F.Paste")
			(net "GND")
		)
		(pad "CK69" smd circle
			(at 28.990036 21.420074 180)
			(size 0.450088 0.450088)
			(layers "F.Cu" "F.Mask" "F.Paste")
			(net "M_E_CPU1_SB_DQ<11>")
		)
		(pad "CK70" smd circle
			(at 29.93009 21.420074 180)
			(size 0.450088 0.450088)
			(layers "F.Cu" "F.Mask" "F.Paste")
			(net "M_E_CPU1_SB_DQS_DP<1>")
		)
		(pad "CK71" smd circle
			(at 30.86989 21.420074 180)
			(size 0.450088 0.450088)
			(layers "F.Cu" "F.Mask" "F.Paste")
			(net "PVDDIO_P1")
		)
		(pad "CK72" smd circle
			(at 31.809944 21.420074 180)
			(size 0.450088 0.450088)
			(layers "F.Cu" "F.Mask" "F.Paste")
			(net "M_A_CPU1_SB_DQ<11>")
		)
		(pad "CK73" smd circle
			(at 32.749998 21.420074 180)
			(size 0.450088 0.450088)
			(layers "F.Cu" "F.Mask" "F.Paste")
			(net "GND")
		)
		(pad "CK74" smd circle
			(at 33.690052 21.420074 180)
			(size 0.450088 0.450088)
			(layers "F.Cu" "F.Mask" "F.Paste")
			(net "M_A_CPU1_SB_DQS_DP<1>")
		)
		(pad "CL1" smd circle
			(at -34.459926 22.23008 180)
			(size 0.450088 0.450088)
			(layers "F.Cu" "F.Mask" "F.Paste")
			(net "GND")
		)
		(pad "CL2" smd circle
			(at -33.519872 22.23008 180)
			(size 0.450088 0.450088)
			(layers "F.Cu" "F.Mask" "F.Paste")
			(net "M_G_CPU1_SB_DQS_DN<1>")
		)
		(pad "CL3" smd circle
			(at -32.580072 22.23008 180)
			(size 0.450088 0.450088)
			(layers "F.Cu" "F.Mask" "F.Paste")
			(net "M_G_CPU1_SB_DQS_DN<6>")
		)
		(pad "CL4" smd circle
			(at -31.640018 22.23008 180)
			(size 0.450088 0.450088)
			(layers "F.Cu" "F.Mask" "F.Paste")
			(net "GND")
		)
		(pad "CL5" smd circle
			(at -30.699964 22.23008 180)
			(size 0.450088 0.450088)
			(layers "F.Cu" "F.Mask" "F.Paste")
			(net "M_K_CPU1_SB_DQS_DN<1>")
		)
		(pad "CL6" smd circle
			(at -29.75991 22.23008 180)
			(size 0.450088 0.450088)
			(layers "F.Cu" "F.Mask" "F.Paste")
			(net "GND")
		)
		(pad "CL7" smd circle
			(at -28.82011 22.23008 180)
			(size 0.450088 0.450088)
			(layers "F.Cu" "F.Mask" "F.Paste")
			(net "M_K_CPU1_SB_DQS_DN<6>")
		)
		(pad "CL8" smd circle
			(at -27.880056 22.23008 180)
			(size 0.450088 0.450088)
			(layers "F.Cu" "F.Mask" "F.Paste")
			(net "GND")
		)
		(pad "CL9" smd circle
			(at -26.940002 22.23008 180)
			(size 0.450088 0.450088)
			(layers "F.Cu" "F.Mask" "F.Paste")
			(net "M_L_CPU1_SB_DQS_DN<1>")
		)
		(pad "CL10" smd circle
			(at -25.999948 22.23008 180)
			(size 0.450088 0.450088)
			(layers "F.Cu" "F.Mask" "F.Paste")
			(net "M_L_CPU1_SB_DQS_DN<6>")
		)
		(pad "CL11" smd circle
			(at -25.059894 22.23008 180)
			(size 0.450088 0.450088)
			(layers "F.Cu" "F.Mask" "F.Paste")
			(net "GND")
		)
		(pad "CL12" smd circle
			(at -24.120094 22.23008 180)
			(size 0.450088 0.450088)
			(layers "F.Cu" "F.Mask" "F.Paste")
			(net "M_H_CPU1_SB_DQS_DN<1>")
		)
		(pad "CL13" smd circle
			(at -23.18004 22.23008 180)
			(size 0.450088 0.450088)
			(layers "F.Cu" "F.Mask" "F.Paste")
			(net "GND")
		)
		(pad "CL14" smd circle
			(at -22.239986 22.23008 180)
			(size 0.450088 0.450088)
			(layers "F.Cu" "F.Mask" "F.Paste")
			(net "M_H_CPU1_SB_DQS_DN<6>")
		)
		(pad "CL15" smd circle
			(at -21.299932 22.23008 180)
			(size 0.450088 0.450088)
			(layers "F.Cu" "F.Mask" "F.Paste")
			(net "GND")
		)
		(pad "CL16" smd circle
			(at -20.359878 22.23008 180)
			(size 0.450088 0.450088)
			(layers "F.Cu" "F.Mask" "F.Paste")
			(net "M_J_CPU1_SB_DQS_DN<1>")
		)
		(pad "CL17" smd circle
			(at -19.420078 22.23008 180)
			(size 0.450088 0.450088)
			(layers "F.Cu" "F.Mask" "F.Paste")
			(net "M_J_CPU1_SB_DQS_DN<6>")
		)
		(pad "CL18" smd circle
			(at -18.480024 22.23008 180)
			(size 0.450088 0.450088)
			(layers "F.Cu" "F.Mask" "F.Paste")
			(net "GND")
		)
		(pad "CL19" smd circle
			(at -17.53997 22.23008 180)
			(size 0.450088 0.450088)
			(layers "F.Cu" "F.Mask" "F.Paste")
			(net "M_I_CPU1_SB_DQS_DN<1>")
		)
		(pad "CL20" smd circle
			(at -16.599916 22.23008 180)
			(size 0.450088 0.450088)
			(layers "F.Cu" "F.Mask" "F.Paste")
			(net "GND")
		)
		(pad "CL21" smd circle
			(at -15.660116 22.23008 180)
			(size 0.450088 0.450088)
			(layers "F.Cu" "F.Mask" "F.Paste")
			(net "M_I_CPU1_SB_DQS_DN<6>")
		)
		(pad "CL22" smd circle
			(at -14.720062 22.23008 180)
			(size 0.450088 0.450088)
			(layers "F.Cu" "F.Mask" "F.Paste")
			(net "GND")
		)
		(pad "CL23" smd circle
			(at -13.780008 22.23008 180)
			(size 0.450088 0.450088)
			(layers "F.Cu" "F.Mask" "F.Paste")
			(net "P5E_CPU1_P2_RX_DP<13>")
		)
		(pad "CL24" smd circle
			(at -12.839954 22.23008 180)
			(size 0.450088 0.450088)
			(layers "F.Cu" "F.Mask" "F.Paste")
			(net "P5E_CPU1_P2_RX_DN<13>")
		)
		(pad "CL25" smd circle
			(at -11.8999 22.23008 180)
			(size 0.450088 0.450088)
			(layers "F.Cu" "F.Mask" "F.Paste")
			(net "GND")
		)
		(pad "CL26" smd circle
			(at -10.9601 22.23008 180)
			(size 0.450088 0.450088)
			(layers "F.Cu" "F.Mask" "F.Paste")
			(net "P5E_CPU1_P2_RX_DP<9>")
		)
		(pad "CL27" smd circle
			(at -10.020046 22.23008 180)
			(size 0.450088 0.450088)
			(layers "F.Cu" "F.Mask" "F.Paste")
			(net "P5E_CPU1_P2_RX_DN<9>")
		)
		(pad "CL28" smd circle
			(at -9.079992 22.23008 180)
			(size 0.450088 0.450088)
			(layers "F.Cu" "F.Mask" "F.Paste")
			(net "GND")
		)
		(pad "CL29" smd circle
			(at -8.139938 22.23008 180)
			(size 0.450088 0.450088)
			(layers "F.Cu" "F.Mask" "F.Paste")
			(net "PVDDCR_CPU1_P1")
		)
		(pad "CL30" smd circle
			(at -7.199884 22.23008 180)
			(size 0.450088 0.450088)
			(layers "F.Cu" "F.Mask" "F.Paste")
			(net "PVDDCR_CPU1_P1")
		)
		(pad "CL31" smd circle
			(at -6.260084 22.23008 180)
			(size 0.450088 0.450088)
			(layers "F.Cu" "F.Mask" "F.Paste")
			(net "GND")
		)
		(pad "CL32" smd circle
			(at -5.32003 22.23008 180)
			(size 0.450088 0.450088)
			(layers "F.Cu" "F.Mask" "F.Paste")
			(net "PVDDCR_CPU1_P1")
		)
		(pad "CL33" smd circle
			(at -4.379976 22.23008 180)
			(size 0.450088 0.450088)
			(layers "F.Cu" "F.Mask" "F.Paste")
			(net "PVDDCR_CPU1_P1")
		)
		(pad "CL34" smd circle
			(at -3.439922 22.23008 180)
			(size 0.450088 0.450088)
			(layers "F.Cu" "F.Mask" "F.Paste")
			(net "GND")
		)
		(pad "CL35" smd circle
			(at -2.500122 22.23008 180)
			(size 0.450088 0.450088)
			(layers "F.Cu" "F.Mask" "F.Paste")
			(net "GND")
		)
		(pad "CL36" smd circle
			(at -1.560068 22.23008 180)
			(size 0.450088 0.450088)
			(layers "F.Cu" "F.Mask" "F.Paste")
			(net "GND")
		)
		(pad "CL40" smd circle
			(at 1.260094 22.23008 180)
			(size 0.450088 0.450088)
			(layers "F.Cu" "F.Mask" "F.Paste")
			(net "GND")
		)
		(pad "CL41" smd circle
			(at 2.199894 22.23008 180)
			(size 0.450088 0.450088)
			(layers "F.Cu" "F.Mask" "F.Paste")
			(net "GND")
		)
		(pad "CL42" smd circle
			(at 3.139948 22.23008 180)
			(size 0.450088 0.450088)
			(layers "F.Cu" "F.Mask" "F.Paste")
			(net "GND")
		)
		(pad "CL43" smd circle
			(at 4.080002 22.23008 180)
			(size 0.450088 0.450088)
			(layers "F.Cu" "F.Mask" "F.Paste")
			(net "PVDDCR_CPU1_P1")
		)
		(pad "CL44" smd circle
			(at 5.020056 22.23008 180)
			(size 0.450088 0.450088)
			(layers "F.Cu" "F.Mask" "F.Paste")
			(net "PVDDCR_CPU1_P1")
		)
		(pad "CL45" smd circle
			(at 5.96011 22.23008 180)
			(size 0.450088 0.450088)
			(layers "F.Cu" "F.Mask" "F.Paste")
			(net "GND")
		)
		(pad "CL46" smd circle
			(at 6.89991 22.23008 180)
			(size 0.450088 0.450088)
			(layers "F.Cu" "F.Mask" "F.Paste")
			(net "PVDDCR_CPU1_P1")
		)
		(pad "CL47" smd circle
			(at 7.839964 22.23008 180)
			(size 0.450088 0.450088)
			(layers "F.Cu" "F.Mask" "F.Paste")
			(net "PVDDCR_CPU1_P1")
		)
		(pad "CL48" smd circle
			(at 8.780018 22.23008 180)
			(size 0.450088 0.450088)
			(layers "F.Cu" "F.Mask" "F.Paste")
			(net "GND")
		)
		(pad "CL49" smd circle
			(at 9.720072 22.23008 180)
			(size 0.450088 0.450088)
			(layers "F.Cu" "F.Mask" "F.Paste")
			(net "P5E_CPU1_P0_TX_DN<6>")
		)
		(pad "CL50" smd circle
			(at 10.659872 22.23008 180)
			(size 0.450088 0.450088)
			(layers "F.Cu" "F.Mask" "F.Paste")
			(net "P5E_CPU1_P0_TX_DP<6>")
		)
		(pad "CL51" smd circle
			(at 11.599926 22.23008 180)
			(size 0.450088 0.450088)
			(layers "F.Cu" "F.Mask" "F.Paste")
			(net "GND")
		)
		(pad "CL52" smd circle
			(at 12.53998 22.23008 180)
			(size 0.450088 0.450088)
			(layers "F.Cu" "F.Mask" "F.Paste")
			(net "P5E_CPU1_P0_TX_DN<2>")
		)
		(pad "CL53" smd circle
			(at 13.480034 22.23008 180)
			(size 0.450088 0.450088)
			(layers "F.Cu" "F.Mask" "F.Paste")
			(net "P5E_CPU1_P0_TX_DP<2>")
		)
		(pad "CL54" smd circle
			(at 14.420088 22.23008 180)
			(size 0.450088 0.450088)
			(layers "F.Cu" "F.Mask" "F.Paste")
			(net "GND")
		)
		(pad "CL55" smd circle
			(at 15.359888 22.23008 180)
			(size 0.450088 0.450088)
			(layers "F.Cu" "F.Mask" "F.Paste")
			(net "M_C_CPU1_SB_DQS_DN<6>")
		)
		(pad "CL56" smd circle
			(at 16.299942 22.23008 180)
			(size 0.450088 0.450088)
			(layers "F.Cu" "F.Mask" "F.Paste")
			(net "GND")
		)
		(pad "CL57" smd circle
			(at 17.239996 22.23008 180)
			(size 0.450088 0.450088)
			(layers "F.Cu" "F.Mask" "F.Paste")
			(net "M_C_CPU1_SB_DQS_DN<1>")
		)
		(pad "CL58" smd circle
			(at 18.18005 22.23008 180)
			(size 0.450088 0.450088)
			(layers "F.Cu" "F.Mask" "F.Paste")
			(net "GND")
		)
		(pad "CL59" smd circle
			(at 19.120104 22.23008 180)
			(size 0.450088 0.450088)
			(layers "F.Cu" "F.Mask" "F.Paste")
			(net "M_D_CPU1_SB_DQS_DN<6>")
		)
		(pad "CL60" smd circle
			(at 20.059904 22.23008 180)
			(size 0.450088 0.450088)
			(layers "F.Cu" "F.Mask" "F.Paste")
			(net "M_D_CPU1_SB_DQS_DN<1>")
		)
		(pad "CL61" smd circle
			(at 20.999958 22.23008 180)
			(size 0.450088 0.450088)
			(layers "F.Cu" "F.Mask" "F.Paste")
			(net "GND")
		)
		(pad "CL62" smd circle
			(at 21.940012 22.23008 180)
			(size 0.450088 0.450088)
			(layers "F.Cu" "F.Mask" "F.Paste")
			(net "M_B_CPU1_SB_DQS_DN<6>")
		)
		(pad "CL63" smd circle
			(at 22.880066 22.23008 180)
			(size 0.450088 0.450088)
			(layers "F.Cu" "F.Mask" "F.Paste")
			(net "GND")
		)
		(pad "CL64" smd circle
			(at 23.82012 22.23008 180)
			(size 0.450088 0.450088)
			(layers "F.Cu" "F.Mask" "F.Paste")
			(net "M_B_CPU1_SB_DQS_DN<1>")
		)
		(pad "CL65" smd circle
			(at 24.75992 22.23008 180)
			(size 0.450088 0.450088)
			(layers "F.Cu" "F.Mask" "F.Paste")
			(net "GND")
		)
		(pad "CL66" smd circle
			(at 25.699974 22.23008 180)
			(size 0.450088 0.450088)
			(layers "F.Cu" "F.Mask" "F.Paste")
			(net "M_F_CPU1_SB_DQS_DN<6>")
		)
		(pad "CL67" smd circle
			(at 26.640028 22.23008 180)
			(size 0.450088 0.450088)
			(layers "F.Cu" "F.Mask" "F.Paste")
			(net "M_F_CPU1_SB_DQS_DN<1>")
		)
		(pad "CL68" smd circle
			(at 27.580082 22.23008 180)
			(size 0.450088 0.450088)
			(layers "F.Cu" "F.Mask" "F.Paste")
			(net "GND")
		)
		(pad "CL69" smd circle
			(at 28.519882 22.23008 180)
			(size 0.450088 0.450088)
			(layers "F.Cu" "F.Mask" "F.Paste")
			(net "M_E_CPU1_SB_DQS_DN<6>")
		)
		(pad "CL70" smd circle
			(at 29.459936 22.23008 180)
			(size 0.450088 0.450088)
			(layers "F.Cu" "F.Mask" "F.Paste")
			(net "GND")
		)
		(pad "CL71" smd circle
			(at 30.39999 22.23008 180)
			(size 0.450088 0.450088)
			(layers "F.Cu" "F.Mask" "F.Paste")
			(net "M_E_CPU1_SB_DQS_DN<1>")
		)
		(pad "CL72" smd circle
			(at 31.340044 22.23008 180)
			(size 0.450088 0.450088)
			(layers "F.Cu" "F.Mask" "F.Paste")
			(net "GND")
		)
		(pad "CL73" smd circle
			(at 32.280098 22.23008 180)
			(size 0.450088 0.450088)
			(layers "F.Cu" "F.Mask" "F.Paste")
			(net "M_A_CPU1_SB_DQS_DN<6>")
		)
		(pad "CL74" smd circle
			(at 33.219898 22.23008 180)
			(size 0.450088 0.450088)
			(layers "F.Cu" "F.Mask" "F.Paste")
			(net "M_A_CPU1_SB_DQS_DN<1>")
		)
		(pad "CL75" smd circle
			(at 34.159952 22.23008 180)
			(size 0.450088 0.450088)
			(layers "F.Cu" "F.Mask" "F.Paste")
			(net "GND")
		)
		(pad "CM2" smd circle
			(at -33.990026 23.040086 180)
			(size 0.450088 0.450088)
			(layers "F.Cu" "F.Mask" "F.Paste")
			(net "M_G_CPU1_SB_DQ<12>")
		)
		(pad "CM3" smd circle
			(at -33.049972 23.040086 180)
			(size 0.450088 0.450088)
			(layers "F.Cu" "F.Mask" "F.Paste")
			(net "GND")
		)
		(pad "CM4" smd circle
			(at -32.109918 23.040086 180)
			(size 0.450088 0.450088)
			(layers "F.Cu" "F.Mask" "F.Paste")
			(net "M_G_CPU1_SB_DQS_DP<6>")
		)
		(pad "CM5" smd circle
			(at -31.170118 23.040086 180)
			(size 0.450088 0.450088)
			(layers "F.Cu" "F.Mask" "F.Paste")
			(net "GND")
		)
		(pad "CM6" smd circle
			(at -30.230064 23.040086 180)
			(size 0.450088 0.450088)
			(layers "F.Cu" "F.Mask" "F.Paste")
			(net "M_K_CPU1_SB_DQ<12>")
		)
		(pad "CM7" smd circle
			(at -29.29001 23.040086 180)
			(size 0.450088 0.450088)
			(layers "F.Cu" "F.Mask" "F.Paste")
			(net "M_K_CPU1_SB_DQS_DP<6>")
		)
		(pad "CM8" smd circle
			(at -28.349956 23.040086 180)
			(size 0.450088 0.450088)
			(layers "F.Cu" "F.Mask" "F.Paste")
			(net "GND")
		)
		(pad "CM9" smd circle
			(at -27.409902 23.040086 180)
			(size 0.450088 0.450088)
			(layers "F.Cu" "F.Mask" "F.Paste")
			(net "M_L_CPU1_SB_DQ<12>")
		)
		(pad "CM10" smd circle
			(at -26.470102 23.040086 180)
			(size 0.450088 0.450088)
			(layers "F.Cu" "F.Mask" "F.Paste")
			(net "GND")
		)
		(pad "CM11" smd circle
			(at -25.530048 23.040086 180)
			(size 0.450088 0.450088)
			(layers "F.Cu" "F.Mask" "F.Paste")
			(net "M_L_CPU1_SB_DQS_DP<6>")
		)
		(pad "CM12" smd circle
			(at -24.589994 23.040086 180)
			(size 0.450088 0.450088)
			(layers "F.Cu" "F.Mask" "F.Paste")
			(net "GND")
		)
		(pad "CM13" smd circle
			(at -23.64994 23.040086 180)
			(size 0.450088 0.450088)
			(layers "F.Cu" "F.Mask" "F.Paste")
			(net "M_H_CPU1_SB_DQ<12>")
		)
		(pad "CM14" smd circle
			(at -22.709886 23.040086 180)
			(size 0.450088 0.450088)
			(layers "F.Cu" "F.Mask" "F.Paste")
			(net "M_H_CPU1_SB_DQS_DP<6>")
		)
		(pad "CM15" smd circle
			(at -21.770086 23.040086 180)
			(size 0.450088 0.450088)
			(layers "F.Cu" "F.Mask" "F.Paste")
			(net "GND")
		)
		(pad "CM16" smd circle
			(at -20.830032 23.040086 180)
			(size 0.450088 0.450088)
			(layers "F.Cu" "F.Mask" "F.Paste")
			(net "M_J_CPU1_SB_DQ<12>")
		)
		(pad "CM17" smd circle
			(at -19.889978 23.040086 180)
			(size 0.450088 0.450088)
			(layers "F.Cu" "F.Mask" "F.Paste")
			(net "GND")
		)
		(pad "CM18" smd circle
			(at -18.949924 23.040086 180)
			(size 0.450088 0.450088)
			(layers "F.Cu" "F.Mask" "F.Paste")
			(net "M_J_CPU1_SB_DQS_DP<6>")
		)
		(pad "CM19" smd circle
			(at -18.010124 23.040086 180)
			(size 0.450088 0.450088)
			(layers "F.Cu" "F.Mask" "F.Paste")
			(net "GND")
		)
		(pad "CM20" smd circle
			(at -17.07007 23.040086 180)
			(size 0.450088 0.450088)
			(layers "F.Cu" "F.Mask" "F.Paste")
			(net "M_I_CPU1_SB_DQ<12>")
		)
		(pad "CM21" smd circle
			(at -16.130016 23.040086 180)
			(size 0.450088 0.450088)
			(layers "F.Cu" "F.Mask" "F.Paste")
			(net "M_I_CPU1_SB_DQS_DP<6>")
		)
		(pad "CM22" smd circle
			(at -15.189962 23.040086 180)
			(size 0.450088 0.450088)
			(layers "F.Cu" "F.Mask" "F.Paste")
			(net "PVDD11_S3_P1")
		)
		(pad "CM23" smd circle
			(at -14.249908 23.040086 180)
			(size 0.450088 0.450088)
			(layers "F.Cu" "F.Mask" "F.Paste")
			(net "GND")
		)
		(pad "CM24" smd circle
			(at -13.310108 23.040086 180)
			(size 0.450088 0.450088)
			(layers "F.Cu" "F.Mask" "F.Paste")
			(net "GND")
		)
		(pad "CM25" smd circle
			(at -12.370054 23.040086 180)
			(size 0.450088 0.450088)
			(layers "F.Cu" "F.Mask" "F.Paste")
			(net "GND")
		)
		(pad "CM26" smd circle
			(at -11.43 23.040086 180)
			(size 0.450088 0.450088)
			(layers "F.Cu" "F.Mask" "F.Paste")
			(net "GND")
		)
		(pad "CM27" smd circle
			(at -10.489946 23.040086 180)
			(size 0.450088 0.450088)
			(layers "F.Cu" "F.Mask" "F.Paste")
			(net "GND")
		)
		(pad "CM28" smd circle
			(at -9.549892 23.040086 180)
			(size 0.450088 0.450088)
			(layers "F.Cu" "F.Mask" "F.Paste")
			(net "GND")
		)
		(pad "CM29" smd circle
			(at -8.610092 23.040086 180)
			(size 0.450088 0.450088)
			(layers "F.Cu" "F.Mask" "F.Paste")
			(net "GND")
		)
		(pad "CM30" smd circle
			(at -7.670038 23.040086 180)
			(size 0.450088 0.450088)
			(layers "F.Cu" "F.Mask" "F.Paste")
			(net "GND")
		)
		(pad "CM31" smd circle
			(at -6.729984 23.040086 180)
			(size 0.450088 0.450088)
			(layers "F.Cu" "F.Mask" "F.Paste")
			(net "GND")
		)
		(pad "CM32" smd circle
			(at -5.78993 23.040086 180)
			(size 0.450088 0.450088)
			(layers "F.Cu" "F.Mask" "F.Paste")
			(net "GND")
		)
		(pad "CM33" smd circle
			(at -4.849876 23.040086 180)
			(size 0.450088 0.450088)
			(layers "F.Cu" "F.Mask" "F.Paste")
			(net "GND")
		)
		(pad "CM34" smd circle
			(at -3.910076 23.040086 180)
			(size 0.450088 0.450088)
			(layers "F.Cu" "F.Mask" "F.Paste")
			(net "GND")
		)
		(pad "CM35" smd circle
			(at -2.970022 23.040086 180)
			(size 0.450088 0.450088)
			(layers "F.Cu" "F.Mask" "F.Paste")
			(net "P5E_CPU1_P2_RX_DP<0>")
		)
		(pad "CM36" smd circle
			(at -2.029968 23.040086 180)
			(size 0.450088 0.450088)
			(layers "F.Cu" "F.Mask" "F.Paste")
			(net "P5E_CPU1_P2_RX_DN<0>")
		)
		(pad "CM37" smd circle
			(at -1.089914 23.040086 180)
			(size 0.450088 0.450088)
			(layers "F.Cu" "F.Mask" "F.Paste")
			(net "GND")
		)
		(pad "CM39" smd circle
			(at 0.78994 23.040086 180)
			(size 0.450088 0.450088)
			(layers "F.Cu" "F.Mask" "F.Paste")
			(net "GND")
		)
		(pad "CM40" smd circle
			(at 1.729994 23.040086 180)
			(size 0.450088 0.450088)
			(layers "F.Cu" "F.Mask" "F.Paste")
			(net "P5E_CPU1_P0_TX_DN<15>")
		)
		(pad "CM41" smd circle
			(at 2.670048 23.040086 180)
			(size 0.450088 0.450088)
			(layers "F.Cu" "F.Mask" "F.Paste")
			(net "P5E_CPU1_P0_TX_DP<15>")
		)
		(pad "CM42" smd circle
			(at 3.610102 23.040086 180)
			(size 0.450088 0.450088)
			(layers "F.Cu" "F.Mask" "F.Paste")
			(net "GND")
		)
		(pad "CM43" smd circle
			(at 4.549902 23.040086 180)
			(size 0.450088 0.450088)
			(layers "F.Cu" "F.Mask" "F.Paste")
			(net "GND")
		)
		(pad "CM44" smd circle
			(at 5.489956 23.040086 180)
			(size 0.450088 0.450088)
			(layers "F.Cu" "F.Mask" "F.Paste")
			(net "GND")
		)
		(pad "CM45" smd circle
			(at 6.43001 23.040086 180)
			(size 0.450088 0.450088)
			(layers "F.Cu" "F.Mask" "F.Paste")
			(net "GND")
		)
		(pad "CM46" smd circle
			(at 7.370064 23.040086 180)
			(size 0.450088 0.450088)
			(layers "F.Cu" "F.Mask" "F.Paste")
			(net "GND")
		)
		(pad "CM47" smd circle
			(at 8.310118 23.040086 180)
			(size 0.450088 0.450088)
			(layers "F.Cu" "F.Mask" "F.Paste")
			(net "GND")
		)
		(pad "CM48" smd circle
			(at 9.249918 23.040086 180)
			(size 0.450088 0.450088)
			(layers "F.Cu" "F.Mask" "F.Paste")
			(net "GND")
		)
		(pad "CM49" smd circle
			(at 10.189972 23.040086 180)
			(size 0.450088 0.450088)
			(layers "F.Cu" "F.Mask" "F.Paste")
			(net "GND")
		)
		(pad "CM50" smd circle
			(at 11.130026 23.040086 180)
			(size 0.450088 0.450088)
			(layers "F.Cu" "F.Mask" "F.Paste")
			(net "GND")
		)
		(pad "CM51" smd circle
			(at 12.07008 23.040086 180)
			(size 0.450088 0.450088)
			(layers "F.Cu" "F.Mask" "F.Paste")
			(net "GND")
		)
		(pad "CM52" smd circle
			(at 13.00988 23.040086 180)
			(size 0.450088 0.450088)
			(layers "F.Cu" "F.Mask" "F.Paste")
			(net "GND")
		)
		(pad "CM53" smd circle
			(at 13.949934 23.040086 180)
			(size 0.450088 0.450088)
			(layers "F.Cu" "F.Mask" "F.Paste")
			(net "GND")
		)
		(pad "CM54" smd circle
			(at 14.889988 23.040086 180)
			(size 0.450088 0.450088)
			(layers "F.Cu" "F.Mask" "F.Paste")
			(net "PVDDIO_P1")
		)
		(pad "CM55" smd circle
			(at 15.830042 23.040086 180)
			(size 0.450088 0.450088)
			(layers "F.Cu" "F.Mask" "F.Paste")
			(net "M_C_CPU1_SB_DQS_DP<6>")
		)
		(pad "CM56" smd circle
			(at 16.770096 23.040086 180)
			(size 0.450088 0.450088)
			(layers "F.Cu" "F.Mask" "F.Paste")
			(net "M_C_CPU1_SB_DQ<12>")
		)
		(pad "CM57" smd circle
			(at 17.709896 23.040086 180)
			(size 0.450088 0.450088)
			(layers "F.Cu" "F.Mask" "F.Paste")
			(net "GND")
		)
		(pad "CM58" smd circle
			(at 18.64995 23.040086 180)
			(size 0.450088 0.450088)
			(layers "F.Cu" "F.Mask" "F.Paste")
			(net "M_D_CPU1_SB_DQS_DP<6>")
		)
		(pad "CM59" smd circle
			(at 19.590004 23.040086 180)
			(size 0.450088 0.450088)
			(layers "F.Cu" "F.Mask" "F.Paste")
			(net "GND")
		)
		(pad "CM60" smd circle
			(at 20.530058 23.040086 180)
			(size 0.450088 0.450088)
			(layers "F.Cu" "F.Mask" "F.Paste")
			(net "M_D_CPU1_SB_DQ<12>")
		)
		(pad "CM61" smd circle
			(at 21.470112 23.040086 180)
			(size 0.450088 0.450088)
			(layers "F.Cu" "F.Mask" "F.Paste")
			(net "GND")
		)
		(pad "CM62" smd circle
			(at 22.409912 23.040086 180)
			(size 0.450088 0.450088)
			(layers "F.Cu" "F.Mask" "F.Paste")
			(net "M_B_CPU1_SB_DQS_DP<6>")
		)
		(pad "CM63" smd circle
			(at 23.349966 23.040086 180)
			(size 0.450088 0.450088)
			(layers "F.Cu" "F.Mask" "F.Paste")
			(net "M_B_CPU1_SB_DQ<12>")
		)
		(pad "CM64" smd circle
			(at 24.29002 23.040086 180)
			(size 0.450088 0.450088)
			(layers "F.Cu" "F.Mask" "F.Paste")
			(net "GND")
		)
		(pad "CM65" smd circle
			(at 25.230074 23.040086 180)
			(size 0.450088 0.450088)
			(layers "F.Cu" "F.Mask" "F.Paste")
			(net "M_F_CPU1_SB_DQS_DP<6>")
		)
		(pad "CM66" smd circle
			(at 26.170128 23.040086 180)
			(size 0.450088 0.450088)
			(layers "F.Cu" "F.Mask" "F.Paste")
			(net "GND")
		)
		(pad "CM67" smd circle
			(at 27.109928 23.040086 180)
			(size 0.450088 0.450088)
			(layers "F.Cu" "F.Mask" "F.Paste")
			(net "M_F_CPU1_SB_DQ<12>")
		)
		(pad "CM68" smd circle
			(at 28.049982 23.040086 180)
			(size 0.450088 0.450088)
			(layers "F.Cu" "F.Mask" "F.Paste")
			(net "GND")
		)
		(pad "CM69" smd circle
			(at 28.990036 23.040086 180)
			(size 0.450088 0.450088)
			(layers "F.Cu" "F.Mask" "F.Paste")
			(net "M_E_CPU1_SB_DQS_DP<6>")
		)
		(pad "CM70" smd circle
			(at 29.93009 23.040086 180)
			(size 0.450088 0.450088)
			(layers "F.Cu" "F.Mask" "F.Paste")
			(net "M_E_CPU1_SB_DQ<12>")
		)
		(pad "CM71" smd circle
			(at 30.86989 23.040086 180)
			(size 0.450088 0.450088)
			(layers "F.Cu" "F.Mask" "F.Paste")
			(net "GND")
		)
		(pad "CM72" smd circle
			(at 31.809944 23.040086 180)
			(size 0.450088 0.450088)
			(layers "F.Cu" "F.Mask" "F.Paste")
			(net "M_A_CPU1_SB_DQS_DP<6>")
		)
		(pad "CM73" smd circle
			(at 32.749998 23.040086 180)
			(size 0.450088 0.450088)
			(layers "F.Cu" "F.Mask" "F.Paste")
			(net "GND")
		)
		(pad "CM74" smd circle
			(at 33.690052 23.040086 180)
			(size 0.450088 0.450088)
			(layers "F.Cu" "F.Mask" "F.Paste")
			(net "M_A_CPU1_SB_DQ<12>")
		)
		(pad "CN1" smd circle
			(at -34.459926 23.850092 180)
			(size 0.450088 0.450088)
			(layers "F.Cu" "F.Mask" "F.Paste")
			(net "GND")
		)
		(pad "CN2" smd circle
			(at -33.519872 23.850092 180)
			(size 0.450088 0.450088)
			(layers "F.Cu" "F.Mask" "F.Paste")
			(net "M_G_CPU1_SB_DQ<14>")
		)
		(pad "CN3" smd circle
			(at -32.580072 23.850092 180)
			(size 0.450088 0.450088)
			(layers "F.Cu" "F.Mask" "F.Paste")
			(net "M_G_CPU1_SB_DQ<13>")
		)
		(pad "CN4" smd circle
			(at -31.640018 23.850092 180)
			(size 0.450088 0.450088)
			(layers "F.Cu" "F.Mask" "F.Paste")
			(net "PVDD11_S3_P1")
		)
		(pad "CN5" smd circle
			(at -30.699964 23.850092 180)
			(size 0.450088 0.450088)
			(layers "F.Cu" "F.Mask" "F.Paste")
			(net "M_K_CPU1_SB_DQ<14>")
		)
		(pad "CN6" smd circle
			(at -29.75991 23.850092 180)
			(size 0.450088 0.450088)
			(layers "F.Cu" "F.Mask" "F.Paste")
			(net "GND")
		)
		(pad "CN7" smd circle
			(at -28.82011 23.850092 180)
			(size 0.450088 0.450088)
			(layers "F.Cu" "F.Mask" "F.Paste")
			(net "M_K_CPU1_SB_DQ<13>")
		)
		(pad "CN8" smd circle
			(at -27.880056 23.850092 180)
			(size 0.450088 0.450088)
			(layers "F.Cu" "F.Mask" "F.Paste")
			(net "GND")
		)
		(pad "CN9" smd circle
			(at -26.940002 23.850092 180)
			(size 0.450088 0.450088)
			(layers "F.Cu" "F.Mask" "F.Paste")
			(net "M_L_CPU1_SB_DQ<14>")
		)
		(pad "CN10" smd circle
			(at -25.999948 23.850092 180)
			(size 0.450088 0.450088)
			(layers "F.Cu" "F.Mask" "F.Paste")
			(net "M_L_CPU1_SB_DQ<13>")
		)
		(pad "CN11" smd circle
			(at -25.059894 23.850092 180)
			(size 0.450088 0.450088)
			(layers "F.Cu" "F.Mask" "F.Paste")
			(net "PVDD11_S3_P1")
		)
		(pad "CN12" smd circle
			(at -24.120094 23.850092 180)
			(size 0.450088 0.450088)
			(layers "F.Cu" "F.Mask" "F.Paste")
			(net "M_H_CPU1_SB_DQ<14>")
		)
		(pad "CN13" smd circle
			(at -23.18004 23.850092 180)
			(size 0.450088 0.450088)
			(layers "F.Cu" "F.Mask" "F.Paste")
			(net "GND")
		)
		(pad "CN14" smd circle
			(at -22.239986 23.850092 180)
			(size 0.450088 0.450088)
			(layers "F.Cu" "F.Mask" "F.Paste")
			(net "M_H_CPU1_SB_DQ<13>")
		)
		(pad "CN15" smd circle
			(at -21.299932 23.850092 180)
			(size 0.450088 0.450088)
			(layers "F.Cu" "F.Mask" "F.Paste")
			(net "GND")
		)
		(pad "CN16" smd circle
			(at -20.359878 23.850092 180)
			(size 0.450088 0.450088)
			(layers "F.Cu" "F.Mask" "F.Paste")
			(net "M_J_CPU1_SB_DQ<14>")
		)
		(pad "CN17" smd circle
			(at -19.420078 23.850092 180)
			(size 0.450088 0.450088)
			(layers "F.Cu" "F.Mask" "F.Paste")
			(net "M_J_CPU1_SB_DQ<13>")
		)
		(pad "CN18" smd circle
			(at -18.480024 23.850092 180)
			(size 0.450088 0.450088)
			(layers "F.Cu" "F.Mask" "F.Paste")
			(net "PVDD11_S3_P1")
		)
		(pad "CN19" smd circle
			(at -17.53997 23.850092 180)
			(size 0.450088 0.450088)
			(layers "F.Cu" "F.Mask" "F.Paste")
			(net "M_I_CPU1_SB_DQ<14>")
		)
		(pad "CN20" smd circle
			(at -16.599916 23.850092 180)
			(size 0.450088 0.450088)
			(layers "F.Cu" "F.Mask" "F.Paste")
			(net "GND")
		)
		(pad "CN21" smd circle
			(at -15.660116 23.850092 180)
			(size 0.450088 0.450088)
			(layers "F.Cu" "F.Mask" "F.Paste")
			(net "M_I_CPU1_SB_DQ<13>")
		)
		(pad "CN22" smd circle
			(at -14.720062 23.850092 180)
			(size 0.450088 0.450088)
			(layers "F.Cu" "F.Mask" "F.Paste")
			(net "GND")
		)
		(pad "CN23" smd circle
			(at -13.780008 23.850092 180)
			(size 0.450088 0.450088)
			(layers "F.Cu" "F.Mask" "F.Paste")
			(net "P5E_CPU1_P2_RX_DP<15>")
		)
		(pad "CN24" smd circle
			(at -12.839954 23.850092 180)
			(size 0.450088 0.450088)
			(layers "F.Cu" "F.Mask" "F.Paste")
			(net "P5E_CPU1_P2_RX_DN<15>")
		)
		(pad "CN25" smd circle
			(at -11.8999 23.850092 180)
			(size 0.450088 0.450088)
			(layers "F.Cu" "F.Mask" "F.Paste")
			(net "GND")
		)
		(pad "CN26" smd circle
			(at -10.9601 23.850092 180)
			(size 0.450088 0.450088)
			(layers "F.Cu" "F.Mask" "F.Paste")
			(net "P5E_CPU1_P2_RX_DP<12>")
		)
		(pad "CN27" smd circle
			(at -10.020046 23.850092 180)
			(size 0.450088 0.450088)
			(layers "F.Cu" "F.Mask" "F.Paste")
			(net "P5E_CPU1_P2_RX_DN<12>")
		)
		(pad "CN28" smd circle
			(at -9.079992 23.850092 180)
			(size 0.450088 0.450088)
			(layers "F.Cu" "F.Mask" "F.Paste")
			(net "GND")
		)
		(pad "CN29" smd circle
			(at -8.139938 23.850092 180)
			(size 0.450088 0.450088)
			(layers "F.Cu" "F.Mask" "F.Paste")
			(net "P5E_CPU1_P2_RX_DP<6>")
		)
		(pad "CN30" smd circle
			(at -7.199884 23.850092 180)
			(size 0.450088 0.450088)
			(layers "F.Cu" "F.Mask" "F.Paste")
			(net "P5E_CPU1_P2_RX_DN<6>")
		)
		(pad "CN31" smd circle
			(at -6.260084 23.850092 180)
			(size 0.450088 0.450088)
			(layers "F.Cu" "F.Mask" "F.Paste")
			(net "GND")
		)
		(pad "CN32" smd circle
			(at -5.32003 23.850092 180)
			(size 0.450088 0.450088)
			(layers "F.Cu" "F.Mask" "F.Paste")
			(net "P5E_CPU1_P2_RX_DP<3>")
		)
		(pad "CN33" smd circle
			(at -4.379976 23.850092 180)
			(size 0.450088 0.450088)
			(layers "F.Cu" "F.Mask" "F.Paste")
			(net "P5E_CPU1_P2_RX_DN<3>")
		)
		(pad "CN34" smd circle
			(at -3.439922 23.850092 180)
			(size 0.450088 0.450088)
			(layers "F.Cu" "F.Mask" "F.Paste")
			(net "GND")
		)
		(pad "CN35" smd circle
			(at -2.500122 23.850092 180)
			(size 0.450088 0.450088)
			(layers "F.Cu" "F.Mask" "F.Paste")
			(net "PVDDCR_CPU1_P1")
		)
		(pad "CN36" smd circle
			(at -1.560068 23.850092 180)
			(size 0.450088 0.450088)
			(layers "F.Cu" "F.Mask" "F.Paste")
			(net "PVDDCR_CPU1_P1")
		)
		(pad "CN40" smd circle
			(at 1.260094 23.850092 180)
			(size 0.450088 0.450088)
			(layers "F.Cu" "F.Mask" "F.Paste")
			(net "PVDDCR_CPU1_P1")
		)
		(pad "CN41" smd circle
			(at 2.199894 23.850092 180)
			(size 0.450088 0.450088)
			(layers "F.Cu" "F.Mask" "F.Paste")
			(net "PVDDCR_CPU1_P1")
		)
		(pad "CN42" smd circle
			(at 3.139948 23.850092 180)
			(size 0.450088 0.450088)
			(layers "F.Cu" "F.Mask" "F.Paste")
			(net "GND")
		)
		(pad "CN43" smd circle
			(at 4.080002 23.850092 180)
			(size 0.450088 0.450088)
			(layers "F.Cu" "F.Mask" "F.Paste")
			(net "P5E_CPU1_P0_TX_DN<12>")
		)
		(pad "CN44" smd circle
			(at 5.020056 23.850092 180)
			(size 0.450088 0.450088)
			(layers "F.Cu" "F.Mask" "F.Paste")
			(net "P5E_CPU1_P0_TX_DP<12>")
		)
		(pad "CN45" smd circle
			(at 5.96011 23.850092 180)
			(size 0.450088 0.450088)
			(layers "F.Cu" "F.Mask" "F.Paste")
			(net "GND")
		)
		(pad "CN46" smd circle
			(at 6.89991 23.850092 180)
			(size 0.450088 0.450088)
			(layers "F.Cu" "F.Mask" "F.Paste")
			(net "P5E_CPU1_P0_TX_DN<9>")
		)
		(pad "CN47" smd circle
			(at 7.839964 23.850092 180)
			(size 0.450088 0.450088)
			(layers "F.Cu" "F.Mask" "F.Paste")
			(net "P5E_CPU1_P0_TX_DP<9>")
		)
		(pad "CN48" smd circle
			(at 8.780018 23.850092 180)
			(size 0.450088 0.450088)
			(layers "F.Cu" "F.Mask" "F.Paste")
			(net "GND")
		)
		(pad "CN49" smd circle
			(at 9.720072 23.850092 180)
			(size 0.450088 0.450088)
			(layers "F.Cu" "F.Mask" "F.Paste")
			(net "P5E_CPU1_P0_TX_DN<3>")
		)
		(pad "CN50" smd circle
			(at 10.659872 23.850092 180)
			(size 0.450088 0.450088)
			(layers "F.Cu" "F.Mask" "F.Paste")
			(net "P5E_CPU1_P0_TX_DP<3>")
		)
		(pad "CN51" smd circle
			(at 11.599926 23.850092 180)
			(size 0.450088 0.450088)
			(layers "F.Cu" "F.Mask" "F.Paste")
			(net "GND")
		)
		(pad "CN52" smd circle
			(at 12.53998 23.850092 180)
			(size 0.450088 0.450088)
			(layers "F.Cu" "F.Mask" "F.Paste")
			(net "P5E_CPU1_P0_TX_DN<0>")
		)
		(pad "CN53" smd circle
			(at 13.480034 23.850092 180)
			(size 0.450088 0.450088)
			(layers "F.Cu" "F.Mask" "F.Paste")
			(net "P5E_CPU1_P0_TX_DP<0>")
		)
		(pad "CN54" smd circle
			(at 14.420088 23.850092 180)
			(size 0.450088 0.450088)
			(layers "F.Cu" "F.Mask" "F.Paste")
			(net "GND")
		)
		(pad "CN55" smd circle
			(at 15.359888 23.850092 180)
			(size 0.450088 0.450088)
			(layers "F.Cu" "F.Mask" "F.Paste")
			(net "M_C_CPU1_SB_DQ<13>")
		)
		(pad "CN56" smd circle
			(at 16.299942 23.850092 180)
			(size 0.450088 0.450088)
			(layers "F.Cu" "F.Mask" "F.Paste")
			(net "GND")
		)
		(pad "CN57" smd circle
			(at 17.239996 23.850092 180)
			(size 0.450088 0.450088)
			(layers "F.Cu" "F.Mask" "F.Paste")
			(net "M_C_CPU1_SB_DQ<14>")
		)
		(pad "CN58" smd circle
			(at 18.18005 23.850092 180)
			(size 0.450088 0.450088)
			(layers "F.Cu" "F.Mask" "F.Paste")
			(net "PVDDIO_P1")
		)
		(pad "CN59" smd circle
			(at 19.120104 23.850092 180)
			(size 0.450088 0.450088)
			(layers "F.Cu" "F.Mask" "F.Paste")
			(net "M_D_CPU1_SB_DQ<13>")
		)
		(pad "CN60" smd circle
			(at 20.059904 23.850092 180)
			(size 0.450088 0.450088)
			(layers "F.Cu" "F.Mask" "F.Paste")
			(net "M_D_CPU1_SB_DQ<14>")
		)
		(pad "CN61" smd circle
			(at 20.999958 23.850092 180)
			(size 0.450088 0.450088)
			(layers "F.Cu" "F.Mask" "F.Paste")
			(net "GND")
		)
		(pad "CN62" smd circle
			(at 21.940012 23.850092 180)
			(size 0.450088 0.450088)
			(layers "F.Cu" "F.Mask" "F.Paste")
			(net "M_B_CPU1_SB_DQ<13>")
		)
		(pad "CN63" smd circle
			(at 22.880066 23.850092 180)
			(size 0.450088 0.450088)
			(layers "F.Cu" "F.Mask" "F.Paste")
			(net "GND")
		)
		(pad "CN64" smd circle
			(at 23.82012 23.850092 180)
			(size 0.450088 0.450088)
			(layers "F.Cu" "F.Mask" "F.Paste")
			(net "M_B_CPU1_SB_DQ<14>")
		)
		(pad "CN65" smd circle
			(at 24.75992 23.850092 180)
			(size 0.450088 0.450088)
			(layers "F.Cu" "F.Mask" "F.Paste")
			(net "PVDDIO_P1")
		)
		(pad "CN66" smd circle
			(at 25.699974 23.850092 180)
			(size 0.450088 0.450088)
			(layers "F.Cu" "F.Mask" "F.Paste")
			(net "M_F_CPU1_SB_DQ<13>")
		)
		(pad "CN67" smd circle
			(at 26.640028 23.850092 180)
			(size 0.450088 0.450088)
			(layers "F.Cu" "F.Mask" "F.Paste")
			(net "M_F_CPU1_SB_DQ<14>")
		)
		(pad "CN68" smd circle
			(at 27.580082 23.850092 180)
			(size 0.450088 0.450088)
			(layers "F.Cu" "F.Mask" "F.Paste")
			(net "GND")
		)
		(pad "CN69" smd circle
			(at 28.519882 23.850092 180)
			(size 0.450088 0.450088)
			(layers "F.Cu" "F.Mask" "F.Paste")
			(net "M_E_CPU1_SB_DQ<13>")
		)
		(pad "CN70" smd circle
			(at 29.459936 23.850092 180)
			(size 0.450088 0.450088)
			(layers "F.Cu" "F.Mask" "F.Paste")
			(net "GND")
		)
		(pad "CN71" smd circle
			(at 30.39999 23.850092 180)
			(size 0.450088 0.450088)
			(layers "F.Cu" "F.Mask" "F.Paste")
			(net "M_E_CPU1_SB_DQ<14>")
		)
		(pad "CN72" smd circle
			(at 31.340044 23.850092 180)
			(size 0.450088 0.450088)
			(layers "F.Cu" "F.Mask" "F.Paste")
			(net "PVDDIO_P1")
		)
		(pad "CN73" smd circle
			(at 32.280098 23.850092 180)
			(size 0.450088 0.450088)
			(layers "F.Cu" "F.Mask" "F.Paste")
			(net "M_A_CPU1_SB_DQ<13>")
		)
		(pad "CN74" smd circle
			(at 33.219898 23.850092 180)
			(size 0.450088 0.450088)
			(layers "F.Cu" "F.Mask" "F.Paste")
			(net "M_A_CPU1_SB_DQ<14>")
		)
		(pad "CN75" smd circle
			(at 34.159952 23.850092 180)
			(size 0.450088 0.450088)
			(layers "F.Cu" "F.Mask" "F.Paste")
			(net "GND")
		)
		(pad "CP2" smd circle
			(at -33.990026 24.660098 180)
			(size 0.450088 0.450088)
			(layers "F.Cu" "F.Mask" "F.Paste")
			(net "M_G_CPU1_SB_DQ<16>")
		)
		(pad "CP3" smd circle
			(at -33.049972 24.660098 180)
			(size 0.450088 0.450088)
			(layers "F.Cu" "F.Mask" "F.Paste")
			(net "GND")
		)
		(pad "CP4" smd circle
			(at -32.109918 24.660098 180)
			(size 0.450088 0.450088)
			(layers "F.Cu" "F.Mask" "F.Paste")
			(net "M_G_CPU1_SB_DQ<15>")
		)
		(pad "CP5" smd circle
			(at -31.170118 24.660098 180)
			(size 0.450088 0.450088)
			(layers "F.Cu" "F.Mask" "F.Paste")
			(net "GND")
		)
		(pad "CP6" smd circle
			(at -30.230064 24.660098 180)
			(size 0.450088 0.450088)
			(layers "F.Cu" "F.Mask" "F.Paste")
			(net "M_K_CPU1_SB_DQ<16>")
		)
		(pad "CP7" smd circle
			(at -29.29001 24.660098 180)
			(size 0.450088 0.450088)
			(layers "F.Cu" "F.Mask" "F.Paste")
			(net "M_K_CPU1_SB_DQ<15>")
		)
		(pad "CP8" smd circle
			(at -28.349956 24.660098 180)
			(size 0.450088 0.450088)
			(layers "F.Cu" "F.Mask" "F.Paste")
			(net "GND")
		)
		(pad "CP9" smd circle
			(at -27.409902 24.660098 180)
			(size 0.450088 0.450088)
			(layers "F.Cu" "F.Mask" "F.Paste")
			(net "M_L_CPU1_SB_DQ<16>")
		)
		(pad "CP10" smd circle
			(at -26.470102 24.660098 180)
			(size 0.450088 0.450088)
			(layers "F.Cu" "F.Mask" "F.Paste")
			(net "GND")
		)
		(pad "CP11" smd circle
			(at -25.530048 24.660098 180)
			(size 0.450088 0.450088)
			(layers "F.Cu" "F.Mask" "F.Paste")
			(net "M_L_CPU1_SB_DQ<15>")
		)
		(pad "CP12" smd circle
			(at -24.589994 24.660098 180)
			(size 0.450088 0.450088)
			(layers "F.Cu" "F.Mask" "F.Paste")
			(net "GND")
		)
		(pad "CP13" smd circle
			(at -23.64994 24.660098 180)
			(size 0.450088 0.450088)
			(layers "F.Cu" "F.Mask" "F.Paste")
			(net "M_H_CPU1_SB_DQ<16>")
		)
		(pad "CP14" smd circle
			(at -22.709886 24.660098 180)
			(size 0.450088 0.450088)
			(layers "F.Cu" "F.Mask" "F.Paste")
			(net "M_H_CPU1_SB_DQ<15>")
		)
		(pad "CP15" smd circle
			(at -21.770086 24.660098 180)
			(size 0.450088 0.450088)
			(layers "F.Cu" "F.Mask" "F.Paste")
			(net "GND")
		)
		(pad "CP16" smd circle
			(at -20.830032 24.660098 180)
			(size 0.450088 0.450088)
			(layers "F.Cu" "F.Mask" "F.Paste")
			(net "M_J_CPU1_SB_DQ<16>")
		)
		(pad "CP17" smd circle
			(at -19.889978 24.660098 180)
			(size 0.450088 0.450088)
			(layers "F.Cu" "F.Mask" "F.Paste")
			(net "GND")
		)
		(pad "CP18" smd circle
			(at -18.949924 24.660098 180)
			(size 0.450088 0.450088)
			(layers "F.Cu" "F.Mask" "F.Paste")
			(net "M_J_CPU1_SB_DQ<15>")
		)
		(pad "CP19" smd circle
			(at -18.010124 24.660098 180)
			(size 0.450088 0.450088)
			(layers "F.Cu" "F.Mask" "F.Paste")
			(net "GND")
		)
		(pad "CP20" smd circle
			(at -17.07007 24.660098 180)
			(size 0.450088 0.450088)
			(layers "F.Cu" "F.Mask" "F.Paste")
			(net "M_I_CPU1_SB_DQ<16>")
		)
		(pad "CP21" smd circle
			(at -16.130016 24.660098 180)
			(size 0.450088 0.450088)
			(layers "F.Cu" "F.Mask" "F.Paste")
			(net "M_I_CPU1_SB_DQ<15>")
		)
		(pad "CP22" smd circle
			(at -15.189962 24.660098 180)
			(size 0.450088 0.450088)
			(layers "F.Cu" "F.Mask" "F.Paste")
			(net "GND")
		)
		(pad "CP23" smd circle
			(at -14.249908 24.660098 180)
			(size 0.450088 0.450088)
			(layers "F.Cu" "F.Mask" "F.Paste")
			(net "PVDDCR_CPU1_P1")
		)
		(pad "CP24" smd circle
			(at -13.310108 24.660098 180)
			(size 0.450088 0.450088)
			(layers "F.Cu" "F.Mask" "F.Paste")
			(net "PVDDCR_CPU1_P1")
		)
		(pad "CP25" smd circle
			(at -12.370054 24.660098 180)
			(size 0.450088 0.450088)
			(layers "F.Cu" "F.Mask" "F.Paste")
			(net "GND")
		)
		(pad "CP26" smd circle
			(at -11.43 24.660098 180)
			(size 0.450088 0.450088)
			(layers "F.Cu" "F.Mask" "F.Paste")
			(net "PVDDCR_CPU1_P1")
		)
		(pad "CP27" smd circle
			(at -10.489946 24.660098 180)
			(size 0.450088 0.450088)
			(layers "F.Cu" "F.Mask" "F.Paste")
			(net "PVDDCR_CPU1_P1")
		)
		(pad "CP28" smd circle
			(at -9.549892 24.660098 180)
			(size 0.450088 0.450088)
			(layers "F.Cu" "F.Mask" "F.Paste")
			(net "GND")
		)
		(pad "CP29" smd circle
			(at -8.610092 24.660098 180)
			(size 0.450088 0.450088)
			(layers "F.Cu" "F.Mask" "F.Paste")
			(net "PVDDCR_CPU1_P1")
		)
		(pad "CP30" smd circle
			(at -7.670038 24.660098 180)
			(size 0.450088 0.450088)
			(layers "F.Cu" "F.Mask" "F.Paste")
			(net "PVDDCR_CPU1_P1")
		)
		(pad "CP31" smd circle
			(at -6.729984 24.660098 180)
			(size 0.450088 0.450088)
			(layers "F.Cu" "F.Mask" "F.Paste")
			(net "GND")
		)
		(pad "CP32" smd circle
			(at -5.78993 24.660098 180)
			(size 0.450088 0.450088)
			(layers "F.Cu" "F.Mask" "F.Paste")
			(net "PVDDCR_CPU1_P1")
		)
		(pad "CP33" smd circle
			(at -4.849876 24.660098 180)
			(size 0.450088 0.450088)
			(layers "F.Cu" "F.Mask" "F.Paste")
			(net "PVDDCR_CPU1_P1")
		)
		(pad "CP34" smd circle
			(at -3.910076 24.660098 180)
			(size 0.450088 0.450088)
			(layers "F.Cu" "F.Mask" "F.Paste")
			(net "GND")
		)
		(pad "CP35" smd circle
			(at -2.970022 24.660098 180)
			(size 0.450088 0.450088)
			(layers "F.Cu" "F.Mask" "F.Paste")
			(net "P5E_CPU1_P2_RX_DP<1>")
		)
		(pad "CP36" smd circle
			(at -2.029968 24.660098 180)
			(size 0.450088 0.450088)
			(layers "F.Cu" "F.Mask" "F.Paste")
			(net "P5E_CPU1_P2_RX_DN<1>")
		)
		(pad "CP37" smd circle
			(at -1.089914 24.660098 180)
			(size 0.450088 0.450088)
			(layers "F.Cu" "F.Mask" "F.Paste")
			(net "GND")
		)
		(pad "CP39" smd circle
			(at 0.78994 24.660098 180)
			(size 0.450088 0.450088)
			(layers "F.Cu" "F.Mask" "F.Paste")
			(net "GND")
		)
		(pad "CP40" smd circle
			(at 1.729994 24.660098 180)
			(size 0.450088 0.450088)
			(layers "F.Cu" "F.Mask" "F.Paste")
			(net "P5E_CPU1_P0_TX_DN<14>")
		)
		(pad "CP41" smd circle
			(at 2.670048 24.660098 180)
			(size 0.450088 0.450088)
			(layers "F.Cu" "F.Mask" "F.Paste")
			(net "P5E_CPU1_P0_TX_DP<14>")
		)
		(pad "CP42" smd circle
			(at 3.610102 24.660098 180)
			(size 0.450088 0.450088)
			(layers "F.Cu" "F.Mask" "F.Paste")
			(net "GND")
		)
		(pad "CP43" smd circle
			(at 4.549902 24.660098 180)
			(size 0.450088 0.450088)
			(layers "F.Cu" "F.Mask" "F.Paste")
			(net "PVDDCR_CPU1_P1")
		)
		(pad "CP44" smd circle
			(at 5.489956 24.660098 180)
			(size 0.450088 0.450088)
			(layers "F.Cu" "F.Mask" "F.Paste")
			(net "PVDDCR_CPU1_P1")
		)
		(pad "CP45" smd circle
			(at 6.43001 24.660098 180)
			(size 0.450088 0.450088)
			(layers "F.Cu" "F.Mask" "F.Paste")
			(net "GND")
		)
		(pad "CP46" smd circle
			(at 7.370064 24.660098 180)
			(size 0.450088 0.450088)
			(layers "F.Cu" "F.Mask" "F.Paste")
			(net "PVDDCR_CPU1_P1")
		)
		(pad "CP47" smd circle
			(at 8.310118 24.660098 180)
			(size 0.450088 0.450088)
			(layers "F.Cu" "F.Mask" "F.Paste")
			(net "PVDDCR_CPU1_P1")
		)
		(pad "CP48" smd circle
			(at 9.249918 24.660098 180)
			(size 0.450088 0.450088)
			(layers "F.Cu" "F.Mask" "F.Paste")
			(net "GND")
		)
		(pad "CP49" smd circle
			(at 10.189972 24.660098 180)
			(size 0.450088 0.450088)
			(layers "F.Cu" "F.Mask" "F.Paste")
			(net "PVDDCR_CPU1_P1")
		)
		(pad "CP50" smd circle
			(at 11.130026 24.660098 180)
			(size 0.450088 0.450088)
			(layers "F.Cu" "F.Mask" "F.Paste")
			(net "PVDDCR_CPU1_P1")
		)
		(pad "CP51" smd circle
			(at 12.07008 24.660098 180)
			(size 0.450088 0.450088)
			(layers "F.Cu" "F.Mask" "F.Paste")
			(net "GND")
		)
		(pad "CP52" smd circle
			(at 13.00988 24.660098 180)
			(size 0.450088 0.450088)
			(layers "F.Cu" "F.Mask" "F.Paste")
			(net "PVDDCR_CPU1_P1")
		)
		(pad "CP53" smd circle
			(at 13.949934 24.660098 180)
			(size 0.450088 0.450088)
			(layers "F.Cu" "F.Mask" "F.Paste")
			(net "PVDDCR_CPU1_P1")
		)
		(pad "CP54" smd circle
			(at 14.889988 24.660098 180)
			(size 0.450088 0.450088)
			(layers "F.Cu" "F.Mask" "F.Paste")
			(net "GND")
		)
		(pad "CP55" smd circle
			(at 15.830042 24.660098 180)
			(size 0.450088 0.450088)
			(layers "F.Cu" "F.Mask" "F.Paste")
			(net "M_C_CPU1_SB_DQ<15>")
		)
		(pad "CP56" smd circle
			(at 16.770096 24.660098 180)
			(size 0.450088 0.450088)
			(layers "F.Cu" "F.Mask" "F.Paste")
			(net "M_C_CPU1_SB_DQ<16>")
		)
		(pad "CP57" smd circle
			(at 17.709896 24.660098 180)
			(size 0.450088 0.450088)
			(layers "F.Cu" "F.Mask" "F.Paste")
			(net "GND")
		)
		(pad "CP58" smd circle
			(at 18.64995 24.660098 180)
			(size 0.450088 0.450088)
			(layers "F.Cu" "F.Mask" "F.Paste")
			(net "M_D_CPU1_SB_DQ<15>")
		)
		(pad "CP59" smd circle
			(at 19.590004 24.660098 180)
			(size 0.450088 0.450088)
			(layers "F.Cu" "F.Mask" "F.Paste")
			(net "GND")
		)
		(pad "CP60" smd circle
			(at 20.530058 24.660098 180)
			(size 0.450088 0.450088)
			(layers "F.Cu" "F.Mask" "F.Paste")
			(net "M_D_CPU1_SB_DQ<16>")
		)
		(pad "CP61" smd circle
			(at 21.470112 24.660098 180)
			(size 0.450088 0.450088)
			(layers "F.Cu" "F.Mask" "F.Paste")
			(net "GND")
		)
		(pad "CP62" smd circle
			(at 22.409912 24.660098 180)
			(size 0.450088 0.450088)
			(layers "F.Cu" "F.Mask" "F.Paste")
			(net "M_B_CPU1_SB_DQ<15>")
		)
		(pad "CP63" smd circle
			(at 23.349966 24.660098 180)
			(size 0.450088 0.450088)
			(layers "F.Cu" "F.Mask" "F.Paste")
			(net "M_B_CPU1_SB_DQ<16>")
		)
		(pad "CP64" smd circle
			(at 24.29002 24.660098 180)
			(size 0.450088 0.450088)
			(layers "F.Cu" "F.Mask" "F.Paste")
			(net "GND")
		)
		(pad "CP65" smd circle
			(at 25.230074 24.660098 180)
			(size 0.450088 0.450088)
			(layers "F.Cu" "F.Mask" "F.Paste")
			(net "M_F_CPU1_SB_DQ<15>")
		)
		(pad "CP66" smd circle
			(at 26.170128 24.660098 180)
			(size 0.450088 0.450088)
			(layers "F.Cu" "F.Mask" "F.Paste")
			(net "GND")
		)
		(pad "CP67" smd circle
			(at 27.109928 24.660098 180)
			(size 0.450088 0.450088)
			(layers "F.Cu" "F.Mask" "F.Paste")
			(net "M_F_CPU1_SB_DQ<16>")
		)
		(pad "CP68" smd circle
			(at 28.049982 24.660098 180)
			(size 0.450088 0.450088)
			(layers "F.Cu" "F.Mask" "F.Paste")
			(net "GND")
		)
		(pad "CP69" smd circle
			(at 28.990036 24.660098 180)
			(size 0.450088 0.450088)
			(layers "F.Cu" "F.Mask" "F.Paste")
			(net "M_E_CPU1_SB_DQ<15>")
		)
		(pad "CP70" smd circle
			(at 29.93009 24.660098 180)
			(size 0.450088 0.450088)
			(layers "F.Cu" "F.Mask" "F.Paste")
			(net "M_E_CPU1_SB_DQ<16>")
		)
		(pad "CP71" smd circle
			(at 30.86989 24.660098 180)
			(size 0.450088 0.450088)
			(layers "F.Cu" "F.Mask" "F.Paste")
			(net "GND")
		)
		(pad "CP72" smd circle
			(at 31.809944 24.660098 180)
			(size 0.450088 0.450088)
			(layers "F.Cu" "F.Mask" "F.Paste")
			(net "M_A_CPU1_SB_DQ<15>")
		)
		(pad "CP73" smd circle
			(at 32.749998 24.660098 180)
			(size 0.450088 0.450088)
			(layers "F.Cu" "F.Mask" "F.Paste")
			(net "GND")
		)
		(pad "CP74" smd circle
			(at 33.690052 24.660098 180)
			(size 0.450088 0.450088)
			(layers "F.Cu" "F.Mask" "F.Paste")
			(net "M_A_CPU1_SB_DQ<16>")
		)
		(pad "CR1" smd circle
			(at -34.459926 25.470104 180)
			(size 0.450088 0.450088)
			(layers "F.Cu" "F.Mask" "F.Paste")
			(net "GND")
		)
		(pad "CR2" smd circle
			(at -33.519872 25.470104 180)
			(size 0.450088 0.450088)
			(layers "F.Cu" "F.Mask" "F.Paste")
			(net "M_G_CPU1_SB_DQ<18>")
		)
		(pad "CR3" smd circle
			(at -32.580072 25.470104 180)
			(size 0.450088 0.450088)
			(layers "F.Cu" "F.Mask" "F.Paste")
			(net "M_G_CPU1_SB_DQ<17>")
		)
		(pad "CR4" smd circle
			(at -31.640018 25.470104 180)
			(size 0.450088 0.450088)
			(layers "F.Cu" "F.Mask" "F.Paste")
			(net "GND")
		)
		(pad "CR5" smd circle
			(at -30.699964 25.470104 180)
			(size 0.450088 0.450088)
			(layers "F.Cu" "F.Mask" "F.Paste")
			(net "M_K_CPU1_SB_DQ<18>")
		)
		(pad "CR6" smd circle
			(at -29.75991 25.470104 180)
			(size 0.450088 0.450088)
			(layers "F.Cu" "F.Mask" "F.Paste")
			(net "GND")
		)
		(pad "CR7" smd circle
			(at -28.82011 25.470104 180)
			(size 0.450088 0.450088)
			(layers "F.Cu" "F.Mask" "F.Paste")
			(net "M_K_CPU1_SB_DQ<17>")
		)
		(pad "CR8" smd circle
			(at -27.880056 25.470104 180)
			(size 0.450088 0.450088)
			(layers "F.Cu" "F.Mask" "F.Paste")
			(net "GND")
		)
		(pad "CR9" smd circle
			(at -26.940002 25.470104 180)
			(size 0.450088 0.450088)
			(layers "F.Cu" "F.Mask" "F.Paste")
			(net "M_L_CPU1_SB_DQ<18>")
		)
		(pad "CR10" smd circle
			(at -25.999948 25.470104 180)
			(size 0.450088 0.450088)
			(layers "F.Cu" "F.Mask" "F.Paste")
			(net "M_L_CPU1_SB_DQ<17>")
		)
		(pad "CR11" smd circle
			(at -25.059894 25.470104 180)
			(size 0.450088 0.450088)
			(layers "F.Cu" "F.Mask" "F.Paste")
			(net "GND")
		)
		(pad "CR12" smd circle
			(at -24.120094 25.470104 180)
			(size 0.450088 0.450088)
			(layers "F.Cu" "F.Mask" "F.Paste")
			(net "M_H_CPU1_SB_DQ<18>")
		)
		(pad "CR13" smd circle
			(at -23.18004 25.470104 180)
			(size 0.450088 0.450088)
			(layers "F.Cu" "F.Mask" "F.Paste")
			(net "GND")
		)
		(pad "CR14" smd circle
			(at -22.239986 25.470104 180)
			(size 0.450088 0.450088)
			(layers "F.Cu" "F.Mask" "F.Paste")
			(net "M_H_CPU1_SB_DQ<17>")
		)
		(pad "CR15" smd circle
			(at -21.299932 25.470104 180)
			(size 0.450088 0.450088)
			(layers "F.Cu" "F.Mask" "F.Paste")
			(net "GND")
		)
		(pad "CR16" smd circle
			(at -20.359878 25.470104 180)
			(size 0.450088 0.450088)
			(layers "F.Cu" "F.Mask" "F.Paste")
			(net "M_J_CPU1_SB_DQ<18>")
		)
		(pad "CR17" smd circle
			(at -19.420078 25.470104 180)
			(size 0.450088 0.450088)
			(layers "F.Cu" "F.Mask" "F.Paste")
			(net "M_J_CPU1_SB_DQ<17>")
		)
		(pad "CR18" smd circle
			(at -18.480024 25.470104 180)
			(size 0.450088 0.450088)
			(layers "F.Cu" "F.Mask" "F.Paste")
			(net "GND")
		)
		(pad "CR19" smd circle
			(at -17.53997 25.470104 180)
			(size 0.450088 0.450088)
			(layers "F.Cu" "F.Mask" "F.Paste")
			(net "M_I_CPU1_SB_DQ<18>")
		)
		(pad "CR20" smd circle
			(at -16.599916 25.470104 180)
			(size 0.450088 0.450088)
			(layers "F.Cu" "F.Mask" "F.Paste")
			(net "GND")
		)
		(pad "CR21" smd circle
			(at -15.660116 25.470104 180)
			(size 0.450088 0.450088)
			(layers "F.Cu" "F.Mask" "F.Paste")
			(net "M_I_CPU1_SB_DQ<17>")
		)
		(pad "CR22" smd circle
			(at -14.720062 25.470104 180)
			(size 0.450088 0.450088)
			(layers "F.Cu" "F.Mask" "F.Paste")
			(net "GND")
		)
		(pad "CR23" smd circle
			(at -13.780008 25.470104 180)
			(size 0.450088 0.450088)
			(layers "F.Cu" "F.Mask" "F.Paste")
			(net "P5E_CPU1_P2_RX_DP<14>")
		)
		(pad "CR24" smd circle
			(at -12.839954 25.470104 180)
			(size 0.450088 0.450088)
			(layers "F.Cu" "F.Mask" "F.Paste")
			(net "P5E_CPU1_P2_RX_DN<14>")
		)
		(pad "CR25" smd circle
			(at -11.8999 25.470104 180)
			(size 0.450088 0.450088)
			(layers "F.Cu" "F.Mask" "F.Paste")
			(net "GND")
		)
		(pad "CR26" smd circle
			(at -10.9601 25.470104 180)
			(size 0.450088 0.450088)
			(layers "F.Cu" "F.Mask" "F.Paste")
			(net "P5E_CPU1_P2_RX_DP<11>")
		)
		(pad "CR27" smd circle
			(at -10.020046 25.470104 180)
			(size 0.450088 0.450088)
			(layers "F.Cu" "F.Mask" "F.Paste")
			(net "P5E_CPU1_P2_RX_DN<11>")
		)
		(pad "CR28" smd circle
			(at -9.079992 25.470104 180)
			(size 0.450088 0.450088)
			(layers "F.Cu" "F.Mask" "F.Paste")
			(net "GND")
		)
		(pad "CR29" smd circle
			(at -8.139938 25.470104 180)
			(size 0.450088 0.450088)
			(layers "F.Cu" "F.Mask" "F.Paste")
			(net "P5E_CPU1_P2_RX_DP<8>")
		)
		(pad "CR30" smd circle
			(at -7.199884 25.470104 180)
			(size 0.450088 0.450088)
			(layers "F.Cu" "F.Mask" "F.Paste")
			(net "P5E_CPU1_P2_RX_DN<8>")
		)
		(pad "CR31" smd circle
			(at -6.260084 25.470104 180)
			(size 0.450088 0.450088)
			(layers "F.Cu" "F.Mask" "F.Paste")
			(net "GND")
		)
		(pad "CR32" smd circle
			(at -5.32003 25.470104 180)
			(size 0.450088 0.450088)
			(layers "F.Cu" "F.Mask" "F.Paste")
			(net "P5E_CPU1_P2_RX_DP<5>")
		)
		(pad "CR33" smd circle
			(at -4.379976 25.470104 180)
			(size 0.450088 0.450088)
			(layers "F.Cu" "F.Mask" "F.Paste")
			(net "P5E_CPU1_P2_RX_DN<5>")
		)
		(pad "CR34" smd circle
			(at -3.439922 25.470104 180)
			(size 0.450088 0.450088)
			(layers "F.Cu" "F.Mask" "F.Paste")
			(net "GND")
		)
		(pad "CR35" smd circle
			(at -2.500122 25.470104 180)
			(size 0.450088 0.450088)
			(layers "F.Cu" "F.Mask" "F.Paste")
			(net "GND")
		)
		(pad "CR36" smd circle
			(at -1.560068 25.470104 180)
			(size 0.450088 0.450088)
			(layers "F.Cu" "F.Mask" "F.Paste")
			(net "GND")
		)
		(pad "CR40" smd circle
			(at 1.260094 25.470104 180)
			(size 0.450088 0.450088)
			(layers "F.Cu" "F.Mask" "F.Paste")
			(net "GND")
		)
		(pad "CR41" smd circle
			(at 2.199894 25.470104 180)
			(size 0.450088 0.450088)
			(layers "F.Cu" "F.Mask" "F.Paste")
			(net "GND")
		)
		(pad "CR42" smd circle
			(at 3.139948 25.470104 180)
			(size 0.450088 0.450088)
			(layers "F.Cu" "F.Mask" "F.Paste")
			(net "GND")
		)
		(pad "CR43" smd circle
			(at 4.080002 25.470104 180)
			(size 0.450088 0.450088)
			(layers "F.Cu" "F.Mask" "F.Paste")
			(net "P5E_CPU1_P0_TX_DN<10>")
		)
		(pad "CR44" smd circle
			(at 5.020056 25.470104 180)
			(size 0.450088 0.450088)
			(layers "F.Cu" "F.Mask" "F.Paste")
			(net "P5E_CPU1_P0_TX_DP<10>")
		)
		(pad "CR45" smd circle
			(at 5.96011 25.470104 180)
			(size 0.450088 0.450088)
			(layers "F.Cu" "F.Mask" "F.Paste")
			(net "GND")
		)
		(pad "CR46" smd circle
			(at 6.89991 25.470104 180)
			(size 0.450088 0.450088)
			(layers "F.Cu" "F.Mask" "F.Paste")
			(net "P5E_CPU1_P0_TX_DN<7>")
		)
		(pad "CR47" smd circle
			(at 7.839964 25.470104 180)
			(size 0.450088 0.450088)
			(layers "F.Cu" "F.Mask" "F.Paste")
			(net "P5E_CPU1_P0_TX_DP<7>")
		)
		(pad "CR48" smd circle
			(at 8.780018 25.470104 180)
			(size 0.450088 0.450088)
			(layers "F.Cu" "F.Mask" "F.Paste")
			(net "GND")
		)
		(pad "CR49" smd circle
			(at 9.720072 25.470104 180)
			(size 0.450088 0.450088)
			(layers "F.Cu" "F.Mask" "F.Paste")
			(net "P5E_CPU1_P0_TX_DN<4>")
		)
		(pad "CR50" smd circle
			(at 10.659872 25.470104 180)
			(size 0.450088 0.450088)
			(layers "F.Cu" "F.Mask" "F.Paste")
			(net "P5E_CPU1_P0_TX_DP<4>")
		)
		(pad "CR51" smd circle
			(at 11.599926 25.470104 180)
			(size 0.450088 0.450088)
			(layers "F.Cu" "F.Mask" "F.Paste")
			(net "GND")
		)
		(pad "CR52" smd circle
			(at 12.53998 25.470104 180)
			(size 0.450088 0.450088)
			(layers "F.Cu" "F.Mask" "F.Paste")
			(net "P5E_CPU1_P0_TX_DN<1>")
		)
		(pad "CR53" smd circle
			(at 13.480034 25.470104 180)
			(size 0.450088 0.450088)
			(layers "F.Cu" "F.Mask" "F.Paste")
			(net "P5E_CPU1_P0_TX_DP<1>")
		)
		(pad "CR54" smd circle
			(at 14.420088 25.470104 180)
			(size 0.450088 0.450088)
			(layers "F.Cu" "F.Mask" "F.Paste")
			(net "GND")
		)
		(pad "CR55" smd circle
			(at 15.359888 25.470104 180)
			(size 0.450088 0.450088)
			(layers "F.Cu" "F.Mask" "F.Paste")
			(net "M_C_CPU1_SB_DQ<17>")
		)
		(pad "CR56" smd circle
			(at 16.299942 25.470104 180)
			(size 0.450088 0.450088)
			(layers "F.Cu" "F.Mask" "F.Paste")
			(net "GND")
		)
		(pad "CR57" smd circle
			(at 17.239996 25.470104 180)
			(size 0.450088 0.450088)
			(layers "F.Cu" "F.Mask" "F.Paste")
			(net "M_C_CPU1_SB_DQ<18>")
		)
		(pad "CR58" smd circle
			(at 18.18005 25.470104 180)
			(size 0.450088 0.450088)
			(layers "F.Cu" "F.Mask" "F.Paste")
			(net "GND")
		)
		(pad "CR59" smd circle
			(at 19.120104 25.470104 180)
			(size 0.450088 0.450088)
			(layers "F.Cu" "F.Mask" "F.Paste")
			(net "M_D_CPU1_SB_DQ<17>")
		)
		(pad "CR60" smd circle
			(at 20.059904 25.470104 180)
			(size 0.450088 0.450088)
			(layers "F.Cu" "F.Mask" "F.Paste")
			(net "M_D_CPU1_SB_DQ<18>")
		)
		(pad "CR61" smd circle
			(at 20.999958 25.470104 180)
			(size 0.450088 0.450088)
			(layers "F.Cu" "F.Mask" "F.Paste")
			(net "GND")
		)
		(pad "CR62" smd circle
			(at 21.940012 25.470104 180)
			(size 0.450088 0.450088)
			(layers "F.Cu" "F.Mask" "F.Paste")
			(net "M_B_CPU1_SB_DQ<17>")
		)
		(pad "CR63" smd circle
			(at 22.880066 25.470104 180)
			(size 0.450088 0.450088)
			(layers "F.Cu" "F.Mask" "F.Paste")
			(net "GND")
		)
		(pad "CR64" smd circle
			(at 23.82012 25.470104 180)
			(size 0.450088 0.450088)
			(layers "F.Cu" "F.Mask" "F.Paste")
			(net "M_B_CPU1_SB_DQ<18>")
		)
		(pad "CR65" smd circle
			(at 24.75992 25.470104 180)
			(size 0.450088 0.450088)
			(layers "F.Cu" "F.Mask" "F.Paste")
			(net "GND")
		)
		(pad "CR66" smd circle
			(at 25.699974 25.470104 180)
			(size 0.450088 0.450088)
			(layers "F.Cu" "F.Mask" "F.Paste")
			(net "M_F_CPU1_SB_DQ<17>")
		)
		(pad "CR67" smd circle
			(at 26.640028 25.470104 180)
			(size 0.450088 0.450088)
			(layers "F.Cu" "F.Mask" "F.Paste")
			(net "M_F_CPU1_SB_DQ<18>")
		)
		(pad "CR68" smd circle
			(at 27.580082 25.470104 180)
			(size 0.450088 0.450088)
			(layers "F.Cu" "F.Mask" "F.Paste")
			(net "GND")
		)
		(pad "CR69" smd circle
			(at 28.519882 25.470104 180)
			(size 0.450088 0.450088)
			(layers "F.Cu" "F.Mask" "F.Paste")
			(net "M_E_CPU1_SB_DQ<17>")
		)
		(pad "CR70" smd circle
			(at 29.459936 25.470104 180)
			(size 0.450088 0.450088)
			(layers "F.Cu" "F.Mask" "F.Paste")
			(net "GND")
		)
		(pad "CR71" smd circle
			(at 30.39999 25.470104 180)
			(size 0.450088 0.450088)
			(layers "F.Cu" "F.Mask" "F.Paste")
			(net "M_E_CPU1_SB_DQ<18>")
		)
		(pad "CR72" smd circle
			(at 31.340044 25.470104 180)
			(size 0.450088 0.450088)
			(layers "F.Cu" "F.Mask" "F.Paste")
			(net "GND")
		)
		(pad "CR73" smd circle
			(at 32.280098 25.470104 180)
			(size 0.450088 0.450088)
			(layers "F.Cu" "F.Mask" "F.Paste")
			(net "M_A_CPU1_SB_DQ<17>")
		)
		(pad "CR74" smd circle
			(at 33.219898 25.470104 180)
			(size 0.450088 0.450088)
			(layers "F.Cu" "F.Mask" "F.Paste")
			(net "M_A_CPU1_SB_DQ<18>")
		)
		(pad "CR75" smd circle
			(at 34.159952 25.470104 180)
			(size 0.450088 0.450088)
			(layers "F.Cu" "F.Mask" "F.Paste")
			(net "GND")
		)
		(pad "CT2" smd circle
			(at -33.990026 26.28011 180)
			(size 0.450088 0.450088)
			(layers "F.Cu" "F.Mask" "F.Paste")
			(net "M_G_CPU1_SB_DQS_DP<2>")
		)
		(pad "CT3" smd circle
			(at -33.049972 26.28011 180)
			(size 0.450088 0.450088)
			(layers "F.Cu" "F.Mask" "F.Paste")
			(net "GND")
		)
		(pad "CT4" smd circle
			(at -32.109918 26.28011 180)
			(size 0.450088 0.450088)
			(layers "F.Cu" "F.Mask" "F.Paste")
			(net "M_G_CPU1_SB_DQ<19>")
		)
		(pad "CT5" smd circle
			(at -31.170118 26.28011 180)
			(size 0.450088 0.450088)
			(layers "F.Cu" "F.Mask" "F.Paste")
			(net "PVDD11_S3_P1")
		)
		(pad "CT6" smd circle
			(at -30.230064 26.28011 180)
			(size 0.450088 0.450088)
			(layers "F.Cu" "F.Mask" "F.Paste")
			(net "M_K_CPU1_SB_DQS_DP<2>")
		)
		(pad "CT7" smd circle
			(at -29.29001 26.28011 180)
			(size 0.450088 0.450088)
			(layers "F.Cu" "F.Mask" "F.Paste")
			(net "M_K_CPU1_SB_DQ<19>")
		)
		(pad "CT8" smd circle
			(at -28.349956 26.28011 180)
			(size 0.450088 0.450088)
			(layers "F.Cu" "F.Mask" "F.Paste")
			(net "GND")
		)
		(pad "CT9" smd circle
			(at -27.409902 26.28011 180)
			(size 0.450088 0.450088)
			(layers "F.Cu" "F.Mask" "F.Paste")
			(net "M_L_CPU1_SB_DQS_DP<2>")
		)
		(pad "CT10" smd circle
			(at -26.470102 26.28011 180)
			(size 0.450088 0.450088)
			(layers "F.Cu" "F.Mask" "F.Paste")
			(net "GND")
		)
		(pad "CT11" smd circle
			(at -25.530048 26.28011 180)
			(size 0.450088 0.450088)
			(layers "F.Cu" "F.Mask" "F.Paste")
			(net "M_L_CPU1_SB_DQ<19>")
		)
		(pad "CT12" smd circle
			(at -24.589994 26.28011 180)
			(size 0.450088 0.450088)
			(layers "F.Cu" "F.Mask" "F.Paste")
			(net "PVDD11_S3_P1")
		)
		(pad "CT13" smd circle
			(at -23.64994 26.28011 180)
			(size 0.450088 0.450088)
			(layers "F.Cu" "F.Mask" "F.Paste")
			(net "M_H_CPU1_SB_DQS_DP<2>")
		)
		(pad "CT14" smd circle
			(at -22.709886 26.28011 180)
			(size 0.450088 0.450088)
			(layers "F.Cu" "F.Mask" "F.Paste")
			(net "M_H_CPU1_SB_DQ<19>")
		)
		(pad "CT15" smd circle
			(at -21.770086 26.28011 180)
			(size 0.450088 0.450088)
			(layers "F.Cu" "F.Mask" "F.Paste")
			(net "GND")
		)
		(pad "CT16" smd circle
			(at -20.830032 26.28011 180)
			(size 0.450088 0.450088)
			(layers "F.Cu" "F.Mask" "F.Paste")
			(net "M_J_CPU1_SB_DQS_DP<2>")
		)
		(pad "CT17" smd circle
			(at -19.889978 26.28011 180)
			(size 0.450088 0.450088)
			(layers "F.Cu" "F.Mask" "F.Paste")
			(net "GND")
		)
		(pad "CT18" smd circle
			(at -18.949924 26.28011 180)
			(size 0.450088 0.450088)
			(layers "F.Cu" "F.Mask" "F.Paste")
			(net "M_J_CPU1_SB_DQ<19>")
		)
		(pad "CT19" smd circle
			(at -18.010124 26.28011 180)
			(size 0.450088 0.450088)
			(layers "F.Cu" "F.Mask" "F.Paste")
			(net "PVDD11_S3_P1")
		)
		(pad "CT20" smd circle
			(at -17.07007 26.28011 180)
			(size 0.450088 0.450088)
			(layers "F.Cu" "F.Mask" "F.Paste")
			(net "M_I_CPU1_SB_DQS_DP<2>")
		)
		(pad "CT21" smd circle
			(at -16.130016 26.28011 180)
			(size 0.450088 0.450088)
			(layers "F.Cu" "F.Mask" "F.Paste")
			(net "M_I_CPU1_SB_DQ<19>")
		)
		(pad "CT22" smd circle
			(at -15.189962 26.28011 180)
			(size 0.450088 0.450088)
			(layers "F.Cu" "F.Mask" "F.Paste")
			(net "PVDD11_S3_P1")
		)
		(pad "CT23" smd circle
			(at -14.249908 26.28011 180)
			(size 0.450088 0.450088)
			(layers "F.Cu" "F.Mask" "F.Paste")
			(net "GND")
		)
		(pad "CT24" smd circle
			(at -13.310108 26.28011 180)
			(size 0.450088 0.450088)
			(layers "F.Cu" "F.Mask" "F.Paste")
			(net "GND")
		)
		(pad "CT25" smd circle
			(at -12.370054 26.28011 180)
			(size 0.450088 0.450088)
			(layers "F.Cu" "F.Mask" "F.Paste")
			(net "GND")
		)
		(pad "CT26" smd circle
			(at -11.43 26.28011 180)
			(size 0.450088 0.450088)
			(layers "F.Cu" "F.Mask" "F.Paste")
			(net "GND")
		)
		(pad "CT27" smd circle
			(at -10.489946 26.28011 180)
			(size 0.450088 0.450088)
			(layers "F.Cu" "F.Mask" "F.Paste")
			(net "GND")
		)
		(pad "CT28" smd circle
			(at -9.549892 26.28011 180)
			(size 0.450088 0.450088)
			(layers "F.Cu" "F.Mask" "F.Paste")
			(net "GND")
		)
		(pad "CT29" smd circle
			(at -8.610092 26.28011 180)
			(size 0.450088 0.450088)
			(layers "F.Cu" "F.Mask" "F.Paste")
			(net "GND")
		)
		(pad "CT30" smd circle
			(at -7.670038 26.28011 180)
			(size 0.450088 0.450088)
			(layers "F.Cu" "F.Mask" "F.Paste")
			(net "GND")
		)
		(pad "CT31" smd circle
			(at -6.729984 26.28011 180)
			(size 0.450088 0.450088)
			(layers "F.Cu" "F.Mask" "F.Paste")
			(net "GND")
		)
		(pad "CT32" smd circle
			(at -5.78993 26.28011 180)
			(size 0.450088 0.450088)
			(layers "F.Cu" "F.Mask" "F.Paste")
			(net "GND")
		)
		(pad "CT33" smd circle
			(at -4.849876 26.28011 180)
			(size 0.450088 0.450088)
			(layers "F.Cu" "F.Mask" "F.Paste")
			(net "GND")
		)
		(pad "CT34" smd circle
			(at -3.910076 26.28011 180)
			(size 0.450088 0.450088)
			(layers "F.Cu" "F.Mask" "F.Paste")
			(net "GND")
		)
		(pad "CT35" smd circle
			(at -2.970022 26.28011 180)
			(size 0.450088 0.450088)
			(layers "F.Cu" "F.Mask" "F.Paste")
			(net "P5E_CPU1_P2_RX_DP<2>")
		)
		(pad "CT36" smd circle
			(at -2.029968 26.28011 180)
			(size 0.450088 0.450088)
			(layers "F.Cu" "F.Mask" "F.Paste")
			(net "P5E_CPU1_P2_RX_DN<2>")
		)
		(pad "CT37" smd circle
			(at -1.089914 26.28011 180)
			(size 0.450088 0.450088)
			(layers "F.Cu" "F.Mask" "F.Paste")
			(net "GND")
		)
		(pad "CT39" smd circle
			(at 0.78994 26.28011 180)
			(size 0.450088 0.450088)
			(layers "F.Cu" "F.Mask" "F.Paste")
			(net "GND")
		)
		(pad "CT40" smd circle
			(at 1.729994 26.28011 180)
			(size 0.450088 0.450088)
			(layers "F.Cu" "F.Mask" "F.Paste")
			(net "P5E_CPU1_P0_TX_DN<13>")
		)
		(pad "CT41" smd circle
			(at 2.670048 26.28011 180)
			(size 0.450088 0.450088)
			(layers "F.Cu" "F.Mask" "F.Paste")
			(net "P5E_CPU1_P0_TX_DP<13>")
		)
		(pad "CT42" smd circle
			(at 3.610102 26.28011 180)
			(size 0.450088 0.450088)
			(layers "F.Cu" "F.Mask" "F.Paste")
			(net "GND")
		)
		(pad "CT43" smd circle
			(at 4.549902 26.28011 180)
			(size 0.450088 0.450088)
			(layers "F.Cu" "F.Mask" "F.Paste")
			(net "GND")
		)
		(pad "CT44" smd circle
			(at 5.489956 26.28011 180)
			(size 0.450088 0.450088)
			(layers "F.Cu" "F.Mask" "F.Paste")
			(net "GND")
		)
		(pad "CT45" smd circle
			(at 6.43001 26.28011 180)
			(size 0.450088 0.450088)
			(layers "F.Cu" "F.Mask" "F.Paste")
			(net "GND")
		)
		(pad "CT46" smd circle
			(at 7.370064 26.28011 180)
			(size 0.450088 0.450088)
			(layers "F.Cu" "F.Mask" "F.Paste")
			(net "GND")
		)
		(pad "CT47" smd circle
			(at 8.310118 26.28011 180)
			(size 0.450088 0.450088)
			(layers "F.Cu" "F.Mask" "F.Paste")
			(net "GND")
		)
		(pad "CT48" smd circle
			(at 9.249918 26.28011 180)
			(size 0.450088 0.450088)
			(layers "F.Cu" "F.Mask" "F.Paste")
			(net "GND")
		)
		(pad "CT49" smd circle
			(at 10.189972 26.28011 180)
			(size 0.450088 0.450088)
			(layers "F.Cu" "F.Mask" "F.Paste")
			(net "GND")
		)
		(pad "CT50" smd circle
			(at 11.130026 26.28011 180)
			(size 0.450088 0.450088)
			(layers "F.Cu" "F.Mask" "F.Paste")
			(net "GND")
		)
		(pad "CT51" smd circle
			(at 12.07008 26.28011 180)
			(size 0.450088 0.450088)
			(layers "F.Cu" "F.Mask" "F.Paste")
			(net "GND")
		)
		(pad "CT52" smd circle
			(at 13.00988 26.28011 180)
			(size 0.450088 0.450088)
			(layers "F.Cu" "F.Mask" "F.Paste")
			(net "GND")
		)
		(pad "CT53" smd circle
			(at 13.949934 26.28011 180)
			(size 0.450088 0.450088)
			(layers "F.Cu" "F.Mask" "F.Paste")
			(net "GND")
		)
		(pad "CT54" smd circle
			(at 14.889988 26.28011 180)
			(size 0.450088 0.450088)
			(layers "F.Cu" "F.Mask" "F.Paste")
			(net "PVDDIO_P1")
		)
		(pad "CT55" smd circle
			(at 15.830042 26.28011 180)
			(size 0.450088 0.450088)
			(layers "F.Cu" "F.Mask" "F.Paste")
			(net "M_C_CPU1_SB_DQ<19>")
		)
		(pad "CT56" smd circle
			(at 16.770096 26.28011 180)
			(size 0.450088 0.450088)
			(layers "F.Cu" "F.Mask" "F.Paste")
			(net "M_C_CPU1_SB_DQS_DP<2>")
		)
		(pad "CT57" smd circle
			(at 17.709896 26.28011 180)
			(size 0.450088 0.450088)
			(layers "F.Cu" "F.Mask" "F.Paste")
			(net "PVDDIO_P1")
		)
		(pad "CT58" smd circle
			(at 18.64995 26.28011 180)
			(size 0.450088 0.450088)
			(layers "F.Cu" "F.Mask" "F.Paste")
			(net "M_D_CPU1_SB_DQ<19>")
		)
		(pad "CT59" smd circle
			(at 19.590004 26.28011 180)
			(size 0.450088 0.450088)
			(layers "F.Cu" "F.Mask" "F.Paste")
			(net "GND")
		)
		(pad "CT60" smd circle
			(at 20.530058 26.28011 180)
			(size 0.450088 0.450088)
			(layers "F.Cu" "F.Mask" "F.Paste")
			(net "M_D_CPU1_SB_DQS_DP<2>")
		)
		(pad "CT61" smd circle
			(at 21.470112 26.28011 180)
			(size 0.450088 0.450088)
			(layers "F.Cu" "F.Mask" "F.Paste")
			(net "GND")
		)
		(pad "CT62" smd circle
			(at 22.409912 26.28011 180)
			(size 0.450088 0.450088)
			(layers "F.Cu" "F.Mask" "F.Paste")
			(net "M_B_CPU1_SB_DQ<19>")
		)
		(pad "CT63" smd circle
			(at 23.349966 26.28011 180)
			(size 0.450088 0.450088)
			(layers "F.Cu" "F.Mask" "F.Paste")
			(net "M_B_CPU1_SB_DQS_DP<2>")
		)
		(pad "CT64" smd circle
			(at 24.29002 26.28011 180)
			(size 0.450088 0.450088)
			(layers "F.Cu" "F.Mask" "F.Paste")
			(net "PVDDIO_P1")
		)
		(pad "CT65" smd circle
			(at 25.230074 26.28011 180)
			(size 0.450088 0.450088)
			(layers "F.Cu" "F.Mask" "F.Paste")
			(net "M_F_CPU1_SB_DQ<19>")
		)
		(pad "CT66" smd circle
			(at 26.170128 26.28011 180)
			(size 0.450088 0.450088)
			(layers "F.Cu" "F.Mask" "F.Paste")
			(net "GND")
		)
		(pad "CT67" smd circle
			(at 27.109928 26.28011 180)
			(size 0.450088 0.450088)
			(layers "F.Cu" "F.Mask" "F.Paste")
			(net "M_F_CPU1_SB_DQS_DP<2>")
		)
		(pad "CT68" smd circle
			(at 28.049982 26.28011 180)
			(size 0.450088 0.450088)
			(layers "F.Cu" "F.Mask" "F.Paste")
			(net "GND")
		)
		(pad "CT69" smd circle
			(at 28.990036 26.28011 180)
			(size 0.450088 0.450088)
			(layers "F.Cu" "F.Mask" "F.Paste")
			(net "M_E_CPU1_SB_DQ<19>")
		)
		(pad "CT70" smd circle
			(at 29.93009 26.28011 180)
			(size 0.450088 0.450088)
			(layers "F.Cu" "F.Mask" "F.Paste")
			(net "M_E_CPU1_SB_DQS_DP<2>")
		)
		(pad "CT71" smd circle
			(at 30.86989 26.28011 180)
			(size 0.450088 0.450088)
			(layers "F.Cu" "F.Mask" "F.Paste")
			(net "PVDDIO_P1")
		)
		(pad "CT72" smd circle
			(at 31.809944 26.28011 180)
			(size 0.450088 0.450088)
			(layers "F.Cu" "F.Mask" "F.Paste")
			(net "M_A_CPU1_SB_DQ<19>")
		)
		(pad "CT73" smd circle
			(at 32.749998 26.28011 180)
			(size 0.450088 0.450088)
			(layers "F.Cu" "F.Mask" "F.Paste")
			(net "GND")
		)
		(pad "CT74" smd circle
			(at 33.690052 26.28011 180)
			(size 0.450088 0.450088)
			(layers "F.Cu" "F.Mask" "F.Paste")
			(net "M_A_CPU1_SB_DQS_DP<2>")
		)
		(pad "CU1" smd circle
			(at -34.459926 27.090116 180)
			(size 0.450088 0.450088)
			(layers "F.Cu" "F.Mask" "F.Paste")
			(net "GND")
		)
		(pad "CU2" smd circle
			(at -33.519872 27.090116 180)
			(size 0.450088 0.450088)
			(layers "F.Cu" "F.Mask" "F.Paste")
			(net "M_G_CPU1_SB_DQS_DN<2>")
		)
		(pad "CU3" smd circle
			(at -32.580072 27.090116 180)
			(size 0.450088 0.450088)
			(layers "F.Cu" "F.Mask" "F.Paste")
			(net "M_G_CPU1_SB_DQS_DN<7>")
		)
		(pad "CU4" smd circle
			(at -31.640018 27.090116 180)
			(size 0.450088 0.450088)
			(layers "F.Cu" "F.Mask" "F.Paste")
			(net "GND")
		)
		(pad "CU5" smd circle
			(at -30.699964 27.090116 180)
			(size 0.450088 0.450088)
			(layers "F.Cu" "F.Mask" "F.Paste")
			(net "M_K_CPU1_SB_DQS_DN<2>")
		)
		(pad "CU6" smd circle
			(at -29.75991 27.090116 180)
			(size 0.450088 0.450088)
			(layers "F.Cu" "F.Mask" "F.Paste")
			(net "GND")
		)
		(pad "CU7" smd circle
			(at -28.82011 27.090116 180)
			(size 0.450088 0.450088)
			(layers "F.Cu" "F.Mask" "F.Paste")
			(net "M_K_CPU1_SB_DQS_DN<7>")
		)
		(pad "CU8" smd circle
			(at -27.880056 27.090116 180)
			(size 0.450088 0.450088)
			(layers "F.Cu" "F.Mask" "F.Paste")
			(net "GND")
		)
		(pad "CU9" smd circle
			(at -26.940002 27.090116 180)
			(size 0.450088 0.450088)
			(layers "F.Cu" "F.Mask" "F.Paste")
			(net "M_L_CPU1_SB_DQS_DN<2>")
		)
		(pad "CU10" smd circle
			(at -25.999948 27.090116 180)
			(size 0.450088 0.450088)
			(layers "F.Cu" "F.Mask" "F.Paste")
			(net "M_L_CPU1_SB_DQS_DN<7>")
		)
		(pad "CU11" smd circle
			(at -25.059894 27.090116 180)
			(size 0.450088 0.450088)
			(layers "F.Cu" "F.Mask" "F.Paste")
			(net "GND")
		)
		(pad "CU12" smd circle
			(at -24.120094 27.090116 180)
			(size 0.450088 0.450088)
			(layers "F.Cu" "F.Mask" "F.Paste")
			(net "M_H_CPU1_SB_DQS_DN<2>")
		)
		(pad "CU13" smd circle
			(at -23.18004 27.090116 180)
			(size 0.450088 0.450088)
			(layers "F.Cu" "F.Mask" "F.Paste")
			(net "GND")
		)
		(pad "CU14" smd circle
			(at -22.239986 27.090116 180)
			(size 0.450088 0.450088)
			(layers "F.Cu" "F.Mask" "F.Paste")
			(net "M_H_CPU1_SB_DQS_DN<7>")
		)
		(pad "CU15" smd circle
			(at -21.299932 27.090116 180)
			(size 0.450088 0.450088)
			(layers "F.Cu" "F.Mask" "F.Paste")
			(net "GND")
		)
		(pad "CU16" smd circle
			(at -20.359878 27.090116 180)
			(size 0.450088 0.450088)
			(layers "F.Cu" "F.Mask" "F.Paste")
			(net "M_J_CPU1_SB_DQS_DN<2>")
		)
		(pad "CU17" smd circle
			(at -19.420078 27.090116 180)
			(size 0.450088 0.450088)
			(layers "F.Cu" "F.Mask" "F.Paste")
			(net "M_J_CPU1_SB_DQS_DN<7>")
		)
		(pad "CU18" smd circle
			(at -18.480024 27.090116 180)
			(size 0.450088 0.450088)
			(layers "F.Cu" "F.Mask" "F.Paste")
			(net "GND")
		)
		(pad "CU19" smd circle
			(at -17.53997 27.090116 180)
			(size 0.450088 0.450088)
			(layers "F.Cu" "F.Mask" "F.Paste")
			(net "M_I_CPU1_SB_DQS_DN<2>")
		)
		(pad "CU20" smd circle
			(at -16.599916 27.090116 180)
			(size 0.450088 0.450088)
			(layers "F.Cu" "F.Mask" "F.Paste")
			(net "GND")
		)
		(pad "CU21" smd circle
			(at -15.660116 27.090116 180)
			(size 0.450088 0.450088)
			(layers "F.Cu" "F.Mask" "F.Paste")
			(net "M_I_CPU1_SB_DQS_DN<7>")
		)
		(pad "CU22" smd circle
			(at -14.720062 27.090116 180)
			(size 0.450088 0.450088)
			(layers "F.Cu" "F.Mask" "F.Paste")
			(net "GND")
		)
		(pad "CU23" smd circle
			(at -13.780008 27.090116 180)
			(size 0.450088 0.450088)
			(layers "F.Cu" "F.Mask" "F.Paste")
			(net "P5E_CPU1_P3_RX_DP<15>")
		)
		(pad "CU24" smd circle
			(at -12.839954 27.090116 180)
			(size 0.450088 0.450088)
			(layers "F.Cu" "F.Mask" "F.Paste")
			(net "P5E_CPU1_P3_RX_DN<15>")
		)
		(pad "CU25" smd circle
			(at -11.8999 27.090116 180)
			(size 0.450088 0.450088)
			(layers "F.Cu" "F.Mask" "F.Paste")
			(net "GND")
		)
		(pad "CU26" smd circle
			(at -10.9601 27.090116 180)
			(size 0.450088 0.450088)
			(layers "F.Cu" "F.Mask" "F.Paste")
			(net "P5E_CPU1_P2_RX_DP<10>")
		)
		(pad "CU27" smd circle
			(at -10.020046 27.090116 180)
			(size 0.450088 0.450088)
			(layers "F.Cu" "F.Mask" "F.Paste")
			(net "P5E_CPU1_P2_RX_DN<10>")
		)
		(pad "CU28" smd circle
			(at -9.079992 27.090116 180)
			(size 0.450088 0.450088)
			(layers "F.Cu" "F.Mask" "F.Paste")
			(net "GND")
		)
		(pad "CU29" smd circle
			(at -8.139938 27.090116 180)
			(size 0.450088 0.450088)
			(layers "F.Cu" "F.Mask" "F.Paste")
			(net "P5E_CPU1_P2_RX_DP<7>")
		)
		(pad "CU30" smd circle
			(at -7.199884 27.090116 180)
			(size 0.450088 0.450088)
			(layers "F.Cu" "F.Mask" "F.Paste")
			(net "P5E_CPU1_P2_RX_DN<7>")
		)
		(pad "CU31" smd circle
			(at -6.260084 27.090116 180)
			(size 0.450088 0.450088)
			(layers "F.Cu" "F.Mask" "F.Paste")
			(net "GND")
		)
		(pad "CU32" smd circle
			(at -5.32003 27.090116 180)
			(size 0.450088 0.450088)
			(layers "F.Cu" "F.Mask" "F.Paste")
			(net "P5E_CPU1_P2_RX_DP<4>")
		)
		(pad "CU33" smd circle
			(at -4.379976 27.090116 180)
			(size 0.450088 0.450088)
			(layers "F.Cu" "F.Mask" "F.Paste")
			(net "P5E_CPU1_P2_RX_DN<4>")
		)
		(pad "CU34" smd circle
			(at -3.439922 27.090116 180)
			(size 0.450088 0.450088)
			(layers "F.Cu" "F.Mask" "F.Paste")
			(net "GND")
		)
		(pad "CU35" smd circle
			(at -2.500122 27.090116 180)
			(size 0.450088 0.450088)
			(layers "F.Cu" "F.Mask" "F.Paste")
			(net "PVDDCR_CPU1_P1")
		)
		(pad "CU36" smd circle
			(at -1.560068 27.090116 180)
			(size 0.450088 0.450088)
			(layers "F.Cu" "F.Mask" "F.Paste")
			(net "PVDDCR_CPU1_P1")
		)
		(pad "CU40" smd circle
			(at 1.260094 27.090116 180)
			(size 0.450088 0.450088)
			(layers "F.Cu" "F.Mask" "F.Paste")
			(net "PVDDCR_CPU1_P1")
		)
		(pad "CU41" smd circle
			(at 2.199894 27.090116 180)
			(size 0.450088 0.450088)
			(layers "F.Cu" "F.Mask" "F.Paste")
			(net "PVDDCR_CPU1_P1")
		)
		(pad "CU42" smd circle
			(at 3.139948 27.090116 180)
			(size 0.450088 0.450088)
			(layers "F.Cu" "F.Mask" "F.Paste")
			(net "GND")
		)
		(pad "CU43" smd circle
			(at 4.080002 27.090116 180)
			(size 0.450088 0.450088)
			(layers "F.Cu" "F.Mask" "F.Paste")
			(net "P5E_CPU1_P0_TX_DN<11>")
		)
		(pad "CU44" smd circle
			(at 5.020056 27.090116 180)
			(size 0.450088 0.450088)
			(layers "F.Cu" "F.Mask" "F.Paste")
			(net "P5E_CPU1_P0_TX_DP<11>")
		)
		(pad "CU45" smd circle
			(at 5.96011 27.090116 180)
			(size 0.450088 0.450088)
			(layers "F.Cu" "F.Mask" "F.Paste")
			(net "GND")
		)
		(pad "CU46" smd circle
			(at 6.89991 27.090116 180)
			(size 0.450088 0.450088)
			(layers "F.Cu" "F.Mask" "F.Paste")
			(net "P5E_CPU1_P0_TX_DN<8>")
		)
		(pad "CU47" smd circle
			(at 7.839964 27.090116 180)
			(size 0.450088 0.450088)
			(layers "F.Cu" "F.Mask" "F.Paste")
			(net "P5E_CPU1_P0_TX_DP<8>")
		)
		(pad "CU48" smd circle
			(at 8.780018 27.090116 180)
			(size 0.450088 0.450088)
			(layers "F.Cu" "F.Mask" "F.Paste")
			(net "GND")
		)
		(pad "CU49" smd circle
			(at 9.720072 27.090116 180)
			(size 0.450088 0.450088)
			(layers "F.Cu" "F.Mask" "F.Paste")
			(net "P5E_CPU1_P0_TX_DN<5>")
		)
		(pad "CU50" smd circle
			(at 10.659872 27.090116 180)
			(size 0.450088 0.450088)
			(layers "F.Cu" "F.Mask" "F.Paste")
			(net "P5E_CPU1_P0_TX_DP<5>")
		)
		(pad "CU51" smd circle
			(at 11.599926 27.090116 180)
			(size 0.450088 0.450088)
			(layers "F.Cu" "F.Mask" "F.Paste")
			(net "GND")
		)
		(pad "CU52" smd circle
			(at 12.53998 27.090116 180)
			(size 0.450088 0.450088)
			(layers "F.Cu" "F.Mask" "F.Paste")
			(net "P5E_CPU1_P1_TX_DN<0>")
		)
		(pad "CU53" smd circle
			(at 13.480034 27.090116 180)
			(size 0.450088 0.450088)
			(layers "F.Cu" "F.Mask" "F.Paste")
			(net "P5E_CPU1_P1_TX_DP<0>")
		)
		(pad "CU54" smd circle
			(at 14.420088 27.090116 180)
			(size 0.450088 0.450088)
			(layers "F.Cu" "F.Mask" "F.Paste")
			(net "GND")
		)
		(pad "CU55" smd circle
			(at 15.359888 27.090116 180)
			(size 0.450088 0.450088)
			(layers "F.Cu" "F.Mask" "F.Paste")
			(net "M_C_CPU1_SB_DQS_DN<7>")
		)
		(pad "CU56" smd circle
			(at 16.299942 27.090116 180)
			(size 0.450088 0.450088)
			(layers "F.Cu" "F.Mask" "F.Paste")
			(net "GND")
		)
		(pad "CU57" smd circle
			(at 17.239996 27.090116 180)
			(size 0.450088 0.450088)
			(layers "F.Cu" "F.Mask" "F.Paste")
			(net "M_C_CPU1_SB_DQS_DN<2>")
		)
		(pad "CU58" smd circle
			(at 18.18005 27.090116 180)
			(size 0.450088 0.450088)
			(layers "F.Cu" "F.Mask" "F.Paste")
			(net "GND")
		)
		(pad "CU59" smd circle
			(at 19.120104 27.090116 180)
			(size 0.450088 0.450088)
			(layers "F.Cu" "F.Mask" "F.Paste")
			(net "M_D_CPU1_SB_DQS_DN<7>")
		)
		(pad "CU60" smd circle
			(at 20.059904 27.090116 180)
			(size 0.450088 0.450088)
			(layers "F.Cu" "F.Mask" "F.Paste")
			(net "M_D_CPU1_SB_DQS_DN<2>")
		)
		(pad "CU61" smd circle
			(at 20.999958 27.090116 180)
			(size 0.450088 0.450088)
			(layers "F.Cu" "F.Mask" "F.Paste")
			(net "GND")
		)
		(pad "CU62" smd circle
			(at 21.940012 27.090116 180)
			(size 0.450088 0.450088)
			(layers "F.Cu" "F.Mask" "F.Paste")
			(net "M_B_CPU1_SB_DQS_DN<7>")
		)
		(pad "CU63" smd circle
			(at 22.880066 27.090116 180)
			(size 0.450088 0.450088)
			(layers "F.Cu" "F.Mask" "F.Paste")
			(net "GND")
		)
		(pad "CU64" smd circle
			(at 23.82012 27.090116 180)
			(size 0.450088 0.450088)
			(layers "F.Cu" "F.Mask" "F.Paste")
			(net "M_B_CPU1_SB_DQS_DN<2>")
		)
		(pad "CU65" smd circle
			(at 24.75992 27.090116 180)
			(size 0.450088 0.450088)
			(layers "F.Cu" "F.Mask" "F.Paste")
			(net "GND")
		)
		(pad "CU66" smd circle
			(at 25.699974 27.090116 180)
			(size 0.450088 0.450088)
			(layers "F.Cu" "F.Mask" "F.Paste")
			(net "M_F_CPU1_SB_DQS_DN<7>")
		)
		(pad "CU67" smd circle
			(at 26.640028 27.090116 180)
			(size 0.450088 0.450088)
			(layers "F.Cu" "F.Mask" "F.Paste")
			(net "M_F_CPU1_SB_DQS_DN<2>")
		)
		(pad "CU68" smd circle
			(at 27.580082 27.090116 180)
			(size 0.450088 0.450088)
			(layers "F.Cu" "F.Mask" "F.Paste")
			(net "GND")
		)
		(pad "CU69" smd circle
			(at 28.519882 27.090116 180)
			(size 0.450088 0.450088)
			(layers "F.Cu" "F.Mask" "F.Paste")
			(net "M_E_CPU1_SB_DQS_DN<7>")
		)
		(pad "CU70" smd circle
			(at 29.459936 27.090116 180)
			(size 0.450088 0.450088)
			(layers "F.Cu" "F.Mask" "F.Paste")
			(net "GND")
		)
		(pad "CU71" smd circle
			(at 30.39999 27.090116 180)
			(size 0.450088 0.450088)
			(layers "F.Cu" "F.Mask" "F.Paste")
			(net "M_E_CPU1_SB_DQS_DN<2>")
		)
		(pad "CU72" smd circle
			(at 31.340044 27.090116 180)
			(size 0.450088 0.450088)
			(layers "F.Cu" "F.Mask" "F.Paste")
			(net "GND")
		)
		(pad "CU73" smd circle
			(at 32.280098 27.090116 180)
			(size 0.450088 0.450088)
			(layers "F.Cu" "F.Mask" "F.Paste")
			(net "M_A_CPU1_SB_DQS_DN<7>")
		)
		(pad "CU74" smd circle
			(at 33.219898 27.090116 180)
			(size 0.450088 0.450088)
			(layers "F.Cu" "F.Mask" "F.Paste")
			(net "M_A_CPU1_SB_DQS_DN<2>")
		)
		(pad "CU75" smd circle
			(at 34.159952 27.090116 180)
			(size 0.450088 0.450088)
			(layers "F.Cu" "F.Mask" "F.Paste")
			(net "GND")
		)
		(pad "CV2" smd circle
			(at -33.990026 27.900122 180)
			(size 0.450088 0.450088)
			(layers "F.Cu" "F.Mask" "F.Paste")
			(net "M_G_CPU1_SB_DQ<20>")
		)
		(pad "CV3" smd circle
			(at -33.049972 27.900122 180)
			(size 0.450088 0.450088)
			(layers "F.Cu" "F.Mask" "F.Paste")
			(net "GND")
		)
		(pad "CV4" smd circle
			(at -32.109918 27.900122 180)
			(size 0.450088 0.450088)
			(layers "F.Cu" "F.Mask" "F.Paste")
			(net "M_G_CPU1_SB_DQS_DP<7>")
		)
		(pad "CV5" smd circle
			(at -31.170118 27.900122 180)
			(size 0.450088 0.450088)
			(layers "F.Cu" "F.Mask" "F.Paste")
			(net "GND")
		)
		(pad "CV6" smd circle
			(at -30.230064 27.900122 180)
			(size 0.450088 0.450088)
			(layers "F.Cu" "F.Mask" "F.Paste")
			(net "M_K_CPU1_SB_DQ<20>")
		)
		(pad "CV7" smd circle
			(at -29.29001 27.900122 180)
			(size 0.450088 0.450088)
			(layers "F.Cu" "F.Mask" "F.Paste")
			(net "M_K_CPU1_SB_DQS_DP<7>")
		)
		(pad "CV8" smd circle
			(at -28.349956 27.900122 180)
			(size 0.450088 0.450088)
			(layers "F.Cu" "F.Mask" "F.Paste")
			(net "GND")
		)
		(pad "CV9" smd circle
			(at -27.409902 27.900122 180)
			(size 0.450088 0.450088)
			(layers "F.Cu" "F.Mask" "F.Paste")
			(net "M_L_CPU1_SB_DQ<20>")
		)
		(pad "CV10" smd circle
			(at -26.470102 27.900122 180)
			(size 0.450088 0.450088)
			(layers "F.Cu" "F.Mask" "F.Paste")
			(net "GND")
		)
		(pad "CV11" smd circle
			(at -25.530048 27.900122 180)
			(size 0.450088 0.450088)
			(layers "F.Cu" "F.Mask" "F.Paste")
			(net "M_L_CPU1_SB_DQS_DP<7>")
		)
		(pad "CV12" smd circle
			(at -24.589994 27.900122 180)
			(size 0.450088 0.450088)
			(layers "F.Cu" "F.Mask" "F.Paste")
			(net "GND")
		)
		(pad "CV13" smd circle
			(at -23.64994 27.900122 180)
			(size 0.450088 0.450088)
			(layers "F.Cu" "F.Mask" "F.Paste")
			(net "M_H_CPU1_SB_DQ<20>")
		)
		(pad "CV14" smd circle
			(at -22.709886 27.900122 180)
			(size 0.450088 0.450088)
			(layers "F.Cu" "F.Mask" "F.Paste")
			(net "M_H_CPU1_SB_DQS_DP<7>")
		)
		(pad "CV15" smd circle
			(at -21.770086 27.900122 180)
			(size 0.450088 0.450088)
			(layers "F.Cu" "F.Mask" "F.Paste")
			(net "GND")
		)
		(pad "CV16" smd circle
			(at -20.830032 27.900122 180)
			(size 0.450088 0.450088)
			(layers "F.Cu" "F.Mask" "F.Paste")
			(net "M_J_CPU1_SB_DQ<20>")
		)
		(pad "CV17" smd circle
			(at -19.889978 27.900122 180)
			(size 0.450088 0.450088)
			(layers "F.Cu" "F.Mask" "F.Paste")
			(net "GND")
		)
		(pad "CV18" smd circle
			(at -18.949924 27.900122 180)
			(size 0.450088 0.450088)
			(layers "F.Cu" "F.Mask" "F.Paste")
			(net "M_J_CPU1_SB_DQS_DP<7>")
		)
		(pad "CV19" smd circle
			(at -18.010124 27.900122 180)
			(size 0.450088 0.450088)
			(layers "F.Cu" "F.Mask" "F.Paste")
			(net "GND")
		)
		(pad "CV20" smd circle
			(at -17.07007 27.900122 180)
			(size 0.450088 0.450088)
			(layers "F.Cu" "F.Mask" "F.Paste")
			(net "M_I_CPU1_SB_DQ<20>")
		)
		(pad "CV21" smd circle
			(at -16.130016 27.900122 180)
			(size 0.450088 0.450088)
			(layers "F.Cu" "F.Mask" "F.Paste")
			(net "M_I_CPU1_SB_DQS_DP<7>")
		)
		(pad "CV22" smd circle
			(at -15.189962 27.900122 180)
			(size 0.450088 0.450088)
			(layers "F.Cu" "F.Mask" "F.Paste")
			(net "GND")
		)
		(pad "CV23" smd circle
			(at -14.249908 27.900122 180)
			(size 0.450088 0.450088)
			(layers "F.Cu" "F.Mask" "F.Paste")
			(net "PVDDCR_CPU1_P1")
		)
		(pad "CV24" smd circle
			(at -13.310108 27.900122 180)
			(size 0.450088 0.450088)
			(layers "F.Cu" "F.Mask" "F.Paste")
			(net "PVDDCR_CPU1_P1")
		)
		(pad "CV25" smd circle
			(at -12.370054 27.900122 180)
			(size 0.450088 0.450088)
			(layers "F.Cu" "F.Mask" "F.Paste")
			(net "GND")
		)
		(pad "CV26" smd circle
			(at -11.43 27.900122 180)
			(size 0.450088 0.450088)
			(layers "F.Cu" "F.Mask" "F.Paste")
			(net "PVDDCR_CPU1_P1")
		)
		(pad "CV27" smd circle
			(at -10.489946 27.900122 180)
			(size 0.450088 0.450088)
			(layers "F.Cu" "F.Mask" "F.Paste")
			(net "PVDDCR_CPU1_P1")
		)
		(pad "CV28" smd circle
			(at -9.549892 27.900122 180)
			(size 0.450088 0.450088)
			(layers "F.Cu" "F.Mask" "F.Paste")
			(net "GND")
		)
		(pad "CV29" smd circle
			(at -8.610092 27.900122 180)
			(size 0.450088 0.450088)
			(layers "F.Cu" "F.Mask" "F.Paste")
			(net "PVDDCR_CPU1_P1")
		)
		(pad "CV30" smd circle
			(at -7.670038 27.900122 180)
			(size 0.450088 0.450088)
			(layers "F.Cu" "F.Mask" "F.Paste")
			(net "PVDDCR_CPU1_P1")
		)
		(pad "CV31" smd circle
			(at -6.729984 27.900122 180)
			(size 0.450088 0.450088)
			(layers "F.Cu" "F.Mask" "F.Paste")
			(net "GND")
		)
		(pad "CV32" smd circle
			(at -5.78993 27.900122 180)
			(size 0.450088 0.450088)
			(layers "F.Cu" "F.Mask" "F.Paste")
			(net "PVDDCR_CPU1_P1")
		)
		(pad "CV33" smd circle
			(at -4.849876 27.900122 180)
			(size 0.450088 0.450088)
			(layers "F.Cu" "F.Mask" "F.Paste")
			(net "PVDDCR_CPU1_P1")
		)
		(pad "CV34" smd circle
			(at -3.910076 27.900122 180)
			(size 0.450088 0.450088)
			(layers "F.Cu" "F.Mask" "F.Paste")
			(net "GND")
		)
		(pad "CV35" smd circle
			(at -2.970022 27.900122 180)
			(size 0.450088 0.450088)
			(layers "F.Cu" "F.Mask" "F.Paste")
			(net "P5E_CPU1_P3_RX_DP<0>")
		)
		(pad "CV36" smd circle
			(at -2.029968 27.900122 180)
			(size 0.450088 0.450088)
			(layers "F.Cu" "F.Mask" "F.Paste")
			(net "P5E_CPU1_P3_RX_DN<0>")
		)
		(pad "CV37" smd circle
			(at -1.089914 27.900122 180)
			(size 0.450088 0.450088)
			(layers "F.Cu" "F.Mask" "F.Paste")
			(net "GND")
		)
		(pad "CV39" smd circle
			(at 0.78994 27.900122 180)
			(size 0.450088 0.450088)
			(layers "F.Cu" "F.Mask" "F.Paste")
			(net "GND")
		)
		(pad "CV40" smd circle
			(at 1.729994 27.900122 180)
			(size 0.450088 0.450088)
			(layers "F.Cu" "F.Mask" "F.Paste")
			(net "P5E_CPU1_P1_TX_DN<15>")
		)
		(pad "CV41" smd circle
			(at 2.670048 27.900122 180)
			(size 0.450088 0.450088)
			(layers "F.Cu" "F.Mask" "F.Paste")
			(net "P5E_CPU1_P1_TX_DP<15>")
		)
		(pad "CV42" smd circle
			(at 3.610102 27.900122 180)
			(size 0.450088 0.450088)
			(layers "F.Cu" "F.Mask" "F.Paste")
			(net "GND")
		)
		(pad "CV43" smd circle
			(at 4.549902 27.900122 180)
			(size 0.450088 0.450088)
			(layers "F.Cu" "F.Mask" "F.Paste")
			(net "PVDDCR_CPU1_P1")
		)
		(pad "CV44" smd circle
			(at 5.489956 27.900122 180)
			(size 0.450088 0.450088)
			(layers "F.Cu" "F.Mask" "F.Paste")
			(net "PVDDCR_CPU1_P1")
		)
		(pad "CV45" smd circle
			(at 6.43001 27.900122 180)
			(size 0.450088 0.450088)
			(layers "F.Cu" "F.Mask" "F.Paste")
			(net "GND")
		)
		(pad "CV46" smd circle
			(at 7.370064 27.900122 180)
			(size 0.450088 0.450088)
			(layers "F.Cu" "F.Mask" "F.Paste")
			(net "PVDDCR_CPU1_P1")
		)
		(pad "CV47" smd circle
			(at 8.310118 27.900122 180)
			(size 0.450088 0.450088)
			(layers "F.Cu" "F.Mask" "F.Paste")
			(net "PVDDCR_CPU1_P1")
		)
		(pad "CV48" smd circle
			(at 9.249918 27.900122 180)
			(size 0.450088 0.450088)
			(layers "F.Cu" "F.Mask" "F.Paste")
			(net "GND")
		)
		(pad "CV49" smd circle
			(at 10.189972 27.900122 180)
			(size 0.450088 0.450088)
			(layers "F.Cu" "F.Mask" "F.Paste")
			(net "PVDDCR_CPU1_P1")
		)
		(pad "CV50" smd circle
			(at 11.130026 27.900122 180)
			(size 0.450088 0.450088)
			(layers "F.Cu" "F.Mask" "F.Paste")
			(net "PVDDCR_CPU1_P1")
		)
		(pad "CV51" smd circle
			(at 12.07008 27.900122 180)
			(size 0.450088 0.450088)
			(layers "F.Cu" "F.Mask" "F.Paste")
			(net "GND")
		)
		(pad "CV52" smd circle
			(at 13.00988 27.900122 180)
			(size 0.450088 0.450088)
			(layers "F.Cu" "F.Mask" "F.Paste")
			(net "PVDDCR_CPU1_P1")
		)
		(pad "CV53" smd circle
			(at 13.949934 27.900122 180)
			(size 0.450088 0.450088)
			(layers "F.Cu" "F.Mask" "F.Paste")
			(net "PVDDCR_CPU1_P1")
		)
		(pad "CV54" smd circle
			(at 14.889988 27.900122 180)
			(size 0.450088 0.450088)
			(layers "F.Cu" "F.Mask" "F.Paste")
			(net "GND")
		)
		(pad "CV55" smd circle
			(at 15.830042 27.900122 180)
			(size 0.450088 0.450088)
			(layers "F.Cu" "F.Mask" "F.Paste")
			(net "M_C_CPU1_SB_DQS_DP<7>")
		)
		(pad "CV56" smd circle
			(at 16.770096 27.900122 180)
			(size 0.450088 0.450088)
			(layers "F.Cu" "F.Mask" "F.Paste")
			(net "M_C_CPU1_SB_DQ<20>")
		)
		(pad "CV57" smd circle
			(at 17.709896 27.900122 180)
			(size 0.450088 0.450088)
			(layers "F.Cu" "F.Mask" "F.Paste")
			(net "GND")
		)
		(pad "CV58" smd circle
			(at 18.64995 27.900122 180)
			(size 0.450088 0.450088)
			(layers "F.Cu" "F.Mask" "F.Paste")
			(net "M_D_CPU1_SB_DQS_DP<7>")
		)
		(pad "CV59" smd circle
			(at 19.590004 27.900122 180)
			(size 0.450088 0.450088)
			(layers "F.Cu" "F.Mask" "F.Paste")
			(net "GND")
		)
		(pad "CV60" smd circle
			(at 20.530058 27.900122 180)
			(size 0.450088 0.450088)
			(layers "F.Cu" "F.Mask" "F.Paste")
			(net "M_D_CPU1_SB_DQ<20>")
		)
		(pad "CV61" smd circle
			(at 21.470112 27.900122 180)
			(size 0.450088 0.450088)
			(layers "F.Cu" "F.Mask" "F.Paste")
			(net "GND")
		)
		(pad "CV62" smd circle
			(at 22.409912 27.900122 180)
			(size 0.450088 0.450088)
			(layers "F.Cu" "F.Mask" "F.Paste")
			(net "M_B_CPU1_SB_DQS_DP<7>")
		)
		(pad "CV63" smd circle
			(at 23.349966 27.900122 180)
			(size 0.450088 0.450088)
			(layers "F.Cu" "F.Mask" "F.Paste")
			(net "M_B_CPU1_SB_DQ<20>")
		)
		(pad "CV64" smd circle
			(at 24.29002 27.900122 180)
			(size 0.450088 0.450088)
			(layers "F.Cu" "F.Mask" "F.Paste")
			(net "GND")
		)
		(pad "CV65" smd circle
			(at 25.230074 27.900122 180)
			(size 0.450088 0.450088)
			(layers "F.Cu" "F.Mask" "F.Paste")
			(net "M_F_CPU1_SB_DQS_DP<7>")
		)
		(pad "CV66" smd circle
			(at 26.170128 27.900122 180)
			(size 0.450088 0.450088)
			(layers "F.Cu" "F.Mask" "F.Paste")
			(net "GND")
		)
		(pad "CV67" smd circle
			(at 27.109928 27.900122 180)
			(size 0.450088 0.450088)
			(layers "F.Cu" "F.Mask" "F.Paste")
			(net "M_F_CPU1_SB_DQ<20>")
		)
		(pad "CV68" smd circle
			(at 28.049982 27.900122 180)
			(size 0.450088 0.450088)
			(layers "F.Cu" "F.Mask" "F.Paste")
			(net "GND")
		)
		(pad "CV69" smd circle
			(at 28.990036 27.900122 180)
			(size 0.450088 0.450088)
			(layers "F.Cu" "F.Mask" "F.Paste")
			(net "M_E_CPU1_SB_DQS_DP<7>")
		)
		(pad "CV70" smd circle
			(at 29.93009 27.900122 180)
			(size 0.450088 0.450088)
			(layers "F.Cu" "F.Mask" "F.Paste")
			(net "M_E_CPU1_SB_DQ<20>")
		)
		(pad "CV71" smd circle
			(at 30.86989 27.900122 180)
			(size 0.450088 0.450088)
			(layers "F.Cu" "F.Mask" "F.Paste")
			(net "GND")
		)
		(pad "CV72" smd circle
			(at 31.809944 27.900122 180)
			(size 0.450088 0.450088)
			(layers "F.Cu" "F.Mask" "F.Paste")
			(net "M_A_CPU1_SB_DQS_DP<7>")
		)
		(pad "CV73" smd circle
			(at 32.749998 27.900122 180)
			(size 0.450088 0.450088)
			(layers "F.Cu" "F.Mask" "F.Paste")
			(net "GND")
		)
		(pad "CV74" smd circle
			(at 33.690052 27.900122 180)
			(size 0.450088 0.450088)
			(layers "F.Cu" "F.Mask" "F.Paste")
			(net "M_A_CPU1_SB_DQ<20>")
		)
		(pad "CW1" smd circle
			(at -34.459926 28.710128 180)
			(size 0.450088 0.450088)
			(layers "F.Cu" "F.Mask" "F.Paste")
			(net "GND")
		)
		(pad "CW2" smd circle
			(at -33.519872 28.710128 180)
			(size 0.450088 0.450088)
			(layers "F.Cu" "F.Mask" "F.Paste")
			(net "M_G_CPU1_SB_DQ<22>")
		)
		(pad "CW3" smd circle
			(at -32.580072 28.710128 180)
			(size 0.450088 0.450088)
			(layers "F.Cu" "F.Mask" "F.Paste")
			(net "M_G_CPU1_SB_DQ<21>")
		)
		(pad "CW4" smd circle
			(at -31.640018 28.710128 180)
			(size 0.450088 0.450088)
			(layers "F.Cu" "F.Mask" "F.Paste")
			(net "PVDD11_S3_P1")
		)
		(pad "CW5" smd circle
			(at -30.699964 28.710128 180)
			(size 0.450088 0.450088)
			(layers "F.Cu" "F.Mask" "F.Paste")
			(net "M_K_CPU1_SB_DQ<22>")
		)
		(pad "CW6" smd circle
			(at -29.75991 28.710128 180)
			(size 0.450088 0.450088)
			(layers "F.Cu" "F.Mask" "F.Paste")
			(net "GND")
		)
		(pad "CW7" smd circle
			(at -28.82011 28.710128 180)
			(size 0.450088 0.450088)
			(layers "F.Cu" "F.Mask" "F.Paste")
			(net "M_K_CPU1_SB_DQ<21>")
		)
		(pad "CW8" smd circle
			(at -27.880056 28.710128 180)
			(size 0.450088 0.450088)
			(layers "F.Cu" "F.Mask" "F.Paste")
			(net "GND")
		)
		(pad "CW9" smd circle
			(at -26.940002 28.710128 180)
			(size 0.450088 0.450088)
			(layers "F.Cu" "F.Mask" "F.Paste")
			(net "M_L_CPU1_SB_DQ<22>")
		)
		(pad "CW10" smd circle
			(at -25.999948 28.710128 180)
			(size 0.450088 0.450088)
			(layers "F.Cu" "F.Mask" "F.Paste")
			(net "M_L_CPU1_SB_DQ<21>")
		)
		(pad "CW11" smd circle
			(at -25.059894 28.710128 180)
			(size 0.450088 0.450088)
			(layers "F.Cu" "F.Mask" "F.Paste")
			(net "PVDD11_S3_P1")
		)
		(pad "CW12" smd circle
			(at -24.120094 28.710128 180)
			(size 0.450088 0.450088)
			(layers "F.Cu" "F.Mask" "F.Paste")
			(net "M_H_CPU1_SB_DQ<22>")
		)
		(pad "CW13" smd circle
			(at -23.18004 28.710128 180)
			(size 0.450088 0.450088)
			(layers "F.Cu" "F.Mask" "F.Paste")
			(net "GND")
		)
		(pad "CW14" smd circle
			(at -22.239986 28.710128 180)
			(size 0.450088 0.450088)
			(layers "F.Cu" "F.Mask" "F.Paste")
			(net "M_H_CPU1_SB_DQ<21>")
		)
		(pad "CW15" smd circle
			(at -21.299932 28.710128 180)
			(size 0.450088 0.450088)
			(layers "F.Cu" "F.Mask" "F.Paste")
			(net "GND")
		)
		(pad "CW16" smd circle
			(at -20.359878 28.710128 180)
			(size 0.450088 0.450088)
			(layers "F.Cu" "F.Mask" "F.Paste")
			(net "M_J_CPU1_SB_DQ<22>")
		)
		(pad "CW17" smd circle
			(at -19.420078 28.710128 180)
			(size 0.450088 0.450088)
			(layers "F.Cu" "F.Mask" "F.Paste")
			(net "M_J_CPU1_SB_DQ<21>")
		)
		(pad "CW18" smd circle
			(at -18.480024 28.710128 180)
			(size 0.450088 0.450088)
			(layers "F.Cu" "F.Mask" "F.Paste")
			(net "PVDD11_S3_P1")
		)
		(pad "CW19" smd circle
			(at -17.53997 28.710128 180)
			(size 0.450088 0.450088)
			(layers "F.Cu" "F.Mask" "F.Paste")
			(net "M_I_CPU1_SB_DQ<22>")
		)
		(pad "CW20" smd circle
			(at -16.599916 28.710128 180)
			(size 0.450088 0.450088)
			(layers "F.Cu" "F.Mask" "F.Paste")
			(net "GND")
		)
		(pad "CW21" smd circle
			(at -15.660116 28.710128 180)
			(size 0.450088 0.450088)
			(layers "F.Cu" "F.Mask" "F.Paste")
			(net "M_I_CPU1_SB_DQ<21>")
		)
		(pad "CW22" smd circle
			(at -14.720062 28.710128 180)
			(size 0.450088 0.450088)
			(layers "F.Cu" "F.Mask" "F.Paste")
			(net "GND")
		)
		(pad "CW23" smd circle
			(at -13.780008 28.710128 180)
			(size 0.450088 0.450088)
			(layers "F.Cu" "F.Mask" "F.Paste")
			(net "P5E_CPU1_P3_RX_DP<12>")
		)
		(pad "CW24" smd circle
			(at -12.839954 28.710128 180)
			(size 0.450088 0.450088)
			(layers "F.Cu" "F.Mask" "F.Paste")
			(net "P5E_CPU1_P3_RX_DN<12>")
		)
		(pad "CW25" smd circle
			(at -11.8999 28.710128 180)
			(size 0.450088 0.450088)
			(layers "F.Cu" "F.Mask" "F.Paste")
			(net "GND")
		)
		(pad "CW26" smd circle
			(at -10.9601 28.710128 180)
			(size 0.450088 0.450088)
			(layers "F.Cu" "F.Mask" "F.Paste")
			(net "P5E_CPU1_P3_RX_DP<9>")
		)
		(pad "CW27" smd circle
			(at -10.020046 28.710128 180)
			(size 0.450088 0.450088)
			(layers "F.Cu" "F.Mask" "F.Paste")
			(net "P5E_CPU1_P3_RX_DN<9>")
		)
		(pad "CW28" smd circle
			(at -9.079992 28.710128 180)
			(size 0.450088 0.450088)
			(layers "F.Cu" "F.Mask" "F.Paste")
			(net "GND")
		)
		(pad "CW29" smd circle
			(at -8.139938 28.710128 180)
			(size 0.450088 0.450088)
			(layers "F.Cu" "F.Mask" "F.Paste")
			(net "P5E_CPU1_P3_RX_DP<6>")
		)
		(pad "CW30" smd circle
			(at -7.199884 28.710128 180)
			(size 0.450088 0.450088)
			(layers "F.Cu" "F.Mask" "F.Paste")
			(net "P5E_CPU1_P3_RX_DN<6>")
		)
		(pad "CW31" smd circle
			(at -6.260084 28.710128 180)
			(size 0.450088 0.450088)
			(layers "F.Cu" "F.Mask" "F.Paste")
			(net "GND")
		)
		(pad "CW32" smd circle
			(at -5.32003 28.710128 180)
			(size 0.450088 0.450088)
			(layers "F.Cu" "F.Mask" "F.Paste")
			(net "P5E_CPU1_P3_RX_DP<3>")
		)
		(pad "CW33" smd circle
			(at -4.379976 28.710128 180)
			(size 0.450088 0.450088)
			(layers "F.Cu" "F.Mask" "F.Paste")
			(net "P5E_CPU1_P3_RX_DN<3>")
		)
		(pad "CW34" smd circle
			(at -3.439922 28.710128 180)
			(size 0.450088 0.450088)
			(layers "F.Cu" "F.Mask" "F.Paste")
			(net "GND")
		)
		(pad "CW35" smd circle
			(at -2.500122 28.710128 180)
			(size 0.450088 0.450088)
			(layers "F.Cu" "F.Mask" "F.Paste")
			(net "GND")
		)
		(pad "CW36" smd circle
			(at -1.560068 28.710128 180)
			(size 0.450088 0.450088)
			(layers "F.Cu" "F.Mask" "F.Paste")
			(net "GND")
		)
		(pad "CW40" smd circle
			(at 1.260094 28.710128 180)
			(size 0.450088 0.450088)
			(layers "F.Cu" "F.Mask" "F.Paste")
			(net "GND")
		)
		(pad "CW41" smd circle
			(at 2.199894 28.710128 180)
			(size 0.450088 0.450088)
			(layers "F.Cu" "F.Mask" "F.Paste")
			(net "GND")
		)
		(pad "CW42" smd circle
			(at 3.139948 28.710128 180)
			(size 0.450088 0.450088)
			(layers "F.Cu" "F.Mask" "F.Paste")
			(net "GND")
		)
		(pad "CW43" smd circle
			(at 4.080002 28.710128 180)
			(size 0.450088 0.450088)
			(layers "F.Cu" "F.Mask" "F.Paste")
			(net "P5E_CPU1_P1_TX_DN<12>")
		)
		(pad "CW44" smd circle
			(at 5.020056 28.710128 180)
			(size 0.450088 0.450088)
			(layers "F.Cu" "F.Mask" "F.Paste")
			(net "P5E_CPU1_P1_TX_DP<12>")
		)
		(pad "CW45" smd circle
			(at 5.96011 28.710128 180)
			(size 0.450088 0.450088)
			(layers "F.Cu" "F.Mask" "F.Paste")
			(net "GND")
		)
		(pad "CW46" smd circle
			(at 6.89991 28.710128 180)
			(size 0.450088 0.450088)
			(layers "F.Cu" "F.Mask" "F.Paste")
			(net "P5E_CPU1_P1_TX_DN<9>")
		)
		(pad "CW47" smd circle
			(at 7.839964 28.710128 180)
			(size 0.450088 0.450088)
			(layers "F.Cu" "F.Mask" "F.Paste")
			(net "P5E_CPU1_P1_TX_DP<9>")
		)
		(pad "CW48" smd circle
			(at 8.780018 28.710128 180)
			(size 0.450088 0.450088)
			(layers "F.Cu" "F.Mask" "F.Paste")
			(net "GND")
		)
		(pad "CW49" smd circle
			(at 9.720072 28.710128 180)
			(size 0.450088 0.450088)
			(layers "F.Cu" "F.Mask" "F.Paste")
			(net "P5E_CPU1_P1_TX_DN<6>")
		)
		(pad "CW50" smd circle
			(at 10.659872 28.710128 180)
			(size 0.450088 0.450088)
			(layers "F.Cu" "F.Mask" "F.Paste")
			(net "P5E_CPU1_P1_TX_DP<6>")
		)
		(pad "CW51" smd circle
			(at 11.599926 28.710128 180)
			(size 0.450088 0.450088)
			(layers "F.Cu" "F.Mask" "F.Paste")
			(net "GND")
		)
		(pad "CW52" smd circle
			(at 12.53998 28.710128 180)
			(size 0.450088 0.450088)
			(layers "F.Cu" "F.Mask" "F.Paste")
			(net "P5E_CPU1_P1_TX_DN<3>")
		)
		(pad "CW53" smd circle
			(at 13.480034 28.710128 180)
			(size 0.450088 0.450088)
			(layers "F.Cu" "F.Mask" "F.Paste")
			(net "P5E_CPU1_P1_TX_DP<3>")
		)
		(pad "CW54" smd circle
			(at 14.420088 28.710128 180)
			(size 0.450088 0.450088)
			(layers "F.Cu" "F.Mask" "F.Paste")
			(net "GND")
		)
		(pad "CW55" smd circle
			(at 15.359888 28.710128 180)
			(size 0.450088 0.450088)
			(layers "F.Cu" "F.Mask" "F.Paste")
			(net "M_C_CPU1_SB_DQ<21>")
		)
		(pad "CW56" smd circle
			(at 16.299942 28.710128 180)
			(size 0.450088 0.450088)
			(layers "F.Cu" "F.Mask" "F.Paste")
			(net "GND")
		)
		(pad "CW57" smd circle
			(at 17.239996 28.710128 180)
			(size 0.450088 0.450088)
			(layers "F.Cu" "F.Mask" "F.Paste")
			(net "M_C_CPU1_SB_DQ<22>")
		)
		(pad "CW58" smd circle
			(at 18.18005 28.710128 180)
			(size 0.450088 0.450088)
			(layers "F.Cu" "F.Mask" "F.Paste")
			(net "PVDDIO_P1")
		)
		(pad "CW59" smd circle
			(at 19.120104 28.710128 180)
			(size 0.450088 0.450088)
			(layers "F.Cu" "F.Mask" "F.Paste")
			(net "M_D_CPU1_SB_DQ<21>")
		)
		(pad "CW60" smd circle
			(at 20.059904 28.710128 180)
			(size 0.450088 0.450088)
			(layers "F.Cu" "F.Mask" "F.Paste")
			(net "M_D_CPU1_SB_DQ<22>")
		)
		(pad "CW61" smd circle
			(at 20.999958 28.710128 180)
			(size 0.450088 0.450088)
			(layers "F.Cu" "F.Mask" "F.Paste")
			(net "GND")
		)
		(pad "CW62" smd circle
			(at 21.940012 28.710128 180)
			(size 0.450088 0.450088)
			(layers "F.Cu" "F.Mask" "F.Paste")
			(net "M_B_CPU1_SB_DQ<21>")
		)
		(pad "CW63" smd circle
			(at 22.880066 28.710128 180)
			(size 0.450088 0.450088)
			(layers "F.Cu" "F.Mask" "F.Paste")
			(net "GND")
		)
		(pad "CW64" smd circle
			(at 23.82012 28.710128 180)
			(size 0.450088 0.450088)
			(layers "F.Cu" "F.Mask" "F.Paste")
			(net "M_B_CPU1_SB_DQ<22>")
		)
		(pad "CW65" smd circle
			(at 24.75992 28.710128 180)
			(size 0.450088 0.450088)
			(layers "F.Cu" "F.Mask" "F.Paste")
			(net "PVDDIO_P1")
		)
		(pad "CW66" smd circle
			(at 25.699974 28.710128 180)
			(size 0.450088 0.450088)
			(layers "F.Cu" "F.Mask" "F.Paste")
			(net "M_F_CPU1_SB_DQ<21>")
		)
		(pad "CW67" smd circle
			(at 26.640028 28.710128 180)
			(size 0.450088 0.450088)
			(layers "F.Cu" "F.Mask" "F.Paste")
			(net "M_F_CPU1_SB_DQ<22>")
		)
		(pad "CW68" smd circle
			(at 27.580082 28.710128 180)
			(size 0.450088 0.450088)
			(layers "F.Cu" "F.Mask" "F.Paste")
			(net "GND")
		)
		(pad "CW69" smd circle
			(at 28.519882 28.710128 180)
			(size 0.450088 0.450088)
			(layers "F.Cu" "F.Mask" "F.Paste")
			(net "M_E_CPU1_SB_DQ<21>")
		)
		(pad "CW70" smd circle
			(at 29.459936 28.710128 180)
			(size 0.450088 0.450088)
			(layers "F.Cu" "F.Mask" "F.Paste")
			(net "GND")
		)
		(pad "CW71" smd circle
			(at 30.39999 28.710128 180)
			(size 0.450088 0.450088)
			(layers "F.Cu" "F.Mask" "F.Paste")
			(net "M_E_CPU1_SB_DQ<22>")
		)
		(pad "CW72" smd circle
			(at 31.340044 28.710128 180)
			(size 0.450088 0.450088)
			(layers "F.Cu" "F.Mask" "F.Paste")
			(net "PVDDIO_P1")
		)
		(pad "CW73" smd circle
			(at 32.280098 28.710128 180)
			(size 0.450088 0.450088)
			(layers "F.Cu" "F.Mask" "F.Paste")
			(net "M_A_CPU1_SB_DQ<21>")
		)
		(pad "CW74" smd circle
			(at 33.219898 28.710128 180)
			(size 0.450088 0.450088)
			(layers "F.Cu" "F.Mask" "F.Paste")
			(net "M_A_CPU1_SB_DQ<22>")
		)
		(pad "CW75" smd circle
			(at 34.159952 28.710128 180)
			(size 0.450088 0.450088)
			(layers "F.Cu" "F.Mask" "F.Paste")
			(net "GND")
		)
		(pad "CY2" smd circle
			(at -33.990026 29.51988 180)
			(size 0.450088 0.450088)
			(layers "F.Cu" "F.Mask" "F.Paste")
			(net "M_G_CPU1_SB_DQ<24>")
		)
		(pad "CY3" smd circle
			(at -33.049972 29.51988 180)
			(size 0.450088 0.450088)
			(layers "F.Cu" "F.Mask" "F.Paste")
			(net "GND")
		)
		(pad "CY4" smd circle
			(at -32.109918 29.51988 180)
			(size 0.450088 0.450088)
			(layers "F.Cu" "F.Mask" "F.Paste")
			(net "M_G_CPU1_SB_DQ<23>")
		)
		(pad "CY5" smd circle
			(at -31.170118 29.51988 180)
			(size 0.450088 0.450088)
			(layers "F.Cu" "F.Mask" "F.Paste")
			(net "GND")
		)
		(pad "CY6" smd circle
			(at -30.230064 29.51988 180)
			(size 0.450088 0.450088)
			(layers "F.Cu" "F.Mask" "F.Paste")
			(net "M_K_CPU1_SB_DQ<24>")
		)
		(pad "CY7" smd circle
			(at -29.29001 29.51988 180)
			(size 0.450088 0.450088)
			(layers "F.Cu" "F.Mask" "F.Paste")
			(net "M_K_CPU1_SB_DQ<23>")
		)
		(pad "CY8" smd circle
			(at -28.349956 29.51988 180)
			(size 0.450088 0.450088)
			(layers "F.Cu" "F.Mask" "F.Paste")
			(net "GND")
		)
		(pad "CY9" smd circle
			(at -27.409902 29.51988 180)
			(size 0.450088 0.450088)
			(layers "F.Cu" "F.Mask" "F.Paste")
			(net "M_L_CPU1_SB_DQ<24>")
		)
		(pad "CY10" smd circle
			(at -26.470102 29.51988 180)
			(size 0.450088 0.450088)
			(layers "F.Cu" "F.Mask" "F.Paste")
			(net "GND")
		)
		(pad "CY11" smd circle
			(at -25.530048 29.51988 180)
			(size 0.450088 0.450088)
			(layers "F.Cu" "F.Mask" "F.Paste")
			(net "M_L_CPU1_SB_DQ<23>")
		)
		(pad "CY12" smd circle
			(at -24.589994 29.51988 180)
			(size 0.450088 0.450088)
			(layers "F.Cu" "F.Mask" "F.Paste")
			(net "GND")
		)
		(pad "CY13" smd circle
			(at -23.64994 29.51988 180)
			(size 0.450088 0.450088)
			(layers "F.Cu" "F.Mask" "F.Paste")
			(net "M_H_CPU1_SB_DQ<24>")
		)
		(pad "CY14" smd circle
			(at -22.709886 29.51988 180)
			(size 0.450088 0.450088)
			(layers "F.Cu" "F.Mask" "F.Paste")
			(net "M_H_CPU1_SB_DQ<23>")
		)
		(pad "CY15" smd circle
			(at -21.770086 29.51988 180)
			(size 0.450088 0.450088)
			(layers "F.Cu" "F.Mask" "F.Paste")
			(net "GND")
		)
		(pad "CY16" smd circle
			(at -20.830032 29.51988 180)
			(size 0.450088 0.450088)
			(layers "F.Cu" "F.Mask" "F.Paste")
			(net "M_J_CPU1_SB_DQ<24>")
		)
		(pad "CY17" smd circle
			(at -19.889978 29.51988 180)
			(size 0.450088 0.450088)
			(layers "F.Cu" "F.Mask" "F.Paste")
			(net "GND")
		)
		(pad "CY18" smd circle
			(at -18.949924 29.51988 180)
			(size 0.450088 0.450088)
			(layers "F.Cu" "F.Mask" "F.Paste")
			(net "M_J_CPU1_SB_DQ<23>")
		)
		(pad "CY19" smd circle
			(at -18.010124 29.51988 180)
			(size 0.450088 0.450088)
			(layers "F.Cu" "F.Mask" "F.Paste")
			(net "GND")
		)
		(pad "CY20" smd circle
			(at -17.07007 29.51988 180)
			(size 0.450088 0.450088)
			(layers "F.Cu" "F.Mask" "F.Paste")
			(net "M_I_CPU1_SB_DQ<24>")
		)
		(pad "CY21" smd circle
			(at -16.130016 29.51988 180)
			(size 0.450088 0.450088)
			(layers "F.Cu" "F.Mask" "F.Paste")
			(net "M_I_CPU1_SB_DQ<23>")
		)
		(pad "CY22" smd circle
			(at -15.189962 29.51988 180)
			(size 0.450088 0.450088)
			(layers "F.Cu" "F.Mask" "F.Paste")
			(net "PVDD11_S3_P1")
		)
		(pad "CY23" smd circle
			(at -14.249908 29.51988 180)
			(size 0.450088 0.450088)
			(layers "F.Cu" "F.Mask" "F.Paste")
			(net "GND")
		)
		(pad "CY24" smd circle
			(at -13.310108 29.51988 180)
			(size 0.450088 0.450088)
			(layers "F.Cu" "F.Mask" "F.Paste")
			(net "GND")
		)
		(pad "CY25" smd circle
			(at -12.370054 29.51988 180)
			(size 0.450088 0.450088)
			(layers "F.Cu" "F.Mask" "F.Paste")
			(net "GND")
		)
		(pad "CY26" smd circle
			(at -11.43 29.51988 180)
			(size 0.450088 0.450088)
			(layers "F.Cu" "F.Mask" "F.Paste")
			(net "GND")
		)
		(pad "CY27" smd circle
			(at -10.489946 29.51988 180)
			(size 0.450088 0.450088)
			(layers "F.Cu" "F.Mask" "F.Paste")
			(net "GND")
		)
		(pad "CY28" smd circle
			(at -9.549892 29.51988 180)
			(size 0.450088 0.450088)
			(layers "F.Cu" "F.Mask" "F.Paste")
			(net "GND")
		)
		(pad "CY29" smd circle
			(at -8.610092 29.51988 180)
			(size 0.450088 0.450088)
			(layers "F.Cu" "F.Mask" "F.Paste")
			(net "GND")
		)
		(pad "CY30" smd circle
			(at -7.670038 29.51988 180)
			(size 0.450088 0.450088)
			(layers "F.Cu" "F.Mask" "F.Paste")
			(net "GND")
		)
		(pad "CY31" smd circle
			(at -6.729984 29.51988 180)
			(size 0.450088 0.450088)
			(layers "F.Cu" "F.Mask" "F.Paste")
			(net "GND")
		)
		(pad "CY32" smd circle
			(at -5.78993 29.51988 180)
			(size 0.450088 0.450088)
			(layers "F.Cu" "F.Mask" "F.Paste")
			(net "GND")
		)
		(pad "CY33" smd circle
			(at -4.849876 29.51988 180)
			(size 0.450088 0.450088)
			(layers "F.Cu" "F.Mask" "F.Paste")
			(net "GND")
		)
		(pad "CY34" smd circle
			(at -3.910076 29.51988 180)
			(size 0.450088 0.450088)
			(layers "F.Cu" "F.Mask" "F.Paste")
			(net "GND")
		)
		(pad "CY35" smd circle
			(at -2.970022 29.51988 180)
			(size 0.450088 0.450088)
			(layers "F.Cu" "F.Mask" "F.Paste")
			(net "P5E_CPU1_P3_RX_DP<1>")
		)
		(pad "CY36" smd circle
			(at -2.029968 29.51988 180)
			(size 0.450088 0.450088)
			(layers "F.Cu" "F.Mask" "F.Paste")
			(net "P5E_CPU1_P3_RX_DN<1>")
		)
		(pad "CY37" smd circle
			(at -1.089914 29.51988 180)
			(size 0.450088 0.450088)
			(layers "F.Cu" "F.Mask" "F.Paste")
			(net "GND")
		)
		(pad "CY39" smd circle
			(at 0.78994 29.51988 180)
			(size 0.450088 0.450088)
			(layers "F.Cu" "F.Mask" "F.Paste")
			(net "GND")
		)
		(pad "CY40" smd circle
			(at 1.729994 29.51988 180)
			(size 0.450088 0.450088)
			(layers "F.Cu" "F.Mask" "F.Paste")
			(net "P5E_CPU1_P1_TX_DN<14>")
		)
		(pad "CY41" smd circle
			(at 2.670048 29.51988 180)
			(size 0.450088 0.450088)
			(layers "F.Cu" "F.Mask" "F.Paste")
			(net "P5E_CPU1_P1_TX_DP<14>")
		)
		(pad "CY42" smd circle
			(at 3.610102 29.51988 180)
			(size 0.450088 0.450088)
			(layers "F.Cu" "F.Mask" "F.Paste")
			(net "GND")
		)
		(pad "CY43" smd circle
			(at 4.549902 29.51988 180)
			(size 0.450088 0.450088)
			(layers "F.Cu" "F.Mask" "F.Paste")
			(net "GND")
		)
		(pad "CY44" smd circle
			(at 5.489956 29.51988 180)
			(size 0.450088 0.450088)
			(layers "F.Cu" "F.Mask" "F.Paste")
			(net "GND")
		)
		(pad "CY45" smd circle
			(at 6.43001 29.51988 180)
			(size 0.450088 0.450088)
			(layers "F.Cu" "F.Mask" "F.Paste")
			(net "GND")
		)
		(pad "CY46" smd circle
			(at 7.370064 29.51988 180)
			(size 0.450088 0.450088)
			(layers "F.Cu" "F.Mask" "F.Paste")
			(net "GND")
		)
		(pad "CY47" smd circle
			(at 8.310118 29.51988 180)
			(size 0.450088 0.450088)
			(layers "F.Cu" "F.Mask" "F.Paste")
			(net "GND")
		)
		(pad "CY48" smd circle
			(at 9.249918 29.51988 180)
			(size 0.450088 0.450088)
			(layers "F.Cu" "F.Mask" "F.Paste")
			(net "GND")
		)
		(pad "CY49" smd circle
			(at 10.189972 29.51988 180)
			(size 0.450088 0.450088)
			(layers "F.Cu" "F.Mask" "F.Paste")
			(net "GND")
		)
		(pad "CY50" smd circle
			(at 11.130026 29.51988 180)
			(size 0.450088 0.450088)
			(layers "F.Cu" "F.Mask" "F.Paste")
			(net "GND")
		)
		(pad "CY51" smd circle
			(at 12.07008 29.51988 180)
			(size 0.450088 0.450088)
			(layers "F.Cu" "F.Mask" "F.Paste")
			(net "GND")
		)
		(pad "CY52" smd circle
			(at 13.00988 29.51988 180)
			(size 0.450088 0.450088)
			(layers "F.Cu" "F.Mask" "F.Paste")
			(net "GND")
		)
		(pad "CY53" smd circle
			(at 13.949934 29.51988 180)
			(size 0.450088 0.450088)
			(layers "F.Cu" "F.Mask" "F.Paste")
			(net "GND")
		)
		(pad "CY54" smd circle
			(at 14.889988 29.51988 180)
			(size 0.450088 0.450088)
			(layers "F.Cu" "F.Mask" "F.Paste")
			(net "PVDDIO_P1")
		)
		(pad "CY55" smd circle
			(at 15.830042 29.51988 180)
			(size 0.450088 0.450088)
			(layers "F.Cu" "F.Mask" "F.Paste")
			(net "M_C_CPU1_SB_DQ<23>")
		)
		(pad "CY56" smd circle
			(at 16.770096 29.51988 180)
			(size 0.450088 0.450088)
			(layers "F.Cu" "F.Mask" "F.Paste")
			(net "M_C_CPU1_SB_DQ<24>")
		)
		(pad "CY57" smd circle
			(at 17.709896 29.51988 180)
			(size 0.450088 0.450088)
			(layers "F.Cu" "F.Mask" "F.Paste")
			(net "GND")
		)
		(pad "CY58" smd circle
			(at 18.64995 29.51988 180)
			(size 0.450088 0.450088)
			(layers "F.Cu" "F.Mask" "F.Paste")
			(net "M_D_CPU1_SB_DQ<23>")
		)
		(pad "CY59" smd circle
			(at 19.590004 29.51988 180)
			(size 0.450088 0.450088)
			(layers "F.Cu" "F.Mask" "F.Paste")
			(net "GND")
		)
		(pad "CY60" smd circle
			(at 20.530058 29.51988 180)
			(size 0.450088 0.450088)
			(layers "F.Cu" "F.Mask" "F.Paste")
			(net "M_D_CPU1_SB_DQ<24>")
		)
		(pad "CY61" smd circle
			(at 21.470112 29.51988 180)
			(size 0.450088 0.450088)
			(layers "F.Cu" "F.Mask" "F.Paste")
			(net "GND")
		)
		(pad "CY62" smd circle
			(at 22.409912 29.51988 180)
			(size 0.450088 0.450088)
			(layers "F.Cu" "F.Mask" "F.Paste")
			(net "M_B_CPU1_SB_DQ<23>")
		)
		(pad "CY63" smd circle
			(at 23.349966 29.51988 180)
			(size 0.450088 0.450088)
			(layers "F.Cu" "F.Mask" "F.Paste")
			(net "M_B_CPU1_SB_DQ<24>")
		)
		(pad "CY64" smd circle
			(at 24.29002 29.51988 180)
			(size 0.450088 0.450088)
			(layers "F.Cu" "F.Mask" "F.Paste")
			(net "GND")
		)
		(pad "CY65" smd circle
			(at 25.230074 29.51988 180)
			(size 0.450088 0.450088)
			(layers "F.Cu" "F.Mask" "F.Paste")
			(net "M_F_CPU1_SB_DQ<23>")
		)
		(pad "CY66" smd circle
			(at 26.170128 29.51988 180)
			(size 0.450088 0.450088)
			(layers "F.Cu" "F.Mask" "F.Paste")
			(net "GND")
		)
		(pad "CY67" smd circle
			(at 27.109928 29.51988 180)
			(size 0.450088 0.450088)
			(layers "F.Cu" "F.Mask" "F.Paste")
			(net "M_F_CPU1_SB_DQ<24>")
		)
		(pad "CY68" smd circle
			(at 28.049982 29.51988 180)
			(size 0.450088 0.450088)
			(layers "F.Cu" "F.Mask" "F.Paste")
			(net "GND")
		)
		(pad "CY69" smd circle
			(at 28.990036 29.51988 180)
			(size 0.450088 0.450088)
			(layers "F.Cu" "F.Mask" "F.Paste")
			(net "M_E_CPU1_SB_DQ<23>")
		)
		(pad "CY70" smd circle
			(at 29.93009 29.51988 180)
			(size 0.450088 0.450088)
			(layers "F.Cu" "F.Mask" "F.Paste")
			(net "M_E_CPU1_SB_DQ<24>")
		)
		(pad "CY71" smd circle
			(at 30.86989 29.51988 180)
			(size 0.450088 0.450088)
			(layers "F.Cu" "F.Mask" "F.Paste")
			(net "GND")
		)
		(pad "CY72" smd circle
			(at 31.809944 29.51988 180)
			(size 0.450088 0.450088)
			(layers "F.Cu" "F.Mask" "F.Paste")
			(net "M_A_CPU1_SB_DQ<23>")
		)
		(pad "CY73" smd circle
			(at 32.749998 29.51988 180)
			(size 0.450088 0.450088)
			(layers "F.Cu" "F.Mask" "F.Paste")
			(net "GND")
		)
		(pad "CY74" smd circle
			(at 33.690052 29.51988 180)
			(size 0.450088 0.450088)
			(layers "F.Cu" "F.Mask" "F.Paste")
			(net "M_A_CPU1_SB_DQ<24>")
		)
		(pad "D2" smd circle
			(at -33.690052 -34.379916 180)
			(size 0.450088 0.450088)
			(layers "F.Cu" "F.Mask" "F.Paste")
			(net "GND")
		)
		(pad "D3" smd circle
			(at -32.749998 -34.379916 180)
			(size 0.450088 0.450088)
			(layers "F.Cu" "F.Mask" "F.Paste")
			(net "GND")
		)
		(pad "D4" smd circle
			(at -31.809944 -34.379916 180)
			(size 0.450088 0.450088)
			(layers "F.Cu" "F.Mask" "F.Paste")
			(net "Net_2157")
		)
		(pad "D5" smd circle
			(at -30.86989 -34.379916 180)
			(size 0.450088 0.450088)
			(layers "F.Cu" "F.Mask" "F.Paste")
			(net "GND")
		)
		(pad "D6" smd circle
			(at -29.93009 -34.379916 180)
			(size 0.450088 0.450088)
			(layers "F.Cu" "F.Mask" "F.Paste")
			(net "GND")
		)
		(pad "D7" smd circle
			(at -28.990036 -34.379916 180)
			(size 0.450088 0.450088)
			(layers "F.Cu" "F.Mask" "F.Paste")
			(net "TP_CPU1_TEST47_IOD1")
		)
		(pad "D8" smd circle
			(at -28.049982 -34.379916 180)
			(size 0.450088 0.450088)
			(layers "F.Cu" "F.Mask" "F.Paste")
			(net "Net_2162")
		)
		(pad "D9" smd circle
			(at -27.109928 -34.379916 180)
			(size 0.450088 0.450088)
			(layers "F.Cu" "F.Mask" "F.Paste")
			(net "GND")
		)
		(pad "D10" smd circle
			(at -26.170128 -34.379916 180)
			(size 0.450088 0.450088)
			(layers "F.Cu" "F.Mask" "F.Paste")
			(net "GND")
		)
		(pad "D11" smd circle
			(at -25.230074 -34.379916 180)
			(size 0.450088 0.450088)
			(layers "F.Cu" "F.Mask" "F.Paste")
			(net "Net_2153")
		)
		(pad "D12" smd circle
			(at -24.29002 -34.379916 180)
			(size 0.450088 0.450088)
			(layers "F.Cu" "F.Mask" "F.Paste")
			(net "GND")
		)
		(pad "D13" smd circle
			(at -23.349966 -34.379916 180)
			(size 0.450088 0.450088)
			(layers "F.Cu" "F.Mask" "F.Paste")
			(net "GND")
		)
		(pad "D14" smd circle
			(at -22.409912 -34.379916 180)
			(size 0.450088 0.450088)
			(layers "F.Cu" "F.Mask" "F.Paste")
			(net "SMB_CPU1_SEC_SDA")
		)
		(pad "D15" smd circle
			(at -21.470112 -34.379916 180)
			(size 0.450088 0.450088)
			(layers "F.Cu" "F.Mask" "F.Paste")
			(net "Net_2100")
		)
		(pad "D16" smd circle
			(at -20.530058 -34.379916 180)
			(size 0.450088 0.450088)
			(layers "F.Cu" "F.Mask" "F.Paste")
			(net "GND")
		)
		(pad "D17" smd circle
			(at -19.590004 -34.379916 180)
			(size 0.450088 0.450088)
			(layers "F.Cu" "F.Mask" "F.Paste")
			(net "GND")
		)
		(pad "D18" smd circle
			(at -18.64995 -34.379916 180)
			(size 0.450088 0.450088)
			(layers "F.Cu" "F.Mask" "F.Paste")
			(net "RST_CPU1_PERST0_N")
		)
		(pad "D19" smd circle
			(at -17.709896 -34.379916 180)
			(size 0.450088 0.450088)
			(layers "F.Cu" "F.Mask" "F.Paste")
			(net "GND")
		)
		(pad "D20" smd circle
			(at -16.770096 -34.379916 180)
			(size 0.450088 0.450088)
			(layers "F.Cu" "F.Mask" "F.Paste")
			(net "GND")
		)
		(pad "D21" smd circle
			(at -15.830042 -34.379916 180)
			(size 0.450088 0.450088)
			(layers "F.Cu" "F.Mask" "F.Paste")
			(net "GND")
		)
		(pad "D22" smd circle
			(at -14.889988 -34.379916 180)
			(size 0.450088 0.450088)
			(layers "F.Cu" "F.Mask" "F.Paste")
			(net "Net_2154")
		)
		(pad "D23" smd circle
			(at -13.949934 -34.379916 180)
			(size 0.450088 0.450088)
			(layers "F.Cu" "F.Mask" "F.Paste")
			(net "Net_2176")
		)
		(pad "D24" smd circle
			(at -13.00988 -34.379916 180)
			(size 0.450088 0.450088)
			(layers "F.Cu" "F.Mask" "F.Paste")
			(net "GND")
		)
		(pad "D25" smd circle
			(at -12.07008 -34.379916 180)
			(size 0.450088 0.450088)
			(layers "F.Cu" "F.Mask" "F.Paste")
			(net "GND")
		)
		(pad "D26" smd circle
			(at -11.130026 -34.379916 180)
			(size 0.450088 0.450088)
			(layers "F.Cu" "F.Mask" "F.Paste")
			(net "GND")
		)
		(pad "D27" smd circle
			(at -10.189972 -34.379916 180)
			(size 0.450088 0.450088)
			(layers "F.Cu" "F.Mask" "F.Paste")
			(net "GND")
		)
		(pad "D28" smd circle
			(at -9.249918 -34.379916 180)
			(size 0.450088 0.450088)
			(layers "F.Cu" "F.Mask" "F.Paste")
			(net "GND")
		)
		(pad "D29" smd circle
			(at -8.310118 -34.379916 180)
			(size 0.450088 0.450088)
			(layers "F.Cu" "F.Mask" "F.Paste")
			(net "GND")
		)
		(pad "D30" smd circle
			(at -7.370064 -34.379916 180)
			(size 0.450088 0.450088)
			(layers "F.Cu" "F.Mask" "F.Paste")
			(net "GND")
		)
		(pad "D31" smd circle
			(at -6.43001 -34.379916 180)
			(size 0.450088 0.450088)
			(layers "F.Cu" "F.Mask" "F.Paste")
			(net "GND")
		)
		(pad "D32" smd circle
			(at -5.489956 -34.379916 180)
			(size 0.450088 0.450088)
			(layers "F.Cu" "F.Mask" "F.Paste")
			(net "NC_CPU1_AZ_SYNC")
		)
		(pad "D33" smd circle
			(at -4.549902 -34.379916 180)
			(size 0.450088 0.450088)
			(layers "F.Cu" "F.Mask" "F.Paste")
			(net "NC_CPU1_AZ_SDIN1")
		)
		(pad "D34" smd circle
			(at -3.610102 -34.379916 180)
			(size 0.450088 0.450088)
			(layers "F.Cu" "F.Mask" "F.Paste")
			(net "Net_2155")
		)
		(pad "D35" smd circle
			(at -2.670048 -34.379916 180)
			(size 0.450088 0.450088)
			(layers "F.Cu" "F.Mask" "F.Paste")
			(net "GND")
		)
		(pad "D36" smd circle
			(at -1.729994 -34.379916 180)
			(size 0.450088 0.450088)
			(layers "F.Cu" "F.Mask" "F.Paste")
			(net "Net_2156")
		)
		(pad "D37" smd circle
			(at -0.78994 -34.379916 180)
			(size 0.450088 0.450088)
			(layers "F.Cu" "F.Mask" "F.Paste")
			(net "GND")
		)
		(pad "D39" smd circle
			(at 1.089914 -34.379916 180)
			(size 0.450088 0.450088)
			(layers "F.Cu" "F.Mask" "F.Paste")
			(net "GND")
		)
		(pad "D40" smd circle
			(at 2.029968 -34.379916 180)
			(size 0.450088 0.450088)
			(layers "F.Cu" "F.Mask" "F.Paste")
			(net "GND")
		)
		(pad "D41" smd circle
			(at 2.970022 -34.379916 180)
			(size 0.450088 0.450088)
			(layers "F.Cu" "F.Mask" "F.Paste")
			(net "GND")
		)
		(pad "D42" smd circle
			(at 3.910076 -34.379916 180)
			(size 0.450088 0.450088)
			(layers "F.Cu" "F.Mask" "F.Paste")
			(net "GND")
		)
		(pad "D43" smd circle
			(at 4.849876 -34.379916 180)
			(size 0.450088 0.450088)
			(layers "F.Cu" "F.Mask" "F.Paste")
			(net "GND")
		)
		(pad "D44" smd circle
			(at 5.78993 -34.379916 180)
			(size 0.450088 0.450088)
			(layers "F.Cu" "F.Mask" "F.Paste")
			(net "GND")
		)
		(pad "D45" smd circle
			(at 6.729984 -34.379916 180)
			(size 0.450088 0.450088)
			(layers "F.Cu" "F.Mask" "F.Paste")
			(net "GND")
		)
		(pad "D46" smd circle
			(at 7.670038 -34.379916 180)
			(size 0.450088 0.450088)
			(layers "F.Cu" "F.Mask" "F.Paste")
			(net "GND")
		)
		(pad "D47" smd circle
			(at 8.610092 -34.379916 180)
			(size 0.450088 0.450088)
			(layers "F.Cu" "F.Mask" "F.Paste")
			(net "GND")
		)
		(pad "D48" smd circle
			(at 9.549892 -34.379916 180)
			(size 0.450088 0.450088)
			(layers "F.Cu" "F.Mask" "F.Paste")
			(net "GND")
		)
		(pad "D49" smd circle
			(at 10.489946 -34.379916 180)
			(size 0.450088 0.450088)
			(layers "F.Cu" "F.Mask" "F.Paste")
			(net "GND")
		)
		(pad "D50" smd circle
			(at 11.43 -34.379916 180)
			(size 0.450088 0.450088)
			(layers "F.Cu" "F.Mask" "F.Paste")
			(net "GND")
		)
		(pad "D51" smd circle
			(at 12.370054 -34.379916 180)
			(size 0.450088 0.450088)
			(layers "F.Cu" "F.Mask" "F.Paste")
			(net "GND")
		)
		(pad "D52" smd circle
			(at 13.310108 -34.379916 180)
			(size 0.450088 0.450088)
			(layers "F.Cu" "F.Mask" "F.Paste")
			(net "GND")
		)
		(pad "D53" smd circle
			(at 14.249908 -34.379916 180)
			(size 0.450088 0.450088)
			(layers "F.Cu" "F.Mask" "F.Paste")
			(net "GND")
		)
		(pad "D54" smd circle
			(at 15.189962 -34.379916 180)
			(size 0.450088 0.450088)
			(layers "F.Cu" "F.Mask" "F.Paste")
			(net "GND")
		)
		(pad "D55" smd circle
			(at 16.130016 -34.379916 180)
			(size 0.450088 0.450088)
			(layers "F.Cu" "F.Mask" "F.Paste")
			(net "PVDDCR_CPU0_P1")
		)
		(pad "D56" smd circle
			(at 17.07007 -34.379916 180)
			(size 0.450088 0.450088)
			(layers "F.Cu" "F.Mask" "F.Paste")
			(net "PVDDCR_CPU0_P1")
		)
		(pad "D57" smd circle
			(at 18.010124 -34.379916 180)
			(size 0.450088 0.450088)
			(layers "F.Cu" "F.Mask" "F.Paste")
			(net "GND")
		)
		(pad "D58" smd circle
			(at 18.949924 -34.379916 180)
			(size 0.450088 0.450088)
			(layers "F.Cu" "F.Mask" "F.Paste")
			(net "Net_2158")
		)
		(pad "D59" smd circle
			(at 19.889978 -34.379916 180)
			(size 0.450088 0.450088)
			(layers "F.Cu" "F.Mask" "F.Paste")
			(net "GND")
		)
		(pad "D60" smd circle
			(at 20.830032 -34.379916 180)
			(size 0.450088 0.450088)
			(layers "F.Cu" "F.Mask" "F.Paste")
			(net "GND")
		)
		(pad "D61" smd circle
			(at 21.770086 -34.379916 180)
			(size 0.450088 0.450088)
			(layers "F.Cu" "F.Mask" "F.Paste")
			(net "GND")
		)
		(pad "D62" smd circle
			(at 22.709886 -34.379916 180)
			(size 0.450088 0.450088)
			(layers "F.Cu" "F.Mask" "F.Paste")
			(net "Net_2159")
		)
		(pad "D63" smd circle
			(at 23.64994 -34.379916 180)
			(size 0.450088 0.450088)
			(layers "F.Cu" "F.Mask" "F.Paste")
			(net "GND")
		)
		(pad "D64" smd circle
			(at 24.589994 -34.379916 180)
			(size 0.450088 0.450088)
			(layers "F.Cu" "F.Mask" "F.Paste")
			(net "GND")
		)
		(pad "D65" smd circle
			(at 25.530048 -34.379916 180)
			(size 0.450088 0.450088)
			(layers "F.Cu" "F.Mask" "F.Paste")
			(net "Net_2160")
		)
		(pad "D66" smd circle
			(at 26.470102 -34.379916 180)
			(size 0.450088 0.450088)
			(layers "F.Cu" "F.Mask" "F.Paste")
			(net "GND")
		)
		(pad "D67" smd circle
			(at 27.409902 -34.379916 180)
			(size 0.450088 0.450088)
			(layers "F.Cu" "F.Mask" "F.Paste")
			(net "GND")
		)
		(pad "D68" smd circle
			(at 28.349956 -34.379916 180)
			(size 0.450088 0.450088)
			(layers "F.Cu" "F.Mask" "F.Paste")
			(net "CPU1_CORETYPE2")
		)
		(pad "D69" smd circle
			(at 29.29001 -34.379916 180)
			(size 0.450088 0.450088)
			(layers "F.Cu" "F.Mask" "F.Paste")
			(net "PWRGD_CPU1_PWROK")
		)
		(pad "D70" smd circle
			(at 30.230064 -34.379916 180)
			(size 0.450088 0.450088)
			(layers "F.Cu" "F.Mask" "F.Paste")
			(net "GND")
		)
		(pad "D71" smd circle
			(at 31.170118 -34.379916 180)
			(size 0.450088 0.450088)
			(layers "F.Cu" "F.Mask" "F.Paste")
			(net "GND")
		)
		(pad "D72" smd circle
			(at 32.109918 -34.379916 180)
			(size 0.450088 0.450088)
			(layers "F.Cu" "F.Mask" "F.Paste")
			(net "Net_2161")
		)
		(pad "D73" smd circle
			(at 33.049972 -34.379916 180)
			(size 0.450088 0.450088)
			(layers "F.Cu" "F.Mask" "F.Paste")
			(net "GND")
		)
		(pad "D74" smd circle
			(at 33.990026 -34.379916 180)
			(size 0.450088 0.450088)
			(layers "F.Cu" "F.Mask" "F.Paste")
			(net "GND")
		)
		(pad "DA1" smd circle
			(at -34.459926 30.329886 180)
			(size 0.450088 0.450088)
			(layers "F.Cu" "F.Mask" "F.Paste")
			(net "GND")
		)
		(pad "DA2" smd circle
			(at -33.519872 30.329886 180)
			(size 0.450088 0.450088)
			(layers "F.Cu" "F.Mask" "F.Paste")
			(net "M_G_CPU1_SB_DQ<26>")
		)
		(pad "DA3" smd circle
			(at -32.580072 30.329886 180)
			(size 0.450088 0.450088)
			(layers "F.Cu" "F.Mask" "F.Paste")
			(net "M_G_CPU1_SB_DQ<25>")
		)
		(pad "DA4" smd circle
			(at -31.640018 30.329886 180)
			(size 0.450088 0.450088)
			(layers "F.Cu" "F.Mask" "F.Paste")
			(net "GND")
		)
		(pad "DA5" smd circle
			(at -30.699964 30.329886 180)
			(size 0.450088 0.450088)
			(layers "F.Cu" "F.Mask" "F.Paste")
			(net "M_K_CPU1_SB_DQ<26>")
		)
		(pad "DA6" smd circle
			(at -29.75991 30.329886 180)
			(size 0.450088 0.450088)
			(layers "F.Cu" "F.Mask" "F.Paste")
			(net "GND")
		)
		(pad "DA7" smd circle
			(at -28.82011 30.329886 180)
			(size 0.450088 0.450088)
			(layers "F.Cu" "F.Mask" "F.Paste")
			(net "M_K_CPU1_SB_DQ<25>")
		)
		(pad "DA8" smd circle
			(at -27.880056 30.329886 180)
			(size 0.450088 0.450088)
			(layers "F.Cu" "F.Mask" "F.Paste")
			(net "GND")
		)
		(pad "DA9" smd circle
			(at -26.940002 30.329886 180)
			(size 0.450088 0.450088)
			(layers "F.Cu" "F.Mask" "F.Paste")
			(net "M_L_CPU1_SB_DQ<26>")
		)
		(pad "DA10" smd circle
			(at -25.999948 30.329886 180)
			(size 0.450088 0.450088)
			(layers "F.Cu" "F.Mask" "F.Paste")
			(net "M_L_CPU1_SB_DQ<25>")
		)
		(pad "DA11" smd circle
			(at -25.059894 30.329886 180)
			(size 0.450088 0.450088)
			(layers "F.Cu" "F.Mask" "F.Paste")
			(net "GND")
		)
		(pad "DA12" smd circle
			(at -24.120094 30.329886 180)
			(size 0.450088 0.450088)
			(layers "F.Cu" "F.Mask" "F.Paste")
			(net "M_H_CPU1_SB_DQ<26>")
		)
		(pad "DA13" smd circle
			(at -23.18004 30.329886 180)
			(size 0.450088 0.450088)
			(layers "F.Cu" "F.Mask" "F.Paste")
			(net "GND")
		)
		(pad "DA14" smd circle
			(at -22.239986 30.329886 180)
			(size 0.450088 0.450088)
			(layers "F.Cu" "F.Mask" "F.Paste")
			(net "M_H_CPU1_SB_DQ<25>")
		)
		(pad "DA15" smd circle
			(at -21.299932 30.329886 180)
			(size 0.450088 0.450088)
			(layers "F.Cu" "F.Mask" "F.Paste")
			(net "GND")
		)
		(pad "DA16" smd circle
			(at -20.359878 30.329886 180)
			(size 0.450088 0.450088)
			(layers "F.Cu" "F.Mask" "F.Paste")
			(net "M_J_CPU1_SB_DQ<26>")
		)
		(pad "DA17" smd circle
			(at -19.420078 30.329886 180)
			(size 0.450088 0.450088)
			(layers "F.Cu" "F.Mask" "F.Paste")
			(net "M_J_CPU1_SB_DQ<25>")
		)
		(pad "DA18" smd circle
			(at -18.480024 30.329886 180)
			(size 0.450088 0.450088)
			(layers "F.Cu" "F.Mask" "F.Paste")
			(net "GND")
		)
		(pad "DA19" smd circle
			(at -17.53997 30.329886 180)
			(size 0.450088 0.450088)
			(layers "F.Cu" "F.Mask" "F.Paste")
			(net "M_I_CPU1_SB_DQ<26>")
		)
		(pad "DA20" smd circle
			(at -16.599916 30.329886 180)
			(size 0.450088 0.450088)
			(layers "F.Cu" "F.Mask" "F.Paste")
			(net "GND")
		)
		(pad "DA21" smd circle
			(at -15.660116 30.329886 180)
			(size 0.450088 0.450088)
			(layers "F.Cu" "F.Mask" "F.Paste")
			(net "M_I_CPU1_SB_DQ<25>")
		)
		(pad "DA22" smd circle
			(at -14.720062 30.329886 180)
			(size 0.450088 0.450088)
			(layers "F.Cu" "F.Mask" "F.Paste")
			(net "GND")
		)
		(pad "DA23" smd circle
			(at -13.780008 30.329886 180)
			(size 0.450088 0.450088)
			(layers "F.Cu" "F.Mask" "F.Paste")
			(net "P5E_CPU1_P3_RX_DP<14>")
		)
		(pad "DA24" smd circle
			(at -12.839954 30.329886 180)
			(size 0.450088 0.450088)
			(layers "F.Cu" "F.Mask" "F.Paste")
			(net "P5E_CPU1_P3_RX_DN<14>")
		)
		(pad "DA25" smd circle
			(at -11.8999 30.329886 180)
			(size 0.450088 0.450088)
			(layers "F.Cu" "F.Mask" "F.Paste")
			(net "GND")
		)
		(pad "DA26" smd circle
			(at -10.9601 30.329886 180)
			(size 0.450088 0.450088)
			(layers "F.Cu" "F.Mask" "F.Paste")
			(net "P5E_CPU1_P3_RX_DP<11>")
		)
		(pad "DA27" smd circle
			(at -10.020046 30.329886 180)
			(size 0.450088 0.450088)
			(layers "F.Cu" "F.Mask" "F.Paste")
			(net "P5E_CPU1_P3_RX_DN<11>")
		)
		(pad "DA28" smd circle
			(at -9.079992 30.329886 180)
			(size 0.450088 0.450088)
			(layers "F.Cu" "F.Mask" "F.Paste")
			(net "GND")
		)
		(pad "DA29" smd circle
			(at -8.139938 30.329886 180)
			(size 0.450088 0.450088)
			(layers "F.Cu" "F.Mask" "F.Paste")
			(net "P5E_CPU1_P3_RX_DP<8>")
		)
		(pad "DA30" smd circle
			(at -7.199884 30.329886 180)
			(size 0.450088 0.450088)
			(layers "F.Cu" "F.Mask" "F.Paste")
			(net "P5E_CPU1_P3_RX_DN<8>")
		)
		(pad "DA31" smd circle
			(at -6.260084 30.329886 180)
			(size 0.450088 0.450088)
			(layers "F.Cu" "F.Mask" "F.Paste")
			(net "GND")
		)
		(pad "DA32" smd circle
			(at -5.32003 30.329886 180)
			(size 0.450088 0.450088)
			(layers "F.Cu" "F.Mask" "F.Paste")
			(net "P5E_CPU1_P3_RX_DP<5>")
		)
		(pad "DA33" smd circle
			(at -4.379976 30.329886 180)
			(size 0.450088 0.450088)
			(layers "F.Cu" "F.Mask" "F.Paste")
			(net "P5E_CPU1_P3_RX_DN<5>")
		)
		(pad "DA34" smd circle
			(at -3.439922 30.329886 180)
			(size 0.450088 0.450088)
			(layers "F.Cu" "F.Mask" "F.Paste")
			(net "GND")
		)
		(pad "DA35" smd circle
			(at -2.500122 30.329886 180)
			(size 0.450088 0.450088)
			(layers "F.Cu" "F.Mask" "F.Paste")
			(net "PVDDCR_CPU1_P1")
		)
		(pad "DA36" smd circle
			(at -1.560068 30.329886 180)
			(size 0.450088 0.450088)
			(layers "F.Cu" "F.Mask" "F.Paste")
			(net "PVDDCR_CPU1_P1")
		)
		(pad "DA40" smd circle
			(at 1.260094 30.329886 180)
			(size 0.450088 0.450088)
			(layers "F.Cu" "F.Mask" "F.Paste")
			(net "PVDDCR_CPU1_P1")
		)
		(pad "DA41" smd circle
			(at 2.199894 30.329886 180)
			(size 0.450088 0.450088)
			(layers "F.Cu" "F.Mask" "F.Paste")
			(net "PVDDCR_CPU1_P1")
		)
		(pad "DA42" smd circle
			(at 3.139948 30.329886 180)
			(size 0.450088 0.450088)
			(layers "F.Cu" "F.Mask" "F.Paste")
			(net "GND")
		)
		(pad "DA43" smd circle
			(at 4.080002 30.329886 180)
			(size 0.450088 0.450088)
			(layers "F.Cu" "F.Mask" "F.Paste")
			(net "P5E_CPU1_P1_TX_DN<10>")
		)
		(pad "DA44" smd circle
			(at 5.020056 30.329886 180)
			(size 0.450088 0.450088)
			(layers "F.Cu" "F.Mask" "F.Paste")
			(net "P5E_CPU1_P1_TX_DP<10>")
		)
		(pad "DA45" smd circle
			(at 5.96011 30.329886 180)
			(size 0.450088 0.450088)
			(layers "F.Cu" "F.Mask" "F.Paste")
			(net "GND")
		)
		(pad "DA46" smd circle
			(at 6.89991 30.329886 180)
			(size 0.450088 0.450088)
			(layers "F.Cu" "F.Mask" "F.Paste")
			(net "P5E_CPU1_P1_TX_DN<7>")
		)
		(pad "DA47" smd circle
			(at 7.839964 30.329886 180)
			(size 0.450088 0.450088)
			(layers "F.Cu" "F.Mask" "F.Paste")
			(net "P5E_CPU1_P1_TX_DP<7>")
		)
		(pad "DA48" smd circle
			(at 8.780018 30.329886 180)
			(size 0.450088 0.450088)
			(layers "F.Cu" "F.Mask" "F.Paste")
			(net "GND")
		)
		(pad "DA49" smd circle
			(at 9.720072 30.329886 180)
			(size 0.450088 0.450088)
			(layers "F.Cu" "F.Mask" "F.Paste")
			(net "P5E_CPU1_P1_TX_DN<4>")
		)
		(pad "DA50" smd circle
			(at 10.659872 30.329886 180)
			(size 0.450088 0.450088)
			(layers "F.Cu" "F.Mask" "F.Paste")
			(net "P5E_CPU1_P1_TX_DP<4>")
		)
		(pad "DA51" smd circle
			(at 11.599926 30.329886 180)
			(size 0.450088 0.450088)
			(layers "F.Cu" "F.Mask" "F.Paste")
			(net "GND")
		)
		(pad "DA52" smd circle
			(at 12.53998 30.329886 180)
			(size 0.450088 0.450088)
			(layers "F.Cu" "F.Mask" "F.Paste")
			(net "P5E_CPU1_P1_TX_DN<1>")
		)
		(pad "DA53" smd circle
			(at 13.480034 30.329886 180)
			(size 0.450088 0.450088)
			(layers "F.Cu" "F.Mask" "F.Paste")
			(net "P5E_CPU1_P1_TX_DP<1>")
		)
		(pad "DA54" smd circle
			(at 14.420088 30.329886 180)
			(size 0.450088 0.450088)
			(layers "F.Cu" "F.Mask" "F.Paste")
			(net "GND")
		)
		(pad "DA55" smd circle
			(at 15.359888 30.329886 180)
			(size 0.450088 0.450088)
			(layers "F.Cu" "F.Mask" "F.Paste")
			(net "M_C_CPU1_SB_DQ<25>")
		)
		(pad "DA56" smd circle
			(at 16.299942 30.329886 180)
			(size 0.450088 0.450088)
			(layers "F.Cu" "F.Mask" "F.Paste")
			(net "GND")
		)
		(pad "DA57" smd circle
			(at 17.239996 30.329886 180)
			(size 0.450088 0.450088)
			(layers "F.Cu" "F.Mask" "F.Paste")
			(net "M_C_CPU1_SB_DQ<26>")
		)
		(pad "DA58" smd circle
			(at 18.18005 30.329886 180)
			(size 0.450088 0.450088)
			(layers "F.Cu" "F.Mask" "F.Paste")
			(net "GND")
		)
		(pad "DA59" smd circle
			(at 19.120104 30.329886 180)
			(size 0.450088 0.450088)
			(layers "F.Cu" "F.Mask" "F.Paste")
			(net "M_D_CPU1_SB_DQ<25>")
		)
		(pad "DA60" smd circle
			(at 20.059904 30.329886 180)
			(size 0.450088 0.450088)
			(layers "F.Cu" "F.Mask" "F.Paste")
			(net "M_D_CPU1_SB_DQ<26>")
		)
		(pad "DA61" smd circle
			(at 20.999958 30.329886 180)
			(size 0.450088 0.450088)
			(layers "F.Cu" "F.Mask" "F.Paste")
			(net "GND")
		)
		(pad "DA62" smd circle
			(at 21.940012 30.329886 180)
			(size 0.450088 0.450088)
			(layers "F.Cu" "F.Mask" "F.Paste")
			(net "M_B_CPU1_SB_DQ<25>")
		)
		(pad "DA63" smd circle
			(at 22.880066 30.329886 180)
			(size 0.450088 0.450088)
			(layers "F.Cu" "F.Mask" "F.Paste")
			(net "GND")
		)
		(pad "DA64" smd circle
			(at 23.82012 30.329886 180)
			(size 0.450088 0.450088)
			(layers "F.Cu" "F.Mask" "F.Paste")
			(net "M_B_CPU1_SB_DQ<26>")
		)
		(pad "DA65" smd circle
			(at 24.75992 30.329886 180)
			(size 0.450088 0.450088)
			(layers "F.Cu" "F.Mask" "F.Paste")
			(net "GND")
		)
		(pad "DA66" smd circle
			(at 25.699974 30.329886 180)
			(size 0.450088 0.450088)
			(layers "F.Cu" "F.Mask" "F.Paste")
			(net "M_F_CPU1_SB_DQ<25>")
		)
		(pad "DA67" smd circle
			(at 26.640028 30.329886 180)
			(size 0.450088 0.450088)
			(layers "F.Cu" "F.Mask" "F.Paste")
			(net "M_F_CPU1_SB_DQ<26>")
		)
		(pad "DA68" smd circle
			(at 27.580082 30.329886 180)
			(size 0.450088 0.450088)
			(layers "F.Cu" "F.Mask" "F.Paste")
			(net "GND")
		)
		(pad "DA69" smd circle
			(at 28.519882 30.329886 180)
			(size 0.450088 0.450088)
			(layers "F.Cu" "F.Mask" "F.Paste")
			(net "M_E_CPU1_SB_DQ<25>")
		)
		(pad "DA70" smd circle
			(at 29.459936 30.329886 180)
			(size 0.450088 0.450088)
			(layers "F.Cu" "F.Mask" "F.Paste")
			(net "GND")
		)
		(pad "DA71" smd circle
			(at 30.39999 30.329886 180)
			(size 0.450088 0.450088)
			(layers "F.Cu" "F.Mask" "F.Paste")
			(net "M_E_CPU1_SB_DQ<26>")
		)
		(pad "DA72" smd circle
			(at 31.340044 30.329886 180)
			(size 0.450088 0.450088)
			(layers "F.Cu" "F.Mask" "F.Paste")
			(net "GND")
		)
		(pad "DA73" smd circle
			(at 32.280098 30.329886 180)
			(size 0.450088 0.450088)
			(layers "F.Cu" "F.Mask" "F.Paste")
			(net "M_A_CPU1_SB_DQ<25>")
		)
		(pad "DA74" smd circle
			(at 33.219898 30.329886 180)
			(size 0.450088 0.450088)
			(layers "F.Cu" "F.Mask" "F.Paste")
			(net "M_A_CPU1_SB_DQ<26>")
		)
		(pad "DA75" smd circle
			(at 34.159952 30.329886 180)
			(size 0.450088 0.450088)
			(layers "F.Cu" "F.Mask" "F.Paste")
			(net "GND")
		)
		(pad "DB2" smd circle
			(at -33.990026 31.139892 180)
			(size 0.450088 0.450088)
			(layers "F.Cu" "F.Mask" "F.Paste")
			(net "M_G_CPU1_SB_DQS_DP<3>")
		)
		(pad "DB3" smd circle
			(at -33.049972 31.139892 180)
			(size 0.450088 0.450088)
			(layers "F.Cu" "F.Mask" "F.Paste")
			(net "GND")
		)
		(pad "DB4" smd circle
			(at -32.109918 31.139892 180)
			(size 0.450088 0.450088)
			(layers "F.Cu" "F.Mask" "F.Paste")
			(net "M_G_CPU1_SB_DQ<27>")
		)
		(pad "DB5" smd circle
			(at -31.170118 31.139892 180)
			(size 0.450088 0.450088)
			(layers "F.Cu" "F.Mask" "F.Paste")
			(net "PVDD11_S3_P1")
		)
		(pad "DB6" smd circle
			(at -30.230064 31.139892 180)
			(size 0.450088 0.450088)
			(layers "F.Cu" "F.Mask" "F.Paste")
			(net "M_K_CPU1_SB_DQS_DP<3>")
		)
		(pad "DB7" smd circle
			(at -29.29001 31.139892 180)
			(size 0.450088 0.450088)
			(layers "F.Cu" "F.Mask" "F.Paste")
			(net "M_K_CPU1_SB_DQ<27>")
		)
		(pad "DB8" smd circle
			(at -28.349956 31.139892 180)
			(size 0.450088 0.450088)
			(layers "F.Cu" "F.Mask" "F.Paste")
			(net "GND")
		)
		(pad "DB9" smd circle
			(at -27.409902 31.139892 180)
			(size 0.450088 0.450088)
			(layers "F.Cu" "F.Mask" "F.Paste")
			(net "M_L_CPU1_SB_DQS_DP<3>")
		)
		(pad "DB10" smd circle
			(at -26.470102 31.139892 180)
			(size 0.450088 0.450088)
			(layers "F.Cu" "F.Mask" "F.Paste")
			(net "GND")
		)
		(pad "DB11" smd circle
			(at -25.530048 31.139892 180)
			(size 0.450088 0.450088)
			(layers "F.Cu" "F.Mask" "F.Paste")
			(net "M_L_CPU1_SB_DQ<27>")
		)
		(pad "DB12" smd circle
			(at -24.589994 31.139892 180)
			(size 0.450088 0.450088)
			(layers "F.Cu" "F.Mask" "F.Paste")
			(net "PVDD11_S3_P1")
		)
		(pad "DB13" smd circle
			(at -23.64994 31.139892 180)
			(size 0.450088 0.450088)
			(layers "F.Cu" "F.Mask" "F.Paste")
			(net "M_H_CPU1_SB_DQS_DP<3>")
		)
		(pad "DB14" smd circle
			(at -22.709886 31.139892 180)
			(size 0.450088 0.450088)
			(layers "F.Cu" "F.Mask" "F.Paste")
			(net "M_H_CPU1_SB_DQ<27>")
		)
		(pad "DB15" smd circle
			(at -21.770086 31.139892 180)
			(size 0.450088 0.450088)
			(layers "F.Cu" "F.Mask" "F.Paste")
			(net "GND")
		)
		(pad "DB16" smd circle
			(at -20.830032 31.139892 180)
			(size 0.450088 0.450088)
			(layers "F.Cu" "F.Mask" "F.Paste")
			(net "M_J_CPU1_SB_DQS_DP<3>")
		)
		(pad "DB17" smd circle
			(at -19.889978 31.139892 180)
			(size 0.450088 0.450088)
			(layers "F.Cu" "F.Mask" "F.Paste")
			(net "GND")
		)
		(pad "DB18" smd circle
			(at -18.949924 31.139892 180)
			(size 0.450088 0.450088)
			(layers "F.Cu" "F.Mask" "F.Paste")
			(net "M_J_CPU1_SB_DQ<27>")
		)
		(pad "DB19" smd circle
			(at -18.010124 31.139892 180)
			(size 0.450088 0.450088)
			(layers "F.Cu" "F.Mask" "F.Paste")
			(net "PVDD11_S3_P1")
		)
		(pad "DB20" smd circle
			(at -17.07007 31.139892 180)
			(size 0.450088 0.450088)
			(layers "F.Cu" "F.Mask" "F.Paste")
			(net "M_I_CPU1_SB_DQS_DP<3>")
		)
		(pad "DB21" smd circle
			(at -16.130016 31.139892 180)
			(size 0.450088 0.450088)
			(layers "F.Cu" "F.Mask" "F.Paste")
			(net "M_I_CPU1_SB_DQ<27>")
		)
		(pad "DB22" smd circle
			(at -15.189962 31.139892 180)
			(size 0.450088 0.450088)
			(layers "F.Cu" "F.Mask" "F.Paste")
			(net "GND")
		)
		(pad "DB23" smd circle
			(at -14.249908 31.139892 180)
			(size 0.450088 0.450088)
			(layers "F.Cu" "F.Mask" "F.Paste")
			(net "PVDDCR_CPU1_P1")
		)
		(pad "DB24" smd circle
			(at -13.310108 31.139892 180)
			(size 0.450088 0.450088)
			(layers "F.Cu" "F.Mask" "F.Paste")
			(net "PVDDCR_CPU1_P1")
		)
		(pad "DB25" smd circle
			(at -12.370054 31.139892 180)
			(size 0.450088 0.450088)
			(layers "F.Cu" "F.Mask" "F.Paste")
			(net "GND")
		)
		(pad "DB26" smd circle
			(at -11.43 31.139892 180)
			(size 0.450088 0.450088)
			(layers "F.Cu" "F.Mask" "F.Paste")
			(net "PVDDCR_CPU1_P1")
		)
		(pad "DB27" smd circle
			(at -10.489946 31.139892 180)
			(size 0.450088 0.450088)
			(layers "F.Cu" "F.Mask" "F.Paste")
			(net "PVDDCR_CPU1_P1")
		)
		(pad "DB28" smd circle
			(at -9.549892 31.139892 180)
			(size 0.450088 0.450088)
			(layers "F.Cu" "F.Mask" "F.Paste")
			(net "GND")
		)
		(pad "DB29" smd circle
			(at -8.610092 31.139892 180)
			(size 0.450088 0.450088)
			(layers "F.Cu" "F.Mask" "F.Paste")
			(net "PVDDCR_CPU1_P1")
		)
		(pad "DB30" smd circle
			(at -7.670038 31.139892 180)
			(size 0.450088 0.450088)
			(layers "F.Cu" "F.Mask" "F.Paste")
			(net "PVDDCR_CPU1_P1")
		)
		(pad "DB31" smd circle
			(at -6.729984 31.139892 180)
			(size 0.450088 0.450088)
			(layers "F.Cu" "F.Mask" "F.Paste")
			(net "GND")
		)
		(pad "DB32" smd circle
			(at -5.78993 31.139892 180)
			(size 0.450088 0.450088)
			(layers "F.Cu" "F.Mask" "F.Paste")
			(net "PVDDCR_CPU1_P1")
		)
		(pad "DB33" smd circle
			(at -4.849876 31.139892 180)
			(size 0.450088 0.450088)
			(layers "F.Cu" "F.Mask" "F.Paste")
			(net "PVDDCR_CPU1_P1")
		)
		(pad "DB34" smd circle
			(at -3.910076 31.139892 180)
			(size 0.450088 0.450088)
			(layers "F.Cu" "F.Mask" "F.Paste")
			(net "GND")
		)
		(pad "DB35" smd circle
			(at -2.970022 31.139892 180)
			(size 0.450088 0.450088)
			(layers "F.Cu" "F.Mask" "F.Paste")
			(net "P5E_CPU1_P3_RX_DP<2>")
		)
		(pad "DB36" smd circle
			(at -2.029968 31.139892 180)
			(size 0.450088 0.450088)
			(layers "F.Cu" "F.Mask" "F.Paste")
			(net "P5E_CPU1_P3_RX_DN<2>")
		)
		(pad "DB37" smd circle
			(at -1.089914 31.139892 180)
			(size 0.450088 0.450088)
			(layers "F.Cu" "F.Mask" "F.Paste")
			(net "GND")
		)
		(pad "DB39" smd circle
			(at 0.78994 31.139892 180)
			(size 0.450088 0.450088)
			(layers "F.Cu" "F.Mask" "F.Paste")
			(net "GND")
		)
		(pad "DB40" smd circle
			(at 1.729994 31.139892 180)
			(size 0.450088 0.450088)
			(layers "F.Cu" "F.Mask" "F.Paste")
			(net "P5E_CPU1_P1_TX_DN<13>")
		)
		(pad "DB41" smd circle
			(at 2.670048 31.139892 180)
			(size 0.450088 0.450088)
			(layers "F.Cu" "F.Mask" "F.Paste")
			(net "P5E_CPU1_P1_TX_DP<13>")
		)
		(pad "DB42" smd circle
			(at 3.610102 31.139892 180)
			(size 0.450088 0.450088)
			(layers "F.Cu" "F.Mask" "F.Paste")
			(net "GND")
		)
		(pad "DB43" smd circle
			(at 4.549902 31.139892 180)
			(size 0.450088 0.450088)
			(layers "F.Cu" "F.Mask" "F.Paste")
			(net "PVDDCR_CPU1_P1")
		)
		(pad "DB44" smd circle
			(at 5.489956 31.139892 180)
			(size 0.450088 0.450088)
			(layers "F.Cu" "F.Mask" "F.Paste")
			(net "PVDDCR_CPU1_P1")
		)
		(pad "DB45" smd circle
			(at 6.43001 31.139892 180)
			(size 0.450088 0.450088)
			(layers "F.Cu" "F.Mask" "F.Paste")
			(net "GND")
		)
		(pad "DB46" smd circle
			(at 7.370064 31.139892 180)
			(size 0.450088 0.450088)
			(layers "F.Cu" "F.Mask" "F.Paste")
			(net "PVDDCR_CPU1_P1")
		)
		(pad "DB47" smd circle
			(at 8.310118 31.139892 180)
			(size 0.450088 0.450088)
			(layers "F.Cu" "F.Mask" "F.Paste")
			(net "PVDDCR_CPU1_P1")
		)
		(pad "DB48" smd circle
			(at 9.249918 31.139892 180)
			(size 0.450088 0.450088)
			(layers "F.Cu" "F.Mask" "F.Paste")
			(net "GND")
		)
		(pad "DB49" smd circle
			(at 10.189972 31.139892 180)
			(size 0.450088 0.450088)
			(layers "F.Cu" "F.Mask" "F.Paste")
			(net "PVDDCR_CPU1_P1")
		)
		(pad "DB50" smd circle
			(at 11.130026 31.139892 180)
			(size 0.450088 0.450088)
			(layers "F.Cu" "F.Mask" "F.Paste")
			(net "PVDDCR_CPU1_P1")
		)
		(pad "DB51" smd circle
			(at 12.07008 31.139892 180)
			(size 0.450088 0.450088)
			(layers "F.Cu" "F.Mask" "F.Paste")
			(net "GND")
		)
		(pad "DB52" smd circle
			(at 13.00988 31.139892 180)
			(size 0.450088 0.450088)
			(layers "F.Cu" "F.Mask" "F.Paste")
			(net "PVDDCR_CPU1_P1")
		)
		(pad "DB53" smd circle
			(at 13.949934 31.139892 180)
			(size 0.450088 0.450088)
			(layers "F.Cu" "F.Mask" "F.Paste")
			(net "PVDDCR_CPU1_P1")
		)
		(pad "DB54" smd circle
			(at 14.889988 31.139892 180)
			(size 0.450088 0.450088)
			(layers "F.Cu" "F.Mask" "F.Paste")
			(net "GND")
		)
		(pad "DB55" smd circle
			(at 15.830042 31.139892 180)
			(size 0.450088 0.450088)
			(layers "F.Cu" "F.Mask" "F.Paste")
			(net "M_C_CPU1_SB_DQ<27>")
		)
		(pad "DB56" smd circle
			(at 16.770096 31.139892 180)
			(size 0.450088 0.450088)
			(layers "F.Cu" "F.Mask" "F.Paste")
			(net "M_C_CPU1_SB_DQS_DP<3>")
		)
		(pad "DB57" smd circle
			(at 17.709896 31.139892 180)
			(size 0.450088 0.450088)
			(layers "F.Cu" "F.Mask" "F.Paste")
			(net "PVDDIO_P1")
		)
		(pad "DB58" smd circle
			(at 18.64995 31.139892 180)
			(size 0.450088 0.450088)
			(layers "F.Cu" "F.Mask" "F.Paste")
			(net "M_D_CPU1_SB_DQ<27>")
		)
		(pad "DB59" smd circle
			(at 19.590004 31.139892 180)
			(size 0.450088 0.450088)
			(layers "F.Cu" "F.Mask" "F.Paste")
			(net "GND")
		)
		(pad "DB60" smd circle
			(at 20.530058 31.139892 180)
			(size 0.450088 0.450088)
			(layers "F.Cu" "F.Mask" "F.Paste")
			(net "M_D_CPU1_SB_DQS_DP<3>")
		)
		(pad "DB61" smd circle
			(at 21.470112 31.139892 180)
			(size 0.450088 0.450088)
			(layers "F.Cu" "F.Mask" "F.Paste")
			(net "GND")
		)
		(pad "DB62" smd circle
			(at 22.409912 31.139892 180)
			(size 0.450088 0.450088)
			(layers "F.Cu" "F.Mask" "F.Paste")
			(net "M_B_CPU1_SB_DQ<27>")
		)
		(pad "DB63" smd circle
			(at 23.349966 31.139892 180)
			(size 0.450088 0.450088)
			(layers "F.Cu" "F.Mask" "F.Paste")
			(net "M_B_CPU1_SB_DQS_DP<3>")
		)
		(pad "DB64" smd circle
			(at 24.29002 31.139892 180)
			(size 0.450088 0.450088)
			(layers "F.Cu" "F.Mask" "F.Paste")
			(net "PVDDIO_P1")
		)
		(pad "DB65" smd circle
			(at 25.230074 31.139892 180)
			(size 0.450088 0.450088)
			(layers "F.Cu" "F.Mask" "F.Paste")
			(net "M_F_CPU1_SB_DQ<27>")
		)
		(pad "DB66" smd circle
			(at 26.170128 31.139892 180)
			(size 0.450088 0.450088)
			(layers "F.Cu" "F.Mask" "F.Paste")
			(net "GND")
		)
		(pad "DB67" smd circle
			(at 27.109928 31.139892 180)
			(size 0.450088 0.450088)
			(layers "F.Cu" "F.Mask" "F.Paste")
			(net "M_F_CPU1_SB_DQS_DP<3>")
		)
		(pad "DB68" smd circle
			(at 28.049982 31.139892 180)
			(size 0.450088 0.450088)
			(layers "F.Cu" "F.Mask" "F.Paste")
			(net "GND")
		)
		(pad "DB69" smd circle
			(at 28.990036 31.139892 180)
			(size 0.450088 0.450088)
			(layers "F.Cu" "F.Mask" "F.Paste")
			(net "M_E_CPU1_SB_DQ<27>")
		)
		(pad "DB70" smd circle
			(at 29.93009 31.139892 180)
			(size 0.450088 0.450088)
			(layers "F.Cu" "F.Mask" "F.Paste")
			(net "M_E_CPU1_SB_DQS_DP<3>")
		)
		(pad "DB71" smd circle
			(at 30.86989 31.139892 180)
			(size 0.450088 0.450088)
			(layers "F.Cu" "F.Mask" "F.Paste")
			(net "PVDDIO_P1")
		)
		(pad "DB72" smd circle
			(at 31.809944 31.139892 180)
			(size 0.450088 0.450088)
			(layers "F.Cu" "F.Mask" "F.Paste")
			(net "M_A_CPU1_SB_DQ<27>")
		)
		(pad "DB73" smd circle
			(at 32.749998 31.139892 180)
			(size 0.450088 0.450088)
			(layers "F.Cu" "F.Mask" "F.Paste")
			(net "GND")
		)
		(pad "DB74" smd circle
			(at 33.690052 31.139892 180)
			(size 0.450088 0.450088)
			(layers "F.Cu" "F.Mask" "F.Paste")
			(net "M_A_CPU1_SB_DQS_DP<3>")
		)
		(pad "DC1" smd circle
			(at -34.459926 31.949898 180)
			(size 0.450088 0.450088)
			(layers "F.Cu" "F.Mask" "F.Paste")
			(net "GND")
		)
		(pad "DC2" smd circle
			(at -33.519872 31.949898 180)
			(size 0.450088 0.450088)
			(layers "F.Cu" "F.Mask" "F.Paste")
			(net "M_G_CPU1_SB_DQS_DN<3>")
		)
		(pad "DC3" smd circle
			(at -32.580072 31.949898 180)
			(size 0.450088 0.450088)
			(layers "F.Cu" "F.Mask" "F.Paste")
			(net "M_G_CPU1_SB_DQS_DN<8>")
		)
		(pad "DC4" smd circle
			(at -31.640018 31.949898 180)
			(size 0.450088 0.450088)
			(layers "F.Cu" "F.Mask" "F.Paste")
			(net "GND")
		)
		(pad "DC5" smd circle
			(at -30.699964 31.949898 180)
			(size 0.450088 0.450088)
			(layers "F.Cu" "F.Mask" "F.Paste")
			(net "M_K_CPU1_SB_DQS_DN<3>")
		)
		(pad "DC6" smd circle
			(at -29.75991 31.949898 180)
			(size 0.450088 0.450088)
			(layers "F.Cu" "F.Mask" "F.Paste")
			(net "GND")
		)
		(pad "DC7" smd circle
			(at -28.82011 31.949898 180)
			(size 0.450088 0.450088)
			(layers "F.Cu" "F.Mask" "F.Paste")
			(net "M_K_CPU1_SB_DQS_DN<8>")
		)
		(pad "DC8" smd circle
			(at -27.880056 31.949898 180)
			(size 0.450088 0.450088)
			(layers "F.Cu" "F.Mask" "F.Paste")
			(net "GND")
		)
		(pad "DC9" smd circle
			(at -26.940002 31.949898 180)
			(size 0.450088 0.450088)
			(layers "F.Cu" "F.Mask" "F.Paste")
			(net "M_L_CPU1_SB_DQS_DN<3>")
		)
		(pad "DC10" smd circle
			(at -25.999948 31.949898 180)
			(size 0.450088 0.450088)
			(layers "F.Cu" "F.Mask" "F.Paste")
			(net "M_L_CPU1_SB_DQS_DN<8>")
		)
		(pad "DC11" smd circle
			(at -25.059894 31.949898 180)
			(size 0.450088 0.450088)
			(layers "F.Cu" "F.Mask" "F.Paste")
			(net "GND")
		)
		(pad "DC12" smd circle
			(at -24.120094 31.949898 180)
			(size 0.450088 0.450088)
			(layers "F.Cu" "F.Mask" "F.Paste")
			(net "M_H_CPU1_SB_DQS_DN<3>")
		)
		(pad "DC13" smd circle
			(at -23.18004 31.949898 180)
			(size 0.450088 0.450088)
			(layers "F.Cu" "F.Mask" "F.Paste")
			(net "GND")
		)
		(pad "DC14" smd circle
			(at -22.239986 31.949898 180)
			(size 0.450088 0.450088)
			(layers "F.Cu" "F.Mask" "F.Paste")
			(net "M_H_CPU1_SB_DQS_DN<8>")
		)
		(pad "DC15" smd circle
			(at -21.299932 31.949898 180)
			(size 0.450088 0.450088)
			(layers "F.Cu" "F.Mask" "F.Paste")
			(net "GND")
		)
		(pad "DC16" smd circle
			(at -20.359878 31.949898 180)
			(size 0.450088 0.450088)
			(layers "F.Cu" "F.Mask" "F.Paste")
			(net "M_J_CPU1_SB_DQS_DN<3>")
		)
		(pad "DC17" smd circle
			(at -19.420078 31.949898 180)
			(size 0.450088 0.450088)
			(layers "F.Cu" "F.Mask" "F.Paste")
			(net "M_J_CPU1_SB_DQS_DN<8>")
		)
		(pad "DC18" smd circle
			(at -18.480024 31.949898 180)
			(size 0.450088 0.450088)
			(layers "F.Cu" "F.Mask" "F.Paste")
			(net "GND")
		)
		(pad "DC19" smd circle
			(at -17.53997 31.949898 180)
			(size 0.450088 0.450088)
			(layers "F.Cu" "F.Mask" "F.Paste")
			(net "M_I_CPU1_SB_DQS_DN<3>")
		)
		(pad "DC20" smd circle
			(at -16.599916 31.949898 180)
			(size 0.450088 0.450088)
			(layers "F.Cu" "F.Mask" "F.Paste")
			(net "GND")
		)
		(pad "DC21" smd circle
			(at -15.660116 31.949898 180)
			(size 0.450088 0.450088)
			(layers "F.Cu" "F.Mask" "F.Paste")
			(net "M_I_CPU1_SB_DQS_DN<8>")
		)
		(pad "DC22" smd circle
			(at -14.720062 31.949898 180)
			(size 0.450088 0.450088)
			(layers "F.Cu" "F.Mask" "F.Paste")
			(net "GND")
		)
		(pad "DC23" smd circle
			(at -13.780008 31.949898 180)
			(size 0.450088 0.450088)
			(layers "F.Cu" "F.Mask" "F.Paste")
			(net "P5E_CPU1_P3_RX_DP<13>")
		)
		(pad "DC24" smd circle
			(at -12.839954 31.949898 180)
			(size 0.450088 0.450088)
			(layers "F.Cu" "F.Mask" "F.Paste")
			(net "P5E_CPU1_P3_RX_DN<13>")
		)
		(pad "DC25" smd circle
			(at -11.8999 31.949898 180)
			(size 0.450088 0.450088)
			(layers "F.Cu" "F.Mask" "F.Paste")
			(net "GND")
		)
		(pad "DC26" smd circle
			(at -10.9601 31.949898 180)
			(size 0.450088 0.450088)
			(layers "F.Cu" "F.Mask" "F.Paste")
			(net "P5E_CPU1_P3_RX_DP<10>")
		)
		(pad "DC27" smd circle
			(at -10.020046 31.949898 180)
			(size 0.450088 0.450088)
			(layers "F.Cu" "F.Mask" "F.Paste")
			(net "P5E_CPU1_P3_RX_DN<10>")
		)
		(pad "DC28" smd circle
			(at -9.079992 31.949898 180)
			(size 0.450088 0.450088)
			(layers "F.Cu" "F.Mask" "F.Paste")
			(net "GND")
		)
		(pad "DC29" smd circle
			(at -8.139938 31.949898 180)
			(size 0.450088 0.450088)
			(layers "F.Cu" "F.Mask" "F.Paste")
			(net "P5E_CPU1_P3_RX_DP<7>")
		)
		(pad "DC30" smd circle
			(at -7.199884 31.949898 180)
			(size 0.450088 0.450088)
			(layers "F.Cu" "F.Mask" "F.Paste")
			(net "P5E_CPU1_P3_RX_DN<7>")
		)
		(pad "DC31" smd circle
			(at -6.260084 31.949898 180)
			(size 0.450088 0.450088)
			(layers "F.Cu" "F.Mask" "F.Paste")
			(net "GND")
		)
		(pad "DC32" smd circle
			(at -5.32003 31.949898 180)
			(size 0.450088 0.450088)
			(layers "F.Cu" "F.Mask" "F.Paste")
			(net "P5E_CPU1_P3_RX_DP<4>")
		)
		(pad "DC33" smd circle
			(at -4.379976 31.949898 180)
			(size 0.450088 0.450088)
			(layers "F.Cu" "F.Mask" "F.Paste")
			(net "P5E_CPU1_P3_RX_DN<4>")
		)
		(pad "DC34" smd circle
			(at -3.439922 31.949898 180)
			(size 0.450088 0.450088)
			(layers "F.Cu" "F.Mask" "F.Paste")
			(net "GND")
		)
		(pad "DC35" smd circle
			(at -2.500122 31.949898 180)
			(size 0.450088 0.450088)
			(layers "F.Cu" "F.Mask" "F.Paste")
			(net "PVDDCR_CPU1_P1")
		)
		(pad "DC36" smd circle
			(at -1.560068 31.949898 180)
			(size 0.450088 0.450088)
			(layers "F.Cu" "F.Mask" "F.Paste")
			(net "PVDDCR_CPU1_P1")
		)
		(pad "DC40" smd circle
			(at 1.260094 31.949898 180)
			(size 0.450088 0.450088)
			(layers "F.Cu" "F.Mask" "F.Paste")
			(net "PVDDCR_CPU1_P1")
		)
		(pad "DC41" smd circle
			(at 2.199894 31.949898 180)
			(size 0.450088 0.450088)
			(layers "F.Cu" "F.Mask" "F.Paste")
			(net "PVDDCR_CPU1_P1")
		)
		(pad "DC42" smd circle
			(at 3.139948 31.949898 180)
			(size 0.450088 0.450088)
			(layers "F.Cu" "F.Mask" "F.Paste")
			(net "GND")
		)
		(pad "DC43" smd circle
			(at 4.080002 31.949898 180)
			(size 0.450088 0.450088)
			(layers "F.Cu" "F.Mask" "F.Paste")
			(net "P5E_CPU1_P1_TX_DN<11>")
		)
		(pad "DC44" smd circle
			(at 5.020056 31.949898 180)
			(size 0.450088 0.450088)
			(layers "F.Cu" "F.Mask" "F.Paste")
			(net "P5E_CPU1_P1_TX_DP<11>")
		)
		(pad "DC45" smd circle
			(at 5.96011 31.949898 180)
			(size 0.450088 0.450088)
			(layers "F.Cu" "F.Mask" "F.Paste")
			(net "GND")
		)
		(pad "DC46" smd circle
			(at 6.89991 31.949898 180)
			(size 0.450088 0.450088)
			(layers "F.Cu" "F.Mask" "F.Paste")
			(net "P5E_CPU1_P1_TX_DN<8>")
		)
		(pad "DC47" smd circle
			(at 7.839964 31.949898 180)
			(size 0.450088 0.450088)
			(layers "F.Cu" "F.Mask" "F.Paste")
			(net "P5E_CPU1_P1_TX_DP<8>")
		)
		(pad "DC48" smd circle
			(at 8.780018 31.949898 180)
			(size 0.450088 0.450088)
			(layers "F.Cu" "F.Mask" "F.Paste")
			(net "GND")
		)
		(pad "DC49" smd circle
			(at 9.720072 31.949898 180)
			(size 0.450088 0.450088)
			(layers "F.Cu" "F.Mask" "F.Paste")
			(net "P5E_CPU1_P1_TX_DN<5>")
		)
		(pad "DC50" smd circle
			(at 10.659872 31.949898 180)
			(size 0.450088 0.450088)
			(layers "F.Cu" "F.Mask" "F.Paste")
			(net "P5E_CPU1_P1_TX_DP<5>")
		)
		(pad "DC51" smd circle
			(at 11.599926 31.949898 180)
			(size 0.450088 0.450088)
			(layers "F.Cu" "F.Mask" "F.Paste")
			(net "GND")
		)
		(pad "DC52" smd circle
			(at 12.53998 31.949898 180)
			(size 0.450088 0.450088)
			(layers "F.Cu" "F.Mask" "F.Paste")
			(net "P5E_CPU1_P1_TX_DN<2>")
		)
		(pad "DC53" smd circle
			(at 13.480034 31.949898 180)
			(size 0.450088 0.450088)
			(layers "F.Cu" "F.Mask" "F.Paste")
			(net "P5E_CPU1_P1_TX_DP<2>")
		)
		(pad "DC54" smd circle
			(at 14.420088 31.949898 180)
			(size 0.450088 0.450088)
			(layers "F.Cu" "F.Mask" "F.Paste")
			(net "GND")
		)
		(pad "DC55" smd circle
			(at 15.359888 31.949898 180)
			(size 0.450088 0.450088)
			(layers "F.Cu" "F.Mask" "F.Paste")
			(net "M_C_CPU1_SB_DQS_DN<8>")
		)
		(pad "DC56" smd circle
			(at 16.299942 31.949898 180)
			(size 0.450088 0.450088)
			(layers "F.Cu" "F.Mask" "F.Paste")
			(net "GND")
		)
		(pad "DC57" smd circle
			(at 17.239996 31.949898 180)
			(size 0.450088 0.450088)
			(layers "F.Cu" "F.Mask" "F.Paste")
			(net "M_C_CPU1_SB_DQS_DN<3>")
		)
		(pad "DC58" smd circle
			(at 18.18005 31.949898 180)
			(size 0.450088 0.450088)
			(layers "F.Cu" "F.Mask" "F.Paste")
			(net "GND")
		)
		(pad "DC59" smd circle
			(at 19.120104 31.949898 180)
			(size 0.450088 0.450088)
			(layers "F.Cu" "F.Mask" "F.Paste")
			(net "M_D_CPU1_SB_DQS_DN<8>")
		)
		(pad "DC60" smd circle
			(at 20.059904 31.949898 180)
			(size 0.450088 0.450088)
			(layers "F.Cu" "F.Mask" "F.Paste")
			(net "M_D_CPU1_SB_DQS_DN<3>")
		)
		(pad "DC61" smd circle
			(at 20.999958 31.949898 180)
			(size 0.450088 0.450088)
			(layers "F.Cu" "F.Mask" "F.Paste")
			(net "GND")
		)
		(pad "DC62" smd circle
			(at 21.940012 31.949898 180)
			(size 0.450088 0.450088)
			(layers "F.Cu" "F.Mask" "F.Paste")
			(net "M_B_CPU1_SB_DQS_DN<8>")
		)
		(pad "DC63" smd circle
			(at 22.880066 31.949898 180)
			(size 0.450088 0.450088)
			(layers "F.Cu" "F.Mask" "F.Paste")
			(net "GND")
		)
		(pad "DC64" smd circle
			(at 23.82012 31.949898 180)
			(size 0.450088 0.450088)
			(layers "F.Cu" "F.Mask" "F.Paste")
			(net "M_B_CPU1_SB_DQS_DN<3>")
		)
		(pad "DC65" smd circle
			(at 24.75992 31.949898 180)
			(size 0.450088 0.450088)
			(layers "F.Cu" "F.Mask" "F.Paste")
			(net "GND")
		)
		(pad "DC66" smd circle
			(at 25.699974 31.949898 180)
			(size 0.450088 0.450088)
			(layers "F.Cu" "F.Mask" "F.Paste")
			(net "M_F_CPU1_SB_DQS_DN<8>")
		)
		(pad "DC67" smd circle
			(at 26.640028 31.949898 180)
			(size 0.450088 0.450088)
			(layers "F.Cu" "F.Mask" "F.Paste")
			(net "M_F_CPU1_SB_DQS_DN<3>")
		)
		(pad "DC68" smd circle
			(at 27.580082 31.949898 180)
			(size 0.450088 0.450088)
			(layers "F.Cu" "F.Mask" "F.Paste")
			(net "GND")
		)
		(pad "DC69" smd circle
			(at 28.519882 31.949898 180)
			(size 0.450088 0.450088)
			(layers "F.Cu" "F.Mask" "F.Paste")
			(net "M_E_CPU1_SB_DQS_DN<8>")
		)
		(pad "DC70" smd circle
			(at 29.459936 31.949898 180)
			(size 0.450088 0.450088)
			(layers "F.Cu" "F.Mask" "F.Paste")
			(net "GND")
		)
		(pad "DC71" smd circle
			(at 30.39999 31.949898 180)
			(size 0.450088 0.450088)
			(layers "F.Cu" "F.Mask" "F.Paste")
			(net "M_E_CPU1_SB_DQS_DN<3>")
		)
		(pad "DC72" smd circle
			(at 31.340044 31.949898 180)
			(size 0.450088 0.450088)
			(layers "F.Cu" "F.Mask" "F.Paste")
			(net "GND")
		)
		(pad "DC73" smd circle
			(at 32.280098 31.949898 180)
			(size 0.450088 0.450088)
			(layers "F.Cu" "F.Mask" "F.Paste")
			(net "M_A_CPU1_SB_DQS_DN<8>")
		)
		(pad "DC74" smd circle
			(at 33.219898 31.949898 180)
			(size 0.450088 0.450088)
			(layers "F.Cu" "F.Mask" "F.Paste")
			(net "M_A_CPU1_SB_DQS_DN<3>")
		)
		(pad "DC75" smd circle
			(at 34.159952 31.949898 180)
			(size 0.450088 0.450088)
			(layers "F.Cu" "F.Mask" "F.Paste")
			(net "GND")
		)
		(pad "DD2" smd circle
			(at -33.990026 32.759904 180)
			(size 0.450088 0.450088)
			(layers "F.Cu" "F.Mask" "F.Paste")
			(net "M_G_CPU1_SB_DQ<28>")
		)
		(pad "DD3" smd circle
			(at -33.049972 32.759904 180)
			(size 0.450088 0.450088)
			(layers "F.Cu" "F.Mask" "F.Paste")
			(net "GND")
		)
		(pad "DD4" smd circle
			(at -32.109918 32.759904 180)
			(size 0.450088 0.450088)
			(layers "F.Cu" "F.Mask" "F.Paste")
			(net "M_G_CPU1_SB_DQS_DP<8>")
		)
		(pad "DD5" smd circle
			(at -31.170118 32.759904 180)
			(size 0.450088 0.450088)
			(layers "F.Cu" "F.Mask" "F.Paste")
			(net "GND")
		)
		(pad "DD6" smd circle
			(at -30.230064 32.759904 180)
			(size 0.450088 0.450088)
			(layers "F.Cu" "F.Mask" "F.Paste")
			(net "M_K_CPU1_SB_DQ<28>")
		)
		(pad "DD7" smd circle
			(at -29.29001 32.759904 180)
			(size 0.450088 0.450088)
			(layers "F.Cu" "F.Mask" "F.Paste")
			(net "M_K_CPU1_SB_DQS_DP<8>")
		)
		(pad "DD8" smd circle
			(at -28.349956 32.759904 180)
			(size 0.450088 0.450088)
			(layers "F.Cu" "F.Mask" "F.Paste")
			(net "GND")
		)
		(pad "DD9" smd circle
			(at -27.409902 32.759904 180)
			(size 0.450088 0.450088)
			(layers "F.Cu" "F.Mask" "F.Paste")
			(net "M_L_CPU1_SB_DQ<28>")
		)
		(pad "DD10" smd circle
			(at -26.470102 32.759904 180)
			(size 0.450088 0.450088)
			(layers "F.Cu" "F.Mask" "F.Paste")
			(net "GND")
		)
		(pad "DD11" smd circle
			(at -25.530048 32.759904 180)
			(size 0.450088 0.450088)
			(layers "F.Cu" "F.Mask" "F.Paste")
			(net "M_L_CPU1_SB_DQS_DP<8>")
		)
		(pad "DD12" smd circle
			(at -24.589994 32.759904 180)
			(size 0.450088 0.450088)
			(layers "F.Cu" "F.Mask" "F.Paste")
			(net "GND")
		)
		(pad "DD13" smd circle
			(at -23.64994 32.759904 180)
			(size 0.450088 0.450088)
			(layers "F.Cu" "F.Mask" "F.Paste")
			(net "M_H_CPU1_SB_DQ<28>")
		)
		(pad "DD14" smd circle
			(at -22.709886 32.759904 180)
			(size 0.450088 0.450088)
			(layers "F.Cu" "F.Mask" "F.Paste")
			(net "M_H_CPU1_SB_DQS_DP<8>")
		)
		(pad "DD15" smd circle
			(at -21.770086 32.759904 180)
			(size 0.450088 0.450088)
			(layers "F.Cu" "F.Mask" "F.Paste")
			(net "GND")
		)
		(pad "DD16" smd circle
			(at -20.830032 32.759904 180)
			(size 0.450088 0.450088)
			(layers "F.Cu" "F.Mask" "F.Paste")
			(net "M_J_CPU1_SB_DQ<28>")
		)
		(pad "DD17" smd circle
			(at -19.889978 32.759904 180)
			(size 0.450088 0.450088)
			(layers "F.Cu" "F.Mask" "F.Paste")
			(net "GND")
		)
		(pad "DD18" smd circle
			(at -18.949924 32.759904 180)
			(size 0.450088 0.450088)
			(layers "F.Cu" "F.Mask" "F.Paste")
			(net "M_J_CPU1_SB_DQS_DP<8>")
		)
		(pad "DD19" smd circle
			(at -18.010124 32.759904 180)
			(size 0.450088 0.450088)
			(layers "F.Cu" "F.Mask" "F.Paste")
			(net "GND")
		)
		(pad "DD20" smd circle
			(at -17.07007 32.759904 180)
			(size 0.450088 0.450088)
			(layers "F.Cu" "F.Mask" "F.Paste")
			(net "M_I_CPU1_SB_DQ<28>")
		)
		(pad "DD21" smd circle
			(at -16.130016 32.759904 180)
			(size 0.450088 0.450088)
			(layers "F.Cu" "F.Mask" "F.Paste")
			(net "M_I_CPU1_SB_DQS_DP<8>")
		)
		(pad "DD22" smd circle
			(at -15.189962 32.759904 180)
			(size 0.450088 0.450088)
			(layers "F.Cu" "F.Mask" "F.Paste")
			(net "PVDDCR_CPU1_P1")
		)
		(pad "DD23" smd circle
			(at -14.249908 32.759904 180)
			(size 0.450088 0.450088)
			(layers "F.Cu" "F.Mask" "F.Paste")
			(net "GND")
		)
		(pad "DD24" smd circle
			(at -13.310108 32.759904 180)
			(size 0.450088 0.450088)
			(layers "F.Cu" "F.Mask" "F.Paste")
			(net "GND")
		)
		(pad "DD25" smd circle
			(at -12.370054 32.759904 180)
			(size 0.450088 0.450088)
			(layers "F.Cu" "F.Mask" "F.Paste")
			(net "PVDDCR_CPU1_P1")
		)
		(pad "DD26" smd circle
			(at -11.43 32.759904 180)
			(size 0.450088 0.450088)
			(layers "F.Cu" "F.Mask" "F.Paste")
			(net "GND")
		)
		(pad "DD27" smd circle
			(at -10.489946 32.759904 180)
			(size 0.450088 0.450088)
			(layers "F.Cu" "F.Mask" "F.Paste")
			(net "GND")
		)
		(pad "DD28" smd circle
			(at -9.549892 32.759904 180)
			(size 0.450088 0.450088)
			(layers "F.Cu" "F.Mask" "F.Paste")
			(net "PVDDCR_CPU1_P1")
		)
		(pad "DD29" smd circle
			(at -8.610092 32.759904 180)
			(size 0.450088 0.450088)
			(layers "F.Cu" "F.Mask" "F.Paste")
			(net "GND")
		)
		(pad "DD30" smd circle
			(at -7.670038 32.759904 180)
			(size 0.450088 0.450088)
			(layers "F.Cu" "F.Mask" "F.Paste")
			(net "GND")
		)
		(pad "DD31" smd circle
			(at -6.729984 32.759904 180)
			(size 0.450088 0.450088)
			(layers "F.Cu" "F.Mask" "F.Paste")
			(net "PVDDCR_CPU1_P1")
		)
		(pad "DD32" smd circle
			(at -5.78993 32.759904 180)
			(size 0.450088 0.450088)
			(layers "F.Cu" "F.Mask" "F.Paste")
			(net "GND")
		)
		(pad "DD33" smd circle
			(at -4.849876 32.759904 180)
			(size 0.450088 0.450088)
			(layers "F.Cu" "F.Mask" "F.Paste")
			(net "GND")
		)
		(pad "DD34" smd circle
			(at -3.910076 32.759904 180)
			(size 0.450088 0.450088)
			(layers "F.Cu" "F.Mask" "F.Paste")
			(net "PVDDCR_CPU1_P1")
		)
		(pad "DD35" smd circle
			(at -2.970022 32.759904 180)
			(size 0.450088 0.450088)
			(layers "F.Cu" "F.Mask" "F.Paste")
			(net "GND")
		)
		(pad "DD36" smd circle
			(at -2.029968 32.759904 180)
			(size 0.450088 0.450088)
			(layers "F.Cu" "F.Mask" "F.Paste")
			(net "GND")
		)
		(pad "DD37" smd circle
			(at -1.089914 32.759904 180)
			(size 0.450088 0.450088)
			(layers "F.Cu" "F.Mask" "F.Paste")
			(net "GND")
		)
		(pad "DD39" smd circle
			(at 0.78994 32.759904 180)
			(size 0.450088 0.450088)
			(layers "F.Cu" "F.Mask" "F.Paste")
			(net "GND")
		)
		(pad "DD40" smd circle
			(at 1.729994 32.759904 180)
			(size 0.450088 0.450088)
			(layers "F.Cu" "F.Mask" "F.Paste")
			(net "GND")
		)
		(pad "DD41" smd circle
			(at 2.670048 32.759904 180)
			(size 0.450088 0.450088)
			(layers "F.Cu" "F.Mask" "F.Paste")
			(net "GND")
		)
		(pad "DD42" smd circle
			(at 3.610102 32.759904 180)
			(size 0.450088 0.450088)
			(layers "F.Cu" "F.Mask" "F.Paste")
			(net "PVDDCR_CPU1_P1")
		)
		(pad "DD43" smd circle
			(at 4.549902 32.759904 180)
			(size 0.450088 0.450088)
			(layers "F.Cu" "F.Mask" "F.Paste")
			(net "GND")
		)
		(pad "DD44" smd circle
			(at 5.489956 32.759904 180)
			(size 0.450088 0.450088)
			(layers "F.Cu" "F.Mask" "F.Paste")
			(net "GND")
		)
		(pad "DD45" smd circle
			(at 6.43001 32.759904 180)
			(size 0.450088 0.450088)
			(layers "F.Cu" "F.Mask" "F.Paste")
			(net "PVDDCR_CPU1_P1")
		)
		(pad "DD46" smd circle
			(at 7.370064 32.759904 180)
			(size 0.450088 0.450088)
			(layers "F.Cu" "F.Mask" "F.Paste")
			(net "GND")
		)
		(pad "DD47" smd circle
			(at 8.310118 32.759904 180)
			(size 0.450088 0.450088)
			(layers "F.Cu" "F.Mask" "F.Paste")
			(net "GND")
		)
		(pad "DD48" smd circle
			(at 9.249918 32.759904 180)
			(size 0.450088 0.450088)
			(layers "F.Cu" "F.Mask" "F.Paste")
			(net "PVDDCR_CPU1_P1")
		)
		(pad "DD49" smd circle
			(at 10.189972 32.759904 180)
			(size 0.450088 0.450088)
			(layers "F.Cu" "F.Mask" "F.Paste")
			(net "GND")
		)
		(pad "DD50" smd circle
			(at 11.130026 32.759904 180)
			(size 0.450088 0.450088)
			(layers "F.Cu" "F.Mask" "F.Paste")
			(net "GND")
		)
		(pad "DD51" smd circle
			(at 12.07008 32.759904 180)
			(size 0.450088 0.450088)
			(layers "F.Cu" "F.Mask" "F.Paste")
			(net "PVDDCR_CPU1_P1")
		)
		(pad "DD52" smd circle
			(at 13.00988 32.759904 180)
			(size 0.450088 0.450088)
			(layers "F.Cu" "F.Mask" "F.Paste")
			(net "GND")
		)
		(pad "DD53" smd circle
			(at 13.949934 32.759904 180)
			(size 0.450088 0.450088)
			(layers "F.Cu" "F.Mask" "F.Paste")
			(net "GND")
		)
		(pad "DD54" smd circle
			(at 14.889988 32.759904 180)
			(size 0.450088 0.450088)
			(layers "F.Cu" "F.Mask" "F.Paste")
			(net "PVDDCR_CPU1_P1")
		)
		(pad "DD55" smd circle
			(at 15.830042 32.759904 180)
			(size 0.450088 0.450088)
			(layers "F.Cu" "F.Mask" "F.Paste")
			(net "M_C_CPU1_SB_DQS_DP<8>")
		)
		(pad "DD56" smd circle
			(at 16.770096 32.759904 180)
			(size 0.450088 0.450088)
			(layers "F.Cu" "F.Mask" "F.Paste")
			(net "M_C_CPU1_SB_DQ<28>")
		)
		(pad "DD57" smd circle
			(at 17.709896 32.759904 180)
			(size 0.450088 0.450088)
			(layers "F.Cu" "F.Mask" "F.Paste")
			(net "GND")
		)
		(pad "DD58" smd circle
			(at 18.64995 32.759904 180)
			(size 0.450088 0.450088)
			(layers "F.Cu" "F.Mask" "F.Paste")
			(net "M_D_CPU1_SB_DQS_DP<8>")
		)
		(pad "DD59" smd circle
			(at 19.590004 32.759904 180)
			(size 0.450088 0.450088)
			(layers "F.Cu" "F.Mask" "F.Paste")
			(net "GND")
		)
		(pad "DD60" smd circle
			(at 20.530058 32.759904 180)
			(size 0.450088 0.450088)
			(layers "F.Cu" "F.Mask" "F.Paste")
			(net "M_D_CPU1_SB_DQ<28>")
		)
		(pad "DD61" smd circle
			(at 21.470112 32.759904 180)
			(size 0.450088 0.450088)
			(layers "F.Cu" "F.Mask" "F.Paste")
			(net "GND")
		)
		(pad "DD62" smd circle
			(at 22.409912 32.759904 180)
			(size 0.450088 0.450088)
			(layers "F.Cu" "F.Mask" "F.Paste")
			(net "M_B_CPU1_SB_DQS_DP<8>")
		)
		(pad "DD63" smd circle
			(at 23.349966 32.759904 180)
			(size 0.450088 0.450088)
			(layers "F.Cu" "F.Mask" "F.Paste")
			(net "M_B_CPU1_SB_DQ<28>")
		)
		(pad "DD64" smd circle
			(at 24.29002 32.759904 180)
			(size 0.450088 0.450088)
			(layers "F.Cu" "F.Mask" "F.Paste")
			(net "GND")
		)
		(pad "DD65" smd circle
			(at 25.230074 32.759904 180)
			(size 0.450088 0.450088)
			(layers "F.Cu" "F.Mask" "F.Paste")
			(net "M_F_CPU1_SB_DQS_DP<8>")
		)
		(pad "DD66" smd circle
			(at 26.170128 32.759904 180)
			(size 0.450088 0.450088)
			(layers "F.Cu" "F.Mask" "F.Paste")
			(net "GND")
		)
		(pad "DD67" smd circle
			(at 27.109928 32.759904 180)
			(size 0.450088 0.450088)
			(layers "F.Cu" "F.Mask" "F.Paste")
			(net "M_F_CPU1_SB_DQ<28>")
		)
		(pad "DD68" smd circle
			(at 28.049982 32.759904 180)
			(size 0.450088 0.450088)
			(layers "F.Cu" "F.Mask" "F.Paste")
			(net "GND")
		)
		(pad "DD69" smd circle
			(at 28.990036 32.759904 180)
			(size 0.450088 0.450088)
			(layers "F.Cu" "F.Mask" "F.Paste")
			(net "M_E_CPU1_SB_DQS_DP<8>")
		)
		(pad "DD70" smd circle
			(at 29.93009 32.759904 180)
			(size 0.450088 0.450088)
			(layers "F.Cu" "F.Mask" "F.Paste")
			(net "M_E_CPU1_SB_DQ<28>")
		)
		(pad "DD71" smd circle
			(at 30.86989 32.759904 180)
			(size 0.450088 0.450088)
			(layers "F.Cu" "F.Mask" "F.Paste")
			(net "GND")
		)
		(pad "DD72" smd circle
			(at 31.809944 32.759904 180)
			(size 0.450088 0.450088)
			(layers "F.Cu" "F.Mask" "F.Paste")
			(net "M_A_CPU1_SB_DQS_DP<8>")
		)
		(pad "DD73" smd circle
			(at 32.749998 32.759904 180)
			(size 0.450088 0.450088)
			(layers "F.Cu" "F.Mask" "F.Paste")
			(net "GND")
		)
		(pad "DD74" smd circle
			(at 33.690052 32.759904 180)
			(size 0.450088 0.450088)
			(layers "F.Cu" "F.Mask" "F.Paste")
			(net "M_A_CPU1_SB_DQ<28>")
		)
		(pad "DE1" smd circle
			(at -34.459926 33.56991 180)
			(size 0.450088 0.450088)
			(layers "F.Cu" "F.Mask" "F.Paste")
			(net "GND")
		)
		(pad "DE2" smd circle
			(at -33.519872 33.56991 180)
			(size 0.450088 0.450088)
			(layers "F.Cu" "F.Mask" "F.Paste")
			(net "M_G_CPU1_SB_DQ<30>")
		)
		(pad "DE3" smd circle
			(at -32.580072 33.56991 180)
			(size 0.450088 0.450088)
			(layers "F.Cu" "F.Mask" "F.Paste")
			(net "M_G_CPU1_SB_DQ<29>")
		)
		(pad "DE4" smd circle
			(at -31.640018 33.56991 180)
			(size 0.450088 0.450088)
			(layers "F.Cu" "F.Mask" "F.Paste")
			(net "PVDD11_S3_P1")
		)
		(pad "DE5" smd circle
			(at -30.699964 33.56991 180)
			(size 0.450088 0.450088)
			(layers "F.Cu" "F.Mask" "F.Paste")
			(net "M_K_CPU1_SB_DQ<30>")
		)
		(pad "DE6" smd circle
			(at -29.75991 33.56991 180)
			(size 0.450088 0.450088)
			(layers "F.Cu" "F.Mask" "F.Paste")
			(net "GND")
		)
		(pad "DE7" smd circle
			(at -28.82011 33.56991 180)
			(size 0.450088 0.450088)
			(layers "F.Cu" "F.Mask" "F.Paste")
			(net "M_K_CPU1_SB_DQ<29>")
		)
		(pad "DE8" smd circle
			(at -27.880056 33.56991 180)
			(size 0.450088 0.450088)
			(layers "F.Cu" "F.Mask" "F.Paste")
			(net "GND")
		)
		(pad "DE9" smd circle
			(at -26.940002 33.56991 180)
			(size 0.450088 0.450088)
			(layers "F.Cu" "F.Mask" "F.Paste")
			(net "M_L_CPU1_SB_DQ<30>")
		)
		(pad "DE10" smd circle
			(at -25.999948 33.56991 180)
			(size 0.450088 0.450088)
			(layers "F.Cu" "F.Mask" "F.Paste")
			(net "M_L_CPU1_SB_DQ<29>")
		)
		(pad "DE11" smd circle
			(at -25.059894 33.56991 180)
			(size 0.450088 0.450088)
			(layers "F.Cu" "F.Mask" "F.Paste")
			(net "PVDD11_S3_P1")
		)
		(pad "DE12" smd circle
			(at -24.120094 33.56991 180)
			(size 0.450088 0.450088)
			(layers "F.Cu" "F.Mask" "F.Paste")
			(net "M_H_CPU1_SB_DQ<30>")
		)
		(pad "DE13" smd circle
			(at -23.18004 33.56991 180)
			(size 0.450088 0.450088)
			(layers "F.Cu" "F.Mask" "F.Paste")
			(net "GND")
		)
		(pad "DE14" smd circle
			(at -22.239986 33.56991 180)
			(size 0.450088 0.450088)
			(layers "F.Cu" "F.Mask" "F.Paste")
			(net "M_H_CPU1_SB_DQ<29>")
		)
		(pad "DE15" smd circle
			(at -21.299932 33.56991 180)
			(size 0.450088 0.450088)
			(layers "F.Cu" "F.Mask" "F.Paste")
			(net "GND")
		)
		(pad "DE16" smd circle
			(at -20.359878 33.56991 180)
			(size 0.450088 0.450088)
			(layers "F.Cu" "F.Mask" "F.Paste")
			(net "M_J_CPU1_SB_DQ<30>")
		)
		(pad "DE17" smd circle
			(at -19.420078 33.56991 180)
			(size 0.450088 0.450088)
			(layers "F.Cu" "F.Mask" "F.Paste")
			(net "M_J_CPU1_SB_DQ<29>")
		)
		(pad "DE18" smd circle
			(at -18.480024 33.56991 180)
			(size 0.450088 0.450088)
			(layers "F.Cu" "F.Mask" "F.Paste")
			(net "PVDD11_S3_P1")
		)
		(pad "DE19" smd circle
			(at -17.53997 33.56991 180)
			(size 0.450088 0.450088)
			(layers "F.Cu" "F.Mask" "F.Paste")
			(net "M_I_CPU1_SB_DQ<30>")
		)
		(pad "DE20" smd circle
			(at -16.599916 33.56991 180)
			(size 0.450088 0.450088)
			(layers "F.Cu" "F.Mask" "F.Paste")
			(net "GND")
		)
		(pad "DE21" smd circle
			(at -15.660116 33.56991 180)
			(size 0.450088 0.450088)
			(layers "F.Cu" "F.Mask" "F.Paste")
			(net "M_I_CPU1_SB_DQ<29>")
		)
		(pad "DE22" smd circle
			(at -14.720062 33.56991 180)
			(size 0.450088 0.450088)
			(layers "F.Cu" "F.Mask" "F.Paste")
			(net "PVDDCR_CPU1_P1")
		)
		(pad "DE23" smd circle
			(at -13.780008 33.56991 180)
			(size 0.450088 0.450088)
			(layers "F.Cu" "F.Mask" "F.Paste")
			(net "GND")
		)
		(pad "DE24" smd circle
			(at -12.839954 33.56991 180)
			(size 0.450088 0.450088)
			(layers "F.Cu" "F.Mask" "F.Paste")
			(net "Net_2110")
		)
		(pad "DE25" smd circle
			(at -11.8999 33.56991 180)
			(size 0.450088 0.450088)
			(layers "F.Cu" "F.Mask" "F.Paste")
			(net "PVDDCR_CPU1_P1")
		)
		(pad "DE26" smd circle
			(at -10.9601 33.56991 180)
			(size 0.450088 0.450088)
			(layers "F.Cu" "F.Mask" "F.Paste")
			(net "GND")
		)
		(pad "DE27" smd circle
			(at -10.020046 33.56991 180)
			(size 0.450088 0.450088)
			(layers "F.Cu" "F.Mask" "F.Paste")
			(net "Net_2117")
		)
		(pad "DE28" smd circle
			(at -9.079992 33.56991 180)
			(size 0.450088 0.450088)
			(layers "F.Cu" "F.Mask" "F.Paste")
			(net "PVDDCR_CPU1_P1")
		)
		(pad "DE29" smd circle
			(at -8.139938 33.56991 180)
			(size 0.450088 0.450088)
			(layers "F.Cu" "F.Mask" "F.Paste")
			(net "GND")
		)
		(pad "DE30" smd circle
			(at -7.199884 33.56991 180)
			(size 0.450088 0.450088)
			(layers "F.Cu" "F.Mask" "F.Paste")
			(net "Net_2076")
		)
		(pad "DE31" smd circle
			(at -6.260084 33.56991 180)
			(size 0.450088 0.450088)
			(layers "F.Cu" "F.Mask" "F.Paste")
			(net "PVDDCR_CPU1_P1")
		)
		(pad "DE32" smd circle
			(at -5.32003 33.56991 180)
			(size 0.450088 0.450088)
			(layers "F.Cu" "F.Mask" "F.Paste")
			(net "TP_SLOT2_BUF_SKU_ID1")
		)
		(pad "DE33" smd circle
			(at -4.379976 33.56991 180)
			(size 0.450088 0.450088)
			(layers "F.Cu" "F.Mask" "F.Paste")
			(net "GND")
		)
		(pad "DE34" smd circle
			(at -3.439922 33.56991 180)
			(size 0.450088 0.450088)
			(layers "F.Cu" "F.Mask" "F.Paste")
			(net "PVDDCR_CPU1_P1")
		)
		(pad "DE35" smd circle
			(at -2.500122 33.56991 180)
			(size 0.450088 0.450088)
			(layers "F.Cu" "F.Mask" "F.Paste")
			(net "PVDDCR_CPU1_P1")
		)
		(pad "DE36" smd circle
			(at -1.560068 33.56991 180)
			(size 0.450088 0.450088)
			(layers "F.Cu" "F.Mask" "F.Paste")
			(net "CPU1_SPD_HOST_CTRL_R_N")
		)
		(pad "DE40" smd circle
			(at 1.260094 33.56991 180)
			(size 0.450088 0.450088)
			(layers "F.Cu" "F.Mask" "F.Paste")
			(net "FM_BMC_READY_N")
		)
		(pad "DE41" smd circle
			(at 2.199894 33.56991 180)
			(size 0.450088 0.450088)
			(layers "F.Cu" "F.Mask" "F.Paste")
			(net "PVDDCR_CPU1_P1")
		)
		(pad "DE42" smd circle
			(at 3.139948 33.56991 180)
			(size 0.450088 0.450088)
			(layers "F.Cu" "F.Mask" "F.Paste")
			(net "PVDDCR_CPU1_P1")
		)
		(pad "DE43" smd circle
			(at 4.080002 33.56991 180)
			(size 0.450088 0.450088)
			(layers "F.Cu" "F.Mask" "F.Paste")
			(net "P3E_CPU1_P4_TX_DN<3>")
		)
		(pad "DE44" smd circle
			(at 5.020056 33.56991 180)
			(size 0.450088 0.450088)
			(layers "F.Cu" "F.Mask" "F.Paste")
			(net "P3E_CPU1_P4_TX_DP<3>")
		)
		(pad "DE45" smd circle
			(at 5.96011 33.56991 180)
			(size 0.450088 0.450088)
			(layers "F.Cu" "F.Mask" "F.Paste")
			(net "PVDDCR_CPU1_P1")
		)
		(pad "DE46" smd circle
			(at 6.89991 33.56991 180)
			(size 0.450088 0.450088)
			(layers "F.Cu" "F.Mask" "F.Paste")
			(net "P3E_CPU1_P4_TX_DN<2>")
		)
		(pad "DE47" smd circle
			(at 7.839964 33.56991 180)
			(size 0.450088 0.450088)
			(layers "F.Cu" "F.Mask" "F.Paste")
			(net "P3E_CPU1_P4_TX_DP<2>")
		)
		(pad "DE48" smd circle
			(at 8.780018 33.56991 180)
			(size 0.450088 0.450088)
			(layers "F.Cu" "F.Mask" "F.Paste")
			(net "PVDDCR_CPU1_P1")
		)
		(pad "DE49" smd circle
			(at 9.720072 33.56991 180)
			(size 0.450088 0.450088)
			(layers "F.Cu" "F.Mask" "F.Paste")
			(net "P3E_CPU1_P4_TX_DN<1>")
		)
		(pad "DE50" smd circle
			(at 10.659872 33.56991 180)
			(size 0.450088 0.450088)
			(layers "F.Cu" "F.Mask" "F.Paste")
			(net "P3E_CPU1_P4_TX_DP<1>")
		)
		(pad "DE51" smd circle
			(at 11.599926 33.56991 180)
			(size 0.450088 0.450088)
			(layers "F.Cu" "F.Mask" "F.Paste")
			(net "PVDDCR_CPU1_P1")
		)
		(pad "DE52" smd circle
			(at 12.53998 33.56991 180)
			(size 0.450088 0.450088)
			(layers "F.Cu" "F.Mask" "F.Paste")
			(net "P3E_CPU1_P4_TX_DN<0>")
		)
		(pad "DE53" smd circle
			(at 13.480034 33.56991 180)
			(size 0.450088 0.450088)
			(layers "F.Cu" "F.Mask" "F.Paste")
			(net "P3E_CPU1_P4_TX_DP<0>")
		)
		(pad "DE54" smd circle
			(at 14.420088 33.56991 180)
			(size 0.450088 0.450088)
			(layers "F.Cu" "F.Mask" "F.Paste")
			(net "PVDDCR_CPU1_P1")
		)
		(pad "DE55" smd circle
			(at 15.359888 33.56991 180)
			(size 0.450088 0.450088)
			(layers "F.Cu" "F.Mask" "F.Paste")
			(net "M_C_CPU1_SB_DQ<29>")
		)
		(pad "DE56" smd circle
			(at 16.299942 33.56991 180)
			(size 0.450088 0.450088)
			(layers "F.Cu" "F.Mask" "F.Paste")
			(net "GND")
		)
		(pad "DE57" smd circle
			(at 17.239996 33.56991 180)
			(size 0.450088 0.450088)
			(layers "F.Cu" "F.Mask" "F.Paste")
			(net "M_C_CPU1_SB_DQ<30>")
		)
		(pad "DE58" smd circle
			(at 18.18005 33.56991 180)
			(size 0.450088 0.450088)
			(layers "F.Cu" "F.Mask" "F.Paste")
			(net "PVDDIO_P1")
		)
		(pad "DE59" smd circle
			(at 19.120104 33.56991 180)
			(size 0.450088 0.450088)
			(layers "F.Cu" "F.Mask" "F.Paste")
			(net "M_D_CPU1_SB_DQ<29>")
		)
		(pad "DE60" smd circle
			(at 20.059904 33.56991 180)
			(size 0.450088 0.450088)
			(layers "F.Cu" "F.Mask" "F.Paste")
			(net "M_D_CPU1_SB_DQ<30>")
		)
		(pad "DE61" smd circle
			(at 20.999958 33.56991 180)
			(size 0.450088 0.450088)
			(layers "F.Cu" "F.Mask" "F.Paste")
			(net "GND")
		)
		(pad "DE62" smd circle
			(at 21.940012 33.56991 180)
			(size 0.450088 0.450088)
			(layers "F.Cu" "F.Mask" "F.Paste")
			(net "M_B_CPU1_SB_DQ<29>")
		)
		(pad "DE63" smd circle
			(at 22.880066 33.56991 180)
			(size 0.450088 0.450088)
			(layers "F.Cu" "F.Mask" "F.Paste")
			(net "GND")
		)
		(pad "DE64" smd circle
			(at 23.82012 33.56991 180)
			(size 0.450088 0.450088)
			(layers "F.Cu" "F.Mask" "F.Paste")
			(net "M_B_CPU1_SB_DQ<30>")
		)
		(pad "DE65" smd circle
			(at 24.75992 33.56991 180)
			(size 0.450088 0.450088)
			(layers "F.Cu" "F.Mask" "F.Paste")
			(net "PVDDIO_P1")
		)
		(pad "DE66" smd circle
			(at 25.699974 33.56991 180)
			(size 0.450088 0.450088)
			(layers "F.Cu" "F.Mask" "F.Paste")
			(net "M_F_CPU1_SB_DQ<29>")
		)
		(pad "DE67" smd circle
			(at 26.640028 33.56991 180)
			(size 0.450088 0.450088)
			(layers "F.Cu" "F.Mask" "F.Paste")
			(net "M_F_CPU1_SB_DQ<30>")
		)
		(pad "DE68" smd circle
			(at 27.580082 33.56991 180)
			(size 0.450088 0.450088)
			(layers "F.Cu" "F.Mask" "F.Paste")
			(net "GND")
		)
		(pad "DE69" smd circle
			(at 28.519882 33.56991 180)
			(size 0.450088 0.450088)
			(layers "F.Cu" "F.Mask" "F.Paste")
			(net "M_E_CPU1_SB_DQ<29>")
		)
		(pad "DE70" smd circle
			(at 29.459936 33.56991 180)
			(size 0.450088 0.450088)
			(layers "F.Cu" "F.Mask" "F.Paste")
			(net "GND")
		)
		(pad "DE71" smd circle
			(at 30.39999 33.56991 180)
			(size 0.450088 0.450088)
			(layers "F.Cu" "F.Mask" "F.Paste")
			(net "M_E_CPU1_SB_DQ<30>")
		)
		(pad "DE72" smd circle
			(at 31.340044 33.56991 180)
			(size 0.450088 0.450088)
			(layers "F.Cu" "F.Mask" "F.Paste")
			(net "PVDDIO_P1")
		)
		(pad "DE73" smd circle
			(at 32.280098 33.56991 180)
			(size 0.450088 0.450088)
			(layers "F.Cu" "F.Mask" "F.Paste")
			(net "M_A_CPU1_SB_DQ<29>")
		)
		(pad "DE74" smd circle
			(at 33.219898 33.56991 180)
			(size 0.450088 0.450088)
			(layers "F.Cu" "F.Mask" "F.Paste")
			(net "M_A_CPU1_SB_DQ<30>")
		)
		(pad "DE75" smd circle
			(at 34.159952 33.56991 180)
			(size 0.450088 0.450088)
			(layers "F.Cu" "F.Mask" "F.Paste")
			(net "GND")
		)
		(pad "DF2" smd circle
			(at -33.990026 34.379916 180)
			(size 0.450088 0.450088)
			(layers "F.Cu" "F.Mask" "F.Paste")
			(net "M_G_CPU1_SB_DQ<31>")
		)
		(pad "DF3" smd circle
			(at -33.049972 34.379916 180)
			(size 0.450088 0.450088)
			(layers "F.Cu" "F.Mask" "F.Paste")
			(net "GND")
		)
		(pad "DF4" smd circle
			(at -32.109918 34.379916 180)
			(size 0.450088 0.450088)
			(layers "F.Cu" "F.Mask" "F.Paste")
			(net "GND")
		)
		(pad "DF5" smd circle
			(at -31.170118 34.379916 180)
			(size 0.450088 0.450088)
			(layers "F.Cu" "F.Mask" "F.Paste")
			(net "GND")
		)
		(pad "DF6" smd circle
			(at -30.230064 34.379916 180)
			(size 0.450088 0.450088)
			(layers "F.Cu" "F.Mask" "F.Paste")
			(net "GND")
		)
		(pad "DF7" smd circle
			(at -29.29001 34.379916 180)
			(size 0.450088 0.450088)
			(layers "F.Cu" "F.Mask" "F.Paste")
			(net "M_K_CPU1_SB_DQ<31>")
		)
		(pad "DF8" smd circle
			(at -28.349956 34.379916 180)
			(size 0.450088 0.450088)
			(layers "F.Cu" "F.Mask" "F.Paste")
			(net "GND")
		)
		(pad "DF9" smd circle
			(at -27.409902 34.379916 180)
			(size 0.450088 0.450088)
			(layers "F.Cu" "F.Mask" "F.Paste")
			(net "M_L_CPU1_SB_DQ<31>")
		)
		(pad "DF10" smd circle
			(at -26.470102 34.379916 180)
			(size 0.450088 0.450088)
			(layers "F.Cu" "F.Mask" "F.Paste")
			(net "GND")
		)
		(pad "DF11" smd circle
			(at -25.530048 34.379916 180)
			(size 0.450088 0.450088)
			(layers "F.Cu" "F.Mask" "F.Paste")
			(net "GND")
		)
		(pad "DF12" smd circle
			(at -24.589994 34.379916 180)
			(size 0.450088 0.450088)
			(layers "F.Cu" "F.Mask" "F.Paste")
			(net "GND")
		)
		(pad "DF13" smd circle
			(at -23.64994 34.379916 180)
			(size 0.450088 0.450088)
			(layers "F.Cu" "F.Mask" "F.Paste")
			(net "GND")
		)
		(pad "DF14" smd circle
			(at -22.709886 34.379916 180)
			(size 0.450088 0.450088)
			(layers "F.Cu" "F.Mask" "F.Paste")
			(net "M_H_CPU1_SB_DQ<31>")
		)
		(pad "DF15" smd circle
			(at -21.770086 34.379916 180)
			(size 0.450088 0.450088)
			(layers "F.Cu" "F.Mask" "F.Paste")
			(net "GND")
		)
		(pad "DF16" smd circle
			(at -20.830032 34.379916 180)
			(size 0.450088 0.450088)
			(layers "F.Cu" "F.Mask" "F.Paste")
			(net "M_J_CPU1_SB_DQ<31>")
		)
		(pad "DF17" smd circle
			(at -19.889978 34.379916 180)
			(size 0.450088 0.450088)
			(layers "F.Cu" "F.Mask" "F.Paste")
			(net "GND")
		)
		(pad "DF18" smd circle
			(at -18.949924 34.379916 180)
			(size 0.450088 0.450088)
			(layers "F.Cu" "F.Mask" "F.Paste")
			(net "GND")
		)
		(pad "DF19" smd circle
			(at -18.010124 34.379916 180)
			(size 0.450088 0.450088)
			(layers "F.Cu" "F.Mask" "F.Paste")
			(net "GND")
		)
		(pad "DF20" smd circle
			(at -17.07007 34.379916 180)
			(size 0.450088 0.450088)
			(layers "F.Cu" "F.Mask" "F.Paste")
			(net "GND")
		)
		(pad "DF21" smd circle
			(at -16.130016 34.379916 180)
			(size 0.450088 0.450088)
			(layers "F.Cu" "F.Mask" "F.Paste")
			(net "M_I_CPU1_SB_DQ<31>")
		)
		(pad "DF22" smd circle
			(at -15.189962 34.379916 180)
			(size 0.450088 0.450088)
			(layers "F.Cu" "F.Mask" "F.Paste")
			(net "GND")
		)
		(pad "DF23" smd circle
			(at -14.249908 34.379916 180)
			(size 0.450088 0.450088)
			(layers "F.Cu" "F.Mask" "F.Paste")
			(net "GND")
		)
		(pad "DF24" smd circle
			(at -13.310108 34.379916 180)
			(size 0.450088 0.450088)
			(layers "F.Cu" "F.Mask" "F.Paste")
			(net "Net_2108")
		)
		(pad "DF25" smd circle
			(at -12.370054 34.379916 180)
			(size 0.450088 0.450088)
			(layers "F.Cu" "F.Mask" "F.Paste")
			(net "Net_2111")
		)
		(pad "DF26" smd circle
			(at -11.43 34.379916 180)
			(size 0.450088 0.450088)
			(layers "F.Cu" "F.Mask" "F.Paste")
			(net "GND")
		)
		(pad "DF27" smd circle
			(at -10.489946 34.379916 180)
			(size 0.450088 0.450088)
			(layers "F.Cu" "F.Mask" "F.Paste")
			(net "PD_ESPI_CPU1_CLK2")
		)
		(pad "DF28" smd circle
			(at -9.549892 34.379916 180)
			(size 0.450088 0.450088)
			(layers "F.Cu" "F.Mask" "F.Paste")
			(net "Net_2104")
		)
		(pad "DF29" smd circle
			(at -8.610092 34.379916 180)
			(size 0.450088 0.450088)
			(layers "F.Cu" "F.Mask" "F.Paste")
			(net "GND")
		)
		(pad "DF30" smd circle
			(at -7.670038 34.379916 180)
			(size 0.450088 0.450088)
			(layers "F.Cu" "F.Mask" "F.Paste")
			(net "Net_2118")
		)
		(pad "DF31" smd circle
			(at -6.729984 34.379916 180)
			(size 0.450088 0.450088)
			(layers "F.Cu" "F.Mask" "F.Paste")
			(net "Net_2077")
		)
		(pad "DF32" smd circle
			(at -5.78993 34.379916 180)
			(size 0.450088 0.450088)
			(layers "F.Cu" "F.Mask" "F.Paste")
			(net "GND")
		)
		(pad "DF33" smd circle
			(at -4.849876 34.379916 180)
			(size 0.450088 0.450088)
			(layers "F.Cu" "F.Mask" "F.Paste")
			(net "TP_SLOT2_BUF_SKU_ID0")
		)
		(pad "DF34" smd circle
			(at -3.910076 34.379916 180)
			(size 0.450088 0.450088)
			(layers "F.Cu" "F.Mask" "F.Paste")
			(net "TP_CPU1_UART0_RTS_N")
		)
		(pad "DF35" smd circle
			(at -2.970022 34.379916 180)
			(size 0.450088 0.450088)
			(layers "F.Cu" "F.Mask" "F.Paste")
			(net "GND")
		)
		(pad "DF36" smd circle
			(at -2.029968 34.379916 180)
			(size 0.450088 0.450088)
			(layers "F.Cu" "F.Mask" "F.Paste")
			(net "Net_2084")
		)
		(pad "DF37" smd circle
			(at -1.089914 34.379916 180)
			(size 0.450088 0.450088)
			(layers "F.Cu" "F.Mask" "F.Paste")
			(net "GND")
		)
		(pad "DF39" smd circle
			(at 0.78994 34.379916 180)
			(size 0.450088 0.450088)
			(layers "F.Cu" "F.Mask" "F.Paste")
			(net "GND")
		)
		(pad "DF40" smd circle
			(at 1.729994 34.379916 180)
			(size 0.450088 0.450088)
			(layers "F.Cu" "F.Mask" "F.Paste")
			(net "IRQ_CPU_BMC_NMI_N")
		)
		(pad "DF41" smd circle
			(at 2.670048 34.379916 180)
			(size 0.450088 0.450088)
			(layers "F.Cu" "F.Mask" "F.Paste")
			(net "Net_2171")
		)
		(pad "DF42" smd circle
			(at 3.610102 34.379916 180)
			(size 0.450088 0.450088)
			(layers "F.Cu" "F.Mask" "F.Paste")
			(net "GND")
		)
		(pad "DF43" smd circle
			(at 4.549902 34.379916 180)
			(size 0.450088 0.450088)
			(layers "F.Cu" "F.Mask" "F.Paste")
			(net "GND")
		)
		(pad "DF44" smd circle
			(at 5.489956 34.379916 180)
			(size 0.450088 0.450088)
			(layers "F.Cu" "F.Mask" "F.Paste")
			(net "GND")
		)
		(pad "DF45" smd circle
			(at 6.43001 34.379916 180)
			(size 0.450088 0.450088)
			(layers "F.Cu" "F.Mask" "F.Paste")
			(net "GND")
		)
		(pad "DF46" smd circle
			(at 7.370064 34.379916 180)
			(size 0.450088 0.450088)
			(layers "F.Cu" "F.Mask" "F.Paste")
			(net "GND")
		)
		(pad "DF47" smd circle
			(at 8.310118 34.379916 180)
			(size 0.450088 0.450088)
			(layers "F.Cu" "F.Mask" "F.Paste")
			(net "GND")
		)
		(pad "DF48" smd circle
			(at 9.249918 34.379916 180)
			(size 0.450088 0.450088)
			(layers "F.Cu" "F.Mask" "F.Paste")
			(net "GND")
		)
		(pad "DF49" smd circle
			(at 10.189972 34.379916 180)
			(size 0.450088 0.450088)
			(layers "F.Cu" "F.Mask" "F.Paste")
			(net "GND")
		)
		(pad "DF50" smd circle
			(at 11.130026 34.379916 180)
			(size 0.450088 0.450088)
			(layers "F.Cu" "F.Mask" "F.Paste")
			(net "GND")
		)
		(pad "DF51" smd circle
			(at 12.07008 34.379916 180)
			(size 0.450088 0.450088)
			(layers "F.Cu" "F.Mask" "F.Paste")
			(net "GND")
		)
		(pad "DF52" smd circle
			(at 13.00988 34.379916 180)
			(size 0.450088 0.450088)
			(layers "F.Cu" "F.Mask" "F.Paste")
			(net "GND")
		)
		(pad "DF53" smd circle
			(at 13.949934 34.379916 180)
			(size 0.450088 0.450088)
			(layers "F.Cu" "F.Mask" "F.Paste")
			(net "GND")
		)
		(pad "DF54" smd circle
			(at 14.889988 34.379916 180)
			(size 0.450088 0.450088)
			(layers "F.Cu" "F.Mask" "F.Paste")
			(net "GND")
		)
		(pad "DF55" smd circle
			(at 15.830042 34.379916 180)
			(size 0.450088 0.450088)
			(layers "F.Cu" "F.Mask" "F.Paste")
			(net "M_C_CPU1_SB_DQ<31>")
		)
		(pad "DF56" smd circle
			(at 16.770096 34.379916 180)
			(size 0.450088 0.450088)
			(layers "F.Cu" "F.Mask" "F.Paste")
			(net "GND")
		)
		(pad "DF57" smd circle
			(at 17.709896 34.379916 180)
			(size 0.450088 0.450088)
			(layers "F.Cu" "F.Mask" "F.Paste")
			(net "GND")
		)
		(pad "DF58" smd circle
			(at 18.64995 34.379916 180)
			(size 0.450088 0.450088)
			(layers "F.Cu" "F.Mask" "F.Paste")
			(net "GND")
		)
		(pad "DF59" smd circle
			(at 19.590004 34.379916 180)
			(size 0.450088 0.450088)
			(layers "F.Cu" "F.Mask" "F.Paste")
			(net "GND")
		)
		(pad "DF60" smd circle
			(at 20.530058 34.379916 180)
			(size 0.450088 0.450088)
			(layers "F.Cu" "F.Mask" "F.Paste")
			(net "M_D_CPU1_SB_DQ<31>")
		)
		(pad "DF61" smd circle
			(at 21.470112 34.379916 180)
			(size 0.450088 0.450088)
			(layers "F.Cu" "F.Mask" "F.Paste")
			(net "GND")
		)
		(pad "DF62" smd circle
			(at 22.409912 34.379916 180)
			(size 0.450088 0.450088)
			(layers "F.Cu" "F.Mask" "F.Paste")
			(net "M_B_CPU1_SB_DQ<31>")
		)
		(pad "DF63" smd circle
			(at 23.349966 34.379916 180)
			(size 0.450088 0.450088)
			(layers "F.Cu" "F.Mask" "F.Paste")
			(net "GND")
		)
		(pad "DF64" smd circle
			(at 24.29002 34.379916 180)
			(size 0.450088 0.450088)
			(layers "F.Cu" "F.Mask" "F.Paste")
			(net "GND")
		)
		(pad "DF65" smd circle
			(at 25.230074 34.379916 180)
			(size 0.450088 0.450088)
			(layers "F.Cu" "F.Mask" "F.Paste")
			(net "GND")
		)
		(pad "DF66" smd circle
			(at 26.170128 34.379916 180)
			(size 0.450088 0.450088)
			(layers "F.Cu" "F.Mask" "F.Paste")
			(net "GND")
		)
		(pad "DF67" smd circle
			(at 27.109928 34.379916 180)
			(size 0.450088 0.450088)
			(layers "F.Cu" "F.Mask" "F.Paste")
			(net "M_F_CPU1_SB_DQ<31>")
		)
		(pad "DF68" smd circle
			(at 28.049982 34.379916 180)
			(size 0.450088 0.450088)
			(layers "F.Cu" "F.Mask" "F.Paste")
			(net "GND")
		)
		(pad "DF69" smd circle
			(at 28.990036 34.379916 180)
			(size 0.450088 0.450088)
			(layers "F.Cu" "F.Mask" "F.Paste")
			(net "M_E_CPU1_SB_DQ<31>")
		)
		(pad "DF70" smd circle
			(at 29.93009 34.379916 180)
			(size 0.450088 0.450088)
			(layers "F.Cu" "F.Mask" "F.Paste")
			(net "GND")
		)
		(pad "DF71" smd circle
			(at 30.86989 34.379916 180)
			(size 0.450088 0.450088)
			(layers "F.Cu" "F.Mask" "F.Paste")
			(net "GND")
		)
		(pad "DF72" smd circle
			(at 31.809944 34.379916 180)
			(size 0.450088 0.450088)
			(layers "F.Cu" "F.Mask" "F.Paste")
			(net "GND")
		)
		(pad "DF73" smd circle
			(at 32.749998 34.379916 180)
			(size 0.450088 0.450088)
			(layers "F.Cu" "F.Mask" "F.Paste")
			(net "GND")
		)
		(pad "DF74" smd circle
			(at 33.690052 34.379916 180)
			(size 0.450088 0.450088)
			(layers "F.Cu" "F.Mask" "F.Paste")
			(net "M_A_CPU1_SB_DQ<31>")
		)
		(pad "DG1" smd circle
			(at -34.459926 35.189922 180)
			(size 0.450088 0.450088)
			(layers "F.Cu" "F.Mask" "F.Paste")
			(net "GND")
		)
		(pad "DG2" smd circle
			(at -33.519872 35.189922 180)
			(size 0.450088 0.450088)
			(layers "F.Cu" "F.Mask" "F.Paste")
			(net "GND")
		)
		(pad "DG3" smd circle
			(at -32.580072 35.189922 180)
			(size 0.450088 0.450088)
			(layers "F.Cu" "F.Mask" "F.Paste")
			(net "VSENSE_PVDDCR_CPU1_P1_DP")
		)
		(pad "DG4" smd circle
			(at -31.640018 35.189922 180)
			(size 0.450088 0.450088)
			(layers "F.Cu" "F.Mask" "F.Paste")
			(net "CPU1_SLP_S5_N")
		)
		(pad "DG5" smd circle
			(at -30.699964 35.189922 180)
			(size 0.450088 0.450088)
			(layers "F.Cu" "F.Mask" "F.Paste")
			(net "PVDD11_S3_P1")
		)
		(pad "DG6" smd circle
			(at -29.75991 35.189922 180)
			(size 0.450088 0.450088)
			(layers "F.Cu" "F.Mask" "F.Paste")
			(net "GND")
		)
		(pad "DG7" smd circle
			(at -28.82011 35.189922 180)
			(size 0.450088 0.450088)
			(layers "F.Cu" "F.Mask" "F.Paste")
			(net "GND")
		)
		(pad "DG8" smd circle
			(at -27.880056 35.189922 180)
			(size 0.450088 0.450088)
			(layers "F.Cu" "F.Mask" "F.Paste")
			(net "GND")
		)
		(pad "DG9" smd circle
			(at -26.940002 35.189922 180)
			(size 0.450088 0.450088)
			(layers "F.Cu" "F.Mask" "F.Paste")
			(net "GND")
		)
		(pad "DG10" smd circle
			(at -25.999948 35.189922 180)
			(size 0.450088 0.450088)
			(layers "F.Cu" "F.Mask" "F.Paste")
			(net "RST_CPU1_RSMRST_N")
		)
		(pad "DG11" smd circle
			(at -25.059894 35.189922 180)
			(size 0.450088 0.450088)
			(layers "F.Cu" "F.Mask" "F.Paste")
			(net "Net_2086")
		)
		(pad "DG12" smd circle
			(at -24.120094 35.189922 180)
			(size 0.450088 0.450088)
			(layers "F.Cu" "F.Mask" "F.Paste")
			(net "Net_2092")
		)
		(pad "DG13" smd circle
			(at -23.18004 35.189922 180)
			(size 0.450088 0.450088)
			(layers "F.Cu" "F.Mask" "F.Paste")
			(net "GND")
		)
		(pad "DG14" smd circle
			(at -22.239986 35.189922 180)
			(size 0.450088 0.450088)
			(layers "F.Cu" "F.Mask" "F.Paste")
			(net "GND")
		)
		(pad "DG15" smd circle
			(at -21.299932 35.189922 180)
			(size 0.450088 0.450088)
			(layers "F.Cu" "F.Mask" "F.Paste")
			(net "GND")
		)
		(pad "DG16" smd circle
			(at -20.359878 35.189922 180)
			(size 0.450088 0.450088)
			(layers "F.Cu" "F.Mask" "F.Paste")
			(net "GND")
		)
		(pad "DG17" smd circle
			(at -19.420078 35.189922 180)
			(size 0.450088 0.450088)
			(layers "F.Cu" "F.Mask" "F.Paste")
			(net "Net_2163")
		)
		(pad "DG18" smd circle
			(at -18.480024 35.189922 180)
			(size 0.450088 0.450088)
			(layers "F.Cu" "F.Mask" "F.Paste")
			(net "GND")
		)
		(pad "DG19" smd circle
			(at -17.53997 35.189922 180)
			(size 0.450088 0.450088)
			(layers "F.Cu" "F.Mask" "F.Paste")
			(net "PVDDCR_CPU1_P1")
		)
		(pad "DG20" smd circle
			(at -16.599916 35.189922 180)
			(size 0.450088 0.450088)
			(layers "F.Cu" "F.Mask" "F.Paste")
			(net "GND")
		)
		(pad "DG21" smd circle
			(at -15.660116 35.189922 180)
			(size 0.450088 0.450088)
			(layers "F.Cu" "F.Mask" "F.Paste")
			(net "GND")
		)
		(pad "DG22" smd circle
			(at -14.720062 35.189922 180)
			(size 0.450088 0.450088)
			(layers "F.Cu" "F.Mask" "F.Paste")
			(net "Net_2105")
		)
		(pad "DG23" smd circle
			(at -13.780008 35.189922 180)
			(size 0.450088 0.450088)
			(layers "F.Cu" "F.Mask" "F.Paste")
			(net "Net_2113")
		)
		(pad "DG24" smd circle
			(at -12.839954 35.189922 180)
			(size 0.450088 0.450088)
			(layers "F.Cu" "F.Mask" "F.Paste")
			(net "GND")
		)
		(pad "DG25" smd circle
			(at -11.8999 35.189922 180)
			(size 0.450088 0.450088)
			(layers "F.Cu" "F.Mask" "F.Paste")
			(net "Net_2112")
		)
		(pad "DG26" smd circle
			(at -10.9601 35.189922 180)
			(size 0.450088 0.450088)
			(layers "F.Cu" "F.Mask" "F.Paste")
			(net "Net_2119")
		)
		(pad "DG27" smd circle
			(at -10.020046 35.189922 180)
			(size 0.450088 0.450088)
			(layers "F.Cu" "F.Mask" "F.Paste")
			(net "GND")
		)
		(pad "DG28" smd circle
			(at -9.079992 35.189922 180)
			(size 0.450088 0.450088)
			(layers "F.Cu" "F.Mask" "F.Paste")
			(net "Net_2114")
		)
		(pad "DG29" smd circle
			(at -8.139938 35.189922 180)
			(size 0.450088 0.450088)
			(layers "F.Cu" "F.Mask" "F.Paste")
			(net "Net_2107")
		)
		(pad "DG30" smd circle
			(at -7.199884 35.189922 180)
			(size 0.450088 0.450088)
			(layers "F.Cu" "F.Mask" "F.Paste")
			(net "GND")
		)
		(pad "DG31" smd circle
			(at -6.260084 35.189922 180)
			(size 0.450088 0.450088)
			(layers "F.Cu" "F.Mask" "F.Paste")
			(net "Net_2078")
		)
		(pad "DG32" smd circle
			(at -5.32003 35.189922 180)
			(size 0.450088 0.450088)
			(layers "F.Cu" "F.Mask" "F.Paste")
			(net "Net_2079")
		)
		(pad "DG33" smd circle
			(at -4.379976 35.189922 180)
			(size 0.450088 0.450088)
			(layers "F.Cu" "F.Mask" "F.Paste")
			(net "GND")
		)
		(pad "DG34" smd circle
			(at -3.439922 35.189922 180)
			(size 0.450088 0.450088)
			(layers "F.Cu" "F.Mask" "F.Paste")
			(net "TP_CPU1_UART0_INTR")
		)
		(pad "DG35" smd circle
			(at -2.500122 35.189922 180)
			(size 0.450088 0.450088)
			(layers "F.Cu" "F.Mask" "F.Paste")
			(net "TP_CPU1_UART0_RX")
		)
		(pad "DG36" smd circle
			(at -1.560068 35.189922 180)
			(size 0.450088 0.450088)
			(layers "F.Cu" "F.Mask" "F.Paste")
			(net "RST_CPU1_PERST1_N")
		)
		(pad "DG40" smd circle
			(at 1.260094 35.189922 180)
			(size 0.450088 0.450088)
			(layers "F.Cu" "F.Mask" "F.Paste")
			(net "NC_CPU1_USB10_OC_N")
		)
		(pad "DG41" smd circle
			(at 2.199894 35.189922 180)
			(size 0.450088 0.450088)
			(layers "F.Cu" "F.Mask" "F.Paste")
			(net "GND")
		)
		(pad "DG42" smd circle
			(at 3.139948 35.189922 180)
			(size 0.450088 0.450088)
			(layers "F.Cu" "F.Mask" "F.Paste")
			(net "Net_2175")
		)
		(pad "DG43" smd circle
			(at 4.080002 35.189922 180)
			(size 0.450088 0.450088)
			(layers "F.Cu" "F.Mask" "F.Paste")
			(net "GND")
		)
		(pad "DG44" smd circle
			(at 5.020056 35.189922 180)
			(size 0.450088 0.450088)
			(layers "F.Cu" "F.Mask" "F.Paste")
			(net "P3E_CPU1_P4_RX_DN<3>")
		)
		(pad "DG45" smd circle
			(at 5.96011 35.189922 180)
			(size 0.450088 0.450088)
			(layers "F.Cu" "F.Mask" "F.Paste")
			(net "P3E_CPU1_P4_RX_DP<3>")
		)
		(pad "DG46" smd circle
			(at 6.89991 35.189922 180)
			(size 0.450088 0.450088)
			(layers "F.Cu" "F.Mask" "F.Paste")
			(net "GND")
		)
		(pad "DG47" smd circle
			(at 7.839964 35.189922 180)
			(size 0.450088 0.450088)
			(layers "F.Cu" "F.Mask" "F.Paste")
			(net "P3E_CPU1_P4_RX_DN<2>")
		)
		(pad "DG48" smd circle
			(at 8.780018 35.189922 180)
			(size 0.450088 0.450088)
			(layers "F.Cu" "F.Mask" "F.Paste")
			(net "P3E_CPU1_P4_RX_DP<2>")
		)
		(pad "DG49" smd circle
			(at 9.720072 35.189922 180)
			(size 0.450088 0.450088)
			(layers "F.Cu" "F.Mask" "F.Paste")
			(net "GND")
		)
		(pad "DG50" smd circle
			(at 10.659872 35.189922 180)
			(size 0.450088 0.450088)
			(layers "F.Cu" "F.Mask" "F.Paste")
			(net "P3E_CPU1_P4_RX_DN<1>")
		)
		(pad "DG51" smd circle
			(at 11.599926 35.189922 180)
			(size 0.450088 0.450088)
			(layers "F.Cu" "F.Mask" "F.Paste")
			(net "P3E_CPU1_P4_RX_DP<1>")
		)
		(pad "DG52" smd circle
			(at 12.53998 35.189922 180)
			(size 0.450088 0.450088)
			(layers "F.Cu" "F.Mask" "F.Paste")
			(net "GND")
		)
		(pad "DG53" smd circle
			(at 13.480034 35.189922 180)
			(size 0.450088 0.450088)
			(layers "F.Cu" "F.Mask" "F.Paste")
			(net "P3E_CPU1_P4_RX_DN<0>")
		)
		(pad "DG54" smd circle
			(at 14.420088 35.189922 180)
			(size 0.450088 0.450088)
			(layers "F.Cu" "F.Mask" "F.Paste")
			(net "P3E_CPU1_P4_RX_DP<0>")
		)
		(pad "DG55" smd circle
			(at 15.359888 35.189922 180)
			(size 0.450088 0.450088)
			(layers "F.Cu" "F.Mask" "F.Paste")
			(net "GND")
		)
		(pad "DG56" smd circle
			(at 16.299942 35.189922 180)
			(size 0.450088 0.450088)
			(layers "F.Cu" "F.Mask" "F.Paste")
			(net "GND")
		)
		(pad "DG57" smd circle
			(at 17.239996 35.189922 180)
			(size 0.450088 0.450088)
			(layers "F.Cu" "F.Mask" "F.Paste")
			(net "PVDDCR_CPU1_P1")
		)
		(pad "DG58" smd circle
			(at 18.18005 35.189922 180)
			(size 0.450088 0.450088)
			(layers "F.Cu" "F.Mask" "F.Paste")
			(net "NC_CPU1_USB3_USB11_TXP")
		)
		(pad "DG59" smd circle
			(at 19.120104 35.189922 180)
			(size 0.450088 0.450088)
			(layers "F.Cu" "F.Mask" "F.Paste")
			(net "GND")
		)
		(pad "DG60" smd circle
			(at 20.059904 35.189922 180)
			(size 0.450088 0.450088)
			(layers "F.Cu" "F.Mask" "F.Paste")
			(net "GND")
		)
		(pad "DG61" smd circle
			(at 20.999958 35.189922 180)
			(size 0.450088 0.450088)
			(layers "F.Cu" "F.Mask" "F.Paste")
			(net "GND")
		)
		(pad "DG62" smd circle
			(at 21.940012 35.189922 180)
			(size 0.450088 0.450088)
			(layers "F.Cu" "F.Mask" "F.Paste")
			(net "GND")
		)
		(pad "DG63" smd circle
			(at 22.880066 35.189922 180)
			(size 0.450088 0.450088)
			(layers "F.Cu" "F.Mask" "F.Paste")
			(net "GND")
		)
		(pad "DG64" smd circle
			(at 23.82012 35.189922 180)
			(size 0.450088 0.450088)
			(layers "F.Cu" "F.Mask" "F.Paste")
			(net "PVDDIO_P1")
		)
		(pad "DG65" smd circle
			(at 24.75992 35.189922 180)
			(size 0.450088 0.450088)
			(layers "F.Cu" "F.Mask" "F.Paste")
			(net "GND")
		)
		(pad "DG66" smd circle
			(at 25.699974 35.189922 180)
			(size 0.450088 0.450088)
			(layers "F.Cu" "F.Mask" "F.Paste")
			(net "GND")
		)
		(pad "DG67" smd circle
			(at 26.640028 35.189922 180)
			(size 0.450088 0.450088)
			(layers "F.Cu" "F.Mask" "F.Paste")
			(net "GND")
		)
		(pad "DG68" smd circle
			(at 27.580082 35.189922 180)
			(size 0.450088 0.450088)
			(layers "F.Cu" "F.Mask" "F.Paste")
			(net "GND")
		)
		(pad "DG69" smd circle
			(at 28.519882 35.189922 180)
			(size 0.450088 0.450088)
			(layers "F.Cu" "F.Mask" "F.Paste")
			(net "GND")
		)
		(pad "DG70" smd circle
			(at 29.459936 35.189922 180)
			(size 0.450088 0.450088)
			(layers "F.Cu" "F.Mask" "F.Paste")
			(net "GND")
		)
		(pad "DG71" smd circle
			(at 30.39999 35.189922 180)
			(size 0.450088 0.450088)
			(layers "F.Cu" "F.Mask" "F.Paste")
			(net "PVDDIO_P1")
		)
		(pad "DG72" smd circle
			(at 31.340044 35.189922 180)
			(size 0.450088 0.450088)
			(layers "F.Cu" "F.Mask" "F.Paste")
			(net "FM_P1_PCC1_N")
		)
		(pad "DG73" smd circle
			(at 32.280098 35.189922 180)
			(size 0.450088 0.450088)
			(layers "F.Cu" "F.Mask" "F.Paste")
			(net "SVID_PVDDCR_CPU1_P1_SVTO")
		)
		(pad "DG74" smd circle
			(at 33.219898 35.189922 180)
			(size 0.450088 0.450088)
			(layers "F.Cu" "F.Mask" "F.Paste")
			(net "GND")
		)
		(pad "DG75" smd circle
			(at 34.159952 35.189922 180)
			(size 0.450088 0.450088)
			(layers "F.Cu" "F.Mask" "F.Paste")
			(net "GND")
		)
		(pad "DH3" smd circle
			(at -33.049972 35.999928 180)
			(size 0.450088 0.450088)
			(layers "F.Cu" "F.Mask" "F.Paste")
			(net "VSENSE_PVDD11_S3_P1_DP")
		)
		(pad "DH4" smd circle
			(at -32.109918 35.999928 180)
			(size 0.450088 0.450088)
			(layers "F.Cu" "F.Mask" "F.Paste")
			(net "Net_2085")
		)
		(pad "DH5" smd circle
			(at -31.170118 35.999928 180)
			(size 0.450088 0.450088)
			(layers "F.Cu" "F.Mask" "F.Paste")
			(net "GND")
		)
		(pad "DH6" smd circle
			(at -30.230064 35.999928 180)
			(size 0.450088 0.450088)
			(layers "F.Cu" "F.Mask" "F.Paste")
			(net "RST_CPU1_SYS_N")
		)
		(pad "DH7" smd circle
			(at -29.29001 35.999928 180)
			(size 0.450088 0.450088)
			(layers "F.Cu" "F.Mask" "F.Paste")
			(net "NC_CPU1_PWR_BTN_N")
		)
		(pad "DH8" smd circle
			(at -28.349956 35.999928 180)
			(size 0.450088 0.450088)
			(layers "F.Cu" "F.Mask" "F.Paste")
			(net "GND")
		)
		(pad "DH9" smd circle
			(at -27.409902 35.999928 180)
			(size 0.450088 0.450088)
			(layers "F.Cu" "F.Mask" "F.Paste")
			(net "CLK_CPU1_RTCCLK")
		)
		(pad "DH10" smd circle
			(at -26.470102 35.999928 180)
			(size 0.450088 0.450088)
			(layers "F.Cu" "F.Mask" "F.Paste")
			(net "CPU1_SP5R4")
		)
		(pad "DH11" smd circle
			(at -25.530048 35.999928 180)
			(size 0.450088 0.450088)
			(layers "F.Cu" "F.Mask" "F.Paste")
			(net "GND")
		)
		(pad "DH12" smd circle
			(at -24.589994 35.999928 180)
			(size 0.450088 0.450088)
			(layers "F.Cu" "F.Mask" "F.Paste")
			(net "Net_2093")
		)
		(pad "DH13" smd circle
			(at -23.64994 35.999928 180)
			(size 0.450088 0.450088)
			(layers "F.Cu" "F.Mask" "F.Paste")
			(net "Net_2170")
		)
		(pad "DH14" smd circle
			(at -22.709886 35.999928 180)
			(size 0.450088 0.450088)
			(layers "F.Cu" "F.Mask" "F.Paste")
			(net "Net_2174")
		)
		(pad "DH15" smd circle
			(at -21.770086 35.999928 180)
			(size 0.450088 0.450088)
			(layers "F.Cu" "F.Mask" "F.Paste")
			(net "FM_CPU1_BMC_RST_N")
		)
		(pad "DH16" smd circle
			(at -20.830032 35.999928 180)
			(size 0.450088 0.450088)
			(layers "F.Cu" "F.Mask" "F.Paste")
			(net "FM_BMC_TPM_PRES_N")
		)
		(pad "DH17" smd circle
			(at -19.889978 35.999928 180)
			(size 0.450088 0.450088)
			(layers "F.Cu" "F.Mask" "F.Paste")
			(net "Net_2164")
		)
		(pad "DH18" smd circle
			(at -18.949924 35.999928 180)
			(size 0.450088 0.450088)
			(layers "F.Cu" "F.Mask" "F.Paste")
			(net "GND")
		)
		(pad "DH19" smd circle
			(at -18.010124 35.999928 180)
			(size 0.450088 0.450088)
			(layers "F.Cu" "F.Mask" "F.Paste")
			(net "PVDDCR_CPU1_P1")
		)
		(pad "DH20" smd circle
			(at -17.07007 35.999928 180)
			(size 0.450088 0.450088)
			(layers "F.Cu" "F.Mask" "F.Paste")
			(net "PVDDCR_CPU1_P1")
		)
		(pad "DH21" smd circle
			(at -16.130016 35.999928 180)
			(size 0.450088 0.450088)
			(layers "F.Cu" "F.Mask" "F.Paste")
			(net "Net_2165")
		)
		(pad "DH22" smd circle
			(at -15.189962 35.999928 180)
			(size 0.450088 0.450088)
			(layers "F.Cu" "F.Mask" "F.Paste")
			(net "PVDDCR_CPU1_P1")
		)
		(pad "DH23" smd circle
			(at -14.249908 35.999928 180)
			(size 0.450088 0.450088)
			(layers "F.Cu" "F.Mask" "F.Paste")
			(net "PVDDCR_CPU1_P1")
		)
		(pad "DH24" smd circle
			(at -13.310108 35.999928 180)
			(size 0.450088 0.450088)
			(layers "F.Cu" "F.Mask" "F.Paste")
			(net "Net_2109")
		)
		(pad "DH25" smd circle
			(at -12.370054 35.999928 180)
			(size 0.450088 0.450088)
			(layers "F.Cu" "F.Mask" "F.Paste")
			(net "PVDDCR_CPU1_P1")
		)
		(pad "DH26" smd circle
			(at -11.43 35.999928 180)
			(size 0.450088 0.450088)
			(layers "F.Cu" "F.Mask" "F.Paste")
			(net "PVDDCR_CPU1_P1")
		)
		(pad "DH27" smd circle
			(at -10.489946 35.999928 180)
			(size 0.450088 0.450088)
			(layers "F.Cu" "F.Mask" "F.Paste")
			(net "Net_2120")
		)
		(pad "DH28" smd circle
			(at -9.549892 35.999928 180)
			(size 0.450088 0.450088)
			(layers "F.Cu" "F.Mask" "F.Paste")
			(net "PVDDCR_CPU1_P1")
		)
		(pad "DH29" smd circle
			(at -8.610092 35.999928 180)
			(size 0.450088 0.450088)
			(layers "F.Cu" "F.Mask" "F.Paste")
			(net "PVDDCR_CPU1_P1")
		)
		(pad "DH30" smd circle
			(at -7.670038 35.999928 180)
			(size 0.450088 0.450088)
			(layers "F.Cu" "F.Mask" "F.Paste")
			(net "Net_2075")
		)
		(pad "DH31" smd circle
			(at -6.729984 35.999928 180)
			(size 0.450088 0.450088)
			(layers "F.Cu" "F.Mask" "F.Paste")
			(net "PVDDCR_CPU1_P1")
		)
		(pad "DH32" smd circle
			(at -5.78993 35.999928 180)
			(size 0.450088 0.450088)
			(layers "F.Cu" "F.Mask" "F.Paste")
			(net "PVDDCR_CPU1_P1")
		)
		(pad "DH33" smd circle
			(at -4.849876 35.999928 180)
			(size 0.450088 0.450088)
			(layers "F.Cu" "F.Mask" "F.Paste")
			(net "TP_CPU1_UART1_RX")
		)
		(pad "DH34" smd circle
			(at -3.910076 35.999928 180)
			(size 0.450088 0.450088)
			(layers "F.Cu" "F.Mask" "F.Paste")
			(net "PVDDCR_CPU1_P1")
		)
		(pad "DH35" smd circle
			(at -2.970022 35.999928 180)
			(size 0.450088 0.450088)
			(layers "F.Cu" "F.Mask" "F.Paste")
			(net "PVDDCR_CPU1_P1")
		)
		(pad "DH36" smd circle
			(at -2.029968 35.999928 180)
			(size 0.450088 0.450088)
			(layers "F.Cu" "F.Mask" "F.Paste")
			(net "CPU1_PWRGD_OUT")
		)
		(pad "DH37" smd circle
			(at -1.089914 35.999928 180)
			(size 0.450088 0.450088)
			(layers "F.Cu" "F.Mask" "F.Paste")
			(net "GND")
		)
		(pad "DH39" smd circle
			(at 0.78994 35.999928 180)
			(size 0.450088 0.450088)
			(layers "F.Cu" "F.Mask" "F.Paste")
			(net "GND")
		)
		(pad "DH40" smd circle
			(at 1.729994 35.999928 180)
			(size 0.450088 0.450088)
			(layers "F.Cu" "F.Mask" "F.Paste")
			(net "NC_CPU1_USB11_OC_N")
		)
		(pad "DH41" smd circle
			(at 2.670048 35.999928 180)
			(size 0.450088 0.450088)
			(layers "F.Cu" "F.Mask" "F.Paste")
			(net "PVDDCR_CPU1_P1")
		)
		(pad "DH42" smd circle
			(at 3.610102 35.999928 180)
			(size 0.450088 0.450088)
			(layers "F.Cu" "F.Mask" "F.Paste")
			(net "PVDDCR_CPU1_P1")
		)
		(pad "DH43" smd circle
			(at 4.549902 35.999928 180)
			(size 0.450088 0.450088)
			(layers "F.Cu" "F.Mask" "F.Paste")
			(net "GND")
		)
		(pad "DH44" smd circle
			(at 5.489956 35.999928 180)
			(size 0.450088 0.450088)
			(layers "F.Cu" "F.Mask" "F.Paste")
			(net "PVDDCR_CPU1_P1")
		)
		(pad "DH45" smd circle
			(at 6.43001 35.999928 180)
			(size 0.450088 0.450088)
			(layers "F.Cu" "F.Mask" "F.Paste")
			(net "PVDDCR_CPU1_P1")
		)
		(pad "DH46" smd circle
			(at 7.370064 35.999928 180)
			(size 0.450088 0.450088)
			(layers "F.Cu" "F.Mask" "F.Paste")
			(net "GND")
		)
		(pad "DH47" smd circle
			(at 8.310118 35.999928 180)
			(size 0.450088 0.450088)
			(layers "F.Cu" "F.Mask" "F.Paste")
			(net "PVDDCR_CPU1_P1")
		)
		(pad "DH48" smd circle
			(at 9.249918 35.999928 180)
			(size 0.450088 0.450088)
			(layers "F.Cu" "F.Mask" "F.Paste")
			(net "PVDDCR_CPU1_P1")
		)
		(pad "DH49" smd circle
			(at 10.189972 35.999928 180)
			(size 0.450088 0.450088)
			(layers "F.Cu" "F.Mask" "F.Paste")
			(net "GND")
		)
		(pad "DH50" smd circle
			(at 11.130026 35.999928 180)
			(size 0.450088 0.450088)
			(layers "F.Cu" "F.Mask" "F.Paste")
			(net "PVDDCR_CPU1_P1")
		)
		(pad "DH51" smd circle
			(at 12.07008 35.999928 180)
			(size 0.450088 0.450088)
			(layers "F.Cu" "F.Mask" "F.Paste")
			(net "PVDDCR_CPU1_P1")
		)
		(pad "DH52" smd circle
			(at 13.00988 35.999928 180)
			(size 0.450088 0.450088)
			(layers "F.Cu" "F.Mask" "F.Paste")
			(net "GND")
		)
		(pad "DH53" smd circle
			(at 13.949934 35.999928 180)
			(size 0.450088 0.450088)
			(layers "F.Cu" "F.Mask" "F.Paste")
			(net "PVDDCR_CPU1_P1")
		)
		(pad "DH54" smd circle
			(at 14.889988 35.999928 180)
			(size 0.450088 0.450088)
			(layers "F.Cu" "F.Mask" "F.Paste")
			(net "PVDDCR_CPU1_P1")
		)
		(pad "DH55" smd circle
			(at 15.830042 35.999928 180)
			(size 0.450088 0.450088)
			(layers "F.Cu" "F.Mask" "F.Paste")
			(net "GND")
		)
		(pad "DH56" smd circle
			(at 16.770096 35.999928 180)
			(size 0.450088 0.450088)
			(layers "F.Cu" "F.Mask" "F.Paste")
			(net "PVDDCR_CPU1_P1")
		)
		(pad "DH57" smd circle
			(at 17.709896 35.999928 180)
			(size 0.450088 0.450088)
			(layers "F.Cu" "F.Mask" "F.Paste")
			(net "PVDDCR_CPU1_P1")
		)
		(pad "DH58" smd circle
			(at 18.64995 35.999928 180)
			(size 0.450088 0.450088)
			(layers "F.Cu" "F.Mask" "F.Paste")
			(net "NC_CPU1_USB3_USB11_TXN")
		)
		(pad "DH59" smd circle
			(at 19.590004 35.999928 180)
			(size 0.450088 0.450088)
			(layers "F.Cu" "F.Mask" "F.Paste")
			(net "GND")
		)
		(pad "DH60" smd circle
			(at 20.530058 35.999928 180)
			(size 0.450088 0.450088)
			(layers "F.Cu" "F.Mask" "F.Paste")
			(net "NC_CPU1_USB2_USB11_DP")
		)
		(pad "DH61" smd circle
			(at 21.470112 35.999928 180)
			(size 0.450088 0.450088)
			(layers "F.Cu" "F.Mask" "F.Paste")
			(net "GND")
		)
		(pad "DH62" smd circle
			(at 22.409912 35.999928 180)
			(size 0.450088 0.450088)
			(layers "F.Cu" "F.Mask" "F.Paste")
			(net "NC_CPU1_USB3_USB11_RXN")
		)
		(pad "DH63" smd circle
			(at 23.349966 35.999928 180)
			(size 0.450088 0.450088)
			(layers "F.Cu" "F.Mask" "F.Paste")
			(net "GND")
		)
		(pad "DH64" smd circle
			(at 24.29002 35.999928 180)
			(size 0.450088 0.450088)
			(layers "F.Cu" "F.Mask" "F.Paste")
			(net "GND")
		)
		(pad "DH65" smd circle
			(at 25.230074 35.999928 180)
			(size 0.450088 0.450088)
			(layers "F.Cu" "F.Mask" "F.Paste")
			(net "NC_CPU1_USB3_USB10_RXN")
		)
		(pad "DH66" smd circle
			(at 26.170128 35.999928 180)
			(size 0.450088 0.450088)
			(layers "F.Cu" "F.Mask" "F.Paste")
			(net "GND")
		)
		(pad "DH67" smd circle
			(at 27.109928 35.999928 180)
			(size 0.450088 0.450088)
			(layers "F.Cu" "F.Mask" "F.Paste")
			(net "NC_CPU1_USB2_USB10_DN")
		)
		(pad "DH68" smd circle
			(at 28.049982 35.999928 180)
			(size 0.450088 0.450088)
			(layers "F.Cu" "F.Mask" "F.Paste")
			(net "GND")
		)
		(pad "DH69" smd circle
			(at 28.990036 35.999928 180)
			(size 0.450088 0.450088)
			(layers "F.Cu" "F.Mask" "F.Paste")
			(net "NC_CPU1_USB3_USB10_TXP")
		)
		(pad "DH70" smd circle
			(at 29.93009 35.999928 180)
			(size 0.450088 0.450088)
			(layers "F.Cu" "F.Mask" "F.Paste")
			(net "GND")
		)
		(pad "DH71" smd circle
			(at 30.86989 35.999928 180)
			(size 0.450088 0.450088)
			(layers "F.Cu" "F.Mask" "F.Paste")
			(net "SMB_APML_CPU1_SDA")
		)
		(pad "DH72" smd circle
			(at 31.809944 35.999928 180)
			(size 0.450088 0.450088)
			(layers "F.Cu" "F.Mask" "F.Paste")
			(net "SVID_PVDDCR_CPU1_P1_SVD")
		)
		(pad "DH73" smd circle
			(at 32.749998 35.999928 180)
			(size 0.450088 0.450088)
			(layers "F.Cu" "F.Mask" "F.Paste")
			(net "CPU1_SP5R3")
		)
		(pad "DJ3" smd circle
			(at -32.580072 36.809934 180)
			(size 0.450088 0.450088)
			(layers "F.Cu" "F.Mask" "F.Paste")
			(net "VSENSE_VSS_SENSE_C_P1")
		)
		(pad "DJ4" smd circle
			(at -31.640018 36.809934 180)
			(size 0.450088 0.450088)
			(layers "F.Cu" "F.Mask" "F.Paste")
			(net "Net_2166")
		)
		(pad "DJ5" smd circle
			(at -30.699964 36.809934 180)
			(size 0.450088 0.450088)
			(layers "F.Cu" "F.Mask" "F.Paste")
			(net "CPU1_SLP_S3_N")
		)
		(pad "DJ7" smd circle
			(at -28.82011 36.809934 180)
			(size 0.450088 0.450088)
			(layers "F.Cu" "F.Mask" "F.Paste")
			(net "GND")
		)
		(pad "DJ8" smd circle
			(at -27.880056 36.809934 180)
			(size 0.450088 0.450088)
			(layers "F.Cu" "F.Mask" "F.Paste")
			(net "CPU1_PWR_GD_IN")
		)
		(pad "DJ9" smd circle
			(at -26.940002 36.809934 180)
			(size 0.450088 0.450088)
			(layers "F.Cu" "F.Mask" "F.Paste")
			(net "CPU1_THERMTRIP_N")
		)
		(pad "DJ10" smd circle
			(at -25.999948 36.809934 180)
			(size 0.450088 0.450088)
			(layers "F.Cu" "F.Mask" "F.Paste")
			(net "IRQ_WAKE_N")
		)
		(pad "DJ11" smd circle
			(at -25.059894 36.809934 180)
			(size 0.450088 0.450088)
			(layers "F.Cu" "F.Mask" "F.Paste")
			(net "CPU1_SMERR_N")
		)
		(pad "DJ13" smd circle
			(at -23.18004 36.809934 180)
			(size 0.450088 0.450088)
			(layers "F.Cu" "F.Mask" "F.Paste")
			(net "XTAL_CPU1_X32K_X2")
		)
		(pad "DJ14" smd circle
			(at -22.239986 36.809934 180)
			(size 0.450088 0.450088)
			(layers "F.Cu" "F.Mask" "F.Paste")
			(net "XTAL_CPU1_X32K_X1")
		)
		(pad "DJ15" smd circle
			(at -21.299932 36.809934 180)
			(size 0.450088 0.450088)
			(layers "F.Cu" "F.Mask" "F.Paste")
			(net "GND")
		)
		(pad "DJ16" smd circle
			(at -20.359878 36.809934 180)
			(size 0.450088 0.450088)
			(layers "F.Cu" "F.Mask" "F.Paste")
			(net "XTAL_CPU1_X48M_X2")
		)
		(pad "DJ17" smd circle
			(at -19.420078 36.809934 180)
			(size 0.450088 0.450088)
			(layers "F.Cu" "F.Mask" "F.Paste")
			(net "XTAL_CPU1_X48M_X1")
		)
		(pad "DJ19" smd circle
			(at -17.53997 36.809934 180)
			(size 0.450088 0.450088)
			(layers "F.Cu" "F.Mask" "F.Paste")
			(net "GND")
		)
		(pad "DJ20" smd circle
			(at -16.599916 36.809934 180)
			(size 0.450088 0.450088)
			(layers "F.Cu" "F.Mask" "F.Paste")
			(net "Net_2095")
		)
		(pad "DJ21" smd circle
			(at -15.660116 36.809934 180)
			(size 0.450088 0.450088)
			(layers "F.Cu" "F.Mask" "F.Paste")
			(net "Net_2094")
		)
		(pad "DJ22" smd circle
			(at -14.720062 36.809934 180)
			(size 0.450088 0.450088)
			(layers "F.Cu" "F.Mask" "F.Paste")
			(net "Net_2103")
		)
		(pad "DJ23" smd circle
			(at -13.780008 36.809934 180)
			(size 0.450088 0.450088)
			(layers "F.Cu" "F.Mask" "F.Paste")
			(net "Net_2115")
		)
		(pad "DJ25" smd circle
			(at -11.8999 36.809934 180)
			(size 0.450088 0.450088)
			(layers "F.Cu" "F.Mask" "F.Paste")
			(net "Net_2102")
		)
		(pad "DJ26" smd circle
			(at -10.9601 36.809934 180)
			(size 0.450088 0.450088)
			(layers "F.Cu" "F.Mask" "F.Paste")
			(net "Net_2116")
		)
		(pad "DJ27" smd circle
			(at -10.020046 36.809934 180)
			(size 0.450088 0.450088)
			(layers "F.Cu" "F.Mask" "F.Paste")
			(net "SPI_CPU1_R_CLK")
		)
		(pad "DJ28" smd circle
			(at -9.079992 36.809934 180)
			(size 0.450088 0.450088)
			(layers "F.Cu" "F.Mask" "F.Paste")
			(net "Net_2106")
		)
		(pad "DJ29" smd circle
			(at -8.139938 36.809934 180)
			(size 0.450088 0.450088)
			(layers "F.Cu" "F.Mask" "F.Paste")
			(net "Net_2087")
		)
		(pad "DJ31" smd circle
			(at -6.260084 36.809934 180)
			(size 0.450088 0.450088)
			(layers "F.Cu" "F.Mask" "F.Paste")
			(net "CPU1_NMI_SYNC_FLOOD_N")
		)
		(pad "DJ32" smd circle
			(at -5.32003 36.809934 180)
			(size 0.450088 0.450088)
			(layers "F.Cu" "F.Mask" "F.Paste")
			(net "Net_2074")
		)
		(pad "DJ33" smd circle
			(at -4.379976 36.809934 180)
			(size 0.450088 0.450088)
			(layers "F.Cu" "F.Mask" "F.Paste")
			(net "TP_CPU1_UART0_CTS_N")
		)
		(pad "DJ34" smd circle
			(at -3.439922 36.809934 180)
			(size 0.450088 0.450088)
			(layers "F.Cu" "F.Mask" "F.Paste")
			(net "TP_CPU1_UART0_TX")
		)
		(pad "DJ35" smd circle
			(at -2.500122 36.809934 180)
			(size 0.450088 0.450088)
			(layers "F.Cu" "F.Mask" "F.Paste")
			(net "INT_CPU1_HP_UBM_N")
		)
		(pad "DJ41" smd circle
			(at 2.199894 36.809934 180)
			(size 0.450088 0.450088)
			(layers "F.Cu" "F.Mask" "F.Paste")
			(net "CLK_100M_CPU1_CLK11_R_DP")
		)
		(pad "DJ42" smd circle
			(at 3.139948 36.809934 180)
			(size 0.450088 0.450088)
			(layers "F.Cu" "F.Mask" "F.Paste")
			(net "CLK_100M_CPU1_CLK11_R_DN")
		)
		(pad "DJ43" smd circle
			(at 4.080002 36.809934 180)
			(size 0.450088 0.450088)
			(layers "F.Cu" "F.Mask" "F.Paste")
			(net "GND")
		)
		(pad "DJ44" smd circle
			(at 5.020056 36.809934 180)
			(size 0.450088 0.450088)
			(layers "F.Cu" "F.Mask" "F.Paste")
			(net "CLK_100M_CPU1_CLK12_R_DN")
		)
		(pad "DJ45" smd circle
			(at 5.96011 36.809934 180)
			(size 0.450088 0.450088)
			(layers "F.Cu" "F.Mask" "F.Paste")
			(net "CLK_100M_CPU1_CLK12_R_DP")
		)
		(pad "DJ47" smd circle
			(at 7.839964 36.809934 180)
			(size 0.450088 0.450088)
			(layers "F.Cu" "F.Mask" "F.Paste")
			(net "Net_2088")
		)
		(pad "DJ48" smd circle
			(at 8.780018 36.809934 180)
			(size 0.450088 0.450088)
			(layers "F.Cu" "F.Mask" "F.Paste")
			(net "Net_2089")
		)
		(pad "DJ49" smd circle
			(at 9.720072 36.809934 180)
			(size 0.450088 0.450088)
			(layers "F.Cu" "F.Mask" "F.Paste")
			(net "GND")
		)
		(pad "DJ50" smd circle
			(at 10.659872 36.809934 180)
			(size 0.450088 0.450088)
			(layers "F.Cu" "F.Mask" "F.Paste")
			(net "Net_2090")
		)
		(pad "DJ51" smd circle
			(at 11.599926 36.809934 180)
			(size 0.450088 0.450088)
			(layers "F.Cu" "F.Mask" "F.Paste")
			(net "Net_2091")
		)
		(pad "DJ53" smd circle
			(at 13.480034 36.809934 180)
			(size 0.450088 0.450088)
			(layers "F.Cu" "F.Mask" "F.Paste")
			(net "CLK_100M_CPU1_CLK13_R_DP")
		)
		(pad "DJ54" smd circle
			(at 14.420088 36.809934 180)
			(size 0.450088 0.450088)
			(layers "F.Cu" "F.Mask" "F.Paste")
			(net "CLK_100M_CPU1_CLK13_R_DN")
		)
		(pad "DJ55" smd circle
			(at 15.359888 36.809934 180)
			(size 0.450088 0.450088)
			(layers "F.Cu" "F.Mask" "F.Paste")
			(net "CPU1_SA0")
		)
		(pad "DJ56" smd circle
			(at 16.299942 36.809934 180)
			(size 0.450088 0.450088)
			(layers "F.Cu" "F.Mask" "F.Paste")
			(net "CPU1_SA1")
		)
		(pad "DJ57" smd circle
			(at 17.239996 36.809934 180)
			(size 0.450088 0.450088)
			(layers "F.Cu" "F.Mask" "F.Paste")
			(net "Net_2178")
		)
		(pad "DJ59" smd circle
			(at 19.120104 36.809934 180)
			(size 0.450088 0.450088)
			(layers "F.Cu" "F.Mask" "F.Paste")
			(net "GND")
		)
		(pad "DJ60" smd circle
			(at 20.059904 36.809934 180)
			(size 0.450088 0.450088)
			(layers "F.Cu" "F.Mask" "F.Paste")
			(net "NC_CPU1_USB2_USB11_DN")
		)
		(pad "DJ61" smd circle
			(at 20.999958 36.809934 180)
			(size 0.450088 0.450088)
			(layers "F.Cu" "F.Mask" "F.Paste")
			(net "GND")
		)
		(pad "DJ62" smd circle
			(at 21.940012 36.809934 180)
			(size 0.450088 0.450088)
			(layers "F.Cu" "F.Mask" "F.Paste")
			(net "NC_CPU1_USB3_USB11_RXP")
		)
		(pad "DJ63" smd circle
			(at 22.880066 36.809934 180)
			(size 0.450088 0.450088)
			(layers "F.Cu" "F.Mask" "F.Paste")
			(net "GND")
		)
		(pad "DJ65" smd circle
			(at 24.75992 36.809934 180)
			(size 0.450088 0.450088)
			(layers "F.Cu" "F.Mask" "F.Paste")
			(net "NC_CPU1_USB3_USB10_RXP")
		)
		(pad "DJ66" smd circle
			(at 25.699974 36.809934 180)
			(size 0.450088 0.450088)
			(layers "F.Cu" "F.Mask" "F.Paste")
			(net "GND")
		)
		(pad "DJ67" smd circle
			(at 26.640028 36.809934 180)
			(size 0.450088 0.450088)
			(layers "F.Cu" "F.Mask" "F.Paste")
			(net "NC_CPU1_USB2_USB10_DP")
		)
		(pad "DJ68" smd circle
			(at 27.580082 36.809934 180)
			(size 0.450088 0.450088)
			(layers "F.Cu" "F.Mask" "F.Paste")
			(net "GND")
		)
		(pad "DJ69" smd circle
			(at 28.519882 36.809934 180)
			(size 0.450088 0.450088)
			(layers "F.Cu" "F.Mask" "F.Paste")
			(net "NC_CPU1_USB3_USB10_TXN")
		)
		(pad "DJ71" smd circle
			(at 30.39999 36.809934 180)
			(size 0.450088 0.450088)
			(layers "F.Cu" "F.Mask" "F.Paste")
			(net "SMB_APML_CPU1_SCL")
		)
		(pad "DJ72" smd circle
			(at 31.340044 36.809934 180)
			(size 0.450088 0.450088)
			(layers "F.Cu" "F.Mask" "F.Paste")
			(net "SVID_PVDDCR_CPU1_P1_SVC")
		)
		(pad "DJ73" smd circle
			(at 32.280098 36.809934 180)
			(size 0.450088 0.450088)
			(layers "F.Cu" "F.Mask" "F.Paste")
			(net "GND")
		)
		(pad "E1" smd circle
			(at -34.159952 -33.56991 180)
			(size 0.450088 0.450088)
			(layers "F.Cu" "F.Mask" "F.Paste")
			(net "GND")
		)
		(pad "E2" smd circle
			(at -33.219898 -33.56991 180)
			(size 0.450088 0.450088)
			(layers "F.Cu" "F.Mask" "F.Paste")
			(net "M_G_CPU1_SA_DQ<0>")
		)
		(pad "E3" smd circle
			(at -32.280098 -33.56991 180)
			(size 0.450088 0.450088)
			(layers "F.Cu" "F.Mask" "F.Paste")
			(net "GND")
		)
		(pad "E4" smd circle
			(at -31.340044 -33.56991 180)
			(size 0.450088 0.450088)
			(layers "F.Cu" "F.Mask" "F.Paste")
			(net "PVDDCR_SOC_P1")
		)
		(pad "E5" smd circle
			(at -30.39999 -33.56991 180)
			(size 0.450088 0.450088)
			(layers "F.Cu" "F.Mask" "F.Paste")
			(net "M_K_CPU1_SA_DQ<0>")
		)
		(pad "E6" smd circle
			(at -29.459936 -33.56991 180)
			(size 0.450088 0.450088)
			(layers "F.Cu" "F.Mask" "F.Paste")
			(net "GND")
		)
		(pad "E7" smd circle
			(at -28.519882 -33.56991 180)
			(size 0.450088 0.450088)
			(layers "F.Cu" "F.Mask" "F.Paste")
			(net "GND")
		)
		(pad "E8" smd circle
			(at -27.580082 -33.56991 180)
			(size 0.450088 0.450088)
			(layers "F.Cu" "F.Mask" "F.Paste")
			(net "GND")
		)
		(pad "E9" smd circle
			(at -26.640028 -33.56991 180)
			(size 0.450088 0.450088)
			(layers "F.Cu" "F.Mask" "F.Paste")
			(net "M_L_CPU1_SA_DQ<0>")
		)
		(pad "E10" smd circle
			(at -25.699974 -33.56991 180)
			(size 0.450088 0.450088)
			(layers "F.Cu" "F.Mask" "F.Paste")
			(net "GND")
		)
		(pad "E11" smd circle
			(at -24.75992 -33.56991 180)
			(size 0.450088 0.450088)
			(layers "F.Cu" "F.Mask" "F.Paste")
			(net "PVDDCR_SOC_P1")
		)
		(pad "E12" smd circle
			(at -23.82012 -33.56991 180)
			(size 0.450088 0.450088)
			(layers "F.Cu" "F.Mask" "F.Paste")
			(net "M_H_CPU1_SA_DQ<0>")
		)
		(pad "E13" smd circle
			(at -22.880066 -33.56991 180)
			(size 0.450088 0.450088)
			(layers "F.Cu" "F.Mask" "F.Paste")
			(net "GND")
		)
		(pad "E14" smd circle
			(at -21.940012 -33.56991 180)
			(size 0.450088 0.450088)
			(layers "F.Cu" "F.Mask" "F.Paste")
			(net "GND")
		)
		(pad "E15" smd circle
			(at -20.999958 -33.56991 180)
			(size 0.450088 0.450088)
			(layers "F.Cu" "F.Mask" "F.Paste")
			(net "GND")
		)
		(pad "E16" smd circle
			(at -20.059904 -33.56991 180)
			(size 0.450088 0.450088)
			(layers "F.Cu" "F.Mask" "F.Paste")
			(net "M_J_CPU1_SA_DQ<0>")
		)
		(pad "E17" smd circle
			(at -19.120104 -33.56991 180)
			(size 0.450088 0.450088)
			(layers "F.Cu" "F.Mask" "F.Paste")
			(net "GND")
		)
		(pad "E18" smd circle
			(at -18.18005 -33.56991 180)
			(size 0.450088 0.450088)
			(layers "F.Cu" "F.Mask" "F.Paste")
			(net "GND")
		)
		(pad "E19" smd circle
			(at -17.239996 -33.56991 180)
			(size 0.450088 0.450088)
			(layers "F.Cu" "F.Mask" "F.Paste")
			(net "M_I_CPU1_SA_DQ<0>")
		)
		(pad "E20" smd circle
			(at -16.299942 -33.56991 180)
			(size 0.450088 0.450088)
			(layers "F.Cu" "F.Mask" "F.Paste")
			(net "GND")
		)
		(pad "E21" smd circle
			(at -15.359888 -33.56991 180)
			(size 0.450088 0.450088)
			(layers "F.Cu" "F.Mask" "F.Paste")
			(net "GND")
		)
		(pad "E22" smd circle
			(at -14.420088 -33.56991 180)
			(size 0.450088 0.450088)
			(layers "F.Cu" "F.Mask" "F.Paste")
			(net "PVDDCR_CPU0_P1")
		)
		(pad "E23" smd circle
			(at -13.480034 -33.56991 180)
			(size 0.450088 0.450088)
			(layers "F.Cu" "F.Mask" "F.Paste")
			(net "NC_CPU1_USB00_OC_N")
		)
		(pad "E24" smd circle
			(at -12.53998 -33.56991 180)
			(size 0.450088 0.450088)
			(layers "F.Cu" "F.Mask" "F.Paste")
			(net "NC_CPU1_USB01_OC_N")
		)
		(pad "E25" smd circle
			(at -11.599926 -33.56991 180)
			(size 0.450088 0.450088)
			(layers "F.Cu" "F.Mask" "F.Paste")
			(net "PVDDCR_CPU0_P1")
		)
		(pad "E26" smd circle
			(at -10.659872 -33.56991 180)
			(size 0.450088 0.450088)
			(layers "F.Cu" "F.Mask" "F.Paste")
			(net "NC_CPU1_USB3_USB00_RXN")
		)
		(pad "E27" smd circle
			(at -9.720072 -33.56991 180)
			(size 0.450088 0.450088)
			(layers "F.Cu" "F.Mask" "F.Paste")
			(net "NC_CPU1_USB3_USB00_RXP")
		)
		(pad "E28" smd circle
			(at -8.780018 -33.56991 180)
			(size 0.450088 0.450088)
			(layers "F.Cu" "F.Mask" "F.Paste")
			(net "PVDDCR_CPU0_P1")
		)
		(pad "E29" smd circle
			(at -7.839964 -33.56991 180)
			(size 0.450088 0.450088)
			(layers "F.Cu" "F.Mask" "F.Paste")
			(net "NC_CPU1_USB3_USB01_TXN")
		)
		(pad "E30" smd circle
			(at -6.89991 -33.56991 180)
			(size 0.450088 0.450088)
			(layers "F.Cu" "F.Mask" "F.Paste")
			(net "NC_CPU1_USB3_USB01_TXP")
		)
		(pad "E31" smd circle
			(at -5.96011 -33.56991 180)
			(size 0.450088 0.450088)
			(layers "F.Cu" "F.Mask" "F.Paste")
			(net "PVDDCR_CPU0_P1")
		)
		(pad "E32" smd circle
			(at -5.020056 -33.56991 180)
			(size 0.450088 0.450088)
			(layers "F.Cu" "F.Mask" "F.Paste")
			(net "TP_CPU1_TEST47_CCD3")
		)
		(pad "E33" smd circle
			(at -4.080002 -33.56991 180)
			(size 0.450088 0.450088)
			(layers "F.Cu" "F.Mask" "F.Paste")
			(net "Net_2167")
		)
		(pad "E34" smd circle
			(at -3.139948 -33.56991 180)
			(size 0.450088 0.450088)
			(layers "F.Cu" "F.Mask" "F.Paste")
			(net "PVDDCR_CPU0_P1")
		)
		(pad "E35" smd circle
			(at -2.199894 -33.56991 180)
			(size 0.450088 0.450088)
			(layers "F.Cu" "F.Mask" "F.Paste")
			(net "PVDDCR_CPU0_P1")
		)
		(pad "E36" smd circle
			(at -1.260094 -33.56991 180)
			(size 0.450088 0.450088)
			(layers "F.Cu" "F.Mask" "F.Paste")
			(net "Net_2168")
		)
		(pad "E40" smd circle
			(at 1.560068 -33.56991 180)
			(size 0.450088 0.450088)
			(layers "F.Cu" "F.Mask" "F.Paste")
			(net "P3E_CPU1_P5_RX_DN<1>")
		)
		(pad "E41" smd circle
			(at 2.500122 -33.56991 180)
			(size 0.450088 0.450088)
			(layers "F.Cu" "F.Mask" "F.Paste")
			(net "P3E_CPU1_P5_RX_DP<1>")
		)
		(pad "E42" smd circle
			(at 3.439922 -33.56991 180)
			(size 0.450088 0.450088)
			(layers "F.Cu" "F.Mask" "F.Paste")
			(net "PVDDCR_CPU0_P1")
		)
		(pad "E43" smd circle
			(at 4.379976 -33.56991 180)
			(size 0.450088 0.450088)
			(layers "F.Cu" "F.Mask" "F.Paste")
			(net "P3E_CPU1_P5_RX_DN<0>")
		)
		(pad "E44" smd circle
			(at 5.32003 -33.56991 180)
			(size 0.450088 0.450088)
			(layers "F.Cu" "F.Mask" "F.Paste")
			(net "P3E_CPU1_P5_RX_DP<0>")
		)
		(pad "E45" smd circle
			(at 6.260084 -33.56991 180)
			(size 0.450088 0.450088)
			(layers "F.Cu" "F.Mask" "F.Paste")
			(net "PVDDCR_CPU0_P1")
		)
		(pad "E46" smd circle
			(at 7.199884 -33.56991 180)
			(size 0.450088 0.450088)
			(layers "F.Cu" "F.Mask" "F.Paste")
			(net "WAFL_CPU0_TX0_CPU1_RX1_DP")
		)
		(pad "E47" smd circle
			(at 8.139938 -33.56991 180)
			(size 0.450088 0.450088)
			(layers "F.Cu" "F.Mask" "F.Paste")
			(net "WAFL_CPU0_TX0_CPU1_RX1_DN")
		)
		(pad "E48" smd circle
			(at 9.079992 -33.56991 180)
			(size 0.450088 0.450088)
			(layers "F.Cu" "F.Mask" "F.Paste")
			(net "PVDDCR_CPU0_P1")
		)
		(pad "E49" smd circle
			(at 10.020046 -33.56991 180)
			(size 0.450088 0.450088)
			(layers "F.Cu" "F.Mask" "F.Paste")
			(net "Net_2071")
		)
		(pad "E50" smd circle
			(at 10.9601 -33.56991 180)
			(size 0.450088 0.450088)
			(layers "F.Cu" "F.Mask" "F.Paste")
			(net "Net_2070")
		)
		(pad "E51" smd circle
			(at 11.8999 -33.56991 180)
			(size 0.450088 0.450088)
			(layers "F.Cu" "F.Mask" "F.Paste")
			(net "PVDDCR_CPU0_P1")
		)
		(pad "E52" smd circle
			(at 12.839954 -33.56991 180)
			(size 0.450088 0.450088)
			(layers "F.Cu" "F.Mask" "F.Paste")
			(net "GND")
		)
		(pad "E53" smd circle
			(at 13.780008 -33.56991 180)
			(size 0.450088 0.450088)
			(layers "F.Cu" "F.Mask" "F.Paste")
			(net "GND")
		)
		(pad "E54" smd circle
			(at 14.720062 -33.56991 180)
			(size 0.450088 0.450088)
			(layers "F.Cu" "F.Mask" "F.Paste")
			(net "PVDDCR_CPU0_P1")
		)
		(pad "E55" smd circle
			(at 15.660116 -33.56991 180)
			(size 0.450088 0.450088)
			(layers "F.Cu" "F.Mask" "F.Paste")
			(net "GND")
		)
		(pad "E56" smd circle
			(at 16.599916 -33.56991 180)
			(size 0.450088 0.450088)
			(layers "F.Cu" "F.Mask" "F.Paste")
			(net "GND")
		)
		(pad "E57" smd circle
			(at 17.53997 -33.56991 180)
			(size 0.450088 0.450088)
			(layers "F.Cu" "F.Mask" "F.Paste")
			(net "M_C_CPU1_SA_DQ<0>")
		)
		(pad "E58" smd circle
			(at 18.480024 -33.56991 180)
			(size 0.450088 0.450088)
			(layers "F.Cu" "F.Mask" "F.Paste")
			(net "GND")
		)
		(pad "E59" smd circle
			(at 19.420078 -33.56991 180)
			(size 0.450088 0.450088)
			(layers "F.Cu" "F.Mask" "F.Paste")
			(net "GND")
		)
		(pad "E60" smd circle
			(at 20.359878 -33.56991 180)
			(size 0.450088 0.450088)
			(layers "F.Cu" "F.Mask" "F.Paste")
			(net "M_D_CPU1_SA_DQ<0>")
		)
		(pad "E61" smd circle
			(at 21.299932 -33.56991 180)
			(size 0.450088 0.450088)
			(layers "F.Cu" "F.Mask" "F.Paste")
			(net "GND")
		)
		(pad "E62" smd circle
			(at 22.239986 -33.56991 180)
			(size 0.450088 0.450088)
			(layers "F.Cu" "F.Mask" "F.Paste")
			(net "GND")
		)
		(pad "E63" smd circle
			(at 23.18004 -33.56991 180)
			(size 0.450088 0.450088)
			(layers "F.Cu" "F.Mask" "F.Paste")
			(net "GND")
		)
		(pad "E64" smd circle
			(at 24.120094 -33.56991 180)
			(size 0.450088 0.450088)
			(layers "F.Cu" "F.Mask" "F.Paste")
			(net "M_B_CPU1_SA_DQ<0>")
		)
		(pad "E65" smd circle
			(at 25.059894 -33.56991 180)
			(size 0.450088 0.450088)
			(layers "F.Cu" "F.Mask" "F.Paste")
			(net "GND")
		)
		(pad "E66" smd circle
			(at 25.999948 -33.56991 180)
			(size 0.450088 0.450088)
			(layers "F.Cu" "F.Mask" "F.Paste")
			(net "GND")
		)
		(pad "E67" smd circle
			(at 26.940002 -33.56991 180)
			(size 0.450088 0.450088)
			(layers "F.Cu" "F.Mask" "F.Paste")
			(net "M_F_CPU1_SA_DQ<0>")
		)
		(pad "E68" smd circle
			(at 27.880056 -33.56991 180)
			(size 0.450088 0.450088)
			(layers "F.Cu" "F.Mask" "F.Paste")
			(net "GND")
		)
		(pad "E69" smd circle
			(at 28.82011 -33.56991 180)
			(size 0.450088 0.450088)
			(layers "F.Cu" "F.Mask" "F.Paste")
			(net "GND")
		)
		(pad "E70" smd circle
			(at 29.75991 -33.56991 180)
			(size 0.450088 0.450088)
			(layers "F.Cu" "F.Mask" "F.Paste")
			(net "GND")
		)
		(pad "E71" smd circle
			(at 30.699964 -33.56991 180)
			(size 0.450088 0.450088)
			(layers "F.Cu" "F.Mask" "F.Paste")
			(net "M_E_CPU1_SA_DQ<0>")
		)
		(pad "E72" smd circle
			(at 31.640018 -33.56991 180)
			(size 0.450088 0.450088)
			(layers "F.Cu" "F.Mask" "F.Paste")
			(net "GND")
		)
		(pad "E73" smd circle
			(at 32.580072 -33.56991 180)
			(size 0.450088 0.450088)
			(layers "F.Cu" "F.Mask" "F.Paste")
			(net "GND")
		)
		(pad "E74" smd circle
			(at 33.519872 -33.56991 180)
			(size 0.450088 0.450088)
			(layers "F.Cu" "F.Mask" "F.Paste")
			(net "M_A_CPU1_SA_DQ<0>")
		)
		(pad "E75" smd circle
			(at 34.459926 -33.56991 180)
			(size 0.450088 0.450088)
			(layers "F.Cu" "F.Mask" "F.Paste")
			(net "GND")
		)
		(pad "F2" smd circle
			(at -33.690052 -32.759904 180)
			(size 0.450088 0.450088)
			(layers "F.Cu" "F.Mask" "F.Paste")
			(net "M_G_CPU1_SA_DQ<2>")
		)
		(pad "F3" smd circle
			(at -32.749998 -32.759904 180)
			(size 0.450088 0.450088)
			(layers "F.Cu" "F.Mask" "F.Paste")
			(net "GND")
		)
		(pad "F4" smd circle
			(at -31.809944 -32.759904 180)
			(size 0.450088 0.450088)
			(layers "F.Cu" "F.Mask" "F.Paste")
			(net "M_G_CPU1_SA_DQ<1>")
		)
		(pad "F5" smd circle
			(at -30.86989 -32.759904 180)
			(size 0.450088 0.450088)
			(layers "F.Cu" "F.Mask" "F.Paste")
			(net "GND")
		)
		(pad "F6" smd circle
			(at -29.93009 -32.759904 180)
			(size 0.450088 0.450088)
			(layers "F.Cu" "F.Mask" "F.Paste")
			(net "M_K_CPU1_SA_DQ<2>")
		)
		(pad "F7" smd circle
			(at -28.990036 -32.759904 180)
			(size 0.450088 0.450088)
			(layers "F.Cu" "F.Mask" "F.Paste")
			(net "M_K_CPU1_SA_DQ<1>")
		)
		(pad "F8" smd circle
			(at -28.049982 -32.759904 180)
			(size 0.450088 0.450088)
			(layers "F.Cu" "F.Mask" "F.Paste")
			(net "GND")
		)
		(pad "F9" smd circle
			(at -27.109928 -32.759904 180)
			(size 0.450088 0.450088)
			(layers "F.Cu" "F.Mask" "F.Paste")
			(net "M_L_CPU1_SA_DQ<2>")
		)
		(pad "F10" smd circle
			(at -26.170128 -32.759904 180)
			(size 0.450088 0.450088)
			(layers "F.Cu" "F.Mask" "F.Paste")
			(net "GND")
		)
		(pad "F11" smd circle
			(at -25.230074 -32.759904 180)
			(size 0.450088 0.450088)
			(layers "F.Cu" "F.Mask" "F.Paste")
			(net "M_L_CPU1_SA_DQ<1>")
		)
		(pad "F12" smd circle
			(at -24.29002 -32.759904 180)
			(size 0.450088 0.450088)
			(layers "F.Cu" "F.Mask" "F.Paste")
			(net "GND")
		)
		(pad "F13" smd circle
			(at -23.349966 -32.759904 180)
			(size 0.450088 0.450088)
			(layers "F.Cu" "F.Mask" "F.Paste")
			(net "M_H_CPU1_SA_DQ<2>")
		)
		(pad "F14" smd circle
			(at -22.409912 -32.759904 180)
			(size 0.450088 0.450088)
			(layers "F.Cu" "F.Mask" "F.Paste")
			(net "M_H_CPU1_SA_DQ<1>")
		)
		(pad "F15" smd circle
			(at -21.470112 -32.759904 180)
			(size 0.450088 0.450088)
			(layers "F.Cu" "F.Mask" "F.Paste")
			(net "GND")
		)
		(pad "F16" smd circle
			(at -20.530058 -32.759904 180)
			(size 0.450088 0.450088)
			(layers "F.Cu" "F.Mask" "F.Paste")
			(net "M_J_CPU1_SA_DQ<2>")
		)
		(pad "F17" smd circle
			(at -19.590004 -32.759904 180)
			(size 0.450088 0.450088)
			(layers "F.Cu" "F.Mask" "F.Paste")
			(net "GND")
		)
		(pad "F18" smd circle
			(at -18.64995 -32.759904 180)
			(size 0.450088 0.450088)
			(layers "F.Cu" "F.Mask" "F.Paste")
			(net "M_J_CPU1_SA_DQ<1>")
		)
		(pad "F19" smd circle
			(at -17.709896 -32.759904 180)
			(size 0.450088 0.450088)
			(layers "F.Cu" "F.Mask" "F.Paste")
			(net "GND")
		)
		(pad "F20" smd circle
			(at -16.770096 -32.759904 180)
			(size 0.450088 0.450088)
			(layers "F.Cu" "F.Mask" "F.Paste")
			(net "M_I_CPU1_SA_DQ<2>")
		)
		(pad "F21" smd circle
			(at -15.830042 -32.759904 180)
			(size 0.450088 0.450088)
			(layers "F.Cu" "F.Mask" "F.Paste")
			(net "M_I_CPU1_SA_DQ<1>")
		)
		(pad "F22" smd circle
			(at -14.889988 -32.759904 180)
			(size 0.450088 0.450088)
			(layers "F.Cu" "F.Mask" "F.Paste")
			(net "PVDDCR_CPU0_P1")
		)
		(pad "F23" smd circle
			(at -13.949934 -32.759904 180)
			(size 0.450088 0.450088)
			(layers "F.Cu" "F.Mask" "F.Paste")
			(net "GND")
		)
		(pad "F24" smd circle
			(at -13.00988 -32.759904 180)
			(size 0.450088 0.450088)
			(layers "F.Cu" "F.Mask" "F.Paste")
			(net "GND")
		)
		(pad "F25" smd circle
			(at -12.07008 -32.759904 180)
			(size 0.450088 0.450088)
			(layers "F.Cu" "F.Mask" "F.Paste")
			(net "PVDDCR_CPU0_P1")
		)
		(pad "F26" smd circle
			(at -11.130026 -32.759904 180)
			(size 0.450088 0.450088)
			(layers "F.Cu" "F.Mask" "F.Paste")
			(net "GND")
		)
		(pad "F27" smd circle
			(at -10.189972 -32.759904 180)
			(size 0.450088 0.450088)
			(layers "F.Cu" "F.Mask" "F.Paste")
			(net "GND")
		)
		(pad "F28" smd circle
			(at -9.249918 -32.759904 180)
			(size 0.450088 0.450088)
			(layers "F.Cu" "F.Mask" "F.Paste")
			(net "PVDDCR_CPU0_P1")
		)
		(pad "F29" smd circle
			(at -8.310118 -32.759904 180)
			(size 0.450088 0.450088)
			(layers "F.Cu" "F.Mask" "F.Paste")
			(net "GND")
		)
		(pad "F30" smd circle
			(at -7.370064 -32.759904 180)
			(size 0.450088 0.450088)
			(layers "F.Cu" "F.Mask" "F.Paste")
			(net "GND")
		)
		(pad "F31" smd circle
			(at -6.43001 -32.759904 180)
			(size 0.450088 0.450088)
			(layers "F.Cu" "F.Mask" "F.Paste")
			(net "PVDDCR_CPU0_P1")
		)
		(pad "F32" smd circle
			(at -5.489956 -32.759904 180)
			(size 0.450088 0.450088)
			(layers "F.Cu" "F.Mask" "F.Paste")
			(net "GND")
		)
		(pad "F33" smd circle
			(at -4.549902 -32.759904 180)
			(size 0.450088 0.450088)
			(layers "F.Cu" "F.Mask" "F.Paste")
			(net "GND")
		)
		(pad "F34" smd circle
			(at -3.610102 -32.759904 180)
			(size 0.450088 0.450088)
			(layers "F.Cu" "F.Mask" "F.Paste")
			(net "PVDDCR_CPU0_P1")
		)
		(pad "F35" smd circle
			(at -2.670048 -32.759904 180)
			(size 0.450088 0.450088)
			(layers "F.Cu" "F.Mask" "F.Paste")
			(net "GND")
		)
		(pad "F36" smd circle
			(at -1.729994 -32.759904 180)
			(size 0.450088 0.450088)
			(layers "F.Cu" "F.Mask" "F.Paste")
			(net "GND")
		)
		(pad "F37" smd circle
			(at -0.78994 -32.759904 180)
			(size 0.450088 0.450088)
			(layers "F.Cu" "F.Mask" "F.Paste")
			(net "GND")
		)
		(pad "F39" smd circle
			(at 1.089914 -32.759904 180)
			(size 0.450088 0.450088)
			(layers "F.Cu" "F.Mask" "F.Paste")
			(net "GND")
		)
		(pad "F40" smd circle
			(at 2.029968 -32.759904 180)
			(size 0.450088 0.450088)
			(layers "F.Cu" "F.Mask" "F.Paste")
			(net "GND")
		)
		(pad "F41" smd circle
			(at 2.970022 -32.759904 180)
			(size 0.450088 0.450088)
			(layers "F.Cu" "F.Mask" "F.Paste")
			(net "GND")
		)
		(pad "F42" smd circle
			(at 3.910076 -32.759904 180)
			(size 0.450088 0.450088)
			(layers "F.Cu" "F.Mask" "F.Paste")
			(net "PVDDCR_CPU0_P1")
		)
		(pad "F43" smd circle
			(at 4.849876 -32.759904 180)
			(size 0.450088 0.450088)
			(layers "F.Cu" "F.Mask" "F.Paste")
			(net "GND")
		)
		(pad "F44" smd circle
			(at 5.78993 -32.759904 180)
			(size 0.450088 0.450088)
			(layers "F.Cu" "F.Mask" "F.Paste")
			(net "GND")
		)
		(pad "F45" smd circle
			(at 6.729984 -32.759904 180)
			(size 0.450088 0.450088)
			(layers "F.Cu" "F.Mask" "F.Paste")
			(net "PVDDCR_CPU0_P1")
		)
		(pad "F46" smd circle
			(at 7.670038 -32.759904 180)
			(size 0.450088 0.450088)
			(layers "F.Cu" "F.Mask" "F.Paste")
			(net "GND")
		)
		(pad "F47" smd circle
			(at 8.610092 -32.759904 180)
			(size 0.450088 0.450088)
			(layers "F.Cu" "F.Mask" "F.Paste")
			(net "GND")
		)
		(pad "F48" smd circle
			(at 9.549892 -32.759904 180)
			(size 0.450088 0.450088)
			(layers "F.Cu" "F.Mask" "F.Paste")
			(net "PVDDCR_CPU0_P1")
		)
		(pad "F49" smd circle
			(at 10.489946 -32.759904 180)
			(size 0.450088 0.450088)
			(layers "F.Cu" "F.Mask" "F.Paste")
			(net "GND")
		)
		(pad "F50" smd circle
			(at 11.43 -32.759904 180)
			(size 0.450088 0.450088)
			(layers "F.Cu" "F.Mask" "F.Paste")
			(net "GND")
		)
		(pad "F51" smd circle
			(at 12.370054 -32.759904 180)
			(size 0.450088 0.450088)
			(layers "F.Cu" "F.Mask" "F.Paste")
			(net "PVDDCR_CPU0_P1")
		)
		(pad "F52" smd circle
			(at 13.310108 -32.759904 180)
			(size 0.450088 0.450088)
			(layers "F.Cu" "F.Mask" "F.Paste")
			(net "GND")
		)
		(pad "F53" smd circle
			(at 14.249908 -32.759904 180)
			(size 0.450088 0.450088)
			(layers "F.Cu" "F.Mask" "F.Paste")
			(net "GND")
		)
		(pad "F54" smd circle
			(at 15.189962 -32.759904 180)
			(size 0.450088 0.450088)
			(layers "F.Cu" "F.Mask" "F.Paste")
			(net "PVDDCR_CPU0_P1")
		)
		(pad "F55" smd circle
			(at 16.130016 -32.759904 180)
			(size 0.450088 0.450088)
			(layers "F.Cu" "F.Mask" "F.Paste")
			(net "M_C_CPU1_SA_DQ<1>")
		)
		(pad "F56" smd circle
			(at 17.07007 -32.759904 180)
			(size 0.450088 0.450088)
			(layers "F.Cu" "F.Mask" "F.Paste")
			(net "M_C_CPU1_SA_DQ<2>")
		)
		(pad "F57" smd circle
			(at 18.010124 -32.759904 180)
			(size 0.450088 0.450088)
			(layers "F.Cu" "F.Mask" "F.Paste")
			(net "GND")
		)
		(pad "F58" smd circle
			(at 18.949924 -32.759904 180)
			(size 0.450088 0.450088)
			(layers "F.Cu" "F.Mask" "F.Paste")
			(net "M_D_CPU1_SA_DQ<1>")
		)
		(pad "F59" smd circle
			(at 19.889978 -32.759904 180)
			(size 0.450088 0.450088)
			(layers "F.Cu" "F.Mask" "F.Paste")
			(net "GND")
		)
		(pad "F60" smd circle
			(at 20.830032 -32.759904 180)
			(size 0.450088 0.450088)
			(layers "F.Cu" "F.Mask" "F.Paste")
			(net "M_D_CPU1_SA_DQ<2>")
		)
		(pad "F61" smd circle
			(at 21.770086 -32.759904 180)
			(size 0.450088 0.450088)
			(layers "F.Cu" "F.Mask" "F.Paste")
			(net "GND")
		)
		(pad "F62" smd circle
			(at 22.709886 -32.759904 180)
			(size 0.450088 0.450088)
			(layers "F.Cu" "F.Mask" "F.Paste")
			(net "M_B_CPU1_SA_DQ<1>")
		)
		(pad "F63" smd circle
			(at 23.64994 -32.759904 180)
			(size 0.450088 0.450088)
			(layers "F.Cu" "F.Mask" "F.Paste")
			(net "M_B_CPU1_SA_DQ<2>")
		)
		(pad "F64" smd circle
			(at 24.589994 -32.759904 180)
			(size 0.450088 0.450088)
			(layers "F.Cu" "F.Mask" "F.Paste")
			(net "GND")
		)
		(pad "F65" smd circle
			(at 25.530048 -32.759904 180)
			(size 0.450088 0.450088)
			(layers "F.Cu" "F.Mask" "F.Paste")
			(net "M_F_CPU1_SA_DQ<1>")
		)
		(pad "F66" smd circle
			(at 26.470102 -32.759904 180)
			(size 0.450088 0.450088)
			(layers "F.Cu" "F.Mask" "F.Paste")
			(net "GND")
		)
		(pad "F67" smd circle
			(at 27.409902 -32.759904 180)
			(size 0.450088 0.450088)
			(layers "F.Cu" "F.Mask" "F.Paste")
			(net "M_F_CPU1_SA_DQ<2>")
		)
		(pad "F68" smd circle
			(at 28.349956 -32.759904 180)
			(size 0.450088 0.450088)
			(layers "F.Cu" "F.Mask" "F.Paste")
			(net "GND")
		)
		(pad "F69" smd circle
			(at 29.29001 -32.759904 180)
			(size 0.450088 0.450088)
			(layers "F.Cu" "F.Mask" "F.Paste")
			(net "M_E_CPU1_SA_DQ<1>")
		)
		(pad "F70" smd circle
			(at 30.230064 -32.759904 180)
			(size 0.450088 0.450088)
			(layers "F.Cu" "F.Mask" "F.Paste")
			(net "M_E_CPU1_SA_DQ<2>")
		)
		(pad "F71" smd circle
			(at 31.170118 -32.759904 180)
			(size 0.450088 0.450088)
			(layers "F.Cu" "F.Mask" "F.Paste")
			(net "GND")
		)
		(pad "F72" smd circle
			(at 32.109918 -32.759904 180)
			(size 0.450088 0.450088)
			(layers "F.Cu" "F.Mask" "F.Paste")
			(net "M_A_CPU1_SA_DQ<1>")
		)
		(pad "F73" smd circle
			(at 33.049972 -32.759904 180)
			(size 0.450088 0.450088)
			(layers "F.Cu" "F.Mask" "F.Paste")
			(net "GND")
		)
		(pad "F74" smd circle
			(at 33.990026 -32.759904 180)
			(size 0.450088 0.450088)
			(layers "F.Cu" "F.Mask" "F.Paste")
			(net "M_A_CPU1_SA_DQ<2>")
		)
		(pad "G1" smd circle
			(at -34.159952 -31.949898 180)
			(size 0.450088 0.450088)
			(layers "F.Cu" "F.Mask" "F.Paste")
			(net "GND")
		)
		(pad "G2" smd circle
			(at -33.219898 -31.949898 180)
			(size 0.450088 0.450088)
			(layers "F.Cu" "F.Mask" "F.Paste")
			(net "M_G_CPU1_SA_DQS_DP<0>")
		)
		(pad "G3" smd circle
			(at -32.280098 -31.949898 180)
			(size 0.450088 0.450088)
			(layers "F.Cu" "F.Mask" "F.Paste")
			(net "M_G_CPU1_SA_DQ<3>")
		)
		(pad "G4" smd circle
			(at -31.340044 -31.949898 180)
			(size 0.450088 0.450088)
			(layers "F.Cu" "F.Mask" "F.Paste")
			(net "GND")
		)
		(pad "G5" smd circle
			(at -30.39999 -31.949898 180)
			(size 0.450088 0.450088)
			(layers "F.Cu" "F.Mask" "F.Paste")
			(net "M_K_CPU1_SA_DQS_DP<0>")
		)
		(pad "G6" smd circle
			(at -29.459936 -31.949898 180)
			(size 0.450088 0.450088)
			(layers "F.Cu" "F.Mask" "F.Paste")
			(net "GND")
		)
		(pad "G7" smd circle
			(at -28.519882 -31.949898 180)
			(size 0.450088 0.450088)
			(layers "F.Cu" "F.Mask" "F.Paste")
			(net "M_K_CPU1_SA_DQ<3>")
		)
		(pad "G8" smd circle
			(at -27.580082 -31.949898 180)
			(size 0.450088 0.450088)
			(layers "F.Cu" "F.Mask" "F.Paste")
			(net "GND")
		)
		(pad "G9" smd circle
			(at -26.640028 -31.949898 180)
			(size 0.450088 0.450088)
			(layers "F.Cu" "F.Mask" "F.Paste")
			(net "M_L_CPU1_SA_DQS_DP<0>")
		)
		(pad "G10" smd circle
			(at -25.699974 -31.949898 180)
			(size 0.450088 0.450088)
			(layers "F.Cu" "F.Mask" "F.Paste")
			(net "M_L_CPU1_SA_DQ<3>")
		)
		(pad "G11" smd circle
			(at -24.75992 -31.949898 180)
			(size 0.450088 0.450088)
			(layers "F.Cu" "F.Mask" "F.Paste")
			(net "GND")
		)
		(pad "G12" smd circle
			(at -23.82012 -31.949898 180)
			(size 0.450088 0.450088)
			(layers "F.Cu" "F.Mask" "F.Paste")
			(net "M_H_CPU1_SA_DQS_DP<0>")
		)
		(pad "G13" smd circle
			(at -22.880066 -31.949898 180)
			(size 0.450088 0.450088)
			(layers "F.Cu" "F.Mask" "F.Paste")
			(net "GND")
		)
		(pad "G14" smd circle
			(at -21.940012 -31.949898 180)
			(size 0.450088 0.450088)
			(layers "F.Cu" "F.Mask" "F.Paste")
			(net "M_H_CPU1_SA_DQ<3>")
		)
		(pad "G15" smd circle
			(at -20.999958 -31.949898 180)
			(size 0.450088 0.450088)
			(layers "F.Cu" "F.Mask" "F.Paste")
			(net "GND")
		)
		(pad "G16" smd circle
			(at -20.059904 -31.949898 180)
			(size 0.450088 0.450088)
			(layers "F.Cu" "F.Mask" "F.Paste")
			(net "M_J_CPU1_SA_DQS_DP<0>")
		)
		(pad "G17" smd circle
			(at -19.120104 -31.949898 180)
			(size 0.450088 0.450088)
			(layers "F.Cu" "F.Mask" "F.Paste")
			(net "M_J_CPU1_SA_DQ<3>")
		)
		(pad "G18" smd circle
			(at -18.18005 -31.949898 180)
			(size 0.450088 0.450088)
			(layers "F.Cu" "F.Mask" "F.Paste")
			(net "GND")
		)
		(pad "G19" smd circle
			(at -17.239996 -31.949898 180)
			(size 0.450088 0.450088)
			(layers "F.Cu" "F.Mask" "F.Paste")
			(net "M_I_CPU1_SA_DQS_DP<0>")
		)
		(pad "G20" smd circle
			(at -16.299942 -31.949898 180)
			(size 0.450088 0.450088)
			(layers "F.Cu" "F.Mask" "F.Paste")
			(net "GND")
		)
		(pad "G21" smd circle
			(at -15.359888 -31.949898 180)
			(size 0.450088 0.450088)
			(layers "F.Cu" "F.Mask" "F.Paste")
			(net "M_I_CPU1_SA_DQ<3>")
		)
		(pad "G22" smd circle
			(at -14.420088 -31.949898 180)
			(size 0.450088 0.450088)
			(layers "F.Cu" "F.Mask" "F.Paste")
			(net "GND")
		)
		(pad "G23" smd circle
			(at -13.480034 -31.949898 180)
			(size 0.450088 0.450088)
			(layers "F.Cu" "F.Mask" "F.Paste")
			(net "GMI_CPU1_G2_CPU0_G0_TX_DP<13>")
		)
		(pad "G24" smd circle
			(at -12.53998 -31.949898 180)
			(size 0.450088 0.450088)
			(layers "F.Cu" "F.Mask" "F.Paste")
			(net "GMI_CPU1_G2_CPU0_G0_TX_DN<13>")
		)
		(pad "G25" smd circle
			(at -11.599926 -31.949898 180)
			(size 0.450088 0.450088)
			(layers "F.Cu" "F.Mask" "F.Paste")
			(net "GND")
		)
		(pad "G26" smd circle
			(at -10.659872 -31.949898 180)
			(size 0.450088 0.450088)
			(layers "F.Cu" "F.Mask" "F.Paste")
			(net "GMI_CPU1_G2_CPU0_G0_TX_DP<10>")
		)
		(pad "G27" smd circle
			(at -9.720072 -31.949898 180)
			(size 0.450088 0.450088)
			(layers "F.Cu" "F.Mask" "F.Paste")
			(net "GMI_CPU1_G2_CPU0_G0_TX_DN<10>")
		)
		(pad "G28" smd circle
			(at -8.780018 -31.949898 180)
			(size 0.450088 0.450088)
			(layers "F.Cu" "F.Mask" "F.Paste")
			(net "GND")
		)
		(pad "G29" smd circle
			(at -7.839964 -31.949898 180)
			(size 0.450088 0.450088)
			(layers "F.Cu" "F.Mask" "F.Paste")
			(net "GMI_CPU1_G2_CPU0_G0_TX_DP<7>")
		)
		(pad "G30" smd circle
			(at -6.89991 -31.949898 180)
			(size 0.450088 0.450088)
			(layers "F.Cu" "F.Mask" "F.Paste")
			(net "GMI_CPU1_G2_CPU0_G0_TX_DN<7>")
		)
		(pad "G31" smd circle
			(at -5.96011 -31.949898 180)
			(size 0.450088 0.450088)
			(layers "F.Cu" "F.Mask" "F.Paste")
			(net "GND")
		)
		(pad "G32" smd circle
			(at -5.020056 -31.949898 180)
			(size 0.450088 0.450088)
			(layers "F.Cu" "F.Mask" "F.Paste")
			(net "GMI_CPU1_G2_CPU0_G0_TX_DP<4>")
		)
		(pad "G33" smd circle
			(at -4.080002 -31.949898 180)
			(size 0.450088 0.450088)
			(layers "F.Cu" "F.Mask" "F.Paste")
			(net "GMI_CPU1_G2_CPU0_G0_TX_DN<4>")
		)
		(pad "G34" smd circle
			(at -3.139948 -31.949898 180)
			(size 0.450088 0.450088)
			(layers "F.Cu" "F.Mask" "F.Paste")
			(net "GND")
		)
		(pad "G35" smd circle
			(at -2.199894 -31.949898 180)
			(size 0.450088 0.450088)
			(layers "F.Cu" "F.Mask" "F.Paste")
			(net "PVDDCR_CPU0_P1")
		)
		(pad "G36" smd circle
			(at -1.260094 -31.949898 180)
			(size 0.450088 0.450088)
			(layers "F.Cu" "F.Mask" "F.Paste")
			(net "PVDDCR_CPU0_P1")
		)
		(pad "G40" smd circle
			(at 1.560068 -31.949898 180)
			(size 0.450088 0.450088)
			(layers "F.Cu" "F.Mask" "F.Paste")
			(net "PVDDCR_CPU0_P1")
		)
		(pad "G41" smd circle
			(at 2.500122 -31.949898 180)
			(size 0.450088 0.450088)
			(layers "F.Cu" "F.Mask" "F.Paste")
			(net "PVDDCR_CPU0_P1")
		)
		(pad "G42" smd circle
			(at 3.439922 -31.949898 180)
			(size 0.450088 0.450088)
			(layers "F.Cu" "F.Mask" "F.Paste")
			(net "GND")
		)
		(pad "G43" smd circle
			(at 4.379976 -31.949898 180)
			(size 0.450088 0.450088)
			(layers "F.Cu" "F.Mask" "F.Paste")
			(net "GMI_CPU0_G2_CPU1_G0_TX_DN<11>")
		)
		(pad "G44" smd circle
			(at 5.32003 -31.949898 180)
			(size 0.450088 0.450088)
			(layers "F.Cu" "F.Mask" "F.Paste")
			(net "GMI_CPU0_G2_CPU1_G0_TX_DP<11>")
		)
		(pad "G45" smd circle
			(at 6.260084 -31.949898 180)
			(size 0.450088 0.450088)
			(layers "F.Cu" "F.Mask" "F.Paste")
			(net "GND")
		)
		(pad "G46" smd circle
			(at 7.199884 -31.949898 180)
			(size 0.450088 0.450088)
			(layers "F.Cu" "F.Mask" "F.Paste")
			(net "GMI_CPU0_G2_CPU1_G0_TX_DN<8>")
		)
		(pad "G47" smd circle
			(at 8.139938 -31.949898 180)
			(size 0.450088 0.450088)
			(layers "F.Cu" "F.Mask" "F.Paste")
			(net "GMI_CPU0_G2_CPU1_G0_TX_DP<8>")
		)
		(pad "G48" smd circle
			(at 9.079992 -31.949898 180)
			(size 0.450088 0.450088)
			(layers "F.Cu" "F.Mask" "F.Paste")
			(net "GND")
		)
		(pad "G49" smd circle
			(at 10.020046 -31.949898 180)
			(size 0.450088 0.450088)
			(layers "F.Cu" "F.Mask" "F.Paste")
			(net "GMI_CPU0_G2_CPU1_G0_TX_DN<5>")
		)
		(pad "G50" smd circle
			(at 10.9601 -31.949898 180)
			(size 0.450088 0.450088)
			(layers "F.Cu" "F.Mask" "F.Paste")
			(net "GMI_CPU0_G2_CPU1_G0_TX_DP<5>")
		)
		(pad "G51" smd circle
			(at 11.8999 -31.949898 180)
			(size 0.450088 0.450088)
			(layers "F.Cu" "F.Mask" "F.Paste")
			(net "GND")
		)
		(pad "G52" smd circle
			(at 12.839954 -31.949898 180)
			(size 0.450088 0.450088)
			(layers "F.Cu" "F.Mask" "F.Paste")
			(net "GMI_CPU0_G2_CPU1_G0_TX_DN<2>")
		)
		(pad "G53" smd circle
			(at 13.780008 -31.949898 180)
			(size 0.450088 0.450088)
			(layers "F.Cu" "F.Mask" "F.Paste")
			(net "GMI_CPU0_G2_CPU1_G0_TX_DP<2>")
		)
		(pad "G54" smd circle
			(at 14.720062 -31.949898 180)
			(size 0.450088 0.450088)
			(layers "F.Cu" "F.Mask" "F.Paste")
			(net "GND")
		)
		(pad "G55" smd circle
			(at 15.660116 -31.949898 180)
			(size 0.450088 0.450088)
			(layers "F.Cu" "F.Mask" "F.Paste")
			(net "M_C_CPU1_SA_DQ<3>")
		)
		(pad "G56" smd circle
			(at 16.599916 -31.949898 180)
			(size 0.450088 0.450088)
			(layers "F.Cu" "F.Mask" "F.Paste")
			(net "GND")
		)
		(pad "G57" smd circle
			(at 17.53997 -31.949898 180)
			(size 0.450088 0.450088)
			(layers "F.Cu" "F.Mask" "F.Paste")
			(net "M_C_CPU1_SA_DQS_DP<0>")
		)
		(pad "G58" smd circle
			(at 18.480024 -31.949898 180)
			(size 0.450088 0.450088)
			(layers "F.Cu" "F.Mask" "F.Paste")
			(net "GND")
		)
		(pad "G59" smd circle
			(at 19.420078 -31.949898 180)
			(size 0.450088 0.450088)
			(layers "F.Cu" "F.Mask" "F.Paste")
			(net "M_D_CPU1_SA_DQ<3>")
		)
		(pad "G60" smd circle
			(at 20.359878 -31.949898 180)
			(size 0.450088 0.450088)
			(layers "F.Cu" "F.Mask" "F.Paste")
			(net "M_D_CPU1_SA_DQS_DP<0>")
		)
		(pad "G61" smd circle
			(at 21.299932 -31.949898 180)
			(size 0.450088 0.450088)
			(layers "F.Cu" "F.Mask" "F.Paste")
			(net "GND")
		)
		(pad "G62" smd circle
			(at 22.239986 -31.949898 180)
			(size 0.450088 0.450088)
			(layers "F.Cu" "F.Mask" "F.Paste")
			(net "M_B_CPU1_SA_DQ<3>")
		)
		(pad "G63" smd circle
			(at 23.18004 -31.949898 180)
			(size 0.450088 0.450088)
			(layers "F.Cu" "F.Mask" "F.Paste")
			(net "GND")
		)
		(pad "G64" smd circle
			(at 24.120094 -31.949898 180)
			(size 0.450088 0.450088)
			(layers "F.Cu" "F.Mask" "F.Paste")
			(net "M_B_CPU1_SA_DQS_DP<0>")
		)
		(pad "G65" smd circle
			(at 25.059894 -31.949898 180)
			(size 0.450088 0.450088)
			(layers "F.Cu" "F.Mask" "F.Paste")
			(net "GND")
		)
		(pad "G66" smd circle
			(at 25.999948 -31.949898 180)
			(size 0.450088 0.450088)
			(layers "F.Cu" "F.Mask" "F.Paste")
			(net "M_F_CPU1_SA_DQ<3>")
		)
		(pad "G67" smd circle
			(at 26.940002 -31.949898 180)
			(size 0.450088 0.450088)
			(layers "F.Cu" "F.Mask" "F.Paste")
			(net "M_F_CPU1_SA_DQS_DP<0>")
		)
		(pad "G68" smd circle
			(at 27.880056 -31.949898 180)
			(size 0.450088 0.450088)
			(layers "F.Cu" "F.Mask" "F.Paste")
			(net "GND")
		)
		(pad "G69" smd circle
			(at 28.82011 -31.949898 180)
			(size 0.450088 0.450088)
			(layers "F.Cu" "F.Mask" "F.Paste")
			(net "M_E_CPU1_SA_DQ<3>")
		)
		(pad "G70" smd circle
			(at 29.75991 -31.949898 180)
			(size 0.450088 0.450088)
			(layers "F.Cu" "F.Mask" "F.Paste")
			(net "GND")
		)
		(pad "G71" smd circle
			(at 30.699964 -31.949898 180)
			(size 0.450088 0.450088)
			(layers "F.Cu" "F.Mask" "F.Paste")
			(net "M_E_CPU1_SA_DQS_DP<0>")
		)
		(pad "G72" smd circle
			(at 31.640018 -31.949898 180)
			(size 0.450088 0.450088)
			(layers "F.Cu" "F.Mask" "F.Paste")
			(net "GND")
		)
		(pad "G73" smd circle
			(at 32.580072 -31.949898 180)
			(size 0.450088 0.450088)
			(layers "F.Cu" "F.Mask" "F.Paste")
			(net "M_A_CPU1_SA_DQ<3>")
		)
		(pad "G74" smd circle
			(at 33.519872 -31.949898 180)
			(size 0.450088 0.450088)
			(layers "F.Cu" "F.Mask" "F.Paste")
			(net "M_A_CPU1_SA_DQS_DP<0>")
		)
		(pad "G75" smd circle
			(at 34.459926 -31.949898 180)
			(size 0.450088 0.450088)
			(layers "F.Cu" "F.Mask" "F.Paste")
			(net "GND")
		)
		(pad "H2" smd circle
			(at -33.690052 -31.139892 180)
			(size 0.450088 0.450088)
			(layers "F.Cu" "F.Mask" "F.Paste")
			(net "M_G_CPU1_SA_DQS_DN<0>")
		)
		(pad "H3" smd circle
			(at -32.749998 -31.139892 180)
			(size 0.450088 0.450088)
			(layers "F.Cu" "F.Mask" "F.Paste")
			(net "GND")
		)
		(pad "H4" smd circle
			(at -31.809944 -31.139892 180)
			(size 0.450088 0.450088)
			(layers "F.Cu" "F.Mask" "F.Paste")
			(net "M_G_CPU1_SA_DQS_DN<5>")
		)
		(pad "H5" smd circle
			(at -30.86989 -31.139892 180)
			(size 0.450088 0.450088)
			(layers "F.Cu" "F.Mask" "F.Paste")
			(net "PVDDCR_SOC_P1")
		)
		(pad "H6" smd circle
			(at -29.93009 -31.139892 180)
			(size 0.450088 0.450088)
			(layers "F.Cu" "F.Mask" "F.Paste")
			(net "M_K_CPU1_SA_DQS_DN<0>")
		)
		(pad "H7" smd circle
			(at -28.990036 -31.139892 180)
			(size 0.450088 0.450088)
			(layers "F.Cu" "F.Mask" "F.Paste")
			(net "M_K_CPU1_SA_DQS_DN<5>")
		)
		(pad "H8" smd circle
			(at -28.049982 -31.139892 180)
			(size 0.450088 0.450088)
			(layers "F.Cu" "F.Mask" "F.Paste")
			(net "GND")
		)
		(pad "H9" smd circle
			(at -27.109928 -31.139892 180)
			(size 0.450088 0.450088)
			(layers "F.Cu" "F.Mask" "F.Paste")
			(net "M_L_CPU1_SA_DQS_DN<0>")
		)
		(pad "H10" smd circle
			(at -26.170128 -31.139892 180)
			(size 0.450088 0.450088)
			(layers "F.Cu" "F.Mask" "F.Paste")
			(net "GND")
		)
		(pad "H11" smd circle
			(at -25.230074 -31.139892 180)
			(size 0.450088 0.450088)
			(layers "F.Cu" "F.Mask" "F.Paste")
			(net "M_L_CPU1_SA_DQS_DN<5>")
		)
		(pad "H12" smd circle
			(at -24.29002 -31.139892 180)
			(size 0.450088 0.450088)
			(layers "F.Cu" "F.Mask" "F.Paste")
			(net "PVDDCR_SOC_P1")
		)
		(pad "H13" smd circle
			(at -23.349966 -31.139892 180)
			(size 0.450088 0.450088)
			(layers "F.Cu" "F.Mask" "F.Paste")
			(net "M_H_CPU1_SA_DQS_DN<0>")
		)
		(pad "H14" smd circle
			(at -22.409912 -31.139892 180)
			(size 0.450088 0.450088)
			(layers "F.Cu" "F.Mask" "F.Paste")
			(net "M_H_CPU1_SA_DQS_DN<5>")
		)
		(pad "H15" smd circle
			(at -21.470112 -31.139892 180)
			(size 0.450088 0.450088)
			(layers "F.Cu" "F.Mask" "F.Paste")
			(net "GND")
		)
		(pad "H16" smd circle
			(at -20.530058 -31.139892 180)
			(size 0.450088 0.450088)
			(layers "F.Cu" "F.Mask" "F.Paste")
			(net "M_J_CPU1_SA_DQS_DN<0>")
		)
		(pad "H17" smd circle
			(at -19.590004 -31.139892 180)
			(size 0.450088 0.450088)
			(layers "F.Cu" "F.Mask" "F.Paste")
			(net "GND")
		)
		(pad "H18" smd circle
			(at -18.64995 -31.139892 180)
			(size 0.450088 0.450088)
			(layers "F.Cu" "F.Mask" "F.Paste")
			(net "M_J_CPU1_SA_DQS_DN<5>")
		)
		(pad "H19" smd circle
			(at -17.709896 -31.139892 180)
			(size 0.450088 0.450088)
			(layers "F.Cu" "F.Mask" "F.Paste")
			(net "PVDDCR_SOC_P1")
		)
		(pad "H20" smd circle
			(at -16.770096 -31.139892 180)
			(size 0.450088 0.450088)
			(layers "F.Cu" "F.Mask" "F.Paste")
			(net "M_I_CPU1_SA_DQS_DN<0>")
		)
		(pad "H21" smd circle
			(at -15.830042 -31.139892 180)
			(size 0.450088 0.450088)
			(layers "F.Cu" "F.Mask" "F.Paste")
			(net "M_I_CPU1_SA_DQS_DN<5>")
		)
		(pad "H22" smd circle
			(at -14.889988 -31.139892 180)
			(size 0.450088 0.450088)
			(layers "F.Cu" "F.Mask" "F.Paste")
			(net "GND")
		)
		(pad "H23" smd circle
			(at -13.949934 -31.139892 180)
			(size 0.450088 0.450088)
			(layers "F.Cu" "F.Mask" "F.Paste")
			(net "PVDDCR_CPU0_P1")
		)
		(pad "H24" smd circle
			(at -13.00988 -31.139892 180)
			(size 0.450088 0.450088)
			(layers "F.Cu" "F.Mask" "F.Paste")
			(net "PVDDCR_CPU0_P1")
		)
		(pad "H25" smd circle
			(at -12.07008 -31.139892 180)
			(size 0.450088 0.450088)
			(layers "F.Cu" "F.Mask" "F.Paste")
			(net "GND")
		)
		(pad "H26" smd circle
			(at -11.130026 -31.139892 180)
			(size 0.450088 0.450088)
			(layers "F.Cu" "F.Mask" "F.Paste")
			(net "PVDDCR_CPU0_P1")
		)
		(pad "H27" smd circle
			(at -10.189972 -31.139892 180)
			(size 0.450088 0.450088)
			(layers "F.Cu" "F.Mask" "F.Paste")
			(net "PVDDCR_CPU0_P1")
		)
		(pad "H28" smd circle
			(at -9.249918 -31.139892 180)
			(size 0.450088 0.450088)
			(layers "F.Cu" "F.Mask" "F.Paste")
			(net "GND")
		)
		(pad "H29" smd circle
			(at -8.310118 -31.139892 180)
			(size 0.450088 0.450088)
			(layers "F.Cu" "F.Mask" "F.Paste")
			(net "PVDDCR_CPU0_P1")
		)
		(pad "H30" smd circle
			(at -7.370064 -31.139892 180)
			(size 0.450088 0.450088)
			(layers "F.Cu" "F.Mask" "F.Paste")
			(net "PVDDCR_CPU0_P1")
		)
		(pad "H31" smd circle
			(at -6.43001 -31.139892 180)
			(size 0.450088 0.450088)
			(layers "F.Cu" "F.Mask" "F.Paste")
			(net "GND")
		)
		(pad "H32" smd circle
			(at -5.489956 -31.139892 180)
			(size 0.450088 0.450088)
			(layers "F.Cu" "F.Mask" "F.Paste")
			(net "PVDDCR_CPU0_P1")
		)
		(pad "H33" smd circle
			(at -4.549902 -31.139892 180)
			(size 0.450088 0.450088)
			(layers "F.Cu" "F.Mask" "F.Paste")
			(net "PVDDCR_CPU0_P1")
		)
		(pad "H34" smd circle
			(at -3.610102 -31.139892 180)
			(size 0.450088 0.450088)
			(layers "F.Cu" "F.Mask" "F.Paste")
			(net "GND")
		)
		(pad "H35" smd circle
			(at -2.670048 -31.139892 180)
			(size 0.450088 0.450088)
			(layers "F.Cu" "F.Mask" "F.Paste")
			(net "GMI_CPU1_G2_CPU0_G0_TX_DP<2>")
		)
		(pad "H36" smd circle
			(at -1.729994 -31.139892 180)
			(size 0.450088 0.450088)
			(layers "F.Cu" "F.Mask" "F.Paste")
			(net "GMI_CPU1_G2_CPU0_G0_TX_DN<2>")
		)
		(pad "H37" smd circle
			(at -0.78994 -31.139892 180)
			(size 0.450088 0.450088)
			(layers "F.Cu" "F.Mask" "F.Paste")
			(net "GND")
		)
		(pad "H39" smd circle
			(at 1.089914 -31.139892 180)
			(size 0.450088 0.450088)
			(layers "F.Cu" "F.Mask" "F.Paste")
			(net "GND")
		)
		(pad "H40" smd circle
			(at 2.029968 -31.139892 180)
			(size 0.450088 0.450088)
			(layers "F.Cu" "F.Mask" "F.Paste")
			(net "GMI_CPU0_G2_CPU1_G0_TX_DN<13>")
		)
		(pad "H41" smd circle
			(at 2.970022 -31.139892 180)
			(size 0.450088 0.450088)
			(layers "F.Cu" "F.Mask" "F.Paste")
			(net "GMI_CPU0_G2_CPU1_G0_TX_DP<13>")
		)
		(pad "H42" smd circle
			(at 3.910076 -31.139892 180)
			(size 0.450088 0.450088)
			(layers "F.Cu" "F.Mask" "F.Paste")
			(net "GND")
		)
		(pad "H43" smd circle
			(at 4.849876 -31.139892 180)
			(size 0.450088 0.450088)
			(layers "F.Cu" "F.Mask" "F.Paste")
			(net "PVDDCR_CPU0_P1")
		)
		(pad "H44" smd circle
			(at 5.78993 -31.139892 180)
			(size 0.450088 0.450088)
			(layers "F.Cu" "F.Mask" "F.Paste")
			(net "PVDDCR_CPU0_P1")
		)
		(pad "H45" smd circle
			(at 6.729984 -31.139892 180)
			(size 0.450088 0.450088)
			(layers "F.Cu" "F.Mask" "F.Paste")
			(net "GND")
		)
		(pad "H46" smd circle
			(at 7.670038 -31.139892 180)
			(size 0.450088 0.450088)
			(layers "F.Cu" "F.Mask" "F.Paste")
			(net "PVDDCR_CPU0_P1")
		)
		(pad "H47" smd circle
			(at 8.610092 -31.139892 180)
			(size 0.450088 0.450088)
			(layers "F.Cu" "F.Mask" "F.Paste")
			(net "PVDDCR_CPU0_P1")
		)
		(pad "H48" smd circle
			(at 9.549892 -31.139892 180)
			(size 0.450088 0.450088)
			(layers "F.Cu" "F.Mask" "F.Paste")
			(net "GND")
		)
		(pad "H49" smd circle
			(at 10.489946 -31.139892 180)
			(size 0.450088 0.450088)
			(layers "F.Cu" "F.Mask" "F.Paste")
			(net "PVDDCR_CPU0_P1")
		)
		(pad "H50" smd circle
			(at 11.43 -31.139892 180)
			(size 0.450088 0.450088)
			(layers "F.Cu" "F.Mask" "F.Paste")
			(net "PVDDCR_CPU0_P1")
		)
		(pad "H51" smd circle
			(at 12.370054 -31.139892 180)
			(size 0.450088 0.450088)
			(layers "F.Cu" "F.Mask" "F.Paste")
			(net "GND")
		)
		(pad "H52" smd circle
			(at 13.310108 -31.139892 180)
			(size 0.450088 0.450088)
			(layers "F.Cu" "F.Mask" "F.Paste")
			(net "PVDDCR_CPU0_P1")
		)
		(pad "H53" smd circle
			(at 14.249908 -31.139892 180)
			(size 0.450088 0.450088)
			(layers "F.Cu" "F.Mask" "F.Paste")
			(net "PVDDCR_CPU0_P1")
		)
		(pad "H54" smd circle
			(at 15.189962 -31.139892 180)
			(size 0.450088 0.450088)
			(layers "F.Cu" "F.Mask" "F.Paste")
			(net "GND")
		)
		(pad "H55" smd circle
			(at 16.130016 -31.139892 180)
			(size 0.450088 0.450088)
			(layers "F.Cu" "F.Mask" "F.Paste")
			(net "M_C_CPU1_SA_DQS_DN<5>")
		)
		(pad "H56" smd circle
			(at 17.07007 -31.139892 180)
			(size 0.450088 0.450088)
			(layers "F.Cu" "F.Mask" "F.Paste")
			(net "M_C_CPU1_SA_DQS_DN<0>")
		)
		(pad "H57" smd circle
			(at 18.010124 -31.139892 180)
			(size 0.450088 0.450088)
			(layers "F.Cu" "F.Mask" "F.Paste")
			(net "PVDDIO_P1")
		)
		(pad "H58" smd circle
			(at 18.949924 -31.139892 180)
			(size 0.450088 0.450088)
			(layers "F.Cu" "F.Mask" "F.Paste")
			(net "M_D_CPU1_SA_DQS_DN<5>")
		)
		(pad "H59" smd circle
			(at 19.889978 -31.139892 180)
			(size 0.450088 0.450088)
			(layers "F.Cu" "F.Mask" "F.Paste")
			(net "GND")
		)
		(pad "H60" smd circle
			(at 20.830032 -31.139892 180)
			(size 0.450088 0.450088)
			(layers "F.Cu" "F.Mask" "F.Paste")
			(net "M_D_CPU1_SA_DQS_DN<0>")
		)
		(pad "H61" smd circle
			(at 21.770086 -31.139892 180)
			(size 0.450088 0.450088)
			(layers "F.Cu" "F.Mask" "F.Paste")
			(net "GND")
		)
		(pad "H62" smd circle
			(at 22.709886 -31.139892 180)
			(size 0.450088 0.450088)
			(layers "F.Cu" "F.Mask" "F.Paste")
			(net "M_B_CPU1_SA_DQS_DN<5>")
		)
		(pad "H63" smd circle
			(at 23.64994 -31.139892 180)
			(size 0.450088 0.450088)
			(layers "F.Cu" "F.Mask" "F.Paste")
			(net "M_B_CPU1_SA_DQS_DN<0>")
		)
		(pad "H64" smd circle
			(at 24.589994 -31.139892 180)
			(size 0.450088 0.450088)
			(layers "F.Cu" "F.Mask" "F.Paste")
			(net "PVDDIO_P1")
		)
		(pad "H65" smd circle
			(at 25.530048 -31.139892 180)
			(size 0.450088 0.450088)
			(layers "F.Cu" "F.Mask" "F.Paste")
			(net "M_F_CPU1_SA_DQS_DN<5>")
		)
		(pad "H66" smd circle
			(at 26.470102 -31.139892 180)
			(size 0.450088 0.450088)
			(layers "F.Cu" "F.Mask" "F.Paste")
			(net "GND")
		)
		(pad "H67" smd circle
			(at 27.409902 -31.139892 180)
			(size 0.450088 0.450088)
			(layers "F.Cu" "F.Mask" "F.Paste")
			(net "M_F_CPU1_SA_DQS_DN<0>")
		)
		(pad "H68" smd circle
			(at 28.349956 -31.139892 180)
			(size 0.450088 0.450088)
			(layers "F.Cu" "F.Mask" "F.Paste")
			(net "GND")
		)
		(pad "H69" smd circle
			(at 29.29001 -31.139892 180)
			(size 0.450088 0.450088)
			(layers "F.Cu" "F.Mask" "F.Paste")
			(net "M_E_CPU1_SA_DQS_DN<5>")
		)
		(pad "H70" smd circle
			(at 30.230064 -31.139892 180)
			(size 0.450088 0.450088)
			(layers "F.Cu" "F.Mask" "F.Paste")
			(net "M_E_CPU1_SA_DQS_DN<0>")
		)
		(pad "H71" smd circle
			(at 31.170118 -31.139892 180)
			(size 0.450088 0.450088)
			(layers "F.Cu" "F.Mask" "F.Paste")
			(net "PVDDIO_P1")
		)
		(pad "H72" smd circle
			(at 32.109918 -31.139892 180)
			(size 0.450088 0.450088)
			(layers "F.Cu" "F.Mask" "F.Paste")
			(net "M_A_CPU1_SA_DQS_DN<5>")
		)
		(pad "H73" smd circle
			(at 33.049972 -31.139892 180)
			(size 0.450088 0.450088)
			(layers "F.Cu" "F.Mask" "F.Paste")
			(net "GND")
		)
		(pad "H74" smd circle
			(at 33.990026 -31.139892 180)
			(size 0.450088 0.450088)
			(layers "F.Cu" "F.Mask" "F.Paste")
			(net "M_A_CPU1_SA_DQS_DN<0>")
		)
		(pad "J1" smd circle
			(at -34.159952 -30.329886 180)
			(size 0.450088 0.450088)
			(layers "F.Cu" "F.Mask" "F.Paste")
			(net "GND")
		)
		(pad "J2" smd circle
			(at -33.219898 -30.329886 180)
			(size 0.450088 0.450088)
			(layers "F.Cu" "F.Mask" "F.Paste")
			(net "M_G_CPU1_SA_DQ<4>")
		)
		(pad "J3" smd circle
			(at -32.280098 -30.329886 180)
			(size 0.450088 0.450088)
			(layers "F.Cu" "F.Mask" "F.Paste")
			(net "M_G_CPU1_SA_DQS_DP<5>")
		)
		(pad "J4" smd circle
			(at -31.340044 -30.329886 180)
			(size 0.450088 0.450088)
			(layers "F.Cu" "F.Mask" "F.Paste")
			(net "GND")
		)
		(pad "J5" smd circle
			(at -30.39999 -30.329886 180)
			(size 0.450088 0.450088)
			(layers "F.Cu" "F.Mask" "F.Paste")
			(net "M_K_CPU1_SA_DQ<4>")
		)
		(pad "J6" smd circle
			(at -29.459936 -30.329886 180)
			(size 0.450088 0.450088)
			(layers "F.Cu" "F.Mask" "F.Paste")
			(net "GND")
		)
		(pad "J7" smd circle
			(at -28.519882 -30.329886 180)
			(size 0.450088 0.450088)
			(layers "F.Cu" "F.Mask" "F.Paste")
			(net "M_K_CPU1_SA_DQS_DP<5>")
		)
		(pad "J8" smd circle
			(at -27.580082 -30.329886 180)
			(size 0.450088 0.450088)
			(layers "F.Cu" "F.Mask" "F.Paste")
			(net "GND")
		)
		(pad "J9" smd circle
			(at -26.640028 -30.329886 180)
			(size 0.450088 0.450088)
			(layers "F.Cu" "F.Mask" "F.Paste")
			(net "M_L_CPU1_SA_DQ<4>")
		)
		(pad "J10" smd circle
			(at -25.699974 -30.329886 180)
			(size 0.450088 0.450088)
			(layers "F.Cu" "F.Mask" "F.Paste")
			(net "M_L_CPU1_SA_DQS_DP<5>")
		)
		(pad "J11" smd circle
			(at -24.75992 -30.329886 180)
			(size 0.450088 0.450088)
			(layers "F.Cu" "F.Mask" "F.Paste")
			(net "GND")
		)
		(pad "J12" smd circle
			(at -23.82012 -30.329886 180)
			(size 0.450088 0.450088)
			(layers "F.Cu" "F.Mask" "F.Paste")
			(net "M_H_CPU1_SA_DQ<4>")
		)
		(pad "J13" smd circle
			(at -22.880066 -30.329886 180)
			(size 0.450088 0.450088)
			(layers "F.Cu" "F.Mask" "F.Paste")
			(net "GND")
		)
		(pad "J14" smd circle
			(at -21.940012 -30.329886 180)
			(size 0.450088 0.450088)
			(layers "F.Cu" "F.Mask" "F.Paste")
			(net "M_H_CPU1_SA_DQS_DP<5>")
		)
		(pad "J15" smd circle
			(at -20.999958 -30.329886 180)
			(size 0.450088 0.450088)
			(layers "F.Cu" "F.Mask" "F.Paste")
			(net "GND")
		)
		(pad "J16" smd circle
			(at -20.059904 -30.329886 180)
			(size 0.450088 0.450088)
			(layers "F.Cu" "F.Mask" "F.Paste")
			(net "M_J_CPU1_SA_DQ<4>")
		)
		(pad "J17" smd circle
			(at -19.120104 -30.329886 180)
			(size 0.450088 0.450088)
			(layers "F.Cu" "F.Mask" "F.Paste")
			(net "M_J_CPU1_SA_DQS_DP<5>")
		)
		(pad "J18" smd circle
			(at -18.18005 -30.329886 180)
			(size 0.450088 0.450088)
			(layers "F.Cu" "F.Mask" "F.Paste")
			(net "GND")
		)
		(pad "J19" smd circle
			(at -17.239996 -30.329886 180)
			(size 0.450088 0.450088)
			(layers "F.Cu" "F.Mask" "F.Paste")
			(net "M_I_CPU1_SA_DQ<4>")
		)
		(pad "J20" smd circle
			(at -16.299942 -30.329886 180)
			(size 0.450088 0.450088)
			(layers "F.Cu" "F.Mask" "F.Paste")
			(net "GND")
		)
		(pad "J21" smd circle
			(at -15.359888 -30.329886 180)
			(size 0.450088 0.450088)
			(layers "F.Cu" "F.Mask" "F.Paste")
			(net "M_I_CPU1_SA_DQS_DP<5>")
		)
		(pad "J22" smd circle
			(at -14.420088 -30.329886 180)
			(size 0.450088 0.450088)
			(layers "F.Cu" "F.Mask" "F.Paste")
			(net "GND")
		)
		(pad "J23" smd circle
			(at -13.480034 -30.329886 180)
			(size 0.450088 0.450088)
			(layers "F.Cu" "F.Mask" "F.Paste")
			(net "GMI_CPU1_G2_CPU0_G0_TX_DP<14>")
		)
		(pad "J24" smd circle
			(at -12.53998 -30.329886 180)
			(size 0.450088 0.450088)
			(layers "F.Cu" "F.Mask" "F.Paste")
			(net "GMI_CPU1_G2_CPU0_G0_TX_DN<14>")
		)
		(pad "J25" smd circle
			(at -11.599926 -30.329886 180)
			(size 0.450088 0.450088)
			(layers "F.Cu" "F.Mask" "F.Paste")
			(net "GND")
		)
		(pad "J26" smd circle
			(at -10.659872 -30.329886 180)
			(size 0.450088 0.450088)
			(layers "F.Cu" "F.Mask" "F.Paste")
			(net "GMI_CPU1_G2_CPU0_G0_TX_DP<11>")
		)
		(pad "J27" smd circle
			(at -9.720072 -30.329886 180)
			(size 0.450088 0.450088)
			(layers "F.Cu" "F.Mask" "F.Paste")
			(net "GMI_CPU1_G2_CPU0_G0_TX_DN<11>")
		)
		(pad "J28" smd circle
			(at -8.780018 -30.329886 180)
			(size 0.450088 0.450088)
			(layers "F.Cu" "F.Mask" "F.Paste")
			(net "GND")
		)
		(pad "J29" smd circle
			(at -7.839964 -30.329886 180)
			(size 0.450088 0.450088)
			(layers "F.Cu" "F.Mask" "F.Paste")
			(net "GMI_CPU1_G2_CPU0_G0_TX_DP<8>")
		)
		(pad "J30" smd circle
			(at -6.89991 -30.329886 180)
			(size 0.450088 0.450088)
			(layers "F.Cu" "F.Mask" "F.Paste")
			(net "GMI_CPU1_G2_CPU0_G0_TX_DN<8>")
		)
		(pad "J31" smd circle
			(at -5.96011 -30.329886 180)
			(size 0.450088 0.450088)
			(layers "F.Cu" "F.Mask" "F.Paste")
			(net "GND")
		)
		(pad "J32" smd circle
			(at -5.020056 -30.329886 180)
			(size 0.450088 0.450088)
			(layers "F.Cu" "F.Mask" "F.Paste")
			(net "GMI_CPU1_G2_CPU0_G0_TX_DP<5>")
		)
		(pad "J33" smd circle
			(at -4.080002 -30.329886 180)
			(size 0.450088 0.450088)
			(layers "F.Cu" "F.Mask" "F.Paste")
			(net "GMI_CPU1_G2_CPU0_G0_TX_DN<5>")
		)
		(pad "J34" smd circle
			(at -3.139948 -30.329886 180)
			(size 0.450088 0.450088)
			(layers "F.Cu" "F.Mask" "F.Paste")
			(net "GND")
		)
		(pad "J35" smd circle
			(at -2.199894 -30.329886 180)
			(size 0.450088 0.450088)
			(layers "F.Cu" "F.Mask" "F.Paste")
			(net "PVDDCR_CPU0_P1")
		)
		(pad "J36" smd circle
			(at -1.260094 -30.329886 180)
			(size 0.450088 0.450088)
			(layers "F.Cu" "F.Mask" "F.Paste")
			(net "PVDDCR_CPU0_P1")
		)
		(pad "J40" smd circle
			(at 1.560068 -30.329886 180)
			(size 0.450088 0.450088)
			(layers "F.Cu" "F.Mask" "F.Paste")
			(net "PVDDCR_CPU0_P1")
		)
		(pad "J41" smd circle
			(at 2.500122 -30.329886 180)
			(size 0.450088 0.450088)
			(layers "F.Cu" "F.Mask" "F.Paste")
			(net "PVDDCR_CPU0_P1")
		)
		(pad "J42" smd circle
			(at 3.439922 -30.329886 180)
			(size 0.450088 0.450088)
			(layers "F.Cu" "F.Mask" "F.Paste")
			(net "GND")
		)
		(pad "J43" smd circle
			(at 4.379976 -30.329886 180)
			(size 0.450088 0.450088)
			(layers "F.Cu" "F.Mask" "F.Paste")
			(net "GMI_CPU0_G2_CPU1_G0_TX_DN<10>")
		)
		(pad "J44" smd circle
			(at 5.32003 -30.329886 180)
			(size 0.450088 0.450088)
			(layers "F.Cu" "F.Mask" "F.Paste")
			(net "GMI_CPU0_G2_CPU1_G0_TX_DP<10>")
		)
		(pad "J45" smd circle
			(at 6.260084 -30.329886 180)
			(size 0.450088 0.450088)
			(layers "F.Cu" "F.Mask" "F.Paste")
			(net "GND")
		)
		(pad "J46" smd circle
			(at 7.199884 -30.329886 180)
			(size 0.450088 0.450088)
			(layers "F.Cu" "F.Mask" "F.Paste")
			(net "GMI_CPU0_G2_CPU1_G0_TX_DN<7>")
		)
		(pad "J47" smd circle
			(at 8.139938 -30.329886 180)
			(size 0.450088 0.450088)
			(layers "F.Cu" "F.Mask" "F.Paste")
			(net "GMI_CPU0_G2_CPU1_G0_TX_DP<7>")
		)
		(pad "J48" smd circle
			(at 9.079992 -30.329886 180)
			(size 0.450088 0.450088)
			(layers "F.Cu" "F.Mask" "F.Paste")
			(net "GND")
		)
		(pad "J49" smd circle
			(at 10.020046 -30.329886 180)
			(size 0.450088 0.450088)
			(layers "F.Cu" "F.Mask" "F.Paste")
			(net "GMI_CPU0_G2_CPU1_G0_TX_DN<4>")
		)
		(pad "J50" smd circle
			(at 10.9601 -30.329886 180)
			(size 0.450088 0.450088)
			(layers "F.Cu" "F.Mask" "F.Paste")
			(net "GMI_CPU0_G2_CPU1_G0_TX_DP<4>")
		)
		(pad "J51" smd circle
			(at 11.8999 -30.329886 180)
			(size 0.450088 0.450088)
			(layers "F.Cu" "F.Mask" "F.Paste")
			(net "GND")
		)
		(pad "J52" smd circle
			(at 12.839954 -30.329886 180)
			(size 0.450088 0.450088)
			(layers "F.Cu" "F.Mask" "F.Paste")
			(net "GMI_CPU0_G2_CPU1_G0_TX_DN<1>")
		)
		(pad "J53" smd circle
			(at 13.780008 -30.329886 180)
			(size 0.450088 0.450088)
			(layers "F.Cu" "F.Mask" "F.Paste")
			(net "GMI_CPU0_G2_CPU1_G0_TX_DP<1>")
		)
		(pad "J54" smd circle
			(at 14.720062 -30.329886 180)
			(size 0.450088 0.450088)
			(layers "F.Cu" "F.Mask" "F.Paste")
			(net "GND")
		)
		(pad "J55" smd circle
			(at 15.660116 -30.329886 180)
			(size 0.450088 0.450088)
			(layers "F.Cu" "F.Mask" "F.Paste")
			(net "M_C_CPU1_SA_DQS_DP<5>")
		)
		(pad "J56" smd circle
			(at 16.599916 -30.329886 180)
			(size 0.450088 0.450088)
			(layers "F.Cu" "F.Mask" "F.Paste")
			(net "GND")
		)
		(pad "J57" smd circle
			(at 17.53997 -30.329886 180)
			(size 0.450088 0.450088)
			(layers "F.Cu" "F.Mask" "F.Paste")
			(net "M_C_CPU1_SA_DQ<4>")
		)
		(pad "J58" smd circle
			(at 18.480024 -30.329886 180)
			(size 0.450088 0.450088)
			(layers "F.Cu" "F.Mask" "F.Paste")
			(net "GND")
		)
		(pad "J59" smd circle
			(at 19.420078 -30.329886 180)
			(size 0.450088 0.450088)
			(layers "F.Cu" "F.Mask" "F.Paste")
			(net "M_D_CPU1_SA_DQS_DP<5>")
		)
		(pad "J60" smd circle
			(at 20.359878 -30.329886 180)
			(size 0.450088 0.450088)
			(layers "F.Cu" "F.Mask" "F.Paste")
			(net "M_D_CPU1_SA_DQ<4>")
		)
		(pad "J61" smd circle
			(at 21.299932 -30.329886 180)
			(size 0.450088 0.450088)
			(layers "F.Cu" "F.Mask" "F.Paste")
			(net "GND")
		)
		(pad "J62" smd circle
			(at 22.239986 -30.329886 180)
			(size 0.450088 0.450088)
			(layers "F.Cu" "F.Mask" "F.Paste")
			(net "M_B_CPU1_SA_DQS_DP<5>")
		)
		(pad "J63" smd circle
			(at 23.18004 -30.329886 180)
			(size 0.450088 0.450088)
			(layers "F.Cu" "F.Mask" "F.Paste")
			(net "GND")
		)
		(pad "J64" smd circle
			(at 24.120094 -30.329886 180)
			(size 0.450088 0.450088)
			(layers "F.Cu" "F.Mask" "F.Paste")
			(net "M_B_CPU1_SA_DQ<4>")
		)
		(pad "J65" smd circle
			(at 25.059894 -30.329886 180)
			(size 0.450088 0.450088)
			(layers "F.Cu" "F.Mask" "F.Paste")
			(net "GND")
		)
		(pad "J66" smd circle
			(at 25.999948 -30.329886 180)
			(size 0.450088 0.450088)
			(layers "F.Cu" "F.Mask" "F.Paste")
			(net "M_F_CPU1_SA_DQS_DP<5>")
		)
		(pad "J67" smd circle
			(at 26.940002 -30.329886 180)
			(size 0.450088 0.450088)
			(layers "F.Cu" "F.Mask" "F.Paste")
			(net "M_F_CPU1_SA_DQ<4>")
		)
		(pad "J68" smd circle
			(at 27.880056 -30.329886 180)
			(size 0.450088 0.450088)
			(layers "F.Cu" "F.Mask" "F.Paste")
			(net "GND")
		)
		(pad "J69" smd circle
			(at 28.82011 -30.329886 180)
			(size 0.450088 0.450088)
			(layers "F.Cu" "F.Mask" "F.Paste")
			(net "M_E_CPU1_SA_DQS_DP<5>")
		)
		(pad "J70" smd circle
			(at 29.75991 -30.329886 180)
			(size 0.450088 0.450088)
			(layers "F.Cu" "F.Mask" "F.Paste")
			(net "GND")
		)
		(pad "J71" smd circle
			(at 30.699964 -30.329886 180)
			(size 0.450088 0.450088)
			(layers "F.Cu" "F.Mask" "F.Paste")
			(net "M_E_CPU1_SA_DQ<4>")
		)
		(pad "J72" smd circle
			(at 31.640018 -30.329886 180)
			(size 0.450088 0.450088)
			(layers "F.Cu" "F.Mask" "F.Paste")
			(net "GND")
		)
		(pad "J73" smd circle
			(at 32.580072 -30.329886 180)
			(size 0.450088 0.450088)
			(layers "F.Cu" "F.Mask" "F.Paste")
			(net "M_A_CPU1_SA_DQS_DP<5>")
		)
		(pad "J74" smd circle
			(at 33.519872 -30.329886 180)
			(size 0.450088 0.450088)
			(layers "F.Cu" "F.Mask" "F.Paste")
			(net "M_A_CPU1_SA_DQ<4>")
		)
		(pad "J75" smd circle
			(at 34.459926 -30.329886 180)
			(size 0.450088 0.450088)
			(layers "F.Cu" "F.Mask" "F.Paste")
			(net "GND")
		)
		(pad "K2" smd circle
			(at -33.690052 -29.51988 180)
			(size 0.450088 0.450088)
			(layers "F.Cu" "F.Mask" "F.Paste")
			(net "M_G_CPU1_SA_DQ<6>")
		)
		(pad "K3" smd circle
			(at -32.749998 -29.51988 180)
			(size 0.450088 0.450088)
			(layers "F.Cu" "F.Mask" "F.Paste")
			(net "GND")
		)
		(pad "K4" smd circle
			(at -31.809944 -29.51988 180)
			(size 0.450088 0.450088)
			(layers "F.Cu" "F.Mask" "F.Paste")
			(net "M_G_CPU1_SA_DQ<5>")
		)
		(pad "K5" smd circle
			(at -30.86989 -29.51988 180)
			(size 0.450088 0.450088)
			(layers "F.Cu" "F.Mask" "F.Paste")
			(net "GND")
		)
		(pad "K6" smd circle
			(at -29.93009 -29.51988 180)
			(size 0.450088 0.450088)
			(layers "F.Cu" "F.Mask" "F.Paste")
			(net "M_K_CPU1_SA_DQ<6>")
		)
		(pad "K7" smd circle
			(at -28.990036 -29.51988 180)
			(size 0.450088 0.450088)
			(layers "F.Cu" "F.Mask" "F.Paste")
			(net "M_K_CPU1_SA_DQ<5>")
		)
		(pad "K8" smd circle
			(at -28.049982 -29.51988 180)
			(size 0.450088 0.450088)
			(layers "F.Cu" "F.Mask" "F.Paste")
			(net "GND")
		)
		(pad "K9" smd circle
			(at -27.109928 -29.51988 180)
			(size 0.450088 0.450088)
			(layers "F.Cu" "F.Mask" "F.Paste")
			(net "M_L_CPU1_SA_DQ<6>")
		)
		(pad "K10" smd circle
			(at -26.170128 -29.51988 180)
			(size 0.450088 0.450088)
			(layers "F.Cu" "F.Mask" "F.Paste")
			(net "GND")
		)
		(pad "K11" smd circle
			(at -25.230074 -29.51988 180)
			(size 0.450088 0.450088)
			(layers "F.Cu" "F.Mask" "F.Paste")
			(net "M_L_CPU1_SA_DQ<5>")
		)
		(pad "K12" smd circle
			(at -24.29002 -29.51988 180)
			(size 0.450088 0.450088)
			(layers "F.Cu" "F.Mask" "F.Paste")
			(net "GND")
		)
		(pad "K13" smd circle
			(at -23.349966 -29.51988 180)
			(size 0.450088 0.450088)
			(layers "F.Cu" "F.Mask" "F.Paste")
			(net "M_H_CPU1_SA_DQ<6>")
		)
		(pad "K14" smd circle
			(at -22.409912 -29.51988 180)
			(size 0.450088 0.450088)
			(layers "F.Cu" "F.Mask" "F.Paste")
			(net "M_H_CPU1_SA_DQ<5>")
		)
		(pad "K15" smd circle
			(at -21.470112 -29.51988 180)
			(size 0.450088 0.450088)
			(layers "F.Cu" "F.Mask" "F.Paste")
			(net "GND")
		)
		(pad "K16" smd circle
			(at -20.530058 -29.51988 180)
			(size 0.450088 0.450088)
			(layers "F.Cu" "F.Mask" "F.Paste")
			(net "M_J_CPU1_SA_DQ<6>")
		)
		(pad "K17" smd circle
			(at -19.590004 -29.51988 180)
			(size 0.450088 0.450088)
			(layers "F.Cu" "F.Mask" "F.Paste")
			(net "GND")
		)
		(pad "K18" smd circle
			(at -18.64995 -29.51988 180)
			(size 0.450088 0.450088)
			(layers "F.Cu" "F.Mask" "F.Paste")
			(net "M_J_CPU1_SA_DQ<5>")
		)
		(pad "K19" smd circle
			(at -17.709896 -29.51988 180)
			(size 0.450088 0.450088)
			(layers "F.Cu" "F.Mask" "F.Paste")
			(net "GND")
		)
		(pad "K20" smd circle
			(at -16.770096 -29.51988 180)
			(size 0.450088 0.450088)
			(layers "F.Cu" "F.Mask" "F.Paste")
			(net "M_I_CPU1_SA_DQ<6>")
		)
		(pad "K21" smd circle
			(at -15.830042 -29.51988 180)
			(size 0.450088 0.450088)
			(layers "F.Cu" "F.Mask" "F.Paste")
			(net "M_I_CPU1_SA_DQ<5>")
		)
		(pad "K22" smd circle
			(at -14.889988 -29.51988 180)
			(size 0.450088 0.450088)
			(layers "F.Cu" "F.Mask" "F.Paste")
			(net "PVDDCR_SOC_P1")
		)
		(pad "K23" smd circle
			(at -13.949934 -29.51988 180)
			(size 0.450088 0.450088)
			(layers "F.Cu" "F.Mask" "F.Paste")
			(net "GND")
		)
		(pad "K24" smd circle
			(at -13.00988 -29.51988 180)
			(size 0.450088 0.450088)
			(layers "F.Cu" "F.Mask" "F.Paste")
			(net "GND")
		)
		(pad "K25" smd circle
			(at -12.07008 -29.51988 180)
			(size 0.450088 0.450088)
			(layers "F.Cu" "F.Mask" "F.Paste")
			(net "GND")
		)
		(pad "K26" smd circle
			(at -11.130026 -29.51988 180)
			(size 0.450088 0.450088)
			(layers "F.Cu" "F.Mask" "F.Paste")
			(net "GND")
		)
		(pad "K27" smd circle
			(at -10.189972 -29.51988 180)
			(size 0.450088 0.450088)
			(layers "F.Cu" "F.Mask" "F.Paste")
			(net "GND")
		)
		(pad "K28" smd circle
			(at -9.249918 -29.51988 180)
			(size 0.450088 0.450088)
			(layers "F.Cu" "F.Mask" "F.Paste")
			(net "GND")
		)
		(pad "K29" smd circle
			(at -8.310118 -29.51988 180)
			(size 0.450088 0.450088)
			(layers "F.Cu" "F.Mask" "F.Paste")
			(net "GND")
		)
		(pad "K30" smd circle
			(at -7.370064 -29.51988 180)
			(size 0.450088 0.450088)
			(layers "F.Cu" "F.Mask" "F.Paste")
			(net "GND")
		)
		(pad "K31" smd circle
			(at -6.43001 -29.51988 180)
			(size 0.450088 0.450088)
			(layers "F.Cu" "F.Mask" "F.Paste")
			(net "GND")
		)
		(pad "K32" smd circle
			(at -5.489956 -29.51988 180)
			(size 0.450088 0.450088)
			(layers "F.Cu" "F.Mask" "F.Paste")
			(net "GND")
		)
		(pad "K33" smd circle
			(at -4.549902 -29.51988 180)
			(size 0.450088 0.450088)
			(layers "F.Cu" "F.Mask" "F.Paste")
			(net "GND")
		)
		(pad "K34" smd circle
			(at -3.610102 -29.51988 180)
			(size 0.450088 0.450088)
			(layers "F.Cu" "F.Mask" "F.Paste")
			(net "GND")
		)
		(pad "K35" smd circle
			(at -2.670048 -29.51988 180)
			(size 0.450088 0.450088)
			(layers "F.Cu" "F.Mask" "F.Paste")
			(net "GMI_CPU1_G2_CPU0_G0_TX_DP<1>")
		)
		(pad "K36" smd circle
			(at -1.729994 -29.51988 180)
			(size 0.450088 0.450088)
			(layers "F.Cu" "F.Mask" "F.Paste")
			(net "GMI_CPU1_G2_CPU0_G0_TX_DN<1>")
		)
		(pad "K37" smd circle
			(at -0.78994 -29.51988 180)
			(size 0.450088 0.450088)
			(layers "F.Cu" "F.Mask" "F.Paste")
			(net "GND")
		)
		(pad "K39" smd circle
			(at 1.089914 -29.51988 180)
			(size 0.450088 0.450088)
			(layers "F.Cu" "F.Mask" "F.Paste")
			(net "GND")
		)
		(pad "K40" smd circle
			(at 2.029968 -29.51988 180)
			(size 0.450088 0.450088)
			(layers "F.Cu" "F.Mask" "F.Paste")
			(net "GMI_CPU0_G2_CPU1_G0_TX_DN<14>")
		)
		(pad "K41" smd circle
			(at 2.970022 -29.51988 180)
			(size 0.450088 0.450088)
			(layers "F.Cu" "F.Mask" "F.Paste")
			(net "GMI_CPU0_G2_CPU1_G0_TX_DP<14>")
		)
		(pad "K42" smd circle
			(at 3.910076 -29.51988 180)
			(size 0.450088 0.450088)
			(layers "F.Cu" "F.Mask" "F.Paste")
			(net "GND")
		)
		(pad "K43" smd circle
			(at 4.849876 -29.51988 180)
			(size 0.450088 0.450088)
			(layers "F.Cu" "F.Mask" "F.Paste")
			(net "GND")
		)
		(pad "K44" smd circle
			(at 5.78993 -29.51988 180)
			(size 0.450088 0.450088)
			(layers "F.Cu" "F.Mask" "F.Paste")
			(net "GND")
		)
		(pad "K45" smd circle
			(at 6.729984 -29.51988 180)
			(size 0.450088 0.450088)
			(layers "F.Cu" "F.Mask" "F.Paste")
			(net "GND")
		)
		(pad "K46" smd circle
			(at 7.670038 -29.51988 180)
			(size 0.450088 0.450088)
			(layers "F.Cu" "F.Mask" "F.Paste")
			(net "GND")
		)
		(pad "K47" smd circle
			(at 8.610092 -29.51988 180)
			(size 0.450088 0.450088)
			(layers "F.Cu" "F.Mask" "F.Paste")
			(net "GND")
		)
		(pad "K48" smd circle
			(at 9.549892 -29.51988 180)
			(size 0.450088 0.450088)
			(layers "F.Cu" "F.Mask" "F.Paste")
			(net "GND")
		)
		(pad "K49" smd circle
			(at 10.489946 -29.51988 180)
			(size 0.450088 0.450088)
			(layers "F.Cu" "F.Mask" "F.Paste")
			(net "GND")
		)
		(pad "K50" smd circle
			(at 11.43 -29.51988 180)
			(size 0.450088 0.450088)
			(layers "F.Cu" "F.Mask" "F.Paste")
			(net "GND")
		)
		(pad "K51" smd circle
			(at 12.370054 -29.51988 180)
			(size 0.450088 0.450088)
			(layers "F.Cu" "F.Mask" "F.Paste")
			(net "GND")
		)
		(pad "K52" smd circle
			(at 13.310108 -29.51988 180)
			(size 0.450088 0.450088)
			(layers "F.Cu" "F.Mask" "F.Paste")
			(net "GND")
		)
		(pad "K53" smd circle
			(at 14.249908 -29.51988 180)
			(size 0.450088 0.450088)
			(layers "F.Cu" "F.Mask" "F.Paste")
			(net "GND")
		)
		(pad "K54" smd circle
			(at 15.189962 -29.51988 180)
			(size 0.450088 0.450088)
			(layers "F.Cu" "F.Mask" "F.Paste")
			(net "PVDDIO_P1")
		)
		(pad "K55" smd circle
			(at 16.130016 -29.51988 180)
			(size 0.450088 0.450088)
			(layers "F.Cu" "F.Mask" "F.Paste")
			(net "M_C_CPU1_SA_DQ<5>")
		)
		(pad "K56" smd circle
			(at 17.07007 -29.51988 180)
			(size 0.450088 0.450088)
			(layers "F.Cu" "F.Mask" "F.Paste")
			(net "M_C_CPU1_SA_DQ<6>")
		)
		(pad "K57" smd circle
			(at 18.010124 -29.51988 180)
			(size 0.450088 0.450088)
			(layers "F.Cu" "F.Mask" "F.Paste")
			(net "GND")
		)
		(pad "K58" smd circle
			(at 18.949924 -29.51988 180)
			(size 0.450088 0.450088)
			(layers "F.Cu" "F.Mask" "F.Paste")
			(net "M_D_CPU1_SA_DQ<5>")
		)
		(pad "K59" smd circle
			(at 19.889978 -29.51988 180)
			(size 0.450088 0.450088)
			(layers "F.Cu" "F.Mask" "F.Paste")
			(net "GND")
		)
		(pad "K60" smd circle
			(at 20.830032 -29.51988 180)
			(size 0.450088 0.450088)
			(layers "F.Cu" "F.Mask" "F.Paste")
			(net "M_D_CPU1_SA_DQ<6>")
		)
		(pad "K61" smd circle
			(at 21.770086 -29.51988 180)
			(size 0.450088 0.450088)
			(layers "F.Cu" "F.Mask" "F.Paste")
			(net "GND")
		)
		(pad "K62" smd circle
			(at 22.709886 -29.51988 180)
			(size 0.450088 0.450088)
			(layers "F.Cu" "F.Mask" "F.Paste")
			(net "M_B_CPU1_SA_DQ<5>")
		)
		(pad "K63" smd circle
			(at 23.64994 -29.51988 180)
			(size 0.450088 0.450088)
			(layers "F.Cu" "F.Mask" "F.Paste")
			(net "M_B_CPU1_SA_DQ<6>")
		)
		(pad "K64" smd circle
			(at 24.589994 -29.51988 180)
			(size 0.450088 0.450088)
			(layers "F.Cu" "F.Mask" "F.Paste")
			(net "GND")
		)
		(pad "K65" smd circle
			(at 25.530048 -29.51988 180)
			(size 0.450088 0.450088)
			(layers "F.Cu" "F.Mask" "F.Paste")
			(net "M_F_CPU1_SA_DQ<5>")
		)
		(pad "K66" smd circle
			(at 26.470102 -29.51988 180)
			(size 0.450088 0.450088)
			(layers "F.Cu" "F.Mask" "F.Paste")
			(net "GND")
		)
		(pad "K67" smd circle
			(at 27.409902 -29.51988 180)
			(size 0.450088 0.450088)
			(layers "F.Cu" "F.Mask" "F.Paste")
			(net "M_F_CPU1_SA_DQ<6>")
		)
		(pad "K68" smd circle
			(at 28.349956 -29.51988 180)
			(size 0.450088 0.450088)
			(layers "F.Cu" "F.Mask" "F.Paste")
			(net "GND")
		)
		(pad "K69" smd circle
			(at 29.29001 -29.51988 180)
			(size 0.450088 0.450088)
			(layers "F.Cu" "F.Mask" "F.Paste")
			(net "M_E_CPU1_SA_DQ<5>")
		)
		(pad "K70" smd circle
			(at 30.230064 -29.51988 180)
			(size 0.450088 0.450088)
			(layers "F.Cu" "F.Mask" "F.Paste")
			(net "M_E_CPU1_SA_DQ<6>")
		)
		(pad "K71" smd circle
			(at 31.170118 -29.51988 180)
			(size 0.450088 0.450088)
			(layers "F.Cu" "F.Mask" "F.Paste")
			(net "GND")
		)
		(pad "K72" smd circle
			(at 32.109918 -29.51988 180)
			(size 0.450088 0.450088)
			(layers "F.Cu" "F.Mask" "F.Paste")
			(net "M_A_CPU1_SA_DQ<5>")
		)
		(pad "K73" smd circle
			(at 33.049972 -29.51988 180)
			(size 0.450088 0.450088)
			(layers "F.Cu" "F.Mask" "F.Paste")
			(net "GND")
		)
		(pad "K74" smd circle
			(at 33.990026 -29.51988 180)
			(size 0.450088 0.450088)
			(layers "F.Cu" "F.Mask" "F.Paste")
			(net "M_A_CPU1_SA_DQ<6>")
		)
		(pad "L1" smd circle
			(at -34.159952 -28.710128 180)
			(size 0.450088 0.450088)
			(layers "F.Cu" "F.Mask" "F.Paste")
			(net "GND")
		)
		(pad "L2" smd circle
			(at -33.219898 -28.710128 180)
			(size 0.450088 0.450088)
			(layers "F.Cu" "F.Mask" "F.Paste")
			(net "M_G_CPU1_SA_DQ<8>")
		)
		(pad "L3" smd circle
			(at -32.280098 -28.710128 180)
			(size 0.450088 0.450088)
			(layers "F.Cu" "F.Mask" "F.Paste")
			(net "M_G_CPU1_SA_DQ<7>")
		)
		(pad "L4" smd circle
			(at -31.340044 -28.710128 180)
			(size 0.450088 0.450088)
			(layers "F.Cu" "F.Mask" "F.Paste")
			(net "PVDDCR_SOC_P1")
		)
		(pad "L5" smd circle
			(at -30.39999 -28.710128 180)
			(size 0.450088 0.450088)
			(layers "F.Cu" "F.Mask" "F.Paste")
			(net "M_K_CPU1_SA_DQ<8>")
		)
		(pad "L6" smd circle
			(at -29.459936 -28.710128 180)
			(size 0.450088 0.450088)
			(layers "F.Cu" "F.Mask" "F.Paste")
			(net "GND")
		)
		(pad "L7" smd circle
			(at -28.519882 -28.710128 180)
			(size 0.450088 0.450088)
			(layers "F.Cu" "F.Mask" "F.Paste")
			(net "M_K_CPU1_SA_DQ<7>")
		)
		(pad "L8" smd circle
			(at -27.580082 -28.710128 180)
			(size 0.450088 0.450088)
			(layers "F.Cu" "F.Mask" "F.Paste")
			(net "GND")
		)
		(pad "L9" smd circle
			(at -26.640028 -28.710128 180)
			(size 0.450088 0.450088)
			(layers "F.Cu" "F.Mask" "F.Paste")
			(net "M_L_CPU1_SA_DQ<8>")
		)
		(pad "L10" smd circle
			(at -25.699974 -28.710128 180)
			(size 0.450088 0.450088)
			(layers "F.Cu" "F.Mask" "F.Paste")
			(net "M_L_CPU1_SA_DQ<7>")
		)
		(pad "L11" smd circle
			(at -24.75992 -28.710128 180)
			(size 0.450088 0.450088)
			(layers "F.Cu" "F.Mask" "F.Paste")
			(net "PVDDCR_SOC_P1")
		)
		(pad "L12" smd circle
			(at -23.82012 -28.710128 180)
			(size 0.450088 0.450088)
			(layers "F.Cu" "F.Mask" "F.Paste")
			(net "M_H_CPU1_SA_DQ<8>")
		)
		(pad "L13" smd circle
			(at -22.880066 -28.710128 180)
			(size 0.450088 0.450088)
			(layers "F.Cu" "F.Mask" "F.Paste")
			(net "GND")
		)
		(pad "L14" smd circle
			(at -21.940012 -28.710128 180)
			(size 0.450088 0.450088)
			(layers "F.Cu" "F.Mask" "F.Paste")
			(net "M_H_CPU1_SA_DQ<7>")
		)
		(pad "L15" smd circle
			(at -20.999958 -28.710128 180)
			(size 0.450088 0.450088)
			(layers "F.Cu" "F.Mask" "F.Paste")
			(net "GND")
		)
		(pad "L16" smd circle
			(at -20.059904 -28.710128 180)
			(size 0.450088 0.450088)
			(layers "F.Cu" "F.Mask" "F.Paste")
			(net "M_J_CPU1_SA_DQ<8>")
		)
		(pad "L17" smd circle
			(at -19.120104 -28.710128 180)
			(size 0.450088 0.450088)
			(layers "F.Cu" "F.Mask" "F.Paste")
			(net "M_J_CPU1_SA_DQ<7>")
		)
		(pad "L18" smd circle
			(at -18.18005 -28.710128 180)
			(size 0.450088 0.450088)
			(layers "F.Cu" "F.Mask" "F.Paste")
			(net "PVDDCR_SOC_P1")
		)
		(pad "L19" smd circle
			(at -17.239996 -28.710128 180)
			(size 0.450088 0.450088)
			(layers "F.Cu" "F.Mask" "F.Paste")
			(net "M_I_CPU1_SA_DQ<8>")
		)
		(pad "L20" smd circle
			(at -16.299942 -28.710128 180)
			(size 0.450088 0.450088)
			(layers "F.Cu" "F.Mask" "F.Paste")
			(net "GND")
		)
		(pad "L21" smd circle
			(at -15.359888 -28.710128 180)
			(size 0.450088 0.450088)
			(layers "F.Cu" "F.Mask" "F.Paste")
			(net "M_I_CPU1_SA_DQ<7>")
		)
		(pad "L22" smd circle
			(at -14.420088 -28.710128 180)
			(size 0.450088 0.450088)
			(layers "F.Cu" "F.Mask" "F.Paste")
			(net "GND")
		)
		(pad "L23" smd circle
			(at -13.480034 -28.710128 180)
			(size 0.450088 0.450088)
			(layers "F.Cu" "F.Mask" "F.Paste")
			(net "GMI_CPU1_G2_CPU0_G0_TX_DP<12>")
		)
		(pad "L24" smd circle
			(at -12.53998 -28.710128 180)
			(size 0.450088 0.450088)
			(layers "F.Cu" "F.Mask" "F.Paste")
			(net "GMI_CPU1_G2_CPU0_G0_TX_DN<12>")
		)
		(pad "L25" smd circle
			(at -11.599926 -28.710128 180)
			(size 0.450088 0.450088)
			(layers "F.Cu" "F.Mask" "F.Paste")
			(net "GND")
		)
		(pad "L26" smd circle
			(at -10.659872 -28.710128 180)
			(size 0.450088 0.450088)
			(layers "F.Cu" "F.Mask" "F.Paste")
			(net "GMI_CPU1_G2_CPU0_G0_TX_DP<9>")
		)
		(pad "L27" smd circle
			(at -9.720072 -28.710128 180)
			(size 0.450088 0.450088)
			(layers "F.Cu" "F.Mask" "F.Paste")
			(net "GMI_CPU1_G2_CPU0_G0_TX_DN<9>")
		)
		(pad "L28" smd circle
			(at -8.780018 -28.710128 180)
			(size 0.450088 0.450088)
			(layers "F.Cu" "F.Mask" "F.Paste")
			(net "GND")
		)
		(pad "L29" smd circle
			(at -7.839964 -28.710128 180)
			(size 0.450088 0.450088)
			(layers "F.Cu" "F.Mask" "F.Paste")
			(net "GMI_CPU1_G2_CPU0_G0_TX_DP<6>")
		)
		(pad "L30" smd circle
			(at -6.89991 -28.710128 180)
			(size 0.450088 0.450088)
			(layers "F.Cu" "F.Mask" "F.Paste")
			(net "GMI_CPU1_G2_CPU0_G0_TX_DN<6>")
		)
		(pad "L31" smd circle
			(at -5.96011 -28.710128 180)
			(size 0.450088 0.450088)
			(layers "F.Cu" "F.Mask" "F.Paste")
			(net "GND")
		)
		(pad "L32" smd circle
			(at -5.020056 -28.710128 180)
			(size 0.450088 0.450088)
			(layers "F.Cu" "F.Mask" "F.Paste")
			(net "GMI_CPU1_G2_CPU0_G0_TX_DP<3>")
		)
		(pad "L33" smd circle
			(at -4.080002 -28.710128 180)
			(size 0.450088 0.450088)
			(layers "F.Cu" "F.Mask" "F.Paste")
			(net "GMI_CPU1_G2_CPU0_G0_TX_DN<3>")
		)
		(pad "L34" smd circle
			(at -3.139948 -28.710128 180)
			(size 0.450088 0.450088)
			(layers "F.Cu" "F.Mask" "F.Paste")
			(net "GND")
		)
		(pad "L35" smd circle
			(at -2.199894 -28.710128 180)
			(size 0.450088 0.450088)
			(layers "F.Cu" "F.Mask" "F.Paste")
			(net "GND")
		)
		(pad "L36" smd circle
			(at -1.260094 -28.710128 180)
			(size 0.450088 0.450088)
			(layers "F.Cu" "F.Mask" "F.Paste")
			(net "GND")
		)
		(pad "L40" smd circle
			(at 1.560068 -28.710128 180)
			(size 0.450088 0.450088)
			(layers "F.Cu" "F.Mask" "F.Paste")
			(net "GND")
		)
		(pad "L41" smd circle
			(at 2.500122 -28.710128 180)
			(size 0.450088 0.450088)
			(layers "F.Cu" "F.Mask" "F.Paste")
			(net "GND")
		)
		(pad "L42" smd circle
			(at 3.439922 -28.710128 180)
			(size 0.450088 0.450088)
			(layers "F.Cu" "F.Mask" "F.Paste")
			(net "GND")
		)
		(pad "L43" smd circle
			(at 4.379976 -28.710128 180)
			(size 0.450088 0.450088)
			(layers "F.Cu" "F.Mask" "F.Paste")
			(net "GMI_CPU0_G2_CPU1_G0_TX_DN<12>")
		)
		(pad "L44" smd circle
			(at 5.32003 -28.710128 180)
			(size 0.450088 0.450088)
			(layers "F.Cu" "F.Mask" "F.Paste")
			(net "GMI_CPU0_G2_CPU1_G0_TX_DP<12>")
		)
		(pad "L45" smd circle
			(at 6.260084 -28.710128 180)
			(size 0.450088 0.450088)
			(layers "F.Cu" "F.Mask" "F.Paste")
			(net "GND")
		)
		(pad "L46" smd circle
			(at 7.199884 -28.710128 180)
			(size 0.450088 0.450088)
			(layers "F.Cu" "F.Mask" "F.Paste")
			(net "GMI_CPU0_G2_CPU1_G0_TX_DN<9>")
		)
		(pad "L47" smd circle
			(at 8.139938 -28.710128 180)
			(size 0.450088 0.450088)
			(layers "F.Cu" "F.Mask" "F.Paste")
			(net "GMI_CPU0_G2_CPU1_G0_TX_DP<9>")
		)
		(pad "L48" smd circle
			(at 9.079992 -28.710128 180)
			(size 0.450088 0.450088)
			(layers "F.Cu" "F.Mask" "F.Paste")
			(net "GND")
		)
		(pad "L49" smd circle
			(at 10.020046 -28.710128 180)
			(size 0.450088 0.450088)
			(layers "F.Cu" "F.Mask" "F.Paste")
			(net "GMI_CPU0_G2_CPU1_G0_TX_DN<6>")
		)
		(pad "L50" smd circle
			(at 10.9601 -28.710128 180)
			(size 0.450088 0.450088)
			(layers "F.Cu" "F.Mask" "F.Paste")
			(net "GMI_CPU0_G2_CPU1_G0_TX_DP<6>")
		)
		(pad "L51" smd circle
			(at 11.8999 -28.710128 180)
			(size 0.450088 0.450088)
			(layers "F.Cu" "F.Mask" "F.Paste")
			(net "GND")
		)
		(pad "L52" smd circle
			(at 12.839954 -28.710128 180)
			(size 0.450088 0.450088)
			(layers "F.Cu" "F.Mask" "F.Paste")
			(net "GMI_CPU0_G2_CPU1_G0_TX_DN<3>")
		)
		(pad "L53" smd circle
			(at 13.780008 -28.710128 180)
			(size 0.450088 0.450088)
			(layers "F.Cu" "F.Mask" "F.Paste")
			(net "GMI_CPU0_G2_CPU1_G0_TX_DP<3>")
		)
		(pad "L54" smd circle
			(at 14.720062 -28.710128 180)
			(size 0.450088 0.450088)
			(layers "F.Cu" "F.Mask" "F.Paste")
			(net "GND")
		)
		(pad "L55" smd circle
			(at 15.660116 -28.710128 180)
			(size 0.450088 0.450088)
			(layers "F.Cu" "F.Mask" "F.Paste")
			(net "M_C_CPU1_SA_DQ<7>")
		)
		(pad "L56" smd circle
			(at 16.599916 -28.710128 180)
			(size 0.450088 0.450088)
			(layers "F.Cu" "F.Mask" "F.Paste")
			(net "GND")
		)
		(pad "L57" smd circle
			(at 17.53997 -28.710128 180)
			(size 0.450088 0.450088)
			(layers "F.Cu" "F.Mask" "F.Paste")
			(net "M_C_CPU1_SA_DQ<8>")
		)
		(pad "L58" smd circle
			(at 18.480024 -28.710128 180)
			(size 0.450088 0.450088)
			(layers "F.Cu" "F.Mask" "F.Paste")
			(net "PVDDIO_P1")
		)
		(pad "L59" smd circle
			(at 19.420078 -28.710128 180)
			(size 0.450088 0.450088)
			(layers "F.Cu" "F.Mask" "F.Paste")
			(net "M_D_CPU1_SA_DQ<7>")
		)
		(pad "L60" smd circle
			(at 20.359878 -28.710128 180)
			(size 0.450088 0.450088)
			(layers "F.Cu" "F.Mask" "F.Paste")
			(net "M_D_CPU1_SA_DQ<8>")
		)
		(pad "L61" smd circle
			(at 21.299932 -28.710128 180)
			(size 0.450088 0.450088)
			(layers "F.Cu" "F.Mask" "F.Paste")
			(net "GND")
		)
		(pad "L62" smd circle
			(at 22.239986 -28.710128 180)
			(size 0.450088 0.450088)
			(layers "F.Cu" "F.Mask" "F.Paste")
			(net "M_B_CPU1_SA_DQ<7>")
		)
		(pad "L63" smd circle
			(at 23.18004 -28.710128 180)
			(size 0.450088 0.450088)
			(layers "F.Cu" "F.Mask" "F.Paste")
			(net "GND")
		)
		(pad "L64" smd circle
			(at 24.120094 -28.710128 180)
			(size 0.450088 0.450088)
			(layers "F.Cu" "F.Mask" "F.Paste")
			(net "M_B_CPU1_SA_DQ<8>")
		)
		(pad "L65" smd circle
			(at 25.059894 -28.710128 180)
			(size 0.450088 0.450088)
			(layers "F.Cu" "F.Mask" "F.Paste")
			(net "PVDDIO_P1")
		)
		(pad "L66" smd circle
			(at 25.999948 -28.710128 180)
			(size 0.450088 0.450088)
			(layers "F.Cu" "F.Mask" "F.Paste")
			(net "M_F_CPU1_SA_DQ<7>")
		)
		(pad "L67" smd circle
			(at 26.940002 -28.710128 180)
			(size 0.450088 0.450088)
			(layers "F.Cu" "F.Mask" "F.Paste")
			(net "M_F_CPU1_SA_DQ<8>")
		)
		(pad "L68" smd circle
			(at 27.880056 -28.710128 180)
			(size 0.450088 0.450088)
			(layers "F.Cu" "F.Mask" "F.Paste")
			(net "GND")
		)
		(pad "L69" smd circle
			(at 28.82011 -28.710128 180)
			(size 0.450088 0.450088)
			(layers "F.Cu" "F.Mask" "F.Paste")
			(net "M_E_CPU1_SA_DQ<7>")
		)
		(pad "L70" smd circle
			(at 29.75991 -28.710128 180)
			(size 0.450088 0.450088)
			(layers "F.Cu" "F.Mask" "F.Paste")
			(net "GND")
		)
		(pad "L71" smd circle
			(at 30.699964 -28.710128 180)
			(size 0.450088 0.450088)
			(layers "F.Cu" "F.Mask" "F.Paste")
			(net "M_E_CPU1_SA_DQ<8>")
		)
		(pad "L72" smd circle
			(at 31.640018 -28.710128 180)
			(size 0.450088 0.450088)
			(layers "F.Cu" "F.Mask" "F.Paste")
			(net "PVDDIO_P1")
		)
		(pad "L73" smd circle
			(at 32.580072 -28.710128 180)
			(size 0.450088 0.450088)
			(layers "F.Cu" "F.Mask" "F.Paste")
			(net "M_A_CPU1_SA_DQ<7>")
		)
		(pad "L74" smd circle
			(at 33.519872 -28.710128 180)
			(size 0.450088 0.450088)
			(layers "F.Cu" "F.Mask" "F.Paste")
			(net "M_A_CPU1_SA_DQ<8>")
		)
		(pad "L75" smd circle
			(at 34.459926 -28.710128 180)
			(size 0.450088 0.450088)
			(layers "F.Cu" "F.Mask" "F.Paste")
			(net "GND")
		)
		(pad "M2" smd circle
			(at -33.690052 -27.900122 180)
			(size 0.450088 0.450088)
			(layers "F.Cu" "F.Mask" "F.Paste")
			(net "M_G_CPU1_SA_DQ<10>")
		)
		(pad "M3" smd circle
			(at -32.749998 -27.900122 180)
			(size 0.450088 0.450088)
			(layers "F.Cu" "F.Mask" "F.Paste")
			(net "GND")
		)
		(pad "M4" smd circle
			(at -31.809944 -27.900122 180)
			(size 0.450088 0.450088)
			(layers "F.Cu" "F.Mask" "F.Paste")
			(net "M_G_CPU1_SA_DQ<9>")
		)
		(pad "M5" smd circle
			(at -30.86989 -27.900122 180)
			(size 0.450088 0.450088)
			(layers "F.Cu" "F.Mask" "F.Paste")
			(net "GND")
		)
		(pad "M6" smd circle
			(at -29.93009 -27.900122 180)
			(size 0.450088 0.450088)
			(layers "F.Cu" "F.Mask" "F.Paste")
			(net "M_K_CPU1_SA_DQ<10>")
		)
		(pad "M7" smd circle
			(at -28.990036 -27.900122 180)
			(size 0.450088 0.450088)
			(layers "F.Cu" "F.Mask" "F.Paste")
			(net "M_K_CPU1_SA_DQ<9>")
		)
		(pad "M8" smd circle
			(at -28.049982 -27.900122 180)
			(size 0.450088 0.450088)
			(layers "F.Cu" "F.Mask" "F.Paste")
			(net "GND")
		)
		(pad "M9" smd circle
			(at -27.109928 -27.900122 180)
			(size 0.450088 0.450088)
			(layers "F.Cu" "F.Mask" "F.Paste")
			(net "M_L_CPU1_SA_DQ<10>")
		)
		(pad "M10" smd circle
			(at -26.170128 -27.900122 180)
			(size 0.450088 0.450088)
			(layers "F.Cu" "F.Mask" "F.Paste")
			(net "GND")
		)
		(pad "M11" smd circle
			(at -25.230074 -27.900122 180)
			(size 0.450088 0.450088)
			(layers "F.Cu" "F.Mask" "F.Paste")
			(net "M_L_CPU1_SA_DQ<9>")
		)
		(pad "M12" smd circle
			(at -24.29002 -27.900122 180)
			(size 0.450088 0.450088)
			(layers "F.Cu" "F.Mask" "F.Paste")
			(net "GND")
		)
		(pad "M13" smd circle
			(at -23.349966 -27.900122 180)
			(size 0.450088 0.450088)
			(layers "F.Cu" "F.Mask" "F.Paste")
			(net "M_H_CPU1_SA_DQ<10>")
		)
		(pad "M14" smd circle
			(at -22.409912 -27.900122 180)
			(size 0.450088 0.450088)
			(layers "F.Cu" "F.Mask" "F.Paste")
			(net "M_H_CPU1_SA_DQ<9>")
		)
		(pad "M15" smd circle
			(at -21.470112 -27.900122 180)
			(size 0.450088 0.450088)
			(layers "F.Cu" "F.Mask" "F.Paste")
			(net "GND")
		)
		(pad "M16" smd circle
			(at -20.530058 -27.900122 180)
			(size 0.450088 0.450088)
			(layers "F.Cu" "F.Mask" "F.Paste")
			(net "M_J_CPU1_SA_DQ<10>")
		)
		(pad "M17" smd circle
			(at -19.590004 -27.900122 180)
			(size 0.450088 0.450088)
			(layers "F.Cu" "F.Mask" "F.Paste")
			(net "GND")
		)
		(pad "M18" smd circle
			(at -18.64995 -27.900122 180)
			(size 0.450088 0.450088)
			(layers "F.Cu" "F.Mask" "F.Paste")
			(net "M_J_CPU1_SA_DQ<9>")
		)
		(pad "M19" smd circle
			(at -17.709896 -27.900122 180)
			(size 0.450088 0.450088)
			(layers "F.Cu" "F.Mask" "F.Paste")
			(net "GND")
		)
		(pad "M20" smd circle
			(at -16.770096 -27.900122 180)
			(size 0.450088 0.450088)
			(layers "F.Cu" "F.Mask" "F.Paste")
			(net "M_I_CPU1_SA_DQ<10>")
		)
		(pad "M21" smd circle
			(at -15.830042 -27.900122 180)
			(size 0.450088 0.450088)
			(layers "F.Cu" "F.Mask" "F.Paste")
			(net "M_I_CPU1_SA_DQ<9>")
		)
		(pad "M22" smd circle
			(at -14.889988 -27.900122 180)
			(size 0.450088 0.450088)
			(layers "F.Cu" "F.Mask" "F.Paste")
			(net "GND")
		)
		(pad "M23" smd circle
			(at -13.949934 -27.900122 180)
			(size 0.450088 0.450088)
			(layers "F.Cu" "F.Mask" "F.Paste")
			(net "PVDDCR_CPU0_P1")
		)
		(pad "M24" smd circle
			(at -13.00988 -27.900122 180)
			(size 0.450088 0.450088)
			(layers "F.Cu" "F.Mask" "F.Paste")
			(net "PVDDCR_CPU0_P1")
		)
		(pad "M25" smd circle
			(at -12.07008 -27.900122 180)
			(size 0.450088 0.450088)
			(layers "F.Cu" "F.Mask" "F.Paste")
			(net "GND")
		)
		(pad "M26" smd circle
			(at -11.130026 -27.900122 180)
			(size 0.450088 0.450088)
			(layers "F.Cu" "F.Mask" "F.Paste")
			(net "PVDDCR_CPU0_P1")
		)
		(pad "M27" smd circle
			(at -10.189972 -27.900122 180)
			(size 0.450088 0.450088)
			(layers "F.Cu" "F.Mask" "F.Paste")
			(net "PVDDCR_CPU0_P1")
		)
		(pad "M28" smd circle
			(at -9.249918 -27.900122 180)
			(size 0.450088 0.450088)
			(layers "F.Cu" "F.Mask" "F.Paste")
			(net "GND")
		)
		(pad "M29" smd circle
			(at -8.310118 -27.900122 180)
			(size 0.450088 0.450088)
			(layers "F.Cu" "F.Mask" "F.Paste")
			(net "PVDDCR_CPU0_P1")
		)
		(pad "M30" smd circle
			(at -7.370064 -27.900122 180)
			(size 0.450088 0.450088)
			(layers "F.Cu" "F.Mask" "F.Paste")
			(net "PVDDCR_CPU0_P1")
		)
		(pad "M31" smd circle
			(at -6.43001 -27.900122 180)
			(size 0.450088 0.450088)
			(layers "F.Cu" "F.Mask" "F.Paste")
			(net "GND")
		)
		(pad "M32" smd circle
			(at -5.489956 -27.900122 180)
			(size 0.450088 0.450088)
			(layers "F.Cu" "F.Mask" "F.Paste")
			(net "PVDDCR_CPU0_P1")
		)
		(pad "M33" smd circle
			(at -4.549902 -27.900122 180)
			(size 0.450088 0.450088)
			(layers "F.Cu" "F.Mask" "F.Paste")
			(net "PVDDCR_CPU0_P1")
		)
		(pad "M34" smd circle
			(at -3.610102 -27.900122 180)
			(size 0.450088 0.450088)
			(layers "F.Cu" "F.Mask" "F.Paste")
			(net "GND")
		)
		(pad "M35" smd circle
			(at -2.670048 -27.900122 180)
			(size 0.450088 0.450088)
			(layers "F.Cu" "F.Mask" "F.Paste")
			(net "GMI_CPU1_G2_CPU0_G0_TX_DP<0>")
		)
		(pad "M36" smd circle
			(at -1.729994 -27.900122 180)
			(size 0.450088 0.450088)
			(layers "F.Cu" "F.Mask" "F.Paste")
			(net "GMI_CPU1_G2_CPU0_G0_TX_DN<0>")
		)
		(pad "M37" smd circle
			(at -0.78994 -27.900122 180)
			(size 0.450088 0.450088)
			(layers "F.Cu" "F.Mask" "F.Paste")
			(net "GND")
		)
		(pad "M39" smd circle
			(at 1.089914 -27.900122 180)
			(size 0.450088 0.450088)
			(layers "F.Cu" "F.Mask" "F.Paste")
			(net "GND")
		)
		(pad "M40" smd circle
			(at 2.029968 -27.900122 180)
			(size 0.450088 0.450088)
			(layers "F.Cu" "F.Mask" "F.Paste")
			(net "GMI_CPU0_G2_CPU1_G0_TX_DN<15>")
		)
		(pad "M41" smd circle
			(at 2.970022 -27.900122 180)
			(size 0.450088 0.450088)
			(layers "F.Cu" "F.Mask" "F.Paste")
			(net "GMI_CPU0_G2_CPU1_G0_TX_DP<15>")
		)
		(pad "M42" smd circle
			(at 3.910076 -27.900122 180)
			(size 0.450088 0.450088)
			(layers "F.Cu" "F.Mask" "F.Paste")
			(net "GND")
		)
		(pad "M43" smd circle
			(at 4.849876 -27.900122 180)
			(size 0.450088 0.450088)
			(layers "F.Cu" "F.Mask" "F.Paste")
			(net "PVDDCR_CPU0_P1")
		)
		(pad "M44" smd circle
			(at 5.78993 -27.900122 180)
			(size 0.450088 0.450088)
			(layers "F.Cu" "F.Mask" "F.Paste")
			(net "PVDDCR_CPU0_P1")
		)
		(pad "M45" smd circle
			(at 6.729984 -27.900122 180)
			(size 0.450088 0.450088)
			(layers "F.Cu" "F.Mask" "F.Paste")
			(net "GND")
		)
		(pad "M46" smd circle
			(at 7.670038 -27.900122 180)
			(size 0.450088 0.450088)
			(layers "F.Cu" "F.Mask" "F.Paste")
			(net "PVDDCR_CPU0_P1")
		)
		(pad "M47" smd circle
			(at 8.610092 -27.900122 180)
			(size 0.450088 0.450088)
			(layers "F.Cu" "F.Mask" "F.Paste")
			(net "PVDDCR_CPU0_P1")
		)
		(pad "M48" smd circle
			(at 9.549892 -27.900122 180)
			(size 0.450088 0.450088)
			(layers "F.Cu" "F.Mask" "F.Paste")
			(net "GND")
		)
		(pad "M49" smd circle
			(at 10.489946 -27.900122 180)
			(size 0.450088 0.450088)
			(layers "F.Cu" "F.Mask" "F.Paste")
			(net "PVDDCR_CPU0_P1")
		)
		(pad "M50" smd circle
			(at 11.43 -27.900122 180)
			(size 0.450088 0.450088)
			(layers "F.Cu" "F.Mask" "F.Paste")
			(net "PVDDCR_CPU0_P1")
		)
		(pad "M51" smd circle
			(at 12.370054 -27.900122 180)
			(size 0.450088 0.450088)
			(layers "F.Cu" "F.Mask" "F.Paste")
			(net "GND")
		)
		(pad "M52" smd circle
			(at 13.310108 -27.900122 180)
			(size 0.450088 0.450088)
			(layers "F.Cu" "F.Mask" "F.Paste")
			(net "PVDDCR_CPU0_P1")
		)
		(pad "M53" smd circle
			(at 14.249908 -27.900122 180)
			(size 0.450088 0.450088)
			(layers "F.Cu" "F.Mask" "F.Paste")
			(net "PVDDCR_CPU0_P1")
		)
		(pad "M54" smd circle
			(at 15.189962 -27.900122 180)
			(size 0.450088 0.450088)
			(layers "F.Cu" "F.Mask" "F.Paste")
			(net "GND")
		)
		(pad "M55" smd circle
			(at 16.130016 -27.900122 180)
			(size 0.450088 0.450088)
			(layers "F.Cu" "F.Mask" "F.Paste")
			(net "M_C_CPU1_SA_DQ<9>")
		)
		(pad "M56" smd circle
			(at 17.07007 -27.900122 180)
			(size 0.450088 0.450088)
			(layers "F.Cu" "F.Mask" "F.Paste")
			(net "M_C_CPU1_SA_DQ<10>")
		)
		(pad "M57" smd circle
			(at 18.010124 -27.900122 180)
			(size 0.450088 0.450088)
			(layers "F.Cu" "F.Mask" "F.Paste")
			(net "GND")
		)
		(pad "M58" smd circle
			(at 18.949924 -27.900122 180)
			(size 0.450088 0.450088)
			(layers "F.Cu" "F.Mask" "F.Paste")
			(net "M_D_CPU1_SA_DQ<9>")
		)
		(pad "M59" smd circle
			(at 19.889978 -27.900122 180)
			(size 0.450088 0.450088)
			(layers "F.Cu" "F.Mask" "F.Paste")
			(net "GND")
		)
		(pad "M60" smd circle
			(at 20.830032 -27.900122 180)
			(size 0.450088 0.450088)
			(layers "F.Cu" "F.Mask" "F.Paste")
			(net "M_D_CPU1_SA_DQ<10>")
		)
		(pad "M61" smd circle
			(at 21.770086 -27.900122 180)
			(size 0.450088 0.450088)
			(layers "F.Cu" "F.Mask" "F.Paste")
			(net "GND")
		)
		(pad "M62" smd circle
			(at 22.709886 -27.900122 180)
			(size 0.450088 0.450088)
			(layers "F.Cu" "F.Mask" "F.Paste")
			(net "M_B_CPU1_SA_DQ<9>")
		)
		(pad "M63" smd circle
			(at 23.64994 -27.900122 180)
			(size 0.450088 0.450088)
			(layers "F.Cu" "F.Mask" "F.Paste")
			(net "M_B_CPU1_SA_DQ<10>")
		)
		(pad "M64" smd circle
			(at 24.589994 -27.900122 180)
			(size 0.450088 0.450088)
			(layers "F.Cu" "F.Mask" "F.Paste")
			(net "GND")
		)
		(pad "M65" smd circle
			(at 25.530048 -27.900122 180)
			(size 0.450088 0.450088)
			(layers "F.Cu" "F.Mask" "F.Paste")
			(net "M_F_CPU1_SA_DQ<9>")
		)
		(pad "M66" smd circle
			(at 26.470102 -27.900122 180)
			(size 0.450088 0.450088)
			(layers "F.Cu" "F.Mask" "F.Paste")
			(net "GND")
		)
		(pad "M67" smd circle
			(at 27.409902 -27.900122 180)
			(size 0.450088 0.450088)
			(layers "F.Cu" "F.Mask" "F.Paste")
			(net "M_F_CPU1_SA_DQ<10>")
		)
		(pad "M68" smd circle
			(at 28.349956 -27.900122 180)
			(size 0.450088 0.450088)
			(layers "F.Cu" "F.Mask" "F.Paste")
			(net "GND")
		)
		(pad "M69" smd circle
			(at 29.29001 -27.900122 180)
			(size 0.450088 0.450088)
			(layers "F.Cu" "F.Mask" "F.Paste")
			(net "M_E_CPU1_SA_DQ<9>")
		)
		(pad "M70" smd circle
			(at 30.230064 -27.900122 180)
			(size 0.450088 0.450088)
			(layers "F.Cu" "F.Mask" "F.Paste")
			(net "M_E_CPU1_SA_DQ<10>")
		)
		(pad "M71" smd circle
			(at 31.170118 -27.900122 180)
			(size 0.450088 0.450088)
			(layers "F.Cu" "F.Mask" "F.Paste")
			(net "GND")
		)
		(pad "M72" smd circle
			(at 32.109918 -27.900122 180)
			(size 0.450088 0.450088)
			(layers "F.Cu" "F.Mask" "F.Paste")
			(net "M_A_CPU1_SA_DQ<9>")
		)
		(pad "M73" smd circle
			(at 33.049972 -27.900122 180)
			(size 0.450088 0.450088)
			(layers "F.Cu" "F.Mask" "F.Paste")
			(net "GND")
		)
		(pad "M74" smd circle
			(at 33.990026 -27.900122 180)
			(size 0.450088 0.450088)
			(layers "F.Cu" "F.Mask" "F.Paste")
			(net "M_A_CPU1_SA_DQ<10>")
		)
		(pad "N1" smd circle
			(at -34.159952 -27.090116 180)
			(size 0.450088 0.450088)
			(layers "F.Cu" "F.Mask" "F.Paste")
			(net "GND")
		)
		(pad "N2" smd circle
			(at -33.219898 -27.090116 180)
			(size 0.450088 0.450088)
			(layers "F.Cu" "F.Mask" "F.Paste")
			(net "M_G_CPU1_SA_DQS_DP<1>")
		)
		(pad "N3" smd circle
			(at -32.280098 -27.090116 180)
			(size 0.450088 0.450088)
			(layers "F.Cu" "F.Mask" "F.Paste")
			(net "M_G_CPU1_SA_DQ<11>")
		)
		(pad "N4" smd circle
			(at -31.340044 -27.090116 180)
			(size 0.450088 0.450088)
			(layers "F.Cu" "F.Mask" "F.Paste")
			(net "GND")
		)
		(pad "N5" smd circle
			(at -30.39999 -27.090116 180)
			(size 0.450088 0.450088)
			(layers "F.Cu" "F.Mask" "F.Paste")
			(net "M_K_CPU1_SA_DQS_DP<1>")
		)
		(pad "N6" smd circle
			(at -29.459936 -27.090116 180)
			(size 0.450088 0.450088)
			(layers "F.Cu" "F.Mask" "F.Paste")
			(net "GND")
		)
		(pad "N7" smd circle
			(at -28.519882 -27.090116 180)
			(size 0.450088 0.450088)
			(layers "F.Cu" "F.Mask" "F.Paste")
			(net "M_K_CPU1_SA_DQ<11>")
		)
		(pad "N8" smd circle
			(at -27.580082 -27.090116 180)
			(size 0.450088 0.450088)
			(layers "F.Cu" "F.Mask" "F.Paste")
			(net "GND")
		)
		(pad "N9" smd circle
			(at -26.640028 -27.090116 180)
			(size 0.450088 0.450088)
			(layers "F.Cu" "F.Mask" "F.Paste")
			(net "M_L_CPU1_SA_DQS_DP<1>")
		)
		(pad "N10" smd circle
			(at -25.699974 -27.090116 180)
			(size 0.450088 0.450088)
			(layers "F.Cu" "F.Mask" "F.Paste")
			(net "M_L_CPU1_SA_DQ<11>")
		)
		(pad "N11" smd circle
			(at -24.75992 -27.090116 180)
			(size 0.450088 0.450088)
			(layers "F.Cu" "F.Mask" "F.Paste")
			(net "GND")
		)
		(pad "N12" smd circle
			(at -23.82012 -27.090116 180)
			(size 0.450088 0.450088)
			(layers "F.Cu" "F.Mask" "F.Paste")
			(net "M_H_CPU1_SA_DQS_DP<1>")
		)
		(pad "N13" smd circle
			(at -22.880066 -27.090116 180)
			(size 0.450088 0.450088)
			(layers "F.Cu" "F.Mask" "F.Paste")
			(net "GND")
		)
		(pad "N14" smd circle
			(at -21.940012 -27.090116 180)
			(size 0.450088 0.450088)
			(layers "F.Cu" "F.Mask" "F.Paste")
			(net "M_H_CPU1_SA_DQ<11>")
		)
		(pad "N15" smd circle
			(at -20.999958 -27.090116 180)
			(size 0.450088 0.450088)
			(layers "F.Cu" "F.Mask" "F.Paste")
			(net "GND")
		)
		(pad "N16" smd circle
			(at -20.059904 -27.090116 180)
			(size 0.450088 0.450088)
			(layers "F.Cu" "F.Mask" "F.Paste")
			(net "M_J_CPU1_SA_DQS_DP<1>")
		)
		(pad "N17" smd circle
			(at -19.120104 -27.090116 180)
			(size 0.450088 0.450088)
			(layers "F.Cu" "F.Mask" "F.Paste")
			(net "M_J_CPU1_SA_DQ<11>")
		)
		(pad "N18" smd circle
			(at -18.18005 -27.090116 180)
			(size 0.450088 0.450088)
			(layers "F.Cu" "F.Mask" "F.Paste")
			(net "GND")
		)
		(pad "N19" smd circle
			(at -17.239996 -27.090116 180)
			(size 0.450088 0.450088)
			(layers "F.Cu" "F.Mask" "F.Paste")
			(net "M_I_CPU1_SA_DQS_DP<1>")
		)
		(pad "N20" smd circle
			(at -16.299942 -27.090116 180)
			(size 0.450088 0.450088)
			(layers "F.Cu" "F.Mask" "F.Paste")
			(net "GND")
		)
		(pad "N21" smd circle
			(at -15.359888 -27.090116 180)
			(size 0.450088 0.450088)
			(layers "F.Cu" "F.Mask" "F.Paste")
			(net "M_I_CPU1_SA_DQ<11>")
		)
		(pad "N22" smd circle
			(at -14.420088 -27.090116 180)
			(size 0.450088 0.450088)
			(layers "F.Cu" "F.Mask" "F.Paste")
			(net "GND")
		)
		(pad "N23" smd circle
			(at -13.480034 -27.090116 180)
			(size 0.450088 0.450088)
			(layers "F.Cu" "F.Mask" "F.Paste")
			(net "GMI_CPU1_G2_CPU0_G0_TX_DP<15>")
		)
		(pad "N24" smd circle
			(at -12.53998 -27.090116 180)
			(size 0.450088 0.450088)
			(layers "F.Cu" "F.Mask" "F.Paste")
			(net "GMI_CPU1_G2_CPU0_G0_TX_DN<15>")
		)
		(pad "N25" smd circle
			(at -11.599926 -27.090116 180)
			(size 0.450088 0.450088)
			(layers "F.Cu" "F.Mask" "F.Paste")
			(net "GND")
		)
		(pad "N26" smd circle
			(at -10.659872 -27.090116 180)
			(size 0.450088 0.450088)
			(layers "F.Cu" "F.Mask" "F.Paste")
			(net "GMI_CPU1_G3_CPU0_G1_TX_DP<10>")
		)
		(pad "N27" smd circle
			(at -9.720072 -27.090116 180)
			(size 0.450088 0.450088)
			(layers "F.Cu" "F.Mask" "F.Paste")
			(net "GMI_CPU1_G3_CPU0_G1_TX_DN<10>")
		)
		(pad "N28" smd circle
			(at -8.780018 -27.090116 180)
			(size 0.450088 0.450088)
			(layers "F.Cu" "F.Mask" "F.Paste")
			(net "GND")
		)
		(pad "N29" smd circle
			(at -7.839964 -27.090116 180)
			(size 0.450088 0.450088)
			(layers "F.Cu" "F.Mask" "F.Paste")
			(net "GMI_CPU1_G3_CPU0_G1_TX_DP<7>")
		)
		(pad "N30" smd circle
			(at -6.89991 -27.090116 180)
			(size 0.450088 0.450088)
			(layers "F.Cu" "F.Mask" "F.Paste")
			(net "GMI_CPU1_G3_CPU0_G1_TX_DN<7>")
		)
		(pad "N31" smd circle
			(at -5.96011 -27.090116 180)
			(size 0.450088 0.450088)
			(layers "F.Cu" "F.Mask" "F.Paste")
			(net "GND")
		)
		(pad "N32" smd circle
			(at -5.020056 -27.090116 180)
			(size 0.450088 0.450088)
			(layers "F.Cu" "F.Mask" "F.Paste")
			(net "GMI_CPU1_G3_CPU0_G1_TX_DP<4>")
		)
		(pad "N33" smd circle
			(at -4.080002 -27.090116 180)
			(size 0.450088 0.450088)
			(layers "F.Cu" "F.Mask" "F.Paste")
			(net "GMI_CPU1_G3_CPU0_G1_TX_DN<4>")
		)
		(pad "N34" smd circle
			(at -3.139948 -27.090116 180)
			(size 0.450088 0.450088)
			(layers "F.Cu" "F.Mask" "F.Paste")
			(net "GND")
		)
		(pad "N35" smd circle
			(at -2.199894 -27.090116 180)
			(size 0.450088 0.450088)
			(layers "F.Cu" "F.Mask" "F.Paste")
			(net "PVDDCR_CPU0_P1")
		)
		(pad "N36" smd circle
			(at -1.260094 -27.090116 180)
			(size 0.450088 0.450088)
			(layers "F.Cu" "F.Mask" "F.Paste")
			(net "PVDDCR_CPU0_P1")
		)
		(pad "N40" smd circle
			(at 1.560068 -27.090116 180)
			(size 0.450088 0.450088)
			(layers "F.Cu" "F.Mask" "F.Paste")
			(net "PVDDCR_CPU0_P1")
		)
		(pad "N41" smd circle
			(at 2.500122 -27.090116 180)
			(size 0.450088 0.450088)
			(layers "F.Cu" "F.Mask" "F.Paste")
			(net "PVDDCR_CPU0_P1")
		)
		(pad "N42" smd circle
			(at 3.439922 -27.090116 180)
			(size 0.450088 0.450088)
			(layers "F.Cu" "F.Mask" "F.Paste")
			(net "GND")
		)
		(pad "N43" smd circle
			(at 4.379976 -27.090116 180)
			(size 0.450088 0.450088)
			(layers "F.Cu" "F.Mask" "F.Paste")
			(net "P5E_CPU1_G1_RX_DN<4>")
		)
		(pad "N44" smd circle
			(at 5.32003 -27.090116 180)
			(size 0.450088 0.450088)
			(layers "F.Cu" "F.Mask" "F.Paste")
			(net "P5E_CPU1_G1_RX_DP<4>")
		)
		(pad "N45" smd circle
			(at 6.260084 -27.090116 180)
			(size 0.450088 0.450088)
			(layers "F.Cu" "F.Mask" "F.Paste")
			(net "GND")
		)
		(pad "N46" smd circle
			(at 7.199884 -27.090116 180)
			(size 0.450088 0.450088)
			(layers "F.Cu" "F.Mask" "F.Paste")
			(net "P5E_CPU1_G1_RX_DN<7>")
		)
		(pad "N47" smd circle
			(at 8.139938 -27.090116 180)
			(size 0.450088 0.450088)
			(layers "F.Cu" "F.Mask" "F.Paste")
			(net "P5E_CPU1_G1_RX_DP<7>")
		)
		(pad "N48" smd circle
			(at 9.079992 -27.090116 180)
			(size 0.450088 0.450088)
			(layers "F.Cu" "F.Mask" "F.Paste")
			(net "GND")
		)
		(pad "N49" smd circle
			(at 10.020046 -27.090116 180)
			(size 0.450088 0.450088)
			(layers "F.Cu" "F.Mask" "F.Paste")
			(net "P5E_CPU1_G1_RX_DN<10>")
		)
		(pad "N50" smd circle
			(at 10.9601 -27.090116 180)
			(size 0.450088 0.450088)
			(layers "F.Cu" "F.Mask" "F.Paste")
			(net "P5E_CPU1_G1_RX_DP<10>")
		)
		(pad "N51" smd circle
			(at 11.8999 -27.090116 180)
			(size 0.450088 0.450088)
			(layers "F.Cu" "F.Mask" "F.Paste")
			(net "GND")
		)
		(pad "N52" smd circle
			(at 12.839954 -27.090116 180)
			(size 0.450088 0.450088)
			(layers "F.Cu" "F.Mask" "F.Paste")
			(net "GMI_CPU0_G2_CPU1_G0_TX_DN<0>")
		)
		(pad "N53" smd circle
			(at 13.780008 -27.090116 180)
			(size 0.450088 0.450088)
			(layers "F.Cu" "F.Mask" "F.Paste")
			(net "GMI_CPU0_G2_CPU1_G0_TX_DP<0>")
		)
		(pad "N54" smd circle
			(at 14.720062 -27.090116 180)
			(size 0.450088 0.450088)
			(layers "F.Cu" "F.Mask" "F.Paste")
			(net "GND")
		)
		(pad "N55" smd circle
			(at 15.660116 -27.090116 180)
			(size 0.450088 0.450088)
			(layers "F.Cu" "F.Mask" "F.Paste")
			(net "M_C_CPU1_SA_DQ<11>")
		)
		(pad "N56" smd circle
			(at 16.599916 -27.090116 180)
			(size 0.450088 0.450088)
			(layers "F.Cu" "F.Mask" "F.Paste")
			(net "GND")
		)
		(pad "N57" smd circle
			(at 17.53997 -27.090116 180)
			(size 0.450088 0.450088)
			(layers "F.Cu" "F.Mask" "F.Paste")
			(net "M_C_CPU1_SA_DQS_DP<1>")
		)
		(pad "N58" smd circle
			(at 18.480024 -27.090116 180)
			(size 0.450088 0.450088)
			(layers "F.Cu" "F.Mask" "F.Paste")
			(net "GND")
		)
		(pad "N59" smd circle
			(at 19.420078 -27.090116 180)
			(size 0.450088 0.450088)
			(layers "F.Cu" "F.Mask" "F.Paste")
			(net "M_D_CPU1_SA_DQ<11>")
		)
		(pad "N60" smd circle
			(at 20.359878 -27.090116 180)
			(size 0.450088 0.450088)
			(layers "F.Cu" "F.Mask" "F.Paste")
			(net "M_D_CPU1_SA_DQS_DP<1>")
		)
		(pad "N61" smd circle
			(at 21.299932 -27.090116 180)
			(size 0.450088 0.450088)
			(layers "F.Cu" "F.Mask" "F.Paste")
			(net "GND")
		)
		(pad "N62" smd circle
			(at 22.239986 -27.090116 180)
			(size 0.450088 0.450088)
			(layers "F.Cu" "F.Mask" "F.Paste")
			(net "M_B_CPU1_SA_DQ<11>")
		)
		(pad "N63" smd circle
			(at 23.18004 -27.090116 180)
			(size 0.450088 0.450088)
			(layers "F.Cu" "F.Mask" "F.Paste")
			(net "GND")
		)
		(pad "N64" smd circle
			(at 24.120094 -27.090116 180)
			(size 0.450088 0.450088)
			(layers "F.Cu" "F.Mask" "F.Paste")
			(net "M_B_CPU1_SA_DQS_DP<1>")
		)
		(pad "N65" smd circle
			(at 25.059894 -27.090116 180)
			(size 0.450088 0.450088)
			(layers "F.Cu" "F.Mask" "F.Paste")
			(net "GND")
		)
		(pad "N66" smd circle
			(at 25.999948 -27.090116 180)
			(size 0.450088 0.450088)
			(layers "F.Cu" "F.Mask" "F.Paste")
			(net "M_F_CPU1_SA_DQ<11>")
		)
		(pad "N67" smd circle
			(at 26.940002 -27.090116 180)
			(size 0.450088 0.450088)
			(layers "F.Cu" "F.Mask" "F.Paste")
			(net "M_F_CPU1_SA_DQS_DP<1>")
		)
		(pad "N68" smd circle
			(at 27.880056 -27.090116 180)
			(size 0.450088 0.450088)
			(layers "F.Cu" "F.Mask" "F.Paste")
			(net "GND")
		)
		(pad "N69" smd circle
			(at 28.82011 -27.090116 180)
			(size 0.450088 0.450088)
			(layers "F.Cu" "F.Mask" "F.Paste")
			(net "M_E_CPU1_SA_DQ<11>")
		)
		(pad "N70" smd circle
			(at 29.75991 -27.090116 180)
			(size 0.450088 0.450088)
			(layers "F.Cu" "F.Mask" "F.Paste")
			(net "GND")
		)
		(pad "N71" smd circle
			(at 30.699964 -27.090116 180)
			(size 0.450088 0.450088)
			(layers "F.Cu" "F.Mask" "F.Paste")
			(net "M_E_CPU1_SA_DQS_DP<1>")
		)
		(pad "N72" smd circle
			(at 31.640018 -27.090116 180)
			(size 0.450088 0.450088)
			(layers "F.Cu" "F.Mask" "F.Paste")
			(net "GND")
		)
		(pad "N73" smd circle
			(at 32.580072 -27.090116 180)
			(size 0.450088 0.450088)
			(layers "F.Cu" "F.Mask" "F.Paste")
			(net "M_A_CPU1_SA_DQ<11>")
		)
		(pad "N74" smd circle
			(at 33.519872 -27.090116 180)
			(size 0.450088 0.450088)
			(layers "F.Cu" "F.Mask" "F.Paste")
			(net "M_A_CPU1_SA_DQS_DP<1>")
		)
		(pad "N75" smd circle
			(at 34.459926 -27.090116 180)
			(size 0.450088 0.450088)
			(layers "F.Cu" "F.Mask" "F.Paste")
			(net "GND")
		)
		(pad "P2" smd circle
			(at -33.690052 -26.28011 180)
			(size 0.450088 0.450088)
			(layers "F.Cu" "F.Mask" "F.Paste")
			(net "M_G_CPU1_SA_DQS_DN<1>")
		)
		(pad "P3" smd circle
			(at -32.749998 -26.28011 180)
			(size 0.450088 0.450088)
			(layers "F.Cu" "F.Mask" "F.Paste")
			(net "GND")
		)
		(pad "P4" smd circle
			(at -31.809944 -26.28011 180)
			(size 0.450088 0.450088)
			(layers "F.Cu" "F.Mask" "F.Paste")
			(net "M_G_CPU1_SA_DQS_DN<6>")
		)
		(pad "P5" smd circle
			(at -30.86989 -26.28011 180)
			(size 0.450088 0.450088)
			(layers "F.Cu" "F.Mask" "F.Paste")
			(net "PVDDCR_SOC_P1")
		)
		(pad "P6" smd circle
			(at -29.93009 -26.28011 180)
			(size 0.450088 0.450088)
			(layers "F.Cu" "F.Mask" "F.Paste")
			(net "M_K_CPU1_SA_DQS_DN<1>")
		)
		(pad "P7" smd circle
			(at -28.990036 -26.28011 180)
			(size 0.450088 0.450088)
			(layers "F.Cu" "F.Mask" "F.Paste")
			(net "M_K_CPU1_SA_DQS_DN<6>")
		)
		(pad "P8" smd circle
			(at -28.049982 -26.28011 180)
			(size 0.450088 0.450088)
			(layers "F.Cu" "F.Mask" "F.Paste")
			(net "GND")
		)
		(pad "P9" smd circle
			(at -27.109928 -26.28011 180)
			(size 0.450088 0.450088)
			(layers "F.Cu" "F.Mask" "F.Paste")
			(net "M_L_CPU1_SA_DQS_DN<1>")
		)
		(pad "P10" smd circle
			(at -26.170128 -26.28011 180)
			(size 0.450088 0.450088)
			(layers "F.Cu" "F.Mask" "F.Paste")
			(net "GND")
		)
		(pad "P11" smd circle
			(at -25.230074 -26.28011 180)
			(size 0.450088 0.450088)
			(layers "F.Cu" "F.Mask" "F.Paste")
			(net "M_L_CPU1_SA_DQS_DN<6>")
		)
		(pad "P12" smd circle
			(at -24.29002 -26.28011 180)
			(size 0.450088 0.450088)
			(layers "F.Cu" "F.Mask" "F.Paste")
			(net "PVDDCR_SOC_P1")
		)
		(pad "P13" smd circle
			(at -23.349966 -26.28011 180)
			(size 0.450088 0.450088)
			(layers "F.Cu" "F.Mask" "F.Paste")
			(net "M_H_CPU1_SA_DQS_DN<1>")
		)
		(pad "P14" smd circle
			(at -22.409912 -26.28011 180)
			(size 0.450088 0.450088)
			(layers "F.Cu" "F.Mask" "F.Paste")
			(net "M_H_CPU1_SA_DQS_DN<6>")
		)
		(pad "P15" smd circle
			(at -21.470112 -26.28011 180)
			(size 0.450088 0.450088)
			(layers "F.Cu" "F.Mask" "F.Paste")
			(net "GND")
		)
		(pad "P16" smd circle
			(at -20.530058 -26.28011 180)
			(size 0.450088 0.450088)
			(layers "F.Cu" "F.Mask" "F.Paste")
			(net "M_J_CPU1_SA_DQS_DN<1>")
		)
		(pad "P17" smd circle
			(at -19.590004 -26.28011 180)
			(size 0.450088 0.450088)
			(layers "F.Cu" "F.Mask" "F.Paste")
			(net "GND")
		)
		(pad "P18" smd circle
			(at -18.64995 -26.28011 180)
			(size 0.450088 0.450088)
			(layers "F.Cu" "F.Mask" "F.Paste")
			(net "M_J_CPU1_SA_DQS_DN<6>")
		)
		(pad "P19" smd circle
			(at -17.709896 -26.28011 180)
			(size 0.450088 0.450088)
			(layers "F.Cu" "F.Mask" "F.Paste")
			(net "PVDDCR_SOC_P1")
		)
		(pad "P20" smd circle
			(at -16.770096 -26.28011 180)
			(size 0.450088 0.450088)
			(layers "F.Cu" "F.Mask" "F.Paste")
			(net "M_I_CPU1_SA_DQS_DN<1>")
		)
		(pad "P21" smd circle
			(at -15.830042 -26.28011 180)
			(size 0.450088 0.450088)
			(layers "F.Cu" "F.Mask" "F.Paste")
			(net "M_I_CPU1_SA_DQS_DN<6>")
		)
		(pad "P22" smd circle
			(at -14.889988 -26.28011 180)
			(size 0.450088 0.450088)
			(layers "F.Cu" "F.Mask" "F.Paste")
			(net "PVDDCR_SOC_P1")
		)
		(pad "P23" smd circle
			(at -13.949934 -26.28011 180)
			(size 0.450088 0.450088)
			(layers "F.Cu" "F.Mask" "F.Paste")
			(net "GND")
		)
		(pad "P24" smd circle
			(at -13.00988 -26.28011 180)
			(size 0.450088 0.450088)
			(layers "F.Cu" "F.Mask" "F.Paste")
			(net "GND")
		)
		(pad "P25" smd circle
			(at -12.07008 -26.28011 180)
			(size 0.450088 0.450088)
			(layers "F.Cu" "F.Mask" "F.Paste")
			(net "GND")
		)
		(pad "P26" smd circle
			(at -11.130026 -26.28011 180)
			(size 0.450088 0.450088)
			(layers "F.Cu" "F.Mask" "F.Paste")
			(net "GND")
		)
		(pad "P27" smd circle
			(at -10.189972 -26.28011 180)
			(size 0.450088 0.450088)
			(layers "F.Cu" "F.Mask" "F.Paste")
			(net "GND")
		)
		(pad "P28" smd circle
			(at -9.249918 -26.28011 180)
			(size 0.450088 0.450088)
			(layers "F.Cu" "F.Mask" "F.Paste")
			(net "GND")
		)
		(pad "P29" smd circle
			(at -8.310118 -26.28011 180)
			(size 0.450088 0.450088)
			(layers "F.Cu" "F.Mask" "F.Paste")
			(net "GND")
		)
		(pad "P30" smd circle
			(at -7.370064 -26.28011 180)
			(size 0.450088 0.450088)
			(layers "F.Cu" "F.Mask" "F.Paste")
			(net "GND")
		)
		(pad "P31" smd circle
			(at -6.43001 -26.28011 180)
			(size 0.450088 0.450088)
			(layers "F.Cu" "F.Mask" "F.Paste")
			(net "GND")
		)
		(pad "P32" smd circle
			(at -5.489956 -26.28011 180)
			(size 0.450088 0.450088)
			(layers "F.Cu" "F.Mask" "F.Paste")
			(net "GND")
		)
		(pad "P33" smd circle
			(at -4.549902 -26.28011 180)
			(size 0.450088 0.450088)
			(layers "F.Cu" "F.Mask" "F.Paste")
			(net "GND")
		)
		(pad "P34" smd circle
			(at -3.610102 -26.28011 180)
			(size 0.450088 0.450088)
			(layers "F.Cu" "F.Mask" "F.Paste")
			(net "GND")
		)
		(pad "P35" smd circle
			(at -2.670048 -26.28011 180)
			(size 0.450088 0.450088)
			(layers "F.Cu" "F.Mask" "F.Paste")
			(net "GMI_CPU1_G3_CPU0_G1_TX_DP<2>")
		)
		(pad "P36" smd circle
			(at -1.729994 -26.28011 180)
			(size 0.450088 0.450088)
			(layers "F.Cu" "F.Mask" "F.Paste")
			(net "GMI_CPU1_G3_CPU0_G1_TX_DN<2>")
		)
		(pad "P37" smd circle
			(at -0.78994 -26.28011 180)
			(size 0.450088 0.450088)
			(layers "F.Cu" "F.Mask" "F.Paste")
			(net "GND")
		)
		(pad "P39" smd circle
			(at 1.089914 -26.28011 180)
			(size 0.450088 0.450088)
			(layers "F.Cu" "F.Mask" "F.Paste")
			(net "GND")
		)
		(pad "P40" smd circle
			(at 2.029968 -26.28011 180)
			(size 0.450088 0.450088)
			(layers "F.Cu" "F.Mask" "F.Paste")
			(net "P5E_CPU1_G1_RX_DN<2>")
		)
		(pad "P41" smd circle
			(at 2.970022 -26.28011 180)
			(size 0.450088 0.450088)
			(layers "F.Cu" "F.Mask" "F.Paste")
			(net "P5E_CPU1_G1_RX_DP<2>")
		)
		(pad "P42" smd circle
			(at 3.910076 -26.28011 180)
			(size 0.450088 0.450088)
			(layers "F.Cu" "F.Mask" "F.Paste")
			(net "GND")
		)
		(pad "P43" smd circle
			(at 4.849876 -26.28011 180)
			(size 0.450088 0.450088)
			(layers "F.Cu" "F.Mask" "F.Paste")
			(net "GND")
		)
		(pad "P44" smd circle
			(at 5.78993 -26.28011 180)
			(size 0.450088 0.450088)
			(layers "F.Cu" "F.Mask" "F.Paste")
			(net "GND")
		)
		(pad "P45" smd circle
			(at 6.729984 -26.28011 180)
			(size 0.450088 0.450088)
			(layers "F.Cu" "F.Mask" "F.Paste")
			(net "GND")
		)
		(pad "P46" smd circle
			(at 7.670038 -26.28011 180)
			(size 0.450088 0.450088)
			(layers "F.Cu" "F.Mask" "F.Paste")
			(net "GND")
		)
		(pad "P47" smd circle
			(at 8.610092 -26.28011 180)
			(size 0.450088 0.450088)
			(layers "F.Cu" "F.Mask" "F.Paste")
			(net "GND")
		)
		(pad "P48" smd circle
			(at 9.549892 -26.28011 180)
			(size 0.450088 0.450088)
			(layers "F.Cu" "F.Mask" "F.Paste")
			(net "GND")
		)
		(pad "P49" smd circle
			(at 10.489946 -26.28011 180)
			(size 0.450088 0.450088)
			(layers "F.Cu" "F.Mask" "F.Paste")
			(net "GND")
		)
		(pad "P50" smd circle
			(at 11.43 -26.28011 180)
			(size 0.450088 0.450088)
			(layers "F.Cu" "F.Mask" "F.Paste")
			(net "GND")
		)
		(pad "P51" smd circle
			(at 12.370054 -26.28011 180)
			(size 0.450088 0.450088)
			(layers "F.Cu" "F.Mask" "F.Paste")
			(net "GND")
		)
		(pad "P52" smd circle
			(at 13.310108 -26.28011 180)
			(size 0.450088 0.450088)
			(layers "F.Cu" "F.Mask" "F.Paste")
			(net "GND")
		)
		(pad "P53" smd circle
			(at 14.249908 -26.28011 180)
			(size 0.450088 0.450088)
			(layers "F.Cu" "F.Mask" "F.Paste")
			(net "GND")
		)
		(pad "P54" smd circle
			(at 15.189962 -26.28011 180)
			(size 0.450088 0.450088)
			(layers "F.Cu" "F.Mask" "F.Paste")
			(net "PVDDIO_P1")
		)
		(pad "P55" smd circle
			(at 16.130016 -26.28011 180)
			(size 0.450088 0.450088)
			(layers "F.Cu" "F.Mask" "F.Paste")
			(net "M_C_CPU1_SA_DQS_DN<6>")
		)
		(pad "P56" smd circle
			(at 17.07007 -26.28011 180)
			(size 0.450088 0.450088)
			(layers "F.Cu" "F.Mask" "F.Paste")
			(net "M_C_CPU1_SA_DQS_DN<1>")
		)
		(pad "P57" smd circle
			(at 18.010124 -26.28011 180)
			(size 0.450088 0.450088)
			(layers "F.Cu" "F.Mask" "F.Paste")
			(net "PVDDIO_P1")
		)
		(pad "P58" smd circle
			(at 18.949924 -26.28011 180)
			(size 0.450088 0.450088)
			(layers "F.Cu" "F.Mask" "F.Paste")
			(net "M_D_CPU1_SA_DQS_DN<6>")
		)
		(pad "P59" smd circle
			(at 19.889978 -26.28011 180)
			(size 0.450088 0.450088)
			(layers "F.Cu" "F.Mask" "F.Paste")
			(net "GND")
		)
		(pad "P60" smd circle
			(at 20.830032 -26.28011 180)
			(size 0.450088 0.450088)
			(layers "F.Cu" "F.Mask" "F.Paste")
			(net "M_D_CPU1_SA_DQS_DN<1>")
		)
		(pad "P61" smd circle
			(at 21.770086 -26.28011 180)
			(size 0.450088 0.450088)
			(layers "F.Cu" "F.Mask" "F.Paste")
			(net "GND")
		)
		(pad "P62" smd circle
			(at 22.709886 -26.28011 180)
			(size 0.450088 0.450088)
			(layers "F.Cu" "F.Mask" "F.Paste")
			(net "M_B_CPU1_SA_DQS_DN<6>")
		)
		(pad "P63" smd circle
			(at 23.64994 -26.28011 180)
			(size 0.450088 0.450088)
			(layers "F.Cu" "F.Mask" "F.Paste")
			(net "M_B_CPU1_SA_DQS_DN<1>")
		)
		(pad "P64" smd circle
			(at 24.589994 -26.28011 180)
			(size 0.450088 0.450088)
			(layers "F.Cu" "F.Mask" "F.Paste")
			(net "PVDDIO_P1")
		)
		(pad "P65" smd circle
			(at 25.530048 -26.28011 180)
			(size 0.450088 0.450088)
			(layers "F.Cu" "F.Mask" "F.Paste")
			(net "M_F_CPU1_SA_DQS_DN<6>")
		)
		(pad "P66" smd circle
			(at 26.470102 -26.28011 180)
			(size 0.450088 0.450088)
			(layers "F.Cu" "F.Mask" "F.Paste")
			(net "GND")
		)
		(pad "P67" smd circle
			(at 27.409902 -26.28011 180)
			(size 0.450088 0.450088)
			(layers "F.Cu" "F.Mask" "F.Paste")
			(net "M_F_CPU1_SA_DQS_DN<1>")
		)
		(pad "P68" smd circle
			(at 28.349956 -26.28011 180)
			(size 0.450088 0.450088)
			(layers "F.Cu" "F.Mask" "F.Paste")
			(net "GND")
		)
		(pad "P69" smd circle
			(at 29.29001 -26.28011 180)
			(size 0.450088 0.450088)
			(layers "F.Cu" "F.Mask" "F.Paste")
			(net "M_E_CPU1_SA_DQS_DN<6>")
		)
		(pad "P70" smd circle
			(at 30.230064 -26.28011 180)
			(size 0.450088 0.450088)
			(layers "F.Cu" "F.Mask" "F.Paste")
			(net "M_E_CPU1_SA_DQS_DN<1>")
		)
		(pad "P71" smd circle
			(at 31.170118 -26.28011 180)
			(size 0.450088 0.450088)
			(layers "F.Cu" "F.Mask" "F.Paste")
			(net "PVDDIO_P1")
		)
		(pad "P72" smd circle
			(at 32.109918 -26.28011 180)
			(size 0.450088 0.450088)
			(layers "F.Cu" "F.Mask" "F.Paste")
			(net "M_A_CPU1_SA_DQS_DN<6>")
		)
		(pad "P73" smd circle
			(at 33.049972 -26.28011 180)
			(size 0.450088 0.450088)
			(layers "F.Cu" "F.Mask" "F.Paste")
			(net "GND")
		)
		(pad "P74" smd circle
			(at 33.990026 -26.28011 180)
			(size 0.450088 0.450088)
			(layers "F.Cu" "F.Mask" "F.Paste")
			(net "M_A_CPU1_SA_DQS_DN<1>")
		)
		(pad "R1" smd circle
			(at -34.159952 -25.470104 180)
			(size 0.450088 0.450088)
			(layers "F.Cu" "F.Mask" "F.Paste")
			(net "GND")
		)
		(pad "R2" smd circle
			(at -33.219898 -25.470104 180)
			(size 0.450088 0.450088)
			(layers "F.Cu" "F.Mask" "F.Paste")
			(net "M_G_CPU1_SA_DQ<12>")
		)
		(pad "R3" smd circle
			(at -32.280098 -25.470104 180)
			(size 0.450088 0.450088)
			(layers "F.Cu" "F.Mask" "F.Paste")
			(net "M_G_CPU1_SA_DQS_DP<6>")
		)
		(pad "R4" smd circle
			(at -31.340044 -25.470104 180)
			(size 0.450088 0.450088)
			(layers "F.Cu" "F.Mask" "F.Paste")
			(net "GND")
		)
		(pad "R5" smd circle
			(at -30.39999 -25.470104 180)
			(size 0.450088 0.450088)
			(layers "F.Cu" "F.Mask" "F.Paste")
			(net "M_K_CPU1_SA_DQ<12>")
		)
		(pad "R6" smd circle
			(at -29.459936 -25.470104 180)
			(size 0.450088 0.450088)
			(layers "F.Cu" "F.Mask" "F.Paste")
			(net "GND")
		)
		(pad "R7" smd circle
			(at -28.519882 -25.470104 180)
			(size 0.450088 0.450088)
			(layers "F.Cu" "F.Mask" "F.Paste")
			(net "M_K_CPU1_SA_DQS_DP<6>")
		)
		(pad "R8" smd circle
			(at -27.580082 -25.470104 180)
			(size 0.450088 0.450088)
			(layers "F.Cu" "F.Mask" "F.Paste")
			(net "GND")
		)
		(pad "R9" smd circle
			(at -26.640028 -25.470104 180)
			(size 0.450088 0.450088)
			(layers "F.Cu" "F.Mask" "F.Paste")
			(net "M_L_CPU1_SA_DQ<12>")
		)
		(pad "R10" smd circle
			(at -25.699974 -25.470104 180)
			(size 0.450088 0.450088)
			(layers "F.Cu" "F.Mask" "F.Paste")
			(net "M_L_CPU1_SA_DQS_DP<6>")
		)
		(pad "R11" smd circle
			(at -24.75992 -25.470104 180)
			(size 0.450088 0.450088)
			(layers "F.Cu" "F.Mask" "F.Paste")
			(net "GND")
		)
		(pad "R12" smd circle
			(at -23.82012 -25.470104 180)
			(size 0.450088 0.450088)
			(layers "F.Cu" "F.Mask" "F.Paste")
			(net "M_H_CPU1_SA_DQ<12>")
		)
		(pad "R13" smd circle
			(at -22.880066 -25.470104 180)
			(size 0.450088 0.450088)
			(layers "F.Cu" "F.Mask" "F.Paste")
			(net "GND")
		)
		(pad "R14" smd circle
			(at -21.940012 -25.470104 180)
			(size 0.450088 0.450088)
			(layers "F.Cu" "F.Mask" "F.Paste")
			(net "M_H_CPU1_SA_DQS_DP<6>")
		)
		(pad "R15" smd circle
			(at -20.999958 -25.470104 180)
			(size 0.450088 0.450088)
			(layers "F.Cu" "F.Mask" "F.Paste")
			(net "GND")
		)
		(pad "R16" smd circle
			(at -20.059904 -25.470104 180)
			(size 0.450088 0.450088)
			(layers "F.Cu" "F.Mask" "F.Paste")
			(net "M_J_CPU1_SA_DQ<12>")
		)
		(pad "R17" smd circle
			(at -19.120104 -25.470104 180)
			(size 0.450088 0.450088)
			(layers "F.Cu" "F.Mask" "F.Paste")
			(net "M_J_CPU1_SA_DQS_DP<6>")
		)
		(pad "R18" smd circle
			(at -18.18005 -25.470104 180)
			(size 0.450088 0.450088)
			(layers "F.Cu" "F.Mask" "F.Paste")
			(net "GND")
		)
		(pad "R19" smd circle
			(at -17.239996 -25.470104 180)
			(size 0.450088 0.450088)
			(layers "F.Cu" "F.Mask" "F.Paste")
			(net "M_I_CPU1_SA_DQ<12>")
		)
		(pad "R20" smd circle
			(at -16.299942 -25.470104 180)
			(size 0.450088 0.450088)
			(layers "F.Cu" "F.Mask" "F.Paste")
			(net "GND")
		)
		(pad "R21" smd circle
			(at -15.359888 -25.470104 180)
			(size 0.450088 0.450088)
			(layers "F.Cu" "F.Mask" "F.Paste")
			(net "M_I_CPU1_SA_DQS_DP<6>")
		)
		(pad "R22" smd circle
			(at -14.420088 -25.470104 180)
			(size 0.450088 0.450088)
			(layers "F.Cu" "F.Mask" "F.Paste")
			(net "GND")
		)
		(pad "R23" smd circle
			(at -13.480034 -25.470104 180)
			(size 0.450088 0.450088)
			(layers "F.Cu" "F.Mask" "F.Paste")
			(net "GMI_CPU1_G3_CPU0_G1_TX_DP<14>")
		)
		(pad "R24" smd circle
			(at -12.53998 -25.470104 180)
			(size 0.450088 0.450088)
			(layers "F.Cu" "F.Mask" "F.Paste")
			(net "GMI_CPU1_G3_CPU0_G1_TX_DN<14>")
		)
		(pad "R25" smd circle
			(at -11.599926 -25.470104 180)
			(size 0.450088 0.450088)
			(layers "F.Cu" "F.Mask" "F.Paste")
			(net "GND")
		)
		(pad "R26" smd circle
			(at -10.659872 -25.470104 180)
			(size 0.450088 0.450088)
			(layers "F.Cu" "F.Mask" "F.Paste")
			(net "GMI_CPU1_G3_CPU0_G1_TX_DP<11>")
		)
		(pad "R27" smd circle
			(at -9.720072 -25.470104 180)
			(size 0.450088 0.450088)
			(layers "F.Cu" "F.Mask" "F.Paste")
			(net "GMI_CPU1_G3_CPU0_G1_TX_DN<11>")
		)
		(pad "R28" smd circle
			(at -8.780018 -25.470104 180)
			(size 0.450088 0.450088)
			(layers "F.Cu" "F.Mask" "F.Paste")
			(net "GND")
		)
		(pad "R29" smd circle
			(at -7.839964 -25.470104 180)
			(size 0.450088 0.450088)
			(layers "F.Cu" "F.Mask" "F.Paste")
			(net "GMI_CPU1_G3_CPU0_G1_TX_DP<8>")
		)
		(pad "R30" smd circle
			(at -6.89991 -25.470104 180)
			(size 0.450088 0.450088)
			(layers "F.Cu" "F.Mask" "F.Paste")
			(net "GMI_CPU1_G3_CPU0_G1_TX_DN<8>")
		)
		(pad "R31" smd circle
			(at -5.96011 -25.470104 180)
			(size 0.450088 0.450088)
			(layers "F.Cu" "F.Mask" "F.Paste")
			(net "GND")
		)
		(pad "R32" smd circle
			(at -5.020056 -25.470104 180)
			(size 0.450088 0.450088)
			(layers "F.Cu" "F.Mask" "F.Paste")
			(net "GMI_CPU1_G3_CPU0_G1_TX_DP<5>")
		)
		(pad "R33" smd circle
			(at -4.080002 -25.470104 180)
			(size 0.450088 0.450088)
			(layers "F.Cu" "F.Mask" "F.Paste")
			(net "GMI_CPU1_G3_CPU0_G1_TX_DN<5>")
		)
		(pad "R34" smd circle
			(at -3.139948 -25.470104 180)
			(size 0.450088 0.450088)
			(layers "F.Cu" "F.Mask" "F.Paste")
			(net "GND")
		)
		(pad "R35" smd circle
			(at -2.199894 -25.470104 180)
			(size 0.450088 0.450088)
			(layers "F.Cu" "F.Mask" "F.Paste")
			(net "GND")
		)
		(pad "R36" smd circle
			(at -1.260094 -25.470104 180)
			(size 0.450088 0.450088)
			(layers "F.Cu" "F.Mask" "F.Paste")
			(net "GND")
		)
		(pad "R40" smd circle
			(at 1.560068 -25.470104 180)
			(size 0.450088 0.450088)
			(layers "F.Cu" "F.Mask" "F.Paste")
			(net "GND")
		)
		(pad "R41" smd circle
			(at 2.500122 -25.470104 180)
			(size 0.450088 0.450088)
			(layers "F.Cu" "F.Mask" "F.Paste")
			(net "GND")
		)
		(pad "R42" smd circle
			(at 3.439922 -25.470104 180)
			(size 0.450088 0.450088)
			(layers "F.Cu" "F.Mask" "F.Paste")
			(net "GND")
		)
		(pad "R43" smd circle
			(at 4.379976 -25.470104 180)
			(size 0.450088 0.450088)
			(layers "F.Cu" "F.Mask" "F.Paste")
			(net "P5E_CPU1_G1_RX_DN<5>")
		)
		(pad "R44" smd circle
			(at 5.32003 -25.470104 180)
			(size 0.450088 0.450088)
			(layers "F.Cu" "F.Mask" "F.Paste")
			(net "P5E_CPU1_G1_RX_DP<5>")
		)
		(pad "R45" smd circle
			(at 6.260084 -25.470104 180)
			(size 0.450088 0.450088)
			(layers "F.Cu" "F.Mask" "F.Paste")
			(net "GND")
		)
		(pad "R46" smd circle
			(at 7.199884 -25.470104 180)
			(size 0.450088 0.450088)
			(layers "F.Cu" "F.Mask" "F.Paste")
			(net "P5E_CPU1_G1_RX_DN<8>")
		)
		(pad "R47" smd circle
			(at 8.139938 -25.470104 180)
			(size 0.450088 0.450088)
			(layers "F.Cu" "F.Mask" "F.Paste")
			(net "P5E_CPU1_G1_RX_DP<8>")
		)
		(pad "R48" smd circle
			(at 9.079992 -25.470104 180)
			(size 0.450088 0.450088)
			(layers "F.Cu" "F.Mask" "F.Paste")
			(net "GND")
		)
		(pad "R49" smd circle
			(at 10.020046 -25.470104 180)
			(size 0.450088 0.450088)
			(layers "F.Cu" "F.Mask" "F.Paste")
			(net "P5E_CPU1_G1_RX_DN<11>")
		)
		(pad "R50" smd circle
			(at 10.9601 -25.470104 180)
			(size 0.450088 0.450088)
			(layers "F.Cu" "F.Mask" "F.Paste")
			(net "P5E_CPU1_G1_RX_DP<11>")
		)
		(pad "R51" smd circle
			(at 11.8999 -25.470104 180)
			(size 0.450088 0.450088)
			(layers "F.Cu" "F.Mask" "F.Paste")
			(net "GND")
		)
		(pad "R52" smd circle
			(at 12.839954 -25.470104 180)
			(size 0.450088 0.450088)
			(layers "F.Cu" "F.Mask" "F.Paste")
			(net "P5E_CPU1_G1_RX_DN<14>")
		)
		(pad "R53" smd circle
			(at 13.780008 -25.470104 180)
			(size 0.450088 0.450088)
			(layers "F.Cu" "F.Mask" "F.Paste")
			(net "P5E_CPU1_G1_RX_DP<14>")
		)
		(pad "R54" smd circle
			(at 14.720062 -25.470104 180)
			(size 0.450088 0.450088)
			(layers "F.Cu" "F.Mask" "F.Paste")
			(net "GND")
		)
		(pad "R55" smd circle
			(at 15.660116 -25.470104 180)
			(size 0.450088 0.450088)
			(layers "F.Cu" "F.Mask" "F.Paste")
			(net "M_C_CPU1_SA_DQS_DP<6>")
		)
		(pad "R56" smd circle
			(at 16.599916 -25.470104 180)
			(size 0.450088 0.450088)
			(layers "F.Cu" "F.Mask" "F.Paste")
			(net "GND")
		)
		(pad "R57" smd circle
			(at 17.53997 -25.470104 180)
			(size 0.450088 0.450088)
			(layers "F.Cu" "F.Mask" "F.Paste")
			(net "M_C_CPU1_SA_DQ<12>")
		)
		(pad "R58" smd circle
			(at 18.480024 -25.470104 180)
			(size 0.450088 0.450088)
			(layers "F.Cu" "F.Mask" "F.Paste")
			(net "GND")
		)
		(pad "R59" smd circle
			(at 19.420078 -25.470104 180)
			(size 0.450088 0.450088)
			(layers "F.Cu" "F.Mask" "F.Paste")
			(net "M_D_CPU1_SA_DQS_DP<6>")
		)
		(pad "R60" smd circle
			(at 20.359878 -25.470104 180)
			(size 0.450088 0.450088)
			(layers "F.Cu" "F.Mask" "F.Paste")
			(net "M_D_CPU1_SA_DQ<12>")
		)
		(pad "R61" smd circle
			(at 21.299932 -25.470104 180)
			(size 0.450088 0.450088)
			(layers "F.Cu" "F.Mask" "F.Paste")
			(net "GND")
		)
		(pad "R62" smd circle
			(at 22.239986 -25.470104 180)
			(size 0.450088 0.450088)
			(layers "F.Cu" "F.Mask" "F.Paste")
			(net "M_B_CPU1_SA_DQS_DP<6>")
		)
		(pad "R63" smd circle
			(at 23.18004 -25.470104 180)
			(size 0.450088 0.450088)
			(layers "F.Cu" "F.Mask" "F.Paste")
			(net "GND")
		)
		(pad "R64" smd circle
			(at 24.120094 -25.470104 180)
			(size 0.450088 0.450088)
			(layers "F.Cu" "F.Mask" "F.Paste")
			(net "M_B_CPU1_SA_DQ<12>")
		)
		(pad "R65" smd circle
			(at 25.059894 -25.470104 180)
			(size 0.450088 0.450088)
			(layers "F.Cu" "F.Mask" "F.Paste")
			(net "GND")
		)
		(pad "R66" smd circle
			(at 25.999948 -25.470104 180)
			(size 0.450088 0.450088)
			(layers "F.Cu" "F.Mask" "F.Paste")
			(net "M_F_CPU1_SA_DQS_DP<6>")
		)
		(pad "R67" smd circle
			(at 26.940002 -25.470104 180)
			(size 0.450088 0.450088)
			(layers "F.Cu" "F.Mask" "F.Paste")
			(net "M_F_CPU1_SA_DQ<12>")
		)
		(pad "R68" smd circle
			(at 27.880056 -25.470104 180)
			(size 0.450088 0.450088)
			(layers "F.Cu" "F.Mask" "F.Paste")
			(net "GND")
		)
		(pad "R69" smd circle
			(at 28.82011 -25.470104 180)
			(size 0.450088 0.450088)
			(layers "F.Cu" "F.Mask" "F.Paste")
			(net "M_E_CPU1_SA_DQS_DP<6>")
		)
		(pad "R70" smd circle
			(at 29.75991 -25.470104 180)
			(size 0.450088 0.450088)
			(layers "F.Cu" "F.Mask" "F.Paste")
			(net "GND")
		)
		(pad "R71" smd circle
			(at 30.699964 -25.470104 180)
			(size 0.450088 0.450088)
			(layers "F.Cu" "F.Mask" "F.Paste")
			(net "M_E_CPU1_SA_DQ<12>")
		)
		(pad "R72" smd circle
			(at 31.640018 -25.470104 180)
			(size 0.450088 0.450088)
			(layers "F.Cu" "F.Mask" "F.Paste")
			(net "GND")
		)
		(pad "R73" smd circle
			(at 32.580072 -25.470104 180)
			(size 0.450088 0.450088)
			(layers "F.Cu" "F.Mask" "F.Paste")
			(net "M_A_CPU1_SA_DQS_DP<6>")
		)
		(pad "R74" smd circle
			(at 33.519872 -25.470104 180)
			(size 0.450088 0.450088)
			(layers "F.Cu" "F.Mask" "F.Paste")
			(net "M_A_CPU1_SA_DQ<12>")
		)
		(pad "R75" smd circle
			(at 34.459926 -25.470104 180)
			(size 0.450088 0.450088)
			(layers "F.Cu" "F.Mask" "F.Paste")
			(net "GND")
		)
		(pad "T2" smd circle
			(at -33.690052 -24.660098 180)
			(size 0.450088 0.450088)
			(layers "F.Cu" "F.Mask" "F.Paste")
			(net "M_G_CPU1_SA_DQ<14>")
		)
		(pad "T3" smd circle
			(at -32.749998 -24.660098 180)
			(size 0.450088 0.450088)
			(layers "F.Cu" "F.Mask" "F.Paste")
			(net "GND")
		)
		(pad "T4" smd circle
			(at -31.809944 -24.660098 180)
			(size 0.450088 0.450088)
			(layers "F.Cu" "F.Mask" "F.Paste")
			(net "M_G_CPU1_SA_DQ<13>")
		)
		(pad "T5" smd circle
			(at -30.86989 -24.660098 180)
			(size 0.450088 0.450088)
			(layers "F.Cu" "F.Mask" "F.Paste")
			(net "GND")
		)
		(pad "T6" smd circle
			(at -29.93009 -24.660098 180)
			(size 0.450088 0.450088)
			(layers "F.Cu" "F.Mask" "F.Paste")
			(net "M_K_CPU1_SA_DQ<14>")
		)
		(pad "T7" smd circle
			(at -28.990036 -24.660098 180)
			(size 0.450088 0.450088)
			(layers "F.Cu" "F.Mask" "F.Paste")
			(net "M_K_CPU1_SA_DQ<13>")
		)
		(pad "T8" smd circle
			(at -28.049982 -24.660098 180)
			(size 0.450088 0.450088)
			(layers "F.Cu" "F.Mask" "F.Paste")
			(net "GND")
		)
		(pad "T9" smd circle
			(at -27.109928 -24.660098 180)
			(size 0.450088 0.450088)
			(layers "F.Cu" "F.Mask" "F.Paste")
			(net "M_L_CPU1_SA_DQ<14>")
		)
		(pad "T10" smd circle
			(at -26.170128 -24.660098 180)
			(size 0.450088 0.450088)
			(layers "F.Cu" "F.Mask" "F.Paste")
			(net "GND")
		)
		(pad "T11" smd circle
			(at -25.230074 -24.660098 180)
			(size 0.450088 0.450088)
			(layers "F.Cu" "F.Mask" "F.Paste")
			(net "M_L_CPU1_SA_DQ<13>")
		)
		(pad "T12" smd circle
			(at -24.29002 -24.660098 180)
			(size 0.450088 0.450088)
			(layers "F.Cu" "F.Mask" "F.Paste")
			(net "GND")
		)
		(pad "T13" smd circle
			(at -23.349966 -24.660098 180)
			(size 0.450088 0.450088)
			(layers "F.Cu" "F.Mask" "F.Paste")
			(net "M_H_CPU1_SA_DQ<14>")
		)
		(pad "T14" smd circle
			(at -22.409912 -24.660098 180)
			(size 0.450088 0.450088)
			(layers "F.Cu" "F.Mask" "F.Paste")
			(net "M_H_CPU1_SA_DQ<13>")
		)
		(pad "T15" smd circle
			(at -21.470112 -24.660098 180)
			(size 0.450088 0.450088)
			(layers "F.Cu" "F.Mask" "F.Paste")
			(net "GND")
		)
		(pad "T16" smd circle
			(at -20.530058 -24.660098 180)
			(size 0.450088 0.450088)
			(layers "F.Cu" "F.Mask" "F.Paste")
			(net "M_J_CPU1_SA_DQ<14>")
		)
		(pad "T17" smd circle
			(at -19.590004 -24.660098 180)
			(size 0.450088 0.450088)
			(layers "F.Cu" "F.Mask" "F.Paste")
			(net "GND")
		)
		(pad "T18" smd circle
			(at -18.64995 -24.660098 180)
			(size 0.450088 0.450088)
			(layers "F.Cu" "F.Mask" "F.Paste")
			(net "M_J_CPU1_SA_DQ<13>")
		)
		(pad "T19" smd circle
			(at -17.709896 -24.660098 180)
			(size 0.450088 0.450088)
			(layers "F.Cu" "F.Mask" "F.Paste")
			(net "GND")
		)
		(pad "T20" smd circle
			(at -16.770096 -24.660098 180)
			(size 0.450088 0.450088)
			(layers "F.Cu" "F.Mask" "F.Paste")
			(net "M_I_CPU1_SA_DQ<14>")
		)
		(pad "T21" smd circle
			(at -15.830042 -24.660098 180)
			(size 0.450088 0.450088)
			(layers "F.Cu" "F.Mask" "F.Paste")
			(net "M_I_CPU1_SA_DQ<13>")
		)
		(pad "T22" smd circle
			(at -14.889988 -24.660098 180)
			(size 0.450088 0.450088)
			(layers "F.Cu" "F.Mask" "F.Paste")
			(net "GND")
		)
		(pad "T23" smd circle
			(at -13.949934 -24.660098 180)
			(size 0.450088 0.450088)
			(layers "F.Cu" "F.Mask" "F.Paste")
			(net "PVDDCR_CPU0_P1")
		)
		(pad "T24" smd circle
			(at -13.00988 -24.660098 180)
			(size 0.450088 0.450088)
			(layers "F.Cu" "F.Mask" "F.Paste")
			(net "PVDDCR_CPU0_P1")
		)
		(pad "T25" smd circle
			(at -12.07008 -24.660098 180)
			(size 0.450088 0.450088)
			(layers "F.Cu" "F.Mask" "F.Paste")
			(net "GND")
		)
		(pad "T26" smd circle
			(at -11.130026 -24.660098 180)
			(size 0.450088 0.450088)
			(layers "F.Cu" "F.Mask" "F.Paste")
			(net "PVDDCR_CPU0_P1")
		)
		(pad "T27" smd circle
			(at -10.189972 -24.660098 180)
			(size 0.450088 0.450088)
			(layers "F.Cu" "F.Mask" "F.Paste")
			(net "PVDDCR_CPU0_P1")
		)
		(pad "T28" smd circle
			(at -9.249918 -24.660098 180)
			(size 0.450088 0.450088)
			(layers "F.Cu" "F.Mask" "F.Paste")
			(net "GND")
		)
		(pad "T29" smd circle
			(at -8.310118 -24.660098 180)
			(size 0.450088 0.450088)
			(layers "F.Cu" "F.Mask" "F.Paste")
			(net "PVDDCR_CPU0_P1")
		)
		(pad "T30" smd circle
			(at -7.370064 -24.660098 180)
			(size 0.450088 0.450088)
			(layers "F.Cu" "F.Mask" "F.Paste")
			(net "PVDDCR_CPU0_P1")
		)
		(pad "T31" smd circle
			(at -6.43001 -24.660098 180)
			(size 0.450088 0.450088)
			(layers "F.Cu" "F.Mask" "F.Paste")
			(net "GND")
		)
		(pad "T32" smd circle
			(at -5.489956 -24.660098 180)
			(size 0.450088 0.450088)
			(layers "F.Cu" "F.Mask" "F.Paste")
			(net "PVDDCR_CPU0_P1")
		)
		(pad "T33" smd circle
			(at -4.549902 -24.660098 180)
			(size 0.450088 0.450088)
			(layers "F.Cu" "F.Mask" "F.Paste")
			(net "PVDDCR_CPU0_P1")
		)
		(pad "T34" smd circle
			(at -3.610102 -24.660098 180)
			(size 0.450088 0.450088)
			(layers "F.Cu" "F.Mask" "F.Paste")
			(net "GND")
		)
		(pad "T35" smd circle
			(at -2.670048 -24.660098 180)
			(size 0.450088 0.450088)
			(layers "F.Cu" "F.Mask" "F.Paste")
			(net "GMI_CPU1_G3_CPU0_G1_TX_DP<1>")
		)
		(pad "T36" smd circle
			(at -1.729994 -24.660098 180)
			(size 0.450088 0.450088)
			(layers "F.Cu" "F.Mask" "F.Paste")
			(net "GMI_CPU1_G3_CPU0_G1_TX_DN<1>")
		)
		(pad "T37" smd circle
			(at -0.78994 -24.660098 180)
			(size 0.450088 0.450088)
			(layers "F.Cu" "F.Mask" "F.Paste")
			(net "GND")
		)
		(pad "T39" smd circle
			(at 1.089914 -24.660098 180)
			(size 0.450088 0.450088)
			(layers "F.Cu" "F.Mask" "F.Paste")
			(net "GND")
		)
		(pad "T40" smd circle
			(at 2.029968 -24.660098 180)
			(size 0.450088 0.450088)
			(layers "F.Cu" "F.Mask" "F.Paste")
			(net "P5E_CPU1_G1_RX_DN<1>")
		)
		(pad "T41" smd circle
			(at 2.970022 -24.660098 180)
			(size 0.450088 0.450088)
			(layers "F.Cu" "F.Mask" "F.Paste")
			(net "P5E_CPU1_G1_RX_DP<1>")
		)
		(pad "T42" smd circle
			(at 3.910076 -24.660098 180)
			(size 0.450088 0.450088)
			(layers "F.Cu" "F.Mask" "F.Paste")
			(net "GND")
		)
		(pad "T43" smd circle
			(at 4.849876 -24.660098 180)
			(size 0.450088 0.450088)
			(layers "F.Cu" "F.Mask" "F.Paste")
			(net "PVDDCR_CPU0_P1")
		)
		(pad "T44" smd circle
			(at 5.78993 -24.660098 180)
			(size 0.450088 0.450088)
			(layers "F.Cu" "F.Mask" "F.Paste")
			(net "PVDDCR_CPU0_P1")
		)
		(pad "T45" smd circle
			(at 6.729984 -24.660098 180)
			(size 0.450088 0.450088)
			(layers "F.Cu" "F.Mask" "F.Paste")
			(net "GND")
		)
		(pad "T46" smd circle
			(at 7.670038 -24.660098 180)
			(size 0.450088 0.450088)
			(layers "F.Cu" "F.Mask" "F.Paste")
			(net "PVDDCR_CPU0_P1")
		)
		(pad "T47" smd circle
			(at 8.610092 -24.660098 180)
			(size 0.450088 0.450088)
			(layers "F.Cu" "F.Mask" "F.Paste")
			(net "PVDDCR_CPU0_P1")
		)
		(pad "T48" smd circle
			(at 9.549892 -24.660098 180)
			(size 0.450088 0.450088)
			(layers "F.Cu" "F.Mask" "F.Paste")
			(net "GND")
		)
		(pad "T49" smd circle
			(at 10.489946 -24.660098 180)
			(size 0.450088 0.450088)
			(layers "F.Cu" "F.Mask" "F.Paste")
			(net "PVDDCR_CPU0_P1")
		)
		(pad "T50" smd circle
			(at 11.43 -24.660098 180)
			(size 0.450088 0.450088)
			(layers "F.Cu" "F.Mask" "F.Paste")
			(net "PVDDCR_CPU0_P1")
		)
		(pad "T51" smd circle
			(at 12.370054 -24.660098 180)
			(size 0.450088 0.450088)
			(layers "F.Cu" "F.Mask" "F.Paste")
			(net "GND")
		)
		(pad "T52" smd circle
			(at 13.310108 -24.660098 180)
			(size 0.450088 0.450088)
			(layers "F.Cu" "F.Mask" "F.Paste")
			(net "PVDDCR_CPU0_P1")
		)
		(pad "T53" smd circle
			(at 14.249908 -24.660098 180)
			(size 0.450088 0.450088)
			(layers "F.Cu" "F.Mask" "F.Paste")
			(net "PVDDCR_CPU0_P1")
		)
		(pad "T54" smd circle
			(at 15.189962 -24.660098 180)
			(size 0.450088 0.450088)
			(layers "F.Cu" "F.Mask" "F.Paste")
			(net "GND")
		)
		(pad "T55" smd circle
			(at 16.130016 -24.660098 180)
			(size 0.450088 0.450088)
			(layers "F.Cu" "F.Mask" "F.Paste")
			(net "M_C_CPU1_SA_DQ<13>")
		)
		(pad "T56" smd circle
			(at 17.07007 -24.660098 180)
			(size 0.450088 0.450088)
			(layers "F.Cu" "F.Mask" "F.Paste")
			(net "M_C_CPU1_SA_DQ<14>")
		)
		(pad "T57" smd circle
			(at 18.010124 -24.660098 180)
			(size 0.450088 0.450088)
			(layers "F.Cu" "F.Mask" "F.Paste")
			(net "GND")
		)
		(pad "T58" smd circle
			(at 18.949924 -24.660098 180)
			(size 0.450088 0.450088)
			(layers "F.Cu" "F.Mask" "F.Paste")
			(net "M_D_CPU1_SA_DQ<13>")
		)
		(pad "T59" smd circle
			(at 19.889978 -24.660098 180)
			(size 0.450088 0.450088)
			(layers "F.Cu" "F.Mask" "F.Paste")
			(net "GND")
		)
		(pad "T60" smd circle
			(at 20.830032 -24.660098 180)
			(size 0.450088 0.450088)
			(layers "F.Cu" "F.Mask" "F.Paste")
			(net "M_D_CPU1_SA_DQ<14>")
		)
		(pad "T61" smd circle
			(at 21.770086 -24.660098 180)
			(size 0.450088 0.450088)
			(layers "F.Cu" "F.Mask" "F.Paste")
			(net "GND")
		)
		(pad "T62" smd circle
			(at 22.709886 -24.660098 180)
			(size 0.450088 0.450088)
			(layers "F.Cu" "F.Mask" "F.Paste")
			(net "M_B_CPU1_SA_DQ<13>")
		)
		(pad "T63" smd circle
			(at 23.64994 -24.660098 180)
			(size 0.450088 0.450088)
			(layers "F.Cu" "F.Mask" "F.Paste")
			(net "M_B_CPU1_SA_DQ<14>")
		)
		(pad "T64" smd circle
			(at 24.589994 -24.660098 180)
			(size 0.450088 0.450088)
			(layers "F.Cu" "F.Mask" "F.Paste")
			(net "GND")
		)
		(pad "T65" smd circle
			(at 25.530048 -24.660098 180)
			(size 0.450088 0.450088)
			(layers "F.Cu" "F.Mask" "F.Paste")
			(net "M_F_CPU1_SA_DQ<13>")
		)
		(pad "T66" smd circle
			(at 26.470102 -24.660098 180)
			(size 0.450088 0.450088)
			(layers "F.Cu" "F.Mask" "F.Paste")
			(net "GND")
		)
		(pad "T67" smd circle
			(at 27.409902 -24.660098 180)
			(size 0.450088 0.450088)
			(layers "F.Cu" "F.Mask" "F.Paste")
			(net "M_F_CPU1_SA_DQ<14>")
		)
		(pad "T68" smd circle
			(at 28.349956 -24.660098 180)
			(size 0.450088 0.450088)
			(layers "F.Cu" "F.Mask" "F.Paste")
			(net "GND")
		)
		(pad "T69" smd circle
			(at 29.29001 -24.660098 180)
			(size 0.450088 0.450088)
			(layers "F.Cu" "F.Mask" "F.Paste")
			(net "M_E_CPU1_SA_DQ<13>")
		)
		(pad "T70" smd circle
			(at 30.230064 -24.660098 180)
			(size 0.450088 0.450088)
			(layers "F.Cu" "F.Mask" "F.Paste")
			(net "M_E_CPU1_SA_DQ<14>")
		)
		(pad "T71" smd circle
			(at 31.170118 -24.660098 180)
			(size 0.450088 0.450088)
			(layers "F.Cu" "F.Mask" "F.Paste")
			(net "GND")
		)
		(pad "T72" smd circle
			(at 32.109918 -24.660098 180)
			(size 0.450088 0.450088)
			(layers "F.Cu" "F.Mask" "F.Paste")
			(net "M_A_CPU1_SA_DQ<13>")
		)
		(pad "T73" smd circle
			(at 33.049972 -24.660098 180)
			(size 0.450088 0.450088)
			(layers "F.Cu" "F.Mask" "F.Paste")
			(net "GND")
		)
		(pad "T74" smd circle
			(at 33.990026 -24.660098 180)
			(size 0.450088 0.450088)
			(layers "F.Cu" "F.Mask" "F.Paste")
			(net "M_A_CPU1_SA_DQ<14>")
		)
		(pad "U1" smd circle
			(at -34.159952 -23.850092 180)
			(size 0.450088 0.450088)
			(layers "F.Cu" "F.Mask" "F.Paste")
			(net "GND")
		)
		(pad "U2" smd circle
			(at -33.219898 -23.850092 180)
			(size 0.450088 0.450088)
			(layers "F.Cu" "F.Mask" "F.Paste")
			(net "M_G_CPU1_SA_DQ<16>")
		)
		(pad "U3" smd circle
			(at -32.280098 -23.850092 180)
			(size 0.450088 0.450088)
			(layers "F.Cu" "F.Mask" "F.Paste")
			(net "M_G_CPU1_SA_DQ<15>")
		)
		(pad "U4" smd circle
			(at -31.340044 -23.850092 180)
			(size 0.450088 0.450088)
			(layers "F.Cu" "F.Mask" "F.Paste")
			(net "PVDDCR_SOC_P1")
		)
		(pad "U5" smd circle
			(at -30.39999 -23.850092 180)
			(size 0.450088 0.450088)
			(layers "F.Cu" "F.Mask" "F.Paste")
			(net "M_K_CPU1_SA_DQ<16>")
		)
		(pad "U6" smd circle
			(at -29.459936 -23.850092 180)
			(size 0.450088 0.450088)
			(layers "F.Cu" "F.Mask" "F.Paste")
			(net "GND")
		)
		(pad "U7" smd circle
			(at -28.519882 -23.850092 180)
			(size 0.450088 0.450088)
			(layers "F.Cu" "F.Mask" "F.Paste")
			(net "M_K_CPU1_SA_DQ<15>")
		)
		(pad "U8" smd circle
			(at -27.580082 -23.850092 180)
			(size 0.450088 0.450088)
			(layers "F.Cu" "F.Mask" "F.Paste")
			(net "GND")
		)
		(pad "U9" smd circle
			(at -26.640028 -23.850092 180)
			(size 0.450088 0.450088)
			(layers "F.Cu" "F.Mask" "F.Paste")
			(net "M_L_CPU1_SA_DQ<16>")
		)
		(pad "U10" smd circle
			(at -25.699974 -23.850092 180)
			(size 0.450088 0.450088)
			(layers "F.Cu" "F.Mask" "F.Paste")
			(net "M_L_CPU1_SA_DQ<15>")
		)
		(pad "U11" smd circle
			(at -24.75992 -23.850092 180)
			(size 0.450088 0.450088)
			(layers "F.Cu" "F.Mask" "F.Paste")
			(net "PVDDCR_SOC_P1")
		)
		(pad "U12" smd circle
			(at -23.82012 -23.850092 180)
			(size 0.450088 0.450088)
			(layers "F.Cu" "F.Mask" "F.Paste")
			(net "M_H_CPU1_SA_DQ<16>")
		)
		(pad "U13" smd circle
			(at -22.880066 -23.850092 180)
			(size 0.450088 0.450088)
			(layers "F.Cu" "F.Mask" "F.Paste")
			(net "GND")
		)
		(pad "U14" smd circle
			(at -21.940012 -23.850092 180)
			(size 0.450088 0.450088)
			(layers "F.Cu" "F.Mask" "F.Paste")
			(net "M_H_CPU1_SA_DQ<15>")
		)
		(pad "U15" smd circle
			(at -20.999958 -23.850092 180)
			(size 0.450088 0.450088)
			(layers "F.Cu" "F.Mask" "F.Paste")
			(net "GND")
		)
		(pad "U16" smd circle
			(at -20.059904 -23.850092 180)
			(size 0.450088 0.450088)
			(layers "F.Cu" "F.Mask" "F.Paste")
			(net "M_J_CPU1_SA_DQ<16>")
		)
		(pad "U17" smd circle
			(at -19.120104 -23.850092 180)
			(size 0.450088 0.450088)
			(layers "F.Cu" "F.Mask" "F.Paste")
			(net "M_J_CPU1_SA_DQ<15>")
		)
		(pad "U18" smd circle
			(at -18.18005 -23.850092 180)
			(size 0.450088 0.450088)
			(layers "F.Cu" "F.Mask" "F.Paste")
			(net "PVDDCR_SOC_P1")
		)
		(pad "U19" smd circle
			(at -17.239996 -23.850092 180)
			(size 0.450088 0.450088)
			(layers "F.Cu" "F.Mask" "F.Paste")
			(net "M_I_CPU1_SA_DQ<16>")
		)
		(pad "U20" smd circle
			(at -16.299942 -23.850092 180)
			(size 0.450088 0.450088)
			(layers "F.Cu" "F.Mask" "F.Paste")
			(net "GND")
		)
		(pad "U21" smd circle
			(at -15.359888 -23.850092 180)
			(size 0.450088 0.450088)
			(layers "F.Cu" "F.Mask" "F.Paste")
			(net "M_I_CPU1_SA_DQ<15>")
		)
		(pad "U22" smd circle
			(at -14.420088 -23.850092 180)
			(size 0.450088 0.450088)
			(layers "F.Cu" "F.Mask" "F.Paste")
			(net "GND")
		)
		(pad "U23" smd circle
			(at -13.480034 -23.850092 180)
			(size 0.450088 0.450088)
			(layers "F.Cu" "F.Mask" "F.Paste")
			(net "GMI_CPU1_G3_CPU0_G1_TX_DP<15>")
		)
		(pad "U24" smd circle
			(at -12.53998 -23.850092 180)
			(size 0.450088 0.450088)
			(layers "F.Cu" "F.Mask" "F.Paste")
			(net "GMI_CPU1_G3_CPU0_G1_TX_DN<15>")
		)
		(pad "U25" smd circle
			(at -11.599926 -23.850092 180)
			(size 0.450088 0.450088)
			(layers "F.Cu" "F.Mask" "F.Paste")
			(net "GND")
		)
		(pad "U26" smd circle
			(at -10.659872 -23.850092 180)
			(size 0.450088 0.450088)
			(layers "F.Cu" "F.Mask" "F.Paste")
			(net "GMI_CPU1_G3_CPU0_G1_TX_DP<12>")
		)
		(pad "U27" smd circle
			(at -9.720072 -23.850092 180)
			(size 0.450088 0.450088)
			(layers "F.Cu" "F.Mask" "F.Paste")
			(net "GMI_CPU1_G3_CPU0_G1_TX_DN<12>")
		)
		(pad "U28" smd circle
			(at -8.780018 -23.850092 180)
			(size 0.450088 0.450088)
			(layers "F.Cu" "F.Mask" "F.Paste")
			(net "GND")
		)
		(pad "U29" smd circle
			(at -7.839964 -23.850092 180)
			(size 0.450088 0.450088)
			(layers "F.Cu" "F.Mask" "F.Paste")
			(net "GMI_CPU1_G3_CPU0_G1_TX_DP<6>")
		)
		(pad "U30" smd circle
			(at -6.89991 -23.850092 180)
			(size 0.450088 0.450088)
			(layers "F.Cu" "F.Mask" "F.Paste")
			(net "GMI_CPU1_G3_CPU0_G1_TX_DN<6>")
		)
		(pad "U31" smd circle
			(at -5.96011 -23.850092 180)
			(size 0.450088 0.450088)
			(layers "F.Cu" "F.Mask" "F.Paste")
			(net "GND")
		)
		(pad "U32" smd circle
			(at -5.020056 -23.850092 180)
			(size 0.450088 0.450088)
			(layers "F.Cu" "F.Mask" "F.Paste")
			(net "GMI_CPU1_G3_CPU0_G1_TX_DP<3>")
		)
		(pad "U33" smd circle
			(at -4.080002 -23.850092 180)
			(size 0.450088 0.450088)
			(layers "F.Cu" "F.Mask" "F.Paste")
			(net "GMI_CPU1_G3_CPU0_G1_TX_DN<3>")
		)
		(pad "U34" smd circle
			(at -3.139948 -23.850092 180)
			(size 0.450088 0.450088)
			(layers "F.Cu" "F.Mask" "F.Paste")
			(net "GND")
		)
		(pad "U35" smd circle
			(at -2.199894 -23.850092 180)
			(size 0.450088 0.450088)
			(layers "F.Cu" "F.Mask" "F.Paste")
			(net "PVDDCR_CPU0_P1")
		)
		(pad "U36" smd circle
			(at -1.260094 -23.850092 180)
			(size 0.450088 0.450088)
			(layers "F.Cu" "F.Mask" "F.Paste")
			(net "PVDDCR_CPU0_P1")
		)
		(pad "U40" smd circle
			(at 1.560068 -23.850092 180)
			(size 0.450088 0.450088)
			(layers "F.Cu" "F.Mask" "F.Paste")
			(net "PVDDCR_CPU0_P1")
		)
		(pad "U41" smd circle
			(at 2.500122 -23.850092 180)
			(size 0.450088 0.450088)
			(layers "F.Cu" "F.Mask" "F.Paste")
			(net "PVDDCR_CPU0_P1")
		)
		(pad "U42" smd circle
			(at 3.439922 -23.850092 180)
			(size 0.450088 0.450088)
			(layers "F.Cu" "F.Mask" "F.Paste")
			(net "GND")
		)
		(pad "U43" smd circle
			(at 4.379976 -23.850092 180)
			(size 0.450088 0.450088)
			(layers "F.Cu" "F.Mask" "F.Paste")
			(net "P5E_CPU1_G1_RX_DN<3>")
		)
		(pad "U44" smd circle
			(at 5.32003 -23.850092 180)
			(size 0.450088 0.450088)
			(layers "F.Cu" "F.Mask" "F.Paste")
			(net "P5E_CPU1_G1_RX_DP<3>")
		)
		(pad "U45" smd circle
			(at 6.260084 -23.850092 180)
			(size 0.450088 0.450088)
			(layers "F.Cu" "F.Mask" "F.Paste")
			(net "GND")
		)
		(pad "U46" smd circle
			(at 7.199884 -23.850092 180)
			(size 0.450088 0.450088)
			(layers "F.Cu" "F.Mask" "F.Paste")
			(net "P5E_CPU1_G1_RX_DN<6>")
		)
		(pad "U47" smd circle
			(at 8.139938 -23.850092 180)
			(size 0.450088 0.450088)
			(layers "F.Cu" "F.Mask" "F.Paste")
			(net "P5E_CPU1_G1_RX_DP<6>")
		)
		(pad "U48" smd circle
			(at 9.079992 -23.850092 180)
			(size 0.450088 0.450088)
			(layers "F.Cu" "F.Mask" "F.Paste")
			(net "GND")
		)
		(pad "U49" smd circle
			(at 10.020046 -23.850092 180)
			(size 0.450088 0.450088)
			(layers "F.Cu" "F.Mask" "F.Paste")
			(net "P5E_CPU1_G1_RX_DN<12>")
		)
		(pad "U50" smd circle
			(at 10.9601 -23.850092 180)
			(size 0.450088 0.450088)
			(layers "F.Cu" "F.Mask" "F.Paste")
			(net "P5E_CPU1_G1_RX_DP<12>")
		)
		(pad "U51" smd circle
			(at 11.8999 -23.850092 180)
			(size 0.450088 0.450088)
			(layers "F.Cu" "F.Mask" "F.Paste")
			(net "GND")
		)
		(pad "U52" smd circle
			(at 12.839954 -23.850092 180)
			(size 0.450088 0.450088)
			(layers "F.Cu" "F.Mask" "F.Paste")
			(net "P5E_CPU1_G1_RX_DN<15>")
		)
		(pad "U53" smd circle
			(at 13.780008 -23.850092 180)
			(size 0.450088 0.450088)
			(layers "F.Cu" "F.Mask" "F.Paste")
			(net "P5E_CPU1_G1_RX_DP<15>")
		)
		(pad "U54" smd circle
			(at 14.720062 -23.850092 180)
			(size 0.450088 0.450088)
			(layers "F.Cu" "F.Mask" "F.Paste")
			(net "GND")
		)
		(pad "U55" smd circle
			(at 15.660116 -23.850092 180)
			(size 0.450088 0.450088)
			(layers "F.Cu" "F.Mask" "F.Paste")
			(net "M_C_CPU1_SA_DQ<15>")
		)
		(pad "U56" smd circle
			(at 16.599916 -23.850092 180)
			(size 0.450088 0.450088)
			(layers "F.Cu" "F.Mask" "F.Paste")
			(net "GND")
		)
		(pad "U57" smd circle
			(at 17.53997 -23.850092 180)
			(size 0.450088 0.450088)
			(layers "F.Cu" "F.Mask" "F.Paste")
			(net "M_C_CPU1_SA_DQ<16>")
		)
		(pad "U58" smd circle
			(at 18.480024 -23.850092 180)
			(size 0.450088 0.450088)
			(layers "F.Cu" "F.Mask" "F.Paste")
			(net "PVDDIO_P1")
		)
		(pad "U59" smd circle
			(at 19.420078 -23.850092 180)
			(size 0.450088 0.450088)
			(layers "F.Cu" "F.Mask" "F.Paste")
			(net "M_D_CPU1_SA_DQ<15>")
		)
		(pad "U60" smd circle
			(at 20.359878 -23.850092 180)
			(size 0.450088 0.450088)
			(layers "F.Cu" "F.Mask" "F.Paste")
			(net "M_D_CPU1_SA_DQ<16>")
		)
		(pad "U61" smd circle
			(at 21.299932 -23.850092 180)
			(size 0.450088 0.450088)
			(layers "F.Cu" "F.Mask" "F.Paste")
			(net "GND")
		)
		(pad "U62" smd circle
			(at 22.239986 -23.850092 180)
			(size 0.450088 0.450088)
			(layers "F.Cu" "F.Mask" "F.Paste")
			(net "M_B_CPU1_SA_DQ<15>")
		)
		(pad "U63" smd circle
			(at 23.18004 -23.850092 180)
			(size 0.450088 0.450088)
			(layers "F.Cu" "F.Mask" "F.Paste")
			(net "GND")
		)
		(pad "U64" smd circle
			(at 24.120094 -23.850092 180)
			(size 0.450088 0.450088)
			(layers "F.Cu" "F.Mask" "F.Paste")
			(net "M_B_CPU1_SA_DQ<16>")
		)
		(pad "U65" smd circle
			(at 25.059894 -23.850092 180)
			(size 0.450088 0.450088)
			(layers "F.Cu" "F.Mask" "F.Paste")
			(net "PVDDIO_P1")
		)
		(pad "U66" smd circle
			(at 25.999948 -23.850092 180)
			(size 0.450088 0.450088)
			(layers "F.Cu" "F.Mask" "F.Paste")
			(net "M_F_CPU1_SA_DQ<15>")
		)
		(pad "U67" smd circle
			(at 26.940002 -23.850092 180)
			(size 0.450088 0.450088)
			(layers "F.Cu" "F.Mask" "F.Paste")
			(net "M_F_CPU1_SA_DQ<16>")
		)
		(pad "U68" smd circle
			(at 27.880056 -23.850092 180)
			(size 0.450088 0.450088)
			(layers "F.Cu" "F.Mask" "F.Paste")
			(net "GND")
		)
		(pad "U69" smd circle
			(at 28.82011 -23.850092 180)
			(size 0.450088 0.450088)
			(layers "F.Cu" "F.Mask" "F.Paste")
			(net "M_E_CPU1_SA_DQ<15>")
		)
		(pad "U70" smd circle
			(at 29.75991 -23.850092 180)
			(size 0.450088 0.450088)
			(layers "F.Cu" "F.Mask" "F.Paste")
			(net "GND")
		)
		(pad "U71" smd circle
			(at 30.699964 -23.850092 180)
			(size 0.450088 0.450088)
			(layers "F.Cu" "F.Mask" "F.Paste")
			(net "M_E_CPU1_SA_DQ<16>")
		)
		(pad "U72" smd circle
			(at 31.640018 -23.850092 180)
			(size 0.450088 0.450088)
			(layers "F.Cu" "F.Mask" "F.Paste")
			(net "PVDDIO_P1")
		)
		(pad "U73" smd circle
			(at 32.580072 -23.850092 180)
			(size 0.450088 0.450088)
			(layers "F.Cu" "F.Mask" "F.Paste")
			(net "M_A_CPU1_SA_DQ<15>")
		)
		(pad "U74" smd circle
			(at 33.519872 -23.850092 180)
			(size 0.450088 0.450088)
			(layers "F.Cu" "F.Mask" "F.Paste")
			(net "M_A_CPU1_SA_DQ<16>")
		)
		(pad "U75" smd circle
			(at 34.459926 -23.850092 180)
			(size 0.450088 0.450088)
			(layers "F.Cu" "F.Mask" "F.Paste")
			(net "GND")
		)
		(pad "V2" smd circle
			(at -33.690052 -23.040086 180)
			(size 0.450088 0.450088)
			(layers "F.Cu" "F.Mask" "F.Paste")
			(net "M_G_CPU1_SA_DQ<18>")
		)
		(pad "V3" smd circle
			(at -32.749998 -23.040086 180)
			(size 0.450088 0.450088)
			(layers "F.Cu" "F.Mask" "F.Paste")
			(net "GND")
		)
		(pad "V4" smd circle
			(at -31.809944 -23.040086 180)
			(size 0.450088 0.450088)
			(layers "F.Cu" "F.Mask" "F.Paste")
			(net "M_G_CPU1_SA_DQ<17>")
		)
		(pad "V5" smd circle
			(at -30.86989 -23.040086 180)
			(size 0.450088 0.450088)
			(layers "F.Cu" "F.Mask" "F.Paste")
			(net "GND")
		)
		(pad "V6" smd circle
			(at -29.93009 -23.040086 180)
			(size 0.450088 0.450088)
			(layers "F.Cu" "F.Mask" "F.Paste")
			(net "M_K_CPU1_SA_DQ<18>")
		)
		(pad "V7" smd circle
			(at -28.990036 -23.040086 180)
			(size 0.450088 0.450088)
			(layers "F.Cu" "F.Mask" "F.Paste")
			(net "M_K_CPU1_SA_DQ<17>")
		)
		(pad "V8" smd circle
			(at -28.049982 -23.040086 180)
			(size 0.450088 0.450088)
			(layers "F.Cu" "F.Mask" "F.Paste")
			(net "GND")
		)
		(pad "V9" smd circle
			(at -27.109928 -23.040086 180)
			(size 0.450088 0.450088)
			(layers "F.Cu" "F.Mask" "F.Paste")
			(net "M_L_CPU1_SA_DQ<18>")
		)
		(pad "V10" smd circle
			(at -26.170128 -23.040086 180)
			(size 0.450088 0.450088)
			(layers "F.Cu" "F.Mask" "F.Paste")
			(net "GND")
		)
		(pad "V11" smd circle
			(at -25.230074 -23.040086 180)
			(size 0.450088 0.450088)
			(layers "F.Cu" "F.Mask" "F.Paste")
			(net "M_L_CPU1_SA_DQ<17>")
		)
		(pad "V12" smd circle
			(at -24.29002 -23.040086 180)
			(size 0.450088 0.450088)
			(layers "F.Cu" "F.Mask" "F.Paste")
			(net "GND")
		)
		(pad "V13" smd circle
			(at -23.349966 -23.040086 180)
			(size 0.450088 0.450088)
			(layers "F.Cu" "F.Mask" "F.Paste")
			(net "M_H_CPU1_SA_DQ<18>")
		)
		(pad "V14" smd circle
			(at -22.409912 -23.040086 180)
			(size 0.450088 0.450088)
			(layers "F.Cu" "F.Mask" "F.Paste")
			(net "M_H_CPU1_SA_DQ<17>")
		)
		(pad "V15" smd circle
			(at -21.470112 -23.040086 180)
			(size 0.450088 0.450088)
			(layers "F.Cu" "F.Mask" "F.Paste")
			(net "GND")
		)
		(pad "V16" smd circle
			(at -20.530058 -23.040086 180)
			(size 0.450088 0.450088)
			(layers "F.Cu" "F.Mask" "F.Paste")
			(net "M_J_CPU1_SA_DQ<18>")
		)
		(pad "V17" smd circle
			(at -19.590004 -23.040086 180)
			(size 0.450088 0.450088)
			(layers "F.Cu" "F.Mask" "F.Paste")
			(net "GND")
		)
		(pad "V18" smd circle
			(at -18.64995 -23.040086 180)
			(size 0.450088 0.450088)
			(layers "F.Cu" "F.Mask" "F.Paste")
			(net "M_J_CPU1_SA_DQ<17>")
		)
		(pad "V19" smd circle
			(at -17.709896 -23.040086 180)
			(size 0.450088 0.450088)
			(layers "F.Cu" "F.Mask" "F.Paste")
			(net "GND")
		)
		(pad "V20" smd circle
			(at -16.770096 -23.040086 180)
			(size 0.450088 0.450088)
			(layers "F.Cu" "F.Mask" "F.Paste")
			(net "M_I_CPU1_SA_DQ<18>")
		)
		(pad "V21" smd circle
			(at -15.830042 -23.040086 180)
			(size 0.450088 0.450088)
			(layers "F.Cu" "F.Mask" "F.Paste")
			(net "M_I_CPU1_SA_DQ<17>")
		)
		(pad "V22" smd circle
			(at -14.889988 -23.040086 180)
			(size 0.450088 0.450088)
			(layers "F.Cu" "F.Mask" "F.Paste")
			(net "PVDDCR_SOC_P1")
		)
		(pad "V23" smd circle
			(at -13.949934 -23.040086 180)
			(size 0.450088 0.450088)
			(layers "F.Cu" "F.Mask" "F.Paste")
			(net "GND")
		)
		(pad "V24" smd circle
			(at -13.00988 -23.040086 180)
			(size 0.450088 0.450088)
			(layers "F.Cu" "F.Mask" "F.Paste")
			(net "GND")
		)
		(pad "V25" smd circle
			(at -12.07008 -23.040086 180)
			(size 0.450088 0.450088)
			(layers "F.Cu" "F.Mask" "F.Paste")
			(net "GND")
		)
		(pad "V26" smd circle
			(at -11.130026 -23.040086 180)
			(size 0.450088 0.450088)
			(layers "F.Cu" "F.Mask" "F.Paste")
			(net "GND")
		)
		(pad "V27" smd circle
			(at -10.189972 -23.040086 180)
			(size 0.450088 0.450088)
			(layers "F.Cu" "F.Mask" "F.Paste")
			(net "GND")
		)
		(pad "V28" smd circle
			(at -9.249918 -23.040086 180)
			(size 0.450088 0.450088)
			(layers "F.Cu" "F.Mask" "F.Paste")
			(net "GND")
		)
		(pad "V29" smd circle
			(at -8.310118 -23.040086 180)
			(size 0.450088 0.450088)
			(layers "F.Cu" "F.Mask" "F.Paste")
			(net "GND")
		)
		(pad "V30" smd circle
			(at -7.370064 -23.040086 180)
			(size 0.450088 0.450088)
			(layers "F.Cu" "F.Mask" "F.Paste")
			(net "GND")
		)
		(pad "V31" smd circle
			(at -6.43001 -23.040086 180)
			(size 0.450088 0.450088)
			(layers "F.Cu" "F.Mask" "F.Paste")
			(net "GND")
		)
		(pad "V32" smd circle
			(at -5.489956 -23.040086 180)
			(size 0.450088 0.450088)
			(layers "F.Cu" "F.Mask" "F.Paste")
			(net "GND")
		)
		(pad "V33" smd circle
			(at -4.549902 -23.040086 180)
			(size 0.450088 0.450088)
			(layers "F.Cu" "F.Mask" "F.Paste")
			(net "GND")
		)
		(pad "V34" smd circle
			(at -3.610102 -23.040086 180)
			(size 0.450088 0.450088)
			(layers "F.Cu" "F.Mask" "F.Paste")
			(net "GND")
		)
		(pad "V35" smd circle
			(at -2.670048 -23.040086 180)
			(size 0.450088 0.450088)
			(layers "F.Cu" "F.Mask" "F.Paste")
			(net "GMI_CPU1_G3_CPU0_G1_TX_DP<0>")
		)
		(pad "V36" smd circle
			(at -1.729994 -23.040086 180)
			(size 0.450088 0.450088)
			(layers "F.Cu" "F.Mask" "F.Paste")
			(net "GMI_CPU1_G3_CPU0_G1_TX_DN<0>")
		)
		(pad "V37" smd circle
			(at -0.78994 -23.040086 180)
			(size 0.450088 0.450088)
			(layers "F.Cu" "F.Mask" "F.Paste")
			(net "GND")
		)
		(pad "V39" smd circle
			(at 1.089914 -23.040086 180)
			(size 0.450088 0.450088)
			(layers "F.Cu" "F.Mask" "F.Paste")
			(net "GND")
		)
		(pad "V40" smd circle
			(at 2.029968 -23.040086 180)
			(size 0.450088 0.450088)
			(layers "F.Cu" "F.Mask" "F.Paste")
			(net "P5E_CPU1_G1_RX_DN<0>")
		)
		(pad "V41" smd circle
			(at 2.970022 -23.040086 180)
			(size 0.450088 0.450088)
			(layers "F.Cu" "F.Mask" "F.Paste")
			(net "P5E_CPU1_G1_RX_DP<0>")
		)
		(pad "V42" smd circle
			(at 3.910076 -23.040086 180)
			(size 0.450088 0.450088)
			(layers "F.Cu" "F.Mask" "F.Paste")
			(net "GND")
		)
		(pad "V43" smd circle
			(at 4.849876 -23.040086 180)
			(size 0.450088 0.450088)
			(layers "F.Cu" "F.Mask" "F.Paste")
			(net "GND")
		)
		(pad "V44" smd circle
			(at 5.78993 -23.040086 180)
			(size 0.450088 0.450088)
			(layers "F.Cu" "F.Mask" "F.Paste")
			(net "GND")
		)
		(pad "V45" smd circle
			(at 6.729984 -23.040086 180)
			(size 0.450088 0.450088)
			(layers "F.Cu" "F.Mask" "F.Paste")
			(net "GND")
		)
		(pad "V46" smd circle
			(at 7.670038 -23.040086 180)
			(size 0.450088 0.450088)
			(layers "F.Cu" "F.Mask" "F.Paste")
			(net "GND")
		)
		(pad "V47" smd circle
			(at 8.610092 -23.040086 180)
			(size 0.450088 0.450088)
			(layers "F.Cu" "F.Mask" "F.Paste")
			(net "GND")
		)
		(pad "V48" smd circle
			(at 9.549892 -23.040086 180)
			(size 0.450088 0.450088)
			(layers "F.Cu" "F.Mask" "F.Paste")
			(net "GND")
		)
		(pad "V49" smd circle
			(at 10.489946 -23.040086 180)
			(size 0.450088 0.450088)
			(layers "F.Cu" "F.Mask" "F.Paste")
			(net "GND")
		)
		(pad "V50" smd circle
			(at 11.43 -23.040086 180)
			(size 0.450088 0.450088)
			(layers "F.Cu" "F.Mask" "F.Paste")
			(net "GND")
		)
		(pad "V51" smd circle
			(at 12.370054 -23.040086 180)
			(size 0.450088 0.450088)
			(layers "F.Cu" "F.Mask" "F.Paste")
			(net "GND")
		)
		(pad "V52" smd circle
			(at 13.310108 -23.040086 180)
			(size 0.450088 0.450088)
			(layers "F.Cu" "F.Mask" "F.Paste")
			(net "GND")
		)
		(pad "V53" smd circle
			(at 14.249908 -23.040086 180)
			(size 0.450088 0.450088)
			(layers "F.Cu" "F.Mask" "F.Paste")
			(net "GND")
		)
		(pad "V54" smd circle
			(at 15.189962 -23.040086 180)
			(size 0.450088 0.450088)
			(layers "F.Cu" "F.Mask" "F.Paste")
			(net "PVDDIO_P1")
		)
		(pad "V55" smd circle
			(at 16.130016 -23.040086 180)
			(size 0.450088 0.450088)
			(layers "F.Cu" "F.Mask" "F.Paste")
			(net "M_C_CPU1_SA_DQ<17>")
		)
		(pad "V56" smd circle
			(at 17.07007 -23.040086 180)
			(size 0.450088 0.450088)
			(layers "F.Cu" "F.Mask" "F.Paste")
			(net "M_C_CPU1_SA_DQ<18>")
		)
		(pad "V57" smd circle
			(at 18.010124 -23.040086 180)
			(size 0.450088 0.450088)
			(layers "F.Cu" "F.Mask" "F.Paste")
			(net "GND")
		)
		(pad "V58" smd circle
			(at 18.949924 -23.040086 180)
			(size 0.450088 0.450088)
			(layers "F.Cu" "F.Mask" "F.Paste")
			(net "M_D_CPU1_SA_DQ<17>")
		)
		(pad "V59" smd circle
			(at 19.889978 -23.040086 180)
			(size 0.450088 0.450088)
			(layers "F.Cu" "F.Mask" "F.Paste")
			(net "GND")
		)
		(pad "V60" smd circle
			(at 20.830032 -23.040086 180)
			(size 0.450088 0.450088)
			(layers "F.Cu" "F.Mask" "F.Paste")
			(net "M_D_CPU1_SA_DQ<18>")
		)
		(pad "V61" smd circle
			(at 21.770086 -23.040086 180)
			(size 0.450088 0.450088)
			(layers "F.Cu" "F.Mask" "F.Paste")
			(net "GND")
		)
		(pad "V62" smd circle
			(at 22.709886 -23.040086 180)
			(size 0.450088 0.450088)
			(layers "F.Cu" "F.Mask" "F.Paste")
			(net "M_B_CPU1_SA_DQ<17>")
		)
		(pad "V63" smd circle
			(at 23.64994 -23.040086 180)
			(size 0.450088 0.450088)
			(layers "F.Cu" "F.Mask" "F.Paste")
			(net "M_B_CPU1_SA_DQ<18>")
		)
		(pad "V64" smd circle
			(at 24.589994 -23.040086 180)
			(size 0.450088 0.450088)
			(layers "F.Cu" "F.Mask" "F.Paste")
			(net "GND")
		)
		(pad "V65" smd circle
			(at 25.530048 -23.040086 180)
			(size 0.450088 0.450088)
			(layers "F.Cu" "F.Mask" "F.Paste")
			(net "M_F_CPU1_SA_DQ<17>")
		)
		(pad "V66" smd circle
			(at 26.470102 -23.040086 180)
			(size 0.450088 0.450088)
			(layers "F.Cu" "F.Mask" "F.Paste")
			(net "GND")
		)
		(pad "V67" smd circle
			(at 27.409902 -23.040086 180)
			(size 0.450088 0.450088)
			(layers "F.Cu" "F.Mask" "F.Paste")
			(net "M_F_CPU1_SA_DQ<18>")
		)
		(pad "V68" smd circle
			(at 28.349956 -23.040086 180)
			(size 0.450088 0.450088)
			(layers "F.Cu" "F.Mask" "F.Paste")
			(net "GND")
		)
		(pad "V69" smd circle
			(at 29.29001 -23.040086 180)
			(size 0.450088 0.450088)
			(layers "F.Cu" "F.Mask" "F.Paste")
			(net "M_E_CPU1_SA_DQ<17>")
		)
		(pad "V70" smd circle
			(at 30.230064 -23.040086 180)
			(size 0.450088 0.450088)
			(layers "F.Cu" "F.Mask" "F.Paste")
			(net "M_E_CPU1_SA_DQ<18>")
		)
		(pad "V71" smd circle
			(at 31.170118 -23.040086 180)
			(size 0.450088 0.450088)
			(layers "F.Cu" "F.Mask" "F.Paste")
			(net "GND")
		)
		(pad "V72" smd circle
			(at 32.109918 -23.040086 180)
			(size 0.450088 0.450088)
			(layers "F.Cu" "F.Mask" "F.Paste")
			(net "M_A_CPU1_SA_DQ<17>")
		)
		(pad "V73" smd circle
			(at 33.049972 -23.040086 180)
			(size 0.450088 0.450088)
			(layers "F.Cu" "F.Mask" "F.Paste")
			(net "GND")
		)
		(pad "V74" smd circle
			(at 33.990026 -23.040086 180)
			(size 0.450088 0.450088)
			(layers "F.Cu" "F.Mask" "F.Paste")
			(net "M_A_CPU1_SA_DQ<18>")
		)
		(pad "W1" smd circle
			(at -34.159952 -22.23008 180)
			(size 0.450088 0.450088)
			(layers "F.Cu" "F.Mask" "F.Paste")
			(net "GND")
		)
		(pad "W2" smd circle
			(at -33.219898 -22.23008 180)
			(size 0.450088 0.450088)
			(layers "F.Cu" "F.Mask" "F.Paste")
			(net "M_G_CPU1_SA_DQS_DP<2>")
		)
		(pad "W3" smd circle
			(at -32.280098 -22.23008 180)
			(size 0.450088 0.450088)
			(layers "F.Cu" "F.Mask" "F.Paste")
			(net "M_G_CPU1_SA_DQ<19>")
		)
		(pad "W4" smd circle
			(at -31.340044 -22.23008 180)
			(size 0.450088 0.450088)
			(layers "F.Cu" "F.Mask" "F.Paste")
			(net "GND")
		)
		(pad "W5" smd circle
			(at -30.39999 -22.23008 180)
			(size 0.450088 0.450088)
			(layers "F.Cu" "F.Mask" "F.Paste")
			(net "M_K_CPU1_SA_DQS_DP<2>")
		)
		(pad "W6" smd circle
			(at -29.459936 -22.23008 180)
			(size 0.450088 0.450088)
			(layers "F.Cu" "F.Mask" "F.Paste")
			(net "GND")
		)
		(pad "W7" smd circle
			(at -28.519882 -22.23008 180)
			(size 0.450088 0.450088)
			(layers "F.Cu" "F.Mask" "F.Paste")
			(net "M_K_CPU1_SA_DQ<19>")
		)
		(pad "W8" smd circle
			(at -27.580082 -22.23008 180)
			(size 0.450088 0.450088)
			(layers "F.Cu" "F.Mask" "F.Paste")
			(net "GND")
		)
		(pad "W9" smd circle
			(at -26.640028 -22.23008 180)
			(size 0.450088 0.450088)
			(layers "F.Cu" "F.Mask" "F.Paste")
			(net "M_L_CPU1_SA_DQS_DP<2>")
		)
		(pad "W10" smd circle
			(at -25.699974 -22.23008 180)
			(size 0.450088 0.450088)
			(layers "F.Cu" "F.Mask" "F.Paste")
			(net "M_L_CPU1_SA_DQ<19>")
		)
		(pad "W11" smd circle
			(at -24.75992 -22.23008 180)
			(size 0.450088 0.450088)
			(layers "F.Cu" "F.Mask" "F.Paste")
			(net "GND")
		)
		(pad "W12" smd circle
			(at -23.82012 -22.23008 180)
			(size 0.450088 0.450088)
			(layers "F.Cu" "F.Mask" "F.Paste")
			(net "M_H_CPU1_SA_DQS_DP<2>")
		)
		(pad "W13" smd circle
			(at -22.880066 -22.23008 180)
			(size 0.450088 0.450088)
			(layers "F.Cu" "F.Mask" "F.Paste")
			(net "GND")
		)
		(pad "W14" smd circle
			(at -21.940012 -22.23008 180)
			(size 0.450088 0.450088)
			(layers "F.Cu" "F.Mask" "F.Paste")
			(net "M_H_CPU1_SA_DQ<19>")
		)
		(pad "W15" smd circle
			(at -20.999958 -22.23008 180)
			(size 0.450088 0.450088)
			(layers "F.Cu" "F.Mask" "F.Paste")
			(net "GND")
		)
		(pad "W16" smd circle
			(at -20.059904 -22.23008 180)
			(size 0.450088 0.450088)
			(layers "F.Cu" "F.Mask" "F.Paste")
			(net "M_J_CPU1_SA_DQS_DP<2>")
		)
		(pad "W17" smd circle
			(at -19.120104 -22.23008 180)
			(size 0.450088 0.450088)
			(layers "F.Cu" "F.Mask" "F.Paste")
			(net "M_J_CPU1_SA_DQ<19>")
		)
		(pad "W18" smd circle
			(at -18.18005 -22.23008 180)
			(size 0.450088 0.450088)
			(layers "F.Cu" "F.Mask" "F.Paste")
			(net "GND")
		)
		(pad "W19" smd circle
			(at -17.239996 -22.23008 180)
			(size 0.450088 0.450088)
			(layers "F.Cu" "F.Mask" "F.Paste")
			(net "M_I_CPU1_SA_DQS_DP<2>")
		)
		(pad "W20" smd circle
			(at -16.299942 -22.23008 180)
			(size 0.450088 0.450088)
			(layers "F.Cu" "F.Mask" "F.Paste")
			(net "GND")
		)
		(pad "W21" smd circle
			(at -15.359888 -22.23008 180)
			(size 0.450088 0.450088)
			(layers "F.Cu" "F.Mask" "F.Paste")
			(net "M_I_CPU1_SA_DQ<19>")
		)
		(pad "W22" smd circle
			(at -14.420088 -22.23008 180)
			(size 0.450088 0.450088)
			(layers "F.Cu" "F.Mask" "F.Paste")
			(net "GND")
		)
		(pad "W23" smd circle
			(at -13.480034 -22.23008 180)
			(size 0.450088 0.450088)
			(layers "F.Cu" "F.Mask" "F.Paste")
			(net "GMI_CPU1_G3_CPU0_G1_TX_DP<13>")
		)
		(pad "W24" smd circle
			(at -12.53998 -22.23008 180)
			(size 0.450088 0.450088)
			(layers "F.Cu" "F.Mask" "F.Paste")
			(net "GMI_CPU1_G3_CPU0_G1_TX_DN<13>")
		)
		(pad "W25" smd circle
			(at -11.599926 -22.23008 180)
			(size 0.450088 0.450088)
			(layers "F.Cu" "F.Mask" "F.Paste")
			(net "GND")
		)
		(pad "W26" smd circle
			(at -10.659872 -22.23008 180)
			(size 0.450088 0.450088)
			(layers "F.Cu" "F.Mask" "F.Paste")
			(net "GMI_CPU1_G3_CPU0_G1_TX_DP<9>")
		)
		(pad "W27" smd circle
			(at -9.720072 -22.23008 180)
			(size 0.450088 0.450088)
			(layers "F.Cu" "F.Mask" "F.Paste")
			(net "GMI_CPU1_G3_CPU0_G1_TX_DN<9>")
		)
		(pad "W28" smd circle
			(at -8.780018 -22.23008 180)
			(size 0.450088 0.450088)
			(layers "F.Cu" "F.Mask" "F.Paste")
			(net "GND")
		)
		(pad "W29" smd circle
			(at -7.839964 -22.23008 180)
			(size 0.450088 0.450088)
			(layers "F.Cu" "F.Mask" "F.Paste")
			(net "PVDDCR_CPU0_P1")
		)
		(pad "W30" smd circle
			(at -6.89991 -22.23008 180)
			(size 0.450088 0.450088)
			(layers "F.Cu" "F.Mask" "F.Paste")
			(net "PVDDCR_CPU0_P1")
		)
		(pad "W31" smd circle
			(at -5.96011 -22.23008 180)
			(size 0.450088 0.450088)
			(layers "F.Cu" "F.Mask" "F.Paste")
			(net "TP_CPU1_TEST41_IOD")
		)
		(pad "W32" smd circle
			(at -5.020056 -22.23008 180)
			(size 0.450088 0.450088)
			(layers "F.Cu" "F.Mask" "F.Paste")
			(net "PVDDCR_CPU0_P1")
		)
		(pad "W33" smd circle
			(at -4.080002 -22.23008 180)
			(size 0.450088 0.450088)
			(layers "F.Cu" "F.Mask" "F.Paste")
			(net "PVDDCR_CPU0_P1")
		)
		(pad "W34" smd circle
			(at -3.139948 -22.23008 180)
			(size 0.450088 0.450088)
			(layers "F.Cu" "F.Mask" "F.Paste")
			(net "GND")
		)
		(pad "W35" smd circle
			(at -2.199894 -22.23008 180)
			(size 0.450088 0.450088)
			(layers "F.Cu" "F.Mask" "F.Paste")
			(net "GND")
		)
		(pad "W36" smd circle
			(at -1.260094 -22.23008 180)
			(size 0.450088 0.450088)
			(layers "F.Cu" "F.Mask" "F.Paste")
			(net "GND")
		)
		(pad "W40" smd circle
			(at 1.560068 -22.23008 180)
			(size 0.450088 0.450088)
			(layers "F.Cu" "F.Mask" "F.Paste")
			(net "GND")
		)
		(pad "W41" smd circle
			(at 2.500122 -22.23008 180)
			(size 0.450088 0.450088)
			(layers "F.Cu" "F.Mask" "F.Paste")
			(net "GND")
		)
		(pad "W42" smd circle
			(at 3.439922 -22.23008 180)
			(size 0.450088 0.450088)
			(layers "F.Cu" "F.Mask" "F.Paste")
			(net "GND")
		)
		(pad "W43" smd circle
			(at 4.379976 -22.23008 180)
			(size 0.450088 0.450088)
			(layers "F.Cu" "F.Mask" "F.Paste")
			(net "PVDDCR_CPU0_P1")
		)
		(pad "W44" smd circle
			(at 5.32003 -22.23008 180)
			(size 0.450088 0.450088)
			(layers "F.Cu" "F.Mask" "F.Paste")
			(net "PVDDCR_CPU0_P1")
		)
		(pad "W45" smd circle
			(at 6.260084 -22.23008 180)
			(size 0.450088 0.450088)
			(layers "F.Cu" "F.Mask" "F.Paste")
			(net "GND")
		)
		(pad "W46" smd circle
			(at 7.199884 -22.23008 180)
			(size 0.450088 0.450088)
			(layers "F.Cu" "F.Mask" "F.Paste")
			(net "PVDDCR_CPU0_P1")
		)
		(pad "W47" smd circle
			(at 8.139938 -22.23008 180)
			(size 0.450088 0.450088)
			(layers "F.Cu" "F.Mask" "F.Paste")
			(net "PVDDCR_CPU0_P1")
		)
		(pad "W48" smd circle
			(at 9.079992 -22.23008 180)
			(size 0.450088 0.450088)
			(layers "F.Cu" "F.Mask" "F.Paste")
			(net "GND")
		)
		(pad "W49" smd circle
			(at 10.020046 -22.23008 180)
			(size 0.450088 0.450088)
			(layers "F.Cu" "F.Mask" "F.Paste")
			(net "P5E_CPU1_G1_RX_DN<9>")
		)
		(pad "W50" smd circle
			(at 10.9601 -22.23008 180)
			(size 0.450088 0.450088)
			(layers "F.Cu" "F.Mask" "F.Paste")
			(net "P5E_CPU1_G1_RX_DP<9>")
		)
		(pad "W51" smd circle
			(at 11.8999 -22.23008 180)
			(size 0.450088 0.450088)
			(layers "F.Cu" "F.Mask" "F.Paste")
			(net "GND")
		)
		(pad "W52" smd circle
			(at 12.839954 -22.23008 180)
			(size 0.450088 0.450088)
			(layers "F.Cu" "F.Mask" "F.Paste")
			(net "P5E_CPU1_G1_RX_DN<13>")
		)
		(pad "W53" smd circle
			(at 13.780008 -22.23008 180)
			(size 0.450088 0.450088)
			(layers "F.Cu" "F.Mask" "F.Paste")
			(net "P5E_CPU1_G1_RX_DP<13>")
		)
		(pad "W54" smd circle
			(at 14.720062 -22.23008 180)
			(size 0.450088 0.450088)
			(layers "F.Cu" "F.Mask" "F.Paste")
			(net "GND")
		)
		(pad "W55" smd circle
			(at 15.660116 -22.23008 180)
			(size 0.450088 0.450088)
			(layers "F.Cu" "F.Mask" "F.Paste")
			(net "M_C_CPU1_SA_DQ<19>")
		)
		(pad "W56" smd circle
			(at 16.599916 -22.23008 180)
			(size 0.450088 0.450088)
			(layers "F.Cu" "F.Mask" "F.Paste")
			(net "GND")
		)
		(pad "W57" smd circle
			(at 17.53997 -22.23008 180)
			(size 0.450088 0.450088)
			(layers "F.Cu" "F.Mask" "F.Paste")
			(net "M_C_CPU1_SA_DQS_DP<2>")
		)
		(pad "W58" smd circle
			(at 18.480024 -22.23008 180)
			(size 0.450088 0.450088)
			(layers "F.Cu" "F.Mask" "F.Paste")
			(net "GND")
		)
		(pad "W59" smd circle
			(at 19.420078 -22.23008 180)
			(size 0.450088 0.450088)
			(layers "F.Cu" "F.Mask" "F.Paste")
			(net "M_D_CPU1_SA_DQ<19>")
		)
		(pad "W60" smd circle
			(at 20.359878 -22.23008 180)
			(size 0.450088 0.450088)
			(layers "F.Cu" "F.Mask" "F.Paste")
			(net "M_D_CPU1_SA_DQS_DP<2>")
		)
		(pad "W61" smd circle
			(at 21.299932 -22.23008 180)
			(size 0.450088 0.450088)
			(layers "F.Cu" "F.Mask" "F.Paste")
			(net "GND")
		)
		(pad "W62" smd circle
			(at 22.239986 -22.23008 180)
			(size 0.450088 0.450088)
			(layers "F.Cu" "F.Mask" "F.Paste")
			(net "M_B_CPU1_SA_DQ<19>")
		)
		(pad "W63" smd circle
			(at 23.18004 -22.23008 180)
			(size 0.450088 0.450088)
			(layers "F.Cu" "F.Mask" "F.Paste")
			(net "GND")
		)
		(pad "W64" smd circle
			(at 24.120094 -22.23008 180)
			(size 0.450088 0.450088)
			(layers "F.Cu" "F.Mask" "F.Paste")
			(net "M_B_CPU1_SA_DQS_DP<2>")
		)
		(pad "W65" smd circle
			(at 25.059894 -22.23008 180)
			(size 0.450088 0.450088)
			(layers "F.Cu" "F.Mask" "F.Paste")
			(net "GND")
		)
		(pad "W66" smd circle
			(at 25.999948 -22.23008 180)
			(size 0.450088 0.450088)
			(layers "F.Cu" "F.Mask" "F.Paste")
			(net "M_F_CPU1_SA_DQ<19>")
		)
		(pad "W67" smd circle
			(at 26.940002 -22.23008 180)
			(size 0.450088 0.450088)
			(layers "F.Cu" "F.Mask" "F.Paste")
			(net "M_F_CPU1_SA_DQS_DP<2>")
		)
		(pad "W68" smd circle
			(at 27.880056 -22.23008 180)
			(size 0.450088 0.450088)
			(layers "F.Cu" "F.Mask" "F.Paste")
			(net "GND")
		)
		(pad "W69" smd circle
			(at 28.82011 -22.23008 180)
			(size 0.450088 0.450088)
			(layers "F.Cu" "F.Mask" "F.Paste")
			(net "M_E_CPU1_SA_DQ<19>")
		)
		(pad "W70" smd circle
			(at 29.75991 -22.23008 180)
			(size 0.450088 0.450088)
			(layers "F.Cu" "F.Mask" "F.Paste")
			(net "GND")
		)
		(pad "W71" smd circle
			(at 30.699964 -22.23008 180)
			(size 0.450088 0.450088)
			(layers "F.Cu" "F.Mask" "F.Paste")
			(net "M_E_CPU1_SA_DQS_DP<2>")
		)
		(pad "W72" smd circle
			(at 31.640018 -22.23008 180)
			(size 0.450088 0.450088)
			(layers "F.Cu" "F.Mask" "F.Paste")
			(net "GND")
		)
		(pad "W73" smd circle
			(at 32.580072 -22.23008 180)
			(size 0.450088 0.450088)
			(layers "F.Cu" "F.Mask" "F.Paste")
			(net "M_A_CPU1_SA_DQ<19>")
		)
		(pad "W74" smd circle
			(at 33.519872 -22.23008 180)
			(size 0.450088 0.450088)
			(layers "F.Cu" "F.Mask" "F.Paste")
			(net "M_A_CPU1_SA_DQS_DP<2>")
		)
		(pad "W75" smd circle
			(at 34.459926 -22.23008 180)
			(size 0.450088 0.450088)
			(layers "F.Cu" "F.Mask" "F.Paste")
			(net "GND")
		)
		(pad "Y2" smd circle
			(at -33.690052 -21.420074 180)
			(size 0.450088 0.450088)
			(layers "F.Cu" "F.Mask" "F.Paste")
			(net "M_G_CPU1_SA_DQS_DN<2>")
		)
		(pad "Y3" smd circle
			(at -32.749998 -21.420074 180)
			(size 0.450088 0.450088)
			(layers "F.Cu" "F.Mask" "F.Paste")
			(net "GND")
		)
		(pad "Y4" smd circle
			(at -31.809944 -21.420074 180)
			(size 0.450088 0.450088)
			(layers "F.Cu" "F.Mask" "F.Paste")
			(net "M_G_CPU1_SA_DQS_DN<7>")
		)
		(pad "Y5" smd circle
			(at -30.86989 -21.420074 180)
			(size 0.450088 0.450088)
			(layers "F.Cu" "F.Mask" "F.Paste")
			(net "PVDDCR_SOC_P1")
		)
		(pad "Y6" smd circle
			(at -29.93009 -21.420074 180)
			(size 0.450088 0.450088)
			(layers "F.Cu" "F.Mask" "F.Paste")
			(net "M_K_CPU1_SA_DQS_DN<2>")
		)
		(pad "Y7" smd circle
			(at -28.990036 -21.420074 180)
			(size 0.450088 0.450088)
			(layers "F.Cu" "F.Mask" "F.Paste")
			(net "M_K_CPU1_SA_DQS_DN<7>")
		)
		(pad "Y8" smd circle
			(at -28.049982 -21.420074 180)
			(size 0.450088 0.450088)
			(layers "F.Cu" "F.Mask" "F.Paste")
			(net "GND")
		)
		(pad "Y9" smd circle
			(at -27.109928 -21.420074 180)
			(size 0.450088 0.450088)
			(layers "F.Cu" "F.Mask" "F.Paste")
			(net "M_L_CPU1_SA_DQS_DN<2>")
		)
		(pad "Y10" smd circle
			(at -26.170128 -21.420074 180)
			(size 0.450088 0.450088)
			(layers "F.Cu" "F.Mask" "F.Paste")
			(net "GND")
		)
		(pad "Y11" smd circle
			(at -25.230074 -21.420074 180)
			(size 0.450088 0.450088)
			(layers "F.Cu" "F.Mask" "F.Paste")
			(net "M_L_CPU1_SA_DQS_DN<7>")
		)
		(pad "Y12" smd circle
			(at -24.29002 -21.420074 180)
			(size 0.450088 0.450088)
			(layers "F.Cu" "F.Mask" "F.Paste")
			(net "PVDDCR_SOC_P1")
		)
		(pad "Y13" smd circle
			(at -23.349966 -21.420074 180)
			(size 0.450088 0.450088)
			(layers "F.Cu" "F.Mask" "F.Paste")
			(net "M_H_CPU1_SA_DQS_DN<2>")
		)
		(pad "Y14" smd circle
			(at -22.409912 -21.420074 180)
			(size 0.450088 0.450088)
			(layers "F.Cu" "F.Mask" "F.Paste")
			(net "M_H_CPU1_SA_DQS_DN<7>")
		)
		(pad "Y15" smd circle
			(at -21.470112 -21.420074 180)
			(size 0.450088 0.450088)
			(layers "F.Cu" "F.Mask" "F.Paste")
			(net "GND")
		)
		(pad "Y16" smd circle
			(at -20.530058 -21.420074 180)
			(size 0.450088 0.450088)
			(layers "F.Cu" "F.Mask" "F.Paste")
			(net "M_J_CPU1_SA_DQS_DN<2>")
		)
		(pad "Y17" smd circle
			(at -19.590004 -21.420074 180)
			(size 0.450088 0.450088)
			(layers "F.Cu" "F.Mask" "F.Paste")
			(net "GND")
		)
		(pad "Y18" smd circle
			(at -18.64995 -21.420074 180)
			(size 0.450088 0.450088)
			(layers "F.Cu" "F.Mask" "F.Paste")
			(net "M_J_CPU1_SA_DQS_DN<7>")
		)
		(pad "Y19" smd circle
			(at -17.709896 -21.420074 180)
			(size 0.450088 0.450088)
			(layers "F.Cu" "F.Mask" "F.Paste")
			(net "PVDDCR_SOC_P1")
		)
		(pad "Y20" smd circle
			(at -16.770096 -21.420074 180)
			(size 0.450088 0.450088)
			(layers "F.Cu" "F.Mask" "F.Paste")
			(net "M_I_CPU1_SA_DQS_DN<2>")
		)
		(pad "Y21" smd circle
			(at -15.830042 -21.420074 180)
			(size 0.450088 0.450088)
			(layers "F.Cu" "F.Mask" "F.Paste")
			(net "M_I_CPU1_SA_DQS_DN<7>")
		)
		(pad "Y22" smd circle
			(at -14.889988 -21.420074 180)
			(size 0.450088 0.450088)
			(layers "F.Cu" "F.Mask" "F.Paste")
			(net "GND")
		)
		(pad "Y23" smd circle
			(at -13.949934 -21.420074 180)
			(size 0.450088 0.450088)
			(layers "F.Cu" "F.Mask" "F.Paste")
			(net "GND")
		)
		(pad "Y24" smd circle
			(at -13.00988 -21.420074 180)
			(size 0.450088 0.450088)
			(layers "F.Cu" "F.Mask" "F.Paste")
			(net "GND")
		)
		(pad "Y25" smd circle
			(at -12.07008 -21.420074 180)
			(size 0.450088 0.450088)
			(layers "F.Cu" "F.Mask" "F.Paste")
			(net "GND")
		)
		(pad "Y26" smd circle
			(at -11.130026 -21.420074 180)
			(size 0.450088 0.450088)
			(layers "F.Cu" "F.Mask" "F.Paste")
			(net "GND")
		)
		(pad "Y27" smd circle
			(at -10.189972 -21.420074 180)
			(size 0.450088 0.450088)
			(layers "F.Cu" "F.Mask" "F.Paste")
			(net "GND")
		)
		(pad "Y28" smd circle
			(at -9.249918 -21.420074 180)
			(size 0.450088 0.450088)
			(layers "F.Cu" "F.Mask" "F.Paste")
			(net "GND")
		)
		(pad "Y29" smd circle
			(at -8.310118 -21.420074 180)
			(size 0.450088 0.450088)
			(layers "F.Cu" "F.Mask" "F.Paste")
			(net "TP_CPU1_TEST5_CCD11")
		)
		(pad "Y30" smd circle
			(at -7.370064 -21.420074 180)
			(size 0.450088 0.450088)
			(layers "F.Cu" "F.Mask" "F.Paste")
			(net "TP_CPU1_TEST5_CCD3")
		)
		(pad "Y31" smd circle
			(at -6.43001 -21.420074 180)
			(size 0.450088 0.450088)
			(layers "F.Cu" "F.Mask" "F.Paste")
			(net "GND")
		)
		(pad "Y32" smd circle
			(at -5.489956 -21.420074 180)
			(size 0.450088 0.450088)
			(layers "F.Cu" "F.Mask" "F.Paste")
			(net "GND")
		)
		(pad "Y33" smd circle
			(at -4.549902 -21.420074 180)
			(size 0.450088 0.450088)
			(layers "F.Cu" "F.Mask" "F.Paste")
			(net "GND")
		)
		(pad "Y34" smd circle
			(at -3.610102 -21.420074 180)
			(size 0.450088 0.450088)
			(layers "F.Cu" "F.Mask" "F.Paste")
			(net "GND")
		)
		(pad "Y35" smd circle
			(at -2.670048 -21.420074 180)
			(size 0.450088 0.450088)
			(layers "F.Cu" "F.Mask" "F.Paste")
			(net "PVDDCR_CPU0_P1")
		)
		(pad "Y36" smd circle
			(at -1.729994 -21.420074 180)
			(size 0.450088 0.450088)
			(layers "F.Cu" "F.Mask" "F.Paste")
			(net "PVDDCR_CPU0_P1")
		)
		(pad "Y37" smd circle
			(at -0.78994 -21.420074 180)
			(size 0.450088 0.450088)
			(layers "F.Cu" "F.Mask" "F.Paste")
			(net "GND")
		)
		(pad "Y39" smd circle
			(at 1.089914 -21.420074 180)
			(size 0.450088 0.450088)
			(layers "F.Cu" "F.Mask" "F.Paste")
			(net "GND")
		)
		(pad "Y40" smd circle
			(at 2.029968 -21.420074 180)
			(size 0.450088 0.450088)
			(layers "F.Cu" "F.Mask" "F.Paste")
			(net "PVDDCR_CPU0_P1")
		)
		(pad "Y41" smd circle
			(at 2.970022 -21.420074 180)
			(size 0.450088 0.450088)
			(layers "F.Cu" "F.Mask" "F.Paste")
			(net "PVDDCR_CPU0_P1")
		)
		(pad "Y42" smd circle
			(at 3.910076 -21.420074 180)
			(size 0.450088 0.450088)
			(layers "F.Cu" "F.Mask" "F.Paste")
			(net "GND")
		)
		(pad "Y43" smd circle
			(at 4.849876 -21.420074 180)
			(size 0.450088 0.450088)
			(layers "F.Cu" "F.Mask" "F.Paste")
			(net "GND")
		)
		(pad "Y44" smd circle
			(at 5.78993 -21.420074 180)
			(size 0.450088 0.450088)
			(layers "F.Cu" "F.Mask" "F.Paste")
			(net "GND")
		)
		(pad "Y45" smd circle
			(at 6.729984 -21.420074 180)
			(size 0.450088 0.450088)
			(layers "F.Cu" "F.Mask" "F.Paste")
			(net "GND")
		)
		(pad "Y46" smd circle
			(at 7.670038 -21.420074 180)
			(size 0.450088 0.450088)
			(layers "F.Cu" "F.Mask" "F.Paste")
			(net "TP_CPU1_TEST6_CCD3")
		)
		(pad "Y47" smd circle
			(at 8.610092 -21.420074 180)
			(size 0.450088 0.450088)
			(layers "F.Cu" "F.Mask" "F.Paste")
			(net "TP_CPU1_TEST5_CCD8")
		)
		(pad "Y48" smd circle
			(at 9.549892 -21.420074 180)
			(size 0.450088 0.450088)
			(layers "F.Cu" "F.Mask" "F.Paste")
			(net "GND")
		)
		(pad "Y49" smd circle
			(at 10.489946 -21.420074 180)
			(size 0.450088 0.450088)
			(layers "F.Cu" "F.Mask" "F.Paste")
			(net "GND")
		)
		(pad "Y50" smd circle
			(at 11.43 -21.420074 180)
			(size 0.450088 0.450088)
			(layers "F.Cu" "F.Mask" "F.Paste")
			(net "GND")
		)
		(pad "Y51" smd circle
			(at 12.370054 -21.420074 180)
			(size 0.450088 0.450088)
			(layers "F.Cu" "F.Mask" "F.Paste")
			(net "GND")
		)
		(pad "Y52" smd circle
			(at 13.310108 -21.420074 180)
			(size 0.450088 0.450088)
			(layers "F.Cu" "F.Mask" "F.Paste")
			(net "GND")
		)
		(pad "Y53" smd circle
			(at 14.249908 -21.420074 180)
			(size 0.450088 0.450088)
			(layers "F.Cu" "F.Mask" "F.Paste")
			(net "GND")
		)
		(pad "Y54" smd circle
			(at 15.189962 -21.420074 180)
			(size 0.450088 0.450088)
			(layers "F.Cu" "F.Mask" "F.Paste")
			(net "GND")
		)
		(pad "Y55" smd circle
			(at 16.130016 -21.420074 180)
			(size 0.450088 0.450088)
			(layers "F.Cu" "F.Mask" "F.Paste")
			(net "M_C_CPU1_SA_DQS_DN<7>")
		)
		(pad "Y56" smd circle
			(at 17.07007 -21.420074 180)
			(size 0.450088 0.450088)
			(layers "F.Cu" "F.Mask" "F.Paste")
			(net "M_C_CPU1_SA_DQS_DN<2>")
		)
		(pad "Y57" smd circle
			(at 18.010124 -21.420074 180)
			(size 0.450088 0.450088)
			(layers "F.Cu" "F.Mask" "F.Paste")
			(net "PVDDIO_P1")
		)
		(pad "Y58" smd circle
			(at 18.949924 -21.420074 180)
			(size 0.450088 0.450088)
			(layers "F.Cu" "F.Mask" "F.Paste")
			(net "M_D_CPU1_SA_DQS_DN<7>")
		)
		(pad "Y59" smd circle
			(at 19.889978 -21.420074 180)
			(size 0.450088 0.450088)
			(layers "F.Cu" "F.Mask" "F.Paste")
			(net "GND")
		)
		(pad "Y60" smd circle
			(at 20.830032 -21.420074 180)
			(size 0.450088 0.450088)
			(layers "F.Cu" "F.Mask" "F.Paste")
			(net "M_D_CPU1_SA_DQS_DN<2>")
		)
		(pad "Y61" smd circle
			(at 21.770086 -21.420074 180)
			(size 0.450088 0.450088)
			(layers "F.Cu" "F.Mask" "F.Paste")
			(net "GND")
		)
		(pad "Y62" smd circle
			(at 22.709886 -21.420074 180)
			(size 0.450088 0.450088)
			(layers "F.Cu" "F.Mask" "F.Paste")
			(net "M_B_CPU1_SA_DQS_DN<7>")
		)
		(pad "Y63" smd circle
			(at 23.64994 -21.420074 180)
			(size 0.450088 0.450088)
			(layers "F.Cu" "F.Mask" "F.Paste")
			(net "M_B_CPU1_SA_DQS_DN<2>")
		)
		(pad "Y64" smd circle
			(at 24.589994 -21.420074 180)
			(size 0.450088 0.450088)
			(layers "F.Cu" "F.Mask" "F.Paste")
			(net "PVDDIO_P1")
		)
		(pad "Y65" smd circle
			(at 25.530048 -21.420074 180)
			(size 0.450088 0.450088)
			(layers "F.Cu" "F.Mask" "F.Paste")
			(net "M_F_CPU1_SA_DQS_DN<7>")
		)
		(pad "Y66" smd circle
			(at 26.470102 -21.420074 180)
			(size 0.450088 0.450088)
			(layers "F.Cu" "F.Mask" "F.Paste")
			(net "GND")
		)
		(pad "Y67" smd circle
			(at 27.409902 -21.420074 180)
			(size 0.450088 0.450088)
			(layers "F.Cu" "F.Mask" "F.Paste")
			(net "M_F_CPU1_SA_DQS_DN<2>")
		)
		(pad "Y68" smd circle
			(at 28.349956 -21.420074 180)
			(size 0.450088 0.450088)
			(layers "F.Cu" "F.Mask" "F.Paste")
			(net "GND")
		)
		(pad "Y69" smd circle
			(at 29.29001 -21.420074 180)
			(size 0.450088 0.450088)
			(layers "F.Cu" "F.Mask" "F.Paste")
			(net "M_E_CPU1_SA_DQS_DN<7>")
		)
		(pad "Y70" smd circle
			(at 30.230064 -21.420074 180)
			(size 0.450088 0.450088)
			(layers "F.Cu" "F.Mask" "F.Paste")
			(net "M_E_CPU1_SA_DQS_DN<2>")
		)
		(pad "Y71" smd circle
			(at 31.170118 -21.420074 180)
			(size 0.450088 0.450088)
			(layers "F.Cu" "F.Mask" "F.Paste")
			(net "PVDDIO_P1")
		)
		(pad "Y72" smd circle
			(at 32.109918 -21.420074 180)
			(size 0.450088 0.450088)
			(layers "F.Cu" "F.Mask" "F.Paste")
			(net "M_A_CPU1_SA_DQS_DN<7>")
		)
		(pad "Y73" smd circle
			(at 33.049972 -21.420074 180)
			(size 0.450088 0.450088)
			(layers "F.Cu" "F.Mask" "F.Paste")
			(net "GND")
		)
		(pad "Y74" smd circle
			(at 33.990026 -21.420074 180)
			(size 0.450088 0.450088)
			(layers "F.Cu" "F.Mask" "F.Paste")
			(net "M_A_CPU1_SA_DQS_DN<2>")
		)
		(zone
			(layers "F.Cu" "B.Cu" "In1.Cu" "In2.Cu" "In3.Cu" "In4.Cu" "In5.Cu" "In6.Cu"
				"In7.Cu" "In8.Cu" "In9.Cu" "In10.Cu" "In11.Cu" "In12.Cu" "In13.Cu" "In14.Cu"
				"In15.Cu" "In16.Cu"
			)
			(hatch none 0.5)
			(connect_pads
				(clearance 0)
			)
			(min_thickness 0.25)
			(keepout
				(tracks not_allowed)
				(vias allowed)
				(pads allowed)
				(copperpour not_allowed)
				(footprints allowed)
			)
			(placement
				(enabled no)
				(sheetname "")
			)
			(fill
				(thermal_gap 0.5)
				(thermal_bridge_width 0.5)
				(island_removal_mode 0)
			)
			(polygon
				(pts
					(arc
						(start 72.342502 -258.880356)
						(mid 67.313302 -258.880356)
						(end 72.342502 -258.880356)
					)
				)
			)
		)
		(zone
			(layers "F.Cu" "B.Cu" "In1.Cu" "In2.Cu" "In3.Cu" "In4.Cu" "In5.Cu" "In6.Cu"
				"In7.Cu" "In8.Cu" "In9.Cu" "In10.Cu" "In11.Cu" "In12.Cu" "In13.Cu" "In14.Cu"
				"In15.Cu" "In16.Cu"
			)
			(hatch none 0.5)
			(connect_pads
				(clearance 0)
			)
			(min_thickness 0.25)
			(keepout
				(tracks not_allowed)
				(vias allowed)
				(pads allowed)
				(copperpour not_allowed)
				(footprints allowed)
			)
			(placement
				(enabled no)
				(sheetname "")
			)
			(fill
				(thermal_gap 0.5)
				(thermal_bridge_width 0.5)
				(island_removal_mode 0)
			)
			(polygon
				(pts
					(arc
						(start 83.842352 -304.780442)
						(mid 78.81366 -304.780442)
						(end 83.842352 -304.780442)
					)
				)
			)
		)
		(zone
			(layers "F.Cu" "B.Cu" "In1.Cu" "In2.Cu" "In3.Cu" "In4.Cu" "In5.Cu" "In6.Cu"
				"In7.Cu" "In8.Cu" "In9.Cu" "In10.Cu" "In11.Cu" "In12.Cu" "In13.Cu" "In14.Cu"
				"In15.Cu" "In16.Cu"
			)
			(hatch none 0.5)
			(connect_pads
				(clearance 0)
			)
			(min_thickness 0.25)
			(keepout
				(tracks not_allowed)
				(vias allowed)
				(pads allowed)
				(copperpour not_allowed)
				(footprints allowed)
			)
			(placement
				(enabled no)
				(sheetname "")
			)
			(fill
				(thermal_gap 0.5)
				(thermal_bridge_width 0.5)
				(island_removal_mode 0)
			)
			(polygon
				(pts
					(arc
						(start 83.842352 -212.98027)
						(mid 78.81366 -212.98027)
						(end 83.842352 -212.98027)
					)
				)
			)
		)
		(zone
			(layers "F.Cu" "B.Cu" "In1.Cu" "In2.Cu" "In3.Cu" "In4.Cu" "In5.Cu" "In6.Cu"
				"In7.Cu" "In8.Cu" "In9.Cu" "In10.Cu" "In11.Cu" "In12.Cu" "In13.Cu" "In14.Cu"
				"In15.Cu" "In16.Cu"
			)
			(hatch none 0.5)
			(connect_pads
				(clearance 0)
			)
			(min_thickness 0.25)
			(keepout
				(tracks not_allowed)
				(vias allowed)
				(pads allowed)
				(copperpour not_allowed)
				(footprints allowed)
			)
			(placement
				(enabled no)
				(sheetname "")
			)
			(fill
				(thermal_gap 0.5)
				(thermal_bridge_width 0.5)
				(island_removal_mode 0)
			)
			(polygon
				(pts
					(arc
						(start 145.042636 -304.780442)
						(mid 140.012928 -304.780442)
						(end 145.042636 -304.780442)
					)
				)
			)
		)
		(zone
			(layers "F.Cu" "B.Cu" "In1.Cu" "In2.Cu" "In3.Cu" "In4.Cu" "In5.Cu" "In6.Cu"
				"In7.Cu" "In8.Cu" "In9.Cu" "In10.Cu" "In11.Cu" "In12.Cu" "In13.Cu" "In14.Cu"
				"In15.Cu" "In16.Cu"
			)
			(hatch none 0.5)
			(connect_pads
				(clearance 0)
			)
			(min_thickness 0.25)
			(keepout
				(tracks not_allowed)
				(vias allowed)
				(pads allowed)
				(copperpour not_allowed)
				(footprints allowed)
			)
			(placement
				(enabled no)
				(sheetname "")
			)
			(fill
				(thermal_gap 0.5)
				(thermal_bridge_width 0.5)
				(island_removal_mode 0)
			)
			(polygon
				(pts
					(arc
						(start 145.042636 -212.98027)
						(mid 140.012928 -212.98027)
						(end 145.042636 -212.98027)
					)
				)
			)
		)
		(zone
			(layers "F.Cu" "B.Cu" "In1.Cu" "In2.Cu" "In3.Cu" "In4.Cu" "In5.Cu" "In6.Cu"
				"In7.Cu" "In8.Cu" "In9.Cu" "In10.Cu" "In11.Cu" "In12.Cu" "In13.Cu" "In14.Cu"
				"In15.Cu" "In16.Cu"
			)
			(hatch none 0.5)
			(connect_pads
				(clearance 0)
			)
			(min_thickness 0.25)
			(keepout
				(tracks not_allowed)
				(vias allowed)
				(pads allowed)
				(copperpour not_allowed)
				(footprints allowed)
			)
			(placement
				(enabled no)
				(sheetname "")
			)
			(fill
				(thermal_gap 0.5)
				(thermal_bridge_width 0.5)
				(island_removal_mode 0)
			)
			(polygon
				(pts
					(arc
						(start 156.542486 -258.880356)
						(mid 151.513286 -258.880356)
						(end 156.542486 -258.880356)
					)
				)
			)
		)
	)
	(footprint ""
		(layer "F.Cu")
		(at 29.214064 -80.424274 -90)
		(property "Reference" "R6182"
			(at 0 0 270)
			(layer "F.SilkS")
			(hide yes)
			(effects
				(font
					(size 1.27 1.27)
				)
			)
		)
		(property "Value" ""
			(at 0 0 270)
			(layer "F.Fab")
			(effects
				(font
					(size 1.27 1.27)
				)
			)
		)
		(duplicate_pad_numbers_are_jumpers no)
		(fp_line
			(start -0.7874 0.4064)
			(end -0.7874 -0.4064)
			(stroke
				(width 0.1524)
				(type default)
			)
			(layer "F.SilkS")
		)
		(fp_line
			(start 0.7874 0.4064)
			(end -0.7874 0.4064)
			(stroke
				(width 0.1524)
				(type default)
			)
			(layer "F.SilkS")
		)
		(fp_line
			(start -0.7874 -0.4064)
			(end 0.7874 -0.4064)
			(stroke
				(width 0.1524)
				(type default)
			)
			(layer "F.SilkS")
		)
		(fp_line
			(start 0.7874 -0.4064)
			(end 0.7874 0.4064)
			(stroke
				(width 0.1524)
				(type default)
			)
			(layer "F.SilkS")
		)
		(fp_line
			(start -0.67945 0.3048)
			(end -0.67945 -0.305054)
			(stroke
				(width 0.1)
				(type default)
			)
			(layer "F.Fab")
		)
		(fp_line
			(start -0.12065 0.3048)
			(end -0.67945 0.3048)
			(stroke
				(width 0.1)
				(type default)
			)
			(layer "F.Fab")
		)
		(fp_line
			(start 0.120396 0.3048)
			(end 0.120396 0.2794)
			(stroke
				(width 0.1)
				(type default)
			)
			(layer "F.Fab")
		)
		(fp_line
			(start 0.67945 0.3048)
			(end 0.120396 0.3048)
			(stroke
				(width 0.1)
				(type default)
			)
			(layer "F.Fab")
		)
		(fp_line
			(start -0.12065 0.2794)
			(end -0.12065 0.3048)
			(stroke
				(width 0.1)
				(type default)
			)
			(layer "F.Fab")
		)
		(fp_line
			(start 0.120396 0.2794)
			(end -0.12065 0.2794)
			(stroke
				(width 0.1)
				(type default)
			)
			(layer "F.Fab")
		)
		(fp_line
			(start -0.12065 -0.2794)
			(end 0.12065 -0.2794)
			(stroke
				(width 0.1)
				(type default)
			)
			(layer "F.Fab")
		)
		(fp_line
			(start 0.12065 -0.2794)
			(end 0.12065 -0.3048)
			(stroke
				(width 0.1)
				(type default)
			)
			(layer "F.Fab")
		)
		(fp_line
			(start 0.12065 -0.3048)
			(end 0.67945 -0.3048)
			(stroke
				(width 0.1)
				(type default)
			)
			(layer "F.Fab")
		)
		(fp_line
			(start 0.67945 -0.3048)
			(end 0.67945 0.3048)
			(stroke
				(width 0.1)
				(type default)
			)
			(layer "F.Fab")
		)
		(fp_line
			(start -0.67945 -0.305054)
			(end -0.12065 -0.305054)
			(stroke
				(width 0.1)
				(type default)
			)
			(layer "F.Fab")
		)
		(fp_line
			(start -0.12065 -0.305054)
			(end -0.12065 -0.2794)
			(stroke
				(width 0.1)
				(type default)
			)
			(layer "F.Fab")
		)
		(pad "1" smd circle
			(at -0.40005 0 270)
			(size 0 0)
			(layers "F.Cu" "F.Mask" "F.Paste")
			(net "P3V3_AUX")
		)
		(pad "2" smd circle
			(at 0.40005 0 270)
			(size 0 0)
			(layers "F.Cu" "F.Mask" "F.Paste")
			(net "PU_U160_EN_N")
		)
	)
	(footprint ""
		(layer "F.Cu")
		(at 142.893542 -383.7432)
		(property "Reference" "R883"
			(at 0 0 0)
			(layer "F.SilkS")
			(hide yes)
			(effects
				(font
					(size 1.27 1.27)
				)
			)
		)
		(property "Value" ""
			(at 0 0 0)
			(layer "F.Fab")
			(effects
				(font
					(size 1.27 1.27)
				)
			)
		)
		(duplicate_pad_numbers_are_jumpers no)
		(fp_line
			(start -0.32512 -0.175006)
			(end 0.32512 -0.175006)
			(stroke
				(width 0.1)
				(type default)
			)
			(layer "F.Fab")
		)
		(fp_line
			(start -0.32512 0.175006)
			(end -0.32512 -0.175006)
			(stroke
				(width 0.1)
				(type default)
			)
			(layer "F.Fab")
		)
		(fp_line
			(start 0.32512 -0.175006)
			(end 0.32512 0.175006)
			(stroke
				(width 0.1)
				(type default)
			)
			(layer "F.Fab")
		)
		(fp_line
			(start 0.32512 0.175006)
			(end -0.32512 0.175006)
			(stroke
				(width 0.1)
				(type default)
			)
			(layer "F.Fab")
		)
		(pad "1" smd rect
			(at -0.2667 0)
			(size 0.3048 0.381)
			(layers "F.Cu" "F.Mask" "F.Paste")
			(net "TEST2_RT_CPU1_P2")
		)
		(pad "2" smd rect
			(at 0.2667 0 180)
			(size 0.3048 0.381)
			(layers "F.Cu" "F.Mask" "F.Paste")
			(net "GND")
		)
	)
	(footprint ""
		(layer "F.Cu")
		(at 15.067788 -92.687648 90)
		(property "Reference" "R3659"
			(at 0 0 90)
			(layer "F.SilkS")
			(hide yes)
			(effects
				(font
					(size 1.27 1.27)
				)
			)
		)
		(property "Value" ""
			(at 0 0 90)
			(layer "F.Fab")
			(effects
				(font
					(size 1.27 1.27)
				)
			)
		)
		(duplicate_pad_numbers_are_jumpers no)
		(fp_line
			(start 0.7874 -0.4064)
			(end 0.7874 0.4064)
			(stroke
				(width 0.1524)
				(type default)
			)
			(layer "F.SilkS")
		)
		(fp_line
			(start -0.7874 -0.4064)
			(end 0.7874 -0.4064)
			(stroke
				(width 0.1524)
				(type default)
			)
			(layer "F.SilkS")
		)
		(fp_line
			(start 0.7874 0.4064)
			(end -0.7874 0.4064)
			(stroke
				(width 0.1524)
				(type default)
			)
			(layer "F.SilkS")
		)
		(fp_line
			(start -0.7874 0.4064)
			(end -0.7874 -0.4064)
			(stroke
				(width 0.1524)
				(type default)
			)
			(layer "F.SilkS")
		)
		(fp_line
			(start -0.12065 -0.305054)
			(end -0.12065 -0.2794)
			(stroke
				(width 0.1)
				(type default)
			)
			(layer "F.Fab")
		)
		(fp_line
			(start -0.67945 -0.305054)
			(end -0.12065 -0.305054)
			(stroke
				(width 0.1)
				(type default)
			)
			(layer "F.Fab")
		)
		(fp_line
			(start 0.67945 -0.3048)
			(end 0.67945 0.3048)
			(stroke
				(width 0.1)
				(type default)
			)
			(layer "F.Fab")
		)
		(fp_line
			(start 0.12065 -0.3048)
			(end 0.67945 -0.3048)
			(stroke
				(width 0.1)
				(type default)
			)
			(layer "F.Fab")
		)
		(fp_line
			(start 0.12065 -0.2794)
			(end 0.12065 -0.3048)
			(stroke
				(width 0.1)
				(type default)
			)
			(layer "F.Fab")
		)
		(fp_line
			(start -0.12065 -0.2794)
			(end 0.12065 -0.2794)
			(stroke
				(width 0.1)
				(type default)
			)
			(layer "F.Fab")
		)
		(fp_line
			(start 0.120396 0.2794)
			(end -0.12065 0.2794)
			(stroke
				(width 0.1)
				(type default)
			)
			(layer "F.Fab")
		)
		(fp_line
			(start -0.12065 0.2794)
			(end -0.12065 0.3048)
			(stroke
				(width 0.1)
				(type default)
			)
			(layer "F.Fab")
		)
		(fp_line
			(start 0.67945 0.3048)
			(end 0.120396 0.3048)
			(stroke
				(width 0.1)
				(type default)
			)
			(layer "F.Fab")
		)
		(fp_line
			(start 0.120396 0.3048)
			(end 0.120396 0.2794)
			(stroke
				(width 0.1)
				(type default)
			)
			(layer "F.Fab")
		)
		(fp_line
			(start -0.12065 0.3048)
			(end -0.67945 0.3048)
			(stroke
				(width 0.1)
				(type default)
			)
			(layer "F.Fab")
		)
		(fp_line
			(start -0.67945 0.3048)
			(end -0.67945 -0.305054)
			(stroke
				(width 0.1)
				(type default)
			)
			(layer "F.Fab")
		)
		(pad "1" smd circle
			(at -0.40005 0 90)
			(size 0 0)
			(layers "F.Cu" "F.Mask" "F.Paste")
			(net "P3V3_AUX")
		)
		(pad "2" smd circle
			(at 0.40005 0 90)
			(size 0 0)
			(layers "F.Cu" "F.Mask" "F.Paste")
			(net "USB_HUB_OVCUR4")
		)
	)
	(footprint ""
		(layer "F.Cu")
		(at 324.00748 -339.84565 90)
		(property "Reference" "PC83_2"
			(at 0 0 90)
			(layer "F.SilkS")
			(hide yes)
			(effects
				(font
					(size 1.27 1.27)
				)
			)
		)
		(property "Value" ""
			(at 0 0 90)
			(layer "F.Fab")
			(effects
				(font
					(size 1.27 1.27)
				)
			)
		)
		(duplicate_pad_numbers_are_jumpers no)
		(fp_line
			(start 0.7874 -0.4064)
			(end 0.7874 0.4064)
			(stroke
				(width 0.1524)
				(type default)
			)
			(layer "F.SilkS")
		)
		(fp_line
			(start -0.7874 -0.4064)
			(end 0.7874 -0.4064)
			(stroke
				(width 0.1524)
				(type default)
			)
			(layer "F.SilkS")
		)
		(fp_line
			(start 0.7874 0.4064)
			(end -0.7874 0.4064)
			(stroke
				(width 0.1524)
				(type default)
			)
			(layer "F.SilkS")
		)
		(fp_line
			(start -0.7874 0.4064)
			(end -0.7874 -0.4064)
			(stroke
				(width 0.1524)
				(type default)
			)
			(layer "F.SilkS")
		)
		(fp_line
			(start -0.12065 -0.305054)
			(end -0.12065 -0.2794)
			(stroke
				(width 0.1)
				(type default)
			)
			(layer "F.Fab")
		)
		(fp_line
			(start -0.67945 -0.305054)
			(end -0.12065 -0.305054)
			(stroke
				(width 0.1)
				(type default)
			)
			(layer "F.Fab")
		)
		(fp_line
			(start 0.67945 -0.3048)
			(end 0.67945 0.3048)
			(stroke
				(width 0.1)
				(type default)
			)
			(layer "F.Fab")
		)
		(fp_line
			(start 0.12065 -0.3048)
			(end 0.67945 -0.3048)
			(stroke
				(width 0.1)
				(type default)
			)
			(layer "F.Fab")
		)
		(fp_line
			(start 0.12065 -0.2794)
			(end 0.12065 -0.3048)
			(stroke
				(width 0.1)
				(type default)
			)
			(layer "F.Fab")
		)
		(fp_line
			(start -0.12065 -0.2794)
			(end 0.12065 -0.2794)
			(stroke
				(width 0.1)
				(type default)
			)
			(layer "F.Fab")
		)
		(fp_line
			(start 0.120396 0.2794)
			(end -0.12065 0.2794)
			(stroke
				(width 0.1)
				(type default)
			)
			(layer "F.Fab")
		)
		(fp_line
			(start -0.12065 0.2794)
			(end -0.12065 0.3048)
			(stroke
				(width 0.1)
				(type default)
			)
			(layer "F.Fab")
		)
		(fp_line
			(start 0.67945 0.3048)
			(end 0.120396 0.3048)
			(stroke
				(width 0.1)
				(type default)
			)
			(layer "F.Fab")
		)
		(fp_line
			(start 0.120396 0.3048)
			(end 0.120396 0.2794)
			(stroke
				(width 0.1)
				(type default)
			)
			(layer "F.Fab")
		)
		(fp_line
			(start -0.12065 0.3048)
			(end -0.67945 0.3048)
			(stroke
				(width 0.1)
				(type default)
			)
			(layer "F.Fab")
		)
		(fp_line
			(start -0.67945 0.3048)
			(end -0.67945 -0.305054)
			(stroke
				(width 0.1)
				(type default)
			)
			(layer "F.Fab")
		)
		(pad "1" smd circle
			(at -0.40005 0 90)
			(size 0 0)
			(layers "F.Cu" "F.Mask" "F.Paste")
			(net "PVDDCR_CPU1_P0_VCCS")
		)
		(pad "2" smd circle
			(at 0.40005 0 90)
			(size 0 0)
			(layers "F.Cu" "F.Mask" "F.Paste")
			(net "GND")
		)
	)
	(footprint ""
		(layer "F.Cu")
		(at 83.222084 -37.36848 180)
		(property "Reference" "R6058"
			(at 0 0 180)
			(layer "F.SilkS")
			(hide yes)
			(effects
				(font
					(size 1.27 1.27)
				)
			)
		)
		(property "Value" ""
			(at 0 0 180)
			(layer "F.Fab")
			(effects
				(font
					(size 1.27 1.27)
				)
			)
		)
		(duplicate_pad_numbers_are_jumpers no)
		(fp_line
			(start 0.7874 0.4064)
			(end -0.7874 0.4064)
			(stroke
				(width 0.1524)
				(type default)
			)
			(layer "F.SilkS")
		)
		(fp_line
			(start 0.7874 -0.4064)
			(end 0.7874 0.4064)
			(stroke
				(width 0.1524)
				(type default)
			)
			(layer "F.SilkS")
		)
		(fp_line
			(start -0.7874 0.4064)
			(end -0.7874 -0.4064)
			(stroke
				(width 0.1524)
				(type default)
			)
			(layer "F.SilkS")
		)
		(fp_line
			(start -0.7874 -0.4064)
			(end 0.7874 -0.4064)
			(stroke
				(width 0.1524)
				(type default)
			)
			(layer "F.SilkS")
		)
		(fp_line
			(start 0.67945 0.3048)
			(end 0.120396 0.3048)
			(stroke
				(width 0.1)
				(type default)
			)
			(layer "F.Fab")
		)
		(fp_line
			(start 0.67945 -0.3048)
			(end 0.67945 0.3048)
			(stroke
				(width 0.1)
				(type default)
			)
			(layer "F.Fab")
		)
		(fp_line
			(start 0.12065 -0.2794)
			(end 0.12065 -0.3048)
			(stroke
				(width 0.1)
				(type default)
			)
			(layer "F.Fab")
		)
		(fp_line
			(start 0.12065 -0.3048)
			(end 0.67945 -0.3048)
			(stroke
				(width 0.1)
				(type default)
			)
			(layer "F.Fab")
		)
		(fp_line
			(start 0.120396 0.3048)
			(end 0.120396 0.2794)
			(stroke
				(width 0.1)
				(type default)
			)
			(layer "F.Fab")
		)
		(fp_line
			(start 0.120396 0.2794)
			(end -0.12065 0.2794)
			(stroke
				(width 0.1)
				(type default)
			)
			(layer "F.Fab")
		)
		(fp_line
			(start -0.12065 0.3048)
			(end -0.67945 0.3048)
			(stroke
				(width 0.1)
				(type default)
			)
			(layer "F.Fab")
		)
		(fp_line
			(start -0.12065 0.2794)
			(end -0.12065 0.3048)
			(stroke
				(width 0.1)
				(type default)
			)
			(layer "F.Fab")
		)
		(fp_line
			(start -0.12065 -0.2794)
			(end 0.12065 -0.2794)
			(stroke
				(width 0.1)
				(type default)
			)
			(layer "F.Fab")
		)
		(fp_line
			(start -0.12065 -0.305054)
			(end -0.12065 -0.2794)
			(stroke
				(width 0.1)
				(type default)
			)
			(layer "F.Fab")
		)
		(fp_line
			(start -0.67945 0.3048)
			(end -0.67945 -0.305054)
			(stroke
				(width 0.1)
				(type default)
			)
			(layer "F.Fab")
		)
		(fp_line
			(start -0.67945 -0.305054)
			(end -0.12065 -0.305054)
			(stroke
				(width 0.1)
				(type default)
			)
			(layer "F.Fab")
		)
		(pad "1" smd circle
			(at -0.40005 0 180)
			(size 0 0)
			(layers "F.Cu" "F.Mask" "F.Paste")
			(net "RST_PERST_OCP_V3_2_BUF2_N")
		)
		(pad "2" smd circle
			(at 0.40005 0 180)
			(size 0 0)
			(layers "F.Cu" "F.Mask" "F.Paste")
			(net "RST_PERST2_OCP_V3_2_N")
		)
	)
	(footprint ""
		(layer "F.Cu")
		(at 91.770454 -337.694524 90)
		(property "Reference" "PC421"
			(at 0 0 90)
			(layer "F.SilkS")
			(hide yes)
			(effects
				(font
					(size 1.27 1.27)
				)
			)
		)
		(property "Value" ""
			(at 0 0 90)
			(layer "F.Fab")
			(effects
				(font
					(size 1.27 1.27)
				)
			)
		)
		(duplicate_pad_numbers_are_jumpers no)
		(fp_line
			(start 0.7874 -0.4064)
			(end 0.7874 0.4064)
			(stroke
				(width 0.1524)
				(type default)
			)
			(layer "F.SilkS")
		)
		(fp_line
			(start -0.7874 -0.4064)
			(end 0.7874 -0.4064)
			(stroke
				(width 0.1524)
				(type default)
			)
			(layer "F.SilkS")
		)
		(fp_line
			(start 0.7874 0.4064)
			(end 0.379476 0.4064)
			(stroke
				(width 0.1524)
				(type default)
			)
			(layer "F.SilkS")
		)
		(fp_line
			(start -0.230124 0.4064)
			(end -0.7874 0.4064)
			(stroke
				(width 0.1524)
				(type default)
			)
			(layer "F.SilkS")
		)
		(fp_line
			(start -0.7874 0.4064)
			(end -0.7874 -0.4064)
			(stroke
				(width 0.1524)
				(type default)
			)
			(layer "F.SilkS")
		)
		(fp_line
			(start -0.12065 -0.305054)
			(end -0.12065 -0.2794)
			(stroke
				(width 0.1)
				(type default)
			)
			(layer "F.Fab")
		)
		(fp_line
			(start -0.67945 -0.305054)
			(end -0.12065 -0.305054)
			(stroke
				(width 0.1)
				(type default)
			)
			(layer "F.Fab")
		)
		(fp_line
			(start 0.67945 -0.3048)
			(end 0.67945 0.3048)
			(stroke
				(width 0.1)
				(type default)
			)
			(layer "F.Fab")
		)
		(fp_line
			(start 0.12065 -0.3048)
			(end 0.67945 -0.3048)
			(stroke
				(width 0.1)
				(type default)
			)
			(layer "F.Fab")
		)
		(fp_line
			(start 0.12065 -0.2794)
			(end 0.12065 -0.3048)
			(stroke
				(width 0.1)
				(type default)
			)
			(layer "F.Fab")
		)
		(fp_line
			(start -0.12065 -0.2794)
			(end 0.12065 -0.2794)
			(stroke
				(width 0.1)
				(type default)
			)
			(layer "F.Fab")
		)
		(fp_line
			(start 0.120396 0.2794)
			(end -0.12065 0.2794)
			(stroke
				(width 0.1)
				(type default)
			)
			(layer "F.Fab")
		)
		(fp_line
			(start -0.12065 0.2794)
			(end -0.12065 0.3048)
			(stroke
				(width 0.1)
				(type default)
			)
			(layer "F.Fab")
		)
		(fp_line
			(start 0.67945 0.3048)
			(end 0.120396 0.3048)
			(stroke
				(width 0.1)
				(type default)
			)
			(layer "F.Fab")
		)
		(fp_line
			(start 0.120396 0.3048)
			(end 0.120396 0.2794)
			(stroke
				(width 0.1)
				(type default)
			)
			(layer "F.Fab")
		)
		(fp_line
			(start -0.12065 0.3048)
			(end -0.67945 0.3048)
			(stroke
				(width 0.1)
				(type default)
			)
			(layer "F.Fab")
		)
		(fp_line
			(start -0.67945 0.3048)
			(end -0.67945 -0.305054)
			(stroke
				(width 0.1)
				(type default)
			)
			(layer "F.Fab")
		)
		(pad "1" smd circle
			(at -0.40005 0 90)
			(size 0 0)
			(layers "F.Cu" "F.Mask" "F.Paste")
			(net "PVDDCR_CPU1_P1_VCC5")
		)
		(pad "2" smd circle
			(at 0.40005 0 90)
			(size 0 0)
			(layers "F.Cu" "F.Mask" "F.Paste")
			(net "GND")
		)
	)
	(footprint ""
		(layer "F.Cu")
		(at 71.882 -385.5212 90)
		(property "Reference" "R6712"
			(at 0 0 90)
			(layer "F.SilkS")
			(hide yes)
			(effects
				(font
					(size 1.27 1.27)
				)
			)
		)
		(property "Value" ""
			(at 0 0 90)
			(layer "F.Fab")
			(effects
				(font
					(size 1.27 1.27)
				)
			)
		)
		(duplicate_pad_numbers_are_jumpers no)
		(fp_line
			(start 0.32512 -0.175006)
			(end 0.32512 0.175006)
			(stroke
				(width 0.1)
				(type default)
			)
			(layer "F.Fab")
		)
		(fp_line
			(start -0.32512 -0.175006)
			(end 0.32512 -0.175006)
			(stroke
				(width 0.1)
				(type default)
			)
			(layer "F.Fab")
		)
		(fp_line
			(start 0.32512 0.175006)
			(end -0.32512 0.175006)
			(stroke
				(width 0.1)
				(type default)
			)
			(layer "F.Fab")
		)
		(fp_line
			(start -0.32512 0.175006)
			(end -0.32512 -0.175006)
			(stroke
				(width 0.1)
				(type default)
			)
			(layer "F.Fab")
		)
		(pad "1" smd rect
			(at -0.2667 0 90)
			(size 0.3048 0.381)
			(layers "F.Cu" "F.Mask" "F.Paste")
			(net "P1V8_CPU1_RT_1D")
		)
		(pad "2" smd rect
			(at 0.2667 0 270)
			(size 0.3048 0.381)
			(layers "F.Cu" "F.Mask" "F.Paste")
			(net "RT_CPU1_P0_ADDR3")
		)
	)
	(footprint ""
		(layer "F.Cu")
		(at 317.246 -364.617 90)
		(property "Reference" "PC75"
			(at 0 0 90)
			(layer "F.SilkS")
			(hide yes)
			(effects
				(font
					(size 1.27 1.27)
				)
			)
		)
		(property "Value" ""
			(at 0 0 90)
			(layer "F.Fab")
			(effects
				(font
					(size 1.27 1.27)
				)
			)
		)
		(duplicate_pad_numbers_are_jumpers no)
		(fp_line
			(start 0.7874 -0.4064)
			(end 0.7874 0.4064)
			(stroke
				(width 0.1524)
				(type default)
			)
			(layer "F.SilkS")
		)
		(fp_line
			(start -0.7874 -0.4064)
			(end 0.7874 -0.4064)
			(stroke
				(width 0.1524)
				(type default)
			)
			(layer "F.SilkS")
		)
		(fp_line
			(start 0.7874 0.4064)
			(end -0.7874 0.4064)
			(stroke
				(width 0.1524)
				(type default)
			)
			(layer "F.SilkS")
		)
		(fp_line
			(start -0.7874 0.4064)
			(end -0.7874 -0.4064)
			(stroke
				(width 0.1524)
				(type default)
			)
			(layer "F.SilkS")
		)
		(fp_line
			(start -0.12065 -0.305054)
			(end -0.12065 -0.2794)
			(stroke
				(width 0.1)
				(type default)
			)
			(layer "F.Fab")
		)
		(fp_line
			(start -0.67945 -0.305054)
			(end -0.12065 -0.305054)
			(stroke
				(width 0.1)
				(type default)
			)
			(layer "F.Fab")
		)
		(fp_line
			(start 0.67945 -0.3048)
			(end 0.67945 0.3048)
			(stroke
				(width 0.1)
				(type default)
			)
			(layer "F.Fab")
		)
		(fp_line
			(start 0.12065 -0.3048)
			(end 0.67945 -0.3048)
			(stroke
				(width 0.1)
				(type default)
			)
			(layer "F.Fab")
		)
		(fp_line
			(start 0.12065 -0.2794)
			(end 0.12065 -0.3048)
			(stroke
				(width 0.1)
				(type default)
			)
			(layer "F.Fab")
		)
		(fp_line
			(start -0.12065 -0.2794)
			(end 0.12065 -0.2794)
			(stroke
				(width 0.1)
				(type default)
			)
			(layer "F.Fab")
		)
		(fp_line
			(start 0.120396 0.2794)
			(end -0.12065 0.2794)
			(stroke
				(width 0.1)
				(type default)
			)
			(layer "F.Fab")
		)
		(fp_line
			(start -0.12065 0.2794)
			(end -0.12065 0.3048)
			(stroke
				(width 0.1)
				(type default)
			)
			(layer "F.Fab")
		)
		(fp_line
			(start 0.67945 0.3048)
			(end 0.120396 0.3048)
			(stroke
				(width 0.1)
				(type default)
			)
			(layer "F.Fab")
		)
		(fp_line
			(start 0.120396 0.3048)
			(end 0.120396 0.2794)
			(stroke
				(width 0.1)
				(type default)
			)
			(layer "F.Fab")
		)
		(fp_line
			(start -0.12065 0.3048)
			(end -0.67945 0.3048)
			(stroke
				(width 0.1)
				(type default)
			)
			(layer "F.Fab")
		)
		(fp_line
			(start -0.67945 0.3048)
			(end -0.67945 -0.305054)
			(stroke
				(width 0.1)
				(type default)
			)
			(layer "F.Fab")
		)
		(pad "1" smd circle
			(at -0.40005 0 90)
			(size 0 0)
			(layers "F.Cu" "F.Mask" "F.Paste")
			(net "PVDDCR_CPU1_P0_VCC")
		)
		(pad "2" smd circle
			(at 0.40005 0 90)
			(size 0 0)
			(layers "F.Cu" "F.Mask" "F.Paste")
			(net "GND")
		)
	)
	(footprint ""
		(layer "F.Cu")
		(at 315.813186 -361.279948)
		(property "Reference" "PC78"
			(at 0 0 0)
			(layer "F.SilkS")
			(hide yes)
			(effects
				(font
					(size 1.27 1.27)
				)
			)
		)
		(property "Value" ""
			(at 0 0 0)
			(layer "F.Fab")
			(effects
				(font
					(size 1.27 1.27)
				)
			)
		)
		(duplicate_pad_numbers_are_jumpers no)
		(fp_line
			(start -0.7874 -0.4064)
			(end 0.7874 -0.4064)
			(stroke
				(width 0.1524)
				(type default)
			)
			(layer "F.SilkS")
		)
		(fp_line
			(start -0.7874 0.4064)
			(end -0.7874 -0.4064)
			(stroke
				(width 0.1524)
				(type default)
			)
			(layer "F.SilkS")
		)
		(fp_line
			(start 0.7874 -0.4064)
			(end 0.7874 0.4064)
			(stroke
				(width 0.1524)
				(type default)
			)
			(layer "F.SilkS")
		)
		(fp_line
			(start 0.7874 0.4064)
			(end -0.7874 0.4064)
			(stroke
				(width 0.1524)
				(type default)
			)
			(layer "F.SilkS")
		)
		(fp_line
			(start -0.67945 -0.305054)
			(end -0.12065 -0.305054)
			(stroke
				(width 0.1)
				(type default)
			)
			(layer "F.Fab")
		)
		(fp_line
			(start -0.67945 0.3048)
			(end -0.67945 -0.305054)
			(stroke
				(width 0.1)
				(type default)
			)
			(layer "F.Fab")
		)
		(fp_line
			(start -0.12065 -0.305054)
			(end -0.12065 -0.2794)
			(stroke
				(width 0.1)
				(type default)
			)
			(layer "F.Fab")
		)
		(fp_line
			(start -0.12065 -0.2794)
			(end 0.12065 -0.2794)
			(stroke
				(width 0.1)
				(type default)
			)
			(layer "F.Fab")
		)
		(fp_line
			(start -0.12065 0.2794)
			(end -0.12065 0.3048)
			(stroke
				(width 0.1)
				(type default)
			)
			(layer "F.Fab")
		)
		(fp_line
			(start -0.12065 0.3048)
			(end -0.67945 0.3048)
			(stroke
				(width 0.1)
				(type default)
			)
			(layer "F.Fab")
		)
		(fp_line
			(start 0.120396 0.2794)
			(end -0.12065 0.2794)
			(stroke
				(width 0.1)
				(type default)
			)
			(layer "F.Fab")
		)
		(fp_line
			(start 0.120396 0.3048)
			(end 0.120396 0.2794)
			(stroke
				(width 0.1)
				(type default)
			)
			(layer "F.Fab")
		)
		(fp_line
			(start 0.12065 -0.3048)
			(end 0.67945 -0.3048)
			(stroke
				(width 0.1)
				(type default)
			)
			(layer "F.Fab")
		)
		(fp_line
			(start 0.12065 -0.2794)
			(end 0.12065 -0.3048)
			(stroke
				(width 0.1)
				(type default)
			)
			(layer "F.Fab")
		)
		(fp_line
			(start 0.67945 -0.3048)
			(end 0.67945 0.3048)
			(stroke
				(width 0.1)
				(type default)
			)
			(layer "F.Fab")
		)
		(fp_line
			(start 0.67945 0.3048)
			(end 0.120396 0.3048)
			(stroke
				(width 0.1)
				(type default)
			)
			(layer "F.Fab")
		)
		(pad "1" smd circle
			(at -0.40005 0)
			(size 0 0)
			(layers "F.Cu" "F.Mask" "F.Paste")
			(net "PVDDCR_CPU1_P0_TEMP0")
		)
		(pad "2" smd circle
			(at 0.40005 0)
			(size 0 0)
			(layers "F.Cu" "F.Mask" "F.Paste")
			(net "GND")
		)
	)
	(footprint ""
		(layer "F.Cu")
		(at 357.044244 -378.95403 -90)
		(property "Reference" "C939"
			(at 0 0 270)
			(layer "F.SilkS")
			(hide yes)
			(effects
				(font
					(size 1.27 1.27)
				)
			)
		)
		(property "Value" ""
			(at 0 0 270)
			(layer "F.Fab")
			(effects
				(font
					(size 1.27 1.27)
				)
			)
		)
		(duplicate_pad_numbers_are_jumpers no)
		(fp_line
			(start -0.299974 0.150114)
			(end -0.299974 -0.150114)
			(stroke
				(width 0.1)
				(type default)
			)
			(layer "F.Fab")
		)
		(fp_line
			(start 0.299974 0.150114)
			(end -0.299974 0.150114)
			(stroke
				(width 0.1)
				(type default)
			)
			(layer "F.Fab")
		)
		(fp_line
			(start -0.299974 -0.150114)
			(end 0.299974 -0.150114)
			(stroke
				(width 0.1)
				(type default)
			)
			(layer "F.Fab")
		)
		(fp_line
			(start 0.299974 -0.150114)
			(end 0.299974 0.150114)
			(stroke
				(width 0.1)
				(type default)
			)
			(layer "F.Fab")
		)
		(pad "1" smd rect
			(at -0.2667 0 270)
			(size 0.3048 0.381)
			(layers "F.Cu" "F.Mask" "F.Paste")
			(net "P5E_CPU0_P1_TX_C_DP<13>")
		)
		(pad "2" smd rect
			(at 0.2667 0 270)
			(size 0.3048 0.381)
			(layers "F.Cu" "F.Mask" "F.Paste")
			(net "P5E_CPU0_P1_TX_DP<13>")
		)
	)
	(footprint ""
		(layer "F.Cu")
		(at 342.923876 -70.098412 90)
		(property "Reference" "D83"
			(at -3.934714 -0.691642 90)
			(unlocked yes)
			(layer "F.SilkS")
			(effects
				(font
					(size 0.7874 0.5842)
					(thickness 0.1524)
				)
				(justify left)
			)
		)
		(property "Value" ""
			(at 0 0 90)
			(layer "F.Fab")
			(effects
				(font
					(size 1.27 1.27)
				)
			)
		)
		(duplicate_pad_numbers_are_jumpers no)
		(fp_line
			(start 1.16078 -0.4826)
			(end 1.16078 0.4826)
			(stroke
				(width 0.1524)
				(type default)
			)
			(layer "F.SilkS")
		)
		(fp_line
			(start 1.03378 -0.4826)
			(end 1.03378 0.4826)
			(stroke
				(width 0.1524)
				(type default)
			)
			(layer "F.SilkS")
		)
		(fp_line
			(start 0.90678 -0.4826)
			(end 0.90678 0.4826)
			(stroke
				(width 0.1524)
				(type default)
			)
			(layer "F.SilkS")
		)
		(fp_line
			(start -0.64008 -0.4826)
			(end 1.16078 -0.4826)
			(stroke
				(width 0.1524)
				(type default)
			)
			(layer "F.SilkS")
		)
		(fp_line
			(start -0.79248 -0.4826)
			(end 1.03378 -0.4826)
			(stroke
				(width 0.1524)
				(type default)
			)
			(layer "F.SilkS")
		)
		(fp_line
			(start -0.89408 -0.4826)
			(end 0.90678 -0.4826)
			(stroke
				(width 0.1524)
				(type default)
			)
			(layer "F.SilkS")
		)
		(fp_line
			(start 1.16078 0.4826)
			(end -0.64008 0.4826)
			(stroke
				(width 0.1524)
				(type default)
			)
			(layer "F.SilkS")
		)
		(fp_line
			(start 1.03378 0.4826)
			(end -0.79248 0.4826)
			(stroke
				(width 0.1524)
				(type default)
			)
			(layer "F.SilkS")
		)
		(fp_line
			(start 0.90678 0.4826)
			(end -0.90678 0.4826)
			(stroke
				(width 0.1524)
				(type default)
			)
			(layer "F.SilkS")
		)
		(fp_line
			(start -0.90678 0.4826)
			(end -0.90678 -0.4699)
			(stroke
				(width 0.1524)
				(type default)
			)
			(layer "F.SilkS")
		)
		(fp_line
			(start 0.499872 -0.249936)
			(end 0.499872 0.249936)
			(stroke
				(width 0.1)
				(type default)
			)
			(layer "F.Fab")
		)
		(fp_line
			(start -0.499872 -0.249936)
			(end 0.499872 -0.249936)
			(stroke
				(width 0.1)
				(type default)
			)
			(layer "F.Fab")
		)
		(fp_line
			(start 0.499872 0.249936)
			(end -0.499872 0.249936)
			(stroke
				(width 0.1)
				(type default)
			)
			(layer "F.Fab")
		)
		(fp_line
			(start -0.499872 0.249936)
			(end -0.499872 -0.249936)
			(stroke
				(width 0.1)
				(type default)
			)
			(layer "F.Fab")
		)
		(pad "A" smd rect
			(at -0.47498 0 90)
			(size 0.6096 0.7112)
			(layers "F.Cu" "F.Mask" "F.Paste")
			(net "LED_PWRGD_PVDDIO_P1_R")
		)
		(pad "C" smd rect
			(at 0.47498 0 90)
			(size 0.6096 0.7112)
			(layers "F.Cu" "F.Mask" "F.Paste")
			(net "LED_PWRGD_PVDDIO_P1_D")
		)
	)
	(footprint ""
		(layer "F.Cu")
		(at 332.070964 -140.008102 -90)
		(property "Reference" "PC113"
			(at 0 0 270)
			(layer "F.SilkS")
			(hide yes)
			(effects
				(font
					(size 1.27 1.27)
				)
			)
		)
		(property "Value" ""
			(at 0 0 270)
			(layer "F.Fab")
			(effects
				(font
					(size 1.27 1.27)
				)
			)
		)
		(duplicate_pad_numbers_are_jumpers no)
		(fp_line
			(start -0.7874 0.4064)
			(end -0.7874 -0.4064)
			(stroke
				(width 0.1524)
				(type default)
			)
			(layer "F.SilkS")
		)
		(fp_line
			(start 0.7874 0.4064)
			(end -0.7874 0.4064)
			(stroke
				(width 0.1524)
				(type default)
			)
			(layer "F.SilkS")
		)
		(fp_line
			(start -0.7874 -0.4064)
			(end 0.7874 -0.4064)
			(stroke
				(width 0.1524)
				(type default)
			)
			(layer "F.SilkS")
		)
		(fp_line
			(start 0.7874 -0.4064)
			(end 0.7874 0.4064)
			(stroke
				(width 0.1524)
				(type default)
			)
			(layer "F.SilkS")
		)
		(fp_line
			(start -0.67945 0.3048)
			(end -0.67945 -0.305054)
			(stroke
				(width 0.1)
				(type default)
			)
			(layer "F.Fab")
		)
		(fp_line
			(start -0.12065 0.3048)
			(end -0.67945 0.3048)
			(stroke
				(width 0.1)
				(type default)
			)
			(layer "F.Fab")
		)
		(fp_line
			(start 0.120396 0.3048)
			(end 0.120396 0.2794)
			(stroke
				(width 0.1)
				(type default)
			)
			(layer "F.Fab")
		)
		(fp_line
			(start 0.67945 0.3048)
			(end 0.120396 0.3048)
			(stroke
				(width 0.1)
				(type default)
			)
			(layer "F.Fab")
		)
		(fp_line
			(start -0.12065 0.2794)
			(end -0.12065 0.3048)
			(stroke
				(width 0.1)
				(type default)
			)
			(layer "F.Fab")
		)
		(fp_line
			(start 0.120396 0.2794)
			(end -0.12065 0.2794)
			(stroke
				(width 0.1)
				(type default)
			)
			(layer "F.Fab")
		)
		(fp_line
			(start -0.12065 -0.2794)
			(end 0.12065 -0.2794)
			(stroke
				(width 0.1)
				(type default)
			)
			(layer "F.Fab")
		)
		(fp_line
			(start 0.12065 -0.2794)
			(end 0.12065 -0.3048)
			(stroke
				(width 0.1)
				(type default)
			)
			(layer "F.Fab")
		)
		(fp_line
			(start 0.12065 -0.3048)
			(end 0.67945 -0.3048)
			(stroke
				(width 0.1)
				(type default)
			)
			(layer "F.Fab")
		)
		(fp_line
			(start 0.67945 -0.3048)
			(end 0.67945 0.3048)
			(stroke
				(width 0.1)
				(type default)
			)
			(layer "F.Fab")
		)
		(fp_line
			(start -0.67945 -0.305054)
			(end -0.12065 -0.305054)
			(stroke
				(width 0.1)
				(type default)
			)
			(layer "F.Fab")
		)
		(fp_line
			(start -0.12065 -0.305054)
			(end -0.12065 -0.2794)
			(stroke
				(width 0.1)
				(type default)
			)
			(layer "F.Fab")
		)
		(pad "1" smd circle
			(at -0.40005 0 270)
			(size 0 0)
			(layers "F.Cu" "F.Mask" "F.Paste")
			(net "PVDD18_S5_P0_REF")
		)
		(pad "2" smd circle
			(at 0.40005 0 270)
			(size 0 0)
			(layers "F.Cu" "F.Mask" "F.Paste")
			(net "PVDD18_S5_P0_RGND")
		)
	)
	(footprint ""
		(layer "F.Cu")
		(at 327.881742 -395.1732 90)
		(property "Reference" "R965"
			(at 0 0 90)
			(layer "F.SilkS")
			(hide yes)
			(effects
				(font
					(size 1.27 1.27)
				)
			)
		)
		(property "Value" ""
			(at 0 0 90)
			(layer "F.Fab")
			(effects
				(font
					(size 1.27 1.27)
				)
			)
		)
		(duplicate_pad_numbers_are_jumpers no)
		(fp_line
			(start 0.32512 -0.175006)
			(end 0.32512 0.175006)
			(stroke
				(width 0.1)
				(type default)
			)
			(layer "F.Fab")
		)
		(fp_line
			(start -0.32512 -0.175006)
			(end 0.32512 -0.175006)
			(stroke
				(width 0.1)
				(type default)
			)
			(layer "F.Fab")
		)
		(fp_line
			(start 0.32512 0.175006)
			(end -0.32512 0.175006)
			(stroke
				(width 0.1)
				(type default)
			)
			(layer "F.Fab")
		)
		(fp_line
			(start -0.32512 0.175006)
			(end -0.32512 -0.175006)
			(stroke
				(width 0.1)
				(type default)
			)
			(layer "F.Fab")
		)
		(pad "1" smd rect
			(at -0.2667 0 90)
			(size 0.3048 0.381)
			(layers "F.Cu" "F.Mask" "F.Paste")
			(net "RT_CPU0_P0_ADDR3")
		)
		(pad "2" smd rect
			(at 0.2667 0 270)
			(size 0.3048 0.381)
			(layers "F.Cu" "F.Mask" "F.Paste")
			(net "GND")
		)
	)
	(footprint ""
		(layer "F.Cu")
		(at 204.331824 -342.075262 -90.054)
		(property "Reference" "PR454"
			(at 0 0 269.946)
			(layer "F.SilkS")
			(hide yes)
			(effects
				(font
					(size 1.27 1.27)
				)
			)
		)
		(property "Value" ""
			(at 0 0 269.946)
			(layer "F.Fab")
			(effects
				(font
					(size 1.27 1.27)
				)
			)
		)
		(duplicate_pad_numbers_are_jumpers no)
		(fp_line
			(start 0.787275 0.40642)
			(end -0.787525 0.40638)
			(stroke
				(width 0.1524)
				(type default)
			)
			(layer "F.SilkS")
		)
		(fp_line
			(start -0.787525 0.40638)
			(end -0.787275 -0.40642)
			(stroke
				(width 0.1524)
				(type default)
			)
			(layer "F.SilkS")
		)
		(fp_line
			(start 0.787525 -0.40638)
			(end 0.787275 0.40642)
			(stroke
				(width 0.1524)
				(type default)
			)
			(layer "F.SilkS")
		)
		(fp_line
			(start -0.787275 -0.40642)
			(end 0.787525 -0.40638)
			(stroke
				(width 0.1524)
				(type default)
			)
			(layer "F.SilkS")
		)
		(fp_line
			(start 0.679484 0.304922)
			(end 0.120429 0.304687)
			(stroke
				(width 0.1)
				(type default)
			)
			(layer "F.Fab")
		)
		(fp_line
			(start -0.120617 0.304914)
			(end -0.679417 0.304678)
			(stroke
				(width 0.1)
				(type default)
			)
			(layer "F.Fab")
		)
		(fp_line
			(start 0.120429 0.304687)
			(end 0.120405 0.279287)
			(stroke
				(width 0.1)
				(type default)
			)
			(layer "F.Fab")
		)
		(fp_line
			(start -0.679417 0.304678)
			(end -0.679484 -0.305176)
			(stroke
				(width 0.1)
				(type default)
			)
			(layer "F.Fab")
		)
		(fp_line
			(start -0.120641 0.279514)
			(end -0.120617 0.304914)
			(stroke
				(width 0.1)
				(type default)
			)
			(layer "F.Fab")
		)
		(fp_line
			(start 0.120405 0.279287)
			(end -0.120641 0.279514)
			(stroke
				(width 0.1)
				(type default)
			)
			(layer "F.Fab")
		)
		(fp_line
			(start -0.120659 -0.279286)
			(end 0.120641 -0.279514)
			(stroke
				(width 0.1)
				(type default)
			)
			(layer "F.Fab")
		)
		(fp_line
			(start 0.120641 -0.279514)
			(end 0.120617 -0.304914)
			(stroke
				(width 0.1)
				(type default)
			)
			(layer "F.Fab")
		)
		(fp_line
			(start 0.679417 -0.304678)
			(end 0.679484 0.304922)
			(stroke
				(width 0.1)
				(type default)
			)
			(layer "F.Fab")
		)
		(fp_line
			(start 0.120617 -0.304914)
			(end 0.679417 -0.304678)
			(stroke
				(width 0.1)
				(type default)
			)
			(layer "F.Fab")
		)
		(fp_line
			(start -0.120683 -0.30494)
			(end -0.120659 -0.279286)
			(stroke
				(width 0.1)
				(type default)
			)
			(layer "F.Fab")
		)
		(fp_line
			(start -0.679484 -0.305176)
			(end -0.120683 -0.30494)
			(stroke
				(width 0.1)
				(type default)
			)
			(layer "F.Fab")
		)
		(pad "1" smd circle
			(at -0.40005 0 269.946)
			(size 0 0)
			(layers "F.Cu" "F.Mask" "F.Paste")
			(net "PVDD_33_S5_FB")
		)
		(pad "2" smd circle
			(at 0.40005 0 269.946)
			(size 0 0)
			(layers "F.Cu" "F.Mask" "F.Paste")
			(net "GND")
		)
	)
	(footprint ""
		(layer "F.Cu")
		(at 421.174418 -366.202214 90)
		(property "Reference" "PC199"
			(at 0 0 90)
			(layer "F.SilkS")
			(hide yes)
			(effects
				(font
					(size 1.27 1.27)
				)
			)
		)
		(property "Value" ""
			(at 0 0 90)
			(layer "F.Fab")
			(effects
				(font
					(size 1.27 1.27)
				)
			)
		)
		(duplicate_pad_numbers_are_jumpers no)
		(fp_line
			(start 0.7874 -0.4064)
			(end 0.7874 0.4064)
			(stroke
				(width 0.1524)
				(type default)
			)
			(layer "F.SilkS")
		)
		(fp_line
			(start -0.7874 -0.4064)
			(end 0.7874 -0.4064)
			(stroke
				(width 0.1524)
				(type default)
			)
			(layer "F.SilkS")
		)
		(fp_line
			(start 0.7874 0.4064)
			(end -0.7874 0.4064)
			(stroke
				(width 0.1524)
				(type default)
			)
			(layer "F.SilkS")
		)
		(fp_line
			(start -0.7874 0.4064)
			(end -0.7874 -0.4064)
			(stroke
				(width 0.1524)
				(type default)
			)
			(layer "F.SilkS")
		)
		(fp_line
			(start -0.12065 -0.305054)
			(end -0.12065 -0.2794)
			(stroke
				(width 0.1)
				(type default)
			)
			(layer "F.Fab")
		)
		(fp_line
			(start -0.67945 -0.305054)
			(end -0.12065 -0.305054)
			(stroke
				(width 0.1)
				(type default)
			)
			(layer "F.Fab")
		)
		(fp_line
			(start 0.67945 -0.3048)
			(end 0.67945 0.3048)
			(stroke
				(width 0.1)
				(type default)
			)
			(layer "F.Fab")
		)
		(fp_line
			(start 0.12065 -0.3048)
			(end 0.67945 -0.3048)
			(stroke
				(width 0.1)
				(type default)
			)
			(layer "F.Fab")
		)
		(fp_line
			(start 0.12065 -0.2794)
			(end 0.12065 -0.3048)
			(stroke
				(width 0.1)
				(type default)
			)
			(layer "F.Fab")
		)
		(fp_line
			(start -0.12065 -0.2794)
			(end 0.12065 -0.2794)
			(stroke
				(width 0.1)
				(type default)
			)
			(layer "F.Fab")
		)
		(fp_line
			(start 0.120396 0.2794)
			(end -0.12065 0.2794)
			(stroke
				(width 0.1)
				(type default)
			)
			(layer "F.Fab")
		)
		(fp_line
			(start -0.12065 0.2794)
			(end -0.12065 0.3048)
			(stroke
				(width 0.1)
				(type default)
			)
			(layer "F.Fab")
		)
		(fp_line
			(start 0.67945 0.3048)
			(end 0.120396 0.3048)
			(stroke
				(width 0.1)
				(type default)
			)
			(layer "F.Fab")
		)
		(fp_line
			(start 0.120396 0.3048)
			(end 0.120396 0.2794)
			(stroke
				(width 0.1)
				(type default)
			)
			(layer "F.Fab")
		)
		(fp_line
			(start -0.12065 0.3048)
			(end -0.67945 0.3048)
			(stroke
				(width 0.1)
				(type default)
			)
			(layer "F.Fab")
		)
		(fp_line
			(start -0.67945 0.3048)
			(end -0.67945 -0.305054)
			(stroke
				(width 0.1)
				(type default)
			)
			(layer "F.Fab")
		)
		(pad "1" smd circle
			(at -0.40005 0 90)
			(size 0 0)
			(layers "F.Cu" "F.Mask" "F.Paste")
			(net "PVDD11_S3_P0_VCCS")
		)
		(pad "2" smd circle
			(at 0.40005 0 90)
			(size 0 0)
			(layers "F.Cu" "F.Mask" "F.Paste")
			(net "GND")
		)
	)
	(footprint ""
		(layer "F.Cu")
		(at 65.529714 -178.24577 180)
		(property "Reference" "PL8"
			(at 3.654044 5.77723 90)
			(unlocked yes)
			(layer "F.SilkS")
			(effects
				(font
					(size 0.7874 0.5842)
					(thickness 0.1524)
				)
				(justify left)
			)
		)
		(property "Value" ""
			(at 0 0 180)
			(layer "F.Fab")
			(effects
				(font
					(size 1.27 1.27)
				)
			)
		)
		(duplicate_pad_numbers_are_jumpers no)
		(fp_line
			(start 3.750056 5.500116)
			(end 3.750056 -5.500116)
			(stroke
				(width 0.1524)
				(type default)
			)
			(layer "F.SilkS")
		)
		(fp_line
			(start 3.750056 -5.500116)
			(end 2.393442 -5.500116)
			(stroke
				(width 0.1524)
				(type default)
			)
			(layer "F.SilkS")
		)
		(fp_line
			(start 2.393442 5.500116)
			(end 3.750056 5.500116)
			(stroke
				(width 0.1524)
				(type default)
			)
			(layer "F.SilkS")
		)
		(fp_line
			(start -2.393442 5.500116)
			(end -3.750056 5.500116)
			(stroke
				(width 0.1524)
				(type default)
			)
			(layer "F.SilkS")
		)
		(fp_line
			(start -3.750056 5.500116)
			(end -3.750056 -5.500116)
			(stroke
				(width 0.1524)
				(type default)
			)
			(layer "F.SilkS")
		)
		(fp_line
			(start -3.750056 -5.500116)
			(end -2.393442 -5.500116)
			(stroke
				(width 0.1524)
				(type default)
			)
			(layer "F.SilkS")
		)
		(fp_poly
			(pts
				(xy -4.272534 -4.92125) (xy -5.288534 -4.41325) (xy -5.288534 -5.42925)
			)
			(stroke
				(width 0)
				(type default)
			)
			(fill yes)
			(layer "F.SilkS")
		)
		(fp_line
			(start 3.750056 5.500116)
			(end 3.750056 -5.500116)
			(stroke
				(width 0.1)
				(type default)
			)
			(layer "F.Fab")
		)
		(fp_line
			(start 3.750056 -5.500116)
			(end -3.750056 -5.500116)
			(stroke
				(width 0.1)
				(type default)
			)
			(layer "F.Fab")
		)
		(fp_line
			(start -3.750056 5.500116)
			(end 3.750056 5.500116)
			(stroke
				(width 0.1)
				(type default)
			)
			(layer "F.Fab")
		)
		(fp_line
			(start -3.750056 -5.500116)
			(end -3.750056 5.500116)
			(stroke
				(width 0.1)
				(type default)
			)
			(layer "F.Fab")
		)
		(fp_poly
			(pts
				(xy -4.9276 -4.757928) (xy -4.9276 -3.741928) (xy -3.9116 -4.249928)
			)
			(stroke
				(width 0)
				(type default)
			)
			(fill yes)
			(layer "F.Fab")
		)
		(pad "1" smd rect
			(at 0 -4.249928 90)
			(size 2.413 4.5212)
			(layers "F.Cu" "F.Mask" "F.Paste")
			(net "SW_PVDDCR_CPU0_P1_SW6")
		)
		(pad "2" smd rect
			(at 0 -1.175004 90)
			(size 1.3716 4.5212)
			(layers "F.Cu" "F.Mask" "F.Paste")
			(net "IND_CPU0_P1_CPL0")
		)
		(pad "3" smd rect
			(at 0 1.175004 90)
			(size 1.3716 4.5212)
			(layers "F.Cu" "F.Mask" "F.Paste")
			(net "IND_CPU0_P1_CPL6")
		)
		(pad "4" smd rect
			(at 0 4.249928 90)
			(size 2.413 4.5212)
			(layers "F.Cu" "F.Mask" "F.Paste")
			(net "PVDDCR_CPU0_P1")
		)
	)
	(footprint ""
		(layer "F.Cu")
		(at 391.845038 -143.151098 90)
		(property "Reference" "C223"
			(at 0 0 90)
			(layer "F.SilkS")
			(hide yes)
			(effects
				(font
					(size 1.27 1.27)
				)
			)
		)
		(property "Value" ""
			(at 0 0 90)
			(layer "F.Fab")
			(effects
				(font
					(size 1.27 1.27)
				)
			)
		)
		(duplicate_pad_numbers_are_jumpers no)
		(fp_line
			(start 0.7874 -0.4064)
			(end 0.7874 0.4064)
			(stroke
				(width 0.1524)
				(type default)
			)
			(layer "F.SilkS")
		)
		(fp_line
			(start -0.7874 -0.4064)
			(end 0.7874 -0.4064)
			(stroke
				(width 0.1524)
				(type default)
			)
			(layer "F.SilkS")
		)
		(fp_line
			(start 0.7874 0.4064)
			(end -0.7874 0.4064)
			(stroke
				(width 0.1524)
				(type default)
			)
			(layer "F.SilkS")
		)
		(fp_line
			(start -0.7874 0.4064)
			(end -0.7874 -0.4064)
			(stroke
				(width 0.1524)
				(type default)
			)
			(layer "F.SilkS")
		)
		(fp_line
			(start -0.12065 -0.305054)
			(end -0.12065 -0.2794)
			(stroke
				(width 0.1)
				(type default)
			)
			(layer "F.Fab")
		)
		(fp_line
			(start -0.67945 -0.305054)
			(end -0.12065 -0.305054)
			(stroke
				(width 0.1)
				(type default)
			)
			(layer "F.Fab")
		)
		(fp_line
			(start 0.67945 -0.3048)
			(end 0.67945 0.3048)
			(stroke
				(width 0.1)
				(type default)
			)
			(layer "F.Fab")
		)
		(fp_line
			(start 0.12065 -0.3048)
			(end 0.67945 -0.3048)
			(stroke
				(width 0.1)
				(type default)
			)
			(layer "F.Fab")
		)
		(fp_line
			(start 0.12065 -0.2794)
			(end 0.12065 -0.3048)
			(stroke
				(width 0.1)
				(type default)
			)
			(layer "F.Fab")
		)
		(fp_line
			(start -0.12065 -0.2794)
			(end 0.12065 -0.2794)
			(stroke
				(width 0.1)
				(type default)
			)
			(layer "F.Fab")
		)
		(fp_line
			(start 0.120396 0.2794)
			(end -0.12065 0.2794)
			(stroke
				(width 0.1)
				(type default)
			)
			(layer "F.Fab")
		)
		(fp_line
			(start -0.12065 0.2794)
			(end -0.12065 0.3048)
			(stroke
				(width 0.1)
				(type default)
			)
			(layer "F.Fab")
		)
		(fp_line
			(start 0.67945 0.3048)
			(end 0.120396 0.3048)
			(stroke
				(width 0.1)
				(type default)
			)
			(layer "F.Fab")
		)
		(fp_line
			(start 0.120396 0.3048)
			(end 0.120396 0.2794)
			(stroke
				(width 0.1)
				(type default)
			)
			(layer "F.Fab")
		)
		(fp_line
			(start -0.12065 0.3048)
			(end -0.67945 0.3048)
			(stroke
				(width 0.1)
				(type default)
			)
			(layer "F.Fab")
		)
		(fp_line
			(start -0.67945 0.3048)
			(end -0.67945 -0.305054)
			(stroke
				(width 0.1)
				(type default)
			)
			(layer "F.Fab")
		)
		(pad "1" smd circle
			(at -0.40005 0 90)
			(size 0 0)
			(layers "F.Cu" "F.Mask" "F.Paste")
			(net "P1V8_AUX")
		)
		(pad "2" smd circle
			(at 0.40005 0 90)
			(size 0 0)
			(layers "F.Cu" "F.Mask" "F.Paste")
			(net "GND")
		)
	)
	(footprint ""
		(layer "F.Cu")
		(at 192.005712 -355.924358 90)
		(property "Reference" "PR331"
			(at 0 0 90)
			(layer "F.SilkS")
			(hide yes)
			(effects
				(font
					(size 1.27 1.27)
				)
			)
		)
		(property "Value" ""
			(at 0 0 90)
			(layer "F.Fab")
			(effects
				(font
					(size 1.27 1.27)
				)
			)
		)
		(duplicate_pad_numbers_are_jumpers no)
		(fp_line
			(start 0.7874 -0.4064)
			(end 0.7874 0.4064)
			(stroke
				(width 0.1524)
				(type default)
			)
			(layer "F.SilkS")
		)
		(fp_line
			(start -0.7874 -0.4064)
			(end 0.7874 -0.4064)
			(stroke
				(width 0.1524)
				(type default)
			)
			(layer "F.SilkS")
		)
		(fp_line
			(start 0.7874 0.4064)
			(end -0.7874 0.4064)
			(stroke
				(width 0.1524)
				(type default)
			)
			(layer "F.SilkS")
		)
		(fp_line
			(start -0.7874 0.4064)
			(end -0.7874 -0.4064)
			(stroke
				(width 0.1524)
				(type default)
			)
			(layer "F.SilkS")
		)
		(fp_line
			(start -0.12065 -0.305054)
			(end -0.12065 -0.2794)
			(stroke
				(width 0.1)
				(type default)
			)
			(layer "F.Fab")
		)
		(fp_line
			(start -0.67945 -0.305054)
			(end -0.12065 -0.305054)
			(stroke
				(width 0.1)
				(type default)
			)
			(layer "F.Fab")
		)
		(fp_line
			(start 0.67945 -0.3048)
			(end 0.67945 0.3048)
			(stroke
				(width 0.1)
				(type default)
			)
			(layer "F.Fab")
		)
		(fp_line
			(start 0.12065 -0.3048)
			(end 0.67945 -0.3048)
			(stroke
				(width 0.1)
				(type default)
			)
			(layer "F.Fab")
		)
		(fp_line
			(start 0.12065 -0.2794)
			(end 0.12065 -0.3048)
			(stroke
				(width 0.1)
				(type default)
			)
			(layer "F.Fab")
		)
		(fp_line
			(start -0.12065 -0.2794)
			(end 0.12065 -0.2794)
			(stroke
				(width 0.1)
				(type default)
			)
			(layer "F.Fab")
		)
		(fp_line
			(start 0.120396 0.2794)
			(end -0.12065 0.2794)
			(stroke
				(width 0.1)
				(type default)
			)
			(layer "F.Fab")
		)
		(fp_line
			(start -0.12065 0.2794)
			(end -0.12065 0.3048)
			(stroke
				(width 0.1)
				(type default)
			)
			(layer "F.Fab")
		)
		(fp_line
			(start 0.67945 0.3048)
			(end 0.120396 0.3048)
			(stroke
				(width 0.1)
				(type default)
			)
			(layer "F.Fab")
		)
		(fp_line
			(start 0.120396 0.3048)
			(end 0.120396 0.2794)
			(stroke
				(width 0.1)
				(type default)
			)
			(layer "F.Fab")
		)
		(fp_line
			(start -0.12065 0.3048)
			(end -0.67945 0.3048)
			(stroke
				(width 0.1)
				(type default)
			)
			(layer "F.Fab")
		)
		(fp_line
			(start -0.67945 0.3048)
			(end -0.67945 -0.305054)
			(stroke
				(width 0.1)
				(type default)
			)
			(layer "F.Fab")
		)
		(pad "1" smd circle
			(at -0.40005 0 90)
			(size 0 0)
			(layers "F.Cu" "F.Mask" "F.Paste")
			(net "SW_PVDD11_S3_P1_BOOT2")
		)
		(pad "2" smd circle
			(at 0.40005 0 90)
			(size 0 0)
			(layers "F.Cu" "F.Mask" "F.Paste")
			(net "SW_PVDD11_S3_P1_BOOT2_RC")
		)
	)
	(footprint ""
		(layer "F.Cu")
		(at 323.624194 -39.12362 180)
		(property "Reference" "R4567"
			(at 0 0 180)
			(layer "F.SilkS")
			(hide yes)
			(effects
				(font
					(size 1.27 1.27)
				)
			)
		)
		(property "Value" ""
			(at 0 0 180)
			(layer "F.Fab")
			(effects
				(font
					(size 1.27 1.27)
				)
			)
		)
		(duplicate_pad_numbers_are_jumpers no)
		(fp_line
			(start 0.7874 0.4064)
			(end -0.7874 0.4064)
			(stroke
				(width 0.1524)
				(type default)
			)
			(layer "F.SilkS")
		)
		(fp_line
			(start 0.7874 -0.4064)
			(end 0.7874 0.4064)
			(stroke
				(width 0.1524)
				(type default)
			)
			(layer "F.SilkS")
		)
		(fp_line
			(start -0.7874 0.4064)
			(end -0.7874 -0.4064)
			(stroke
				(width 0.1524)
				(type default)
			)
			(layer "F.SilkS")
		)
		(fp_line
			(start -0.7874 -0.4064)
			(end 0.7874 -0.4064)
			(stroke
				(width 0.1524)
				(type default)
			)
			(layer "F.SilkS")
		)
		(fp_line
			(start 0.67945 0.3048)
			(end 0.120396 0.3048)
			(stroke
				(width 0.1)
				(type default)
			)
			(layer "F.Fab")
		)
		(fp_line
			(start 0.67945 -0.3048)
			(end 0.67945 0.3048)
			(stroke
				(width 0.1)
				(type default)
			)
			(layer "F.Fab")
		)
		(fp_line
			(start 0.12065 -0.2794)
			(end 0.12065 -0.3048)
			(stroke
				(width 0.1)
				(type default)
			)
			(layer "F.Fab")
		)
		(fp_line
			(start 0.12065 -0.3048)
			(end 0.67945 -0.3048)
			(stroke
				(width 0.1)
				(type default)
			)
			(layer "F.Fab")
		)
		(fp_line
			(start 0.120396 0.3048)
			(end 0.120396 0.2794)
			(stroke
				(width 0.1)
				(type default)
			)
			(layer "F.Fab")
		)
		(fp_line
			(start 0.120396 0.2794)
			(end -0.12065 0.2794)
			(stroke
				(width 0.1)
				(type default)
			)
			(layer "F.Fab")
		)
		(fp_line
			(start -0.12065 0.3048)
			(end -0.67945 0.3048)
			(stroke
				(width 0.1)
				(type default)
			)
			(layer "F.Fab")
		)
		(fp_line
			(start -0.12065 0.2794)
			(end -0.12065 0.3048)
			(stroke
				(width 0.1)
				(type default)
			)
			(layer "F.Fab")
		)
		(fp_line
			(start -0.12065 -0.2794)
			(end 0.12065 -0.2794)
			(stroke
				(width 0.1)
				(type default)
			)
			(layer "F.Fab")
		)
		(fp_line
			(start -0.12065 -0.305054)
			(end -0.12065 -0.2794)
			(stroke
				(width 0.1)
				(type default)
			)
			(layer "F.Fab")
		)
		(fp_line
			(start -0.67945 0.3048)
			(end -0.67945 -0.305054)
			(stroke
				(width 0.1)
				(type default)
			)
			(layer "F.Fab")
		)
		(fp_line
			(start -0.67945 -0.305054)
			(end -0.12065 -0.305054)
			(stroke
				(width 0.1)
				(type default)
			)
			(layer "F.Fab")
		)
		(pad "1" smd circle
			(at -0.40005 0 180)
			(size 0 0)
			(layers "F.Cu" "F.Mask" "F.Paste")
			(net "P3V3_PDB_AUX_ADC")
		)
		(pad "2" smd circle
			(at 0.40005 0 180)
			(size 0 0)
			(layers "F.Cu" "F.Mask" "F.Paste")
			(net "P1V581_PDB_ADC")
		)
	)
	(footprint ""
		(layer "F.Cu")
		(at 244.115336 -393.909296 -90)
		(property "Reference" "PR6001"
			(at -4.524248 3.668268 90)
			(unlocked yes)
			(layer "F.SilkS")
			(effects
				(font
					(size 0.7874 0.5842)
					(thickness 0.1524)
				)
				(justify left)
			)
		)
		(property "Value" ""
			(at 0 0 270)
			(layer "F.Fab")
			(effects
				(font
					(size 1.27 1.27)
				)
			)
		)
		(duplicate_pad_numbers_are_jumpers no)
		(fp_line
			(start -3.9878 3.5814)
			(end -3.9878 -3.5814)
			(stroke
				(width 0.1524)
				(type default)
			)
			(layer "F.SilkS")
		)
		(fp_line
			(start 3.9878 3.5814)
			(end -3.9878 3.5814)
			(stroke
				(width 0.1524)
				(type default)
			)
			(layer "F.SilkS")
		)
		(fp_line
			(start -3.9878 -3.5814)
			(end 3.9878 -3.5814)
			(stroke
				(width 0.1524)
				(type default)
			)
			(layer "F.SilkS")
		)
		(fp_line
			(start 3.9878 -3.5814)
			(end 3.9878 3.5814)
			(stroke
				(width 0.1524)
				(type default)
			)
			(layer "F.SilkS")
		)
		(fp_line
			(start -3.5306 3.353054)
			(end -3.5306 -3.353054)
			(stroke
				(width 0.1)
				(type default)
			)
			(layer "F.Fab")
		)
		(fp_line
			(start 3.5306 3.353054)
			(end -3.5306 3.353054)
			(stroke
				(width 0.1)
				(type default)
			)
			(layer "F.Fab")
		)
		(fp_line
			(start -3.5306 -3.353054)
			(end 3.5306 -3.353054)
			(stroke
				(width 0.1)
				(type default)
			)
			(layer "F.Fab")
		)
		(fp_line
			(start 3.5306 -3.353054)
			(end 3.5306 3.353054)
			(stroke
				(width 0.1)
				(type default)
			)
			(layer "F.Fab")
		)
		(pad "1A" smd rect
			(at -2.249932 0 90)
			(size 3.2004 6.858)
			(layers "F.Cu" "F.Mask" "F.Paste")
			(net "P12V_PSU")
		)
		(pad "1B" smd rect
			(at -0.776732 0 270)
			(size 0.254 0.508)
			(layers "F.Cu" "F.Mask" "F.Paste")
			(net "P12V_HSC_SENSE2_R1_P")
		)
		(pad "2A" smd rect
			(at 2.249932 0 90)
			(size 3.2004 6.858)
			(layers "F.Cu" "F.Mask" "F.Paste")
			(net "P12V_MAIN_R")
		)
		(pad "2B" smd rect
			(at 0.776732 0 270)
			(size 0.254 0.508)
			(layers "F.Cu" "F.Mask" "F.Paste")
			(net "P12V_HSC_SENSE2_R1_N")
		)
	)
	(footprint ""
		(layer "F.Cu")
		(at 137.762488 -384.10388 180)
		(property "Reference" "R897"
			(at 0 0 180)
			(layer "F.SilkS")
			(hide yes)
			(effects
				(font
					(size 1.27 1.27)
				)
			)
		)
		(property "Value" ""
			(at 0 0 180)
			(layer "F.Fab")
			(effects
				(font
					(size 1.27 1.27)
				)
			)
		)
		(duplicate_pad_numbers_are_jumpers no)
		(fp_line
			(start 0.7874 0.4064)
			(end -0.7874 0.4064)
			(stroke
				(width 0.1524)
				(type default)
			)
			(layer "F.SilkS")
		)
		(fp_line
			(start 0.7874 -0.4064)
			(end 0.7874 0.4064)
			(stroke
				(width 0.1524)
				(type default)
			)
			(layer "F.SilkS")
		)
		(fp_line
			(start -0.7874 0.4064)
			(end -0.7874 -0.4064)
			(stroke
				(width 0.1524)
				(type default)
			)
			(layer "F.SilkS")
		)
		(fp_line
			(start -0.7874 -0.4064)
			(end 0.7874 -0.4064)
			(stroke
				(width 0.1524)
				(type default)
			)
			(layer "F.SilkS")
		)
		(fp_line
			(start 0.67945 0.3048)
			(end 0.120396 0.3048)
			(stroke
				(width 0.1)
				(type default)
			)
			(layer "F.Fab")
		)
		(fp_line
			(start 0.67945 -0.3048)
			(end 0.67945 0.3048)
			(stroke
				(width 0.1)
				(type default)
			)
			(layer "F.Fab")
		)
		(fp_line
			(start 0.12065 -0.2794)
			(end 0.12065 -0.3048)
			(stroke
				(width 0.1)
				(type default)
			)
			(layer "F.Fab")
		)
		(fp_line
			(start 0.12065 -0.3048)
			(end 0.67945 -0.3048)
			(stroke
				(width 0.1)
				(type default)
			)
			(layer "F.Fab")
		)
		(fp_line
			(start 0.120396 0.3048)
			(end 0.120396 0.2794)
			(stroke
				(width 0.1)
				(type default)
			)
			(layer "F.Fab")
		)
		(fp_line
			(start 0.120396 0.2794)
			(end -0.12065 0.2794)
			(stroke
				(width 0.1)
				(type default)
			)
			(layer "F.Fab")
		)
		(fp_line
			(start -0.12065 0.3048)
			(end -0.67945 0.3048)
			(stroke
				(width 0.1)
				(type default)
			)
			(layer "F.Fab")
		)
		(fp_line
			(start -0.12065 0.2794)
			(end -0.12065 0.3048)
			(stroke
				(width 0.1)
				(type default)
			)
			(layer "F.Fab")
		)
		(fp_line
			(start -0.12065 -0.2794)
			(end 0.12065 -0.2794)
			(stroke
				(width 0.1)
				(type default)
			)
			(layer "F.Fab")
		)
		(fp_line
			(start -0.12065 -0.305054)
			(end -0.12065 -0.2794)
			(stroke
				(width 0.1)
				(type default)
			)
			(layer "F.Fab")
		)
		(fp_line
			(start -0.67945 0.3048)
			(end -0.67945 -0.305054)
			(stroke
				(width 0.1)
				(type default)
			)
			(layer "F.Fab")
		)
		(fp_line
			(start -0.67945 -0.305054)
			(end -0.12065 -0.305054)
			(stroke
				(width 0.1)
				(type default)
			)
			(layer "F.Fab")
		)
		(pad "1" smd rect
			(at -0.40005 0)
			(size 0.4572 0.508)
			(layers "F.Cu" "F.Mask" "F.Paste")
			(net "P1V8_CPU1_RT_1D")
		)
		(pad "2" smd rect
			(at 0.40005 0)
			(size 0.4572 0.508)
			(layers "F.Cu" "F.Mask" "F.Paste")
			(net "P1V8_CPU1_RT3_1A_1D")
		)
	)
	(footprint ""
		(layer "F.Cu")
		(at 194.183 -133.568948 90)
		(property "Reference" "R3482"
			(at 0 0 90)
			(layer "F.SilkS")
			(hide yes)
			(effects
				(font
					(size 1.27 1.27)
				)
			)
		)
		(property "Value" ""
			(at 0 0 90)
			(layer "F.Fab")
			(effects
				(font
					(size 1.27 1.27)
				)
			)
		)
		(duplicate_pad_numbers_are_jumpers no)
		(fp_line
			(start 0.7874 -0.4064)
			(end 0.7874 0.4064)
			(stroke
				(width 0.1524)
				(type default)
			)
			(layer "F.SilkS")
		)
		(fp_line
			(start -0.7874 -0.4064)
			(end 0.7874 -0.4064)
			(stroke
				(width 0.1524)
				(type default)
			)
			(layer "F.SilkS")
		)
		(fp_line
			(start 0.7874 0.4064)
			(end -0.7874 0.4064)
			(stroke
				(width 0.1524)
				(type default)
			)
			(layer "F.SilkS")
		)
		(fp_line
			(start -0.7874 0.4064)
			(end -0.7874 -0.4064)
			(stroke
				(width 0.1524)
				(type default)
			)
			(layer "F.SilkS")
		)
		(fp_line
			(start -0.12065 -0.305054)
			(end -0.12065 -0.2794)
			(stroke
				(width 0.1)
				(type default)
			)
			(layer "F.Fab")
		)
		(fp_line
			(start -0.67945 -0.305054)
			(end -0.12065 -0.305054)
			(stroke
				(width 0.1)
				(type default)
			)
			(layer "F.Fab")
		)
		(fp_line
			(start 0.67945 -0.3048)
			(end 0.67945 0.3048)
			(stroke
				(width 0.1)
				(type default)
			)
			(layer "F.Fab")
		)
		(fp_line
			(start 0.12065 -0.3048)
			(end 0.67945 -0.3048)
			(stroke
				(width 0.1)
				(type default)
			)
			(layer "F.Fab")
		)
		(fp_line
			(start 0.12065 -0.2794)
			(end 0.12065 -0.3048)
			(stroke
				(width 0.1)
				(type default)
			)
			(layer "F.Fab")
		)
		(fp_line
			(start -0.12065 -0.2794)
			(end 0.12065 -0.2794)
			(stroke
				(width 0.1)
				(type default)
			)
			(layer "F.Fab")
		)
		(fp_line
			(start 0.120396 0.2794)
			(end -0.12065 0.2794)
			(stroke
				(width 0.1)
				(type default)
			)
			(layer "F.Fab")
		)
		(fp_line
			(start -0.12065 0.2794)
			(end -0.12065 0.3048)
			(stroke
				(width 0.1)
				(type default)
			)
			(layer "F.Fab")
		)
		(fp_line
			(start 0.67945 0.3048)
			(end 0.120396 0.3048)
			(stroke
				(width 0.1)
				(type default)
			)
			(layer "F.Fab")
		)
		(fp_line
			(start 0.120396 0.3048)
			(end 0.120396 0.2794)
			(stroke
				(width 0.1)
				(type default)
			)
			(layer "F.Fab")
		)
		(fp_line
			(start -0.12065 0.3048)
			(end -0.67945 0.3048)
			(stroke
				(width 0.1)
				(type default)
			)
			(layer "F.Fab")
		)
		(fp_line
			(start -0.67945 0.3048)
			(end -0.67945 -0.305054)
			(stroke
				(width 0.1)
				(type default)
			)
			(layer "F.Fab")
		)
		(pad "1" smd circle
			(at -0.40005 0 90)
			(size 0 0)
			(layers "F.Cu" "F.Mask" "F.Paste")
			(net "GPU_FPGA_BOOT_EN_R")
		)
		(pad "2" smd circle
			(at 0.40005 0 90)
			(size 0 0)
			(layers "F.Cu" "F.Mask" "F.Paste")
			(net "GPU_FPGA_BOOT_EN")
		)
	)
	(footprint ""
		(layer "F.Cu")
		(at 185.799222 -22.097492 180)
		(property "Reference" "PR4002"
			(at 0 0 180)
			(layer "F.SilkS")
			(hide yes)
			(effects
				(font
					(size 1.27 1.27)
				)
			)
		)
		(property "Value" ""
			(at 0 0 180)
			(layer "F.Fab")
			(effects
				(font
					(size 1.27 1.27)
				)
			)
		)
		(duplicate_pad_numbers_are_jumpers no)
		(fp_line
			(start 0.7874 0.4064)
			(end -0.7874 0.4064)
			(stroke
				(width 0.1524)
				(type default)
			)
			(layer "F.SilkS")
		)
		(fp_line
			(start 0.7874 -0.4064)
			(end 0.7874 0.4064)
			(stroke
				(width 0.1524)
				(type default)
			)
			(layer "F.SilkS")
		)
		(fp_line
			(start -0.7874 0.4064)
			(end -0.7874 -0.4064)
			(stroke
				(width 0.1524)
				(type default)
			)
			(layer "F.SilkS")
		)
		(fp_line
			(start -0.7874 -0.4064)
			(end 0.7874 -0.4064)
			(stroke
				(width 0.1524)
				(type default)
			)
			(layer "F.SilkS")
		)
		(fp_line
			(start 0.67945 0.3048)
			(end 0.120396 0.3048)
			(stroke
				(width 0.1)
				(type default)
			)
			(layer "F.Fab")
		)
		(fp_line
			(start 0.67945 -0.3048)
			(end 0.67945 0.3048)
			(stroke
				(width 0.1)
				(type default)
			)
			(layer "F.Fab")
		)
		(fp_line
			(start 0.12065 -0.2794)
			(end 0.12065 -0.3048)
			(stroke
				(width 0.1)
				(type default)
			)
			(layer "F.Fab")
		)
		(fp_line
			(start 0.12065 -0.3048)
			(end 0.67945 -0.3048)
			(stroke
				(width 0.1)
				(type default)
			)
			(layer "F.Fab")
		)
		(fp_line
			(start 0.120396 0.3048)
			(end 0.120396 0.2794)
			(stroke
				(width 0.1)
				(type default)
			)
			(layer "F.Fab")
		)
		(fp_line
			(start 0.120396 0.2794)
			(end -0.12065 0.2794)
			(stroke
				(width 0.1)
				(type default)
			)
			(layer "F.Fab")
		)
		(fp_line
			(start -0.12065 0.3048)
			(end -0.67945 0.3048)
			(stroke
				(width 0.1)
				(type default)
			)
			(layer "F.Fab")
		)
		(fp_line
			(start -0.12065 0.2794)
			(end -0.12065 0.3048)
			(stroke
				(width 0.1)
				(type default)
			)
			(layer "F.Fab")
		)
		(fp_line
			(start -0.12065 -0.2794)
			(end 0.12065 -0.2794)
			(stroke
				(width 0.1)
				(type default)
			)
			(layer "F.Fab")
		)
		(fp_line
			(start -0.12065 -0.305054)
			(end -0.12065 -0.2794)
			(stroke
				(width 0.1)
				(type default)
			)
			(layer "F.Fab")
		)
		(fp_line
			(start -0.67945 0.3048)
			(end -0.67945 -0.305054)
			(stroke
				(width 0.1)
				(type default)
			)
			(layer "F.Fab")
		)
		(fp_line
			(start -0.67945 -0.305054)
			(end -0.12065 -0.305054)
			(stroke
				(width 0.1)
				(type default)
			)
			(layer "F.Fab")
		)
		(pad "1" smd circle
			(at -0.40005 0 180)
			(size 0 0)
			(layers "F.Cu" "F.Mask" "F.Paste")
			(net "P12V_SCM_OV")
		)
		(pad "2" smd circle
			(at 0.40005 0 180)
			(size 0 0)
			(layers "F.Cu" "F.Mask" "F.Paste")
			(net "GND")
		)
	)
	(footprint ""
		(layer "F.Cu")
		(at 68.225162 -34.874708 180)
		(property "Reference" "R1181"
			(at 0 0 180)
			(layer "F.SilkS")
			(hide yes)
			(effects
				(font
					(size 1.27 1.27)
				)
			)
		)
		(property "Value" ""
			(at 0 0 180)
			(layer "F.Fab")
			(effects
				(font
					(size 1.27 1.27)
				)
			)
		)
		(duplicate_pad_numbers_are_jumpers no)
		(fp_line
			(start 0.7874 0.4064)
			(end -0.7874 0.4064)
			(stroke
				(width 0.1524)
				(type default)
			)
			(layer "F.SilkS")
		)
		(fp_line
			(start 0.7874 -0.4064)
			(end 0.7874 0.4064)
			(stroke
				(width 0.1524)
				(type default)
			)
			(layer "F.SilkS")
		)
		(fp_line
			(start -0.7874 0.4064)
			(end -0.7874 -0.4064)
			(stroke
				(width 0.1524)
				(type default)
			)
			(layer "F.SilkS")
		)
		(fp_line
			(start -0.7874 -0.4064)
			(end 0.7874 -0.4064)
			(stroke
				(width 0.1524)
				(type default)
			)
			(layer "F.SilkS")
		)
		(fp_line
			(start 0.67945 0.3048)
			(end 0.120396 0.3048)
			(stroke
				(width 0.1)
				(type default)
			)
			(layer "F.Fab")
		)
		(fp_line
			(start 0.67945 -0.3048)
			(end 0.67945 0.3048)
			(stroke
				(width 0.1)
				(type default)
			)
			(layer "F.Fab")
		)
		(fp_line
			(start 0.12065 -0.2794)
			(end 0.12065 -0.3048)
			(stroke
				(width 0.1)
				(type default)
			)
			(layer "F.Fab")
		)
		(fp_line
			(start 0.12065 -0.3048)
			(end 0.67945 -0.3048)
			(stroke
				(width 0.1)
				(type default)
			)
			(layer "F.Fab")
		)
		(fp_line
			(start 0.120396 0.3048)
			(end 0.120396 0.2794)
			(stroke
				(width 0.1)
				(type default)
			)
			(layer "F.Fab")
		)
		(fp_line
			(start 0.120396 0.2794)
			(end -0.12065 0.2794)
			(stroke
				(width 0.1)
				(type default)
			)
			(layer "F.Fab")
		)
		(fp_line
			(start -0.12065 0.3048)
			(end -0.67945 0.3048)
			(stroke
				(width 0.1)
				(type default)
			)
			(layer "F.Fab")
		)
		(fp_line
			(start -0.12065 0.2794)
			(end -0.12065 0.3048)
			(stroke
				(width 0.1)
				(type default)
			)
			(layer "F.Fab")
		)
		(fp_line
			(start -0.12065 -0.2794)
			(end 0.12065 -0.2794)
			(stroke
				(width 0.1)
				(type default)
			)
			(layer "F.Fab")
		)
		(fp_line
			(start -0.12065 -0.305054)
			(end -0.12065 -0.2794)
			(stroke
				(width 0.1)
				(type default)
			)
			(layer "F.Fab")
		)
		(fp_line
			(start -0.67945 0.3048)
			(end -0.67945 -0.305054)
			(stroke
				(width 0.1)
				(type default)
			)
			(layer "F.Fab")
		)
		(fp_line
			(start -0.67945 -0.305054)
			(end -0.12065 -0.305054)
			(stroke
				(width 0.1)
				(type default)
			)
			(layer "F.Fab")
		)
		(pad "1" smd circle
			(at -0.40005 0 180)
			(size 0 0)
			(layers "F.Cu" "F.Mask" "F.Paste")
			(net "P12V_OCP_V3_2_BUF_EN_R")
		)
		(pad "2" smd circle
			(at 0.40005 0 180)
			(size 0 0)
			(layers "F.Cu" "F.Mask" "F.Paste")
			(net "P12V_OCP_EN_2_R")
		)
	)
	(footprint ""
		(layer "F.Cu")
		(at 303.573434 -427.1391 -90)
		(property "Reference" "Q130"
			(at 1.471676 -1.958848 90)
			(unlocked yes)
			(layer "F.SilkS")
			(effects
				(font
					(size 0.7874 0.5842)
					(thickness 0.1524)
				)
				(justify left)
			)
		)
		(property "Value" ""
			(at 0 0 270)
			(layer "F.Fab")
			(effects
				(font
					(size 1.27 1.27)
				)
			)
		)
		(duplicate_pad_numbers_are_jumpers no)
		(fp_line
			(start -1.332738 1.100074)
			(end -1.332738 -1.100074)
			(stroke
				(width 0.1524)
				(type default)
			)
			(layer "F.SilkS")
		)
		(fp_line
			(start 1.332738 1.100074)
			(end -1.332738 1.100074)
			(stroke
				(width 0.1524)
				(type default)
			)
			(layer "F.SilkS")
		)
		(fp_line
			(start 0 -0.541274)
			(end 0.4826 -1.100074)
			(stroke
				(width 0.1524)
				(type default)
			)
			(layer "F.SilkS")
		)
		(fp_line
			(start -1.332738 -1.100074)
			(end -0.4826 -1.100074)
			(stroke
				(width 0.1524)
				(type default)
			)
			(layer "F.SilkS")
		)
		(fp_line
			(start -0.4826 -1.100074)
			(end 0 -0.541274)
			(stroke
				(width 0.1524)
				(type default)
			)
			(layer "F.SilkS")
		)
		(fp_line
			(start 0.4826 -1.100074)
			(end 1.332738 -1.100074)
			(stroke
				(width 0.1524)
				(type default)
			)
			(layer "F.SilkS")
		)
		(fp_line
			(start 1.332738 -1.100074)
			(end 1.332738 1.100074)
			(stroke
				(width 0.1524)
				(type default)
			)
			(layer "F.SilkS")
		)
		(fp_poly
			(pts
				(xy -1.542542 -1.16332) (xy -2.287016 -1.411478) (xy -1.7907 -1.908048)
			)
			(stroke
				(width 0)
				(type default)
			)
			(fill yes)
			(layer "F.SilkS")
		)
		(fp_line
			(start -0.674878 1.100074)
			(end -0.674878 -1.100074)
			(stroke
				(width 0.1)
				(type default)
			)
			(layer "F.Fab")
		)
		(fp_line
			(start 0.674878 1.100074)
			(end -0.674878 1.100074)
			(stroke
				(width 0.1)
				(type default)
			)
			(layer "F.Fab")
		)
		(fp_line
			(start -0.674878 -1.100074)
			(end 0.674878 -1.100074)
			(stroke
				(width 0.1)
				(type default)
			)
			(layer "F.Fab")
		)
		(fp_line
			(start 0.674878 -1.100074)
			(end 0.674878 1.100074)
			(stroke
				(width 0.1)
				(type default)
			)
			(layer "F.Fab")
		)
		(fp_poly
			(pts
				(xy -2.2352 -0.298958) (xy -2.2352 -1.001014) (xy -1.533144 -0.649986)
			)
			(stroke
				(width 0)
				(type default)
			)
			(fill yes)
			(layer "F.Fab")
		)
		(pad "1" smd rect
			(at -0.94996 -0.649986)
			(size 0.4318 0.508)
			(layers "F.Cu" "F.Mask" "F.Paste")
			(net "GND")
		)
		(pad "2" smd rect
			(at -0.94996 0)
			(size 0.4318 0.508)
			(layers "F.Cu" "F.Mask" "F.Paste")
			(net "GPU_3V3IO_RSVD3_FFU")
		)
		(pad "3" smd rect
			(at -0.94996 0.649986)
			(size 0.4318 0.508)
			(layers "F.Cu" "F.Mask" "F.Paste")
			(net "GPU_3V3IO_RSVD3_FFU_ISO")
		)
		(pad "4" smd rect
			(at 0.94996 0.649986)
			(size 0.4318 0.508)
			(layers "F.Cu" "F.Mask" "F.Paste")
			(net "GND")
		)
		(pad "5" smd rect
			(at 0.94996 0)
			(size 0.4318 0.508)
			(layers "F.Cu" "F.Mask" "F.Paste")
			(net "GPU_3V3IO_RSVD3_FFU_N")
		)
		(pad "6" smd rect
			(at 0.94996 -0.649986)
			(size 0.4318 0.508)
			(layers "F.Cu" "F.Mask" "F.Paste")
			(net "GPU_3V3IO_RSVD3_FFU_N")
		)
	)
	(footprint ""
		(layer "F.Cu")
		(at 118.718584 -61.916056 180)
		(property "Reference" "R1748"
			(at 0 0 180)
			(layer "F.SilkS")
			(hide yes)
			(effects
				(font
					(size 1.27 1.27)
				)
			)
		)
		(property "Value" ""
			(at 0 0 180)
			(layer "F.Fab")
			(effects
				(font
					(size 1.27 1.27)
				)
			)
		)
		(duplicate_pad_numbers_are_jumpers no)
		(fp_line
			(start 0.7874 0.4064)
			(end -0.7874 0.4064)
			(stroke
				(width 0.1524)
				(type default)
			)
			(layer "F.SilkS")
		)
		(fp_line
			(start 0.7874 -0.4064)
			(end 0.7874 0.4064)
			(stroke
				(width 0.1524)
				(type default)
			)
			(layer "F.SilkS")
		)
		(fp_line
			(start -0.7874 0.4064)
			(end -0.7874 -0.4064)
			(stroke
				(width 0.1524)
				(type default)
			)
			(layer "F.SilkS")
		)
		(fp_line
			(start -0.7874 -0.4064)
			(end 0.7874 -0.4064)
			(stroke
				(width 0.1524)
				(type default)
			)
			(layer "F.SilkS")
		)
		(fp_line
			(start 0.67945 0.3048)
			(end 0.120396 0.3048)
			(stroke
				(width 0.1)
				(type default)
			)
			(layer "F.Fab")
		)
		(fp_line
			(start 0.67945 -0.3048)
			(end 0.67945 0.3048)
			(stroke
				(width 0.1)
				(type default)
			)
			(layer "F.Fab")
		)
		(fp_line
			(start 0.12065 -0.2794)
			(end 0.12065 -0.3048)
			(stroke
				(width 0.1)
				(type default)
			)
			(layer "F.Fab")
		)
		(fp_line
			(start 0.12065 -0.3048)
			(end 0.67945 -0.3048)
			(stroke
				(width 0.1)
				(type default)
			)
			(layer "F.Fab")
		)
		(fp_line
			(start 0.120396 0.3048)
			(end 0.120396 0.2794)
			(stroke
				(width 0.1)
				(type default)
			)
			(layer "F.Fab")
		)
		(fp_line
			(start 0.120396 0.2794)
			(end -0.12065 0.2794)
			(stroke
				(width 0.1)
				(type default)
			)
			(layer "F.Fab")
		)
		(fp_line
			(start -0.12065 0.3048)
			(end -0.67945 0.3048)
			(stroke
				(width 0.1)
				(type default)
			)
			(layer "F.Fab")
		)
		(fp_line
			(start -0.12065 0.2794)
			(end -0.12065 0.3048)
			(stroke
				(width 0.1)
				(type default)
			)
			(layer "F.Fab")
		)
		(fp_line
			(start -0.12065 -0.2794)
			(end 0.12065 -0.2794)
			(stroke
				(width 0.1)
				(type default)
			)
			(layer "F.Fab")
		)
		(fp_line
			(start -0.12065 -0.305054)
			(end -0.12065 -0.2794)
			(stroke
				(width 0.1)
				(type default)
			)
			(layer "F.Fab")
		)
		(fp_line
			(start -0.67945 0.3048)
			(end -0.67945 -0.305054)
			(stroke
				(width 0.1)
				(type default)
			)
			(layer "F.Fab")
		)
		(fp_line
			(start -0.67945 -0.305054)
			(end -0.12065 -0.305054)
			(stroke
				(width 0.1)
				(type default)
			)
			(layer "F.Fab")
		)
		(pad "1" smd circle
			(at -0.40005 0 180)
			(size 0 0)
			(layers "F.Cu" "F.Mask" "F.Paste")
			(net "JTAG_SCM_MUX_TCK")
		)
		(pad "2" smd circle
			(at 0.40005 0 180)
			(size 0 0)
			(layers "F.Cu" "F.Mask" "F.Paste")
			(net "GND")
		)
	)
	(footprint ""
		(layer "F.Cu")
		(at 181.9402 -96.103948 -90)
		(property "Reference" "R179"
			(at 0 0 270)
			(layer "F.SilkS")
			(hide yes)
			(effects
				(font
					(size 1.27 1.27)
				)
			)
		)
		(property "Value" ""
			(at 0 0 270)
			(layer "F.Fab")
			(effects
				(font
					(size 1.27 1.27)
				)
			)
		)
		(duplicate_pad_numbers_are_jumpers no)
		(fp_line
			(start -0.7874 0.4064)
			(end -0.7874 -0.4064)
			(stroke
				(width 0.1524)
				(type default)
			)
			(layer "F.SilkS")
		)
		(fp_line
			(start 0.7874 0.4064)
			(end -0.7874 0.4064)
			(stroke
				(width 0.1524)
				(type default)
			)
			(layer "F.SilkS")
		)
		(fp_line
			(start -0.7874 -0.4064)
			(end 0.7874 -0.4064)
			(stroke
				(width 0.1524)
				(type default)
			)
			(layer "F.SilkS")
		)
		(fp_line
			(start 0.7874 -0.4064)
			(end 0.7874 0.4064)
			(stroke
				(width 0.1524)
				(type default)
			)
			(layer "F.SilkS")
		)
		(fp_line
			(start -0.67945 0.3048)
			(end -0.67945 -0.305054)
			(stroke
				(width 0.1)
				(type default)
			)
			(layer "F.Fab")
		)
		(fp_line
			(start -0.12065 0.3048)
			(end -0.67945 0.3048)
			(stroke
				(width 0.1)
				(type default)
			)
			(layer "F.Fab")
		)
		(fp_line
			(start 0.120396 0.3048)
			(end 0.120396 0.2794)
			(stroke
				(width 0.1)
				(type default)
			)
			(layer "F.Fab")
		)
		(fp_line
			(start 0.67945 0.3048)
			(end 0.120396 0.3048)
			(stroke
				(width 0.1)
				(type default)
			)
			(layer "F.Fab")
		)
		(fp_line
			(start -0.12065 0.2794)
			(end -0.12065 0.3048)
			(stroke
				(width 0.1)
				(type default)
			)
			(layer "F.Fab")
		)
		(fp_line
			(start 0.120396 0.2794)
			(end -0.12065 0.2794)
			(stroke
				(width 0.1)
				(type default)
			)
			(layer "F.Fab")
		)
		(fp_line
			(start -0.12065 -0.2794)
			(end 0.12065 -0.2794)
			(stroke
				(width 0.1)
				(type default)
			)
			(layer "F.Fab")
		)
		(fp_line
			(start 0.12065 -0.2794)
			(end 0.12065 -0.3048)
			(stroke
				(width 0.1)
				(type default)
			)
			(layer "F.Fab")
		)
		(fp_line
			(start 0.12065 -0.3048)
			(end 0.67945 -0.3048)
			(stroke
				(width 0.1)
				(type default)
			)
			(layer "F.Fab")
		)
		(fp_line
			(start 0.67945 -0.3048)
			(end 0.67945 0.3048)
			(stroke
				(width 0.1)
				(type default)
			)
			(layer "F.Fab")
		)
		(fp_line
			(start -0.67945 -0.305054)
			(end -0.12065 -0.305054)
			(stroke
				(width 0.1)
				(type default)
			)
			(layer "F.Fab")
		)
		(fp_line
			(start -0.12065 -0.305054)
			(end -0.12065 -0.2794)
			(stroke
				(width 0.1)
				(type default)
			)
			(layer "F.Fab")
		)
		(pad "1" smd circle
			(at -0.40005 0 270)
			(size 0 0)
			(layers "F.Cu" "F.Mask" "F.Paste")
			(net "FM_CPU0_PROCHOT_R_N")
		)
		(pad "2" smd circle
			(at 0.40005 0 270)
			(size 0 0)
			(layers "F.Cu" "F.Mask" "F.Paste")
			(net "CPU0_PROCHOT_N")
		)
	)
	(footprint ""
		(layer "F.Cu")
		(at 320.921888 -22.571456 90)
		(property "Reference" "R130"
			(at 0 0 90)
			(layer "F.SilkS")
			(hide yes)
			(effects
				(font
					(size 1.27 1.27)
				)
			)
		)
		(property "Value" ""
			(at 0 0 90)
			(layer "F.Fab")
			(effects
				(font
					(size 1.27 1.27)
				)
			)
		)
		(duplicate_pad_numbers_are_jumpers no)
		(fp_line
			(start 0.7874 -0.4064)
			(end 0.7874 0.4064)
			(stroke
				(width 0.1524)
				(type default)
			)
			(layer "F.SilkS")
		)
		(fp_line
			(start -0.7874 -0.4064)
			(end 0.7874 -0.4064)
			(stroke
				(width 0.1524)
				(type default)
			)
			(layer "F.SilkS")
		)
		(fp_line
			(start 0.7874 0.4064)
			(end -0.7874 0.4064)
			(stroke
				(width 0.1524)
				(type default)
			)
			(layer "F.SilkS")
		)
		(fp_line
			(start -0.7874 0.4064)
			(end -0.7874 -0.4064)
			(stroke
				(width 0.1524)
				(type default)
			)
			(layer "F.SilkS")
		)
		(fp_line
			(start -0.12065 -0.305054)
			(end -0.12065 -0.2794)
			(stroke
				(width 0.1)
				(type default)
			)
			(layer "F.Fab")
		)
		(fp_line
			(start -0.67945 -0.305054)
			(end -0.12065 -0.305054)
			(stroke
				(width 0.1)
				(type default)
			)
			(layer "F.Fab")
		)
		(fp_line
			(start 0.67945 -0.3048)
			(end 0.67945 0.3048)
			(stroke
				(width 0.1)
				(type default)
			)
			(layer "F.Fab")
		)
		(fp_line
			(start 0.12065 -0.3048)
			(end 0.67945 -0.3048)
			(stroke
				(width 0.1)
				(type default)
			)
			(layer "F.Fab")
		)
		(fp_line
			(start 0.12065 -0.2794)
			(end 0.12065 -0.3048)
			(stroke
				(width 0.1)
				(type default)
			)
			(layer "F.Fab")
		)
		(fp_line
			(start -0.12065 -0.2794)
			(end 0.12065 -0.2794)
			(stroke
				(width 0.1)
				(type default)
			)
			(layer "F.Fab")
		)
		(fp_line
			(start 0.120396 0.2794)
			(end -0.12065 0.2794)
			(stroke
				(width 0.1)
				(type default)
			)
			(layer "F.Fab")
		)
		(fp_line
			(start -0.12065 0.2794)
			(end -0.12065 0.3048)
			(stroke
				(width 0.1)
				(type default)
			)
			(layer "F.Fab")
		)
		(fp_line
			(start 0.67945 0.3048)
			(end 0.120396 0.3048)
			(stroke
				(width 0.1)
				(type default)
			)
			(layer "F.Fab")
		)
		(fp_line
			(start 0.120396 0.3048)
			(end 0.120396 0.2794)
			(stroke
				(width 0.1)
				(type default)
			)
			(layer "F.Fab")
		)
		(fp_line
			(start -0.12065 0.3048)
			(end -0.67945 0.3048)
			(stroke
				(width 0.1)
				(type default)
			)
			(layer "F.Fab")
		)
		(fp_line
			(start -0.67945 0.3048)
			(end -0.67945 -0.305054)
			(stroke
				(width 0.1)
				(type default)
			)
			(layer "F.Fab")
		)
		(pad "1" smd circle
			(at -0.40005 0 90)
			(size 0 0)
			(layers "F.Cu" "F.Mask" "F.Paste")
			(net "UART_VCC_J8")
		)
		(pad "2" smd circle
			(at 0.40005 0 90)
			(size 0 0)
			(layers "F.Cu" "F.Mask" "F.Paste")
			(net "P5V_AUX")
		)
	)
	(footprint ""
		(layer "F.Cu")
		(at 330.523342 -393.86256)
		(property "Reference" "R1027"
			(at 0 0 0)
			(layer "F.SilkS")
			(hide yes)
			(effects
				(font
					(size 1.27 1.27)
				)
			)
		)
		(property "Value" ""
			(at 0 0 0)
			(layer "F.Fab")
			(effects
				(font
					(size 1.27 1.27)
				)
			)
		)
		(duplicate_pad_numbers_are_jumpers no)
		(fp_line
			(start -0.32512 -0.175006)
			(end 0.32512 -0.175006)
			(stroke
				(width 0.1)
				(type default)
			)
			(layer "F.Fab")
		)
		(fp_line
			(start -0.32512 0.175006)
			(end -0.32512 -0.175006)
			(stroke
				(width 0.1)
				(type default)
			)
			(layer "F.Fab")
		)
		(fp_line
			(start 0.32512 -0.175006)
			(end 0.32512 0.175006)
			(stroke
				(width 0.1)
				(type default)
			)
			(layer "F.Fab")
		)
		(fp_line
			(start 0.32512 0.175006)
			(end -0.32512 0.175006)
			(stroke
				(width 0.1)
				(type default)
			)
			(layer "F.Fab")
		)
		(pad "1" smd rect
			(at -0.2667 0)
			(size 0.3048 0.381)
			(layers "F.Cu" "F.Mask" "F.Paste")
			(net "P1V8_CPU0_RT_1D")
		)
		(pad "2" smd rect
			(at 0.2667 0 180)
			(size 0.3048 0.381)
			(layers "F.Cu" "F.Mask" "F.Paste")
			(net "GPIO2_RT_CPU0_P1")
		)
	)
	(footprint ""
		(layer "F.Cu")
		(at 152.018492 -117.944646 180)
		(property "Reference" "C1561"
			(at 0 0 180)
			(layer "F.SilkS")
			(hide yes)
			(effects
				(font
					(size 1.27 1.27)
				)
			)
		)
		(property "Value" ""
			(at 0 0 180)
			(layer "F.Fab")
			(effects
				(font
					(size 1.27 1.27)
				)
			)
		)
		(duplicate_pad_numbers_are_jumpers no)
		(fp_line
			(start 0.7874 0.4064)
			(end -0.7874 0.4064)
			(stroke
				(width 0.1524)
				(type default)
			)
			(layer "F.SilkS")
		)
		(fp_line
			(start 0.7874 -0.4064)
			(end 0.7874 0.4064)
			(stroke
				(width 0.1524)
				(type default)
			)
			(layer "F.SilkS")
		)
		(fp_line
			(start -0.7874 0.4064)
			(end -0.7874 -0.4064)
			(stroke
				(width 0.1524)
				(type default)
			)
			(layer "F.SilkS")
		)
		(fp_line
			(start -0.7874 -0.4064)
			(end 0.7874 -0.4064)
			(stroke
				(width 0.1524)
				(type default)
			)
			(layer "F.SilkS")
		)
		(fp_line
			(start 0.67945 0.3048)
			(end 0.120396 0.3048)
			(stroke
				(width 0.1)
				(type default)
			)
			(layer "F.Fab")
		)
		(fp_line
			(start 0.67945 -0.3048)
			(end 0.67945 0.3048)
			(stroke
				(width 0.1)
				(type default)
			)
			(layer "F.Fab")
		)
		(fp_line
			(start 0.12065 -0.2794)
			(end 0.12065 -0.3048)
			(stroke
				(width 0.1)
				(type default)
			)
			(layer "F.Fab")
		)
		(fp_line
			(start 0.12065 -0.3048)
			(end 0.67945 -0.3048)
			(stroke
				(width 0.1)
				(type default)
			)
			(layer "F.Fab")
		)
		(fp_line
			(start 0.120396 0.3048)
			(end 0.120396 0.2794)
			(stroke
				(width 0.1)
				(type default)
			)
			(layer "F.Fab")
		)
		(fp_line
			(start 0.120396 0.2794)
			(end -0.12065 0.2794)
			(stroke
				(width 0.1)
				(type default)
			)
			(layer "F.Fab")
		)
		(fp_line
			(start -0.12065 0.3048)
			(end -0.67945 0.3048)
			(stroke
				(width 0.1)
				(type default)
			)
			(layer "F.Fab")
		)
		(fp_line
			(start -0.12065 0.2794)
			(end -0.12065 0.3048)
			(stroke
				(width 0.1)
				(type default)
			)
			(layer "F.Fab")
		)
		(fp_line
			(start -0.12065 -0.2794)
			(end 0.12065 -0.2794)
			(stroke
				(width 0.1)
				(type default)
			)
			(layer "F.Fab")
		)
		(fp_line
			(start -0.12065 -0.305054)
			(end -0.12065 -0.2794)
			(stroke
				(width 0.1)
				(type default)
			)
			(layer "F.Fab")
		)
		(fp_line
			(start -0.67945 0.3048)
			(end -0.67945 -0.305054)
			(stroke
				(width 0.1)
				(type default)
			)
			(layer "F.Fab")
		)
		(fp_line
			(start -0.67945 -0.305054)
			(end -0.12065 -0.305054)
			(stroke
				(width 0.1)
				(type default)
			)
			(layer "F.Fab")
		)
		(pad "1" smd circle
			(at -0.40005 0 180)
			(size 0 0)
			(layers "F.Cu" "F.Mask" "F.Paste")
			(net "U206_VS")
		)
		(pad "2" smd circle
			(at 0.40005 0 180)
			(size 0 0)
			(layers "F.Cu" "F.Mask" "F.Paste")
			(net "GND")
		)
	)
	(footprint ""
		(layer "F.Cu")
		(at 77.215746 -394.166852 -90)
		(property "Reference" "R752"
			(at 0 0 270)
			(layer "F.SilkS")
			(hide yes)
			(effects
				(font
					(size 1.27 1.27)
				)
			)
		)
		(property "Value" ""
			(at 0 0 270)
			(layer "F.Fab")
			(effects
				(font
					(size 1.27 1.27)
				)
			)
		)
		(duplicate_pad_numbers_are_jumpers no)
		(fp_line
			(start -0.32512 0.175006)
			(end -0.32512 -0.175006)
			(stroke
				(width 0.1)
				(type default)
			)
			(layer "F.Fab")
		)
		(fp_line
			(start 0.32512 0.175006)
			(end -0.32512 0.175006)
			(stroke
				(width 0.1)
				(type default)
			)
			(layer "F.Fab")
		)
		(fp_line
			(start -0.32512 -0.175006)
			(end 0.32512 -0.175006)
			(stroke
				(width 0.1)
				(type default)
			)
			(layer "F.Fab")
		)
		(fp_line
			(start 0.32512 -0.175006)
			(end 0.32512 0.175006)
			(stroke
				(width 0.1)
				(type default)
			)
			(layer "F.Fab")
		)
		(pad "1" smd rect
			(at -0.2667 0 270)
			(size 0.3048 0.381)
			(layers "F.Cu" "F.Mask" "F.Paste")
			(net "RST_RT_CPU1_P1_RESET_R_N")
		)
		(pad "2" smd rect
			(at 0.2667 0 90)
			(size 0.3048 0.381)
			(layers "F.Cu" "F.Mask" "F.Paste")
			(net "GND")
		)
	)
	(footprint ""
		(layer "F.Cu")
		(at 250.55957 -68.946522)
		(property "Reference" "R4063"
			(at 0 0 0)
			(layer "F.SilkS")
			(hide yes)
			(effects
				(font
					(size 1.27 1.27)
				)
			)
		)
		(property "Value" ""
			(at 0 0 0)
			(layer "F.Fab")
			(effects
				(font
					(size 1.27 1.27)
				)
			)
		)
		(duplicate_pad_numbers_are_jumpers no)
		(fp_line
			(start -0.7874 -0.4064)
			(end 0.7874 -0.4064)
			(stroke
				(width 0.1524)
				(type default)
			)
			(layer "F.SilkS")
		)
		(fp_line
			(start -0.7874 0.4064)
			(end -0.7874 -0.4064)
			(stroke
				(width 0.1524)
				(type default)
			)
			(layer "F.SilkS")
		)
		(fp_line
			(start 0.7874 -0.4064)
			(end 0.7874 0.4064)
			(stroke
				(width 0.1524)
				(type default)
			)
			(layer "F.SilkS")
		)
		(fp_line
			(start 0.7874 0.4064)
			(end -0.7874 0.4064)
			(stroke
				(width 0.1524)
				(type default)
			)
			(layer "F.SilkS")
		)
		(fp_line
			(start -0.67945 -0.305054)
			(end -0.12065 -0.305054)
			(stroke
				(width 0.1)
				(type default)
			)
			(layer "F.Fab")
		)
		(fp_line
			(start -0.67945 0.3048)
			(end -0.67945 -0.305054)
			(stroke
				(width 0.1)
				(type default)
			)
			(layer "F.Fab")
		)
		(fp_line
			(start -0.12065 -0.305054)
			(end -0.12065 -0.2794)
			(stroke
				(width 0.1)
				(type default)
			)
			(layer "F.Fab")
		)
		(fp_line
			(start -0.12065 -0.2794)
			(end 0.12065 -0.2794)
			(stroke
				(width 0.1)
				(type default)
			)
			(layer "F.Fab")
		)
		(fp_line
			(start -0.12065 0.2794)
			(end -0.12065 0.3048)
			(stroke
				(width 0.1)
				(type default)
			)
			(layer "F.Fab")
		)
		(fp_line
			(start -0.12065 0.3048)
			(end -0.67945 0.3048)
			(stroke
				(width 0.1)
				(type default)
			)
			(layer "F.Fab")
		)
		(fp_line
			(start 0.120396 0.2794)
			(end -0.12065 0.2794)
			(stroke
				(width 0.1)
				(type default)
			)
			(layer "F.Fab")
		)
		(fp_line
			(start 0.120396 0.3048)
			(end 0.120396 0.2794)
			(stroke
				(width 0.1)
				(type default)
			)
			(layer "F.Fab")
		)
		(fp_line
			(start 0.12065 -0.3048)
			(end 0.67945 -0.3048)
			(stroke
				(width 0.1)
				(type default)
			)
			(layer "F.Fab")
		)
		(fp_line
			(start 0.12065 -0.2794)
			(end 0.12065 -0.3048)
			(stroke
				(width 0.1)
				(type default)
			)
			(layer "F.Fab")
		)
		(fp_line
			(start 0.67945 -0.3048)
			(end 0.67945 0.3048)
			(stroke
				(width 0.1)
				(type default)
			)
			(layer "F.Fab")
		)
		(fp_line
			(start 0.67945 0.3048)
			(end 0.120396 0.3048)
			(stroke
				(width 0.1)
				(type default)
			)
			(layer "F.Fab")
		)
		(pad "1" smd circle
			(at -0.40005 0)
			(size 0 0)
			(layers "F.Cu" "F.Mask" "F.Paste")
			(net "E1S_0_P3V3_EN")
		)
		(pad "2" smd circle
			(at 0.40005 0)
			(size 0 0)
			(layers "F.Cu" "F.Mask" "F.Paste")
			(net "P3V3_E1S_EN_0_R")
		)
	)
	(footprint ""
		(layer "F.Cu")
		(at 95.39097 -60.86221 180)
		(property "Reference" "PR3795"
			(at 0 0 180)
			(layer "F.SilkS")
			(hide yes)
			(effects
				(font
					(size 1.27 1.27)
				)
			)
		)
		(property "Value" ""
			(at 0 0 180)
			(layer "F.Fab")
			(effects
				(font
					(size 1.27 1.27)
				)
			)
		)
		(duplicate_pad_numbers_are_jumpers no)
		(fp_line
			(start 0.7874 0.4064)
			(end -0.7874 0.4064)
			(stroke
				(width 0.1524)
				(type default)
			)
			(layer "F.SilkS")
		)
		(fp_line
			(start 0.7874 -0.4064)
			(end 0.7874 0.4064)
			(stroke
				(width 0.1524)
				(type default)
			)
			(layer "F.SilkS")
		)
		(fp_line
			(start -0.7874 0.4064)
			(end -0.7874 -0.4064)
			(stroke
				(width 0.1524)
				(type default)
			)
			(layer "F.SilkS")
		)
		(fp_line
			(start -0.7874 -0.4064)
			(end 0.7874 -0.4064)
			(stroke
				(width 0.1524)
				(type default)
			)
			(layer "F.SilkS")
		)
		(fp_line
			(start 0.67945 0.3048)
			(end 0.120396 0.3048)
			(stroke
				(width 0.1)
				(type default)
			)
			(layer "F.Fab")
		)
		(fp_line
			(start 0.67945 -0.3048)
			(end 0.67945 0.3048)
			(stroke
				(width 0.1)
				(type default)
			)
			(layer "F.Fab")
		)
		(fp_line
			(start 0.12065 -0.2794)
			(end 0.12065 -0.3048)
			(stroke
				(width 0.1)
				(type default)
			)
			(layer "F.Fab")
		)
		(fp_line
			(start 0.12065 -0.3048)
			(end 0.67945 -0.3048)
			(stroke
				(width 0.1)
				(type default)
			)
			(layer "F.Fab")
		)
		(fp_line
			(start 0.120396 0.3048)
			(end 0.120396 0.2794)
			(stroke
				(width 0.1)
				(type default)
			)
			(layer "F.Fab")
		)
		(fp_line
			(start 0.120396 0.2794)
			(end -0.12065 0.2794)
			(stroke
				(width 0.1)
				(type default)
			)
			(layer "F.Fab")
		)
		(fp_line
			(start -0.12065 0.3048)
			(end -0.67945 0.3048)
			(stroke
				(width 0.1)
				(type default)
			)
			(layer "F.Fab")
		)
		(fp_line
			(start -0.12065 0.2794)
			(end -0.12065 0.3048)
			(stroke
				(width 0.1)
				(type default)
			)
			(layer "F.Fab")
		)
		(fp_line
			(start -0.12065 -0.2794)
			(end 0.12065 -0.2794)
			(stroke
				(width 0.1)
				(type default)
			)
			(layer "F.Fab")
		)
		(fp_line
			(start -0.12065 -0.305054)
			(end -0.12065 -0.2794)
			(stroke
				(width 0.1)
				(type default)
			)
			(layer "F.Fab")
		)
		(fp_line
			(start -0.67945 0.3048)
			(end -0.67945 -0.305054)
			(stroke
				(width 0.1)
				(type default)
			)
			(layer "F.Fab")
		)
		(fp_line
			(start -0.67945 -0.305054)
			(end -0.12065 -0.305054)
			(stroke
				(width 0.1)
				(type default)
			)
			(layer "F.Fab")
		)
		(pad "1" smd circle
			(at -0.40005 0 180)
			(size 0 0)
			(layers "F.Cu" "F.Mask" "F.Paste")
			(net "P3V3_AUX")
		)
		(pad "2" smd circle
			(at 0.40005 0 180)
			(size 0 0)
			(layers "F.Cu" "F.Mask" "F.Paste")
			(net "P3V3_OCP_UV_2")
		)
	)
	(footprint ""
		(layer "F.Cu")
		(at 38.0746 -435.448964 -90)
		(property "Reference" "R2918"
			(at 0 0 270)
			(layer "F.SilkS")
			(hide yes)
			(effects
				(font
					(size 1.27 1.27)
				)
			)
		)
		(property "Value" ""
			(at 0 0 270)
			(layer "F.Fab")
			(effects
				(font
					(size 1.27 1.27)
				)
			)
		)
		(duplicate_pad_numbers_are_jumpers no)
		(fp_line
			(start -0.7874 0.4064)
			(end -0.7874 -0.4064)
			(stroke
				(width 0.1524)
				(type default)
			)
			(layer "F.SilkS")
		)
		(fp_line
			(start 0.7874 0.4064)
			(end -0.7874 0.4064)
			(stroke
				(width 0.1524)
				(type default)
			)
			(layer "F.SilkS")
		)
		(fp_line
			(start -0.7874 -0.4064)
			(end 0.7874 -0.4064)
			(stroke
				(width 0.1524)
				(type default)
			)
			(layer "F.SilkS")
		)
		(fp_line
			(start 0.7874 -0.4064)
			(end 0.7874 0.4064)
			(stroke
				(width 0.1524)
				(type default)
			)
			(layer "F.SilkS")
		)
		(fp_line
			(start -0.67945 0.3048)
			(end -0.67945 -0.305054)
			(stroke
				(width 0.1)
				(type default)
			)
			(layer "F.Fab")
		)
		(fp_line
			(start -0.12065 0.3048)
			(end -0.67945 0.3048)
			(stroke
				(width 0.1)
				(type default)
			)
			(layer "F.Fab")
		)
		(fp_line
			(start 0.120396 0.3048)
			(end 0.120396 0.2794)
			(stroke
				(width 0.1)
				(type default)
			)
			(layer "F.Fab")
		)
		(fp_line
			(start 0.67945 0.3048)
			(end 0.120396 0.3048)
			(stroke
				(width 0.1)
				(type default)
			)
			(layer "F.Fab")
		)
		(fp_line
			(start -0.12065 0.2794)
			(end -0.12065 0.3048)
			(stroke
				(width 0.1)
				(type default)
			)
			(layer "F.Fab")
		)
		(fp_line
			(start 0.120396 0.2794)
			(end -0.12065 0.2794)
			(stroke
				(width 0.1)
				(type default)
			)
			(layer "F.Fab")
		)
		(fp_line
			(start -0.12065 -0.2794)
			(end 0.12065 -0.2794)
			(stroke
				(width 0.1)
				(type default)
			)
			(layer "F.Fab")
		)
		(fp_line
			(start 0.12065 -0.2794)
			(end 0.12065 -0.3048)
			(stroke
				(width 0.1)
				(type default)
			)
			(layer "F.Fab")
		)
		(fp_line
			(start 0.12065 -0.3048)
			(end 0.67945 -0.3048)
			(stroke
				(width 0.1)
				(type default)
			)
			(layer "F.Fab")
		)
		(fp_line
			(start 0.67945 -0.3048)
			(end 0.67945 0.3048)
			(stroke
				(width 0.1)
				(type default)
			)
			(layer "F.Fab")
		)
		(fp_line
			(start -0.67945 -0.305054)
			(end -0.12065 -0.305054)
			(stroke
				(width 0.1)
				(type default)
			)
			(layer "F.Fab")
		)
		(fp_line
			(start -0.12065 -0.305054)
			(end -0.12065 -0.2794)
			(stroke
				(width 0.1)
				(type default)
			)
			(layer "F.Fab")
		)
		(pad "1" smd circle
			(at -0.40005 0 270)
			(size 0 0)
			(layers "F.Cu" "F.Mask" "F.Paste")
			(net "FM_SWB_PWR_EN_R")
		)
		(pad "2" smd circle
			(at 0.40005 0 270)
			(size 0 0)
			(layers "F.Cu" "F.Mask" "F.Paste")
			(net "GND")
		)
	)
	(footprint ""
		(layer "F.Cu")
		(at 427.834552 -355.524562)
		(property "Reference" "PC207_1"
			(at 0 0 0)
			(layer "F.SilkS")
			(hide yes)
			(effects
				(font
					(size 1.27 1.27)
				)
			)
		)
		(property "Value" ""
			(at 0 0 0)
			(layer "F.Fab")
			(effects
				(font
					(size 1.27 1.27)
				)
			)
		)
		(duplicate_pad_numbers_are_jumpers no)
		(fp_line
			(start -0.7874 -0.4064)
			(end 0.7874 -0.4064)
			(stroke
				(width 0.1524)
				(type default)
			)
			(layer "F.SilkS")
		)
		(fp_line
			(start -0.7874 0.4064)
			(end -0.7874 -0.4064)
			(stroke
				(width 0.1524)
				(type default)
			)
			(layer "F.SilkS")
		)
		(fp_line
			(start 0.7874 -0.4064)
			(end 0.7874 0.4064)
			(stroke
				(width 0.1524)
				(type default)
			)
			(layer "F.SilkS")
		)
		(fp_line
			(start 0.7874 0.4064)
			(end -0.7874 0.4064)
			(stroke
				(width 0.1524)
				(type default)
			)
			(layer "F.SilkS")
		)
		(fp_line
			(start -0.67945 -0.305054)
			(end -0.12065 -0.305054)
			(stroke
				(width 0.1)
				(type default)
			)
			(layer "F.Fab")
		)
		(fp_line
			(start -0.67945 0.3048)
			(end -0.67945 -0.305054)
			(stroke
				(width 0.1)
				(type default)
			)
			(layer "F.Fab")
		)
		(fp_line
			(start -0.12065 -0.305054)
			(end -0.12065 -0.2794)
			(stroke
				(width 0.1)
				(type default)
			)
			(layer "F.Fab")
		)
		(fp_line
			(start -0.12065 -0.2794)
			(end 0.12065 -0.2794)
			(stroke
				(width 0.1)
				(type default)
			)
			(layer "F.Fab")
		)
		(fp_line
			(start -0.12065 0.2794)
			(end -0.12065 0.3048)
			(stroke
				(width 0.1)
				(type default)
			)
			(layer "F.Fab")
		)
		(fp_line
			(start -0.12065 0.3048)
			(end -0.67945 0.3048)
			(stroke
				(width 0.1)
				(type default)
			)
			(layer "F.Fab")
		)
		(fp_line
			(start 0.120396 0.2794)
			(end -0.12065 0.2794)
			(stroke
				(width 0.1)
				(type default)
			)
			(layer "F.Fab")
		)
		(fp_line
			(start 0.120396 0.3048)
			(end 0.120396 0.2794)
			(stroke
				(width 0.1)
				(type default)
			)
			(layer "F.Fab")
		)
		(fp_line
			(start 0.12065 -0.3048)
			(end 0.67945 -0.3048)
			(stroke
				(width 0.1)
				(type default)
			)
			(layer "F.Fab")
		)
		(fp_line
			(start 0.12065 -0.2794)
			(end 0.12065 -0.3048)
			(stroke
				(width 0.1)
				(type default)
			)
			(layer "F.Fab")
		)
		(fp_line
			(start 0.67945 -0.3048)
			(end 0.67945 0.3048)
			(stroke
				(width 0.1)
				(type default)
			)
			(layer "F.Fab")
		)
		(fp_line
			(start 0.67945 0.3048)
			(end 0.120396 0.3048)
			(stroke
				(width 0.1)
				(type default)
			)
			(layer "F.Fab")
		)
		(pad "1" smd circle
			(at -0.40005 0)
			(size 0 0)
			(layers "F.Cu" "F.Mask" "F.Paste")
			(net "SW_P12V_AUX_PVDD11_S3_P0_FLT")
		)
		(pad "2" smd circle
			(at 0.40005 0)
			(size 0 0)
			(layers "F.Cu" "F.Mask" "F.Paste")
			(net "GND")
		)
	)
	(footprint ""
		(layer "F.Cu")
		(at 132.885942 -146.856196)
		(property "Reference" "H8027"
			(at -6.168898 4.4323 0)
			(unlocked yes)
			(layer "F.SilkS")
			(effects
				(font
					(size 0.7874 0.5842)
					(thickness 0.1524)
				)
				(justify left)
			)
		)
		(property "Value" ""
			(at 0 0 0)
			(layer "F.Fab")
			(effects
				(font
					(size 1.27 1.27)
				)
			)
		)
		(duplicate_pad_numbers_are_jumpers no)
		(pad "1" thru_hole circle
			(at 0 0)
			(size 6.1976 6.1976)
			(drill 3.7338)
			(layers "*.Cu" "*.Mask")
			(remove_unused_layers no)
			(net "GND")
			(clearance -0.9779)
			(padstack
				(mode front_inner_back)
				(layer "Inner"
					(shape circle)
					(size 5.5372 5.5372)
					(clearance -0.6477)
				)
				(layer "B.Cu"
					(shape circle)
					(size 6.1976 6.1976)
					(clearance -0.9779)
				)
			)
		)
	)
	(footprint ""
		(layer "F.Cu")
		(at 271.607788 -102.247192 90)
		(property "Reference" "C1509"
			(at 0 0 90)
			(layer "F.SilkS")
			(hide yes)
			(effects
				(font
					(size 1.27 1.27)
				)
			)
		)
		(property "Value" ""
			(at 0 0 90)
			(layer "F.Fab")
			(effects
				(font
					(size 1.27 1.27)
				)
			)
		)
		(duplicate_pad_numbers_are_jumpers no)
		(fp_line
			(start 0.7874 -0.4064)
			(end 0.7874 0.4064)
			(stroke
				(width 0.1524)
				(type default)
			)
			(layer "F.SilkS")
		)
		(fp_line
			(start -0.7874 -0.4064)
			(end 0.7874 -0.4064)
			(stroke
				(width 0.1524)
				(type default)
			)
			(layer "F.SilkS")
		)
		(fp_line
			(start 0.7874 0.4064)
			(end -0.7874 0.4064)
			(stroke
				(width 0.1524)
				(type default)
			)
			(layer "F.SilkS")
		)
		(fp_line
			(start -0.7874 0.4064)
			(end -0.7874 -0.4064)
			(stroke
				(width 0.1524)
				(type default)
			)
			(layer "F.SilkS")
		)
		(fp_line
			(start -0.12065 -0.305054)
			(end -0.12065 -0.2794)
			(stroke
				(width 0.1)
				(type default)
			)
			(layer "F.Fab")
		)
		(fp_line
			(start -0.67945 -0.305054)
			(end -0.12065 -0.305054)
			(stroke
				(width 0.1)
				(type default)
			)
			(layer "F.Fab")
		)
		(fp_line
			(start 0.67945 -0.3048)
			(end 0.67945 0.3048)
			(stroke
				(width 0.1)
				(type default)
			)
			(layer "F.Fab")
		)
		(fp_line
			(start 0.12065 -0.3048)
			(end 0.67945 -0.3048)
			(stroke
				(width 0.1)
				(type default)
			)
			(layer "F.Fab")
		)
		(fp_line
			(start 0.12065 -0.2794)
			(end 0.12065 -0.3048)
			(stroke
				(width 0.1)
				(type default)
			)
			(layer "F.Fab")
		)
		(fp_line
			(start -0.12065 -0.2794)
			(end 0.12065 -0.2794)
			(stroke
				(width 0.1)
				(type default)
			)
			(layer "F.Fab")
		)
		(fp_line
			(start 0.120396 0.2794)
			(end -0.12065 0.2794)
			(stroke
				(width 0.1)
				(type default)
			)
			(layer "F.Fab")
		)
		(fp_line
			(start -0.12065 0.2794)
			(end -0.12065 0.3048)
			(stroke
				(width 0.1)
				(type default)
			)
			(layer "F.Fab")
		)
		(fp_line
			(start 0.67945 0.3048)
			(end 0.120396 0.3048)
			(stroke
				(width 0.1)
				(type default)
			)
			(layer "F.Fab")
		)
		(fp_line
			(start 0.120396 0.3048)
			(end 0.120396 0.2794)
			(stroke
				(width 0.1)
				(type default)
			)
			(layer "F.Fab")
		)
		(fp_line
			(start -0.12065 0.3048)
			(end -0.67945 0.3048)
			(stroke
				(width 0.1)
				(type default)
			)
			(layer "F.Fab")
		)
		(fp_line
			(start -0.67945 0.3048)
			(end -0.67945 -0.305054)
			(stroke
				(width 0.1)
				(type default)
			)
			(layer "F.Fab")
		)
		(pad "1" smd circle
			(at -0.40005 0 90)
			(size 0 0)
			(layers "F.Cu" "F.Mask" "F.Paste")
			(net "PVDD18_S5_P0")
		)
		(pad "2" smd circle
			(at 0.40005 0 90)
			(size 0 0)
			(layers "F.Cu" "F.Mask" "F.Paste")
			(net "GND")
		)
	)
	(footprint ""
		(layer "F.Cu")
		(at 361.316016 -256.012188 90)
		(property "Reference" "C2148"
			(at 0 0 90)
			(layer "F.SilkS")
			(hide yes)
			(effects
				(font
					(size 1.27 1.27)
				)
			)
		)
		(property "Value" ""
			(at 0 0 90)
			(layer "F.Fab")
			(effects
				(font
					(size 1.27 1.27)
				)
			)
		)
		(duplicate_pad_numbers_are_jumpers no)
		(fp_line
			(start 0.7874 -0.4064)
			(end 0.7874 0.4064)
			(stroke
				(width 0.1524)
				(type default)
			)
			(layer "F.SilkS")
		)
		(fp_line
			(start -0.7874 -0.4064)
			(end 0.7874 -0.4064)
			(stroke
				(width 0.1524)
				(type default)
			)
			(layer "F.SilkS")
		)
		(fp_line
			(start 0.7874 0.4064)
			(end -0.7874 0.4064)
			(stroke
				(width 0.1524)
				(type default)
			)
			(layer "F.SilkS")
		)
		(fp_line
			(start -0.7874 0.4064)
			(end -0.7874 -0.4064)
			(stroke
				(width 0.1524)
				(type default)
			)
			(layer "F.SilkS")
		)
		(fp_line
			(start -0.12065 -0.305054)
			(end -0.12065 -0.2794)
			(stroke
				(width 0.1)
				(type default)
			)
			(layer "F.Fab")
		)
		(fp_line
			(start -0.67945 -0.305054)
			(end -0.12065 -0.305054)
			(stroke
				(width 0.1)
				(type default)
			)
			(layer "F.Fab")
		)
		(fp_line
			(start 0.67945 -0.3048)
			(end 0.67945 0.3048)
			(stroke
				(width 0.1)
				(type default)
			)
			(layer "F.Fab")
		)
		(fp_line
			(start 0.12065 -0.3048)
			(end 0.67945 -0.3048)
			(stroke
				(width 0.1)
				(type default)
			)
			(layer "F.Fab")
		)
		(fp_line
			(start 0.12065 -0.2794)
			(end 0.12065 -0.3048)
			(stroke
				(width 0.1)
				(type default)
			)
			(layer "F.Fab")
		)
		(fp_line
			(start -0.12065 -0.2794)
			(end 0.12065 -0.2794)
			(stroke
				(width 0.1)
				(type default)
			)
			(layer "F.Fab")
		)
		(fp_line
			(start 0.120396 0.2794)
			(end -0.12065 0.2794)
			(stroke
				(width 0.1)
				(type default)
			)
			(layer "F.Fab")
		)
		(fp_line
			(start -0.12065 0.2794)
			(end -0.12065 0.3048)
			(stroke
				(width 0.1)
				(type default)
			)
			(layer "F.Fab")
		)
		(fp_line
			(start 0.67945 0.3048)
			(end 0.120396 0.3048)
			(stroke
				(width 0.1)
				(type default)
			)
			(layer "F.Fab")
		)
		(fp_line
			(start 0.120396 0.3048)
			(end 0.120396 0.2794)
			(stroke
				(width 0.1)
				(type default)
			)
			(layer "F.Fab")
		)
		(fp_line
			(start -0.12065 0.3048)
			(end -0.67945 0.3048)
			(stroke
				(width 0.1)
				(type default)
			)
			(layer "F.Fab")
		)
		(fp_line
			(start -0.67945 0.3048)
			(end -0.67945 -0.305054)
			(stroke
				(width 0.1)
				(type default)
			)
			(layer "F.Fab")
		)
		(pad "1" smd circle
			(at -0.40005 0 90)
			(size 0 0)
			(layers "F.Cu" "F.Mask" "F.Paste")
			(net "PVDDCR_SOC_P0")
		)
		(pad "2" smd circle
			(at 0.40005 0 90)
			(size 0 0)
			(layers "F.Cu" "F.Mask" "F.Paste")
			(net "GND")
		)
	)
	(footprint ""
		(layer "F.Cu")
		(at 169.230548 -429.022002 180)
		(property "Reference" "R6791"
			(at 0 0 180)
			(layer "F.SilkS")
			(hide yes)
			(effects
				(font
					(size 1.27 1.27)
				)
			)
		)
		(property "Value" ""
			(at 0 0 180)
			(layer "F.Fab")
			(effects
				(font
					(size 1.27 1.27)
				)
			)
		)
		(duplicate_pad_numbers_are_jumpers no)
		(fp_line
			(start 0.32512 0.175006)
			(end -0.32512 0.175006)
			(stroke
				(width 0.1)
				(type default)
			)
			(layer "F.Fab")
		)
		(fp_line
			(start 0.32512 -0.175006)
			(end 0.32512 0.175006)
			(stroke
				(width 0.1)
				(type default)
			)
			(layer "F.Fab")
		)
		(fp_line
			(start -0.32512 0.175006)
			(end -0.32512 -0.175006)
			(stroke
				(width 0.1)
				(type default)
			)
			(layer "F.Fab")
		)
		(fp_line
			(start -0.32512 -0.175006)
			(end 0.32512 -0.175006)
			(stroke
				(width 0.1)
				(type default)
			)
			(layer "F.Fab")
		)
		(pad "1" smd rect
			(at -0.2667 0 180)
			(size 0.3048 0.381)
			(layers "F.Cu" "F.Mask" "F.Paste")
			(net "U21_E2")
		)
		(pad "2" smd rect
			(at 0.2667 0)
			(size 0.3048 0.381)
			(layers "F.Cu" "F.Mask" "F.Paste")
			(net "GND")
		)
	)
	(footprint ""
		(layer "F.Cu")
		(at 193.294 -54.356 90)
		(property "Reference" "R8029"
			(at 0 0 90)
			(layer "F.SilkS")
			(hide yes)
			(effects
				(font
					(size 1.27 1.27)
				)
			)
		)
		(property "Value" ""
			(at 0 0 90)
			(layer "F.Fab")
			(effects
				(font
					(size 1.27 1.27)
				)
			)
		)
		(duplicate_pad_numbers_are_jumpers no)
		(fp_line
			(start 0.7874 -0.4064)
			(end 0.7874 0.4064)
			(stroke
				(width 0.1524)
				(type default)
			)
			(layer "F.SilkS")
		)
		(fp_line
			(start -0.7874 -0.4064)
			(end 0.7874 -0.4064)
			(stroke
				(width 0.1524)
				(type default)
			)
			(layer "F.SilkS")
		)
		(fp_line
			(start 0.7874 0.4064)
			(end -0.7874 0.4064)
			(stroke
				(width 0.1524)
				(type default)
			)
			(layer "F.SilkS")
		)
		(fp_line
			(start -0.7874 0.4064)
			(end -0.7874 -0.4064)
			(stroke
				(width 0.1524)
				(type default)
			)
			(layer "F.SilkS")
		)
		(fp_line
			(start -0.12065 -0.305054)
			(end -0.12065 -0.2794)
			(stroke
				(width 0.1)
				(type default)
			)
			(layer "F.Fab")
		)
		(fp_line
			(start -0.67945 -0.305054)
			(end -0.12065 -0.305054)
			(stroke
				(width 0.1)
				(type default)
			)
			(layer "F.Fab")
		)
		(fp_line
			(start 0.67945 -0.3048)
			(end 0.67945 0.3048)
			(stroke
				(width 0.1)
				(type default)
			)
			(layer "F.Fab")
		)
		(fp_line
			(start 0.12065 -0.3048)
			(end 0.67945 -0.3048)
			(stroke
				(width 0.1)
				(type default)
			)
			(layer "F.Fab")
		)
		(fp_line
			(start 0.12065 -0.2794)
			(end 0.12065 -0.3048)
			(stroke
				(width 0.1)
				(type default)
			)
			(layer "F.Fab")
		)
		(fp_line
			(start -0.12065 -0.2794)
			(end 0.12065 -0.2794)
			(stroke
				(width 0.1)
				(type default)
			)
			(layer "F.Fab")
		)
		(fp_line
			(start 0.120396 0.2794)
			(end -0.12065 0.2794)
			(stroke
				(width 0.1)
				(type default)
			)
			(layer "F.Fab")
		)
		(fp_line
			(start -0.12065 0.2794)
			(end -0.12065 0.3048)
			(stroke
				(width 0.1)
				(type default)
			)
			(layer "F.Fab")
		)
		(fp_line
			(start 0.67945 0.3048)
			(end 0.120396 0.3048)
			(stroke
				(width 0.1)
				(type default)
			)
			(layer "F.Fab")
		)
		(fp_line
			(start 0.120396 0.3048)
			(end 0.120396 0.2794)
			(stroke
				(width 0.1)
				(type default)
			)
			(layer "F.Fab")
		)
		(fp_line
			(start -0.12065 0.3048)
			(end -0.67945 0.3048)
			(stroke
				(width 0.1)
				(type default)
			)
			(layer "F.Fab")
		)
		(fp_line
			(start -0.67945 0.3048)
			(end -0.67945 -0.305054)
			(stroke
				(width 0.1)
				(type default)
			)
			(layer "F.Fab")
		)
		(pad "1" smd circle
			(at -0.40005 0 90)
			(size 0 0)
			(layers "F.Cu" "F.Mask" "F.Paste")
			(net "LED_P12V_SCM_FAULT")
		)
		(pad "2" smd circle
			(at 0.40005 0 90)
			(size 0 0)
			(layers "F.Cu" "F.Mask" "F.Paste")
			(net "P3V3_AUX")
		)
	)
	(footprint ""
		(layer "F.Cu")
		(at 434.796692 -19.625818 -90)
		(property "Reference" "R1929"
			(at 0 0 270)
			(layer "F.SilkS")
			(hide yes)
			(effects
				(font
					(size 1.27 1.27)
				)
			)
		)
		(property "Value" ""
			(at 0 0 270)
			(layer "F.Fab")
			(effects
				(font
					(size 1.27 1.27)
				)
			)
		)
		(duplicate_pad_numbers_are_jumpers no)
		(fp_line
			(start -0.7874 0.4064)
			(end -0.7874 -0.4064)
			(stroke
				(width 0.1524)
				(type default)
			)
			(layer "F.SilkS")
		)
		(fp_line
			(start 0.7874 0.4064)
			(end -0.7874 0.4064)
			(stroke
				(width 0.1524)
				(type default)
			)
			(layer "F.SilkS")
		)
		(fp_line
			(start -0.7874 -0.4064)
			(end 0.7874 -0.4064)
			(stroke
				(width 0.1524)
				(type default)
			)
			(layer "F.SilkS")
		)
		(fp_line
			(start 0.7874 -0.4064)
			(end 0.7874 0.4064)
			(stroke
				(width 0.1524)
				(type default)
			)
			(layer "F.SilkS")
		)
		(fp_line
			(start -0.67945 0.3048)
			(end -0.67945 -0.305054)
			(stroke
				(width 0.1)
				(type default)
			)
			(layer "F.Fab")
		)
		(fp_line
			(start -0.12065 0.3048)
			(end -0.67945 0.3048)
			(stroke
				(width 0.1)
				(type default)
			)
			(layer "F.Fab")
		)
		(fp_line
			(start 0.120396 0.3048)
			(end 0.120396 0.2794)
			(stroke
				(width 0.1)
				(type default)
			)
			(layer "F.Fab")
		)
		(fp_line
			(start 0.67945 0.3048)
			(end 0.120396 0.3048)
			(stroke
				(width 0.1)
				(type default)
			)
			(layer "F.Fab")
		)
		(fp_line
			(start -0.12065 0.2794)
			(end -0.12065 0.3048)
			(stroke
				(width 0.1)
				(type default)
			)
			(layer "F.Fab")
		)
		(fp_line
			(start 0.120396 0.2794)
			(end -0.12065 0.2794)
			(stroke
				(width 0.1)
				(type default)
			)
			(layer "F.Fab")
		)
		(fp_line
			(start -0.12065 -0.2794)
			(end 0.12065 -0.2794)
			(stroke
				(width 0.1)
				(type default)
			)
			(layer "F.Fab")
		)
		(fp_line
			(start 0.12065 -0.2794)
			(end 0.12065 -0.3048)
			(stroke
				(width 0.1)
				(type default)
			)
			(layer "F.Fab")
		)
		(fp_line
			(start 0.12065 -0.3048)
			(end 0.67945 -0.3048)
			(stroke
				(width 0.1)
				(type default)
			)
			(layer "F.Fab")
		)
		(fp_line
			(start 0.67945 -0.3048)
			(end 0.67945 0.3048)
			(stroke
				(width 0.1)
				(type default)
			)
			(layer "F.Fab")
		)
		(fp_line
			(start -0.67945 -0.305054)
			(end -0.12065 -0.305054)
			(stroke
				(width 0.1)
				(type default)
			)
			(layer "F.Fab")
		)
		(fp_line
			(start -0.12065 -0.305054)
			(end -0.12065 -0.2794)
			(stroke
				(width 0.1)
				(type default)
			)
			(layer "F.Fab")
		)
		(pad "1" smd circle
			(at -0.40005 0 270)
			(size 0 0)
			(layers "F.Cu" "F.Mask" "F.Paste")
			(net "GND")
		)
		(pad "2" smd circle
			(at 0.40005 0 270)
			(size 0 0)
			(layers "F.Cu" "F.Mask" "F.Paste")
			(net "OCP_SFF_AUX_PWR_EN")
		)
	)
	(footprint ""
		(layer "F.Cu")
		(at 171.26966 -388.753604 180)
		(property "Reference" "L32"
			(at 0 0 180)
			(layer "F.SilkS")
			(hide yes)
			(effects
				(font
					(size 1.27 1.27)
				)
			)
		)
		(property "Value" ""
			(at 0 0 180)
			(layer "F.Fab")
			(effects
				(font
					(size 1.27 1.27)
				)
			)
		)
		(duplicate_pad_numbers_are_jumpers no)
		(fp_line
			(start 0.762 0.381)
			(end -0.762 0.381)
			(stroke
				(width 0.1524)
				(type default)
			)
			(layer "F.SilkS")
		)
		(fp_line
			(start 0.762 -0.381)
			(end 0.762 0.381)
			(stroke
				(width 0.1524)
				(type default)
			)
			(layer "F.SilkS")
		)
		(fp_line
			(start -0.762 0.381)
			(end -0.762 -0.381)
			(stroke
				(width 0.1524)
				(type default)
			)
			(layer "F.SilkS")
		)
		(fp_line
			(start -0.762 -0.381)
			(end 0.762 -0.381)
			(stroke
				(width 0.1524)
				(type default)
			)
			(layer "F.SilkS")
		)
		(fp_line
			(start 0.680466 0.306324)
			(end 0.118364 0.306324)
			(stroke
				(width 0.1)
				(type default)
			)
			(layer "F.Fab")
		)
		(fp_line
			(start 0.680466 -0.306324)
			(end 0.680466 0.306324)
			(stroke
				(width 0.1)
				(type default)
			)
			(layer "F.Fab")
		)
		(fp_line
			(start 0.118872 -0.2794)
			(end 0.118872 -0.306324)
			(stroke
				(width 0.1)
				(type default)
			)
			(layer "F.Fab")
		)
		(fp_line
			(start 0.118872 -0.306324)
			(end 0.680466 -0.306324)
			(stroke
				(width 0.1)
				(type default)
			)
			(layer "F.Fab")
		)
		(fp_line
			(start 0.118364 0.306324)
			(end 0.118364 0.2794)
			(stroke
				(width 0.1)
				(type default)
			)
			(layer "F.Fab")
		)
		(fp_line
			(start 0.118364 0.2794)
			(end -0.119634 0.2794)
			(stroke
				(width 0.1)
				(type default)
			)
			(layer "F.Fab")
		)
		(fp_line
			(start -0.118364 -0.2794)
			(end 0.118872 -0.2794)
			(stroke
				(width 0.1)
				(type default)
			)
			(layer "F.Fab")
		)
		(fp_line
			(start -0.118364 -0.307086)
			(end -0.118364 -0.2794)
			(stroke
				(width 0.1)
				(type default)
			)
			(layer "F.Fab")
		)
		(fp_line
			(start -0.119634 0.30607)
			(end -0.681736 0.30607)
			(stroke
				(width 0.1)
				(type default)
			)
			(layer "F.Fab")
		)
		(fp_line
			(start -0.119634 0.2794)
			(end -0.119634 0.30607)
			(stroke
				(width 0.1)
				(type default)
			)
			(layer "F.Fab")
		)
		(fp_line
			(start -0.681736 0.30607)
			(end -0.681736 -0.307086)
			(stroke
				(width 0.1)
				(type default)
			)
			(layer "F.Fab")
		)
		(fp_line
			(start -0.681736 -0.307086)
			(end -0.118364 -0.307086)
			(stroke
				(width 0.1)
				(type default)
			)
			(layer "F.Fab")
		)
		(pad "1" smd rect
			(at -0.40005 0)
			(size 0.4572 0.508)
			(layers "F.Cu" "F.Mask" "F.Paste")
			(net "P1V8_CPU1_RT_1D")
		)
		(pad "2" smd rect
			(at 0.40005 0)
			(size 0.4572 0.508)
			(layers "F.Cu" "F.Mask" "F.Paste")
			(net "P1V8_CPU1_RT2_1A_1D")
		)
	)
	(footprint ""
		(layer "F.Cu")
		(at 345.8337 -15.924276 90)
		(property "Reference" "D49"
			(at -3.1496 0.230632 90)
			(unlocked yes)
			(layer "F.SilkS")
			(effects
				(font
					(size 0.7874 0.5842)
					(thickness 0.1524)
				)
				(justify left)
			)
		)
		(property "Value" ""
			(at 0 0 90)
			(layer "F.Fab")
			(effects
				(font
					(size 1.27 1.27)
				)
			)
		)
		(duplicate_pad_numbers_are_jumpers no)
		(fp_line
			(start 1.16078 -0.4826)
			(end 1.16078 0.4826)
			(stroke
				(width 0.1524)
				(type default)
			)
			(layer "F.SilkS")
		)
		(fp_line
			(start 1.03378 -0.4826)
			(end 1.03378 0.4826)
			(stroke
				(width 0.1524)
				(type default)
			)
			(layer "F.SilkS")
		)
		(fp_line
			(start 0.90678 -0.4826)
			(end 0.90678 0.4826)
			(stroke
				(width 0.1524)
				(type default)
			)
			(layer "F.SilkS")
		)
		(fp_line
			(start -0.64008 -0.4826)
			(end 1.16078 -0.4826)
			(stroke
				(width 0.1524)
				(type default)
			)
			(layer "F.SilkS")
		)
		(fp_line
			(start -0.79248 -0.4826)
			(end 1.03378 -0.4826)
			(stroke
				(width 0.1524)
				(type default)
			)
			(layer "F.SilkS")
		)
		(fp_line
			(start -0.89408 -0.4826)
			(end 0.90678 -0.4826)
			(stroke
				(width 0.1524)
				(type default)
			)
			(layer "F.SilkS")
		)
		(fp_line
			(start 1.16078 0.4826)
			(end -0.64008 0.4826)
			(stroke
				(width 0.1524)
				(type default)
			)
			(layer "F.SilkS")
		)
		(fp_line
			(start 1.03378 0.4826)
			(end -0.79248 0.4826)
			(stroke
				(width 0.1524)
				(type default)
			)
			(layer "F.SilkS")
		)
		(fp_line
			(start 0.90678 0.4826)
			(end -0.90678 0.4826)
			(stroke
				(width 0.1524)
				(type default)
			)
			(layer "F.SilkS")
		)
		(fp_line
			(start -0.90678 0.4826)
			(end -0.90678 -0.4699)
			(stroke
				(width 0.1524)
				(type default)
			)
			(layer "F.SilkS")
		)
		(fp_line
			(start 0.499872 -0.249936)
			(end 0.499872 0.249936)
			(stroke
				(width 0.1)
				(type default)
			)
			(layer "F.Fab")
		)
		(fp_line
			(start -0.499872 -0.249936)
			(end 0.499872 -0.249936)
			(stroke
				(width 0.1)
				(type default)
			)
			(layer "F.Fab")
		)
		(fp_line
			(start 0.499872 0.249936)
			(end -0.499872 0.249936)
			(stroke
				(width 0.1)
				(type default)
			)
			(layer "F.Fab")
		)
		(fp_line
			(start -0.499872 0.249936)
			(end -0.499872 -0.249936)
			(stroke
				(width 0.1)
				(type default)
			)
			(layer "F.Fab")
		)
		(pad "A" smd rect
			(at -0.47498 0 90)
			(size 0.6096 0.7112)
			(layers "F.Cu" "F.Mask" "F.Paste")
			(net "P5V_STBY_PWR_LED")
		)
		(pad "C" smd rect
			(at 0.47498 0 90)
			(size 0.6096 0.7112)
			(layers "F.Cu" "F.Mask" "F.Paste")
			(net "GND")
		)
	)
	(footprint ""
		(layer "F.Cu")
		(at 360.190542 -399.034)
		(property "Reference" "R1397"
			(at 0 0 0)
			(layer "F.SilkS")
			(hide yes)
			(effects
				(font
					(size 1.27 1.27)
				)
			)
		)
		(property "Value" ""
			(at 0 0 0)
			(layer "F.Fab")
			(effects
				(font
					(size 1.27 1.27)
				)
			)
		)
		(duplicate_pad_numbers_are_jumpers no)
		(fp_line
			(start -0.32512 -0.175006)
			(end 0.32512 -0.175006)
			(stroke
				(width 0.1)
				(type default)
			)
			(layer "F.Fab")
		)
		(fp_line
			(start -0.32512 0.175006)
			(end -0.32512 -0.175006)
			(stroke
				(width 0.1)
				(type default)
			)
			(layer "F.Fab")
		)
		(fp_line
			(start 0.32512 -0.175006)
			(end 0.32512 0.175006)
			(stroke
				(width 0.1)
				(type default)
			)
			(layer "F.Fab")
		)
		(fp_line
			(start 0.32512 0.175006)
			(end -0.32512 0.175006)
			(stroke
				(width 0.1)
				(type default)
			)
			(layer "F.Fab")
		)
		(pad "1" smd rect
			(at -0.2667 0)
			(size 0.3048 0.381)
			(layers "F.Cu" "F.Mask" "F.Paste")
			(net "P1V8_CPU0_RT_1D")
		)
		(pad "2" smd rect
			(at 0.2667 0 180)
			(size 0.3048 0.381)
			(layers "F.Cu" "F.Mask" "F.Paste")
			(net "RXDET_BYP_RT_CPU0_P1")
		)
	)
	(footprint ""
		(layer "F.Cu")
		(at 370.905278 -146.552158 180)
		(property "Reference" "R8286"
			(at 0 0 180)
			(layer "F.SilkS")
			(hide yes)
			(effects
				(font
					(size 1.27 1.27)
				)
			)
		)
		(property "Value" ""
			(at 0 0 180)
			(layer "F.Fab")
			(effects
				(font
					(size 1.27 1.27)
				)
			)
		)
		(duplicate_pad_numbers_are_jumpers no)
		(fp_line
			(start 0.7874 0.4064)
			(end -0.7874 0.4064)
			(stroke
				(width 0.1524)
				(type default)
			)
			(layer "F.SilkS")
		)
		(fp_line
			(start 0.7874 -0.4064)
			(end 0.7874 0.4064)
			(stroke
				(width 0.1524)
				(type default)
			)
			(layer "F.SilkS")
		)
		(fp_line
			(start -0.7874 0.4064)
			(end -0.7874 -0.4064)
			(stroke
				(width 0.1524)
				(type default)
			)
			(layer "F.SilkS")
		)
		(fp_line
			(start -0.7874 -0.4064)
			(end 0.7874 -0.4064)
			(stroke
				(width 0.1524)
				(type default)
			)
			(layer "F.SilkS")
		)
		(fp_line
			(start 0.67945 0.3048)
			(end 0.120396 0.3048)
			(stroke
				(width 0.1)
				(type default)
			)
			(layer "F.Fab")
		)
		(fp_line
			(start 0.67945 -0.3048)
			(end 0.67945 0.3048)
			(stroke
				(width 0.1)
				(type default)
			)
			(layer "F.Fab")
		)
		(fp_line
			(start 0.12065 -0.2794)
			(end 0.12065 -0.3048)
			(stroke
				(width 0.1)
				(type default)
			)
			(layer "F.Fab")
		)
		(fp_line
			(start 0.12065 -0.3048)
			(end 0.67945 -0.3048)
			(stroke
				(width 0.1)
				(type default)
			)
			(layer "F.Fab")
		)
		(fp_line
			(start 0.120396 0.3048)
			(end 0.120396 0.2794)
			(stroke
				(width 0.1)
				(type default)
			)
			(layer "F.Fab")
		)
		(fp_line
			(start 0.120396 0.2794)
			(end -0.12065 0.2794)
			(stroke
				(width 0.1)
				(type default)
			)
			(layer "F.Fab")
		)
		(fp_line
			(start -0.12065 0.3048)
			(end -0.67945 0.3048)
			(stroke
				(width 0.1)
				(type default)
			)
			(layer "F.Fab")
		)
		(fp_line
			(start -0.12065 0.2794)
			(end -0.12065 0.3048)
			(stroke
				(width 0.1)
				(type default)
			)
			(layer "F.Fab")
		)
		(fp_line
			(start -0.12065 -0.2794)
			(end 0.12065 -0.2794)
			(stroke
				(width 0.1)
				(type default)
			)
			(layer "F.Fab")
		)
		(fp_line
			(start -0.12065 -0.305054)
			(end -0.12065 -0.2794)
			(stroke
				(width 0.1)
				(type default)
			)
			(layer "F.Fab")
		)
		(fp_line
			(start -0.67945 0.3048)
			(end -0.67945 -0.305054)
			(stroke
				(width 0.1)
				(type default)
			)
			(layer "F.Fab")
		)
		(fp_line
			(start -0.67945 -0.305054)
			(end -0.12065 -0.305054)
			(stroke
				(width 0.1)
				(type default)
			)
			(layer "F.Fab")
		)
		(pad "1" smd circle
			(at -0.40005 0 180)
			(size 0 0)
			(layers "F.Cu" "F.Mask" "F.Paste")
			(net "SVID_PVDDCR_CPU0_P0_SVTO")
		)
		(pad "2" smd circle
			(at 0.40005 0 180)
			(size 0 0)
			(layers "F.Cu" "F.Mask" "F.Paste")
			(net "GND")
		)
	)
	(footprint ""
		(layer "F.Cu")
		(at 405.753062 -57.2135)
		(property "Reference" "C85"
			(at 0 0 0)
			(layer "F.SilkS")
			(hide yes)
			(effects
				(font
					(size 1.27 1.27)
				)
			)
		)
		(property "Value" ""
			(at 0 0 0)
			(layer "F.Fab")
			(effects
				(font
					(size 1.27 1.27)
				)
			)
		)
		(duplicate_pad_numbers_are_jumpers no)
		(fp_line
			(start -0.7874 -0.4064)
			(end 0.7874 -0.4064)
			(stroke
				(width 0.1524)
				(type default)
			)
			(layer "F.SilkS")
		)
		(fp_line
			(start -0.7874 0.4064)
			(end -0.7874 -0.4064)
			(stroke
				(width 0.1524)
				(type default)
			)
			(layer "F.SilkS")
		)
		(fp_line
			(start 0.7874 -0.4064)
			(end 0.7874 0.4064)
			(stroke
				(width 0.1524)
				(type default)
			)
			(layer "F.SilkS")
		)
		(fp_line
			(start 0.7874 0.4064)
			(end -0.7874 0.4064)
			(stroke
				(width 0.1524)
				(type default)
			)
			(layer "F.SilkS")
		)
		(fp_line
			(start -0.67945 -0.305054)
			(end -0.12065 -0.305054)
			(stroke
				(width 0.1)
				(type default)
			)
			(layer "F.Fab")
		)
		(fp_line
			(start -0.67945 0.3048)
			(end -0.67945 -0.305054)
			(stroke
				(width 0.1)
				(type default)
			)
			(layer "F.Fab")
		)
		(fp_line
			(start -0.12065 -0.305054)
			(end -0.12065 -0.2794)
			(stroke
				(width 0.1)
				(type default)
			)
			(layer "F.Fab")
		)
		(fp_line
			(start -0.12065 -0.2794)
			(end 0.12065 -0.2794)
			(stroke
				(width 0.1)
				(type default)
			)
			(layer "F.Fab")
		)
		(fp_line
			(start -0.12065 0.2794)
			(end -0.12065 0.3048)
			(stroke
				(width 0.1)
				(type default)
			)
			(layer "F.Fab")
		)
		(fp_line
			(start -0.12065 0.3048)
			(end -0.67945 0.3048)
			(stroke
				(width 0.1)
				(type default)
			)
			(layer "F.Fab")
		)
		(fp_line
			(start 0.120396 0.2794)
			(end -0.12065 0.2794)
			(stroke
				(width 0.1)
				(type default)
			)
			(layer "F.Fab")
		)
		(fp_line
			(start 0.120396 0.3048)
			(end 0.120396 0.2794)
			(stroke
				(width 0.1)
				(type default)
			)
			(layer "F.Fab")
		)
		(fp_line
			(start 0.12065 -0.3048)
			(end 0.67945 -0.3048)
			(stroke
				(width 0.1)
				(type default)
			)
			(layer "F.Fab")
		)
		(fp_line
			(start 0.12065 -0.2794)
			(end 0.12065 -0.3048)
			(stroke
				(width 0.1)
				(type default)
			)
			(layer "F.Fab")
		)
		(fp_line
			(start 0.67945 -0.3048)
			(end 0.67945 0.3048)
			(stroke
				(width 0.1)
				(type default)
			)
			(layer "F.Fab")
		)
		(fp_line
			(start 0.67945 0.3048)
			(end 0.120396 0.3048)
			(stroke
				(width 0.1)
				(type default)
			)
			(layer "F.Fab")
		)
		(pad "1" smd circle
			(at -0.40005 0)
			(size 0 0)
			(layers "F.Cu" "F.Mask" "F.Paste")
			(net "HDT_HDR_TRST_N")
		)
		(pad "2" smd circle
			(at 0.40005 0)
			(size 0 0)
			(layers "F.Cu" "F.Mask" "F.Paste")
			(net "GND")
		)
	)
	(footprint ""
		(layer "F.Cu")
		(at 115.189 -415.29 180)
		(property "Reference" "Q75"
			(at -3.272282 -1.210564 90)
			(unlocked yes)
			(layer "F.SilkS")
			(effects
				(font
					(size 0.7874 0.5842)
					(thickness 0.1524)
				)
				(justify left)
			)
		)
		(property "Value" ""
			(at 0 0 180)
			(layer "F.Fab")
			(effects
				(font
					(size 1.27 1.27)
				)
			)
		)
		(duplicate_pad_numbers_are_jumpers no)
		(fp_line
			(start 1.332738 1.100074)
			(end -1.332738 1.100074)
			(stroke
				(width 0.1524)
				(type default)
			)
			(layer "F.SilkS")
		)
		(fp_line
			(start 1.332738 -1.100074)
			(end 1.332738 1.100074)
			(stroke
				(width 0.1524)
				(type default)
			)
			(layer "F.SilkS")
		)
		(fp_line
			(start 0.4826 -1.100074)
			(end 1.332738 -1.100074)
			(stroke
				(width 0.1524)
				(type default)
			)
			(layer "F.SilkS")
		)
		(fp_line
			(start 0 -0.541274)
			(end 0.4826 -1.100074)
			(stroke
				(width 0.1524)
				(type default)
			)
			(layer "F.SilkS")
		)
		(fp_line
			(start -0.4826 -1.100074)
			(end 0 -0.541274)
			(stroke
				(width 0.1524)
				(type default)
			)
			(layer "F.SilkS")
		)
		(fp_line
			(start -1.332738 1.100074)
			(end -1.332738 -1.100074)
			(stroke
				(width 0.1524)
				(type default)
			)
			(layer "F.SilkS")
		)
		(fp_line
			(start -1.332738 -1.100074)
			(end -0.4826 -1.100074)
			(stroke
				(width 0.1524)
				(type default)
			)
			(layer "F.SilkS")
		)
		(fp_poly
			(pts
				(xy -1.533144 -0.649986) (xy -2.2352 -0.298958) (xy -2.2352 -1.001014)
			)
			(stroke
				(width 0)
				(type default)
			)
			(fill yes)
			(layer "F.SilkS")
		)
		(fp_line
			(start 0.674878 1.100074)
			(end -0.674878 1.100074)
			(stroke
				(width 0.1)
				(type default)
			)
			(layer "F.Fab")
		)
		(fp_line
			(start 0.674878 -1.100074)
			(end 0.674878 1.100074)
			(stroke
				(width 0.1)
				(type default)
			)
			(layer "F.Fab")
		)
		(fp_line
			(start -0.674878 1.100074)
			(end -0.674878 -1.100074)
			(stroke
				(width 0.1)
				(type default)
			)
			(layer "F.Fab")
		)
		(fp_line
			(start -0.674878 -1.100074)
			(end 0.674878 -1.100074)
			(stroke
				(width 0.1)
				(type default)
			)
			(layer "F.Fab")
		)
		(fp_poly
			(pts
				(xy -2.2352 -0.298958) (xy -2.2352 -1.001014) (xy -1.533144 -0.649986)
			)
			(stroke
				(width 0)
				(type default)
			)
			(fill yes)
			(layer "F.Fab")
		)
		(pad "1" smd rect
			(at -0.94996 -0.649986 270)
			(size 0.4318 0.508)
			(layers "F.Cu" "F.Mask" "F.Paste")
			(net "GND")
		)
		(pad "2" smd rect
			(at -0.94996 0 270)
			(size 0.4318 0.508)
			(layers "F.Cu" "F.Mask" "F.Paste")
			(net "FM_SMB_1_ALERT_GPU_N")
		)
		(pad "3" smd rect
			(at -0.94996 0.649986 270)
			(size 0.4318 0.508)
			(layers "F.Cu" "F.Mask" "F.Paste")
			(net "FM_SMB_1_ALERT_GPU_ISO_N")
		)
		(pad "4" smd rect
			(at 0.94996 0.649986 270)
			(size 0.4318 0.508)
			(layers "F.Cu" "F.Mask" "F.Paste")
			(net "GND")
		)
		(pad "5" smd rect
			(at 0.94996 0 270)
			(size 0.4318 0.508)
			(layers "F.Cu" "F.Mask" "F.Paste")
			(net "FM_SMB_1_ALERT_GPU")
		)
		(pad "6" smd rect
			(at 0.94996 -0.649986 270)
			(size 0.4318 0.508)
			(layers "F.Cu" "F.Mask" "F.Paste")
			(net "FM_SMB_1_ALERT_GPU")
		)
	)
	(footprint ""
		(layer "F.Cu")
		(at 56.958484 -408.517344 -90)
		(property "Reference" "C6636"
			(at 0 0 270)
			(layer "F.SilkS")
			(hide yes)
			(effects
				(font
					(size 1.27 1.27)
				)
			)
		)
		(property "Value" ""
			(at 0 0 270)
			(layer "F.Fab")
			(effects
				(font
					(size 1.27 1.27)
				)
			)
		)
		(duplicate_pad_numbers_are_jumpers no)
		(fp_line
			(start -0.299974 0.150114)
			(end -0.299974 -0.150114)
			(stroke
				(width 0.1)
				(type default)
			)
			(layer "F.Fab")
		)
		(fp_line
			(start 0.299974 0.150114)
			(end -0.299974 0.150114)
			(stroke
				(width 0.1)
				(type default)
			)
			(layer "F.Fab")
		)
		(fp_line
			(start -0.299974 -0.150114)
			(end 0.299974 -0.150114)
			(stroke
				(width 0.1)
				(type default)
			)
			(layer "F.Fab")
		)
		(fp_line
			(start 0.299974 -0.150114)
			(end 0.299974 0.150114)
			(stroke
				(width 0.1)
				(type default)
			)
			(layer "F.Fab")
		)
		(pad "1" smd rect
			(at -0.2667 0 270)
			(size 0.3048 0.381)
			(layers "F.Cu" "F.Mask" "F.Paste")
			(net "P5E_CPU1_P0_TX_BUF_C_DN<3>")
		)
		(pad "2" smd rect
			(at 0.2667 0 270)
			(size 0.3048 0.381)
			(layers "F.Cu" "F.Mask" "F.Paste")
			(net "P5E_CPU1_P0_TX_BUF_DN<3>")
		)
	)
	(footprint ""
		(layer "F.Cu")
		(at 392.840972 -387.853428)
		(property "Reference" "C871"
			(at 0 0 0)
			(layer "F.SilkS")
			(hide yes)
			(effects
				(font
					(size 1.27 1.27)
				)
			)
		)
		(property "Value" ""
			(at 0 0 0)
			(layer "F.Fab")
			(effects
				(font
					(size 1.27 1.27)
				)
			)
		)
		(duplicate_pad_numbers_are_jumpers no)
		(fp_line
			(start -0.299974 -0.150114)
			(end 0.299974 -0.150114)
			(stroke
				(width 0.1)
				(type default)
			)
			(layer "F.Fab")
		)
		(fp_line
			(start -0.299974 0.150114)
			(end -0.299974 -0.150114)
			(stroke
				(width 0.1)
				(type default)
			)
			(layer "F.Fab")
		)
		(fp_line
			(start 0.299974 -0.150114)
			(end 0.299974 0.150114)
			(stroke
				(width 0.1)
				(type default)
			)
			(layer "F.Fab")
		)
		(fp_line
			(start 0.299974 0.150114)
			(end -0.299974 0.150114)
			(stroke
				(width 0.1)
				(type default)
			)
			(layer "F.Fab")
		)
		(pad "1" smd rect
			(at -0.2667 0)
			(size 0.3048 0.381)
			(layers "F.Cu" "F.Mask" "F.Paste")
			(net "P5E_CPU0_P3_TX_C_DP<15>")
		)
		(pad "2" smd rect
			(at 0.2667 0)
			(size 0.3048 0.381)
			(layers "F.Cu" "F.Mask" "F.Paste")
			(net "P5E_CPU0_P3_TX_DP<15>")
		)
	)
	(footprint ""
		(layer "F.Cu")
		(at 150.373334 -121.826274)
		(property "Reference" "R4620"
			(at 0 0 0)
			(layer "F.SilkS")
			(hide yes)
			(effects
				(font
					(size 1.27 1.27)
				)
			)
		)
		(property "Value" ""
			(at 0 0 0)
			(layer "F.Fab")
			(effects
				(font
					(size 1.27 1.27)
				)
			)
		)
		(duplicate_pad_numbers_are_jumpers no)
		(fp_line
			(start -0.7874 -0.4064)
			(end 0.7874 -0.4064)
			(stroke
				(width 0.1524)
				(type default)
			)
			(layer "F.SilkS")
		)
		(fp_line
			(start -0.7874 0.4064)
			(end -0.7874 -0.4064)
			(stroke
				(width 0.1524)
				(type default)
			)
			(layer "F.SilkS")
		)
		(fp_line
			(start 0.7874 -0.4064)
			(end 0.7874 0.4064)
			(stroke
				(width 0.1524)
				(type default)
			)
			(layer "F.SilkS")
		)
		(fp_line
			(start 0.7874 0.4064)
			(end -0.7874 0.4064)
			(stroke
				(width 0.1524)
				(type default)
			)
			(layer "F.SilkS")
		)
		(fp_line
			(start -0.67945 -0.305054)
			(end -0.12065 -0.305054)
			(stroke
				(width 0.1)
				(type default)
			)
			(layer "F.Fab")
		)
		(fp_line
			(start -0.67945 0.3048)
			(end -0.67945 -0.305054)
			(stroke
				(width 0.1)
				(type default)
			)
			(layer "F.Fab")
		)
		(fp_line
			(start -0.12065 -0.305054)
			(end -0.12065 -0.2794)
			(stroke
				(width 0.1)
				(type default)
			)
			(layer "F.Fab")
		)
		(fp_line
			(start -0.12065 -0.2794)
			(end 0.12065 -0.2794)
			(stroke
				(width 0.1)
				(type default)
			)
			(layer "F.Fab")
		)
		(fp_line
			(start -0.12065 0.2794)
			(end -0.12065 0.3048)
			(stroke
				(width 0.1)
				(type default)
			)
			(layer "F.Fab")
		)
		(fp_line
			(start -0.12065 0.3048)
			(end -0.67945 0.3048)
			(stroke
				(width 0.1)
				(type default)
			)
			(layer "F.Fab")
		)
		(fp_line
			(start 0.120396 0.2794)
			(end -0.12065 0.2794)
			(stroke
				(width 0.1)
				(type default)
			)
			(layer "F.Fab")
		)
		(fp_line
			(start 0.120396 0.3048)
			(end 0.120396 0.2794)
			(stroke
				(width 0.1)
				(type default)
			)
			(layer "F.Fab")
		)
		(fp_line
			(start 0.12065 -0.3048)
			(end 0.67945 -0.3048)
			(stroke
				(width 0.1)
				(type default)
			)
			(layer "F.Fab")
		)
		(fp_line
			(start 0.12065 -0.2794)
			(end 0.12065 -0.3048)
			(stroke
				(width 0.1)
				(type default)
			)
			(layer "F.Fab")
		)
		(fp_line
			(start 0.67945 -0.3048)
			(end 0.67945 0.3048)
			(stroke
				(width 0.1)
				(type default)
			)
			(layer "F.Fab")
		)
		(fp_line
			(start 0.67945 0.3048)
			(end 0.120396 0.3048)
			(stroke
				(width 0.1)
				(type default)
			)
			(layer "F.Fab")
		)
		(pad "1" smd circle
			(at -0.40005 0)
			(size 0 0)
			(layers "F.Cu" "F.Mask" "F.Paste")
			(net "P3V3_AUX")
		)
		(pad "2" smd circle
			(at 0.40005 0)
			(size 0 0)
			(layers "F.Cu" "F.Mask" "F.Paste")
			(net "IRQ_UV_DETECT_N")
		)
	)
	(footprint ""
		(layer "F.Cu")
		(at 163.738814 -119.345202 180)
		(property "Reference" "R3486"
			(at 0 0 180)
			(layer "F.SilkS")
			(hide yes)
			(effects
				(font
					(size 1.27 1.27)
				)
			)
		)
		(property "Value" ""
			(at 0 0 180)
			(layer "F.Fab")
			(effects
				(font
					(size 1.27 1.27)
				)
			)
		)
		(duplicate_pad_numbers_are_jumpers no)
		(fp_line
			(start 0.7874 0.4064)
			(end -0.7874 0.4064)
			(stroke
				(width 0.1524)
				(type default)
			)
			(layer "F.SilkS")
		)
		(fp_line
			(start 0.7874 -0.4064)
			(end 0.7874 0.4064)
			(stroke
				(width 0.1524)
				(type default)
			)
			(layer "F.SilkS")
		)
		(fp_line
			(start -0.7874 0.4064)
			(end -0.7874 -0.4064)
			(stroke
				(width 0.1524)
				(type default)
			)
			(layer "F.SilkS")
		)
		(fp_line
			(start -0.7874 -0.4064)
			(end 0.7874 -0.4064)
			(stroke
				(width 0.1524)
				(type default)
			)
			(layer "F.SilkS")
		)
		(fp_line
			(start 0.67945 0.3048)
			(end 0.120396 0.3048)
			(stroke
				(width 0.1)
				(type default)
			)
			(layer "F.Fab")
		)
		(fp_line
			(start 0.67945 -0.3048)
			(end 0.67945 0.3048)
			(stroke
				(width 0.1)
				(type default)
			)
			(layer "F.Fab")
		)
		(fp_line
			(start 0.12065 -0.2794)
			(end 0.12065 -0.3048)
			(stroke
				(width 0.1)
				(type default)
			)
			(layer "F.Fab")
		)
		(fp_line
			(start 0.12065 -0.3048)
			(end 0.67945 -0.3048)
			(stroke
				(width 0.1)
				(type default)
			)
			(layer "F.Fab")
		)
		(fp_line
			(start 0.120396 0.3048)
			(end 0.120396 0.2794)
			(stroke
				(width 0.1)
				(type default)
			)
			(layer "F.Fab")
		)
		(fp_line
			(start 0.120396 0.2794)
			(end -0.12065 0.2794)
			(stroke
				(width 0.1)
				(type default)
			)
			(layer "F.Fab")
		)
		(fp_line
			(start -0.12065 0.3048)
			(end -0.67945 0.3048)
			(stroke
				(width 0.1)
				(type default)
			)
			(layer "F.Fab")
		)
		(fp_line
			(start -0.12065 0.2794)
			(end -0.12065 0.3048)
			(stroke
				(width 0.1)
				(type default)
			)
			(layer "F.Fab")
		)
		(fp_line
			(start -0.12065 -0.2794)
			(end 0.12065 -0.2794)
			(stroke
				(width 0.1)
				(type default)
			)
			(layer "F.Fab")
		)
		(fp_line
			(start -0.12065 -0.305054)
			(end -0.12065 -0.2794)
			(stroke
				(width 0.1)
				(type default)
			)
			(layer "F.Fab")
		)
		(fp_line
			(start -0.67945 0.3048)
			(end -0.67945 -0.305054)
			(stroke
				(width 0.1)
				(type default)
			)
			(layer "F.Fab")
		)
		(fp_line
			(start -0.67945 -0.305054)
			(end -0.12065 -0.305054)
			(stroke
				(width 0.1)
				(type default)
			)
			(layer "F.Fab")
		)
		(pad "1" smd circle
			(at -0.40005 0 180)
			(size 0 0)
			(layers "F.Cu" "F.Mask" "F.Paste")
			(net "GPU_PRSNT_N_ISO_R")
		)
		(pad "2" smd circle
			(at 0.40005 0 180)
			(size 0 0)
			(layers "F.Cu" "F.Mask" "F.Paste")
			(net "GPU_PRSNT_N_ISO")
		)
	)
	(footprint ""
		(layer "F.Cu")
		(at 331.649832 -440.489848)
		(property "Reference" "J107"
			(at 19.92249 18.882106 0)
			(unlocked yes)
			(layer "F.SilkS")
			(effects
				(font
					(size 0.7874 0.5842)
					(thickness 0.1524)
				)
				(justify left)
			)
		)
		(property "Value" ""
			(at 0 0 0)
			(layer "F.Fab")
			(effects
				(font
					(size 1.27 1.27)
				)
			)
		)
		(duplicate_pad_numbers_are_jumpers no)
		(fp_line
			(start -4.249928 22.400006)
			(end -4.249928 -0.484124)
			(stroke
				(width 0.1524)
				(type default)
			)
			(layer "F.SilkS")
		)
		(fp_line
			(start -3.583432 22.400006)
			(end -4.249928 22.400006)
			(stroke
				(width 0.1524)
				(type default)
			)
			(layer "F.SilkS")
		)
		(fp_line
			(start -1.249934 -1.500124)
			(end 15.649956 -1.500124)
			(stroke
				(width 0.1524)
				(type default)
			)
			(layer "F.SilkS")
		)
		(fp_line
			(start -1.249934 16.817848)
			(end -1.249934 19.400012)
			(stroke
				(width 0.1524)
				(type default)
			)
			(layer "F.SilkS")
		)
		(fp_line
			(start -1.249934 19.400012)
			(end -0.687832 19.400012)
			(stroke
				(width 0.1524)
				(type default)
			)
			(layer "F.SilkS")
		)
		(fp_line
			(start -0.560832 22.400006)
			(end -2.288032 22.400006)
			(stroke
				(width 0.1524)
				(type default)
			)
			(layer "F.SilkS")
		)
		(fp_line
			(start 0.0254 -0.9144)
			(end 1.0414 -0.9144)
			(stroke
				(width 0.1524)
				(type default)
			)
			(layer "F.SilkS")
		)
		(fp_line
			(start 0.5334 -1.4224)
			(end 0.0254 -0.9144)
			(stroke
				(width 0.1524)
				(type default)
			)
			(layer "F.SilkS")
		)
		(fp_line
			(start 0.5334 -1.4224)
			(end 0.5334 -0.5588)
			(stroke
				(width 0.1524)
				(type default)
			)
			(layer "F.SilkS")
		)
		(fp_line
			(start 0.5334 -0.5588)
			(end 1.8034 -0.5588)
			(stroke
				(width 0.1524)
				(type default)
			)
			(layer "F.SilkS")
		)
		(fp_line
			(start 0.886968 19.400012)
			(end 1.090168 19.400012)
			(stroke
				(width 0.1524)
				(type default)
			)
			(layer "F.SilkS")
		)
		(fp_line
			(start 1.0414 -0.9144)
			(end 0.5334 -1.4224)
			(stroke
				(width 0.1524)
				(type default)
			)
			(layer "F.SilkS")
		)
		(fp_line
			(start 1.8034 -0.5588)
			(end 2.032 -0.7874)
			(stroke
				(width 0.1524)
				(type default)
			)
			(layer "F.SilkS")
		)
		(fp_line
			(start 2.436368 22.400006)
			(end 0.836168 22.400006)
			(stroke
				(width 0.1524)
				(type default)
			)
			(layer "F.SilkS")
		)
		(fp_line
			(start 4.011168 19.400012)
			(end 5.433568 19.400012)
			(stroke
				(width 0.1524)
				(type default)
			)
			(layer "F.SilkS")
		)
		(fp_line
			(start 5.611368 22.400006)
			(end 3.909568 22.400006)
			(stroke
				(width 0.1524)
				(type default)
			)
			(layer "F.SilkS")
		)
		(fp_line
			(start 7.186168 19.400012)
			(end 8.506968 19.400012)
			(stroke
				(width 0.1524)
				(type default)
			)
			(layer "F.SilkS")
		)
		(fp_line
			(start 8.659368 22.400006)
			(end 6.957568 22.400006)
			(stroke
				(width 0.1524)
				(type default)
			)
			(layer "F.SilkS")
		)
		(fp_line
			(start 10.183368 19.400012)
			(end 11.580368 19.400012)
			(stroke
				(width 0.1524)
				(type default)
			)
			(layer "F.SilkS")
		)
		(fp_line
			(start 11.707368 22.400006)
			(end 10.030968 22.400006)
			(stroke
				(width 0.1524)
				(type default)
			)
			(layer "F.SilkS")
		)
		(fp_line
			(start 13.282168 19.400012)
			(end 14.501368 19.400012)
			(stroke
				(width 0.1524)
				(type default)
			)
			(layer "F.SilkS")
		)
		(fp_line
			(start 14.755368 22.400006)
			(end 13.104368 22.400006)
			(stroke
				(width 0.1524)
				(type default)
			)
			(layer "F.SilkS")
		)
		(fp_line
			(start 15.649956 19.400012)
			(end 15.649956 -0.484124)
			(stroke
				(width 0.1524)
				(type default)
			)
			(layer "F.SilkS")
		)
		(fp_line
			(start 17.828768 22.400006)
			(end 16.152368 22.400006)
			(stroke
				(width 0.1524)
				(type default)
			)
			(layer "F.SilkS")
		)
		(fp_line
			(start 18.64995 -0.484124)
			(end 18.64995 3.846068)
			(stroke
				(width 0.1524)
				(type default)
			)
			(layer "F.SilkS")
		)
		(fp_line
			(start 18.64995 5.174488)
			(end 18.64995 19.129248)
			(stroke
				(width 0.1524)
				(type default)
			)
			(layer "F.SilkS")
		)
		(fp_poly
			(pts
				(xy -0.765048 0) (xy -1.781048 0.508) (xy -1.781048 -0.508)
			)
			(stroke
				(width 0)
				(type default)
			)
			(fill yes)
			(layer "F.SilkS")
		)
		(fp_line
			(start -4.249928 -11.999976)
			(end 18.64995 -11.999976)
			(stroke
				(width 0.1524)
				(type default)
			)
			(layer "B.SilkS")
		)
		(fp_line
			(start -4.249928 21.669248)
			(end -4.249928 -11.999976)
			(stroke
				(width 0.1524)
				(type default)
			)
			(layer "B.SilkS")
		)
		(fp_line
			(start -2.110232 22.400006)
			(end -3.583432 22.400006)
			(stroke
				(width 0.1524)
				(type default)
			)
			(layer "B.SilkS")
		)
		(fp_line
			(start 0.937768 22.400006)
			(end -0.713232 22.400006)
			(stroke
				(width 0.1524)
				(type default)
			)
			(layer "B.SilkS")
		)
		(fp_line
			(start 4.011168 22.400006)
			(end 2.334768 22.400006)
			(stroke
				(width 0.1524)
				(type default)
			)
			(layer "B.SilkS")
		)
		(fp_line
			(start 7.008368 22.400006)
			(end 5.408168 22.400006)
			(stroke
				(width 0.1524)
				(type default)
			)
			(layer "B.SilkS")
		)
		(fp_line
			(start 10.132568 22.400006)
			(end 8.532368 22.400006)
			(stroke
				(width 0.1524)
				(type default)
			)
			(layer "B.SilkS")
		)
		(fp_line
			(start 13.282168 22.400006)
			(end 11.554968 22.400006)
			(stroke
				(width 0.1524)
				(type default)
			)
			(layer "B.SilkS")
		)
		(fp_line
			(start 16.304768 22.400006)
			(end 14.679168 22.400006)
			(stroke
				(width 0.1524)
				(type default)
			)
			(layer "B.SilkS")
		)
		(fp_line
			(start 18.64995 -11.999976)
			(end 18.64995 22.400006)
			(stroke
				(width 0.1524)
				(type default)
			)
			(layer "B.SilkS")
		)
		(fp_line
			(start 18.64995 22.400006)
			(end 17.676368 22.400006)
			(stroke
				(width 0.1524)
				(type default)
			)
			(layer "B.SilkS")
		)
		(fp_line
			(start -4.249928 -11.999976)
			(end 18.64995 -11.999976)
			(stroke
				(width 0.1)
				(type default)
			)
			(layer "B.Fab")
		)
		(fp_line
			(start -4.249928 22.400006)
			(end -4.249928 -11.999976)
			(stroke
				(width 0.1)
				(type default)
			)
			(layer "B.Fab")
		)
		(fp_line
			(start 18.64995 -11.999976)
			(end 18.64995 22.400006)
			(stroke
				(width 0.1)
				(type default)
			)
			(layer "B.Fab")
		)
		(fp_line
			(start 18.64995 22.400006)
			(end -4.249928 22.400006)
			(stroke
				(width 0.1)
				(type default)
			)
			(layer "B.Fab")
		)
		(fp_line
			(start -1.249934 -8.999982)
			(end -1.249934 19.400012)
			(stroke
				(width 0.1)
				(type default)
			)
			(layer "F.Fab")
		)
		(fp_line
			(start -1.249934 19.400012)
			(end 15.649956 19.400012)
			(stroke
				(width 0.1)
				(type default)
			)
			(layer "F.Fab")
		)
		(fp_line
			(start 15.649956 -8.999982)
			(end -1.249934 -8.999982)
			(stroke
				(width 0.1)
				(type default)
			)
			(layer "F.Fab")
		)
		(fp_line
			(start 15.649956 19.400012)
			(end 15.649956 -8.999982)
			(stroke
				(width 0.1)
				(type default)
			)
			(layer "F.Fab")
		)
		(fp_poly
			(pts
				(xy -2.670048 -0.508) (xy -2.670048 0.508) (xy -1.654048 0)
			)
			(stroke
				(width 0)
				(type default)
			)
			(fill yes)
			(layer "F.Fab")
		)
		(fp_text user "1"
			(at -1.176274 19.97964 90)
			(unlocked yes)
			(layer "F.SilkS")
			(effects
				(font
					(size 0.7874 0.5842)
					(thickness 0.1524)
				)
			)
		)
		(fp_text user "2"
			(at 2.111248 19.8628 90)
			(unlocked yes)
			(layer "F.SilkS")
			(effects
				(font
					(size 0.7874 0.5842)
					(thickness 0.1524)
				)
			)
		)
		(fp_text user "EDGE OF DAUGHTER CARD"
			(at 2.2479 -0.899668 0)
			(unlocked yes)
			(layer "F.SilkS")
			(effects
				(font
					(size 0.635 0.4064)
					(thickness 0.1524)
				)
				(justify left)
			)
		)
		(fp_text user "3"
			(at 4.111244 19.8628 90)
			(unlocked yes)
			(layer "F.SilkS")
			(effects
				(font
					(size 0.7874 0.5842)
					(thickness 0.1524)
				)
			)
		)
		(fp_text user "4"
			(at 5.137912 20.054824 90)
			(unlocked yes)
			(layer "F.SilkS")
			(effects
				(font
					(size 0.7874 0.5842)
					(thickness 0.1524)
				)
			)
		)
		(fp_text user "5"
			(at 8.111236 19.8628 90)
			(unlocked yes)
			(layer "F.SilkS")
			(effects
				(font
					(size 0.7874 0.5842)
					(thickness 0.1524)
				)
			)
		)
		(fp_text user "6"
			(at 10.414762 19.99488 90)
			(unlocked yes)
			(layer "F.SilkS")
			(effects
				(font
					(size 0.7874 0.5842)
					(thickness 0.1524)
				)
			)
		)
		(fp_text user "7"
			(at 11.587226 20.5359 90)
			(unlocked yes)
			(layer "F.SilkS")
			(effects
				(font
					(size 0.7874 0.5842)
					(thickness 0.1524)
				)
			)
		)
		(fp_text user "8"
			(at 14.111224 19.8628 90)
			(unlocked yes)
			(layer "F.SilkS")
			(effects
				(font
					(size 0.7874 0.5842)
					(thickness 0.1524)
				)
			)
		)
		(fp_text user "B"
			(at 16.524224 1.199896 90)
			(unlocked yes)
			(layer "F.SilkS")
			(effects
				(font
					(size 0.7874 0.5842)
					(thickness 0.1524)
				)
			)
		)
		(fp_text user "C"
			(at 16.524224 2.400046 90)
			(unlocked yes)
			(layer "F.SilkS")
			(effects
				(font
					(size 0.7874 0.5842)
					(thickness 0.1524)
				)
			)
		)
		(fp_text user "D"
			(at 16.524224 3.599942 90)
			(unlocked yes)
			(layer "F.SilkS")
			(effects
				(font
					(size 0.7874 0.5842)
					(thickness 0.1524)
				)
			)
		)
		(fp_text user "E"
			(at 16.524224 4.800092 90)
			(unlocked yes)
			(layer "F.SilkS")
			(effects
				(font
					(size 0.7874 0.5842)
					(thickness 0.1524)
				)
			)
		)
		(fp_text user "F"
			(at 16.524224 5.999988 90)
			(unlocked yes)
			(layer "F.SilkS")
			(effects
				(font
					(size 0.7874 0.5842)
					(thickness 0.1524)
				)
			)
		)
		(fp_text user "G"
			(at 16.524224 7.199884 90)
			(unlocked yes)
			(layer "F.SilkS")
			(effects
				(font
					(size 0.7874 0.5842)
					(thickness 0.1524)
				)
			)
		)
		(fp_text user "H"
			(at 16.524224 8.400034 90)
			(unlocked yes)
			(layer "F.SilkS")
			(effects
				(font
					(size 0.7874 0.5842)
					(thickness 0.1524)
				)
			)
		)
		(fp_text user "I"
			(at 16.524224 9.59993 90)
			(unlocked yes)
			(layer "F.SilkS")
			(effects
				(font
					(size 0.7874 0.5842)
					(thickness 0.1524)
				)
			)
		)
		(fp_text user "J"
			(at 16.524224 10.80008 90)
			(unlocked yes)
			(layer "F.SilkS")
			(effects
				(font
					(size 0.7874 0.5842)
					(thickness 0.1524)
				)
			)
		)
		(fp_text user "K"
			(at 16.524224 11.999976 90)
			(unlocked yes)
			(layer "F.SilkS")
			(effects
				(font
					(size 0.7874 0.5842)
					(thickness 0.1524)
				)
			)
		)
		(fp_text user "L"
			(at 16.524224 13.200126 90)
			(unlocked yes)
			(layer "F.SilkS")
			(effects
				(font
					(size 0.7874 0.5842)
					(thickness 0.1524)
				)
			)
		)
		(fp_text user "M"
			(at 16.524224 14.400022 90)
			(unlocked yes)
			(layer "F.SilkS")
			(effects
				(font
					(size 0.7874 0.5842)
					(thickness 0.1524)
				)
			)
		)
		(fp_text user "N"
			(at 16.524224 15.599918 90)
			(unlocked yes)
			(layer "F.SilkS")
			(effects
				(font
					(size 0.7874 0.5842)
					(thickness 0.1524)
				)
			)
		)
		(fp_text user "PRESS-FIT"
			(at 18.046954 15.912592 90)
			(unlocked yes)
			(layer "F.SilkS")
			(effects
				(font
					(size 0.7874 0.5842)
					(thickness 0.1524)
				)
				(justify left)
			)
		)
		(fp_text user "A"
			(at -1.199134 0 90)
			(unlocked yes)
			(layer "B.SilkS")
			(effects
				(font
					(size 0.7874 0.5842)
					(thickness 0.1524)
				)
				(justify mirror)
			)
		)
		(fp_text user "G"
			(at -1.173734 7.4168 90)
			(unlocked yes)
			(layer "B.SilkS")
			(effects
				(font
					(size 0.7874 0.5842)
					(thickness 0.1524)
				)
				(justify mirror)
			)
		)
		(fp_text user "H"
			(at -1.148334 8.636 90)
			(unlocked yes)
			(layer "B.SilkS")
			(effects
				(font
					(size 0.7874 0.5842)
					(thickness 0.1524)
				)
				(justify mirror)
			)
		)
		(fp_text user "B"
			(at -1.14681 1.326896 90)
			(unlocked yes)
			(layer "B.SilkS")
			(effects
				(font
					(size 0.7874 0.5842)
					(thickness 0.1524)
				)
				(justify mirror)
			)
		)
		(fp_text user "C"
			(at -1.14681 2.527046 90)
			(unlocked yes)
			(layer "B.SilkS")
			(effects
				(font
					(size 0.7874 0.5842)
					(thickness 0.1524)
				)
				(justify mirror)
			)
		)
		(fp_text user "D"
			(at -1.14681 3.726942 90)
			(unlocked yes)
			(layer "B.SilkS")
			(effects
				(font
					(size 0.7874 0.5842)
					(thickness 0.1524)
				)
				(justify mirror)
			)
		)
		(fp_text user "E"
			(at -1.14681 4.927092 90)
			(unlocked yes)
			(layer "B.SilkS")
			(effects
				(font
					(size 0.7874 0.5842)
					(thickness 0.1524)
				)
				(justify mirror)
			)
		)
		(fp_text user "F"
			(at -1.14681 6.126988 90)
			(unlocked yes)
			(layer "B.SilkS")
			(effects
				(font
					(size 0.7874 0.5842)
					(thickness 0.1524)
				)
				(justify mirror)
			)
		)
		(fp_text user "I"
			(at -1.14681 9.72693 90)
			(unlocked yes)
			(layer "B.SilkS")
			(effects
				(font
					(size 0.7874 0.5842)
					(thickness 0.1524)
				)
				(justify mirror)
			)
		)
		(fp_text user "J"
			(at -1.14681 10.92708 90)
			(unlocked yes)
			(layer "B.SilkS")
			(effects
				(font
					(size 0.7874 0.5842)
					(thickness 0.1524)
				)
				(justify mirror)
			)
		)
		(fp_text user "K"
			(at -1.14681 12.126976 90)
			(unlocked yes)
			(layer "B.SilkS")
			(effects
				(font
					(size 0.7874 0.5842)
					(thickness 0.1524)
				)
				(justify mirror)
			)
		)
		(fp_text user "L"
			(at -1.14681 13.327126 90)
			(unlocked yes)
			(layer "B.SilkS")
			(effects
				(font
					(size 0.7874 0.5842)
					(thickness 0.1524)
				)
				(justify mirror)
			)
		)
		(fp_text user "M"
			(at -1.14681 14.527022 90)
			(unlocked yes)
			(layer "B.SilkS")
			(effects
				(font
					(size 0.7874 0.5842)
					(thickness 0.1524)
				)
				(justify mirror)
			)
		)
		(fp_text user "N"
			(at -1.14681 15.726918 90)
			(unlocked yes)
			(layer "B.SilkS")
			(effects
				(font
					(size 0.7874 0.5842)
					(thickness 0.1524)
				)
				(justify mirror)
			)
		)
		(fp_text user "1"
			(at 0.060452 16.764 90)
			(unlocked yes)
			(layer "B.SilkS")
			(effects
				(font
					(size 0.7874 0.5842)
					(thickness 0.1524)
				)
				(justify mirror)
			)
		)
		(fp_text user "2"
			(at 2.060448 16.764 90)
			(unlocked yes)
			(layer "B.SilkS")
			(effects
				(font
					(size 0.7874 0.5842)
					(thickness 0.1524)
				)
				(justify mirror)
			)
		)
		(fp_text user "3"
			(at 4.060444 16.764 90)
			(unlocked yes)
			(layer "B.SilkS")
			(effects
				(font
					(size 0.7874 0.5842)
					(thickness 0.1524)
				)
				(justify mirror)
			)
		)
		(fp_text user "4"
			(at 6.06044 16.764 90)
			(unlocked yes)
			(layer "B.SilkS")
			(effects
				(font
					(size 0.7874 0.5842)
					(thickness 0.1524)
				)
				(justify mirror)
			)
		)
		(fp_text user "5"
			(at 8.060436 16.764 90)
			(unlocked yes)
			(layer "B.SilkS")
			(effects
				(font
					(size 0.7874 0.5842)
					(thickness 0.1524)
				)
				(justify mirror)
			)
		)
		(fp_text user "6"
			(at 10.060432 16.764 90)
			(unlocked yes)
			(layer "B.SilkS")
			(effects
				(font
					(size 0.7874 0.5842)
					(thickness 0.1524)
				)
				(justify mirror)
			)
		)
		(fp_text user "7"
			(at 12.060428 16.764 90)
			(unlocked yes)
			(layer "B.SilkS")
			(effects
				(font
					(size 0.7874 0.5842)
					(thickness 0.1524)
				)
				(justify mirror)
			)
		)
		(fp_text user "8"
			(at 14.060424 16.764 90)
			(unlocked yes)
			(layer "B.SilkS")
			(effects
				(font
					(size 0.7874 0.5842)
					(thickness 0.1524)
				)
				(justify mirror)
			)
		)
		(fp_text user "PRESS-FIT"
			(at 17.23771 -0.0762 90)
			(unlocked yes)
			(layer "B.SilkS")
			(effects
				(font
					(size 1.905 1.4224)
					(thickness 0.1524)
				)
				(justify left mirror)
			)
		)
		(fp_text user "A"
			(at -1.199134 0 90)
			(unlocked yes)
			(layer "B.Fab")
			(effects
				(font
					(size 0.7874 0.5842)
					(thickness 0.1524)
				)
				(justify mirror)
			)
		)
		(fp_text user "G"
			(at -1.173734 7.4168 90)
			(unlocked yes)
			(layer "B.Fab")
			(effects
				(font
					(size 0.7874 0.5842)
					(thickness 0.1524)
				)
				(justify mirror)
			)
		)
		(fp_text user "H"
			(at -1.148334 8.636 90)
			(unlocked yes)
			(layer "B.Fab")
			(effects
				(font
					(size 0.7874 0.5842)
					(thickness 0.1524)
				)
				(justify mirror)
			)
		)
		(fp_text user "B"
			(at -1.14681 1.326896 90)
			(unlocked yes)
			(layer "B.Fab")
			(effects
				(font
					(size 0.7874 0.5842)
					(thickness 0.1524)
				)
				(justify mirror)
			)
		)
		(fp_text user "C"
			(at -1.14681 2.527046 90)
			(unlocked yes)
			(layer "B.Fab")
			(effects
				(font
					(size 0.7874 0.5842)
					(thickness 0.1524)
				)
				(justify mirror)
			)
		)
		(fp_text user "D"
			(at -1.14681 3.726942 90)
			(unlocked yes)
			(layer "B.Fab")
			(effects
				(font
					(size 0.7874 0.5842)
					(thickness 0.1524)
				)
				(justify mirror)
			)
		)
		(fp_text user "E"
			(at -1.14681 4.927092 90)
			(unlocked yes)
			(layer "B.Fab")
			(effects
				(font
					(size 0.7874 0.5842)
					(thickness 0.1524)
				)
				(justify mirror)
			)
		)
		(fp_text user "F"
			(at -1.14681 6.126988 90)
			(unlocked yes)
			(layer "B.Fab")
			(effects
				(font
					(size 0.7874 0.5842)
					(thickness 0.1524)
				)
				(justify mirror)
			)
		)
		(fp_text user "I"
			(at -1.14681 9.72693 90)
			(unlocked yes)
			(layer "B.Fab")
			(effects
				(font
					(size 0.7874 0.5842)
					(thickness 0.1524)
				)
				(justify mirror)
			)
		)
		(fp_text user "J"
			(at -1.14681 10.92708 90)
			(unlocked yes)
			(layer "B.Fab")
			(effects
				(font
					(size 0.7874 0.5842)
					(thickness 0.1524)
				)
				(justify mirror)
			)
		)
		(fp_text user "K"
			(at -1.14681 12.126976 90)
			(unlocked yes)
			(layer "B.Fab")
			(effects
				(font
					(size 0.7874 0.5842)
					(thickness 0.1524)
				)
				(justify mirror)
			)
		)
		(fp_text user "L"
			(at -1.14681 13.327126 90)
			(unlocked yes)
			(layer "B.Fab")
			(effects
				(font
					(size 0.7874 0.5842)
					(thickness 0.1524)
				)
				(justify mirror)
			)
		)
		(fp_text user "M"
			(at -1.14681 14.527022 90)
			(unlocked yes)
			(layer "B.Fab")
			(effects
				(font
					(size 0.7874 0.5842)
					(thickness 0.1524)
				)
				(justify mirror)
			)
		)
		(fp_text user "N"
			(at -1.14681 15.726918 90)
			(unlocked yes)
			(layer "B.Fab")
			(effects
				(font
					(size 0.7874 0.5842)
					(thickness 0.1524)
				)
				(justify mirror)
			)
		)
		(fp_text user "1"
			(at 0.060452 16.764 90)
			(unlocked yes)
			(layer "B.Fab")
			(effects
				(font
					(size 0.7874 0.5842)
					(thickness 0.1524)
				)
				(justify mirror)
			)
		)
		(fp_text user "2"
			(at 2.060448 16.764 90)
			(unlocked yes)
			(layer "B.Fab")
			(effects
				(font
					(size 0.7874 0.5842)
					(thickness 0.1524)
				)
				(justify mirror)
			)
		)
		(fp_text user "3"
			(at 4.060444 16.764 90)
			(unlocked yes)
			(layer "B.Fab")
			(effects
				(font
					(size 0.7874 0.5842)
					(thickness 0.1524)
				)
				(justify mirror)
			)
		)
		(fp_text user "4"
			(at 6.06044 16.764 90)
			(unlocked yes)
			(layer "B.Fab")
			(effects
				(font
					(size 0.7874 0.5842)
					(thickness 0.1524)
				)
				(justify mirror)
			)
		)
		(fp_text user "5"
			(at 8.060436 16.764 90)
			(unlocked yes)
			(layer "B.Fab")
			(effects
				(font
					(size 0.7874 0.5842)
					(thickness 0.1524)
				)
				(justify mirror)
			)
		)
		(fp_text user "6"
			(at 10.060432 16.764 90)
			(unlocked yes)
			(layer "B.Fab")
			(effects
				(font
					(size 0.7874 0.5842)
					(thickness 0.1524)
				)
				(justify mirror)
			)
		)
		(fp_text user "7"
			(at 12.060428 16.764 90)
			(unlocked yes)
			(layer "B.Fab")
			(effects
				(font
					(size 0.7874 0.5842)
					(thickness 0.1524)
				)
				(justify mirror)
			)
		)
		(fp_text user "8"
			(at 14.060424 16.764 90)
			(unlocked yes)
			(layer "B.Fab")
			(effects
				(font
					(size 0.7874 0.5842)
					(thickness 0.1524)
				)
				(justify mirror)
			)
		)
		(fp_text user "PRESS-FIT"
			(at 17.23771 -0.0762 90)
			(unlocked yes)
			(layer "B.Fab")
			(effects
				(font
					(size 1.905 1.4224)
					(thickness 0.1524)
				)
				(justify left mirror)
			)
		)
		(fp_text user "B"
			(at -2.253742 1.199896 90)
			(unlocked yes)
			(layer "F.Fab")
			(effects
				(font
					(size 0.7874 0.5842)
					(thickness 0.1524)
				)
			)
		)
		(fp_text user "C"
			(at -2.253742 2.400046 90)
			(unlocked yes)
			(layer "F.Fab")
			(effects
				(font
					(size 0.7874 0.5842)
					(thickness 0.1524)
				)
			)
		)
		(fp_text user "D"
			(at -2.253742 3.599942 90)
			(unlocked yes)
			(layer "F.Fab")
			(effects
				(font
					(size 0.7874 0.5842)
					(thickness 0.1524)
				)
			)
		)
		(fp_text user "E"
			(at -2.253742 4.800092 90)
			(unlocked yes)
			(layer "F.Fab")
			(effects
				(font
					(size 0.7874 0.5842)
					(thickness 0.1524)
				)
			)
		)
		(fp_text user "F"
			(at -2.253742 5.999988 90)
			(unlocked yes)
			(layer "F.Fab")
			(effects
				(font
					(size 0.7874 0.5842)
					(thickness 0.1524)
				)
			)
		)
		(fp_text user "G"
			(at -2.253742 7.199884 90)
			(unlocked yes)
			(layer "F.Fab")
			(effects
				(font
					(size 0.7874 0.5842)
					(thickness 0.1524)
				)
			)
		)
		(fp_text user "H"
			(at -2.253742 8.400034 90)
			(unlocked yes)
			(layer "F.Fab")
			(effects
				(font
					(size 0.7874 0.5842)
					(thickness 0.1524)
				)
			)
		)
		(fp_text user "I"
			(at -2.253742 9.59993 90)
			(unlocked yes)
			(layer "F.Fab")
			(effects
				(font
					(size 0.7874 0.5842)
					(thickness 0.1524)
				)
			)
		)
		(fp_text user "J"
			(at -2.253742 10.80008 90)
			(unlocked yes)
			(layer "F.Fab")
			(effects
				(font
					(size 0.7874 0.5842)
					(thickness 0.1524)
				)
			)
		)
		(fp_text user "K"
			(at -2.253742 11.999976 90)
			(unlocked yes)
			(layer "F.Fab")
			(effects
				(font
					(size 0.7874 0.5842)
					(thickness 0.1524)
				)
			)
		)
		(fp_text user "L"
			(at -2.253742 13.200126 90)
			(unlocked yes)
			(layer "F.Fab")
			(effects
				(font
					(size 0.7874 0.5842)
					(thickness 0.1524)
				)
			)
		)
		(fp_text user "M"
			(at -2.253742 14.400022 90)
			(unlocked yes)
			(layer "F.Fab")
			(effects
				(font
					(size 0.7874 0.5842)
					(thickness 0.1524)
				)
			)
		)
		(fp_text user "N"
			(at -2.253742 15.599918 90)
			(unlocked yes)
			(layer "F.Fab")
			(effects
				(font
					(size 0.7874 0.5842)
					(thickness 0.1524)
				)
			)
		)
		(fp_text user "1"
			(at 0.111252 19.8628 90)
			(unlocked yes)
			(layer "F.Fab")
			(effects
				(font
					(size 0.7874 0.5842)
					(thickness 0.1524)
				)
			)
		)
		(fp_text user "2"
			(at 2.111248 19.8628 90)
			(unlocked yes)
			(layer "F.Fab")
			(effects
				(font
					(size 0.7874 0.5842)
					(thickness 0.1524)
				)
			)
		)
		(fp_text user "3"
			(at 4.111244 19.8628 90)
			(unlocked yes)
			(layer "F.Fab")
			(effects
				(font
					(size 0.7874 0.5842)
					(thickness 0.1524)
				)
			)
		)
		(fp_text user "4"
			(at 6.11124 19.8628 90)
			(unlocked yes)
			(layer "F.Fab")
			(effects
				(font
					(size 0.7874 0.5842)
					(thickness 0.1524)
				)
			)
		)
		(fp_text user "5"
			(at 8.111236 19.8628 90)
			(unlocked yes)
			(layer "F.Fab")
			(effects
				(font
					(size 0.7874 0.5842)
					(thickness 0.1524)
				)
			)
		)
		(fp_text user "6"
			(at 10.111232 19.8628 90)
			(unlocked yes)
			(layer "F.Fab")
			(effects
				(font
					(size 0.7874 0.5842)
					(thickness 0.1524)
				)
			)
		)
		(fp_text user "7"
			(at 12.111228 19.8628 90)
			(unlocked yes)
			(layer "F.Fab")
			(effects
				(font
					(size 0.7874 0.5842)
					(thickness 0.1524)
				)
			)
		)
		(fp_text user "8"
			(at 14.111224 19.8628 90)
			(unlocked yes)
			(layer "F.Fab")
			(effects
				(font
					(size 0.7874 0.5842)
					(thickness 0.1524)
				)
			)
		)
		(fp_text user "PRESS-FIT"
			(at 17.240758 16.521684 90)
			(unlocked yes)
			(layer "F.Fab")
			(effects
				(font
					(size 1.905 1.4224)
					(thickness 0.1524)
				)
				(justify left)
			)
		)
		(pad "A1" thru_hole rect
			(at 0 0 180)
			(size 0.766318 0.766318)
			(drill 0.359918)
			(layers "*.Cu" "*.Mask")
			(remove_unused_layers no)
			(net "NC_J107_A1")
			(clearance 0.0508)
			(thermal_gap 0.0508)
			(padstack
				(mode front_inner_back)
				(layer "Inner"
					(shape circle)
					(size 0.766318 0.766318)
					(clearance 0.0508)
				)
				(layer "B.Cu"
					(shape rect)
					(size 0.766318 0.766318)
					(clearance 0.0508)
				)
			)
		)
		(pad "A2" thru_hole circle
			(at 1.999996 0.199898 180)
			(size 0.906272 0.906272)
			(drill 0.499872)
			(layers "*.Cu" "*.Mask")
			(remove_unused_layers no)
			(net "GND")
			(clearance 0.0508)
			(thermal_gap 0.0508)
		)
		(pad "A3" thru_hole circle
			(at 3.999992 0 180)
			(size 0.766318 0.766318)
			(drill 0.359918)
			(layers "*.Cu" "*.Mask")
			(remove_unused_layers no)
			(net "NC_J107_A3")
			(clearance 0.0508)
			(thermal_gap 0.0508)
		)
		(pad "A4" thru_hole circle
			(at 5.999988 0.199898 180)
			(size 0.906272 0.906272)
			(drill 0.499872)
			(layers "*.Cu" "*.Mask")
			(remove_unused_layers no)
			(net "GND")
			(clearance 0.0508)
			(thermal_gap 0.0508)
		)
		(pad "A5" thru_hole circle
			(at 7.999984 0 180)
			(size 0.766318 0.766318)
			(drill 0.359918)
			(layers "*.Cu" "*.Mask")
			(remove_unused_layers no)
			(net "NC_J107_A5")
			(clearance 0.0508)
			(thermal_gap 0.0508)
		)
		(pad "A6" thru_hole circle
			(at 9.99998 0.199898 180)
			(size 0.906272 0.906272)
			(drill 0.499872)
			(layers "*.Cu" "*.Mask")
			(remove_unused_layers no)
			(net "GND")
			(clearance 0.0508)
			(thermal_gap 0.0508)
		)
		(pad "A7" thru_hole circle
			(at 11.999976 0 180)
			(size 0.766318 0.766318)
			(drill 0.359918)
			(layers "*.Cu" "*.Mask")
			(remove_unused_layers no)
			(net "SWB_HSC_PWRGD")
			(clearance 0.0508)
			(thermal_gap 0.0508)
		)
		(pad "A8" thru_hole circle
			(at 13.999972 0.199898 180)
			(size 0.906272 0.906272)
			(drill 0.499872)
			(layers "*.Cu" "*.Mask")
			(remove_unused_layers no)
			(net "GND")
			(clearance 0.0508)
			(thermal_gap 0.0508)
		)
		(pad "B1" thru_hole circle
			(at 0 1.199896 180)
			(size 0.906272 0.906272)
			(drill 0.499872)
			(layers "*.Cu" "*.Mask")
			(remove_unused_layers no)
			(net "GND")
			(clearance 0.0508)
			(thermal_gap 0.0508)
		)
		(pad "B3" thru_hole circle
			(at 3.999992 1.199896 180)
			(size 0.906272 0.906272)
			(drill 0.499872)
			(layers "*.Cu" "*.Mask")
			(remove_unused_layers no)
			(net "GND")
			(clearance 0.0508)
			(thermal_gap 0.0508)
		)
		(pad "B5" thru_hole circle
			(at 7.999984 1.199896 180)
			(size 0.906272 0.906272)
			(drill 0.499872)
			(layers "*.Cu" "*.Mask")
			(remove_unused_layers no)
			(net "GND")
			(clearance 0.0508)
			(thermal_gap 0.0508)
		)
		(pad "B7" thru_hole circle
			(at 11.999976 1.199896 180)
			(size 0.906272 0.906272)
			(drill 0.499872)
			(layers "*.Cu" "*.Mask")
			(remove_unused_layers no)
			(net "GND")
			(clearance 0.0508)
			(thermal_gap 0.0508)
		)
		(pad "D2" thru_hole circle
			(at 1.999996 3.800094 180)
			(size 0.906272 0.906272)
			(drill 0.499872)
			(layers "*.Cu" "*.Mask")
			(remove_unused_layers no)
			(net "GND")
			(clearance 0.0508)
			(thermal_gap 0.0508)
		)
		(pad "D4" thru_hole circle
			(at 5.999988 3.800094 180)
			(size 0.906272 0.906272)
			(drill 0.499872)
			(layers "*.Cu" "*.Mask")
			(remove_unused_layers no)
			(net "GND")
			(clearance 0.0508)
			(thermal_gap 0.0508)
		)
		(pad "D6" thru_hole circle
			(at 9.99998 3.800094 180)
			(size 0.906272 0.906272)
			(drill 0.499872)
			(layers "*.Cu" "*.Mask")
			(remove_unused_layers no)
			(net "GND")
			(clearance 0.0508)
			(thermal_gap 0.0508)
		)
		(pad "D8" thru_hole circle
			(at 13.999972 3.800094 180)
			(size 0.906272 0.906272)
			(drill 0.499872)
			(layers "*.Cu" "*.Mask")
			(remove_unused_layers no)
			(net "GND")
			(clearance 0.0508)
			(thermal_gap 0.0508)
		)
		(pad "E1" thru_hole circle
			(at 0 4.800092 180)
			(size 0.906272 0.906272)
			(drill 0.499872)
			(layers "*.Cu" "*.Mask")
			(remove_unused_layers no)
			(net "GND")
			(clearance 0.0508)
			(thermal_gap 0.0508)
		)
		(pad "E3" thru_hole circle
			(at 3.999992 4.800092 180)
			(size 0.906272 0.906272)
			(drill 0.499872)
			(layers "*.Cu" "*.Mask")
			(remove_unused_layers no)
			(net "GND")
			(clearance 0.0508)
			(thermal_gap 0.0508)
		)
		(pad "E5" thru_hole circle
			(at 7.999984 4.800092 180)
			(size 0.906272 0.906272)
			(drill 0.499872)
			(layers "*.Cu" "*.Mask")
			(remove_unused_layers no)
			(net "GND")
			(clearance 0.0508)
			(thermal_gap 0.0508)
		)
		(pad "E7" thru_hole circle
			(at 11.999976 4.800092 180)
			(size 0.906272 0.906272)
			(drill 0.499872)
			(layers "*.Cu" "*.Mask")
			(remove_unused_layers no)
			(net "GND")
			(clearance 0.0508)
			(thermal_gap 0.0508)
		)
		(pad "G2" thru_hole circle
			(at 1.999996 7.400036 180)
			(size 0.906272 0.906272)
			(drill 0.499872)
			(layers "*.Cu" "*.Mask")
			(remove_unused_layers no)
			(net "GND")
			(clearance 0.0508)
			(thermal_gap 0.0508)
		)
		(pad "G4" thru_hole circle
			(at 5.999988 7.400036 180)
			(size 0.906272 0.906272)
			(drill 0.499872)
			(layers "*.Cu" "*.Mask")
			(remove_unused_layers no)
			(net "GND")
			(clearance 0.0508)
			(thermal_gap 0.0508)
		)
		(pad "G6" thru_hole circle
			(at 9.99998 7.400036 180)
			(size 0.906272 0.906272)
			(drill 0.499872)
			(layers "*.Cu" "*.Mask")
			(remove_unused_layers no)
			(net "GND")
			(clearance 0.0508)
			(thermal_gap 0.0508)
		)
		(pad "G8" thru_hole circle
			(at 13.999972 7.400036 180)
			(size 0.906272 0.906272)
			(drill 0.499872)
			(layers "*.Cu" "*.Mask")
			(remove_unused_layers no)
			(net "GND")
			(clearance 0.0508)
			(thermal_gap 0.0508)
		)
		(pad "H1" thru_hole circle
			(at 0 8.400034 180)
			(size 0.906272 0.906272)
			(drill 0.499872)
			(layers "*.Cu" "*.Mask")
			(remove_unused_layers no)
			(net "GND")
			(clearance 0.0508)
			(thermal_gap 0.0508)
		)
		(pad "H3" thru_hole circle
			(at 3.999992 8.400034 180)
			(size 0.906272 0.906272)
			(drill 0.499872)
			(layers "*.Cu" "*.Mask")
			(remove_unused_layers no)
			(net "GND")
			(clearance 0.0508)
			(thermal_gap 0.0508)
		)
		(pad "H5" thru_hole circle
			(at 7.999984 8.400034 180)
			(size 0.906272 0.906272)
			(drill 0.499872)
			(layers "*.Cu" "*.Mask")
			(remove_unused_layers no)
			(net "GND")
			(clearance 0.0508)
			(thermal_gap 0.0508)
		)
		(pad "H7" thru_hole circle
			(at 11.999976 8.400034 180)
			(size 0.906272 0.906272)
			(drill 0.499872)
			(layers "*.Cu" "*.Mask")
			(remove_unused_layers no)
			(net "GND")
			(clearance 0.0508)
			(thermal_gap 0.0508)
		)
		(pad "J2" thru_hole circle
			(at 1.999996 10.999978 180)
			(size 0.906272 0.906272)
			(drill 0.499872)
			(layers "*.Cu" "*.Mask")
			(remove_unused_layers no)
			(net "GND")
			(clearance 0.0508)
			(thermal_gap 0.0508)
		)
		(pad "J4" thru_hole circle
			(at 5.999988 10.999978 180)
			(size 0.906272 0.906272)
			(drill 0.499872)
			(layers "*.Cu" "*.Mask")
			(remove_unused_layers no)
			(net "GND")
			(clearance 0.0508)
			(thermal_gap 0.0508)
		)
		(pad "J6" thru_hole circle
			(at 9.99998 10.999978 180)
			(size 0.906272 0.906272)
			(drill 0.499872)
			(layers "*.Cu" "*.Mask")
			(remove_unused_layers no)
			(net "GND")
			(clearance 0.0508)
			(thermal_gap 0.0508)
		)
		(pad "J8" thru_hole circle
			(at 13.999972 10.999978 180)
			(size 0.906272 0.906272)
			(drill 0.499872)
			(layers "*.Cu" "*.Mask")
			(remove_unused_layers no)
			(net "GND")
			(clearance 0.0508)
			(thermal_gap 0.0508)
		)
		(pad "K1" thru_hole circle
			(at 0 11.999976 180)
			(size 0.906272 0.906272)
			(drill 0.499872)
			(layers "*.Cu" "*.Mask")
			(remove_unused_layers no)
			(net "GND")
			(clearance 0.0508)
			(thermal_gap 0.0508)
		)
		(pad "K3" thru_hole circle
			(at 3.999992 11.999976 180)
			(size 0.906272 0.906272)
			(drill 0.499872)
			(layers "*.Cu" "*.Mask")
			(remove_unused_layers no)
			(net "GND")
			(clearance 0.0508)
			(thermal_gap 0.0508)
		)
		(pad "K5" thru_hole circle
			(at 7.999984 11.999976 180)
			(size 0.906272 0.906272)
			(drill 0.499872)
			(layers "*.Cu" "*.Mask")
			(remove_unused_layers no)
			(net "GND")
			(clearance 0.0508)
			(thermal_gap 0.0508)
		)
		(pad "K7" thru_hole circle
			(at 11.999976 11.999976 180)
			(size 0.906272 0.906272)
			(drill 0.499872)
			(layers "*.Cu" "*.Mask")
			(remove_unused_layers no)
			(net "GND")
			(clearance 0.0508)
			(thermal_gap 0.0508)
		)
		(pad "M2" thru_hole circle
			(at 1.999996 14.59992 180)
			(size 0.906272 0.906272)
			(drill 0.499872)
			(layers "*.Cu" "*.Mask")
			(remove_unused_layers no)
			(net "GND")
			(clearance 0.0508)
			(thermal_gap 0.0508)
		)
		(pad "M4" thru_hole circle
			(at 5.999988 14.59992 180)
			(size 0.906272 0.906272)
			(drill 0.499872)
			(layers "*.Cu" "*.Mask")
			(remove_unused_layers no)
			(net "GND")
			(clearance 0.0508)
			(thermal_gap 0.0508)
		)
		(pad "M6" thru_hole circle
			(at 9.99998 14.59992 180)
			(size 0.906272 0.906272)
			(drill 0.499872)
			(layers "*.Cu" "*.Mask")
			(remove_unused_layers no)
			(net "GND")
			(clearance 0.0508)
			(thermal_gap 0.0508)
		)
		(pad "M8" thru_hole circle
			(at 13.999972 14.59992 180)
			(size 0.906272 0.906272)
			(drill 0.499872)
			(layers "*.Cu" "*.Mask")
			(remove_unused_layers no)
			(net "GND")
			(clearance 0.0508)
			(thermal_gap 0.0508)
		)
		(pad "N1" thru_hole circle
			(at 0 15.599918 180)
			(size 0.906272 0.906272)
			(drill 0.499872)
			(layers "*.Cu" "*.Mask")
			(remove_unused_layers no)
			(net "GND")
			(clearance 0.0508)
			(thermal_gap 0.0508)
		)
		(pad "N2" thru_hole circle
			(at 1.999996 15.80007 180)
			(size 0.766318 0.766318)
			(drill 0.359918)
			(layers "*.Cu" "*.Mask")
			(remove_unused_layers no)
			(net "PRSNT_CABLE_SWB_B2_N")
			(clearance 0.0508)
			(thermal_gap 0.0508)
		)
		(pad "N3" thru_hole circle
			(at 3.999992 15.599918 180)
			(size 0.906272 0.906272)
			(drill 0.499872)
			(layers "*.Cu" "*.Mask")
			(remove_unused_layers no)
			(net "GND")
			(clearance 0.0508)
			(thermal_gap 0.0508)
		)
		(pad "N4" thru_hole circle
			(at 5.999988 15.80007 180)
			(size 0.766318 0.766318)
			(drill 0.359918)
			(layers "*.Cu" "*.Mask")
			(remove_unused_layers no)
			(net "NC_J107_N4")
			(clearance 0.0508)
			(thermal_gap 0.0508)
		)
		(pad "N5" thru_hole circle
			(at 7.999984 15.599918 180)
			(size 0.906272 0.906272)
			(drill 0.499872)
			(layers "*.Cu" "*.Mask")
			(remove_unused_layers no)
			(net "GND")
			(clearance 0.0508)
			(thermal_gap 0.0508)
		)
		(pad "N6" thru_hole circle
			(at 9.99998 15.80007 180)
			(size 0.766318 0.766318)
			(drill 0.359918)
			(layers "*.Cu" "*.Mask")
			(remove_unused_layers no)
			(net "NC_J107_N6")
			(clearance 0.0508)
			(thermal_gap 0.0508)
		)
		(pad "N7" thru_hole circle
			(at 11.999976 15.599918 180)
			(size 0.906272 0.906272)
			(drill 0.499872)
			(layers "*.Cu" "*.Mask")
			(remove_unused_layers no)
			(net "GND")
			(clearance 0.0508)
			(thermal_gap 0.0508)
		)
		(pad "N8" thru_hole circle
			(at 13.999972 15.80007 180)
			(size 0.766318 0.766318)
			(drill 0.359918)
			(layers "*.Cu" "*.Mask")
			(remove_unused_layers no)
			(net "SWB_HSC_EN_BUF")
			(clearance 0.0508)
			(thermal_gap 0.0508)
		)
		(zone
			(layer "B.Cu")
			(hatch none 0.5)
			(connect_pads
				(clearance 0)
			)
			(min_thickness 0.25)
			(keepout
				(tracks allowed)
				(vias not_allowed)
				(pads allowed)
				(copperpour not_allowed)
				(footprints allowed)
			)
			(placement
				(enabled no)
				(sheetname "")
			)
			(fill
				(thermal_gap 0.5)
				(thermal_bridge_width 0.5)
				(island_removal_mode 0)
			)
			(polygon
				(pts
					(xy 331.141832 -424.246548) (xy 346.165932 -424.246548) (xy 346.165932 -440.934348) (xy 331.141832 -440.934348)
				)
			)
		)
	)
	(footprint ""
		(layer "F.Cu")
		(at 384.113278 -139.186158 180)
		(property "Reference" "PR314"
			(at 0 0 180)
			(layer "F.SilkS")
			(hide yes)
			(effects
				(font
					(size 1.27 1.27)
				)
			)
		)
		(property "Value" ""
			(at 0 0 180)
			(layer "F.Fab")
			(effects
				(font
					(size 1.27 1.27)
				)
			)
		)
		(duplicate_pad_numbers_are_jumpers no)
		(fp_line
			(start 0.7874 0.4064)
			(end -0.7874 0.4064)
			(stroke
				(width 0.1524)
				(type default)
			)
			(layer "F.SilkS")
		)
		(fp_line
			(start 0.7874 -0.4064)
			(end 0.7874 0.4064)
			(stroke
				(width 0.1524)
				(type default)
			)
			(layer "F.SilkS")
		)
		(fp_line
			(start -0.7874 0.4064)
			(end -0.7874 -0.4064)
			(stroke
				(width 0.1524)
				(type default)
			)
			(layer "F.SilkS")
		)
		(fp_line
			(start -0.7874 -0.4064)
			(end 0.7874 -0.4064)
			(stroke
				(width 0.1524)
				(type default)
			)
			(layer "F.SilkS")
		)
		(fp_line
			(start 0.67945 0.3048)
			(end 0.120396 0.3048)
			(stroke
				(width 0.1)
				(type default)
			)
			(layer "F.Fab")
		)
		(fp_line
			(start 0.67945 -0.3048)
			(end 0.67945 0.3048)
			(stroke
				(width 0.1)
				(type default)
			)
			(layer "F.Fab")
		)
		(fp_line
			(start 0.12065 -0.2794)
			(end 0.12065 -0.3048)
			(stroke
				(width 0.1)
				(type default)
			)
			(layer "F.Fab")
		)
		(fp_line
			(start 0.12065 -0.3048)
			(end 0.67945 -0.3048)
			(stroke
				(width 0.1)
				(type default)
			)
			(layer "F.Fab")
		)
		(fp_line
			(start 0.120396 0.3048)
			(end 0.120396 0.2794)
			(stroke
				(width 0.1)
				(type default)
			)
			(layer "F.Fab")
		)
		(fp_line
			(start 0.120396 0.2794)
			(end -0.12065 0.2794)
			(stroke
				(width 0.1)
				(type default)
			)
			(layer "F.Fab")
		)
		(fp_line
			(start -0.12065 0.3048)
			(end -0.67945 0.3048)
			(stroke
				(width 0.1)
				(type default)
			)
			(layer "F.Fab")
		)
		(fp_line
			(start -0.12065 0.2794)
			(end -0.12065 0.3048)
			(stroke
				(width 0.1)
				(type default)
			)
			(layer "F.Fab")
		)
		(fp_line
			(start -0.12065 -0.2794)
			(end 0.12065 -0.2794)
			(stroke
				(width 0.1)
				(type default)
			)
			(layer "F.Fab")
		)
		(fp_line
			(start -0.12065 -0.305054)
			(end -0.12065 -0.2794)
			(stroke
				(width 0.1)
				(type default)
			)
			(layer "F.Fab")
		)
		(fp_line
			(start -0.67945 0.3048)
			(end -0.67945 -0.305054)
			(stroke
				(width 0.1)
				(type default)
			)
			(layer "F.Fab")
		)
		(fp_line
			(start -0.67945 -0.305054)
			(end -0.12065 -0.305054)
			(stroke
				(width 0.1)
				(type default)
			)
			(layer "F.Fab")
		)
		(pad "1" smd circle
			(at -0.40005 0 180)
			(size 0 0)
			(layers "F.Cu" "F.Mask" "F.Paste")
			(net "P12V_AUX")
		)
		(pad "2" smd circle
			(at 0.40005 0 180)
			(size 0 0)
			(layers "F.Cu" "F.Mask" "F.Paste")
			(net "PVDDCR_CPU0_P0_VINSEN")
		)
	)
	(footprint ""
		(layer "F.Cu")
		(at 75.05573 -386.951474)
		(property "Reference" "R598"
			(at 0 0 0)
			(layer "F.SilkS")
			(hide yes)
			(effects
				(font
					(size 1.27 1.27)
				)
			)
		)
		(property "Value" ""
			(at 0 0 0)
			(layer "F.Fab")
			(effects
				(font
					(size 1.27 1.27)
				)
			)
		)
		(duplicate_pad_numbers_are_jumpers no)
		(fp_line
			(start -0.32512 -0.175006)
			(end 0.32512 -0.175006)
			(stroke
				(width 0.1)
				(type default)
			)
			(layer "F.Fab")
		)
		(fp_line
			(start -0.32512 0.175006)
			(end -0.32512 -0.175006)
			(stroke
				(width 0.1)
				(type default)
			)
			(layer "F.Fab")
		)
		(fp_line
			(start 0.32512 -0.175006)
			(end 0.32512 0.175006)
			(stroke
				(width 0.1)
				(type default)
			)
			(layer "F.Fab")
		)
		(fp_line
			(start 0.32512 0.175006)
			(end -0.32512 0.175006)
			(stroke
				(width 0.1)
				(type default)
			)
			(layer "F.Fab")
		)
		(pad "1" smd rect
			(at -0.2667 0)
			(size 0.3048 0.381)
			(layers "F.Cu" "F.Mask" "F.Paste")
			(net "CLK_100M_RETIMER_CPU1_P1_R_DN")
		)
		(pad "2" smd rect
			(at 0.2667 0 180)
			(size 0.3048 0.381)
			(layers "F.Cu" "F.Mask" "F.Paste")
			(net "CLK_100M_RETIMER_CPU1_P1_DN")
		)
	)
	(footprint ""
		(layer "F.Cu")
		(at 30.484064 -75.234038 90)
		(property "Reference" "R1318"
			(at 0 0 90)
			(layer "F.SilkS")
			(hide yes)
			(effects
				(font
					(size 1.27 1.27)
				)
			)
		)
		(property "Value" ""
			(at 0 0 90)
			(layer "F.Fab")
			(effects
				(font
					(size 1.27 1.27)
				)
			)
		)
		(duplicate_pad_numbers_are_jumpers no)
		(fp_line
			(start 0.7874 -0.4064)
			(end 0.7874 0.4064)
			(stroke
				(width 0.1524)
				(type default)
			)
			(layer "F.SilkS")
		)
		(fp_line
			(start -0.7874 -0.4064)
			(end 0.7874 -0.4064)
			(stroke
				(width 0.1524)
				(type default)
			)
			(layer "F.SilkS")
		)
		(fp_line
			(start 0.7874 0.4064)
			(end -0.7874 0.4064)
			(stroke
				(width 0.1524)
				(type default)
			)
			(layer "F.SilkS")
		)
		(fp_line
			(start -0.7874 0.4064)
			(end -0.7874 -0.4064)
			(stroke
				(width 0.1524)
				(type default)
			)
			(layer "F.SilkS")
		)
		(fp_line
			(start -0.12065 -0.305054)
			(end -0.12065 -0.2794)
			(stroke
				(width 0.1)
				(type default)
			)
			(layer "F.Fab")
		)
		(fp_line
			(start -0.67945 -0.305054)
			(end -0.12065 -0.305054)
			(stroke
				(width 0.1)
				(type default)
			)
			(layer "F.Fab")
		)
		(fp_line
			(start 0.67945 -0.3048)
			(end 0.67945 0.3048)
			(stroke
				(width 0.1)
				(type default)
			)
			(layer "F.Fab")
		)
		(fp_line
			(start 0.12065 -0.3048)
			(end 0.67945 -0.3048)
			(stroke
				(width 0.1)
				(type default)
			)
			(layer "F.Fab")
		)
		(fp_line
			(start 0.12065 -0.2794)
			(end 0.12065 -0.3048)
			(stroke
				(width 0.1)
				(type default)
			)
			(layer "F.Fab")
		)
		(fp_line
			(start -0.12065 -0.2794)
			(end 0.12065 -0.2794)
			(stroke
				(width 0.1)
				(type default)
			)
			(layer "F.Fab")
		)
		(fp_line
			(start 0.120396 0.2794)
			(end -0.12065 0.2794)
			(stroke
				(width 0.1)
				(type default)
			)
			(layer "F.Fab")
		)
		(fp_line
			(start -0.12065 0.2794)
			(end -0.12065 0.3048)
			(stroke
				(width 0.1)
				(type default)
			)
			(layer "F.Fab")
		)
		(fp_line
			(start 0.67945 0.3048)
			(end 0.120396 0.3048)
			(stroke
				(width 0.1)
				(type default)
			)
			(layer "F.Fab")
		)
		(fp_line
			(start 0.120396 0.3048)
			(end 0.120396 0.2794)
			(stroke
				(width 0.1)
				(type default)
			)
			(layer "F.Fab")
		)
		(fp_line
			(start -0.12065 0.3048)
			(end -0.67945 0.3048)
			(stroke
				(width 0.1)
				(type default)
			)
			(layer "F.Fab")
		)
		(fp_line
			(start -0.67945 0.3048)
			(end -0.67945 -0.305054)
			(stroke
				(width 0.1)
				(type default)
			)
			(layer "F.Fab")
		)
		(pad "1" smd circle
			(at -0.40005 0 90)
			(size 0 0)
			(layers "F.Cu" "F.Mask" "F.Paste")
			(net "PD_U212_EN_N")
		)
		(pad "2" smd circle
			(at 0.40005 0 90)
			(size 0 0)
			(layers "F.Cu" "F.Mask" "F.Paste")
			(net "GND")
		)
	)
	(footprint ""
		(layer "F.Cu")
		(at 47.608744 -421.326564)
		(property "Reference" "R1381"
			(at 0 0 0)
			(layer "F.SilkS")
			(hide yes)
			(effects
				(font
					(size 1.27 1.27)
				)
			)
		)
		(property "Value" ""
			(at 0 0 0)
			(layer "F.Fab")
			(effects
				(font
					(size 1.27 1.27)
				)
			)
		)
		(duplicate_pad_numbers_are_jumpers no)
		(fp_line
			(start -0.32512 -0.175006)
			(end 0.32512 -0.175006)
			(stroke
				(width 0.1)
				(type default)
			)
			(layer "F.Fab")
		)
		(fp_line
			(start -0.32512 0.175006)
			(end -0.32512 -0.175006)
			(stroke
				(width 0.1)
				(type default)
			)
			(layer "F.Fab")
		)
		(fp_line
			(start 0.32512 -0.175006)
			(end 0.32512 0.175006)
			(stroke
				(width 0.1)
				(type default)
			)
			(layer "F.Fab")
		)
		(fp_line
			(start 0.32512 0.175006)
			(end -0.32512 0.175006)
			(stroke
				(width 0.1)
				(type default)
			)
			(layer "F.Fab")
		)
		(pad "1" smd rect
			(at -0.2667 0)
			(size 0.3048 0.381)
			(layers "F.Cu" "F.Mask" "F.Paste")
			(net "JTAG_TCK_RT_CPU1_P0")
		)
		(pad "2" smd rect
			(at 0.2667 0 180)
			(size 0.3048 0.381)
			(layers "F.Cu" "F.Mask" "F.Paste")
			(net "GND")
		)
	)
	(footprint ""
		(layer "F.Cu")
		(at 116.896896 -373.03583 -90)
		(property "Reference" "C1537"
			(at 0 0 270)
			(layer "F.SilkS")
			(hide yes)
			(effects
				(font
					(size 1.27 1.27)
				)
			)
		)
		(property "Value" ""
			(at 0 0 270)
			(layer "F.Fab")
			(effects
				(font
					(size 1.27 1.27)
				)
			)
		)
		(duplicate_pad_numbers_are_jumpers no)
		(fp_line
			(start -0.299974 0.150114)
			(end -0.299974 -0.150114)
			(stroke
				(width 0.1)
				(type default)
			)
			(layer "F.Fab")
		)
		(fp_line
			(start 0.299974 0.150114)
			(end -0.299974 0.150114)
			(stroke
				(width 0.1)
				(type default)
			)
			(layer "F.Fab")
		)
		(fp_line
			(start -0.299974 -0.150114)
			(end 0.299974 -0.150114)
			(stroke
				(width 0.1)
				(type default)
			)
			(layer "F.Fab")
		)
		(fp_line
			(start 0.299974 -0.150114)
			(end 0.299974 0.150114)
			(stroke
				(width 0.1)
				(type default)
			)
			(layer "F.Fab")
		)
		(pad "1" smd rect
			(at -0.2667 0 270)
			(size 0.3048 0.381)
			(layers "F.Cu" "F.Mask" "F.Paste")
			(net "P5E_CPU1_P3_TX_C_DP<5>")
		)
		(pad "2" smd rect
			(at 0.2667 0 270)
			(size 0.3048 0.381)
			(layers "F.Cu" "F.Mask" "F.Paste")
			(net "P5E_CPU1_P3_TX_DP<5>")
		)
	)
	(footprint ""
		(layer "F.Cu")
		(at 306.711096 -381.41783 -90)
		(property "Reference" "C922"
			(at 0 0 270)
			(layer "F.SilkS")
			(hide yes)
			(effects
				(font
					(size 1.27 1.27)
				)
			)
		)
		(property "Value" ""
			(at 0 0 270)
			(layer "F.Fab")
			(effects
				(font
					(size 1.27 1.27)
				)
			)
		)
		(duplicate_pad_numbers_are_jumpers no)
		(fp_line
			(start -0.299974 0.150114)
			(end -0.299974 -0.150114)
			(stroke
				(width 0.1)
				(type default)
			)
			(layer "F.Fab")
		)
		(fp_line
			(start 0.299974 0.150114)
			(end -0.299974 0.150114)
			(stroke
				(width 0.1)
				(type default)
			)
			(layer "F.Fab")
		)
		(fp_line
			(start -0.299974 -0.150114)
			(end 0.299974 -0.150114)
			(stroke
				(width 0.1)
				(type default)
			)
			(layer "F.Fab")
		)
		(fp_line
			(start 0.299974 -0.150114)
			(end 0.299974 0.150114)
			(stroke
				(width 0.1)
				(type default)
			)
			(layer "F.Fab")
		)
		(pad "1" smd rect
			(at -0.2667 0 270)
			(size 0.3048 0.381)
			(layers "F.Cu" "F.Mask" "F.Paste")
			(net "P5E_CPU0_P0_TX_C_DN<5>")
		)
		(pad "2" smd rect
			(at 0.2667 0 270)
			(size 0.3048 0.381)
			(layers "F.Cu" "F.Mask" "F.Paste")
			(net "P5E_CPU0_P0_TX_DN<5>")
		)
	)
	(footprint ""
		(layer "F.Cu")
		(at 33.186878 -16.099536 90)
		(property "Reference" "C691"
			(at 0 0 90)
			(layer "F.SilkS")
			(hide yes)
			(effects
				(font
					(size 1.27 1.27)
				)
			)
		)
		(property "Value" ""
			(at 0 0 90)
			(layer "F.Fab")
			(effects
				(font
					(size 1.27 1.27)
				)
			)
		)
		(duplicate_pad_numbers_are_jumpers no)
		(fp_line
			(start 0.299974 -0.150114)
			(end 0.299974 0.150114)
			(stroke
				(width 0.1)
				(type default)
			)
			(layer "F.Fab")
		)
		(fp_line
			(start -0.299974 -0.150114)
			(end 0.299974 -0.150114)
			(stroke
				(width 0.1)
				(type default)
			)
			(layer "F.Fab")
		)
		(fp_line
			(start 0.299974 0.150114)
			(end -0.299974 0.150114)
			(stroke
				(width 0.1)
				(type default)
			)
			(layer "F.Fab")
		)
		(fp_line
			(start -0.299974 0.150114)
			(end -0.299974 -0.150114)
			(stroke
				(width 0.1)
				(type default)
			)
			(layer "F.Fab")
		)
		(pad "1" smd rect
			(at -0.2667 0 90)
			(size 0.3048 0.381)
			(layers "F.Cu" "F.Mask" "F.Paste")
			(net "P5E_CPU1_G1_TX_C_DP<9>")
		)
		(pad "2" smd rect
			(at 0.2667 0 90)
			(size 0.3048 0.381)
			(layers "F.Cu" "F.Mask" "F.Paste")
			(net "P5E_CPU1_G1_TX_DP<9>")
		)
	)
	(footprint ""
		(layer "F.Cu")
		(at 393.284456 -72.28205)
		(property "Reference" "R1276"
			(at 0 0 0)
			(layer "F.SilkS")
			(hide yes)
			(effects
				(font
					(size 1.27 1.27)
				)
			)
		)
		(property "Value" ""
			(at 0 0 0)
			(layer "F.Fab")
			(effects
				(font
					(size 1.27 1.27)
				)
			)
		)
		(duplicate_pad_numbers_are_jumpers no)
		(fp_line
			(start -0.7874 -0.4064)
			(end 0.7874 -0.4064)
			(stroke
				(width 0.1524)
				(type default)
			)
			(layer "F.SilkS")
		)
		(fp_line
			(start -0.7874 0.4064)
			(end -0.7874 -0.4064)
			(stroke
				(width 0.1524)
				(type default)
			)
			(layer "F.SilkS")
		)
		(fp_line
			(start 0.7874 -0.4064)
			(end 0.7874 0.4064)
			(stroke
				(width 0.1524)
				(type default)
			)
			(layer "F.SilkS")
		)
		(fp_line
			(start 0.7874 0.4064)
			(end -0.7874 0.4064)
			(stroke
				(width 0.1524)
				(type default)
			)
			(layer "F.SilkS")
		)
		(fp_line
			(start -0.67945 -0.305054)
			(end -0.12065 -0.305054)
			(stroke
				(width 0.1)
				(type default)
			)
			(layer "F.Fab")
		)
		(fp_line
			(start -0.67945 0.3048)
			(end -0.67945 -0.305054)
			(stroke
				(width 0.1)
				(type default)
			)
			(layer "F.Fab")
		)
		(fp_line
			(start -0.12065 -0.305054)
			(end -0.12065 -0.2794)
			(stroke
				(width 0.1)
				(type default)
			)
			(layer "F.Fab")
		)
		(fp_line
			(start -0.12065 -0.2794)
			(end 0.12065 -0.2794)
			(stroke
				(width 0.1)
				(type default)
			)
			(layer "F.Fab")
		)
		(fp_line
			(start -0.12065 0.2794)
			(end -0.12065 0.3048)
			(stroke
				(width 0.1)
				(type default)
			)
			(layer "F.Fab")
		)
		(fp_line
			(start -0.12065 0.3048)
			(end -0.67945 0.3048)
			(stroke
				(width 0.1)
				(type default)
			)
			(layer "F.Fab")
		)
		(fp_line
			(start 0.120396 0.2794)
			(end -0.12065 0.2794)
			(stroke
				(width 0.1)
				(type default)
			)
			(layer "F.Fab")
		)
		(fp_line
			(start 0.120396 0.3048)
			(end 0.120396 0.2794)
			(stroke
				(width 0.1)
				(type default)
			)
			(layer "F.Fab")
		)
		(fp_line
			(start 0.12065 -0.3048)
			(end 0.67945 -0.3048)
			(stroke
				(width 0.1)
				(type default)
			)
			(layer "F.Fab")
		)
		(fp_line
			(start 0.12065 -0.2794)
			(end 0.12065 -0.3048)
			(stroke
				(width 0.1)
				(type default)
			)
			(layer "F.Fab")
		)
		(fp_line
			(start 0.67945 -0.3048)
			(end 0.67945 0.3048)
			(stroke
				(width 0.1)
				(type default)
			)
			(layer "F.Fab")
		)
		(fp_line
			(start 0.67945 0.3048)
			(end 0.120396 0.3048)
			(stroke
				(width 0.1)
				(type default)
			)
			(layer "F.Fab")
		)
		(pad "1" smd circle
			(at -0.40005 0)
			(size 0 0)
			(layers "F.Cu" "F.Mask" "F.Paste")
			(net "SMB_INA230_6_3V3AUX_SDA_R")
		)
		(pad "2" smd circle
			(at 0.40005 0)
			(size 0 0)
			(layers "F.Cu" "F.Mask" "F.Paste")
			(net "SMB_INA230_6_3V3AUX_SDA_R1")
		)
	)
	(footprint ""
		(layer "F.Cu")
		(at 268.59992 -124.469398)
		(property "Reference" "C2056"
			(at 0 0 0)
			(layer "F.SilkS")
			(hide yes)
			(effects
				(font
					(size 1.27 1.27)
				)
			)
		)
		(property "Value" ""
			(at 0 0 0)
			(layer "F.Fab")
			(effects
				(font
					(size 1.27 1.27)
				)
			)
		)
		(duplicate_pad_numbers_are_jumpers no)
		(fp_line
			(start -0.7874 -0.4064)
			(end 0.7874 -0.4064)
			(stroke
				(width 0.1524)
				(type default)
			)
			(layer "F.SilkS")
		)
		(fp_line
			(start -0.7874 0.4064)
			(end -0.7874 -0.4064)
			(stroke
				(width 0.1524)
				(type default)
			)
			(layer "F.SilkS")
		)
		(fp_line
			(start 0.7874 -0.4064)
			(end 0.7874 0.4064)
			(stroke
				(width 0.1524)
				(type default)
			)
			(layer "F.SilkS")
		)
		(fp_line
			(start 0.7874 0.4064)
			(end -0.7874 0.4064)
			(stroke
				(width 0.1524)
				(type default)
			)
			(layer "F.SilkS")
		)
		(fp_line
			(start -0.67945 -0.305054)
			(end -0.12065 -0.305054)
			(stroke
				(width 0.1)
				(type default)
			)
			(layer "F.Fab")
		)
		(fp_line
			(start -0.67945 0.3048)
			(end -0.67945 -0.305054)
			(stroke
				(width 0.1)
				(type default)
			)
			(layer "F.Fab")
		)
		(fp_line
			(start -0.12065 -0.305054)
			(end -0.12065 -0.2794)
			(stroke
				(width 0.1)
				(type default)
			)
			(layer "F.Fab")
		)
		(fp_line
			(start -0.12065 -0.2794)
			(end 0.12065 -0.2794)
			(stroke
				(width 0.1)
				(type default)
			)
			(layer "F.Fab")
		)
		(fp_line
			(start -0.12065 0.2794)
			(end -0.12065 0.3048)
			(stroke
				(width 0.1)
				(type default)
			)
			(layer "F.Fab")
		)
		(fp_line
			(start -0.12065 0.3048)
			(end -0.67945 0.3048)
			(stroke
				(width 0.1)
				(type default)
			)
			(layer "F.Fab")
		)
		(fp_line
			(start 0.120396 0.2794)
			(end -0.12065 0.2794)
			(stroke
				(width 0.1)
				(type default)
			)
			(layer "F.Fab")
		)
		(fp_line
			(start 0.120396 0.3048)
			(end 0.120396 0.2794)
			(stroke
				(width 0.1)
				(type default)
			)
			(layer "F.Fab")
		)
		(fp_line
			(start 0.12065 -0.3048)
			(end 0.67945 -0.3048)
			(stroke
				(width 0.1)
				(type default)
			)
			(layer "F.Fab")
		)
		(fp_line
			(start 0.12065 -0.2794)
			(end 0.12065 -0.3048)
			(stroke
				(width 0.1)
				(type default)
			)
			(layer "F.Fab")
		)
		(fp_line
			(start 0.67945 -0.3048)
			(end 0.67945 0.3048)
			(stroke
				(width 0.1)
				(type default)
			)
			(layer "F.Fab")
		)
		(fp_line
			(start 0.67945 0.3048)
			(end 0.120396 0.3048)
			(stroke
				(width 0.1)
				(type default)
			)
			(layer "F.Fab")
		)
		(pad "1" smd circle
			(at -0.40005 0)
			(size 0 0)
			(layers "F.Cu" "F.Mask" "F.Paste")
			(net "P3V3_AUX")
		)
		(pad "2" smd circle
			(at 0.40005 0)
			(size 0 0)
			(layers "F.Cu" "F.Mask" "F.Paste")
			(net "GND")
		)
	)
	(footprint ""
		(layer "F.Cu")
		(at 372.46687 -15.637002)
		(property "Reference" "R53"
			(at 0 0 0)
			(layer "F.SilkS")
			(hide yes)
			(effects
				(font
					(size 1.27 1.27)
				)
			)
		)
		(property "Value" ""
			(at 0 0 0)
			(layer "F.Fab")
			(effects
				(font
					(size 1.27 1.27)
				)
			)
		)
		(duplicate_pad_numbers_are_jumpers no)
		(fp_line
			(start -0.7874 -0.4064)
			(end 0.7874 -0.4064)
			(stroke
				(width 0.1524)
				(type default)
			)
			(layer "F.SilkS")
		)
		(fp_line
			(start -0.7874 0.4064)
			(end -0.7874 -0.4064)
			(stroke
				(width 0.1524)
				(type default)
			)
			(layer "F.SilkS")
		)
		(fp_line
			(start 0.7874 -0.4064)
			(end 0.7874 0.4064)
			(stroke
				(width 0.1524)
				(type default)
			)
			(layer "F.SilkS")
		)
		(fp_line
			(start 0.7874 0.4064)
			(end -0.7874 0.4064)
			(stroke
				(width 0.1524)
				(type default)
			)
			(layer "F.SilkS")
		)
		(fp_line
			(start -0.67945 -0.305054)
			(end -0.12065 -0.305054)
			(stroke
				(width 0.1)
				(type default)
			)
			(layer "F.Fab")
		)
		(fp_line
			(start -0.67945 0.3048)
			(end -0.67945 -0.305054)
			(stroke
				(width 0.1)
				(type default)
			)
			(layer "F.Fab")
		)
		(fp_line
			(start -0.12065 -0.305054)
			(end -0.12065 -0.2794)
			(stroke
				(width 0.1)
				(type default)
			)
			(layer "F.Fab")
		)
		(fp_line
			(start -0.12065 -0.2794)
			(end 0.12065 -0.2794)
			(stroke
				(width 0.1)
				(type default)
			)
			(layer "F.Fab")
		)
		(fp_line
			(start -0.12065 0.2794)
			(end -0.12065 0.3048)
			(stroke
				(width 0.1)
				(type default)
			)
			(layer "F.Fab")
		)
		(fp_line
			(start -0.12065 0.3048)
			(end -0.67945 0.3048)
			(stroke
				(width 0.1)
				(type default)
			)
			(layer "F.Fab")
		)
		(fp_line
			(start 0.120396 0.2794)
			(end -0.12065 0.2794)
			(stroke
				(width 0.1)
				(type default)
			)
			(layer "F.Fab")
		)
		(fp_line
			(start 0.120396 0.3048)
			(end 0.120396 0.2794)
			(stroke
				(width 0.1)
				(type default)
			)
			(layer "F.Fab")
		)
		(fp_line
			(start 0.12065 -0.3048)
			(end 0.67945 -0.3048)
			(stroke
				(width 0.1)
				(type default)
			)
			(layer "F.Fab")
		)
		(fp_line
			(start 0.12065 -0.2794)
			(end 0.12065 -0.3048)
			(stroke
				(width 0.1)
				(type default)
			)
			(layer "F.Fab")
		)
		(fp_line
			(start 0.67945 -0.3048)
			(end 0.67945 0.3048)
			(stroke
				(width 0.1)
				(type default)
			)
			(layer "F.Fab")
		)
		(fp_line
			(start 0.67945 0.3048)
			(end 0.120396 0.3048)
			(stroke
				(width 0.1)
				(type default)
			)
			(layer "F.Fab")
		)
		(pad "1" smd circle
			(at -0.40005 0)
			(size 0 0)
			(layers "F.Cu" "F.Mask" "F.Paste")
			(net "P3V3_AUX")
		)
		(pad "2" smd circle
			(at 0.40005 0)
			(size 0 0)
			(layers "F.Cu" "F.Mask" "F.Paste")
			(net "OCP_SFF_PWRBRK_BUFF_N")
		)
	)
	(footprint ""
		(layer "F.Cu")
		(at 197.269608 -116.673376)
		(property "Reference" "R957"
			(at 0 0 0)
			(layer "F.SilkS")
			(hide yes)
			(effects
				(font
					(size 1.27 1.27)
				)
			)
		)
		(property "Value" ""
			(at 0 0 0)
			(layer "F.Fab")
			(effects
				(font
					(size 1.27 1.27)
				)
			)
		)
		(duplicate_pad_numbers_are_jumpers no)
		(fp_line
			(start -0.7874 -0.4064)
			(end 0.7874 -0.4064)
			(stroke
				(width 0.1524)
				(type default)
			)
			(layer "F.SilkS")
		)
		(fp_line
			(start -0.7874 0.4064)
			(end -0.7874 -0.4064)
			(stroke
				(width 0.1524)
				(type default)
			)
			(layer "F.SilkS")
		)
		(fp_line
			(start 0.7874 -0.4064)
			(end 0.7874 0.4064)
			(stroke
				(width 0.1524)
				(type default)
			)
			(layer "F.SilkS")
		)
		(fp_line
			(start 0.7874 0.4064)
			(end -0.7874 0.4064)
			(stroke
				(width 0.1524)
				(type default)
			)
			(layer "F.SilkS")
		)
		(fp_line
			(start -0.67945 -0.305054)
			(end -0.12065 -0.305054)
			(stroke
				(width 0.1)
				(type default)
			)
			(layer "F.Fab")
		)
		(fp_line
			(start -0.67945 0.3048)
			(end -0.67945 -0.305054)
			(stroke
				(width 0.1)
				(type default)
			)
			(layer "F.Fab")
		)
		(fp_line
			(start -0.12065 -0.305054)
			(end -0.12065 -0.2794)
			(stroke
				(width 0.1)
				(type default)
			)
			(layer "F.Fab")
		)
		(fp_line
			(start -0.12065 -0.2794)
			(end 0.12065 -0.2794)
			(stroke
				(width 0.1)
				(type default)
			)
			(layer "F.Fab")
		)
		(fp_line
			(start -0.12065 0.2794)
			(end -0.12065 0.3048)
			(stroke
				(width 0.1)
				(type default)
			)
			(layer "F.Fab")
		)
		(fp_line
			(start -0.12065 0.3048)
			(end -0.67945 0.3048)
			(stroke
				(width 0.1)
				(type default)
			)
			(layer "F.Fab")
		)
		(fp_line
			(start 0.120396 0.2794)
			(end -0.12065 0.2794)
			(stroke
				(width 0.1)
				(type default)
			)
			(layer "F.Fab")
		)
		(fp_line
			(start 0.120396 0.3048)
			(end 0.120396 0.2794)
			(stroke
				(width 0.1)
				(type default)
			)
			(layer "F.Fab")
		)
		(fp_line
			(start 0.12065 -0.3048)
			(end 0.67945 -0.3048)
			(stroke
				(width 0.1)
				(type default)
			)
			(layer "F.Fab")
		)
		(fp_line
			(start 0.12065 -0.2794)
			(end 0.12065 -0.3048)
			(stroke
				(width 0.1)
				(type default)
			)
			(layer "F.Fab")
		)
		(fp_line
			(start 0.67945 -0.3048)
			(end 0.67945 0.3048)
			(stroke
				(width 0.1)
				(type default)
			)
			(layer "F.Fab")
		)
		(fp_line
			(start 0.67945 0.3048)
			(end 0.120396 0.3048)
			(stroke
				(width 0.1)
				(type default)
			)
			(layer "F.Fab")
		)
		(pad "1" smd circle
			(at -0.40005 0)
			(size 0 0)
			(layers "F.Cu" "F.Mask" "F.Paste")
			(net "FM_RST_PERST_SCM_R_N")
		)
		(pad "2" smd circle
			(at 0.40005 0)
			(size 0 0)
			(layers "F.Cu" "F.Mask" "F.Paste")
			(net "FM_RST_PERST_SCM_N")
		)
	)
	(footprint ""
		(layer "F.Cu")
		(at 180.528468 -53.065934)
		(property "Reference" "C1098"
			(at 0 0 0)
			(layer "F.SilkS")
			(hide yes)
			(effects
				(font
					(size 1.27 1.27)
				)
			)
		)
		(property "Value" ""
			(at 0 0 0)
			(layer "F.Fab")
			(effects
				(font
					(size 1.27 1.27)
				)
			)
		)
		(duplicate_pad_numbers_are_jumpers no)
		(fp_line
			(start -0.299974 -0.150114)
			(end 0.299974 -0.150114)
			(stroke
				(width 0.1)
				(type default)
			)
			(layer "F.Fab")
		)
		(fp_line
			(start -0.299974 0.150114)
			(end -0.299974 -0.150114)
			(stroke
				(width 0.1)
				(type default)
			)
			(layer "F.Fab")
		)
		(fp_line
			(start 0.299974 -0.150114)
			(end 0.299974 0.150114)
			(stroke
				(width 0.1)
				(type default)
			)
			(layer "F.Fab")
		)
		(fp_line
			(start 0.299974 0.150114)
			(end -0.299974 0.150114)
			(stroke
				(width 0.1)
				(type default)
			)
			(layer "F.Fab")
		)
		(pad "1" smd rect
			(at -0.2667 0)
			(size 0.3048 0.381)
			(layers "F.Cu" "F.Mask" "F.Paste")
			(net "P3E_CPU1_P4_TX_C_DP<3>")
		)
		(pad "2" smd rect
			(at 0.2667 0)
			(size 0.3048 0.381)
			(layers "F.Cu" "F.Mask" "F.Paste")
			(net "P3E_CPU1_P4_TX_DP<3>")
		)
	)
	(footprint ""
		(layer "F.Cu")
		(at 352.45548 -436.925212 -90)
		(property "Reference" "U316"
			(at 1.614424 -1.87071 90)
			(unlocked yes)
			(layer "F.SilkS")
			(effects
				(font
					(size 0.7874 0.5842)
					(thickness 0.1524)
				)
				(justify left)
			)
		)
		(property "Value" ""
			(at 0 0 270)
			(layer "F.Fab")
			(effects
				(font
					(size 1.27 1.27)
				)
			)
		)
		(duplicate_pad_numbers_are_jumpers no)
		(fp_line
			(start -1.3462 1.100074)
			(end -1.3462 -1.100074)
			(stroke
				(width 0.1524)
				(type default)
			)
			(layer "F.SilkS")
		)
		(fp_line
			(start 1.3462 1.100074)
			(end -1.3462 1.100074)
			(stroke
				(width 0.1524)
				(type default)
			)
			(layer "F.SilkS")
		)
		(fp_line
			(start 0 -0.381)
			(end 0.670052 -1.100074)
			(stroke
				(width 0.1524)
				(type default)
			)
			(layer "F.SilkS")
		)
		(fp_line
			(start -1.3462 -1.100074)
			(end -0.670052 -1.100074)
			(stroke
				(width 0.1524)
				(type default)
			)
			(layer "F.SilkS")
		)
		(fp_line
			(start -0.670052 -1.100074)
			(end 0 -0.381)
			(stroke
				(width 0.1524)
				(type default)
			)
			(layer "F.SilkS")
		)
		(fp_line
			(start 0.670052 -1.100074)
			(end 1.3462 -1.100074)
			(stroke
				(width 0.1524)
				(type default)
			)
			(layer "F.SilkS")
		)
		(fp_line
			(start 1.3462 -1.100074)
			(end 1.3462 1.100074)
			(stroke
				(width 0.1524)
				(type default)
			)
			(layer "F.SilkS")
		)
		(fp_poly
			(pts
				(xy -2.29108 -1.452372) (xy -1.752346 -1.991106) (xy -1.482852 -1.182878)
			)
			(stroke
				(width 0)
				(type default)
			)
			(fill yes)
			(layer "F.SilkS")
		)
		(fp_line
			(start -0.670052 1.100074)
			(end -0.670052 0.8001)
			(stroke
				(width 0.1)
				(type default)
			)
			(layer "F.Fab")
		)
		(fp_line
			(start 0.670052 1.100074)
			(end -0.670052 1.100074)
			(stroke
				(width 0.1)
				(type default)
			)
			(layer "F.Fab")
		)
		(fp_line
			(start -1.100074 0.8001)
			(end -1.100074 -0.8001)
			(stroke
				(width 0.1)
				(type default)
			)
			(layer "F.Fab")
		)
		(fp_line
			(start -0.670052 0.8001)
			(end -1.100074 0.8001)
			(stroke
				(width 0.1)
				(type default)
			)
			(layer "F.Fab")
		)
		(fp_line
			(start -0.670052 0.8001)
			(end -0.670052 -0.8001)
			(stroke
				(width 0.1)
				(type default)
			)
			(layer "F.Fab")
		)
		(fp_line
			(start 0.670052 0.8001)
			(end 0.670052 1.100074)
			(stroke
				(width 0.1)
				(type default)
			)
			(layer "F.Fab")
		)
		(fp_line
			(start 1.100074 0.8001)
			(end 0.670052 0.8001)
			(stroke
				(width 0.1)
				(type default)
			)
			(layer "F.Fab")
		)
		(fp_line
			(start -1.100074 -0.8001)
			(end -0.670052 -0.8001)
			(stroke
				(width 0.1)
				(type default)
			)
			(layer "F.Fab")
		)
		(fp_line
			(start -0.670052 -0.8001)
			(end -0.670052 -1.100074)
			(stroke
				(width 0.1)
				(type default)
			)
			(layer "F.Fab")
		)
		(fp_line
			(start 0.670052 -0.8001)
			(end 0.670052 0.8001)
			(stroke
				(width 0.1)
				(type default)
			)
			(layer "F.Fab")
		)
		(fp_line
			(start 0.670052 -0.8001)
			(end 1.100074 -0.8001)
			(stroke
				(width 0.1)
				(type default)
			)
			(layer "F.Fab")
		)
		(fp_line
			(start 1.100074 -0.8001)
			(end 1.100074 0.8001)
			(stroke
				(width 0.1)
				(type default)
			)
			(layer "F.Fab")
		)
		(fp_line
			(start -0.670052 -1.100074)
			(end 0.670052 -1.100074)
			(stroke
				(width 0.1)
				(type default)
			)
			(layer "F.Fab")
		)
		(fp_line
			(start 0.670052 -1.100074)
			(end 0.670052 -0.8001)
			(stroke
				(width 0.1)
				(type default)
			)
			(layer "F.Fab")
		)
		(fp_poly
			(pts
				(xy -1.524 -0.649986) (xy -2.286 -1.030986) (xy -2.286 -0.268986)
			)
			(stroke
				(width 0)
				(type default)
			)
			(fill yes)
			(layer "F.Fab")
		)
		(pad "1" smd rect
			(at -0.94996 -0.649986 180)
			(size 0.4064 0.508)
			(layers "F.Cu" "F.Mask" "F.Paste")
			(net "SWB_HSC_EN")
		)
		(pad "2" smd rect
			(at -0.94996 0 180)
			(size 0.4064 0.508)
			(layers "F.Cu" "F.Mask" "F.Paste")
			(net "GND")
		)
		(pad "3" smd rect
			(at -0.94996 0.649986 180)
			(size 0.4064 0.508)
			(layers "F.Cu" "F.Mask" "F.Paste")
			(net "GND")
		)
		(pad "4" smd rect
			(at 0.94996 0.649986 180)
			(size 0.4064 0.508)
			(layers "F.Cu" "F.Mask" "F.Paste")
			(net "NC_U316_2Y")
		)
		(pad "5" smd rect
			(at 0.94996 0 180)
			(size 0.4064 0.508)
			(layers "F.Cu" "F.Mask" "F.Paste")
			(net "P3V3_AUX")
		)
		(pad "6" smd rect
			(at 0.94996 -0.649986 180)
			(size 0.4064 0.508)
			(layers "F.Cu" "F.Mask" "F.Paste")
			(net "SWB_HSC_EN_BUF_R")
		)
	)
	(footprint ""
		(layer "F.Cu")
		(at 305.754024 -32.701992)
		(property "Reference" "R5101"
			(at 0 0 0)
			(layer "F.SilkS")
			(hide yes)
			(effects
				(font
					(size 1.27 1.27)
				)
			)
		)
		(property "Value" ""
			(at 0 0 0)
			(layer "F.Fab")
			(effects
				(font
					(size 1.27 1.27)
				)
			)
		)
		(duplicate_pad_numbers_are_jumpers no)
		(fp_line
			(start -0.7874 -0.4064)
			(end 0.7874 -0.4064)
			(stroke
				(width 0.1524)
				(type default)
			)
			(layer "F.SilkS")
		)
		(fp_line
			(start -0.7874 0.4064)
			(end -0.7874 -0.4064)
			(stroke
				(width 0.1524)
				(type default)
			)
			(layer "F.SilkS")
		)
		(fp_line
			(start 0.7874 -0.4064)
			(end 0.7874 0.4064)
			(stroke
				(width 0.1524)
				(type default)
			)
			(layer "F.SilkS")
		)
		(fp_line
			(start 0.7874 0.4064)
			(end -0.7874 0.4064)
			(stroke
				(width 0.1524)
				(type default)
			)
			(layer "F.SilkS")
		)
		(fp_line
			(start -0.67945 -0.305054)
			(end -0.12065 -0.305054)
			(stroke
				(width 0.1)
				(type default)
			)
			(layer "F.Fab")
		)
		(fp_line
			(start -0.67945 0.3048)
			(end -0.67945 -0.305054)
			(stroke
				(width 0.1)
				(type default)
			)
			(layer "F.Fab")
		)
		(fp_line
			(start -0.12065 -0.305054)
			(end -0.12065 -0.2794)
			(stroke
				(width 0.1)
				(type default)
			)
			(layer "F.Fab")
		)
		(fp_line
			(start -0.12065 -0.2794)
			(end 0.12065 -0.2794)
			(stroke
				(width 0.1)
				(type default)
			)
			(layer "F.Fab")
		)
		(fp_line
			(start -0.12065 0.2794)
			(end -0.12065 0.3048)
			(stroke
				(width 0.1)
				(type default)
			)
			(layer "F.Fab")
		)
		(fp_line
			(start -0.12065 0.3048)
			(end -0.67945 0.3048)
			(stroke
				(width 0.1)
				(type default)
			)
			(layer "F.Fab")
		)
		(fp_line
			(start 0.120396 0.2794)
			(end -0.12065 0.2794)
			(stroke
				(width 0.1)
				(type default)
			)
			(layer "F.Fab")
		)
		(fp_line
			(start 0.120396 0.3048)
			(end 0.120396 0.2794)
			(stroke
				(width 0.1)
				(type default)
			)
			(layer "F.Fab")
		)
		(fp_line
			(start 0.12065 -0.3048)
			(end 0.67945 -0.3048)
			(stroke
				(width 0.1)
				(type default)
			)
			(layer "F.Fab")
		)
		(fp_line
			(start 0.12065 -0.2794)
			(end 0.12065 -0.3048)
			(stroke
				(width 0.1)
				(type default)
			)
			(layer "F.Fab")
		)
		(fp_line
			(start 0.67945 -0.3048)
			(end 0.67945 0.3048)
			(stroke
				(width 0.1)
				(type default)
			)
			(layer "F.Fab")
		)
		(fp_line
			(start 0.67945 0.3048)
			(end 0.120396 0.3048)
			(stroke
				(width 0.1)
				(type default)
			)
			(layer "F.Fab")
		)
		(pad "1" smd circle
			(at -0.40005 0)
			(size 0 0)
			(layers "F.Cu" "F.Mask" "F.Paste")
			(net "P3V3_AUX")
		)
		(pad "2" smd circle
			(at 0.40005 0)
			(size 0 0)
			(layers "F.Cu" "F.Mask" "F.Paste")
			(net "P3V3_STBY_R")
		)
	)
	(footprint ""
		(layer "F.Cu")
		(at 70.739 -53.594)
		(property "Reference" "R1175"
			(at 0 0 0)
			(layer "F.SilkS")
			(hide yes)
			(effects
				(font
					(size 1.27 1.27)
				)
			)
		)
		(property "Value" ""
			(at 0 0 0)
			(layer "F.Fab")
			(effects
				(font
					(size 1.27 1.27)
				)
			)
		)
		(duplicate_pad_numbers_are_jumpers no)
		(fp_line
			(start -0.7874 -0.4064)
			(end 0.7874 -0.4064)
			(stroke
				(width 0.1524)
				(type default)
			)
			(layer "F.SilkS")
		)
		(fp_line
			(start -0.7874 0.4064)
			(end -0.7874 -0.4064)
			(stroke
				(width 0.1524)
				(type default)
			)
			(layer "F.SilkS")
		)
		(fp_line
			(start 0.7874 -0.4064)
			(end 0.7874 0.4064)
			(stroke
				(width 0.1524)
				(type default)
			)
			(layer "F.SilkS")
		)
		(fp_line
			(start 0.7874 0.4064)
			(end -0.7874 0.4064)
			(stroke
				(width 0.1524)
				(type default)
			)
			(layer "F.SilkS")
		)
		(fp_line
			(start -0.67945 -0.305054)
			(end -0.12065 -0.305054)
			(stroke
				(width 0.1)
				(type default)
			)
			(layer "F.Fab")
		)
		(fp_line
			(start -0.67945 0.3048)
			(end -0.67945 -0.305054)
			(stroke
				(width 0.1)
				(type default)
			)
			(layer "F.Fab")
		)
		(fp_line
			(start -0.12065 -0.305054)
			(end -0.12065 -0.2794)
			(stroke
				(width 0.1)
				(type default)
			)
			(layer "F.Fab")
		)
		(fp_line
			(start -0.12065 -0.2794)
			(end 0.12065 -0.2794)
			(stroke
				(width 0.1)
				(type default)
			)
			(layer "F.Fab")
		)
		(fp_line
			(start -0.12065 0.2794)
			(end -0.12065 0.3048)
			(stroke
				(width 0.1)
				(type default)
			)
			(layer "F.Fab")
		)
		(fp_line
			(start -0.12065 0.3048)
			(end -0.67945 0.3048)
			(stroke
				(width 0.1)
				(type default)
			)
			(layer "F.Fab")
		)
		(fp_line
			(start 0.120396 0.2794)
			(end -0.12065 0.2794)
			(stroke
				(width 0.1)
				(type default)
			)
			(layer "F.Fab")
		)
		(fp_line
			(start 0.120396 0.3048)
			(end 0.120396 0.2794)
			(stroke
				(width 0.1)
				(type default)
			)
			(layer "F.Fab")
		)
		(fp_line
			(start 0.12065 -0.3048)
			(end 0.67945 -0.3048)
			(stroke
				(width 0.1)
				(type default)
			)
			(layer "F.Fab")
		)
		(fp_line
			(start 0.12065 -0.2794)
			(end 0.12065 -0.3048)
			(stroke
				(width 0.1)
				(type default)
			)
			(layer "F.Fab")
		)
		(fp_line
			(start 0.67945 -0.3048)
			(end 0.67945 0.3048)
			(stroke
				(width 0.1)
				(type default)
			)
			(layer "F.Fab")
		)
		(fp_line
			(start 0.67945 0.3048)
			(end 0.120396 0.3048)
			(stroke
				(width 0.1)
				(type default)
			)
			(layer "F.Fab")
		)
		(pad "1" smd circle
			(at -0.40005 0)
			(size 0 0)
			(layers "F.Cu" "F.Mask" "F.Paste")
			(net "OCP_V3_2_AUX_PWR_EN_R2")
		)
		(pad "2" smd circle
			(at 0.40005 0)
			(size 0 0)
			(layers "F.Cu" "F.Mask" "F.Paste")
			(net "OCP_V3_2_AUX_PWR_EN")
		)
	)
	(footprint ""
		(layer "F.Cu")
		(at 74.409046 -62.969394 -90)
		(property "Reference" "R1174"
			(at 0 0 270)
			(layer "F.SilkS")
			(hide yes)
			(effects
				(font
					(size 1.27 1.27)
				)
			)
		)
		(property "Value" ""
			(at 0 0 270)
			(layer "F.Fab")
			(effects
				(font
					(size 1.27 1.27)
				)
			)
		)
		(duplicate_pad_numbers_are_jumpers no)
		(fp_line
			(start -0.7874 0.4064)
			(end -0.7874 -0.4064)
			(stroke
				(width 0.1524)
				(type default)
			)
			(layer "F.SilkS")
		)
		(fp_line
			(start 0.7874 0.4064)
			(end -0.7874 0.4064)
			(stroke
				(width 0.1524)
				(type default)
			)
			(layer "F.SilkS")
		)
		(fp_line
			(start -0.7874 -0.4064)
			(end 0.7874 -0.4064)
			(stroke
				(width 0.1524)
				(type default)
			)
			(layer "F.SilkS")
		)
		(fp_line
			(start 0.7874 -0.4064)
			(end 0.7874 0.4064)
			(stroke
				(width 0.1524)
				(type default)
			)
			(layer "F.SilkS")
		)
		(fp_line
			(start -0.67945 0.3048)
			(end -0.67945 -0.305054)
			(stroke
				(width 0.1)
				(type default)
			)
			(layer "F.Fab")
		)
		(fp_line
			(start -0.12065 0.3048)
			(end -0.67945 0.3048)
			(stroke
				(width 0.1)
				(type default)
			)
			(layer "F.Fab")
		)
		(fp_line
			(start 0.120396 0.3048)
			(end 0.120396 0.2794)
			(stroke
				(width 0.1)
				(type default)
			)
			(layer "F.Fab")
		)
		(fp_line
			(start 0.67945 0.3048)
			(end 0.120396 0.3048)
			(stroke
				(width 0.1)
				(type default)
			)
			(layer "F.Fab")
		)
		(fp_line
			(start -0.12065 0.2794)
			(end -0.12065 0.3048)
			(stroke
				(width 0.1)
				(type default)
			)
			(layer "F.Fab")
		)
		(fp_line
			(start 0.120396 0.2794)
			(end -0.12065 0.2794)
			(stroke
				(width 0.1)
				(type default)
			)
			(layer "F.Fab")
		)
		(fp_line
			(start -0.12065 -0.2794)
			(end 0.12065 -0.2794)
			(stroke
				(width 0.1)
				(type default)
			)
			(layer "F.Fab")
		)
		(fp_line
			(start 0.12065 -0.2794)
			(end 0.12065 -0.3048)
			(stroke
				(width 0.1)
				(type default)
			)
			(layer "F.Fab")
		)
		(fp_line
			(start 0.12065 -0.3048)
			(end 0.67945 -0.3048)
			(stroke
				(width 0.1)
				(type default)
			)
			(layer "F.Fab")
		)
		(fp_line
			(start 0.67945 -0.3048)
			(end 0.67945 0.3048)
			(stroke
				(width 0.1)
				(type default)
			)
			(layer "F.Fab")
		)
		(fp_line
			(start -0.67945 -0.305054)
			(end -0.12065 -0.305054)
			(stroke
				(width 0.1)
				(type default)
			)
			(layer "F.Fab")
		)
		(fp_line
			(start -0.12065 -0.305054)
			(end -0.12065 -0.2794)
			(stroke
				(width 0.1)
				(type default)
			)
			(layer "F.Fab")
		)
		(pad "1" smd circle
			(at -0.40005 0 270)
			(size 0 0)
			(layers "F.Cu" "F.Mask" "F.Paste")
			(net "RST_PERST_OCP_V3_2_N")
		)
		(pad "2" smd circle
			(at 0.40005 0 270)
			(size 0 0)
			(layers "F.Cu" "F.Mask" "F.Paste")
			(net "RST_PERST_OCP_V3_2_R_N")
		)
	)
	(footprint ""
		(layer "F.Cu")
		(at 105.918 -423.291 90)
		(property "Reference" "C1963"
			(at 0 0 90)
			(layer "F.SilkS")
			(hide yes)
			(effects
				(font
					(size 1.27 1.27)
				)
			)
		)
		(property "Value" ""
			(at 0 0 90)
			(layer "F.Fab")
			(effects
				(font
					(size 1.27 1.27)
				)
			)
		)
		(duplicate_pad_numbers_are_jumpers no)
		(fp_line
			(start 0.7874 -0.4064)
			(end 0.7874 0.4064)
			(stroke
				(width 0.1524)
				(type default)
			)
			(layer "F.SilkS")
		)
		(fp_line
			(start -0.7874 -0.4064)
			(end 0.7874 -0.4064)
			(stroke
				(width 0.1524)
				(type default)
			)
			(layer "F.SilkS")
		)
		(fp_line
			(start 0.7874 0.4064)
			(end -0.7874 0.4064)
			(stroke
				(width 0.1524)
				(type default)
			)
			(layer "F.SilkS")
		)
		(fp_line
			(start -0.7874 0.4064)
			(end -0.7874 -0.4064)
			(stroke
				(width 0.1524)
				(type default)
			)
			(layer "F.SilkS")
		)
		(fp_line
			(start -0.12065 -0.305054)
			(end -0.12065 -0.2794)
			(stroke
				(width 0.1)
				(type default)
			)
			(layer "F.Fab")
		)
		(fp_line
			(start -0.67945 -0.305054)
			(end -0.12065 -0.305054)
			(stroke
				(width 0.1)
				(type default)
			)
			(layer "F.Fab")
		)
		(fp_line
			(start 0.67945 -0.3048)
			(end 0.67945 0.3048)
			(stroke
				(width 0.1)
				(type default)
			)
			(layer "F.Fab")
		)
		(fp_line
			(start 0.12065 -0.3048)
			(end 0.67945 -0.3048)
			(stroke
				(width 0.1)
				(type default)
			)
			(layer "F.Fab")
		)
		(fp_line
			(start 0.12065 -0.2794)
			(end 0.12065 -0.3048)
			(stroke
				(width 0.1)
				(type default)
			)
			(layer "F.Fab")
		)
		(fp_line
			(start -0.12065 -0.2794)
			(end 0.12065 -0.2794)
			(stroke
				(width 0.1)
				(type default)
			)
			(layer "F.Fab")
		)
		(fp_line
			(start 0.120396 0.2794)
			(end -0.12065 0.2794)
			(stroke
				(width 0.1)
				(type default)
			)
			(layer "F.Fab")
		)
		(fp_line
			(start -0.12065 0.2794)
			(end -0.12065 0.3048)
			(stroke
				(width 0.1)
				(type default)
			)
			(layer "F.Fab")
		)
		(fp_line
			(start 0.67945 0.3048)
			(end 0.120396 0.3048)
			(stroke
				(width 0.1)
				(type default)
			)
			(layer "F.Fab")
		)
		(fp_line
			(start 0.120396 0.3048)
			(end 0.120396 0.2794)
			(stroke
				(width 0.1)
				(type default)
			)
			(layer "F.Fab")
		)
		(fp_line
			(start -0.12065 0.3048)
			(end -0.67945 0.3048)
			(stroke
				(width 0.1)
				(type default)
			)
			(layer "F.Fab")
		)
		(fp_line
			(start -0.67945 0.3048)
			(end -0.67945 -0.305054)
			(stroke
				(width 0.1)
				(type default)
			)
			(layer "F.Fab")
		)
		(pad "1" smd circle
			(at -0.40005 0 90)
			(size 0 0)
			(layers "F.Cu" "F.Mask" "F.Paste")
			(net "P3V3_AUX")
		)
		(pad "2" smd circle
			(at 0.40005 0 90)
			(size 0 0)
			(layers "F.Cu" "F.Mask" "F.Paste")
			(net "GND")
		)
	)
	(footprint ""
		(layer "F.Cu")
		(at 62.043564 -16.220948 -90)
		(property "Reference" "R3170"
			(at 0 0 270)
			(layer "F.SilkS")
			(hide yes)
			(effects
				(font
					(size 1.27 1.27)
				)
			)
		)
		(property "Value" ""
			(at 0 0 270)
			(layer "F.Fab")
			(effects
				(font
					(size 1.27 1.27)
				)
			)
		)
		(duplicate_pad_numbers_are_jumpers no)
		(fp_line
			(start -0.7874 0.4064)
			(end -0.7874 -0.4064)
			(stroke
				(width 0.1524)
				(type default)
			)
			(layer "F.SilkS")
		)
		(fp_line
			(start 0.7874 0.4064)
			(end -0.7874 0.4064)
			(stroke
				(width 0.1524)
				(type default)
			)
			(layer "F.SilkS")
		)
		(fp_line
			(start -0.7874 -0.4064)
			(end 0.7874 -0.4064)
			(stroke
				(width 0.1524)
				(type default)
			)
			(layer "F.SilkS")
		)
		(fp_line
			(start 0.7874 -0.4064)
			(end 0.7874 0.4064)
			(stroke
				(width 0.1524)
				(type default)
			)
			(layer "F.SilkS")
		)
		(fp_line
			(start -0.67945 0.3048)
			(end -0.67945 -0.305054)
			(stroke
				(width 0.1)
				(type default)
			)
			(layer "F.Fab")
		)
		(fp_line
			(start -0.12065 0.3048)
			(end -0.67945 0.3048)
			(stroke
				(width 0.1)
				(type default)
			)
			(layer "F.Fab")
		)
		(fp_line
			(start 0.120396 0.3048)
			(end 0.120396 0.2794)
			(stroke
				(width 0.1)
				(type default)
			)
			(layer "F.Fab")
		)
		(fp_line
			(start 0.67945 0.3048)
			(end 0.120396 0.3048)
			(stroke
				(width 0.1)
				(type default)
			)
			(layer "F.Fab")
		)
		(fp_line
			(start -0.12065 0.2794)
			(end -0.12065 0.3048)
			(stroke
				(width 0.1)
				(type default)
			)
			(layer "F.Fab")
		)
		(fp_line
			(start 0.120396 0.2794)
			(end -0.12065 0.2794)
			(stroke
				(width 0.1)
				(type default)
			)
			(layer "F.Fab")
		)
		(fp_line
			(start -0.12065 -0.2794)
			(end 0.12065 -0.2794)
			(stroke
				(width 0.1)
				(type default)
			)
			(layer "F.Fab")
		)
		(fp_line
			(start 0.12065 -0.2794)
			(end 0.12065 -0.3048)
			(stroke
				(width 0.1)
				(type default)
			)
			(layer "F.Fab")
		)
		(fp_line
			(start 0.12065 -0.3048)
			(end 0.67945 -0.3048)
			(stroke
				(width 0.1)
				(type default)
			)
			(layer "F.Fab")
		)
		(fp_line
			(start 0.67945 -0.3048)
			(end 0.67945 0.3048)
			(stroke
				(width 0.1)
				(type default)
			)
			(layer "F.Fab")
		)
		(fp_line
			(start -0.67945 -0.305054)
			(end -0.12065 -0.305054)
			(stroke
				(width 0.1)
				(type default)
			)
			(layer "F.Fab")
		)
		(fp_line
			(start -0.12065 -0.305054)
			(end -0.12065 -0.2794)
			(stroke
				(width 0.1)
				(type default)
			)
			(layer "F.Fab")
		)
		(pad "1" smd circle
			(at -0.40005 0 270)
			(size 0 0)
			(layers "F.Cu" "F.Mask" "F.Paste")
			(net "OCP_V3_2_ISO_BIF1_EN")
		)
		(pad "2" smd circle
			(at 0.40005 0 270)
			(size 0 0)
			(layers "F.Cu" "F.Mask" "F.Paste")
			(net "OCP_V3_2_BIF1_R_N")
		)
	)
	(footprint ""
		(layer "F.Cu")
		(at 33.363662 -429.790098 90)
		(property "Reference" "R3270"
			(at 0 0 90)
			(layer "F.SilkS")
			(hide yes)
			(effects
				(font
					(size 1.27 1.27)
				)
			)
		)
		(property "Value" ""
			(at 0 0 90)
			(layer "F.Fab")
			(effects
				(font
					(size 1.27 1.27)
				)
			)
		)
		(duplicate_pad_numbers_are_jumpers no)
		(fp_line
			(start 0.7874 -0.4064)
			(end 0.7874 0.4064)
			(stroke
				(width 0.1524)
				(type default)
			)
			(layer "F.SilkS")
		)
		(fp_line
			(start -0.7874 -0.4064)
			(end 0.7874 -0.4064)
			(stroke
				(width 0.1524)
				(type default)
			)
			(layer "F.SilkS")
		)
		(fp_line
			(start 0.7874 0.4064)
			(end -0.7874 0.4064)
			(stroke
				(width 0.1524)
				(type default)
			)
			(layer "F.SilkS")
		)
		(fp_line
			(start -0.7874 0.4064)
			(end -0.7874 -0.4064)
			(stroke
				(width 0.1524)
				(type default)
			)
			(layer "F.SilkS")
		)
		(fp_line
			(start -0.12065 -0.305054)
			(end -0.12065 -0.2794)
			(stroke
				(width 0.1)
				(type default)
			)
			(layer "F.Fab")
		)
		(fp_line
			(start -0.67945 -0.305054)
			(end -0.12065 -0.305054)
			(stroke
				(width 0.1)
				(type default)
			)
			(layer "F.Fab")
		)
		(fp_line
			(start 0.67945 -0.3048)
			(end 0.67945 0.3048)
			(stroke
				(width 0.1)
				(type default)
			)
			(layer "F.Fab")
		)
		(fp_line
			(start 0.12065 -0.3048)
			(end 0.67945 -0.3048)
			(stroke
				(width 0.1)
				(type default)
			)
			(layer "F.Fab")
		)
		(fp_line
			(start 0.12065 -0.2794)
			(end 0.12065 -0.3048)
			(stroke
				(width 0.1)
				(type default)
			)
			(layer "F.Fab")
		)
		(fp_line
			(start -0.12065 -0.2794)
			(end 0.12065 -0.2794)
			(stroke
				(width 0.1)
				(type default)
			)
			(layer "F.Fab")
		)
		(fp_line
			(start 0.120396 0.2794)
			(end -0.12065 0.2794)
			(stroke
				(width 0.1)
				(type default)
			)
			(layer "F.Fab")
		)
		(fp_line
			(start -0.12065 0.2794)
			(end -0.12065 0.3048)
			(stroke
				(width 0.1)
				(type default)
			)
			(layer "F.Fab")
		)
		(fp_line
			(start 0.67945 0.3048)
			(end 0.120396 0.3048)
			(stroke
				(width 0.1)
				(type default)
			)
			(layer "F.Fab")
		)
		(fp_line
			(start 0.120396 0.3048)
			(end 0.120396 0.2794)
			(stroke
				(width 0.1)
				(type default)
			)
			(layer "F.Fab")
		)
		(fp_line
			(start -0.12065 0.3048)
			(end -0.67945 0.3048)
			(stroke
				(width 0.1)
				(type default)
			)
			(layer "F.Fab")
		)
		(fp_line
			(start -0.67945 0.3048)
			(end -0.67945 -0.305054)
			(stroke
				(width 0.1)
				(type default)
			)
			(layer "F.Fab")
		)
		(pad "1" smd circle
			(at -0.40005 0 90)
			(size 0 0)
			(layers "F.Cu" "F.Mask" "F.Paste")
			(net "FM_P2E_FGB")
		)
		(pad "2" smd circle
			(at 0.40005 0 90)
			(size 0 0)
			(layers "F.Cu" "F.Mask" "F.Paste")
			(net "GND")
		)
	)
	(footprint ""
		(layer "F.Cu")
		(at 159.639 -106.426 180)
		(property "Reference" "Q9003"
			(at 2.59461 -2.129028 0)
			(unlocked yes)
			(layer "F.SilkS")
			(effects
				(font
					(size 0.7874 0.5842)
					(thickness 0.1524)
				)
				(justify left)
			)
		)
		(property "Value" ""
			(at 0 0 180)
			(layer "F.Fab")
			(effects
				(font
					(size 1.27 1.27)
				)
			)
		)
		(duplicate_pad_numbers_are_jumpers no)
		(fp_line
			(start 1.332738 1.100074)
			(end -1.332738 1.100074)
			(stroke
				(width 0.1524)
				(type default)
			)
			(layer "F.SilkS")
		)
		(fp_line
			(start 1.332738 -1.100074)
			(end 1.332738 1.100074)
			(stroke
				(width 0.1524)
				(type default)
			)
			(layer "F.SilkS")
		)
		(fp_line
			(start 0.4826 -1.100074)
			(end 1.332738 -1.100074)
			(stroke
				(width 0.1524)
				(type default)
			)
			(layer "F.SilkS")
		)
		(fp_line
			(start 0 -0.541274)
			(end 0.4826 -1.100074)
			(stroke
				(width 0.1524)
				(type default)
			)
			(layer "F.SilkS")
		)
		(fp_line
			(start -0.4826 -1.100074)
			(end 0 -0.541274)
			(stroke
				(width 0.1524)
				(type default)
			)
			(layer "F.SilkS")
		)
		(fp_line
			(start -1.332738 1.100074)
			(end -1.332738 -1.100074)
			(stroke
				(width 0.1524)
				(type default)
			)
			(layer "F.SilkS")
		)
		(fp_line
			(start -1.332738 -1.100074)
			(end -0.4826 -1.100074)
			(stroke
				(width 0.1524)
				(type default)
			)
			(layer "F.SilkS")
		)
		(fp_poly
			(pts
				(xy -2.28219 -1.735074) (xy -1.785874 -2.23139) (xy -1.537716 -1.486916)
			)
			(stroke
				(width 0)
				(type default)
			)
			(fill yes)
			(layer "F.SilkS")
		)
		(fp_line
			(start 0.674878 1.100074)
			(end -0.674878 1.100074)
			(stroke
				(width 0.1)
				(type default)
			)
			(layer "F.Fab")
		)
		(fp_line
			(start 0.674878 -1.100074)
			(end 0.674878 1.100074)
			(stroke
				(width 0.1)
				(type default)
			)
			(layer "F.Fab")
		)
		(fp_line
			(start -0.674878 1.100074)
			(end -0.674878 -1.100074)
			(stroke
				(width 0.1)
				(type default)
			)
			(layer "F.Fab")
		)
		(fp_line
			(start -0.674878 -1.100074)
			(end 0.674878 -1.100074)
			(stroke
				(width 0.1)
				(type default)
			)
			(layer "F.Fab")
		)
		(fp_poly
			(pts
				(xy -2.2352 -0.298958) (xy -2.2352 -1.001014) (xy -1.533144 -0.649986)
			)
			(stroke
				(width 0)
				(type default)
			)
			(fill yes)
			(layer "F.Fab")
		)
		(pad "1" smd rect
			(at -0.94996 -0.649986 270)
			(size 0.4318 0.508)
			(layers "F.Cu" "F.Mask" "F.Paste")
			(net "GND")
		)
		(pad "2" smd rect
			(at -0.94996 0 270)
			(size 0.4318 0.508)
			(layers "F.Cu" "F.Mask" "F.Paste")
			(net "IRQ_HSC_FAULT_N")
		)
		(pad "3" smd rect
			(at -0.94996 0.649986 270)
			(size 0.4318 0.508)
			(layers "F.Cu" "F.Mask" "F.Paste")
			(net "IRQ_HSC_FAULT_BUF_N")
		)
		(pad "4" smd rect
			(at 0.94996 0.649986 270)
			(size 0.4318 0.508)
			(layers "F.Cu" "F.Mask" "F.Paste")
			(net "GND")
		)
		(pad "5" smd rect
			(at 0.94996 0 270)
			(size 0.4318 0.508)
			(layers "F.Cu" "F.Mask" "F.Paste")
			(net "IRQ_HSC_FAULT")
		)
		(pad "6" smd rect
			(at 0.94996 -0.649986 270)
			(size 0.4318 0.508)
			(layers "F.Cu" "F.Mask" "F.Paste")
			(net "IRQ_HSC_FAULT")
		)
	)
	(footprint ""
		(layer "F.Cu")
		(at 292.008306 -346.71635)
		(property "Reference" "PU18"
			(at -2.321306 -7.71398 0)
			(unlocked yes)
			(layer "F.SilkS")
			(effects
				(font
					(size 0.7874 0.5842)
					(thickness 0.1524)
				)
				(justify left)
			)
		)
		(property "Value" ""
			(at 0 0 0)
			(layer "F.Fab")
			(effects
				(font
					(size 1.27 1.27)
				)
			)
		)
		(duplicate_pad_numbers_are_jumpers no)
		(fp_line
			(start -2.500122 -2.999994)
			(end -2.24409 -2.999994)
			(stroke
				(width 0.1524)
				(type default)
			)
			(layer "F.SilkS")
		)
		(fp_line
			(start -2.500122 -2.529078)
			(end -2.500122 -2.999994)
			(stroke
				(width 0.1524)
				(type default)
			)
			(layer "F.SilkS")
		)
		(fp_line
			(start -2.500122 0.6604)
			(end -2.500122 0.229108)
			(stroke
				(width 0.1524)
				(type default)
			)
			(layer "F.SilkS")
		)
		(fp_line
			(start -2.500122 2.999994)
			(end -2.500122 2.339594)
			(stroke
				(width 0.1524)
				(type default)
			)
			(layer "F.SilkS")
		)
		(fp_line
			(start -2.2987 2.999994)
			(end -2.500122 2.999994)
			(stroke
				(width 0.1524)
				(type default)
			)
			(layer "F.SilkS")
		)
		(fp_line
			(start 2.31394 -2.999994)
			(end 2.500122 -2.999994)
			(stroke
				(width 0.1524)
				(type default)
			)
			(layer "F.SilkS")
		)
		(fp_line
			(start 2.500122 -2.999994)
			(end 2.500122 -2.44348)
			(stroke
				(width 0.1524)
				(type default)
			)
			(layer "F.SilkS")
		)
		(fp_line
			(start 2.500122 2.339594)
			(end 2.500122 2.999994)
			(stroke
				(width 0.1524)
				(type default)
			)
			(layer "F.SilkS")
		)
		(fp_line
			(start 2.500122 2.999994)
			(end 2.2987 2.999994)
			(stroke
				(width 0.1524)
				(type default)
			)
			(layer "F.SilkS")
		)
		(fp_poly
			(pts
				(xy -3.429508 -2.672588) (xy -2.96545 -3.136646) (xy -2.733548 -2.440686)
			)
			(stroke
				(width 0)
				(type default)
			)
			(fill yes)
			(layer "F.SilkS")
		)
		(fp_line
			(start -2.500122 -2.999994)
			(end 2.500122 -2.999994)
			(stroke
				(width 0.1)
				(type default)
			)
			(layer "F.Fab")
		)
		(fp_line
			(start -2.500122 2.999994)
			(end -2.500122 -2.999994)
			(stroke
				(width 0.1)
				(type default)
			)
			(layer "F.Fab")
		)
		(fp_line
			(start 2.500122 -2.999994)
			(end 2.500122 2.999994)
			(stroke
				(width 0.1)
				(type default)
			)
			(layer "F.Fab")
		)
		(fp_line
			(start 2.500122 2.999994)
			(end -2.500122 2.999994)
			(stroke
				(width 0.1)
				(type default)
			)
			(layer "F.Fab")
		)
		(fp_poly
			(pts
				(xy -4.218432 -2.783078) (xy -4.218432 -1.767078) (xy -3.202432 -2.275078)
			)
			(stroke
				(width 0)
				(type default)
			)
			(fill yes)
			(layer "F.Fab")
		)
		(pad "1" smd rect
			(at -2.400046 -2.275078 90)
			(size 0.2286 0.6096)
			(layers "F.Cu" "F.Mask" "F.Paste")
			(net "PVDDIO_P0_VOS2")
		)
		(pad "2" smd rect
			(at -2.400046 -1.82499 90)
			(size 0.2286 0.6096)
			(layers "F.Cu" "F.Mask" "F.Paste")
			(net "GND")
		)
		(pad "3" smd rect
			(at -2.400046 -1.374902 90)
			(size 0.2286 0.6096)
			(layers "F.Cu" "F.Mask" "F.Paste")
			(net "PVDDIO_P0_VCC2")
		)
		(pad "4" smd rect
			(at -2.400046 -0.925068 90)
			(size 0.2286 0.6096)
			(layers "F.Cu" "F.Mask" "F.Paste")
			(net "PVDDCR_CPU1_P0_PVCC")
		)
		(pad "5" smd rect
			(at -2.400046 -0.47498 90)
			(size 0.2286 0.6096)
			(layers "F.Cu" "F.Mask" "F.Paste")
			(net "GND")
		)
		(pad "6" smd rect
			(at -2.400046 -0.024892 90)
			(size 0.2286 0.6096)
			(layers "F.Cu" "F.Mask" "F.Paste")
			(net "NC_PVDDIO_P0_GL1_2")
		)
		(pad "7_9-20_24" smd circle
			(at 0 1.150112 90)
			(size 0 0)
			(layers "F.Cu" "F.Mask" "F.Paste")
			(net "GND")
		)
		(pad "10_19" smd rect
			(at 0 2.899918 90)
			(size 0.6096 4.318)
			(layers "F.Cu" "F.Mask" "F.Paste")
			(net "SW_PVDDIO_P0_SW2")
		)
		(pad "25_29" smd rect
			(at 1.549908 -1.279906 270)
			(size 2.0574 2.3114)
			(layers "F.Cu" "F.Mask" "F.Paste")
			(net "SW_P12V_AUX_PVDDIO_P0_FLT")
		)
		(pad "30" smd rect
			(at 2.05994 -2.899918)
			(size 0.2286 0.6096)
			(layers "F.Cu" "F.Mask" "F.Paste")
			(net "SW_P12V_AUX_PVDDIO_P0_FLT")
		)
		(pad "31" smd rect
			(at 1.610106 -2.899918)
			(size 0.2286 0.6096)
			(layers "F.Cu" "F.Mask" "F.Paste")
			(net "NC_PVDDIO_P0_DNC2")
		)
		(pad "32" smd rect
			(at 1.160018 -2.899918)
			(size 0.2286 0.6096)
			(layers "F.Cu" "F.Mask" "F.Paste")
			(net "SW_PVDDIO_P0_BOOTR2")
		)
		(pad "33" smd rect
			(at 0.70993 -2.899918)
			(size 0.2286 0.6096)
			(layers "F.Cu" "F.Mask" "F.Paste")
			(net "SW_PVDDIO_P0_BOOT2")
		)
		(pad "34" smd rect
			(at 0.260096 -2.899918)
			(size 0.2286 0.6096)
			(layers "F.Cu" "F.Mask" "F.Paste")
			(net "PVDDIO_P0_PWM2")
		)
		(pad "35" smd rect
			(at -0.189992 -2.899918)
			(size 0.2286 0.6096)
			(layers "F.Cu" "F.Mask" "F.Paste")
			(net "PVDDIO_P0_VCC2")
		)
		(pad "36" smd rect
			(at -0.64008 -2.899918)
			(size 0.2286 0.6096)
			(layers "F.Cu" "F.Mask" "F.Paste")
			(net "PVDDIO_P0_TEMP1")
		)
		(pad "37" smd rect
			(at -1.089914 -2.899918)
			(size 0.2286 0.6096)
			(layers "F.Cu" "F.Mask" "F.Paste")
			(net "PVDDIO_P0_LSET2")
		)
		(pad "38" smd rect
			(at -1.540002 -2.899918)
			(size 0.2286 0.6096)
			(layers "F.Cu" "F.Mask" "F.Paste")
			(net "PVDDIO_P0_IMON2")
		)
		(pad "39" smd rect
			(at -1.99009 -2.899918)
			(size 0.2286 0.6096)
			(layers "F.Cu" "F.Mask" "F.Paste")
			(net "PVDDCR_CPU1_P0_VCCS")
		)
		(pad "40" smd rect
			(at -0.87503 -1.27508)
			(size 1.7526 1.9558)
			(layers "F.Cu" "F.Mask" "F.Paste")
			(net "GND")
		)
		(pad "41" smd rect
			(at -1.525016 0.249936 270)
			(size 0.3048 0.4572)
			(layers "F.Cu" "F.Mask" "F.Paste")
			(net "NC_PVDDIO_P0_GL2_2")
		)
		(zone
			(layer "F.Cu")
			(hatch none 0.5)
			(connect_pads
				(clearance 0)
			)
			(min_thickness 0.25)
			(keepout
				(tracks not_allowed)
				(vias allowed)
				(pads allowed)
				(copperpour not_allowed)
				(footprints allowed)
			)
			(placement
				(enabled no)
				(sheetname "")
			)
			(fill
				(thermal_gap 0.5)
				(thermal_bridge_width 0.5)
				(island_removal_mode 0)
			)
			(polygon
				(pts
					(xy 289.508184 -344.150442) (xy 289.508184 -344.465656) (xy 294.508428 -344.465656) (xy 294.508428 -344.142568)
					(xy 294.218106 -344.142568) (xy 294.218106 -344.172032) (xy 289.798506 -344.172032) (xy 289.798506 -344.150442)
				)
			)
		)
		(zone
			(layer "F.Cu")
			(hatch none 0.5)
			(connect_pads
				(clearance 0)
			)
			(min_thickness 0.25)
			(keepout
				(tracks not_allowed)
				(vias allowed)
				(pads allowed)
				(copperpour not_allowed)
				(footprints allowed)
			)
			(placement
				(enabled no)
				(sheetname "")
			)
			(fill
				(thermal_gap 0.5)
				(thermal_bridge_width 0.5)
				(island_removal_mode 0)
			)
			(polygon
				(pts
					(xy 292.060376 -346.96273) (xy 292.060376 -349.02013) (xy 290.206176 -349.02013) (xy 290.206176 -348.779084)
					(xy 289.96386 -348.779084) (xy 289.96386 -349.260668) (xy 293.766494 -349.260668) (xy 293.766494 -349.075756)
					(xy 292.351714 -349.075756) (xy 292.351714 -346.916756) (xy 294.508428 -346.916756) (xy 294.508428 -346.667074)
					(xy 292.356032 -346.667074)
				)
			)
		)
	)
	(footprint ""
		(layer "F.Cu")
		(at 396.289022 -416.899344 -90)
		(property "Reference" "C6581"
			(at 0 0 270)
			(layer "F.SilkS")
			(hide yes)
			(effects
				(font
					(size 1.27 1.27)
				)
			)
		)
		(property "Value" ""
			(at 0 0 270)
			(layer "F.Fab")
			(effects
				(font
					(size 1.27 1.27)
				)
			)
		)
		(duplicate_pad_numbers_are_jumpers no)
		(fp_line
			(start -0.299974 0.150114)
			(end -0.299974 -0.150114)
			(stroke
				(width 0.1)
				(type default)
			)
			(layer "F.Fab")
		)
		(fp_line
			(start 0.299974 0.150114)
			(end -0.299974 0.150114)
			(stroke
				(width 0.1)
				(type default)
			)
			(layer "F.Fab")
		)
		(fp_line
			(start -0.299974 -0.150114)
			(end 0.299974 -0.150114)
			(stroke
				(width 0.1)
				(type default)
			)
			(layer "F.Fab")
		)
		(fp_line
			(start 0.299974 -0.150114)
			(end 0.299974 0.150114)
			(stroke
				(width 0.1)
				(type default)
			)
			(layer "F.Fab")
		)
		(pad "1" smd rect
			(at -0.2667 0 270)
			(size 0.3048 0.381)
			(layers "F.Cu" "F.Mask" "F.Paste")
			(net "P5E_CPU0_P2_TX_BUF_C_DP<8>")
		)
		(pad "2" smd rect
			(at 0.2667 0 270)
			(size 0.3048 0.381)
			(layers "F.Cu" "F.Mask" "F.Paste")
			(net "P5E_CPU0_P2_TX_BUF_DP<8>")
		)
	)
	(footprint ""
		(layer "F.Cu")
		(at 233.287824 -144.959324)
		(property "Reference" "R1646"
			(at 0 0 0)
			(layer "F.SilkS")
			(hide yes)
			(effects
				(font
					(size 1.27 1.27)
				)
			)
		)
		(property "Value" ""
			(at 0 0 0)
			(layer "F.Fab")
			(effects
				(font
					(size 1.27 1.27)
				)
			)
		)
		(duplicate_pad_numbers_are_jumpers no)
		(fp_line
			(start -0.7874 -0.4064)
			(end 0.7874 -0.4064)
			(stroke
				(width 0.1524)
				(type default)
			)
			(layer "F.SilkS")
		)
		(fp_line
			(start -0.7874 0.4064)
			(end -0.7874 -0.4064)
			(stroke
				(width 0.1524)
				(type default)
			)
			(layer "F.SilkS")
		)
		(fp_line
			(start 0.7874 -0.4064)
			(end 0.7874 0.4064)
			(stroke
				(width 0.1524)
				(type default)
			)
			(layer "F.SilkS")
		)
		(fp_line
			(start 0.7874 0.4064)
			(end -0.7874 0.4064)
			(stroke
				(width 0.1524)
				(type default)
			)
			(layer "F.SilkS")
		)
		(fp_line
			(start -0.67945 -0.305054)
			(end -0.12065 -0.305054)
			(stroke
				(width 0.1)
				(type default)
			)
			(layer "F.Fab")
		)
		(fp_line
			(start -0.67945 0.3048)
			(end -0.67945 -0.305054)
			(stroke
				(width 0.1)
				(type default)
			)
			(layer "F.Fab")
		)
		(fp_line
			(start -0.12065 -0.305054)
			(end -0.12065 -0.2794)
			(stroke
				(width 0.1)
				(type default)
			)
			(layer "F.Fab")
		)
		(fp_line
			(start -0.12065 -0.2794)
			(end 0.12065 -0.2794)
			(stroke
				(width 0.1)
				(type default)
			)
			(layer "F.Fab")
		)
		(fp_line
			(start -0.12065 0.2794)
			(end -0.12065 0.3048)
			(stroke
				(width 0.1)
				(type default)
			)
			(layer "F.Fab")
		)
		(fp_line
			(start -0.12065 0.3048)
			(end -0.67945 0.3048)
			(stroke
				(width 0.1)
				(type default)
			)
			(layer "F.Fab")
		)
		(fp_line
			(start 0.120396 0.2794)
			(end -0.12065 0.2794)
			(stroke
				(width 0.1)
				(type default)
			)
			(layer "F.Fab")
		)
		(fp_line
			(start 0.120396 0.3048)
			(end 0.120396 0.2794)
			(stroke
				(width 0.1)
				(type default)
			)
			(layer "F.Fab")
		)
		(fp_line
			(start 0.12065 -0.3048)
			(end 0.67945 -0.3048)
			(stroke
				(width 0.1)
				(type default)
			)
			(layer "F.Fab")
		)
		(fp_line
			(start 0.12065 -0.2794)
			(end 0.12065 -0.3048)
			(stroke
				(width 0.1)
				(type default)
			)
			(layer "F.Fab")
		)
		(fp_line
			(start 0.67945 -0.3048)
			(end 0.67945 0.3048)
			(stroke
				(width 0.1)
				(type default)
			)
			(layer "F.Fab")
		)
		(fp_line
			(start 0.67945 0.3048)
			(end 0.120396 0.3048)
			(stroke
				(width 0.1)
				(type default)
			)
			(layer "F.Fab")
		)
		(pad "1" smd circle
			(at -0.40005 0)
			(size 0 0)
			(layers "F.Cu" "F.Mask" "F.Paste")
			(net "PVDD18_S5_P0")
		)
		(pad "2" smd circle
			(at 0.40005 0)
			(size 0 0)
			(layers "F.Cu" "F.Mask" "F.Paste")
			(net "CPU0_HDT_BYPASS_SEL")
		)
	)
	(footprint ""
		(layer "F.Cu")
		(at 287.92551 -360.420158 90)
		(property "Reference" "PL19"
			(at -3.0734 -3.876548 90)
			(unlocked yes)
			(layer "F.SilkS")
			(effects
				(font
					(size 0.7874 0.5842)
					(thickness 0.1524)
				)
				(justify left)
			)
		)
		(property "Value" ""
			(at 0 0 90)
			(layer "F.Fab")
			(effects
				(font
					(size 1.27 1.27)
				)
			)
		)
		(duplicate_pad_numbers_are_jumpers no)
		(fp_line
			(start 3.050032 -2.999994)
			(end -3.050032 -2.999994)
			(stroke
				(width 0.1524)
				(type default)
			)
			(layer "F.SilkS")
		)
		(fp_line
			(start -3.050032 -2.999994)
			(end -3.050032 -1.4478)
			(stroke
				(width 0.1524)
				(type default)
			)
			(layer "F.SilkS")
		)
		(fp_line
			(start 3.050032 -1.4478)
			(end 3.050032 -2.999994)
			(stroke
				(width 0.1524)
				(type default)
			)
			(layer "F.SilkS")
		)
		(fp_line
			(start -3.050032 1.4478)
			(end -3.050032 2.999994)
			(stroke
				(width 0.1524)
				(type default)
			)
			(layer "F.SilkS")
		)
		(fp_line
			(start 3.050032 2.999994)
			(end 3.050032 1.4478)
			(stroke
				(width 0.1524)
				(type default)
			)
			(layer "F.SilkS")
		)
		(fp_line
			(start -3.050032 2.999994)
			(end 3.050032 2.999994)
			(stroke
				(width 0.1524)
				(type default)
			)
			(layer "F.SilkS")
		)
		(fp_line
			(start 3.050032 -2.999994)
			(end -3.050032 -2.999994)
			(stroke
				(width 0.1)
				(type default)
			)
			(layer "F.Fab")
		)
		(fp_line
			(start -3.050032 -2.999994)
			(end -3.050032 2.999994)
			(stroke
				(width 0.1)
				(type default)
			)
			(layer "F.Fab")
		)
		(fp_line
			(start 3.050032 2.999994)
			(end 3.050032 -2.999994)
			(stroke
				(width 0.1)
				(type default)
			)
			(layer "F.Fab")
		)
		(fp_line
			(start -3.050032 2.999994)
			(end 3.050032 2.999994)
			(stroke
				(width 0.1)
				(type default)
			)
			(layer "F.Fab")
		)
		(pad "1" smd rect
			(at -2.525014 0 90)
			(size 1.651 2.6162)
			(layers "F.Cu" "F.Mask" "F.Paste")
			(net "SW_P12V_AUX_PVDDIO_P0_FLT")
		)
		(pad "2" smd rect
			(at 2.525014 0 90)
			(size 1.651 2.6162)
			(layers "F.Cu" "F.Mask" "F.Paste")
			(net "P12V_AUX")
		)
	)
	(footprint ""
		(layer "F.Cu")
		(at 220.26626 -98.11004 90)
		(property "Reference" "R1519"
			(at 0 0 90)
			(layer "F.SilkS")
			(hide yes)
			(effects
				(font
					(size 1.27 1.27)
				)
			)
		)
		(property "Value" ""
			(at 0 0 90)
			(layer "F.Fab")
			(effects
				(font
					(size 1.27 1.27)
				)
			)
		)
		(duplicate_pad_numbers_are_jumpers no)
		(fp_line
			(start 0.7874 -0.4064)
			(end 0.7874 0.4064)
			(stroke
				(width 0.1524)
				(type default)
			)
			(layer "F.SilkS")
		)
		(fp_line
			(start -0.7874 -0.4064)
			(end 0.7874 -0.4064)
			(stroke
				(width 0.1524)
				(type default)
			)
			(layer "F.SilkS")
		)
		(fp_line
			(start 0.7874 0.4064)
			(end -0.7874 0.4064)
			(stroke
				(width 0.1524)
				(type default)
			)
			(layer "F.SilkS")
		)
		(fp_line
			(start -0.7874 0.4064)
			(end -0.7874 -0.4064)
			(stroke
				(width 0.1524)
				(type default)
			)
			(layer "F.SilkS")
		)
		(fp_line
			(start -0.12065 -0.305054)
			(end -0.12065 -0.2794)
			(stroke
				(width 0.1)
				(type default)
			)
			(layer "F.Fab")
		)
		(fp_line
			(start -0.67945 -0.305054)
			(end -0.12065 -0.305054)
			(stroke
				(width 0.1)
				(type default)
			)
			(layer "F.Fab")
		)
		(fp_line
			(start 0.67945 -0.3048)
			(end 0.67945 0.3048)
			(stroke
				(width 0.1)
				(type default)
			)
			(layer "F.Fab")
		)
		(fp_line
			(start 0.12065 -0.3048)
			(end 0.67945 -0.3048)
			(stroke
				(width 0.1)
				(type default)
			)
			(layer "F.Fab")
		)
		(fp_line
			(start 0.12065 -0.2794)
			(end 0.12065 -0.3048)
			(stroke
				(width 0.1)
				(type default)
			)
			(layer "F.Fab")
		)
		(fp_line
			(start -0.12065 -0.2794)
			(end 0.12065 -0.2794)
			(stroke
				(width 0.1)
				(type default)
			)
			(layer "F.Fab")
		)
		(fp_line
			(start 0.120396 0.2794)
			(end -0.12065 0.2794)
			(stroke
				(width 0.1)
				(type default)
			)
			(layer "F.Fab")
		)
		(fp_line
			(start -0.12065 0.2794)
			(end -0.12065 0.3048)
			(stroke
				(width 0.1)
				(type default)
			)
			(layer "F.Fab")
		)
		(fp_line
			(start 0.67945 0.3048)
			(end 0.120396 0.3048)
			(stroke
				(width 0.1)
				(type default)
			)
			(layer "F.Fab")
		)
		(fp_line
			(start 0.120396 0.3048)
			(end 0.120396 0.2794)
			(stroke
				(width 0.1)
				(type default)
			)
			(layer "F.Fab")
		)
		(fp_line
			(start -0.12065 0.3048)
			(end -0.67945 0.3048)
			(stroke
				(width 0.1)
				(type default)
			)
			(layer "F.Fab")
		)
		(fp_line
			(start -0.67945 0.3048)
			(end -0.67945 -0.305054)
			(stroke
				(width 0.1)
				(type default)
			)
			(layer "F.Fab")
		)
		(pad "1" smd circle
			(at -0.40005 0 90)
			(size 0 0)
			(layers "F.Cu" "F.Mask" "F.Paste")
			(net "OCP_V3_1_P3V3_R3_PWRGD")
		)
		(pad "2" smd circle
			(at 0.40005 0 90)
			(size 0 0)
			(layers "F.Cu" "F.Mask" "F.Paste")
			(net "OCP_V3_1_P3V3_PWRGD")
		)
	)
	(footprint ""
		(layer "F.Cu")
		(at 367.007902 -172.913802 -90)
		(property "Reference" "PC473_1"
			(at 0 0 270)
			(layer "F.SilkS")
			(hide yes)
			(effects
				(font
					(size 1.27 1.27)
				)
			)
		)
		(property "Value" ""
			(at 0 0 270)
			(layer "F.Fab")
			(effects
				(font
					(size 1.27 1.27)
				)
			)
		)
		(duplicate_pad_numbers_are_jumpers no)
		(fp_line
			(start -0.7874 0.4064)
			(end -0.7874 -0.4064)
			(stroke
				(width 0.1524)
				(type default)
			)
			(layer "F.SilkS")
		)
		(fp_line
			(start 0.7874 0.4064)
			(end -0.7874 0.4064)
			(stroke
				(width 0.1524)
				(type default)
			)
			(layer "F.SilkS")
		)
		(fp_line
			(start -0.7874 -0.4064)
			(end 0.7874 -0.4064)
			(stroke
				(width 0.1524)
				(type default)
			)
			(layer "F.SilkS")
		)
		(fp_line
			(start 0.7874 -0.4064)
			(end 0.7874 0.4064)
			(stroke
				(width 0.1524)
				(type default)
			)
			(layer "F.SilkS")
		)
		(fp_line
			(start -0.67945 0.3048)
			(end -0.67945 -0.305054)
			(stroke
				(width 0.1)
				(type default)
			)
			(layer "F.Fab")
		)
		(fp_line
			(start -0.12065 0.3048)
			(end -0.67945 0.3048)
			(stroke
				(width 0.1)
				(type default)
			)
			(layer "F.Fab")
		)
		(fp_line
			(start 0.120396 0.3048)
			(end 0.120396 0.2794)
			(stroke
				(width 0.1)
				(type default)
			)
			(layer "F.Fab")
		)
		(fp_line
			(start 0.67945 0.3048)
			(end 0.120396 0.3048)
			(stroke
				(width 0.1)
				(type default)
			)
			(layer "F.Fab")
		)
		(fp_line
			(start -0.12065 0.2794)
			(end -0.12065 0.3048)
			(stroke
				(width 0.1)
				(type default)
			)
			(layer "F.Fab")
		)
		(fp_line
			(start 0.120396 0.2794)
			(end -0.12065 0.2794)
			(stroke
				(width 0.1)
				(type default)
			)
			(layer "F.Fab")
		)
		(fp_line
			(start -0.12065 -0.2794)
			(end 0.12065 -0.2794)
			(stroke
				(width 0.1)
				(type default)
			)
			(layer "F.Fab")
		)
		(fp_line
			(start 0.12065 -0.2794)
			(end 0.12065 -0.3048)
			(stroke
				(width 0.1)
				(type default)
			)
			(layer "F.Fab")
		)
		(fp_line
			(start 0.12065 -0.3048)
			(end 0.67945 -0.3048)
			(stroke
				(width 0.1)
				(type default)
			)
			(layer "F.Fab")
		)
		(fp_line
			(start 0.67945 -0.3048)
			(end 0.67945 0.3048)
			(stroke
				(width 0.1)
				(type default)
			)
			(layer "F.Fab")
		)
		(fp_line
			(start -0.67945 -0.305054)
			(end -0.12065 -0.305054)
			(stroke
				(width 0.1)
				(type default)
			)
			(layer "F.Fab")
		)
		(fp_line
			(start -0.12065 -0.305054)
			(end -0.12065 -0.2794)
			(stroke
				(width 0.1)
				(type default)
			)
			(layer "F.Fab")
		)
		(pad "1" smd circle
			(at -0.40005 0 270)
			(size 0 0)
			(layers "F.Cu" "F.Mask" "F.Paste")
			(net "PVDDCR_CPU0_P0_VCCS")
		)
		(pad "2" smd circle
			(at 0.40005 0 270)
			(size 0 0)
			(layers "F.Cu" "F.Mask" "F.Paste")
			(net "GND")
		)
	)
	(footprint ""
		(layer "F.Cu")
		(at 205.234286 -110.649512 180)
		(property "Reference" "R3483"
			(at 0 0 180)
			(layer "F.SilkS")
			(hide yes)
			(effects
				(font
					(size 1.27 1.27)
				)
			)
		)
		(property "Value" ""
			(at 0 0 180)
			(layer "F.Fab")
			(effects
				(font
					(size 1.27 1.27)
				)
			)
		)
		(duplicate_pad_numbers_are_jumpers no)
		(fp_line
			(start 0.7874 0.4064)
			(end -0.7874 0.4064)
			(stroke
				(width 0.1524)
				(type default)
			)
			(layer "F.SilkS")
		)
		(fp_line
			(start 0.7874 -0.4064)
			(end 0.7874 0.4064)
			(stroke
				(width 0.1524)
				(type default)
			)
			(layer "F.SilkS")
		)
		(fp_line
			(start -0.7874 0.4064)
			(end -0.7874 -0.4064)
			(stroke
				(width 0.1524)
				(type default)
			)
			(layer "F.SilkS")
		)
		(fp_line
			(start -0.7874 -0.4064)
			(end 0.7874 -0.4064)
			(stroke
				(width 0.1524)
				(type default)
			)
			(layer "F.SilkS")
		)
		(fp_line
			(start 0.67945 0.3048)
			(end 0.120396 0.3048)
			(stroke
				(width 0.1)
				(type default)
			)
			(layer "F.Fab")
		)
		(fp_line
			(start 0.67945 -0.3048)
			(end 0.67945 0.3048)
			(stroke
				(width 0.1)
				(type default)
			)
			(layer "F.Fab")
		)
		(fp_line
			(start 0.12065 -0.2794)
			(end 0.12065 -0.3048)
			(stroke
				(width 0.1)
				(type default)
			)
			(layer "F.Fab")
		)
		(fp_line
			(start 0.12065 -0.3048)
			(end 0.67945 -0.3048)
			(stroke
				(width 0.1)
				(type default)
			)
			(layer "F.Fab")
		)
		(fp_line
			(start 0.120396 0.3048)
			(end 0.120396 0.2794)
			(stroke
				(width 0.1)
				(type default)
			)
			(layer "F.Fab")
		)
		(fp_line
			(start 0.120396 0.2794)
			(end -0.12065 0.2794)
			(stroke
				(width 0.1)
				(type default)
			)
			(layer "F.Fab")
		)
		(fp_line
			(start -0.12065 0.3048)
			(end -0.67945 0.3048)
			(stroke
				(width 0.1)
				(type default)
			)
			(layer "F.Fab")
		)
		(fp_line
			(start -0.12065 0.2794)
			(end -0.12065 0.3048)
			(stroke
				(width 0.1)
				(type default)
			)
			(layer "F.Fab")
		)
		(fp_line
			(start -0.12065 -0.2794)
			(end 0.12065 -0.2794)
			(stroke
				(width 0.1)
				(type default)
			)
			(layer "F.Fab")
		)
		(fp_line
			(start -0.12065 -0.305054)
			(end -0.12065 -0.2794)
			(stroke
				(width 0.1)
				(type default)
			)
			(layer "F.Fab")
		)
		(fp_line
			(start -0.67945 0.3048)
			(end -0.67945 -0.305054)
			(stroke
				(width 0.1)
				(type default)
			)
			(layer "F.Fab")
		)
		(fp_line
			(start -0.67945 -0.305054)
			(end -0.12065 -0.305054)
			(stroke
				(width 0.1)
				(type default)
			)
			(layer "F.Fab")
		)
		(pad "1" smd circle
			(at -0.40005 0 180)
			(size 0 0)
			(layers "F.Cu" "F.Mask" "F.Paste")
			(net "GPU_FPGA_EROT_RECOV_N")
		)
		(pad "2" smd circle
			(at 0.40005 0 180)
			(size 0 0)
			(layers "F.Cu" "F.Mask" "F.Paste")
			(net "GPU_FPGA_EROT_RECOV_R_N")
		)
	)
	(footprint ""
		(layer "F.Cu")
		(at 112.79886 -31.497778 90)
		(property "Reference" "U6002"
			(at -4.285742 -6.178804 90)
			(unlocked yes)
			(layer "F.SilkS")
			(effects
				(font
					(size 0.7874 0.5842)
					(thickness 0.1524)
				)
				(justify left)
			)
		)
		(property "Value" ""
			(at 0 0 90)
			(layer "F.Fab")
			(effects
				(font
					(size 1.27 1.27)
				)
			)
		)
		(duplicate_pad_numbers_are_jumpers no)
		(fp_line
			(start 4.549902 -4.549902)
			(end 4.549902 -4.014724)
			(stroke
				(width 0.1524)
				(type default)
			)
			(layer "F.SilkS")
		)
		(fp_line
			(start 4.014724 -4.549902)
			(end 4.549902 -4.549902)
			(stroke
				(width 0.1524)
				(type default)
			)
			(layer "F.SilkS")
		)
		(fp_line
			(start -4.549902 -4.549902)
			(end -4.014724 -4.549902)
			(stroke
				(width 0.1524)
				(type default)
			)
			(layer "F.SilkS")
		)
		(fp_line
			(start -4.549902 -4.014724)
			(end -4.549902 -4.549902)
			(stroke
				(width 0.1524)
				(type default)
			)
			(layer "F.SilkS")
		)
		(fp_line
			(start 4.549902 4.014724)
			(end 4.549902 4.549902)
			(stroke
				(width 0.1524)
				(type default)
			)
			(layer "F.SilkS")
		)
		(fp_line
			(start 4.549902 4.549902)
			(end 4.014724 4.549902)
			(stroke
				(width 0.1524)
				(type default)
			)
			(layer "F.SilkS")
		)
		(fp_line
			(start -4.014724 4.549902)
			(end -4.549902 4.549902)
			(stroke
				(width 0.1524)
				(type default)
			)
			(layer "F.SilkS")
		)
		(fp_line
			(start -4.549902 4.549902)
			(end -4.549902 4.014724)
			(stroke
				(width 0.1524)
				(type default)
			)
			(layer "F.SilkS")
		)
		(fp_poly
			(pts
				(xy -5.134102 -4.041902) (xy -4.549902 -4.041902) (xy -4.549902 -4.626102) (xy -5.134102 -4.626102)
			)
			(stroke
				(width 0)
				(type default)
			)
			(fill yes)
			(layer "F.SilkS")
		)
		(fp_line
			(start 4.549902 -4.549902)
			(end 4.549902 4.549902)
			(stroke
				(width 0.1)
				(type default)
			)
			(layer "F.Fab")
		)
		(fp_line
			(start -4.549902 -4.549902)
			(end 4.549902 -4.549902)
			(stroke
				(width 0.1)
				(type default)
			)
			(layer "F.Fab")
		)
		(fp_line
			(start 4.549902 4.549902)
			(end -4.549902 4.549902)
			(stroke
				(width 0.1)
				(type default)
			)
			(layer "F.Fab")
		)
		(fp_line
			(start -4.549902 4.549902)
			(end -4.549902 -4.549902)
			(stroke
				(width 0.1)
				(type default)
			)
			(layer "F.Fab")
		)
		(fp_poly
			(pts
				(xy -5.134102 -4.041902) (xy -4.549902 -4.041902) (xy -4.549902 -4.626102) (xy -5.134102 -4.626102)
			)
			(stroke
				(width 0)
				(type default)
			)
			(fill yes)
			(layer "F.Fab")
		)
		(pad "1" smd circle
			(at -4.400042 -3.750056)
			(size 0 0)
			(layers "F.Cu" "F.Mask" "F.Paste")
			(net "USB_HUB2_TI_USB_DP_DN1_MRP_CFG_STRAP")
		)
		(pad "2" smd circle
			(at -4.400042 -3.24993)
			(size 0 0)
			(layers "F.Cu" "F.Mask" "F.Paste")
			(net "Net_10829")
		)
		(pad "3" smd circle
			(at -4.400042 -2.750058)
			(size 0 0)
			(layers "F.Cu" "F.Mask" "F.Paste")
			(net "Net_10820")
		)
		(pad "4" smd circle
			(at -4.400042 -2.249932)
			(size 0 0)
			(layers "F.Cu" "F.Mask" "F.Paste")
			(net "Net_10823")
		)
		(pad "5" smd circle
			(at -4.400042 -1.75006)
			(size 0 0)
			(layers "F.Cu" "F.Mask" "F.Paste")
			(net "USB_HUB2_TI_VDD_MRP_USB3DN_TXDM1")
		)
		(pad "6" smd circle
			(at -4.400042 -1.249934)
			(size 0 0)
			(layers "F.Cu" "F.Mask" "F.Paste")
			(net "USB_HUB2_TI_USB_SSRXP_DN1_MRP_VDD12")
		)
		(pad "7" smd circle
			(at -4.400042 -0.750062)
			(size 0 0)
			(layers "F.Cu" "F.Mask" "F.Paste")
			(net "Net_10826")
		)
		(pad "8" smd circle
			(at -4.400042 -0.249936)
			(size 0 0)
			(layers "F.Cu" "F.Mask" "F.Paste")
			(net "USB_HUB2_TI_VDD_MRP_USB3DN_RXDM1")
		)
		(pad "9" smd circle
			(at -4.400042 0.249936)
			(size 0 0)
			(layers "F.Cu" "F.Mask" "F.Paste")
			(net "USB2_CPU0_P0_HUB2_R_DP")
		)
		(pad "10" smd circle
			(at -4.400042 0.750062)
			(size 0 0)
			(layers "F.Cu" "F.Mask" "F.Paste")
			(net "USB2_CPU0_P0_HUB2_R_DN")
		)
		(pad "11" smd circle
			(at -4.400042 1.249934)
			(size 0 0)
			(layers "F.Cu" "F.Mask" "F.Paste")
			(net "USB3_CPU0_BMC_HUB2_TX_DP")
		)
		(pad "12" smd circle
			(at -4.400042 1.75006)
			(size 0 0)
			(layers "F.Cu" "F.Mask" "F.Paste")
			(net "USB3_CPU0_BMC_HUB2_TX_DN")
		)
		(pad "13" smd circle
			(at -4.400042 2.249932)
			(size 0 0)
			(layers "F.Cu" "F.Mask" "F.Paste")
			(net "P1V2_CPU0_USB2_DVDD12")
		)
		(pad "14" smd circle
			(at -4.400042 2.750058)
			(size 0 0)
			(layers "F.Cu" "F.Mask" "F.Paste")
			(net "USB3_CPU0_BMC_RX_C2_DP")
		)
		(pad "15" smd circle
			(at -4.400042 3.24993)
			(size 0 0)
			(layers "F.Cu" "F.Mask" "F.Paste")
			(net "USB3_CPU0_BMC_RX_C2_DN")
		)
		(pad "16" smd circle
			(at -4.400042 3.750056)
			(size 0 0)
			(layers "F.Cu" "F.Mask" "F.Paste")
			(net "USB_HUB2_TI_VDD33_MRP_PROG_FUNC7")
		)
		(pad "17" smd circle
			(at -3.750056 4.400042 90)
			(size 0 0)
			(layers "F.Cu" "F.Mask" "F.Paste")
			(net "USB_HUB2_TI_USB_DP_DN3_MRP_VDD12")
		)
		(pad "18" smd circle
			(at -3.24993 4.400042 90)
			(size 0 0)
			(layers "F.Cu" "F.Mask" "F.Paste")
			(net "USB_HUB2_TI_USB_DM_DN3_MRP_VDD33")
		)
		(pad "19" smd circle
			(at -2.750058 4.400042 90)
			(size 0 0)
			(layers "F.Cu" "F.Mask" "F.Paste")
			(net "Net_10819")
		)
		(pad "20" smd circle
			(at -2.249932 4.400042 90)
			(size 0 0)
			(layers "F.Cu" "F.Mask" "F.Paste")
			(net "Net_10822")
		)
		(pad "21" smd circle
			(at -1.75006 4.400042 90)
			(size 0 0)
			(layers "F.Cu" "F.Mask" "F.Paste")
			(net "USB_HUB2_TI_VDD_MRP_USB3DN_TXDP3")
		)
		(pad "22" smd circle
			(at -1.249934 4.400042 90)
			(size 0 0)
			(layers "F.Cu" "F.Mask" "F.Paste")
			(net "Net_10825")
		)
		(pad "23" smd circle
			(at -0.750062 4.400042 90)
			(size 0 0)
			(layers "F.Cu" "F.Mask" "F.Paste")
			(net "USB_HUB2_TI_USB_SSRXM_DN3_MRP_VDD12")
		)
		(pad "24" smd circle
			(at -0.249936 4.400042 90)
			(size 0 0)
			(layers "F.Cu" "F.Mask" "F.Paste")
			(net "Net_10827")
		)
		(pad "25" smd circle
			(at 0.249936 4.400042 90)
			(size 0 0)
			(layers "F.Cu" "F.Mask" "F.Paste")
			(net "Net_10828")
		)
		(pad "26" smd circle
			(at 0.750062 4.400042 90)
			(size 0 0)
			(layers "F.Cu" "F.Mask" "F.Paste")
			(net "Net_10818")
		)
		(pad "27" smd circle
			(at 1.249934 4.400042 90)
			(size 0 0)
			(layers "F.Cu" "F.Mask" "F.Paste")
			(net "Net_10821")
		)
		(pad "28" smd circle
			(at 1.75006 4.400042 90)
			(size 0 0)
			(layers "F.Cu" "F.Mask" "F.Paste")
			(net "USB_HUB2_TI_VDD_MRP_USB3DN_TXDP4")
		)
		(pad "29" smd circle
			(at 2.249932 4.400042 90)
			(size 0 0)
			(layers "F.Cu" "F.Mask" "F.Paste")
			(net "Net_10824")
		)
		(pad "30" smd circle
			(at 2.750058 4.400042 90)
			(size 0 0)
			(layers "F.Cu" "F.Mask" "F.Paste")
			(net "USB_HUB2_TI_USB_SSRXM_DN4_MRP_VDD12")
		)
		(pad "31" smd circle
			(at 3.24993 4.400042 90)
			(size 0 0)
			(layers "F.Cu" "F.Mask" "F.Paste")
			(net "USB_HUB2_TI_VDD_MRP_USB3DN_RXDP4")
		)
		(pad "32" smd circle
			(at 3.750056 4.400042 90)
			(size 0 0)
			(layers "F.Cu" "F.Mask" "F.Paste")
			(net "Net_10830")
		)
		(pad "33" smd circle
			(at 4.400042 3.750056)
			(size 0 0)
			(layers "F.Cu" "F.Mask" "F.Paste")
			(net "USB_HUB2_TI_PWRCTL3_MRP_VDD33")
		)
		(pad "34" smd circle
			(at 4.400042 3.24993)
			(size 0 0)
			(layers "F.Cu" "F.Mask" "F.Paste")
			(net "USB_HUB2_TI_VDD33_MRP_PRT_CTL4_GANGPWR")
		)
		(pad "35" smd circle
			(at 4.400042 2.750058)
			(size 0 0)
			(layers "F.Cu" "F.Mask" "F.Paste")
			(net "USB_HUB2_TI_PWRCTL2_MRP_VDD12")
		)
		(pad "36" smd circle
			(at 4.400042 2.249932)
			(size 0 0)
			(layers "F.Cu" "F.Mask" "F.Paste")
			(net "Net_10831")
		)
		(pad "37" smd circle
			(at 4.400042 1.75006)
			(size 0 0)
			(layers "F.Cu" "F.Mask" "F.Paste")
			(net "SMB_USB_HUB2_TI_SDA_MRP_PRT_CTL2")
		)
		(pad "38" smd circle
			(at 4.400042 1.249934)
			(size 0 0)
			(layers "F.Cu" "F.Mask" "F.Paste")
			(net "SMB_USB_HUB2_TI_SCL_MRP_PRT_CTL1")
		)
		(pad "39" smd circle
			(at 4.400042 0.750062)
			(size 0 0)
			(layers "F.Cu" "F.Mask" "F.Paste")
			(net "USB_HUB2_TI_SMBUSZ_MRP_PROG_FUNC2")
		)
		(pad "40" smd circle
			(at 4.400042 0.249936)
			(size 0 0)
			(layers "F.Cu" "F.Mask" "F.Paste")
			(net "USB_HUB2_TI_FULLPWRMGMTZ_MRP_PROG_FUNC3")
		)
		(pad "41" smd circle
			(at 4.400042 -0.249936)
			(size 0 0)
			(layers "F.Cu" "F.Mask" "F.Paste")
			(net "USB_HUB2_TI_PWRCTL_POL_MRP_VBUS_DET")
		)
		(pad "42" smd circle
			(at 4.400042 -0.750062)
			(size 0 0)
			(layers "F.Cu" "F.Mask" "F.Paste")
			(net "USB_HUB2_TI_GANGED_MRP_I2C_SLV_CFG0")
		)
		(pad "43" smd circle
			(at 4.400042 -1.249934)
			(size 0 0)
			(layers "F.Cu" "F.Mask" "F.Paste")
			(net "USB_HUB2_TI_OVERCUR4_MRP_I2C_SLV_CFG1")
		)
		(pad "44" smd circle
			(at 4.400042 -1.75006)
			(size 0 0)
			(layers "F.Cu" "F.Mask" "F.Paste")
			(net "USB_HUB2_TI_OVERCUR3_MRP_CFG_BC_EN")
		)
		(pad "45" smd circle
			(at 4.400042 -2.249932)
			(size 0 0)
			(layers "F.Cu" "F.Mask" "F.Paste")
			(net "USB_HUB2_TI_HS_SUSPEND_MRP_CFG_NON_REM")
		)
		(pad "46" smd circle
			(at 4.400042 -2.750058)
			(size 0 0)
			(layers "F.Cu" "F.Mask" "F.Paste")
			(net "USB_HUB2_TI_OVERCUR1_MRP_PROG_FUNC4")
		)
		(pad "47" smd circle
			(at 4.400042 -3.24993)
			(size 0 0)
			(layers "F.Cu" "F.Mask" "F.Paste")
			(net "USB_HUB2_TI_OVERCUR2_MRP_PROG_FUNC5")
		)
		(pad "48" smd circle
			(at 4.400042 -3.750056)
			(size 0 0)
			(layers "F.Cu" "F.Mask" "F.Paste")
			(net "USB_HUB2_TI_USB_VBUS_MRP_RESET_N")
		)
		(pad "49" smd circle
			(at 3.750056 -4.400042 90)
			(size 0 0)
			(layers "F.Cu" "F.Mask" "F.Paste")
			(net "USB_HUB2_TI_TEST_MRP_PROG_FUNC6")
		)
		(pad "50" smd circle
			(at 3.24993 -4.400042 90)
			(size 0 0)
			(layers "F.Cu" "F.Mask" "F.Paste")
			(net "USB_HUB2_TI_GRSTZ_MRP_PROG_FUNC1")
		)
		(pad "51" smd circle
			(at 2.750058 -4.400042 90)
			(size 0 0)
			(layers "F.Cu" "F.Mask" "F.Paste")
			(net "P1V2_CPU0_USB2_DVDD12")
		)
		(pad "52" smd circle
			(at 2.249932 -4.400042 90)
			(size 0 0)
			(layers "F.Cu" "F.Mask" "F.Paste")
			(net "P3V3_AUX_CPU0_USB2_AVDD33")
		)
		(pad "53" smd circle
			(at 1.75006 -4.400042 90)
			(size 0 0)
			(layers "F.Cu" "F.Mask" "F.Paste")
			(net "USB2_CPU0_P0_R2_DP")
		)
		(pad "54" smd circle
			(at 1.249934 -4.400042 90)
			(size 0 0)
			(layers "F.Cu" "F.Mask" "F.Paste")
			(net "USB2_CPU0_P0_R2_DN")
		)
		(pad "55" smd circle
			(at 0.750062 -4.400042 90)
			(size 0 0)
			(layers "F.Cu" "F.Mask" "F.Paste")
			(net "USB3_CPU0_BMC_RX_HUB2_DP")
		)
		(pad "56" smd circle
			(at 0.249936 -4.400042 90)
			(size 0 0)
			(layers "F.Cu" "F.Mask" "F.Paste")
			(net "USB3_CPU0_BMC_RX_HUB2_DN")
		)
		(pad "57" smd circle
			(at -0.249936 -4.400042 90)
			(size 0 0)
			(layers "F.Cu" "F.Mask" "F.Paste")
			(net "P1V2_CPU0_USB2_DVDD12")
		)
		(pad "58" smd circle
			(at -0.750062 -4.400042 90)
			(size 0 0)
			(layers "F.Cu" "F.Mask" "F.Paste")
			(net "USB3_CPU0_BMC_TX_C2_DP")
		)
		(pad "59" smd circle
			(at -1.249934 -4.400042 90)
			(size 0 0)
			(layers "F.Cu" "F.Mask" "F.Paste")
			(net "USB3_CPU0_BMC_TX_C2_DN")
		)
		(pad "60" smd circle
			(at -1.75006 -4.400042 90)
			(size 0 0)
			(layers "F.Cu" "F.Mask" "F.Paste")
			(net "USB_HUB2_TI_NC_MRP_ATEST")
		)
		(pad "61" smd circle
			(at -2.249932 -4.400042 90)
			(size 0 0)
			(layers "F.Cu" "F.Mask" "F.Paste")
			(net "XTAL_USB_CPU0_HUB2_XOUT")
		)
		(pad "62" smd circle
			(at -2.750058 -4.400042 90)
			(size 0 0)
			(layers "F.Cu" "F.Mask" "F.Paste")
			(net "XTAL_USB_CPU0_HUB2_XIN")
		)
		(pad "63" smd circle
			(at -3.24993 -4.400042 90)
			(size 0 0)
			(layers "F.Cu" "F.Mask" "F.Paste")
			(net "P3V3_AUX_CPU0_USB2_AVDD33")
		)
		(pad "64" smd circle
			(at -3.750056 -4.400042 90)
			(size 0 0)
			(layers "F.Cu" "F.Mask" "F.Paste")
			(net "USB_HUB2_TI_USB_R1_MRP_RBIAS")
		)
		(pad "TH" smd circle
			(at 0 0 90)
			(size 0 0)
			(layers "F.Cu" "F.Mask" "F.Paste")
			(net "GND")
		)
		(zone
			(layer "F.Cu")
			(hatch none 0.5)
			(connect_pads
				(clearance 0)
			)
			(min_thickness 0.25)
			(keepout
				(tracks not_allowed)
				(vias allowed)
				(pads allowed)
				(copperpour not_allowed)
				(footprints allowed)
			)
			(placement
				(enabled no)
				(sheetname "")
			)
			(fill
				(thermal_gap 0.5)
				(thermal_bridge_width 0.5)
				(island_removal_mode 0)
			)
			(polygon
				(pts
					(xy 116.83746 -27.459178) (xy 112.82426 -27.459178) (xy 112.82426 -28.446984)
					(arc
						(start 115.748816 -28.446984)
						(mid 115.820119 -28.476519)
						(end 115.849654 -28.547822)
					)
					(arc
						(start 115.849654 -34.447734)
						(mid 115.820119 -34.519037)
						(end 115.748816 -34.548572)
					)
					(arc
						(start 109.848904 -34.548572)
						(mid 109.777601 -34.519037)
						(end 109.748066 -34.447734)
					)
					(arc
						(start 109.748066 -28.547822)
						(mid 109.777601 -28.476519)
						(end 109.848904 -28.446984)
					)
					(xy 112.77346 -28.446984) (xy 112.79886 -28.446984) (xy 112.79886 -27.459178) (xy 112.77346 -27.459178)
					(xy 108.76026 -27.459178) (xy 108.76026 -35.536378) (xy 116.83746 -35.536378)
				)
			)
		)
	)
	(footprint ""
		(layer "F.Cu")
		(at 406.475946 -136.231376 180)
		(property "Reference" "R2346"
			(at 0 0 180)
			(layer "F.SilkS")
			(hide yes)
			(effects
				(font
					(size 1.27 1.27)
				)
			)
		)
		(property "Value" ""
			(at 0 0 180)
			(layer "F.Fab")
			(effects
				(font
					(size 1.27 1.27)
				)
			)
		)
		(duplicate_pad_numbers_are_jumpers no)
		(fp_line
			(start 0.7874 0.4064)
			(end -0.7874 0.4064)
			(stroke
				(width 0.1524)
				(type default)
			)
			(layer "F.SilkS")
		)
		(fp_line
			(start 0.7874 -0.4064)
			(end 0.7874 0.4064)
			(stroke
				(width 0.1524)
				(type default)
			)
			(layer "F.SilkS")
		)
		(fp_line
			(start -0.7874 0.4064)
			(end -0.7874 -0.4064)
			(stroke
				(width 0.1524)
				(type default)
			)
			(layer "F.SilkS")
		)
		(fp_line
			(start -0.7874 -0.4064)
			(end 0.7874 -0.4064)
			(stroke
				(width 0.1524)
				(type default)
			)
			(layer "F.SilkS")
		)
		(fp_line
			(start 0.67945 0.3048)
			(end 0.120396 0.3048)
			(stroke
				(width 0.1)
				(type default)
			)
			(layer "F.Fab")
		)
		(fp_line
			(start 0.67945 -0.3048)
			(end 0.67945 0.3048)
			(stroke
				(width 0.1)
				(type default)
			)
			(layer "F.Fab")
		)
		(fp_line
			(start 0.12065 -0.2794)
			(end 0.12065 -0.3048)
			(stroke
				(width 0.1)
				(type default)
			)
			(layer "F.Fab")
		)
		(fp_line
			(start 0.12065 -0.3048)
			(end 0.67945 -0.3048)
			(stroke
				(width 0.1)
				(type default)
			)
			(layer "F.Fab")
		)
		(fp_line
			(start 0.120396 0.3048)
			(end 0.120396 0.2794)
			(stroke
				(width 0.1)
				(type default)
			)
			(layer "F.Fab")
		)
		(fp_line
			(start 0.120396 0.2794)
			(end -0.12065 0.2794)
			(stroke
				(width 0.1)
				(type default)
			)
			(layer "F.Fab")
		)
		(fp_line
			(start -0.12065 0.3048)
			(end -0.67945 0.3048)
			(stroke
				(width 0.1)
				(type default)
			)
			(layer "F.Fab")
		)
		(fp_line
			(start -0.12065 0.2794)
			(end -0.12065 0.3048)
			(stroke
				(width 0.1)
				(type default)
			)
			(layer "F.Fab")
		)
		(fp_line
			(start -0.12065 -0.2794)
			(end 0.12065 -0.2794)
			(stroke
				(width 0.1)
				(type default)
			)
			(layer "F.Fab")
		)
		(fp_line
			(start -0.12065 -0.305054)
			(end -0.12065 -0.2794)
			(stroke
				(width 0.1)
				(type default)
			)
			(layer "F.Fab")
		)
		(fp_line
			(start -0.67945 0.3048)
			(end -0.67945 -0.305054)
			(stroke
				(width 0.1)
				(type default)
			)
			(layer "F.Fab")
		)
		(fp_line
			(start -0.67945 -0.305054)
			(end -0.12065 -0.305054)
			(stroke
				(width 0.1)
				(type default)
			)
			(layer "F.Fab")
		)
		(pad "1" smd circle
			(at -0.40005 0 180)
			(size 0 0)
			(layers "F.Cu" "F.Mask" "F.Paste")
			(net "P3V3_AUX")
		)
		(pad "2" smd circle
			(at 0.40005 0 180)
			(size 0 0)
			(layers "F.Cu" "F.Mask" "F.Paste")
			(net "PWRGD_P5V_AUX_R2")
		)
	)
	(footprint ""
		(layer "F.Cu")
		(at 82.706718 -21.016722 90)
		(property "Reference" "R3816"
			(at 0 0 90)
			(layer "F.SilkS")
			(hide yes)
			(effects
				(font
					(size 1.27 1.27)
				)
			)
		)
		(property "Value" ""
			(at 0 0 90)
			(layer "F.Fab")
			(effects
				(font
					(size 1.27 1.27)
				)
			)
		)
		(duplicate_pad_numbers_are_jumpers no)
		(fp_line
			(start 0.7874 -0.4064)
			(end 0.7874 0.4064)
			(stroke
				(width 0.1524)
				(type default)
			)
			(layer "F.SilkS")
		)
		(fp_line
			(start -0.7874 -0.4064)
			(end 0.7874 -0.4064)
			(stroke
				(width 0.1524)
				(type default)
			)
			(layer "F.SilkS")
		)
		(fp_line
			(start 0.7874 0.4064)
			(end -0.7874 0.4064)
			(stroke
				(width 0.1524)
				(type default)
			)
			(layer "F.SilkS")
		)
		(fp_line
			(start -0.7874 0.4064)
			(end -0.7874 -0.4064)
			(stroke
				(width 0.1524)
				(type default)
			)
			(layer "F.SilkS")
		)
		(fp_line
			(start -0.12065 -0.305054)
			(end -0.12065 -0.2794)
			(stroke
				(width 0.1)
				(type default)
			)
			(layer "F.Fab")
		)
		(fp_line
			(start -0.67945 -0.305054)
			(end -0.12065 -0.305054)
			(stroke
				(width 0.1)
				(type default)
			)
			(layer "F.Fab")
		)
		(fp_line
			(start 0.67945 -0.3048)
			(end 0.67945 0.3048)
			(stroke
				(width 0.1)
				(type default)
			)
			(layer "F.Fab")
		)
		(fp_line
			(start 0.12065 -0.3048)
			(end 0.67945 -0.3048)
			(stroke
				(width 0.1)
				(type default)
			)
			(layer "F.Fab")
		)
		(fp_line
			(start 0.12065 -0.2794)
			(end 0.12065 -0.3048)
			(stroke
				(width 0.1)
				(type default)
			)
			(layer "F.Fab")
		)
		(fp_line
			(start -0.12065 -0.2794)
			(end 0.12065 -0.2794)
			(stroke
				(width 0.1)
				(type default)
			)
			(layer "F.Fab")
		)
		(fp_line
			(start 0.120396 0.2794)
			(end -0.12065 0.2794)
			(stroke
				(width 0.1)
				(type default)
			)
			(layer "F.Fab")
		)
		(fp_line
			(start -0.12065 0.2794)
			(end -0.12065 0.3048)
			(stroke
				(width 0.1)
				(type default)
			)
			(layer "F.Fab")
		)
		(fp_line
			(start 0.67945 0.3048)
			(end 0.120396 0.3048)
			(stroke
				(width 0.1)
				(type default)
			)
			(layer "F.Fab")
		)
		(fp_line
			(start 0.120396 0.3048)
			(end 0.120396 0.2794)
			(stroke
				(width 0.1)
				(type default)
			)
			(layer "F.Fab")
		)
		(fp_line
			(start -0.12065 0.3048)
			(end -0.67945 0.3048)
			(stroke
				(width 0.1)
				(type default)
			)
			(layer "F.Fab")
		)
		(fp_line
			(start -0.67945 0.3048)
			(end -0.67945 -0.305054)
			(stroke
				(width 0.1)
				(type default)
			)
			(layer "F.Fab")
		)
		(pad "1" smd circle
			(at -0.40005 0 90)
			(size 0 0)
			(layers "F.Cu" "F.Mask" "F.Paste")
			(net "P3V3_AUX")
		)
		(pad "2" smd circle
			(at 0.40005 0 90)
			(size 0 0)
			(layers "F.Cu" "F.Mask" "F.Paste")
			(net "P12V_OCP_FAULT_2")
		)
	)
	(footprint ""
		(layer "F.Cu")
		(at 210.204558 -401.920202 180)
		(property "Reference" "PU288"
			(at 2.820924 -5.00888 90)
			(unlocked yes)
			(layer "F.SilkS")
			(effects
				(font
					(size 0.7874 0.5842)
					(thickness 0.1524)
				)
			)
		)
		(property "Value" ""
			(at 0 0 180)
			(layer "F.Fab")
			(effects
				(font
					(size 1.27 1.27)
				)
			)
		)
		(duplicate_pad_numbers_are_jumpers no)
		(fp_line
			(start 2.567686 2.567686)
			(end 2.567686 -2.567686)
			(stroke
				(width 0.1524)
				(type default)
			)
			(layer "F.SilkS")
		)
		(fp_line
			(start 2.567686 -2.567686)
			(end -2.567686 -2.567686)
			(stroke
				(width 0.1524)
				(type default)
			)
			(layer "F.SilkS")
		)
		(fp_line
			(start -2.567686 2.567686)
			(end 2.567686 2.567686)
			(stroke
				(width 0.1524)
				(type default)
			)
			(layer "F.SilkS")
		)
		(fp_line
			(start -2.567686 -2.567686)
			(end -2.567686 2.567686)
			(stroke
				(width 0.1524)
				(type default)
			)
			(layer "F.SilkS")
		)
		(fp_poly
			(pts
				(xy -2.632456 -2.13233) (xy -3.709924 -2.491486) (xy -2.991612 -3.209798)
			)
			(stroke
				(width 0)
				(type default)
			)
			(fill yes)
			(layer "F.SilkS")
		)
		(fp_line
			(start 2.549906 2.549906)
			(end 2.549906 -2.549906)
			(stroke
				(width 0.1)
				(type default)
			)
			(layer "F.Fab")
		)
		(fp_line
			(start 2.549906 -2.549906)
			(end -2.549906 -2.549906)
			(stroke
				(width 0.1)
				(type default)
			)
			(layer "F.Fab")
		)
		(fp_line
			(start -2.549906 2.549906)
			(end 2.549906 2.549906)
			(stroke
				(width 0.1)
				(type default)
			)
			(layer "F.Fab")
		)
		(fp_line
			(start -2.549906 -2.549906)
			(end -2.549906 2.549906)
			(stroke
				(width 0.1)
				(type default)
			)
			(layer "F.Fab")
		)
		(fp_poly
			(pts
				(xy -3.806698 -2.25806) (xy -3.806698 -1.24206) (xy -2.790698 -1.75006)
			)
			(stroke
				(width 0)
				(type default)
			)
			(fill yes)
			(layer "F.Fab")
		)
		(pad "1" smd rect
			(at -2.250186 -1.75006 270)
			(size 0.254 0.3556)
			(layers "F.Cu" "F.Mask" "F.Paste")
			(net "P12V_AUX")
		)
		(pad "2" smd rect
			(at -2.237486 -1.249934 270)
			(size 0.254 0.381)
			(layers "F.Cu" "F.Mask" "F.Paste")
			(net "P12V_AUX")
		)
		(pad "3" smd rect
			(at -2.237486 -0.750062 270)
			(size 0.254 0.381)
			(layers "F.Cu" "F.Mask" "F.Paste")
			(net "HSC_D_OC_2")
		)
		(pad "4" smd rect
			(at -2.237486 -0.249936 270)
			(size 0.254 0.381)
			(layers "F.Cu" "F.Mask" "F.Paste")
			(net "HSC_ON")
		)
		(pad "5" smd rect
			(at -2.237486 0.249936 270)
			(size 0.254 0.381)
			(layers "F.Cu" "F.Mask" "F.Paste")
			(net "HSC_FAULT")
		)
		(pad "6" smd rect
			(at -2.237486 0.750062 270)
			(size 0.254 0.381)
			(layers "F.Cu" "F.Mask" "F.Paste")
			(net "HSC_FLT_TYPE_2")
		)
		(pad "7" smd rect
			(at -2.237486 1.249934 270)
			(size 0.254 0.381)
			(layers "F.Cu" "F.Mask" "F.Paste")
			(net "HSC_NC1_2")
		)
		(pad "8" smd rect
			(at -2.250186 1.75006 270)
			(size 0.254 0.3556)
			(layers "F.Cu" "F.Mask" "F.Paste")
			(net "HSC_MODE_2")
		)
		(pad "9" smd rect
			(at -1.75006 2.250186 180)
			(size 0.254 0.3556)
			(layers "F.Cu" "F.Mask" "F.Paste")
			(net "P12V_PSU")
		)
		(pad "10" smd rect
			(at -1.249934 2.237486 180)
			(size 0.254 0.381)
			(layers "F.Cu" "F.Mask" "F.Paste")
			(net "P12V_PSU")
		)
		(pad "11" smd rect
			(at -0.750062 2.237486 180)
			(size 0.254 0.381)
			(layers "F.Cu" "F.Mask" "F.Paste")
			(net "P12V_PSU")
		)
		(pad "12" smd rect
			(at -0.249936 2.237486 180)
			(size 0.254 0.381)
			(layers "F.Cu" "F.Mask" "F.Paste")
			(net "P12V_PSU")
		)
		(pad "13" smd rect
			(at 0.249936 2.237486 180)
			(size 0.254 0.381)
			(layers "F.Cu" "F.Mask" "F.Paste")
			(net "P12V_PSU")
		)
		(pad "14" smd rect
			(at 0.750062 2.237486 180)
			(size 0.254 0.381)
			(layers "F.Cu" "F.Mask" "F.Paste")
			(net "P12V_PSU")
		)
		(pad "15" smd rect
			(at 1.249934 2.237486 180)
			(size 0.254 0.381)
			(layers "F.Cu" "F.Mask" "F.Paste")
			(net "P12V_PSU")
		)
		(pad "16" smd rect
			(at 1.75006 2.250186 180)
			(size 0.254 0.3556)
			(layers "F.Cu" "F.Mask" "F.Paste")
			(net "P12V_PSU")
		)
		(pad "17" smd rect
			(at 2.250186 1.75006 270)
			(size 0.254 0.3556)
			(layers "F.Cu" "F.Mask" "F.Paste")
			(net "HSC_SCREF_2")
		)
		(pad "18" smd rect
			(at 2.237486 1.249934 270)
			(size 0.254 0.381)
			(layers "F.Cu" "F.Mask" "F.Paste")
			(net "HSC_VTEMP")
		)
		(pad "19" smd rect
			(at 2.237486 0.750062 270)
			(size 0.254 0.381)
			(layers "F.Cu" "F.Mask" "F.Paste")
			(net "HSC_SS")
		)
		(pad "20" smd rect
			(at 2.237486 0.249936 270)
			(size 0.254 0.381)
			(layers "F.Cu" "F.Mask" "F.Paste")
			(net "AGND_HSC")
		)
		(pad "21" smd rect
			(at 2.237486 -0.249936 270)
			(size 0.254 0.381)
			(layers "F.Cu" "F.Mask" "F.Paste")
			(net "HSC_VDD_R_2")
		)
		(pad "22" smd rect
			(at 2.237486 -0.750062 270)
			(size 0.254 0.381)
			(layers "F.Cu" "F.Mask" "F.Paste")
			(net "HSC_IMON")
		)
		(pad "23" smd rect
			(at 2.237486 -1.249934 270)
			(size 0.254 0.381)
			(layers "F.Cu" "F.Mask" "F.Paste")
			(net "HSC_CS_2")
		)
		(pad "24" smd rect
			(at 2.250186 -1.75006 270)
			(size 0.254 0.3556)
			(layers "F.Cu" "F.Mask" "F.Paste")
			(net "HSC_OCREF")
		)
		(pad "25" smd rect
			(at 1.75006 -2.250186 180)
			(size 0.254 0.3556)
			(layers "F.Cu" "F.Mask" "F.Paste")
			(net "P12V_AUX")
		)
		(pad "26" smd rect
			(at 1.249934 -2.237486 180)
			(size 0.254 0.381)
			(layers "F.Cu" "F.Mask" "F.Paste")
			(net "P12V_AUX")
		)
		(pad "27" smd rect
			(at 0.750062 -2.237486 180)
			(size 0.254 0.381)
			(layers "F.Cu" "F.Mask" "F.Paste")
			(net "P12V_AUX")
		)
		(pad "28" smd rect
			(at 0.249936 -2.237486 180)
			(size 0.254 0.381)
			(layers "F.Cu" "F.Mask" "F.Paste")
			(net "P12V_AUX")
		)
		(pad "29" smd rect
			(at -0.249936 -2.237486 180)
			(size 0.254 0.381)
			(layers "F.Cu" "F.Mask" "F.Paste")
			(net "P12V_AUX")
		)
		(pad "30" smd rect
			(at -0.750062 -2.237486 180)
			(size 0.254 0.381)
			(layers "F.Cu" "F.Mask" "F.Paste")
			(net "P12V_AUX")
		)
		(pad "31" smd rect
			(at -1.249934 -2.237486 180)
			(size 0.254 0.381)
			(layers "F.Cu" "F.Mask" "F.Paste")
			(net "P12V_AUX")
		)
		(pad "32" smd rect
			(at -1.75006 -2.250186 180)
			(size 0.254 0.3556)
			(layers "F.Cu" "F.Mask" "F.Paste")
			(net "P12V_AUX")
		)
		(pad "33" smd rect
			(at 0 0 180)
			(size 3.4036 3.4036)
			(layers "F.Cu" "F.Mask" "F.Paste")
			(net "P12V_PSU")
		)
		(zone
			(layer "F.Cu")
			(hatch none 0.5)
			(connect_pads
				(clearance 0)
			)
			(min_thickness 0.25)
			(keepout
				(tracks not_allowed)
				(vias allowed)
				(pads allowed)
				(copperpour not_allowed)
				(footprints allowed)
			)
			(placement
				(enabled no)
				(sheetname "")
			)
			(fill
				(thermal_gap 0.5)
				(thermal_bridge_width 0.5)
				(island_removal_mode 0)
			)
			(polygon
				(pts
					(xy 208.182972 -403.58822) (xy 208.451958 -403.58822) (xy 208.451958 -400.167602) (xy 211.957158 -400.167602)
					(xy 211.957158 -402.428202) (xy 212.200744 -402.428202) (xy 212.200744 -400.472402) (xy 212.226144 -400.472402)
					(xy 212.226144 -399.898616) (xy 211.652358 -399.898616) (xy 211.652358 -399.924016) (xy 208.756758 -399.924016)
					(xy 208.756758 -399.898616) (xy 208.182972 -399.898616) (xy 208.182972 -400.472402) (xy 208.208372 -400.472402)
					(xy 208.208372 -403.368002) (xy 208.182972 -403.368002)
				)
			)
		)
	)
	(footprint ""
		(layer "F.Cu")
		(at 288.970212 -426.357542)
		(property "Reference" "U176"
			(at -0.771906 -2.687574 0)
			(unlocked yes)
			(layer "F.SilkS")
			(effects
				(font
					(size 0.7874 0.5842)
					(thickness 0.1524)
				)
				(justify left)
			)
		)
		(property "Value" ""
			(at 0 0 0)
			(layer "F.Fab")
			(effects
				(font
					(size 1.27 1.27)
				)
			)
		)
		(duplicate_pad_numbers_are_jumpers no)
		(fp_line
			(start -1.3716 -1.524)
			(end -0.508 -1.524)
			(stroke
				(width 0.1524)
				(type default)
			)
			(layer "F.SilkS")
		)
		(fp_line
			(start -1.3716 1.524)
			(end -1.3716 -1.524)
			(stroke
				(width 0.1524)
				(type default)
			)
			(layer "F.SilkS")
		)
		(fp_line
			(start -0.508 -1.524)
			(end 0 -1.016)
			(stroke
				(width 0.1524)
				(type default)
			)
			(layer "F.SilkS")
		)
		(fp_line
			(start 0 -1.016)
			(end 0.508 -1.524)
			(stroke
				(width 0.1524)
				(type default)
			)
			(layer "F.SilkS")
		)
		(fp_line
			(start 0.508 -1.524)
			(end 1.3716 -1.524)
			(stroke
				(width 0.1524)
				(type default)
			)
			(layer "F.SilkS")
		)
		(fp_line
			(start 1.3716 -1.524)
			(end 1.3716 1.524)
			(stroke
				(width 0.1524)
				(type default)
			)
			(layer "F.SilkS")
		)
		(fp_line
			(start 1.3716 1.524)
			(end -1.3716 1.524)
			(stroke
				(width 0.1524)
				(type default)
			)
			(layer "F.SilkS")
		)
		(fp_poly
			(pts
				(xy -2.082292 -2.04724) (xy -1.457452 -2.04724) (xy -1.78562 -1.49352)
			)
			(stroke
				(width 0)
				(type default)
			)
			(fill yes)
			(layer "F.SilkS")
		)
		(fp_line
			(start -2.54 -1.0668)
			(end -1.5494 -1.0668)
			(stroke
				(width 0.1)
				(type default)
			)
			(layer "F.Fab")
		)
		(fp_line
			(start -2.54 1.0668)
			(end -2.54 -1.0668)
			(stroke
				(width 0.1)
				(type default)
			)
			(layer "F.Fab")
		)
		(fp_line
			(start -1.5494 -1.524)
			(end 1.5494 -1.524)
			(stroke
				(width 0.1)
				(type default)
			)
			(layer "F.Fab")
		)
		(fp_line
			(start -1.5494 -1.0668)
			(end -1.5494 -1.524)
			(stroke
				(width 0.1)
				(type default)
			)
			(layer "F.Fab")
		)
		(fp_line
			(start -1.5494 1.0668)
			(end -2.54 1.0668)
			(stroke
				(width 0.1)
				(type default)
			)
			(layer "F.Fab")
		)
		(fp_line
			(start -1.5494 1.0668)
			(end -1.5494 -1.0668)
			(stroke
				(width 0.1)
				(type default)
			)
			(layer "F.Fab")
		)
		(fp_line
			(start -1.5494 1.524)
			(end -1.5494 1.0668)
			(stroke
				(width 0.1)
				(type default)
			)
			(layer "F.Fab")
		)
		(fp_line
			(start 1.5494 -1.524)
			(end 1.5494 -1.0668)
			(stroke
				(width 0.1)
				(type default)
			)
			(layer "F.Fab")
		)
		(fp_line
			(start 1.5494 -1.0668)
			(end 1.5494 1.0668)
			(stroke
				(width 0.1)
				(type default)
			)
			(layer "F.Fab")
		)
		(fp_line
			(start 1.5494 -1.0668)
			(end 2.54 -1.0668)
			(stroke
				(width 0.1)
				(type default)
			)
			(layer "F.Fab")
		)
		(fp_line
			(start 1.5494 1.0668)
			(end 1.5494 1.524)
			(stroke
				(width 0.1)
				(type default)
			)
			(layer "F.Fab")
		)
		(fp_line
			(start 1.5494 1.524)
			(end -1.5494 1.524)
			(stroke
				(width 0.1)
				(type default)
			)
			(layer "F.Fab")
		)
		(fp_line
			(start 2.54 -1.0668)
			(end 2.54 1.0668)
			(stroke
				(width 0.1)
				(type default)
			)
			(layer "F.Fab")
		)
		(fp_line
			(start 2.54 1.0668)
			(end 1.5494 1.0668)
			(stroke
				(width 0.1)
				(type default)
			)
			(layer "F.Fab")
		)
		(fp_poly
			(pts
				(xy -3.60172 -0.719328) (xy -3.60172 -1.344168) (xy -3.048 -1.016)
			)
			(stroke
				(width 0)
				(type default)
			)
			(fill yes)
			(layer "F.Fab")
		)
		(pad "1" smd rect
			(at -2.232406 -0.975106 270)
			(size 0.3556 1.4224)
			(layers "F.Cu" "F.Mask" "F.Paste")
			(net "SMB_BMC_SWB_EN_R2")
		)
		(pad "2" smd rect
			(at -2.232406 -0.32512 270)
			(size 0.3556 1.4224)
			(layers "F.Cu" "F.Mask" "F.Paste")
			(net "I3C_BMC_SWB_BUF_R_SCL")
		)
		(pad "3" smd rect
			(at -2.232406 0.32512 270)
			(size 0.3556 1.4224)
			(layers "F.Cu" "F.Mask" "F.Paste")
			(net "I3C_BMC_SWB_R_SCL")
		)
		(pad "4" smd rect
			(at -2.232406 0.975106 270)
			(size 0.3556 1.4224)
			(layers "F.Cu" "F.Mask" "F.Paste")
			(net "GND")
		)
		(pad "5" smd rect
			(at 2.232406 0.975106 270)
			(size 0.3556 1.4224)
			(layers "F.Cu" "F.Mask" "F.Paste")
			(net "Net_10762")
		)
		(pad "6" smd rect
			(at 2.232406 0.32512 270)
			(size 0.3556 1.4224)
			(layers "F.Cu" "F.Mask" "F.Paste")
			(net "I3C_BMC_SWB_R_SDA")
		)
		(pad "7" smd rect
			(at 2.232406 -0.32512 270)
			(size 0.3556 1.4224)
			(layers "F.Cu" "F.Mask" "F.Paste")
			(net "I3C_BMC_SWB_BUF_R_SDA")
		)
		(pad "8" smd rect
			(at 2.232406 -0.975106 270)
			(size 0.3556 1.4224)
			(layers "F.Cu" "F.Mask" "F.Paste")
			(net "P3V3_AUX")
		)
	)
	(footprint ""
		(layer "F.Cu")
		(at 102.268782 -380.385828)
		(property "Reference" "C710"
			(at 0 0 0)
			(layer "F.SilkS")
			(hide yes)
			(effects
				(font
					(size 1.27 1.27)
				)
			)
		)
		(property "Value" ""
			(at 0 0 0)
			(layer "F.Fab")
			(effects
				(font
					(size 1.27 1.27)
				)
			)
		)
		(duplicate_pad_numbers_are_jumpers no)
		(fp_line
			(start -0.299974 -0.150114)
			(end 0.299974 -0.150114)
			(stroke
				(width 0.1)
				(type default)
			)
			(layer "F.Fab")
		)
		(fp_line
			(start -0.299974 0.150114)
			(end -0.299974 -0.150114)
			(stroke
				(width 0.1)
				(type default)
			)
			(layer "F.Fab")
		)
		(fp_line
			(start 0.299974 -0.150114)
			(end 0.299974 0.150114)
			(stroke
				(width 0.1)
				(type default)
			)
			(layer "F.Fab")
		)
		(fp_line
			(start 0.299974 0.150114)
			(end -0.299974 0.150114)
			(stroke
				(width 0.1)
				(type default)
			)
			(layer "F.Fab")
		)
		(pad "1" smd rect
			(at -0.2667 0)
			(size 0.3048 0.381)
			(layers "F.Cu" "F.Mask" "F.Paste")
			(net "P5E_CPU1_P1_TX_C_DN<15>")
		)
		(pad "2" smd rect
			(at 0.2667 0)
			(size 0.3048 0.381)
			(layers "F.Cu" "F.Mask" "F.Paste")
			(net "P5E_CPU1_P1_TX_DN<15>")
		)
	)
	(footprint ""
		(layer "F.Cu")
		(at 338.31022 -15.98803 90)
		(property "Reference" "R948"
			(at 0 0 90)
			(layer "F.SilkS")
			(hide yes)
			(effects
				(font
					(size 1.27 1.27)
				)
			)
		)
		(property "Value" ""
			(at 0 0 90)
			(layer "F.Fab")
			(effects
				(font
					(size 1.27 1.27)
				)
			)
		)
		(duplicate_pad_numbers_are_jumpers no)
		(fp_line
			(start 0.7874 -0.4064)
			(end 0.7874 0.4064)
			(stroke
				(width 0.1524)
				(type default)
			)
			(layer "F.SilkS")
		)
		(fp_line
			(start -0.7874 -0.4064)
			(end 0.7874 -0.4064)
			(stroke
				(width 0.1524)
				(type default)
			)
			(layer "F.SilkS")
		)
		(fp_line
			(start 0.7874 0.4064)
			(end -0.7874 0.4064)
			(stroke
				(width 0.1524)
				(type default)
			)
			(layer "F.SilkS")
		)
		(fp_line
			(start -0.7874 0.4064)
			(end -0.7874 -0.4064)
			(stroke
				(width 0.1524)
				(type default)
			)
			(layer "F.SilkS")
		)
		(fp_line
			(start -0.12065 -0.305054)
			(end -0.12065 -0.2794)
			(stroke
				(width 0.1)
				(type default)
			)
			(layer "F.Fab")
		)
		(fp_line
			(start -0.67945 -0.305054)
			(end -0.12065 -0.305054)
			(stroke
				(width 0.1)
				(type default)
			)
			(layer "F.Fab")
		)
		(fp_line
			(start 0.67945 -0.3048)
			(end 0.67945 0.3048)
			(stroke
				(width 0.1)
				(type default)
			)
			(layer "F.Fab")
		)
		(fp_line
			(start 0.12065 -0.3048)
			(end 0.67945 -0.3048)
			(stroke
				(width 0.1)
				(type default)
			)
			(layer "F.Fab")
		)
		(fp_line
			(start 0.12065 -0.2794)
			(end 0.12065 -0.3048)
			(stroke
				(width 0.1)
				(type default)
			)
			(layer "F.Fab")
		)
		(fp_line
			(start -0.12065 -0.2794)
			(end 0.12065 -0.2794)
			(stroke
				(width 0.1)
				(type default)
			)
			(layer "F.Fab")
		)
		(fp_line
			(start 0.120396 0.2794)
			(end -0.12065 0.2794)
			(stroke
				(width 0.1)
				(type default)
			)
			(layer "F.Fab")
		)
		(fp_line
			(start -0.12065 0.2794)
			(end -0.12065 0.3048)
			(stroke
				(width 0.1)
				(type default)
			)
			(layer "F.Fab")
		)
		(fp_line
			(start 0.67945 0.3048)
			(end 0.120396 0.3048)
			(stroke
				(width 0.1)
				(type default)
			)
			(layer "F.Fab")
		)
		(fp_line
			(start 0.120396 0.3048)
			(end 0.120396 0.2794)
			(stroke
				(width 0.1)
				(type default)
			)
			(layer "F.Fab")
		)
		(fp_line
			(start -0.12065 0.3048)
			(end -0.67945 0.3048)
			(stroke
				(width 0.1)
				(type default)
			)
			(layer "F.Fab")
		)
		(fp_line
			(start -0.67945 0.3048)
			(end -0.67945 -0.305054)
			(stroke
				(width 0.1)
				(type default)
			)
			(layer "F.Fab")
		)
		(pad "1" smd circle
			(at -0.40005 0 90)
			(size 0 0)
			(layers "F.Cu" "F.Mask" "F.Paste")
			(net "PU_BOOT_RDY_LED")
		)
		(pad "2" smd circle
			(at 0.40005 0 90)
			(size 0 0)
			(layers "F.Cu" "F.Mask" "F.Paste")
			(net "P3V3_AUX")
		)
	)
	(footprint ""
		(layer "F.Cu")
		(at 160.174686 -58.15965 -90)
		(property "Reference" "C2021"
			(at 0 0 270)
			(layer "F.SilkS")
			(hide yes)
			(effects
				(font
					(size 1.27 1.27)
				)
			)
		)
		(property "Value" ""
			(at 0 0 270)
			(layer "F.Fab")
			(effects
				(font
					(size 1.27 1.27)
				)
			)
		)
		(duplicate_pad_numbers_are_jumpers no)
		(fp_line
			(start -0.7874 0.4064)
			(end -0.7874 -0.4064)
			(stroke
				(width 0.1524)
				(type default)
			)
			(layer "F.SilkS")
		)
		(fp_line
			(start 0.7874 0.4064)
			(end -0.7874 0.4064)
			(stroke
				(width 0.1524)
				(type default)
			)
			(layer "F.SilkS")
		)
		(fp_line
			(start -0.7874 -0.4064)
			(end 0.7874 -0.4064)
			(stroke
				(width 0.1524)
				(type default)
			)
			(layer "F.SilkS")
		)
		(fp_line
			(start 0.7874 -0.4064)
			(end 0.7874 0.4064)
			(stroke
				(width 0.1524)
				(type default)
			)
			(layer "F.SilkS")
		)
		(fp_line
			(start -0.67945 0.3048)
			(end -0.67945 -0.305054)
			(stroke
				(width 0.1)
				(type default)
			)
			(layer "F.Fab")
		)
		(fp_line
			(start -0.12065 0.3048)
			(end -0.67945 0.3048)
			(stroke
				(width 0.1)
				(type default)
			)
			(layer "F.Fab")
		)
		(fp_line
			(start 0.120396 0.3048)
			(end 0.120396 0.2794)
			(stroke
				(width 0.1)
				(type default)
			)
			(layer "F.Fab")
		)
		(fp_line
			(start 0.67945 0.3048)
			(end 0.120396 0.3048)
			(stroke
				(width 0.1)
				(type default)
			)
			(layer "F.Fab")
		)
		(fp_line
			(start -0.12065 0.2794)
			(end -0.12065 0.3048)
			(stroke
				(width 0.1)
				(type default)
			)
			(layer "F.Fab")
		)
		(fp_line
			(start 0.120396 0.2794)
			(end -0.12065 0.2794)
			(stroke
				(width 0.1)
				(type default)
			)
			(layer "F.Fab")
		)
		(fp_line
			(start -0.12065 -0.2794)
			(end 0.12065 -0.2794)
			(stroke
				(width 0.1)
				(type default)
			)
			(layer "F.Fab")
		)
		(fp_line
			(start 0.12065 -0.2794)
			(end 0.12065 -0.3048)
			(stroke
				(width 0.1)
				(type default)
			)
			(layer "F.Fab")
		)
		(fp_line
			(start 0.12065 -0.3048)
			(end 0.67945 -0.3048)
			(stroke
				(width 0.1)
				(type default)
			)
			(layer "F.Fab")
		)
		(fp_line
			(start 0.67945 -0.3048)
			(end 0.67945 0.3048)
			(stroke
				(width 0.1)
				(type default)
			)
			(layer "F.Fab")
		)
		(fp_line
			(start -0.67945 -0.305054)
			(end -0.12065 -0.305054)
			(stroke
				(width 0.1)
				(type default)
			)
			(layer "F.Fab")
		)
		(fp_line
			(start -0.12065 -0.305054)
			(end -0.12065 -0.2794)
			(stroke
				(width 0.1)
				(type default)
			)
			(layer "F.Fab")
		)
		(pad "1" smd circle
			(at -0.40005 0 270)
			(size 0 0)
			(layers "F.Cu" "F.Mask" "F.Paste")
			(net "VSENSE_P12V_INA230_4_INP")
		)
		(pad "2" smd circle
			(at 0.40005 0 270)
			(size 0 0)
			(layers "F.Cu" "F.Mask" "F.Paste")
			(net "VSENSE_P12V_INA230_4_INN")
		)
	)
	(footprint ""
		(layer "F.Cu")
		(at 13.872464 -15.32128 90)
		(property "Reference" "R3178"
			(at 0 0 90)
			(layer "F.SilkS")
			(hide yes)
			(effects
				(font
					(size 1.27 1.27)
				)
			)
		)
		(property "Value" ""
			(at 0 0 90)
			(layer "F.Fab")
			(effects
				(font
					(size 1.27 1.27)
				)
			)
		)
		(duplicate_pad_numbers_are_jumpers no)
		(fp_line
			(start 0.7874 -0.4064)
			(end 0.7874 0.4064)
			(stroke
				(width 0.1524)
				(type default)
			)
			(layer "F.SilkS")
		)
		(fp_line
			(start -0.7874 -0.4064)
			(end 0.7874 -0.4064)
			(stroke
				(width 0.1524)
				(type default)
			)
			(layer "F.SilkS")
		)
		(fp_line
			(start 0.7874 0.4064)
			(end -0.7874 0.4064)
			(stroke
				(width 0.1524)
				(type default)
			)
			(layer "F.SilkS")
		)
		(fp_line
			(start -0.7874 0.4064)
			(end -0.7874 -0.4064)
			(stroke
				(width 0.1524)
				(type default)
			)
			(layer "F.SilkS")
		)
		(fp_line
			(start -0.12065 -0.305054)
			(end -0.12065 -0.2794)
			(stroke
				(width 0.1)
				(type default)
			)
			(layer "F.Fab")
		)
		(fp_line
			(start -0.67945 -0.305054)
			(end -0.12065 -0.305054)
			(stroke
				(width 0.1)
				(type default)
			)
			(layer "F.Fab")
		)
		(fp_line
			(start 0.67945 -0.3048)
			(end 0.67945 0.3048)
			(stroke
				(width 0.1)
				(type default)
			)
			(layer "F.Fab")
		)
		(fp_line
			(start 0.12065 -0.3048)
			(end 0.67945 -0.3048)
			(stroke
				(width 0.1)
				(type default)
			)
			(layer "F.Fab")
		)
		(fp_line
			(start 0.12065 -0.2794)
			(end 0.12065 -0.3048)
			(stroke
				(width 0.1)
				(type default)
			)
			(layer "F.Fab")
		)
		(fp_line
			(start -0.12065 -0.2794)
			(end 0.12065 -0.2794)
			(stroke
				(width 0.1)
				(type default)
			)
			(layer "F.Fab")
		)
		(fp_line
			(start 0.120396 0.2794)
			(end -0.12065 0.2794)
			(stroke
				(width 0.1)
				(type default)
			)
			(layer "F.Fab")
		)
		(fp_line
			(start -0.12065 0.2794)
			(end -0.12065 0.3048)
			(stroke
				(width 0.1)
				(type default)
			)
			(layer "F.Fab")
		)
		(fp_line
			(start 0.67945 0.3048)
			(end 0.120396 0.3048)
			(stroke
				(width 0.1)
				(type default)
			)
			(layer "F.Fab")
		)
		(fp_line
			(start 0.120396 0.3048)
			(end 0.120396 0.2794)
			(stroke
				(width 0.1)
				(type default)
			)
			(layer "F.Fab")
		)
		(fp_line
			(start -0.12065 0.3048)
			(end -0.67945 0.3048)
			(stroke
				(width 0.1)
				(type default)
			)
			(layer "F.Fab")
		)
		(fp_line
			(start -0.67945 0.3048)
			(end -0.67945 -0.305054)
			(stroke
				(width 0.1)
				(type default)
			)
			(layer "F.Fab")
		)
		(pad "1" smd circle
			(at -0.40005 0 90)
			(size 0 0)
			(layers "F.Cu" "F.Mask" "F.Paste")
			(net "USB2_P10_DP")
		)
		(pad "2" smd circle
			(at 0.40005 0 90)
			(size 0 0)
			(layers "F.Cu" "F.Mask" "F.Paste")
			(net "USB2_CPU0_P10_DP")
		)
	)
	(footprint ""
		(layer "F.Cu")
		(at 340.715346 -23.897336 -90)
		(property "Reference" "R944"
			(at 0 0 270)
			(layer "F.SilkS")
			(hide yes)
			(effects
				(font
					(size 1.27 1.27)
				)
			)
		)
		(property "Value" ""
			(at 0 0 270)
			(layer "F.Fab")
			(effects
				(font
					(size 1.27 1.27)
				)
			)
		)
		(duplicate_pad_numbers_are_jumpers no)
		(fp_line
			(start -0.7874 0.4064)
			(end -0.7874 -0.4064)
			(stroke
				(width 0.1524)
				(type default)
			)
			(layer "F.SilkS")
		)
		(fp_line
			(start 0.7874 0.4064)
			(end -0.7874 0.4064)
			(stroke
				(width 0.1524)
				(type default)
			)
			(layer "F.SilkS")
		)
		(fp_line
			(start -0.7874 -0.4064)
			(end 0.7874 -0.4064)
			(stroke
				(width 0.1524)
				(type default)
			)
			(layer "F.SilkS")
		)
		(fp_line
			(start 0.7874 -0.4064)
			(end 0.7874 0.4064)
			(stroke
				(width 0.1524)
				(type default)
			)
			(layer "F.SilkS")
		)
		(fp_line
			(start -0.67945 0.3048)
			(end -0.67945 -0.305054)
			(stroke
				(width 0.1)
				(type default)
			)
			(layer "F.Fab")
		)
		(fp_line
			(start -0.12065 0.3048)
			(end -0.67945 0.3048)
			(stroke
				(width 0.1)
				(type default)
			)
			(layer "F.Fab")
		)
		(fp_line
			(start 0.120396 0.3048)
			(end 0.120396 0.2794)
			(stroke
				(width 0.1)
				(type default)
			)
			(layer "F.Fab")
		)
		(fp_line
			(start 0.67945 0.3048)
			(end 0.120396 0.3048)
			(stroke
				(width 0.1)
				(type default)
			)
			(layer "F.Fab")
		)
		(fp_line
			(start -0.12065 0.2794)
			(end -0.12065 0.3048)
			(stroke
				(width 0.1)
				(type default)
			)
			(layer "F.Fab")
		)
		(fp_line
			(start 0.120396 0.2794)
			(end -0.12065 0.2794)
			(stroke
				(width 0.1)
				(type default)
			)
			(layer "F.Fab")
		)
		(fp_line
			(start -0.12065 -0.2794)
			(end 0.12065 -0.2794)
			(stroke
				(width 0.1)
				(type default)
			)
			(layer "F.Fab")
		)
		(fp_line
			(start 0.12065 -0.2794)
			(end 0.12065 -0.3048)
			(stroke
				(width 0.1)
				(type default)
			)
			(layer "F.Fab")
		)
		(fp_line
			(start 0.12065 -0.3048)
			(end 0.67945 -0.3048)
			(stroke
				(width 0.1)
				(type default)
			)
			(layer "F.Fab")
		)
		(fp_line
			(start 0.67945 -0.3048)
			(end 0.67945 0.3048)
			(stroke
				(width 0.1)
				(type default)
			)
			(layer "F.Fab")
		)
		(fp_line
			(start -0.67945 -0.305054)
			(end -0.12065 -0.305054)
			(stroke
				(width 0.1)
				(type default)
			)
			(layer "F.Fab")
		)
		(fp_line
			(start -0.12065 -0.305054)
			(end -0.12065 -0.2794)
			(stroke
				(width 0.1)
				(type default)
			)
			(layer "F.Fab")
		)
		(pad "1" smd circle
			(at -0.40005 0 270)
			(size 0 0)
			(layers "F.Cu" "F.Mask" "F.Paste")
			(net "P3V3_AUX")
		)
		(pad "2" smd circle
			(at 0.40005 0 270)
			(size 0 0)
			(layers "F.Cu" "F.Mask" "F.Paste")
			(net "BOOT_RDY_BUF_LED")
		)
	)
	(footprint ""
		(layer "F.Cu")
		(at 275.422106 -346.71635)
		(property "Reference" "PU20"
			(at -1.737106 -7.58698 0)
			(unlocked yes)
			(layer "F.SilkS")
			(effects
				(font
					(size 0.7874 0.5842)
					(thickness 0.1524)
				)
				(justify left)
			)
		)
		(property "Value" ""
			(at 0 0 0)
			(layer "F.Fab")
			(effects
				(font
					(size 1.27 1.27)
				)
			)
		)
		(duplicate_pad_numbers_are_jumpers no)
		(fp_line
			(start -2.500122 -2.999994)
			(end -2.24409 -2.999994)
			(stroke
				(width 0.1524)
				(type default)
			)
			(layer "F.SilkS")
		)
		(fp_line
			(start -2.500122 -2.529078)
			(end -2.500122 -2.999994)
			(stroke
				(width 0.1524)
				(type default)
			)
			(layer "F.SilkS")
		)
		(fp_line
			(start -2.500122 0.6604)
			(end -2.500122 0.229108)
			(stroke
				(width 0.1524)
				(type default)
			)
			(layer "F.SilkS")
		)
		(fp_line
			(start -2.500122 2.999994)
			(end -2.500122 2.339594)
			(stroke
				(width 0.1524)
				(type default)
			)
			(layer "F.SilkS")
		)
		(fp_line
			(start -2.2987 2.999994)
			(end -2.500122 2.999994)
			(stroke
				(width 0.1524)
				(type default)
			)
			(layer "F.SilkS")
		)
		(fp_line
			(start 2.31394 -2.999994)
			(end 2.500122 -2.999994)
			(stroke
				(width 0.1524)
				(type default)
			)
			(layer "F.SilkS")
		)
		(fp_line
			(start 2.500122 -2.999994)
			(end 2.500122 -2.44348)
			(stroke
				(width 0.1524)
				(type default)
			)
			(layer "F.SilkS")
		)
		(fp_line
			(start 2.500122 2.339594)
			(end 2.500122 2.999994)
			(stroke
				(width 0.1524)
				(type default)
			)
			(layer "F.SilkS")
		)
		(fp_line
			(start 2.500122 2.999994)
			(end 2.2987 2.999994)
			(stroke
				(width 0.1524)
				(type default)
			)
			(layer "F.SilkS")
		)
		(fp_poly
			(pts
				(xy -3.464814 -2.702052) (xy -2.983484 -3.183382) (xy -2.742946 -2.461514)
			)
			(stroke
				(width 0)
				(type default)
			)
			(fill yes)
			(layer "F.SilkS")
		)
		(fp_line
			(start -2.500122 -2.999994)
			(end 2.500122 -2.999994)
			(stroke
				(width 0.1)
				(type default)
			)
			(layer "F.Fab")
		)
		(fp_line
			(start -2.500122 2.999994)
			(end -2.500122 -2.999994)
			(stroke
				(width 0.1)
				(type default)
			)
			(layer "F.Fab")
		)
		(fp_line
			(start 2.500122 -2.999994)
			(end 2.500122 2.999994)
			(stroke
				(width 0.1)
				(type default)
			)
			(layer "F.Fab")
		)
		(fp_line
			(start 2.500122 2.999994)
			(end -2.500122 2.999994)
			(stroke
				(width 0.1)
				(type default)
			)
			(layer "F.Fab")
		)
		(fp_poly
			(pts
				(xy -4.218432 -2.783078) (xy -4.218432 -1.767078) (xy -3.202432 -2.275078)
			)
			(stroke
				(width 0)
				(type default)
			)
			(fill yes)
			(layer "F.Fab")
		)
		(pad "1" smd rect
			(at -2.400046 -2.275078 90)
			(size 0.2286 0.6096)
			(layers "F.Cu" "F.Mask" "F.Paste")
			(net "PVDDIO_P0_VOS4")
		)
		(pad "2" smd rect
			(at -2.400046 -1.82499 90)
			(size 0.2286 0.6096)
			(layers "F.Cu" "F.Mask" "F.Paste")
			(net "GND")
		)
		(pad "3" smd rect
			(at -2.400046 -1.374902 90)
			(size 0.2286 0.6096)
			(layers "F.Cu" "F.Mask" "F.Paste")
			(net "PVDDIO_P0_VCC4")
		)
		(pad "4" smd rect
			(at -2.400046 -0.925068 90)
			(size 0.2286 0.6096)
			(layers "F.Cu" "F.Mask" "F.Paste")
			(net "PVDDCR_CPU1_P0_PVCC")
		)
		(pad "5" smd rect
			(at -2.400046 -0.47498 90)
			(size 0.2286 0.6096)
			(layers "F.Cu" "F.Mask" "F.Paste")
			(net "GND")
		)
		(pad "6" smd rect
			(at -2.400046 -0.024892 90)
			(size 0.2286 0.6096)
			(layers "F.Cu" "F.Mask" "F.Paste")
			(net "NC_PVDDIO_P0_GL1_4")
		)
		(pad "7_9-20_24" smd circle
			(at 0 1.150112 90)
			(size 0 0)
			(layers "F.Cu" "F.Mask" "F.Paste")
			(net "GND")
		)
		(pad "10_19" smd rect
			(at 0 2.899918 90)
			(size 0.6096 4.318)
			(layers "F.Cu" "F.Mask" "F.Paste")
			(net "SW_PVDDIO_P0_SW4")
		)
		(pad "25_29" smd rect
			(at 1.549908 -1.279906 270)
			(size 2.0574 2.3114)
			(layers "F.Cu" "F.Mask" "F.Paste")
			(net "SW_P12V_AUX_PVDDIO_P0_FLT")
		)
		(pad "30" smd rect
			(at 2.05994 -2.899918)
			(size 0.2286 0.6096)
			(layers "F.Cu" "F.Mask" "F.Paste")
			(net "SW_P12V_AUX_PVDDIO_P0_FLT")
		)
		(pad "31" smd rect
			(at 1.610106 -2.899918)
			(size 0.2286 0.6096)
			(layers "F.Cu" "F.Mask" "F.Paste")
			(net "NC_PVDDIO_P0_DNC4")
		)
		(pad "32" smd rect
			(at 1.160018 -2.899918)
			(size 0.2286 0.6096)
			(layers "F.Cu" "F.Mask" "F.Paste")
			(net "SW_PVDDIO_P0_BOOTR4")
		)
		(pad "33" smd rect
			(at 0.70993 -2.899918)
			(size 0.2286 0.6096)
			(layers "F.Cu" "F.Mask" "F.Paste")
			(net "SW_PVDDIO_P0_BOOT4")
		)
		(pad "34" smd rect
			(at 0.260096 -2.899918)
			(size 0.2286 0.6096)
			(layers "F.Cu" "F.Mask" "F.Paste")
			(net "PVDDIO_P0_PWM4")
		)
		(pad "35" smd rect
			(at -0.189992 -2.899918)
			(size 0.2286 0.6096)
			(layers "F.Cu" "F.Mask" "F.Paste")
			(net "PVDDIO_P0_VCC4")
		)
		(pad "36" smd rect
			(at -0.64008 -2.899918)
			(size 0.2286 0.6096)
			(layers "F.Cu" "F.Mask" "F.Paste")
			(net "PVDDIO_P0_TEMP1")
		)
		(pad "37" smd rect
			(at -1.089914 -2.899918)
			(size 0.2286 0.6096)
			(layers "F.Cu" "F.Mask" "F.Paste")
			(net "PVDDIO_P0_LSET4")
		)
		(pad "38" smd rect
			(at -1.540002 -2.899918)
			(size 0.2286 0.6096)
			(layers "F.Cu" "F.Mask" "F.Paste")
			(net "PVDDIO_P0_IMON4")
		)
		(pad "39" smd rect
			(at -1.99009 -2.899918)
			(size 0.2286 0.6096)
			(layers "F.Cu" "F.Mask" "F.Paste")
			(net "PVDDCR_CPU1_P0_VCCS")
		)
		(pad "40" smd rect
			(at -0.87503 -1.27508)
			(size 1.7526 1.9558)
			(layers "F.Cu" "F.Mask" "F.Paste")
			(net "GND")
		)
		(pad "41" smd rect
			(at -1.525016 0.249936 270)
			(size 0.3048 0.4572)
			(layers "F.Cu" "F.Mask" "F.Paste")
			(net "NC_PVDDIO_P0_GL2_4")
		)
		(zone
			(layer "F.Cu")
			(hatch none 0.5)
			(connect_pads
				(clearance 0)
			)
			(min_thickness 0.25)
			(keepout
				(tracks not_allowed)
				(vias allowed)
				(pads allowed)
				(copperpour not_allowed)
				(footprints allowed)
			)
			(placement
				(enabled no)
				(sheetname "")
			)
			(fill
				(thermal_gap 0.5)
				(thermal_bridge_width 0.5)
				(island_removal_mode 0)
			)
			(polygon
				(pts
					(xy 272.921984 -344.138758) (xy 272.921984 -344.465656) (xy 277.922228 -344.465656) (xy 277.922228 -344.141806)
					(xy 277.631906 -344.141806) (xy 277.631906 -344.172032) (xy 273.212306 -344.172032) (xy 273.212306 -344.138758)
				)
			)
		)
		(zone
			(layer "F.Cu")
			(hatch none 0.5)
			(connect_pads
				(clearance 0)
			)
			(min_thickness 0.25)
			(keepout
				(tracks not_allowed)
				(vias allowed)
				(pads allowed)
				(copperpour not_allowed)
				(footprints allowed)
			)
			(placement
				(enabled no)
				(sheetname "")
			)
			(fill
				(thermal_gap 0.5)
				(thermal_bridge_width 0.5)
				(island_removal_mode 0)
			)
			(polygon
				(pts
					(xy 275.474176 -346.96273) (xy 275.474176 -349.02013) (xy 273.619976 -349.02013) (xy 273.619976 -348.779084)
					(xy 273.37766 -348.779084) (xy 273.37766 -349.260668) (xy 277.21814 -349.260668) (xy 277.21814 -349.075756)
					(xy 275.765514 -349.075756) (xy 275.765514 -346.916756) (xy 277.922228 -346.916756) (xy 277.922228 -346.667074)
					(xy 275.769832 -346.667074)
				)
			)
		)
	)
	(footprint ""
		(layer "F.Cu")
		(at 413.93364 -378.95403 -90)
		(property "Reference" "C851"
			(at 0 0 270)
			(layer "F.SilkS")
			(hide yes)
			(effects
				(font
					(size 1.27 1.27)
				)
			)
		)
		(property "Value" ""
			(at 0 0 270)
			(layer "F.Fab")
			(effects
				(font
					(size 1.27 1.27)
				)
			)
		)
		(duplicate_pad_numbers_are_jumpers no)
		(fp_line
			(start -0.299974 0.150114)
			(end -0.299974 -0.150114)
			(stroke
				(width 0.1)
				(type default)
			)
			(layer "F.Fab")
		)
		(fp_line
			(start 0.299974 0.150114)
			(end -0.299974 0.150114)
			(stroke
				(width 0.1)
				(type default)
			)
			(layer "F.Fab")
		)
		(fp_line
			(start -0.299974 -0.150114)
			(end 0.299974 -0.150114)
			(stroke
				(width 0.1)
				(type default)
			)
			(layer "F.Fab")
		)
		(fp_line
			(start 0.299974 -0.150114)
			(end 0.299974 0.150114)
			(stroke
				(width 0.1)
				(type default)
			)
			(layer "F.Fab")
		)
		(pad "1" smd rect
			(at -0.2667 0 270)
			(size 0.3048 0.381)
			(layers "F.Cu" "F.Mask" "F.Paste")
			(net "P5E_CPU0_P2_TX_C_DP<9>")
		)
		(pad "2" smd rect
			(at 0.2667 0 270)
			(size 0.3048 0.381)
			(layers "F.Cu" "F.Mask" "F.Paste")
			(net "P5E_CPU0_P2_TX_DP<9>")
		)
	)
	(footprint ""
		(layer "F.Cu")
		(at 445.252602 -418.17671 -90)
		(property "Reference" "PR6611"
			(at 0 0 270)
			(layer "F.SilkS")
			(hide yes)
			(effects
				(font
					(size 1.27 1.27)
				)
			)
		)
		(property "Value" ""
			(at 0 0 270)
			(layer "F.Fab")
			(effects
				(font
					(size 1.27 1.27)
				)
			)
		)
		(duplicate_pad_numbers_are_jumpers no)
		(fp_line
			(start -0.7874 0.4064)
			(end -0.7874 -0.4064)
			(stroke
				(width 0.1524)
				(type default)
			)
			(layer "F.SilkS")
		)
		(fp_line
			(start 0.7874 0.4064)
			(end -0.7874 0.4064)
			(stroke
				(width 0.1524)
				(type default)
			)
			(layer "F.SilkS")
		)
		(fp_line
			(start -0.7874 -0.4064)
			(end 0.7874 -0.4064)
			(stroke
				(width 0.1524)
				(type default)
			)
			(layer "F.SilkS")
		)
		(fp_line
			(start 0.7874 -0.4064)
			(end 0.7874 0.4064)
			(stroke
				(width 0.1524)
				(type default)
			)
			(layer "F.SilkS")
		)
		(fp_line
			(start -0.67945 0.3048)
			(end -0.67945 -0.305054)
			(stroke
				(width 0.1)
				(type default)
			)
			(layer "F.Fab")
		)
		(fp_line
			(start -0.12065 0.3048)
			(end -0.67945 0.3048)
			(stroke
				(width 0.1)
				(type default)
			)
			(layer "F.Fab")
		)
		(fp_line
			(start 0.120396 0.3048)
			(end 0.120396 0.2794)
			(stroke
				(width 0.1)
				(type default)
			)
			(layer "F.Fab")
		)
		(fp_line
			(start 0.67945 0.3048)
			(end 0.120396 0.3048)
			(stroke
				(width 0.1)
				(type default)
			)
			(layer "F.Fab")
		)
		(fp_line
			(start -0.12065 0.2794)
			(end -0.12065 0.3048)
			(stroke
				(width 0.1)
				(type default)
			)
			(layer "F.Fab")
		)
		(fp_line
			(start 0.120396 0.2794)
			(end -0.12065 0.2794)
			(stroke
				(width 0.1)
				(type default)
			)
			(layer "F.Fab")
		)
		(fp_line
			(start -0.12065 -0.2794)
			(end 0.12065 -0.2794)
			(stroke
				(width 0.1)
				(type default)
			)
			(layer "F.Fab")
		)
		(fp_line
			(start 0.12065 -0.2794)
			(end 0.12065 -0.3048)
			(stroke
				(width 0.1)
				(type default)
			)
			(layer "F.Fab")
		)
		(fp_line
			(start 0.12065 -0.3048)
			(end 0.67945 -0.3048)
			(stroke
				(width 0.1)
				(type default)
			)
			(layer "F.Fab")
		)
		(fp_line
			(start 0.67945 -0.3048)
			(end 0.67945 0.3048)
			(stroke
				(width 0.1)
				(type default)
			)
			(layer "F.Fab")
		)
		(fp_line
			(start -0.67945 -0.305054)
			(end -0.12065 -0.305054)
			(stroke
				(width 0.1)
				(type default)
			)
			(layer "F.Fab")
		)
		(fp_line
			(start -0.12065 -0.305054)
			(end -0.12065 -0.2794)
			(stroke
				(width 0.1)
				(type default)
			)
			(layer "F.Fab")
		)
		(pad "1" smd circle
			(at -0.40005 0 270)
			(size 0 0)
			(layers "F.Cu" "F.Mask" "F.Paste")
			(net "NC_P0V9_RETIMER_CPU0_IMON5")
		)
		(pad "2" smd circle
			(at 0.40005 0 270)
			(size 0 0)
			(layers "F.Cu" "F.Mask" "F.Paste")
			(net "GND")
		)
	)
	(footprint ""
		(layer "F.Cu")
		(at 355.08057 -404.0124 -90)
		(property "Reference" "R1040"
			(at 0 0 270)
			(layer "F.SilkS")
			(hide yes)
			(effects
				(font
					(size 1.27 1.27)
				)
			)
		)
		(property "Value" ""
			(at 0 0 270)
			(layer "F.Fab")
			(effects
				(font
					(size 1.27 1.27)
				)
			)
		)
		(duplicate_pad_numbers_are_jumpers no)
		(fp_line
			(start -0.32512 0.175006)
			(end -0.32512 -0.175006)
			(stroke
				(width 0.1)
				(type default)
			)
			(layer "F.Fab")
		)
		(fp_line
			(start 0.32512 0.175006)
			(end -0.32512 0.175006)
			(stroke
				(width 0.1)
				(type default)
			)
			(layer "F.Fab")
		)
		(fp_line
			(start -0.32512 -0.175006)
			(end 0.32512 -0.175006)
			(stroke
				(width 0.1)
				(type default)
			)
			(layer "F.Fab")
		)
		(fp_line
			(start 0.32512 -0.175006)
			(end 0.32512 0.175006)
			(stroke
				(width 0.1)
				(type default)
			)
			(layer "F.Fab")
		)
		(pad "1" smd rect
			(at -0.2667 0 270)
			(size 0.3048 0.381)
			(layers "F.Cu" "F.Mask" "F.Paste")
			(net "P1V8_CPU0_RT_1D")
		)
		(pad "2" smd rect
			(at 0.2667 0 90)
			(size 0.3048 0.381)
			(layers "F.Cu" "F.Mask" "F.Paste")
			(net "RT_CPU0_P1_VQPS")
		)
	)
	(footprint ""
		(layer "F.Cu")
		(at 103.413814 -36.6522 180)
		(property "Reference" "R6326"
			(at 0 0 180)
			(layer "F.SilkS")
			(hide yes)
			(effects
				(font
					(size 1.27 1.27)
				)
			)
		)
		(property "Value" ""
			(at 0 0 180)
			(layer "F.Fab")
			(effects
				(font
					(size 1.27 1.27)
				)
			)
		)
		(duplicate_pad_numbers_are_jumpers no)
		(fp_line
			(start 0.7874 0.4064)
			(end -0.7874 0.4064)
			(stroke
				(width 0.1524)
				(type default)
			)
			(layer "F.SilkS")
		)
		(fp_line
			(start 0.7874 -0.4064)
			(end 0.7874 0.4064)
			(stroke
				(width 0.1524)
				(type default)
			)
			(layer "F.SilkS")
		)
		(fp_line
			(start -0.7874 0.4064)
			(end -0.7874 -0.4064)
			(stroke
				(width 0.1524)
				(type default)
			)
			(layer "F.SilkS")
		)
		(fp_line
			(start -0.7874 -0.4064)
			(end 0.7874 -0.4064)
			(stroke
				(width 0.1524)
				(type default)
			)
			(layer "F.SilkS")
		)
		(fp_line
			(start 0.67945 0.3048)
			(end 0.120396 0.3048)
			(stroke
				(width 0.1)
				(type default)
			)
			(layer "F.Fab")
		)
		(fp_line
			(start 0.67945 -0.3048)
			(end 0.67945 0.3048)
			(stroke
				(width 0.1)
				(type default)
			)
			(layer "F.Fab")
		)
		(fp_line
			(start 0.12065 -0.2794)
			(end 0.12065 -0.3048)
			(stroke
				(width 0.1)
				(type default)
			)
			(layer "F.Fab")
		)
		(fp_line
			(start 0.12065 -0.3048)
			(end 0.67945 -0.3048)
			(stroke
				(width 0.1)
				(type default)
			)
			(layer "F.Fab")
		)
		(fp_line
			(start 0.120396 0.3048)
			(end 0.120396 0.2794)
			(stroke
				(width 0.1)
				(type default)
			)
			(layer "F.Fab")
		)
		(fp_line
			(start 0.120396 0.2794)
			(end -0.12065 0.2794)
			(stroke
				(width 0.1)
				(type default)
			)
			(layer "F.Fab")
		)
		(fp_line
			(start -0.12065 0.3048)
			(end -0.67945 0.3048)
			(stroke
				(width 0.1)
				(type default)
			)
			(layer "F.Fab")
		)
		(fp_line
			(start -0.12065 0.2794)
			(end -0.12065 0.3048)
			(stroke
				(width 0.1)
				(type default)
			)
			(layer "F.Fab")
		)
		(fp_line
			(start -0.12065 -0.2794)
			(end 0.12065 -0.2794)
			(stroke
				(width 0.1)
				(type default)
			)
			(layer "F.Fab")
		)
		(fp_line
			(start -0.12065 -0.305054)
			(end -0.12065 -0.2794)
			(stroke
				(width 0.1)
				(type default)
			)
			(layer "F.Fab")
		)
		(fp_line
			(start -0.67945 0.3048)
			(end -0.67945 -0.305054)
			(stroke
				(width 0.1)
				(type default)
			)
			(layer "F.Fab")
		)
		(fp_line
			(start -0.67945 -0.305054)
			(end -0.12065 -0.305054)
			(stroke
				(width 0.1)
				(type default)
			)
			(layer "F.Fab")
		)
		(pad "1" smd circle
			(at -0.40005 0 180)
			(size 0 0)
			(layers "F.Cu" "F.Mask" "F.Paste")
			(net "USB_HUB2_MRP_PROG_FUNC6")
		)
		(pad "2" smd circle
			(at 0.40005 0 180)
			(size 0 0)
			(layers "F.Cu" "F.Mask" "F.Paste")
			(net "GND")
		)
	)
	(footprint ""
		(layer "F.Cu")
		(at 358.797098 -257.744976)
		(property "Reference" "C2572"
			(at 0 0 0)
			(layer "F.SilkS")
			(hide yes)
			(effects
				(font
					(size 1.27 1.27)
				)
			)
		)
		(property "Value" ""
			(at 0 0 0)
			(layer "F.Fab")
			(effects
				(font
					(size 1.27 1.27)
				)
			)
		)
		(duplicate_pad_numbers_are_jumpers no)
		(fp_line
			(start -0.7874 -0.4064)
			(end 0.7874 -0.4064)
			(stroke
				(width 0.1524)
				(type default)
			)
			(layer "F.SilkS")
		)
		(fp_line
			(start -0.7874 0.4064)
			(end -0.7874 -0.4064)
			(stroke
				(width 0.1524)
				(type default)
			)
			(layer "F.SilkS")
		)
		(fp_line
			(start 0.7874 -0.4064)
			(end 0.7874 0.4064)
			(stroke
				(width 0.1524)
				(type default)
			)
			(layer "F.SilkS")
		)
		(fp_line
			(start 0.7874 0.4064)
			(end -0.7874 0.4064)
			(stroke
				(width 0.1524)
				(type default)
			)
			(layer "F.SilkS")
		)
		(fp_line
			(start -0.67945 -0.305054)
			(end -0.12065 -0.305054)
			(stroke
				(width 0.1)
				(type default)
			)
			(layer "F.Fab")
		)
		(fp_line
			(start -0.67945 0.3048)
			(end -0.67945 -0.305054)
			(stroke
				(width 0.1)
				(type default)
			)
			(layer "F.Fab")
		)
		(fp_line
			(start -0.12065 -0.305054)
			(end -0.12065 -0.2794)
			(stroke
				(width 0.1)
				(type default)
			)
			(layer "F.Fab")
		)
		(fp_line
			(start -0.12065 -0.2794)
			(end 0.12065 -0.2794)
			(stroke
				(width 0.1)
				(type default)
			)
			(layer "F.Fab")
		)
		(fp_line
			(start -0.12065 0.2794)
			(end -0.12065 0.3048)
			(stroke
				(width 0.1)
				(type default)
			)
			(layer "F.Fab")
		)
		(fp_line
			(start -0.12065 0.3048)
			(end -0.67945 0.3048)
			(stroke
				(width 0.1)
				(type default)
			)
			(layer "F.Fab")
		)
		(fp_line
			(start 0.120396 0.2794)
			(end -0.12065 0.2794)
			(stroke
				(width 0.1)
				(type default)
			)
			(layer "F.Fab")
		)
		(fp_line
			(start 0.120396 0.3048)
			(end 0.120396 0.2794)
			(stroke
				(width 0.1)
				(type default)
			)
			(layer "F.Fab")
		)
		(fp_line
			(start 0.12065 -0.3048)
			(end 0.67945 -0.3048)
			(stroke
				(width 0.1)
				(type default)
			)
			(layer "F.Fab")
		)
		(fp_line
			(start 0.12065 -0.2794)
			(end 0.12065 -0.3048)
			(stroke
				(width 0.1)
				(type default)
			)
			(layer "F.Fab")
		)
		(fp_line
			(start 0.67945 -0.3048)
			(end 0.67945 0.3048)
			(stroke
				(width 0.1)
				(type default)
			)
			(layer "F.Fab")
		)
		(fp_line
			(start 0.67945 0.3048)
			(end 0.120396 0.3048)
			(stroke
				(width 0.1)
				(type default)
			)
			(layer "F.Fab")
		)
		(pad "1" smd circle
			(at -0.40005 0)
			(size 0 0)
			(layers "F.Cu" "F.Mask" "F.Paste")
			(net "PVDDCR_SOC_P0")
		)
		(pad "2" smd circle
			(at 0.40005 0)
			(size 0 0)
			(layers "F.Cu" "F.Mask" "F.Paste")
			(net "GND")
		)
	)
	(footprint ""
		(layer "F.Cu")
		(at 57.17286 -39.36238 90)
		(property "Reference" "R1520"
			(at 0 0 90)
			(layer "F.SilkS")
			(hide yes)
			(effects
				(font
					(size 1.27 1.27)
				)
			)
		)
		(property "Value" ""
			(at 0 0 90)
			(layer "F.Fab")
			(effects
				(font
					(size 1.27 1.27)
				)
			)
		)
		(duplicate_pad_numbers_are_jumpers no)
		(fp_line
			(start 0.7874 -0.4064)
			(end 0.7874 0.4064)
			(stroke
				(width 0.1524)
				(type default)
			)
			(layer "F.SilkS")
		)
		(fp_line
			(start -0.7874 -0.4064)
			(end 0.7874 -0.4064)
			(stroke
				(width 0.1524)
				(type default)
			)
			(layer "F.SilkS")
		)
		(fp_line
			(start 0.7874 0.4064)
			(end -0.7874 0.4064)
			(stroke
				(width 0.1524)
				(type default)
			)
			(layer "F.SilkS")
		)
		(fp_line
			(start -0.7874 0.4064)
			(end -0.7874 -0.4064)
			(stroke
				(width 0.1524)
				(type default)
			)
			(layer "F.SilkS")
		)
		(fp_line
			(start -0.12065 -0.305054)
			(end -0.12065 -0.2794)
			(stroke
				(width 0.1)
				(type default)
			)
			(layer "F.Fab")
		)
		(fp_line
			(start -0.67945 -0.305054)
			(end -0.12065 -0.305054)
			(stroke
				(width 0.1)
				(type default)
			)
			(layer "F.Fab")
		)
		(fp_line
			(start 0.67945 -0.3048)
			(end 0.67945 0.3048)
			(stroke
				(width 0.1)
				(type default)
			)
			(layer "F.Fab")
		)
		(fp_line
			(start 0.12065 -0.3048)
			(end 0.67945 -0.3048)
			(stroke
				(width 0.1)
				(type default)
			)
			(layer "F.Fab")
		)
		(fp_line
			(start 0.12065 -0.2794)
			(end 0.12065 -0.3048)
			(stroke
				(width 0.1)
				(type default)
			)
			(layer "F.Fab")
		)
		(fp_line
			(start -0.12065 -0.2794)
			(end 0.12065 -0.2794)
			(stroke
				(width 0.1)
				(type default)
			)
			(layer "F.Fab")
		)
		(fp_line
			(start 0.120396 0.2794)
			(end -0.12065 0.2794)
			(stroke
				(width 0.1)
				(type default)
			)
			(layer "F.Fab")
		)
		(fp_line
			(start -0.12065 0.2794)
			(end -0.12065 0.3048)
			(stroke
				(width 0.1)
				(type default)
			)
			(layer "F.Fab")
		)
		(fp_line
			(start 0.67945 0.3048)
			(end 0.120396 0.3048)
			(stroke
				(width 0.1)
				(type default)
			)
			(layer "F.Fab")
		)
		(fp_line
			(start 0.120396 0.3048)
			(end 0.120396 0.2794)
			(stroke
				(width 0.1)
				(type default)
			)
			(layer "F.Fab")
		)
		(fp_line
			(start -0.12065 0.3048)
			(end -0.67945 0.3048)
			(stroke
				(width 0.1)
				(type default)
			)
			(layer "F.Fab")
		)
		(fp_line
			(start -0.67945 0.3048)
			(end -0.67945 -0.305054)
			(stroke
				(width 0.1)
				(type default)
			)
			(layer "F.Fab")
		)
		(pad "1" smd circle
			(at -0.40005 0 90)
			(size 0 0)
			(layers "F.Cu" "F.Mask" "F.Paste")
			(net "P12V_OCP_V3_2_BUF_EN_R")
		)
		(pad "2" smd circle
			(at 0.40005 0 90)
			(size 0 0)
			(layers "F.Cu" "F.Mask" "F.Paste")
			(net "P3V3_OCP_EN_2_R")
		)
	)
	(footprint ""
		(layer "F.Cu")
		(at 417.86937 -353.77628 90)
		(property "Reference" "PR413"
			(at 0 0 90)
			(layer "F.SilkS")
			(hide yes)
			(effects
				(font
					(size 1.27 1.27)
				)
			)
		)
		(property "Value" ""
			(at 0 0 90)
			(layer "F.Fab")
			(effects
				(font
					(size 1.27 1.27)
				)
			)
		)
		(duplicate_pad_numbers_are_jumpers no)
		(fp_line
			(start 0.7874 -0.4064)
			(end 0.7874 0.4064)
			(stroke
				(width 0.1524)
				(type default)
			)
			(layer "F.SilkS")
		)
		(fp_line
			(start -0.7874 -0.4064)
			(end 0.7874 -0.4064)
			(stroke
				(width 0.1524)
				(type default)
			)
			(layer "F.SilkS")
		)
		(fp_line
			(start 0.7874 0.4064)
			(end -0.7874 0.4064)
			(stroke
				(width 0.1524)
				(type default)
			)
			(layer "F.SilkS")
		)
		(fp_line
			(start -0.7874 0.4064)
			(end -0.7874 -0.4064)
			(stroke
				(width 0.1524)
				(type default)
			)
			(layer "F.SilkS")
		)
		(fp_line
			(start -0.12065 -0.305054)
			(end -0.12065 -0.2794)
			(stroke
				(width 0.1)
				(type default)
			)
			(layer "F.Fab")
		)
		(fp_line
			(start -0.67945 -0.305054)
			(end -0.12065 -0.305054)
			(stroke
				(width 0.1)
				(type default)
			)
			(layer "F.Fab")
		)
		(fp_line
			(start 0.67945 -0.3048)
			(end 0.67945 0.3048)
			(stroke
				(width 0.1)
				(type default)
			)
			(layer "F.Fab")
		)
		(fp_line
			(start 0.12065 -0.3048)
			(end 0.67945 -0.3048)
			(stroke
				(width 0.1)
				(type default)
			)
			(layer "F.Fab")
		)
		(fp_line
			(start 0.12065 -0.2794)
			(end 0.12065 -0.3048)
			(stroke
				(width 0.1)
				(type default)
			)
			(layer "F.Fab")
		)
		(fp_line
			(start -0.12065 -0.2794)
			(end 0.12065 -0.2794)
			(stroke
				(width 0.1)
				(type default)
			)
			(layer "F.Fab")
		)
		(fp_line
			(start 0.120396 0.2794)
			(end -0.12065 0.2794)
			(stroke
				(width 0.1)
				(type default)
			)
			(layer "F.Fab")
		)
		(fp_line
			(start -0.12065 0.2794)
			(end -0.12065 0.3048)
			(stroke
				(width 0.1)
				(type default)
			)
			(layer "F.Fab")
		)
		(fp_line
			(start 0.67945 0.3048)
			(end 0.120396 0.3048)
			(stroke
				(width 0.1)
				(type default)
			)
			(layer "F.Fab")
		)
		(fp_line
			(start 0.120396 0.3048)
			(end 0.120396 0.2794)
			(stroke
				(width 0.1)
				(type default)
			)
			(layer "F.Fab")
		)
		(fp_line
			(start -0.12065 0.3048)
			(end -0.67945 0.3048)
			(stroke
				(width 0.1)
				(type default)
			)
			(layer "F.Fab")
		)
		(fp_line
			(start -0.67945 0.3048)
			(end -0.67945 -0.305054)
			(stroke
				(width 0.1)
				(type default)
			)
			(layer "F.Fab")
		)
		(pad "1" smd circle
			(at -0.40005 0 90)
			(size 0 0)
			(layers "F.Cu" "F.Mask" "F.Paste")
			(net "PVDD11_S3_P0_PVCC")
		)
		(pad "2" smd circle
			(at 0.40005 0 90)
			(size 0 0)
			(layers "F.Cu" "F.Mask" "F.Paste")
			(net "P3V3_AUX")
		)
	)
	(footprint ""
		(layer "F.Cu")
		(at 449.650612 -23.594314 180)
		(property "Reference" "PC2085"
			(at 0 0 180)
			(layer "F.SilkS")
			(hide yes)
			(effects
				(font
					(size 1.27 1.27)
				)
			)
		)
		(property "Value" ""
			(at 0 0 180)
			(layer "F.Fab")
			(effects
				(font
					(size 1.27 1.27)
				)
			)
		)
		(duplicate_pad_numbers_are_jumpers no)
		(fp_line
			(start 0.7874 0.4064)
			(end -0.7874 0.4064)
			(stroke
				(width 0.1524)
				(type default)
			)
			(layer "F.SilkS")
		)
		(fp_line
			(start 0.7874 -0.4064)
			(end 0.7874 0.4064)
			(stroke
				(width 0.1524)
				(type default)
			)
			(layer "F.SilkS")
		)
		(fp_line
			(start -0.7874 0.4064)
			(end -0.7874 -0.4064)
			(stroke
				(width 0.1524)
				(type default)
			)
			(layer "F.SilkS")
		)
		(fp_line
			(start -0.7874 -0.4064)
			(end 0.7874 -0.4064)
			(stroke
				(width 0.1524)
				(type default)
			)
			(layer "F.SilkS")
		)
		(fp_line
			(start 0.67945 0.3048)
			(end 0.120396 0.3048)
			(stroke
				(width 0.1)
				(type default)
			)
			(layer "F.Fab")
		)
		(fp_line
			(start 0.67945 -0.3048)
			(end 0.67945 0.3048)
			(stroke
				(width 0.1)
				(type default)
			)
			(layer "F.Fab")
		)
		(fp_line
			(start 0.12065 -0.2794)
			(end 0.12065 -0.3048)
			(stroke
				(width 0.1)
				(type default)
			)
			(layer "F.Fab")
		)
		(fp_line
			(start 0.12065 -0.3048)
			(end 0.67945 -0.3048)
			(stroke
				(width 0.1)
				(type default)
			)
			(layer "F.Fab")
		)
		(fp_line
			(start 0.120396 0.3048)
			(end 0.120396 0.2794)
			(stroke
				(width 0.1)
				(type default)
			)
			(layer "F.Fab")
		)
		(fp_line
			(start 0.120396 0.2794)
			(end -0.12065 0.2794)
			(stroke
				(width 0.1)
				(type default)
			)
			(layer "F.Fab")
		)
		(fp_line
			(start -0.12065 0.3048)
			(end -0.67945 0.3048)
			(stroke
				(width 0.1)
				(type default)
			)
			(layer "F.Fab")
		)
		(fp_line
			(start -0.12065 0.2794)
			(end -0.12065 0.3048)
			(stroke
				(width 0.1)
				(type default)
			)
			(layer "F.Fab")
		)
		(fp_line
			(start -0.12065 -0.2794)
			(end 0.12065 -0.2794)
			(stroke
				(width 0.1)
				(type default)
			)
			(layer "F.Fab")
		)
		(fp_line
			(start -0.12065 -0.305054)
			(end -0.12065 -0.2794)
			(stroke
				(width 0.1)
				(type default)
			)
			(layer "F.Fab")
		)
		(fp_line
			(start -0.67945 0.3048)
			(end -0.67945 -0.305054)
			(stroke
				(width 0.1)
				(type default)
			)
			(layer "F.Fab")
		)
		(fp_line
			(start -0.67945 -0.305054)
			(end -0.12065 -0.305054)
			(stroke
				(width 0.1)
				(type default)
			)
			(layer "F.Fab")
		)
		(pad "1" smd circle
			(at -0.40005 0 180)
			(size 0 0)
			(layers "F.Cu" "F.Mask" "F.Paste")
			(net "P12V_OCP_VCC_1")
		)
		(pad "2" smd circle
			(at 0.40005 0 180)
			(size 0 0)
			(layers "F.Cu" "F.Mask" "F.Paste")
			(net "GND")
		)
	)
	(footprint ""
		(layer "F.Cu")
		(at 445.157098 -93.484192 180)
		(property "Reference" "R3627"
			(at 0 0 180)
			(layer "F.SilkS")
			(hide yes)
			(effects
				(font
					(size 1.27 1.27)
				)
			)
		)
		(property "Value" ""
			(at 0 0 180)
			(layer "F.Fab")
			(effects
				(font
					(size 1.27 1.27)
				)
			)
		)
		(duplicate_pad_numbers_are_jumpers no)
		(fp_line
			(start 0.7874 0.4064)
			(end -0.7874 0.4064)
			(stroke
				(width 0.1524)
				(type default)
			)
			(layer "F.SilkS")
		)
		(fp_line
			(start 0.7874 -0.4064)
			(end 0.7874 0.4064)
			(stroke
				(width 0.1524)
				(type default)
			)
			(layer "F.SilkS")
		)
		(fp_line
			(start -0.7874 0.4064)
			(end -0.7874 -0.4064)
			(stroke
				(width 0.1524)
				(type default)
			)
			(layer "F.SilkS")
		)
		(fp_line
			(start -0.7874 -0.4064)
			(end 0.7874 -0.4064)
			(stroke
				(width 0.1524)
				(type default)
			)
			(layer "F.SilkS")
		)
		(fp_line
			(start 0.67945 0.3048)
			(end 0.120396 0.3048)
			(stroke
				(width 0.1)
				(type default)
			)
			(layer "F.Fab")
		)
		(fp_line
			(start 0.67945 -0.3048)
			(end 0.67945 0.3048)
			(stroke
				(width 0.1)
				(type default)
			)
			(layer "F.Fab")
		)
		(fp_line
			(start 0.12065 -0.2794)
			(end 0.12065 -0.3048)
			(stroke
				(width 0.1)
				(type default)
			)
			(layer "F.Fab")
		)
		(fp_line
			(start 0.12065 -0.3048)
			(end 0.67945 -0.3048)
			(stroke
				(width 0.1)
				(type default)
			)
			(layer "F.Fab")
		)
		(fp_line
			(start 0.120396 0.3048)
			(end 0.120396 0.2794)
			(stroke
				(width 0.1)
				(type default)
			)
			(layer "F.Fab")
		)
		(fp_line
			(start 0.120396 0.2794)
			(end -0.12065 0.2794)
			(stroke
				(width 0.1)
				(type default)
			)
			(layer "F.Fab")
		)
		(fp_line
			(start -0.12065 0.3048)
			(end -0.67945 0.3048)
			(stroke
				(width 0.1)
				(type default)
			)
			(layer "F.Fab")
		)
		(fp_line
			(start -0.12065 0.2794)
			(end -0.12065 0.3048)
			(stroke
				(width 0.1)
				(type default)
			)
			(layer "F.Fab")
		)
		(fp_line
			(start -0.12065 -0.2794)
			(end 0.12065 -0.2794)
			(stroke
				(width 0.1)
				(type default)
			)
			(layer "F.Fab")
		)
		(fp_line
			(start -0.12065 -0.305054)
			(end -0.12065 -0.2794)
			(stroke
				(width 0.1)
				(type default)
			)
			(layer "F.Fab")
		)
		(fp_line
			(start -0.67945 0.3048)
			(end -0.67945 -0.305054)
			(stroke
				(width 0.1)
				(type default)
			)
			(layer "F.Fab")
		)
		(fp_line
			(start -0.67945 -0.305054)
			(end -0.12065 -0.305054)
			(stroke
				(width 0.1)
				(type default)
			)
			(layer "F.Fab")
		)
		(pad "1" smd circle
			(at -0.40005 0 180)
			(size 0 0)
			(layers "F.Cu" "F.Mask" "F.Paste")
			(net "P3V3_AUX")
		)
		(pad "2" smd circle
			(at 0.40005 0 180)
			(size 0 0)
			(layers "F.Cu" "F.Mask" "F.Paste")
			(net "INA230_1_A0")
		)
	)
	(footprint ""
		(layer "F.Cu")
		(at 311.541922 -33.715706)
		(property "Reference" "R3863"
			(at 0 0 0)
			(layer "F.SilkS")
			(hide yes)
			(effects
				(font
					(size 1.27 1.27)
				)
			)
		)
		(property "Value" ""
			(at 0 0 0)
			(layer "F.Fab")
			(effects
				(font
					(size 1.27 1.27)
				)
			)
		)
		(duplicate_pad_numbers_are_jumpers no)
		(fp_line
			(start -0.7874 -0.4064)
			(end 0.7874 -0.4064)
			(stroke
				(width 0.1524)
				(type default)
			)
			(layer "F.SilkS")
		)
		(fp_line
			(start -0.7874 0.4064)
			(end -0.7874 -0.4064)
			(stroke
				(width 0.1524)
				(type default)
			)
			(layer "F.SilkS")
		)
		(fp_line
			(start 0.7874 -0.4064)
			(end 0.7874 0.4064)
			(stroke
				(width 0.1524)
				(type default)
			)
			(layer "F.SilkS")
		)
		(fp_line
			(start 0.7874 0.4064)
			(end -0.7874 0.4064)
			(stroke
				(width 0.1524)
				(type default)
			)
			(layer "F.SilkS")
		)
		(fp_line
			(start -0.67945 -0.305054)
			(end -0.12065 -0.305054)
			(stroke
				(width 0.1)
				(type default)
			)
			(layer "F.Fab")
		)
		(fp_line
			(start -0.67945 0.3048)
			(end -0.67945 -0.305054)
			(stroke
				(width 0.1)
				(type default)
			)
			(layer "F.Fab")
		)
		(fp_line
			(start -0.12065 -0.305054)
			(end -0.12065 -0.2794)
			(stroke
				(width 0.1)
				(type default)
			)
			(layer "F.Fab")
		)
		(fp_line
			(start -0.12065 -0.2794)
			(end 0.12065 -0.2794)
			(stroke
				(width 0.1)
				(type default)
			)
			(layer "F.Fab")
		)
		(fp_line
			(start -0.12065 0.2794)
			(end -0.12065 0.3048)
			(stroke
				(width 0.1)
				(type default)
			)
			(layer "F.Fab")
		)
		(fp_line
			(start -0.12065 0.3048)
			(end -0.67945 0.3048)
			(stroke
				(width 0.1)
				(type default)
			)
			(layer "F.Fab")
		)
		(fp_line
			(start 0.120396 0.2794)
			(end -0.12065 0.2794)
			(stroke
				(width 0.1)
				(type default)
			)
			(layer "F.Fab")
		)
		(fp_line
			(start 0.120396 0.3048)
			(end 0.120396 0.2794)
			(stroke
				(width 0.1)
				(type default)
			)
			(layer "F.Fab")
		)
		(fp_line
			(start 0.12065 -0.3048)
			(end 0.67945 -0.3048)
			(stroke
				(width 0.1)
				(type default)
			)
			(layer "F.Fab")
		)
		(fp_line
			(start 0.12065 -0.2794)
			(end 0.12065 -0.3048)
			(stroke
				(width 0.1)
				(type default)
			)
			(layer "F.Fab")
		)
		(fp_line
			(start 0.67945 -0.3048)
			(end 0.67945 0.3048)
			(stroke
				(width 0.1)
				(type default)
			)
			(layer "F.Fab")
		)
		(fp_line
			(start 0.67945 0.3048)
			(end 0.120396 0.3048)
			(stroke
				(width 0.1)
				(type default)
			)
			(layer "F.Fab")
		)
		(pad "1" smd rect
			(at -0.40005 0 180)
			(size 0.4572 0.508)
			(layers "F.Cu" "F.Mask" "F.Paste")
			(net "P12V_OCP_SFF_ISENSE_MAM_MAM")
		)
		(pad "2" smd rect
			(at 0.40005 0 180)
			(size 0.4572 0.508)
			(layers "F.Cu" "F.Mask" "F.Paste")
			(net "P12V_OCP_SFF_ISENSE_MAM")
		)
	)
	(footprint ""
		(layer "F.Cu")
		(at 449.443602 -427.152308)
		(property "Reference" "PC6603"
			(at 0 0 0)
			(layer "F.SilkS")
			(hide yes)
			(effects
				(font
					(size 1.27 1.27)
				)
			)
		)
		(property "Value" ""
			(at 0 0 0)
			(layer "F.Fab")
			(effects
				(font
					(size 1.27 1.27)
				)
			)
		)
		(duplicate_pad_numbers_are_jumpers no)
		(fp_line
			(start -0.7874 -0.4064)
			(end 0.7874 -0.4064)
			(stroke
				(width 0.1524)
				(type default)
			)
			(layer "F.SilkS")
		)
		(fp_line
			(start -0.7874 0.4064)
			(end -0.7874 -0.4064)
			(stroke
				(width 0.1524)
				(type default)
			)
			(layer "F.SilkS")
		)
		(fp_line
			(start 0.7874 -0.4064)
			(end 0.7874 0.4064)
			(stroke
				(width 0.1524)
				(type default)
			)
			(layer "F.SilkS")
		)
		(fp_line
			(start 0.7874 0.4064)
			(end -0.7874 0.4064)
			(stroke
				(width 0.1524)
				(type default)
			)
			(layer "F.SilkS")
		)
		(fp_line
			(start -0.67945 -0.305054)
			(end -0.12065 -0.305054)
			(stroke
				(width 0.1)
				(type default)
			)
			(layer "F.Fab")
		)
		(fp_line
			(start -0.67945 0.3048)
			(end -0.67945 -0.305054)
			(stroke
				(width 0.1)
				(type default)
			)
			(layer "F.Fab")
		)
		(fp_line
			(start -0.12065 -0.305054)
			(end -0.12065 -0.2794)
			(stroke
				(width 0.1)
				(type default)
			)
			(layer "F.Fab")
		)
		(fp_line
			(start -0.12065 -0.2794)
			(end 0.12065 -0.2794)
			(stroke
				(width 0.1)
				(type default)
			)
			(layer "F.Fab")
		)
		(fp_line
			(start -0.12065 0.2794)
			(end -0.12065 0.3048)
			(stroke
				(width 0.1)
				(type default)
			)
			(layer "F.Fab")
		)
		(fp_line
			(start -0.12065 0.3048)
			(end -0.67945 0.3048)
			(stroke
				(width 0.1)
				(type default)
			)
			(layer "F.Fab")
		)
		(fp_line
			(start 0.120396 0.2794)
			(end -0.12065 0.2794)
			(stroke
				(width 0.1)
				(type default)
			)
			(layer "F.Fab")
		)
		(fp_line
			(start 0.120396 0.3048)
			(end 0.120396 0.2794)
			(stroke
				(width 0.1)
				(type default)
			)
			(layer "F.Fab")
		)
		(fp_line
			(start 0.12065 -0.3048)
			(end 0.67945 -0.3048)
			(stroke
				(width 0.1)
				(type default)
			)
			(layer "F.Fab")
		)
		(fp_line
			(start 0.12065 -0.2794)
			(end 0.12065 -0.3048)
			(stroke
				(width 0.1)
				(type default)
			)
			(layer "F.Fab")
		)
		(fp_line
			(start 0.67945 -0.3048)
			(end 0.67945 0.3048)
			(stroke
				(width 0.1)
				(type default)
			)
			(layer "F.Fab")
		)
		(fp_line
			(start 0.67945 0.3048)
			(end 0.120396 0.3048)
			(stroke
				(width 0.1)
				(type default)
			)
			(layer "F.Fab")
		)
		(pad "1" smd circle
			(at -0.40005 0)
			(size 0 0)
			(layers "F.Cu" "F.Mask" "F.Paste")
			(net "P0V9_RETIMER_CPU0_VCC")
		)
		(pad "2" smd circle
			(at 0.40005 0)
			(size 0 0)
			(layers "F.Cu" "F.Mask" "F.Paste")
			(net "GND")
		)
	)
	(footprint ""
		(layer "F.Cu")
		(at 11.176 -39.1668)
		(property "Reference" "H28"
			(at -1.16586 -4.917948 0)
			(unlocked yes)
			(layer "F.SilkS")
			(effects
				(font
					(size 0.7874 0.5842)
					(thickness 0.1524)
				)
				(justify left)
			)
		)
		(property "Value" ""
			(at 0 0 0)
			(layer "F.Fab")
			(effects
				(font
					(size 1.27 1.27)
				)
			)
		)
		(duplicate_pad_numbers_are_jumpers no)
		(fp_circle
			(center 0 0)
			(end 2.4003 0)
			(stroke
				(width 0.1524)
				(type default)
			)
			(fill no)
			(layer "F.SilkS")
		)
		(fp_arc
			(start -6.391402 1.610868)
			(mid -0.81161 -6.541116)
			(end 6.5913 0)
			(stroke
				(width 0.1524)
				(type default)
			)
			(layer "B.SilkS")
		)
		(fp_arc
			(start 6.5913 0)
			(mid 2.749338 5.990524)
			(end -4.29768 4.99745)
			(stroke
				(width 0.1524)
				(type default)
			)
			(layer "B.SilkS")
		)
		(fp_circle
			(center 0 0)
			(end 6.5913 0)
			(stroke
				(width 0.1)
				(type default)
			)
			(fill no)
			(layer "B.Fab")
		)
		(fp_circle
			(center 0 0)
			(end 2.4003 0)
			(stroke
				(width 0.1)
				(type default)
			)
			(fill no)
			(layer "F.Fab")
		)
		(pad "" np_thru_hole circle
			(at 0 0)
			(size 3.175 3.175)
			(drill 3.175)
			(layers "*.Cu" "*.Mask")
			(clearance 0.381)
			(thermal_gap 0.381)
		)
		(zone
			(layers "F.Cu" "B.Cu" "In1.Cu" "In2.Cu" "In3.Cu" "In4.Cu" "In5.Cu" "In6.Cu"
				"In7.Cu" "In8.Cu" "In9.Cu" "In10.Cu" "In11.Cu" "In12.Cu" "In13.Cu" "In14.Cu"
				"In15.Cu" "In16.Cu"
			)
			(hatch none 0.5)
			(connect_pads
				(clearance 0)
			)
			(min_thickness 0.25)
			(keepout
				(tracks not_allowed)
				(vias allowed)
				(pads allowed)
				(copperpour not_allowed)
				(footprints allowed)
			)
			(placement
				(enabled no)
				(sheetname "")
			)
			(fill
				(thermal_gap 0.5)
				(thermal_bridge_width 0.5)
				(island_removal_mode 0)
			)
			(polygon
				(pts
					(arc
						(start 13.2715 -39.1668)
						(mid 9.0805 -39.1668)
						(end 13.2715 -39.1668)
					)
				)
			)
		)
	)
	(footprint ""
		(layer "F.Cu")
		(at 429.136302 -436.164736 -90)
		(property "Reference" "R2832"
			(at 0 0 270)
			(layer "F.SilkS")
			(hide yes)
			(effects
				(font
					(size 1.27 1.27)
				)
			)
		)
		(property "Value" ""
			(at 0 0 270)
			(layer "F.Fab")
			(effects
				(font
					(size 1.27 1.27)
				)
			)
		)
		(duplicate_pad_numbers_are_jumpers no)
		(fp_line
			(start -0.7874 0.4064)
			(end -0.7874 -0.4064)
			(stroke
				(width 0.1524)
				(type default)
			)
			(layer "F.SilkS")
		)
		(fp_line
			(start 0.7874 0.4064)
			(end -0.7874 0.4064)
			(stroke
				(width 0.1524)
				(type default)
			)
			(layer "F.SilkS")
		)
		(fp_line
			(start -0.7874 -0.4064)
			(end 0.7874 -0.4064)
			(stroke
				(width 0.1524)
				(type default)
			)
			(layer "F.SilkS")
		)
		(fp_line
			(start 0.7874 -0.4064)
			(end 0.7874 0.4064)
			(stroke
				(width 0.1524)
				(type default)
			)
			(layer "F.SilkS")
		)
		(fp_line
			(start -0.67945 0.3048)
			(end -0.67945 -0.305054)
			(stroke
				(width 0.1)
				(type default)
			)
			(layer "F.Fab")
		)
		(fp_line
			(start -0.12065 0.3048)
			(end -0.67945 0.3048)
			(stroke
				(width 0.1)
				(type default)
			)
			(layer "F.Fab")
		)
		(fp_line
			(start 0.120396 0.3048)
			(end 0.120396 0.2794)
			(stroke
				(width 0.1)
				(type default)
			)
			(layer "F.Fab")
		)
		(fp_line
			(start 0.67945 0.3048)
			(end 0.120396 0.3048)
			(stroke
				(width 0.1)
				(type default)
			)
			(layer "F.Fab")
		)
		(fp_line
			(start -0.12065 0.2794)
			(end -0.12065 0.3048)
			(stroke
				(width 0.1)
				(type default)
			)
			(layer "F.Fab")
		)
		(fp_line
			(start 0.120396 0.2794)
			(end -0.12065 0.2794)
			(stroke
				(width 0.1)
				(type default)
			)
			(layer "F.Fab")
		)
		(fp_line
			(start -0.12065 -0.2794)
			(end 0.12065 -0.2794)
			(stroke
				(width 0.1)
				(type default)
			)
			(layer "F.Fab")
		)
		(fp_line
			(start 0.12065 -0.2794)
			(end 0.12065 -0.3048)
			(stroke
				(width 0.1)
				(type default)
			)
			(layer "F.Fab")
		)
		(fp_line
			(start 0.12065 -0.3048)
			(end 0.67945 -0.3048)
			(stroke
				(width 0.1)
				(type default)
			)
			(layer "F.Fab")
		)
		(fp_line
			(start 0.67945 -0.3048)
			(end 0.67945 0.3048)
			(stroke
				(width 0.1)
				(type default)
			)
			(layer "F.Fab")
		)
		(fp_line
			(start -0.67945 -0.305054)
			(end -0.12065 -0.305054)
			(stroke
				(width 0.1)
				(type default)
			)
			(layer "F.Fab")
		)
		(fp_line
			(start -0.12065 -0.305054)
			(end -0.12065 -0.2794)
			(stroke
				(width 0.1)
				(type default)
			)
			(layer "F.Fab")
		)
		(pad "1" smd circle
			(at -0.40005 0 270)
			(size 0 0)
			(layers "F.Cu" "F.Mask" "F.Paste")
			(net "P3V3_AUX")
		)
		(pad "2" smd circle
			(at 0.40005 0 270)
			(size 0 0)
			(layers "F.Cu" "F.Mask" "F.Paste")
			(net "FM_SWB_BIC_READY_N")
		)
	)
	(footprint ""
		(layer "F.Cu")
		(at 44.069 -434.594 180)
		(property "Reference" "R3507"
			(at 0 0 180)
			(layer "F.SilkS")
			(hide yes)
			(effects
				(font
					(size 1.27 1.27)
				)
			)
		)
		(property "Value" ""
			(at 0 0 180)
			(layer "F.Fab")
			(effects
				(font
					(size 1.27 1.27)
				)
			)
		)
		(duplicate_pad_numbers_are_jumpers no)
		(fp_line
			(start 0.7874 0.4064)
			(end -0.7874 0.4064)
			(stroke
				(width 0.1524)
				(type default)
			)
			(layer "F.SilkS")
		)
		(fp_line
			(start 0.7874 -0.4064)
			(end 0.7874 0.4064)
			(stroke
				(width 0.1524)
				(type default)
			)
			(layer "F.SilkS")
		)
		(fp_line
			(start -0.7874 0.4064)
			(end -0.7874 -0.4064)
			(stroke
				(width 0.1524)
				(type default)
			)
			(layer "F.SilkS")
		)
		(fp_line
			(start -0.7874 -0.4064)
			(end 0.7874 -0.4064)
			(stroke
				(width 0.1524)
				(type default)
			)
			(layer "F.SilkS")
		)
		(fp_line
			(start 0.67945 0.3048)
			(end 0.120396 0.3048)
			(stroke
				(width 0.1)
				(type default)
			)
			(layer "F.Fab")
		)
		(fp_line
			(start 0.67945 -0.3048)
			(end 0.67945 0.3048)
			(stroke
				(width 0.1)
				(type default)
			)
			(layer "F.Fab")
		)
		(fp_line
			(start 0.12065 -0.2794)
			(end 0.12065 -0.3048)
			(stroke
				(width 0.1)
				(type default)
			)
			(layer "F.Fab")
		)
		(fp_line
			(start 0.12065 -0.3048)
			(end 0.67945 -0.3048)
			(stroke
				(width 0.1)
				(type default)
			)
			(layer "F.Fab")
		)
		(fp_line
			(start 0.120396 0.3048)
			(end 0.120396 0.2794)
			(stroke
				(width 0.1)
				(type default)
			)
			(layer "F.Fab")
		)
		(fp_line
			(start 0.120396 0.2794)
			(end -0.12065 0.2794)
			(stroke
				(width 0.1)
				(type default)
			)
			(layer "F.Fab")
		)
		(fp_line
			(start -0.12065 0.3048)
			(end -0.67945 0.3048)
			(stroke
				(width 0.1)
				(type default)
			)
			(layer "F.Fab")
		)
		(fp_line
			(start -0.12065 0.2794)
			(end -0.12065 0.3048)
			(stroke
				(width 0.1)
				(type default)
			)
			(layer "F.Fab")
		)
		(fp_line
			(start -0.12065 -0.2794)
			(end 0.12065 -0.2794)
			(stroke
				(width 0.1)
				(type default)
			)
			(layer "F.Fab")
		)
		(fp_line
			(start -0.12065 -0.305054)
			(end -0.12065 -0.2794)
			(stroke
				(width 0.1)
				(type default)
			)
			(layer "F.Fab")
		)
		(fp_line
			(start -0.67945 0.3048)
			(end -0.67945 -0.305054)
			(stroke
				(width 0.1)
				(type default)
			)
			(layer "F.Fab")
		)
		(fp_line
			(start -0.67945 -0.305054)
			(end -0.12065 -0.305054)
			(stroke
				(width 0.1)
				(type default)
			)
			(layer "F.Fab")
		)
		(pad "1" smd circle
			(at -0.40005 0 180)
			(size 0 0)
			(layers "F.Cu" "F.Mask" "F.Paste")
			(net "GPU_FPGA_RST_R_N")
		)
		(pad "2" smd circle
			(at 0.40005 0 180)
			(size 0 0)
			(layers "F.Cu" "F.Mask" "F.Paste")
			(net "GND")
		)
	)
	(footprint ""
		(layer "F.Cu")
		(at 323.018404 -334.986376 -90)
		(property "Reference" "PC82_C1P0_2"
			(at 0 0 270)
			(layer "F.SilkS")
			(hide yes)
			(effects
				(font
					(size 1.27 1.27)
				)
			)
		)
		(property "Value" ""
			(at 0 0 270)
			(layer "F.Fab")
			(effects
				(font
					(size 1.27 1.27)
				)
			)
		)
		(duplicate_pad_numbers_are_jumpers no)
		(fp_line
			(start -0.7874 0.4064)
			(end -0.7874 -0.4064)
			(stroke
				(width 0.1524)
				(type default)
			)
			(layer "F.SilkS")
		)
		(fp_line
			(start 0.7874 0.4064)
			(end -0.7874 0.4064)
			(stroke
				(width 0.1524)
				(type default)
			)
			(layer "F.SilkS")
		)
		(fp_line
			(start -0.7874 -0.4064)
			(end 0.7874 -0.4064)
			(stroke
				(width 0.1524)
				(type default)
			)
			(layer "F.SilkS")
		)
		(fp_line
			(start 0.7874 -0.4064)
			(end 0.7874 0.4064)
			(stroke
				(width 0.1524)
				(type default)
			)
			(layer "F.SilkS")
		)
		(fp_line
			(start -0.67945 0.3048)
			(end -0.67945 -0.305054)
			(stroke
				(width 0.1)
				(type default)
			)
			(layer "F.Fab")
		)
		(fp_line
			(start -0.12065 0.3048)
			(end -0.67945 0.3048)
			(stroke
				(width 0.1)
				(type default)
			)
			(layer "F.Fab")
		)
		(fp_line
			(start 0.120396 0.3048)
			(end 0.120396 0.2794)
			(stroke
				(width 0.1)
				(type default)
			)
			(layer "F.Fab")
		)
		(fp_line
			(start 0.67945 0.3048)
			(end 0.120396 0.3048)
			(stroke
				(width 0.1)
				(type default)
			)
			(layer "F.Fab")
		)
		(fp_line
			(start -0.12065 0.2794)
			(end -0.12065 0.3048)
			(stroke
				(width 0.1)
				(type default)
			)
			(layer "F.Fab")
		)
		(fp_line
			(start 0.120396 0.2794)
			(end -0.12065 0.2794)
			(stroke
				(width 0.1)
				(type default)
			)
			(layer "F.Fab")
		)
		(fp_line
			(start -0.12065 -0.2794)
			(end 0.12065 -0.2794)
			(stroke
				(width 0.1)
				(type default)
			)
			(layer "F.Fab")
		)
		(fp_line
			(start 0.12065 -0.2794)
			(end 0.12065 -0.3048)
			(stroke
				(width 0.1)
				(type default)
			)
			(layer "F.Fab")
		)
		(fp_line
			(start 0.12065 -0.3048)
			(end 0.67945 -0.3048)
			(stroke
				(width 0.1)
				(type default)
			)
			(layer "F.Fab")
		)
		(fp_line
			(start 0.67945 -0.3048)
			(end 0.67945 0.3048)
			(stroke
				(width 0.1)
				(type default)
			)
			(layer "F.Fab")
		)
		(fp_line
			(start -0.67945 -0.305054)
			(end -0.12065 -0.305054)
			(stroke
				(width 0.1)
				(type default)
			)
			(layer "F.Fab")
		)
		(fp_line
			(start -0.12065 -0.305054)
			(end -0.12065 -0.2794)
			(stroke
				(width 0.1)
				(type default)
			)
			(layer "F.Fab")
		)
		(pad "1" smd circle
			(at -0.40005 0 270)
			(size 0 0)
			(layers "F.Cu" "F.Mask" "F.Paste")
			(net "PVDDCR_CPU1_P0_PVCC")
		)
		(pad "2" smd circle
			(at 0.40005 0 270)
			(size 0 0)
			(layers "F.Cu" "F.Mask" "F.Paste")
			(net "GND")
		)
	)
	(footprint ""
		(layer "F.Cu")
		(at 87.122254 -334.978502)
		(property "Reference" "PU35"
			(at -3.048254 -8.529828 0)
			(unlocked yes)
			(layer "F.SilkS")
			(effects
				(font
					(size 0.7874 0.5842)
					(thickness 0.1524)
				)
				(justify left)
			)
		)
		(property "Value" ""
			(at 0 0 0)
			(layer "F.Fab")
			(effects
				(font
					(size 1.27 1.27)
				)
			)
		)
		(duplicate_pad_numbers_are_jumpers no)
		(fp_line
			(start -2.500122 -2.999994)
			(end -2.24409 -2.999994)
			(stroke
				(width 0.1524)
				(type default)
			)
			(layer "F.SilkS")
		)
		(fp_line
			(start -2.500122 -2.529078)
			(end -2.500122 -2.999994)
			(stroke
				(width 0.1524)
				(type default)
			)
			(layer "F.SilkS")
		)
		(fp_line
			(start -2.500122 0.6604)
			(end -2.500122 0.229108)
			(stroke
				(width 0.1524)
				(type default)
			)
			(layer "F.SilkS")
		)
		(fp_line
			(start -2.500122 2.999994)
			(end -2.500122 2.339594)
			(stroke
				(width 0.1524)
				(type default)
			)
			(layer "F.SilkS")
		)
		(fp_line
			(start -2.2987 2.999994)
			(end -2.500122 2.999994)
			(stroke
				(width 0.1524)
				(type default)
			)
			(layer "F.SilkS")
		)
		(fp_line
			(start 2.31394 -2.999994)
			(end 2.500122 -2.999994)
			(stroke
				(width 0.1524)
				(type default)
			)
			(layer "F.SilkS")
		)
		(fp_line
			(start 2.500122 -2.999994)
			(end 2.500122 -2.44348)
			(stroke
				(width 0.1524)
				(type default)
			)
			(layer "F.SilkS")
		)
		(fp_line
			(start 2.500122 2.339594)
			(end 2.500122 2.999994)
			(stroke
				(width 0.1524)
				(type default)
			)
			(layer "F.SilkS")
		)
		(fp_line
			(start 2.500122 2.999994)
			(end 2.2987 2.999994)
			(stroke
				(width 0.1524)
				(type default)
			)
			(layer "F.SilkS")
		)
		(fp_poly
			(pts
				(xy -2.737612 -2.387092) (xy -3.410966 -2.611628) (xy -2.962148 -3.0607)
			)
			(stroke
				(width 0)
				(type default)
			)
			(fill yes)
			(layer "F.SilkS")
		)
		(fp_line
			(start -2.500122 -2.999994)
			(end 2.500122 -2.999994)
			(stroke
				(width 0.1)
				(type default)
			)
			(layer "F.Fab")
		)
		(fp_line
			(start -2.500122 2.999994)
			(end -2.500122 -2.999994)
			(stroke
				(width 0.1)
				(type default)
			)
			(layer "F.Fab")
		)
		(fp_line
			(start 2.500122 -2.999994)
			(end 2.500122 2.999994)
			(stroke
				(width 0.1)
				(type default)
			)
			(layer "F.Fab")
		)
		(fp_line
			(start 2.500122 2.999994)
			(end -2.500122 2.999994)
			(stroke
				(width 0.1)
				(type default)
			)
			(layer "F.Fab")
		)
		(fp_poly
			(pts
				(xy -4.218432 -2.783078) (xy -4.218432 -1.767078) (xy -3.202432 -2.275078)
			)
			(stroke
				(width 0)
				(type default)
			)
			(fill yes)
			(layer "F.Fab")
		)
		(pad "1" smd rect
			(at -2.400046 -2.275078 90)
			(size 0.2286 0.6096)
			(layers "F.Cu" "F.Mask" "F.Paste")
			(net "PVDDCR_CPU1_P1_VOS1")
		)
		(pad "2" smd rect
			(at -2.400046 -1.82499 90)
			(size 0.2286 0.6096)
			(layers "F.Cu" "F.Mask" "F.Paste")
			(net "GND")
		)
		(pad "3" smd rect
			(at -2.400046 -1.374902 90)
			(size 0.2286 0.6096)
			(layers "F.Cu" "F.Mask" "F.Paste")
			(net "PVDDCR_CPU1_P1_VCC1")
		)
		(pad "4" smd rect
			(at -2.400046 -0.925068 90)
			(size 0.2286 0.6096)
			(layers "F.Cu" "F.Mask" "F.Paste")
			(net "PVDDCR_CPU1_P1_PVCC")
		)
		(pad "5" smd rect
			(at -2.400046 -0.47498 90)
			(size 0.2286 0.6096)
			(layers "F.Cu" "F.Mask" "F.Paste")
			(net "GND")
		)
		(pad "6" smd rect
			(at -2.400046 -0.024892 90)
			(size 0.2286 0.6096)
			(layers "F.Cu" "F.Mask" "F.Paste")
			(net "NC_PVDDCR_CPU1_P1_GL1_1")
		)
		(pad "7_9-20_24" smd circle
			(at 0 1.150112 90)
			(size 0 0)
			(layers "F.Cu" "F.Mask" "F.Paste")
			(net "GND")
		)
		(pad "10_19" smd rect
			(at 0 2.899918 90)
			(size 0.6096 4.318)
			(layers "F.Cu" "F.Mask" "F.Paste")
			(net "SW_PVDDCR_CPU1_P1_SW1")
		)
		(pad "25_29" smd rect
			(at 1.549908 -1.279906 270)
			(size 2.0574 2.3114)
			(layers "F.Cu" "F.Mask" "F.Paste")
			(net "SW_P12V_AUX_PVDDCR_CPU1_P1_FLT")
		)
		(pad "30" smd rect
			(at 2.05994 -2.899918)
			(size 0.2286 0.6096)
			(layers "F.Cu" "F.Mask" "F.Paste")
			(net "SW_P12V_AUX_PVDDCR_CPU1_P1_FLT")
		)
		(pad "31" smd rect
			(at 1.610106 -2.899918)
			(size 0.2286 0.6096)
			(layers "F.Cu" "F.Mask" "F.Paste")
			(net "NC_PVDDCR_CPU1_P1_DNC1")
		)
		(pad "32" smd rect
			(at 1.160018 -2.899918)
			(size 0.2286 0.6096)
			(layers "F.Cu" "F.Mask" "F.Paste")
			(net "SW_PVDDCR_CPU1_P1_BOOTR1")
		)
		(pad "33" smd rect
			(at 0.70993 -2.899918)
			(size 0.2286 0.6096)
			(layers "F.Cu" "F.Mask" "F.Paste")
			(net "SW_PVDDCR_CPU1_P1_BOOT1")
		)
		(pad "34" smd rect
			(at 0.260096 -2.899918)
			(size 0.2286 0.6096)
			(layers "F.Cu" "F.Mask" "F.Paste")
			(net "PVDDCR_CPU1_P1_PWM1")
		)
		(pad "35" smd rect
			(at -0.189992 -2.899918)
			(size 0.2286 0.6096)
			(layers "F.Cu" "F.Mask" "F.Paste")
			(net "PVDDCR_CPU1_P1_VCC1")
		)
		(pad "36" smd rect
			(at -0.64008 -2.899918)
			(size 0.2286 0.6096)
			(layers "F.Cu" "F.Mask" "F.Paste")
			(net "PVDDCR_CPU1_P1_TEMP0")
		)
		(pad "37" smd rect
			(at -1.089914 -2.899918)
			(size 0.2286 0.6096)
			(layers "F.Cu" "F.Mask" "F.Paste")
			(net "PVDDCR_CPU1_P1_LSET1")
		)
		(pad "38" smd rect
			(at -1.540002 -2.899918)
			(size 0.2286 0.6096)
			(layers "F.Cu" "F.Mask" "F.Paste")
			(net "PVDDCR_CPU1_P1_IMON1")
		)
		(pad "39" smd rect
			(at -1.99009 -2.899918)
			(size 0.2286 0.6096)
			(layers "F.Cu" "F.Mask" "F.Paste")
			(net "PVDDCR_CPU1_P1_VCCS")
		)
		(pad "40" smd rect
			(at -0.87503 -1.27508)
			(size 1.7526 1.9558)
			(layers "F.Cu" "F.Mask" "F.Paste")
			(net "GND")
		)
		(pad "41" smd rect
			(at -1.525016 0.249936 270)
			(size 0.3048 0.4572)
			(layers "F.Cu" "F.Mask" "F.Paste")
			(net "NC_PVDDCR_CPU1_P1_GL2_1")
		)
		(zone
			(layer "F.Cu")
			(hatch none 0.5)
			(connect_pads
				(clearance 0)
			)
			(min_thickness 0.25)
			(keepout
				(tracks not_allowed)
				(vias allowed)
				(pads allowed)
				(copperpour not_allowed)
				(footprints allowed)
			)
			(placement
				(enabled no)
				(sheetname "")
			)
			(fill
				(thermal_gap 0.5)
				(thermal_bridge_width 0.5)
				(island_removal_mode 0)
			)
			(polygon
				(pts
					(xy 84.622132 -332.40599) (xy 84.622132 -332.727808) (xy 89.622376 -332.727808) (xy 89.622376 -332.394306)
					(xy 89.332054 -332.394306) (xy 89.332054 -332.434184) (xy 84.912454 -332.434184) (xy 84.912454 -332.40599)
				)
			)
		)
		(zone
			(layer "F.Cu")
			(hatch none 0.5)
			(connect_pads
				(clearance 0)
			)
			(min_thickness 0.25)
			(keepout
				(tracks not_allowed)
				(vias allowed)
				(pads allowed)
				(copperpour not_allowed)
				(footprints allowed)
			)
			(placement
				(enabled no)
				(sheetname "")
			)
			(fill
				(thermal_gap 0.5)
				(thermal_bridge_width 0.5)
				(island_removal_mode 0)
			)
			(polygon
				(pts
					(xy 87.174324 -335.224882) (xy 87.174324 -337.282282) (xy 85.320124 -337.282282) (xy 85.320124 -337.041236)
					(xy 85.077808 -337.041236) (xy 85.077808 -337.52282) (xy 88.87587 -337.52282) (xy 88.87587 -337.337908)
					(xy 87.465662 -337.337908) (xy 87.465662 -335.178908) (xy 89.622376 -335.178908) (xy 89.622376 -334.929226)
					(xy 87.46998 -334.929226)
				)
			)
		)
	)
	(footprint ""
		(layer "F.Cu")
		(at 105.960164 -255.555242)
		(property "Reference" "C2671"
			(at 0 0 0)
			(layer "F.SilkS")
			(hide yes)
			(effects
				(font
					(size 1.27 1.27)
				)
			)
		)
		(property "Value" ""
			(at 0 0 0)
			(layer "F.Fab")
			(effects
				(font
					(size 1.27 1.27)
				)
			)
		)
		(duplicate_pad_numbers_are_jumpers no)
		(fp_line
			(start -0.7874 -0.4064)
			(end 0.7874 -0.4064)
			(stroke
				(width 0.1524)
				(type default)
			)
			(layer "F.SilkS")
		)
		(fp_line
			(start -0.7874 0.4064)
			(end -0.7874 -0.4064)
			(stroke
				(width 0.1524)
				(type default)
			)
			(layer "F.SilkS")
		)
		(fp_line
			(start 0.7874 -0.4064)
			(end 0.7874 0.4064)
			(stroke
				(width 0.1524)
				(type default)
			)
			(layer "F.SilkS")
		)
		(fp_line
			(start 0.7874 0.4064)
			(end -0.7874 0.4064)
			(stroke
				(width 0.1524)
				(type default)
			)
			(layer "F.SilkS")
		)
		(fp_line
			(start -0.67945 -0.305054)
			(end -0.12065 -0.305054)
			(stroke
				(width 0.1)
				(type default)
			)
			(layer "F.Fab")
		)
		(fp_line
			(start -0.67945 0.3048)
			(end -0.67945 -0.305054)
			(stroke
				(width 0.1)
				(type default)
			)
			(layer "F.Fab")
		)
		(fp_line
			(start -0.12065 -0.305054)
			(end -0.12065 -0.2794)
			(stroke
				(width 0.1)
				(type default)
			)
			(layer "F.Fab")
		)
		(fp_line
			(start -0.12065 -0.2794)
			(end 0.12065 -0.2794)
			(stroke
				(width 0.1)
				(type default)
			)
			(layer "F.Fab")
		)
		(fp_line
			(start -0.12065 0.2794)
			(end -0.12065 0.3048)
			(stroke
				(width 0.1)
				(type default)
			)
			(layer "F.Fab")
		)
		(fp_line
			(start -0.12065 0.3048)
			(end -0.67945 0.3048)
			(stroke
				(width 0.1)
				(type default)
			)
			(layer "F.Fab")
		)
		(fp_line
			(start 0.120396 0.2794)
			(end -0.12065 0.2794)
			(stroke
				(width 0.1)
				(type default)
			)
			(layer "F.Fab")
		)
		(fp_line
			(start 0.120396 0.3048)
			(end 0.120396 0.2794)
			(stroke
				(width 0.1)
				(type default)
			)
			(layer "F.Fab")
		)
		(fp_line
			(start 0.12065 -0.3048)
			(end 0.67945 -0.3048)
			(stroke
				(width 0.1)
				(type default)
			)
			(layer "F.Fab")
		)
		(fp_line
			(start 0.12065 -0.2794)
			(end 0.12065 -0.3048)
			(stroke
				(width 0.1)
				(type default)
			)
			(layer "F.Fab")
		)
		(fp_line
			(start 0.67945 -0.3048)
			(end 0.67945 0.3048)
			(stroke
				(width 0.1)
				(type default)
			)
			(layer "F.Fab")
		)
		(fp_line
			(start 0.67945 0.3048)
			(end 0.120396 0.3048)
			(stroke
				(width 0.1)
				(type default)
			)
			(layer "F.Fab")
		)
		(pad "1" smd circle
			(at -0.40005 0)
			(size 0 0)
			(layers "F.Cu" "F.Mask" "F.Paste")
			(net "PVDD18_S5_P1")
		)
		(pad "2" smd circle
			(at 0.40005 0)
			(size 0 0)
			(layers "F.Cu" "F.Mask" "F.Paste")
			(net "GND")
		)
	)
	(footprint ""
		(layer "F.Cu")
		(at 307.741574 -24.090884)
		(property "Reference" "C22"
			(at 0 0 0)
			(layer "F.SilkS")
			(hide yes)
			(effects
				(font
					(size 1.27 1.27)
				)
			)
		)
		(property "Value" ""
			(at 0 0 0)
			(layer "F.Fab")
			(effects
				(font
					(size 1.27 1.27)
				)
			)
		)
		(duplicate_pad_numbers_are_jumpers no)
		(fp_line
			(start -0.7874 -0.4064)
			(end 0.7874 -0.4064)
			(stroke
				(width 0.1524)
				(type default)
			)
			(layer "F.SilkS")
		)
		(fp_line
			(start -0.7874 0.4064)
			(end -0.7874 -0.4064)
			(stroke
				(width 0.1524)
				(type default)
			)
			(layer "F.SilkS")
		)
		(fp_line
			(start 0.7874 -0.4064)
			(end 0.7874 0.4064)
			(stroke
				(width 0.1524)
				(type default)
			)
			(layer "F.SilkS")
		)
		(fp_line
			(start 0.7874 0.4064)
			(end -0.7874 0.4064)
			(stroke
				(width 0.1524)
				(type default)
			)
			(layer "F.SilkS")
		)
		(fp_line
			(start -0.67945 -0.305054)
			(end -0.12065 -0.305054)
			(stroke
				(width 0.1)
				(type default)
			)
			(layer "F.Fab")
		)
		(fp_line
			(start -0.67945 0.3048)
			(end -0.67945 -0.305054)
			(stroke
				(width 0.1)
				(type default)
			)
			(layer "F.Fab")
		)
		(fp_line
			(start -0.12065 -0.305054)
			(end -0.12065 -0.2794)
			(stroke
				(width 0.1)
				(type default)
			)
			(layer "F.Fab")
		)
		(fp_line
			(start -0.12065 -0.2794)
			(end 0.12065 -0.2794)
			(stroke
				(width 0.1)
				(type default)
			)
			(layer "F.Fab")
		)
		(fp_line
			(start -0.12065 0.2794)
			(end -0.12065 0.3048)
			(stroke
				(width 0.1)
				(type default)
			)
			(layer "F.Fab")
		)
		(fp_line
			(start -0.12065 0.3048)
			(end -0.67945 0.3048)
			(stroke
				(width 0.1)
				(type default)
			)
			(layer "F.Fab")
		)
		(fp_line
			(start 0.120396 0.2794)
			(end -0.12065 0.2794)
			(stroke
				(width 0.1)
				(type default)
			)
			(layer "F.Fab")
		)
		(fp_line
			(start 0.120396 0.3048)
			(end 0.120396 0.2794)
			(stroke
				(width 0.1)
				(type default)
			)
			(layer "F.Fab")
		)
		(fp_line
			(start 0.12065 -0.3048)
			(end 0.67945 -0.3048)
			(stroke
				(width 0.1)
				(type default)
			)
			(layer "F.Fab")
		)
		(fp_line
			(start 0.12065 -0.2794)
			(end 0.12065 -0.3048)
			(stroke
				(width 0.1)
				(type default)
			)
			(layer "F.Fab")
		)
		(fp_line
			(start 0.67945 -0.3048)
			(end 0.67945 0.3048)
			(stroke
				(width 0.1)
				(type default)
			)
			(layer "F.Fab")
		)
		(fp_line
			(start 0.67945 0.3048)
			(end 0.120396 0.3048)
			(stroke
				(width 0.1)
				(type default)
			)
			(layer "F.Fab")
		)
		(pad "1" smd circle
			(at -0.40005 0)
			(size 0 0)
			(layers "F.Cu" "F.Mask" "F.Paste")
			(net "U9_NR")
		)
		(pad "2" smd circle
			(at 0.40005 0)
			(size 0 0)
			(layers "F.Cu" "F.Mask" "F.Paste")
			(net "GND")
		)
	)
	(footprint ""
		(layer "F.Cu")
		(at 66.666364 -151.549862 -90)
		(property "Reference" "PC22"
			(at 0 0 270)
			(layer "F.SilkS")
			(hide yes)
			(effects
				(font
					(size 1.27 1.27)
				)
			)
		)
		(property "Value" ""
			(at 0 0 270)
			(layer "F.Fab")
			(effects
				(font
					(size 1.27 1.27)
				)
			)
		)
		(duplicate_pad_numbers_are_jumpers no)
		(fp_line
			(start -0.7874 0.4064)
			(end -0.7874 -0.4064)
			(stroke
				(width 0.1524)
				(type default)
			)
			(layer "F.SilkS")
		)
		(fp_line
			(start 0.7874 0.4064)
			(end -0.7874 0.4064)
			(stroke
				(width 0.1524)
				(type default)
			)
			(layer "F.SilkS")
		)
		(fp_line
			(start -0.7874 -0.4064)
			(end 0.7874 -0.4064)
			(stroke
				(width 0.1524)
				(type default)
			)
			(layer "F.SilkS")
		)
		(fp_line
			(start 0.7874 -0.4064)
			(end 0.7874 0.4064)
			(stroke
				(width 0.1524)
				(type default)
			)
			(layer "F.SilkS")
		)
		(fp_line
			(start -0.67945 0.3048)
			(end -0.67945 -0.305054)
			(stroke
				(width 0.1)
				(type default)
			)
			(layer "F.Fab")
		)
		(fp_line
			(start -0.12065 0.3048)
			(end -0.67945 0.3048)
			(stroke
				(width 0.1)
				(type default)
			)
			(layer "F.Fab")
		)
		(fp_line
			(start 0.120396 0.3048)
			(end 0.120396 0.2794)
			(stroke
				(width 0.1)
				(type default)
			)
			(layer "F.Fab")
		)
		(fp_line
			(start 0.67945 0.3048)
			(end 0.120396 0.3048)
			(stroke
				(width 0.1)
				(type default)
			)
			(layer "F.Fab")
		)
		(fp_line
			(start -0.12065 0.2794)
			(end -0.12065 0.3048)
			(stroke
				(width 0.1)
				(type default)
			)
			(layer "F.Fab")
		)
		(fp_line
			(start 0.120396 0.2794)
			(end -0.12065 0.2794)
			(stroke
				(width 0.1)
				(type default)
			)
			(layer "F.Fab")
		)
		(fp_line
			(start -0.12065 -0.2794)
			(end 0.12065 -0.2794)
			(stroke
				(width 0.1)
				(type default)
			)
			(layer "F.Fab")
		)
		(fp_line
			(start 0.12065 -0.2794)
			(end 0.12065 -0.3048)
			(stroke
				(width 0.1)
				(type default)
			)
			(layer "F.Fab")
		)
		(fp_line
			(start 0.12065 -0.3048)
			(end 0.67945 -0.3048)
			(stroke
				(width 0.1)
				(type default)
			)
			(layer "F.Fab")
		)
		(fp_line
			(start 0.67945 -0.3048)
			(end 0.67945 0.3048)
			(stroke
				(width 0.1)
				(type default)
			)
			(layer "F.Fab")
		)
		(fp_line
			(start -0.67945 -0.305054)
			(end -0.12065 -0.305054)
			(stroke
				(width 0.1)
				(type default)
			)
			(layer "F.Fab")
		)
		(fp_line
			(start -0.12065 -0.305054)
			(end -0.12065 -0.2794)
			(stroke
				(width 0.1)
				(type default)
			)
			(layer "F.Fab")
		)
		(pad "1" smd circle
			(at -0.40005 0 270)
			(size 0 0)
			(layers "F.Cu" "F.Mask" "F.Paste")
			(net "SW_P12V_AUX_PVDD18_S5_P1_FLT")
		)
		(pad "2" smd circle
			(at 0.40005 0 270)
			(size 0 0)
			(layers "F.Cu" "F.Mask" "F.Paste")
			(net "GND")
		)
	)
	(footprint ""
		(layer "F.Cu")
		(at 2.677922 -58.875168 -90)
		(property "Reference" "R930"
			(at 0 0 270)
			(layer "F.SilkS")
			(hide yes)
			(effects
				(font
					(size 1.27 1.27)
				)
			)
		)
		(property "Value" ""
			(at 0 0 270)
			(layer "F.Fab")
			(effects
				(font
					(size 1.27 1.27)
				)
			)
		)
		(duplicate_pad_numbers_are_jumpers no)
		(fp_line
			(start -0.7874 0.4064)
			(end -0.7874 -0.4064)
			(stroke
				(width 0.1524)
				(type default)
			)
			(layer "F.SilkS")
		)
		(fp_line
			(start 0.7874 0.4064)
			(end -0.7874 0.4064)
			(stroke
				(width 0.1524)
				(type default)
			)
			(layer "F.SilkS")
		)
		(fp_line
			(start -0.7874 -0.4064)
			(end 0.7874 -0.4064)
			(stroke
				(width 0.1524)
				(type default)
			)
			(layer "F.SilkS")
		)
		(fp_line
			(start 0.7874 -0.4064)
			(end 0.7874 0.4064)
			(stroke
				(width 0.1524)
				(type default)
			)
			(layer "F.SilkS")
		)
		(fp_line
			(start -0.67945 0.3048)
			(end -0.67945 -0.305054)
			(stroke
				(width 0.1)
				(type default)
			)
			(layer "F.Fab")
		)
		(fp_line
			(start -0.12065 0.3048)
			(end -0.67945 0.3048)
			(stroke
				(width 0.1)
				(type default)
			)
			(layer "F.Fab")
		)
		(fp_line
			(start 0.120396 0.3048)
			(end 0.120396 0.2794)
			(stroke
				(width 0.1)
				(type default)
			)
			(layer "F.Fab")
		)
		(fp_line
			(start 0.67945 0.3048)
			(end 0.120396 0.3048)
			(stroke
				(width 0.1)
				(type default)
			)
			(layer "F.Fab")
		)
		(fp_line
			(start -0.12065 0.2794)
			(end -0.12065 0.3048)
			(stroke
				(width 0.1)
				(type default)
			)
			(layer "F.Fab")
		)
		(fp_line
			(start 0.120396 0.2794)
			(end -0.12065 0.2794)
			(stroke
				(width 0.1)
				(type default)
			)
			(layer "F.Fab")
		)
		(fp_line
			(start -0.12065 -0.2794)
			(end 0.12065 -0.2794)
			(stroke
				(width 0.1)
				(type default)
			)
			(layer "F.Fab")
		)
		(fp_line
			(start 0.12065 -0.2794)
			(end 0.12065 -0.3048)
			(stroke
				(width 0.1)
				(type default)
			)
			(layer "F.Fab")
		)
		(fp_line
			(start 0.12065 -0.3048)
			(end 0.67945 -0.3048)
			(stroke
				(width 0.1)
				(type default)
			)
			(layer "F.Fab")
		)
		(fp_line
			(start 0.67945 -0.3048)
			(end 0.67945 0.3048)
			(stroke
				(width 0.1)
				(type default)
			)
			(layer "F.Fab")
		)
		(fp_line
			(start -0.67945 -0.305054)
			(end -0.12065 -0.305054)
			(stroke
				(width 0.1)
				(type default)
			)
			(layer "F.Fab")
		)
		(fp_line
			(start -0.12065 -0.305054)
			(end -0.12065 -0.2794)
			(stroke
				(width 0.1)
				(type default)
			)
			(layer "F.Fab")
		)
		(pad "1" smd circle
			(at -0.40005 0 270)
			(size 0 0)
			(layers "F.Cu" "F.Mask" "F.Paste")
			(net "CPU1_XTRIG_L5")
		)
		(pad "2" smd circle
			(at 0.40005 0 270)
			(size 0 0)
			(layers "F.Cu" "F.Mask" "F.Paste")
			(net "CPU1_XTRIG_R1_L5")
		)
	)
	(footprint ""
		(layer "F.Cu")
		(at 208.894426 -115.657376)
		(property "Reference" "R195"
			(at 0 0 0)
			(layer "F.SilkS")
			(hide yes)
			(effects
				(font
					(size 1.27 1.27)
				)
			)
		)
		(property "Value" ""
			(at 0 0 0)
			(layer "F.Fab")
			(effects
				(font
					(size 1.27 1.27)
				)
			)
		)
		(duplicate_pad_numbers_are_jumpers no)
		(fp_line
			(start -0.7874 -0.4064)
			(end 0.7874 -0.4064)
			(stroke
				(width 0.1524)
				(type default)
			)
			(layer "F.SilkS")
		)
		(fp_line
			(start -0.7874 0.4064)
			(end -0.7874 -0.4064)
			(stroke
				(width 0.1524)
				(type default)
			)
			(layer "F.SilkS")
		)
		(fp_line
			(start 0.7874 -0.4064)
			(end 0.7874 0.4064)
			(stroke
				(width 0.1524)
				(type default)
			)
			(layer "F.SilkS")
		)
		(fp_line
			(start 0.7874 0.4064)
			(end -0.7874 0.4064)
			(stroke
				(width 0.1524)
				(type default)
			)
			(layer "F.SilkS")
		)
		(fp_line
			(start -0.67945 -0.305054)
			(end -0.12065 -0.305054)
			(stroke
				(width 0.1)
				(type default)
			)
			(layer "F.Fab")
		)
		(fp_line
			(start -0.67945 0.3048)
			(end -0.67945 -0.305054)
			(stroke
				(width 0.1)
				(type default)
			)
			(layer "F.Fab")
		)
		(fp_line
			(start -0.12065 -0.305054)
			(end -0.12065 -0.2794)
			(stroke
				(width 0.1)
				(type default)
			)
			(layer "F.Fab")
		)
		(fp_line
			(start -0.12065 -0.2794)
			(end 0.12065 -0.2794)
			(stroke
				(width 0.1)
				(type default)
			)
			(layer "F.Fab")
		)
		(fp_line
			(start -0.12065 0.2794)
			(end -0.12065 0.3048)
			(stroke
				(width 0.1)
				(type default)
			)
			(layer "F.Fab")
		)
		(fp_line
			(start -0.12065 0.3048)
			(end -0.67945 0.3048)
			(stroke
				(width 0.1)
				(type default)
			)
			(layer "F.Fab")
		)
		(fp_line
			(start 0.120396 0.2794)
			(end -0.12065 0.2794)
			(stroke
				(width 0.1)
				(type default)
			)
			(layer "F.Fab")
		)
		(fp_line
			(start 0.120396 0.3048)
			(end 0.120396 0.2794)
			(stroke
				(width 0.1)
				(type default)
			)
			(layer "F.Fab")
		)
		(fp_line
			(start 0.12065 -0.3048)
			(end 0.67945 -0.3048)
			(stroke
				(width 0.1)
				(type default)
			)
			(layer "F.Fab")
		)
		(fp_line
			(start 0.12065 -0.2794)
			(end 0.12065 -0.3048)
			(stroke
				(width 0.1)
				(type default)
			)
			(layer "F.Fab")
		)
		(fp_line
			(start 0.67945 -0.3048)
			(end 0.67945 0.3048)
			(stroke
				(width 0.1)
				(type default)
			)
			(layer "F.Fab")
		)
		(fp_line
			(start 0.67945 0.3048)
			(end 0.120396 0.3048)
			(stroke
				(width 0.1)
				(type default)
			)
			(layer "F.Fab")
		)
		(pad "1" smd circle
			(at -0.40005 0)
			(size 0 0)
			(layers "F.Cu" "F.Mask" "F.Paste")
			(net "FM_CPU1_PWRGD_OUT")
		)
		(pad "2" smd circle
			(at 0.40005 0)
			(size 0 0)
			(layers "F.Cu" "F.Mask" "F.Paste")
			(net "CPU1_PWRGD_OUT")
		)
	)
	(footprint ""
		(layer "F.Cu")
		(at 261.468616 -75.770994 180)
		(property "Reference" "R3773"
			(at 0 0 180)
			(layer "F.SilkS")
			(hide yes)
			(effects
				(font
					(size 1.27 1.27)
				)
			)
		)
		(property "Value" ""
			(at 0 0 180)
			(layer "F.Fab")
			(effects
				(font
					(size 1.27 1.27)
				)
			)
		)
		(duplicate_pad_numbers_are_jumpers no)
		(fp_line
			(start 0.7874 0.4064)
			(end -0.7874 0.4064)
			(stroke
				(width 0.1524)
				(type default)
			)
			(layer "F.SilkS")
		)
		(fp_line
			(start 0.7874 -0.4064)
			(end 0.7874 0.4064)
			(stroke
				(width 0.1524)
				(type default)
			)
			(layer "F.SilkS")
		)
		(fp_line
			(start -0.7874 0.4064)
			(end -0.7874 -0.4064)
			(stroke
				(width 0.1524)
				(type default)
			)
			(layer "F.SilkS")
		)
		(fp_line
			(start -0.7874 -0.4064)
			(end 0.7874 -0.4064)
			(stroke
				(width 0.1524)
				(type default)
			)
			(layer "F.SilkS")
		)
		(fp_line
			(start 0.67945 0.3048)
			(end 0.120396 0.3048)
			(stroke
				(width 0.1)
				(type default)
			)
			(layer "F.Fab")
		)
		(fp_line
			(start 0.67945 -0.3048)
			(end 0.67945 0.3048)
			(stroke
				(width 0.1)
				(type default)
			)
			(layer "F.Fab")
		)
		(fp_line
			(start 0.12065 -0.2794)
			(end 0.12065 -0.3048)
			(stroke
				(width 0.1)
				(type default)
			)
			(layer "F.Fab")
		)
		(fp_line
			(start 0.12065 -0.3048)
			(end 0.67945 -0.3048)
			(stroke
				(width 0.1)
				(type default)
			)
			(layer "F.Fab")
		)
		(fp_line
			(start 0.120396 0.3048)
			(end 0.120396 0.2794)
			(stroke
				(width 0.1)
				(type default)
			)
			(layer "F.Fab")
		)
		(fp_line
			(start 0.120396 0.2794)
			(end -0.12065 0.2794)
			(stroke
				(width 0.1)
				(type default)
			)
			(layer "F.Fab")
		)
		(fp_line
			(start -0.12065 0.3048)
			(end -0.67945 0.3048)
			(stroke
				(width 0.1)
				(type default)
			)
			(layer "F.Fab")
		)
		(fp_line
			(start -0.12065 0.2794)
			(end -0.12065 0.3048)
			(stroke
				(width 0.1)
				(type default)
			)
			(layer "F.Fab")
		)
		(fp_line
			(start -0.12065 -0.2794)
			(end 0.12065 -0.2794)
			(stroke
				(width 0.1)
				(type default)
			)
			(layer "F.Fab")
		)
		(fp_line
			(start -0.12065 -0.305054)
			(end -0.12065 -0.2794)
			(stroke
				(width 0.1)
				(type default)
			)
			(layer "F.Fab")
		)
		(fp_line
			(start -0.67945 0.3048)
			(end -0.67945 -0.305054)
			(stroke
				(width 0.1)
				(type default)
			)
			(layer "F.Fab")
		)
		(fp_line
			(start -0.67945 -0.305054)
			(end -0.12065 -0.305054)
			(stroke
				(width 0.1)
				(type default)
			)
			(layer "F.Fab")
		)
		(pad "1" smd circle
			(at -0.40005 0 180)
			(size 0 0)
			(layers "F.Cu" "F.Mask" "F.Paste")
			(net "P3V3_AUX")
		)
		(pad "2" smd circle
			(at 0.40005 0 180)
			(size 0 0)
			(layers "F.Cu" "F.Mask" "F.Paste")
			(net "RST_SMB_E1S_0_N")
		)
	)
	(footprint ""
		(layer "F.Cu")
		(at 249.28703 -45.995082 90)
		(property "Reference" "PR3962"
			(at 0 0 90)
			(layer "F.SilkS")
			(hide yes)
			(effects
				(font
					(size 1.27 1.27)
				)
			)
		)
		(property "Value" ""
			(at 0 0 90)
			(layer "F.Fab")
			(effects
				(font
					(size 1.27 1.27)
				)
			)
		)
		(duplicate_pad_numbers_are_jumpers no)
		(fp_line
			(start 0.7874 -0.4064)
			(end 0.7874 0.4064)
			(stroke
				(width 0.1524)
				(type default)
			)
			(layer "F.SilkS")
		)
		(fp_line
			(start -0.7874 -0.4064)
			(end 0.7874 -0.4064)
			(stroke
				(width 0.1524)
				(type default)
			)
			(layer "F.SilkS")
		)
		(fp_line
			(start 0.7874 0.4064)
			(end -0.7874 0.4064)
			(stroke
				(width 0.1524)
				(type default)
			)
			(layer "F.SilkS")
		)
		(fp_line
			(start -0.7874 0.4064)
			(end -0.7874 -0.4064)
			(stroke
				(width 0.1524)
				(type default)
			)
			(layer "F.SilkS")
		)
		(fp_line
			(start -0.12065 -0.305054)
			(end -0.12065 -0.2794)
			(stroke
				(width 0.1)
				(type default)
			)
			(layer "F.Fab")
		)
		(fp_line
			(start -0.67945 -0.305054)
			(end -0.12065 -0.305054)
			(stroke
				(width 0.1)
				(type default)
			)
			(layer "F.Fab")
		)
		(fp_line
			(start 0.67945 -0.3048)
			(end 0.67945 0.3048)
			(stroke
				(width 0.1)
				(type default)
			)
			(layer "F.Fab")
		)
		(fp_line
			(start 0.12065 -0.3048)
			(end 0.67945 -0.3048)
			(stroke
				(width 0.1)
				(type default)
			)
			(layer "F.Fab")
		)
		(fp_line
			(start 0.12065 -0.2794)
			(end 0.12065 -0.3048)
			(stroke
				(width 0.1)
				(type default)
			)
			(layer "F.Fab")
		)
		(fp_line
			(start -0.12065 -0.2794)
			(end 0.12065 -0.2794)
			(stroke
				(width 0.1)
				(type default)
			)
			(layer "F.Fab")
		)
		(fp_line
			(start 0.120396 0.2794)
			(end -0.12065 0.2794)
			(stroke
				(width 0.1)
				(type default)
			)
			(layer "F.Fab")
		)
		(fp_line
			(start -0.12065 0.2794)
			(end -0.12065 0.3048)
			(stroke
				(width 0.1)
				(type default)
			)
			(layer "F.Fab")
		)
		(fp_line
			(start 0.67945 0.3048)
			(end 0.120396 0.3048)
			(stroke
				(width 0.1)
				(type default)
			)
			(layer "F.Fab")
		)
		(fp_line
			(start 0.120396 0.3048)
			(end 0.120396 0.2794)
			(stroke
				(width 0.1)
				(type default)
			)
			(layer "F.Fab")
		)
		(fp_line
			(start -0.12065 0.3048)
			(end -0.67945 0.3048)
			(stroke
				(width 0.1)
				(type default)
			)
			(layer "F.Fab")
		)
		(fp_line
			(start -0.67945 0.3048)
			(end -0.67945 -0.305054)
			(stroke
				(width 0.1)
				(type default)
			)
			(layer "F.Fab")
		)
		(pad "1" smd circle
			(at -0.40005 0 90)
			(size 0 0)
			(layers "F.Cu" "F.Mask" "F.Paste")
			(net "P12V_E1S_OV_0")
		)
		(pad "2" smd circle
			(at 0.40005 0 90)
			(size 0 0)
			(layers "F.Cu" "F.Mask" "F.Paste")
			(net "GND")
		)
	)
	(footprint ""
		(layer "F.Cu")
		(at 334.400906 -416.899344 -90)
		(property "Reference" "C6522"
			(at 0 0 270)
			(layer "F.SilkS")
			(hide yes)
			(effects
				(font
					(size 1.27 1.27)
				)
			)
		)
		(property "Value" ""
			(at 0 0 270)
			(layer "F.Fab")
			(effects
				(font
					(size 1.27 1.27)
				)
			)
		)
		(duplicate_pad_numbers_are_jumpers no)
		(fp_line
			(start -0.299974 0.150114)
			(end -0.299974 -0.150114)
			(stroke
				(width 0.1)
				(type default)
			)
			(layer "F.Fab")
		)
		(fp_line
			(start 0.299974 0.150114)
			(end -0.299974 0.150114)
			(stroke
				(width 0.1)
				(type default)
			)
			(layer "F.Fab")
		)
		(fp_line
			(start -0.299974 -0.150114)
			(end 0.299974 -0.150114)
			(stroke
				(width 0.1)
				(type default)
			)
			(layer "F.Fab")
		)
		(fp_line
			(start 0.299974 -0.150114)
			(end 0.299974 0.150114)
			(stroke
				(width 0.1)
				(type default)
			)
			(layer "F.Fab")
		)
		(pad "1" smd rect
			(at -0.2667 0 270)
			(size 0.3048 0.381)
			(layers "F.Cu" "F.Mask" "F.Paste")
			(net "P5E_CPU0_P0_TX_BUF_C_DN<10>")
		)
		(pad "2" smd rect
			(at 0.2667 0 270)
			(size 0.3048 0.381)
			(layers "F.Cu" "F.Mask" "F.Paste")
			(net "P5E_CPU0_P0_TX_BUF_DN<10>")
		)
	)
	(footprint ""
		(layer "F.Cu")
		(at 10.339832 -347.702632)
		(property "Reference" "H102"
			(at -4.555998 -5.990336 0)
			(unlocked yes)
			(layer "F.SilkS")
			(effects
				(font
					(size 0.7874 0.5842)
					(thickness 0.1524)
				)
				(justify left)
			)
		)
		(property "Value" ""
			(at 0 0 0)
			(layer "F.Fab")
			(effects
				(font
					(size 1.27 1.27)
				)
			)
		)
		(duplicate_pad_numbers_are_jumpers no)
		(pad "1" thru_hole circle
			(at 0 0)
			(size 10.0076 10.0076)
			(drill 5.6134)
			(layers "*.Cu" "*.Mask")
			(remove_unused_layers no)
			(net "GND")
			(clearance -1.9431)
		)
	)
	(footprint ""
		(layer "F.Cu")
		(at 349.717106 -416.899344 -90)
		(property "Reference" "C6532"
			(at 0 0 270)
			(layer "F.SilkS")
			(hide yes)
			(effects
				(font
					(size 1.27 1.27)
				)
			)
		)
		(property "Value" ""
			(at 0 0 270)
			(layer "F.Fab")
			(effects
				(font
					(size 1.27 1.27)
				)
			)
		)
		(duplicate_pad_numbers_are_jumpers no)
		(fp_line
			(start -0.299974 0.150114)
			(end -0.299974 -0.150114)
			(stroke
				(width 0.1)
				(type default)
			)
			(layer "F.Fab")
		)
		(fp_line
			(start 0.299974 0.150114)
			(end -0.299974 0.150114)
			(stroke
				(width 0.1)
				(type default)
			)
			(layer "F.Fab")
		)
		(fp_line
			(start -0.299974 -0.150114)
			(end 0.299974 -0.150114)
			(stroke
				(width 0.1)
				(type default)
			)
			(layer "F.Fab")
		)
		(fp_line
			(start 0.299974 -0.150114)
			(end 0.299974 0.150114)
			(stroke
				(width 0.1)
				(type default)
			)
			(layer "F.Fab")
		)
		(pad "1" smd rect
			(at -0.2667 0 270)
			(size 0.3048 0.381)
			(layers "F.Cu" "F.Mask" "F.Paste")
			(net "P5E_CPU0_P0_TX_BUF_C_DN<15>")
		)
		(pad "2" smd rect
			(at 0.2667 0 270)
			(size 0.3048 0.381)
			(layers "F.Cu" "F.Mask" "F.Paste")
			(net "P5E_CPU0_P0_TX_BUF_DN<15>")
		)
	)
	(footprint ""
		(layer "F.Cu")
		(at 14.892782 -404.341584 90)
		(property "Reference" "R658"
			(at 0 0 90)
			(layer "F.SilkS")
			(hide yes)
			(effects
				(font
					(size 1.27 1.27)
				)
			)
		)
		(property "Value" ""
			(at 0 0 90)
			(layer "F.Fab")
			(effects
				(font
					(size 1.27 1.27)
				)
			)
		)
		(duplicate_pad_numbers_are_jumpers no)
		(fp_line
			(start 0.7874 -0.4064)
			(end 0.7874 0.4064)
			(stroke
				(width 0.1524)
				(type default)
			)
			(layer "F.SilkS")
		)
		(fp_line
			(start -0.7874 -0.4064)
			(end 0.7874 -0.4064)
			(stroke
				(width 0.1524)
				(type default)
			)
			(layer "F.SilkS")
		)
		(fp_line
			(start 0.7874 0.4064)
			(end -0.7874 0.4064)
			(stroke
				(width 0.1524)
				(type default)
			)
			(layer "F.SilkS")
		)
		(fp_line
			(start -0.7874 0.4064)
			(end -0.7874 -0.4064)
			(stroke
				(width 0.1524)
				(type default)
			)
			(layer "F.SilkS")
		)
		(fp_line
			(start -0.12065 -0.305054)
			(end -0.12065 -0.2794)
			(stroke
				(width 0.1)
				(type default)
			)
			(layer "F.Fab")
		)
		(fp_line
			(start -0.67945 -0.305054)
			(end -0.12065 -0.305054)
			(stroke
				(width 0.1)
				(type default)
			)
			(layer "F.Fab")
		)
		(fp_line
			(start 0.67945 -0.3048)
			(end 0.67945 0.3048)
			(stroke
				(width 0.1)
				(type default)
			)
			(layer "F.Fab")
		)
		(fp_line
			(start 0.12065 -0.3048)
			(end 0.67945 -0.3048)
			(stroke
				(width 0.1)
				(type default)
			)
			(layer "F.Fab")
		)
		(fp_line
			(start 0.12065 -0.2794)
			(end 0.12065 -0.3048)
			(stroke
				(width 0.1)
				(type default)
			)
			(layer "F.Fab")
		)
		(fp_line
			(start -0.12065 -0.2794)
			(end 0.12065 -0.2794)
			(stroke
				(width 0.1)
				(type default)
			)
			(layer "F.Fab")
		)
		(fp_line
			(start 0.120396 0.2794)
			(end -0.12065 0.2794)
			(stroke
				(width 0.1)
				(type default)
			)
			(layer "F.Fab")
		)
		(fp_line
			(start -0.12065 0.2794)
			(end -0.12065 0.3048)
			(stroke
				(width 0.1)
				(type default)
			)
			(layer "F.Fab")
		)
		(fp_line
			(start 0.67945 0.3048)
			(end 0.120396 0.3048)
			(stroke
				(width 0.1)
				(type default)
			)
			(layer "F.Fab")
		)
		(fp_line
			(start 0.120396 0.3048)
			(end 0.120396 0.2794)
			(stroke
				(width 0.1)
				(type default)
			)
			(layer "F.Fab")
		)
		(fp_line
			(start -0.12065 0.3048)
			(end -0.67945 0.3048)
			(stroke
				(width 0.1)
				(type default)
			)
			(layer "F.Fab")
		)
		(fp_line
			(start -0.67945 0.3048)
			(end -0.67945 -0.305054)
			(stroke
				(width 0.1)
				(type default)
			)
			(layer "F.Fab")
		)
		(pad "1" smd circle
			(at -0.40005 0 90)
			(size 0 0)
			(layers "F.Cu" "F.Mask" "F.Paste")
			(net "P0V9_RETIMER_CPU1_PMSDA")
		)
		(pad "2" smd circle
			(at 0.40005 0 90)
			(size 0 0)
			(layers "F.Cu" "F.Mask" "F.Paste")
			(net "P0V9_RETIMER_CPU1_PMSDA_R")
		)
	)
	(footprint ""
		(layer "F.Cu")
		(at 124.968 -106.172 -90)
		(property "Reference" "U8007"
			(at 2.004314 -3.839972 90)
			(unlocked yes)
			(layer "F.SilkS")
			(effects
				(font
					(size 0.7874 0.5842)
					(thickness 0.1524)
				)
				(justify left)
			)
		)
		(property "Value" ""
			(at 0 0 270)
			(layer "F.Fab")
			(effects
				(font
					(size 1.27 1.27)
				)
			)
		)
		(duplicate_pad_numbers_are_jumpers no)
		(fp_line
			(start -1.868424 1.519936)
			(end 1.868424 1.519936)
			(stroke
				(width 0.1524)
				(type default)
			)
			(layer "F.SilkS")
		)
		(fp_line
			(start 1.868424 1.519936)
			(end 1.868424 -1.519936)
			(stroke
				(width 0.1524)
				(type default)
			)
			(layer "F.SilkS")
		)
		(fp_line
			(start -1.868424 -1.519936)
			(end -1.868424 1.519936)
			(stroke
				(width 0.1524)
				(type default)
			)
			(layer "F.SilkS")
		)
		(fp_line
			(start 1.868424 -1.519936)
			(end -1.868424 -1.519936)
			(stroke
				(width 0.1524)
				(type default)
			)
			(layer "F.SilkS")
		)
		(fp_line
			(start -0.700024 1.519936)
			(end 0.700024 1.519936)
			(stroke
				(width 0.1)
				(type default)
			)
			(layer "F.Fab")
		)
		(fp_line
			(start 0.700024 1.519936)
			(end 0.700024 -1.519936)
			(stroke
				(width 0.1)
				(type default)
			)
			(layer "F.Fab")
		)
		(fp_line
			(start -0.700024 -1.519936)
			(end -0.700024 1.519936)
			(stroke
				(width 0.1)
				(type default)
			)
			(layer "F.Fab")
		)
		(fp_line
			(start 0.700024 -1.519936)
			(end -0.700024 -1.519936)
			(stroke
				(width 0.1)
				(type default)
			)
			(layer "F.Fab")
		)
		(pad "1" smd rect
			(at -1.18491 -0.94996 180)
			(size 0.6096 1.0668)
			(layers "F.Cu" "F.Mask" "F.Paste")
			(net "UV_ADR_P2V5_COMP")
		)
		(pad "2" smd rect
			(at -1.18491 0.94996 180)
			(size 0.6096 1.0668)
			(layers "F.Cu" "F.Mask" "F.Paste")
			(net "GND")
		)
		(pad "3" smd rect
			(at 1.18491 0 180)
			(size 0.6096 1.0668)
			(layers "F.Cu" "F.Mask" "F.Paste")
			(net "Net_10850")
		)
	)
	(footprint ""
		(layer "F.Cu")
		(at 418.636958 -365.883952 180)
		(property "Reference" "R119"
			(at 0 0 180)
			(layer "F.SilkS")
			(hide yes)
			(effects
				(font
					(size 1.27 1.27)
				)
			)
		)
		(property "Value" ""
			(at 0 0 180)
			(layer "F.Fab")
			(effects
				(font
					(size 1.27 1.27)
				)
			)
		)
		(duplicate_pad_numbers_are_jumpers no)
		(fp_line
			(start 0.7874 0.4064)
			(end -0.7874 0.4064)
			(stroke
				(width 0.1524)
				(type default)
			)
			(layer "F.SilkS")
		)
		(fp_line
			(start 0.7874 -0.4064)
			(end 0.7874 0.4064)
			(stroke
				(width 0.1524)
				(type default)
			)
			(layer "F.SilkS")
		)
		(fp_line
			(start -0.7874 0.4064)
			(end -0.7874 -0.4064)
			(stroke
				(width 0.1524)
				(type default)
			)
			(layer "F.SilkS")
		)
		(fp_line
			(start -0.7874 -0.4064)
			(end 0.7874 -0.4064)
			(stroke
				(width 0.1524)
				(type default)
			)
			(layer "F.SilkS")
		)
		(fp_line
			(start 0.67945 0.3048)
			(end 0.120396 0.3048)
			(stroke
				(width 0.1)
				(type default)
			)
			(layer "F.Fab")
		)
		(fp_line
			(start 0.67945 -0.3048)
			(end 0.67945 0.3048)
			(stroke
				(width 0.1)
				(type default)
			)
			(layer "F.Fab")
		)
		(fp_line
			(start 0.12065 -0.2794)
			(end 0.12065 -0.3048)
			(stroke
				(width 0.1)
				(type default)
			)
			(layer "F.Fab")
		)
		(fp_line
			(start 0.12065 -0.3048)
			(end 0.67945 -0.3048)
			(stroke
				(width 0.1)
				(type default)
			)
			(layer "F.Fab")
		)
		(fp_line
			(start 0.120396 0.3048)
			(end 0.120396 0.2794)
			(stroke
				(width 0.1)
				(type default)
			)
			(layer "F.Fab")
		)
		(fp_line
			(start 0.120396 0.2794)
			(end -0.12065 0.2794)
			(stroke
				(width 0.1)
				(type default)
			)
			(layer "F.Fab")
		)
		(fp_line
			(start -0.12065 0.3048)
			(end -0.67945 0.3048)
			(stroke
				(width 0.1)
				(type default)
			)
			(layer "F.Fab")
		)
		(fp_line
			(start -0.12065 0.2794)
			(end -0.12065 0.3048)
			(stroke
				(width 0.1)
				(type default)
			)
			(layer "F.Fab")
		)
		(fp_line
			(start -0.12065 -0.2794)
			(end 0.12065 -0.2794)
			(stroke
				(width 0.1)
				(type default)
			)
			(layer "F.Fab")
		)
		(fp_line
			(start -0.12065 -0.305054)
			(end -0.12065 -0.2794)
			(stroke
				(width 0.1)
				(type default)
			)
			(layer "F.Fab")
		)
		(fp_line
			(start -0.67945 0.3048)
			(end -0.67945 -0.305054)
			(stroke
				(width 0.1)
				(type default)
			)
			(layer "F.Fab")
		)
		(fp_line
			(start -0.67945 -0.305054)
			(end -0.12065 -0.305054)
			(stroke
				(width 0.1)
				(type default)
			)
			(layer "F.Fab")
		)
		(pad "1" smd circle
			(at -0.40005 0 180)
			(size 0 0)
			(layers "F.Cu" "F.Mask" "F.Paste")
			(net "SMB_SCM_2_R6_SDA")
		)
		(pad "2" smd circle
			(at 0.40005 0 180)
			(size 0 0)
			(layers "F.Cu" "F.Mask" "F.Paste")
			(net "PVDD11_S3_P0_PMSDA_R")
		)
	)
	(footprint ""
		(layer "F.Cu")
		(at 450.082666 -400.78787 180)
		(property "Reference" "PR6564"
			(at 0 0 180)
			(layer "F.SilkS")
			(hide yes)
			(effects
				(font
					(size 1.27 1.27)
				)
			)
		)
		(property "Value" ""
			(at 0 0 180)
			(layer "F.Fab")
			(effects
				(font
					(size 1.27 1.27)
				)
			)
		)
		(duplicate_pad_numbers_are_jumpers no)
		(fp_line
			(start 0.7874 0.4064)
			(end -0.7874 0.4064)
			(stroke
				(width 0.1524)
				(type default)
			)
			(layer "F.SilkS")
		)
		(fp_line
			(start 0.7874 -0.4064)
			(end 0.7874 0.4064)
			(stroke
				(width 0.1524)
				(type default)
			)
			(layer "F.SilkS")
		)
		(fp_line
			(start -0.233934 -0.4064)
			(end 0.7874 -0.4064)
			(stroke
				(width 0.1524)
				(type default)
			)
			(layer "F.SilkS")
		)
		(fp_line
			(start -0.7874 0.4064)
			(end -0.7874 -0.07747)
			(stroke
				(width 0.1524)
				(type default)
			)
			(layer "F.SilkS")
		)
		(fp_line
			(start 0.67945 0.3048)
			(end 0.120396 0.3048)
			(stroke
				(width 0.1)
				(type default)
			)
			(layer "F.Fab")
		)
		(fp_line
			(start 0.67945 -0.3048)
			(end 0.67945 0.3048)
			(stroke
				(width 0.1)
				(type default)
			)
			(layer "F.Fab")
		)
		(fp_line
			(start 0.12065 -0.2794)
			(end 0.12065 -0.3048)
			(stroke
				(width 0.1)
				(type default)
			)
			(layer "F.Fab")
		)
		(fp_line
			(start 0.12065 -0.3048)
			(end 0.67945 -0.3048)
			(stroke
				(width 0.1)
				(type default)
			)
			(layer "F.Fab")
		)
		(fp_line
			(start 0.120396 0.3048)
			(end 0.120396 0.2794)
			(stroke
				(width 0.1)
				(type default)
			)
			(layer "F.Fab")
		)
		(fp_line
			(start 0.120396 0.2794)
			(end -0.12065 0.2794)
			(stroke
				(width 0.1)
				(type default)
			)
			(layer "F.Fab")
		)
		(fp_line
			(start -0.12065 0.3048)
			(end -0.67945 0.3048)
			(stroke
				(width 0.1)
				(type default)
			)
			(layer "F.Fab")
		)
		(fp_line
			(start -0.12065 0.2794)
			(end -0.12065 0.3048)
			(stroke
				(width 0.1)
				(type default)
			)
			(layer "F.Fab")
		)
		(fp_line
			(start -0.12065 -0.2794)
			(end 0.12065 -0.2794)
			(stroke
				(width 0.1)
				(type default)
			)
			(layer "F.Fab")
		)
		(fp_line
			(start -0.12065 -0.305054)
			(end -0.12065 -0.2794)
			(stroke
				(width 0.1)
				(type default)
			)
			(layer "F.Fab")
		)
		(fp_line
			(start -0.67945 0.3048)
			(end -0.67945 -0.305054)
			(stroke
				(width 0.1)
				(type default)
			)
			(layer "F.Fab")
		)
		(fp_line
			(start -0.67945 -0.305054)
			(end -0.12065 -0.305054)
			(stroke
				(width 0.1)
				(type default)
			)
			(layer "F.Fab")
		)
		(pad "1" smd circle
			(at -0.40005 0 180)
			(size 0 0)
			(layers "F.Cu" "F.Mask" "F.Paste")
			(net "P0V9_RETIMER_CPU0_VOS2")
		)
		(pad "2" smd circle
			(at 0.40005 0 180)
			(size 0 0)
			(layers "F.Cu" "F.Mask" "F.Paste")
			(net "P0V9_CPU0_RT_2D")
		)
	)
	(footprint ""
		(layer "F.Cu")
		(at 197.979538 -339.282024 90)
		(property "Reference" "PC118"
			(at 0 0 90)
			(layer "F.SilkS")
			(hide yes)
			(effects
				(font
					(size 1.27 1.27)
				)
			)
		)
		(property "Value" ""
			(at 0 0 90)
			(layer "F.Fab")
			(effects
				(font
					(size 1.27 1.27)
				)
			)
		)
		(duplicate_pad_numbers_are_jumpers no)
		(fp_line
			(start 0.7874 -0.4064)
			(end 0.7874 0.4064)
			(stroke
				(width 0.1524)
				(type default)
			)
			(layer "F.SilkS")
		)
		(fp_line
			(start -0.7874 -0.4064)
			(end 0.7874 -0.4064)
			(stroke
				(width 0.1524)
				(type default)
			)
			(layer "F.SilkS")
		)
		(fp_line
			(start 0.7874 0.4064)
			(end -0.7874 0.4064)
			(stroke
				(width 0.1524)
				(type default)
			)
			(layer "F.SilkS")
		)
		(fp_line
			(start -0.7874 0.4064)
			(end -0.7874 -0.4064)
			(stroke
				(width 0.1524)
				(type default)
			)
			(layer "F.SilkS")
		)
		(fp_line
			(start -0.12065 -0.305054)
			(end -0.12065 -0.2794)
			(stroke
				(width 0.1)
				(type default)
			)
			(layer "F.Fab")
		)
		(fp_line
			(start -0.67945 -0.305054)
			(end -0.12065 -0.305054)
			(stroke
				(width 0.1)
				(type default)
			)
			(layer "F.Fab")
		)
		(fp_line
			(start 0.67945 -0.3048)
			(end 0.67945 0.3048)
			(stroke
				(width 0.1)
				(type default)
			)
			(layer "F.Fab")
		)
		(fp_line
			(start 0.12065 -0.3048)
			(end 0.67945 -0.3048)
			(stroke
				(width 0.1)
				(type default)
			)
			(layer "F.Fab")
		)
		(fp_line
			(start 0.12065 -0.2794)
			(end 0.12065 -0.3048)
			(stroke
				(width 0.1)
				(type default)
			)
			(layer "F.Fab")
		)
		(fp_line
			(start -0.12065 -0.2794)
			(end 0.12065 -0.2794)
			(stroke
				(width 0.1)
				(type default)
			)
			(layer "F.Fab")
		)
		(fp_line
			(start 0.120396 0.2794)
			(end -0.12065 0.2794)
			(stroke
				(width 0.1)
				(type default)
			)
			(layer "F.Fab")
		)
		(fp_line
			(start -0.12065 0.2794)
			(end -0.12065 0.3048)
			(stroke
				(width 0.1)
				(type default)
			)
			(layer "F.Fab")
		)
		(fp_line
			(start 0.67945 0.3048)
			(end 0.120396 0.3048)
			(stroke
				(width 0.1)
				(type default)
			)
			(layer "F.Fab")
		)
		(fp_line
			(start 0.120396 0.3048)
			(end 0.120396 0.2794)
			(stroke
				(width 0.1)
				(type default)
			)
			(layer "F.Fab")
		)
		(fp_line
			(start -0.12065 0.3048)
			(end -0.67945 0.3048)
			(stroke
				(width 0.1)
				(type default)
			)
			(layer "F.Fab")
		)
		(fp_line
			(start -0.67945 0.3048)
			(end -0.67945 -0.305054)
			(stroke
				(width 0.1)
				(type default)
			)
			(layer "F.Fab")
		)
		(pad "1" smd circle
			(at -0.40005 0 90)
			(size 0 0)
			(layers "F.Cu" "F.Mask" "F.Paste")
			(net "PVDD_33_S5_VCC")
		)
		(pad "2" smd circle
			(at 0.40005 0 90)
			(size 0 0)
			(layers "F.Cu" "F.Mask" "F.Paste")
			(net "GND")
		)
	)
	(footprint ""
		(layer "F.Cu")
		(at 104.488488 -344.591132 90)
		(property "Reference" "PR428"
			(at 0 0 90)
			(layer "F.SilkS")
			(hide yes)
			(effects
				(font
					(size 1.27 1.27)
				)
			)
		)
		(property "Value" ""
			(at 0 0 90)
			(layer "F.Fab")
			(effects
				(font
					(size 1.27 1.27)
				)
			)
		)
		(duplicate_pad_numbers_are_jumpers no)
		(fp_line
			(start 0.7874 -0.4064)
			(end 0.7874 0.4064)
			(stroke
				(width 0.1524)
				(type default)
			)
			(layer "F.SilkS")
		)
		(fp_line
			(start -0.7874 -0.4064)
			(end 0.7874 -0.4064)
			(stroke
				(width 0.1524)
				(type default)
			)
			(layer "F.SilkS")
		)
		(fp_line
			(start 0.7874 0.4064)
			(end -0.7874 0.4064)
			(stroke
				(width 0.1524)
				(type default)
			)
			(layer "F.SilkS")
		)
		(fp_line
			(start -0.7874 0.4064)
			(end -0.7874 -0.4064)
			(stroke
				(width 0.1524)
				(type default)
			)
			(layer "F.SilkS")
		)
		(fp_line
			(start -0.12065 -0.305054)
			(end -0.12065 -0.2794)
			(stroke
				(width 0.1)
				(type default)
			)
			(layer "F.Fab")
		)
		(fp_line
			(start -0.67945 -0.305054)
			(end -0.12065 -0.305054)
			(stroke
				(width 0.1)
				(type default)
			)
			(layer "F.Fab")
		)
		(fp_line
			(start 0.67945 -0.3048)
			(end 0.67945 0.3048)
			(stroke
				(width 0.1)
				(type default)
			)
			(layer "F.Fab")
		)
		(fp_line
			(start 0.12065 -0.3048)
			(end 0.67945 -0.3048)
			(stroke
				(width 0.1)
				(type default)
			)
			(layer "F.Fab")
		)
		(fp_line
			(start 0.12065 -0.2794)
			(end 0.12065 -0.3048)
			(stroke
				(width 0.1)
				(type default)
			)
			(layer "F.Fab")
		)
		(fp_line
			(start -0.12065 -0.2794)
			(end 0.12065 -0.2794)
			(stroke
				(width 0.1)
				(type default)
			)
			(layer "F.Fab")
		)
		(fp_line
			(start 0.120396 0.2794)
			(end -0.12065 0.2794)
			(stroke
				(width 0.1)
				(type default)
			)
			(layer "F.Fab")
		)
		(fp_line
			(start -0.12065 0.2794)
			(end -0.12065 0.3048)
			(stroke
				(width 0.1)
				(type default)
			)
			(layer "F.Fab")
		)
		(fp_line
			(start 0.67945 0.3048)
			(end 0.120396 0.3048)
			(stroke
				(width 0.1)
				(type default)
			)
			(layer "F.Fab")
		)
		(fp_line
			(start 0.120396 0.3048)
			(end 0.120396 0.2794)
			(stroke
				(width 0.1)
				(type default)
			)
			(layer "F.Fab")
		)
		(fp_line
			(start -0.12065 0.3048)
			(end -0.67945 0.3048)
			(stroke
				(width 0.1)
				(type default)
			)
			(layer "F.Fab")
		)
		(fp_line
			(start -0.67945 0.3048)
			(end -0.67945 -0.305054)
			(stroke
				(width 0.1)
				(type default)
			)
			(layer "F.Fab")
		)
		(pad "1" smd circle
			(at -0.40005 0 90)
			(size 0 0)
			(layers "F.Cu" "F.Mask" "F.Paste")
			(net "SW_PVDDCR_CPU1_P1_BOOT6")
		)
		(pad "2" smd circle
			(at 0.40005 0 90)
			(size 0 0)
			(layers "F.Cu" "F.Mask" "F.Paste")
			(net "SW_PVDDCR_CPU1_P1_BOOT6_R")
		)
	)
	(footprint ""
		(layer "F.Cu")
		(at 279.513792 -123.035314 180)
		(property "Reference" "R319"
			(at 0 0 180)
			(layer "F.SilkS")
			(hide yes)
			(effects
				(font
					(size 1.27 1.27)
				)
			)
		)
		(property "Value" ""
			(at 0 0 180)
			(layer "F.Fab")
			(effects
				(font
					(size 1.27 1.27)
				)
			)
		)
		(duplicate_pad_numbers_are_jumpers no)
		(fp_line
			(start 0.7874 0.4064)
			(end -0.7874 0.4064)
			(stroke
				(width 0.1524)
				(type default)
			)
			(layer "F.SilkS")
		)
		(fp_line
			(start 0.7874 -0.4064)
			(end 0.7874 0.4064)
			(stroke
				(width 0.1524)
				(type default)
			)
			(layer "F.SilkS")
		)
		(fp_line
			(start -0.7874 0.4064)
			(end -0.7874 -0.4064)
			(stroke
				(width 0.1524)
				(type default)
			)
			(layer "F.SilkS")
		)
		(fp_line
			(start -0.7874 -0.4064)
			(end 0.7874 -0.4064)
			(stroke
				(width 0.1524)
				(type default)
			)
			(layer "F.SilkS")
		)
		(fp_line
			(start 0.67945 0.3048)
			(end 0.120396 0.3048)
			(stroke
				(width 0.1)
				(type default)
			)
			(layer "F.Fab")
		)
		(fp_line
			(start 0.67945 -0.3048)
			(end 0.67945 0.3048)
			(stroke
				(width 0.1)
				(type default)
			)
			(layer "F.Fab")
		)
		(fp_line
			(start 0.12065 -0.2794)
			(end 0.12065 -0.3048)
			(stroke
				(width 0.1)
				(type default)
			)
			(layer "F.Fab")
		)
		(fp_line
			(start 0.12065 -0.3048)
			(end 0.67945 -0.3048)
			(stroke
				(width 0.1)
				(type default)
			)
			(layer "F.Fab")
		)
		(fp_line
			(start 0.120396 0.3048)
			(end 0.120396 0.2794)
			(stroke
				(width 0.1)
				(type default)
			)
			(layer "F.Fab")
		)
		(fp_line
			(start 0.120396 0.2794)
			(end -0.12065 0.2794)
			(stroke
				(width 0.1)
				(type default)
			)
			(layer "F.Fab")
		)
		(fp_line
			(start -0.12065 0.3048)
			(end -0.67945 0.3048)
			(stroke
				(width 0.1)
				(type default)
			)
			(layer "F.Fab")
		)
		(fp_line
			(start -0.12065 0.2794)
			(end -0.12065 0.3048)
			(stroke
				(width 0.1)
				(type default)
			)
			(layer "F.Fab")
		)
		(fp_line
			(start -0.12065 -0.2794)
			(end 0.12065 -0.2794)
			(stroke
				(width 0.1)
				(type default)
			)
			(layer "F.Fab")
		)
		(fp_line
			(start -0.12065 -0.305054)
			(end -0.12065 -0.2794)
			(stroke
				(width 0.1)
				(type default)
			)
			(layer "F.Fab")
		)
		(fp_line
			(start -0.67945 0.3048)
			(end -0.67945 -0.305054)
			(stroke
				(width 0.1)
				(type default)
			)
			(layer "F.Fab")
		)
		(fp_line
			(start -0.67945 -0.305054)
			(end -0.12065 -0.305054)
			(stroke
				(width 0.1)
				(type default)
			)
			(layer "F.Fab")
		)
		(pad "1" smd circle
			(at -0.40005 0 180)
			(size 0 0)
			(layers "F.Cu" "F.Mask" "F.Paste")
			(net "PCA9548_PCIE3_ADDR1")
		)
		(pad "2" smd circle
			(at 0.40005 0 180)
			(size 0 0)
			(layers "F.Cu" "F.Mask" "F.Paste")
			(net "GND")
		)
	)
	(footprint ""
		(layer "F.Cu")
		(at 30.569662 -419.249098 -90)
		(property "Reference" "R3272"
			(at 0 0 270)
			(layer "F.SilkS")
			(hide yes)
			(effects
				(font
					(size 1.27 1.27)
				)
			)
		)
		(property "Value" ""
			(at 0 0 270)
			(layer "F.Fab")
			(effects
				(font
					(size 1.27 1.27)
				)
			)
		)
		(duplicate_pad_numbers_are_jumpers no)
		(fp_line
			(start -0.7874 0.4064)
			(end -0.7874 -0.4064)
			(stroke
				(width 0.1524)
				(type default)
			)
			(layer "F.SilkS")
		)
		(fp_line
			(start 0.7874 0.4064)
			(end -0.7874 0.4064)
			(stroke
				(width 0.1524)
				(type default)
			)
			(layer "F.SilkS")
		)
		(fp_line
			(start -0.7874 -0.4064)
			(end 0.7874 -0.4064)
			(stroke
				(width 0.1524)
				(type default)
			)
			(layer "F.SilkS")
		)
		(fp_line
			(start 0.7874 -0.4064)
			(end 0.7874 0.4064)
			(stroke
				(width 0.1524)
				(type default)
			)
			(layer "F.SilkS")
		)
		(fp_line
			(start -0.67945 0.3048)
			(end -0.67945 -0.305054)
			(stroke
				(width 0.1)
				(type default)
			)
			(layer "F.Fab")
		)
		(fp_line
			(start -0.12065 0.3048)
			(end -0.67945 0.3048)
			(stroke
				(width 0.1)
				(type default)
			)
			(layer "F.Fab")
		)
		(fp_line
			(start 0.120396 0.3048)
			(end 0.120396 0.2794)
			(stroke
				(width 0.1)
				(type default)
			)
			(layer "F.Fab")
		)
		(fp_line
			(start 0.67945 0.3048)
			(end 0.120396 0.3048)
			(stroke
				(width 0.1)
				(type default)
			)
			(layer "F.Fab")
		)
		(fp_line
			(start -0.12065 0.2794)
			(end -0.12065 0.3048)
			(stroke
				(width 0.1)
				(type default)
			)
			(layer "F.Fab")
		)
		(fp_line
			(start 0.120396 0.2794)
			(end -0.12065 0.2794)
			(stroke
				(width 0.1)
				(type default)
			)
			(layer "F.Fab")
		)
		(fp_line
			(start -0.12065 -0.2794)
			(end 0.12065 -0.2794)
			(stroke
				(width 0.1)
				(type default)
			)
			(layer "F.Fab")
		)
		(fp_line
			(start 0.12065 -0.2794)
			(end 0.12065 -0.3048)
			(stroke
				(width 0.1)
				(type default)
			)
			(layer "F.Fab")
		)
		(fp_line
			(start 0.12065 -0.3048)
			(end 0.67945 -0.3048)
			(stroke
				(width 0.1)
				(type default)
			)
			(layer "F.Fab")
		)
		(fp_line
			(start 0.67945 -0.3048)
			(end 0.67945 0.3048)
			(stroke
				(width 0.1)
				(type default)
			)
			(layer "F.Fab")
		)
		(fp_line
			(start -0.67945 -0.305054)
			(end -0.12065 -0.305054)
			(stroke
				(width 0.1)
				(type default)
			)
			(layer "F.Fab")
		)
		(fp_line
			(start -0.12065 -0.305054)
			(end -0.12065 -0.2794)
			(stroke
				(width 0.1)
				(type default)
			)
			(layer "F.Fab")
		)
		(pad "1" smd circle
			(at -0.40005 0 270)
			(size 0 0)
			(layers "F.Cu" "F.Mask" "F.Paste")
			(net "FM_P2E_EQA1")
		)
		(pad "2" smd circle
			(at 0.40005 0 270)
			(size 0 0)
			(layers "F.Cu" "F.Mask" "F.Paste")
			(net "GND")
		)
	)
	(footprint ""
		(layer "F.Cu")
		(at 306.420266 -430.240186 180)
		(property "Reference" "C19"
			(at 0 0 180)
			(layer "F.SilkS")
			(hide yes)
			(effects
				(font
					(size 1.27 1.27)
				)
			)
		)
		(property "Value" ""
			(at 0 0 180)
			(layer "F.Fab")
			(effects
				(font
					(size 1.27 1.27)
				)
			)
		)
		(duplicate_pad_numbers_are_jumpers no)
		(fp_line
			(start 0.7874 0.4064)
			(end -0.7874 0.4064)
			(stroke
				(width 0.1524)
				(type default)
			)
			(layer "F.SilkS")
		)
		(fp_line
			(start 0.7874 -0.4064)
			(end 0.7874 0.4064)
			(stroke
				(width 0.1524)
				(type default)
			)
			(layer "F.SilkS")
		)
		(fp_line
			(start -0.7874 0.4064)
			(end -0.7874 -0.4064)
			(stroke
				(width 0.1524)
				(type default)
			)
			(layer "F.SilkS")
		)
		(fp_line
			(start -0.7874 -0.4064)
			(end 0.7874 -0.4064)
			(stroke
				(width 0.1524)
				(type default)
			)
			(layer "F.SilkS")
		)
		(fp_line
			(start 0.67945 0.3048)
			(end 0.120396 0.3048)
			(stroke
				(width 0.1)
				(type default)
			)
			(layer "F.Fab")
		)
		(fp_line
			(start 0.67945 -0.3048)
			(end 0.67945 0.3048)
			(stroke
				(width 0.1)
				(type default)
			)
			(layer "F.Fab")
		)
		(fp_line
			(start 0.12065 -0.2794)
			(end 0.12065 -0.3048)
			(stroke
				(width 0.1)
				(type default)
			)
			(layer "F.Fab")
		)
		(fp_line
			(start 0.12065 -0.3048)
			(end 0.67945 -0.3048)
			(stroke
				(width 0.1)
				(type default)
			)
			(layer "F.Fab")
		)
		(fp_line
			(start 0.120396 0.3048)
			(end 0.120396 0.2794)
			(stroke
				(width 0.1)
				(type default)
			)
			(layer "F.Fab")
		)
		(fp_line
			(start 0.120396 0.2794)
			(end -0.12065 0.2794)
			(stroke
				(width 0.1)
				(type default)
			)
			(layer "F.Fab")
		)
		(fp_line
			(start -0.12065 0.3048)
			(end -0.67945 0.3048)
			(stroke
				(width 0.1)
				(type default)
			)
			(layer "F.Fab")
		)
		(fp_line
			(start -0.12065 0.2794)
			(end -0.12065 0.3048)
			(stroke
				(width 0.1)
				(type default)
			)
			(layer "F.Fab")
		)
		(fp_line
			(start -0.12065 -0.2794)
			(end 0.12065 -0.2794)
			(stroke
				(width 0.1)
				(type default)
			)
			(layer "F.Fab")
		)
		(fp_line
			(start -0.12065 -0.305054)
			(end -0.12065 -0.2794)
			(stroke
				(width 0.1)
				(type default)
			)
			(layer "F.Fab")
		)
		(fp_line
			(start -0.67945 0.3048)
			(end -0.67945 -0.305054)
			(stroke
				(width 0.1)
				(type default)
			)
			(layer "F.Fab")
		)
		(fp_line
			(start -0.67945 -0.305054)
			(end -0.12065 -0.305054)
			(stroke
				(width 0.1)
				(type default)
			)
			(layer "F.Fab")
		)
		(pad "1" smd circle
			(at -0.40005 0 180)
			(size 0 0)
			(layers "F.Cu" "F.Mask" "F.Paste")
			(net "PRSNT_CABLE_GPU_A2_ISO_N")
		)
		(pad "2" smd circle
			(at 0.40005 0 180)
			(size 0 0)
			(layers "F.Cu" "F.Mask" "F.Paste")
			(net "GND")
		)
	)
	(footprint ""
		(layer "F.Cu")
		(at 16.623284 -423.13352 -90)
		(property "Reference" "U6000"
			(at -5.784342 3.991102 0)
			(unlocked yes)
			(layer "F.SilkS")
			(effects
				(font
					(size 0.7874 0.5842)
					(thickness 0.1524)
				)
				(justify left)
			)
		)
		(property "Value" ""
			(at 0 0 270)
			(layer "F.Fab")
			(effects
				(font
					(size 1.27 1.27)
				)
			)
		)
		(duplicate_pad_numbers_are_jumpers no)
		(fp_line
			(start -2.050034 2.050034)
			(end -2.050034 1.524)
			(stroke
				(width 0.1524)
				(type default)
			)
			(layer "F.SilkS")
		)
		(fp_line
			(start -1.524 2.050034)
			(end -2.050034 2.050034)
			(stroke
				(width 0.1524)
				(type default)
			)
			(layer "F.SilkS")
		)
		(fp_line
			(start 2.050034 2.050034)
			(end 1.524 2.050034)
			(stroke
				(width 0.1524)
				(type default)
			)
			(layer "F.SilkS")
		)
		(fp_line
			(start 2.050034 1.524)
			(end 2.050034 2.050034)
			(stroke
				(width 0.1524)
				(type default)
			)
			(layer "F.SilkS")
		)
		(fp_line
			(start -2.050034 -1.524)
			(end -2.050034 -2.050034)
			(stroke
				(width 0.1524)
				(type default)
			)
			(layer "F.SilkS")
		)
		(fp_line
			(start -2.050034 -2.050034)
			(end -1.524 -2.050034)
			(stroke
				(width 0.1524)
				(type default)
			)
			(layer "F.SilkS")
		)
		(fp_line
			(start 1.524 -2.050034)
			(end 2.050034 -2.050034)
			(stroke
				(width 0.1524)
				(type default)
			)
			(layer "F.SilkS")
		)
		(fp_line
			(start 2.050034 -2.050034)
			(end 2.050034 -1.524)
			(stroke
				(width 0.1524)
				(type default)
			)
			(layer "F.SilkS")
		)
		(fp_rect
			(start -2.050034 -2.126234)
			(end -2.634234 -1.542034)
			(stroke
				(width 0)
				(type default)
			)
			(fill yes)
			(layer "F.SilkS")
		)
		(fp_line
			(start -2.050034 2.050034)
			(end -2.050034 -2.050034)
			(stroke
				(width 0.1)
				(type default)
			)
			(layer "F.Fab")
		)
		(fp_line
			(start 2.050034 2.050034)
			(end -2.050034 2.050034)
			(stroke
				(width 0.1)
				(type default)
			)
			(layer "F.Fab")
		)
		(fp_line
			(start -2.050034 -2.050034)
			(end 2.050034 -2.050034)
			(stroke
				(width 0.1)
				(type default)
			)
			(layer "F.Fab")
		)
		(fp_line
			(start 2.050034 -2.050034)
			(end 2.050034 2.050034)
			(stroke
				(width 0.1)
				(type default)
			)
			(layer "F.Fab")
		)
		(fp_poly
			(pts
				(xy -2.634234 -1.542034) (xy -2.050034 -1.542034) (xy -2.050034 -2.126234) (xy -2.634234 -2.126234)
			)
			(stroke
				(width 0)
				(type default)
			)
			(fill yes)
			(layer "F.Fab")
		)
		(pad "1" smd circle
			(at -1.89992 -1.249934 180)
			(size 0 0)
			(layers "F.Cu" "F.Mask" "F.Paste")
			(net "FM_P2E_BUF2_EQB0")
		)
		(pad "2" smd circle
			(at -1.89992 -0.750062 180)
			(size 0 0)
			(layers "F.Cu" "F.Mask" "F.Paste")
			(net "FM_P2E_BUF2_EQB1")
		)
		(pad "3" smd circle
			(at -1.89992 -0.249936 180)
			(size 0 0)
			(layers "F.Cu" "F.Mask" "F.Paste")
			(net "PD_P2E_BUF2_ENSMB")
		)
		(pad "4" smd circle
			(at -1.89992 0.249936 180)
			(size 0 0)
			(layers "F.Cu" "F.Mask" "F.Paste")
			(net "FM_P2E_BUF2_VODA_DB")
		)
		(pad "5" smd circle
			(at -1.89992 0.750062 180)
			(size 0 0)
			(layers "F.Cu" "F.Mask" "F.Paste")
			(net "FM_P2E_BUF2_VODB_DB")
		)
		(pad "6" smd circle
			(at -1.89992 1.249934 180)
			(size 0 0)
			(layers "F.Cu" "F.Mask" "F.Paste")
			(net "FM_P2E_EN2_N")
		)
		(pad "7" smd circle
			(at -1.249934 1.89992 270)
			(size 0 0)
			(layers "F.Cu" "F.Mask" "F.Paste")
			(net "P2E_MB_BMC_TX_BUF2_DP<0>")
		)
		(pad "8" smd circle
			(at -0.750062 1.89992 270)
			(size 0 0)
			(layers "F.Cu" "F.Mask" "F.Paste")
			(net "P2E_MB_BMC_TX_BUF2_DN<0>")
		)
		(pad "9" smd circle
			(at -0.249936 1.89992 270)
			(size 0 0)
			(layers "F.Cu" "F.Mask" "F.Paste")
			(net "FM_P2E_BUF2_EQA1")
		)
		(pad "10" smd circle
			(at 0.249936 1.89992 270)
			(size 0 0)
			(layers "F.Cu" "F.Mask" "F.Paste")
			(net "FM_P2E_BUF2_EQA0")
		)
		(pad "11" smd circle
			(at 0.750062 1.89992 270)
			(size 0 0)
			(layers "F.Cu" "F.Mask" "F.Paste")
			(net "P2E_MB_BMC_RX_R2_DP<0>")
		)
		(pad "12" smd circle
			(at 1.249934 1.89992 270)
			(size 0 0)
			(layers "F.Cu" "F.Mask" "F.Paste")
			(net "P2E_MB_BMC_RX_R2_DN<0>")
		)
		(pad "13" smd circle
			(at 1.89992 1.249934 180)
			(size 0 0)
			(layers "F.Cu" "F.Mask" "F.Paste")
			(net "NC_RES")
		)
		(pad "14" smd circle
			(at 1.89992 0.750062 180)
			(size 0 0)
			(layers "F.Cu" "F.Mask" "F.Paste")
			(net "FM_P2E_BUF2_SD_TH")
		)
		(pad "15" smd circle
			(at 1.89992 0.249936 180)
			(size 0 0)
			(layers "F.Cu" "F.Mask" "F.Paste")
			(net "P3V3_AUX")
		)
		(pad "16" smd circle
			(at 1.89992 -0.249936 180)
			(size 0 0)
			(layers "F.Cu" "F.Mask" "F.Paste")
			(net "GND")
		)
		(pad "17" smd circle
			(at 1.89992 -0.750062 180)
			(size 0 0)
			(layers "F.Cu" "F.Mask" "F.Paste")
			(net "FM_P2E_BUF2_VOD_SEL")
		)
		(pad "18" smd circle
			(at 1.89992 -1.249934 180)
			(size 0 0)
			(layers "F.Cu" "F.Mask" "F.Paste")
			(net "FM_P2E_BUF2_RXDET")
		)
		(pad "19" smd circle
			(at 1.249934 -1.89992 270)
			(size 0 0)
			(layers "F.Cu" "F.Mask" "F.Paste")
			(net "P2E_MB_BMC_RX_BUF2_C_DN<0>")
		)
		(pad "20" smd circle
			(at 0.750062 -1.89992 270)
			(size 0 0)
			(layers "F.Cu" "F.Mask" "F.Paste")
			(net "P2E_MB_BMC_RX_BUF2_C_DP<0>")
		)
		(pad "21" smd circle
			(at 0.249936 -1.89992 270)
			(size 0 0)
			(layers "F.Cu" "F.Mask" "F.Paste")
			(net "BUF2_VDD")
		)
		(pad "22" smd circle
			(at -0.249936 -1.89992 270)
			(size 0 0)
			(layers "F.Cu" "F.Mask" "F.Paste")
			(net "BUF2_VDD")
		)
		(pad "23" smd circle
			(at -0.750062 -1.89992 270)
			(size 0 0)
			(layers "F.Cu" "F.Mask" "F.Paste")
			(net "P2E_MB_BMC_TX_C_R2_DN<0>")
		)
		(pad "24" smd circle
			(at -1.249934 -1.89992 270)
			(size 0 0)
			(layers "F.Cu" "F.Mask" "F.Paste")
			(net "P2E_MB_BMC_TX_C_R2_DP<0>")
		)
		(pad "25" smd circle
			(at 0 0 270)
			(size 0 0)
			(layers "F.Cu" "F.Mask" "F.Paste")
			(net "GND")
		)
		(zone
			(layer "F.Cu")
			(hatch none 0.5)
			(connect_pads
				(clearance 0)
			)
			(min_thickness 0.25)
			(keepout
				(tracks not_allowed)
				(vias allowed)
				(pads allowed)
				(copperpour not_allowed)
				(footprints allowed)
			)
			(placement
				(enabled no)
				(sheetname "")
			)
			(fill
				(thermal_gap 0.5)
				(thermal_bridge_width 0.5)
				(island_removal_mode 0)
			)
			(polygon
				(pts
					(xy 16.597884 -424.65752) (xy 16.597884 -424.50512) (xy 15.251684 -424.50512) (xy 15.251684 -421.76192)
					(xy 16.732758 -421.76192) (xy 16.732758 -421.60952) (xy 15.099284 -421.60952) (xy 15.099284 -424.65752)
				)
			)
		)
	)
	(footprint ""
		(layer "F.Cu")
		(at 458.86116 -37.91585)
		(property "Reference" "U8082"
			(at -2.2733 1.990852 0)
			(unlocked yes)
			(layer "F.SilkS")
			(effects
				(font
					(size 0.7874 0.5842)
					(thickness 0.1524)
				)
				(justify left)
			)
		)
		(property "Value" ""
			(at 0 0 0)
			(layer "F.Fab")
			(effects
				(font
					(size 1.27 1.27)
				)
			)
		)
		(duplicate_pad_numbers_are_jumpers no)
		(fp_line
			(start -1.400048 1.100074)
			(end -1.400048 -1.100074)
			(stroke
				(width 0.1524)
				(type default)
			)
			(layer "F.SilkS")
		)
		(fp_line
			(start 1.400048 -1.100074)
			(end -1.400048 -1.100074)
			(stroke
				(width 0.1524)
				(type default)
			)
			(layer "F.SilkS")
		)
		(fp_line
			(start 1.400048 -1.100074)
			(end 1.400048 1.100074)
			(stroke
				(width 0.1524)
				(type default)
			)
			(layer "F.SilkS")
		)
		(fp_line
			(start 1.400048 1.100074)
			(end -1.400048 1.100074)
			(stroke
				(width 0.1524)
				(type default)
			)
			(layer "F.SilkS")
		)
		(fp_poly
			(pts
				(xy -2.055368 -1.405128) (xy -1.705102 -1.755394) (xy -1.529842 -1.229868)
			)
			(stroke
				(width 0)
				(type default)
			)
			(fill yes)
			(layer "F.SilkS")
		)
		(fp_line
			(start -0.674878 -1.100074)
			(end 0.674878 -1.100074)
			(stroke
				(width 0.1)
				(type default)
			)
			(layer "F.Fab")
		)
		(fp_line
			(start -0.674878 1.100074)
			(end -0.674878 -1.100074)
			(stroke
				(width 0.1)
				(type default)
			)
			(layer "F.Fab")
		)
		(fp_line
			(start 0.674878 -1.100074)
			(end 0.674878 1.100074)
			(stroke
				(width 0.1)
				(type default)
			)
			(layer "F.Fab")
		)
		(fp_line
			(start 0.674878 1.100074)
			(end -0.674878 1.100074)
			(stroke
				(width 0.1)
				(type default)
			)
			(layer "F.Fab")
		)
		(fp_poly
			(pts
				(xy -1.590548 -0.649986) (xy -2.606548 -1.157986) (xy -2.606548 -0.141986)
			)
			(stroke
				(width 0)
				(type default)
			)
			(fill yes)
			(layer "F.Fab")
		)
		(pad "1" smd rect
			(at -0.94996 -0.649986 270)
			(size 0.4318 0.6096)
			(layers "F.Cu" "F.Mask" "F.Paste")
			(net "PU_OCP_SFF_WAKE_OE")
		)
		(pad "2" smd rect
			(at -0.94996 0 270)
			(size 0.4318 0.6096)
			(layers "F.Cu" "F.Mask" "F.Paste")
			(net "IRQ_LVC3_OCP_SFF_WAKE_N")
		)
		(pad "3" smd rect
			(at -0.94996 0.649986 270)
			(size 0.4318 0.6096)
			(layers "F.Cu" "F.Mask" "F.Paste")
			(net "GND")
		)
		(pad "4" smd rect
			(at 0.94996 0.649986 270)
			(size 0.4318 0.6096)
			(layers "F.Cu" "F.Mask" "F.Paste")
			(net "OCP_SFF_WAKE_BUFF_N")
		)
		(pad "5" smd rect
			(at 0.94996 -0.649986 270)
			(size 0.4318 0.6096)
			(layers "F.Cu" "F.Mask" "F.Paste")
			(net "P3V3_AUX")
		)
	)
	(footprint ""
		(layer "F.Cu")
		(at 332.252066 -416.899344 -90)
		(property "Reference" "C6519"
			(at 0 0 270)
			(layer "F.SilkS")
			(hide yes)
			(effects
				(font
					(size 1.27 1.27)
				)
			)
		)
		(property "Value" ""
			(at 0 0 270)
			(layer "F.Fab")
			(effects
				(font
					(size 1.27 1.27)
				)
			)
		)
		(duplicate_pad_numbers_are_jumpers no)
		(fp_line
			(start -0.299974 0.150114)
			(end -0.299974 -0.150114)
			(stroke
				(width 0.1)
				(type default)
			)
			(layer "F.Fab")
		)
		(fp_line
			(start 0.299974 0.150114)
			(end -0.299974 0.150114)
			(stroke
				(width 0.1)
				(type default)
			)
			(layer "F.Fab")
		)
		(fp_line
			(start -0.299974 -0.150114)
			(end 0.299974 -0.150114)
			(stroke
				(width 0.1)
				(type default)
			)
			(layer "F.Fab")
		)
		(fp_line
			(start 0.299974 -0.150114)
			(end 0.299974 0.150114)
			(stroke
				(width 0.1)
				(type default)
			)
			(layer "F.Fab")
		)
		(pad "1" smd rect
			(at -0.2667 0 270)
			(size 0.3048 0.381)
			(layers "F.Cu" "F.Mask" "F.Paste")
			(net "P5E_CPU0_P0_TX_BUF_C_DP<9>")
		)
		(pad "2" smd rect
			(at 0.2667 0 270)
			(size 0.3048 0.381)
			(layers "F.Cu" "F.Mask" "F.Paste")
			(net "P5E_CPU0_P0_TX_BUF_DP<9>")
		)
	)
	(footprint ""
		(layer "F.Cu")
		(at 163.039044 -373.03583 -90)
		(property "Reference" "C751"
			(at 0 0 270)
			(layer "F.SilkS")
			(hide yes)
			(effects
				(font
					(size 1.27 1.27)
				)
			)
		)
		(property "Value" ""
			(at 0 0 270)
			(layer "F.Fab")
			(effects
				(font
					(size 1.27 1.27)
				)
			)
		)
		(duplicate_pad_numbers_are_jumpers no)
		(fp_line
			(start -0.299974 0.150114)
			(end -0.299974 -0.150114)
			(stroke
				(width 0.1)
				(type default)
			)
			(layer "F.Fab")
		)
		(fp_line
			(start 0.299974 0.150114)
			(end -0.299974 0.150114)
			(stroke
				(width 0.1)
				(type default)
			)
			(layer "F.Fab")
		)
		(fp_line
			(start -0.299974 -0.150114)
			(end 0.299974 -0.150114)
			(stroke
				(width 0.1)
				(type default)
			)
			(layer "F.Fab")
		)
		(fp_line
			(start 0.299974 -0.150114)
			(end 0.299974 0.150114)
			(stroke
				(width 0.1)
				(type default)
			)
			(layer "F.Fab")
		)
		(pad "1" smd rect
			(at -0.2667 0 270)
			(size 0.3048 0.381)
			(layers "F.Cu" "F.Mask" "F.Paste")
			(net "P5E_CPU1_P2_TX_C_DP<11>")
		)
		(pad "2" smd rect
			(at 0.2667 0 270)
			(size 0.3048 0.381)
			(layers "F.Cu" "F.Mask" "F.Paste")
			(net "P5E_CPU1_P2_TX_DP<11>")
		)
	)
	(footprint ""
		(layer "F.Cu")
		(at 43.543982 -388.030974 90)
		(property "Reference" "R628"
			(at 0 0 90)
			(layer "F.SilkS")
			(hide yes)
			(effects
				(font
					(size 1.27 1.27)
				)
			)
		)
		(property "Value" ""
			(at 0 0 90)
			(layer "F.Fab")
			(effects
				(font
					(size 1.27 1.27)
				)
			)
		)
		(duplicate_pad_numbers_are_jumpers no)
		(fp_line
			(start 0.32512 -0.175006)
			(end 0.32512 0.175006)
			(stroke
				(width 0.1)
				(type default)
			)
			(layer "F.Fab")
		)
		(fp_line
			(start -0.32512 -0.175006)
			(end 0.32512 -0.175006)
			(stroke
				(width 0.1)
				(type default)
			)
			(layer "F.Fab")
		)
		(fp_line
			(start 0.32512 0.175006)
			(end -0.32512 0.175006)
			(stroke
				(width 0.1)
				(type default)
			)
			(layer "F.Fab")
		)
		(fp_line
			(start -0.32512 0.175006)
			(end -0.32512 -0.175006)
			(stroke
				(width 0.1)
				(type default)
			)
			(layer "F.Fab")
		)
		(pad "1" smd rect
			(at -0.2667 0 90)
			(size 0.3048 0.381)
			(layers "F.Cu" "F.Mask" "F.Paste")
			(net "CLK_100M_RETIMER_CPU1_P0_DP")
		)
		(pad "2" smd rect
			(at 0.2667 0 270)
			(size 0.3048 0.381)
			(layers "F.Cu" "F.Mask" "F.Paste")
			(net "GND")
		)
	)
	(footprint ""
		(layer "F.Cu")
		(at 70.7136 -34.788348)
		(property "Reference" "R3569"
			(at 0 0 0)
			(layer "F.SilkS")
			(hide yes)
			(effects
				(font
					(size 1.27 1.27)
				)
			)
		)
		(property "Value" ""
			(at 0 0 0)
			(layer "F.Fab")
			(effects
				(font
					(size 1.27 1.27)
				)
			)
		)
		(duplicate_pad_numbers_are_jumpers no)
		(fp_line
			(start -0.7874 -0.4064)
			(end 0.7874 -0.4064)
			(stroke
				(width 0.1524)
				(type default)
			)
			(layer "F.SilkS")
		)
		(fp_line
			(start -0.7874 0.4064)
			(end -0.7874 -0.4064)
			(stroke
				(width 0.1524)
				(type default)
			)
			(layer "F.SilkS")
		)
		(fp_line
			(start 0.7874 -0.4064)
			(end 0.7874 0.4064)
			(stroke
				(width 0.1524)
				(type default)
			)
			(layer "F.SilkS")
		)
		(fp_line
			(start 0.7874 0.4064)
			(end -0.7874 0.4064)
			(stroke
				(width 0.1524)
				(type default)
			)
			(layer "F.SilkS")
		)
		(fp_line
			(start -0.67945 -0.305054)
			(end -0.12065 -0.305054)
			(stroke
				(width 0.1)
				(type default)
			)
			(layer "F.Fab")
		)
		(fp_line
			(start -0.67945 0.3048)
			(end -0.67945 -0.305054)
			(stroke
				(width 0.1)
				(type default)
			)
			(layer "F.Fab")
		)
		(fp_line
			(start -0.12065 -0.305054)
			(end -0.12065 -0.2794)
			(stroke
				(width 0.1)
				(type default)
			)
			(layer "F.Fab")
		)
		(fp_line
			(start -0.12065 -0.2794)
			(end 0.12065 -0.2794)
			(stroke
				(width 0.1)
				(type default)
			)
			(layer "F.Fab")
		)
		(fp_line
			(start -0.12065 0.2794)
			(end -0.12065 0.3048)
			(stroke
				(width 0.1)
				(type default)
			)
			(layer "F.Fab")
		)
		(fp_line
			(start -0.12065 0.3048)
			(end -0.67945 0.3048)
			(stroke
				(width 0.1)
				(type default)
			)
			(layer "F.Fab")
		)
		(fp_line
			(start 0.120396 0.2794)
			(end -0.12065 0.2794)
			(stroke
				(width 0.1)
				(type default)
			)
			(layer "F.Fab")
		)
		(fp_line
			(start 0.120396 0.3048)
			(end 0.120396 0.2794)
			(stroke
				(width 0.1)
				(type default)
			)
			(layer "F.Fab")
		)
		(fp_line
			(start 0.12065 -0.3048)
			(end 0.67945 -0.3048)
			(stroke
				(width 0.1)
				(type default)
			)
			(layer "F.Fab")
		)
		(fp_line
			(start 0.12065 -0.2794)
			(end 0.12065 -0.3048)
			(stroke
				(width 0.1)
				(type default)
			)
			(layer "F.Fab")
		)
		(fp_line
			(start 0.67945 -0.3048)
			(end 0.67945 0.3048)
			(stroke
				(width 0.1)
				(type default)
			)
			(layer "F.Fab")
		)
		(fp_line
			(start 0.67945 0.3048)
			(end 0.120396 0.3048)
			(stroke
				(width 0.1)
				(type default)
			)
			(layer "F.Fab")
		)
		(pad "1" smd circle
			(at -0.40005 0)
			(size 0 0)
			(layers "F.Cu" "F.Mask" "F.Paste")
			(net "SMB_INA230_3_3V3AUX_SDA_R")
		)
		(pad "2" smd circle
			(at 0.40005 0)
			(size 0 0)
			(layers "F.Cu" "F.Mask" "F.Paste")
			(net "SMB_INA230_3_3V3AUX_SDA_R1")
		)
	)
	(footprint ""
		(layer "F.Cu")
		(at 439.029602 -423.66311)
		(property "Reference" "PR6805"
			(at 0 0 0)
			(layer "F.SilkS")
			(hide yes)
			(effects
				(font
					(size 1.27 1.27)
				)
			)
		)
		(property "Value" ""
			(at 0 0 0)
			(layer "F.Fab")
			(effects
				(font
					(size 1.27 1.27)
				)
			)
		)
		(duplicate_pad_numbers_are_jumpers no)
		(fp_line
			(start -0.7874 -0.4064)
			(end 0.7874 -0.4064)
			(stroke
				(width 0.1524)
				(type default)
			)
			(layer "F.SilkS")
		)
		(fp_line
			(start -0.7874 0.4064)
			(end -0.7874 -0.4064)
			(stroke
				(width 0.1524)
				(type default)
			)
			(layer "F.SilkS")
		)
		(fp_line
			(start 0.7874 -0.4064)
			(end 0.7874 0.4064)
			(stroke
				(width 0.1524)
				(type default)
			)
			(layer "F.SilkS")
		)
		(fp_line
			(start 0.7874 0.4064)
			(end -0.7874 0.4064)
			(stroke
				(width 0.1524)
				(type default)
			)
			(layer "F.SilkS")
		)
		(fp_line
			(start -0.67945 -0.305054)
			(end -0.12065 -0.305054)
			(stroke
				(width 0.1)
				(type default)
			)
			(layer "F.Fab")
		)
		(fp_line
			(start -0.67945 0.3048)
			(end -0.67945 -0.305054)
			(stroke
				(width 0.1)
				(type default)
			)
			(layer "F.Fab")
		)
		(fp_line
			(start -0.12065 -0.305054)
			(end -0.12065 -0.2794)
			(stroke
				(width 0.1)
				(type default)
			)
			(layer "F.Fab")
		)
		(fp_line
			(start -0.12065 -0.2794)
			(end 0.12065 -0.2794)
			(stroke
				(width 0.1)
				(type default)
			)
			(layer "F.Fab")
		)
		(fp_line
			(start -0.12065 0.2794)
			(end -0.12065 0.3048)
			(stroke
				(width 0.1)
				(type default)
			)
			(layer "F.Fab")
		)
		(fp_line
			(start -0.12065 0.3048)
			(end -0.67945 0.3048)
			(stroke
				(width 0.1)
				(type default)
			)
			(layer "F.Fab")
		)
		(fp_line
			(start 0.120396 0.2794)
			(end -0.12065 0.2794)
			(stroke
				(width 0.1)
				(type default)
			)
			(layer "F.Fab")
		)
		(fp_line
			(start 0.120396 0.3048)
			(end 0.120396 0.2794)
			(stroke
				(width 0.1)
				(type default)
			)
			(layer "F.Fab")
		)
		(fp_line
			(start 0.12065 -0.3048)
			(end 0.67945 -0.3048)
			(stroke
				(width 0.1)
				(type default)
			)
			(layer "F.Fab")
		)
		(fp_line
			(start 0.12065 -0.2794)
			(end 0.12065 -0.3048)
			(stroke
				(width 0.1)
				(type default)
			)
			(layer "F.Fab")
		)
		(fp_line
			(start 0.67945 -0.3048)
			(end 0.67945 0.3048)
			(stroke
				(width 0.1)
				(type default)
			)
			(layer "F.Fab")
		)
		(fp_line
			(start 0.67945 0.3048)
			(end 0.120396 0.3048)
			(stroke
				(width 0.1)
				(type default)
			)
			(layer "F.Fab")
		)
		(pad "1" smd circle
			(at -0.40005 0)
			(size 0 0)
			(layers "F.Cu" "F.Mask" "F.Paste")
			(net "P3V3_AUX")
		)
		(pad "2" smd circle
			(at 0.40005 0)
			(size 0 0)
			(layers "F.Cu" "F.Mask" "F.Paste")
			(net "P0V9_RETIMER_CPU0_SVID_CLK")
		)
	)
	(footprint ""
		(layer "F.Cu")
		(at 429.278796 -393.9032 90)
		(property "Reference" "C665"
			(at 0 0 90)
			(layer "F.SilkS")
			(hide yes)
			(effects
				(font
					(size 1.27 1.27)
				)
			)
		)
		(property "Value" ""
			(at 0 0 90)
			(layer "F.Fab")
			(effects
				(font
					(size 1.27 1.27)
				)
			)
		)
		(duplicate_pad_numbers_are_jumpers no)
		(fp_line
			(start 1.524 -0.762)
			(end 1.524 0.762)
			(stroke
				(width 0.1524)
				(type default)
			)
			(layer "F.SilkS")
		)
		(fp_line
			(start -1.524 -0.762)
			(end 1.524 -0.762)
			(stroke
				(width 0.1524)
				(type default)
			)
			(layer "F.SilkS")
		)
		(fp_line
			(start 1.524 0.762)
			(end -1.524 0.762)
			(stroke
				(width 0.1524)
				(type default)
			)
			(layer "F.SilkS")
		)
		(fp_line
			(start -1.524 0.762)
			(end -1.524 -0.762)
			(stroke
				(width 0.1524)
				(type default)
			)
			(layer "F.SilkS")
		)
		(fp_line
			(start 1.1049 -0.724916)
			(end -1.1049 -0.724916)
			(stroke
				(width 0.1)
				(type default)
			)
			(layer "F.Fab")
		)
		(fp_line
			(start -1.1049 -0.724916)
			(end -1.1049 0.724916)
			(stroke
				(width 0.1)
				(type default)
			)
			(layer "F.Fab")
		)
		(fp_line
			(start 1.1049 0.724916)
			(end 1.1049 -0.724916)
			(stroke
				(width 0.1)
				(type default)
			)
			(layer "F.Fab")
		)
		(fp_line
			(start -1.1049 0.724916)
			(end 1.1049 0.724916)
			(stroke
				(width 0.1)
				(type default)
			)
			(layer "F.Fab")
		)
		(pad "1" smd rect
			(at -0.889 0 270)
			(size 1.016 1.27)
			(layers "F.Cu" "F.Mask" "F.Paste")
			(net "P1V8_CPU0_RT_1D")
		)
		(pad "2" smd rect
			(at 0.889 0 270)
			(size 1.016 1.27)
			(layers "F.Cu" "F.Mask" "F.Paste")
			(net "GND")
		)
	)
	(footprint ""
		(layer "F.Cu")
		(at 215.4301 -404.020782)
		(property "Reference" "PC2183"
			(at 0 0 0)
			(layer "F.SilkS")
			(hide yes)
			(effects
				(font
					(size 1.27 1.27)
				)
			)
		)
		(property "Value" ""
			(at 0 0 0)
			(layer "F.Fab")
			(effects
				(font
					(size 1.27 1.27)
				)
			)
		)
		(duplicate_pad_numbers_are_jumpers no)
		(fp_line
			(start -0.7874 -0.4064)
			(end 0.7874 -0.4064)
			(stroke
				(width 0.1524)
				(type default)
			)
			(layer "F.SilkS")
		)
		(fp_line
			(start -0.7874 0.4064)
			(end -0.7874 -0.4064)
			(stroke
				(width 0.1524)
				(type default)
			)
			(layer "F.SilkS")
		)
		(fp_line
			(start 0.7874 -0.4064)
			(end 0.7874 0.4064)
			(stroke
				(width 0.1524)
				(type default)
			)
			(layer "F.SilkS")
		)
		(fp_line
			(start 0.7874 0.4064)
			(end -0.7874 0.4064)
			(stroke
				(width 0.1524)
				(type default)
			)
			(layer "F.SilkS")
		)
		(fp_line
			(start -0.67945 -0.305054)
			(end -0.12065 -0.305054)
			(stroke
				(width 0.1)
				(type default)
			)
			(layer "F.Fab")
		)
		(fp_line
			(start -0.67945 0.3048)
			(end -0.67945 -0.305054)
			(stroke
				(width 0.1)
				(type default)
			)
			(layer "F.Fab")
		)
		(fp_line
			(start -0.12065 -0.305054)
			(end -0.12065 -0.2794)
			(stroke
				(width 0.1)
				(type default)
			)
			(layer "F.Fab")
		)
		(fp_line
			(start -0.12065 -0.2794)
			(end 0.12065 -0.2794)
			(stroke
				(width 0.1)
				(type default)
			)
			(layer "F.Fab")
		)
		(fp_line
			(start -0.12065 0.2794)
			(end -0.12065 0.3048)
			(stroke
				(width 0.1)
				(type default)
			)
			(layer "F.Fab")
		)
		(fp_line
			(start -0.12065 0.3048)
			(end -0.67945 0.3048)
			(stroke
				(width 0.1)
				(type default)
			)
			(layer "F.Fab")
		)
		(fp_line
			(start 0.120396 0.2794)
			(end -0.12065 0.2794)
			(stroke
				(width 0.1)
				(type default)
			)
			(layer "F.Fab")
		)
		(fp_line
			(start 0.120396 0.3048)
			(end 0.120396 0.2794)
			(stroke
				(width 0.1)
				(type default)
			)
			(layer "F.Fab")
		)
		(fp_line
			(start 0.12065 -0.3048)
			(end 0.67945 -0.3048)
			(stroke
				(width 0.1)
				(type default)
			)
			(layer "F.Fab")
		)
		(fp_line
			(start 0.12065 -0.2794)
			(end 0.12065 -0.3048)
			(stroke
				(width 0.1)
				(type default)
			)
			(layer "F.Fab")
		)
		(fp_line
			(start 0.67945 -0.3048)
			(end 0.67945 0.3048)
			(stroke
				(width 0.1)
				(type default)
			)
			(layer "F.Fab")
		)
		(fp_line
			(start 0.67945 0.3048)
			(end 0.120396 0.3048)
			(stroke
				(width 0.1)
				(type default)
			)
			(layer "F.Fab")
		)
		(pad "1" smd circle
			(at -0.40005 0)
			(size 0 0)
			(layers "F.Cu" "F.Mask" "F.Paste")
			(net "HSC_ON")
		)
		(pad "2" smd circle
			(at 0.40005 0)
			(size 0 0)
			(layers "F.Cu" "F.Mask" "F.Paste")
			(net "AGND_HSC")
		)
	)
	(footprint ""
		(layer "F.Cu")
		(at 363.318044 -418.360098 180)
		(property "Reference" "R9004"
			(at 0 0 180)
			(layer "F.SilkS")
			(hide yes)
			(effects
				(font
					(size 1.27 1.27)
				)
			)
		)
		(property "Value" ""
			(at 0 0 180)
			(layer "F.Fab")
			(effects
				(font
					(size 1.27 1.27)
				)
			)
		)
		(duplicate_pad_numbers_are_jumpers no)
		(fp_line
			(start 0.7874 0.4064)
			(end -0.7874 0.4064)
			(stroke
				(width 0.1524)
				(type default)
			)
			(layer "F.SilkS")
		)
		(fp_line
			(start 0.7874 -0.4064)
			(end 0.7874 0.4064)
			(stroke
				(width 0.1524)
				(type default)
			)
			(layer "F.SilkS")
		)
		(fp_line
			(start -0.7874 0.4064)
			(end -0.7874 -0.4064)
			(stroke
				(width 0.1524)
				(type default)
			)
			(layer "F.SilkS")
		)
		(fp_line
			(start -0.7874 -0.4064)
			(end 0.7874 -0.4064)
			(stroke
				(width 0.1524)
				(type default)
			)
			(layer "F.SilkS")
		)
		(fp_line
			(start 0.67945 0.3048)
			(end 0.120396 0.3048)
			(stroke
				(width 0.1)
				(type default)
			)
			(layer "F.Fab")
		)
		(fp_line
			(start 0.67945 -0.3048)
			(end 0.67945 0.3048)
			(stroke
				(width 0.1)
				(type default)
			)
			(layer "F.Fab")
		)
		(fp_line
			(start 0.12065 -0.2794)
			(end 0.12065 -0.3048)
			(stroke
				(width 0.1)
				(type default)
			)
			(layer "F.Fab")
		)
		(fp_line
			(start 0.12065 -0.3048)
			(end 0.67945 -0.3048)
			(stroke
				(width 0.1)
				(type default)
			)
			(layer "F.Fab")
		)
		(fp_line
			(start 0.120396 0.3048)
			(end 0.120396 0.2794)
			(stroke
				(width 0.1)
				(type default)
			)
			(layer "F.Fab")
		)
		(fp_line
			(start 0.120396 0.2794)
			(end -0.12065 0.2794)
			(stroke
				(width 0.1)
				(type default)
			)
			(layer "F.Fab")
		)
		(fp_line
			(start -0.12065 0.3048)
			(end -0.67945 0.3048)
			(stroke
				(width 0.1)
				(type default)
			)
			(layer "F.Fab")
		)
		(fp_line
			(start -0.12065 0.2794)
			(end -0.12065 0.3048)
			(stroke
				(width 0.1)
				(type default)
			)
			(layer "F.Fab")
		)
		(fp_line
			(start -0.12065 -0.2794)
			(end 0.12065 -0.2794)
			(stroke
				(width 0.1)
				(type default)
			)
			(layer "F.Fab")
		)
		(fp_line
			(start -0.12065 -0.305054)
			(end -0.12065 -0.2794)
			(stroke
				(width 0.1)
				(type default)
			)
			(layer "F.Fab")
		)
		(fp_line
			(start -0.67945 0.3048)
			(end -0.67945 -0.305054)
			(stroke
				(width 0.1)
				(type default)
			)
			(layer "F.Fab")
		)
		(fp_line
			(start -0.67945 -0.305054)
			(end -0.12065 -0.305054)
			(stroke
				(width 0.1)
				(type default)
			)
			(layer "F.Fab")
		)
		(pad "1" smd circle
			(at -0.40005 0 180)
			(size 0 0)
			(layers "F.Cu" "F.Mask" "F.Paste")
			(net "P3V3_AUX")
		)
		(pad "2" smd circle
			(at 0.40005 0 180)
			(size 0 0)
			(layers "F.Cu" "F.Mask" "F.Paste")
			(net "PRSNT_CABLE_SWB_B1")
		)
	)
	(footprint ""
		(layer "F.Cu")
		(at 63.877698 -26.99004 -90)
		(property "Reference" "PR3854"
			(at 0 0 270)
			(layer "F.SilkS")
			(hide yes)
			(effects
				(font
					(size 1.27 1.27)
				)
			)
		)
		(property "Value" ""
			(at 0 0 270)
			(layer "F.Fab")
			(effects
				(font
					(size 1.27 1.27)
				)
			)
		)
		(duplicate_pad_numbers_are_jumpers no)
		(fp_line
			(start -0.7874 0.4064)
			(end -0.7874 -0.4064)
			(stroke
				(width 0.1524)
				(type default)
			)
			(layer "F.SilkS")
		)
		(fp_line
			(start 0.7874 0.4064)
			(end -0.7874 0.4064)
			(stroke
				(width 0.1524)
				(type default)
			)
			(layer "F.SilkS")
		)
		(fp_line
			(start -0.7874 -0.4064)
			(end 0.7874 -0.4064)
			(stroke
				(width 0.1524)
				(type default)
			)
			(layer "F.SilkS")
		)
		(fp_line
			(start 0.7874 -0.4064)
			(end 0.7874 0.4064)
			(stroke
				(width 0.1524)
				(type default)
			)
			(layer "F.SilkS")
		)
		(fp_line
			(start -0.67945 0.3048)
			(end -0.67945 -0.305054)
			(stroke
				(width 0.1)
				(type default)
			)
			(layer "F.Fab")
		)
		(fp_line
			(start -0.12065 0.3048)
			(end -0.67945 0.3048)
			(stroke
				(width 0.1)
				(type default)
			)
			(layer "F.Fab")
		)
		(fp_line
			(start 0.120396 0.3048)
			(end 0.120396 0.2794)
			(stroke
				(width 0.1)
				(type default)
			)
			(layer "F.Fab")
		)
		(fp_line
			(start 0.67945 0.3048)
			(end 0.120396 0.3048)
			(stroke
				(width 0.1)
				(type default)
			)
			(layer "F.Fab")
		)
		(fp_line
			(start -0.12065 0.2794)
			(end -0.12065 0.3048)
			(stroke
				(width 0.1)
				(type default)
			)
			(layer "F.Fab")
		)
		(fp_line
			(start 0.120396 0.2794)
			(end -0.12065 0.2794)
			(stroke
				(width 0.1)
				(type default)
			)
			(layer "F.Fab")
		)
		(fp_line
			(start -0.12065 -0.2794)
			(end 0.12065 -0.2794)
			(stroke
				(width 0.1)
				(type default)
			)
			(layer "F.Fab")
		)
		(fp_line
			(start 0.12065 -0.2794)
			(end 0.12065 -0.3048)
			(stroke
				(width 0.1)
				(type default)
			)
			(layer "F.Fab")
		)
		(fp_line
			(start 0.12065 -0.3048)
			(end 0.67945 -0.3048)
			(stroke
				(width 0.1)
				(type default)
			)
			(layer "F.Fab")
		)
		(fp_line
			(start 0.67945 -0.3048)
			(end 0.67945 0.3048)
			(stroke
				(width 0.1)
				(type default)
			)
			(layer "F.Fab")
		)
		(fp_line
			(start -0.67945 -0.305054)
			(end -0.12065 -0.305054)
			(stroke
				(width 0.1)
				(type default)
			)
			(layer "F.Fab")
		)
		(fp_line
			(start -0.12065 -0.305054)
			(end -0.12065 -0.2794)
			(stroke
				(width 0.1)
				(type default)
			)
			(layer "F.Fab")
		)
		(pad "1" smd circle
			(at -0.40005 0 270)
			(size 0 0)
			(layers "F.Cu" "F.Mask" "F.Paste")
			(net "P12V_OCP_OV_FB_2")
		)
		(pad "2" smd circle
			(at 0.40005 0 270)
			(size 0 0)
			(layers "F.Cu" "F.Mask" "F.Paste")
			(net "GND")
		)
	)
	(footprint ""
		(layer "F.Cu")
		(at 261.62 -143.764 180)
		(property "Reference" "R1531"
			(at 0 0 180)
			(layer "F.SilkS")
			(hide yes)
			(effects
				(font
					(size 1.27 1.27)
				)
			)
		)
		(property "Value" ""
			(at 0 0 180)
			(layer "F.Fab")
			(effects
				(font
					(size 1.27 1.27)
				)
			)
		)
		(duplicate_pad_numbers_are_jumpers no)
		(fp_line
			(start 0.7874 0.4064)
			(end -0.7874 0.4064)
			(stroke
				(width 0.1524)
				(type default)
			)
			(layer "F.SilkS")
		)
		(fp_line
			(start 0.7874 -0.4064)
			(end 0.7874 0.4064)
			(stroke
				(width 0.1524)
				(type default)
			)
			(layer "F.SilkS")
		)
		(fp_line
			(start -0.7874 0.4064)
			(end -0.7874 -0.4064)
			(stroke
				(width 0.1524)
				(type default)
			)
			(layer "F.SilkS")
		)
		(fp_line
			(start -0.7874 -0.4064)
			(end 0.7874 -0.4064)
			(stroke
				(width 0.1524)
				(type default)
			)
			(layer "F.SilkS")
		)
		(fp_line
			(start 0.67945 0.3048)
			(end 0.120396 0.3048)
			(stroke
				(width 0.1)
				(type default)
			)
			(layer "F.Fab")
		)
		(fp_line
			(start 0.67945 -0.3048)
			(end 0.67945 0.3048)
			(stroke
				(width 0.1)
				(type default)
			)
			(layer "F.Fab")
		)
		(fp_line
			(start 0.12065 -0.2794)
			(end 0.12065 -0.3048)
			(stroke
				(width 0.1)
				(type default)
			)
			(layer "F.Fab")
		)
		(fp_line
			(start 0.12065 -0.3048)
			(end 0.67945 -0.3048)
			(stroke
				(width 0.1)
				(type default)
			)
			(layer "F.Fab")
		)
		(fp_line
			(start 0.120396 0.3048)
			(end 0.120396 0.2794)
			(stroke
				(width 0.1)
				(type default)
			)
			(layer "F.Fab")
		)
		(fp_line
			(start 0.120396 0.2794)
			(end -0.12065 0.2794)
			(stroke
				(width 0.1)
				(type default)
			)
			(layer "F.Fab")
		)
		(fp_line
			(start -0.12065 0.3048)
			(end -0.67945 0.3048)
			(stroke
				(width 0.1)
				(type default)
			)
			(layer "F.Fab")
		)
		(fp_line
			(start -0.12065 0.2794)
			(end -0.12065 0.3048)
			(stroke
				(width 0.1)
				(type default)
			)
			(layer "F.Fab")
		)
		(fp_line
			(start -0.12065 -0.2794)
			(end 0.12065 -0.2794)
			(stroke
				(width 0.1)
				(type default)
			)
			(layer "F.Fab")
		)
		(fp_line
			(start -0.12065 -0.305054)
			(end -0.12065 -0.2794)
			(stroke
				(width 0.1)
				(type default)
			)
			(layer "F.Fab")
		)
		(fp_line
			(start -0.67945 0.3048)
			(end -0.67945 -0.305054)
			(stroke
				(width 0.1)
				(type default)
			)
			(layer "F.Fab")
		)
		(fp_line
			(start -0.67945 -0.305054)
			(end -0.12065 -0.305054)
			(stroke
				(width 0.1)
				(type default)
			)
			(layer "F.Fab")
		)
		(pad "1" smd circle
			(at -0.40005 0 180)
			(size 0 0)
			(layers "F.Cu" "F.Mask" "F.Paste")
			(net "PVDD18_S5_P0")
		)
		(pad "2" smd circle
			(at 0.40005 0 180)
			(size 0 0)
			(layers "F.Cu" "F.Mask" "F.Paste")
			(net "SPI_CPU0_D1")
		)
	)
	(footprint ""
		(layer "F.Cu")
		(at 350.44761 -60.094876 180)
		(property "Reference" "R481"
			(at 0 0 180)
			(layer "F.SilkS")
			(hide yes)
			(effects
				(font
					(size 1.27 1.27)
				)
			)
		)
		(property "Value" ""
			(at 0 0 180)
			(layer "F.Fab")
			(effects
				(font
					(size 1.27 1.27)
				)
			)
		)
		(duplicate_pad_numbers_are_jumpers no)
		(fp_line
			(start 0.7874 0.4064)
			(end -0.7874 0.4064)
			(stroke
				(width 0.1524)
				(type default)
			)
			(layer "F.SilkS")
		)
		(fp_line
			(start 0.7874 -0.4064)
			(end 0.7874 0.4064)
			(stroke
				(width 0.1524)
				(type default)
			)
			(layer "F.SilkS")
		)
		(fp_line
			(start -0.7874 0.4064)
			(end -0.7874 -0.4064)
			(stroke
				(width 0.1524)
				(type default)
			)
			(layer "F.SilkS")
		)
		(fp_line
			(start -0.7874 -0.4064)
			(end 0.7874 -0.4064)
			(stroke
				(width 0.1524)
				(type default)
			)
			(layer "F.SilkS")
		)
		(fp_line
			(start 0.67945 0.3048)
			(end 0.120396 0.3048)
			(stroke
				(width 0.1)
				(type default)
			)
			(layer "F.Fab")
		)
		(fp_line
			(start 0.67945 -0.3048)
			(end 0.67945 0.3048)
			(stroke
				(width 0.1)
				(type default)
			)
			(layer "F.Fab")
		)
		(fp_line
			(start 0.12065 -0.2794)
			(end 0.12065 -0.3048)
			(stroke
				(width 0.1)
				(type default)
			)
			(layer "F.Fab")
		)
		(fp_line
			(start 0.12065 -0.3048)
			(end 0.67945 -0.3048)
			(stroke
				(width 0.1)
				(type default)
			)
			(layer "F.Fab")
		)
		(fp_line
			(start 0.120396 0.3048)
			(end 0.120396 0.2794)
			(stroke
				(width 0.1)
				(type default)
			)
			(layer "F.Fab")
		)
		(fp_line
			(start 0.120396 0.2794)
			(end -0.12065 0.2794)
			(stroke
				(width 0.1)
				(type default)
			)
			(layer "F.Fab")
		)
		(fp_line
			(start -0.12065 0.3048)
			(end -0.67945 0.3048)
			(stroke
				(width 0.1)
				(type default)
			)
			(layer "F.Fab")
		)
		(fp_line
			(start -0.12065 0.2794)
			(end -0.12065 0.3048)
			(stroke
				(width 0.1)
				(type default)
			)
			(layer "F.Fab")
		)
		(fp_line
			(start -0.12065 -0.2794)
			(end 0.12065 -0.2794)
			(stroke
				(width 0.1)
				(type default)
			)
			(layer "F.Fab")
		)
		(fp_line
			(start -0.12065 -0.305054)
			(end -0.12065 -0.2794)
			(stroke
				(width 0.1)
				(type default)
			)
			(layer "F.Fab")
		)
		(fp_line
			(start -0.67945 0.3048)
			(end -0.67945 -0.305054)
			(stroke
				(width 0.1)
				(type default)
			)
			(layer "F.Fab")
		)
		(fp_line
			(start -0.67945 -0.305054)
			(end -0.12065 -0.305054)
			(stroke
				(width 0.1)
				(type default)
			)
			(layer "F.Fab")
		)
		(pad "1" smd circle
			(at -0.40005 0 180)
			(size 0 0)
			(layers "F.Cu" "F.Mask" "F.Paste")
			(net "CPU0_XTRIG_L4")
		)
		(pad "2" smd circle
			(at 0.40005 0 180)
			(size 0 0)
			(layers "F.Cu" "F.Mask" "F.Paste")
			(net "CPU0_XTRIG_R1_L4")
		)
	)
	(footprint ""
		(layer "F.Cu")
		(at 144.36344 -30.78734 -90)
		(property "Reference" "C6014"
			(at 0 0 270)
			(layer "F.SilkS")
			(hide yes)
			(effects
				(font
					(size 1.27 1.27)
				)
			)
		)
		(property "Value" ""
			(at 0 0 270)
			(layer "F.Fab")
			(effects
				(font
					(size 1.27 1.27)
				)
			)
		)
		(duplicate_pad_numbers_are_jumpers no)
		(fp_line
			(start -0.7874 0.4064)
			(end -0.7874 -0.4064)
			(stroke
				(width 0.1524)
				(type default)
			)
			(layer "F.SilkS")
		)
		(fp_line
			(start 0.7874 0.4064)
			(end -0.7874 0.4064)
			(stroke
				(width 0.1524)
				(type default)
			)
			(layer "F.SilkS")
		)
		(fp_line
			(start -0.7874 -0.4064)
			(end 0.7874 -0.4064)
			(stroke
				(width 0.1524)
				(type default)
			)
			(layer "F.SilkS")
		)
		(fp_line
			(start 0.7874 -0.4064)
			(end 0.7874 0.4064)
			(stroke
				(width 0.1524)
				(type default)
			)
			(layer "F.SilkS")
		)
		(fp_line
			(start -0.6858 0.3048)
			(end -0.6858 -0.3048)
			(stroke
				(width 0.1)
				(type default)
			)
			(layer "F.Fab")
		)
		(fp_line
			(start -0.1016 0.3048)
			(end -0.6858 0.3048)
			(stroke
				(width 0.1)
				(type default)
			)
			(layer "F.Fab")
		)
		(fp_line
			(start 0.1016 0.3048)
			(end 0.1016 0.2794)
			(stroke
				(width 0.1)
				(type default)
			)
			(layer "F.Fab")
		)
		(fp_line
			(start 0.6858 0.3048)
			(end 0.1016 0.3048)
			(stroke
				(width 0.1)
				(type default)
			)
			(layer "F.Fab")
		)
		(fp_line
			(start -0.1016 0.2794)
			(end -0.1016 0.3048)
			(stroke
				(width 0.1)
				(type default)
			)
			(layer "F.Fab")
		)
		(fp_line
			(start 0.1016 0.2794)
			(end -0.1016 0.2794)
			(stroke
				(width 0.1)
				(type default)
			)
			(layer "F.Fab")
		)
		(fp_line
			(start -0.1016 -0.2794)
			(end 0.1016 -0.2794)
			(stroke
				(width 0.1)
				(type default)
			)
			(layer "F.Fab")
		)
		(fp_line
			(start 0.1016 -0.2794)
			(end 0.1016 -0.3048)
			(stroke
				(width 0.1)
				(type default)
			)
			(layer "F.Fab")
		)
		(fp_line
			(start -0.6858 -0.3048)
			(end -0.1016 -0.3048)
			(stroke
				(width 0.1)
				(type default)
			)
			(layer "F.Fab")
		)
		(fp_line
			(start -0.1016 -0.3048)
			(end -0.1016 -0.2794)
			(stroke
				(width 0.1)
				(type default)
			)
			(layer "F.Fab")
		)
		(fp_line
			(start 0.1016 -0.3048)
			(end 0.6858 -0.3048)
			(stroke
				(width 0.1)
				(type default)
			)
			(layer "F.Fab")
		)
		(fp_line
			(start 0.6858 -0.3048)
			(end 0.6858 0.3048)
			(stroke
				(width 0.1)
				(type default)
			)
			(layer "F.Fab")
		)
		(pad "1" smd rect
			(at -0.40005 0 90)
			(size 0.4572 0.508)
			(layers "F.Cu" "F.Mask" "F.Paste")
			(net "USB3_CPU0_BMC_TX_DN")
		)
		(pad "2" smd rect
			(at 0.40005 0 90)
			(size 0.4572 0.508)
			(layers "F.Cu" "F.Mask" "F.Paste")
			(net "USB3_CPU0_BMC_TX_C2_DN")
		)
	)
	(footprint ""
		(layer "F.Cu")
		(at 185.095642 -413.64408 90)
		(property "Reference" "R8004"
			(at 0 0 90)
			(layer "F.SilkS")
			(hide yes)
			(effects
				(font
					(size 1.27 1.27)
				)
			)
		)
		(property "Value" ""
			(at 0 0 90)
			(layer "F.Fab")
			(effects
				(font
					(size 1.27 1.27)
				)
			)
		)
		(duplicate_pad_numbers_are_jumpers no)
		(fp_line
			(start 0.7874 -0.4064)
			(end 0.7874 0.4064)
			(stroke
				(width 0.1524)
				(type default)
			)
			(layer "F.SilkS")
		)
		(fp_line
			(start -0.7874 -0.4064)
			(end 0.7874 -0.4064)
			(stroke
				(width 0.1524)
				(type default)
			)
			(layer "F.SilkS")
		)
		(fp_line
			(start 0.7874 0.4064)
			(end -0.7874 0.4064)
			(stroke
				(width 0.1524)
				(type default)
			)
			(layer "F.SilkS")
		)
		(fp_line
			(start -0.7874 0.4064)
			(end -0.7874 -0.4064)
			(stroke
				(width 0.1524)
				(type default)
			)
			(layer "F.SilkS")
		)
		(fp_line
			(start -0.12065 -0.305054)
			(end -0.12065 -0.2794)
			(stroke
				(width 0.1)
				(type default)
			)
			(layer "F.Fab")
		)
		(fp_line
			(start -0.67945 -0.305054)
			(end -0.12065 -0.305054)
			(stroke
				(width 0.1)
				(type default)
			)
			(layer "F.Fab")
		)
		(fp_line
			(start 0.67945 -0.3048)
			(end 0.67945 0.3048)
			(stroke
				(width 0.1)
				(type default)
			)
			(layer "F.Fab")
		)
		(fp_line
			(start 0.12065 -0.3048)
			(end 0.67945 -0.3048)
			(stroke
				(width 0.1)
				(type default)
			)
			(layer "F.Fab")
		)
		(fp_line
			(start 0.12065 -0.2794)
			(end 0.12065 -0.3048)
			(stroke
				(width 0.1)
				(type default)
			)
			(layer "F.Fab")
		)
		(fp_line
			(start -0.12065 -0.2794)
			(end 0.12065 -0.2794)
			(stroke
				(width 0.1)
				(type default)
			)
			(layer "F.Fab")
		)
		(fp_line
			(start 0.120396 0.2794)
			(end -0.12065 0.2794)
			(stroke
				(width 0.1)
				(type default)
			)
			(layer "F.Fab")
		)
		(fp_line
			(start -0.12065 0.2794)
			(end -0.12065 0.3048)
			(stroke
				(width 0.1)
				(type default)
			)
			(layer "F.Fab")
		)
		(fp_line
			(start 0.67945 0.3048)
			(end 0.120396 0.3048)
			(stroke
				(width 0.1)
				(type default)
			)
			(layer "F.Fab")
		)
		(fp_line
			(start 0.120396 0.3048)
			(end 0.120396 0.2794)
			(stroke
				(width 0.1)
				(type default)
			)
			(layer "F.Fab")
		)
		(fp_line
			(start -0.12065 0.3048)
			(end -0.67945 0.3048)
			(stroke
				(width 0.1)
				(type default)
			)
			(layer "F.Fab")
		)
		(fp_line
			(start -0.67945 0.3048)
			(end -0.67945 -0.305054)
			(stroke
				(width 0.1)
				(type default)
			)
			(layer "F.Fab")
		)
		(pad "1" smd circle
			(at -0.40005 0 90)
			(size 0 0)
			(layers "F.Cu" "F.Mask" "F.Paste")
			(net "PRSNT_SWB_ISO_N")
		)
		(pad "2" smd circle
			(at 0.40005 0 90)
			(size 0 0)
			(layers "F.Cu" "F.Mask" "F.Paste")
			(net "PRSNT_SWB_ISO_R1_N")
		)
	)
	(footprint ""
		(layer "F.Cu")
		(at 169.368724 -380.385828)
		(property "Reference" "C742"
			(at 0 0 0)
			(layer "F.SilkS")
			(hide yes)
			(effects
				(font
					(size 1.27 1.27)
				)
			)
		)
		(property "Value" ""
			(at 0 0 0)
			(layer "F.Fab")
			(effects
				(font
					(size 1.27 1.27)
				)
			)
		)
		(duplicate_pad_numbers_are_jumpers no)
		(fp_line
			(start -0.299974 -0.150114)
			(end 0.299974 -0.150114)
			(stroke
				(width 0.1)
				(type default)
			)
			(layer "F.Fab")
		)
		(fp_line
			(start -0.299974 0.150114)
			(end -0.299974 -0.150114)
			(stroke
				(width 0.1)
				(type default)
			)
			(layer "F.Fab")
		)
		(fp_line
			(start 0.299974 -0.150114)
			(end 0.299974 0.150114)
			(stroke
				(width 0.1)
				(type default)
			)
			(layer "F.Fab")
		)
		(fp_line
			(start 0.299974 0.150114)
			(end -0.299974 0.150114)
			(stroke
				(width 0.1)
				(type default)
			)
			(layer "F.Fab")
		)
		(pad "1" smd rect
			(at -0.2667 0)
			(size 0.3048 0.381)
			(layers "F.Cu" "F.Mask" "F.Paste")
			(net "P5E_CPU1_P2_TX_C_DN<15>")
		)
		(pad "2" smd rect
			(at 0.2667 0)
			(size 0.3048 0.381)
			(layers "F.Cu" "F.Mask" "F.Paste")
			(net "P5E_CPU1_P2_TX_DN<15>")
		)
	)
	(footprint ""
		(layer "F.Cu")
		(at 271.585944 -100.446078 -90)
		(property "Reference" "C1507"
			(at 0 0 270)
			(layer "F.SilkS")
			(hide yes)
			(effects
				(font
					(size 1.27 1.27)
				)
			)
		)
		(property "Value" ""
			(at 0 0 270)
			(layer "F.Fab")
			(effects
				(font
					(size 1.27 1.27)
				)
			)
		)
		(duplicate_pad_numbers_are_jumpers no)
		(fp_line
			(start -0.7874 0.4064)
			(end -0.7874 -0.4064)
			(stroke
				(width 0.1524)
				(type default)
			)
			(layer "F.SilkS")
		)
		(fp_line
			(start 0.7874 0.4064)
			(end -0.7874 0.4064)
			(stroke
				(width 0.1524)
				(type default)
			)
			(layer "F.SilkS")
		)
		(fp_line
			(start -0.7874 -0.4064)
			(end 0.7874 -0.4064)
			(stroke
				(width 0.1524)
				(type default)
			)
			(layer "F.SilkS")
		)
		(fp_line
			(start 0.7874 -0.4064)
			(end 0.7874 0.4064)
			(stroke
				(width 0.1524)
				(type default)
			)
			(layer "F.SilkS")
		)
		(fp_line
			(start -0.67945 0.3048)
			(end -0.67945 -0.305054)
			(stroke
				(width 0.1)
				(type default)
			)
			(layer "F.Fab")
		)
		(fp_line
			(start -0.12065 0.3048)
			(end -0.67945 0.3048)
			(stroke
				(width 0.1)
				(type default)
			)
			(layer "F.Fab")
		)
		(fp_line
			(start 0.120396 0.3048)
			(end 0.120396 0.2794)
			(stroke
				(width 0.1)
				(type default)
			)
			(layer "F.Fab")
		)
		(fp_line
			(start 0.67945 0.3048)
			(end 0.120396 0.3048)
			(stroke
				(width 0.1)
				(type default)
			)
			(layer "F.Fab")
		)
		(fp_line
			(start -0.12065 0.2794)
			(end -0.12065 0.3048)
			(stroke
				(width 0.1)
				(type default)
			)
			(layer "F.Fab")
		)
		(fp_line
			(start 0.120396 0.2794)
			(end -0.12065 0.2794)
			(stroke
				(width 0.1)
				(type default)
			)
			(layer "F.Fab")
		)
		(fp_line
			(start -0.12065 -0.2794)
			(end 0.12065 -0.2794)
			(stroke
				(width 0.1)
				(type default)
			)
			(layer "F.Fab")
		)
		(fp_line
			(start 0.12065 -0.2794)
			(end 0.12065 -0.3048)
			(stroke
				(width 0.1)
				(type default)
			)
			(layer "F.Fab")
		)
		(fp_line
			(start 0.12065 -0.3048)
			(end 0.67945 -0.3048)
			(stroke
				(width 0.1)
				(type default)
			)
			(layer "F.Fab")
		)
		(fp_line
			(start 0.67945 -0.3048)
			(end 0.67945 0.3048)
			(stroke
				(width 0.1)
				(type default)
			)
			(layer "F.Fab")
		)
		(fp_line
			(start -0.67945 -0.305054)
			(end -0.12065 -0.305054)
			(stroke
				(width 0.1)
				(type default)
			)
			(layer "F.Fab")
		)
		(fp_line
			(start -0.12065 -0.305054)
			(end -0.12065 -0.2794)
			(stroke
				(width 0.1)
				(type default)
			)
			(layer "F.Fab")
		)
		(pad "1" smd circle
			(at -0.40005 0 270)
			(size 0 0)
			(layers "F.Cu" "F.Mask" "F.Paste")
			(net "PVDD18_S5_P0")
		)
		(pad "2" smd circle
			(at 0.40005 0 270)
			(size 0 0)
			(layers "F.Cu" "F.Mask" "F.Paste")
			(net "GND")
		)
	)
	(footprint ""
		(layer "F.Cu")
		(at 119.36857 -169.258234 -90)
		(property "Reference" "PC319"
			(at 0 0 270)
			(layer "F.SilkS")
			(hide yes)
			(effects
				(font
					(size 1.27 1.27)
				)
			)
		)
		(property "Value" ""
			(at 0 0 270)
			(layer "F.Fab")
			(effects
				(font
					(size 1.27 1.27)
				)
			)
		)
		(duplicate_pad_numbers_are_jumpers no)
		(fp_line
			(start -0.7874 0.4064)
			(end -0.7874 -0.4064)
			(stroke
				(width 0.1524)
				(type default)
			)
			(layer "F.SilkS")
		)
		(fp_line
			(start -0.286766 0.4064)
			(end -0.7874 0.4064)
			(stroke
				(width 0.1524)
				(type default)
			)
			(layer "F.SilkS")
		)
		(fp_line
			(start 0.7874 0.4064)
			(end 0.348234 0.4064)
			(stroke
				(width 0.1524)
				(type default)
			)
			(layer "F.SilkS")
		)
		(fp_line
			(start -0.7874 -0.4064)
			(end 0.7874 -0.4064)
			(stroke
				(width 0.1524)
				(type default)
			)
			(layer "F.SilkS")
		)
		(fp_line
			(start 0.7874 -0.4064)
			(end 0.7874 0.4064)
			(stroke
				(width 0.1524)
				(type default)
			)
			(layer "F.SilkS")
		)
		(fp_line
			(start -0.67945 0.3048)
			(end -0.67945 -0.305054)
			(stroke
				(width 0.1)
				(type default)
			)
			(layer "F.Fab")
		)
		(fp_line
			(start -0.12065 0.3048)
			(end -0.67945 0.3048)
			(stroke
				(width 0.1)
				(type default)
			)
			(layer "F.Fab")
		)
		(fp_line
			(start 0.120396 0.3048)
			(end 0.120396 0.2794)
			(stroke
				(width 0.1)
				(type default)
			)
			(layer "F.Fab")
		)
		(fp_line
			(start 0.67945 0.3048)
			(end 0.120396 0.3048)
			(stroke
				(width 0.1)
				(type default)
			)
			(layer "F.Fab")
		)
		(fp_line
			(start -0.12065 0.2794)
			(end -0.12065 0.3048)
			(stroke
				(width 0.1)
				(type default)
			)
			(layer "F.Fab")
		)
		(fp_line
			(start 0.120396 0.2794)
			(end -0.12065 0.2794)
			(stroke
				(width 0.1)
				(type default)
			)
			(layer "F.Fab")
		)
		(fp_line
			(start -0.12065 -0.2794)
			(end 0.12065 -0.2794)
			(stroke
				(width 0.1)
				(type default)
			)
			(layer "F.Fab")
		)
		(fp_line
			(start 0.12065 -0.2794)
			(end 0.12065 -0.3048)
			(stroke
				(width 0.1)
				(type default)
			)
			(layer "F.Fab")
		)
		(fp_line
			(start 0.12065 -0.3048)
			(end 0.67945 -0.3048)
			(stroke
				(width 0.1)
				(type default)
			)
			(layer "F.Fab")
		)
		(fp_line
			(start 0.67945 -0.3048)
			(end 0.67945 0.3048)
			(stroke
				(width 0.1)
				(type default)
			)
			(layer "F.Fab")
		)
		(fp_line
			(start -0.67945 -0.305054)
			(end -0.12065 -0.305054)
			(stroke
				(width 0.1)
				(type default)
			)
			(layer "F.Fab")
		)
		(fp_line
			(start -0.12065 -0.305054)
			(end -0.12065 -0.2794)
			(stroke
				(width 0.1)
				(type default)
			)
			(layer "F.Fab")
		)
		(pad "1" smd circle
			(at -0.40005 0 270)
			(size 0 0)
			(layers "F.Cu" "F.Mask" "F.Paste")
			(net "PVDDCR_SOC_P1_VCC1")
		)
		(pad "2" smd circle
			(at 0.40005 0 270)
			(size 0 0)
			(layers "F.Cu" "F.Mask" "F.Paste")
			(net "GND")
		)
	)
	(footprint ""
		(layer "F.Cu")
		(at 306.501038 -424.956986)
		(property "Reference" "R4139"
			(at 0 0 0)
			(layer "F.SilkS")
			(hide yes)
			(effects
				(font
					(size 1.27 1.27)
				)
			)
		)
		(property "Value" ""
			(at 0 0 0)
			(layer "F.Fab")
			(effects
				(font
					(size 1.27 1.27)
				)
			)
		)
		(duplicate_pad_numbers_are_jumpers no)
		(fp_line
			(start -0.7874 -0.4064)
			(end 0.7874 -0.4064)
			(stroke
				(width 0.1524)
				(type default)
			)
			(layer "F.SilkS")
		)
		(fp_line
			(start -0.7874 0.4064)
			(end -0.7874 -0.4064)
			(stroke
				(width 0.1524)
				(type default)
			)
			(layer "F.SilkS")
		)
		(fp_line
			(start 0.7874 -0.4064)
			(end 0.7874 0.4064)
			(stroke
				(width 0.1524)
				(type default)
			)
			(layer "F.SilkS")
		)
		(fp_line
			(start 0.7874 0.4064)
			(end -0.7874 0.4064)
			(stroke
				(width 0.1524)
				(type default)
			)
			(layer "F.SilkS")
		)
		(fp_line
			(start -0.67945 -0.305054)
			(end -0.12065 -0.305054)
			(stroke
				(width 0.1)
				(type default)
			)
			(layer "F.Fab")
		)
		(fp_line
			(start -0.67945 0.3048)
			(end -0.67945 -0.305054)
			(stroke
				(width 0.1)
				(type default)
			)
			(layer "F.Fab")
		)
		(fp_line
			(start -0.12065 -0.305054)
			(end -0.12065 -0.2794)
			(stroke
				(width 0.1)
				(type default)
			)
			(layer "F.Fab")
		)
		(fp_line
			(start -0.12065 -0.2794)
			(end 0.12065 -0.2794)
			(stroke
				(width 0.1)
				(type default)
			)
			(layer "F.Fab")
		)
		(fp_line
			(start -0.12065 0.2794)
			(end -0.12065 0.3048)
			(stroke
				(width 0.1)
				(type default)
			)
			(layer "F.Fab")
		)
		(fp_line
			(start -0.12065 0.3048)
			(end -0.67945 0.3048)
			(stroke
				(width 0.1)
				(type default)
			)
			(layer "F.Fab")
		)
		(fp_line
			(start 0.120396 0.2794)
			(end -0.12065 0.2794)
			(stroke
				(width 0.1)
				(type default)
			)
			(layer "F.Fab")
		)
		(fp_line
			(start 0.120396 0.3048)
			(end 0.120396 0.2794)
			(stroke
				(width 0.1)
				(type default)
			)
			(layer "F.Fab")
		)
		(fp_line
			(start 0.12065 -0.3048)
			(end 0.67945 -0.3048)
			(stroke
				(width 0.1)
				(type default)
			)
			(layer "F.Fab")
		)
		(fp_line
			(start 0.12065 -0.2794)
			(end 0.12065 -0.3048)
			(stroke
				(width 0.1)
				(type default)
			)
			(layer "F.Fab")
		)
		(fp_line
			(start 0.67945 -0.3048)
			(end 0.67945 0.3048)
			(stroke
				(width 0.1)
				(type default)
			)
			(layer "F.Fab")
		)
		(fp_line
			(start 0.67945 0.3048)
			(end 0.120396 0.3048)
			(stroke
				(width 0.1)
				(type default)
			)
			(layer "F.Fab")
		)
		(pad "1" smd circle
			(at -0.40005 0)
			(size 0 0)
			(layers "F.Cu" "F.Mask" "F.Paste")
			(net "P3V3_AUX")
		)
		(pad "2" smd circle
			(at 0.40005 0)
			(size 0 0)
			(layers "F.Cu" "F.Mask" "F.Paste")
			(net "PRSNT_CABLE_GPU_A2")
		)
	)
	(footprint ""
		(layer "F.Cu")
		(at 198.247 -93.345 180)
		(property "Reference" "R8090"
			(at 0 0 180)
			(layer "F.SilkS")
			(hide yes)
			(effects
				(font
					(size 1.27 1.27)
				)
			)
		)
		(property "Value" ""
			(at 0 0 180)
			(layer "F.Fab")
			(effects
				(font
					(size 1.27 1.27)
				)
			)
		)
		(duplicate_pad_numbers_are_jumpers no)
		(fp_line
			(start 0.7874 0.4064)
			(end -0.7874 0.4064)
			(stroke
				(width 0.1524)
				(type default)
			)
			(layer "F.SilkS")
		)
		(fp_line
			(start 0.7874 -0.4064)
			(end 0.7874 0.4064)
			(stroke
				(width 0.1524)
				(type default)
			)
			(layer "F.SilkS")
		)
		(fp_line
			(start -0.7874 0.4064)
			(end -0.7874 -0.4064)
			(stroke
				(width 0.1524)
				(type default)
			)
			(layer "F.SilkS")
		)
		(fp_line
			(start -0.7874 -0.4064)
			(end 0.7874 -0.4064)
			(stroke
				(width 0.1524)
				(type default)
			)
			(layer "F.SilkS")
		)
		(fp_line
			(start 0.67945 0.3048)
			(end 0.120396 0.3048)
			(stroke
				(width 0.1)
				(type default)
			)
			(layer "F.Fab")
		)
		(fp_line
			(start 0.67945 -0.3048)
			(end 0.67945 0.3048)
			(stroke
				(width 0.1)
				(type default)
			)
			(layer "F.Fab")
		)
		(fp_line
			(start 0.12065 -0.2794)
			(end 0.12065 -0.3048)
			(stroke
				(width 0.1)
				(type default)
			)
			(layer "F.Fab")
		)
		(fp_line
			(start 0.12065 -0.3048)
			(end 0.67945 -0.3048)
			(stroke
				(width 0.1)
				(type default)
			)
			(layer "F.Fab")
		)
		(fp_line
			(start 0.120396 0.3048)
			(end 0.120396 0.2794)
			(stroke
				(width 0.1)
				(type default)
			)
			(layer "F.Fab")
		)
		(fp_line
			(start 0.120396 0.2794)
			(end -0.12065 0.2794)
			(stroke
				(width 0.1)
				(type default)
			)
			(layer "F.Fab")
		)
		(fp_line
			(start -0.12065 0.3048)
			(end -0.67945 0.3048)
			(stroke
				(width 0.1)
				(type default)
			)
			(layer "F.Fab")
		)
		(fp_line
			(start -0.12065 0.2794)
			(end -0.12065 0.3048)
			(stroke
				(width 0.1)
				(type default)
			)
			(layer "F.Fab")
		)
		(fp_line
			(start -0.12065 -0.2794)
			(end 0.12065 -0.2794)
			(stroke
				(width 0.1)
				(type default)
			)
			(layer "F.Fab")
		)
		(fp_line
			(start -0.12065 -0.305054)
			(end -0.12065 -0.2794)
			(stroke
				(width 0.1)
				(type default)
			)
			(layer "F.Fab")
		)
		(fp_line
			(start -0.67945 0.3048)
			(end -0.67945 -0.305054)
			(stroke
				(width 0.1)
				(type default)
			)
			(layer "F.Fab")
		)
		(fp_line
			(start -0.67945 -0.305054)
			(end -0.12065 -0.305054)
			(stroke
				(width 0.1)
				(type default)
			)
			(layer "F.Fab")
		)
		(pad "1" smd circle
			(at -0.40005 0 180)
			(size 0 0)
			(layers "F.Cu" "F.Mask" "F.Paste")
			(net "PWRGD_CHGL_CPU1_R1")
		)
		(pad "2" smd circle
			(at 0.40005 0 180)
			(size 0 0)
			(layers "F.Cu" "F.Mask" "F.Paste")
			(net "PWRGD_CHGL_CPU1_R2")
		)
	)
	(footprint ""
		(layer "F.Cu")
		(at 421.901874 -5.569966 -90)
		(property "Reference" "J38"
			(at -8.103616 -20.50034 0)
			(unlocked yes)
			(layer "F.SilkS")
			(effects
				(font
					(size 0.7874 0.5842)
					(thickness 0.1524)
				)
				(justify left)
			)
		)
		(property "Value" ""
			(at 0 0 270)
			(layer "F.Fab")
			(effects
				(font
					(size 1.27 1.27)
				)
			)
		)
		(duplicate_pad_numbers_are_jumpers no)
		(fp_line
			(start -6.825234 34.360104)
			(end 6.210046 34.360104)
			(stroke
				(width 0.1524)
				(type default)
			)
			(layer "F.SilkS")
		)
		(fp_line
			(start 6.210046 34.360104)
			(end 6.210046 -34.360104)
			(stroke
				(width 0.1524)
				(type default)
			)
			(layer "F.SilkS")
		)
		(fp_line
			(start -5.5499 33.8201)
			(end 5.5499 33.8201)
			(stroke
				(width 0.1524)
				(type default)
			)
			(layer "F.SilkS")
		)
		(fp_line
			(start 5.5499 33.8201)
			(end 5.5499 -33.8201)
			(stroke
				(width 0.1524)
				(type default)
			)
			(layer "F.SilkS")
		)
		(fp_line
			(start -5.5499 33.281874)
			(end -5.5499 33.8201)
			(stroke
				(width 0.1524)
				(type default)
			)
			(layer "F.SilkS")
		)
		(fp_line
			(start -5.5499 30.97784)
			(end -5.5499 32.011874)
			(stroke
				(width 0.1524)
				(type default)
			)
			(layer "F.SilkS")
		)
		(fp_line
			(start -7.420102 29.471874)
			(end -7.420102 33.205674)
			(stroke
				(width 0.1524)
				(type default)
			)
			(layer "F.SilkS")
		)
		(fp_line
			(start -7.420102 27.058874)
			(end -7.420102 27.693874)
			(stroke
				(width 0.1524)
				(type default)
			)
			(layer "F.SilkS")
		)
		(fp_line
			(start -7.420102 25.153874)
			(end -7.420102 25.661874)
			(stroke
				(width 0.1524)
				(type default)
			)
			(layer "F.SilkS")
		)
		(fp_line
			(start -7.420102 23.248874)
			(end -7.420102 23.883874)
			(stroke
				(width 0.1524)
				(type default)
			)
			(layer "F.SilkS")
		)
		(fp_line
			(start -7.420102 21.343874)
			(end -7.420102 21.851874)
			(stroke
				(width 0.1524)
				(type default)
			)
			(layer "F.SilkS")
		)
		(fp_line
			(start -7.420102 19.311874)
			(end -7.420102 19.946874)
			(stroke
				(width 0.1524)
				(type default)
			)
			(layer "F.SilkS")
		)
		(fp_line
			(start -7.420102 17.533874)
			(end -7.420102 18.168874)
			(stroke
				(width 0.1524)
				(type default)
			)
			(layer "F.SilkS")
		)
		(fp_line
			(start -7.420102 15.628874)
			(end -7.420102 16.136874)
			(stroke
				(width 0.1524)
				(type default)
			)
			(layer "F.SilkS")
		)
		(fp_line
			(start -5.5499 9.8806)
			(end -5.5499 14.13256)
			(stroke
				(width 0.1524)
				(type default)
			)
			(layer "F.SilkS")
		)
		(fp_line
			(start -7.420102 9.024874)
			(end -7.420102 14.104874)
			(stroke
				(width 0.1524)
				(type default)
			)
			(layer "F.SilkS")
		)
		(fp_line
			(start -7.420102 6.992874)
			(end -7.420102 7.627874)
			(stroke
				(width 0.1524)
				(type default)
			)
			(layer "F.SilkS")
		)
		(fp_line
			(start -7.420102 4.960874)
			(end -7.420102 5.595874)
			(stroke
				(width 0.1524)
				(type default)
			)
			(layer "F.SilkS")
		)
		(fp_line
			(start -7.420102 3.055874)
			(end -7.420102 3.690874)
			(stroke
				(width 0.1524)
				(type default)
			)
			(layer "F.SilkS")
		)
		(fp_line
			(start -5.5499 -1.9304)
			(end -5.5499 1.4224)
			(stroke
				(width 0.1524)
				(type default)
			)
			(layer "F.SilkS")
		)
		(fp_line
			(start -7.420102 -2.532126)
			(end -7.420102 1.912874)
			(stroke
				(width 0.1524)
				(type default)
			)
			(layer "F.SilkS")
		)
		(fp_line
			(start -7.420102 -4.310126)
			(end -7.420102 -3.548126)
			(stroke
				(width 0.1524)
				(type default)
			)
			(layer "F.SilkS")
		)
		(fp_line
			(start -7.420102 -6.342126)
			(end -7.420102 -5.707126)
			(stroke
				(width 0.1524)
				(type default)
			)
			(layer "F.SilkS")
		)
		(fp_line
			(start -7.420102 -8.247126)
			(end -7.420102 -7.739126)
			(stroke
				(width 0.1524)
				(type default)
			)
			(layer "F.SilkS")
		)
		(fp_line
			(start -5.5499 -22.5425)
			(end -5.5499 -18.7833)
			(stroke
				(width 0.1524)
				(type default)
			)
			(layer "F.SilkS")
		)
		(fp_line
			(start -7.420102 -23.360126)
			(end -7.420102 -11.422126)
			(stroke
				(width 0.1524)
				(type default)
			)
			(layer "F.SilkS")
		)
		(fp_line
			(start -5.5499 -33.8201)
			(end -5.5499 -30.988)
			(stroke
				(width 0.1524)
				(type default)
			)
			(layer "F.SilkS")
		)
		(fp_line
			(start 5.5499 -33.8201)
			(end -5.5499 -33.8201)
			(stroke
				(width 0.1524)
				(type default)
			)
			(layer "F.SilkS")
		)
		(fp_line
			(start -7.420102 -34.360104)
			(end -7.420102 -25.265126)
			(stroke
				(width 0.1524)
				(type default)
			)
			(layer "F.SilkS")
		)
		(fp_line
			(start 6.210046 -34.360104)
			(end -7.420102 -34.360104)
			(stroke
				(width 0.1524)
				(type default)
			)
			(layer "F.SilkS")
		)
		(fp_poly
			(pts
				(xy 3.230118 -18.4912) (xy 4.246372 -18.9992) (xy 4.246118 -17.9832)
			)
			(stroke
				(width 0)
				(type default)
			)
			(fill yes)
			(layer "F.SilkS")
		)
		(fp_line
			(start -5.5499 33.8201)
			(end 5.5499 33.8201)
			(stroke
				(width 0.1)
				(type default)
			)
			(layer "F.Fab")
		)
		(fp_line
			(start 5.5499 33.8201)
			(end 5.5499 -33.8201)
			(stroke
				(width 0.1)
				(type default)
			)
			(layer "F.Fab")
		)
		(fp_line
			(start -5.5499 -33.8201)
			(end -5.5499 33.8201)
			(stroke
				(width 0.1)
				(type default)
			)
			(layer "F.Fab")
		)
		(fp_line
			(start 5.5499 -33.8201)
			(end -5.5499 -33.8201)
			(stroke
				(width 0.1)
				(type default)
			)
			(layer "F.Fab")
		)
		(fp_poly
			(pts
				(xy 7.4168 -17.957038) (xy 7.4168 -18.973038) (xy 6.4008 -18.465038)
			)
			(stroke
				(width 0)
				(type default)
			)
			(fill yes)
			(layer "F.Fab")
		)
		(pad "" np_thru_hole circle
			(at -0.599948 -32.079946 180)
			(size 1.1176 1.1176)
			(drill 1.1176)
			(layers "*.Cu" "*.Mask")
			(clearance 0.381)
			(thermal_gap 0.381)
		)
		(pad "" np_thru_hole circle
			(at 0.40005 32.085026 180)
			(size 1.1176 1.1176)
			(drill 1.1176)
			(layers "*.Cu" "*.Mask")
			(clearance 0.381)
			(thermal_gap 0.381)
		)
		(pad "A1" smd rect
			(at -2.750058 -18.465038 180)
			(size 0.381 1.4478)
			(layers "F.Cu" "F.Mask" "F.Paste")
			(net "GND")
		)
		(pad "A2" smd rect
			(at -2.750058 -17.86509 180)
			(size 0.381 1.4478)
			(layers "F.Cu" "F.Mask" "F.Paste")
			(net "GND")
		)
		(pad "A3" smd rect
			(at -2.750058 -17.264888 180)
			(size 0.381 1.4478)
			(layers "F.Cu" "F.Mask" "F.Paste")
			(net "GND")
		)
		(pad "A4" smd rect
			(at -2.750058 -16.66494 180)
			(size 0.381 1.4478)
			(layers "F.Cu" "F.Mask" "F.Paste")
			(net "GND")
		)
		(pad "A5" smd rect
			(at -2.750058 -16.064992 180)
			(size 0.381 1.4478)
			(layers "F.Cu" "F.Mask" "F.Paste")
			(net "GND")
		)
		(pad "A6" smd rect
			(at -2.750058 -15.465044 180)
			(size 0.381 1.4478)
			(layers "F.Cu" "F.Mask" "F.Paste")
			(net "GND")
		)
		(pad "A7" smd rect
			(at -2.750058 -14.865096 180)
			(size 0.381 1.4478)
			(layers "F.Cu" "F.Mask" "F.Paste")
			(net "SMB_OCP_SFF_3V3AUX_BUF_R_SCL")
		)
		(pad "A8" smd rect
			(at -2.750058 -14.264894 180)
			(size 0.381 1.4478)
			(layers "F.Cu" "F.Mask" "F.Paste")
			(net "SMB_OCP_SFF_3V3AUX_BUF_R_SDA")
		)
		(pad "A9" smd rect
			(at -2.750058 -13.664946 180)
			(size 0.381 1.4478)
			(layers "F.Cu" "F.Mask" "F.Paste")
			(net "RST_SMB_OCP_SFF_N")
		)
		(pad "A10" smd rect
			(at -2.750058 -13.064998 180)
			(size 0.381 1.4478)
			(layers "F.Cu" "F.Mask" "F.Paste")
			(net "OCP_SFF_PRSNTA_R_N")
		)
		(pad "A11" smd rect
			(at -2.750058 -12.46505 180)
			(size 0.381 1.4478)
			(layers "F.Cu" "F.Mask" "F.Paste")
			(net "RST_PERST1_OCP_SFF_N")
		)
		(pad "A12" smd rect
			(at -2.750058 -11.865102 180)
			(size 0.381 1.4478)
			(layers "F.Cu" "F.Mask" "F.Paste")
			(net "OCP_SFF_PRSNT2_R_N")
		)
		(pad "A13" smd rect
			(at -2.750058 -11.2649 180)
			(size 0.381 1.4478)
			(layers "F.Cu" "F.Mask" "F.Paste")
			(net "GND")
		)
		(pad "A14" smd rect
			(at -2.750058 -10.664952 180)
			(size 0.381 1.4478)
			(layers "F.Cu" "F.Mask" "F.Paste")
			(net "CLK_100M_CPU0_CLK03_DN")
		)
		(pad "A15" smd rect
			(at -2.750058 -10.065004 180)
			(size 0.381 1.4478)
			(layers "F.Cu" "F.Mask" "F.Paste")
			(net "CLK_100M_CPU0_CLK03_DP")
		)
		(pad "A16" smd rect
			(at -2.750058 -9.465056 180)
			(size 0.381 1.4478)
			(layers "F.Cu" "F.Mask" "F.Paste")
			(net "GND")
		)
		(pad "A17" smd rect
			(at -2.750058 -8.865108 180)
			(size 0.381 1.4478)
			(layers "F.Cu" "F.Mask" "F.Paste")
			(net "P5E_CPU0_G3_RX_DN<0>")
		)
		(pad "A18" smd rect
			(at -2.750058 -8.264906 180)
			(size 0.381 1.4478)
			(layers "F.Cu" "F.Mask" "F.Paste")
			(net "P5E_CPU0_G3_RX_DP<0>")
		)
		(pad "A19" smd rect
			(at -2.750058 -7.664958 180)
			(size 0.381 1.4478)
			(layers "F.Cu" "F.Mask" "F.Paste")
			(net "GND")
		)
		(pad "A20" smd rect
			(at -2.750058 -7.06501 180)
			(size 0.381 1.4478)
			(layers "F.Cu" "F.Mask" "F.Paste")
			(net "P5E_CPU0_G3_RX_DN<1>")
		)
		(pad "A21" smd rect
			(at -2.750058 -6.465062 180)
			(size 0.381 1.4478)
			(layers "F.Cu" "F.Mask" "F.Paste")
			(net "P5E_CPU0_G3_RX_DP<1>")
		)
		(pad "A22" smd rect
			(at -2.750058 -5.865114 180)
			(size 0.381 1.4478)
			(layers "F.Cu" "F.Mask" "F.Paste")
			(net "GND")
		)
		(pad "A23" smd rect
			(at -2.750058 -5.264912 180)
			(size 0.381 1.4478)
			(layers "F.Cu" "F.Mask" "F.Paste")
			(net "P5E_CPU0_G3_RX_DN<2>")
		)
		(pad "A24" smd rect
			(at -2.750058 -4.664964 180)
			(size 0.381 1.4478)
			(layers "F.Cu" "F.Mask" "F.Paste")
			(net "P5E_CPU0_G3_RX_DP<2>")
		)
		(pad "A25" smd rect
			(at -2.750058 -4.065016 180)
			(size 0.381 1.4478)
			(layers "F.Cu" "F.Mask" "F.Paste")
			(net "GND")
		)
		(pad "A26" smd rect
			(at -2.750058 -3.465068 180)
			(size 0.381 1.4478)
			(layers "F.Cu" "F.Mask" "F.Paste")
			(net "P5E_CPU0_G3_RX_DN<3>")
		)
		(pad "A27" smd rect
			(at -2.750058 -2.86512 180)
			(size 0.381 1.4478)
			(layers "F.Cu" "F.Mask" "F.Paste")
			(net "P5E_CPU0_G3_RX_DP<3>")
		)
		(pad "A28" smd rect
			(at -2.750058 -2.264918 180)
			(size 0.381 1.4478)
			(layers "F.Cu" "F.Mask" "F.Paste")
			(net "GND")
		)
		(pad "A29" smd rect
			(at -2.750058 1.74498 180)
			(size 0.381 1.4478)
			(layers "F.Cu" "F.Mask" "F.Paste")
			(net "GND")
		)
		(pad "A30" smd rect
			(at -2.750058 2.344928 180)
			(size 0.381 1.4478)
			(layers "F.Cu" "F.Mask" "F.Paste")
			(net "P5E_CPU0_G3_RX_DN<4>")
		)
		(pad "A31" smd rect
			(at -2.750058 2.944876 180)
			(size 0.381 1.4478)
			(layers "F.Cu" "F.Mask" "F.Paste")
			(net "P5E_CPU0_G3_RX_DP<4>")
		)
		(pad "A32" smd rect
			(at -2.750058 3.545078 180)
			(size 0.381 1.4478)
			(layers "F.Cu" "F.Mask" "F.Paste")
			(net "GND")
		)
		(pad "A33" smd rect
			(at -2.750058 4.145026 180)
			(size 0.381 1.4478)
			(layers "F.Cu" "F.Mask" "F.Paste")
			(net "P5E_CPU0_G3_RX_DN<5>")
		)
		(pad "A34" smd rect
			(at -2.750058 4.744974 180)
			(size 0.381 1.4478)
			(layers "F.Cu" "F.Mask" "F.Paste")
			(net "P5E_CPU0_G3_RX_DP<5>")
		)
		(pad "A35" smd rect
			(at -2.750058 5.344922 180)
			(size 0.381 1.4478)
			(layers "F.Cu" "F.Mask" "F.Paste")
			(net "GND")
		)
		(pad "A36" smd rect
			(at -2.750058 5.945124 180)
			(size 0.381 1.4478)
			(layers "F.Cu" "F.Mask" "F.Paste")
			(net "P5E_CPU0_G3_RX_DN<6>")
		)
		(pad "A37" smd rect
			(at -2.750058 6.545072 180)
			(size 0.381 1.4478)
			(layers "F.Cu" "F.Mask" "F.Paste")
			(net "P5E_CPU0_G3_RX_DP<6>")
		)
		(pad "A38" smd rect
			(at -2.750058 7.14502 180)
			(size 0.381 1.4478)
			(layers "F.Cu" "F.Mask" "F.Paste")
			(net "GND")
		)
		(pad "A39" smd rect
			(at -2.750058 7.744968 180)
			(size 0.381 1.4478)
			(layers "F.Cu" "F.Mask" "F.Paste")
			(net "P5E_CPU0_G3_RX_DN<7>")
		)
		(pad "A40" smd rect
			(at -2.750058 8.344916 180)
			(size 0.381 1.4478)
			(layers "F.Cu" "F.Mask" "F.Paste")
			(net "P5E_CPU0_G3_RX_DP<7>")
		)
		(pad "A41" smd rect
			(at -2.750058 8.945118 180)
			(size 0.381 1.4478)
			(layers "F.Cu" "F.Mask" "F.Paste")
			(net "GND")
		)
		(pad "A42" smd rect
			(at -2.750058 9.545066 180)
			(size 0.381 1.4478)
			(layers "F.Cu" "F.Mask" "F.Paste")
			(net "OCP_SFF_PRSNT1_R_N")
		)
		(pad "A43" smd rect
			(at -2.750058 14.454886 180)
			(size 0.381 1.4478)
			(layers "F.Cu" "F.Mask" "F.Paste")
			(net "GND")
		)
		(pad "A44" smd rect
			(at -2.750058 15.055088 180)
			(size 0.381 1.4478)
			(layers "F.Cu" "F.Mask" "F.Paste")
			(net "P5E_CPU0_G3_RX_DN<8>")
		)
		(pad "A45" smd rect
			(at -2.750058 15.655036 180)
			(size 0.381 1.4478)
			(layers "F.Cu" "F.Mask" "F.Paste")
			(net "P5E_CPU0_G3_RX_DP<8>")
		)
		(pad "A46" smd rect
			(at -2.750058 16.254984 180)
			(size 0.381 1.4478)
			(layers "F.Cu" "F.Mask" "F.Paste")
			(net "GND")
		)
		(pad "A47" smd rect
			(at -2.750058 16.854932 180)
			(size 0.381 1.4478)
			(layers "F.Cu" "F.Mask" "F.Paste")
			(net "P5E_CPU0_G3_RX_DN<9>")
		)
		(pad "A48" smd rect
			(at -2.750058 17.45488 180)
			(size 0.381 1.4478)
			(layers "F.Cu" "F.Mask" "F.Paste")
			(net "P5E_CPU0_G3_RX_DP<9>")
		)
		(pad "A49" smd rect
			(at -2.750058 18.055082 180)
			(size 0.381 1.4478)
			(layers "F.Cu" "F.Mask" "F.Paste")
			(net "GND")
		)
		(pad "A50" smd rect
			(at -2.750058 18.65503 180)
			(size 0.381 1.4478)
			(layers "F.Cu" "F.Mask" "F.Paste")
			(net "P5E_CPU0_G3_RX_DN<10>")
		)
		(pad "A51" smd rect
			(at -2.750058 19.254978 180)
			(size 0.381 1.4478)
			(layers "F.Cu" "F.Mask" "F.Paste")
			(net "P5E_CPU0_G3_RX_DP<10>")
		)
		(pad "A52" smd rect
			(at -2.750058 19.854926 180)
			(size 0.381 1.4478)
			(layers "F.Cu" "F.Mask" "F.Paste")
			(net "GND")
		)
		(pad "A53" smd rect
			(at -2.750058 20.455128 180)
			(size 0.381 1.4478)
			(layers "F.Cu" "F.Mask" "F.Paste")
			(net "P5E_CPU0_G3_RX_DN<11>")
		)
		(pad "A54" smd rect
			(at -2.750058 21.055076 180)
			(size 0.381 1.4478)
			(layers "F.Cu" "F.Mask" "F.Paste")
			(net "P5E_CPU0_G3_RX_DP<11>")
		)
		(pad "A55" smd rect
			(at -2.750058 21.655024 180)
			(size 0.381 1.4478)
			(layers "F.Cu" "F.Mask" "F.Paste")
			(net "GND")
		)
		(pad "A56" smd rect
			(at -2.750058 22.254972 180)
			(size 0.381 1.4478)
			(layers "F.Cu" "F.Mask" "F.Paste")
			(net "P5E_CPU0_G3_RX_DN<12>")
		)
		(pad "A57" smd rect
			(at -2.750058 22.85492 180)
			(size 0.381 1.4478)
			(layers "F.Cu" "F.Mask" "F.Paste")
			(net "P5E_CPU0_G3_RX_DP<12>")
		)
		(pad "A58" smd rect
			(at -2.750058 23.455122 180)
			(size 0.381 1.4478)
			(layers "F.Cu" "F.Mask" "F.Paste")
			(net "GND")
		)
		(pad "A59" smd rect
			(at -2.750058 24.05507 180)
			(size 0.381 1.4478)
			(layers "F.Cu" "F.Mask" "F.Paste")
			(net "P5E_CPU0_G3_RX_DN<13>")
		)
		(pad "A60" smd rect
			(at -2.750058 24.655018 180)
			(size 0.381 1.4478)
			(layers "F.Cu" "F.Mask" "F.Paste")
			(net "P5E_CPU0_G3_RX_DP<13>")
		)
		(pad "A61" smd rect
			(at -2.750058 25.254966 180)
			(size 0.381 1.4478)
			(layers "F.Cu" "F.Mask" "F.Paste")
			(net "GND")
		)
		(pad "A62" smd rect
			(at -2.750058 25.854914 180)
			(size 0.381 1.4478)
			(layers "F.Cu" "F.Mask" "F.Paste")
			(net "P5E_CPU0_G3_RX_DN<14>")
		)
		(pad "A63" smd rect
			(at -2.750058 26.455116 180)
			(size 0.381 1.4478)
			(layers "F.Cu" "F.Mask" "F.Paste")
			(net "P5E_CPU0_G3_RX_DP<14>")
		)
		(pad "A64" smd rect
			(at -2.750058 27.055064 180)
			(size 0.381 1.4478)
			(layers "F.Cu" "F.Mask" "F.Paste")
			(net "GND")
		)
		(pad "A65" smd rect
			(at -2.750058 27.655012 180)
			(size 0.381 1.4478)
			(layers "F.Cu" "F.Mask" "F.Paste")
			(net "P5E_CPU0_G3_RX_DN<15>")
		)
		(pad "A66" smd rect
			(at -2.750058 28.25496 180)
			(size 0.381 1.4478)
			(layers "F.Cu" "F.Mask" "F.Paste")
			(net "P5E_CPU0_G3_RX_DP<15>")
		)
		(pad "A67" smd rect
			(at -2.750058 28.854908 180)
			(size 0.381 1.4478)
			(layers "F.Cu" "F.Mask" "F.Paste")
			(net "GND")
		)
		(pad "A68" smd rect
			(at -2.750058 29.45511 180)
			(size 0.381 1.4478)
			(layers "F.Cu" "F.Mask" "F.Paste")
			(net "USB2_P11_DN")
		)
		(pad "A69" smd rect
			(at -2.750058 30.055058 180)
			(size 0.381 1.4478)
			(layers "F.Cu" "F.Mask" "F.Paste")
			(net "USB2_P11_DP")
		)
		(pad "A70" smd rect
			(at -2.750058 30.655006 180)
			(size 0.381 1.4478)
			(layers "F.Cu" "F.Mask" "F.Paste")
			(net "OCP_SFF_PWRBRK_N")
		)
		(pad "B1" smd rect
			(at -5.700014 -18.465038 180)
			(size 0.381 1.4478)
			(layers "F.Cu" "F.Mask" "F.Paste")
			(net "P12V_OCP_SFF_R")
		)
		(pad "B2" smd rect
			(at -5.700014 -17.86509 180)
			(size 0.381 1.4478)
			(layers "F.Cu" "F.Mask" "F.Paste")
			(net "P12V_OCP_SFF_R")
		)
		(pad "B3" smd rect
			(at -5.700014 -17.264888 180)
			(size 0.381 1.4478)
			(layers "F.Cu" "F.Mask" "F.Paste")
			(net "P12V_OCP_SFF_R")
		)
		(pad "B4" smd rect
			(at -5.700014 -16.66494 180)
			(size 0.381 1.4478)
			(layers "F.Cu" "F.Mask" "F.Paste")
			(net "P12V_OCP_SFF_R")
		)
		(pad "B5" smd rect
			(at -5.700014 -16.064992 180)
			(size 0.381 1.4478)
			(layers "F.Cu" "F.Mask" "F.Paste")
			(net "P12V_OCP_SFF_R")
		)
		(pad "B6" smd rect
			(at -5.700014 -15.465044 180)
			(size 0.381 1.4478)
			(layers "F.Cu" "F.Mask" "F.Paste")
			(net "P12V_OCP_SFF_R")
		)
		(pad "B7" smd rect
			(at -5.700014 -14.865096 180)
			(size 0.381 1.4478)
			(layers "F.Cu" "F.Mask" "F.Paste")
			(net "OCP_SFF_BIF0_R_N")
		)
		(pad "B8" smd rect
			(at -5.700014 -14.264894 180)
			(size 0.381 1.4478)
			(layers "F.Cu" "F.Mask" "F.Paste")
			(net "OCP_SFF_BIF1_R_N")
		)
		(pad "B9" smd rect
			(at -5.700014 -13.664946 180)
			(size 0.381 1.4478)
			(layers "F.Cu" "F.Mask" "F.Paste")
			(net "OCP_SFF_BIF2_R_N")
		)
		(pad "B10" smd rect
			(at -5.700014 -13.064998 180)
			(size 0.381 1.4478)
			(layers "F.Cu" "F.Mask" "F.Paste")
			(net "RST_PERST0_OCP_SFF_N")
		)
		(pad "B11" smd rect
			(at -5.700014 -12.46505 180)
			(size 0.381 1.4478)
			(layers "F.Cu" "F.Mask" "F.Paste")
			(net "P3V3_OCP_SFF")
		)
		(pad "B12" smd rect
			(at -5.700014 -11.865102 180)
			(size 0.381 1.4478)
			(layers "F.Cu" "F.Mask" "F.Paste")
			(net "OCP_SFF_AUX_PWR_EN_R")
		)
		(pad "B13" smd rect
			(at -5.700014 -11.2649 180)
			(size 0.381 1.4478)
			(layers "F.Cu" "F.Mask" "F.Paste")
			(net "GND")
		)
		(pad "B14" smd rect
			(at -5.700014 -10.664952 180)
			(size 0.381 1.4478)
			(layers "F.Cu" "F.Mask" "F.Paste")
			(net "CLK_100M_CPU0_CLK02_DN")
		)
		(pad "B15" smd rect
			(at -5.700014 -10.065004 180)
			(size 0.381 1.4478)
			(layers "F.Cu" "F.Mask" "F.Paste")
			(net "CLK_100M_CPU0_CLK02_DP")
		)
		(pad "B16" smd rect
			(at -5.700014 -9.465056 180)
			(size 0.381 1.4478)
			(layers "F.Cu" "F.Mask" "F.Paste")
			(net "GND")
		)
		(pad "B17" smd rect
			(at -5.700014 -8.865108 180)
			(size 0.381 1.4478)
			(layers "F.Cu" "F.Mask" "F.Paste")
			(net "P5E_CPU0_G3_TX_C_DP<0>")
		)
		(pad "B18" smd rect
			(at -5.700014 -8.264906 180)
			(size 0.381 1.4478)
			(layers "F.Cu" "F.Mask" "F.Paste")
			(net "P5E_CPU0_G3_TX_C_DN<0>")
		)
		(pad "B19" smd rect
			(at -5.700014 -7.664958 180)
			(size 0.381 1.4478)
			(layers "F.Cu" "F.Mask" "F.Paste")
			(net "GND")
		)
		(pad "B20" smd rect
			(at -5.700014 -7.06501 180)
			(size 0.381 1.4478)
			(layers "F.Cu" "F.Mask" "F.Paste")
			(net "P5E_CPU0_G3_TX_C_DP<1>")
		)
		(pad "B21" smd rect
			(at -5.700014 -6.465062 180)
			(size 0.381 1.4478)
			(layers "F.Cu" "F.Mask" "F.Paste")
			(net "P5E_CPU0_G3_TX_C_DN<1>")
		)
		(pad "B22" smd rect
			(at -5.700014 -5.865114 180)
			(size 0.381 1.4478)
			(layers "F.Cu" "F.Mask" "F.Paste")
			(net "GND")
		)
		(pad "B23" smd rect
			(at -5.700014 -5.264912 180)
			(size 0.381 1.4478)
			(layers "F.Cu" "F.Mask" "F.Paste")
			(net "P5E_CPU0_G3_TX_C_DP<2>")
		)
		(pad "B24" smd rect
			(at -5.700014 -4.664964 180)
			(size 0.381 1.4478)
			(layers "F.Cu" "F.Mask" "F.Paste")
			(net "P5E_CPU0_G3_TX_C_DN<2>")
		)
		(pad "B25" smd rect
			(at -5.700014 -4.065016 180)
			(size 0.381 1.4478)
			(layers "F.Cu" "F.Mask" "F.Paste")
			(net "GND")
		)
		(pad "B26" smd rect
			(at -5.700014 -3.465068 180)
			(size 0.381 1.4478)
			(layers "F.Cu" "F.Mask" "F.Paste")
			(net "P5E_CPU0_G3_TX_C_DP<3>")
		)
		(pad "B27" smd rect
			(at -5.700014 -2.86512 180)
			(size 0.381 1.4478)
			(layers "F.Cu" "F.Mask" "F.Paste")
			(net "P5E_CPU0_G3_TX_C_DN<3>")
		)
		(pad "B28" smd rect
			(at -5.700014 -2.264918 180)
			(size 0.381 1.4478)
			(layers "F.Cu" "F.Mask" "F.Paste")
			(net "GND")
		)
		(pad "B29" smd rect
			(at -5.700014 1.74498 180)
			(size 0.381 1.4478)
			(layers "F.Cu" "F.Mask" "F.Paste")
			(net "GND")
		)
		(pad "B30" smd rect
			(at -5.700014 2.344928 180)
			(size 0.381 1.4478)
			(layers "F.Cu" "F.Mask" "F.Paste")
			(net "P5E_CPU0_G3_TX_C_DP<4>")
		)
		(pad "B31" smd rect
			(at -5.700014 2.944876 180)
			(size 0.381 1.4478)
			(layers "F.Cu" "F.Mask" "F.Paste")
			(net "P5E_CPU0_G3_TX_C_DN<4>")
		)
		(pad "B32" smd rect
			(at -5.700014 3.545078 180)
			(size 0.381 1.4478)
			(layers "F.Cu" "F.Mask" "F.Paste")
			(net "GND")
		)
		(pad "B33" smd rect
			(at -5.700014 4.145026 180)
			(size 0.381 1.4478)
			(layers "F.Cu" "F.Mask" "F.Paste")
			(net "P5E_CPU0_G3_TX_C_DP<5>")
		)
		(pad "B34" smd rect
			(at -5.700014 4.744974 180)
			(size 0.381 1.4478)
			(layers "F.Cu" "F.Mask" "F.Paste")
			(net "P5E_CPU0_G3_TX_C_DN<5>")
		)
		(pad "B35" smd rect
			(at -5.700014 5.344922 180)
			(size 0.381 1.4478)
			(layers "F.Cu" "F.Mask" "F.Paste")
			(net "GND")
		)
		(pad "B36" smd rect
			(at -5.700014 5.945124 180)
			(size 0.381 1.4478)
			(layers "F.Cu" "F.Mask" "F.Paste")
			(net "P5E_CPU0_G3_TX_C_DP<6>")
		)
		(pad "B37" smd rect
			(at -5.700014 6.545072 180)
			(size 0.381 1.4478)
			(layers "F.Cu" "F.Mask" "F.Paste")
			(net "P5E_CPU0_G3_TX_C_DN<6>")
		)
		(pad "B38" smd rect
			(at -5.700014 7.14502 180)
			(size 0.381 1.4478)
			(layers "F.Cu" "F.Mask" "F.Paste")
			(net "GND")
		)
		(pad "B39" smd rect
			(at -5.700014 7.744968 180)
			(size 0.381 1.4478)
			(layers "F.Cu" "F.Mask" "F.Paste")
			(net "P5E_CPU0_G3_TX_C_DP<7>")
		)
		(pad "B40" smd rect
			(at -5.700014 8.344916 180)
			(size 0.381 1.4478)
			(layers "F.Cu" "F.Mask" "F.Paste")
			(net "P5E_CPU0_G3_TX_C_DN<7>")
		)
		(pad "B41" smd rect
			(at -5.700014 8.945118 180)
			(size 0.381 1.4478)
			(layers "F.Cu" "F.Mask" "F.Paste")
			(net "GND")
		)
		(pad "B42" smd rect
			(at -5.700014 9.545066 180)
			(size 0.381 1.4478)
			(layers "F.Cu" "F.Mask" "F.Paste")
			(net "OCP_SFF_PRSNT0_R_N")
		)
		(pad "B43" smd rect
			(at -5.700014 14.454886 180)
			(size 0.381 1.4478)
			(layers "F.Cu" "F.Mask" "F.Paste")
			(net "GND")
		)
		(pad "B44" smd rect
			(at -5.700014 15.055088 180)
			(size 0.381 1.4478)
			(layers "F.Cu" "F.Mask" "F.Paste")
			(net "P5E_CPU0_G3_TX_C_DP<8>")
		)
		(pad "B45" smd rect
			(at -5.700014 15.655036 180)
			(size 0.381 1.4478)
			(layers "F.Cu" "F.Mask" "F.Paste")
			(net "P5E_CPU0_G3_TX_C_DN<8>")
		)
		(pad "B46" smd rect
			(at -5.700014 16.254984 180)
			(size 0.381 1.4478)
			(layers "F.Cu" "F.Mask" "F.Paste")
			(net "GND")
		)
		(pad "B47" smd rect
			(at -5.700014 16.854932 180)
			(size 0.381 1.4478)
			(layers "F.Cu" "F.Mask" "F.Paste")
			(net "P5E_CPU0_G3_TX_C_DP<9>")
		)
		(pad "B48" smd rect
			(at -5.700014 17.45488 180)
			(size 0.381 1.4478)
			(layers "F.Cu" "F.Mask" "F.Paste")
			(net "P5E_CPU0_G3_TX_C_DN<9>")
		)
		(pad "B49" smd rect
			(at -5.700014 18.055082 180)
			(size 0.381 1.4478)
			(layers "F.Cu" "F.Mask" "F.Paste")
			(net "GND")
		)
		(pad "B50" smd rect
			(at -5.700014 18.65503 180)
			(size 0.381 1.4478)
			(layers "F.Cu" "F.Mask" "F.Paste")
			(net "P5E_CPU0_G3_TX_C_DP<10>")
		)
		(pad "B51" smd rect
			(at -5.700014 19.254978 180)
			(size 0.381 1.4478)
			(layers "F.Cu" "F.Mask" "F.Paste")
			(net "P5E_CPU0_G3_TX_C_DN<10>")
		)
		(pad "B52" smd rect
			(at -5.700014 19.854926 180)
			(size 0.381 1.4478)
			(layers "F.Cu" "F.Mask" "F.Paste")
			(net "GND")
		)
		(pad "B53" smd rect
			(at -5.700014 20.455128 180)
			(size 0.381 1.4478)
			(layers "F.Cu" "F.Mask" "F.Paste")
			(net "P5E_CPU0_G3_TX_C_DP<11>")
		)
		(pad "B54" smd rect
			(at -5.700014 21.055076 180)
			(size 0.381 1.4478)
			(layers "F.Cu" "F.Mask" "F.Paste")
			(net "P5E_CPU0_G3_TX_C_DN<11>")
		)
		(pad "B55" smd rect
			(at -5.700014 21.655024 180)
			(size 0.381 1.4478)
			(layers "F.Cu" "F.Mask" "F.Paste")
			(net "GND")
		)
		(pad "B56" smd rect
			(at -5.700014 22.254972 180)
			(size 0.381 1.4478)
			(layers "F.Cu" "F.Mask" "F.Paste")
			(net "P5E_CPU0_G3_TX_C_DP<12>")
		)
		(pad "B57" smd rect
			(at -5.700014 22.85492 180)
			(size 0.381 1.4478)
			(layers "F.Cu" "F.Mask" "F.Paste")
			(net "P5E_CPU0_G3_TX_C_DN<12>")
		)
		(pad "B58" smd rect
			(at -5.700014 23.455122 180)
			(size 0.381 1.4478)
			(layers "F.Cu" "F.Mask" "F.Paste")
			(net "GND")
		)
		(pad "B59" smd rect
			(at -5.700014 24.05507 180)
			(size 0.381 1.4478)
			(layers "F.Cu" "F.Mask" "F.Paste")
			(net "P5E_CPU0_G3_TX_C_DP<13>")
		)
		(pad "B60" smd rect
			(at -5.700014 24.655018 180)
			(size 0.381 1.4478)
			(layers "F.Cu" "F.Mask" "F.Paste")
			(net "P5E_CPU0_G3_TX_C_DN<13>")
		)
		(pad "B61" smd rect
			(at -5.700014 25.254966 180)
			(size 0.381 1.4478)
			(layers "F.Cu" "F.Mask" "F.Paste")
			(net "GND")
		)
		(pad "B62" smd rect
			(at -5.700014 25.854914 180)
			(size 0.381 1.4478)
			(layers "F.Cu" "F.Mask" "F.Paste")
			(net "P5E_CPU0_G3_TX_C_DP<14>")
		)
		(pad "B63" smd rect
			(at -5.700014 26.455116 180)
			(size 0.381 1.4478)
			(layers "F.Cu" "F.Mask" "F.Paste")
			(net "P5E_CPU0_G3_TX_C_DN<14>")
		)
		(pad "B64" smd rect
			(at -5.700014 27.055064 180)
			(size 0.381 1.4478)
			(layers "F.Cu" "F.Mask" "F.Paste")
			(net "GND")
		)
		(pad "B65" smd rect
			(at -5.700014 27.655012 180)
			(size 0.381 1.4478)
			(layers "F.Cu" "F.Mask" "F.Paste")
			(net "P5E_CPU0_G3_TX_C_DP<15>")
		)
		(pad "B66" smd rect
			(at -5.700014 28.25496 180)
			(size 0.381 1.4478)
			(layers "F.Cu" "F.Mask" "F.Paste")
			(net "P5E_CPU0_G3_TX_C_DN<15>")
		)
		(pad "B67" smd rect
			(at -5.700014 28.854908 180)
			(size 0.381 1.4478)
			(layers "F.Cu" "F.Mask" "F.Paste")
			(net "GND")
		)
		(pad "B68" smd rect
			(at -5.700014 29.45511 180)
			(size 0.381 1.4478)
			(layers "F.Cu" "F.Mask" "F.Paste")
			(net "TP_OCP_SFF_B68")
		)
		(pad "B69" smd rect
			(at -5.700014 30.055058 180)
			(size 0.381 1.4478)
			(layers "F.Cu" "F.Mask" "F.Paste")
			(net "TP_OCP_SFF_B69")
		)
		(pad "B70" smd rect
			(at -5.700014 30.655006 180)
			(size 0.381 1.4478)
			(layers "F.Cu" "F.Mask" "F.Paste")
			(net "OCP_SFF_PRSNT3_R_N")
		)
		(pad "G1" thru_hole circle
			(at 2.400046 -32.759904 180)
			(size 1.6256 1.6256)
			(drill 1.1176)
			(layers "*.Cu" "*.Mask")
			(remove_unused_layers no)
			(net "GND")
			(clearance 0)
		)
		(pad "G2" thru_hole circle
			(at 2.400046 -20.379944 180)
			(size 1.6256 1.6256)
			(drill 1.1176)
			(layers "*.Cu" "*.Mask")
			(remove_unused_layers no)
			(net "GND")
			(clearance 0)
		)
		(pad "G3" thru_hole circle
			(at 2.400046 0 180)
			(size 1.6256 1.6256)
			(drill 1.1176)
			(layers "*.Cu" "*.Mask")
			(remove_unused_layers no)
			(net "GND")
			(clearance 0)
		)
		(pad "G4" thru_hole circle
			(at 2.400046 12.5349 180)
			(size 1.6256 1.6256)
			(drill 1.1176)
			(layers "*.Cu" "*.Mask")
			(remove_unused_layers no)
			(net "GND")
			(clearance 0)
		)
		(pad "G5" thru_hole circle
			(at 2.400046 32.759904 180)
			(size 1.6256 1.6256)
			(drill 1.1176)
			(layers "*.Cu" "*.Mask")
			(remove_unused_layers no)
			(net "GND")
			(clearance 0)
		)
		(pad "OA1" smd rect
			(at -2.750058 -30.660086 180)
			(size 0.381 1.4478)
			(layers "F.Cu" "F.Mask" "F.Paste")
			(net "RST_PERST2_OCP_SFF_N")
		)
		(pad "OA2" smd rect
			(at -2.750058 -30.059884 180)
			(size 0.381 1.4478)
			(layers "F.Cu" "F.Mask" "F.Paste")
			(net "RST_PERST3_OCP_SFF_N")
		)
		(pad "OA3" smd rect
			(at -2.750058 -29.459936 180)
			(size 0.381 1.4478)
			(layers "F.Cu" "F.Mask" "F.Paste")
			(net "IRQ_LVC3_OCP_SFF_WAKE_N")
		)
		(pad "OA4" smd rect
			(at -2.750058 -28.859988 180)
			(size 0.381 1.4478)
			(layers "F.Cu" "F.Mask" "F.Paste")
			(net "OCP_SFF_ISO1_RBT_ARB_IN")
		)
		(pad "OA5" smd rect
			(at -2.750058 -28.26004 180)
			(size 0.381 1.4478)
			(layers "F.Cu" "F.Mask" "F.Paste")
			(net "OCP_SFF_ISO2_RBT_ARB_OUT")
		)
		(pad "OA6" smd rect
			(at -2.750058 -27.660092 180)
			(size 0.381 1.4478)
			(layers "F.Cu" "F.Mask" "F.Paste")
			(net "OCP_SFF_ID1")
		)
		(pad "OA7" smd rect
			(at -2.750058 -27.05989 180)
			(size 0.381 1.4478)
			(layers "F.Cu" "F.Mask" "F.Paste")
			(net "NCSI_OCP_SFF_TX_EN")
		)
		(pad "OA8" smd rect
			(at -2.750058 -26.459942 180)
			(size 0.381 1.4478)
			(layers "F.Cu" "F.Mask" "F.Paste")
			(net "NCSI_OCP_SFF_TXD1")
		)
		(pad "OA9" smd rect
			(at -2.750058 -25.859994 180)
			(size 0.381 1.4478)
			(layers "F.Cu" "F.Mask" "F.Paste")
			(net "NCSI_OCP_SFF_TXD0")
		)
		(pad "OA10" smd rect
			(at -2.750058 -25.260046 180)
			(size 0.381 1.4478)
			(layers "F.Cu" "F.Mask" "F.Paste")
			(net "GND")
		)
		(pad "OA11" smd rect
			(at -2.750058 -24.660098 180)
			(size 0.381 1.4478)
			(layers "F.Cu" "F.Mask" "F.Paste")
			(net "CLK_100M_CPU0_CLK05_DN")
		)
		(pad "OA12" smd rect
			(at -2.750058 -24.059896 180)
			(size 0.381 1.4478)
			(layers "F.Cu" "F.Mask" "F.Paste")
			(net "CLK_100M_CPU0_CLK05_DP")
		)
		(pad "OA13" smd rect
			(at -2.750058 -23.459948 180)
			(size 0.381 1.4478)
			(layers "F.Cu" "F.Mask" "F.Paste")
			(net "GND")
		)
		(pad "OA14" smd rect
			(at -2.750058 -22.86 180)
			(size 0.381 1.4478)
			(layers "F.Cu" "F.Mask" "F.Paste")
			(net "CLK_50M_NCSI_OCP_SFF_ISO")
		)
		(pad "OB1" smd rect
			(at -5.700014 -30.660086 180)
			(size 0.381 1.4478)
			(layers "F.Cu" "F.Mask" "F.Paste")
			(net "FM_OCP_SFF_PWR_GOOD")
		)
		(pad "OB2" smd rect
			(at -5.700014 -30.059884 180)
			(size 0.381 1.4478)
			(layers "F.Cu" "F.Mask" "F.Paste")
			(net "OCP_SFF_MAIN_PWR_EN_R")
		)
		(pad "OB3" smd rect
			(at -5.700014 -29.459936 180)
			(size 0.381 1.4478)
			(layers "F.Cu" "F.Mask" "F.Paste")
			(net "SGPIO_OCP_SFF_LD_N")
		)
		(pad "OB4" smd rect
			(at -5.700014 -28.859988 180)
			(size 0.381 1.4478)
			(layers "F.Cu" "F.Mask" "F.Paste")
			(net "SGPIO_OCP_SFF_DATAIN")
		)
		(pad "OB5" smd rect
			(at -5.700014 -28.26004 180)
			(size 0.381 1.4478)
			(layers "F.Cu" "F.Mask" "F.Paste")
			(net "SGPIO_OCP_SFF_DATAOUT")
		)
		(pad "OB6" smd rect
			(at -5.700014 -27.660092 180)
			(size 0.381 1.4478)
			(layers "F.Cu" "F.Mask" "F.Paste")
			(net "SGPIO_OCP_SFF_CLK")
		)
		(pad "OB7" smd rect
			(at -5.700014 -27.05989 180)
			(size 0.381 1.4478)
			(layers "F.Cu" "F.Mask" "F.Paste")
			(net "OCP_SFF_ID0")
		)
		(pad "OB8" smd rect
			(at -5.700014 -26.459942 180)
			(size 0.381 1.4478)
			(layers "F.Cu" "F.Mask" "F.Paste")
			(net "NCSI_OCP_SFF_RXD1")
		)
		(pad "OB9" smd rect
			(at -5.700014 -25.859994 180)
			(size 0.381 1.4478)
			(layers "F.Cu" "F.Mask" "F.Paste")
			(net "NCSI_OCP_SFF_RXD0")
		)
		(pad "OB10" smd rect
			(at -5.700014 -25.260046 180)
			(size 0.381 1.4478)
			(layers "F.Cu" "F.Mask" "F.Paste")
			(net "GND")
		)
		(pad "OB11" smd rect
			(at -5.700014 -24.660098 180)
			(size 0.381 1.4478)
			(layers "F.Cu" "F.Mask" "F.Paste")
			(net "CLK_100M_CPU0_CLK04_DN")
		)
		(pad "OB12" smd rect
			(at -5.700014 -24.059896 180)
			(size 0.381 1.4478)
			(layers "F.Cu" "F.Mask" "F.Paste")
			(net "CLK_100M_CPU0_CLK04_DP")
		)
		(pad "OB13" smd rect
			(at -5.700014 -23.459948 180)
			(size 0.381 1.4478)
			(layers "F.Cu" "F.Mask" "F.Paste")
			(net "GND")
		)
		(pad "OB14" smd rect
			(at -5.700014 -22.86 180)
			(size 0.381 1.4478)
			(layers "F.Cu" "F.Mask" "F.Paste")
			(net "NCSI_OCP_SFF_CRS_DV")
		)
		(zone
			(layers "F.Cu" "B.Cu" "In1.Cu" "In2.Cu" "In3.Cu" "In4.Cu" "In5.Cu" "In6.Cu"
				"In7.Cu" "In8.Cu" "In9.Cu" "In10.Cu" "In11.Cu" "In12.Cu" "In13.Cu" "In14.Cu"
				"In15.Cu" "In16.Cu"
			)
			(hatch none 0.5)
			(connect_pads
				(clearance 0)
			)
			(min_thickness 0.25)
			(keepout
				(tracks not_allowed)
				(vias allowed)
				(pads allowed)
				(copperpour not_allowed)
				(footprints allowed)
			)
			(placement
				(enabled no)
				(sheetname "")
			)
			(fill
				(thermal_gap 0.5)
				(thermal_bridge_width 0.5)
				(island_removal_mode 0)
			)
			(polygon
				(pts
					(arc
						(start 390.782048 -5.169916)
						(mid 388.851648 -5.169916)
						(end 390.782048 -5.169916)
					)
				)
			)
		)
		(zone
			(layers "F.Cu" "B.Cu" "In1.Cu" "In2.Cu" "In3.Cu" "In4.Cu" "In5.Cu" "In6.Cu"
				"In7.Cu" "In8.Cu" "In9.Cu" "In10.Cu" "In11.Cu" "In12.Cu" "In13.Cu" "In14.Cu"
				"In15.Cu" "In16.Cu"
			)
			(hatch none 0.5)
			(connect_pads
				(clearance 0)
			)
			(min_thickness 0.25)
			(keepout
				(tracks not_allowed)
				(vias allowed)
				(pads allowed)
				(copperpour not_allowed)
				(footprints allowed)
			)
			(placement
				(enabled no)
				(sheetname "")
			)
			(fill
				(thermal_gap 0.5)
				(thermal_bridge_width 0.5)
				(island_removal_mode 0)
			)
			(polygon
				(pts
					(arc
						(start 454.94702 -6.169914)
						(mid 453.01662 -6.169914)
						(end 454.94702 -6.169914)
					)
				)
			)
		)
	)
	(footprint ""
		(layer "F.Cu")
		(at 83.222084 -38.63848 180)
		(property "Reference" "R6059"
			(at 0 0 180)
			(layer "F.SilkS")
			(hide yes)
			(effects
				(font
					(size 1.27 1.27)
				)
			)
		)
		(property "Value" ""
			(at 0 0 180)
			(layer "F.Fab")
			(effects
				(font
					(size 1.27 1.27)
				)
			)
		)
		(duplicate_pad_numbers_are_jumpers no)
		(fp_line
			(start 0.7874 0.4064)
			(end -0.7874 0.4064)
			(stroke
				(width 0.1524)
				(type default)
			)
			(layer "F.SilkS")
		)
		(fp_line
			(start 0.7874 -0.4064)
			(end 0.7874 0.4064)
			(stroke
				(width 0.1524)
				(type default)
			)
			(layer "F.SilkS")
		)
		(fp_line
			(start -0.7874 0.4064)
			(end -0.7874 -0.4064)
			(stroke
				(width 0.1524)
				(type default)
			)
			(layer "F.SilkS")
		)
		(fp_line
			(start -0.7874 -0.4064)
			(end 0.7874 -0.4064)
			(stroke
				(width 0.1524)
				(type default)
			)
			(layer "F.SilkS")
		)
		(fp_line
			(start 0.67945 0.3048)
			(end 0.120396 0.3048)
			(stroke
				(width 0.1)
				(type default)
			)
			(layer "F.Fab")
		)
		(fp_line
			(start 0.67945 -0.3048)
			(end 0.67945 0.3048)
			(stroke
				(width 0.1)
				(type default)
			)
			(layer "F.Fab")
		)
		(fp_line
			(start 0.12065 -0.2794)
			(end 0.12065 -0.3048)
			(stroke
				(width 0.1)
				(type default)
			)
			(layer "F.Fab")
		)
		(fp_line
			(start 0.12065 -0.3048)
			(end 0.67945 -0.3048)
			(stroke
				(width 0.1)
				(type default)
			)
			(layer "F.Fab")
		)
		(fp_line
			(start 0.120396 0.3048)
			(end 0.120396 0.2794)
			(stroke
				(width 0.1)
				(type default)
			)
			(layer "F.Fab")
		)
		(fp_line
			(start 0.120396 0.2794)
			(end -0.12065 0.2794)
			(stroke
				(width 0.1)
				(type default)
			)
			(layer "F.Fab")
		)
		(fp_line
			(start -0.12065 0.3048)
			(end -0.67945 0.3048)
			(stroke
				(width 0.1)
				(type default)
			)
			(layer "F.Fab")
		)
		(fp_line
			(start -0.12065 0.2794)
			(end -0.12065 0.3048)
			(stroke
				(width 0.1)
				(type default)
			)
			(layer "F.Fab")
		)
		(fp_line
			(start -0.12065 -0.2794)
			(end 0.12065 -0.2794)
			(stroke
				(width 0.1)
				(type default)
			)
			(layer "F.Fab")
		)
		(fp_line
			(start -0.12065 -0.305054)
			(end -0.12065 -0.2794)
			(stroke
				(width 0.1)
				(type default)
			)
			(layer "F.Fab")
		)
		(fp_line
			(start -0.67945 0.3048)
			(end -0.67945 -0.305054)
			(stroke
				(width 0.1)
				(type default)
			)
			(layer "F.Fab")
		)
		(fp_line
			(start -0.67945 -0.305054)
			(end -0.12065 -0.305054)
			(stroke
				(width 0.1)
				(type default)
			)
			(layer "F.Fab")
		)
		(pad "1" smd circle
			(at -0.40005 0 180)
			(size 0 0)
			(layers "F.Cu" "F.Mask" "F.Paste")
			(net "RST_PERST_OCP_V3_2_BUF2_N")
		)
		(pad "2" smd circle
			(at 0.40005 0 180)
			(size 0 0)
			(layers "F.Cu" "F.Mask" "F.Paste")
			(net "RST_PERST3_OCP_V3_2_N")
		)
	)
	(footprint ""
		(layer "F.Cu")
		(at 69.341492 -171.932854)
		(property "Reference" "PC321"
			(at 0 0 0)
			(layer "F.SilkS")
			(hide yes)
			(effects
				(font
					(size 1.27 1.27)
				)
			)
		)
		(property "Value" ""
			(at 0 0 0)
			(layer "F.Fab")
			(effects
				(font
					(size 1.27 1.27)
				)
			)
		)
		(duplicate_pad_numbers_are_jumpers no)
		(fp_line
			(start -0.7874 -0.4064)
			(end 0.7874 -0.4064)
			(stroke
				(width 0.1524)
				(type default)
			)
			(layer "F.SilkS")
		)
		(fp_line
			(start -0.7874 0.4064)
			(end -0.7874 -0.4064)
			(stroke
				(width 0.1524)
				(type default)
			)
			(layer "F.SilkS")
		)
		(fp_line
			(start 0.7874 -0.4064)
			(end 0.7874 0.4064)
			(stroke
				(width 0.1524)
				(type default)
			)
			(layer "F.SilkS")
		)
		(fp_line
			(start 0.7874 0.4064)
			(end -0.7874 0.4064)
			(stroke
				(width 0.1524)
				(type default)
			)
			(layer "F.SilkS")
		)
		(fp_line
			(start -0.67945 -0.305054)
			(end -0.12065 -0.305054)
			(stroke
				(width 0.1)
				(type default)
			)
			(layer "F.Fab")
		)
		(fp_line
			(start -0.67945 0.3048)
			(end -0.67945 -0.305054)
			(stroke
				(width 0.1)
				(type default)
			)
			(layer "F.Fab")
		)
		(fp_line
			(start -0.12065 -0.305054)
			(end -0.12065 -0.2794)
			(stroke
				(width 0.1)
				(type default)
			)
			(layer "F.Fab")
		)
		(fp_line
			(start -0.12065 -0.2794)
			(end 0.12065 -0.2794)
			(stroke
				(width 0.1)
				(type default)
			)
			(layer "F.Fab")
		)
		(fp_line
			(start -0.12065 0.2794)
			(end -0.12065 0.3048)
			(stroke
				(width 0.1)
				(type default)
			)
			(layer "F.Fab")
		)
		(fp_line
			(start -0.12065 0.3048)
			(end -0.67945 0.3048)
			(stroke
				(width 0.1)
				(type default)
			)
			(layer "F.Fab")
		)
		(fp_line
			(start 0.120396 0.2794)
			(end -0.12065 0.2794)
			(stroke
				(width 0.1)
				(type default)
			)
			(layer "F.Fab")
		)
		(fp_line
			(start 0.120396 0.3048)
			(end 0.120396 0.2794)
			(stroke
				(width 0.1)
				(type default)
			)
			(layer "F.Fab")
		)
		(fp_line
			(start 0.12065 -0.3048)
			(end 0.67945 -0.3048)
			(stroke
				(width 0.1)
				(type default)
			)
			(layer "F.Fab")
		)
		(fp_line
			(start 0.12065 -0.2794)
			(end 0.12065 -0.3048)
			(stroke
				(width 0.1)
				(type default)
			)
			(layer "F.Fab")
		)
		(fp_line
			(start 0.67945 -0.3048)
			(end 0.67945 0.3048)
			(stroke
				(width 0.1)
				(type default)
			)
			(layer "F.Fab")
		)
		(fp_line
			(start 0.67945 0.3048)
			(end 0.120396 0.3048)
			(stroke
				(width 0.1)
				(type default)
			)
			(layer "F.Fab")
		)
		(pad "1" smd circle
			(at -0.40005 0)
			(size 0 0)
			(layers "F.Cu" "F.Mask" "F.Paste")
			(net "SW_PVDDCR_CPU0_P1_SW6")
		)
		(pad "2" smd circle
			(at 0.40005 0)
			(size 0 0)
			(layers "F.Cu" "F.Mask" "F.Paste")
			(net "SW_PVDDCR_CPU0_P1_SW6_RC")
		)
	)
	(footprint ""
		(layer "F.Cu")
		(at 438.996074 -360.606848)
		(property "Reference" "PL24"
			(at -2.3876 -2.969768 0)
			(unlocked yes)
			(layer "F.SilkS")
			(effects
				(font
					(size 0.7874 0.5842)
					(thickness 0.1524)
				)
				(justify left)
			)
		)
		(property "Value" ""
			(at 0 0 0)
			(layer "F.Fab")
			(effects
				(font
					(size 1.27 1.27)
				)
			)
		)
		(duplicate_pad_numbers_are_jumpers no)
		(fp_line
			(start -2.249932 -2.249932)
			(end 2.249932 -2.249932)
			(stroke
				(width 0.1524)
				(type default)
			)
			(layer "F.SilkS")
		)
		(fp_line
			(start -2.249932 -1.3843)
			(end -2.249932 -2.249932)
			(stroke
				(width 0.1524)
				(type default)
			)
			(layer "F.SilkS")
		)
		(fp_line
			(start -2.249932 2.249932)
			(end -2.249932 1.3843)
			(stroke
				(width 0.1524)
				(type default)
			)
			(layer "F.SilkS")
		)
		(fp_line
			(start 2.249932 -2.249932)
			(end 2.249932 -1.3843)
			(stroke
				(width 0.1524)
				(type default)
			)
			(layer "F.SilkS")
		)
		(fp_line
			(start 2.249932 1.3843)
			(end 2.249932 2.249932)
			(stroke
				(width 0.1524)
				(type default)
			)
			(layer "F.SilkS")
		)
		(fp_line
			(start 2.249932 2.249932)
			(end -2.249932 2.249932)
			(stroke
				(width 0.1524)
				(type default)
			)
			(layer "F.SilkS")
		)
		(fp_line
			(start -2.249932 -2.249932)
			(end 2.249932 -2.249932)
			(stroke
				(width 0.1)
				(type default)
			)
			(layer "F.Fab")
		)
		(fp_line
			(start -2.249932 2.249932)
			(end -2.249932 -2.249932)
			(stroke
				(width 0.1)
				(type default)
			)
			(layer "F.Fab")
		)
		(fp_line
			(start 2.249932 -2.249932)
			(end 2.249932 2.249932)
			(stroke
				(width 0.1)
				(type default)
			)
			(layer "F.Fab")
		)
		(fp_line
			(start 2.249932 2.249932)
			(end -2.249932 2.249932)
			(stroke
				(width 0.1)
				(type default)
			)
			(layer "F.Fab")
		)
		(pad "1" smd rect
			(at -1.82499 0)
			(size 1.0668 2.5146)
			(layers "F.Cu" "F.Mask" "F.Paste")
			(net "SW_P12V_AUX_PVDD11_S3_P0_FLT")
		)
		(pad "2" smd rect
			(at 1.82499 0)
			(size 1.0668 2.5146)
			(layers "F.Cu" "F.Mask" "F.Paste")
			(net "P12V_AUX")
		)
	)
	(footprint ""
		(layer "F.Cu")
		(at 402.487638 -168.510966 90)
		(property "Reference" "PC584_2"
			(at 0 0 90)
			(layer "F.SilkS")
			(hide yes)
			(effects
				(font
					(size 1.27 1.27)
				)
			)
		)
		(property "Value" ""
			(at 0 0 90)
			(layer "F.Fab")
			(effects
				(font
					(size 1.27 1.27)
				)
			)
		)
		(duplicate_pad_numbers_are_jumpers no)
		(fp_line
			(start 0.7874 -0.4064)
			(end 0.7874 0.4064)
			(stroke
				(width 0.1524)
				(type default)
			)
			(layer "F.SilkS")
		)
		(fp_line
			(start -0.7874 -0.4064)
			(end 0.7874 -0.4064)
			(stroke
				(width 0.1524)
				(type default)
			)
			(layer "F.SilkS")
		)
		(fp_line
			(start 0.7874 0.4064)
			(end -0.7874 0.4064)
			(stroke
				(width 0.1524)
				(type default)
			)
			(layer "F.SilkS")
		)
		(fp_line
			(start -0.7874 0.4064)
			(end -0.7874 -0.4064)
			(stroke
				(width 0.1524)
				(type default)
			)
			(layer "F.SilkS")
		)
		(fp_line
			(start -0.12065 -0.305054)
			(end -0.12065 -0.2794)
			(stroke
				(width 0.1)
				(type default)
			)
			(layer "F.Fab")
		)
		(fp_line
			(start -0.67945 -0.305054)
			(end -0.12065 -0.305054)
			(stroke
				(width 0.1)
				(type default)
			)
			(layer "F.Fab")
		)
		(fp_line
			(start 0.67945 -0.3048)
			(end 0.67945 0.3048)
			(stroke
				(width 0.1)
				(type default)
			)
			(layer "F.Fab")
		)
		(fp_line
			(start 0.12065 -0.3048)
			(end 0.67945 -0.3048)
			(stroke
				(width 0.1)
				(type default)
			)
			(layer "F.Fab")
		)
		(fp_line
			(start 0.12065 -0.2794)
			(end 0.12065 -0.3048)
			(stroke
				(width 0.1)
				(type default)
			)
			(layer "F.Fab")
		)
		(fp_line
			(start -0.12065 -0.2794)
			(end 0.12065 -0.2794)
			(stroke
				(width 0.1)
				(type default)
			)
			(layer "F.Fab")
		)
		(fp_line
			(start 0.120396 0.2794)
			(end -0.12065 0.2794)
			(stroke
				(width 0.1)
				(type default)
			)
			(layer "F.Fab")
		)
		(fp_line
			(start -0.12065 0.2794)
			(end -0.12065 0.3048)
			(stroke
				(width 0.1)
				(type default)
			)
			(layer "F.Fab")
		)
		(fp_line
			(start 0.67945 0.3048)
			(end 0.120396 0.3048)
			(stroke
				(width 0.1)
				(type default)
			)
			(layer "F.Fab")
		)
		(fp_line
			(start 0.120396 0.3048)
			(end 0.120396 0.2794)
			(stroke
				(width 0.1)
				(type default)
			)
			(layer "F.Fab")
		)
		(fp_line
			(start -0.12065 0.3048)
			(end -0.67945 0.3048)
			(stroke
				(width 0.1)
				(type default)
			)
			(layer "F.Fab")
		)
		(fp_line
			(start -0.67945 0.3048)
			(end -0.67945 -0.305054)
			(stroke
				(width 0.1)
				(type default)
			)
			(layer "F.Fab")
		)
		(pad "1" smd circle
			(at -0.40005 0 90)
			(size 0 0)
			(layers "F.Cu" "F.Mask" "F.Paste")
			(net "SW_P12V_AUX_PVDDCR_SOC_P0_FLT")
		)
		(pad "2" smd circle
			(at 0.40005 0 90)
			(size 0 0)
			(layers "F.Cu" "F.Mask" "F.Paste")
			(net "GND")
		)
	)
	(footprint ""
		(layer "F.Cu")
		(at 259.834126 -96.206056 180)
		(property "Reference" "R1633"
			(at 0 0 180)
			(layer "F.SilkS")
			(hide yes)
			(effects
				(font
					(size 1.27 1.27)
				)
			)
		)
		(property "Value" ""
			(at 0 0 180)
			(layer "F.Fab")
			(effects
				(font
					(size 1.27 1.27)
				)
			)
		)
		(duplicate_pad_numbers_are_jumpers no)
		(fp_line
			(start 0.7874 0.4064)
			(end -0.7874 0.4064)
			(stroke
				(width 0.1524)
				(type default)
			)
			(layer "F.SilkS")
		)
		(fp_line
			(start 0.7874 -0.4064)
			(end 0.7874 0.4064)
			(stroke
				(width 0.1524)
				(type default)
			)
			(layer "F.SilkS")
		)
		(fp_line
			(start -0.7874 0.4064)
			(end -0.7874 -0.4064)
			(stroke
				(width 0.1524)
				(type default)
			)
			(layer "F.SilkS")
		)
		(fp_line
			(start -0.7874 -0.4064)
			(end 0.7874 -0.4064)
			(stroke
				(width 0.1524)
				(type default)
			)
			(layer "F.SilkS")
		)
		(fp_line
			(start 0.67945 0.3048)
			(end 0.120396 0.3048)
			(stroke
				(width 0.1)
				(type default)
			)
			(layer "F.Fab")
		)
		(fp_line
			(start 0.67945 -0.3048)
			(end 0.67945 0.3048)
			(stroke
				(width 0.1)
				(type default)
			)
			(layer "F.Fab")
		)
		(fp_line
			(start 0.12065 -0.2794)
			(end 0.12065 -0.3048)
			(stroke
				(width 0.1)
				(type default)
			)
			(layer "F.Fab")
		)
		(fp_line
			(start 0.12065 -0.3048)
			(end 0.67945 -0.3048)
			(stroke
				(width 0.1)
				(type default)
			)
			(layer "F.Fab")
		)
		(fp_line
			(start 0.120396 0.3048)
			(end 0.120396 0.2794)
			(stroke
				(width 0.1)
				(type default)
			)
			(layer "F.Fab")
		)
		(fp_line
			(start 0.120396 0.2794)
			(end -0.12065 0.2794)
			(stroke
				(width 0.1)
				(type default)
			)
			(layer "F.Fab")
		)
		(fp_line
			(start -0.12065 0.3048)
			(end -0.67945 0.3048)
			(stroke
				(width 0.1)
				(type default)
			)
			(layer "F.Fab")
		)
		(fp_line
			(start -0.12065 0.2794)
			(end -0.12065 0.3048)
			(stroke
				(width 0.1)
				(type default)
			)
			(layer "F.Fab")
		)
		(fp_line
			(start -0.12065 -0.2794)
			(end 0.12065 -0.2794)
			(stroke
				(width 0.1)
				(type default)
			)
			(layer "F.Fab")
		)
		(fp_line
			(start -0.12065 -0.305054)
			(end -0.12065 -0.2794)
			(stroke
				(width 0.1)
				(type default)
			)
			(layer "F.Fab")
		)
		(fp_line
			(start -0.67945 0.3048)
			(end -0.67945 -0.305054)
			(stroke
				(width 0.1)
				(type default)
			)
			(layer "F.Fab")
		)
		(fp_line
			(start -0.67945 -0.305054)
			(end -0.12065 -0.305054)
			(stroke
				(width 0.1)
				(type default)
			)
			(layer "F.Fab")
		)
		(pad "1" smd circle
			(at -0.40005 0 180)
			(size 0 0)
			(layers "F.Cu" "F.Mask" "F.Paste")
			(net "JTAG_TCK_R")
		)
		(pad "2" smd circle
			(at 0.40005 0 180)
			(size 0 0)
			(layers "F.Cu" "F.Mask" "F.Paste")
			(net "JTAG_TCK")
		)
	)
	(footprint ""
		(layer "F.Cu")
		(at 54.010814 -159.399478 180)
		(property "Reference" "PC89"
			(at 2.781808 3.588512 0)
			(unlocked yes)
			(layer "F.SilkS")
			(effects
				(font
					(size 0.7874 0.5842)
					(thickness 0.1524)
				)
				(justify left)
			)
		)
		(property "Value" ""
			(at 0 0 180)
			(layer "F.Fab")
			(effects
				(font
					(size 1.27 1.27)
				)
			)
		)
		(duplicate_pad_numbers_are_jumpers no)
		(fp_line
			(start 2.750058 2.750058)
			(end 2.750058 0.9398)
			(stroke
				(width 0.1524)
				(type default)
			)
			(layer "F.SilkS")
		)
		(fp_line
			(start 2.750058 -0.9398)
			(end 2.750058 -2.750058)
			(stroke
				(width 0.1524)
				(type default)
			)
			(layer "F.SilkS")
		)
		(fp_line
			(start 2.750058 -2.750058)
			(end -1.988058 -2.750058)
			(stroke
				(width 0.1524)
				(type default)
			)
			(layer "F.SilkS")
		)
		(fp_line
			(start -1.988058 2.750058)
			(end 2.750058 2.750058)
			(stroke
				(width 0.1524)
				(type default)
			)
			(layer "F.SilkS")
		)
		(fp_line
			(start -1.988058 -2.750058)
			(end -2.750058 -1.988058)
			(stroke
				(width 0.1524)
				(type default)
			)
			(layer "F.SilkS")
		)
		(fp_line
			(start -2.750058 1.988058)
			(end -1.988058 2.750058)
			(stroke
				(width 0.1524)
				(type default)
			)
			(layer "F.SilkS")
		)
		(fp_line
			(start -2.750058 0.9398)
			(end -2.750058 1.988058)
			(stroke
				(width 0.1524)
				(type default)
			)
			(layer "F.SilkS")
		)
		(fp_line
			(start -2.750058 -1.988058)
			(end -2.750058 -0.9398)
			(stroke
				(width 0.1524)
				(type default)
			)
			(layer "F.SilkS")
		)
		(fp_line
			(start 2.750058 2.750058)
			(end 2.750058 -2.750058)
			(stroke
				(width 0.1)
				(type default)
			)
			(layer "F.Fab")
		)
		(fp_line
			(start 2.750058 -2.750058)
			(end -2.750058 -2.750058)
			(stroke
				(width 0.1)
				(type default)
			)
			(layer "F.Fab")
		)
		(fp_line
			(start -2.750058 2.750058)
			(end 2.750058 2.750058)
			(stroke
				(width 0.1)
				(type default)
			)
			(layer "F.Fab")
		)
		(fp_line
			(start -2.750058 -2.750058)
			(end -2.750058 2.750058)
			(stroke
				(width 0.1)
				(type default)
			)
			(layer "F.Fab")
		)
		(pad "1" smd rect
			(at -2.199894 0 270)
			(size 1.6002 3.0226)
			(layers "F.Cu" "F.Mask" "F.Paste")
			(net "PVDD18_S5_P1")
		)
		(pad "2" smd rect
			(at 2.199894 0 270)
			(size 1.6002 3.0226)
			(layers "F.Cu" "F.Mask" "F.Paste")
			(net "GND")
		)
	)
	(footprint ""
		(layer "F.Cu")
		(at 264.986516 -139.591796 180)
		(property "Reference" "R1530"
			(at 0 0 180)
			(layer "F.SilkS")
			(hide yes)
			(effects
				(font
					(size 1.27 1.27)
				)
			)
		)
		(property "Value" ""
			(at 0 0 180)
			(layer "F.Fab")
			(effects
				(font
					(size 1.27 1.27)
				)
			)
		)
		(duplicate_pad_numbers_are_jumpers no)
		(fp_line
			(start 0.7874 0.4064)
			(end -0.7874 0.4064)
			(stroke
				(width 0.1524)
				(type default)
			)
			(layer "F.SilkS")
		)
		(fp_line
			(start 0.7874 -0.4064)
			(end 0.7874 0.4064)
			(stroke
				(width 0.1524)
				(type default)
			)
			(layer "F.SilkS")
		)
		(fp_line
			(start -0.7874 0.4064)
			(end -0.7874 -0.4064)
			(stroke
				(width 0.1524)
				(type default)
			)
			(layer "F.SilkS")
		)
		(fp_line
			(start -0.7874 -0.4064)
			(end 0.7874 -0.4064)
			(stroke
				(width 0.1524)
				(type default)
			)
			(layer "F.SilkS")
		)
		(fp_line
			(start 0.67945 0.3048)
			(end 0.120396 0.3048)
			(stroke
				(width 0.1)
				(type default)
			)
			(layer "F.Fab")
		)
		(fp_line
			(start 0.67945 -0.3048)
			(end 0.67945 0.3048)
			(stroke
				(width 0.1)
				(type default)
			)
			(layer "F.Fab")
		)
		(fp_line
			(start 0.12065 -0.2794)
			(end 0.12065 -0.3048)
			(stroke
				(width 0.1)
				(type default)
			)
			(layer "F.Fab")
		)
		(fp_line
			(start 0.12065 -0.3048)
			(end 0.67945 -0.3048)
			(stroke
				(width 0.1)
				(type default)
			)
			(layer "F.Fab")
		)
		(fp_line
			(start 0.120396 0.3048)
			(end 0.120396 0.2794)
			(stroke
				(width 0.1)
				(type default)
			)
			(layer "F.Fab")
		)
		(fp_line
			(start 0.120396 0.2794)
			(end -0.12065 0.2794)
			(stroke
				(width 0.1)
				(type default)
			)
			(layer "F.Fab")
		)
		(fp_line
			(start -0.12065 0.3048)
			(end -0.67945 0.3048)
			(stroke
				(width 0.1)
				(type default)
			)
			(layer "F.Fab")
		)
		(fp_line
			(start -0.12065 0.2794)
			(end -0.12065 0.3048)
			(stroke
				(width 0.1)
				(type default)
			)
			(layer "F.Fab")
		)
		(fp_line
			(start -0.12065 -0.2794)
			(end 0.12065 -0.2794)
			(stroke
				(width 0.1)
				(type default)
			)
			(layer "F.Fab")
		)
		(fp_line
			(start -0.12065 -0.305054)
			(end -0.12065 -0.2794)
			(stroke
				(width 0.1)
				(type default)
			)
			(layer "F.Fab")
		)
		(fp_line
			(start -0.67945 0.3048)
			(end -0.67945 -0.305054)
			(stroke
				(width 0.1)
				(type default)
			)
			(layer "F.Fab")
		)
		(fp_line
			(start -0.67945 -0.305054)
			(end -0.12065 -0.305054)
			(stroke
				(width 0.1)
				(type default)
			)
			(layer "F.Fab")
		)
		(pad "1" smd circle
			(at -0.40005 0 180)
			(size 0 0)
			(layers "F.Cu" "F.Mask" "F.Paste")
			(net "PVDD18_S5_P0")
		)
		(pad "2" smd circle
			(at 0.40005 0 180)
			(size 0 0)
			(layers "F.Cu" "F.Mask" "F.Paste")
			(net "SPI_CPU0_D2")
		)
	)
	(footprint ""
		(layer "F.Cu")
		(at 298.159932 -52.63007 90)
		(property "Reference" "J6"
			(at -1.948434 2.597658 0)
			(unlocked yes)
			(layer "F.SilkS")
			(effects
				(font
					(size 0.7874 0.5842)
					(thickness 0.1524)
				)
			)
		)
		(property "Value" ""
			(at 0 0 90)
			(layer "F.Fab")
			(effects
				(font
					(size 1.27 1.27)
				)
			)
		)
		(duplicate_pad_numbers_are_jumpers no)
		(fp_line
			(start 3.759962 -1.335024)
			(end 3.759962 6.415024)
			(stroke
				(width 0.1524)
				(type default)
			)
			(layer "F.SilkS")
		)
		(fp_line
			(start -1.219962 -1.335024)
			(end 3.759962 -1.335024)
			(stroke
				(width 0.1524)
				(type default)
			)
			(layer "F.SilkS")
		)
		(fp_line
			(start 3.759962 6.415024)
			(end -1.219962 6.415024)
			(stroke
				(width 0.1524)
				(type default)
			)
			(layer "F.SilkS")
		)
		(fp_line
			(start -1.219962 6.415024)
			(end -1.219962 -1.335024)
			(stroke
				(width 0.1524)
				(type default)
			)
			(layer "F.SilkS")
		)
		(fp_poly
			(pts
				(xy -1.423162 0) (xy -2.439162 0.508) (xy -2.439162 -0.508)
			)
			(stroke
				(width 0)
				(type default)
			)
			(fill yes)
			(layer "F.SilkS")
		)
		(fp_line
			(start 3.759962 -1.335024)
			(end 3.759962 6.415024)
			(stroke
				(width 0.1)
				(type default)
			)
			(layer "F.Fab")
		)
		(fp_line
			(start -1.219962 -1.335024)
			(end 3.759962 -1.335024)
			(stroke
				(width 0.1)
				(type default)
			)
			(layer "F.Fab")
		)
		(fp_line
			(start 3.759962 6.415024)
			(end -1.219962 6.415024)
			(stroke
				(width 0.1)
				(type default)
			)
			(layer "F.Fab")
		)
		(fp_line
			(start -1.219962 6.415024)
			(end -1.219962 -1.335024)
			(stroke
				(width 0.1)
				(type default)
			)
			(layer "F.Fab")
		)
		(fp_poly
			(pts
				(xy -2.439162 -0.508) (xy -2.439162 0.508) (xy -1.423162 0)
			)
			(stroke
				(width 0)
				(type default)
			)
			(fill yes)
			(layer "F.Fab")
		)
		(pad "1" thru_hole rect
			(at 0 0 90)
			(size 1.6256 1.6256)
			(drill 1.1176)
			(layers "*.Cu" "*.Mask")
			(remove_unused_layers no)
			(net "CPU0_PWR_BTN_N")
			(clearance 0)
			(padstack
				(mode front_inner_back)
				(layer "Inner"
					(shape circle)
					(size 1.6256 1.6256)
					(clearance 0)
				)
				(layer "B.Cu"
					(shape rect)
					(size 1.6256 1.6256)
					(clearance 0)
				)
			)
		)
		(pad "2" thru_hole circle
			(at 2.54 0 90)
			(size 1.6256 1.6256)
			(drill 1.1176)
			(layers "*.Cu" "*.Mask")
			(remove_unused_layers no)
			(net "GND")
			(clearance 0)
		)
		(pad "3" thru_hole circle
			(at 0 2.54 90)
			(size 1.6256 1.6256)
			(drill 1.1176)
			(layers "*.Cu" "*.Mask")
			(remove_unused_layers no)
			(net "RST_CPU0_SYS_N")
			(clearance 0)
		)
		(pad "4" thru_hole circle
			(at 2.54 2.54 90)
			(size 1.6256 1.6256)
			(drill 1.1176)
			(layers "*.Cu" "*.Mask")
			(remove_unused_layers no)
			(net "GND")
			(clearance 0)
		)
		(pad "5" thru_hole circle
			(at 0 5.08 90)
			(size 1.6256 1.6256)
			(drill 1.1176)
			(layers "*.Cu" "*.Mask")
			(remove_unused_layers no)
			(net "Net_10748")
			(clearance 0)
		)
		(pad "6" thru_hole circle
			(at 2.54 5.08 90)
			(size 1.6256 1.6256)
			(drill 1.1176)
			(layers "*.Cu" "*.Mask")
			(remove_unused_layers no)
			(net "GND")
			(clearance 0)
		)
	)
	(footprint ""
		(layer "F.Cu")
		(at 8.75919 -101.854 180)
		(property "Reference" "R3653"
			(at 0 0 180)
			(layer "F.SilkS")
			(hide yes)
			(effects
				(font
					(size 1.27 1.27)
				)
			)
		)
		(property "Value" ""
			(at 0 0 180)
			(layer "F.Fab")
			(effects
				(font
					(size 1.27 1.27)
				)
			)
		)
		(duplicate_pad_numbers_are_jumpers no)
		(fp_line
			(start 0.7874 0.4064)
			(end -0.7874 0.4064)
			(stroke
				(width 0.1524)
				(type default)
			)
			(layer "F.SilkS")
		)
		(fp_line
			(start 0.7874 -0.4064)
			(end 0.7874 0.4064)
			(stroke
				(width 0.1524)
				(type default)
			)
			(layer "F.SilkS")
		)
		(fp_line
			(start -0.7874 0.4064)
			(end -0.7874 -0.4064)
			(stroke
				(width 0.1524)
				(type default)
			)
			(layer "F.SilkS")
		)
		(fp_line
			(start -0.7874 -0.4064)
			(end 0.7874 -0.4064)
			(stroke
				(width 0.1524)
				(type default)
			)
			(layer "F.SilkS")
		)
		(fp_line
			(start 0.67945 0.3048)
			(end 0.120396 0.3048)
			(stroke
				(width 0.1)
				(type default)
			)
			(layer "F.Fab")
		)
		(fp_line
			(start 0.67945 -0.3048)
			(end 0.67945 0.3048)
			(stroke
				(width 0.1)
				(type default)
			)
			(layer "F.Fab")
		)
		(fp_line
			(start 0.12065 -0.2794)
			(end 0.12065 -0.3048)
			(stroke
				(width 0.1)
				(type default)
			)
			(layer "F.Fab")
		)
		(fp_line
			(start 0.12065 -0.3048)
			(end 0.67945 -0.3048)
			(stroke
				(width 0.1)
				(type default)
			)
			(layer "F.Fab")
		)
		(fp_line
			(start 0.120396 0.3048)
			(end 0.120396 0.2794)
			(stroke
				(width 0.1)
				(type default)
			)
			(layer "F.Fab")
		)
		(fp_line
			(start 0.120396 0.2794)
			(end -0.12065 0.2794)
			(stroke
				(width 0.1)
				(type default)
			)
			(layer "F.Fab")
		)
		(fp_line
			(start -0.12065 0.3048)
			(end -0.67945 0.3048)
			(stroke
				(width 0.1)
				(type default)
			)
			(layer "F.Fab")
		)
		(fp_line
			(start -0.12065 0.2794)
			(end -0.12065 0.3048)
			(stroke
				(width 0.1)
				(type default)
			)
			(layer "F.Fab")
		)
		(fp_line
			(start -0.12065 -0.2794)
			(end 0.12065 -0.2794)
			(stroke
				(width 0.1)
				(type default)
			)
			(layer "F.Fab")
		)
		(fp_line
			(start -0.12065 -0.305054)
			(end -0.12065 -0.2794)
			(stroke
				(width 0.1)
				(type default)
			)
			(layer "F.Fab")
		)
		(fp_line
			(start -0.67945 0.3048)
			(end -0.67945 -0.305054)
			(stroke
				(width 0.1)
				(type default)
			)
			(layer "F.Fab")
		)
		(fp_line
			(start -0.67945 -0.305054)
			(end -0.12065 -0.305054)
			(stroke
				(width 0.1)
				(type default)
			)
			(layer "F.Fab")
		)
		(pad "1" smd circle
			(at -0.40005 0 180)
			(size 0 0)
			(layers "F.Cu" "F.Mask" "F.Paste")
			(net "USB_HUB_RREF")
		)
		(pad "2" smd circle
			(at 0.40005 0 180)
			(size 0 0)
			(layers "F.Cu" "F.Mask" "F.Paste")
			(net "GND")
		)
	)
	(footprint ""
		(layer "F.Cu")
		(at 100.941124 -34.28492)
		(property "Reference" "R3193"
			(at 0 0 0)
			(layer "F.SilkS")
			(hide yes)
			(effects
				(font
					(size 1.27 1.27)
				)
			)
		)
		(property "Value" ""
			(at 0 0 0)
			(layer "F.Fab")
			(effects
				(font
					(size 1.27 1.27)
				)
			)
		)
		(duplicate_pad_numbers_are_jumpers no)
		(fp_line
			(start -0.7874 -0.4064)
			(end 0.7874 -0.4064)
			(stroke
				(width 0.1524)
				(type default)
			)
			(layer "F.SilkS")
		)
		(fp_line
			(start -0.7874 0.4064)
			(end -0.7874 -0.4064)
			(stroke
				(width 0.1524)
				(type default)
			)
			(layer "F.SilkS")
		)
		(fp_line
			(start 0.7874 -0.4064)
			(end 0.7874 0.4064)
			(stroke
				(width 0.1524)
				(type default)
			)
			(layer "F.SilkS")
		)
		(fp_line
			(start 0.7874 0.4064)
			(end -0.7874 0.4064)
			(stroke
				(width 0.1524)
				(type default)
			)
			(layer "F.SilkS")
		)
		(fp_line
			(start -0.67945 -0.305054)
			(end -0.12065 -0.305054)
			(stroke
				(width 0.1)
				(type default)
			)
			(layer "F.Fab")
		)
		(fp_line
			(start -0.67945 0.3048)
			(end -0.67945 -0.305054)
			(stroke
				(width 0.1)
				(type default)
			)
			(layer "F.Fab")
		)
		(fp_line
			(start -0.12065 -0.305054)
			(end -0.12065 -0.2794)
			(stroke
				(width 0.1)
				(type default)
			)
			(layer "F.Fab")
		)
		(fp_line
			(start -0.12065 -0.2794)
			(end 0.12065 -0.2794)
			(stroke
				(width 0.1)
				(type default)
			)
			(layer "F.Fab")
		)
		(fp_line
			(start -0.12065 0.2794)
			(end -0.12065 0.3048)
			(stroke
				(width 0.1)
				(type default)
			)
			(layer "F.Fab")
		)
		(fp_line
			(start -0.12065 0.3048)
			(end -0.67945 0.3048)
			(stroke
				(width 0.1)
				(type default)
			)
			(layer "F.Fab")
		)
		(fp_line
			(start 0.120396 0.2794)
			(end -0.12065 0.2794)
			(stroke
				(width 0.1)
				(type default)
			)
			(layer "F.Fab")
		)
		(fp_line
			(start 0.120396 0.3048)
			(end 0.120396 0.2794)
			(stroke
				(width 0.1)
				(type default)
			)
			(layer "F.Fab")
		)
		(fp_line
			(start 0.12065 -0.3048)
			(end 0.67945 -0.3048)
			(stroke
				(width 0.1)
				(type default)
			)
			(layer "F.Fab")
		)
		(fp_line
			(start 0.12065 -0.2794)
			(end 0.12065 -0.3048)
			(stroke
				(width 0.1)
				(type default)
			)
			(layer "F.Fab")
		)
		(fp_line
			(start 0.67945 -0.3048)
			(end 0.67945 0.3048)
			(stroke
				(width 0.1)
				(type default)
			)
			(layer "F.Fab")
		)
		(fp_line
			(start 0.67945 0.3048)
			(end 0.120396 0.3048)
			(stroke
				(width 0.1)
				(type default)
			)
			(layer "F.Fab")
		)
		(pad "1" smd circle
			(at -0.40005 0)
			(size 0 0)
			(layers "F.Cu" "F.Mask" "F.Paste")
			(net "IRQ_LVC3_V3_2_WAKE_BUF_N")
		)
		(pad "2" smd circle
			(at 0.40005 0)
			(size 0 0)
			(layers "F.Cu" "F.Mask" "F.Paste")
			(net "IRQ_OCP_V3_2_WAKE_BUF_N")
		)
	)
	(footprint ""
		(layer "F.Cu")
		(at 235.718096 -144.958562 180)
		(property "Reference" "R1647"
			(at 0 0 180)
			(layer "F.SilkS")
			(hide yes)
			(effects
				(font
					(size 1.27 1.27)
				)
			)
		)
		(property "Value" ""
			(at 0 0 180)
			(layer "F.Fab")
			(effects
				(font
					(size 1.27 1.27)
				)
			)
		)
		(duplicate_pad_numbers_are_jumpers no)
		(fp_line
			(start 0.7874 0.4064)
			(end -0.7874 0.4064)
			(stroke
				(width 0.1524)
				(type default)
			)
			(layer "F.SilkS")
		)
		(fp_line
			(start 0.7874 -0.4064)
			(end 0.7874 0.4064)
			(stroke
				(width 0.1524)
				(type default)
			)
			(layer "F.SilkS")
		)
		(fp_line
			(start -0.7874 0.4064)
			(end -0.7874 -0.4064)
			(stroke
				(width 0.1524)
				(type default)
			)
			(layer "F.SilkS")
		)
		(fp_line
			(start -0.7874 -0.4064)
			(end 0.7874 -0.4064)
			(stroke
				(width 0.1524)
				(type default)
			)
			(layer "F.SilkS")
		)
		(fp_line
			(start 0.67945 0.3048)
			(end 0.120396 0.3048)
			(stroke
				(width 0.1)
				(type default)
			)
			(layer "F.Fab")
		)
		(fp_line
			(start 0.67945 -0.3048)
			(end 0.67945 0.3048)
			(stroke
				(width 0.1)
				(type default)
			)
			(layer "F.Fab")
		)
		(fp_line
			(start 0.12065 -0.2794)
			(end 0.12065 -0.3048)
			(stroke
				(width 0.1)
				(type default)
			)
			(layer "F.Fab")
		)
		(fp_line
			(start 0.12065 -0.3048)
			(end 0.67945 -0.3048)
			(stroke
				(width 0.1)
				(type default)
			)
			(layer "F.Fab")
		)
		(fp_line
			(start 0.120396 0.3048)
			(end 0.120396 0.2794)
			(stroke
				(width 0.1)
				(type default)
			)
			(layer "F.Fab")
		)
		(fp_line
			(start 0.120396 0.2794)
			(end -0.12065 0.2794)
			(stroke
				(width 0.1)
				(type default)
			)
			(layer "F.Fab")
		)
		(fp_line
			(start -0.12065 0.3048)
			(end -0.67945 0.3048)
			(stroke
				(width 0.1)
				(type default)
			)
			(layer "F.Fab")
		)
		(fp_line
			(start -0.12065 0.2794)
			(end -0.12065 0.3048)
			(stroke
				(width 0.1)
				(type default)
			)
			(layer "F.Fab")
		)
		(fp_line
			(start -0.12065 -0.2794)
			(end 0.12065 -0.2794)
			(stroke
				(width 0.1)
				(type default)
			)
			(layer "F.Fab")
		)
		(fp_line
			(start -0.12065 -0.305054)
			(end -0.12065 -0.2794)
			(stroke
				(width 0.1)
				(type default)
			)
			(layer "F.Fab")
		)
		(fp_line
			(start -0.67945 0.3048)
			(end -0.67945 -0.305054)
			(stroke
				(width 0.1)
				(type default)
			)
			(layer "F.Fab")
		)
		(fp_line
			(start -0.67945 -0.305054)
			(end -0.12065 -0.305054)
			(stroke
				(width 0.1)
				(type default)
			)
			(layer "F.Fab")
		)
		(pad "1" smd circle
			(at -0.40005 0 180)
			(size 0 0)
			(layers "F.Cu" "F.Mask" "F.Paste")
			(net "PVDD18_S5_P0")
		)
		(pad "2" smd circle
			(at 0.40005 0 180)
			(size 0 0)
			(layers "F.Cu" "F.Mask" "F.Paste")
			(net "FM_PLD_CPU0_PRSNT_HDT_N")
		)
	)
	(footprint ""
		(layer "F.Cu")
		(at 140.289026 -408.517344 -90)
		(property "Reference" "C6709"
			(at 0 0 270)
			(layer "F.SilkS")
			(hide yes)
			(effects
				(font
					(size 1.27 1.27)
				)
			)
		)
		(property "Value" ""
			(at 0 0 270)
			(layer "F.Fab")
			(effects
				(font
					(size 1.27 1.27)
				)
			)
		)
		(duplicate_pad_numbers_are_jumpers no)
		(fp_line
			(start -0.299974 0.150114)
			(end -0.299974 -0.150114)
			(stroke
				(width 0.1)
				(type default)
			)
			(layer "F.Fab")
		)
		(fp_line
			(start 0.299974 0.150114)
			(end -0.299974 0.150114)
			(stroke
				(width 0.1)
				(type default)
			)
			(layer "F.Fab")
		)
		(fp_line
			(start -0.299974 -0.150114)
			(end 0.299974 -0.150114)
			(stroke
				(width 0.1)
				(type default)
			)
			(layer "F.Fab")
		)
		(fp_line
			(start 0.299974 -0.150114)
			(end 0.299974 0.150114)
			(stroke
				(width 0.1)
				(type default)
			)
			(layer "F.Fab")
		)
		(pad "1" smd rect
			(at -0.2667 0 270)
			(size 0.3048 0.381)
			(layers "F.Cu" "F.Mask" "F.Paste")
			(net "P5E_CPU1_P2_TX_BUF_C_DP<8>")
		)
		(pad "2" smd rect
			(at 0.2667 0 270)
			(size 0.3048 0.381)
			(layers "F.Cu" "F.Mask" "F.Paste")
			(net "P5E_CPU1_P2_TX_BUF_DP<8>")
		)
	)
	(footprint ""
		(layer "F.Cu")
		(at 367.157 -411.226 -90)
		(property "Reference" "R6252"
			(at 0 0 270)
			(layer "F.SilkS")
			(hide yes)
			(effects
				(font
					(size 1.27 1.27)
				)
			)
		)
		(property "Value" ""
			(at 0 0 270)
			(layer "F.Fab")
			(effects
				(font
					(size 1.27 1.27)
				)
			)
		)
		(duplicate_pad_numbers_are_jumpers no)
		(fp_line
			(start -0.7874 0.4064)
			(end -0.7874 -0.4064)
			(stroke
				(width 0.1524)
				(type default)
			)
			(layer "F.SilkS")
		)
		(fp_line
			(start 0.7874 0.4064)
			(end -0.7874 0.4064)
			(stroke
				(width 0.1524)
				(type default)
			)
			(layer "F.SilkS")
		)
		(fp_line
			(start -0.7874 -0.4064)
			(end 0.7874 -0.4064)
			(stroke
				(width 0.1524)
				(type default)
			)
			(layer "F.SilkS")
		)
		(fp_line
			(start 0.7874 -0.4064)
			(end 0.7874 0.4064)
			(stroke
				(width 0.1524)
				(type default)
			)
			(layer "F.SilkS")
		)
		(fp_line
			(start -0.67945 0.3048)
			(end -0.67945 -0.305054)
			(stroke
				(width 0.1)
				(type default)
			)
			(layer "F.Fab")
		)
		(fp_line
			(start -0.12065 0.3048)
			(end -0.67945 0.3048)
			(stroke
				(width 0.1)
				(type default)
			)
			(layer "F.Fab")
		)
		(fp_line
			(start 0.120396 0.3048)
			(end 0.120396 0.2794)
			(stroke
				(width 0.1)
				(type default)
			)
			(layer "F.Fab")
		)
		(fp_line
			(start 0.67945 0.3048)
			(end 0.120396 0.3048)
			(stroke
				(width 0.1)
				(type default)
			)
			(layer "F.Fab")
		)
		(fp_line
			(start -0.12065 0.2794)
			(end -0.12065 0.3048)
			(stroke
				(width 0.1)
				(type default)
			)
			(layer "F.Fab")
		)
		(fp_line
			(start 0.120396 0.2794)
			(end -0.12065 0.2794)
			(stroke
				(width 0.1)
				(type default)
			)
			(layer "F.Fab")
		)
		(fp_line
			(start -0.12065 -0.2794)
			(end 0.12065 -0.2794)
			(stroke
				(width 0.1)
				(type default)
			)
			(layer "F.Fab")
		)
		(fp_line
			(start 0.12065 -0.2794)
			(end 0.12065 -0.3048)
			(stroke
				(width 0.1)
				(type default)
			)
			(layer "F.Fab")
		)
		(fp_line
			(start 0.12065 -0.3048)
			(end 0.67945 -0.3048)
			(stroke
				(width 0.1)
				(type default)
			)
			(layer "F.Fab")
		)
		(fp_line
			(start 0.67945 -0.3048)
			(end 0.67945 0.3048)
			(stroke
				(width 0.1)
				(type default)
			)
			(layer "F.Fab")
		)
		(fp_line
			(start -0.67945 -0.305054)
			(end -0.12065 -0.305054)
			(stroke
				(width 0.1)
				(type default)
			)
			(layer "F.Fab")
		)
		(fp_line
			(start -0.12065 -0.305054)
			(end -0.12065 -0.2794)
			(stroke
				(width 0.1)
				(type default)
			)
			(layer "F.Fab")
		)
		(pad "1" smd circle
			(at -0.40005 0 270)
			(size 0 0)
			(layers "F.Cu" "F.Mask" "F.Paste")
			(net "SMB_LM75_0_3V3AUX_SCL")
		)
		(pad "2" smd circle
			(at 0.40005 0 270)
			(size 0 0)
			(layers "F.Cu" "F.Mask" "F.Paste")
			(net "SMB_HSC_TYPE_ADC_SCL")
		)
	)
	(footprint ""
		(layer "F.Cu")
		(at 118.598696 -370.57203 -90)
		(property "Reference" "C1535"
			(at 0 0 270)
			(layer "F.SilkS")
			(hide yes)
			(effects
				(font
					(size 1.27 1.27)
				)
			)
		)
		(property "Value" ""
			(at 0 0 270)
			(layer "F.Fab")
			(effects
				(font
					(size 1.27 1.27)
				)
			)
		)
		(duplicate_pad_numbers_are_jumpers no)
		(fp_line
			(start -0.299974 0.150114)
			(end -0.299974 -0.150114)
			(stroke
				(width 0.1)
				(type default)
			)
			(layer "F.Fab")
		)
		(fp_line
			(start 0.299974 0.150114)
			(end -0.299974 0.150114)
			(stroke
				(width 0.1)
				(type default)
			)
			(layer "F.Fab")
		)
		(fp_line
			(start -0.299974 -0.150114)
			(end 0.299974 -0.150114)
			(stroke
				(width 0.1)
				(type default)
			)
			(layer "F.Fab")
		)
		(fp_line
			(start 0.299974 -0.150114)
			(end 0.299974 0.150114)
			(stroke
				(width 0.1)
				(type default)
			)
			(layer "F.Fab")
		)
		(pad "1" smd rect
			(at -0.2667 0 270)
			(size 0.3048 0.381)
			(layers "F.Cu" "F.Mask" "F.Paste")
			(net "P5E_CPU1_P3_TX_C_DP<6>")
		)
		(pad "2" smd rect
			(at 0.2667 0 270)
			(size 0.3048 0.381)
			(layers "F.Cu" "F.Mask" "F.Paste")
			(net "P5E_CPU1_P3_TX_DP<6>")
		)
	)
	(footprint ""
		(layer "F.Cu")
		(at 252.961648 -55.177182 180)
		(property "Reference" "PR3954"
			(at 0 0 180)
			(layer "F.SilkS")
			(hide yes)
			(effects
				(font
					(size 1.27 1.27)
				)
			)
		)
		(property "Value" ""
			(at 0 0 180)
			(layer "F.Fab")
			(effects
				(font
					(size 1.27 1.27)
				)
			)
		)
		(duplicate_pad_numbers_are_jumpers no)
		(fp_line
			(start 0.7874 0.4064)
			(end -0.7874 0.4064)
			(stroke
				(width 0.1524)
				(type default)
			)
			(layer "F.SilkS")
		)
		(fp_line
			(start 0.7874 -0.4064)
			(end 0.7874 0.4064)
			(stroke
				(width 0.1524)
				(type default)
			)
			(layer "F.SilkS")
		)
		(fp_line
			(start -0.7874 0.4064)
			(end -0.7874 -0.4064)
			(stroke
				(width 0.1524)
				(type default)
			)
			(layer "F.SilkS")
		)
		(fp_line
			(start -0.7874 -0.4064)
			(end 0.7874 -0.4064)
			(stroke
				(width 0.1524)
				(type default)
			)
			(layer "F.SilkS")
		)
		(fp_line
			(start 0.67945 0.3048)
			(end 0.120396 0.3048)
			(stroke
				(width 0.1)
				(type default)
			)
			(layer "F.Fab")
		)
		(fp_line
			(start 0.67945 -0.3048)
			(end 0.67945 0.3048)
			(stroke
				(width 0.1)
				(type default)
			)
			(layer "F.Fab")
		)
		(fp_line
			(start 0.12065 -0.2794)
			(end 0.12065 -0.3048)
			(stroke
				(width 0.1)
				(type default)
			)
			(layer "F.Fab")
		)
		(fp_line
			(start 0.12065 -0.3048)
			(end 0.67945 -0.3048)
			(stroke
				(width 0.1)
				(type default)
			)
			(layer "F.Fab")
		)
		(fp_line
			(start 0.120396 0.3048)
			(end 0.120396 0.2794)
			(stroke
				(width 0.1)
				(type default)
			)
			(layer "F.Fab")
		)
		(fp_line
			(start 0.120396 0.2794)
			(end -0.12065 0.2794)
			(stroke
				(width 0.1)
				(type default)
			)
			(layer "F.Fab")
		)
		(fp_line
			(start -0.12065 0.3048)
			(end -0.67945 0.3048)
			(stroke
				(width 0.1)
				(type default)
			)
			(layer "F.Fab")
		)
		(fp_line
			(start -0.12065 0.2794)
			(end -0.12065 0.3048)
			(stroke
				(width 0.1)
				(type default)
			)
			(layer "F.Fab")
		)
		(fp_line
			(start -0.12065 -0.2794)
			(end 0.12065 -0.2794)
			(stroke
				(width 0.1)
				(type default)
			)
			(layer "F.Fab")
		)
		(fp_line
			(start -0.12065 -0.305054)
			(end -0.12065 -0.2794)
			(stroke
				(width 0.1)
				(type default)
			)
			(layer "F.Fab")
		)
		(fp_line
			(start -0.67945 0.3048)
			(end -0.67945 -0.305054)
			(stroke
				(width 0.1)
				(type default)
			)
			(layer "F.Fab")
		)
		(fp_line
			(start -0.67945 -0.305054)
			(end -0.12065 -0.305054)
			(stroke
				(width 0.1)
				(type default)
			)
			(layer "F.Fab")
		)
		(pad "1" smd circle
			(at -0.40005 0 180)
			(size 0 0)
			(layers "F.Cu" "F.Mask" "F.Paste")
			(net "P12V_E1S_OV_FB_0")
		)
		(pad "2" smd circle
			(at 0.40005 0 180)
			(size 0 0)
			(layers "F.Cu" "F.Mask" "F.Paste")
			(net "GND")
		)
	)
	(footprint ""
		(layer "F.Cu")
		(at 304.523394 -408.801316 -90)
		(property "Reference" "C559"
			(at 0 0 270)
			(layer "F.SilkS")
			(hide yes)
			(effects
				(font
					(size 1.27 1.27)
				)
			)
		)
		(property "Value" ""
			(at 0 0 270)
			(layer "F.Fab")
			(effects
				(font
					(size 1.27 1.27)
				)
			)
		)
		(duplicate_pad_numbers_are_jumpers no)
		(fp_line
			(start -1.524 0.762)
			(end -1.524 -0.762)
			(stroke
				(width 0.1524)
				(type default)
			)
			(layer "F.SilkS")
		)
		(fp_line
			(start 1.524 0.762)
			(end -1.524 0.762)
			(stroke
				(width 0.1524)
				(type default)
			)
			(layer "F.SilkS")
		)
		(fp_line
			(start -1.524 -0.762)
			(end 1.524 -0.762)
			(stroke
				(width 0.1524)
				(type default)
			)
			(layer "F.SilkS")
		)
		(fp_line
			(start 1.524 -0.762)
			(end 1.524 0.762)
			(stroke
				(width 0.1524)
				(type default)
			)
			(layer "F.SilkS")
		)
		(fp_line
			(start -1.1049 0.724916)
			(end 1.1049 0.724916)
			(stroke
				(width 0.1)
				(type default)
			)
			(layer "F.Fab")
		)
		(fp_line
			(start 1.1049 0.724916)
			(end 1.1049 -0.724916)
			(stroke
				(width 0.1)
				(type default)
			)
			(layer "F.Fab")
		)
		(fp_line
			(start -1.1049 -0.724916)
			(end -1.1049 0.724916)
			(stroke
				(width 0.1)
				(type default)
			)
			(layer "F.Fab")
		)
		(fp_line
			(start 1.1049 -0.724916)
			(end -1.1049 -0.724916)
			(stroke
				(width 0.1)
				(type default)
			)
			(layer "F.Fab")
		)
		(pad "1" smd rect
			(at -0.889 0 90)
			(size 1.016 1.27)
			(layers "F.Cu" "F.Mask" "F.Paste")
			(net "P0V9_CPU0_RT_2D")
		)
		(pad "2" smd rect
			(at 0.889 0 90)
			(size 1.016 1.27)
			(layers "F.Cu" "F.Mask" "F.Paste")
			(net "GND")
		)
	)
	(footprint ""
		(layer "F.Cu")
		(at 331.494892 -384.32486 180)
		(property "Reference" "C963"
			(at 0 0 180)
			(layer "F.SilkS")
			(hide yes)
			(effects
				(font
					(size 1.27 1.27)
				)
			)
		)
		(property "Value" ""
			(at 0 0 180)
			(layer "F.Fab")
			(effects
				(font
					(size 1.27 1.27)
				)
			)
		)
		(duplicate_pad_numbers_are_jumpers no)
		(fp_line
			(start 0.299974 0.150114)
			(end -0.299974 0.150114)
			(stroke
				(width 0.1)
				(type default)
			)
			(layer "F.Fab")
		)
		(fp_line
			(start 0.299974 -0.150114)
			(end 0.299974 0.150114)
			(stroke
				(width 0.1)
				(type default)
			)
			(layer "F.Fab")
		)
		(fp_line
			(start -0.299974 0.150114)
			(end -0.299974 -0.150114)
			(stroke
				(width 0.1)
				(type default)
			)
			(layer "F.Fab")
		)
		(fp_line
			(start -0.299974 -0.150114)
			(end 0.299974 -0.150114)
			(stroke
				(width 0.1)
				(type default)
			)
			(layer "F.Fab")
		)
		(pad "1" smd rect
			(at -0.2667 0 180)
			(size 0.3048 0.381)
			(layers "F.Cu" "F.Mask" "F.Paste")
			(net "P5E_CPU0_P1_TX_C_DP<1>")
		)
		(pad "2" smd rect
			(at 0.2667 0 180)
			(size 0.3048 0.381)
			(layers "F.Cu" "F.Mask" "F.Paste")
			(net "P5E_CPU0_P1_TX_DP<1>")
		)
	)
	(footprint ""
		(layer "F.Cu")
		(at 401.128484 -403.818852 -90)
		(property "Reference" "R1080"
			(at 0 0 270)
			(layer "F.SilkS")
			(hide yes)
			(effects
				(font
					(size 1.27 1.27)
				)
			)
		)
		(property "Value" ""
			(at 0 0 270)
			(layer "F.Fab")
			(effects
				(font
					(size 1.27 1.27)
				)
			)
		)
		(duplicate_pad_numbers_are_jumpers no)
		(fp_line
			(start -0.32512 0.175006)
			(end -0.32512 -0.175006)
			(stroke
				(width 0.1)
				(type default)
			)
			(layer "F.Fab")
		)
		(fp_line
			(start 0.32512 0.175006)
			(end -0.32512 0.175006)
			(stroke
				(width 0.1)
				(type default)
			)
			(layer "F.Fab")
		)
		(fp_line
			(start -0.32512 -0.175006)
			(end 0.32512 -0.175006)
			(stroke
				(width 0.1)
				(type default)
			)
			(layer "F.Fab")
		)
		(fp_line
			(start 0.32512 -0.175006)
			(end 0.32512 0.175006)
			(stroke
				(width 0.1)
				(type default)
			)
			(layer "F.Fab")
		)
		(pad "1" smd rect
			(at -0.2667 0 270)
			(size 0.3048 0.381)
			(layers "F.Cu" "F.Mask" "F.Paste")
			(net "P1V8_CPU0_RT_1D")
		)
		(pad "2" smd rect
			(at 0.2667 0 90)
			(size 0.3048 0.381)
			(layers "F.Cu" "F.Mask" "F.Paste")
			(net "MODE_RT_CPU0_P2")
		)
	)
	(footprint ""
		(layer "F.Cu")
		(at 453.210676 -402.801328)
		(property "Reference" "PR6561"
			(at 0 0 0)
			(layer "F.SilkS")
			(hide yes)
			(effects
				(font
					(size 1.27 1.27)
				)
			)
		)
		(property "Value" ""
			(at 0 0 0)
			(layer "F.Fab")
			(effects
				(font
					(size 1.27 1.27)
				)
			)
		)
		(duplicate_pad_numbers_are_jumpers no)
		(fp_line
			(start -0.7874 -0.4064)
			(end 0.7874 -0.4064)
			(stroke
				(width 0.1524)
				(type default)
			)
			(layer "F.SilkS")
		)
		(fp_line
			(start -0.7874 0.4064)
			(end -0.7874 -0.4064)
			(stroke
				(width 0.1524)
				(type default)
			)
			(layer "F.SilkS")
		)
		(fp_line
			(start 0.7874 -0.4064)
			(end 0.7874 0.4064)
			(stroke
				(width 0.1524)
				(type default)
			)
			(layer "F.SilkS")
		)
		(fp_line
			(start 0.7874 0.4064)
			(end -0.7874 0.4064)
			(stroke
				(width 0.1524)
				(type default)
			)
			(layer "F.SilkS")
		)
		(fp_line
			(start -0.67945 -0.305054)
			(end -0.12065 -0.305054)
			(stroke
				(width 0.1)
				(type default)
			)
			(layer "F.Fab")
		)
		(fp_line
			(start -0.67945 0.3048)
			(end -0.67945 -0.305054)
			(stroke
				(width 0.1)
				(type default)
			)
			(layer "F.Fab")
		)
		(fp_line
			(start -0.12065 -0.305054)
			(end -0.12065 -0.2794)
			(stroke
				(width 0.1)
				(type default)
			)
			(layer "F.Fab")
		)
		(fp_line
			(start -0.12065 -0.2794)
			(end 0.12065 -0.2794)
			(stroke
				(width 0.1)
				(type default)
			)
			(layer "F.Fab")
		)
		(fp_line
			(start -0.12065 0.2794)
			(end -0.12065 0.3048)
			(stroke
				(width 0.1)
				(type default)
			)
			(layer "F.Fab")
		)
		(fp_line
			(start -0.12065 0.3048)
			(end -0.67945 0.3048)
			(stroke
				(width 0.1)
				(type default)
			)
			(layer "F.Fab")
		)
		(fp_line
			(start 0.120396 0.2794)
			(end -0.12065 0.2794)
			(stroke
				(width 0.1)
				(type default)
			)
			(layer "F.Fab")
		)
		(fp_line
			(start 0.120396 0.3048)
			(end 0.120396 0.2794)
			(stroke
				(width 0.1)
				(type default)
			)
			(layer "F.Fab")
		)
		(fp_line
			(start 0.12065 -0.3048)
			(end 0.67945 -0.3048)
			(stroke
				(width 0.1)
				(type default)
			)
			(layer "F.Fab")
		)
		(fp_line
			(start 0.12065 -0.2794)
			(end 0.12065 -0.3048)
			(stroke
				(width 0.1)
				(type default)
			)
			(layer "F.Fab")
		)
		(fp_line
			(start 0.67945 -0.3048)
			(end 0.67945 0.3048)
			(stroke
				(width 0.1)
				(type default)
			)
			(layer "F.Fab")
		)
		(fp_line
			(start 0.67945 0.3048)
			(end 0.120396 0.3048)
			(stroke
				(width 0.1)
				(type default)
			)
			(layer "F.Fab")
		)
		(pad "1" smd circle
			(at -0.40005 0)
			(size 0 0)
			(layers "F.Cu" "F.Mask" "F.Paste")
			(net "P0V9_RETIMER_CPU0_LSET2")
		)
		(pad "2" smd circle
			(at 0.40005 0)
			(size 0 0)
			(layers "F.Cu" "F.Mask" "F.Paste")
			(net "GND")
		)
	)
	(footprint ""
		(layer "F.Cu")
		(at 239.893602 -290.341812 89.946)
		(property "Reference" "PR6507"
			(at 0 0 89.946)
			(layer "F.SilkS")
			(hide yes)
			(effects
				(font
					(size 1.27 1.27)
				)
			)
		)
		(property "Value" ""
			(at 0 0 89.946)
			(layer "F.Fab")
			(effects
				(font
					(size 1.27 1.27)
				)
			)
		)
		(duplicate_pad_numbers_are_jumpers no)
		(fp_line
			(start -0.787275 -0.40642)
			(end 0.787525 -0.40638)
			(stroke
				(width 0.1524)
				(type default)
			)
			(layer "F.SilkS")
		)
		(fp_line
			(start 0.787525 -0.40638)
			(end 0.787275 0.40642)
			(stroke
				(width 0.1524)
				(type default)
			)
			(layer "F.SilkS")
		)
		(fp_line
			(start -0.787525 0.40638)
			(end -0.787275 -0.40642)
			(stroke
				(width 0.1524)
				(type default)
			)
			(layer "F.SilkS")
		)
		(fp_line
			(start 0.787275 0.40642)
			(end -0.787525 0.40638)
			(stroke
				(width 0.1524)
				(type default)
			)
			(layer "F.SilkS")
		)
		(fp_line
			(start -0.679484 -0.305176)
			(end -0.120683 -0.30494)
			(stroke
				(width 0.1)
				(type default)
			)
			(layer "F.Fab")
		)
		(fp_line
			(start -0.120683 -0.30494)
			(end -0.120659 -0.279286)
			(stroke
				(width 0.1)
				(type default)
			)
			(layer "F.Fab")
		)
		(fp_line
			(start 0.120617 -0.304914)
			(end 0.679417 -0.304678)
			(stroke
				(width 0.1)
				(type default)
			)
			(layer "F.Fab")
		)
		(fp_line
			(start 0.679417 -0.304678)
			(end 0.679484 0.304922)
			(stroke
				(width 0.1)
				(type default)
			)
			(layer "F.Fab")
		)
		(fp_line
			(start 0.120641 -0.279514)
			(end 0.120617 -0.304914)
			(stroke
				(width 0.1)
				(type default)
			)
			(layer "F.Fab")
		)
		(fp_line
			(start -0.120659 -0.279286)
			(end 0.120641 -0.279514)
			(stroke
				(width 0.1)
				(type default)
			)
			(layer "F.Fab")
		)
		(fp_line
			(start 0.120405 0.279287)
			(end -0.120641 0.279514)
			(stroke
				(width 0.1)
				(type default)
			)
			(layer "F.Fab")
		)
		(fp_line
			(start -0.120641 0.279514)
			(end -0.120617 0.304914)
			(stroke
				(width 0.1)
				(type default)
			)
			(layer "F.Fab")
		)
		(fp_line
			(start -0.679417 0.304678)
			(end -0.679484 -0.305176)
			(stroke
				(width 0.1)
				(type default)
			)
			(layer "F.Fab")
		)
		(fp_line
			(start 0.120429 0.304687)
			(end 0.120405 0.279287)
			(stroke
				(width 0.1)
				(type default)
			)
			(layer "F.Fab")
		)
		(fp_line
			(start -0.120617 0.304914)
			(end -0.679417 0.304678)
			(stroke
				(width 0.1)
				(type default)
			)
			(layer "F.Fab")
		)
		(fp_line
			(start 0.679484 0.304922)
			(end 0.120429 0.304687)
			(stroke
				(width 0.1)
				(type default)
			)
			(layer "F.Fab")
		)
		(pad "1" smd circle
			(at -0.40005 0 89.946)
			(size 0 0)
			(layers "F.Cu" "F.Mask" "F.Paste")
			(net "P1V8_RETIMER_CPU0_FB")
		)
		(pad "2" smd circle
			(at 0.40005 0 89.946)
			(size 0 0)
			(layers "F.Cu" "F.Mask" "F.Paste")
			(net "GND")
		)
	)
	(footprint ""
		(layer "F.Cu")
		(at 253.526036 -385.27736 90)
		(property "Reference" "PPQ5"
			(at -7.496048 -2.441956 0)
			(unlocked yes)
			(layer "F.SilkS")
			(effects
				(font
					(size 0.7874 0.5842)
					(thickness 0.1524)
				)
				(justify left)
			)
		)
		(property "Value" ""
			(at 0 0 90)
			(layer "F.Fab")
			(effects
				(font
					(size 1.27 1.27)
				)
			)
		)
		(duplicate_pad_numbers_are_jumpers no)
		(fp_line
			(start 2.350008 -2.649982)
			(end 2.350008 -2.4892)
			(stroke
				(width 0.1524)
				(type default)
			)
			(layer "F.SilkS")
		)
		(fp_line
			(start -2.350008 -2.649982)
			(end 2.350008 -2.649982)
			(stroke
				(width 0.1524)
				(type default)
			)
			(layer "F.SilkS")
		)
		(fp_line
			(start -2.350008 -2.4384)
			(end -2.350008 -2.649982)
			(stroke
				(width 0.1524)
				(type default)
			)
			(layer "F.SilkS")
		)
		(fp_line
			(start 2.350008 2.4892)
			(end 2.350008 2.649982)
			(stroke
				(width 0.1524)
				(type default)
			)
			(layer "F.SilkS")
		)
		(fp_line
			(start 2.350008 2.649982)
			(end -2.350008 2.649982)
			(stroke
				(width 0.1524)
				(type default)
			)
			(layer "F.SilkS")
		)
		(fp_line
			(start -2.350008 2.649982)
			(end -2.350008 2.413)
			(stroke
				(width 0.1524)
				(type default)
			)
			(layer "F.SilkS")
		)
		(fp_poly
			(pts
				(xy -3.438144 -3.488182) (xy -2.638044 -3.491738) (xy -3.052318 -2.44856)
			)
			(stroke
				(width 0)
				(type default)
			)
			(fill yes)
			(layer "F.SilkS")
		)
		(fp_line
			(start 2.350008 -2.649982)
			(end 2.350008 2.649982)
			(stroke
				(width 0.1)
				(type default)
			)
			(layer "F.Fab")
		)
		(fp_line
			(start -2.350008 -2.649982)
			(end 2.350008 -2.649982)
			(stroke
				(width 0.1)
				(type default)
			)
			(layer "F.Fab")
		)
		(fp_line
			(start 2.350008 2.649982)
			(end -2.350008 2.649982)
			(stroke
				(width 0.1)
				(type default)
			)
			(layer "F.Fab")
		)
		(fp_line
			(start -2.350008 2.649982)
			(end -2.350008 -2.649982)
			(stroke
				(width 0.1)
				(type default)
			)
			(layer "F.Fab")
		)
		(fp_poly
			(pts
				(xy -3.717544 -1.905) (xy -4.758944 -2.3241) (xy -4.758944 -1.524)
			)
			(stroke
				(width 0)
				(type default)
			)
			(fill yes)
			(layer "F.Fab")
		)
		(pad "1" smd rect
			(at -2.999994 -1.905)
			(size 0.7112 1.1684)
			(layers "F.Cu" "F.Mask" "F.Paste")
			(net "P12V_AUX")
		)
		(pad "2" smd rect
			(at -2.999994 -0.635)
			(size 0.7112 1.1684)
			(layers "F.Cu" "F.Mask" "F.Paste")
			(net "P12V_AUX")
		)
		(pad "3" smd rect
			(at -2.999994 0.635)
			(size 0.7112 1.1684)
			(layers "F.Cu" "F.Mask" "F.Paste")
			(net "P12V_AUX")
		)
		(pad "4" smd rect
			(at -2.999994 1.905)
			(size 0.7112 1.1684)
			(layers "F.Cu" "F.Mask" "F.Paste")
			(net "P12V_HSC_GATE_G1")
		)
		(pad "5" smd circle
			(at 0.925068 0)
			(size 0 0)
			(layers "F.Cu" "F.Mask" "F.Paste")
			(net "P12V_MAIN_R")
		)
		(zone
			(layer "F.Cu")
			(hatch none 0.5)
			(connect_pads
				(clearance 0)
			)
			(min_thickness 0.25)
			(keepout
				(tracks not_allowed)
				(vias allowed)
				(pads allowed)
				(copperpour not_allowed)
				(footprints allowed)
			)
			(placement
				(enabled no)
				(sheetname "")
			)
			(fill
				(thermal_gap 0.5)
				(thermal_bridge_width 0.5)
				(island_removal_mode 0)
			)
			(polygon
				(pts
					(xy 250.884436 -383.7178) (xy 256.167636 -383.7178) (xy 256.167636 -382.92786) (xy 250.884436 -382.92786)
				)
			)
		)
	)
	(footprint ""
		(layer "F.Cu")
		(at 420.75735 -37.277548)
		(property "Reference" "R6042"
			(at 0 0 0)
			(layer "F.SilkS")
			(hide yes)
			(effects
				(font
					(size 1.27 1.27)
				)
			)
		)
		(property "Value" ""
			(at 0 0 0)
			(layer "F.Fab")
			(effects
				(font
					(size 1.27 1.27)
				)
			)
		)
		(duplicate_pad_numbers_are_jumpers no)
		(fp_line
			(start -0.7874 -0.4064)
			(end 0.7874 -0.4064)
			(stroke
				(width 0.1524)
				(type default)
			)
			(layer "F.SilkS")
		)
		(fp_line
			(start -0.7874 0.4064)
			(end -0.7874 -0.4064)
			(stroke
				(width 0.1524)
				(type default)
			)
			(layer "F.SilkS")
		)
		(fp_line
			(start 0.7874 -0.4064)
			(end 0.7874 0.4064)
			(stroke
				(width 0.1524)
				(type default)
			)
			(layer "F.SilkS")
		)
		(fp_line
			(start 0.7874 0.4064)
			(end -0.7874 0.4064)
			(stroke
				(width 0.1524)
				(type default)
			)
			(layer "F.SilkS")
		)
		(fp_line
			(start -0.67945 -0.305054)
			(end -0.12065 -0.305054)
			(stroke
				(width 0.1)
				(type default)
			)
			(layer "F.Fab")
		)
		(fp_line
			(start -0.67945 0.3048)
			(end -0.67945 -0.305054)
			(stroke
				(width 0.1)
				(type default)
			)
			(layer "F.Fab")
		)
		(fp_line
			(start -0.12065 -0.305054)
			(end -0.12065 -0.2794)
			(stroke
				(width 0.1)
				(type default)
			)
			(layer "F.Fab")
		)
		(fp_line
			(start -0.12065 -0.2794)
			(end 0.12065 -0.2794)
			(stroke
				(width 0.1)
				(type default)
			)
			(layer "F.Fab")
		)
		(fp_line
			(start -0.12065 0.2794)
			(end -0.12065 0.3048)
			(stroke
				(width 0.1)
				(type default)
			)
			(layer "F.Fab")
		)
		(fp_line
			(start -0.12065 0.3048)
			(end -0.67945 0.3048)
			(stroke
				(width 0.1)
				(type default)
			)
			(layer "F.Fab")
		)
		(fp_line
			(start 0.120396 0.2794)
			(end -0.12065 0.2794)
			(stroke
				(width 0.1)
				(type default)
			)
			(layer "F.Fab")
		)
		(fp_line
			(start 0.120396 0.3048)
			(end 0.120396 0.2794)
			(stroke
				(width 0.1)
				(type default)
			)
			(layer "F.Fab")
		)
		(fp_line
			(start 0.12065 -0.3048)
			(end 0.67945 -0.3048)
			(stroke
				(width 0.1)
				(type default)
			)
			(layer "F.Fab")
		)
		(fp_line
			(start 0.12065 -0.2794)
			(end 0.12065 -0.3048)
			(stroke
				(width 0.1)
				(type default)
			)
			(layer "F.Fab")
		)
		(fp_line
			(start 0.67945 -0.3048)
			(end 0.67945 0.3048)
			(stroke
				(width 0.1)
				(type default)
			)
			(layer "F.Fab")
		)
		(fp_line
			(start 0.67945 0.3048)
			(end 0.120396 0.3048)
			(stroke
				(width 0.1)
				(type default)
			)
			(layer "F.Fab")
		)
		(pad "1" smd circle
			(at -0.40005 0)
			(size 0 0)
			(layers "F.Cu" "F.Mask" "F.Paste")
			(net "P3V3_AUX")
		)
		(pad "2" smd circle
			(at 0.40005 0)
			(size 0 0)
			(layers "F.Cu" "F.Mask" "F.Paste")
			(net "PU_FPGA_DEBUG_SW_SPARE")
		)
	)
	(footprint ""
		(layer "F.Cu")
		(at 340.162388 -165.803834 90)
		(property "Reference" "PL50"
			(at 0.439166 -4.093718 90)
			(unlocked yes)
			(layer "F.SilkS")
			(effects
				(font
					(size 0.7874 0.5842)
					(thickness 0.1524)
				)
				(justify left)
			)
		)
		(property "Value" ""
			(at 0 0 90)
			(layer "F.Fab")
			(effects
				(font
					(size 1.27 1.27)
				)
			)
		)
		(duplicate_pad_numbers_are_jumpers no)
		(fp_line
			(start 3.24993 -3.24993)
			(end 3.24993 -2.2352)
			(stroke
				(width 0.1524)
				(type default)
			)
			(layer "F.SilkS")
		)
		(fp_line
			(start -3.24993 -3.24993)
			(end 3.24993 -3.24993)
			(stroke
				(width 0.1524)
				(type default)
			)
			(layer "F.SilkS")
		)
		(fp_line
			(start -3.24993 -2.2352)
			(end -3.24993 -3.24993)
			(stroke
				(width 0.1524)
				(type default)
			)
			(layer "F.SilkS")
		)
		(fp_line
			(start 3.24993 2.2352)
			(end 3.24993 3.24993)
			(stroke
				(width 0.1524)
				(type default)
			)
			(layer "F.SilkS")
		)
		(fp_line
			(start 3.24993 3.24993)
			(end -3.24993 3.24993)
			(stroke
				(width 0.1524)
				(type default)
			)
			(layer "F.SilkS")
		)
		(fp_line
			(start -3.24993 3.24993)
			(end -3.24993 2.2352)
			(stroke
				(width 0.1524)
				(type default)
			)
			(layer "F.SilkS")
		)
		(fp_line
			(start 3.24993 -3.24993)
			(end 3.24993 3.24993)
			(stroke
				(width 0.1)
				(type default)
			)
			(layer "F.Fab")
		)
		(fp_line
			(start -3.24993 -3.24993)
			(end 3.24993 -3.24993)
			(stroke
				(width 0.1)
				(type default)
			)
			(layer "F.Fab")
		)
		(fp_line
			(start 3.24993 3.24993)
			(end -3.24993 3.24993)
			(stroke
				(width 0.1)
				(type default)
			)
			(layer "F.Fab")
		)
		(fp_line
			(start -3.24993 3.24993)
			(end -3.24993 -3.24993)
			(stroke
				(width 0.1)
				(type default)
			)
			(layer "F.Fab")
		)
		(pad "1" smd rect
			(at -2.29997 0 90)
			(size 2.0066 4.2164)
			(layers "F.Cu" "F.Mask" "F.Paste")
			(net "GND")
		)
		(pad "2" smd rect
			(at 2.29997 0 90)
			(size 2.0066 4.2164)
			(layers "F.Cu" "F.Mask" "F.Paste")
			(net "IND_CPU0_P0_CPL0")
		)
	)
	(footprint ""
		(layer "F.Cu")
		(at 189.865 -100.294948 90)
		(property "Reference" "R184"
			(at 0 0 90)
			(layer "F.SilkS")
			(hide yes)
			(effects
				(font
					(size 1.27 1.27)
				)
			)
		)
		(property "Value" ""
			(at 0 0 90)
			(layer "F.Fab")
			(effects
				(font
					(size 1.27 1.27)
				)
			)
		)
		(duplicate_pad_numbers_are_jumpers no)
		(fp_line
			(start 0.7874 -0.4064)
			(end 0.7874 0.4064)
			(stroke
				(width 0.1524)
				(type default)
			)
			(layer "F.SilkS")
		)
		(fp_line
			(start -0.7874 -0.4064)
			(end 0.7874 -0.4064)
			(stroke
				(width 0.1524)
				(type default)
			)
			(layer "F.SilkS")
		)
		(fp_line
			(start 0.7874 0.4064)
			(end -0.7874 0.4064)
			(stroke
				(width 0.1524)
				(type default)
			)
			(layer "F.SilkS")
		)
		(fp_line
			(start -0.7874 0.4064)
			(end -0.7874 -0.4064)
			(stroke
				(width 0.1524)
				(type default)
			)
			(layer "F.SilkS")
		)
		(fp_line
			(start -0.12065 -0.305054)
			(end -0.12065 -0.2794)
			(stroke
				(width 0.1)
				(type default)
			)
			(layer "F.Fab")
		)
		(fp_line
			(start -0.67945 -0.305054)
			(end -0.12065 -0.305054)
			(stroke
				(width 0.1)
				(type default)
			)
			(layer "F.Fab")
		)
		(fp_line
			(start 0.67945 -0.3048)
			(end 0.67945 0.3048)
			(stroke
				(width 0.1)
				(type default)
			)
			(layer "F.Fab")
		)
		(fp_line
			(start 0.12065 -0.3048)
			(end 0.67945 -0.3048)
			(stroke
				(width 0.1)
				(type default)
			)
			(layer "F.Fab")
		)
		(fp_line
			(start 0.12065 -0.2794)
			(end 0.12065 -0.3048)
			(stroke
				(width 0.1)
				(type default)
			)
			(layer "F.Fab")
		)
		(fp_line
			(start -0.12065 -0.2794)
			(end 0.12065 -0.2794)
			(stroke
				(width 0.1)
				(type default)
			)
			(layer "F.Fab")
		)
		(fp_line
			(start 0.120396 0.2794)
			(end -0.12065 0.2794)
			(stroke
				(width 0.1)
				(type default)
			)
			(layer "F.Fab")
		)
		(fp_line
			(start -0.12065 0.2794)
			(end -0.12065 0.3048)
			(stroke
				(width 0.1)
				(type default)
			)
			(layer "F.Fab")
		)
		(fp_line
			(start 0.67945 0.3048)
			(end 0.120396 0.3048)
			(stroke
				(width 0.1)
				(type default)
			)
			(layer "F.Fab")
		)
		(fp_line
			(start 0.120396 0.3048)
			(end 0.120396 0.2794)
			(stroke
				(width 0.1)
				(type default)
			)
			(layer "F.Fab")
		)
		(fp_line
			(start -0.12065 0.3048)
			(end -0.67945 0.3048)
			(stroke
				(width 0.1)
				(type default)
			)
			(layer "F.Fab")
		)
		(fp_line
			(start -0.67945 0.3048)
			(end -0.67945 -0.305054)
			(stroke
				(width 0.1)
				(type default)
			)
			(layer "F.Fab")
		)
		(pad "1" smd circle
			(at -0.40005 0 90)
			(size 0 0)
			(layers "F.Cu" "F.Mask" "F.Paste")
			(net "CPU0_CORETYPE1")
		)
		(pad "2" smd circle
			(at 0.40005 0 90)
			(size 0 0)
			(layers "F.Cu" "F.Mask" "F.Paste")
			(net "FM_CPU0_CORETYPE1")
		)
	)
	(footprint ""
		(layer "F.Cu")
		(at 76.115164 -18.066512)
		(property "Reference" "PR3805"
			(at 0 0 0)
			(layer "F.SilkS")
			(hide yes)
			(effects
				(font
					(size 1.27 1.27)
				)
			)
		)
		(property "Value" ""
			(at 0 0 0)
			(layer "F.Fab")
			(effects
				(font
					(size 1.27 1.27)
				)
			)
		)
		(duplicate_pad_numbers_are_jumpers no)
		(fp_line
			(start -0.7874 -0.4064)
			(end 0.7874 -0.4064)
			(stroke
				(width 0.1524)
				(type default)
			)
			(layer "F.SilkS")
		)
		(fp_line
			(start -0.7874 0.4064)
			(end -0.7874 -0.4064)
			(stroke
				(width 0.1524)
				(type default)
			)
			(layer "F.SilkS")
		)
		(fp_line
			(start 0.7874 -0.4064)
			(end 0.7874 0.4064)
			(stroke
				(width 0.1524)
				(type default)
			)
			(layer "F.SilkS")
		)
		(fp_line
			(start 0.7874 0.4064)
			(end -0.7874 0.4064)
			(stroke
				(width 0.1524)
				(type default)
			)
			(layer "F.SilkS")
		)
		(fp_line
			(start -0.67945 -0.305054)
			(end -0.12065 -0.305054)
			(stroke
				(width 0.1)
				(type default)
			)
			(layer "F.Fab")
		)
		(fp_line
			(start -0.67945 0.3048)
			(end -0.67945 -0.305054)
			(stroke
				(width 0.1)
				(type default)
			)
			(layer "F.Fab")
		)
		(fp_line
			(start -0.12065 -0.305054)
			(end -0.12065 -0.2794)
			(stroke
				(width 0.1)
				(type default)
			)
			(layer "F.Fab")
		)
		(fp_line
			(start -0.12065 -0.2794)
			(end 0.12065 -0.2794)
			(stroke
				(width 0.1)
				(type default)
			)
			(layer "F.Fab")
		)
		(fp_line
			(start -0.12065 0.2794)
			(end -0.12065 0.3048)
			(stroke
				(width 0.1)
				(type default)
			)
			(layer "F.Fab")
		)
		(fp_line
			(start -0.12065 0.3048)
			(end -0.67945 0.3048)
			(stroke
				(width 0.1)
				(type default)
			)
			(layer "F.Fab")
		)
		(fp_line
			(start 0.120396 0.2794)
			(end -0.12065 0.2794)
			(stroke
				(width 0.1)
				(type default)
			)
			(layer "F.Fab")
		)
		(fp_line
			(start 0.120396 0.3048)
			(end 0.120396 0.2794)
			(stroke
				(width 0.1)
				(type default)
			)
			(layer "F.Fab")
		)
		(fp_line
			(start 0.12065 -0.3048)
			(end 0.67945 -0.3048)
			(stroke
				(width 0.1)
				(type default)
			)
			(layer "F.Fab")
		)
		(fp_line
			(start 0.12065 -0.2794)
			(end 0.12065 -0.3048)
			(stroke
				(width 0.1)
				(type default)
			)
			(layer "F.Fab")
		)
		(fp_line
			(start 0.67945 -0.3048)
			(end 0.67945 0.3048)
			(stroke
				(width 0.1)
				(type default)
			)
			(layer "F.Fab")
		)
		(fp_line
			(start 0.67945 0.3048)
			(end 0.120396 0.3048)
			(stroke
				(width 0.1)
				(type default)
			)
			(layer "F.Fab")
		)
		(pad "1" smd circle
			(at -0.40005 0)
			(size 0 0)
			(layers "F.Cu" "F.Mask" "F.Paste")
			(net "P12V_AUX")
		)
		(pad "2" smd circle
			(at 0.40005 0)
			(size 0 0)
			(layers "F.Cu" "F.Mask" "F.Paste")
			(net "P12V_OCP_UV_2")
		)
	)
	(footprint ""
		(layer "F.Cu")
		(at 374.846342 -416.899344 -90)
		(property "Reference" "C6567"
			(at 0 0 270)
			(layer "F.SilkS")
			(hide yes)
			(effects
				(font
					(size 1.27 1.27)
				)
			)
		)
		(property "Value" ""
			(at 0 0 270)
			(layer "F.Fab")
			(effects
				(font
					(size 1.27 1.27)
				)
			)
		)
		(duplicate_pad_numbers_are_jumpers no)
		(fp_line
			(start -0.299974 0.150114)
			(end -0.299974 -0.150114)
			(stroke
				(width 0.1)
				(type default)
			)
			(layer "F.Fab")
		)
		(fp_line
			(start 0.299974 0.150114)
			(end -0.299974 0.150114)
			(stroke
				(width 0.1)
				(type default)
			)
			(layer "F.Fab")
		)
		(fp_line
			(start -0.299974 -0.150114)
			(end 0.299974 -0.150114)
			(stroke
				(width 0.1)
				(type default)
			)
			(layer "F.Fab")
		)
		(fp_line
			(start 0.299974 -0.150114)
			(end 0.299974 0.150114)
			(stroke
				(width 0.1)
				(type default)
			)
			(layer "F.Fab")
		)
		(pad "1" smd rect
			(at -0.2667 0 270)
			(size 0.3048 0.381)
			(layers "F.Cu" "F.Mask" "F.Paste")
			(net "P5E_CPU0_P2_TX_BUF_C_DP<1>")
		)
		(pad "2" smd rect
			(at 0.2667 0 270)
			(size 0.3048 0.381)
			(layers "F.Cu" "F.Mask" "F.Paste")
			(net "P5E_CPU0_P2_TX_BUF_DP<1>")
		)
	)
	(footprint ""
		(layer "F.Cu")
		(at 210.608672 -126.469648)
		(property "Reference" "C10"
			(at 0 0 0)
			(layer "F.SilkS")
			(hide yes)
			(effects
				(font
					(size 1.27 1.27)
				)
			)
		)
		(property "Value" ""
			(at 0 0 0)
			(layer "F.Fab")
			(effects
				(font
					(size 1.27 1.27)
				)
			)
		)
		(duplicate_pad_numbers_are_jumpers no)
		(fp_line
			(start -0.7874 -0.4064)
			(end 0.7874 -0.4064)
			(stroke
				(width 0.1524)
				(type default)
			)
			(layer "F.SilkS")
		)
		(fp_line
			(start -0.7874 0.4064)
			(end -0.7874 -0.4064)
			(stroke
				(width 0.1524)
				(type default)
			)
			(layer "F.SilkS")
		)
		(fp_line
			(start 0.7874 -0.4064)
			(end 0.7874 0.4064)
			(stroke
				(width 0.1524)
				(type default)
			)
			(layer "F.SilkS")
		)
		(fp_line
			(start 0.7874 0.4064)
			(end -0.7874 0.4064)
			(stroke
				(width 0.1524)
				(type default)
			)
			(layer "F.SilkS")
		)
		(fp_line
			(start -0.67945 -0.305054)
			(end -0.12065 -0.305054)
			(stroke
				(width 0.1)
				(type default)
			)
			(layer "F.Fab")
		)
		(fp_line
			(start -0.67945 0.3048)
			(end -0.67945 -0.305054)
			(stroke
				(width 0.1)
				(type default)
			)
			(layer "F.Fab")
		)
		(fp_line
			(start -0.12065 -0.305054)
			(end -0.12065 -0.2794)
			(stroke
				(width 0.1)
				(type default)
			)
			(layer "F.Fab")
		)
		(fp_line
			(start -0.12065 -0.2794)
			(end 0.12065 -0.2794)
			(stroke
				(width 0.1)
				(type default)
			)
			(layer "F.Fab")
		)
		(fp_line
			(start -0.12065 0.2794)
			(end -0.12065 0.3048)
			(stroke
				(width 0.1)
				(type default)
			)
			(layer "F.Fab")
		)
		(fp_line
			(start -0.12065 0.3048)
			(end -0.67945 0.3048)
			(stroke
				(width 0.1)
				(type default)
			)
			(layer "F.Fab")
		)
		(fp_line
			(start 0.120396 0.2794)
			(end -0.12065 0.2794)
			(stroke
				(width 0.1)
				(type default)
			)
			(layer "F.Fab")
		)
		(fp_line
			(start 0.120396 0.3048)
			(end 0.120396 0.2794)
			(stroke
				(width 0.1)
				(type default)
			)
			(layer "F.Fab")
		)
		(fp_line
			(start 0.12065 -0.3048)
			(end 0.67945 -0.3048)
			(stroke
				(width 0.1)
				(type default)
			)
			(layer "F.Fab")
		)
		(fp_line
			(start 0.12065 -0.2794)
			(end 0.12065 -0.3048)
			(stroke
				(width 0.1)
				(type default)
			)
			(layer "F.Fab")
		)
		(fp_line
			(start 0.67945 -0.3048)
			(end 0.67945 0.3048)
			(stroke
				(width 0.1)
				(type default)
			)
			(layer "F.Fab")
		)
		(fp_line
			(start 0.67945 0.3048)
			(end 0.120396 0.3048)
			(stroke
				(width 0.1)
				(type default)
			)
			(layer "F.Fab")
		)
		(pad "1" smd circle
			(at -0.40005 0)
			(size 0 0)
			(layers "F.Cu" "F.Mask" "F.Paste")
			(net "P3V3_AUX")
		)
		(pad "2" smd circle
			(at 0.40005 0)
			(size 0 0)
			(layers "F.Cu" "F.Mask" "F.Paste")
			(net "GND")
		)
	)
	(footprint ""
		(layer "F.Cu")
		(at 127.705104 -54.17439 180)
		(property "Reference" "C1518"
			(at 0 0 180)
			(layer "F.SilkS")
			(hide yes)
			(effects
				(font
					(size 1.27 1.27)
				)
			)
		)
		(property "Value" ""
			(at 0 0 180)
			(layer "F.Fab")
			(effects
				(font
					(size 1.27 1.27)
				)
			)
		)
		(duplicate_pad_numbers_are_jumpers no)
		(fp_line
			(start 0.7874 0.4064)
			(end -0.7874 0.4064)
			(stroke
				(width 0.1524)
				(type default)
			)
			(layer "F.SilkS")
		)
		(fp_line
			(start 0.7874 -0.4064)
			(end 0.7874 0.4064)
			(stroke
				(width 0.1524)
				(type default)
			)
			(layer "F.SilkS")
		)
		(fp_line
			(start -0.7874 0.4064)
			(end -0.7874 -0.4064)
			(stroke
				(width 0.1524)
				(type default)
			)
			(layer "F.SilkS")
		)
		(fp_line
			(start -0.7874 -0.4064)
			(end 0.7874 -0.4064)
			(stroke
				(width 0.1524)
				(type default)
			)
			(layer "F.SilkS")
		)
		(fp_line
			(start 0.67945 0.3048)
			(end 0.120396 0.3048)
			(stroke
				(width 0.1)
				(type default)
			)
			(layer "F.Fab")
		)
		(fp_line
			(start 0.67945 -0.3048)
			(end 0.67945 0.3048)
			(stroke
				(width 0.1)
				(type default)
			)
			(layer "F.Fab")
		)
		(fp_line
			(start 0.12065 -0.2794)
			(end 0.12065 -0.3048)
			(stroke
				(width 0.1)
				(type default)
			)
			(layer "F.Fab")
		)
		(fp_line
			(start 0.12065 -0.3048)
			(end 0.67945 -0.3048)
			(stroke
				(width 0.1)
				(type default)
			)
			(layer "F.Fab")
		)
		(fp_line
			(start 0.120396 0.3048)
			(end 0.120396 0.2794)
			(stroke
				(width 0.1)
				(type default)
			)
			(layer "F.Fab")
		)
		(fp_line
			(start 0.120396 0.2794)
			(end -0.12065 0.2794)
			(stroke
				(width 0.1)
				(type default)
			)
			(layer "F.Fab")
		)
		(fp_line
			(start -0.12065 0.3048)
			(end -0.67945 0.3048)
			(stroke
				(width 0.1)
				(type default)
			)
			(layer "F.Fab")
		)
		(fp_line
			(start -0.12065 0.2794)
			(end -0.12065 0.3048)
			(stroke
				(width 0.1)
				(type default)
			)
			(layer "F.Fab")
		)
		(fp_line
			(start -0.12065 -0.2794)
			(end 0.12065 -0.2794)
			(stroke
				(width 0.1)
				(type default)
			)
			(layer "F.Fab")
		)
		(fp_line
			(start -0.12065 -0.305054)
			(end -0.12065 -0.2794)
			(stroke
				(width 0.1)
				(type default)
			)
			(layer "F.Fab")
		)
		(fp_line
			(start -0.67945 0.3048)
			(end -0.67945 -0.305054)
			(stroke
				(width 0.1)
				(type default)
			)
			(layer "F.Fab")
		)
		(fp_line
			(start -0.67945 -0.305054)
			(end -0.12065 -0.305054)
			(stroke
				(width 0.1)
				(type default)
			)
			(layer "F.Fab")
		)
		(pad "1" smd circle
			(at -0.40005 0 180)
			(size 0 0)
			(layers "F.Cu" "F.Mask" "F.Paste")
			(net "PVDD18_S5_P0")
		)
		(pad "2" smd circle
			(at 0.40005 0 180)
			(size 0 0)
			(layers "F.Cu" "F.Mask" "F.Paste")
			(net "GND")
		)
	)
	(footprint ""
		(layer "F.Cu")
		(at 358.021128 -394.82268 90)
		(property "Reference" "C590"
			(at 0 0 90)
			(layer "F.SilkS")
			(hide yes)
			(effects
				(font
					(size 1.27 1.27)
				)
			)
		)
		(property "Value" ""
			(at 0 0 90)
			(layer "F.Fab")
			(effects
				(font
					(size 1.27 1.27)
				)
			)
		)
		(duplicate_pad_numbers_are_jumpers no)
		(fp_line
			(start 0.7874 -0.4064)
			(end 0.7874 0.4064)
			(stroke
				(width 0.1524)
				(type default)
			)
			(layer "F.SilkS")
		)
		(fp_line
			(start -0.7874 -0.4064)
			(end 0.7874 -0.4064)
			(stroke
				(width 0.1524)
				(type default)
			)
			(layer "F.SilkS")
		)
		(fp_line
			(start 0.7874 0.4064)
			(end -0.7874 0.4064)
			(stroke
				(width 0.1524)
				(type default)
			)
			(layer "F.SilkS")
		)
		(fp_line
			(start -0.7874 0.4064)
			(end -0.7874 -0.4064)
			(stroke
				(width 0.1524)
				(type default)
			)
			(layer "F.SilkS")
		)
		(fp_line
			(start -0.12065 -0.305054)
			(end -0.12065 -0.2794)
			(stroke
				(width 0.1)
				(type default)
			)
			(layer "F.Fab")
		)
		(fp_line
			(start -0.67945 -0.305054)
			(end -0.12065 -0.305054)
			(stroke
				(width 0.1)
				(type default)
			)
			(layer "F.Fab")
		)
		(fp_line
			(start 0.67945 -0.3048)
			(end 0.67945 0.3048)
			(stroke
				(width 0.1)
				(type default)
			)
			(layer "F.Fab")
		)
		(fp_line
			(start 0.12065 -0.3048)
			(end 0.67945 -0.3048)
			(stroke
				(width 0.1)
				(type default)
			)
			(layer "F.Fab")
		)
		(fp_line
			(start 0.12065 -0.2794)
			(end 0.12065 -0.3048)
			(stroke
				(width 0.1)
				(type default)
			)
			(layer "F.Fab")
		)
		(fp_line
			(start -0.12065 -0.2794)
			(end 0.12065 -0.2794)
			(stroke
				(width 0.1)
				(type default)
			)
			(layer "F.Fab")
		)
		(fp_line
			(start 0.120396 0.2794)
			(end -0.12065 0.2794)
			(stroke
				(width 0.1)
				(type default)
			)
			(layer "F.Fab")
		)
		(fp_line
			(start -0.12065 0.2794)
			(end -0.12065 0.3048)
			(stroke
				(width 0.1)
				(type default)
			)
			(layer "F.Fab")
		)
		(fp_line
			(start 0.67945 0.3048)
			(end 0.120396 0.3048)
			(stroke
				(width 0.1)
				(type default)
			)
			(layer "F.Fab")
		)
		(fp_line
			(start 0.120396 0.3048)
			(end 0.120396 0.2794)
			(stroke
				(width 0.1)
				(type default)
			)
			(layer "F.Fab")
		)
		(fp_line
			(start -0.12065 0.3048)
			(end -0.67945 0.3048)
			(stroke
				(width 0.1)
				(type default)
			)
			(layer "F.Fab")
		)
		(fp_line
			(start -0.67945 0.3048)
			(end -0.67945 -0.305054)
			(stroke
				(width 0.1)
				(type default)
			)
			(layer "F.Fab")
		)
		(pad "1" smd circle
			(at -0.40005 0 90)
			(size 0 0)
			(layers "F.Cu" "F.Mask" "F.Paste")
			(net "P1V8_CPU0_RT1_1A")
		)
		(pad "2" smd circle
			(at 0.40005 0 90)
			(size 0 0)
			(layers "F.Cu" "F.Mask" "F.Paste")
			(net "GND")
		)
	)
	(footprint ""
		(layer "F.Cu")
		(at 215.4301 -405.036782 180)
		(property "Reference" "PC2226"
			(at 0 0 180)
			(layer "F.SilkS")
			(hide yes)
			(effects
				(font
					(size 1.27 1.27)
				)
			)
		)
		(property "Value" ""
			(at 0 0 180)
			(layer "F.Fab")
			(effects
				(font
					(size 1.27 1.27)
				)
			)
		)
		(duplicate_pad_numbers_are_jumpers no)
		(fp_line
			(start 0.7874 0.4064)
			(end -0.7874 0.4064)
			(stroke
				(width 0.1524)
				(type default)
			)
			(layer "F.SilkS")
		)
		(fp_line
			(start 0.7874 -0.4064)
			(end 0.7874 0.4064)
			(stroke
				(width 0.1524)
				(type default)
			)
			(layer "F.SilkS")
		)
		(fp_line
			(start -0.7874 0.4064)
			(end -0.7874 -0.4064)
			(stroke
				(width 0.1524)
				(type default)
			)
			(layer "F.SilkS")
		)
		(fp_line
			(start -0.7874 -0.4064)
			(end 0.7874 -0.4064)
			(stroke
				(width 0.1524)
				(type default)
			)
			(layer "F.SilkS")
		)
		(fp_line
			(start 0.67945 0.3048)
			(end 0.120396 0.3048)
			(stroke
				(width 0.1)
				(type default)
			)
			(layer "F.Fab")
		)
		(fp_line
			(start 0.67945 -0.3048)
			(end 0.67945 0.3048)
			(stroke
				(width 0.1)
				(type default)
			)
			(layer "F.Fab")
		)
		(fp_line
			(start 0.12065 -0.2794)
			(end 0.12065 -0.3048)
			(stroke
				(width 0.1)
				(type default)
			)
			(layer "F.Fab")
		)
		(fp_line
			(start 0.12065 -0.3048)
			(end 0.67945 -0.3048)
			(stroke
				(width 0.1)
				(type default)
			)
			(layer "F.Fab")
		)
		(fp_line
			(start 0.120396 0.3048)
			(end 0.120396 0.2794)
			(stroke
				(width 0.1)
				(type default)
			)
			(layer "F.Fab")
		)
		(fp_line
			(start 0.120396 0.2794)
			(end -0.12065 0.2794)
			(stroke
				(width 0.1)
				(type default)
			)
			(layer "F.Fab")
		)
		(fp_line
			(start -0.12065 0.3048)
			(end -0.67945 0.3048)
			(stroke
				(width 0.1)
				(type default)
			)
			(layer "F.Fab")
		)
		(fp_line
			(start -0.12065 0.2794)
			(end -0.12065 0.3048)
			(stroke
				(width 0.1)
				(type default)
			)
			(layer "F.Fab")
		)
		(fp_line
			(start -0.12065 -0.2794)
			(end 0.12065 -0.2794)
			(stroke
				(width 0.1)
				(type default)
			)
			(layer "F.Fab")
		)
		(fp_line
			(start -0.12065 -0.305054)
			(end -0.12065 -0.2794)
			(stroke
				(width 0.1)
				(type default)
			)
			(layer "F.Fab")
		)
		(fp_line
			(start -0.67945 0.3048)
			(end -0.67945 -0.305054)
			(stroke
				(width 0.1)
				(type default)
			)
			(layer "F.Fab")
		)
		(fp_line
			(start -0.67945 -0.305054)
			(end -0.12065 -0.305054)
			(stroke
				(width 0.1)
				(type default)
			)
			(layer "F.Fab")
		)
		(pad "1" smd circle
			(at -0.40005 0 180)
			(size 0 0)
			(layers "F.Cu" "F.Mask" "F.Paste")
			(net "HSC_SS")
		)
		(pad "2" smd circle
			(at 0.40005 0 180)
			(size 0 0)
			(layers "F.Cu" "F.Mask" "F.Paste")
			(net "AGND_HSC")
		)
	)
	(footprint ""
		(layer "F.Cu")
		(at 400.48307 -323.965316 180)
		(property "Reference" "R475"
			(at 0 0 180)
			(layer "F.SilkS")
			(hide yes)
			(effects
				(font
					(size 1.27 1.27)
				)
			)
		)
		(property "Value" ""
			(at 0 0 180)
			(layer "F.Fab")
			(effects
				(font
					(size 1.27 1.27)
				)
			)
		)
		(duplicate_pad_numbers_are_jumpers no)
		(fp_line
			(start 0.7874 0.4064)
			(end -0.7874 0.4064)
			(stroke
				(width 0.1524)
				(type default)
			)
			(layer "F.SilkS")
		)
		(fp_line
			(start 0.7874 -0.4064)
			(end 0.7874 0.4064)
			(stroke
				(width 0.1524)
				(type default)
			)
			(layer "F.SilkS")
		)
		(fp_line
			(start -0.7874 0.4064)
			(end -0.7874 -0.4064)
			(stroke
				(width 0.1524)
				(type default)
			)
			(layer "F.SilkS")
		)
		(fp_line
			(start -0.7874 -0.4064)
			(end 0.7874 -0.4064)
			(stroke
				(width 0.1524)
				(type default)
			)
			(layer "F.SilkS")
		)
		(fp_line
			(start 0.67945 0.3048)
			(end 0.120396 0.3048)
			(stroke
				(width 0.1)
				(type default)
			)
			(layer "F.Fab")
		)
		(fp_line
			(start 0.67945 -0.3048)
			(end 0.67945 0.3048)
			(stroke
				(width 0.1)
				(type default)
			)
			(layer "F.Fab")
		)
		(fp_line
			(start 0.12065 -0.2794)
			(end 0.12065 -0.3048)
			(stroke
				(width 0.1)
				(type default)
			)
			(layer "F.Fab")
		)
		(fp_line
			(start 0.12065 -0.3048)
			(end 0.67945 -0.3048)
			(stroke
				(width 0.1)
				(type default)
			)
			(layer "F.Fab")
		)
		(fp_line
			(start 0.120396 0.3048)
			(end 0.120396 0.2794)
			(stroke
				(width 0.1)
				(type default)
			)
			(layer "F.Fab")
		)
		(fp_line
			(start 0.120396 0.2794)
			(end -0.12065 0.2794)
			(stroke
				(width 0.1)
				(type default)
			)
			(layer "F.Fab")
		)
		(fp_line
			(start -0.12065 0.3048)
			(end -0.67945 0.3048)
			(stroke
				(width 0.1)
				(type default)
			)
			(layer "F.Fab")
		)
		(fp_line
			(start -0.12065 0.2794)
			(end -0.12065 0.3048)
			(stroke
				(width 0.1)
				(type default)
			)
			(layer "F.Fab")
		)
		(fp_line
			(start -0.12065 -0.2794)
			(end 0.12065 -0.2794)
			(stroke
				(width 0.1)
				(type default)
			)
			(layer "F.Fab")
		)
		(fp_line
			(start -0.12065 -0.305054)
			(end -0.12065 -0.2794)
			(stroke
				(width 0.1)
				(type default)
			)
			(layer "F.Fab")
		)
		(fp_line
			(start -0.67945 0.3048)
			(end -0.67945 -0.305054)
			(stroke
				(width 0.1)
				(type default)
			)
			(layer "F.Fab")
		)
		(fp_line
			(start -0.67945 -0.305054)
			(end -0.12065 -0.305054)
			(stroke
				(width 0.1)
				(type default)
			)
			(layer "F.Fab")
		)
		(pad "1" smd circle
			(at -0.40005 0 180)
			(size 0 0)
			(layers "F.Cu" "F.Mask" "F.Paste")
			(net "SPI_CPU0_TPM_CS_N")
		)
		(pad "2" smd circle
			(at 0.40005 0 180)
			(size 0 0)
			(layers "F.Cu" "F.Mask" "F.Paste")
			(net "SPI_CPU0_R_TPM_CS_N")
		)
	)
	(footprint ""
		(layer "F.Cu")
		(at 18.45564 -404.341584 90)
		(property "Reference" "R661"
			(at 0 0 90)
			(layer "F.SilkS")
			(hide yes)
			(effects
				(font
					(size 1.27 1.27)
				)
			)
		)
		(property "Value" ""
			(at 0 0 90)
			(layer "F.Fab")
			(effects
				(font
					(size 1.27 1.27)
				)
			)
		)
		(duplicate_pad_numbers_are_jumpers no)
		(fp_line
			(start 0.7874 -0.4064)
			(end 0.7874 0.4064)
			(stroke
				(width 0.1524)
				(type default)
			)
			(layer "F.SilkS")
		)
		(fp_line
			(start -0.7874 -0.4064)
			(end 0.7874 -0.4064)
			(stroke
				(width 0.1524)
				(type default)
			)
			(layer "F.SilkS")
		)
		(fp_line
			(start 0.7874 0.4064)
			(end -0.7874 0.4064)
			(stroke
				(width 0.1524)
				(type default)
			)
			(layer "F.SilkS")
		)
		(fp_line
			(start -0.7874 0.4064)
			(end -0.7874 -0.4064)
			(stroke
				(width 0.1524)
				(type default)
			)
			(layer "F.SilkS")
		)
		(fp_line
			(start -0.12065 -0.305054)
			(end -0.12065 -0.2794)
			(stroke
				(width 0.1)
				(type default)
			)
			(layer "F.Fab")
		)
		(fp_line
			(start -0.67945 -0.305054)
			(end -0.12065 -0.305054)
			(stroke
				(width 0.1)
				(type default)
			)
			(layer "F.Fab")
		)
		(fp_line
			(start 0.67945 -0.3048)
			(end 0.67945 0.3048)
			(stroke
				(width 0.1)
				(type default)
			)
			(layer "F.Fab")
		)
		(fp_line
			(start 0.12065 -0.3048)
			(end 0.67945 -0.3048)
			(stroke
				(width 0.1)
				(type default)
			)
			(layer "F.Fab")
		)
		(fp_line
			(start 0.12065 -0.2794)
			(end 0.12065 -0.3048)
			(stroke
				(width 0.1)
				(type default)
			)
			(layer "F.Fab")
		)
		(fp_line
			(start -0.12065 -0.2794)
			(end 0.12065 -0.2794)
			(stroke
				(width 0.1)
				(type default)
			)
			(layer "F.Fab")
		)
		(fp_line
			(start 0.120396 0.2794)
			(end -0.12065 0.2794)
			(stroke
				(width 0.1)
				(type default)
			)
			(layer "F.Fab")
		)
		(fp_line
			(start -0.12065 0.2794)
			(end -0.12065 0.3048)
			(stroke
				(width 0.1)
				(type default)
			)
			(layer "F.Fab")
		)
		(fp_line
			(start 0.67945 0.3048)
			(end 0.120396 0.3048)
			(stroke
				(width 0.1)
				(type default)
			)
			(layer "F.Fab")
		)
		(fp_line
			(start 0.120396 0.3048)
			(end 0.120396 0.2794)
			(stroke
				(width 0.1)
				(type default)
			)
			(layer "F.Fab")
		)
		(fp_line
			(start -0.12065 0.3048)
			(end -0.67945 0.3048)
			(stroke
				(width 0.1)
				(type default)
			)
			(layer "F.Fab")
		)
		(fp_line
			(start -0.67945 0.3048)
			(end -0.67945 -0.305054)
			(stroke
				(width 0.1)
				(type default)
			)
			(layer "F.Fab")
		)
		(pad "1" smd circle
			(at -0.40005 0 90)
			(size 0 0)
			(layers "F.Cu" "F.Mask" "F.Paste")
			(net "PWRGD_P0V9_RETIMER_CPU1")
		)
		(pad "2" smd circle
			(at 0.40005 0 90)
			(size 0 0)
			(layers "F.Cu" "F.Mask" "F.Paste")
			(net "PWRGD_P0V9_RETIMER_CPU1_R")
		)
	)
	(footprint ""
		(layer "F.Cu")
		(at 187.316872 -428.930562 90)
		(property "Reference" "R3441"
			(at 0 0 90)
			(layer "F.SilkS")
			(hide yes)
			(effects
				(font
					(size 1.27 1.27)
				)
			)
		)
		(property "Value" ""
			(at 0 0 90)
			(layer "F.Fab")
			(effects
				(font
					(size 1.27 1.27)
				)
			)
		)
		(duplicate_pad_numbers_are_jumpers no)
		(fp_line
			(start 0.7874 -0.4064)
			(end 0.7874 0.4064)
			(stroke
				(width 0.1524)
				(type default)
			)
			(layer "F.SilkS")
		)
		(fp_line
			(start -0.7874 -0.4064)
			(end 0.7874 -0.4064)
			(stroke
				(width 0.1524)
				(type default)
			)
			(layer "F.SilkS")
		)
		(fp_line
			(start 0.7874 0.4064)
			(end -0.7874 0.4064)
			(stroke
				(width 0.1524)
				(type default)
			)
			(layer "F.SilkS")
		)
		(fp_line
			(start -0.7874 0.4064)
			(end -0.7874 -0.4064)
			(stroke
				(width 0.1524)
				(type default)
			)
			(layer "F.SilkS")
		)
		(fp_line
			(start -0.12065 -0.305054)
			(end -0.12065 -0.2794)
			(stroke
				(width 0.1)
				(type default)
			)
			(layer "F.Fab")
		)
		(fp_line
			(start -0.67945 -0.305054)
			(end -0.12065 -0.305054)
			(stroke
				(width 0.1)
				(type default)
			)
			(layer "F.Fab")
		)
		(fp_line
			(start 0.67945 -0.3048)
			(end 0.67945 0.3048)
			(stroke
				(width 0.1)
				(type default)
			)
			(layer "F.Fab")
		)
		(fp_line
			(start 0.12065 -0.3048)
			(end 0.67945 -0.3048)
			(stroke
				(width 0.1)
				(type default)
			)
			(layer "F.Fab")
		)
		(fp_line
			(start 0.12065 -0.2794)
			(end 0.12065 -0.3048)
			(stroke
				(width 0.1)
				(type default)
			)
			(layer "F.Fab")
		)
		(fp_line
			(start -0.12065 -0.2794)
			(end 0.12065 -0.2794)
			(stroke
				(width 0.1)
				(type default)
			)
			(layer "F.Fab")
		)
		(fp_line
			(start 0.120396 0.2794)
			(end -0.12065 0.2794)
			(stroke
				(width 0.1)
				(type default)
			)
			(layer "F.Fab")
		)
		(fp_line
			(start -0.12065 0.2794)
			(end -0.12065 0.3048)
			(stroke
				(width 0.1)
				(type default)
			)
			(layer "F.Fab")
		)
		(fp_line
			(start 0.67945 0.3048)
			(end 0.120396 0.3048)
			(stroke
				(width 0.1)
				(type default)
			)
			(layer "F.Fab")
		)
		(fp_line
			(start 0.120396 0.3048)
			(end 0.120396 0.2794)
			(stroke
				(width 0.1)
				(type default)
			)
			(layer "F.Fab")
		)
		(fp_line
			(start -0.12065 0.3048)
			(end -0.67945 0.3048)
			(stroke
				(width 0.1)
				(type default)
			)
			(layer "F.Fab")
		)
		(fp_line
			(start -0.67945 0.3048)
			(end -0.67945 -0.305054)
			(stroke
				(width 0.1)
				(type default)
			)
			(layer "F.Fab")
		)
		(pad "1" smd circle
			(at -0.40005 0 90)
			(size 0 0)
			(layers "F.Cu" "F.Mask" "F.Paste")
			(net "GPU_BASE_ID1")
		)
		(pad "2" smd circle
			(at 0.40005 0 90)
			(size 0 0)
			(layers "F.Cu" "F.Mask" "F.Paste")
			(net "GND")
		)
	)
	(footprint ""
		(layer "F.Cu")
		(at 169.724324 -382.038606 -90)
		(property "Reference" "R1421"
			(at 0 0 270)
			(layer "F.SilkS")
			(hide yes)
			(effects
				(font
					(size 1.27 1.27)
				)
			)
		)
		(property "Value" ""
			(at 0 0 270)
			(layer "F.Fab")
			(effects
				(font
					(size 1.27 1.27)
				)
			)
		)
		(duplicate_pad_numbers_are_jumpers no)
		(fp_line
			(start -0.32512 0.175006)
			(end -0.32512 -0.175006)
			(stroke
				(width 0.1)
				(type default)
			)
			(layer "F.Fab")
		)
		(fp_line
			(start 0.32512 0.175006)
			(end -0.32512 0.175006)
			(stroke
				(width 0.1)
				(type default)
			)
			(layer "F.Fab")
		)
		(fp_line
			(start -0.32512 -0.175006)
			(end 0.32512 -0.175006)
			(stroke
				(width 0.1)
				(type default)
			)
			(layer "F.Fab")
		)
		(fp_line
			(start 0.32512 -0.175006)
			(end 0.32512 0.175006)
			(stroke
				(width 0.1)
				(type default)
			)
			(layer "F.Fab")
		)
		(pad "1" smd rect
			(at -0.2667 0 270)
			(size 0.3048 0.381)
			(layers "F.Cu" "F.Mask" "F.Paste")
			(net "CLKREQ_RT_CPU1_P2_N")
		)
		(pad "2" smd rect
			(at 0.2667 0 90)
			(size 0.3048 0.381)
			(layers "F.Cu" "F.Mask" "F.Paste")
			(net "GND")
		)
	)
	(footprint ""
		(layer "F.Cu")
		(at 105.84561 -63.54191)
		(property "Reference" "R6220"
			(at 0 0 0)
			(layer "F.SilkS")
			(hide yes)
			(effects
				(font
					(size 1.27 1.27)
				)
			)
		)
		(property "Value" ""
			(at 0 0 0)
			(layer "F.Fab")
			(effects
				(font
					(size 1.27 1.27)
				)
			)
		)
		(duplicate_pad_numbers_are_jumpers no)
		(fp_line
			(start -0.7874 -0.4064)
			(end 0.7874 -0.4064)
			(stroke
				(width 0.1524)
				(type default)
			)
			(layer "F.SilkS")
		)
		(fp_line
			(start -0.7874 0.4064)
			(end -0.7874 -0.4064)
			(stroke
				(width 0.1524)
				(type default)
			)
			(layer "F.SilkS")
		)
		(fp_line
			(start 0.7874 -0.4064)
			(end 0.7874 0.4064)
			(stroke
				(width 0.1524)
				(type default)
			)
			(layer "F.SilkS")
		)
		(fp_line
			(start 0.7874 0.4064)
			(end -0.7874 0.4064)
			(stroke
				(width 0.1524)
				(type default)
			)
			(layer "F.SilkS")
		)
		(fp_line
			(start -0.67945 -0.305054)
			(end -0.12065 -0.305054)
			(stroke
				(width 0.1)
				(type default)
			)
			(layer "F.Fab")
		)
		(fp_line
			(start -0.67945 0.3048)
			(end -0.67945 -0.305054)
			(stroke
				(width 0.1)
				(type default)
			)
			(layer "F.Fab")
		)
		(fp_line
			(start -0.12065 -0.305054)
			(end -0.12065 -0.2794)
			(stroke
				(width 0.1)
				(type default)
			)
			(layer "F.Fab")
		)
		(fp_line
			(start -0.12065 -0.2794)
			(end 0.12065 -0.2794)
			(stroke
				(width 0.1)
				(type default)
			)
			(layer "F.Fab")
		)
		(fp_line
			(start -0.12065 0.2794)
			(end -0.12065 0.3048)
			(stroke
				(width 0.1)
				(type default)
			)
			(layer "F.Fab")
		)
		(fp_line
			(start -0.12065 0.3048)
			(end -0.67945 0.3048)
			(stroke
				(width 0.1)
				(type default)
			)
			(layer "F.Fab")
		)
		(fp_line
			(start 0.120396 0.2794)
			(end -0.12065 0.2794)
			(stroke
				(width 0.1)
				(type default)
			)
			(layer "F.Fab")
		)
		(fp_line
			(start 0.120396 0.3048)
			(end 0.120396 0.2794)
			(stroke
				(width 0.1)
				(type default)
			)
			(layer "F.Fab")
		)
		(fp_line
			(start 0.12065 -0.3048)
			(end 0.67945 -0.3048)
			(stroke
				(width 0.1)
				(type default)
			)
			(layer "F.Fab")
		)
		(fp_line
			(start 0.12065 -0.2794)
			(end 0.12065 -0.3048)
			(stroke
				(width 0.1)
				(type default)
			)
			(layer "F.Fab")
		)
		(fp_line
			(start 0.67945 -0.3048)
			(end 0.67945 0.3048)
			(stroke
				(width 0.1)
				(type default)
			)
			(layer "F.Fab")
		)
		(fp_line
			(start 0.67945 0.3048)
			(end 0.120396 0.3048)
			(stroke
				(width 0.1)
				(type default)
			)
			(layer "F.Fab")
		)
		(pad "1" smd circle
			(at -0.40005 0)
			(size 0 0)
			(layers "F.Cu" "F.Mask" "F.Paste")
			(net "P3V3_AUX")
		)
		(pad "2" smd circle
			(at 0.40005 0)
			(size 0 0)
			(layers "F.Cu" "F.Mask" "F.Paste")
			(net "USB_CPU0_ADD_A2")
		)
	)
	(footprint ""
		(layer "F.Cu")
		(at 205.203044 -109.561376)
		(property "Reference" "R6078"
			(at 0 0 0)
			(layer "F.SilkS")
			(hide yes)
			(effects
				(font
					(size 1.27 1.27)
				)
			)
		)
		(property "Value" ""
			(at 0 0 0)
			(layer "F.Fab")
			(effects
				(font
					(size 1.27 1.27)
				)
			)
		)
		(duplicate_pad_numbers_are_jumpers no)
		(fp_line
			(start -0.7874 -0.4064)
			(end 0.7874 -0.4064)
			(stroke
				(width 0.1524)
				(type default)
			)
			(layer "F.SilkS")
		)
		(fp_line
			(start -0.7874 0.4064)
			(end -0.7874 -0.4064)
			(stroke
				(width 0.1524)
				(type default)
			)
			(layer "F.SilkS")
		)
		(fp_line
			(start 0.7874 -0.4064)
			(end 0.7874 0.4064)
			(stroke
				(width 0.1524)
				(type default)
			)
			(layer "F.SilkS")
		)
		(fp_line
			(start 0.7874 0.4064)
			(end -0.7874 0.4064)
			(stroke
				(width 0.1524)
				(type default)
			)
			(layer "F.SilkS")
		)
		(fp_line
			(start -0.67945 -0.305054)
			(end -0.12065 -0.305054)
			(stroke
				(width 0.1)
				(type default)
			)
			(layer "F.Fab")
		)
		(fp_line
			(start -0.67945 0.3048)
			(end -0.67945 -0.305054)
			(stroke
				(width 0.1)
				(type default)
			)
			(layer "F.Fab")
		)
		(fp_line
			(start -0.12065 -0.305054)
			(end -0.12065 -0.2794)
			(stroke
				(width 0.1)
				(type default)
			)
			(layer "F.Fab")
		)
		(fp_line
			(start -0.12065 -0.2794)
			(end 0.12065 -0.2794)
			(stroke
				(width 0.1)
				(type default)
			)
			(layer "F.Fab")
		)
		(fp_line
			(start -0.12065 0.2794)
			(end -0.12065 0.3048)
			(stroke
				(width 0.1)
				(type default)
			)
			(layer "F.Fab")
		)
		(fp_line
			(start -0.12065 0.3048)
			(end -0.67945 0.3048)
			(stroke
				(width 0.1)
				(type default)
			)
			(layer "F.Fab")
		)
		(fp_line
			(start 0.120396 0.2794)
			(end -0.12065 0.2794)
			(stroke
				(width 0.1)
				(type default)
			)
			(layer "F.Fab")
		)
		(fp_line
			(start 0.120396 0.3048)
			(end 0.120396 0.2794)
			(stroke
				(width 0.1)
				(type default)
			)
			(layer "F.Fab")
		)
		(fp_line
			(start 0.12065 -0.3048)
			(end 0.67945 -0.3048)
			(stroke
				(width 0.1)
				(type default)
			)
			(layer "F.Fab")
		)
		(fp_line
			(start 0.12065 -0.2794)
			(end 0.12065 -0.3048)
			(stroke
				(width 0.1)
				(type default)
			)
			(layer "F.Fab")
		)
		(fp_line
			(start 0.67945 -0.3048)
			(end 0.67945 0.3048)
			(stroke
				(width 0.1)
				(type default)
			)
			(layer "F.Fab")
		)
		(fp_line
			(start 0.67945 0.3048)
			(end 0.120396 0.3048)
			(stroke
				(width 0.1)
				(type default)
			)
			(layer "F.Fab")
		)
		(pad "1" smd circle
			(at -0.40005 0)
			(size 0 0)
			(layers "F.Cu" "F.Mask" "F.Paste")
			(net "PWRGD_P3V3_AUX")
		)
		(pad "2" smd circle
			(at 0.40005 0)
			(size 0 0)
			(layers "F.Cu" "F.Mask" "F.Paste")
			(net "PWRGD_P3V3_AUX_PDB")
		)
	)
	(footprint ""
		(layer "F.Cu")
		(at 211.709 -119.634)
		(property "Reference" "R9023"
			(at 0 0 0)
			(layer "F.SilkS")
			(hide yes)
			(effects
				(font
					(size 1.27 1.27)
				)
			)
		)
		(property "Value" ""
			(at 0 0 0)
			(layer "F.Fab")
			(effects
				(font
					(size 1.27 1.27)
				)
			)
		)
		(duplicate_pad_numbers_are_jumpers no)
		(fp_line
			(start -0.7874 -0.4064)
			(end 0.7874 -0.4064)
			(stroke
				(width 0.1524)
				(type default)
			)
			(layer "F.SilkS")
		)
		(fp_line
			(start -0.7874 0.4064)
			(end -0.7874 -0.4064)
			(stroke
				(width 0.1524)
				(type default)
			)
			(layer "F.SilkS")
		)
		(fp_line
			(start 0.7874 -0.4064)
			(end 0.7874 0.4064)
			(stroke
				(width 0.1524)
				(type default)
			)
			(layer "F.SilkS")
		)
		(fp_line
			(start 0.7874 0.4064)
			(end -0.7874 0.4064)
			(stroke
				(width 0.1524)
				(type default)
			)
			(layer "F.SilkS")
		)
		(fp_line
			(start -0.67945 -0.305054)
			(end -0.12065 -0.305054)
			(stroke
				(width 0.1)
				(type default)
			)
			(layer "F.Fab")
		)
		(fp_line
			(start -0.67945 0.3048)
			(end -0.67945 -0.305054)
			(stroke
				(width 0.1)
				(type default)
			)
			(layer "F.Fab")
		)
		(fp_line
			(start -0.12065 -0.305054)
			(end -0.12065 -0.2794)
			(stroke
				(width 0.1)
				(type default)
			)
			(layer "F.Fab")
		)
		(fp_line
			(start -0.12065 -0.2794)
			(end 0.12065 -0.2794)
			(stroke
				(width 0.1)
				(type default)
			)
			(layer "F.Fab")
		)
		(fp_line
			(start -0.12065 0.2794)
			(end -0.12065 0.3048)
			(stroke
				(width 0.1)
				(type default)
			)
			(layer "F.Fab")
		)
		(fp_line
			(start -0.12065 0.3048)
			(end -0.67945 0.3048)
			(stroke
				(width 0.1)
				(type default)
			)
			(layer "F.Fab")
		)
		(fp_line
			(start 0.120396 0.2794)
			(end -0.12065 0.2794)
			(stroke
				(width 0.1)
				(type default)
			)
			(layer "F.Fab")
		)
		(fp_line
			(start 0.120396 0.3048)
			(end 0.120396 0.2794)
			(stroke
				(width 0.1)
				(type default)
			)
			(layer "F.Fab")
		)
		(fp_line
			(start 0.12065 -0.3048)
			(end 0.67945 -0.3048)
			(stroke
				(width 0.1)
				(type default)
			)
			(layer "F.Fab")
		)
		(fp_line
			(start 0.12065 -0.2794)
			(end 0.12065 -0.3048)
			(stroke
				(width 0.1)
				(type default)
			)
			(layer "F.Fab")
		)
		(fp_line
			(start 0.67945 -0.3048)
			(end 0.67945 0.3048)
			(stroke
				(width 0.1)
				(type default)
			)
			(layer "F.Fab")
		)
		(fp_line
			(start 0.67945 0.3048)
			(end 0.120396 0.3048)
			(stroke
				(width 0.1)
				(type default)
			)
			(layer "F.Fab")
		)
		(pad "1" smd circle
			(at -0.40005 0)
			(size 0 0)
			(layers "F.Cu" "F.Mask" "F.Paste")
			(net "RST_PERST_OCP_SFF_N")
		)
		(pad "2" smd circle
			(at 0.40005 0)
			(size 0 0)
			(layers "F.Cu" "F.Mask" "F.Paste")
			(net "RST_PERST_OCP_SFF_R_N")
		)
	)
	(footprint ""
		(layer "F.Cu")
		(at 295.642792 -346.866464 -90)
		(property "Reference" "PC151_2"
			(at 0 0 270)
			(layer "F.SilkS")
			(hide yes)
			(effects
				(font
					(size 1.27 1.27)
				)
			)
		)
		(property "Value" ""
			(at 0 0 270)
			(layer "F.Fab")
			(effects
				(font
					(size 1.27 1.27)
				)
			)
		)
		(duplicate_pad_numbers_are_jumpers no)
		(fp_line
			(start -0.7874 0.4064)
			(end -0.7874 -0.4064)
			(stroke
				(width 0.1524)
				(type default)
			)
			(layer "F.SilkS")
		)
		(fp_line
			(start 0.7874 0.4064)
			(end -0.7874 0.4064)
			(stroke
				(width 0.1524)
				(type default)
			)
			(layer "F.SilkS")
		)
		(fp_line
			(start -0.7874 -0.4064)
			(end 0.7874 -0.4064)
			(stroke
				(width 0.1524)
				(type default)
			)
			(layer "F.SilkS")
		)
		(fp_line
			(start 0.7874 -0.4064)
			(end 0.7874 0.4064)
			(stroke
				(width 0.1524)
				(type default)
			)
			(layer "F.SilkS")
		)
		(fp_line
			(start -0.67945 0.3048)
			(end -0.67945 -0.305054)
			(stroke
				(width 0.1)
				(type default)
			)
			(layer "F.Fab")
		)
		(fp_line
			(start -0.12065 0.3048)
			(end -0.67945 0.3048)
			(stroke
				(width 0.1)
				(type default)
			)
			(layer "F.Fab")
		)
		(fp_line
			(start 0.120396 0.3048)
			(end 0.120396 0.2794)
			(stroke
				(width 0.1)
				(type default)
			)
			(layer "F.Fab")
		)
		(fp_line
			(start 0.67945 0.3048)
			(end 0.120396 0.3048)
			(stroke
				(width 0.1)
				(type default)
			)
			(layer "F.Fab")
		)
		(fp_line
			(start -0.12065 0.2794)
			(end -0.12065 0.3048)
			(stroke
				(width 0.1)
				(type default)
			)
			(layer "F.Fab")
		)
		(fp_line
			(start 0.120396 0.2794)
			(end -0.12065 0.2794)
			(stroke
				(width 0.1)
				(type default)
			)
			(layer "F.Fab")
		)
		(fp_line
			(start -0.12065 -0.2794)
			(end 0.12065 -0.2794)
			(stroke
				(width 0.1)
				(type default)
			)
			(layer "F.Fab")
		)
		(fp_line
			(start 0.12065 -0.2794)
			(end 0.12065 -0.3048)
			(stroke
				(width 0.1)
				(type default)
			)
			(layer "F.Fab")
		)
		(fp_line
			(start 0.12065 -0.3048)
			(end 0.67945 -0.3048)
			(stroke
				(width 0.1)
				(type default)
			)
			(layer "F.Fab")
		)
		(fp_line
			(start 0.67945 -0.3048)
			(end 0.67945 0.3048)
			(stroke
				(width 0.1)
				(type default)
			)
			(layer "F.Fab")
		)
		(fp_line
			(start -0.67945 -0.305054)
			(end -0.12065 -0.305054)
			(stroke
				(width 0.1)
				(type default)
			)
			(layer "F.Fab")
		)
		(fp_line
			(start -0.12065 -0.305054)
			(end -0.12065 -0.2794)
			(stroke
				(width 0.1)
				(type default)
			)
			(layer "F.Fab")
		)
		(pad "1" smd circle
			(at -0.40005 0 270)
			(size 0 0)
			(layers "F.Cu" "F.Mask" "F.Paste")
			(net "SW_P12V_AUX_PVDDIO_P0_FLT")
		)
		(pad "2" smd circle
			(at 0.40005 0 270)
			(size 0 0)
			(layers "F.Cu" "F.Mask" "F.Paste")
			(net "GND")
		)
	)
	(footprint ""
		(layer "F.Cu")
		(at 246.245888 -293.13505 -90)
		(property "Reference" "PC6506"
			(at 0 0 270)
			(layer "F.SilkS")
			(hide yes)
			(effects
				(font
					(size 1.27 1.27)
				)
			)
		)
		(property "Value" ""
			(at 0 0 270)
			(layer "F.Fab")
			(effects
				(font
					(size 1.27 1.27)
				)
			)
		)
		(duplicate_pad_numbers_are_jumpers no)
		(fp_line
			(start -0.7874 0.4064)
			(end -0.7874 -0.4064)
			(stroke
				(width 0.1524)
				(type default)
			)
			(layer "F.SilkS")
		)
		(fp_line
			(start 0.7874 0.4064)
			(end -0.7874 0.4064)
			(stroke
				(width 0.1524)
				(type default)
			)
			(layer "F.SilkS")
		)
		(fp_line
			(start -0.7874 -0.4064)
			(end 0.7874 -0.4064)
			(stroke
				(width 0.1524)
				(type default)
			)
			(layer "F.SilkS")
		)
		(fp_line
			(start 0.7874 -0.4064)
			(end 0.7874 0.4064)
			(stroke
				(width 0.1524)
				(type default)
			)
			(layer "F.SilkS")
		)
		(fp_line
			(start -0.67945 0.3048)
			(end -0.67945 -0.305054)
			(stroke
				(width 0.1)
				(type default)
			)
			(layer "F.Fab")
		)
		(fp_line
			(start -0.12065 0.3048)
			(end -0.67945 0.3048)
			(stroke
				(width 0.1)
				(type default)
			)
			(layer "F.Fab")
		)
		(fp_line
			(start 0.120396 0.3048)
			(end 0.120396 0.2794)
			(stroke
				(width 0.1)
				(type default)
			)
			(layer "F.Fab")
		)
		(fp_line
			(start 0.67945 0.3048)
			(end 0.120396 0.3048)
			(stroke
				(width 0.1)
				(type default)
			)
			(layer "F.Fab")
		)
		(fp_line
			(start -0.12065 0.2794)
			(end -0.12065 0.3048)
			(stroke
				(width 0.1)
				(type default)
			)
			(layer "F.Fab")
		)
		(fp_line
			(start 0.120396 0.2794)
			(end -0.12065 0.2794)
			(stroke
				(width 0.1)
				(type default)
			)
			(layer "F.Fab")
		)
		(fp_line
			(start -0.12065 -0.2794)
			(end 0.12065 -0.2794)
			(stroke
				(width 0.1)
				(type default)
			)
			(layer "F.Fab")
		)
		(fp_line
			(start 0.12065 -0.2794)
			(end 0.12065 -0.3048)
			(stroke
				(width 0.1)
				(type default)
			)
			(layer "F.Fab")
		)
		(fp_line
			(start 0.12065 -0.3048)
			(end 0.67945 -0.3048)
			(stroke
				(width 0.1)
				(type default)
			)
			(layer "F.Fab")
		)
		(fp_line
			(start 0.67945 -0.3048)
			(end 0.67945 0.3048)
			(stroke
				(width 0.1)
				(type default)
			)
			(layer "F.Fab")
		)
		(fp_line
			(start -0.67945 -0.305054)
			(end -0.12065 -0.305054)
			(stroke
				(width 0.1)
				(type default)
			)
			(layer "F.Fab")
		)
		(fp_line
			(start -0.12065 -0.305054)
			(end -0.12065 -0.2794)
			(stroke
				(width 0.1)
				(type default)
			)
			(layer "F.Fab")
		)
		(pad "1" smd circle
			(at -0.40005 0 270)
			(size 0 0)
			(layers "F.Cu" "F.Mask" "F.Paste")
			(net "P1V8_RETIMER_CPU0_VCC")
		)
		(pad "2" smd circle
			(at 0.40005 0 270)
			(size 0 0)
			(layers "F.Cu" "F.Mask" "F.Paste")
			(net "GND")
		)
	)
	(footprint ""
		(layer "F.Cu")
		(at 339.70722 -337.689698 90)
		(property "Reference" "PC131"
			(at 0 0 90)
			(layer "F.SilkS")
			(hide yes)
			(effects
				(font
					(size 1.27 1.27)
				)
			)
		)
		(property "Value" ""
			(at 0 0 90)
			(layer "F.Fab")
			(effects
				(font
					(size 1.27 1.27)
				)
			)
		)
		(duplicate_pad_numbers_are_jumpers no)
		(fp_line
			(start 0.7874 -0.4064)
			(end 0.7874 0.4064)
			(stroke
				(width 0.1524)
				(type default)
			)
			(layer "F.SilkS")
		)
		(fp_line
			(start -0.7874 -0.4064)
			(end 0.7874 -0.4064)
			(stroke
				(width 0.1524)
				(type default)
			)
			(layer "F.SilkS")
		)
		(fp_line
			(start 0.7874 0.4064)
			(end 0.435102 0.4064)
			(stroke
				(width 0.1524)
				(type default)
			)
			(layer "F.SilkS")
		)
		(fp_line
			(start -0.174498 0.4064)
			(end -0.7874 0.4064)
			(stroke
				(width 0.1524)
				(type default)
			)
			(layer "F.SilkS")
		)
		(fp_line
			(start -0.7874 0.4064)
			(end -0.7874 -0.4064)
			(stroke
				(width 0.1524)
				(type default)
			)
			(layer "F.SilkS")
		)
		(fp_line
			(start -0.12065 -0.305054)
			(end -0.12065 -0.2794)
			(stroke
				(width 0.1)
				(type default)
			)
			(layer "F.Fab")
		)
		(fp_line
			(start -0.67945 -0.305054)
			(end -0.12065 -0.305054)
			(stroke
				(width 0.1)
				(type default)
			)
			(layer "F.Fab")
		)
		(fp_line
			(start 0.67945 -0.3048)
			(end 0.67945 0.3048)
			(stroke
				(width 0.1)
				(type default)
			)
			(layer "F.Fab")
		)
		(fp_line
			(start 0.12065 -0.3048)
			(end 0.67945 -0.3048)
			(stroke
				(width 0.1)
				(type default)
			)
			(layer "F.Fab")
		)
		(fp_line
			(start 0.12065 -0.2794)
			(end 0.12065 -0.3048)
			(stroke
				(width 0.1)
				(type default)
			)
			(layer "F.Fab")
		)
		(fp_line
			(start -0.12065 -0.2794)
			(end 0.12065 -0.2794)
			(stroke
				(width 0.1)
				(type default)
			)
			(layer "F.Fab")
		)
		(fp_line
			(start 0.120396 0.2794)
			(end -0.12065 0.2794)
			(stroke
				(width 0.1)
				(type default)
			)
			(layer "F.Fab")
		)
		(fp_line
			(start -0.12065 0.2794)
			(end -0.12065 0.3048)
			(stroke
				(width 0.1)
				(type default)
			)
			(layer "F.Fab")
		)
		(fp_line
			(start 0.67945 0.3048)
			(end 0.120396 0.3048)
			(stroke
				(width 0.1)
				(type default)
			)
			(layer "F.Fab")
		)
		(fp_line
			(start 0.120396 0.3048)
			(end 0.120396 0.2794)
			(stroke
				(width 0.1)
				(type default)
			)
			(layer "F.Fab")
		)
		(fp_line
			(start -0.12065 0.3048)
			(end -0.67945 0.3048)
			(stroke
				(width 0.1)
				(type default)
			)
			(layer "F.Fab")
		)
		(fp_line
			(start -0.67945 0.3048)
			(end -0.67945 -0.305054)
			(stroke
				(width 0.1)
				(type default)
			)
			(layer "F.Fab")
		)
		(pad "1" smd circle
			(at -0.40005 0 90)
			(size 0 0)
			(layers "F.Cu" "F.Mask" "F.Paste")
			(net "PVDDCR_CPU1_P0_VCC5")
		)
		(pad "2" smd circle
			(at 0.40005 0 90)
			(size 0 0)
			(layers "F.Cu" "F.Mask" "F.Paste")
			(net "GND")
		)
	)
	(footprint ""
		(layer "F.Cu")
		(at 27.559 -359.283)
		(property "Reference" "PC358"
			(at 0 0 0)
			(layer "F.SilkS")
			(hide yes)
			(effects
				(font
					(size 1.27 1.27)
				)
			)
		)
		(property "Value" ""
			(at 0 0 0)
			(layer "F.Fab")
			(effects
				(font
					(size 1.27 1.27)
				)
			)
		)
		(duplicate_pad_numbers_are_jumpers no)
		(fp_line
			(start -0.7874 -0.4064)
			(end 0.7874 -0.4064)
			(stroke
				(width 0.1524)
				(type default)
			)
			(layer "F.SilkS")
		)
		(fp_line
			(start -0.7874 0.4064)
			(end -0.7874 -0.4064)
			(stroke
				(width 0.1524)
				(type default)
			)
			(layer "F.SilkS")
		)
		(fp_line
			(start 0.7874 -0.4064)
			(end 0.7874 0.4064)
			(stroke
				(width 0.1524)
				(type default)
			)
			(layer "F.SilkS")
		)
		(fp_line
			(start 0.7874 0.4064)
			(end -0.7874 0.4064)
			(stroke
				(width 0.1524)
				(type default)
			)
			(layer "F.SilkS")
		)
		(fp_line
			(start -0.67945 -0.305054)
			(end -0.12065 -0.305054)
			(stroke
				(width 0.1)
				(type default)
			)
			(layer "F.Fab")
		)
		(fp_line
			(start -0.67945 0.3048)
			(end -0.67945 -0.305054)
			(stroke
				(width 0.1)
				(type default)
			)
			(layer "F.Fab")
		)
		(fp_line
			(start -0.12065 -0.305054)
			(end -0.12065 -0.2794)
			(stroke
				(width 0.1)
				(type default)
			)
			(layer "F.Fab")
		)
		(fp_line
			(start -0.12065 -0.2794)
			(end 0.12065 -0.2794)
			(stroke
				(width 0.1)
				(type default)
			)
			(layer "F.Fab")
		)
		(fp_line
			(start -0.12065 0.2794)
			(end -0.12065 0.3048)
			(stroke
				(width 0.1)
				(type default)
			)
			(layer "F.Fab")
		)
		(fp_line
			(start -0.12065 0.3048)
			(end -0.67945 0.3048)
			(stroke
				(width 0.1)
				(type default)
			)
			(layer "F.Fab")
		)
		(fp_line
			(start 0.120396 0.2794)
			(end -0.12065 0.2794)
			(stroke
				(width 0.1)
				(type default)
			)
			(layer "F.Fab")
		)
		(fp_line
			(start 0.120396 0.3048)
			(end 0.120396 0.2794)
			(stroke
				(width 0.1)
				(type default)
			)
			(layer "F.Fab")
		)
		(fp_line
			(start 0.12065 -0.3048)
			(end 0.67945 -0.3048)
			(stroke
				(width 0.1)
				(type default)
			)
			(layer "F.Fab")
		)
		(fp_line
			(start 0.12065 -0.2794)
			(end 0.12065 -0.3048)
			(stroke
				(width 0.1)
				(type default)
			)
			(layer "F.Fab")
		)
		(fp_line
			(start 0.67945 -0.3048)
			(end 0.67945 0.3048)
			(stroke
				(width 0.1)
				(type default)
			)
			(layer "F.Fab")
		)
		(fp_line
			(start 0.67945 0.3048)
			(end 0.120396 0.3048)
			(stroke
				(width 0.1)
				(type default)
			)
			(layer "F.Fab")
		)
		(pad "1" smd circle
			(at -0.40005 0)
			(size 0 0)
			(layers "F.Cu" "F.Mask" "F.Paste")
			(net "VSENSE_PVDDCR_CPU1_P1_VSEN0")
		)
		(pad "2" smd circle
			(at 0.40005 0)
			(size 0 0)
			(layers "F.Cu" "F.Mask" "F.Paste")
			(net "VSENSE_VSS_SENSE_C_P1")
		)
	)
	(footprint ""
		(layer "F.Cu")
		(at 407.685748 -16.100298 90)
		(property "Reference" "C1793"
			(at 0 0 90)
			(layer "F.SilkS")
			(hide yes)
			(effects
				(font
					(size 1.27 1.27)
				)
			)
		)
		(property "Value" ""
			(at 0 0 90)
			(layer "F.Fab")
			(effects
				(font
					(size 1.27 1.27)
				)
			)
		)
		(duplicate_pad_numbers_are_jumpers no)
		(fp_line
			(start 0.299974 -0.150114)
			(end 0.299974 0.150114)
			(stroke
				(width 0.1)
				(type default)
			)
			(layer "F.Fab")
		)
		(fp_line
			(start -0.299974 -0.150114)
			(end 0.299974 -0.150114)
			(stroke
				(width 0.1)
				(type default)
			)
			(layer "F.Fab")
		)
		(fp_line
			(start 0.299974 0.150114)
			(end -0.299974 0.150114)
			(stroke
				(width 0.1)
				(type default)
			)
			(layer "F.Fab")
		)
		(fp_line
			(start -0.299974 0.150114)
			(end -0.299974 -0.150114)
			(stroke
				(width 0.1)
				(type default)
			)
			(layer "F.Fab")
		)
		(pad "1" smd rect
			(at -0.2667 0 90)
			(size 0.3048 0.381)
			(layers "F.Cu" "F.Mask" "F.Paste")
			(net "P5E_CPU0_G3_TX_C_DP<9>")
		)
		(pad "2" smd rect
			(at 0.2667 0 90)
			(size 0.3048 0.381)
			(layers "F.Cu" "F.Mask" "F.Paste")
			(net "P5E_CPU0_G3_TX_DP<9>")
		)
	)
	(footprint ""
		(layer "F.Cu")
		(at 271.085056 -122.84837 180)
		(property "Reference" "R3711"
			(at 0 0 180)
			(layer "F.SilkS")
			(hide yes)
			(effects
				(font
					(size 1.27 1.27)
				)
			)
		)
		(property "Value" ""
			(at 0 0 180)
			(layer "F.Fab")
			(effects
				(font
					(size 1.27 1.27)
				)
			)
		)
		(duplicate_pad_numbers_are_jumpers no)
		(fp_line
			(start 0.7874 0.4064)
			(end -0.7874 0.4064)
			(stroke
				(width 0.1524)
				(type default)
			)
			(layer "F.SilkS")
		)
		(fp_line
			(start 0.7874 -0.4064)
			(end 0.7874 0.4064)
			(stroke
				(width 0.1524)
				(type default)
			)
			(layer "F.SilkS")
		)
		(fp_line
			(start -0.7874 0.4064)
			(end -0.7874 -0.4064)
			(stroke
				(width 0.1524)
				(type default)
			)
			(layer "F.SilkS")
		)
		(fp_line
			(start -0.7874 -0.4064)
			(end 0.7874 -0.4064)
			(stroke
				(width 0.1524)
				(type default)
			)
			(layer "F.SilkS")
		)
		(fp_line
			(start 0.67945 0.3048)
			(end 0.120396 0.3048)
			(stroke
				(width 0.1)
				(type default)
			)
			(layer "F.Fab")
		)
		(fp_line
			(start 0.67945 -0.3048)
			(end 0.67945 0.3048)
			(stroke
				(width 0.1)
				(type default)
			)
			(layer "F.Fab")
		)
		(fp_line
			(start 0.12065 -0.2794)
			(end 0.12065 -0.3048)
			(stroke
				(width 0.1)
				(type default)
			)
			(layer "F.Fab")
		)
		(fp_line
			(start 0.12065 -0.3048)
			(end 0.67945 -0.3048)
			(stroke
				(width 0.1)
				(type default)
			)
			(layer "F.Fab")
		)
		(fp_line
			(start 0.120396 0.3048)
			(end 0.120396 0.2794)
			(stroke
				(width 0.1)
				(type default)
			)
			(layer "F.Fab")
		)
		(fp_line
			(start 0.120396 0.2794)
			(end -0.12065 0.2794)
			(stroke
				(width 0.1)
				(type default)
			)
			(layer "F.Fab")
		)
		(fp_line
			(start -0.12065 0.3048)
			(end -0.67945 0.3048)
			(stroke
				(width 0.1)
				(type default)
			)
			(layer "F.Fab")
		)
		(fp_line
			(start -0.12065 0.2794)
			(end -0.12065 0.3048)
			(stroke
				(width 0.1)
				(type default)
			)
			(layer "F.Fab")
		)
		(fp_line
			(start -0.12065 -0.2794)
			(end 0.12065 -0.2794)
			(stroke
				(width 0.1)
				(type default)
			)
			(layer "F.Fab")
		)
		(fp_line
			(start -0.12065 -0.305054)
			(end -0.12065 -0.2794)
			(stroke
				(width 0.1)
				(type default)
			)
			(layer "F.Fab")
		)
		(fp_line
			(start -0.67945 0.3048)
			(end -0.67945 -0.305054)
			(stroke
				(width 0.1)
				(type default)
			)
			(layer "F.Fab")
		)
		(fp_line
			(start -0.67945 -0.305054)
			(end -0.12065 -0.305054)
			(stroke
				(width 0.1)
				(type default)
			)
			(layer "F.Fab")
		)
		(pad "1" smd circle
			(at -0.40005 0 180)
			(size 0 0)
			(layers "F.Cu" "F.Mask" "F.Paste")
			(net "SMB_VR_SENSOR_3V3AUX_SCL")
		)
		(pad "2" smd circle
			(at 0.40005 0 180)
			(size 0 0)
			(layers "F.Cu" "F.Mask" "F.Paste")
			(net "SMB_VR_SENSOR_3V3AUX_SCL_R")
		)
	)
	(footprint ""
		(layer "F.Cu")
		(at 78.401164 -408.517344 -90)
		(property "Reference" "C6650"
			(at 0 0 270)
			(layer "F.SilkS")
			(hide yes)
			(effects
				(font
					(size 1.27 1.27)
				)
			)
		)
		(property "Value" ""
			(at 0 0 270)
			(layer "F.Fab")
			(effects
				(font
					(size 1.27 1.27)
				)
			)
		)
		(duplicate_pad_numbers_are_jumpers no)
		(fp_line
			(start -0.299974 0.150114)
			(end -0.299974 -0.150114)
			(stroke
				(width 0.1)
				(type default)
			)
			(layer "F.Fab")
		)
		(fp_line
			(start 0.299974 0.150114)
			(end -0.299974 0.150114)
			(stroke
				(width 0.1)
				(type default)
			)
			(layer "F.Fab")
		)
		(fp_line
			(start -0.299974 -0.150114)
			(end 0.299974 -0.150114)
			(stroke
				(width 0.1)
				(type default)
			)
			(layer "F.Fab")
		)
		(fp_line
			(start 0.299974 -0.150114)
			(end 0.299974 0.150114)
			(stroke
				(width 0.1)
				(type default)
			)
			(layer "F.Fab")
		)
		(pad "1" smd rect
			(at -0.2667 0 270)
			(size 0.3048 0.381)
			(layers "F.Cu" "F.Mask" "F.Paste")
			(net "P5E_CPU1_P0_TX_BUF_C_DN<10>")
		)
		(pad "2" smd rect
			(at 0.2667 0 270)
			(size 0.3048 0.381)
			(layers "F.Cu" "F.Mask" "F.Paste")
			(net "P5E_CPU1_P0_TX_BUF_DN<10>")
		)
	)
	(footprint ""
		(layer "F.Cu")
		(at 368.324384 -14.394942)
		(property "Reference" "U104"
			(at -1.8034 -2.301748 0)
			(unlocked yes)
			(layer "F.SilkS")
			(effects
				(font
					(size 0.7874 0.5842)
					(thickness 0.1524)
				)
				(justify left)
			)
		)
		(property "Value" ""
			(at 0 0 0)
			(layer "F.Fab")
			(effects
				(font
					(size 1.27 1.27)
				)
			)
		)
		(duplicate_pad_numbers_are_jumpers no)
		(fp_line
			(start -1.733296 -1.549908)
			(end -1.733296 1.549908)
			(stroke
				(width 0.1524)
				(type default)
			)
			(layer "F.SilkS")
		)
		(fp_line
			(start -1.733296 1.549908)
			(end 1.733296 1.549908)
			(stroke
				(width 0.1524)
				(type default)
			)
			(layer "F.SilkS")
		)
		(fp_line
			(start -0.660908 -1.549908)
			(end -1.733296 -1.549908)
			(stroke
				(width 0.1524)
				(type default)
			)
			(layer "F.SilkS")
		)
		(fp_line
			(start 0 -0.889)
			(end -0.660908 -1.549908)
			(stroke
				(width 0.1524)
				(type default)
			)
			(layer "F.SilkS")
		)
		(fp_line
			(start 0.660908 -1.549908)
			(end 0 -0.889)
			(stroke
				(width 0.1524)
				(type default)
			)
			(layer "F.SilkS")
		)
		(fp_line
			(start 1.733296 -1.549908)
			(end 0.660908 -1.549908)
			(stroke
				(width 0.1524)
				(type default)
			)
			(layer "F.SilkS")
		)
		(fp_line
			(start 1.733296 1.549908)
			(end 1.733296 -1.549908)
			(stroke
				(width 0.1524)
				(type default)
			)
			(layer "F.SilkS")
		)
		(fp_poly
			(pts
				(xy -1.927606 -0.774954) (xy -2.419096 -0.49022) (xy -2.450338 -0.997204)
			)
			(stroke
				(width 0)
				(type default)
			)
			(fill yes)
			(layer "F.SilkS")
		)
		(fp_line
			(start -0.849884 -1.549908)
			(end -0.849884 1.549908)
			(stroke
				(width 0.1)
				(type default)
			)
			(layer "F.Fab")
		)
		(fp_line
			(start -0.849884 1.549908)
			(end 0.849884 1.549908)
			(stroke
				(width 0.1)
				(type default)
			)
			(layer "F.Fab")
		)
		(fp_line
			(start 0.849884 -1.549908)
			(end -0.849884 -1.549908)
			(stroke
				(width 0.1)
				(type default)
			)
			(layer "F.Fab")
		)
		(fp_line
			(start 0.849884 1.549908)
			(end 0.849884 -1.549908)
			(stroke
				(width 0.1)
				(type default)
			)
			(layer "F.Fab")
		)
		(fp_poly
			(pts
				(xy -2.4384 -1.20396) (xy -2.4384 -0.69596) (xy -1.9304 -0.94996)
			)
			(stroke
				(width 0)
				(type default)
			)
			(fill yes)
			(layer "F.Fab")
		)
		(pad "1" smd rect
			(at -1.199896 -0.94996 270)
			(size 0.5588 0.8128)
			(layers "F.Cu" "F.Mask" "F.Paste")
			(net "NC_U104_NC1")
		)
		(pad "2" smd rect
			(at -1.199896 0 270)
			(size 0.5588 0.8128)
			(layers "F.Cu" "F.Mask" "F.Paste")
			(net "FM_SYS_THROTTLE_N")
		)
		(pad "3" smd rect
			(at -1.199896 0.94996 270)
			(size 0.5588 0.8128)
			(layers "F.Cu" "F.Mask" "F.Paste")
			(net "GND")
		)
		(pad "4" smd rect
			(at 1.199896 0.94996 270)
			(size 0.5588 0.8128)
			(layers "F.Cu" "F.Mask" "F.Paste")
			(net "OCP_SFF_PWRBRK_BUFF_N")
		)
		(pad "5" smd rect
			(at 1.199896 -0.94996 270)
			(size 0.5588 0.8128)
			(layers "F.Cu" "F.Mask" "F.Paste")
			(net "P3V3_AUX")
		)
	)
	(footprint ""
		(layer "F.Cu")
		(at 157.15107 -74.75347 90)
		(property "Reference" "R6063"
			(at 0 0 90)
			(layer "F.SilkS")
			(hide yes)
			(effects
				(font
					(size 1.27 1.27)
				)
			)
		)
		(property "Value" ""
			(at 0 0 90)
			(layer "F.Fab")
			(effects
				(font
					(size 1.27 1.27)
				)
			)
		)
		(duplicate_pad_numbers_are_jumpers no)
		(fp_line
			(start 0.7874 -0.4064)
			(end 0.7874 0.4064)
			(stroke
				(width 0.1524)
				(type default)
			)
			(layer "F.SilkS")
		)
		(fp_line
			(start -0.7874 -0.4064)
			(end 0.7874 -0.4064)
			(stroke
				(width 0.1524)
				(type default)
			)
			(layer "F.SilkS")
		)
		(fp_line
			(start 0.7874 0.4064)
			(end -0.7874 0.4064)
			(stroke
				(width 0.1524)
				(type default)
			)
			(layer "F.SilkS")
		)
		(fp_line
			(start -0.7874 0.4064)
			(end -0.7874 -0.4064)
			(stroke
				(width 0.1524)
				(type default)
			)
			(layer "F.SilkS")
		)
		(fp_line
			(start -0.12065 -0.305054)
			(end -0.12065 -0.2794)
			(stroke
				(width 0.1)
				(type default)
			)
			(layer "F.Fab")
		)
		(fp_line
			(start -0.67945 -0.305054)
			(end -0.12065 -0.305054)
			(stroke
				(width 0.1)
				(type default)
			)
			(layer "F.Fab")
		)
		(fp_line
			(start 0.67945 -0.3048)
			(end 0.67945 0.3048)
			(stroke
				(width 0.1)
				(type default)
			)
			(layer "F.Fab")
		)
		(fp_line
			(start 0.12065 -0.3048)
			(end 0.67945 -0.3048)
			(stroke
				(width 0.1)
				(type default)
			)
			(layer "F.Fab")
		)
		(fp_line
			(start 0.12065 -0.2794)
			(end 0.12065 -0.3048)
			(stroke
				(width 0.1)
				(type default)
			)
			(layer "F.Fab")
		)
		(fp_line
			(start -0.12065 -0.2794)
			(end 0.12065 -0.2794)
			(stroke
				(width 0.1)
				(type default)
			)
			(layer "F.Fab")
		)
		(fp_line
			(start 0.120396 0.2794)
			(end -0.12065 0.2794)
			(stroke
				(width 0.1)
				(type default)
			)
			(layer "F.Fab")
		)
		(fp_line
			(start -0.12065 0.2794)
			(end -0.12065 0.3048)
			(stroke
				(width 0.1)
				(type default)
			)
			(layer "F.Fab")
		)
		(fp_line
			(start 0.67945 0.3048)
			(end 0.120396 0.3048)
			(stroke
				(width 0.1)
				(type default)
			)
			(layer "F.Fab")
		)
		(fp_line
			(start 0.120396 0.3048)
			(end 0.120396 0.2794)
			(stroke
				(width 0.1)
				(type default)
			)
			(layer "F.Fab")
		)
		(fp_line
			(start -0.12065 0.3048)
			(end -0.67945 0.3048)
			(stroke
				(width 0.1)
				(type default)
			)
			(layer "F.Fab")
		)
		(fp_line
			(start -0.67945 0.3048)
			(end -0.67945 -0.305054)
			(stroke
				(width 0.1)
				(type default)
			)
			(layer "F.Fab")
		)
		(pad "1" smd circle
			(at -0.40005 0 90)
			(size 0 0)
			(layers "F.Cu" "F.Mask" "F.Paste")
			(net "IRQ_OCP_V3_2_WAKE_BUF_N")
		)
		(pad "2" smd circle
			(at 0.40005 0 90)
			(size 0 0)
			(layers "F.Cu" "F.Mask" "F.Paste")
			(net "IRQ_LVC3_WAKE_N")
		)
	)
	(footprint ""
		(layer "F.Cu")
		(at 127.643128 -166.926768 -90)
		(property "Reference" "PR526"
			(at 0 0 270)
			(layer "F.SilkS")
			(hide yes)
			(effects
				(font
					(size 1.27 1.27)
				)
			)
		)
		(property "Value" ""
			(at 0 0 270)
			(layer "F.Fab")
			(effects
				(font
					(size 1.27 1.27)
				)
			)
		)
		(duplicate_pad_numbers_are_jumpers no)
		(fp_line
			(start -0.7874 0.4064)
			(end -0.7874 -0.4064)
			(stroke
				(width 0.1524)
				(type default)
			)
			(layer "F.SilkS")
		)
		(fp_line
			(start 0.7874 0.4064)
			(end -0.7874 0.4064)
			(stroke
				(width 0.1524)
				(type default)
			)
			(layer "F.SilkS")
		)
		(fp_line
			(start -0.7874 -0.4064)
			(end 0.7874 -0.4064)
			(stroke
				(width 0.1524)
				(type default)
			)
			(layer "F.SilkS")
		)
		(fp_line
			(start 0.7874 -0.4064)
			(end 0.7874 0.4064)
			(stroke
				(width 0.1524)
				(type default)
			)
			(layer "F.SilkS")
		)
		(fp_line
			(start -0.67945 0.3048)
			(end -0.67945 -0.305054)
			(stroke
				(width 0.1)
				(type default)
			)
			(layer "F.Fab")
		)
		(fp_line
			(start -0.12065 0.3048)
			(end -0.67945 0.3048)
			(stroke
				(width 0.1)
				(type default)
			)
			(layer "F.Fab")
		)
		(fp_line
			(start 0.120396 0.3048)
			(end 0.120396 0.2794)
			(stroke
				(width 0.1)
				(type default)
			)
			(layer "F.Fab")
		)
		(fp_line
			(start 0.67945 0.3048)
			(end 0.120396 0.3048)
			(stroke
				(width 0.1)
				(type default)
			)
			(layer "F.Fab")
		)
		(fp_line
			(start -0.12065 0.2794)
			(end -0.12065 0.3048)
			(stroke
				(width 0.1)
				(type default)
			)
			(layer "F.Fab")
		)
		(fp_line
			(start 0.120396 0.2794)
			(end -0.12065 0.2794)
			(stroke
				(width 0.1)
				(type default)
			)
			(layer "F.Fab")
		)
		(fp_line
			(start -0.12065 -0.2794)
			(end 0.12065 -0.2794)
			(stroke
				(width 0.1)
				(type default)
			)
			(layer "F.Fab")
		)
		(fp_line
			(start 0.12065 -0.2794)
			(end 0.12065 -0.3048)
			(stroke
				(width 0.1)
				(type default)
			)
			(layer "F.Fab")
		)
		(fp_line
			(start 0.12065 -0.3048)
			(end 0.67945 -0.3048)
			(stroke
				(width 0.1)
				(type default)
			)
			(layer "F.Fab")
		)
		(fp_line
			(start 0.67945 -0.3048)
			(end 0.67945 0.3048)
			(stroke
				(width 0.1)
				(type default)
			)
			(layer "F.Fab")
		)
		(fp_line
			(start -0.67945 -0.305054)
			(end -0.12065 -0.305054)
			(stroke
				(width 0.1)
				(type default)
			)
			(layer "F.Fab")
		)
		(fp_line
			(start -0.12065 -0.305054)
			(end -0.12065 -0.2794)
			(stroke
				(width 0.1)
				(type default)
			)
			(layer "F.Fab")
		)
		(pad "1" smd circle
			(at -0.40005 0 270)
			(size 0 0)
			(layers "F.Cu" "F.Mask" "F.Paste")
			(net "SW_PVDDCR_SOC_P1_SW2_RC")
		)
		(pad "2" smd circle
			(at 0.40005 0 270)
			(size 0 0)
			(layers "F.Cu" "F.Mask" "F.Paste")
			(net "GND")
		)
	)
	(footprint ""
		(layer "F.Cu")
		(at 256.442972 -101.74351 -90)
		(property "Reference" "C1514"
			(at 0 0 270)
			(layer "F.SilkS")
			(hide yes)
			(effects
				(font
					(size 1.27 1.27)
				)
			)
		)
		(property "Value" ""
			(at 0 0 270)
			(layer "F.Fab")
			(effects
				(font
					(size 1.27 1.27)
				)
			)
		)
		(duplicate_pad_numbers_are_jumpers no)
		(fp_line
			(start -0.7874 0.4064)
			(end -0.7874 -0.4064)
			(stroke
				(width 0.1524)
				(type default)
			)
			(layer "F.SilkS")
		)
		(fp_line
			(start 0.7874 0.4064)
			(end -0.7874 0.4064)
			(stroke
				(width 0.1524)
				(type default)
			)
			(layer "F.SilkS")
		)
		(fp_line
			(start -0.7874 -0.4064)
			(end 0.7874 -0.4064)
			(stroke
				(width 0.1524)
				(type default)
			)
			(layer "F.SilkS")
		)
		(fp_line
			(start 0.7874 -0.4064)
			(end 0.7874 0.4064)
			(stroke
				(width 0.1524)
				(type default)
			)
			(layer "F.SilkS")
		)
		(fp_line
			(start -0.67945 0.3048)
			(end -0.67945 -0.305054)
			(stroke
				(width 0.1)
				(type default)
			)
			(layer "F.Fab")
		)
		(fp_line
			(start -0.12065 0.3048)
			(end -0.67945 0.3048)
			(stroke
				(width 0.1)
				(type default)
			)
			(layer "F.Fab")
		)
		(fp_line
			(start 0.120396 0.3048)
			(end 0.120396 0.2794)
			(stroke
				(width 0.1)
				(type default)
			)
			(layer "F.Fab")
		)
		(fp_line
			(start 0.67945 0.3048)
			(end 0.120396 0.3048)
			(stroke
				(width 0.1)
				(type default)
			)
			(layer "F.Fab")
		)
		(fp_line
			(start -0.12065 0.2794)
			(end -0.12065 0.3048)
			(stroke
				(width 0.1)
				(type default)
			)
			(layer "F.Fab")
		)
		(fp_line
			(start 0.120396 0.2794)
			(end -0.12065 0.2794)
			(stroke
				(width 0.1)
				(type default)
			)
			(layer "F.Fab")
		)
		(fp_line
			(start -0.12065 -0.2794)
			(end 0.12065 -0.2794)
			(stroke
				(width 0.1)
				(type default)
			)
			(layer "F.Fab")
		)
		(fp_line
			(start 0.12065 -0.2794)
			(end 0.12065 -0.3048)
			(stroke
				(width 0.1)
				(type default)
			)
			(layer "F.Fab")
		)
		(fp_line
			(start 0.12065 -0.3048)
			(end 0.67945 -0.3048)
			(stroke
				(width 0.1)
				(type default)
			)
			(layer "F.Fab")
		)
		(fp_line
			(start 0.67945 -0.3048)
			(end 0.67945 0.3048)
			(stroke
				(width 0.1)
				(type default)
			)
			(layer "F.Fab")
		)
		(fp_line
			(start -0.67945 -0.305054)
			(end -0.12065 -0.305054)
			(stroke
				(width 0.1)
				(type default)
			)
			(layer "F.Fab")
		)
		(fp_line
			(start -0.12065 -0.305054)
			(end -0.12065 -0.2794)
			(stroke
				(width 0.1)
				(type default)
			)
			(layer "F.Fab")
		)
		(pad "1" smd circle
			(at -0.40005 0 270)
			(size 0 0)
			(layers "F.Cu" "F.Mask" "F.Paste")
			(net "PVDD18_S5_P0")
		)
		(pad "2" smd circle
			(at 0.40005 0 270)
			(size 0 0)
			(layers "F.Cu" "F.Mask" "F.Paste")
			(net "GND")
		)
	)
	(footprint ""
		(layer "F.Cu")
		(at 125.270514 -159.980884)
		(property "Reference" "PR208"
			(at 0 0 0)
			(layer "F.SilkS")
			(hide yes)
			(effects
				(font
					(size 1.27 1.27)
				)
			)
		)
		(property "Value" ""
			(at 0 0 0)
			(layer "F.Fab")
			(effects
				(font
					(size 1.27 1.27)
				)
			)
		)
		(duplicate_pad_numbers_are_jumpers no)
		(fp_line
			(start -0.7874 -0.4064)
			(end 0.7874 -0.4064)
			(stroke
				(width 0.1524)
				(type default)
			)
			(layer "F.SilkS")
		)
		(fp_line
			(start -0.7874 0.4064)
			(end -0.7874 -0.4064)
			(stroke
				(width 0.1524)
				(type default)
			)
			(layer "F.SilkS")
		)
		(fp_line
			(start 0.7874 -0.4064)
			(end 0.7874 0.4064)
			(stroke
				(width 0.1524)
				(type default)
			)
			(layer "F.SilkS")
		)
		(fp_line
			(start 0.7874 0.4064)
			(end -0.7874 0.4064)
			(stroke
				(width 0.1524)
				(type default)
			)
			(layer "F.SilkS")
		)
		(fp_line
			(start -0.67945 -0.305054)
			(end -0.12065 -0.305054)
			(stroke
				(width 0.1)
				(type default)
			)
			(layer "F.Fab")
		)
		(fp_line
			(start -0.67945 0.3048)
			(end -0.67945 -0.305054)
			(stroke
				(width 0.1)
				(type default)
			)
			(layer "F.Fab")
		)
		(fp_line
			(start -0.12065 -0.305054)
			(end -0.12065 -0.2794)
			(stroke
				(width 0.1)
				(type default)
			)
			(layer "F.Fab")
		)
		(fp_line
			(start -0.12065 -0.2794)
			(end 0.12065 -0.2794)
			(stroke
				(width 0.1)
				(type default)
			)
			(layer "F.Fab")
		)
		(fp_line
			(start -0.12065 0.2794)
			(end -0.12065 0.3048)
			(stroke
				(width 0.1)
				(type default)
			)
			(layer "F.Fab")
		)
		(fp_line
			(start -0.12065 0.3048)
			(end -0.67945 0.3048)
			(stroke
				(width 0.1)
				(type default)
			)
			(layer "F.Fab")
		)
		(fp_line
			(start 0.120396 0.2794)
			(end -0.12065 0.2794)
			(stroke
				(width 0.1)
				(type default)
			)
			(layer "F.Fab")
		)
		(fp_line
			(start 0.120396 0.3048)
			(end 0.120396 0.2794)
			(stroke
				(width 0.1)
				(type default)
			)
			(layer "F.Fab")
		)
		(fp_line
			(start 0.12065 -0.3048)
			(end 0.67945 -0.3048)
			(stroke
				(width 0.1)
				(type default)
			)
			(layer "F.Fab")
		)
		(fp_line
			(start 0.12065 -0.2794)
			(end 0.12065 -0.3048)
			(stroke
				(width 0.1)
				(type default)
			)
			(layer "F.Fab")
		)
		(fp_line
			(start 0.67945 -0.3048)
			(end 0.67945 0.3048)
			(stroke
				(width 0.1)
				(type default)
			)
			(layer "F.Fab")
		)
		(fp_line
			(start 0.67945 0.3048)
			(end 0.120396 0.3048)
			(stroke
				(width 0.1)
				(type default)
			)
			(layer "F.Fab")
		)
		(pad "1" smd circle
			(at -0.40005 0)
			(size 0 0)
			(layers "F.Cu" "F.Mask" "F.Paste")
			(net "GND")
		)
		(pad "2" smd circle
			(at 0.40005 0)
			(size 0 0)
			(layers "F.Cu" "F.Mask" "F.Paste")
			(net "PVDDCR_SOC_P1_LSET2")
		)
	)
	(footprint ""
		(layer "F.Cu")
		(at 211.992464 -26.868374 -90)
		(property "Reference" "C1274"
			(at 0 0 270)
			(layer "F.SilkS")
			(hide yes)
			(effects
				(font
					(size 1.27 1.27)
				)
			)
		)
		(property "Value" ""
			(at 0 0 270)
			(layer "F.Fab")
			(effects
				(font
					(size 1.27 1.27)
				)
			)
		)
		(duplicate_pad_numbers_are_jumpers no)
		(fp_line
			(start -0.7874 0.4064)
			(end -0.7874 -0.4064)
			(stroke
				(width 0.1524)
				(type default)
			)
			(layer "F.SilkS")
		)
		(fp_line
			(start 0.7874 0.4064)
			(end -0.7874 0.4064)
			(stroke
				(width 0.1524)
				(type default)
			)
			(layer "F.SilkS")
		)
		(fp_line
			(start -0.7874 -0.4064)
			(end 0.7874 -0.4064)
			(stroke
				(width 0.1524)
				(type default)
			)
			(layer "F.SilkS")
		)
		(fp_line
			(start 0.7874 -0.4064)
			(end 0.7874 0.4064)
			(stroke
				(width 0.1524)
				(type default)
			)
			(layer "F.SilkS")
		)
		(fp_line
			(start -0.67945 0.3048)
			(end -0.67945 -0.305054)
			(stroke
				(width 0.1)
				(type default)
			)
			(layer "F.Fab")
		)
		(fp_line
			(start -0.12065 0.3048)
			(end -0.67945 0.3048)
			(stroke
				(width 0.1)
				(type default)
			)
			(layer "F.Fab")
		)
		(fp_line
			(start 0.120396 0.3048)
			(end 0.120396 0.2794)
			(stroke
				(width 0.1)
				(type default)
			)
			(layer "F.Fab")
		)
		(fp_line
			(start 0.67945 0.3048)
			(end 0.120396 0.3048)
			(stroke
				(width 0.1)
				(type default)
			)
			(layer "F.Fab")
		)
		(fp_line
			(start -0.12065 0.2794)
			(end -0.12065 0.3048)
			(stroke
				(width 0.1)
				(type default)
			)
			(layer "F.Fab")
		)
		(fp_line
			(start 0.120396 0.2794)
			(end -0.12065 0.2794)
			(stroke
				(width 0.1)
				(type default)
			)
			(layer "F.Fab")
		)
		(fp_line
			(start -0.12065 -0.2794)
			(end 0.12065 -0.2794)
			(stroke
				(width 0.1)
				(type default)
			)
			(layer "F.Fab")
		)
		(fp_line
			(start 0.12065 -0.2794)
			(end 0.12065 -0.3048)
			(stroke
				(width 0.1)
				(type default)
			)
			(layer "F.Fab")
		)
		(fp_line
			(start 0.12065 -0.3048)
			(end 0.67945 -0.3048)
			(stroke
				(width 0.1)
				(type default)
			)
			(layer "F.Fab")
		)
		(fp_line
			(start 0.67945 -0.3048)
			(end 0.67945 0.3048)
			(stroke
				(width 0.1)
				(type default)
			)
			(layer "F.Fab")
		)
		(fp_line
			(start -0.67945 -0.305054)
			(end -0.12065 -0.305054)
			(stroke
				(width 0.1)
				(type default)
			)
			(layer "F.Fab")
		)
		(fp_line
			(start -0.12065 -0.305054)
			(end -0.12065 -0.2794)
			(stroke
				(width 0.1)
				(type default)
			)
			(layer "F.Fab")
		)
		(pad "1" smd circle
			(at -0.40005 0 270)
			(size 0 0)
			(layers "F.Cu" "F.Mask" "F.Paste")
			(net "P3V3_AUX")
		)
		(pad "2" smd circle
			(at 0.40005 0 270)
			(size 0 0)
			(layers "F.Cu" "F.Mask" "F.Paste")
			(net "GND")
		)
	)
	(footprint ""
		(layer "F.Cu")
		(at 325.49338 -394.82268 90)
		(property "Reference" "C505"
			(at 0 0 90)
			(layer "F.SilkS")
			(hide yes)
			(effects
				(font
					(size 1.27 1.27)
				)
			)
		)
		(property "Value" ""
			(at 0 0 90)
			(layer "F.Fab")
			(effects
				(font
					(size 1.27 1.27)
				)
			)
		)
		(duplicate_pad_numbers_are_jumpers no)
		(fp_line
			(start 0.7874 -0.4064)
			(end 0.7874 0.4064)
			(stroke
				(width 0.1524)
				(type default)
			)
			(layer "F.SilkS")
		)
		(fp_line
			(start -0.7874 -0.4064)
			(end 0.7874 -0.4064)
			(stroke
				(width 0.1524)
				(type default)
			)
			(layer "F.SilkS")
		)
		(fp_line
			(start 0.7874 0.4064)
			(end -0.7874 0.4064)
			(stroke
				(width 0.1524)
				(type default)
			)
			(layer "F.SilkS")
		)
		(fp_line
			(start -0.7874 0.4064)
			(end -0.7874 -0.4064)
			(stroke
				(width 0.1524)
				(type default)
			)
			(layer "F.SilkS")
		)
		(fp_line
			(start -0.12065 -0.305054)
			(end -0.12065 -0.2794)
			(stroke
				(width 0.1)
				(type default)
			)
			(layer "F.Fab")
		)
		(fp_line
			(start -0.67945 -0.305054)
			(end -0.12065 -0.305054)
			(stroke
				(width 0.1)
				(type default)
			)
			(layer "F.Fab")
		)
		(fp_line
			(start 0.67945 -0.3048)
			(end 0.67945 0.3048)
			(stroke
				(width 0.1)
				(type default)
			)
			(layer "F.Fab")
		)
		(fp_line
			(start 0.12065 -0.3048)
			(end 0.67945 -0.3048)
			(stroke
				(width 0.1)
				(type default)
			)
			(layer "F.Fab")
		)
		(fp_line
			(start 0.12065 -0.2794)
			(end 0.12065 -0.3048)
			(stroke
				(width 0.1)
				(type default)
			)
			(layer "F.Fab")
		)
		(fp_line
			(start -0.12065 -0.2794)
			(end 0.12065 -0.2794)
			(stroke
				(width 0.1)
				(type default)
			)
			(layer "F.Fab")
		)
		(fp_line
			(start 0.120396 0.2794)
			(end -0.12065 0.2794)
			(stroke
				(width 0.1)
				(type default)
			)
			(layer "F.Fab")
		)
		(fp_line
			(start -0.12065 0.2794)
			(end -0.12065 0.3048)
			(stroke
				(width 0.1)
				(type default)
			)
			(layer "F.Fab")
		)
		(fp_line
			(start 0.67945 0.3048)
			(end 0.120396 0.3048)
			(stroke
				(width 0.1)
				(type default)
			)
			(layer "F.Fab")
		)
		(fp_line
			(start 0.120396 0.3048)
			(end 0.120396 0.2794)
			(stroke
				(width 0.1)
				(type default)
			)
			(layer "F.Fab")
		)
		(fp_line
			(start -0.12065 0.3048)
			(end -0.67945 0.3048)
			(stroke
				(width 0.1)
				(type default)
			)
			(layer "F.Fab")
		)
		(fp_line
			(start -0.67945 0.3048)
			(end -0.67945 -0.305054)
			(stroke
				(width 0.1)
				(type default)
			)
			(layer "F.Fab")
		)
		(pad "1" smd circle
			(at -0.40005 0 90)
			(size 0 0)
			(layers "F.Cu" "F.Mask" "F.Paste")
			(net "P1V8_CPU0_RT0_1A")
		)
		(pad "2" smd circle
			(at 0.40005 0 90)
			(size 0 0)
			(layers "F.Cu" "F.Mask" "F.Paste")
			(net "GND")
		)
	)
	(footprint ""
		(layer "F.Cu")
		(at 95.39097 -61.87821)
		(property "Reference" "PR3812"
			(at 0 0 0)
			(layer "F.SilkS")
			(hide yes)
			(effects
				(font
					(size 1.27 1.27)
				)
			)
		)
		(property "Value" ""
			(at 0 0 0)
			(layer "F.Fab")
			(effects
				(font
					(size 1.27 1.27)
				)
			)
		)
		(duplicate_pad_numbers_are_jumpers no)
		(fp_line
			(start -0.7874 -0.4064)
			(end 0.7874 -0.4064)
			(stroke
				(width 0.1524)
				(type default)
			)
			(layer "F.SilkS")
		)
		(fp_line
			(start -0.7874 0.4064)
			(end -0.7874 -0.4064)
			(stroke
				(width 0.1524)
				(type default)
			)
			(layer "F.SilkS")
		)
		(fp_line
			(start 0.7874 -0.4064)
			(end 0.7874 0.4064)
			(stroke
				(width 0.1524)
				(type default)
			)
			(layer "F.SilkS")
		)
		(fp_line
			(start 0.7874 0.4064)
			(end -0.7874 0.4064)
			(stroke
				(width 0.1524)
				(type default)
			)
			(layer "F.SilkS")
		)
		(fp_line
			(start -0.67945 -0.305054)
			(end -0.12065 -0.305054)
			(stroke
				(width 0.1)
				(type default)
			)
			(layer "F.Fab")
		)
		(fp_line
			(start -0.67945 0.3048)
			(end -0.67945 -0.305054)
			(stroke
				(width 0.1)
				(type default)
			)
			(layer "F.Fab")
		)
		(fp_line
			(start -0.12065 -0.305054)
			(end -0.12065 -0.2794)
			(stroke
				(width 0.1)
				(type default)
			)
			(layer "F.Fab")
		)
		(fp_line
			(start -0.12065 -0.2794)
			(end 0.12065 -0.2794)
			(stroke
				(width 0.1)
				(type default)
			)
			(layer "F.Fab")
		)
		(fp_line
			(start -0.12065 0.2794)
			(end -0.12065 0.3048)
			(stroke
				(width 0.1)
				(type default)
			)
			(layer "F.Fab")
		)
		(fp_line
			(start -0.12065 0.3048)
			(end -0.67945 0.3048)
			(stroke
				(width 0.1)
				(type default)
			)
			(layer "F.Fab")
		)
		(fp_line
			(start 0.120396 0.2794)
			(end -0.12065 0.2794)
			(stroke
				(width 0.1)
				(type default)
			)
			(layer "F.Fab")
		)
		(fp_line
			(start 0.120396 0.3048)
			(end 0.120396 0.2794)
			(stroke
				(width 0.1)
				(type default)
			)
			(layer "F.Fab")
		)
		(fp_line
			(start 0.12065 -0.3048)
			(end 0.67945 -0.3048)
			(stroke
				(width 0.1)
				(type default)
			)
			(layer "F.Fab")
		)
		(fp_line
			(start 0.12065 -0.2794)
			(end 0.12065 -0.3048)
			(stroke
				(width 0.1)
				(type default)
			)
			(layer "F.Fab")
		)
		(fp_line
			(start 0.67945 -0.3048)
			(end 0.67945 0.3048)
			(stroke
				(width 0.1)
				(type default)
			)
			(layer "F.Fab")
		)
		(fp_line
			(start 0.67945 0.3048)
			(end 0.120396 0.3048)
			(stroke
				(width 0.1)
				(type default)
			)
			(layer "F.Fab")
		)
		(pad "1" smd circle
			(at -0.40005 0)
			(size 0 0)
			(layers "F.Cu" "F.Mask" "F.Paste")
			(net "P3V3_OCP_OV_2")
		)
		(pad "2" smd circle
			(at 0.40005 0)
			(size 0 0)
			(layers "F.Cu" "F.Mask" "F.Paste")
			(net "GND")
		)
	)
	(footprint ""
		(layer "F.Cu")
		(at 427.269656 -396.145004 180)
		(property "Reference" "R1050"
			(at 0 0 180)
			(layer "F.SilkS")
			(hide yes)
			(effects
				(font
					(size 1.27 1.27)
				)
			)
		)
		(property "Value" ""
			(at 0 0 180)
			(layer "F.Fab")
			(effects
				(font
					(size 1.27 1.27)
				)
			)
		)
		(duplicate_pad_numbers_are_jumpers no)
		(fp_line
			(start 0.7874 0.4064)
			(end -0.7874 0.4064)
			(stroke
				(width 0.1524)
				(type default)
			)
			(layer "F.SilkS")
		)
		(fp_line
			(start 0.7874 -0.4064)
			(end 0.7874 0.4064)
			(stroke
				(width 0.1524)
				(type default)
			)
			(layer "F.SilkS")
		)
		(fp_line
			(start -0.7874 0.4064)
			(end -0.7874 -0.4064)
			(stroke
				(width 0.1524)
				(type default)
			)
			(layer "F.SilkS")
		)
		(fp_line
			(start -0.7874 -0.4064)
			(end 0.7874 -0.4064)
			(stroke
				(width 0.1524)
				(type default)
			)
			(layer "F.SilkS")
		)
		(fp_line
			(start 0.67945 0.3048)
			(end 0.120396 0.3048)
			(stroke
				(width 0.1)
				(type default)
			)
			(layer "F.Fab")
		)
		(fp_line
			(start 0.67945 -0.3048)
			(end 0.67945 0.3048)
			(stroke
				(width 0.1)
				(type default)
			)
			(layer "F.Fab")
		)
		(fp_line
			(start 0.12065 -0.2794)
			(end 0.12065 -0.3048)
			(stroke
				(width 0.1)
				(type default)
			)
			(layer "F.Fab")
		)
		(fp_line
			(start 0.12065 -0.3048)
			(end 0.67945 -0.3048)
			(stroke
				(width 0.1)
				(type default)
			)
			(layer "F.Fab")
		)
		(fp_line
			(start 0.120396 0.3048)
			(end 0.120396 0.2794)
			(stroke
				(width 0.1)
				(type default)
			)
			(layer "F.Fab")
		)
		(fp_line
			(start 0.120396 0.2794)
			(end -0.12065 0.2794)
			(stroke
				(width 0.1)
				(type default)
			)
			(layer "F.Fab")
		)
		(fp_line
			(start -0.12065 0.3048)
			(end -0.67945 0.3048)
			(stroke
				(width 0.1)
				(type default)
			)
			(layer "F.Fab")
		)
		(fp_line
			(start -0.12065 0.2794)
			(end -0.12065 0.3048)
			(stroke
				(width 0.1)
				(type default)
			)
			(layer "F.Fab")
		)
		(fp_line
			(start -0.12065 -0.2794)
			(end 0.12065 -0.2794)
			(stroke
				(width 0.1)
				(type default)
			)
			(layer "F.Fab")
		)
		(fp_line
			(start -0.12065 -0.305054)
			(end -0.12065 -0.2794)
			(stroke
				(width 0.1)
				(type default)
			)
			(layer "F.Fab")
		)
		(fp_line
			(start -0.67945 0.3048)
			(end -0.67945 -0.305054)
			(stroke
				(width 0.1)
				(type default)
			)
			(layer "F.Fab")
		)
		(fp_line
			(start -0.67945 -0.305054)
			(end -0.12065 -0.305054)
			(stroke
				(width 0.1)
				(type default)
			)
			(layer "F.Fab")
		)
		(pad "1" smd rect
			(at -0.40005 0)
			(size 0.4572 0.508)
			(layers "F.Cu" "F.Mask" "F.Paste")
			(net "P1V8_CPU0_RT_1D")
		)
		(pad "2" smd rect
			(at 0.40005 0)
			(size 0.4572 0.508)
			(layers "F.Cu" "F.Mask" "F.Paste")
			(net "P1V8_CPU0_RT2_1A_1D")
		)
	)
	(footprint ""
		(layer "F.Cu")
		(at 35.57651 -351.932748)
		(property "Reference" "PR369"
			(at 0 0 0)
			(layer "F.SilkS")
			(hide yes)
			(effects
				(font
					(size 1.27 1.27)
				)
			)
		)
		(property "Value" ""
			(at 0 0 0)
			(layer "F.Fab")
			(effects
				(font
					(size 1.27 1.27)
				)
			)
		)
		(duplicate_pad_numbers_are_jumpers no)
		(fp_line
			(start -0.7874 -0.4064)
			(end 0.7874 -0.4064)
			(stroke
				(width 0.1524)
				(type default)
			)
			(layer "F.SilkS")
		)
		(fp_line
			(start -0.7874 0.4064)
			(end -0.7874 -0.4064)
			(stroke
				(width 0.1524)
				(type default)
			)
			(layer "F.SilkS")
		)
		(fp_line
			(start 0.7874 -0.4064)
			(end 0.7874 0.4064)
			(stroke
				(width 0.1524)
				(type default)
			)
			(layer "F.SilkS")
		)
		(fp_line
			(start 0.7874 0.4064)
			(end -0.7874 0.4064)
			(stroke
				(width 0.1524)
				(type default)
			)
			(layer "F.SilkS")
		)
		(fp_line
			(start -0.67945 -0.305054)
			(end -0.12065 -0.305054)
			(stroke
				(width 0.1)
				(type default)
			)
			(layer "F.Fab")
		)
		(fp_line
			(start -0.67945 0.3048)
			(end -0.67945 -0.305054)
			(stroke
				(width 0.1)
				(type default)
			)
			(layer "F.Fab")
		)
		(fp_line
			(start -0.12065 -0.305054)
			(end -0.12065 -0.2794)
			(stroke
				(width 0.1)
				(type default)
			)
			(layer "F.Fab")
		)
		(fp_line
			(start -0.12065 -0.2794)
			(end 0.12065 -0.2794)
			(stroke
				(width 0.1)
				(type default)
			)
			(layer "F.Fab")
		)
		(fp_line
			(start -0.12065 0.2794)
			(end -0.12065 0.3048)
			(stroke
				(width 0.1)
				(type default)
			)
			(layer "F.Fab")
		)
		(fp_line
			(start -0.12065 0.3048)
			(end -0.67945 0.3048)
			(stroke
				(width 0.1)
				(type default)
			)
			(layer "F.Fab")
		)
		(fp_line
			(start 0.120396 0.2794)
			(end -0.12065 0.2794)
			(stroke
				(width 0.1)
				(type default)
			)
			(layer "F.Fab")
		)
		(fp_line
			(start 0.120396 0.3048)
			(end 0.120396 0.2794)
			(stroke
				(width 0.1)
				(type default)
			)
			(layer "F.Fab")
		)
		(fp_line
			(start 0.12065 -0.3048)
			(end 0.67945 -0.3048)
			(stroke
				(width 0.1)
				(type default)
			)
			(layer "F.Fab")
		)
		(fp_line
			(start 0.12065 -0.2794)
			(end 0.12065 -0.3048)
			(stroke
				(width 0.1)
				(type default)
			)
			(layer "F.Fab")
		)
		(fp_line
			(start 0.67945 -0.3048)
			(end 0.67945 0.3048)
			(stroke
				(width 0.1)
				(type default)
			)
			(layer "F.Fab")
		)
		(fp_line
			(start 0.67945 0.3048)
			(end 0.120396 0.3048)
			(stroke
				(width 0.1)
				(type default)
			)
			(layer "F.Fab")
		)
		(pad "1" smd circle
			(at -0.40005 0)
			(size 0 0)
			(layers "F.Cu" "F.Mask" "F.Paste")
			(net "PVDDIO_P1_LSET3")
		)
		(pad "2" smd circle
			(at 0.40005 0)
			(size 0 0)
			(layers "F.Cu" "F.Mask" "F.Paste")
			(net "GND")
		)
	)
	(footprint ""
		(layer "F.Cu")
		(at 209.622136 -142.582138)
		(property "Reference" "Q54"
			(at -1.651 -2.25933 0)
			(unlocked yes)
			(layer "F.SilkS")
			(effects
				(font
					(size 0.7874 0.5842)
					(thickness 0.1524)
				)
				(justify left)
			)
		)
		(property "Value" ""
			(at 0 0 0)
			(layer "F.Fab")
			(effects
				(font
					(size 1.27 1.27)
				)
			)
		)
		(duplicate_pad_numbers_are_jumpers no)
		(fp_line
			(start -1.603248 -1.500124)
			(end 1.603248 -1.500124)
			(stroke
				(width 0.1524)
				(type default)
			)
			(layer "F.SilkS")
		)
		(fp_line
			(start -1.603248 1.500124)
			(end -1.603248 -1.500124)
			(stroke
				(width 0.1524)
				(type default)
			)
			(layer "F.SilkS")
		)
		(fp_line
			(start 1.603248 -1.500124)
			(end 1.603248 1.500124)
			(stroke
				(width 0.1524)
				(type default)
			)
			(layer "F.SilkS")
		)
		(fp_line
			(start 1.603248 1.500124)
			(end -1.603248 1.500124)
			(stroke
				(width 0.1524)
				(type default)
			)
			(layer "F.SilkS")
		)
		(fp_line
			(start -1.249934 -1.169924)
			(end -1.249934 -0.729996)
			(stroke
				(width 0.1)
				(type default)
			)
			(layer "F.Fab")
		)
		(fp_line
			(start -1.249934 -0.729996)
			(end -0.6985 -0.729996)
			(stroke
				(width 0.1)
				(type default)
			)
			(layer "F.Fab")
		)
		(fp_line
			(start -1.249934 0.729996)
			(end -1.249934 1.169924)
			(stroke
				(width 0.1)
				(type default)
			)
			(layer "F.Fab")
		)
		(fp_line
			(start -1.249934 1.169924)
			(end -0.700024 1.169924)
			(stroke
				(width 0.1)
				(type default)
			)
			(layer "F.Fab")
		)
		(fp_line
			(start -0.700024 -1.500124)
			(end -0.700024 -1.169924)
			(stroke
				(width 0.1)
				(type default)
			)
			(layer "F.Fab")
		)
		(fp_line
			(start -0.700024 -1.169924)
			(end -1.249934 -1.169924)
			(stroke
				(width 0.1)
				(type default)
			)
			(layer "F.Fab")
		)
		(fp_line
			(start -0.700024 1.169924)
			(end -0.700024 1.500124)
			(stroke
				(width 0.1)
				(type default)
			)
			(layer "F.Fab")
		)
		(fp_line
			(start -0.700024 1.500124)
			(end 0.700024 1.500124)
			(stroke
				(width 0.1)
				(type default)
			)
			(layer "F.Fab")
		)
		(fp_line
			(start -0.6985 -0.729996)
			(end -0.6985 0.729996)
			(stroke
				(width 0.1)
				(type default)
			)
			(layer "F.Fab")
		)
		(fp_line
			(start -0.6985 0.729996)
			(end -1.249934 0.729996)
			(stroke
				(width 0.1)
				(type default)
			)
			(layer "F.Fab")
		)
		(fp_line
			(start 0.700024 -1.500124)
			(end -0.700024 -1.500124)
			(stroke
				(width 0.1)
				(type default)
			)
			(layer "F.Fab")
		)
		(fp_line
			(start 0.700024 -0.219964)
			(end 0.700024 -1.500124)
			(stroke
				(width 0.1)
				(type default)
			)
			(layer "F.Fab")
		)
		(fp_line
			(start 0.700024 0.219964)
			(end 1.249934 0.219964)
			(stroke
				(width 0.1)
				(type default)
			)
			(layer "F.Fab")
		)
		(fp_line
			(start 0.700024 1.500124)
			(end 0.700024 0.219964)
			(stroke
				(width 0.1)
				(type default)
			)
			(layer "F.Fab")
		)
		(fp_line
			(start 1.249934 -0.219964)
			(end 0.700024 -0.219964)
			(stroke
				(width 0.1)
				(type default)
			)
			(layer "F.Fab")
		)
		(fp_line
			(start 1.249934 0.219964)
			(end 1.249934 -0.219964)
			(stroke
				(width 0.1)
				(type default)
			)
			(layer "F.Fab")
		)
		(fp_rect
			(start -0.700024 1.500124)
			(end 0.700024 -1.500124)
			(stroke
				(width 0)
				(type default)
			)
			(fill no)
			(layer "F.Fab")
		)
		(pad "D" smd rect
			(at 0.999998 0 270)
			(size 0.8128 0.9144)
			(layers "F.Cu" "F.Mask" "F.Paste")
			(net "P12V_AUX_BLEEDING")
		)
		(pad "G" smd rect
			(at -0.999998 -0.94996 270)
			(size 0.8128 0.9144)
			(layers "F.Cu" "F.Mask" "F.Paste")
			(net "FM_P12V_HSC_EN_R_N")
		)
		(pad "S" smd rect
			(at -0.999998 0.94996 270)
			(size 0.8128 0.9144)
			(layers "F.Cu" "F.Mask" "F.Paste")
			(net "GND")
		)
	)
	(footprint ""
		(layer "F.Cu")
		(at 208.894426 -108.545376 180)
		(property "Reference" "R6046"
			(at 0 0 180)
			(layer "F.SilkS")
			(hide yes)
			(effects
				(font
					(size 1.27 1.27)
				)
			)
		)
		(property "Value" ""
			(at 0 0 180)
			(layer "F.Fab")
			(effects
				(font
					(size 1.27 1.27)
				)
			)
		)
		(duplicate_pad_numbers_are_jumpers no)
		(fp_line
			(start 0.7874 0.4064)
			(end -0.7874 0.4064)
			(stroke
				(width 0.1524)
				(type default)
			)
			(layer "F.SilkS")
		)
		(fp_line
			(start 0.7874 -0.4064)
			(end 0.7874 0.4064)
			(stroke
				(width 0.1524)
				(type default)
			)
			(layer "F.SilkS")
		)
		(fp_line
			(start -0.7874 0.4064)
			(end -0.7874 -0.4064)
			(stroke
				(width 0.1524)
				(type default)
			)
			(layer "F.SilkS")
		)
		(fp_line
			(start -0.7874 -0.4064)
			(end 0.7874 -0.4064)
			(stroke
				(width 0.1524)
				(type default)
			)
			(layer "F.SilkS")
		)
		(fp_line
			(start 0.67945 0.3048)
			(end 0.120396 0.3048)
			(stroke
				(width 0.1)
				(type default)
			)
			(layer "F.Fab")
		)
		(fp_line
			(start 0.67945 -0.3048)
			(end 0.67945 0.3048)
			(stroke
				(width 0.1)
				(type default)
			)
			(layer "F.Fab")
		)
		(fp_line
			(start 0.12065 -0.2794)
			(end 0.12065 -0.3048)
			(stroke
				(width 0.1)
				(type default)
			)
			(layer "F.Fab")
		)
		(fp_line
			(start 0.12065 -0.3048)
			(end 0.67945 -0.3048)
			(stroke
				(width 0.1)
				(type default)
			)
			(layer "F.Fab")
		)
		(fp_line
			(start 0.120396 0.3048)
			(end 0.120396 0.2794)
			(stroke
				(width 0.1)
				(type default)
			)
			(layer "F.Fab")
		)
		(fp_line
			(start 0.120396 0.2794)
			(end -0.12065 0.2794)
			(stroke
				(width 0.1)
				(type default)
			)
			(layer "F.Fab")
		)
		(fp_line
			(start -0.12065 0.3048)
			(end -0.67945 0.3048)
			(stroke
				(width 0.1)
				(type default)
			)
			(layer "F.Fab")
		)
		(fp_line
			(start -0.12065 0.2794)
			(end -0.12065 0.3048)
			(stroke
				(width 0.1)
				(type default)
			)
			(layer "F.Fab")
		)
		(fp_line
			(start -0.12065 -0.2794)
			(end 0.12065 -0.2794)
			(stroke
				(width 0.1)
				(type default)
			)
			(layer "F.Fab")
		)
		(fp_line
			(start -0.12065 -0.305054)
			(end -0.12065 -0.2794)
			(stroke
				(width 0.1)
				(type default)
			)
			(layer "F.Fab")
		)
		(fp_line
			(start -0.67945 0.3048)
			(end -0.67945 -0.305054)
			(stroke
				(width 0.1)
				(type default)
			)
			(layer "F.Fab")
		)
		(fp_line
			(start -0.67945 -0.305054)
			(end -0.12065 -0.305054)
			(stroke
				(width 0.1)
				(type default)
			)
			(layer "F.Fab")
		)
		(pad "1" smd circle
			(at -0.40005 0 180)
			(size 0 0)
			(layers "F.Cu" "F.Mask" "F.Paste")
			(net "HP_LVC3_OCP_SFF_PRSNT2_PLD_N")
		)
		(pad "2" smd circle
			(at 0.40005 0 180)
			(size 0 0)
			(layers "F.Cu" "F.Mask" "F.Paste")
			(net "PRSNT_OCP_SFF_N")
		)
	)
	(footprint ""
		(layer "F.Cu")
		(at 305.082448 -149.210522 180)
		(property "Reference" "R5015"
			(at 0 0 180)
			(layer "F.SilkS")
			(hide yes)
			(effects
				(font
					(size 1.27 1.27)
				)
			)
		)
		(property "Value" ""
			(at 0 0 180)
			(layer "F.Fab")
			(effects
				(font
					(size 1.27 1.27)
				)
			)
		)
		(duplicate_pad_numbers_are_jumpers no)
		(fp_line
			(start 0.7874 0.4064)
			(end -0.7874 0.4064)
			(stroke
				(width 0.1524)
				(type default)
			)
			(layer "F.SilkS")
		)
		(fp_line
			(start 0.7874 -0.4064)
			(end 0.7874 0.4064)
			(stroke
				(width 0.1524)
				(type default)
			)
			(layer "F.SilkS")
		)
		(fp_line
			(start -0.7874 0.4064)
			(end -0.7874 -0.4064)
			(stroke
				(width 0.1524)
				(type default)
			)
			(layer "F.SilkS")
		)
		(fp_line
			(start -0.7874 -0.4064)
			(end 0.7874 -0.4064)
			(stroke
				(width 0.1524)
				(type default)
			)
			(layer "F.SilkS")
		)
		(fp_line
			(start 0.67945 0.3048)
			(end 0.120396 0.3048)
			(stroke
				(width 0.1)
				(type default)
			)
			(layer "F.Fab")
		)
		(fp_line
			(start 0.67945 -0.3048)
			(end 0.67945 0.3048)
			(stroke
				(width 0.1)
				(type default)
			)
			(layer "F.Fab")
		)
		(fp_line
			(start 0.12065 -0.2794)
			(end 0.12065 -0.3048)
			(stroke
				(width 0.1)
				(type default)
			)
			(layer "F.Fab")
		)
		(fp_line
			(start 0.12065 -0.3048)
			(end 0.67945 -0.3048)
			(stroke
				(width 0.1)
				(type default)
			)
			(layer "F.Fab")
		)
		(fp_line
			(start 0.120396 0.3048)
			(end 0.120396 0.2794)
			(stroke
				(width 0.1)
				(type default)
			)
			(layer "F.Fab")
		)
		(fp_line
			(start 0.120396 0.2794)
			(end -0.12065 0.2794)
			(stroke
				(width 0.1)
				(type default)
			)
			(layer "F.Fab")
		)
		(fp_line
			(start -0.12065 0.3048)
			(end -0.67945 0.3048)
			(stroke
				(width 0.1)
				(type default)
			)
			(layer "F.Fab")
		)
		(fp_line
			(start -0.12065 0.2794)
			(end -0.12065 0.3048)
			(stroke
				(width 0.1)
				(type default)
			)
			(layer "F.Fab")
		)
		(fp_line
			(start -0.12065 -0.2794)
			(end 0.12065 -0.2794)
			(stroke
				(width 0.1)
				(type default)
			)
			(layer "F.Fab")
		)
		(fp_line
			(start -0.12065 -0.305054)
			(end -0.12065 -0.2794)
			(stroke
				(width 0.1)
				(type default)
			)
			(layer "F.Fab")
		)
		(fp_line
			(start -0.67945 0.3048)
			(end -0.67945 -0.305054)
			(stroke
				(width 0.1)
				(type default)
			)
			(layer "F.Fab")
		)
		(fp_line
			(start -0.67945 -0.305054)
			(end -0.12065 -0.305054)
			(stroke
				(width 0.1)
				(type default)
			)
			(layer "F.Fab")
		)
		(pad "1" smd circle
			(at -0.40005 0 180)
			(size 0 0)
			(layers "F.Cu" "F.Mask" "F.Paste")
			(net "PVDD11_S3_P0")
		)
		(pad "2" smd circle
			(at 0.40005 0 180)
			(size 0 0)
			(layers "F.Cu" "F.Mask" "F.Paste")
			(net "I3C_SCM_0_R_SDA")
		)
	)
	(footprint ""
		(layer "F.Cu")
		(at 399.362168 -322.930012 180)
		(property "Reference" "R465"
			(at 0 0 180)
			(layer "F.SilkS")
			(hide yes)
			(effects
				(font
					(size 1.27 1.27)
				)
			)
		)
		(property "Value" ""
			(at 0 0 180)
			(layer "F.Fab")
			(effects
				(font
					(size 1.27 1.27)
				)
			)
		)
		(duplicate_pad_numbers_are_jumpers no)
		(fp_line
			(start 0.7874 0.4064)
			(end -0.7874 0.4064)
			(stroke
				(width 0.1524)
				(type default)
			)
			(layer "F.SilkS")
		)
		(fp_line
			(start 0.7874 -0.4064)
			(end 0.7874 0.4064)
			(stroke
				(width 0.1524)
				(type default)
			)
			(layer "F.SilkS")
		)
		(fp_line
			(start -0.7874 0.4064)
			(end -0.7874 -0.4064)
			(stroke
				(width 0.1524)
				(type default)
			)
			(layer "F.SilkS")
		)
		(fp_line
			(start -0.7874 -0.4064)
			(end 0.7874 -0.4064)
			(stroke
				(width 0.1524)
				(type default)
			)
			(layer "F.SilkS")
		)
		(fp_line
			(start 0.67945 0.3048)
			(end 0.120396 0.3048)
			(stroke
				(width 0.1)
				(type default)
			)
			(layer "F.Fab")
		)
		(fp_line
			(start 0.67945 -0.3048)
			(end 0.67945 0.3048)
			(stroke
				(width 0.1)
				(type default)
			)
			(layer "F.Fab")
		)
		(fp_line
			(start 0.12065 -0.2794)
			(end 0.12065 -0.3048)
			(stroke
				(width 0.1)
				(type default)
			)
			(layer "F.Fab")
		)
		(fp_line
			(start 0.12065 -0.3048)
			(end 0.67945 -0.3048)
			(stroke
				(width 0.1)
				(type default)
			)
			(layer "F.Fab")
		)
		(fp_line
			(start 0.120396 0.3048)
			(end 0.120396 0.2794)
			(stroke
				(width 0.1)
				(type default)
			)
			(layer "F.Fab")
		)
		(fp_line
			(start 0.120396 0.2794)
			(end -0.12065 0.2794)
			(stroke
				(width 0.1)
				(type default)
			)
			(layer "F.Fab")
		)
		(fp_line
			(start -0.12065 0.3048)
			(end -0.67945 0.3048)
			(stroke
				(width 0.1)
				(type default)
			)
			(layer "F.Fab")
		)
		(fp_line
			(start -0.12065 0.2794)
			(end -0.12065 0.3048)
			(stroke
				(width 0.1)
				(type default)
			)
			(layer "F.Fab")
		)
		(fp_line
			(start -0.12065 -0.2794)
			(end 0.12065 -0.2794)
			(stroke
				(width 0.1)
				(type default)
			)
			(layer "F.Fab")
		)
		(fp_line
			(start -0.12065 -0.305054)
			(end -0.12065 -0.2794)
			(stroke
				(width 0.1)
				(type default)
			)
			(layer "F.Fab")
		)
		(fp_line
			(start -0.67945 0.3048)
			(end -0.67945 -0.305054)
			(stroke
				(width 0.1)
				(type default)
			)
			(layer "F.Fab")
		)
		(fp_line
			(start -0.67945 -0.305054)
			(end -0.12065 -0.305054)
			(stroke
				(width 0.1)
				(type default)
			)
			(layer "F.Fab")
		)
		(pad "1" smd circle
			(at -0.40005 0 180)
			(size 0 0)
			(layers "F.Cu" "F.Mask" "F.Paste")
			(net "SPI_CPU0_D1")
		)
		(pad "2" smd circle
			(at 0.40005 0 180)
			(size 0 0)
			(layers "F.Cu" "F.Mask" "F.Paste")
			(net "SPI_CPU0_R_D1")
		)
	)
	(footprint ""
		(layer "F.Cu")
		(at 353.900232 -256.505202)
		(property "Reference" "C3897"
			(at 0 0 0)
			(layer "F.SilkS")
			(hide yes)
			(effects
				(font
					(size 1.27 1.27)
				)
			)
		)
		(property "Value" ""
			(at 0 0 0)
			(layer "F.Fab")
			(effects
				(font
					(size 1.27 1.27)
				)
			)
		)
		(duplicate_pad_numbers_are_jumpers no)
		(fp_line
			(start -0.7874 -0.4064)
			(end 0.7874 -0.4064)
			(stroke
				(width 0.1524)
				(type default)
			)
			(layer "F.SilkS")
		)
		(fp_line
			(start -0.7874 0.4064)
			(end -0.7874 -0.4064)
			(stroke
				(width 0.1524)
				(type default)
			)
			(layer "F.SilkS")
		)
		(fp_line
			(start 0.7874 -0.4064)
			(end 0.7874 0.4064)
			(stroke
				(width 0.1524)
				(type default)
			)
			(layer "F.SilkS")
		)
		(fp_line
			(start 0.7874 0.4064)
			(end -0.7874 0.4064)
			(stroke
				(width 0.1524)
				(type default)
			)
			(layer "F.SilkS")
		)
		(fp_line
			(start -0.67945 -0.305054)
			(end -0.12065 -0.305054)
			(stroke
				(width 0.1)
				(type default)
			)
			(layer "F.Fab")
		)
		(fp_line
			(start -0.67945 0.3048)
			(end -0.67945 -0.305054)
			(stroke
				(width 0.1)
				(type default)
			)
			(layer "F.Fab")
		)
		(fp_line
			(start -0.12065 -0.305054)
			(end -0.12065 -0.2794)
			(stroke
				(width 0.1)
				(type default)
			)
			(layer "F.Fab")
		)
		(fp_line
			(start -0.12065 -0.2794)
			(end 0.12065 -0.2794)
			(stroke
				(width 0.1)
				(type default)
			)
			(layer "F.Fab")
		)
		(fp_line
			(start -0.12065 0.2794)
			(end -0.12065 0.3048)
			(stroke
				(width 0.1)
				(type default)
			)
			(layer "F.Fab")
		)
		(fp_line
			(start -0.12065 0.3048)
			(end -0.67945 0.3048)
			(stroke
				(width 0.1)
				(type default)
			)
			(layer "F.Fab")
		)
		(fp_line
			(start 0.120396 0.2794)
			(end -0.12065 0.2794)
			(stroke
				(width 0.1)
				(type default)
			)
			(layer "F.Fab")
		)
		(fp_line
			(start 0.120396 0.3048)
			(end 0.120396 0.2794)
			(stroke
				(width 0.1)
				(type default)
			)
			(layer "F.Fab")
		)
		(fp_line
			(start 0.12065 -0.3048)
			(end 0.67945 -0.3048)
			(stroke
				(width 0.1)
				(type default)
			)
			(layer "F.Fab")
		)
		(fp_line
			(start 0.12065 -0.2794)
			(end 0.12065 -0.3048)
			(stroke
				(width 0.1)
				(type default)
			)
			(layer "F.Fab")
		)
		(fp_line
			(start 0.67945 -0.3048)
			(end 0.67945 0.3048)
			(stroke
				(width 0.1)
				(type default)
			)
			(layer "F.Fab")
		)
		(fp_line
			(start 0.67945 0.3048)
			(end 0.120396 0.3048)
			(stroke
				(width 0.1)
				(type default)
			)
			(layer "F.Fab")
		)
		(pad "1" smd circle
			(at -0.40005 0)
			(size 0 0)
			(layers "F.Cu" "F.Mask" "F.Paste")
			(net "PVDD18_S5_P0")
		)
		(pad "2" smd circle
			(at 0.40005 0)
			(size 0 0)
			(layers "F.Cu" "F.Mask" "F.Paste")
			(net "GND")
		)
	)
	(footprint ""
		(layer "F.Cu")
		(at 66.731896 -333.26578 90)
		(property "Reference" "PR516"
			(at 0 0 90)
			(layer "F.SilkS")
			(hide yes)
			(effects
				(font
					(size 1.27 1.27)
				)
			)
		)
		(property "Value" ""
			(at 0 0 90)
			(layer "F.Fab")
			(effects
				(font
					(size 1.27 1.27)
				)
			)
		)
		(duplicate_pad_numbers_are_jumpers no)
		(fp_line
			(start 0.7874 -0.4064)
			(end 0.7874 0.4064)
			(stroke
				(width 0.1524)
				(type default)
			)
			(layer "F.SilkS")
		)
		(fp_line
			(start -0.7874 -0.4064)
			(end 0.7874 -0.4064)
			(stroke
				(width 0.1524)
				(type default)
			)
			(layer "F.SilkS")
		)
		(fp_line
			(start 0.7874 0.4064)
			(end -0.7874 0.4064)
			(stroke
				(width 0.1524)
				(type default)
			)
			(layer "F.SilkS")
		)
		(fp_line
			(start -0.7874 0.4064)
			(end -0.7874 -0.4064)
			(stroke
				(width 0.1524)
				(type default)
			)
			(layer "F.SilkS")
		)
		(fp_line
			(start -0.12065 -0.305054)
			(end -0.12065 -0.2794)
			(stroke
				(width 0.1)
				(type default)
			)
			(layer "F.Fab")
		)
		(fp_line
			(start -0.67945 -0.305054)
			(end -0.12065 -0.305054)
			(stroke
				(width 0.1)
				(type default)
			)
			(layer "F.Fab")
		)
		(fp_line
			(start 0.67945 -0.3048)
			(end 0.67945 0.3048)
			(stroke
				(width 0.1)
				(type default)
			)
			(layer "F.Fab")
		)
		(fp_line
			(start 0.12065 -0.3048)
			(end 0.67945 -0.3048)
			(stroke
				(width 0.1)
				(type default)
			)
			(layer "F.Fab")
		)
		(fp_line
			(start 0.12065 -0.2794)
			(end 0.12065 -0.3048)
			(stroke
				(width 0.1)
				(type default)
			)
			(layer "F.Fab")
		)
		(fp_line
			(start -0.12065 -0.2794)
			(end 0.12065 -0.2794)
			(stroke
				(width 0.1)
				(type default)
			)
			(layer "F.Fab")
		)
		(fp_line
			(start 0.120396 0.2794)
			(end -0.12065 0.2794)
			(stroke
				(width 0.1)
				(type default)
			)
			(layer "F.Fab")
		)
		(fp_line
			(start -0.12065 0.2794)
			(end -0.12065 0.3048)
			(stroke
				(width 0.1)
				(type default)
			)
			(layer "F.Fab")
		)
		(fp_line
			(start 0.67945 0.3048)
			(end 0.120396 0.3048)
			(stroke
				(width 0.1)
				(type default)
			)
			(layer "F.Fab")
		)
		(fp_line
			(start 0.120396 0.3048)
			(end 0.120396 0.2794)
			(stroke
				(width 0.1)
				(type default)
			)
			(layer "F.Fab")
		)
		(fp_line
			(start -0.12065 0.3048)
			(end -0.67945 0.3048)
			(stroke
				(width 0.1)
				(type default)
			)
			(layer "F.Fab")
		)
		(fp_line
			(start -0.67945 0.3048)
			(end -0.67945 -0.305054)
			(stroke
				(width 0.1)
				(type default)
			)
			(layer "F.Fab")
		)
		(pad "1" smd circle
			(at -0.40005 0 90)
			(size 0 0)
			(layers "F.Cu" "F.Mask" "F.Paste")
			(net "SW_PVDDCR_CPU1_P1_SW3_RC")
		)
		(pad "2" smd circle
			(at 0.40005 0 90)
			(size 0 0)
			(layers "F.Cu" "F.Mask" "F.Paste")
			(net "GND")
		)
	)
	(footprint ""
		(layer "F.Cu")
		(at 120.396 -425.704 180)
		(property "Reference" "R3454"
			(at 0 0 180)
			(layer "F.SilkS")
			(hide yes)
			(effects
				(font
					(size 1.27 1.27)
				)
			)
		)
		(property "Value" ""
			(at 0 0 180)
			(layer "F.Fab")
			(effects
				(font
					(size 1.27 1.27)
				)
			)
		)
		(duplicate_pad_numbers_are_jumpers no)
		(fp_line
			(start 0.7874 0.4064)
			(end -0.7874 0.4064)
			(stroke
				(width 0.1524)
				(type default)
			)
			(layer "F.SilkS")
		)
		(fp_line
			(start 0.7874 -0.4064)
			(end 0.7874 0.4064)
			(stroke
				(width 0.1524)
				(type default)
			)
			(layer "F.SilkS")
		)
		(fp_line
			(start -0.7874 0.4064)
			(end -0.7874 -0.4064)
			(stroke
				(width 0.1524)
				(type default)
			)
			(layer "F.SilkS")
		)
		(fp_line
			(start -0.7874 -0.4064)
			(end 0.7874 -0.4064)
			(stroke
				(width 0.1524)
				(type default)
			)
			(layer "F.SilkS")
		)
		(fp_line
			(start 0.67945 0.3048)
			(end 0.120396 0.3048)
			(stroke
				(width 0.1)
				(type default)
			)
			(layer "F.Fab")
		)
		(fp_line
			(start 0.67945 -0.3048)
			(end 0.67945 0.3048)
			(stroke
				(width 0.1)
				(type default)
			)
			(layer "F.Fab")
		)
		(fp_line
			(start 0.12065 -0.2794)
			(end 0.12065 -0.3048)
			(stroke
				(width 0.1)
				(type default)
			)
			(layer "F.Fab")
		)
		(fp_line
			(start 0.12065 -0.3048)
			(end 0.67945 -0.3048)
			(stroke
				(width 0.1)
				(type default)
			)
			(layer "F.Fab")
		)
		(fp_line
			(start 0.120396 0.3048)
			(end 0.120396 0.2794)
			(stroke
				(width 0.1)
				(type default)
			)
			(layer "F.Fab")
		)
		(fp_line
			(start 0.120396 0.2794)
			(end -0.12065 0.2794)
			(stroke
				(width 0.1)
				(type default)
			)
			(layer "F.Fab")
		)
		(fp_line
			(start -0.12065 0.3048)
			(end -0.67945 0.3048)
			(stroke
				(width 0.1)
				(type default)
			)
			(layer "F.Fab")
		)
		(fp_line
			(start -0.12065 0.2794)
			(end -0.12065 0.3048)
			(stroke
				(width 0.1)
				(type default)
			)
			(layer "F.Fab")
		)
		(fp_line
			(start -0.12065 -0.2794)
			(end 0.12065 -0.2794)
			(stroke
				(width 0.1)
				(type default)
			)
			(layer "F.Fab")
		)
		(fp_line
			(start -0.12065 -0.305054)
			(end -0.12065 -0.2794)
			(stroke
				(width 0.1)
				(type default)
			)
			(layer "F.Fab")
		)
		(fp_line
			(start -0.67945 0.3048)
			(end -0.67945 -0.305054)
			(stroke
				(width 0.1)
				(type default)
			)
			(layer "F.Fab")
		)
		(fp_line
			(start -0.67945 -0.305054)
			(end -0.12065 -0.305054)
			(stroke
				(width 0.1)
				(type default)
			)
			(layer "F.Fab")
		)
		(pad "1" smd circle
			(at -0.40005 0 180)
			(size 0 0)
			(layers "F.Cu" "F.Mask" "F.Paste")
			(net "GPU_FPGA_BOOT_EN_BUF_R")
		)
		(pad "2" smd circle
			(at 0.40005 0 180)
			(size 0 0)
			(layers "F.Cu" "F.Mask" "F.Paste")
			(net "GND")
		)
	)
	(footprint ""
		(layer "F.Cu")
		(at 410.796486 -134.807706)
		(property "Reference" "PC1648"
			(at 0 0 0)
			(layer "F.SilkS")
			(hide yes)
			(effects
				(font
					(size 1.27 1.27)
				)
			)
		)
		(property "Value" ""
			(at 0 0 0)
			(layer "F.Fab")
			(effects
				(font
					(size 1.27 1.27)
				)
			)
		)
		(duplicate_pad_numbers_are_jumpers no)
		(fp_line
			(start -0.7874 -0.4064)
			(end 0.7874 -0.4064)
			(stroke
				(width 0.1524)
				(type default)
			)
			(layer "F.SilkS")
		)
		(fp_line
			(start -0.7874 0.4064)
			(end -0.7874 -0.4064)
			(stroke
				(width 0.1524)
				(type default)
			)
			(layer "F.SilkS")
		)
		(fp_line
			(start 0.7874 -0.4064)
			(end 0.7874 0.4064)
			(stroke
				(width 0.1524)
				(type default)
			)
			(layer "F.SilkS")
		)
		(fp_line
			(start 0.7874 0.4064)
			(end -0.7874 0.4064)
			(stroke
				(width 0.1524)
				(type default)
			)
			(layer "F.SilkS")
		)
		(fp_line
			(start -0.67945 -0.305054)
			(end -0.12065 -0.305054)
			(stroke
				(width 0.1)
				(type default)
			)
			(layer "F.Fab")
		)
		(fp_line
			(start -0.67945 0.3048)
			(end -0.67945 -0.305054)
			(stroke
				(width 0.1)
				(type default)
			)
			(layer "F.Fab")
		)
		(fp_line
			(start -0.12065 -0.305054)
			(end -0.12065 -0.2794)
			(stroke
				(width 0.1)
				(type default)
			)
			(layer "F.Fab")
		)
		(fp_line
			(start -0.12065 -0.2794)
			(end 0.12065 -0.2794)
			(stroke
				(width 0.1)
				(type default)
			)
			(layer "F.Fab")
		)
		(fp_line
			(start -0.12065 0.2794)
			(end -0.12065 0.3048)
			(stroke
				(width 0.1)
				(type default)
			)
			(layer "F.Fab")
		)
		(fp_line
			(start -0.12065 0.3048)
			(end -0.67945 0.3048)
			(stroke
				(width 0.1)
				(type default)
			)
			(layer "F.Fab")
		)
		(fp_line
			(start 0.120396 0.2794)
			(end -0.12065 0.2794)
			(stroke
				(width 0.1)
				(type default)
			)
			(layer "F.Fab")
		)
		(fp_line
			(start 0.120396 0.3048)
			(end 0.120396 0.2794)
			(stroke
				(width 0.1)
				(type default)
			)
			(layer "F.Fab")
		)
		(fp_line
			(start 0.12065 -0.3048)
			(end 0.67945 -0.3048)
			(stroke
				(width 0.1)
				(type default)
			)
			(layer "F.Fab")
		)
		(fp_line
			(start 0.12065 -0.2794)
			(end 0.12065 -0.3048)
			(stroke
				(width 0.1)
				(type default)
			)
			(layer "F.Fab")
		)
		(fp_line
			(start 0.67945 -0.3048)
			(end 0.67945 0.3048)
			(stroke
				(width 0.1)
				(type default)
			)
			(layer "F.Fab")
		)
		(fp_line
			(start 0.67945 0.3048)
			(end 0.120396 0.3048)
			(stroke
				(width 0.1)
				(type default)
			)
			(layer "F.Fab")
		)
		(pad "1" smd circle
			(at -0.40005 0)
			(size 0 0)
			(layers "F.Cu" "F.Mask" "F.Paste")
			(net "P12V_AUX")
		)
		(pad "2" smd circle
			(at 0.40005 0)
			(size 0 0)
			(layers "F.Cu" "F.Mask" "F.Paste")
			(net "GND")
		)
	)
	(footprint ""
		(layer "F.Cu")
		(at 395.279118 -76.305664)
		(property "Reference" "U55"
			(at -0.526288 -4.18084 0)
			(unlocked yes)
			(layer "F.SilkS")
			(effects
				(font
					(size 0.7874 0.5842)
					(thickness 0.1524)
				)
			)
		)
		(property "Value" ""
			(at 0 0 0)
			(layer "F.Fab")
			(effects
				(font
					(size 1.27 1.27)
				)
			)
		)
		(duplicate_pad_numbers_are_jumpers no)
		(fp_line
			(start -1.500124 -1.500124)
			(end -1.004062 -1.500124)
			(stroke
				(width 0.1524)
				(type default)
			)
			(layer "F.SilkS")
		)
		(fp_line
			(start -1.500124 -1.004062)
			(end -1.500124 -1.500124)
			(stroke
				(width 0.1524)
				(type default)
			)
			(layer "F.SilkS")
		)
		(fp_line
			(start -1.500124 1.500124)
			(end -1.500124 1.004062)
			(stroke
				(width 0.1524)
				(type default)
			)
			(layer "F.SilkS")
		)
		(fp_line
			(start -1.004062 1.500124)
			(end -1.500124 1.500124)
			(stroke
				(width 0.1524)
				(type default)
			)
			(layer "F.SilkS")
		)
		(fp_line
			(start 1.004062 -1.500124)
			(end 1.500124 -1.500124)
			(stroke
				(width 0.1524)
				(type default)
			)
			(layer "F.SilkS")
		)
		(fp_line
			(start 1.500124 -1.500124)
			(end 1.500124 -1.004062)
			(stroke
				(width 0.1524)
				(type default)
			)
			(layer "F.SilkS")
		)
		(fp_line
			(start 1.500124 1.004062)
			(end 1.500124 1.500124)
			(stroke
				(width 0.1524)
				(type default)
			)
			(layer "F.SilkS")
		)
		(fp_line
			(start 1.500124 1.500124)
			(end 1.004062 1.500124)
			(stroke
				(width 0.1524)
				(type default)
			)
			(layer "F.SilkS")
		)
		(fp_poly
			(pts
				(xy -1.271016 -2.21869) (xy -2.285238 -2.159254) (xy -1.718564 -1.17475)
			)
			(stroke
				(width 0)
				(type default)
			)
			(fill yes)
			(layer "F.SilkS")
		)
		(fp_line
			(start -1.500124 -1.500124)
			(end 1.500124 -1.500124)
			(stroke
				(width 0.1)
				(type default)
			)
			(layer "F.Fab")
		)
		(fp_line
			(start -1.500124 1.500124)
			(end -1.500124 -1.500124)
			(stroke
				(width 0.1)
				(type default)
			)
			(layer "F.Fab")
		)
		(fp_line
			(start 1.500124 -1.500124)
			(end 1.500124 1.500124)
			(stroke
				(width 0.1)
				(type default)
			)
			(layer "F.Fab")
		)
		(fp_line
			(start 1.500124 1.500124)
			(end -1.500124 1.500124)
			(stroke
				(width 0.1)
				(type default)
			)
			(layer "F.Fab")
		)
		(fp_poly
			(pts
				(xy -2.847848 -1.258062) (xy -2.847848 -0.242062) (xy -1.831848 -0.750062)
			)
			(stroke
				(width 0)
				(type default)
			)
			(fill yes)
			(layer "F.Fab")
		)
		(pad "1" smd rect
			(at -1.400048 -0.750062 270)
			(size 0.2286 0.6096)
			(layers "F.Cu" "F.Mask" "F.Paste")
			(net "INA230_6_A1")
		)
		(pad "2" smd rect
			(at -1.400048 -0.249936 270)
			(size 0.2286 0.6096)
			(layers "F.Cu" "F.Mask" "F.Paste")
			(net "INA230_6_A0")
		)
		(pad "3" smd rect
			(at -1.400048 0.249936 270)
			(size 0.2286 0.6096)
			(layers "F.Cu" "F.Mask" "F.Paste")
			(net "P12V_OCP_SFF_ADC_ALERT_R")
		)
		(pad "4" smd rect
			(at -1.400048 0.750062 270)
			(size 0.2286 0.6096)
			(layers "F.Cu" "F.Mask" "F.Paste")
			(net "SMB_INA230_6_3V3AUX_SDA_R1")
		)
		(pad "5" smd rect
			(at -0.750062 1.400048)
			(size 0.2286 0.6096)
			(layers "F.Cu" "F.Mask" "F.Paste")
			(net "SMB_INA230_6_3V3AUX_SCL_R1")
		)
		(pad "6" smd rect
			(at -0.249936 1.400048)
			(size 0.2286 0.6096)
			(layers "F.Cu" "F.Mask" "F.Paste")
			(net "NC_INA230_6_NC0")
		)
		(pad "7" smd rect
			(at 0.249936 1.400048)
			(size 0.2286 0.6096)
			(layers "F.Cu" "F.Mask" "F.Paste")
			(net "NC_INA230_6_NC1")
		)
		(pad "8" smd rect
			(at 0.750062 1.400048)
			(size 0.2286 0.6096)
			(layers "F.Cu" "F.Mask" "F.Paste")
			(net "NC_INA230_6_NC2")
		)
		(pad "9" smd rect
			(at 1.400048 0.750062 270)
			(size 0.2286 0.6096)
			(layers "F.Cu" "F.Mask" "F.Paste")
			(net "P3V3_AUX")
		)
		(pad "10" smd rect
			(at 1.400048 0.249936 270)
			(size 0.2286 0.6096)
			(layers "F.Cu" "F.Mask" "F.Paste")
			(net "GND")
		)
		(pad "11" smd rect
			(at 1.400048 -0.249936 270)
			(size 0.2286 0.6096)
			(layers "F.Cu" "F.Mask" "F.Paste")
			(net "P12V_OCP_SFF")
		)
		(pad "12" smd rect
			(at 1.400048 -0.750062 270)
			(size 0.2286 0.6096)
			(layers "F.Cu" "F.Mask" "F.Paste")
			(net "VSENSE_P12V_INA230_6_INN")
		)
		(pad "13" smd rect
			(at 0.750062 -1.400048)
			(size 0.2286 0.6096)
			(layers "F.Cu" "F.Mask" "F.Paste")
			(net "VSENSE_P12V_INA230_6_INP")
		)
		(pad "14" smd rect
			(at 0.249936 -1.400048)
			(size 0.2286 0.6096)
			(layers "F.Cu" "F.Mask" "F.Paste")
			(net "NC_INA230_6_NC3")
		)
		(pad "15" smd rect
			(at -0.249936 -1.400048)
			(size 0.2286 0.6096)
			(layers "F.Cu" "F.Mask" "F.Paste")
			(net "NC_INA230_6_NC4")
		)
		(pad "16" smd rect
			(at -0.750062 -1.400048)
			(size 0.2286 0.6096)
			(layers "F.Cu" "F.Mask" "F.Paste")
			(net "NC_INA230_6_NC5")
		)
		(pad "TH" smd rect
			(at 0 0)
			(size 1.7018 1.7018)
			(layers "F.Cu" "F.Mask" "F.Paste")
			(net "GND")
		)
		(zone
			(layer "F.Cu")
			(hatch none 0.5)
			(connect_pads
				(clearance 0)
			)
			(min_thickness 0.25)
			(keepout
				(tracks not_allowed)
				(vias allowed)
				(pads allowed)
				(copperpour not_allowed)
				(footprints allowed)
			)
			(placement
				(enabled no)
				(sheetname "")
			)
			(fill
				(thermal_gap 0.5)
				(thermal_bridge_width 0.5)
				(island_removal_mode 0)
			)
			(polygon
				(pts
					(xy 394.23467 -76.331064) (xy 394.23467 -77.350112) (xy 396.323566 -77.350112) (xy 396.323566 -75.261216)
					(xy 394.23467 -75.261216) (xy 394.23467 -76.305664) (xy 394.377418 -76.305664) (xy 394.377418 -75.403964)
					(xy 396.180818 -75.403964) (xy 396.180818 -77.207364) (xy 394.377418 -77.207364) (xy 394.377418 -76.331064)
				)
			)
		)
	)
	(footprint ""
		(layer "F.Cu")
		(at 213.19744 -30.246828 90)
		(property "Reference" "R4091"
			(at 0 0 90)
			(layer "F.SilkS")
			(hide yes)
			(effects
				(font
					(size 1.27 1.27)
				)
			)
		)
		(property "Value" ""
			(at 0 0 90)
			(layer "F.Fab")
			(effects
				(font
					(size 1.27 1.27)
				)
			)
		)
		(duplicate_pad_numbers_are_jumpers no)
		(fp_line
			(start 0.7874 -0.4064)
			(end 0.7874 0.4064)
			(stroke
				(width 0.1524)
				(type default)
			)
			(layer "F.SilkS")
		)
		(fp_line
			(start -0.7874 -0.4064)
			(end 0.7874 -0.4064)
			(stroke
				(width 0.1524)
				(type default)
			)
			(layer "F.SilkS")
		)
		(fp_line
			(start 0.7874 0.4064)
			(end -0.7874 0.4064)
			(stroke
				(width 0.1524)
				(type default)
			)
			(layer "F.SilkS")
		)
		(fp_line
			(start -0.7874 0.4064)
			(end -0.7874 -0.4064)
			(stroke
				(width 0.1524)
				(type default)
			)
			(layer "F.SilkS")
		)
		(fp_line
			(start -0.12065 -0.305054)
			(end -0.12065 -0.2794)
			(stroke
				(width 0.1)
				(type default)
			)
			(layer "F.Fab")
		)
		(fp_line
			(start -0.67945 -0.305054)
			(end -0.12065 -0.305054)
			(stroke
				(width 0.1)
				(type default)
			)
			(layer "F.Fab")
		)
		(fp_line
			(start 0.67945 -0.3048)
			(end 0.67945 0.3048)
			(stroke
				(width 0.1)
				(type default)
			)
			(layer "F.Fab")
		)
		(fp_line
			(start 0.12065 -0.3048)
			(end 0.67945 -0.3048)
			(stroke
				(width 0.1)
				(type default)
			)
			(layer "F.Fab")
		)
		(fp_line
			(start 0.12065 -0.2794)
			(end 0.12065 -0.3048)
			(stroke
				(width 0.1)
				(type default)
			)
			(layer "F.Fab")
		)
		(fp_line
			(start -0.12065 -0.2794)
			(end 0.12065 -0.2794)
			(stroke
				(width 0.1)
				(type default)
			)
			(layer "F.Fab")
		)
		(fp_line
			(start 0.120396 0.2794)
			(end -0.12065 0.2794)
			(stroke
				(width 0.1)
				(type default)
			)
			(layer "F.Fab")
		)
		(fp_line
			(start -0.12065 0.2794)
			(end -0.12065 0.3048)
			(stroke
				(width 0.1)
				(type default)
			)
			(layer "F.Fab")
		)
		(fp_line
			(start 0.67945 0.3048)
			(end 0.120396 0.3048)
			(stroke
				(width 0.1)
				(type default)
			)
			(layer "F.Fab")
		)
		(fp_line
			(start 0.120396 0.3048)
			(end 0.120396 0.2794)
			(stroke
				(width 0.1)
				(type default)
			)
			(layer "F.Fab")
		)
		(fp_line
			(start -0.12065 0.3048)
			(end -0.67945 0.3048)
			(stroke
				(width 0.1)
				(type default)
			)
			(layer "F.Fab")
		)
		(fp_line
			(start -0.67945 0.3048)
			(end -0.67945 -0.305054)
			(stroke
				(width 0.1)
				(type default)
			)
			(layer "F.Fab")
		)
		(pad "1" smd circle
			(at -0.40005 0 90)
			(size 0 0)
			(layers "F.Cu" "F.Mask" "F.Paste")
			(net "P3V3_AUX")
		)
		(pad "2" smd circle
			(at 0.40005 0 90)
			(size 0 0)
			(layers "F.Cu" "F.Mask" "F.Paste")
			(net "P12V_SCM_ADC_ALERT_R")
		)
	)
	(footprint ""
		(layer "F.Cu")
		(at 420.031418 -366.202214 90)
		(property "Reference" "PC202_2"
			(at 0 0 90)
			(layer "F.SilkS")
			(hide yes)
			(effects
				(font
					(size 1.27 1.27)
				)
			)
		)
		(property "Value" ""
			(at 0 0 90)
			(layer "F.Fab")
			(effects
				(font
					(size 1.27 1.27)
				)
			)
		)
		(duplicate_pad_numbers_are_jumpers no)
		(fp_line
			(start 0.7874 -0.4064)
			(end 0.7874 0.4064)
			(stroke
				(width 0.1524)
				(type default)
			)
			(layer "F.SilkS")
		)
		(fp_line
			(start -0.7874 -0.4064)
			(end 0.7874 -0.4064)
			(stroke
				(width 0.1524)
				(type default)
			)
			(layer "F.SilkS")
		)
		(fp_line
			(start 0.7874 0.4064)
			(end -0.7874 0.4064)
			(stroke
				(width 0.1524)
				(type default)
			)
			(layer "F.SilkS")
		)
		(fp_line
			(start -0.7874 0.4064)
			(end -0.7874 -0.4064)
			(stroke
				(width 0.1524)
				(type default)
			)
			(layer "F.SilkS")
		)
		(fp_line
			(start -0.12065 -0.305054)
			(end -0.12065 -0.2794)
			(stroke
				(width 0.1)
				(type default)
			)
			(layer "F.Fab")
		)
		(fp_line
			(start -0.67945 -0.305054)
			(end -0.12065 -0.305054)
			(stroke
				(width 0.1)
				(type default)
			)
			(layer "F.Fab")
		)
		(fp_line
			(start 0.67945 -0.3048)
			(end 0.67945 0.3048)
			(stroke
				(width 0.1)
				(type default)
			)
			(layer "F.Fab")
		)
		(fp_line
			(start 0.12065 -0.3048)
			(end 0.67945 -0.3048)
			(stroke
				(width 0.1)
				(type default)
			)
			(layer "F.Fab")
		)
		(fp_line
			(start 0.12065 -0.2794)
			(end 0.12065 -0.3048)
			(stroke
				(width 0.1)
				(type default)
			)
			(layer "F.Fab")
		)
		(fp_line
			(start -0.12065 -0.2794)
			(end 0.12065 -0.2794)
			(stroke
				(width 0.1)
				(type default)
			)
			(layer "F.Fab")
		)
		(fp_line
			(start 0.120396 0.2794)
			(end -0.12065 0.2794)
			(stroke
				(width 0.1)
				(type default)
			)
			(layer "F.Fab")
		)
		(fp_line
			(start -0.12065 0.2794)
			(end -0.12065 0.3048)
			(stroke
				(width 0.1)
				(type default)
			)
			(layer "F.Fab")
		)
		(fp_line
			(start 0.67945 0.3048)
			(end 0.120396 0.3048)
			(stroke
				(width 0.1)
				(type default)
			)
			(layer "F.Fab")
		)
		(fp_line
			(start 0.120396 0.3048)
			(end 0.120396 0.2794)
			(stroke
				(width 0.1)
				(type default)
			)
			(layer "F.Fab")
		)
		(fp_line
			(start -0.12065 0.3048)
			(end -0.67945 0.3048)
			(stroke
				(width 0.1)
				(type default)
			)
			(layer "F.Fab")
		)
		(fp_line
			(start -0.67945 0.3048)
			(end -0.67945 -0.305054)
			(stroke
				(width 0.1)
				(type default)
			)
			(layer "F.Fab")
		)
		(pad "1" smd circle
			(at -0.40005 0 90)
			(size 0 0)
			(layers "F.Cu" "F.Mask" "F.Paste")
			(net "PVDD11_S3_P0_VCCS")
		)
		(pad "2" smd circle
			(at 0.40005 0 90)
			(size 0 0)
			(layers "F.Cu" "F.Mask" "F.Paste")
			(net "GND")
		)
	)
	(footprint ""
		(layer "F.Cu")
		(at 89.898982 -55.713122 180)
		(property "Reference" "PC2151"
			(at 0 0 180)
			(layer "F.SilkS")
			(hide yes)
			(effects
				(font
					(size 1.27 1.27)
				)
			)
		)
		(property "Value" ""
			(at 0 0 180)
			(layer "F.Fab")
			(effects
				(font
					(size 1.27 1.27)
				)
			)
		)
		(duplicate_pad_numbers_are_jumpers no)
		(fp_line
			(start 0.7874 0.4064)
			(end -0.7874 0.4064)
			(stroke
				(width 0.1524)
				(type default)
			)
			(layer "F.SilkS")
		)
		(fp_line
			(start 0.7874 -0.4064)
			(end 0.7874 0.4064)
			(stroke
				(width 0.1524)
				(type default)
			)
			(layer "F.SilkS")
		)
		(fp_line
			(start -0.7874 0.4064)
			(end -0.7874 -0.4064)
			(stroke
				(width 0.1524)
				(type default)
			)
			(layer "F.SilkS")
		)
		(fp_line
			(start -0.7874 -0.4064)
			(end 0.7874 -0.4064)
			(stroke
				(width 0.1524)
				(type default)
			)
			(layer "F.SilkS")
		)
		(fp_line
			(start 0.67945 0.3048)
			(end 0.120396 0.3048)
			(stroke
				(width 0.1)
				(type default)
			)
			(layer "F.Fab")
		)
		(fp_line
			(start 0.67945 -0.3048)
			(end 0.67945 0.3048)
			(stroke
				(width 0.1)
				(type default)
			)
			(layer "F.Fab")
		)
		(fp_line
			(start 0.12065 -0.2794)
			(end 0.12065 -0.3048)
			(stroke
				(width 0.1)
				(type default)
			)
			(layer "F.Fab")
		)
		(fp_line
			(start 0.12065 -0.3048)
			(end 0.67945 -0.3048)
			(stroke
				(width 0.1)
				(type default)
			)
			(layer "F.Fab")
		)
		(fp_line
			(start 0.120396 0.3048)
			(end 0.120396 0.2794)
			(stroke
				(width 0.1)
				(type default)
			)
			(layer "F.Fab")
		)
		(fp_line
			(start 0.120396 0.2794)
			(end -0.12065 0.2794)
			(stroke
				(width 0.1)
				(type default)
			)
			(layer "F.Fab")
		)
		(fp_line
			(start -0.12065 0.3048)
			(end -0.67945 0.3048)
			(stroke
				(width 0.1)
				(type default)
			)
			(layer "F.Fab")
		)
		(fp_line
			(start -0.12065 0.2794)
			(end -0.12065 0.3048)
			(stroke
				(width 0.1)
				(type default)
			)
			(layer "F.Fab")
		)
		(fp_line
			(start -0.12065 -0.2794)
			(end 0.12065 -0.2794)
			(stroke
				(width 0.1)
				(type default)
			)
			(layer "F.Fab")
		)
		(fp_line
			(start -0.12065 -0.305054)
			(end -0.12065 -0.2794)
			(stroke
				(width 0.1)
				(type default)
			)
			(layer "F.Fab")
		)
		(fp_line
			(start -0.67945 0.3048)
			(end -0.67945 -0.305054)
			(stroke
				(width 0.1)
				(type default)
			)
			(layer "F.Fab")
		)
		(fp_line
			(start -0.67945 -0.305054)
			(end -0.12065 -0.305054)
			(stroke
				(width 0.1)
				(type default)
			)
			(layer "F.Fab")
		)
		(pad "1" smd circle
			(at -0.40005 0 180)
			(size 0 0)
			(layers "F.Cu" "F.Mask" "F.Paste")
			(net "P3V3_OCP_GATE_2")
		)
		(pad "2" smd circle
			(at 0.40005 0 180)
			(size 0 0)
			(layers "F.Cu" "F.Mask" "F.Paste")
			(net "GND")
		)
	)
	(footprint ""
		(layer "F.Cu")
		(at 306.831746 -416.899344 -90)
		(property "Reference" "C6504"
			(at 0 0 270)
			(layer "F.SilkS")
			(hide yes)
			(effects
				(font
					(size 1.27 1.27)
				)
			)
		)
		(property "Value" ""
			(at 0 0 270)
			(layer "F.Fab")
			(effects
				(font
					(size 1.27 1.27)
				)
			)
		)
		(duplicate_pad_numbers_are_jumpers no)
		(fp_line
			(start -0.299974 0.150114)
			(end -0.299974 -0.150114)
			(stroke
				(width 0.1)
				(type default)
			)
			(layer "F.Fab")
		)
		(fp_line
			(start 0.299974 0.150114)
			(end -0.299974 0.150114)
			(stroke
				(width 0.1)
				(type default)
			)
			(layer "F.Fab")
		)
		(fp_line
			(start -0.299974 -0.150114)
			(end 0.299974 -0.150114)
			(stroke
				(width 0.1)
				(type default)
			)
			(layer "F.Fab")
		)
		(fp_line
			(start 0.299974 -0.150114)
			(end 0.299974 0.150114)
			(stroke
				(width 0.1)
				(type default)
			)
			(layer "F.Fab")
		)
		(pad "1" smd rect
			(at -0.2667 0 270)
			(size 0.3048 0.381)
			(layers "F.Cu" "F.Mask" "F.Paste")
			(net "P5E_CPU0_P0_TX_BUF_C_DN<1>")
		)
		(pad "2" smd rect
			(at 0.2667 0 270)
			(size 0.3048 0.381)
			(layers "F.Cu" "F.Mask" "F.Paste")
			(net "P5E_CPU0_P0_TX_BUF_DN<1>")
		)
	)
	(footprint ""
		(layer "F.Cu")
		(at 159.18307 -74.75347 90)
		(property "Reference" "R116"
			(at 0 0 90)
			(layer "F.SilkS")
			(hide yes)
			(effects
				(font
					(size 1.27 1.27)
				)
			)
		)
		(property "Value" ""
			(at 0 0 90)
			(layer "F.Fab")
			(effects
				(font
					(size 1.27 1.27)
				)
			)
		)
		(duplicate_pad_numbers_are_jumpers no)
		(fp_line
			(start 0.7874 -0.4064)
			(end 0.7874 0.4064)
			(stroke
				(width 0.1524)
				(type default)
			)
			(layer "F.SilkS")
		)
		(fp_line
			(start -0.7874 -0.4064)
			(end 0.7874 -0.4064)
			(stroke
				(width 0.1524)
				(type default)
			)
			(layer "F.SilkS")
		)
		(fp_line
			(start 0.7874 0.4064)
			(end -0.7874 0.4064)
			(stroke
				(width 0.1524)
				(type default)
			)
			(layer "F.SilkS")
		)
		(fp_line
			(start -0.7874 0.4064)
			(end -0.7874 -0.4064)
			(stroke
				(width 0.1524)
				(type default)
			)
			(layer "F.SilkS")
		)
		(fp_line
			(start -0.12065 -0.305054)
			(end -0.12065 -0.2794)
			(stroke
				(width 0.1)
				(type default)
			)
			(layer "F.Fab")
		)
		(fp_line
			(start -0.67945 -0.305054)
			(end -0.12065 -0.305054)
			(stroke
				(width 0.1)
				(type default)
			)
			(layer "F.Fab")
		)
		(fp_line
			(start 0.67945 -0.3048)
			(end 0.67945 0.3048)
			(stroke
				(width 0.1)
				(type default)
			)
			(layer "F.Fab")
		)
		(fp_line
			(start 0.12065 -0.3048)
			(end 0.67945 -0.3048)
			(stroke
				(width 0.1)
				(type default)
			)
			(layer "F.Fab")
		)
		(fp_line
			(start 0.12065 -0.2794)
			(end 0.12065 -0.3048)
			(stroke
				(width 0.1)
				(type default)
			)
			(layer "F.Fab")
		)
		(fp_line
			(start -0.12065 -0.2794)
			(end 0.12065 -0.2794)
			(stroke
				(width 0.1)
				(type default)
			)
			(layer "F.Fab")
		)
		(fp_line
			(start 0.120396 0.2794)
			(end -0.12065 0.2794)
			(stroke
				(width 0.1)
				(type default)
			)
			(layer "F.Fab")
		)
		(fp_line
			(start -0.12065 0.2794)
			(end -0.12065 0.3048)
			(stroke
				(width 0.1)
				(type default)
			)
			(layer "F.Fab")
		)
		(fp_line
			(start 0.67945 0.3048)
			(end 0.120396 0.3048)
			(stroke
				(width 0.1)
				(type default)
			)
			(layer "F.Fab")
		)
		(fp_line
			(start 0.120396 0.3048)
			(end 0.120396 0.2794)
			(stroke
				(width 0.1)
				(type default)
			)
			(layer "F.Fab")
		)
		(fp_line
			(start -0.12065 0.3048)
			(end -0.67945 0.3048)
			(stroke
				(width 0.1)
				(type default)
			)
			(layer "F.Fab")
		)
		(fp_line
			(start -0.67945 0.3048)
			(end -0.67945 -0.305054)
			(stroke
				(width 0.1)
				(type default)
			)
			(layer "F.Fab")
		)
		(pad "1" smd circle
			(at -0.40005 0 90)
			(size 0 0)
			(layers "F.Cu" "F.Mask" "F.Paste")
			(net "IRQ_OCP_SFF_WAKE_BUF_N")
		)
		(pad "2" smd circle
			(at 0.40005 0 90)
			(size 0 0)
			(layers "F.Cu" "F.Mask" "F.Paste")
			(net "IRQ_LVC3_WAKE_N")
		)
	)
	(footprint ""
		(layer "F.Cu")
		(at 389.127492 -378.95403 -90)
		(property "Reference" "C876"
			(at 0 0 270)
			(layer "F.SilkS")
			(hide yes)
			(effects
				(font
					(size 1.27 1.27)
				)
			)
		)
		(property "Value" ""
			(at 0 0 270)
			(layer "F.Fab")
			(effects
				(font
					(size 1.27 1.27)
				)
			)
		)
		(duplicate_pad_numbers_are_jumpers no)
		(fp_line
			(start -0.299974 0.150114)
			(end -0.299974 -0.150114)
			(stroke
				(width 0.1)
				(type default)
			)
			(layer "F.Fab")
		)
		(fp_line
			(start 0.299974 0.150114)
			(end -0.299974 0.150114)
			(stroke
				(width 0.1)
				(type default)
			)
			(layer "F.Fab")
		)
		(fp_line
			(start -0.299974 -0.150114)
			(end 0.299974 -0.150114)
			(stroke
				(width 0.1)
				(type default)
			)
			(layer "F.Fab")
		)
		(fp_line
			(start 0.299974 -0.150114)
			(end 0.299974 0.150114)
			(stroke
				(width 0.1)
				(type default)
			)
			(layer "F.Fab")
		)
		(pad "1" smd rect
			(at -0.2667 0 270)
			(size 0.3048 0.381)
			(layers "F.Cu" "F.Mask" "F.Paste")
			(net "P5E_CPU0_P3_TX_C_DN<12>")
		)
		(pad "2" smd rect
			(at 0.2667 0 270)
			(size 0.3048 0.381)
			(layers "F.Cu" "F.Mask" "F.Paste")
			(net "P5E_CPU0_P3_TX_DN<12>")
		)
	)
	(footprint ""
		(layer "F.Cu")
		(at 189.79769 -36.0807)
		(property "Reference" "R1856"
			(at 0 0 0)
			(layer "F.SilkS")
			(hide yes)
			(effects
				(font
					(size 1.27 1.27)
				)
			)
		)
		(property "Value" ""
			(at 0 0 0)
			(layer "F.Fab")
			(effects
				(font
					(size 1.27 1.27)
				)
			)
		)
		(duplicate_pad_numbers_are_jumpers no)
		(fp_line
			(start -0.7874 -0.4064)
			(end 0.7874 -0.4064)
			(stroke
				(width 0.1524)
				(type default)
			)
			(layer "F.SilkS")
		)
		(fp_line
			(start -0.7874 0.4064)
			(end -0.7874 -0.4064)
			(stroke
				(width 0.1524)
				(type default)
			)
			(layer "F.SilkS")
		)
		(fp_line
			(start 0.7874 -0.4064)
			(end 0.7874 0.4064)
			(stroke
				(width 0.1524)
				(type default)
			)
			(layer "F.SilkS")
		)
		(fp_line
			(start 0.7874 0.4064)
			(end -0.7874 0.4064)
			(stroke
				(width 0.1524)
				(type default)
			)
			(layer "F.SilkS")
		)
		(fp_line
			(start -0.67945 -0.305054)
			(end -0.12065 -0.305054)
			(stroke
				(width 0.1)
				(type default)
			)
			(layer "F.Fab")
		)
		(fp_line
			(start -0.67945 0.3048)
			(end -0.67945 -0.305054)
			(stroke
				(width 0.1)
				(type default)
			)
			(layer "F.Fab")
		)
		(fp_line
			(start -0.12065 -0.305054)
			(end -0.12065 -0.2794)
			(stroke
				(width 0.1)
				(type default)
			)
			(layer "F.Fab")
		)
		(fp_line
			(start -0.12065 -0.2794)
			(end 0.12065 -0.2794)
			(stroke
				(width 0.1)
				(type default)
			)
			(layer "F.Fab")
		)
		(fp_line
			(start -0.12065 0.2794)
			(end -0.12065 0.3048)
			(stroke
				(width 0.1)
				(type default)
			)
			(layer "F.Fab")
		)
		(fp_line
			(start -0.12065 0.3048)
			(end -0.67945 0.3048)
			(stroke
				(width 0.1)
				(type default)
			)
			(layer "F.Fab")
		)
		(fp_line
			(start 0.120396 0.2794)
			(end -0.12065 0.2794)
			(stroke
				(width 0.1)
				(type default)
			)
			(layer "F.Fab")
		)
		(fp_line
			(start 0.120396 0.3048)
			(end 0.120396 0.2794)
			(stroke
				(width 0.1)
				(type default)
			)
			(layer "F.Fab")
		)
		(fp_line
			(start 0.12065 -0.3048)
			(end 0.67945 -0.3048)
			(stroke
				(width 0.1)
				(type default)
			)
			(layer "F.Fab")
		)
		(fp_line
			(start 0.12065 -0.2794)
			(end 0.12065 -0.3048)
			(stroke
				(width 0.1)
				(type default)
			)
			(layer "F.Fab")
		)
		(fp_line
			(start 0.67945 -0.3048)
			(end 0.67945 0.3048)
			(stroke
				(width 0.1)
				(type default)
			)
			(layer "F.Fab")
		)
		(fp_line
			(start 0.67945 0.3048)
			(end 0.120396 0.3048)
			(stroke
				(width 0.1)
				(type default)
			)
			(layer "F.Fab")
		)
		(pad "1" smd circle
			(at -0.40005 0)
			(size 0 0)
			(layers "F.Cu" "F.Mask" "F.Paste")
			(net "FM_SCM_PRSNT1_N")
		)
		(pad "2" smd circle
			(at 0.40005 0)
			(size 0 0)
			(layers "F.Cu" "F.Mask" "F.Paste")
			(net "FM_SCM_PRSNT1_R_N")
		)
	)
	(footprint ""
		(layer "F.Cu")
		(at 124.46 -28.854654 180)
		(property "Reference" "Y9"
			(at 1.37668 -2.9845 0)
			(unlocked yes)
			(layer "F.SilkS")
			(effects
				(font
					(size 0.7874 0.5842)
					(thickness 0.1524)
				)
				(justify left)
			)
		)
		(property "Value" ""
			(at 0 0 180)
			(layer "F.Fab")
			(effects
				(font
					(size 1.27 1.27)
				)
			)
		)
		(duplicate_pad_numbers_are_jumpers no)
		(fp_line
			(start 1.380236 1.579372)
			(end 1.380236 -1.579372)
			(stroke
				(width 0.1524)
				(type default)
			)
			(layer "F.SilkS")
		)
		(fp_line
			(start 1.380236 -1.579372)
			(end -1.380236 -1.579372)
			(stroke
				(width 0.1524)
				(type default)
			)
			(layer "F.SilkS")
		)
		(fp_line
			(start -1.380236 1.579372)
			(end 1.380236 1.579372)
			(stroke
				(width 0.1524)
				(type default)
			)
			(layer "F.SilkS")
		)
		(fp_line
			(start -1.380236 -1.579372)
			(end -1.380236 1.579372)
			(stroke
				(width 0.1524)
				(type default)
			)
			(layer "F.SilkS")
		)
		(fp_poly
			(pts
				(xy -0.774446 -1.816354) (xy -1.155446 -2.578354) (xy -0.393446 -2.578354)
			)
			(stroke
				(width 0)
				(type default)
			)
			(fill yes)
			(layer "F.SilkS")
		)
		(fp_line
			(start 1.050036 1.299972)
			(end 1.050036 -1.299972)
			(stroke
				(width 0.1)
				(type default)
			)
			(layer "F.Fab")
		)
		(fp_line
			(start 1.050036 -1.299972)
			(end -1.050036 -1.299972)
			(stroke
				(width 0.1)
				(type default)
			)
			(layer "F.Fab")
		)
		(fp_line
			(start -1.050036 1.299972)
			(end 1.050036 1.299972)
			(stroke
				(width 0.1)
				(type default)
			)
			(layer "F.Fab")
		)
		(fp_line
			(start -1.050036 -1.299972)
			(end -1.050036 1.299972)
			(stroke
				(width 0.1)
				(type default)
			)
			(layer "F.Fab")
		)
		(fp_poly
			(pts
				(xy -2.3114 -1.306068) (xy -2.3114 -0.544068) (xy -1.5494 -0.925068)
			)
			(stroke
				(width 0)
				(type default)
			)
			(fill yes)
			(layer "F.Fab")
		)
		(pad "1" smd rect
			(at -0.774954 -0.925068 180)
			(size 0.9144 1.016)
			(layers "F.Cu" "F.Mask" "F.Paste")
			(net "XTAL_USB_CPU0_HUB1_XIN")
		)
		(pad "2" smd rect
			(at -0.774954 0.925068 180)
			(size 0.9144 1.016)
			(layers "F.Cu" "F.Mask" "F.Paste")
			(net "GND")
		)
		(pad "3" smd rect
			(at 0.774954 0.925068 180)
			(size 0.9144 1.016)
			(layers "F.Cu" "F.Mask" "F.Paste")
			(net "XTAL_USB_CPU0_HUB1_XOUT")
		)
		(pad "4" smd rect
			(at 0.774954 -0.925068 180)
			(size 0.9144 1.016)
			(layers "F.Cu" "F.Mask" "F.Paste")
			(net "GND")
		)
	)
	(footprint ""
		(layer "F.Cu")
		(at 376.995182 -416.899344 -90)
		(property "Reference" "C6570"
			(at 0 0 270)
			(layer "F.SilkS")
			(hide yes)
			(effects
				(font
					(size 1.27 1.27)
				)
			)
		)
		(property "Value" ""
			(at 0 0 270)
			(layer "F.Fab")
			(effects
				(font
					(size 1.27 1.27)
				)
			)
		)
		(duplicate_pad_numbers_are_jumpers no)
		(fp_line
			(start -0.299974 0.150114)
			(end -0.299974 -0.150114)
			(stroke
				(width 0.1)
				(type default)
			)
			(layer "F.Fab")
		)
		(fp_line
			(start 0.299974 0.150114)
			(end -0.299974 0.150114)
			(stroke
				(width 0.1)
				(type default)
			)
			(layer "F.Fab")
		)
		(fp_line
			(start -0.299974 -0.150114)
			(end 0.299974 -0.150114)
			(stroke
				(width 0.1)
				(type default)
			)
			(layer "F.Fab")
		)
		(fp_line
			(start 0.299974 -0.150114)
			(end 0.299974 0.150114)
			(stroke
				(width 0.1)
				(type default)
			)
			(layer "F.Fab")
		)
		(pad "1" smd rect
			(at -0.2667 0 270)
			(size 0.3048 0.381)
			(layers "F.Cu" "F.Mask" "F.Paste")
			(net "P5E_CPU0_P2_TX_BUF_C_DN<2>")
		)
		(pad "2" smd rect
			(at 0.2667 0 270)
			(size 0.3048 0.381)
			(layers "F.Cu" "F.Mask" "F.Paste")
			(net "P5E_CPU0_P2_TX_BUF_DN<2>")
		)
	)
	(footprint ""
		(layer "F.Cu")
		(at 26.684478 -16.099536 90)
		(property "Reference" "C686"
			(at 0 0 90)
			(layer "F.SilkS")
			(hide yes)
			(effects
				(font
					(size 1.27 1.27)
				)
			)
		)
		(property "Value" ""
			(at 0 0 90)
			(layer "F.Fab")
			(effects
				(font
					(size 1.27 1.27)
				)
			)
		)
		(duplicate_pad_numbers_are_jumpers no)
		(fp_line
			(start 0.299974 -0.150114)
			(end 0.299974 0.150114)
			(stroke
				(width 0.1)
				(type default)
			)
			(layer "F.Fab")
		)
		(fp_line
			(start -0.299974 -0.150114)
			(end 0.299974 -0.150114)
			(stroke
				(width 0.1)
				(type default)
			)
			(layer "F.Fab")
		)
		(fp_line
			(start 0.299974 0.150114)
			(end -0.299974 0.150114)
			(stroke
				(width 0.1)
				(type default)
			)
			(layer "F.Fab")
		)
		(fp_line
			(start -0.299974 0.150114)
			(end -0.299974 -0.150114)
			(stroke
				(width 0.1)
				(type default)
			)
			(layer "F.Fab")
		)
		(pad "1" smd rect
			(at -0.2667 0 90)
			(size 0.3048 0.381)
			(layers "F.Cu" "F.Mask" "F.Paste")
			(net "P5E_CPU1_G1_TX_C_DN<11>")
		)
		(pad "2" smd rect
			(at 0.2667 0 90)
			(size 0.3048 0.381)
			(layers "F.Cu" "F.Mask" "F.Paste")
			(net "P5E_CPU1_G1_TX_DN<11>")
		)
	)
	(footprint ""
		(layer "F.Cu")
		(at 8.343138 -136.15416 90)
		(property "Reference" "C71"
			(at 0 0 90)
			(layer "F.SilkS")
			(hide yes)
			(effects
				(font
					(size 1.27 1.27)
				)
			)
		)
		(property "Value" ""
			(at 0 0 90)
			(layer "F.Fab")
			(effects
				(font
					(size 1.27 1.27)
				)
			)
		)
		(duplicate_pad_numbers_are_jumpers no)
		(fp_line
			(start 0.7874 -0.4064)
			(end 0.7874 0.4064)
			(stroke
				(width 0.1524)
				(type default)
			)
			(layer "F.SilkS")
		)
		(fp_line
			(start -0.7874 -0.4064)
			(end 0.7874 -0.4064)
			(stroke
				(width 0.1524)
				(type default)
			)
			(layer "F.SilkS")
		)
		(fp_line
			(start 0.7874 0.4064)
			(end -0.7874 0.4064)
			(stroke
				(width 0.1524)
				(type default)
			)
			(layer "F.SilkS")
		)
		(fp_line
			(start -0.7874 0.4064)
			(end -0.7874 -0.4064)
			(stroke
				(width 0.1524)
				(type default)
			)
			(layer "F.SilkS")
		)
		(fp_line
			(start -0.12065 -0.305054)
			(end -0.12065 -0.2794)
			(stroke
				(width 0.1)
				(type default)
			)
			(layer "F.Fab")
		)
		(fp_line
			(start -0.67945 -0.305054)
			(end -0.12065 -0.305054)
			(stroke
				(width 0.1)
				(type default)
			)
			(layer "F.Fab")
		)
		(fp_line
			(start 0.67945 -0.3048)
			(end 0.67945 0.3048)
			(stroke
				(width 0.1)
				(type default)
			)
			(layer "F.Fab")
		)
		(fp_line
			(start 0.12065 -0.3048)
			(end 0.67945 -0.3048)
			(stroke
				(width 0.1)
				(type default)
			)
			(layer "F.Fab")
		)
		(fp_line
			(start 0.12065 -0.2794)
			(end 0.12065 -0.3048)
			(stroke
				(width 0.1)
				(type default)
			)
			(layer "F.Fab")
		)
		(fp_line
			(start -0.12065 -0.2794)
			(end 0.12065 -0.2794)
			(stroke
				(width 0.1)
				(type default)
			)
			(layer "F.Fab")
		)
		(fp_line
			(start 0.120396 0.2794)
			(end -0.12065 0.2794)
			(stroke
				(width 0.1)
				(type default)
			)
			(layer "F.Fab")
		)
		(fp_line
			(start -0.12065 0.2794)
			(end -0.12065 0.3048)
			(stroke
				(width 0.1)
				(type default)
			)
			(layer "F.Fab")
		)
		(fp_line
			(start 0.67945 0.3048)
			(end 0.120396 0.3048)
			(stroke
				(width 0.1)
				(type default)
			)
			(layer "F.Fab")
		)
		(fp_line
			(start 0.120396 0.3048)
			(end 0.120396 0.2794)
			(stroke
				(width 0.1)
				(type default)
			)
			(layer "F.Fab")
		)
		(fp_line
			(start -0.12065 0.3048)
			(end -0.67945 0.3048)
			(stroke
				(width 0.1)
				(type default)
			)
			(layer "F.Fab")
		)
		(fp_line
			(start -0.67945 0.3048)
			(end -0.67945 -0.305054)
			(stroke
				(width 0.1)
				(type default)
			)
			(layer "F.Fab")
		)
		(pad "1" smd circle
			(at -0.40005 0 90)
			(size 0 0)
			(layers "F.Cu" "F.Mask" "F.Paste")
			(net "CLK_GEN2_XTAL_IN_R")
		)
		(pad "2" smd circle
			(at 0.40005 0 90)
			(size 0 0)
			(layers "F.Cu" "F.Mask" "F.Paste")
			(net "GND")
		)
	)
	(footprint ""
		(layer "F.Cu")
		(at 83.589114 -177.532284)
		(property "Reference" "PR187"
			(at 0 0 0)
			(layer "F.SilkS")
			(hide yes)
			(effects
				(font
					(size 1.27 1.27)
				)
			)
		)
		(property "Value" ""
			(at 0 0 0)
			(layer "F.Fab")
			(effects
				(font
					(size 1.27 1.27)
				)
			)
		)
		(duplicate_pad_numbers_are_jumpers no)
		(fp_line
			(start -0.7874 -0.4064)
			(end 0.7874 -0.4064)
			(stroke
				(width 0.1524)
				(type default)
			)
			(layer "F.SilkS")
		)
		(fp_line
			(start -0.7874 0.4064)
			(end -0.7874 -0.4064)
			(stroke
				(width 0.1524)
				(type default)
			)
			(layer "F.SilkS")
		)
		(fp_line
			(start 0.7874 -0.4064)
			(end 0.7874 0.4064)
			(stroke
				(width 0.1524)
				(type default)
			)
			(layer "F.SilkS")
		)
		(fp_line
			(start 0.7874 0.4064)
			(end -0.7874 0.4064)
			(stroke
				(width 0.1524)
				(type default)
			)
			(layer "F.SilkS")
		)
		(fp_line
			(start -0.67945 -0.305054)
			(end -0.12065 -0.305054)
			(stroke
				(width 0.1)
				(type default)
			)
			(layer "F.Fab")
		)
		(fp_line
			(start -0.67945 0.3048)
			(end -0.67945 -0.305054)
			(stroke
				(width 0.1)
				(type default)
			)
			(layer "F.Fab")
		)
		(fp_line
			(start -0.12065 -0.305054)
			(end -0.12065 -0.2794)
			(stroke
				(width 0.1)
				(type default)
			)
			(layer "F.Fab")
		)
		(fp_line
			(start -0.12065 -0.2794)
			(end 0.12065 -0.2794)
			(stroke
				(width 0.1)
				(type default)
			)
			(layer "F.Fab")
		)
		(fp_line
			(start -0.12065 0.2794)
			(end -0.12065 0.3048)
			(stroke
				(width 0.1)
				(type default)
			)
			(layer "F.Fab")
		)
		(fp_line
			(start -0.12065 0.3048)
			(end -0.67945 0.3048)
			(stroke
				(width 0.1)
				(type default)
			)
			(layer "F.Fab")
		)
		(fp_line
			(start 0.120396 0.2794)
			(end -0.12065 0.2794)
			(stroke
				(width 0.1)
				(type default)
			)
			(layer "F.Fab")
		)
		(fp_line
			(start 0.120396 0.3048)
			(end 0.120396 0.2794)
			(stroke
				(width 0.1)
				(type default)
			)
			(layer "F.Fab")
		)
		(fp_line
			(start 0.12065 -0.3048)
			(end 0.67945 -0.3048)
			(stroke
				(width 0.1)
				(type default)
			)
			(layer "F.Fab")
		)
		(fp_line
			(start 0.12065 -0.2794)
			(end 0.12065 -0.3048)
			(stroke
				(width 0.1)
				(type default)
			)
			(layer "F.Fab")
		)
		(fp_line
			(start 0.67945 -0.3048)
			(end 0.67945 0.3048)
			(stroke
				(width 0.1)
				(type default)
			)
			(layer "F.Fab")
		)
		(fp_line
			(start 0.67945 0.3048)
			(end 0.120396 0.3048)
			(stroke
				(width 0.1)
				(type default)
			)
			(layer "F.Fab")
		)
		(pad "1" smd circle
			(at -0.40005 0)
			(size 0 0)
			(layers "F.Cu" "F.Mask" "F.Paste")
			(net "GND")
		)
		(pad "2" smd circle
			(at 0.40005 0)
			(size 0 0)
			(layers "F.Cu" "F.Mask" "F.Paste")
			(net "PVDDCR_CPU0_P1_LSET1")
		)
	)
	(footprint ""
		(layer "F.Cu")
		(at 213.919054 -124.604018)
		(property "Reference" "R905"
			(at 0 0 0)
			(layer "F.SilkS")
			(hide yes)
			(effects
				(font
					(size 1.27 1.27)
				)
			)
		)
		(property "Value" ""
			(at 0 0 0)
			(layer "F.Fab")
			(effects
				(font
					(size 1.27 1.27)
				)
			)
		)
		(duplicate_pad_numbers_are_jumpers no)
		(fp_line
			(start -0.7874 -0.4064)
			(end 0.7874 -0.4064)
			(stroke
				(width 0.1524)
				(type default)
			)
			(layer "F.SilkS")
		)
		(fp_line
			(start -0.7874 0.4064)
			(end -0.7874 -0.4064)
			(stroke
				(width 0.1524)
				(type default)
			)
			(layer "F.SilkS")
		)
		(fp_line
			(start 0.7874 -0.4064)
			(end 0.7874 0.4064)
			(stroke
				(width 0.1524)
				(type default)
			)
			(layer "F.SilkS")
		)
		(fp_line
			(start 0.7874 0.4064)
			(end -0.7874 0.4064)
			(stroke
				(width 0.1524)
				(type default)
			)
			(layer "F.SilkS")
		)
		(fp_line
			(start -0.67945 -0.305054)
			(end -0.12065 -0.305054)
			(stroke
				(width 0.1)
				(type default)
			)
			(layer "F.Fab")
		)
		(fp_line
			(start -0.67945 0.3048)
			(end -0.67945 -0.305054)
			(stroke
				(width 0.1)
				(type default)
			)
			(layer "F.Fab")
		)
		(fp_line
			(start -0.12065 -0.305054)
			(end -0.12065 -0.2794)
			(stroke
				(width 0.1)
				(type default)
			)
			(layer "F.Fab")
		)
		(fp_line
			(start -0.12065 -0.2794)
			(end 0.12065 -0.2794)
			(stroke
				(width 0.1)
				(type default)
			)
			(layer "F.Fab")
		)
		(fp_line
			(start -0.12065 0.2794)
			(end -0.12065 0.3048)
			(stroke
				(width 0.1)
				(type default)
			)
			(layer "F.Fab")
		)
		(fp_line
			(start -0.12065 0.3048)
			(end -0.67945 0.3048)
			(stroke
				(width 0.1)
				(type default)
			)
			(layer "F.Fab")
		)
		(fp_line
			(start 0.120396 0.2794)
			(end -0.12065 0.2794)
			(stroke
				(width 0.1)
				(type default)
			)
			(layer "F.Fab")
		)
		(fp_line
			(start 0.120396 0.3048)
			(end 0.120396 0.2794)
			(stroke
				(width 0.1)
				(type default)
			)
			(layer "F.Fab")
		)
		(fp_line
			(start 0.12065 -0.3048)
			(end 0.67945 -0.3048)
			(stroke
				(width 0.1)
				(type default)
			)
			(layer "F.Fab")
		)
		(fp_line
			(start 0.12065 -0.2794)
			(end 0.12065 -0.3048)
			(stroke
				(width 0.1)
				(type default)
			)
			(layer "F.Fab")
		)
		(fp_line
			(start 0.67945 -0.3048)
			(end 0.67945 0.3048)
			(stroke
				(width 0.1)
				(type default)
			)
			(layer "F.Fab")
		)
		(fp_line
			(start 0.67945 0.3048)
			(end 0.120396 0.3048)
			(stroke
				(width 0.1)
				(type default)
			)
			(layer "F.Fab")
		)
		(pad "1" smd circle
			(at -0.40005 0)
			(size 0 0)
			(layers "F.Cu" "F.Mask" "F.Paste")
			(net "RST_PERST_OCP_SFF_BUF2_N")
		)
		(pad "2" smd circle
			(at 0.40005 0)
			(size 0 0)
			(layers "F.Cu" "F.Mask" "F.Paste")
			(net "RST_PERST2_OCP_SFF_N")
		)
	)
	(footprint ""
		(layer "F.Cu")
		(at 161.731706 -408.517344 -90)
		(property "Reference" "C6723"
			(at 0 0 270)
			(layer "F.SilkS")
			(hide yes)
			(effects
				(font
					(size 1.27 1.27)
				)
			)
		)
		(property "Value" ""
			(at 0 0 270)
			(layer "F.Fab")
			(effects
				(font
					(size 1.27 1.27)
				)
			)
		)
		(duplicate_pad_numbers_are_jumpers no)
		(fp_line
			(start -0.299974 0.150114)
			(end -0.299974 -0.150114)
			(stroke
				(width 0.1)
				(type default)
			)
			(layer "F.Fab")
		)
		(fp_line
			(start 0.299974 0.150114)
			(end -0.299974 0.150114)
			(stroke
				(width 0.1)
				(type default)
			)
			(layer "F.Fab")
		)
		(fp_line
			(start -0.299974 -0.150114)
			(end 0.299974 -0.150114)
			(stroke
				(width 0.1)
				(type default)
			)
			(layer "F.Fab")
		)
		(fp_line
			(start 0.299974 -0.150114)
			(end 0.299974 0.150114)
			(stroke
				(width 0.1)
				(type default)
			)
			(layer "F.Fab")
		)
		(pad "1" smd rect
			(at -0.2667 0 270)
			(size 0.3048 0.381)
			(layers "F.Cu" "F.Mask" "F.Paste")
			(net "P5E_CPU1_P2_TX_BUF_C_DP<15>")
		)
		(pad "2" smd rect
			(at 0.2667 0 270)
			(size 0.3048 0.381)
			(layers "F.Cu" "F.Mask" "F.Paste")
			(net "P5E_CPU1_P2_TX_BUF_DP<15>")
		)
	)
	(footprint ""
		(layer "F.Cu")
		(at 178.943 -133.568948 -90)
		(property "Reference" "R216"
			(at 0 0 270)
			(layer "F.SilkS")
			(hide yes)
			(effects
				(font
					(size 1.27 1.27)
				)
			)
		)
		(property "Value" ""
			(at 0 0 270)
			(layer "F.Fab")
			(effects
				(font
					(size 1.27 1.27)
				)
			)
		)
		(duplicate_pad_numbers_are_jumpers no)
		(fp_line
			(start -0.7874 0.4064)
			(end -0.7874 -0.4064)
			(stroke
				(width 0.1524)
				(type default)
			)
			(layer "F.SilkS")
		)
		(fp_line
			(start 0.7874 0.4064)
			(end -0.7874 0.4064)
			(stroke
				(width 0.1524)
				(type default)
			)
			(layer "F.SilkS")
		)
		(fp_line
			(start -0.7874 -0.4064)
			(end 0.7874 -0.4064)
			(stroke
				(width 0.1524)
				(type default)
			)
			(layer "F.SilkS")
		)
		(fp_line
			(start 0.7874 -0.4064)
			(end 0.7874 0.4064)
			(stroke
				(width 0.1524)
				(type default)
			)
			(layer "F.SilkS")
		)
		(fp_line
			(start -0.67945 0.3048)
			(end -0.67945 -0.305054)
			(stroke
				(width 0.1)
				(type default)
			)
			(layer "F.Fab")
		)
		(fp_line
			(start -0.12065 0.3048)
			(end -0.67945 0.3048)
			(stroke
				(width 0.1)
				(type default)
			)
			(layer "F.Fab")
		)
		(fp_line
			(start 0.120396 0.3048)
			(end 0.120396 0.2794)
			(stroke
				(width 0.1)
				(type default)
			)
			(layer "F.Fab")
		)
		(fp_line
			(start 0.67945 0.3048)
			(end 0.120396 0.3048)
			(stroke
				(width 0.1)
				(type default)
			)
			(layer "F.Fab")
		)
		(fp_line
			(start -0.12065 0.2794)
			(end -0.12065 0.3048)
			(stroke
				(width 0.1)
				(type default)
			)
			(layer "F.Fab")
		)
		(fp_line
			(start 0.120396 0.2794)
			(end -0.12065 0.2794)
			(stroke
				(width 0.1)
				(type default)
			)
			(layer "F.Fab")
		)
		(fp_line
			(start -0.12065 -0.2794)
			(end 0.12065 -0.2794)
			(stroke
				(width 0.1)
				(type default)
			)
			(layer "F.Fab")
		)
		(fp_line
			(start 0.12065 -0.2794)
			(end 0.12065 -0.3048)
			(stroke
				(width 0.1)
				(type default)
			)
			(layer "F.Fab")
		)
		(fp_line
			(start 0.12065 -0.3048)
			(end 0.67945 -0.3048)
			(stroke
				(width 0.1)
				(type default)
			)
			(layer "F.Fab")
		)
		(fp_line
			(start 0.67945 -0.3048)
			(end 0.67945 0.3048)
			(stroke
				(width 0.1)
				(type default)
			)
			(layer "F.Fab")
		)
		(fp_line
			(start -0.67945 -0.305054)
			(end -0.12065 -0.305054)
			(stroke
				(width 0.1)
				(type default)
			)
			(layer "F.Fab")
		)
		(fp_line
			(start -0.12065 -0.305054)
			(end -0.12065 -0.2794)
			(stroke
				(width 0.1)
				(type default)
			)
			(layer "F.Fab")
		)
		(pad "1" smd circle
			(at -0.40005 0 270)
			(size 0 0)
			(layers "F.Cu" "F.Mask" "F.Paste")
			(net "RST_CPU0_SYS_N")
		)
		(pad "2" smd circle
			(at 0.40005 0 270)
			(size 0 0)
			(layers "F.Cu" "F.Mask" "F.Paste")
			(net "FM_CPU0_SYS_RESET_N")
		)
	)
	(footprint ""
		(layer "F.Cu")
		(at 28.021026 -427.612302)
		(property "Reference" "R6157"
			(at 0 0 0)
			(layer "F.SilkS")
			(hide yes)
			(effects
				(font
					(size 1.27 1.27)
				)
			)
		)
		(property "Value" ""
			(at 0 0 0)
			(layer "F.Fab")
			(effects
				(font
					(size 1.27 1.27)
				)
			)
		)
		(duplicate_pad_numbers_are_jumpers no)
		(fp_line
			(start -0.32512 -0.175006)
			(end 0.32512 -0.175006)
			(stroke
				(width 0.1)
				(type default)
			)
			(layer "F.Fab")
		)
		(fp_line
			(start -0.32512 0.175006)
			(end -0.32512 -0.175006)
			(stroke
				(width 0.1)
				(type default)
			)
			(layer "F.Fab")
		)
		(fp_line
			(start 0.32512 -0.175006)
			(end 0.32512 0.175006)
			(stroke
				(width 0.1)
				(type default)
			)
			(layer "F.Fab")
		)
		(fp_line
			(start 0.32512 0.175006)
			(end -0.32512 0.175006)
			(stroke
				(width 0.1)
				(type default)
			)
			(layer "F.Fab")
		)
		(pad "1" smd rect
			(at -0.2667 0)
			(size 0.3048 0.381)
			(layers "F.Cu" "F.Mask" "F.Paste")
			(net "P2E_MB_BMC_RX_DN<0>")
		)
		(pad "2" smd rect
			(at 0.2667 0 180)
			(size 0.3048 0.381)
			(layers "F.Cu" "F.Mask" "F.Paste")
			(net "P2E_MB_BMC_RX_R1_DN<0>")
		)
	)
	(footprint ""
		(layer "F.Cu")
		(at 51.746404 -408.517344 -90)
		(property "Reference" "C6631"
			(at 0 0 270)
			(layer "F.SilkS")
			(hide yes)
			(effects
				(font
					(size 1.27 1.27)
				)
			)
		)
		(property "Value" ""
			(at 0 0 270)
			(layer "F.Fab")
			(effects
				(font
					(size 1.27 1.27)
				)
			)
		)
		(duplicate_pad_numbers_are_jumpers no)
		(fp_line
			(start -0.299974 0.150114)
			(end -0.299974 -0.150114)
			(stroke
				(width 0.1)
				(type default)
			)
			(layer "F.Fab")
		)
		(fp_line
			(start 0.299974 0.150114)
			(end -0.299974 0.150114)
			(stroke
				(width 0.1)
				(type default)
			)
			(layer "F.Fab")
		)
		(fp_line
			(start -0.299974 -0.150114)
			(end 0.299974 -0.150114)
			(stroke
				(width 0.1)
				(type default)
			)
			(layer "F.Fab")
		)
		(fp_line
			(start 0.299974 -0.150114)
			(end 0.299974 0.150114)
			(stroke
				(width 0.1)
				(type default)
			)
			(layer "F.Fab")
		)
		(pad "1" smd rect
			(at -0.2667 0 270)
			(size 0.3048 0.381)
			(layers "F.Cu" "F.Mask" "F.Paste")
			(net "P5E_CPU1_P0_TX_BUF_C_DP<1>")
		)
		(pad "2" smd rect
			(at 0.2667 0 270)
			(size 0.3048 0.381)
			(layers "F.Cu" "F.Mask" "F.Paste")
			(net "P5E_CPU1_P0_TX_BUF_DP<1>")
		)
	)
	(footprint ""
		(layer "F.Cu")
		(at 154.998166 -57.118758)
		(property "Reference" "U264"
			(at 4.994656 -3.027426 0)
			(unlocked yes)
			(layer "F.SilkS")
			(effects
				(font
					(size 0.7874 0.5842)
					(thickness 0.1524)
				)
			)
		)
		(property "Value" ""
			(at 0 0 0)
			(layer "F.Fab")
			(effects
				(font
					(size 1.27 1.27)
				)
			)
		)
		(duplicate_pad_numbers_are_jumpers no)
		(fp_line
			(start -1.500124 -1.500124)
			(end -1.004062 -1.500124)
			(stroke
				(width 0.1524)
				(type default)
			)
			(layer "F.SilkS")
		)
		(fp_line
			(start -1.500124 -1.004062)
			(end -1.500124 -1.500124)
			(stroke
				(width 0.1524)
				(type default)
			)
			(layer "F.SilkS")
		)
		(fp_line
			(start -1.500124 1.500124)
			(end -1.500124 1.004062)
			(stroke
				(width 0.1524)
				(type default)
			)
			(layer "F.SilkS")
		)
		(fp_line
			(start -1.004062 1.500124)
			(end -1.500124 1.500124)
			(stroke
				(width 0.1524)
				(type default)
			)
			(layer "F.SilkS")
		)
		(fp_line
			(start 1.004062 -1.500124)
			(end 1.500124 -1.500124)
			(stroke
				(width 0.1524)
				(type default)
			)
			(layer "F.SilkS")
		)
		(fp_line
			(start 1.500124 -1.500124)
			(end 1.500124 -1.004062)
			(stroke
				(width 0.1524)
				(type default)
			)
			(layer "F.SilkS")
		)
		(fp_line
			(start 1.500124 1.004062)
			(end 1.500124 1.500124)
			(stroke
				(width 0.1524)
				(type default)
			)
			(layer "F.SilkS")
		)
		(fp_line
			(start 1.500124 1.500124)
			(end 1.004062 1.500124)
			(stroke
				(width 0.1524)
				(type default)
			)
			(layer "F.SilkS")
		)
		(fp_poly
			(pts
				(xy -3.570986 -0.960882) (xy -3.08737 -1.854454) (xy -2.435606 -0.924306)
			)
			(stroke
				(width 0)
				(type default)
			)
			(fill yes)
			(layer "F.SilkS")
		)
		(fp_line
			(start -1.500124 -1.500124)
			(end 1.500124 -1.500124)
			(stroke
				(width 0.1)
				(type default)
			)
			(layer "F.Fab")
		)
		(fp_line
			(start -1.500124 1.500124)
			(end -1.500124 -1.500124)
			(stroke
				(width 0.1)
				(type default)
			)
			(layer "F.Fab")
		)
		(fp_line
			(start 1.500124 -1.500124)
			(end 1.500124 1.500124)
			(stroke
				(width 0.1)
				(type default)
			)
			(layer "F.Fab")
		)
		(fp_line
			(start 1.500124 1.500124)
			(end -1.500124 1.500124)
			(stroke
				(width 0.1)
				(type default)
			)
			(layer "F.Fab")
		)
		(fp_poly
			(pts
				(xy -2.847848 -1.258062) (xy -2.847848 -0.242062) (xy -1.831848 -0.750062)
			)
			(stroke
				(width 0)
				(type default)
			)
			(fill yes)
			(layer "F.Fab")
		)
		(pad "1" smd rect
			(at -1.400048 -0.750062 270)
			(size 0.2286 0.6096)
			(layers "F.Cu" "F.Mask" "F.Paste")
			(net "INA230_4_A1")
		)
		(pad "2" smd rect
			(at -1.400048 -0.249936 270)
			(size 0.2286 0.6096)
			(layers "F.Cu" "F.Mask" "F.Paste")
			(net "INA230_4_A0")
		)
		(pad "3" smd rect
			(at -1.400048 0.249936 270)
			(size 0.2286 0.6096)
			(layers "F.Cu" "F.Mask" "F.Paste")
			(net "M2_0_P3V3_ADC_ALERT_R")
		)
		(pad "4" smd rect
			(at -1.400048 0.750062 270)
			(size 0.2286 0.6096)
			(layers "F.Cu" "F.Mask" "F.Paste")
			(net "SMB_INA230_4_3V3AUX_SDA_R1")
		)
		(pad "5" smd rect
			(at -0.750062 1.400048)
			(size 0.2286 0.6096)
			(layers "F.Cu" "F.Mask" "F.Paste")
			(net "SMB_INA230_4_3V3AUX_SCL_R1")
		)
		(pad "6" smd rect
			(at -0.249936 1.400048)
			(size 0.2286 0.6096)
			(layers "F.Cu" "F.Mask" "F.Paste")
			(net "NC_INA230_4_NC0")
		)
		(pad "7" smd rect
			(at 0.249936 1.400048)
			(size 0.2286 0.6096)
			(layers "F.Cu" "F.Mask" "F.Paste")
			(net "NC_INA230_4_NC1")
		)
		(pad "8" smd rect
			(at 0.750062 1.400048)
			(size 0.2286 0.6096)
			(layers "F.Cu" "F.Mask" "F.Paste")
			(net "NC_INA230_4_NC2")
		)
		(pad "9" smd rect
			(at 1.400048 0.750062 270)
			(size 0.2286 0.6096)
			(layers "F.Cu" "F.Mask" "F.Paste")
			(net "P3V3_AUX")
		)
		(pad "10" smd rect
			(at 1.400048 0.249936 270)
			(size 0.2286 0.6096)
			(layers "F.Cu" "F.Mask" "F.Paste")
			(net "GND")
		)
		(pad "11" smd rect
			(at 1.400048 -0.249936 270)
			(size 0.2286 0.6096)
			(layers "F.Cu" "F.Mask" "F.Paste")
			(net "P3V3")
		)
		(pad "12" smd rect
			(at 1.400048 -0.750062 270)
			(size 0.2286 0.6096)
			(layers "F.Cu" "F.Mask" "F.Paste")
			(net "VSENSE_P12V_INA230_4_INN")
		)
		(pad "13" smd rect
			(at 0.750062 -1.400048)
			(size 0.2286 0.6096)
			(layers "F.Cu" "F.Mask" "F.Paste")
			(net "VSENSE_P12V_INA230_4_INP")
		)
		(pad "14" smd rect
			(at 0.249936 -1.400048)
			(size 0.2286 0.6096)
			(layers "F.Cu" "F.Mask" "F.Paste")
			(net "NC_INA230_4_NC3")
		)
		(pad "15" smd rect
			(at -0.249936 -1.400048)
			(size 0.2286 0.6096)
			(layers "F.Cu" "F.Mask" "F.Paste")
			(net "NC_INA230_4_NC4")
		)
		(pad "16" smd rect
			(at -0.750062 -1.400048)
			(size 0.2286 0.6096)
			(layers "F.Cu" "F.Mask" "F.Paste")
			(net "NC_INA230_4_NC5")
		)
		(pad "TH" smd rect
			(at 0 0)
			(size 1.7018 1.7018)
			(layers "F.Cu" "F.Mask" "F.Paste")
			(net "GND")
		)
		(zone
			(layer "F.Cu")
			(hatch none 0.5)
			(connect_pads
				(clearance 0)
			)
			(min_thickness 0.25)
			(keepout
				(tracks not_allowed)
				(vias allowed)
				(pads allowed)
				(copperpour not_allowed)
				(footprints allowed)
			)
			(placement
				(enabled no)
				(sheetname "")
			)
			(fill
				(thermal_gap 0.5)
				(thermal_bridge_width 0.5)
				(island_removal_mode 0)
			)
			(polygon
				(pts
					(xy 153.953718 -57.118758) (xy 154.096466 -57.118758) (xy 154.096466 -56.217058) (xy 155.899866 -56.217058)
					(xy 155.899866 -56.64454) (xy 156.042614 -56.64454) (xy 156.042614 -56.07431) (xy 153.953718 -56.07431)
				)
			)
		)
	)
	(footprint ""
		(layer "F.Cu")
		(at 297.486324 -116.545614 180)
		(property "Reference" "R66"
			(at 0 0 180)
			(layer "F.SilkS")
			(hide yes)
			(effects
				(font
					(size 1.27 1.27)
				)
			)
		)
		(property "Value" ""
			(at 0 0 180)
			(layer "F.Fab")
			(effects
				(font
					(size 1.27 1.27)
				)
			)
		)
		(duplicate_pad_numbers_are_jumpers no)
		(fp_line
			(start 0.7874 0.4064)
			(end -0.7874 0.4064)
			(stroke
				(width 0.1524)
				(type default)
			)
			(layer "F.SilkS")
		)
		(fp_line
			(start 0.7874 -0.4064)
			(end 0.7874 0.4064)
			(stroke
				(width 0.1524)
				(type default)
			)
			(layer "F.SilkS")
		)
		(fp_line
			(start -0.7874 0.4064)
			(end -0.7874 -0.4064)
			(stroke
				(width 0.1524)
				(type default)
			)
			(layer "F.SilkS")
		)
		(fp_line
			(start -0.7874 -0.4064)
			(end 0.7874 -0.4064)
			(stroke
				(width 0.1524)
				(type default)
			)
			(layer "F.SilkS")
		)
		(fp_line
			(start 0.67945 0.3048)
			(end 0.120396 0.3048)
			(stroke
				(width 0.1)
				(type default)
			)
			(layer "F.Fab")
		)
		(fp_line
			(start 0.67945 -0.3048)
			(end 0.67945 0.3048)
			(stroke
				(width 0.1)
				(type default)
			)
			(layer "F.Fab")
		)
		(fp_line
			(start 0.12065 -0.2794)
			(end 0.12065 -0.3048)
			(stroke
				(width 0.1)
				(type default)
			)
			(layer "F.Fab")
		)
		(fp_line
			(start 0.12065 -0.3048)
			(end 0.67945 -0.3048)
			(stroke
				(width 0.1)
				(type default)
			)
			(layer "F.Fab")
		)
		(fp_line
			(start 0.120396 0.3048)
			(end 0.120396 0.2794)
			(stroke
				(width 0.1)
				(type default)
			)
			(layer "F.Fab")
		)
		(fp_line
			(start 0.120396 0.2794)
			(end -0.12065 0.2794)
			(stroke
				(width 0.1)
				(type default)
			)
			(layer "F.Fab")
		)
		(fp_line
			(start -0.12065 0.3048)
			(end -0.67945 0.3048)
			(stroke
				(width 0.1)
				(type default)
			)
			(layer "F.Fab")
		)
		(fp_line
			(start -0.12065 0.2794)
			(end -0.12065 0.3048)
			(stroke
				(width 0.1)
				(type default)
			)
			(layer "F.Fab")
		)
		(fp_line
			(start -0.12065 -0.2794)
			(end 0.12065 -0.2794)
			(stroke
				(width 0.1)
				(type default)
			)
			(layer "F.Fab")
		)
		(fp_line
			(start -0.12065 -0.305054)
			(end -0.12065 -0.2794)
			(stroke
				(width 0.1)
				(type default)
			)
			(layer "F.Fab")
		)
		(fp_line
			(start -0.67945 0.3048)
			(end -0.67945 -0.305054)
			(stroke
				(width 0.1)
				(type default)
			)
			(layer "F.Fab")
		)
		(fp_line
			(start -0.67945 -0.305054)
			(end -0.12065 -0.305054)
			(stroke
				(width 0.1)
				(type default)
			)
			(layer "F.Fab")
		)
		(pad "1" smd circle
			(at -0.40005 0 180)
			(size 0 0)
			(layers "F.Cu" "F.Mask" "F.Paste")
			(net "P3V3_AUX")
		)
		(pad "2" smd circle
			(at 0.40005 0 180)
			(size 0 0)
			(layers "F.Cu" "F.Mask" "F.Paste")
			(net "SMB_FRU_3V3AUX_SCL")
		)
	)
	(footprint ""
		(layer "F.Cu")
		(at 394.067284 -391.0584 180)
		(property "Reference" "R1101"
			(at 0 0 180)
			(layer "F.SilkS")
			(hide yes)
			(effects
				(font
					(size 1.27 1.27)
				)
			)
		)
		(property "Value" ""
			(at 0 0 180)
			(layer "F.Fab")
			(effects
				(font
					(size 1.27 1.27)
				)
			)
		)
		(duplicate_pad_numbers_are_jumpers no)
		(fp_line
			(start 0.32512 0.175006)
			(end -0.32512 0.175006)
			(stroke
				(width 0.1)
				(type default)
			)
			(layer "F.Fab")
		)
		(fp_line
			(start 0.32512 -0.175006)
			(end 0.32512 0.175006)
			(stroke
				(width 0.1)
				(type default)
			)
			(layer "F.Fab")
		)
		(fp_line
			(start -0.32512 0.175006)
			(end -0.32512 -0.175006)
			(stroke
				(width 0.1)
				(type default)
			)
			(layer "F.Fab")
		)
		(fp_line
			(start -0.32512 -0.175006)
			(end 0.32512 -0.175006)
			(stroke
				(width 0.1)
				(type default)
			)
			(layer "F.Fab")
		)
		(pad "1" smd rect
			(at -0.2667 0 180)
			(size 0.3048 0.381)
			(layers "F.Cu" "F.Mask" "F.Paste")
			(net "P1V8_CPU0_RT_1D")
		)
		(pad "2" smd rect
			(at 0.2667 0)
			(size 0.3048 0.381)
			(layers "F.Cu" "F.Mask" "F.Paste")
			(net "RT_CPU0_P3_ADDR1")
		)
	)
	(footprint ""
		(layer "F.Cu")
		(at 440.40171 -14.643354 180)
		(property "Reference" "C1236"
			(at 0 0 180)
			(layer "F.SilkS")
			(hide yes)
			(effects
				(font
					(size 1.27 1.27)
				)
			)
		)
		(property "Value" ""
			(at 0 0 180)
			(layer "F.Fab")
			(effects
				(font
					(size 1.27 1.27)
				)
			)
		)
		(duplicate_pad_numbers_are_jumpers no)
		(fp_line
			(start 0.7874 0.4064)
			(end -0.7874 0.4064)
			(stroke
				(width 0.1524)
				(type default)
			)
			(layer "F.SilkS")
		)
		(fp_line
			(start 0.7874 -0.4064)
			(end 0.7874 0.4064)
			(stroke
				(width 0.1524)
				(type default)
			)
			(layer "F.SilkS")
		)
		(fp_line
			(start -0.7874 0.4064)
			(end -0.7874 -0.4064)
			(stroke
				(width 0.1524)
				(type default)
			)
			(layer "F.SilkS")
		)
		(fp_line
			(start -0.7874 -0.4064)
			(end 0.7874 -0.4064)
			(stroke
				(width 0.1524)
				(type default)
			)
			(layer "F.SilkS")
		)
		(fp_line
			(start 0.67945 0.3048)
			(end 0.120396 0.3048)
			(stroke
				(width 0.1)
				(type default)
			)
			(layer "F.Fab")
		)
		(fp_line
			(start 0.67945 -0.3048)
			(end 0.67945 0.3048)
			(stroke
				(width 0.1)
				(type default)
			)
			(layer "F.Fab")
		)
		(fp_line
			(start 0.12065 -0.2794)
			(end 0.12065 -0.3048)
			(stroke
				(width 0.1)
				(type default)
			)
			(layer "F.Fab")
		)
		(fp_line
			(start 0.12065 -0.3048)
			(end 0.67945 -0.3048)
			(stroke
				(width 0.1)
				(type default)
			)
			(layer "F.Fab")
		)
		(fp_line
			(start 0.120396 0.3048)
			(end 0.120396 0.2794)
			(stroke
				(width 0.1)
				(type default)
			)
			(layer "F.Fab")
		)
		(fp_line
			(start 0.120396 0.2794)
			(end -0.12065 0.2794)
			(stroke
				(width 0.1)
				(type default)
			)
			(layer "F.Fab")
		)
		(fp_line
			(start -0.12065 0.3048)
			(end -0.67945 0.3048)
			(stroke
				(width 0.1)
				(type default)
			)
			(layer "F.Fab")
		)
		(fp_line
			(start -0.12065 0.2794)
			(end -0.12065 0.3048)
			(stroke
				(width 0.1)
				(type default)
			)
			(layer "F.Fab")
		)
		(fp_line
			(start -0.12065 -0.2794)
			(end 0.12065 -0.2794)
			(stroke
				(width 0.1)
				(type default)
			)
			(layer "F.Fab")
		)
		(fp_line
			(start -0.12065 -0.305054)
			(end -0.12065 -0.2794)
			(stroke
				(width 0.1)
				(type default)
			)
			(layer "F.Fab")
		)
		(fp_line
			(start -0.67945 0.3048)
			(end -0.67945 -0.305054)
			(stroke
				(width 0.1)
				(type default)
			)
			(layer "F.Fab")
		)
		(fp_line
			(start -0.67945 -0.305054)
			(end -0.12065 -0.305054)
			(stroke
				(width 0.1)
				(type default)
			)
			(layer "F.Fab")
		)
		(pad "1" smd circle
			(at -0.40005 0 180)
			(size 0 0)
			(layers "F.Cu" "F.Mask" "F.Paste")
			(net "P12V_OCP_SFF_R")
		)
		(pad "2" smd circle
			(at 0.40005 0 180)
			(size 0 0)
			(layers "F.Cu" "F.Mask" "F.Paste")
			(net "GND")
		)
	)
	(footprint ""
		(layer "F.Cu")
		(at 183.769 -92.674948 90)
		(property "Reference" "R6074"
			(at 0 0 90)
			(layer "F.SilkS")
			(hide yes)
			(effects
				(font
					(size 1.27 1.27)
				)
			)
		)
		(property "Value" ""
			(at 0 0 90)
			(layer "F.Fab")
			(effects
				(font
					(size 1.27 1.27)
				)
			)
		)
		(duplicate_pad_numbers_are_jumpers no)
		(fp_line
			(start 0.7874 -0.4064)
			(end 0.7874 0.4064)
			(stroke
				(width 0.1524)
				(type default)
			)
			(layer "F.SilkS")
		)
		(fp_line
			(start -0.7874 -0.4064)
			(end 0.7874 -0.4064)
			(stroke
				(width 0.1524)
				(type default)
			)
			(layer "F.SilkS")
		)
		(fp_line
			(start 0.7874 0.4064)
			(end -0.7874 0.4064)
			(stroke
				(width 0.1524)
				(type default)
			)
			(layer "F.SilkS")
		)
		(fp_line
			(start -0.7874 0.4064)
			(end -0.7874 -0.4064)
			(stroke
				(width 0.1524)
				(type default)
			)
			(layer "F.SilkS")
		)
		(fp_line
			(start -0.12065 -0.305054)
			(end -0.12065 -0.2794)
			(stroke
				(width 0.1)
				(type default)
			)
			(layer "F.Fab")
		)
		(fp_line
			(start -0.67945 -0.305054)
			(end -0.12065 -0.305054)
			(stroke
				(width 0.1)
				(type default)
			)
			(layer "F.Fab")
		)
		(fp_line
			(start 0.67945 -0.3048)
			(end 0.67945 0.3048)
			(stroke
				(width 0.1)
				(type default)
			)
			(layer "F.Fab")
		)
		(fp_line
			(start 0.12065 -0.3048)
			(end 0.67945 -0.3048)
			(stroke
				(width 0.1)
				(type default)
			)
			(layer "F.Fab")
		)
		(fp_line
			(start 0.12065 -0.2794)
			(end 0.12065 -0.3048)
			(stroke
				(width 0.1)
				(type default)
			)
			(layer "F.Fab")
		)
		(fp_line
			(start -0.12065 -0.2794)
			(end 0.12065 -0.2794)
			(stroke
				(width 0.1)
				(type default)
			)
			(layer "F.Fab")
		)
		(fp_line
			(start 0.120396 0.2794)
			(end -0.12065 0.2794)
			(stroke
				(width 0.1)
				(type default)
			)
			(layer "F.Fab")
		)
		(fp_line
			(start -0.12065 0.2794)
			(end -0.12065 0.3048)
			(stroke
				(width 0.1)
				(type default)
			)
			(layer "F.Fab")
		)
		(fp_line
			(start 0.67945 0.3048)
			(end 0.120396 0.3048)
			(stroke
				(width 0.1)
				(type default)
			)
			(layer "F.Fab")
		)
		(fp_line
			(start 0.120396 0.3048)
			(end 0.120396 0.2794)
			(stroke
				(width 0.1)
				(type default)
			)
			(layer "F.Fab")
		)
		(fp_line
			(start -0.12065 0.3048)
			(end -0.67945 0.3048)
			(stroke
				(width 0.1)
				(type default)
			)
			(layer "F.Fab")
		)
		(fp_line
			(start -0.67945 0.3048)
			(end -0.67945 -0.305054)
			(stroke
				(width 0.1)
				(type default)
			)
			(layer "F.Fab")
		)
		(pad "1" smd circle
			(at -0.40005 0 90)
			(size 0 0)
			(layers "F.Cu" "F.Mask" "F.Paste")
			(net "FM_THERMAL_ALERT_N")
		)
		(pad "2" smd circle
			(at 0.40005 0 90)
			(size 0 0)
			(layers "F.Cu" "F.Mask" "F.Paste")
			(net "FM_THERMAL_ALERT_R_N")
		)
	)
	(footprint ""
		(layer "F.Cu")
		(at 403.961346 -142.871952 -90)
		(property "Reference" "C57"
			(at 0 0 270)
			(layer "F.SilkS")
			(hide yes)
			(effects
				(font
					(size 1.27 1.27)
				)
			)
		)
		(property "Value" ""
			(at 0 0 270)
			(layer "F.Fab")
			(effects
				(font
					(size 1.27 1.27)
				)
			)
		)
		(duplicate_pad_numbers_are_jumpers no)
		(fp_line
			(start -1.524 0.762)
			(end -1.524 -0.762)
			(stroke
				(width 0.1524)
				(type default)
			)
			(layer "F.SilkS")
		)
		(fp_line
			(start 1.524 0.762)
			(end -1.524 0.762)
			(stroke
				(width 0.1524)
				(type default)
			)
			(layer "F.SilkS")
		)
		(fp_line
			(start -1.524 -0.762)
			(end 1.524 -0.762)
			(stroke
				(width 0.1524)
				(type default)
			)
			(layer "F.SilkS")
		)
		(fp_line
			(start 1.524 -0.762)
			(end 1.524 0.762)
			(stroke
				(width 0.1524)
				(type default)
			)
			(layer "F.SilkS")
		)
		(fp_line
			(start -1.1049 0.724916)
			(end 1.1049 0.724916)
			(stroke
				(width 0.1)
				(type default)
			)
			(layer "F.Fab")
		)
		(fp_line
			(start 1.1049 0.724916)
			(end 1.1049 -0.724916)
			(stroke
				(width 0.1)
				(type default)
			)
			(layer "F.Fab")
		)
		(fp_line
			(start -1.1049 -0.724916)
			(end -1.1049 0.724916)
			(stroke
				(width 0.1)
				(type default)
			)
			(layer "F.Fab")
		)
		(fp_line
			(start 1.1049 -0.724916)
			(end -1.1049 -0.724916)
			(stroke
				(width 0.1)
				(type default)
			)
			(layer "F.Fab")
		)
		(pad "1" smd rect
			(at -0.889 0 90)
			(size 1.016 1.27)
			(layers "F.Cu" "F.Mask" "F.Paste")
			(net "P5V_AUX")
		)
		(pad "2" smd rect
			(at 0.889 0 90)
			(size 1.016 1.27)
			(layers "F.Cu" "F.Mask" "F.Paste")
			(net "GND")
		)
	)
	(footprint ""
		(layer "F.Cu")
		(at 201.352912 -96.822768)
		(property "Reference" "U28"
			(at -2.032 -2.377948 0)
			(unlocked yes)
			(layer "F.SilkS")
			(effects
				(font
					(size 0.7874 0.5842)
					(thickness 0.1524)
				)
				(justify left)
			)
		)
		(property "Value" ""
			(at 0 0 0)
			(layer "F.Fab")
			(effects
				(font
					(size 1.27 1.27)
				)
			)
		)
		(duplicate_pad_numbers_are_jumpers no)
		(fp_line
			(start -2.0574 -1.651)
			(end -0.381 -1.651)
			(stroke
				(width 0.1524)
				(type default)
			)
			(layer "F.SilkS")
		)
		(fp_line
			(start -2.0574 1.651)
			(end -2.0574 -1.651)
			(stroke
				(width 0.1524)
				(type default)
			)
			(layer "F.SilkS")
		)
		(fp_line
			(start -0.381 -1.651)
			(end 0 -1.016)
			(stroke
				(width 0.1524)
				(type default)
			)
			(layer "F.SilkS")
		)
		(fp_line
			(start 0 -1.016)
			(end 0.381 -1.651)
			(stroke
				(width 0.1524)
				(type default)
			)
			(layer "F.SilkS")
		)
		(fp_line
			(start 0.381 -1.651)
			(end 2.0574 -1.651)
			(stroke
				(width 0.1524)
				(type default)
			)
			(layer "F.SilkS")
		)
		(fp_line
			(start 2.0574 -1.651)
			(end 2.0574 1.651)
			(stroke
				(width 0.1524)
				(type default)
			)
			(layer "F.SilkS")
		)
		(fp_line
			(start 2.0574 1.651)
			(end -2.0574 1.651)
			(stroke
				(width 0.1524)
				(type default)
			)
			(layer "F.SilkS")
		)
		(fp_poly
			(pts
				(xy -2.71272 -0.719328) (xy -2.71272 -1.344168) (xy -2.159 -1.016)
			)
			(stroke
				(width 0)
				(type default)
			)
			(fill yes)
			(layer "F.SilkS")
		)
		(fp_line
			(start -1.599946 -1.199896)
			(end -0.899922 -1.199896)
			(stroke
				(width 0.1)
				(type default)
			)
			(layer "F.Fab")
		)
		(fp_line
			(start -1.599946 1.199896)
			(end -1.599946 -1.199896)
			(stroke
				(width 0.1)
				(type default)
			)
			(layer "F.Fab")
		)
		(fp_line
			(start -0.899922 -1.549908)
			(end 0.899922 -1.549908)
			(stroke
				(width 0.1)
				(type default)
			)
			(layer "F.Fab")
		)
		(fp_line
			(start -0.899922 -1.199896)
			(end -0.899922 -1.549908)
			(stroke
				(width 0.1)
				(type default)
			)
			(layer "F.Fab")
		)
		(fp_line
			(start -0.899922 1.199896)
			(end -1.599946 1.199896)
			(stroke
				(width 0.1)
				(type default)
			)
			(layer "F.Fab")
		)
		(fp_line
			(start -0.899922 1.549908)
			(end -0.899922 1.199896)
			(stroke
				(width 0.1)
				(type default)
			)
			(layer "F.Fab")
		)
		(fp_line
			(start 0.899922 -1.549908)
			(end 0.899922 -1.199896)
			(stroke
				(width 0.1)
				(type default)
			)
			(layer "F.Fab")
		)
		(fp_line
			(start 0.899922 -1.199896)
			(end 1.599946 -1.199896)
			(stroke
				(width 0.1)
				(type default)
			)
			(layer "F.Fab")
		)
		(fp_line
			(start 0.899922 1.199896)
			(end 0.899922 1.549908)
			(stroke
				(width 0.1)
				(type default)
			)
			(layer "F.Fab")
		)
		(fp_line
			(start 0.899922 1.549908)
			(end -0.899922 1.549908)
			(stroke
				(width 0.1)
				(type default)
			)
			(layer "F.Fab")
		)
		(fp_line
			(start 1.599946 -1.199896)
			(end 1.599946 1.199896)
			(stroke
				(width 0.1)
				(type default)
			)
			(layer "F.Fab")
		)
		(fp_line
			(start 1.599946 1.199896)
			(end 0.899922 1.199896)
			(stroke
				(width 0.1)
				(type default)
			)
			(layer "F.Fab")
		)
		(fp_poly
			(pts
				(xy -2.71272 -0.719328) (xy -2.71272 -1.344168) (xy -2.159 -1.016)
			)
			(stroke
				(width 0)
				(type default)
			)
			(fill yes)
			(layer "F.Fab")
		)
		(pad "1" smd rect
			(at -1.225042 -0.94996 270)
			(size 0.5588 1.3462)
			(layers "F.Cu" "F.Mask" "F.Paste")
			(net "Net_10855")
		)
		(pad "2" smd rect
			(at -1.225042 0 270)
			(size 0.5588 1.3462)
			(layers "F.Cu" "F.Mask" "F.Paste")
			(net "HP_LVC3_OCP_V3_1_P12V_R_PWRGD")
		)
		(pad "3" smd rect
			(at -1.225042 0.94996 270)
			(size 0.5588 1.3462)
			(layers "F.Cu" "F.Mask" "F.Paste")
			(net "GND")
		)
		(pad "4" smd rect
			(at 1.225042 0.94996 270)
			(size 0.5588 1.3462)
			(layers "F.Cu" "F.Mask" "F.Paste")
			(net "P12V_OCP_V3_1_PLD_R_PWRGD")
		)
		(pad "5" smd rect
			(at 1.225042 -0.94996 270)
			(size 0.5588 1.3462)
			(layers "F.Cu" "F.Mask" "F.Paste")
			(net "P3V3_AUX")
		)
	)
	(footprint ""
		(layer "F.Cu")
		(at 64.889126 -20.04822 180)
		(property "Reference" "PC2143"
			(at 0 0 180)
			(layer "F.SilkS")
			(hide yes)
			(effects
				(font
					(size 1.27 1.27)
				)
			)
		)
		(property "Value" ""
			(at 0 0 180)
			(layer "F.Fab")
			(effects
				(font
					(size 1.27 1.27)
				)
			)
		)
		(duplicate_pad_numbers_are_jumpers no)
		(fp_line
			(start 1.524 0.762)
			(end -1.524 0.762)
			(stroke
				(width 0.1524)
				(type default)
			)
			(layer "F.SilkS")
		)
		(fp_line
			(start 1.524 -0.762)
			(end 1.524 0.762)
			(stroke
				(width 0.1524)
				(type default)
			)
			(layer "F.SilkS")
		)
		(fp_line
			(start -1.524 0.762)
			(end -1.524 -0.762)
			(stroke
				(width 0.1524)
				(type default)
			)
			(layer "F.SilkS")
		)
		(fp_line
			(start -1.524 -0.762)
			(end 1.524 -0.762)
			(stroke
				(width 0.1524)
				(type default)
			)
			(layer "F.SilkS")
		)
		(fp_line
			(start 1.1049 0.724916)
			(end 1.1049 -0.724916)
			(stroke
				(width 0.1)
				(type default)
			)
			(layer "F.Fab")
		)
		(fp_line
			(start 1.1049 -0.724916)
			(end -1.1049 -0.724916)
			(stroke
				(width 0.1)
				(type default)
			)
			(layer "F.Fab")
		)
		(fp_line
			(start -1.1049 0.724916)
			(end 1.1049 0.724916)
			(stroke
				(width 0.1)
				(type default)
			)
			(layer "F.Fab")
		)
		(fp_line
			(start -1.1049 -0.724916)
			(end -1.1049 0.724916)
			(stroke
				(width 0.1)
				(type default)
			)
			(layer "F.Fab")
		)
		(pad "1" smd rect
			(at -0.889 0)
			(size 1.016 1.27)
			(layers "F.Cu" "F.Mask" "F.Paste")
			(net "P12V_OCP_V3_2")
		)
		(pad "2" smd rect
			(at 0.889 0)
			(size 1.016 1.27)
			(layers "F.Cu" "F.Mask" "F.Paste")
			(net "GND")
		)
	)
	(footprint ""
		(layer "F.Cu")
		(at 101.948234 -140.18641)
		(property "Reference" "PR602"
			(at 0 0 0)
			(layer "F.SilkS")
			(hide yes)
			(effects
				(font
					(size 1.27 1.27)
				)
			)
		)
		(property "Value" ""
			(at 0 0 0)
			(layer "F.Fab")
			(effects
				(font
					(size 1.27 1.27)
				)
			)
		)
		(duplicate_pad_numbers_are_jumpers no)
		(fp_line
			(start -0.7874 -0.4064)
			(end 0.7874 -0.4064)
			(stroke
				(width 0.1524)
				(type default)
			)
			(layer "F.SilkS")
		)
		(fp_line
			(start -0.7874 0.4064)
			(end -0.7874 -0.4064)
			(stroke
				(width 0.1524)
				(type default)
			)
			(layer "F.SilkS")
		)
		(fp_line
			(start 0.7874 -0.4064)
			(end 0.7874 0.4064)
			(stroke
				(width 0.1524)
				(type default)
			)
			(layer "F.SilkS")
		)
		(fp_line
			(start 0.7874 0.4064)
			(end -0.7874 0.4064)
			(stroke
				(width 0.1524)
				(type default)
			)
			(layer "F.SilkS")
		)
		(fp_line
			(start -0.67945 -0.305054)
			(end -0.12065 -0.305054)
			(stroke
				(width 0.1)
				(type default)
			)
			(layer "F.Fab")
		)
		(fp_line
			(start -0.67945 0.3048)
			(end -0.67945 -0.305054)
			(stroke
				(width 0.1)
				(type default)
			)
			(layer "F.Fab")
		)
		(fp_line
			(start -0.12065 -0.305054)
			(end -0.12065 -0.2794)
			(stroke
				(width 0.1)
				(type default)
			)
			(layer "F.Fab")
		)
		(fp_line
			(start -0.12065 -0.2794)
			(end 0.12065 -0.2794)
			(stroke
				(width 0.1)
				(type default)
			)
			(layer "F.Fab")
		)
		(fp_line
			(start -0.12065 0.2794)
			(end -0.12065 0.3048)
			(stroke
				(width 0.1)
				(type default)
			)
			(layer "F.Fab")
		)
		(fp_line
			(start -0.12065 0.3048)
			(end -0.67945 0.3048)
			(stroke
				(width 0.1)
				(type default)
			)
			(layer "F.Fab")
		)
		(fp_line
			(start 0.120396 0.2794)
			(end -0.12065 0.2794)
			(stroke
				(width 0.1)
				(type default)
			)
			(layer "F.Fab")
		)
		(fp_line
			(start 0.120396 0.3048)
			(end 0.120396 0.2794)
			(stroke
				(width 0.1)
				(type default)
			)
			(layer "F.Fab")
		)
		(fp_line
			(start 0.12065 -0.3048)
			(end 0.67945 -0.3048)
			(stroke
				(width 0.1)
				(type default)
			)
			(layer "F.Fab")
		)
		(fp_line
			(start 0.12065 -0.2794)
			(end 0.12065 -0.3048)
			(stroke
				(width 0.1)
				(type default)
			)
			(layer "F.Fab")
		)
		(fp_line
			(start 0.67945 -0.3048)
			(end 0.67945 0.3048)
			(stroke
				(width 0.1)
				(type default)
			)
			(layer "F.Fab")
		)
		(fp_line
			(start 0.67945 0.3048)
			(end 0.120396 0.3048)
			(stroke
				(width 0.1)
				(type default)
			)
			(layer "F.Fab")
		)
		(pad "1" smd circle
			(at -0.40005 0)
			(size 0 0)
			(layers "F.Cu" "F.Mask" "F.Paste")
			(net "PVDDCR_CPU0_P1_VINSEN")
		)
		(pad "2" smd circle
			(at 0.40005 0)
			(size 0 0)
			(layers "F.Cu" "F.Mask" "F.Paste")
			(net "GND")
		)
	)
	(footprint ""
		(layer "F.Cu")
		(at 321.107308 -101.37775 180)
		(property "Reference" "R1269"
			(at 0 0 180)
			(layer "F.SilkS")
			(hide yes)
			(effects
				(font
					(size 1.27 1.27)
				)
			)
		)
		(property "Value" ""
			(at 0 0 180)
			(layer "F.Fab")
			(effects
				(font
					(size 1.27 1.27)
				)
			)
		)
		(duplicate_pad_numbers_are_jumpers no)
		(fp_line
			(start 0.7874 0.4064)
			(end -0.7874 0.4064)
			(stroke
				(width 0.1524)
				(type default)
			)
			(layer "F.SilkS")
		)
		(fp_line
			(start 0.7874 -0.4064)
			(end 0.7874 0.4064)
			(stroke
				(width 0.1524)
				(type default)
			)
			(layer "F.SilkS")
		)
		(fp_line
			(start -0.7874 0.4064)
			(end -0.7874 -0.4064)
			(stroke
				(width 0.1524)
				(type default)
			)
			(layer "F.SilkS")
		)
		(fp_line
			(start -0.7874 -0.4064)
			(end 0.7874 -0.4064)
			(stroke
				(width 0.1524)
				(type default)
			)
			(layer "F.SilkS")
		)
		(fp_line
			(start 0.67945 0.3048)
			(end 0.120396 0.3048)
			(stroke
				(width 0.1)
				(type default)
			)
			(layer "F.Fab")
		)
		(fp_line
			(start 0.67945 -0.3048)
			(end 0.67945 0.3048)
			(stroke
				(width 0.1)
				(type default)
			)
			(layer "F.Fab")
		)
		(fp_line
			(start 0.12065 -0.2794)
			(end 0.12065 -0.3048)
			(stroke
				(width 0.1)
				(type default)
			)
			(layer "F.Fab")
		)
		(fp_line
			(start 0.12065 -0.3048)
			(end 0.67945 -0.3048)
			(stroke
				(width 0.1)
				(type default)
			)
			(layer "F.Fab")
		)
		(fp_line
			(start 0.120396 0.3048)
			(end 0.120396 0.2794)
			(stroke
				(width 0.1)
				(type default)
			)
			(layer "F.Fab")
		)
		(fp_line
			(start 0.120396 0.2794)
			(end -0.12065 0.2794)
			(stroke
				(width 0.1)
				(type default)
			)
			(layer "F.Fab")
		)
		(fp_line
			(start -0.12065 0.3048)
			(end -0.67945 0.3048)
			(stroke
				(width 0.1)
				(type default)
			)
			(layer "F.Fab")
		)
		(fp_line
			(start -0.12065 0.2794)
			(end -0.12065 0.3048)
			(stroke
				(width 0.1)
				(type default)
			)
			(layer "F.Fab")
		)
		(fp_line
			(start -0.12065 -0.2794)
			(end 0.12065 -0.2794)
			(stroke
				(width 0.1)
				(type default)
			)
			(layer "F.Fab")
		)
		(fp_line
			(start -0.12065 -0.305054)
			(end -0.12065 -0.2794)
			(stroke
				(width 0.1)
				(type default)
			)
			(layer "F.Fab")
		)
		(fp_line
			(start -0.67945 0.3048)
			(end -0.67945 -0.305054)
			(stroke
				(width 0.1)
				(type default)
			)
			(layer "F.Fab")
		)
		(fp_line
			(start -0.67945 -0.305054)
			(end -0.12065 -0.305054)
			(stroke
				(width 0.1)
				(type default)
			)
			(layer "F.Fab")
		)
		(pad "1" smd circle
			(at -0.40005 0 180)
			(size 0 0)
			(layers "F.Cu" "F.Mask" "F.Paste")
			(net "P12V_E1S_0_ADC_ALERT_R")
		)
		(pad "2" smd circle
			(at 0.40005 0 180)
			(size 0 0)
			(layers "F.Cu" "F.Mask" "F.Paste")
			(net "E1S_0_P3V3_P12V_ADC_R_ALERT")
		)
	)
	(footprint ""
		(layer "F.Cu")
		(at 431.828956 -105.32745 -90)
		(property "Reference" "PU202"
			(at 1.905 3.718306 90)
			(unlocked yes)
			(layer "F.SilkS")
			(effects
				(font
					(size 0.7874 0.5842)
					(thickness 0.1524)
				)
				(justify left)
			)
		)
		(property "Value" ""
			(at 0 0 270)
			(layer "F.Fab")
			(effects
				(font
					(size 1.27 1.27)
				)
			)
		)
		(duplicate_pad_numbers_are_jumpers no)
		(fp_line
			(start -1.774952 1.039876)
			(end 1.774952 1.039876)
			(stroke
				(width 0.1524)
				(type default)
			)
			(layer "F.SilkS")
		)
		(fp_line
			(start 1.774952 1.039876)
			(end 1.774952 -1.039876)
			(stroke
				(width 0.1524)
				(type default)
			)
			(layer "F.SilkS")
		)
		(fp_line
			(start -1.774952 -1.039876)
			(end -1.774952 1.039876)
			(stroke
				(width 0.1524)
				(type default)
			)
			(layer "F.SilkS")
		)
		(fp_line
			(start 1.774952 -1.039876)
			(end -1.774952 -1.039876)
			(stroke
				(width 0.1524)
				(type default)
			)
			(layer "F.SilkS")
		)
		(fp_poly
			(pts
				(xy -0.999998 -1.801876) (xy -0.999998 -1.039876) (xy -1.769872 -1.039876) (xy -1.769872 -0.249936)
				(xy -2.531872 -0.249936) (xy -2.531872 -1.801876)
			)
			(stroke
				(width 0)
				(type default)
			)
			(fill yes)
			(layer "F.SilkS")
		)
		(fp_line
			(start -1.769872 1.039876)
			(end 1.769872 1.039876)
			(stroke
				(width 0.1)
				(type default)
			)
			(layer "F.Fab")
		)
		(fp_line
			(start 1.769872 1.039876)
			(end 1.769872 -1.039876)
			(stroke
				(width 0.1)
				(type default)
			)
			(layer "F.Fab")
		)
		(fp_line
			(start -1.769872 -1.039876)
			(end -1.769872 1.039876)
			(stroke
				(width 0.1)
				(type default)
			)
			(layer "F.Fab")
		)
		(fp_line
			(start 1.769872 -1.039876)
			(end -1.769872 -1.039876)
			(stroke
				(width 0.1)
				(type default)
			)
			(layer "F.Fab")
		)
		(fp_poly
			(pts
				(xy -1.769872 -1.039876) (xy -0.999998 -1.039876) (xy -0.999998 -1.801876) (xy -2.531872 -1.801876)
				(xy -2.531872 -0.249936) (xy -1.769872 -0.249936)
			)
			(stroke
				(width 0)
				(type default)
			)
			(fill yes)
			(layer "F.Fab")
		)
		(pad "A1" smd circle
			(at -1.500124 -0.750062 270)
			(size 0.2286 0.2286)
			(layers "F.Cu" "F.Mask" "F.Paste")
			(net "P3V3_OCP_SENSE_1")
		)
		(pad "A2" smd circle
			(at -0.999998 -0.750062 270)
			(size 0.2286 0.2286)
			(layers "F.Cu" "F.Mask" "F.Paste")
			(net "P3V3_OCP_VCC_1")
		)
		(pad "A3" smd circle
			(at -0.499872 -0.750062 270)
			(size 0.2286 0.2286)
			(layers "F.Cu" "F.Mask" "F.Paste")
			(net "P3V3_AUX")
		)
		(pad "A4" smd circle
			(at 0 -0.750062 270)
			(size 0.2286 0.2286)
			(layers "F.Cu" "F.Mask" "F.Paste")
			(net "P3V3_OCP_SFF_R")
		)
		(pad "A5" smd circle
			(at 0.499872 -0.750062 270)
			(size 0.2286 0.2286)
			(layers "F.Cu" "F.Mask" "F.Paste")
			(net "P3V3_AUX")
		)
		(pad "A6" smd circle
			(at 0.999998 -0.750062 270)
			(size 0.2286 0.2286)
			(layers "F.Cu" "F.Mask" "F.Paste")
			(net "P3V3_OCP_GATE_PU202_1")
		)
		(pad "A7" smd circle
			(at 1.500124 -0.750062 270)
			(size 0.2286 0.2286)
			(layers "F.Cu" "F.Mask" "F.Paste")
			(net "GND")
		)
		(pad "B1" smd circle
			(at -1.500124 -0.249936 270)
			(size 0.2286 0.2286)
			(layers "F.Cu" "F.Mask" "F.Paste")
			(net "P3V3_OCP_CB_1")
		)
		(pad "B2" smd circle
			(at -0.999998 -0.249936 270)
			(size 0.2286 0.2286)
			(layers "F.Cu" "F.Mask" "F.Paste")
			(net "GND")
		)
		(pad "B3" smd circle
			(at -0.499872 -0.249936 270)
			(size 0.2286 0.2286)
			(layers "F.Cu" "F.Mask" "F.Paste")
			(net "P3V3_AUX")
		)
		(pad "B4" smd circle
			(at 0 -0.249936 270)
			(size 0.2286 0.2286)
			(layers "F.Cu" "F.Mask" "F.Paste")
			(net "P3V3_OCP_SFF_R")
		)
		(pad "B5" smd circle
			(at 0.499872 -0.249936 270)
			(size 0.2286 0.2286)
			(layers "F.Cu" "F.Mask" "F.Paste")
			(net "P3V3_AUX")
		)
		(pad "B6" smd circle
			(at 0.999998 -0.249936 270)
			(size 0.2286 0.2286)
			(layers "F.Cu" "F.Mask" "F.Paste")
			(net "P3V3_OCP_SFF_R")
		)
		(pad "B7" smd circle
			(at 1.500124 -0.249936 270)
			(size 0.2286 0.2286)
			(layers "F.Cu" "F.Mask" "F.Paste")
			(net "GND")
		)
		(pad "C1" smd circle
			(at -1.500124 0.249936 270)
			(size 0.2286 0.2286)
			(layers "F.Cu" "F.Mask" "F.Paste")
			(net "GND")
		)
		(pad "C2" smd circle
			(at -0.999998 0.249936 270)
			(size 0.2286 0.2286)
			(layers "F.Cu" "F.Mask" "F.Paste")
			(net "GND")
		)
		(pad "C3" smd circle
			(at -0.499872 0.249936 270)
			(size 0.2286 0.2286)
			(layers "F.Cu" "F.Mask" "F.Paste")
			(net "P3V3_AUX")
		)
		(pad "C4" smd circle
			(at 0 0.249936 270)
			(size 0.2286 0.2286)
			(layers "F.Cu" "F.Mask" "F.Paste")
			(net "P3V3_OCP_SFF_R")
		)
		(pad "C5" smd circle
			(at 0.499872 0.249936 270)
			(size 0.2286 0.2286)
			(layers "F.Cu" "F.Mask" "F.Paste")
			(net "P3V3_AUX")
		)
		(pad "C6" smd circle
			(at 0.999998 0.249936 270)
			(size 0.2286 0.2286)
			(layers "F.Cu" "F.Mask" "F.Paste")
			(net "P3V3_OCP_SFF_R")
		)
		(pad "C7" smd circle
			(at 1.500124 0.249936 270)
			(size 0.2286 0.2286)
			(layers "F.Cu" "F.Mask" "F.Paste")
			(net "P3V3_OCP_FAULT_1")
		)
		(pad "D1" smd circle
			(at -1.500124 0.750062 270)
			(size 0.2286 0.2286)
			(layers "F.Cu" "F.Mask" "F.Paste")
			(net "P3V3_OCP_REG_1")
		)
		(pad "D2" smd circle
			(at -0.999998 0.750062 270)
			(size 0.2286 0.2286)
			(layers "F.Cu" "F.Mask" "F.Paste")
			(net "P3V3_OCP_UV_1")
		)
		(pad "D3" smd circle
			(at -0.499872 0.750062 270)
			(size 0.2286 0.2286)
			(layers "F.Cu" "F.Mask" "F.Paste")
			(net "P3V3_OCP_OV_1")
		)
		(pad "D4" smd circle
			(at 0 0.750062 270)
			(size 0.2286 0.2286)
			(layers "F.Cu" "F.Mask" "F.Paste")
			(net "P3V3_OCP_SFF_R")
		)
		(pad "D5" smd circle
			(at 0.499872 0.750062 270)
			(size 0.2286 0.2286)
			(layers "F.Cu" "F.Mask" "F.Paste")
			(net "P3V3_AUX")
		)
		(pad "D6" smd circle
			(at 0.999998 0.750062 270)
			(size 0.2286 0.2286)
			(layers "F.Cu" "F.Mask" "F.Paste")
			(net "P3V3_OCP_SFF_R")
		)
		(pad "D7" smd circle
			(at 1.500124 0.750062 270)
			(size 0.2286 0.2286)
			(layers "F.Cu" "F.Mask" "F.Paste")
			(net "P3V3_OCP_PWRGD_1")
		)
	)
	(footprint ""
		(layer "F.Cu")
		(at 218.205304 -59.453272 180)
		(property "Reference" "PC2220"
			(at 0 0 180)
			(layer "F.SilkS")
			(hide yes)
			(effects
				(font
					(size 1.27 1.27)
				)
			)
		)
		(property "Value" ""
			(at 0 0 180)
			(layer "F.Fab")
			(effects
				(font
					(size 1.27 1.27)
				)
			)
		)
		(duplicate_pad_numbers_are_jumpers no)
		(fp_line
			(start 1.524 0.762)
			(end -1.524 0.762)
			(stroke
				(width 0.1524)
				(type default)
			)
			(layer "F.SilkS")
		)
		(fp_line
			(start 1.524 -0.762)
			(end 1.524 0.762)
			(stroke
				(width 0.1524)
				(type default)
			)
			(layer "F.SilkS")
		)
		(fp_line
			(start -1.524 0.762)
			(end -1.524 -0.762)
			(stroke
				(width 0.1524)
				(type default)
			)
			(layer "F.SilkS")
		)
		(fp_line
			(start -1.524 -0.762)
			(end 1.524 -0.762)
			(stroke
				(width 0.1524)
				(type default)
			)
			(layer "F.SilkS")
		)
		(fp_line
			(start 1.1049 0.724916)
			(end 1.1049 -0.724916)
			(stroke
				(width 0.1)
				(type default)
			)
			(layer "F.Fab")
		)
		(fp_line
			(start 1.1049 -0.724916)
			(end -1.1049 -0.724916)
			(stroke
				(width 0.1)
				(type default)
			)
			(layer "F.Fab")
		)
		(fp_line
			(start -1.1049 0.724916)
			(end 1.1049 0.724916)
			(stroke
				(width 0.1)
				(type default)
			)
			(layer "F.Fab")
		)
		(fp_line
			(start -1.1049 -0.724916)
			(end -1.1049 0.724916)
			(stroke
				(width 0.1)
				(type default)
			)
			(layer "F.Fab")
		)
		(pad "1" smd rect
			(at -0.889 0)
			(size 1.016 1.27)
			(layers "F.Cu" "F.Mask" "F.Paste")
			(net "P3V3_E1S_0_R")
		)
		(pad "2" smd rect
			(at 0.889 0)
			(size 1.016 1.27)
			(layers "F.Cu" "F.Mask" "F.Paste")
			(net "GND")
		)
	)
	(footprint ""
		(layer "F.Cu")
		(at 381.598678 -142.665958 180)
		(property "Reference" "PR292"
			(at 0 0 180)
			(layer "F.SilkS")
			(hide yes)
			(effects
				(font
					(size 1.27 1.27)
				)
			)
		)
		(property "Value" ""
			(at 0 0 180)
			(layer "F.Fab")
			(effects
				(font
					(size 1.27 1.27)
				)
			)
		)
		(duplicate_pad_numbers_are_jumpers no)
		(fp_line
			(start 0.7874 0.4064)
			(end -0.7874 0.4064)
			(stroke
				(width 0.1524)
				(type default)
			)
			(layer "F.SilkS")
		)
		(fp_line
			(start 0.7874 -0.4064)
			(end 0.7874 0.4064)
			(stroke
				(width 0.1524)
				(type default)
			)
			(layer "F.SilkS")
		)
		(fp_line
			(start -0.7874 0.4064)
			(end -0.7874 -0.4064)
			(stroke
				(width 0.1524)
				(type default)
			)
			(layer "F.SilkS")
		)
		(fp_line
			(start -0.7874 -0.4064)
			(end 0.7874 -0.4064)
			(stroke
				(width 0.1524)
				(type default)
			)
			(layer "F.SilkS")
		)
		(fp_line
			(start 0.67945 0.3048)
			(end 0.120396 0.3048)
			(stroke
				(width 0.1)
				(type default)
			)
			(layer "F.Fab")
		)
		(fp_line
			(start 0.67945 -0.3048)
			(end 0.67945 0.3048)
			(stroke
				(width 0.1)
				(type default)
			)
			(layer "F.Fab")
		)
		(fp_line
			(start 0.12065 -0.2794)
			(end 0.12065 -0.3048)
			(stroke
				(width 0.1)
				(type default)
			)
			(layer "F.Fab")
		)
		(fp_line
			(start 0.12065 -0.3048)
			(end 0.67945 -0.3048)
			(stroke
				(width 0.1)
				(type default)
			)
			(layer "F.Fab")
		)
		(fp_line
			(start 0.120396 0.3048)
			(end 0.120396 0.2794)
			(stroke
				(width 0.1)
				(type default)
			)
			(layer "F.Fab")
		)
		(fp_line
			(start 0.120396 0.2794)
			(end -0.12065 0.2794)
			(stroke
				(width 0.1)
				(type default)
			)
			(layer "F.Fab")
		)
		(fp_line
			(start -0.12065 0.3048)
			(end -0.67945 0.3048)
			(stroke
				(width 0.1)
				(type default)
			)
			(layer "F.Fab")
		)
		(fp_line
			(start -0.12065 0.2794)
			(end -0.12065 0.3048)
			(stroke
				(width 0.1)
				(type default)
			)
			(layer "F.Fab")
		)
		(fp_line
			(start -0.12065 -0.2794)
			(end 0.12065 -0.2794)
			(stroke
				(width 0.1)
				(type default)
			)
			(layer "F.Fab")
		)
		(fp_line
			(start -0.12065 -0.305054)
			(end -0.12065 -0.2794)
			(stroke
				(width 0.1)
				(type default)
			)
			(layer "F.Fab")
		)
		(fp_line
			(start -0.67945 0.3048)
			(end -0.67945 -0.305054)
			(stroke
				(width 0.1)
				(type default)
			)
			(layer "F.Fab")
		)
		(fp_line
			(start -0.67945 -0.305054)
			(end -0.12065 -0.305054)
			(stroke
				(width 0.1)
				(type default)
			)
			(layer "F.Fab")
		)
		(pad "1" smd circle
			(at -0.40005 0 180)
			(size 0 0)
			(layers "F.Cu" "F.Mask" "F.Paste")
			(net "PVDDCR_SOC_P0_EN//ADDR_CFG")
		)
		(pad "2" smd circle
			(at 0.40005 0 180)
			(size 0 0)
			(layers "F.Cu" "F.Mask" "F.Paste")
			(net "GND")
		)
	)
	(footprint ""
		(layer "F.Cu")
		(at 24.917654 -349.386398 90)
		(property "Reference" "PC616"
			(at 0 0 90)
			(layer "F.SilkS")
			(hide yes)
			(effects
				(font
					(size 1.27 1.27)
				)
			)
		)
		(property "Value" ""
			(at 0 0 90)
			(layer "F.Fab")
			(effects
				(font
					(size 1.27 1.27)
				)
			)
		)
		(duplicate_pad_numbers_are_jumpers no)
		(fp_line
			(start 0.7874 -0.4064)
			(end 0.7874 0.4064)
			(stroke
				(width 0.1524)
				(type default)
			)
			(layer "F.SilkS")
		)
		(fp_line
			(start -0.7874 -0.4064)
			(end 0.7874 -0.4064)
			(stroke
				(width 0.1524)
				(type default)
			)
			(layer "F.SilkS")
		)
		(fp_line
			(start 0.7874 0.4064)
			(end 0.498602 0.4064)
			(stroke
				(width 0.1524)
				(type default)
			)
			(layer "F.SilkS")
		)
		(fp_line
			(start -0.314198 0.4064)
			(end -0.7874 0.4064)
			(stroke
				(width 0.1524)
				(type default)
			)
			(layer "F.SilkS")
		)
		(fp_line
			(start -0.7874 0.4064)
			(end -0.7874 -0.4064)
			(stroke
				(width 0.1524)
				(type default)
			)
			(layer "F.SilkS")
		)
		(fp_line
			(start -0.12065 -0.305054)
			(end -0.12065 -0.2794)
			(stroke
				(width 0.1)
				(type default)
			)
			(layer "F.Fab")
		)
		(fp_line
			(start -0.67945 -0.305054)
			(end -0.12065 -0.305054)
			(stroke
				(width 0.1)
				(type default)
			)
			(layer "F.Fab")
		)
		(fp_line
			(start 0.67945 -0.3048)
			(end 0.67945 0.3048)
			(stroke
				(width 0.1)
				(type default)
			)
			(layer "F.Fab")
		)
		(fp_line
			(start 0.12065 -0.3048)
			(end 0.67945 -0.3048)
			(stroke
				(width 0.1)
				(type default)
			)
			(layer "F.Fab")
		)
		(fp_line
			(start 0.12065 -0.2794)
			(end 0.12065 -0.3048)
			(stroke
				(width 0.1)
				(type default)
			)
			(layer "F.Fab")
		)
		(fp_line
			(start -0.12065 -0.2794)
			(end 0.12065 -0.2794)
			(stroke
				(width 0.1)
				(type default)
			)
			(layer "F.Fab")
		)
		(fp_line
			(start 0.120396 0.2794)
			(end -0.12065 0.2794)
			(stroke
				(width 0.1)
				(type default)
			)
			(layer "F.Fab")
		)
		(fp_line
			(start -0.12065 0.2794)
			(end -0.12065 0.3048)
			(stroke
				(width 0.1)
				(type default)
			)
			(layer "F.Fab")
		)
		(fp_line
			(start 0.67945 0.3048)
			(end 0.120396 0.3048)
			(stroke
				(width 0.1)
				(type default)
			)
			(layer "F.Fab")
		)
		(fp_line
			(start 0.120396 0.3048)
			(end 0.120396 0.2794)
			(stroke
				(width 0.1)
				(type default)
			)
			(layer "F.Fab")
		)
		(fp_line
			(start -0.12065 0.3048)
			(end -0.67945 0.3048)
			(stroke
				(width 0.1)
				(type default)
			)
			(layer "F.Fab")
		)
		(fp_line
			(start -0.67945 0.3048)
			(end -0.67945 -0.305054)
			(stroke
				(width 0.1)
				(type default)
			)
			(layer "F.Fab")
		)
		(pad "1" smd circle
			(at -0.40005 0 90)
			(size 0 0)
			(layers "F.Cu" "F.Mask" "F.Paste")
			(net "PVDDIO_P1_VCC4")
		)
		(pad "2" smd circle
			(at 0.40005 0 90)
			(size 0 0)
			(layers "F.Cu" "F.Mask" "F.Paste")
			(net "GND")
		)
	)
	(footprint ""
		(layer "F.Cu")
		(at 120.68175 -28.085796)
		(property "Reference" "R6266"
			(at 0 0 0)
			(layer "F.SilkS")
			(hide yes)
			(effects
				(font
					(size 1.27 1.27)
				)
			)
		)
		(property "Value" ""
			(at 0 0 0)
			(layer "F.Fab")
			(effects
				(font
					(size 1.27 1.27)
				)
			)
		)
		(duplicate_pad_numbers_are_jumpers no)
		(fp_line
			(start -0.7874 -0.4064)
			(end 0.7874 -0.4064)
			(stroke
				(width 0.1524)
				(type default)
			)
			(layer "F.SilkS")
		)
		(fp_line
			(start -0.7874 0.4064)
			(end -0.7874 -0.4064)
			(stroke
				(width 0.1524)
				(type default)
			)
			(layer "F.SilkS")
		)
		(fp_line
			(start 0.7874 -0.4064)
			(end 0.7874 0.4064)
			(stroke
				(width 0.1524)
				(type default)
			)
			(layer "F.SilkS")
		)
		(fp_line
			(start 0.7874 0.4064)
			(end -0.7874 0.4064)
			(stroke
				(width 0.1524)
				(type default)
			)
			(layer "F.SilkS")
		)
		(fp_line
			(start -0.67945 -0.305054)
			(end -0.12065 -0.305054)
			(stroke
				(width 0.1)
				(type default)
			)
			(layer "F.Fab")
		)
		(fp_line
			(start -0.67945 0.3048)
			(end -0.67945 -0.305054)
			(stroke
				(width 0.1)
				(type default)
			)
			(layer "F.Fab")
		)
		(fp_line
			(start -0.12065 -0.305054)
			(end -0.12065 -0.2794)
			(stroke
				(width 0.1)
				(type default)
			)
			(layer "F.Fab")
		)
		(fp_line
			(start -0.12065 -0.2794)
			(end 0.12065 -0.2794)
			(stroke
				(width 0.1)
				(type default)
			)
			(layer "F.Fab")
		)
		(fp_line
			(start -0.12065 0.2794)
			(end -0.12065 0.3048)
			(stroke
				(width 0.1)
				(type default)
			)
			(layer "F.Fab")
		)
		(fp_line
			(start -0.12065 0.3048)
			(end -0.67945 0.3048)
			(stroke
				(width 0.1)
				(type default)
			)
			(layer "F.Fab")
		)
		(fp_line
			(start 0.120396 0.2794)
			(end -0.12065 0.2794)
			(stroke
				(width 0.1)
				(type default)
			)
			(layer "F.Fab")
		)
		(fp_line
			(start 0.120396 0.3048)
			(end 0.120396 0.2794)
			(stroke
				(width 0.1)
				(type default)
			)
			(layer "F.Fab")
		)
		(fp_line
			(start 0.12065 -0.3048)
			(end 0.67945 -0.3048)
			(stroke
				(width 0.1)
				(type default)
			)
			(layer "F.Fab")
		)
		(fp_line
			(start 0.12065 -0.2794)
			(end 0.12065 -0.3048)
			(stroke
				(width 0.1)
				(type default)
			)
			(layer "F.Fab")
		)
		(fp_line
			(start 0.67945 -0.3048)
			(end 0.67945 0.3048)
			(stroke
				(width 0.1)
				(type default)
			)
			(layer "F.Fab")
		)
		(fp_line
			(start 0.67945 0.3048)
			(end 0.120396 0.3048)
			(stroke
				(width 0.1)
				(type default)
			)
			(layer "F.Fab")
		)
		(pad "1" smd circle
			(at -0.40005 0)
			(size 0 0)
			(layers "F.Cu" "F.Mask" "F.Paste")
			(net "USB_HUB2_TI_USB_SSRXM_DN3_MRP_VDD12")
		)
		(pad "2" smd circle
			(at 0.40005 0)
			(size 0 0)
			(layers "F.Cu" "F.Mask" "F.Paste")
			(net "P1V2_CPU0_USB2_DVDD12")
		)
	)
	(footprint ""
		(layer "F.Cu")
		(at 156.154628 -45.64888 180)
		(property "Reference" "C1305"
			(at 0 0 180)
			(layer "F.SilkS")
			(hide yes)
			(effects
				(font
					(size 1.27 1.27)
				)
			)
		)
		(property "Value" ""
			(at 0 0 180)
			(layer "F.Fab")
			(effects
				(font
					(size 1.27 1.27)
				)
			)
		)
		(duplicate_pad_numbers_are_jumpers no)
		(fp_line
			(start 0.7874 0.4064)
			(end -0.7874 0.4064)
			(stroke
				(width 0.1524)
				(type default)
			)
			(layer "F.SilkS")
		)
		(fp_line
			(start 0.7874 -0.4064)
			(end 0.7874 0.4064)
			(stroke
				(width 0.1524)
				(type default)
			)
			(layer "F.SilkS")
		)
		(fp_line
			(start -0.7874 0.4064)
			(end -0.7874 -0.4064)
			(stroke
				(width 0.1524)
				(type default)
			)
			(layer "F.SilkS")
		)
		(fp_line
			(start -0.7874 -0.4064)
			(end 0.7874 -0.4064)
			(stroke
				(width 0.1524)
				(type default)
			)
			(layer "F.SilkS")
		)
		(fp_line
			(start 0.67945 0.3048)
			(end 0.120396 0.3048)
			(stroke
				(width 0.1)
				(type default)
			)
			(layer "F.Fab")
		)
		(fp_line
			(start 0.67945 -0.3048)
			(end 0.67945 0.3048)
			(stroke
				(width 0.1)
				(type default)
			)
			(layer "F.Fab")
		)
		(fp_line
			(start 0.12065 -0.2794)
			(end 0.12065 -0.3048)
			(stroke
				(width 0.1)
				(type default)
			)
			(layer "F.Fab")
		)
		(fp_line
			(start 0.12065 -0.3048)
			(end 0.67945 -0.3048)
			(stroke
				(width 0.1)
				(type default)
			)
			(layer "F.Fab")
		)
		(fp_line
			(start 0.120396 0.3048)
			(end 0.120396 0.2794)
			(stroke
				(width 0.1)
				(type default)
			)
			(layer "F.Fab")
		)
		(fp_line
			(start 0.120396 0.2794)
			(end -0.12065 0.2794)
			(stroke
				(width 0.1)
				(type default)
			)
			(layer "F.Fab")
		)
		(fp_line
			(start -0.12065 0.3048)
			(end -0.67945 0.3048)
			(stroke
				(width 0.1)
				(type default)
			)
			(layer "F.Fab")
		)
		(fp_line
			(start -0.12065 0.2794)
			(end -0.12065 0.3048)
			(stroke
				(width 0.1)
				(type default)
			)
			(layer "F.Fab")
		)
		(fp_line
			(start -0.12065 -0.2794)
			(end 0.12065 -0.2794)
			(stroke
				(width 0.1)
				(type default)
			)
			(layer "F.Fab")
		)
		(fp_line
			(start -0.12065 -0.305054)
			(end -0.12065 -0.2794)
			(stroke
				(width 0.1)
				(type default)
			)
			(layer "F.Fab")
		)
		(fp_line
			(start -0.67945 0.3048)
			(end -0.67945 -0.305054)
			(stroke
				(width 0.1)
				(type default)
			)
			(layer "F.Fab")
		)
		(fp_line
			(start -0.67945 -0.305054)
			(end -0.12065 -0.305054)
			(stroke
				(width 0.1)
				(type default)
			)
			(layer "F.Fab")
		)
		(pad "1" smd circle
			(at -0.40005 0 180)
			(size 0 0)
			(layers "F.Cu" "F.Mask" "F.Paste")
			(net "P3V3_AUX")
		)
		(pad "2" smd circle
			(at 0.40005 0 180)
			(size 0 0)
			(layers "F.Cu" "F.Mask" "F.Paste")
			(net "GND")
		)
	)
	(footprint ""
		(layer "F.Cu")
		(at 320.981324 -192.89776 -90)
		(property "Reference" "R426"
			(at 0 0 270)
			(layer "F.SilkS")
			(hide yes)
			(effects
				(font
					(size 1.27 1.27)
				)
			)
		)
		(property "Value" ""
			(at 0 0 270)
			(layer "F.Fab")
			(effects
				(font
					(size 1.27 1.27)
				)
			)
		)
		(duplicate_pad_numbers_are_jumpers no)
		(fp_line
			(start -0.7874 0.4064)
			(end -0.7874 -0.4064)
			(stroke
				(width 0.1524)
				(type default)
			)
			(layer "F.SilkS")
		)
		(fp_line
			(start 0.7874 0.4064)
			(end -0.7874 0.4064)
			(stroke
				(width 0.1524)
				(type default)
			)
			(layer "F.SilkS")
		)
		(fp_line
			(start -0.7874 -0.4064)
			(end 0.7874 -0.4064)
			(stroke
				(width 0.1524)
				(type default)
			)
			(layer "F.SilkS")
		)
		(fp_line
			(start 0.7874 -0.4064)
			(end 0.7874 0.4064)
			(stroke
				(width 0.1524)
				(type default)
			)
			(layer "F.SilkS")
		)
		(fp_line
			(start -0.67945 0.3048)
			(end -0.67945 -0.305054)
			(stroke
				(width 0.1)
				(type default)
			)
			(layer "F.Fab")
		)
		(fp_line
			(start -0.12065 0.3048)
			(end -0.67945 0.3048)
			(stroke
				(width 0.1)
				(type default)
			)
			(layer "F.Fab")
		)
		(fp_line
			(start 0.120396 0.3048)
			(end 0.120396 0.2794)
			(stroke
				(width 0.1)
				(type default)
			)
			(layer "F.Fab")
		)
		(fp_line
			(start 0.67945 0.3048)
			(end 0.120396 0.3048)
			(stroke
				(width 0.1)
				(type default)
			)
			(layer "F.Fab")
		)
		(fp_line
			(start -0.12065 0.2794)
			(end -0.12065 0.3048)
			(stroke
				(width 0.1)
				(type default)
			)
			(layer "F.Fab")
		)
		(fp_line
			(start 0.120396 0.2794)
			(end -0.12065 0.2794)
			(stroke
				(width 0.1)
				(type default)
			)
			(layer "F.Fab")
		)
		(fp_line
			(start -0.12065 -0.2794)
			(end 0.12065 -0.2794)
			(stroke
				(width 0.1)
				(type default)
			)
			(layer "F.Fab")
		)
		(fp_line
			(start 0.12065 -0.2794)
			(end 0.12065 -0.3048)
			(stroke
				(width 0.1)
				(type default)
			)
			(layer "F.Fab")
		)
		(fp_line
			(start 0.12065 -0.3048)
			(end 0.67945 -0.3048)
			(stroke
				(width 0.1)
				(type default)
			)
			(layer "F.Fab")
		)
		(fp_line
			(start 0.67945 -0.3048)
			(end 0.67945 0.3048)
			(stroke
				(width 0.1)
				(type default)
			)
			(layer "F.Fab")
		)
		(fp_line
			(start -0.67945 -0.305054)
			(end -0.12065 -0.305054)
			(stroke
				(width 0.1)
				(type default)
			)
			(layer "F.Fab")
		)
		(fp_line
			(start -0.12065 -0.305054)
			(end -0.12065 -0.2794)
			(stroke
				(width 0.1)
				(type default)
			)
			(layer "F.Fab")
		)
		(pad "1" smd rect
			(at -0.40005 0 90)
			(size 0.4572 0.508)
			(layers "F.Cu" "F.Mask" "F.Paste")
			(net "I3C_0_SPD_DDRAF_CPU0_SCL")
		)
		(pad "2" smd rect
			(at 0.40005 0 90)
			(size 0.4572 0.508)
			(layers "F.Cu" "F.Mask" "F.Paste")
			(net "I3C_0_SPD_DDRAF_CPU0_R_SCL")
		)
	)
	(footprint ""
		(layer "F.Cu")
		(at 438.488836 -168.716452 180)
		(property "Reference" "U106"
			(at -0.808228 2.125726 0)
			(unlocked yes)
			(layer "F.SilkS")
			(effects
				(font
					(size 0.7874 0.5842)
					(thickness 0.1524)
				)
			)
		)
		(property "Value" ""
			(at 0 0 180)
			(layer "F.Fab")
			(effects
				(font
					(size 1.27 1.27)
				)
			)
		)
		(duplicate_pad_numbers_are_jumpers no)
		(fp_line
			(start 1.03378 1.284478)
			(end -1.03378 1.284478)
			(stroke
				(width 0.1524)
				(type default)
			)
			(layer "F.SilkS")
		)
		(fp_line
			(start 1.03378 -1.284478)
			(end 1.03378 1.284478)
			(stroke
				(width 0.1524)
				(type default)
			)
			(layer "F.SilkS")
		)
		(fp_line
			(start -1.03378 1.284478)
			(end -1.03378 -1.284478)
			(stroke
				(width 0.1524)
				(type default)
			)
			(layer "F.SilkS")
		)
		(fp_line
			(start -1.03378 -1.284478)
			(end 1.03378 -1.284478)
			(stroke
				(width 0.1524)
				(type default)
			)
			(layer "F.SilkS")
		)
		(fp_poly
			(pts
				(xy -1.806702 -1.052576) (xy -1.201674 -0.750062) (xy -1.806702 -0.447548)
			)
			(stroke
				(width 0)
				(type default)
			)
			(fill yes)
			(layer "F.SilkS")
		)
		(fp_line
			(start 0.774954 1.02489)
			(end -0.774954 1.02489)
			(stroke
				(width 0.1)
				(type default)
			)
			(layer "F.Fab")
		)
		(fp_line
			(start 0.774954 -1.02489)
			(end 0.774954 1.02489)
			(stroke
				(width 0.1)
				(type default)
			)
			(layer "F.Fab")
		)
		(fp_line
			(start -0.774954 1.02489)
			(end -0.774954 -1.02489)
			(stroke
				(width 0.1)
				(type default)
			)
			(layer "F.Fab")
		)
		(fp_line
			(start -0.774954 -1.02489)
			(end 0.774954 -1.02489)
			(stroke
				(width 0.1)
				(type default)
			)
			(layer "F.Fab")
		)
		(fp_poly
			(pts
				(xy -1.201674 -0.750062) (xy -1.806702 -0.447548) (xy -1.806702 -1.052576)
			)
			(stroke
				(width 0)
				(type default)
			)
			(fill yes)
			(layer "F.Fab")
		)
		(pad "1" smd rect
			(at -0.64008 -0.750062 270)
			(size 0.3048 0.5334)
			(layers "F.Cu" "F.Mask" "F.Paste")
			(net "I3C_1_SPD_DDRGL_CPU0_SCL")
		)
		(pad "2" smd rect
			(at -0.64008 -0.249936 270)
			(size 0.254 0.5334)
			(layers "F.Cu" "F.Mask" "F.Paste")
			(net "I3C_1_SPD_DDRGL_CPU0_SDA")
		)
		(pad "3" smd rect
			(at -0.64008 0.249936 270)
			(size 0.254 0.5334)
			(layers "F.Cu" "F.Mask" "F.Paste")
			(net "I3C_SCM_1_R_SCL")
		)
		(pad "4" smd rect
			(at -0.64008 0.750062 270)
			(size 0.3048 0.5334)
			(layers "F.Cu" "F.Mask" "F.Paste")
			(net "I3C_SCM_1_R_SDA")
		)
		(pad "5" smd rect
			(at 0 0.839978 180)
			(size 0.3302 0.635)
			(layers "F.Cu" "F.Mask" "F.Paste")
			(net "GND")
		)
		(pad "6" smd rect
			(at 0.64008 0.750062 270)
			(size 0.3048 0.5334)
			(layers "F.Cu" "F.Mask" "F.Paste")
			(net "FM_I3C_CPU0_MUX1_OE_N")
		)
		(pad "7" smd rect
			(at 0.64008 0.249936 270)
			(size 0.254 0.5334)
			(layers "F.Cu" "F.Mask" "F.Paste")
			(net "I3C_SPD_DDRGL_CPU0_LVC1_SDA")
		)
		(pad "8" smd rect
			(at 0.64008 -0.249936 270)
			(size 0.254 0.5334)
			(layers "F.Cu" "F.Mask" "F.Paste")
			(net "I3C_SPD_DDRGL_CPU0_LVC1_SCL")
		)
		(pad "9" smd rect
			(at 0.64008 -0.750062 270)
			(size 0.3048 0.5334)
			(layers "F.Cu" "F.Mask" "F.Paste")
			(net "FM_I3C_CPU0_MUX1_SEL")
		)
		(pad "10" smd rect
			(at 0 -0.839978 180)
			(size 0.3302 0.635)
			(layers "F.Cu" "F.Mask" "F.Paste")
			(net "P3V3_AUX")
		)
	)
	(footprint ""
		(layer "F.Cu")
		(at 177.8762 -96.103948 90)
		(property "Reference" "R239"
			(at 0 0 90)
			(layer "F.SilkS")
			(hide yes)
			(effects
				(font
					(size 1.27 1.27)
				)
			)
		)
		(property "Value" ""
			(at 0 0 90)
			(layer "F.Fab")
			(effects
				(font
					(size 1.27 1.27)
				)
			)
		)
		(duplicate_pad_numbers_are_jumpers no)
		(fp_line
			(start 0.7874 -0.4064)
			(end 0.7874 0.4064)
			(stroke
				(width 0.1524)
				(type default)
			)
			(layer "F.SilkS")
		)
		(fp_line
			(start -0.7874 -0.4064)
			(end 0.7874 -0.4064)
			(stroke
				(width 0.1524)
				(type default)
			)
			(layer "F.SilkS")
		)
		(fp_line
			(start 0.7874 0.4064)
			(end -0.7874 0.4064)
			(stroke
				(width 0.1524)
				(type default)
			)
			(layer "F.SilkS")
		)
		(fp_line
			(start -0.7874 0.4064)
			(end -0.7874 -0.4064)
			(stroke
				(width 0.1524)
				(type default)
			)
			(layer "F.SilkS")
		)
		(fp_line
			(start -0.12065 -0.305054)
			(end -0.12065 -0.2794)
			(stroke
				(width 0.1)
				(type default)
			)
			(layer "F.Fab")
		)
		(fp_line
			(start -0.67945 -0.305054)
			(end -0.12065 -0.305054)
			(stroke
				(width 0.1)
				(type default)
			)
			(layer "F.Fab")
		)
		(fp_line
			(start 0.67945 -0.3048)
			(end 0.67945 0.3048)
			(stroke
				(width 0.1)
				(type default)
			)
			(layer "F.Fab")
		)
		(fp_line
			(start 0.12065 -0.3048)
			(end 0.67945 -0.3048)
			(stroke
				(width 0.1)
				(type default)
			)
			(layer "F.Fab")
		)
		(fp_line
			(start 0.12065 -0.2794)
			(end 0.12065 -0.3048)
			(stroke
				(width 0.1)
				(type default)
			)
			(layer "F.Fab")
		)
		(fp_line
			(start -0.12065 -0.2794)
			(end 0.12065 -0.2794)
			(stroke
				(width 0.1)
				(type default)
			)
			(layer "F.Fab")
		)
		(fp_line
			(start 0.120396 0.2794)
			(end -0.12065 0.2794)
			(stroke
				(width 0.1)
				(type default)
			)
			(layer "F.Fab")
		)
		(fp_line
			(start -0.12065 0.2794)
			(end -0.12065 0.3048)
			(stroke
				(width 0.1)
				(type default)
			)
			(layer "F.Fab")
		)
		(fp_line
			(start 0.67945 0.3048)
			(end 0.120396 0.3048)
			(stroke
				(width 0.1)
				(type default)
			)
			(layer "F.Fab")
		)
		(fp_line
			(start 0.120396 0.3048)
			(end 0.120396 0.2794)
			(stroke
				(width 0.1)
				(type default)
			)
			(layer "F.Fab")
		)
		(fp_line
			(start -0.12065 0.3048)
			(end -0.67945 0.3048)
			(stroke
				(width 0.1)
				(type default)
			)
			(layer "F.Fab")
		)
		(fp_line
			(start -0.67945 0.3048)
			(end -0.67945 -0.305054)
			(stroke
				(width 0.1)
				(type default)
			)
			(layer "F.Fab")
		)
		(pad "1" smd circle
			(at -0.40005 0 90)
			(size 0 0)
			(layers "F.Cu" "F.Mask" "F.Paste")
			(net "CPU0_XTRIG_L7")
		)
		(pad "2" smd circle
			(at 0.40005 0 90)
			(size 0 0)
			(layers "F.Cu" "F.Mask" "F.Paste")
			(net "FM_CPU0_XTRIG_L7")
		)
	)
	(footprint ""
		(layer "F.Cu")
		(at 251.474224 -133.622796)
		(property "Reference" "R1655"
			(at 0 0 0)
			(layer "F.SilkS")
			(hide yes)
			(effects
				(font
					(size 1.27 1.27)
				)
			)
		)
		(property "Value" ""
			(at 0 0 0)
			(layer "F.Fab")
			(effects
				(font
					(size 1.27 1.27)
				)
			)
		)
		(duplicate_pad_numbers_are_jumpers no)
		(fp_line
			(start -0.7874 -0.4064)
			(end 0.7874 -0.4064)
			(stroke
				(width 0.1524)
				(type default)
			)
			(layer "F.SilkS")
		)
		(fp_line
			(start -0.7874 0.4064)
			(end -0.7874 -0.4064)
			(stroke
				(width 0.1524)
				(type default)
			)
			(layer "F.SilkS")
		)
		(fp_line
			(start 0.7874 -0.4064)
			(end 0.7874 0.4064)
			(stroke
				(width 0.1524)
				(type default)
			)
			(layer "F.SilkS")
		)
		(fp_line
			(start 0.7874 0.4064)
			(end -0.7874 0.4064)
			(stroke
				(width 0.1524)
				(type default)
			)
			(layer "F.SilkS")
		)
		(fp_line
			(start -0.67945 -0.305054)
			(end -0.12065 -0.305054)
			(stroke
				(width 0.1)
				(type default)
			)
			(layer "F.Fab")
		)
		(fp_line
			(start -0.67945 0.3048)
			(end -0.67945 -0.305054)
			(stroke
				(width 0.1)
				(type default)
			)
			(layer "F.Fab")
		)
		(fp_line
			(start -0.12065 -0.305054)
			(end -0.12065 -0.2794)
			(stroke
				(width 0.1)
				(type default)
			)
			(layer "F.Fab")
		)
		(fp_line
			(start -0.12065 -0.2794)
			(end 0.12065 -0.2794)
			(stroke
				(width 0.1)
				(type default)
			)
			(layer "F.Fab")
		)
		(fp_line
			(start -0.12065 0.2794)
			(end -0.12065 0.3048)
			(stroke
				(width 0.1)
				(type default)
			)
			(layer "F.Fab")
		)
		(fp_line
			(start -0.12065 0.3048)
			(end -0.67945 0.3048)
			(stroke
				(width 0.1)
				(type default)
			)
			(layer "F.Fab")
		)
		(fp_line
			(start 0.120396 0.2794)
			(end -0.12065 0.2794)
			(stroke
				(width 0.1)
				(type default)
			)
			(layer "F.Fab")
		)
		(fp_line
			(start 0.120396 0.3048)
			(end 0.120396 0.2794)
			(stroke
				(width 0.1)
				(type default)
			)
			(layer "F.Fab")
		)
		(fp_line
			(start 0.12065 -0.3048)
			(end 0.67945 -0.3048)
			(stroke
				(width 0.1)
				(type default)
			)
			(layer "F.Fab")
		)
		(fp_line
			(start 0.12065 -0.2794)
			(end 0.12065 -0.3048)
			(stroke
				(width 0.1)
				(type default)
			)
			(layer "F.Fab")
		)
		(fp_line
			(start 0.67945 -0.3048)
			(end 0.67945 0.3048)
			(stroke
				(width 0.1)
				(type default)
			)
			(layer "F.Fab")
		)
		(fp_line
			(start 0.67945 0.3048)
			(end 0.120396 0.3048)
			(stroke
				(width 0.1)
				(type default)
			)
			(layer "F.Fab")
		)
		(pad "1" smd circle
			(at -0.40005 0)
			(size 0 0)
			(layers "F.Cu" "F.Mask" "F.Paste")
			(net "P3V3_AUX")
		)
		(pad "2" smd circle
			(at 0.40005 0)
			(size 0 0)
			(layers "F.Cu" "F.Mask" "F.Paste")
			(net "SPI_CPU0_LVC3_SCM_CS1_N")
		)
	)
	(footprint ""
		(layer "F.Cu")
		(at 376.174 -427.482 90)
		(property "Reference" "C1070"
			(at 0 0 90)
			(layer "F.SilkS")
			(hide yes)
			(effects
				(font
					(size 1.27 1.27)
				)
			)
		)
		(property "Value" ""
			(at 0 0 90)
			(layer "F.Fab")
			(effects
				(font
					(size 1.27 1.27)
				)
			)
		)
		(duplicate_pad_numbers_are_jumpers no)
		(fp_line
			(start 0.299974 -0.150114)
			(end 0.299974 0.150114)
			(stroke
				(width 0.1)
				(type default)
			)
			(layer "F.Fab")
		)
		(fp_line
			(start -0.299974 -0.150114)
			(end 0.299974 -0.150114)
			(stroke
				(width 0.1)
				(type default)
			)
			(layer "F.Fab")
		)
		(fp_line
			(start 0.299974 0.150114)
			(end -0.299974 0.150114)
			(stroke
				(width 0.1)
				(type default)
			)
			(layer "F.Fab")
		)
		(fp_line
			(start -0.299974 0.150114)
			(end -0.299974 -0.150114)
			(stroke
				(width 0.1)
				(type default)
			)
			(layer "F.Fab")
		)
		(pad "1" smd rect
			(at -0.2667 0 90)
			(size 0.3048 0.381)
			(layers "F.Cu" "F.Mask" "F.Paste")
			(net "P3V3_AUX")
		)
		(pad "2" smd rect
			(at 0.2667 0 90)
			(size 0.3048 0.381)
			(layers "F.Cu" "F.Mask" "F.Paste")
			(net "GND")
		)
	)
	(footprint ""
		(layer "F.Cu")
		(at 395.037056 -72.28205 180)
		(property "Reference" "R1273"
			(at 0 0 180)
			(layer "F.SilkS")
			(hide yes)
			(effects
				(font
					(size 1.27 1.27)
				)
			)
		)
		(property "Value" ""
			(at 0 0 180)
			(layer "F.Fab")
			(effects
				(font
					(size 1.27 1.27)
				)
			)
		)
		(duplicate_pad_numbers_are_jumpers no)
		(fp_line
			(start 0.7874 0.4064)
			(end -0.7874 0.4064)
			(stroke
				(width 0.1524)
				(type default)
			)
			(layer "F.SilkS")
		)
		(fp_line
			(start 0.7874 -0.4064)
			(end 0.7874 0.4064)
			(stroke
				(width 0.1524)
				(type default)
			)
			(layer "F.SilkS")
		)
		(fp_line
			(start -0.7874 0.4064)
			(end -0.7874 -0.4064)
			(stroke
				(width 0.1524)
				(type default)
			)
			(layer "F.SilkS")
		)
		(fp_line
			(start -0.7874 -0.4064)
			(end 0.7874 -0.4064)
			(stroke
				(width 0.1524)
				(type default)
			)
			(layer "F.SilkS")
		)
		(fp_line
			(start 0.67945 0.3048)
			(end 0.120396 0.3048)
			(stroke
				(width 0.1)
				(type default)
			)
			(layer "F.Fab")
		)
		(fp_line
			(start 0.67945 -0.3048)
			(end 0.67945 0.3048)
			(stroke
				(width 0.1)
				(type default)
			)
			(layer "F.Fab")
		)
		(fp_line
			(start 0.12065 -0.2794)
			(end 0.12065 -0.3048)
			(stroke
				(width 0.1)
				(type default)
			)
			(layer "F.Fab")
		)
		(fp_line
			(start 0.12065 -0.3048)
			(end 0.67945 -0.3048)
			(stroke
				(width 0.1)
				(type default)
			)
			(layer "F.Fab")
		)
		(fp_line
			(start 0.120396 0.3048)
			(end 0.120396 0.2794)
			(stroke
				(width 0.1)
				(type default)
			)
			(layer "F.Fab")
		)
		(fp_line
			(start 0.120396 0.2794)
			(end -0.12065 0.2794)
			(stroke
				(width 0.1)
				(type default)
			)
			(layer "F.Fab")
		)
		(fp_line
			(start -0.12065 0.3048)
			(end -0.67945 0.3048)
			(stroke
				(width 0.1)
				(type default)
			)
			(layer "F.Fab")
		)
		(fp_line
			(start -0.12065 0.2794)
			(end -0.12065 0.3048)
			(stroke
				(width 0.1)
				(type default)
			)
			(layer "F.Fab")
		)
		(fp_line
			(start -0.12065 -0.2794)
			(end 0.12065 -0.2794)
			(stroke
				(width 0.1)
				(type default)
			)
			(layer "F.Fab")
		)
		(fp_line
			(start -0.12065 -0.305054)
			(end -0.12065 -0.2794)
			(stroke
				(width 0.1)
				(type default)
			)
			(layer "F.Fab")
		)
		(fp_line
			(start -0.67945 0.3048)
			(end -0.67945 -0.305054)
			(stroke
				(width 0.1)
				(type default)
			)
			(layer "F.Fab")
		)
		(fp_line
			(start -0.67945 -0.305054)
			(end -0.12065 -0.305054)
			(stroke
				(width 0.1)
				(type default)
			)
			(layer "F.Fab")
		)
		(pad "1" smd circle
			(at -0.40005 0 180)
			(size 0 0)
			(layers "F.Cu" "F.Mask" "F.Paste")
			(net "SMB_INA230_6_3V3AUX_SCL_R")
		)
		(pad "2" smd circle
			(at 0.40005 0 180)
			(size 0 0)
			(layers "F.Cu" "F.Mask" "F.Paste")
			(net "SMB_INA230_6_3V3AUX_SCL_R1")
		)
	)
	(footprint ""
		(layer "F.Cu")
		(at 113.105946 -257.74523)
		(property "Reference" "C2450"
			(at 0 0 0)
			(layer "F.SilkS")
			(hide yes)
			(effects
				(font
					(size 1.27 1.27)
				)
			)
		)
		(property "Value" ""
			(at 0 0 0)
			(layer "F.Fab")
			(effects
				(font
					(size 1.27 1.27)
				)
			)
		)
		(duplicate_pad_numbers_are_jumpers no)
		(fp_line
			(start -0.7874 -0.4064)
			(end 0.7874 -0.4064)
			(stroke
				(width 0.1524)
				(type default)
			)
			(layer "F.SilkS")
		)
		(fp_line
			(start -0.7874 0.4064)
			(end -0.7874 -0.4064)
			(stroke
				(width 0.1524)
				(type default)
			)
			(layer "F.SilkS")
		)
		(fp_line
			(start 0.7874 -0.4064)
			(end 0.7874 0.4064)
			(stroke
				(width 0.1524)
				(type default)
			)
			(layer "F.SilkS")
		)
		(fp_line
			(start 0.7874 0.4064)
			(end -0.7874 0.4064)
			(stroke
				(width 0.1524)
				(type default)
			)
			(layer "F.SilkS")
		)
		(fp_line
			(start -0.67945 -0.305054)
			(end -0.12065 -0.305054)
			(stroke
				(width 0.1)
				(type default)
			)
			(layer "F.Fab")
		)
		(fp_line
			(start -0.67945 0.3048)
			(end -0.67945 -0.305054)
			(stroke
				(width 0.1)
				(type default)
			)
			(layer "F.Fab")
		)
		(fp_line
			(start -0.12065 -0.305054)
			(end -0.12065 -0.2794)
			(stroke
				(width 0.1)
				(type default)
			)
			(layer "F.Fab")
		)
		(fp_line
			(start -0.12065 -0.2794)
			(end 0.12065 -0.2794)
			(stroke
				(width 0.1)
				(type default)
			)
			(layer "F.Fab")
		)
		(fp_line
			(start -0.12065 0.2794)
			(end -0.12065 0.3048)
			(stroke
				(width 0.1)
				(type default)
			)
			(layer "F.Fab")
		)
		(fp_line
			(start -0.12065 0.3048)
			(end -0.67945 0.3048)
			(stroke
				(width 0.1)
				(type default)
			)
			(layer "F.Fab")
		)
		(fp_line
			(start 0.120396 0.2794)
			(end -0.12065 0.2794)
			(stroke
				(width 0.1)
				(type default)
			)
			(layer "F.Fab")
		)
		(fp_line
			(start 0.120396 0.3048)
			(end 0.120396 0.2794)
			(stroke
				(width 0.1)
				(type default)
			)
			(layer "F.Fab")
		)
		(fp_line
			(start 0.12065 -0.3048)
			(end 0.67945 -0.3048)
			(stroke
				(width 0.1)
				(type default)
			)
			(layer "F.Fab")
		)
		(fp_line
			(start 0.12065 -0.2794)
			(end 0.12065 -0.3048)
			(stroke
				(width 0.1)
				(type default)
			)
			(layer "F.Fab")
		)
		(fp_line
			(start 0.67945 -0.3048)
			(end 0.67945 0.3048)
			(stroke
				(width 0.1)
				(type default)
			)
			(layer "F.Fab")
		)
		(fp_line
			(start 0.67945 0.3048)
			(end 0.120396 0.3048)
			(stroke
				(width 0.1)
				(type default)
			)
			(layer "F.Fab")
		)
		(pad "1" smd circle
			(at -0.40005 0)
			(size 0 0)
			(layers "F.Cu" "F.Mask" "F.Paste")
			(net "PVDDCR_SOC_P1")
		)
		(pad "2" smd circle
			(at 0.40005 0)
			(size 0 0)
			(layers "F.Cu" "F.Mask" "F.Paste")
			(net "GND")
		)
	)
	(footprint ""
		(layer "F.Cu")
		(at 70.125844 -408.517344 -90)
		(property "Reference" "C6643"
			(at 0 0 270)
			(layer "F.SilkS")
			(hide yes)
			(effects
				(font
					(size 1.27 1.27)
				)
			)
		)
		(property "Value" ""
			(at 0 0 270)
			(layer "F.Fab")
			(effects
				(font
					(size 1.27 1.27)
				)
			)
		)
		(duplicate_pad_numbers_are_jumpers no)
		(fp_line
			(start -0.299974 0.150114)
			(end -0.299974 -0.150114)
			(stroke
				(width 0.1)
				(type default)
			)
			(layer "F.Fab")
		)
		(fp_line
			(start 0.299974 0.150114)
			(end -0.299974 0.150114)
			(stroke
				(width 0.1)
				(type default)
			)
			(layer "F.Fab")
		)
		(fp_line
			(start -0.299974 -0.150114)
			(end 0.299974 -0.150114)
			(stroke
				(width 0.1)
				(type default)
			)
			(layer "F.Fab")
		)
		(fp_line
			(start 0.299974 -0.150114)
			(end 0.299974 0.150114)
			(stroke
				(width 0.1)
				(type default)
			)
			(layer "F.Fab")
		)
		(pad "1" smd rect
			(at -0.2667 0 270)
			(size 0.3048 0.381)
			(layers "F.Cu" "F.Mask" "F.Paste")
			(net "P5E_CPU1_P0_TX_BUF_C_DP<7>")
		)
		(pad "2" smd rect
			(at 0.2667 0 270)
			(size 0.3048 0.381)
			(layers "F.Cu" "F.Mask" "F.Paste")
			(net "P5E_CPU1_P0_TX_BUF_DP<7>")
		)
	)
	(footprint ""
		(layer "F.Cu")
		(at 287.339024 -398.913858 90)
		(property "Reference" "C1787"
			(at 0 0 90)
			(layer "F.SilkS")
			(hide yes)
			(effects
				(font
					(size 1.27 1.27)
				)
			)
		)
		(property "Value" ""
			(at 0 0 90)
			(layer "F.Fab")
			(effects
				(font
					(size 1.27 1.27)
				)
			)
		)
		(duplicate_pad_numbers_are_jumpers no)
		(fp_line
			(start 0.7874 -0.4064)
			(end 0.7874 0.4064)
			(stroke
				(width 0.1524)
				(type default)
			)
			(layer "F.SilkS")
		)
		(fp_line
			(start -0.7874 -0.4064)
			(end 0.7874 -0.4064)
			(stroke
				(width 0.1524)
				(type default)
			)
			(layer "F.SilkS")
		)
		(fp_line
			(start 0.7874 0.4064)
			(end -0.7874 0.4064)
			(stroke
				(width 0.1524)
				(type default)
			)
			(layer "F.SilkS")
		)
		(fp_line
			(start -0.7874 0.4064)
			(end -0.7874 -0.4064)
			(stroke
				(width 0.1524)
				(type default)
			)
			(layer "F.SilkS")
		)
		(fp_line
			(start -0.12065 -0.305054)
			(end -0.12065 -0.2794)
			(stroke
				(width 0.1)
				(type default)
			)
			(layer "F.Fab")
		)
		(fp_line
			(start -0.67945 -0.305054)
			(end -0.12065 -0.305054)
			(stroke
				(width 0.1)
				(type default)
			)
			(layer "F.Fab")
		)
		(fp_line
			(start 0.67945 -0.3048)
			(end 0.67945 0.3048)
			(stroke
				(width 0.1)
				(type default)
			)
			(layer "F.Fab")
		)
		(fp_line
			(start 0.12065 -0.3048)
			(end 0.67945 -0.3048)
			(stroke
				(width 0.1)
				(type default)
			)
			(layer "F.Fab")
		)
		(fp_line
			(start 0.12065 -0.2794)
			(end 0.12065 -0.3048)
			(stroke
				(width 0.1)
				(type default)
			)
			(layer "F.Fab")
		)
		(fp_line
			(start -0.12065 -0.2794)
			(end 0.12065 -0.2794)
			(stroke
				(width 0.1)
				(type default)
			)
			(layer "F.Fab")
		)
		(fp_line
			(start 0.120396 0.2794)
			(end -0.12065 0.2794)
			(stroke
				(width 0.1)
				(type default)
			)
			(layer "F.Fab")
		)
		(fp_line
			(start -0.12065 0.2794)
			(end -0.12065 0.3048)
			(stroke
				(width 0.1)
				(type default)
			)
			(layer "F.Fab")
		)
		(fp_line
			(start 0.67945 0.3048)
			(end 0.120396 0.3048)
			(stroke
				(width 0.1)
				(type default)
			)
			(layer "F.Fab")
		)
		(fp_line
			(start 0.120396 0.3048)
			(end 0.120396 0.2794)
			(stroke
				(width 0.1)
				(type default)
			)
			(layer "F.Fab")
		)
		(fp_line
			(start -0.12065 0.3048)
			(end -0.67945 0.3048)
			(stroke
				(width 0.1)
				(type default)
			)
			(layer "F.Fab")
		)
		(fp_line
			(start -0.67945 0.3048)
			(end -0.67945 -0.305054)
			(stroke
				(width 0.1)
				(type default)
			)
			(layer "F.Fab")
		)
		(pad "1" smd circle
			(at -0.40005 0 90)
			(size 0 0)
			(layers "F.Cu" "F.Mask" "F.Paste")
			(net "P3V3_AUX")
		)
		(pad "2" smd circle
			(at 0.40005 0 90)
			(size 0 0)
			(layers "F.Cu" "F.Mask" "F.Paste")
			(net "GND")
		)
	)
	(footprint ""
		(layer "F.Cu")
		(at 26.947622 -405.840438)
		(property "Reference" "PC6620"
			(at 0 0 0)
			(layer "F.SilkS")
			(hide yes)
			(effects
				(font
					(size 1.27 1.27)
				)
			)
		)
		(property "Value" ""
			(at 0 0 0)
			(layer "F.Fab")
			(effects
				(font
					(size 1.27 1.27)
				)
			)
		)
		(duplicate_pad_numbers_are_jumpers no)
		(fp_line
			(start -0.7874 -0.4064)
			(end 0.7874 -0.4064)
			(stroke
				(width 0.1524)
				(type default)
			)
			(layer "F.SilkS")
		)
		(fp_line
			(start -0.7874 0.4064)
			(end -0.7874 -0.4064)
			(stroke
				(width 0.1524)
				(type default)
			)
			(layer "F.SilkS")
		)
		(fp_line
			(start 0.7874 -0.4064)
			(end 0.7874 0.4064)
			(stroke
				(width 0.1524)
				(type default)
			)
			(layer "F.SilkS")
		)
		(fp_line
			(start 0.7874 0.4064)
			(end -0.7874 0.4064)
			(stroke
				(width 0.1524)
				(type default)
			)
			(layer "F.SilkS")
		)
		(fp_line
			(start -0.67945 -0.305054)
			(end -0.12065 -0.305054)
			(stroke
				(width 0.1)
				(type default)
			)
			(layer "F.Fab")
		)
		(fp_line
			(start -0.67945 0.3048)
			(end -0.67945 -0.305054)
			(stroke
				(width 0.1)
				(type default)
			)
			(layer "F.Fab")
		)
		(fp_line
			(start -0.12065 -0.305054)
			(end -0.12065 -0.2794)
			(stroke
				(width 0.1)
				(type default)
			)
			(layer "F.Fab")
		)
		(fp_line
			(start -0.12065 -0.2794)
			(end 0.12065 -0.2794)
			(stroke
				(width 0.1)
				(type default)
			)
			(layer "F.Fab")
		)
		(fp_line
			(start -0.12065 0.2794)
			(end -0.12065 0.3048)
			(stroke
				(width 0.1)
				(type default)
			)
			(layer "F.Fab")
		)
		(fp_line
			(start -0.12065 0.3048)
			(end -0.67945 0.3048)
			(stroke
				(width 0.1)
				(type default)
			)
			(layer "F.Fab")
		)
		(fp_line
			(start 0.120396 0.2794)
			(end -0.12065 0.2794)
			(stroke
				(width 0.1)
				(type default)
			)
			(layer "F.Fab")
		)
		(fp_line
			(start 0.120396 0.3048)
			(end 0.120396 0.2794)
			(stroke
				(width 0.1)
				(type default)
			)
			(layer "F.Fab")
		)
		(fp_line
			(start 0.12065 -0.3048)
			(end 0.67945 -0.3048)
			(stroke
				(width 0.1)
				(type default)
			)
			(layer "F.Fab")
		)
		(fp_line
			(start 0.12065 -0.2794)
			(end 0.12065 -0.3048)
			(stroke
				(width 0.1)
				(type default)
			)
			(layer "F.Fab")
		)
		(fp_line
			(start 0.67945 -0.3048)
			(end 0.67945 0.3048)
			(stroke
				(width 0.1)
				(type default)
			)
			(layer "F.Fab")
		)
		(fp_line
			(start 0.67945 0.3048)
			(end 0.120396 0.3048)
			(stroke
				(width 0.1)
				(type default)
			)
			(layer "F.Fab")
		)
		(pad "1" smd circle
			(at -0.40005 0)
			(size 0 0)
			(layers "F.Cu" "F.Mask" "F.Paste")
			(net "P12V_AUX")
		)
		(pad "2" smd circle
			(at 0.40005 0)
			(size 0 0)
			(layers "F.Cu" "F.Mask" "F.Paste")
			(net "GND")
		)
	)
	(footprint ""
		(layer "F.Cu")
		(at 335.82991 -150.686262 90)
		(property "Reference" "PL78"
			(at -5.08 -5.81533 90)
			(unlocked yes)
			(layer "F.SilkS")
			(effects
				(font
					(size 0.7874 0.5842)
					(thickness 0.1524)
				)
				(justify left)
			)
		)
		(property "Value" ""
			(at 0 0 90)
			(layer "F.Fab")
			(effects
				(font
					(size 1.27 1.27)
				)
			)
		)
		(duplicate_pad_numbers_are_jumpers no)
		(fp_line
			(start 5.1054 -5.100066)
			(end -5.1054 -5.100066)
			(stroke
				(width 0.1524)
				(type default)
			)
			(layer "F.SilkS")
		)
		(fp_line
			(start -5.1054 -5.100066)
			(end -5.1054 -1.8796)
			(stroke
				(width 0.1524)
				(type default)
			)
			(layer "F.SilkS")
		)
		(fp_line
			(start 5.1054 -1.8796)
			(end 5.1054 -5.100066)
			(stroke
				(width 0.1524)
				(type default)
			)
			(layer "F.SilkS")
		)
		(fp_line
			(start -5.1054 1.8796)
			(end -5.1054 5.100066)
			(stroke
				(width 0.1524)
				(type default)
			)
			(layer "F.SilkS")
		)
		(fp_line
			(start 5.1054 5.100066)
			(end 5.1054 1.8796)
			(stroke
				(width 0.1524)
				(type default)
			)
			(layer "F.SilkS")
		)
		(fp_line
			(start -5.1054 5.100066)
			(end 5.1054 5.100066)
			(stroke
				(width 0.1524)
				(type default)
			)
			(layer "F.SilkS")
		)
		(fp_line
			(start 5.1054 -5.100066)
			(end 5.1054 5.100066)
			(stroke
				(width 0.1)
				(type default)
			)
			(layer "F.Fab")
		)
		(fp_line
			(start -5.1054 -5.100066)
			(end 5.1054 -5.100066)
			(stroke
				(width 0.1)
				(type default)
			)
			(layer "F.Fab")
		)
		(fp_line
			(start 5.1054 5.100066)
			(end -5.1054 5.100066)
			(stroke
				(width 0.1)
				(type default)
			)
			(layer "F.Fab")
		)
		(fp_line
			(start -5.1054 5.100066)
			(end -5.1054 -5.100066)
			(stroke
				(width 0.1)
				(type default)
			)
			(layer "F.Fab")
		)
		(pad "1" smd rect
			(at -3.999992 0 90)
			(size 3.5052 3.5052)
			(layers "F.Cu" "F.Mask" "F.Paste")
			(net "SW_PVDD18_S5_P0_SW")
		)
		(pad "2" smd rect
			(at 3.999992 0 90)
			(size 3.5052 3.5052)
			(layers "F.Cu" "F.Mask" "F.Paste")
			(net "PVDD18_S5_P0")
		)
	)
	(footprint ""
		(layer "F.Cu")
		(at 391.291318 -76.407264)
		(property "Reference" "R1309"
			(at 0 0 0)
			(layer "F.SilkS")
			(hide yes)
			(effects
				(font
					(size 1.27 1.27)
				)
			)
		)
		(property "Value" ""
			(at 0 0 0)
			(layer "F.Fab")
			(effects
				(font
					(size 1.27 1.27)
				)
			)
		)
		(duplicate_pad_numbers_are_jumpers no)
		(fp_line
			(start -0.7874 -0.4064)
			(end 0.7874 -0.4064)
			(stroke
				(width 0.1524)
				(type default)
			)
			(layer "F.SilkS")
		)
		(fp_line
			(start -0.7874 0.4064)
			(end -0.7874 -0.4064)
			(stroke
				(width 0.1524)
				(type default)
			)
			(layer "F.SilkS")
		)
		(fp_line
			(start 0.7874 -0.4064)
			(end 0.7874 0.4064)
			(stroke
				(width 0.1524)
				(type default)
			)
			(layer "F.SilkS")
		)
		(fp_line
			(start 0.7874 0.4064)
			(end -0.7874 0.4064)
			(stroke
				(width 0.1524)
				(type default)
			)
			(layer "F.SilkS")
		)
		(fp_line
			(start -0.67945 -0.305054)
			(end -0.12065 -0.305054)
			(stroke
				(width 0.1)
				(type default)
			)
			(layer "F.Fab")
		)
		(fp_line
			(start -0.67945 0.3048)
			(end -0.67945 -0.305054)
			(stroke
				(width 0.1)
				(type default)
			)
			(layer "F.Fab")
		)
		(fp_line
			(start -0.12065 -0.305054)
			(end -0.12065 -0.2794)
			(stroke
				(width 0.1)
				(type default)
			)
			(layer "F.Fab")
		)
		(fp_line
			(start -0.12065 -0.2794)
			(end 0.12065 -0.2794)
			(stroke
				(width 0.1)
				(type default)
			)
			(layer "F.Fab")
		)
		(fp_line
			(start -0.12065 0.2794)
			(end -0.12065 0.3048)
			(stroke
				(width 0.1)
				(type default)
			)
			(layer "F.Fab")
		)
		(fp_line
			(start -0.12065 0.3048)
			(end -0.67945 0.3048)
			(stroke
				(width 0.1)
				(type default)
			)
			(layer "F.Fab")
		)
		(fp_line
			(start 0.120396 0.2794)
			(end -0.12065 0.2794)
			(stroke
				(width 0.1)
				(type default)
			)
			(layer "F.Fab")
		)
		(fp_line
			(start 0.120396 0.3048)
			(end 0.120396 0.2794)
			(stroke
				(width 0.1)
				(type default)
			)
			(layer "F.Fab")
		)
		(fp_line
			(start 0.12065 -0.3048)
			(end 0.67945 -0.3048)
			(stroke
				(width 0.1)
				(type default)
			)
			(layer "F.Fab")
		)
		(fp_line
			(start 0.12065 -0.2794)
			(end 0.12065 -0.3048)
			(stroke
				(width 0.1)
				(type default)
			)
			(layer "F.Fab")
		)
		(fp_line
			(start 0.67945 -0.3048)
			(end 0.67945 0.3048)
			(stroke
				(width 0.1)
				(type default)
			)
			(layer "F.Fab")
		)
		(fp_line
			(start 0.67945 0.3048)
			(end 0.120396 0.3048)
			(stroke
				(width 0.1)
				(type default)
			)
			(layer "F.Fab")
		)
		(pad "1" smd circle
			(at -0.40005 0)
			(size 0 0)
			(layers "F.Cu" "F.Mask" "F.Paste")
			(net "GND")
		)
		(pad "2" smd circle
			(at 0.40005 0)
			(size 0 0)
			(layers "F.Cu" "F.Mask" "F.Paste")
			(net "INA230_6_A0")
		)
	)
	(footprint ""
		(layer "F.Cu")
		(at 90.380312 -74.52106 -90)
		(property "Reference" "PR3856"
			(at 0 0 270)
			(layer "F.SilkS")
			(hide yes)
			(effects
				(font
					(size 1.27 1.27)
				)
			)
		)
		(property "Value" ""
			(at 0 0 270)
			(layer "F.Fab")
			(effects
				(font
					(size 1.27 1.27)
				)
			)
		)
		(duplicate_pad_numbers_are_jumpers no)
		(fp_line
			(start -0.7874 0.4064)
			(end -0.7874 -0.4064)
			(stroke
				(width 0.1524)
				(type default)
			)
			(layer "F.SilkS")
		)
		(fp_line
			(start 0.7874 0.4064)
			(end -0.7874 0.4064)
			(stroke
				(width 0.1524)
				(type default)
			)
			(layer "F.SilkS")
		)
		(fp_line
			(start -0.7874 -0.4064)
			(end 0.7874 -0.4064)
			(stroke
				(width 0.1524)
				(type default)
			)
			(layer "F.SilkS")
		)
		(fp_line
			(start 0.7874 -0.4064)
			(end 0.7874 0.4064)
			(stroke
				(width 0.1524)
				(type default)
			)
			(layer "F.SilkS")
		)
		(fp_line
			(start -0.67945 0.3048)
			(end -0.67945 -0.305054)
			(stroke
				(width 0.1)
				(type default)
			)
			(layer "F.Fab")
		)
		(fp_line
			(start -0.12065 0.3048)
			(end -0.67945 0.3048)
			(stroke
				(width 0.1)
				(type default)
			)
			(layer "F.Fab")
		)
		(fp_line
			(start 0.120396 0.3048)
			(end 0.120396 0.2794)
			(stroke
				(width 0.1)
				(type default)
			)
			(layer "F.Fab")
		)
		(fp_line
			(start 0.67945 0.3048)
			(end 0.120396 0.3048)
			(stroke
				(width 0.1)
				(type default)
			)
			(layer "F.Fab")
		)
		(fp_line
			(start -0.12065 0.2794)
			(end -0.12065 0.3048)
			(stroke
				(width 0.1)
				(type default)
			)
			(layer "F.Fab")
		)
		(fp_line
			(start 0.120396 0.2794)
			(end -0.12065 0.2794)
			(stroke
				(width 0.1)
				(type default)
			)
			(layer "F.Fab")
		)
		(fp_line
			(start -0.12065 -0.2794)
			(end 0.12065 -0.2794)
			(stroke
				(width 0.1)
				(type default)
			)
			(layer "F.Fab")
		)
		(fp_line
			(start 0.12065 -0.2794)
			(end 0.12065 -0.3048)
			(stroke
				(width 0.1)
				(type default)
			)
			(layer "F.Fab")
		)
		(fp_line
			(start 0.12065 -0.3048)
			(end 0.67945 -0.3048)
			(stroke
				(width 0.1)
				(type default)
			)
			(layer "F.Fab")
		)
		(fp_line
			(start 0.67945 -0.3048)
			(end 0.67945 0.3048)
			(stroke
				(width 0.1)
				(type default)
			)
			(layer "F.Fab")
		)
		(fp_line
			(start -0.67945 -0.305054)
			(end -0.12065 -0.305054)
			(stroke
				(width 0.1)
				(type default)
			)
			(layer "F.Fab")
		)
		(fp_line
			(start -0.12065 -0.305054)
			(end -0.12065 -0.2794)
			(stroke
				(width 0.1)
				(type default)
			)
			(layer "F.Fab")
		)
		(pad "1" smd circle
			(at -0.40005 0 270)
			(size 0 0)
			(layers "F.Cu" "F.Mask" "F.Paste")
			(net "GND")
		)
		(pad "2" smd circle
			(at 0.40005 0 270)
			(size 0 0)
			(layers "F.Cu" "F.Mask" "F.Paste")
			(net "P3V3_OCP_ILIMIT_2")
		)
	)
	(footprint ""
		(layer "F.Cu")
		(at 346.833444 -378.95403 -90)
		(property "Reference" "C947"
			(at 0 0 270)
			(layer "F.SilkS")
			(hide yes)
			(effects
				(font
					(size 1.27 1.27)
				)
			)
		)
		(property "Value" ""
			(at 0 0 270)
			(layer "F.Fab")
			(effects
				(font
					(size 1.27 1.27)
				)
			)
		)
		(duplicate_pad_numbers_are_jumpers no)
		(fp_line
			(start -0.299974 0.150114)
			(end -0.299974 -0.150114)
			(stroke
				(width 0.1)
				(type default)
			)
			(layer "F.Fab")
		)
		(fp_line
			(start 0.299974 0.150114)
			(end -0.299974 0.150114)
			(stroke
				(width 0.1)
				(type default)
			)
			(layer "F.Fab")
		)
		(fp_line
			(start -0.299974 -0.150114)
			(end 0.299974 -0.150114)
			(stroke
				(width 0.1)
				(type default)
			)
			(layer "F.Fab")
		)
		(fp_line
			(start 0.299974 -0.150114)
			(end 0.299974 0.150114)
			(stroke
				(width 0.1)
				(type default)
			)
			(layer "F.Fab")
		)
		(pad "1" smd rect
			(at -0.2667 0 270)
			(size 0.3048 0.381)
			(layers "F.Cu" "F.Mask" "F.Paste")
			(net "P5E_CPU0_P1_TX_C_DP<9>")
		)
		(pad "2" smd rect
			(at 0.2667 0 270)
			(size 0.3048 0.381)
			(layers "F.Cu" "F.Mask" "F.Paste")
			(net "P5E_CPU0_P1_TX_DP<9>")
		)
	)
	(footprint ""
		(layer "F.Cu")
		(at 298.989496 -381.41783 -90)
		(property "Reference" "C929"
			(at 0 0 270)
			(layer "F.SilkS")
			(hide yes)
			(effects
				(font
					(size 1.27 1.27)
				)
			)
		)
		(property "Value" ""
			(at 0 0 270)
			(layer "F.Fab")
			(effects
				(font
					(size 1.27 1.27)
				)
			)
		)
		(duplicate_pad_numbers_are_jumpers no)
		(fp_line
			(start -0.299974 0.150114)
			(end -0.299974 -0.150114)
			(stroke
				(width 0.1)
				(type default)
			)
			(layer "F.Fab")
		)
		(fp_line
			(start 0.299974 0.150114)
			(end -0.299974 0.150114)
			(stroke
				(width 0.1)
				(type default)
			)
			(layer "F.Fab")
		)
		(fp_line
			(start -0.299974 -0.150114)
			(end 0.299974 -0.150114)
			(stroke
				(width 0.1)
				(type default)
			)
			(layer "F.Fab")
		)
		(fp_line
			(start 0.299974 -0.150114)
			(end 0.299974 0.150114)
			(stroke
				(width 0.1)
				(type default)
			)
			(layer "F.Fab")
		)
		(pad "1" smd rect
			(at -0.2667 0 270)
			(size 0.3048 0.381)
			(layers "F.Cu" "F.Mask" "F.Paste")
			(net "P5E_CPU0_P0_TX_C_DP<2>")
		)
		(pad "2" smd rect
			(at 0.2667 0 270)
			(size 0.3048 0.381)
			(layers "F.Cu" "F.Mask" "F.Paste")
			(net "P5E_CPU0_P0_TX_DP<2>")
		)
	)
	(footprint ""
		(layer "F.Cu")
		(at 103.185722 -29.819854 90)
		(property "Reference" "R344"
			(at 0 0 90)
			(layer "F.SilkS")
			(hide yes)
			(effects
				(font
					(size 1.27 1.27)
				)
			)
		)
		(property "Value" ""
			(at 0 0 90)
			(layer "F.Fab")
			(effects
				(font
					(size 1.27 1.27)
				)
			)
		)
		(duplicate_pad_numbers_are_jumpers no)
		(fp_line
			(start 0.32512 -0.175006)
			(end 0.32512 0.175006)
			(stroke
				(width 0.1)
				(type default)
			)
			(layer "F.Fab")
		)
		(fp_line
			(start -0.32512 -0.175006)
			(end 0.32512 -0.175006)
			(stroke
				(width 0.1)
				(type default)
			)
			(layer "F.Fab")
		)
		(fp_line
			(start 0.32512 0.175006)
			(end -0.32512 0.175006)
			(stroke
				(width 0.1)
				(type default)
			)
			(layer "F.Fab")
		)
		(fp_line
			(start -0.32512 0.175006)
			(end -0.32512 -0.175006)
			(stroke
				(width 0.1)
				(type default)
			)
			(layer "F.Fab")
		)
		(pad "1" smd rect
			(at -0.2667 0 90)
			(size 0.3048 0.381)
			(layers "F.Cu" "F.Mask" "F.Paste")
			(net "USB3_CPU0_BMC_TX_C2_DP")
		)
		(pad "2" smd rect
			(at 0.2667 0 270)
			(size 0.3048 0.381)
			(layers "F.Cu" "F.Mask" "F.Paste")
			(net "GND")
		)
	)
	(footprint ""
		(layer "F.Cu")
		(at 188.849 -96.103948 -90)
		(property "Reference" "R1303"
			(at 0 0 270)
			(layer "F.SilkS")
			(hide yes)
			(effects
				(font
					(size 1.27 1.27)
				)
			)
		)
		(property "Value" ""
			(at 0 0 270)
			(layer "F.Fab")
			(effects
				(font
					(size 1.27 1.27)
				)
			)
		)
		(duplicate_pad_numbers_are_jumpers no)
		(fp_line
			(start -0.7874 0.4064)
			(end -0.7874 -0.4064)
			(stroke
				(width 0.1524)
				(type default)
			)
			(layer "F.SilkS")
		)
		(fp_line
			(start 0.7874 0.4064)
			(end -0.7874 0.4064)
			(stroke
				(width 0.1524)
				(type default)
			)
			(layer "F.SilkS")
		)
		(fp_line
			(start -0.7874 -0.4064)
			(end 0.7874 -0.4064)
			(stroke
				(width 0.1524)
				(type default)
			)
			(layer "F.SilkS")
		)
		(fp_line
			(start 0.7874 -0.4064)
			(end 0.7874 0.4064)
			(stroke
				(width 0.1524)
				(type default)
			)
			(layer "F.SilkS")
		)
		(fp_line
			(start -0.67945 0.3048)
			(end -0.67945 -0.305054)
			(stroke
				(width 0.1)
				(type default)
			)
			(layer "F.Fab")
		)
		(fp_line
			(start -0.12065 0.3048)
			(end -0.67945 0.3048)
			(stroke
				(width 0.1)
				(type default)
			)
			(layer "F.Fab")
		)
		(fp_line
			(start 0.120396 0.3048)
			(end 0.120396 0.2794)
			(stroke
				(width 0.1)
				(type default)
			)
			(layer "F.Fab")
		)
		(fp_line
			(start 0.67945 0.3048)
			(end 0.120396 0.3048)
			(stroke
				(width 0.1)
				(type default)
			)
			(layer "F.Fab")
		)
		(fp_line
			(start -0.12065 0.2794)
			(end -0.12065 0.3048)
			(stroke
				(width 0.1)
				(type default)
			)
			(layer "F.Fab")
		)
		(fp_line
			(start 0.120396 0.2794)
			(end -0.12065 0.2794)
			(stroke
				(width 0.1)
				(type default)
			)
			(layer "F.Fab")
		)
		(fp_line
			(start -0.12065 -0.2794)
			(end 0.12065 -0.2794)
			(stroke
				(width 0.1)
				(type default)
			)
			(layer "F.Fab")
		)
		(fp_line
			(start 0.12065 -0.2794)
			(end 0.12065 -0.3048)
			(stroke
				(width 0.1)
				(type default)
			)
			(layer "F.Fab")
		)
		(fp_line
			(start 0.12065 -0.3048)
			(end 0.67945 -0.3048)
			(stroke
				(width 0.1)
				(type default)
			)
			(layer "F.Fab")
		)
		(fp_line
			(start 0.67945 -0.3048)
			(end 0.67945 0.3048)
			(stroke
				(width 0.1)
				(type default)
			)
			(layer "F.Fab")
		)
		(fp_line
			(start -0.67945 -0.305054)
			(end -0.12065 -0.305054)
			(stroke
				(width 0.1)
				(type default)
			)
			(layer "F.Fab")
		)
		(fp_line
			(start -0.12065 -0.305054)
			(end -0.12065 -0.2794)
			(stroke
				(width 0.1)
				(type default)
			)
			(layer "F.Fab")
		)
		(pad "1" smd circle
			(at -0.40005 0 270)
			(size 0 0)
			(layers "F.Cu" "F.Mask" "F.Paste")
			(net "FM_SMB_RST_E1S_0_N")
		)
		(pad "2" smd circle
			(at 0.40005 0 270)
			(size 0 0)
			(layers "F.Cu" "F.Mask" "F.Paste")
			(net "P3V3_AUX")
		)
	)
	(footprint ""
		(layer "F.Cu")
		(at 456.50023 -51.066954 180)
		(property "Reference" "PU9"
			(at -4.50596 2.89306 0)
			(unlocked yes)
			(layer "F.SilkS")
			(effects
				(font
					(size 0.7874 0.5842)
					(thickness 0.1524)
				)
				(justify left)
			)
		)
		(property "Value" ""
			(at 0 0 180)
			(layer "F.Fab")
			(effects
				(font
					(size 1.27 1.27)
				)
			)
		)
		(duplicate_pad_numbers_are_jumpers no)
		(fp_line
			(start 2.549906 3.050032)
			(end 2.549906 2.577846)
			(stroke
				(width 0.1524)
				(type default)
			)
			(layer "F.SilkS")
		)
		(fp_line
			(start 2.549906 -2.51968)
			(end 2.549906 -3.050032)
			(stroke
				(width 0.1524)
				(type default)
			)
			(layer "F.SilkS")
		)
		(fp_line
			(start 2.549906 -3.050032)
			(end 2.032 -3.050032)
			(stroke
				(width 0.1524)
				(type default)
			)
			(layer "F.SilkS")
		)
		(fp_line
			(start 2.13487 3.050032)
			(end 2.549906 3.050032)
			(stroke
				(width 0.1524)
				(type default)
			)
			(layer "F.SilkS")
		)
		(fp_line
			(start -2.032 -3.050032)
			(end -2.549906 -3.050032)
			(stroke
				(width 0.1524)
				(type default)
			)
			(layer "F.SilkS")
		)
		(fp_line
			(start -2.549906 3.050032)
			(end -2.08153 3.050032)
			(stroke
				(width 0.1524)
				(type default)
			)
			(layer "F.SilkS")
		)
		(fp_line
			(start -2.549906 2.577846)
			(end -2.549906 3.050032)
			(stroke
				(width 0.1524)
				(type default)
			)
			(layer "F.SilkS")
		)
		(fp_line
			(start -2.549906 -3.050032)
			(end -2.549906 -2.51968)
			(stroke
				(width 0.1524)
				(type default)
			)
			(layer "F.SilkS")
		)
		(fp_poly
			(pts
				(xy -2.72796 -2.277872) (xy -3.04673 -2.118614) (xy -3.04673 -2.43713)
			)
			(stroke
				(width 0)
				(type default)
			)
			(fill yes)
			(layer "F.SilkS")
		)
		(fp_line
			(start 2.549906 3.050032)
			(end 2.549906 -3.050032)
			(stroke
				(width 0.1)
				(type default)
			)
			(layer "F.Fab")
		)
		(fp_line
			(start 2.549906 -3.050032)
			(end -2.549906 -3.050032)
			(stroke
				(width 0.1)
				(type default)
			)
			(layer "F.Fab")
		)
		(fp_line
			(start -2.549906 3.050032)
			(end 2.549906 3.050032)
			(stroke
				(width 0.1)
				(type default)
			)
			(layer "F.Fab")
		)
		(fp_line
			(start -2.549906 -3.050032)
			(end -2.549906 3.050032)
			(stroke
				(width 0.1)
				(type default)
			)
			(layer "F.Fab")
		)
		(fp_poly
			(pts
				(xy -3.8354 -2.757932) (xy -3.8354 -1.741932) (xy -2.8194 -2.249932)
			)
			(stroke
				(width 0)
				(type default)
			)
			(fill yes)
			(layer "F.Fab")
		)
		(pad "1" smd rect
			(at -2.362708 -2.249932 270)
			(size 0.2794 0.5842)
			(layers "F.Cu" "F.Mask" "F.Paste")
			(net "P3V3_AUX_ILIM")
		)
		(pad "2" smd rect
			(at -2.350008 -1.75006 270)
			(size 0.2794 0.6096)
			(layers "F.Cu" "F.Mask" "F.Paste")
			(net "PWRGD_P3V3_AUX_R1")
		)
		(pad "3" smd rect
			(at -2.350008 -1.249934 270)
			(size 0.2794 0.6096)
			(layers "F.Cu" "F.Mask" "F.Paste")
			(net "P12V_AUX")
		)
		(pad "4" smd rect
			(at -2.350008 -0.750062 270)
			(size 0.2794 0.6096)
			(layers "F.Cu" "F.Mask" "F.Paste")
			(net "P3V3_AUX_VCC")
		)
		(pad "5" smd rect
			(at -2.350008 -0.249936 270)
			(size 0.2794 0.6096)
			(layers "F.Cu" "F.Mask" "F.Paste")
			(net "P3V3_AUX_VDRV")
		)
		(pad "6" smd rect
			(at -2.350008 0.249936 270)
			(size 0.2794 0.6096)
			(layers "F.Cu" "F.Mask" "F.Paste")
			(net "NC_PU9_3")
		)
		(pad "7_10-19" smd circle
			(at 0 0.062484 90)
			(size 0 0)
			(layers "F.Cu" "F.Mask" "F.Paste")
			(net "GND")
		)
		(pad "11_18" smd circle
			(at 0 2.712466 90)
			(size 0 0)
			(layers "F.Cu" "F.Mask" "F.Paste")
			(net "SW_P3V3_AUX_SW")
		)
		(pad "20_24" smd circle
			(at 1.787906 0.749808 180)
			(size 0 0)
			(layers "F.Cu" "F.Mask" "F.Paste")
			(net "SW_P3V3_AUX_FLT")
		)
		(pad "25" smd rect
			(at 2.350008 -0.750062 270)
			(size 0.2794 0.6096)
			(layers "F.Cu" "F.Mask" "F.Paste")
			(net "SW_P3V3_AUX_BOOTR")
		)
		(pad "26" smd rect
			(at 2.350008 -1.249934 270)
			(size 0.2794 0.6096)
			(layers "F.Cu" "F.Mask" "F.Paste")
			(net "SW_P3V3_AUX_BOOT")
		)
		(pad "27" smd rect
			(at 2.350008 -1.75006 270)
			(size 0.2794 0.6096)
			(layers "F.Cu" "F.Mask" "F.Paste")
			(net "P3V3_AUX_EN")
		)
		(pad "28" smd rect
			(at 2.362708 -2.249932 270)
			(size 0.2794 0.5842)
			(layers "F.Cu" "F.Mask" "F.Paste")
			(net "P3V3_AUX_VOS")
		)
		(pad "29" smd rect
			(at 1.75006 -2.887726 180)
			(size 0.2794 0.5842)
			(layers "F.Cu" "F.Mask" "F.Paste")
			(net "P3V3_AUX_SS")
		)
		(pad "30" smd rect
			(at 1.249934 -2.875026 180)
			(size 0.2794 0.6096)
			(layers "F.Cu" "F.Mask" "F.Paste")
			(net "P3V3_AUX_FB")
		)
		(pad "31" smd rect
			(at 0.750062 -2.875026 180)
			(size 0.2794 0.6096)
			(layers "F.Cu" "F.Mask" "F.Paste")
			(net "GND")
		)
		(pad "32" smd rect
			(at 0.249936 -2.875026 180)
			(size 0.2794 0.6096)
			(layers "F.Cu" "F.Mask" "F.Paste")
			(net "GND")
		)
		(pad "33" smd rect
			(at -0.249936 -2.875026 180)
			(size 0.2794 0.6096)
			(layers "F.Cu" "F.Mask" "F.Paste")
			(net "NC_PU9_1")
		)
		(pad "34" smd rect
			(at -0.750062 -2.875026 180)
			(size 0.2794 0.6096)
			(layers "F.Cu" "F.Mask" "F.Paste")
			(net "NC_PU9_2")
		)
		(pad "35" smd rect
			(at -1.249934 -2.875026 180)
			(size 0.2794 0.6096)
			(layers "F.Cu" "F.Mask" "F.Paste")
			(net "NC_HICCUP")
		)
		(pad "36" smd rect
			(at -1.75006 -2.887726 180)
			(size 0.2794 0.5842)
			(layers "F.Cu" "F.Mask" "F.Paste")
			(net "P3V3_AUX_MODE")
		)
		(pad "37" smd rect
			(at -1.549908 0.150114 270)
			(size 0.3048 0.508)
			(layers "F.Cu" "F.Mask" "F.Paste")
			(net "NC_PU9_4")
		)
		(zone
			(layer "F.Cu")
			(hatch none 0.5)
			(connect_pads
				(clearance 0)
			)
			(min_thickness 0.25)
			(keepout
				(tracks not_allowed)
				(vias allowed)
				(pads allowed)
				(copperpour not_allowed)
				(footprints allowed)
			)
			(placement
				(enabled no)
				(sheetname "")
			)
			(fill
				(thermal_gap 0.5)
				(thermal_bridge_width 0.5)
				(island_removal_mode 0)
			)
			(polygon
				(pts
					(xy 459.04023 -53.467) (xy 458.589888 -53.467) (xy 458.554836 -53.431948) (xy 454.445624 -53.431948)
					(xy 454.410572 -53.467) (xy 453.96023 -53.467) (xy 453.96023 -53.642006) (xy 459.04023 -53.642006)
				)
			)
		)
		(zone
			(layer "F.Cu")
			(hatch none 0.5)
			(connect_pads
				(clearance 0)
			)
			(min_thickness 0.25)
			(keepout
				(tracks not_allowed)
				(vias allowed)
				(pads allowed)
				(copperpour not_allowed)
				(footprints allowed)
			)
			(placement
				(enabled no)
				(sheetname "")
			)
			(fill
				(thermal_gap 0.5)
				(thermal_bridge_width 0.5)
				(island_removal_mode 0)
			)
			(polygon
				(pts
					(xy 458.494638 -51.093624) (xy 458.354938 -51.093624) (xy 458.354938 -51.420522) (xy 457.745338 -51.420522)
					(xy 457.745338 -51.013868) (xy 458.354938 -51.013868) (xy 458.354938 -51.068224) (xy 458.494638 -51.068224)
					(xy 458.494638 -49.111154) (xy 458.520038 -49.111154) (xy 458.520038 -48.522128) (xy 457.94803 -48.522128)
					(xy 457.94803 -48.547528) (xy 455.05243 -48.547528) (xy 455.05243 -48.522128) (xy 454.480422 -48.522128)
					(xy 454.480422 -49.111154) (xy 454.505822 -49.111154) (xy 454.505822 -50.735992) (xy 455.5744 -50.735992)
					(xy 455.5744 -52.932076) (xy 454.44537 -52.932076) (xy 454.410572 -52.966874) (xy 453.96023 -52.966874)
					(xy 453.96023 -53.167026) (xy 454.389744 -53.167026) (xy 454.424796 -53.131974) (xy 455.874374 -53.131974)
					(xy 455.874374 -50.467006) (xy 454.725278 -50.467006) (xy 454.725278 -48.791876) (xy 458.275182 -48.791876)
					(xy 458.275182 -50.76698) (xy 457.52512 -50.76698) (xy 457.52512 -51.666902) (xy 458.494638 -51.666902)
				)
			)
		)
	)
	(footprint ""
		(layer "F.Cu")
		(at 124.840238 -42.57675 180)
		(property "Reference" "R6277"
			(at 0 0 180)
			(layer "F.SilkS")
			(hide yes)
			(effects
				(font
					(size 1.27 1.27)
				)
			)
		)
		(property "Value" ""
			(at 0 0 180)
			(layer "F.Fab")
			(effects
				(font
					(size 1.27 1.27)
				)
			)
		)
		(duplicate_pad_numbers_are_jumpers no)
		(fp_line
			(start 0.7874 0.4064)
			(end -0.7874 0.4064)
			(stroke
				(width 0.1524)
				(type default)
			)
			(layer "F.SilkS")
		)
		(fp_line
			(start 0.7874 -0.4064)
			(end 0.7874 0.4064)
			(stroke
				(width 0.1524)
				(type default)
			)
			(layer "F.SilkS")
		)
		(fp_line
			(start -0.7874 0.4064)
			(end -0.7874 -0.4064)
			(stroke
				(width 0.1524)
				(type default)
			)
			(layer "F.SilkS")
		)
		(fp_line
			(start -0.7874 -0.4064)
			(end 0.7874 -0.4064)
			(stroke
				(width 0.1524)
				(type default)
			)
			(layer "F.SilkS")
		)
		(fp_line
			(start 0.67945 0.3048)
			(end 0.120396 0.3048)
			(stroke
				(width 0.1)
				(type default)
			)
			(layer "F.Fab")
		)
		(fp_line
			(start 0.67945 -0.3048)
			(end 0.67945 0.3048)
			(stroke
				(width 0.1)
				(type default)
			)
			(layer "F.Fab")
		)
		(fp_line
			(start 0.12065 -0.2794)
			(end 0.12065 -0.3048)
			(stroke
				(width 0.1)
				(type default)
			)
			(layer "F.Fab")
		)
		(fp_line
			(start 0.12065 -0.3048)
			(end 0.67945 -0.3048)
			(stroke
				(width 0.1)
				(type default)
			)
			(layer "F.Fab")
		)
		(fp_line
			(start 0.120396 0.3048)
			(end 0.120396 0.2794)
			(stroke
				(width 0.1)
				(type default)
			)
			(layer "F.Fab")
		)
		(fp_line
			(start 0.120396 0.2794)
			(end -0.12065 0.2794)
			(stroke
				(width 0.1)
				(type default)
			)
			(layer "F.Fab")
		)
		(fp_line
			(start -0.12065 0.3048)
			(end -0.67945 0.3048)
			(stroke
				(width 0.1)
				(type default)
			)
			(layer "F.Fab")
		)
		(fp_line
			(start -0.12065 0.2794)
			(end -0.12065 0.3048)
			(stroke
				(width 0.1)
				(type default)
			)
			(layer "F.Fab")
		)
		(fp_line
			(start -0.12065 -0.2794)
			(end 0.12065 -0.2794)
			(stroke
				(width 0.1)
				(type default)
			)
			(layer "F.Fab")
		)
		(fp_line
			(start -0.12065 -0.305054)
			(end -0.12065 -0.2794)
			(stroke
				(width 0.1)
				(type default)
			)
			(layer "F.Fab")
		)
		(fp_line
			(start -0.67945 0.3048)
			(end -0.67945 -0.305054)
			(stroke
				(width 0.1)
				(type default)
			)
			(layer "F.Fab")
		)
		(fp_line
			(start -0.67945 -0.305054)
			(end -0.12065 -0.305054)
			(stroke
				(width 0.1)
				(type default)
			)
			(layer "F.Fab")
		)
		(pad "1" smd circle
			(at -0.40005 0 180)
			(size 0 0)
			(layers "F.Cu" "F.Mask" "F.Paste")
			(net "P3V3_AUX")
		)
		(pad "2" smd circle
			(at 0.40005 0 180)
			(size 0 0)
			(layers "F.Cu" "F.Mask" "F.Paste")
			(net "USB_HUB2_MRP_PRT_CTL4_GANGPWR")
		)
	)
	(footprint ""
		(layer "F.Cu")
		(at 35.066478 -17.623536 90)
		(property "Reference" "C692"
			(at 0 0 90)
			(layer "F.SilkS")
			(hide yes)
			(effects
				(font
					(size 1.27 1.27)
				)
			)
		)
		(property "Value" ""
			(at 0 0 90)
			(layer "F.Fab")
			(effects
				(font
					(size 1.27 1.27)
				)
			)
		)
		(duplicate_pad_numbers_are_jumpers no)
		(fp_line
			(start 0.299974 -0.150114)
			(end 0.299974 0.150114)
			(stroke
				(width 0.1)
				(type default)
			)
			(layer "F.Fab")
		)
		(fp_line
			(start -0.299974 -0.150114)
			(end 0.299974 -0.150114)
			(stroke
				(width 0.1)
				(type default)
			)
			(layer "F.Fab")
		)
		(fp_line
			(start 0.299974 0.150114)
			(end -0.299974 0.150114)
			(stroke
				(width 0.1)
				(type default)
			)
			(layer "F.Fab")
		)
		(fp_line
			(start -0.299974 0.150114)
			(end -0.299974 -0.150114)
			(stroke
				(width 0.1)
				(type default)
			)
			(layer "F.Fab")
		)
		(pad "1" smd rect
			(at -0.2667 0 90)
			(size 0.3048 0.381)
			(layers "F.Cu" "F.Mask" "F.Paste")
			(net "P5E_CPU1_G1_TX_C_DN<8>")
		)
		(pad "2" smd rect
			(at 0.2667 0 90)
			(size 0.3048 0.381)
			(layers "F.Cu" "F.Mask" "F.Paste")
			(net "P5E_CPU1_G1_TX_DN<8>")
		)
	)
	(footprint ""
		(layer "F.Cu")
		(at 365.7854 -426.604176)
		(property "Reference" "R1420"
			(at 0 0 0)
			(layer "F.SilkS")
			(hide yes)
			(effects
				(font
					(size 1.27 1.27)
				)
			)
		)
		(property "Value" ""
			(at 0 0 0)
			(layer "F.Fab")
			(effects
				(font
					(size 1.27 1.27)
				)
			)
		)
		(duplicate_pad_numbers_are_jumpers no)
		(fp_line
			(start -0.32512 -0.175006)
			(end 0.32512 -0.175006)
			(stroke
				(width 0.1)
				(type default)
			)
			(layer "F.Fab")
		)
		(fp_line
			(start -0.32512 0.175006)
			(end -0.32512 -0.175006)
			(stroke
				(width 0.1)
				(type default)
			)
			(layer "F.Fab")
		)
		(fp_line
			(start 0.32512 -0.175006)
			(end 0.32512 0.175006)
			(stroke
				(width 0.1)
				(type default)
			)
			(layer "F.Fab")
		)
		(fp_line
			(start 0.32512 0.175006)
			(end -0.32512 0.175006)
			(stroke
				(width 0.1)
				(type default)
			)
			(layer "F.Fab")
		)
		(pad "1" smd rect
			(at -0.2667 0)
			(size 0.3048 0.381)
			(layers "F.Cu" "F.Mask" "F.Paste")
			(net "P1V8_CPU0_RT_1D")
		)
		(pad "2" smd rect
			(at 0.2667 0 180)
			(size 0.3048 0.381)
			(layers "F.Cu" "F.Mask" "F.Paste")
			(net "SMB_RT_CPU0_P3_ROM_MUX_1D_SDA")
		)
	)
	(footprint ""
		(layer "F.Cu")
		(at 251.474224 -131.067556)
		(property "Reference" "R610"
			(at 0 0 0)
			(layer "F.SilkS")
			(hide yes)
			(effects
				(font
					(size 1.27 1.27)
				)
			)
		)
		(property "Value" ""
			(at 0 0 0)
			(layer "F.Fab")
			(effects
				(font
					(size 1.27 1.27)
				)
			)
		)
		(duplicate_pad_numbers_are_jumpers no)
		(fp_line
			(start -0.7874 -0.4064)
			(end 0.7874 -0.4064)
			(stroke
				(width 0.1524)
				(type default)
			)
			(layer "F.SilkS")
		)
		(fp_line
			(start -0.7874 0.4064)
			(end -0.7874 -0.4064)
			(stroke
				(width 0.1524)
				(type default)
			)
			(layer "F.SilkS")
		)
		(fp_line
			(start 0.7874 -0.4064)
			(end 0.7874 0.4064)
			(stroke
				(width 0.1524)
				(type default)
			)
			(layer "F.SilkS")
		)
		(fp_line
			(start 0.7874 0.4064)
			(end -0.7874 0.4064)
			(stroke
				(width 0.1524)
				(type default)
			)
			(layer "F.SilkS")
		)
		(fp_line
			(start -0.67945 -0.305054)
			(end -0.12065 -0.305054)
			(stroke
				(width 0.1)
				(type default)
			)
			(layer "F.Fab")
		)
		(fp_line
			(start -0.67945 0.3048)
			(end -0.67945 -0.305054)
			(stroke
				(width 0.1)
				(type default)
			)
			(layer "F.Fab")
		)
		(fp_line
			(start -0.12065 -0.305054)
			(end -0.12065 -0.2794)
			(stroke
				(width 0.1)
				(type default)
			)
			(layer "F.Fab")
		)
		(fp_line
			(start -0.12065 -0.2794)
			(end 0.12065 -0.2794)
			(stroke
				(width 0.1)
				(type default)
			)
			(layer "F.Fab")
		)
		(fp_line
			(start -0.12065 0.2794)
			(end -0.12065 0.3048)
			(stroke
				(width 0.1)
				(type default)
			)
			(layer "F.Fab")
		)
		(fp_line
			(start -0.12065 0.3048)
			(end -0.67945 0.3048)
			(stroke
				(width 0.1)
				(type default)
			)
			(layer "F.Fab")
		)
		(fp_line
			(start 0.120396 0.2794)
			(end -0.12065 0.2794)
			(stroke
				(width 0.1)
				(type default)
			)
			(layer "F.Fab")
		)
		(fp_line
			(start 0.120396 0.3048)
			(end 0.120396 0.2794)
			(stroke
				(width 0.1)
				(type default)
			)
			(layer "F.Fab")
		)
		(fp_line
			(start 0.12065 -0.3048)
			(end 0.67945 -0.3048)
			(stroke
				(width 0.1)
				(type default)
			)
			(layer "F.Fab")
		)
		(fp_line
			(start 0.12065 -0.2794)
			(end 0.12065 -0.3048)
			(stroke
				(width 0.1)
				(type default)
			)
			(layer "F.Fab")
		)
		(fp_line
			(start 0.67945 -0.3048)
			(end 0.67945 0.3048)
			(stroke
				(width 0.1)
				(type default)
			)
			(layer "F.Fab")
		)
		(fp_line
			(start 0.67945 0.3048)
			(end 0.120396 0.3048)
			(stroke
				(width 0.1)
				(type default)
			)
			(layer "F.Fab")
		)
		(pad "1" smd circle
			(at -0.40005 0)
			(size 0 0)
			(layers "F.Cu" "F.Mask" "F.Paste")
			(net "P3V3_AUX")
		)
		(pad "2" smd circle
			(at 0.40005 0)
			(size 0 0)
			(layers "F.Cu" "F.Mask" "F.Paste")
			(net "SPI_CPU0_LVC3_SCM_CS0_N")
		)
	)
	(footprint ""
		(layer "F.Cu")
		(at 412.472886 -73.848468 180)
		(property "Reference" "R48"
			(at 0 0 180)
			(layer "F.SilkS")
			(hide yes)
			(effects
				(font
					(size 1.27 1.27)
				)
			)
		)
		(property "Value" ""
			(at 0 0 180)
			(layer "F.Fab")
			(effects
				(font
					(size 1.27 1.27)
				)
			)
		)
		(duplicate_pad_numbers_are_jumpers no)
		(fp_line
			(start 0.7874 0.4064)
			(end -0.7874 0.4064)
			(stroke
				(width 0.1524)
				(type default)
			)
			(layer "F.SilkS")
		)
		(fp_line
			(start 0.7874 -0.4064)
			(end 0.7874 0.4064)
			(stroke
				(width 0.1524)
				(type default)
			)
			(layer "F.SilkS")
		)
		(fp_line
			(start -0.7874 0.4064)
			(end -0.7874 -0.4064)
			(stroke
				(width 0.1524)
				(type default)
			)
			(layer "F.SilkS")
		)
		(fp_line
			(start -0.7874 -0.4064)
			(end 0.7874 -0.4064)
			(stroke
				(width 0.1524)
				(type default)
			)
			(layer "F.SilkS")
		)
		(fp_line
			(start 0.67945 0.3048)
			(end 0.120396 0.3048)
			(stroke
				(width 0.1)
				(type default)
			)
			(layer "F.Fab")
		)
		(fp_line
			(start 0.67945 -0.3048)
			(end 0.67945 0.3048)
			(stroke
				(width 0.1)
				(type default)
			)
			(layer "F.Fab")
		)
		(fp_line
			(start 0.12065 -0.2794)
			(end 0.12065 -0.3048)
			(stroke
				(width 0.1)
				(type default)
			)
			(layer "F.Fab")
		)
		(fp_line
			(start 0.12065 -0.3048)
			(end 0.67945 -0.3048)
			(stroke
				(width 0.1)
				(type default)
			)
			(layer "F.Fab")
		)
		(fp_line
			(start 0.120396 0.3048)
			(end 0.120396 0.2794)
			(stroke
				(width 0.1)
				(type default)
			)
			(layer "F.Fab")
		)
		(fp_line
			(start 0.120396 0.2794)
			(end -0.12065 0.2794)
			(stroke
				(width 0.1)
				(type default)
			)
			(layer "F.Fab")
		)
		(fp_line
			(start -0.12065 0.3048)
			(end -0.67945 0.3048)
			(stroke
				(width 0.1)
				(type default)
			)
			(layer "F.Fab")
		)
		(fp_line
			(start -0.12065 0.2794)
			(end -0.12065 0.3048)
			(stroke
				(width 0.1)
				(type default)
			)
			(layer "F.Fab")
		)
		(fp_line
			(start -0.12065 -0.2794)
			(end 0.12065 -0.2794)
			(stroke
				(width 0.1)
				(type default)
			)
			(layer "F.Fab")
		)
		(fp_line
			(start -0.12065 -0.305054)
			(end -0.12065 -0.2794)
			(stroke
				(width 0.1)
				(type default)
			)
			(layer "F.Fab")
		)
		(fp_line
			(start -0.67945 0.3048)
			(end -0.67945 -0.305054)
			(stroke
				(width 0.1)
				(type default)
			)
			(layer "F.Fab")
		)
		(fp_line
			(start -0.67945 -0.305054)
			(end -0.12065 -0.305054)
			(stroke
				(width 0.1)
				(type default)
			)
			(layer "F.Fab")
		)
		(pad "1" smd circle
			(at -0.40005 0 180)
			(size 0 0)
			(layers "F.Cu" "F.Mask" "F.Paste")
			(net "SMB_OCP_SFF_3V3AUX_BUF_R_SDA")
		)
		(pad "2" smd circle
			(at 0.40005 0 180)
			(size 0 0)
			(layers "F.Cu" "F.Mask" "F.Paste")
			(net "SMB_OCP_SFF_3V3AUX_BUF_SDA")
		)
	)
	(footprint ""
		(layer "F.Cu")
		(at 20.21586 -347.8149)
		(property "Reference" "H11"
			(at 0.9144 3.91287 0)
			(unlocked yes)
			(layer "F.SilkS")
			(effects
				(font
					(size 0.7874 0.5842)
					(thickness 0.1524)
				)
				(justify left)
			)
		)
		(property "Value" ""
			(at 0 0 0)
			(layer "F.Fab")
			(effects
				(font
					(size 1.27 1.27)
				)
			)
		)
		(duplicate_pad_numbers_are_jumpers no)
		(pad "1" thru_hole circle
			(at 0 0)
			(size 6.1976 6.1976)
			(drill 3.7338)
			(layers "*.Cu" "*.Mask")
			(remove_unused_layers no)
			(net "GND")
			(clearance -0.9779)
			(padstack
				(mode front_inner_back)
				(layer "Inner"
					(shape circle)
					(size 5.5372 5.5372)
					(clearance -0.6477)
				)
				(layer "B.Cu"
					(shape circle)
					(size 6.1976 6.1976)
					(clearance -0.9779)
				)
			)
		)
	)
	(footprint ""
		(layer "F.Cu")
		(at 293.79418 -351.368106 -90)
		(property "Reference" "PC156"
			(at 0 0 270)
			(layer "F.SilkS")
			(hide yes)
			(effects
				(font
					(size 1.27 1.27)
				)
			)
		)
		(property "Value" ""
			(at 0 0 270)
			(layer "F.Fab")
			(effects
				(font
					(size 1.27 1.27)
				)
			)
		)
		(duplicate_pad_numbers_are_jumpers no)
		(fp_line
			(start -0.7874 0.4064)
			(end -0.7874 -0.4064)
			(stroke
				(width 0.1524)
				(type default)
			)
			(layer "F.SilkS")
		)
		(fp_line
			(start 0.7874 0.4064)
			(end -0.7874 0.4064)
			(stroke
				(width 0.1524)
				(type default)
			)
			(layer "F.SilkS")
		)
		(fp_line
			(start -0.7874 -0.4064)
			(end 0.7874 -0.4064)
			(stroke
				(width 0.1524)
				(type default)
			)
			(layer "F.SilkS")
		)
		(fp_line
			(start 0.7874 -0.4064)
			(end 0.7874 0.4064)
			(stroke
				(width 0.1524)
				(type default)
			)
			(layer "F.SilkS")
		)
		(fp_line
			(start -0.67945 0.3048)
			(end -0.67945 -0.305054)
			(stroke
				(width 0.1)
				(type default)
			)
			(layer "F.Fab")
		)
		(fp_line
			(start -0.12065 0.3048)
			(end -0.67945 0.3048)
			(stroke
				(width 0.1)
				(type default)
			)
			(layer "F.Fab")
		)
		(fp_line
			(start 0.120396 0.3048)
			(end 0.120396 0.2794)
			(stroke
				(width 0.1)
				(type default)
			)
			(layer "F.Fab")
		)
		(fp_line
			(start 0.67945 0.3048)
			(end 0.120396 0.3048)
			(stroke
				(width 0.1)
				(type default)
			)
			(layer "F.Fab")
		)
		(fp_line
			(start -0.12065 0.2794)
			(end -0.12065 0.3048)
			(stroke
				(width 0.1)
				(type default)
			)
			(layer "F.Fab")
		)
		(fp_line
			(start 0.120396 0.2794)
			(end -0.12065 0.2794)
			(stroke
				(width 0.1)
				(type default)
			)
			(layer "F.Fab")
		)
		(fp_line
			(start -0.12065 -0.2794)
			(end 0.12065 -0.2794)
			(stroke
				(width 0.1)
				(type default)
			)
			(layer "F.Fab")
		)
		(fp_line
			(start 0.12065 -0.2794)
			(end 0.12065 -0.3048)
			(stroke
				(width 0.1)
				(type default)
			)
			(layer "F.Fab")
		)
		(fp_line
			(start 0.12065 -0.3048)
			(end 0.67945 -0.3048)
			(stroke
				(width 0.1)
				(type default)
			)
			(layer "F.Fab")
		)
		(fp_line
			(start 0.67945 -0.3048)
			(end 0.67945 0.3048)
			(stroke
				(width 0.1)
				(type default)
			)
			(layer "F.Fab")
		)
		(fp_line
			(start -0.67945 -0.305054)
			(end -0.12065 -0.305054)
			(stroke
				(width 0.1)
				(type default)
			)
			(layer "F.Fab")
		)
		(fp_line
			(start -0.12065 -0.305054)
			(end -0.12065 -0.2794)
			(stroke
				(width 0.1)
				(type default)
			)
			(layer "F.Fab")
		)
		(pad "1" smd circle
			(at -0.40005 0 270)
			(size 0 0)
			(layers "F.Cu" "F.Mask" "F.Paste")
			(net "SW_PVDDIO_P0_BOOT2_R")
		)
		(pad "2" smd circle
			(at 0.40005 0 270)
			(size 0 0)
			(layers "F.Cu" "F.Mask" "F.Paste")
			(net "SW_PVDDIO_P0_BOOTR2")
		)
	)
	(footprint ""
		(layer "F.Cu")
		(at 17.380458 -418.690298 -90)
		(property "Reference" "R6180"
			(at 0 0 270)
			(layer "F.SilkS")
			(hide yes)
			(effects
				(font
					(size 1.27 1.27)
				)
			)
		)
		(property "Value" ""
			(at 0 0 270)
			(layer "F.Fab")
			(effects
				(font
					(size 1.27 1.27)
				)
			)
		)
		(duplicate_pad_numbers_are_jumpers no)
		(fp_line
			(start -0.7874 0.4064)
			(end -0.7874 -0.4064)
			(stroke
				(width 0.1524)
				(type default)
			)
			(layer "F.SilkS")
		)
		(fp_line
			(start 0.7874 0.4064)
			(end -0.7874 0.4064)
			(stroke
				(width 0.1524)
				(type default)
			)
			(layer "F.SilkS")
		)
		(fp_line
			(start -0.7874 -0.4064)
			(end 0.7874 -0.4064)
			(stroke
				(width 0.1524)
				(type default)
			)
			(layer "F.SilkS")
		)
		(fp_line
			(start 0.7874 -0.4064)
			(end 0.7874 0.4064)
			(stroke
				(width 0.1524)
				(type default)
			)
			(layer "F.SilkS")
		)
		(fp_line
			(start -0.67945 0.3048)
			(end -0.67945 -0.305054)
			(stroke
				(width 0.1)
				(type default)
			)
			(layer "F.Fab")
		)
		(fp_line
			(start -0.12065 0.3048)
			(end -0.67945 0.3048)
			(stroke
				(width 0.1)
				(type default)
			)
			(layer "F.Fab")
		)
		(fp_line
			(start 0.120396 0.3048)
			(end 0.120396 0.2794)
			(stroke
				(width 0.1)
				(type default)
			)
			(layer "F.Fab")
		)
		(fp_line
			(start 0.67945 0.3048)
			(end 0.120396 0.3048)
			(stroke
				(width 0.1)
				(type default)
			)
			(layer "F.Fab")
		)
		(fp_line
			(start -0.12065 0.2794)
			(end -0.12065 0.3048)
			(stroke
				(width 0.1)
				(type default)
			)
			(layer "F.Fab")
		)
		(fp_line
			(start 0.120396 0.2794)
			(end -0.12065 0.2794)
			(stroke
				(width 0.1)
				(type default)
			)
			(layer "F.Fab")
		)
		(fp_line
			(start -0.12065 -0.2794)
			(end 0.12065 -0.2794)
			(stroke
				(width 0.1)
				(type default)
			)
			(layer "F.Fab")
		)
		(fp_line
			(start 0.12065 -0.2794)
			(end 0.12065 -0.3048)
			(stroke
				(width 0.1)
				(type default)
			)
			(layer "F.Fab")
		)
		(fp_line
			(start 0.12065 -0.3048)
			(end 0.67945 -0.3048)
			(stroke
				(width 0.1)
				(type default)
			)
			(layer "F.Fab")
		)
		(fp_line
			(start 0.67945 -0.3048)
			(end 0.67945 0.3048)
			(stroke
				(width 0.1)
				(type default)
			)
			(layer "F.Fab")
		)
		(fp_line
			(start -0.67945 -0.305054)
			(end -0.12065 -0.305054)
			(stroke
				(width 0.1)
				(type default)
			)
			(layer "F.Fab")
		)
		(fp_line
			(start -0.12065 -0.305054)
			(end -0.12065 -0.2794)
			(stroke
				(width 0.1)
				(type default)
			)
			(layer "F.Fab")
		)
		(pad "1" smd circle
			(at -0.40005 0 270)
			(size 0 0)
			(layers "F.Cu" "F.Mask" "F.Paste")
			(net "FM_P2E_BUF2_VOD_SEL")
		)
		(pad "2" smd circle
			(at 0.40005 0 270)
			(size 0 0)
			(layers "F.Cu" "F.Mask" "F.Paste")
			(net "GND")
		)
	)
	(footprint ""
		(layer "F.Cu")
		(at 120.68175 -23.005796)
		(property "Reference" "R6274"
			(at 0 0 0)
			(layer "F.SilkS")
			(hide yes)
			(effects
				(font
					(size 1.27 1.27)
				)
			)
		)
		(property "Value" ""
			(at 0 0 0)
			(layer "F.Fab")
			(effects
				(font
					(size 1.27 1.27)
				)
			)
		)
		(duplicate_pad_numbers_are_jumpers no)
		(fp_line
			(start -0.7874 -0.4064)
			(end 0.7874 -0.4064)
			(stroke
				(width 0.1524)
				(type default)
			)
			(layer "F.SilkS")
		)
		(fp_line
			(start -0.7874 0.4064)
			(end -0.7874 -0.4064)
			(stroke
				(width 0.1524)
				(type default)
			)
			(layer "F.SilkS")
		)
		(fp_line
			(start 0.7874 -0.4064)
			(end 0.7874 0.4064)
			(stroke
				(width 0.1524)
				(type default)
			)
			(layer "F.SilkS")
		)
		(fp_line
			(start 0.7874 0.4064)
			(end -0.7874 0.4064)
			(stroke
				(width 0.1524)
				(type default)
			)
			(layer "F.SilkS")
		)
		(fp_line
			(start -0.67945 -0.305054)
			(end -0.12065 -0.305054)
			(stroke
				(width 0.1)
				(type default)
			)
			(layer "F.Fab")
		)
		(fp_line
			(start -0.67945 0.3048)
			(end -0.67945 -0.305054)
			(stroke
				(width 0.1)
				(type default)
			)
			(layer "F.Fab")
		)
		(fp_line
			(start -0.12065 -0.305054)
			(end -0.12065 -0.2794)
			(stroke
				(width 0.1)
				(type default)
			)
			(layer "F.Fab")
		)
		(fp_line
			(start -0.12065 -0.2794)
			(end 0.12065 -0.2794)
			(stroke
				(width 0.1)
				(type default)
			)
			(layer "F.Fab")
		)
		(fp_line
			(start -0.12065 0.2794)
			(end -0.12065 0.3048)
			(stroke
				(width 0.1)
				(type default)
			)
			(layer "F.Fab")
		)
		(fp_line
			(start -0.12065 0.3048)
			(end -0.67945 0.3048)
			(stroke
				(width 0.1)
				(type default)
			)
			(layer "F.Fab")
		)
		(fp_line
			(start 0.120396 0.2794)
			(end -0.12065 0.2794)
			(stroke
				(width 0.1)
				(type default)
			)
			(layer "F.Fab")
		)
		(fp_line
			(start 0.120396 0.3048)
			(end 0.120396 0.2794)
			(stroke
				(width 0.1)
				(type default)
			)
			(layer "F.Fab")
		)
		(fp_line
			(start 0.12065 -0.3048)
			(end 0.67945 -0.3048)
			(stroke
				(width 0.1)
				(type default)
			)
			(layer "F.Fab")
		)
		(fp_line
			(start 0.12065 -0.2794)
			(end 0.12065 -0.3048)
			(stroke
				(width 0.1)
				(type default)
			)
			(layer "F.Fab")
		)
		(fp_line
			(start 0.67945 -0.3048)
			(end 0.67945 0.3048)
			(stroke
				(width 0.1)
				(type default)
			)
			(layer "F.Fab")
		)
		(fp_line
			(start 0.67945 0.3048)
			(end 0.120396 0.3048)
			(stroke
				(width 0.1)
				(type default)
			)
			(layer "F.Fab")
		)
		(pad "1" smd circle
			(at -0.40005 0)
			(size 0 0)
			(layers "F.Cu" "F.Mask" "F.Paste")
			(net "USB_HUB2_TI_VDD33_MRP_PROG_FUNC7")
		)
		(pad "2" smd circle
			(at 0.40005 0)
			(size 0 0)
			(layers "F.Cu" "F.Mask" "F.Paste")
			(net "P3V3_AUX_CPU0_USB2_AVDD33")
		)
	)
	(footprint ""
		(layer "F.Cu")
		(at 331.517244 -381.41783 -90)
		(property "Reference" "C961"
			(at 0 0 270)
			(layer "F.SilkS")
			(hide yes)
			(effects
				(font
					(size 1.27 1.27)
				)
			)
		)
		(property "Value" ""
			(at 0 0 270)
			(layer "F.Fab")
			(effects
				(font
					(size 1.27 1.27)
				)
			)
		)
		(duplicate_pad_numbers_are_jumpers no)
		(fp_line
			(start -0.299974 0.150114)
			(end -0.299974 -0.150114)
			(stroke
				(width 0.1)
				(type default)
			)
			(layer "F.Fab")
		)
		(fp_line
			(start 0.299974 0.150114)
			(end -0.299974 0.150114)
			(stroke
				(width 0.1)
				(type default)
			)
			(layer "F.Fab")
		)
		(fp_line
			(start -0.299974 -0.150114)
			(end 0.299974 -0.150114)
			(stroke
				(width 0.1)
				(type default)
			)
			(layer "F.Fab")
		)
		(fp_line
			(start 0.299974 -0.150114)
			(end 0.299974 0.150114)
			(stroke
				(width 0.1)
				(type default)
			)
			(layer "F.Fab")
		)
		(pad "1" smd rect
			(at -0.2667 0 270)
			(size 0.3048 0.381)
			(layers "F.Cu" "F.Mask" "F.Paste")
			(net "P5E_CPU0_P1_TX_C_DP<2>")
		)
		(pad "2" smd rect
			(at 0.2667 0 270)
			(size 0.3048 0.381)
			(layers "F.Cu" "F.Mask" "F.Paste")
			(net "P5E_CPU0_P1_TX_DP<2>")
		)
	)
	(footprint ""
		(layer "F.Cu")
		(at 89.567512 -72.46366 90)
		(property "Reference" "PC2168"
			(at 0 0 90)
			(layer "F.SilkS")
			(hide yes)
			(effects
				(font
					(size 1.27 1.27)
				)
			)
		)
		(property "Value" ""
			(at 0 0 90)
			(layer "F.Fab")
			(effects
				(font
					(size 1.27 1.27)
				)
			)
		)
		(duplicate_pad_numbers_are_jumpers no)
		(fp_line
			(start 0.7874 -0.4064)
			(end 0.7874 0.4064)
			(stroke
				(width 0.1524)
				(type default)
			)
			(layer "F.SilkS")
		)
		(fp_line
			(start -0.7874 -0.4064)
			(end 0.7874 -0.4064)
			(stroke
				(width 0.1524)
				(type default)
			)
			(layer "F.SilkS")
		)
		(fp_line
			(start 0.7874 0.4064)
			(end -0.7874 0.4064)
			(stroke
				(width 0.1524)
				(type default)
			)
			(layer "F.SilkS")
		)
		(fp_line
			(start -0.7874 0.4064)
			(end -0.7874 -0.4064)
			(stroke
				(width 0.1524)
				(type default)
			)
			(layer "F.SilkS")
		)
		(fp_line
			(start -0.12065 -0.305054)
			(end -0.12065 -0.2794)
			(stroke
				(width 0.1)
				(type default)
			)
			(layer "F.Fab")
		)
		(fp_line
			(start -0.67945 -0.305054)
			(end -0.12065 -0.305054)
			(stroke
				(width 0.1)
				(type default)
			)
			(layer "F.Fab")
		)
		(fp_line
			(start 0.67945 -0.3048)
			(end 0.67945 0.3048)
			(stroke
				(width 0.1)
				(type default)
			)
			(layer "F.Fab")
		)
		(fp_line
			(start 0.12065 -0.3048)
			(end 0.67945 -0.3048)
			(stroke
				(width 0.1)
				(type default)
			)
			(layer "F.Fab")
		)
		(fp_line
			(start 0.12065 -0.2794)
			(end 0.12065 -0.3048)
			(stroke
				(width 0.1)
				(type default)
			)
			(layer "F.Fab")
		)
		(fp_line
			(start -0.12065 -0.2794)
			(end 0.12065 -0.2794)
			(stroke
				(width 0.1)
				(type default)
			)
			(layer "F.Fab")
		)
		(fp_line
			(start 0.120396 0.2794)
			(end -0.12065 0.2794)
			(stroke
				(width 0.1)
				(type default)
			)
			(layer "F.Fab")
		)
		(fp_line
			(start -0.12065 0.2794)
			(end -0.12065 0.3048)
			(stroke
				(width 0.1)
				(type default)
			)
			(layer "F.Fab")
		)
		(fp_line
			(start 0.67945 0.3048)
			(end 0.120396 0.3048)
			(stroke
				(width 0.1)
				(type default)
			)
			(layer "F.Fab")
		)
		(fp_line
			(start 0.120396 0.3048)
			(end 0.120396 0.2794)
			(stroke
				(width 0.1)
				(type default)
			)
			(layer "F.Fab")
		)
		(fp_line
			(start -0.12065 0.3048)
			(end -0.67945 0.3048)
			(stroke
				(width 0.1)
				(type default)
			)
			(layer "F.Fab")
		)
		(fp_line
			(start -0.67945 0.3048)
			(end -0.67945 -0.305054)
			(stroke
				(width 0.1)
				(type default)
			)
			(layer "F.Fab")
		)
		(pad "1" smd circle
			(at -0.40005 0 90)
			(size 0 0)
			(layers "F.Cu" "F.Mask" "F.Paste")
			(net "P3V3_OCP_MODE_2")
		)
		(pad "2" smd circle
			(at 0.40005 0 90)
			(size 0 0)
			(layers "F.Cu" "F.Mask" "F.Paste")
			(net "GND")
		)
	)
	(footprint ""
		(layer "F.Cu")
		(at 36.837112 -368.455448 90)
		(property "Reference" "PC365"
			(at 0 0 90)
			(layer "F.SilkS")
			(hide yes)
			(effects
				(font
					(size 1.27 1.27)
				)
			)
		)
		(property "Value" ""
			(at 0 0 90)
			(layer "F.Fab")
			(effects
				(font
					(size 1.27 1.27)
				)
			)
		)
		(duplicate_pad_numbers_are_jumpers no)
		(fp_line
			(start 0.7874 -0.4064)
			(end 0.7874 0.4064)
			(stroke
				(width 0.1524)
				(type default)
			)
			(layer "F.SilkS")
		)
		(fp_line
			(start -0.7874 -0.4064)
			(end 0.7874 -0.4064)
			(stroke
				(width 0.1524)
				(type default)
			)
			(layer "F.SilkS")
		)
		(fp_line
			(start 0.7874 0.4064)
			(end -0.7874 0.4064)
			(stroke
				(width 0.1524)
				(type default)
			)
			(layer "F.SilkS")
		)
		(fp_line
			(start -0.7874 0.4064)
			(end -0.7874 -0.4064)
			(stroke
				(width 0.1524)
				(type default)
			)
			(layer "F.SilkS")
		)
		(fp_line
			(start -0.12065 -0.305054)
			(end -0.12065 -0.2794)
			(stroke
				(width 0.1)
				(type default)
			)
			(layer "F.Fab")
		)
		(fp_line
			(start -0.67945 -0.305054)
			(end -0.12065 -0.305054)
			(stroke
				(width 0.1)
				(type default)
			)
			(layer "F.Fab")
		)
		(fp_line
			(start 0.67945 -0.3048)
			(end 0.67945 0.3048)
			(stroke
				(width 0.1)
				(type default)
			)
			(layer "F.Fab")
		)
		(fp_line
			(start 0.12065 -0.3048)
			(end 0.67945 -0.3048)
			(stroke
				(width 0.1)
				(type default)
			)
			(layer "F.Fab")
		)
		(fp_line
			(start 0.12065 -0.2794)
			(end 0.12065 -0.3048)
			(stroke
				(width 0.1)
				(type default)
			)
			(layer "F.Fab")
		)
		(fp_line
			(start -0.12065 -0.2794)
			(end 0.12065 -0.2794)
			(stroke
				(width 0.1)
				(type default)
			)
			(layer "F.Fab")
		)
		(fp_line
			(start 0.120396 0.2794)
			(end -0.12065 0.2794)
			(stroke
				(width 0.1)
				(type default)
			)
			(layer "F.Fab")
		)
		(fp_line
			(start -0.12065 0.2794)
			(end -0.12065 0.3048)
			(stroke
				(width 0.1)
				(type default)
			)
			(layer "F.Fab")
		)
		(fp_line
			(start 0.67945 0.3048)
			(end 0.120396 0.3048)
			(stroke
				(width 0.1)
				(type default)
			)
			(layer "F.Fab")
		)
		(fp_line
			(start 0.120396 0.3048)
			(end 0.120396 0.2794)
			(stroke
				(width 0.1)
				(type default)
			)
			(layer "F.Fab")
		)
		(fp_line
			(start -0.12065 0.3048)
			(end -0.67945 0.3048)
			(stroke
				(width 0.1)
				(type default)
			)
			(layer "F.Fab")
		)
		(fp_line
			(start -0.67945 0.3048)
			(end -0.67945 -0.305054)
			(stroke
				(width 0.1)
				(type default)
			)
			(layer "F.Fab")
		)
		(pad "1" smd circle
			(at -0.40005 0 90)
			(size 0 0)
			(layers "F.Cu" "F.Mask" "F.Paste")
			(net "PVDDCR_CPU1_P1_VCC")
		)
		(pad "2" smd circle
			(at 0.40005 0 90)
			(size 0 0)
			(layers "F.Cu" "F.Mask" "F.Paste")
			(net "GND")
		)
	)
	(footprint ""
		(layer "F.Cu")
		(at 322.653152 -34.620962)
		(property "Reference" "U193"
			(at -1.712468 3.20294 0)
			(unlocked yes)
			(layer "F.SilkS")
			(effects
				(font
					(size 0.7874 0.5842)
					(thickness 0.1524)
				)
				(justify left)
			)
		)
		(property "Value" ""
			(at 0 0 0)
			(layer "F.Fab")
			(effects
				(font
					(size 1.27 1.27)
				)
			)
		)
		(duplicate_pad_numbers_are_jumpers no)
		(fp_line
			(start -1.715516 -2.489962)
			(end -1.715516 2.489962)
			(stroke
				(width 0.1524)
				(type default)
			)
			(layer "F.SilkS")
		)
		(fp_line
			(start -1.715516 2.489962)
			(end 1.715516 2.489962)
			(stroke
				(width 0.1524)
				(type default)
			)
			(layer "F.SilkS")
		)
		(fp_line
			(start -1.092962 -2.489962)
			(end -1.715516 -2.489962)
			(stroke
				(width 0.1524)
				(type default)
			)
			(layer "F.SilkS")
		)
		(fp_line
			(start 0 -1.397)
			(end -1.092962 -2.489962)
			(stroke
				(width 0.1524)
				(type default)
			)
			(layer "F.SilkS")
		)
		(fp_line
			(start 1.092962 -2.489962)
			(end 0 -1.397)
			(stroke
				(width 0.1524)
				(type default)
			)
			(layer "F.SilkS")
		)
		(fp_line
			(start 1.715516 -2.489962)
			(end 1.092962 -2.489962)
			(stroke
				(width 0.1524)
				(type default)
			)
			(layer "F.SilkS")
		)
		(fp_line
			(start 1.715516 2.489962)
			(end 1.715516 -2.489962)
			(stroke
				(width 0.1524)
				(type default)
			)
			(layer "F.SilkS")
		)
		(fp_poly
			(pts
				(xy -3.203956 -3.79984) (xy -2.187956 -3.79984) (xy -2.695956 -2.78384)
			)
			(stroke
				(width 0)
				(type default)
			)
			(fill yes)
			(layer "F.SilkS")
		)
		(fp_line
			(start -1.994916 -2.489962)
			(end -1.994916 2.489962)
			(stroke
				(width 0.1)
				(type default)
			)
			(layer "F.Fab")
		)
		(fp_line
			(start -1.994916 2.489962)
			(end 1.994916 2.489962)
			(stroke
				(width 0.1)
				(type default)
			)
			(layer "F.Fab")
		)
		(fp_line
			(start 1.994916 -2.489962)
			(end -1.994916 -2.489962)
			(stroke
				(width 0.1)
				(type default)
			)
			(layer "F.Fab")
		)
		(fp_line
			(start 1.994916 2.489962)
			(end 1.994916 -2.489962)
			(stroke
				(width 0.1)
				(type default)
			)
			(layer "F.Fab")
		)
		(fp_poly
			(pts
				(xy -4.699 -2.7305) (xy -4.699 -1.7145) (xy -3.683 -2.2225)
			)
			(stroke
				(width 0)
				(type default)
			)
			(fill yes)
			(layer "F.Fab")
		)
		(pad "1" smd rect
			(at -2.655062 -2.2225 90)
			(size 0.381 1.6002)
			(layers "F.Cu" "F.Mask" "F.Paste")
			(net "MAX11617_VREF_R")
		)
		(pad "2" smd rect
			(at -2.655062 -1.5875 90)
			(size 0.381 1.6002)
			(layers "F.Cu" "F.Mask" "F.Paste")
			(net "GND")
		)
		(pad "3" smd rect
			(at -2.655062 -0.9525 90)
			(size 0.381 1.6002)
			(layers "F.Cu" "F.Mask" "F.Paste")
			(net "GND")
		)
		(pad "4" smd rect
			(at -2.655062 -0.3175 90)
			(size 0.381 1.6002)
			(layers "F.Cu" "F.Mask" "F.Paste")
			(net "GND")
		)
		(pad "5" smd rect
			(at -2.655062 0.3175 90)
			(size 0.381 1.6002)
			(layers "F.Cu" "F.Mask" "F.Paste")
			(net "P12V_AUX_ADC_MAM")
		)
		(pad "6" smd rect
			(at -2.655062 0.9525 90)
			(size 0.381 1.6002)
			(layers "F.Cu" "F.Mask" "F.Paste")
			(net "P12V_OCP_SFF_ISENSE_MAM")
		)
		(pad "7" smd rect
			(at -2.655062 1.5875 90)
			(size 0.381 1.6002)
			(layers "F.Cu" "F.Mask" "F.Paste")
			(net "P12V_OCP_V3_2_ISENSE_MAM")
		)
		(pad "8" smd rect
			(at -2.655062 2.2225 90)
			(size 0.381 1.6002)
			(layers "F.Cu" "F.Mask" "F.Paste")
			(net "P5V_ADC_MAM")
		)
		(pad "9" smd rect
			(at 2.655062 2.2225 90)
			(size 0.381 1.6002)
			(layers "F.Cu" "F.Mask" "F.Paste")
			(net "P3V3_ADC_MAM")
		)
		(pad "10" smd rect
			(at 2.655062 1.5875 90)
			(size 0.381 1.6002)
			(layers "F.Cu" "F.Mask" "F.Paste")
			(net "P3V3_AUX_ADC_MAM")
		)
		(pad "11" smd rect
			(at 2.655062 0.9525 90)
			(size 0.381 1.6002)
			(layers "F.Cu" "F.Mask" "F.Paste")
			(net "P3V3_PDB_AUX_ADC_MAM")
		)
		(pad "12" smd rect
			(at 2.655062 0.3175 90)
			(size 0.381 1.6002)
			(layers "F.Cu" "F.Mask" "F.Paste")
			(net "P12V_E1S_0_ISENSE_MAM")
		)
		(pad "13" smd rect
			(at 2.655062 -0.3175 90)
			(size 0.381 1.6002)
			(layers "F.Cu" "F.Mask" "F.Paste")
			(net "SMB_SEN_MAM_3V3AUX_SCL")
		)
		(pad "14" smd rect
			(at 2.655062 -0.9525 90)
			(size 0.381 1.6002)
			(layers "F.Cu" "F.Mask" "F.Paste")
			(net "SMB_SEN_MAM_3V3AUX_SDA")
		)
		(pad "15" smd rect
			(at 2.655062 -1.5875 90)
			(size 0.381 1.6002)
			(layers "F.Cu" "F.Mask" "F.Paste")
			(net "GND")
		)
		(pad "16" smd rect
			(at 2.655062 -2.2225 90)
			(size 0.381 1.6002)
			(layers "F.Cu" "F.Mask" "F.Paste")
			(net "P3V3_MAX11617_VDD")
		)
	)
	(footprint ""
		(layer "F.Cu")
		(at 142.595092 -381.48006 180)
		(property "Reference" "C772"
			(at 0 0 180)
			(layer "F.SilkS")
			(hide yes)
			(effects
				(font
					(size 1.27 1.27)
				)
			)
		)
		(property "Value" ""
			(at 0 0 180)
			(layer "F.Fab")
			(effects
				(font
					(size 1.27 1.27)
				)
			)
		)
		(duplicate_pad_numbers_are_jumpers no)
		(fp_line
			(start 0.299974 0.150114)
			(end -0.299974 0.150114)
			(stroke
				(width 0.1)
				(type default)
			)
			(layer "F.Fab")
		)
		(fp_line
			(start 0.299974 -0.150114)
			(end 0.299974 0.150114)
			(stroke
				(width 0.1)
				(type default)
			)
			(layer "F.Fab")
		)
		(fp_line
			(start -0.299974 0.150114)
			(end -0.299974 -0.150114)
			(stroke
				(width 0.1)
				(type default)
			)
			(layer "F.Fab")
		)
		(fp_line
			(start -0.299974 -0.150114)
			(end 0.299974 -0.150114)
			(stroke
				(width 0.1)
				(type default)
			)
			(layer "F.Fab")
		)
		(pad "1" smd rect
			(at -0.2667 0 180)
			(size 0.3048 0.381)
			(layers "F.Cu" "F.Mask" "F.Paste")
			(net "P5E_CPU1_P2_TX_C_DN<0>")
		)
		(pad "2" smd rect
			(at 0.2667 0 180)
			(size 0.3048 0.381)
			(layers "F.Cu" "F.Mask" "F.Paste")
			(net "P5E_CPU1_P2_TX_DN<0>")
		)
	)
	(footprint ""
		(layer "F.Cu")
		(at 97.288096 -178.0413 90)
		(property "Reference" "PC300"
			(at 0 0 90)
			(layer "F.SilkS")
			(hide yes)
			(effects
				(font
					(size 1.27 1.27)
				)
			)
		)
		(property "Value" ""
			(at 0 0 90)
			(layer "F.Fab")
			(effects
				(font
					(size 1.27 1.27)
				)
			)
		)
		(duplicate_pad_numbers_are_jumpers no)
		(fp_line
			(start 0.7874 -0.4064)
			(end 0.7874 0.4064)
			(stroke
				(width 0.1524)
				(type default)
			)
			(layer "F.SilkS")
		)
		(fp_line
			(start -0.7874 -0.4064)
			(end 0.7874 -0.4064)
			(stroke
				(width 0.1524)
				(type default)
			)
			(layer "F.SilkS")
		)
		(fp_line
			(start 0.7874 0.4064)
			(end -0.7874 0.4064)
			(stroke
				(width 0.1524)
				(type default)
			)
			(layer "F.SilkS")
		)
		(fp_line
			(start -0.7874 0.4064)
			(end -0.7874 -0.4064)
			(stroke
				(width 0.1524)
				(type default)
			)
			(layer "F.SilkS")
		)
		(fp_line
			(start -0.12065 -0.305054)
			(end -0.12065 -0.2794)
			(stroke
				(width 0.1)
				(type default)
			)
			(layer "F.Fab")
		)
		(fp_line
			(start -0.67945 -0.305054)
			(end -0.12065 -0.305054)
			(stroke
				(width 0.1)
				(type default)
			)
			(layer "F.Fab")
		)
		(fp_line
			(start 0.67945 -0.3048)
			(end 0.67945 0.3048)
			(stroke
				(width 0.1)
				(type default)
			)
			(layer "F.Fab")
		)
		(fp_line
			(start 0.12065 -0.3048)
			(end 0.67945 -0.3048)
			(stroke
				(width 0.1)
				(type default)
			)
			(layer "F.Fab")
		)
		(fp_line
			(start 0.12065 -0.2794)
			(end 0.12065 -0.3048)
			(stroke
				(width 0.1)
				(type default)
			)
			(layer "F.Fab")
		)
		(fp_line
			(start -0.12065 -0.2794)
			(end 0.12065 -0.2794)
			(stroke
				(width 0.1)
				(type default)
			)
			(layer "F.Fab")
		)
		(fp_line
			(start 0.120396 0.2794)
			(end -0.12065 0.2794)
			(stroke
				(width 0.1)
				(type default)
			)
			(layer "F.Fab")
		)
		(fp_line
			(start -0.12065 0.2794)
			(end -0.12065 0.3048)
			(stroke
				(width 0.1)
				(type default)
			)
			(layer "F.Fab")
		)
		(fp_line
			(start 0.67945 0.3048)
			(end 0.120396 0.3048)
			(stroke
				(width 0.1)
				(type default)
			)
			(layer "F.Fab")
		)
		(fp_line
			(start 0.120396 0.3048)
			(end 0.120396 0.2794)
			(stroke
				(width 0.1)
				(type default)
			)
			(layer "F.Fab")
		)
		(fp_line
			(start -0.12065 0.3048)
			(end -0.67945 0.3048)
			(stroke
				(width 0.1)
				(type default)
			)
			(layer "F.Fab")
		)
		(fp_line
			(start -0.67945 0.3048)
			(end -0.67945 -0.305054)
			(stroke
				(width 0.1)
				(type default)
			)
			(layer "F.Fab")
		)
		(pad "1" smd circle
			(at -0.40005 0 90)
			(size 0 0)
			(layers "F.Cu" "F.Mask" "F.Paste")
			(net "SW_PVDDCR_CPU0_P1_BOOT3_RC")
		)
		(pad "2" smd circle
			(at 0.40005 0 90)
			(size 0 0)
			(layers "F.Cu" "F.Mask" "F.Paste")
			(net "SW_PVDDCR_CPU0_P1_PH3")
		)
	)
	(footprint ""
		(layer "F.Cu")
		(at 167.132 -119.344948 180)
		(property "Reference" "R638"
			(at 0 0 180)
			(layer "F.SilkS")
			(hide yes)
			(effects
				(font
					(size 1.27 1.27)
				)
			)
		)
		(property "Value" ""
			(at 0 0 180)
			(layer "F.Fab")
			(effects
				(font
					(size 1.27 1.27)
				)
			)
		)
		(duplicate_pad_numbers_are_jumpers no)
		(fp_line
			(start 0.7874 0.4064)
			(end -0.7874 0.4064)
			(stroke
				(width 0.1524)
				(type default)
			)
			(layer "F.SilkS")
		)
		(fp_line
			(start 0.7874 -0.4064)
			(end 0.7874 0.4064)
			(stroke
				(width 0.1524)
				(type default)
			)
			(layer "F.SilkS")
		)
		(fp_line
			(start -0.7874 0.4064)
			(end -0.7874 -0.4064)
			(stroke
				(width 0.1524)
				(type default)
			)
			(layer "F.SilkS")
		)
		(fp_line
			(start -0.7874 -0.4064)
			(end 0.7874 -0.4064)
			(stroke
				(width 0.1524)
				(type default)
			)
			(layer "F.SilkS")
		)
		(fp_line
			(start 0.67945 0.3048)
			(end 0.120396 0.3048)
			(stroke
				(width 0.1)
				(type default)
			)
			(layer "F.Fab")
		)
		(fp_line
			(start 0.67945 -0.3048)
			(end 0.67945 0.3048)
			(stroke
				(width 0.1)
				(type default)
			)
			(layer "F.Fab")
		)
		(fp_line
			(start 0.12065 -0.2794)
			(end 0.12065 -0.3048)
			(stroke
				(width 0.1)
				(type default)
			)
			(layer "F.Fab")
		)
		(fp_line
			(start 0.12065 -0.3048)
			(end 0.67945 -0.3048)
			(stroke
				(width 0.1)
				(type default)
			)
			(layer "F.Fab")
		)
		(fp_line
			(start 0.120396 0.3048)
			(end 0.120396 0.2794)
			(stroke
				(width 0.1)
				(type default)
			)
			(layer "F.Fab")
		)
		(fp_line
			(start 0.120396 0.2794)
			(end -0.12065 0.2794)
			(stroke
				(width 0.1)
				(type default)
			)
			(layer "F.Fab")
		)
		(fp_line
			(start -0.12065 0.3048)
			(end -0.67945 0.3048)
			(stroke
				(width 0.1)
				(type default)
			)
			(layer "F.Fab")
		)
		(fp_line
			(start -0.12065 0.2794)
			(end -0.12065 0.3048)
			(stroke
				(width 0.1)
				(type default)
			)
			(layer "F.Fab")
		)
		(fp_line
			(start -0.12065 -0.2794)
			(end 0.12065 -0.2794)
			(stroke
				(width 0.1)
				(type default)
			)
			(layer "F.Fab")
		)
		(fp_line
			(start -0.12065 -0.305054)
			(end -0.12065 -0.2794)
			(stroke
				(width 0.1)
				(type default)
			)
			(layer "F.Fab")
		)
		(fp_line
			(start -0.67945 0.3048)
			(end -0.67945 -0.305054)
			(stroke
				(width 0.1)
				(type default)
			)
			(layer "F.Fab")
		)
		(fp_line
			(start -0.67945 -0.305054)
			(end -0.12065 -0.305054)
			(stroke
				(width 0.1)
				(type default)
			)
			(layer "F.Fab")
		)
		(pad "1" smd circle
			(at -0.40005 0 180)
			(size 0 0)
			(layers "F.Cu" "F.Mask" "F.Paste")
			(net "CPLD_JTAG_EN")
		)
		(pad "2" smd circle
			(at 0.40005 0 180)
			(size 0 0)
			(layers "F.Cu" "F.Mask" "F.Paste")
			(net "P3V3_AUX")
		)
	)
	(footprint ""
		(layer "F.Cu")
		(at 268.197584 -393.91336 -90)
		(property "Reference" "PR2532"
			(at -4.57454 2.978404 90)
			(unlocked yes)
			(layer "F.SilkS")
			(effects
				(font
					(size 0.7874 0.5842)
					(thickness 0.1524)
				)
				(justify left)
			)
		)
		(property "Value" ""
			(at 0 0 270)
			(layer "F.Fab")
			(effects
				(font
					(size 1.27 1.27)
				)
			)
		)
		(duplicate_pad_numbers_are_jumpers no)
		(fp_line
			(start -3.9878 3.5814)
			(end -3.9878 -3.5814)
			(stroke
				(width 0.1524)
				(type default)
			)
			(layer "F.SilkS")
		)
		(fp_line
			(start 3.9878 3.5814)
			(end -3.9878 3.5814)
			(stroke
				(width 0.1524)
				(type default)
			)
			(layer "F.SilkS")
		)
		(fp_line
			(start -3.9878 -3.5814)
			(end 3.9878 -3.5814)
			(stroke
				(width 0.1524)
				(type default)
			)
			(layer "F.SilkS")
		)
		(fp_line
			(start 3.9878 -3.5814)
			(end 3.9878 3.5814)
			(stroke
				(width 0.1524)
				(type default)
			)
			(layer "F.SilkS")
		)
		(fp_line
			(start -3.5306 3.353054)
			(end -3.5306 -3.353054)
			(stroke
				(width 0.1)
				(type default)
			)
			(layer "F.Fab")
		)
		(fp_line
			(start 3.5306 3.353054)
			(end -3.5306 3.353054)
			(stroke
				(width 0.1)
				(type default)
			)
			(layer "F.Fab")
		)
		(fp_line
			(start -3.5306 -3.353054)
			(end 3.5306 -3.353054)
			(stroke
				(width 0.1)
				(type default)
			)
			(layer "F.Fab")
		)
		(fp_line
			(start 3.5306 -3.353054)
			(end 3.5306 3.353054)
			(stroke
				(width 0.1)
				(type default)
			)
			(layer "F.Fab")
		)
		(pad "1A" smd rect
			(at -2.249932 0 90)
			(size 3.2004 6.858)
			(layers "F.Cu" "F.Mask" "F.Paste")
			(net "P12V_PSU")
		)
		(pad "1B" smd rect
			(at -0.776732 0 270)
			(size 0.254 0.508)
			(layers "F.Cu" "F.Mask" "F.Paste")
			(net "P12V_HSC_SENSE2_R2_P")
		)
		(pad "2A" smd rect
			(at 2.249932 0 90)
			(size 3.2004 6.858)
			(layers "F.Cu" "F.Mask" "F.Paste")
			(net "P12V_MAIN_R")
		)
		(pad "2B" smd rect
			(at 0.776732 0 270)
			(size 0.254 0.508)
			(layers "F.Cu" "F.Mask" "F.Paste")
			(net "P12V_HSC_SENSE2_R2_N")
		)
	)
	(footprint ""
		(layer "F.Cu")
		(at 308.002432 -410.406596 90)
		(property "Reference" "C7034"
			(at 0 0 90)
			(layer "F.SilkS")
			(hide yes)
			(effects
				(font
					(size 1.27 1.27)
				)
			)
		)
		(property "Value" ""
			(at 0 0 90)
			(layer "F.Fab")
			(effects
				(font
					(size 1.27 1.27)
				)
			)
		)
		(duplicate_pad_numbers_are_jumpers no)
		(fp_line
			(start 1.524 -0.762)
			(end 1.524 0.762)
			(stroke
				(width 0.1524)
				(type default)
			)
			(layer "F.SilkS")
		)
		(fp_line
			(start -1.524 -0.762)
			(end 1.524 -0.762)
			(stroke
				(width 0.1524)
				(type default)
			)
			(layer "F.SilkS")
		)
		(fp_line
			(start 1.524 0.762)
			(end -1.524 0.762)
			(stroke
				(width 0.1524)
				(type default)
			)
			(layer "F.SilkS")
		)
		(fp_line
			(start -1.524 0.762)
			(end -1.524 -0.762)
			(stroke
				(width 0.1524)
				(type default)
			)
			(layer "F.SilkS")
		)
		(fp_line
			(start 1.1049 -0.724916)
			(end -1.1049 -0.724916)
			(stroke
				(width 0.1)
				(type default)
			)
			(layer "F.Fab")
		)
		(fp_line
			(start -1.1049 -0.724916)
			(end -1.1049 0.724916)
			(stroke
				(width 0.1)
				(type default)
			)
			(layer "F.Fab")
		)
		(fp_line
			(start 1.1049 0.724916)
			(end 1.1049 -0.724916)
			(stroke
				(width 0.1)
				(type default)
			)
			(layer "F.Fab")
		)
		(fp_line
			(start -1.1049 0.724916)
			(end 1.1049 0.724916)
			(stroke
				(width 0.1)
				(type default)
			)
			(layer "F.Fab")
		)
		(pad "1" smd rect
			(at -0.889 0 270)
			(size 1.016 1.27)
			(layers "F.Cu" "F.Mask" "F.Paste")
			(net "P0V9_CPU0_RT_2D")
		)
		(pad "2" smd rect
			(at 0.889 0 270)
			(size 1.016 1.27)
			(layers "F.Cu" "F.Mask" "F.Paste")
			(net "GND")
		)
	)
	(footprint ""
		(layer "F.Cu")
		(at 68.2117 -36.294568)
		(property "Reference" "R4092"
			(at 0 0 0)
			(layer "F.SilkS")
			(hide yes)
			(effects
				(font
					(size 1.27 1.27)
				)
			)
		)
		(property "Value" ""
			(at 0 0 0)
			(layer "F.Fab")
			(effects
				(font
					(size 1.27 1.27)
				)
			)
		)
		(duplicate_pad_numbers_are_jumpers no)
		(fp_line
			(start -0.7874 -0.4064)
			(end 0.7874 -0.4064)
			(stroke
				(width 0.1524)
				(type default)
			)
			(layer "F.SilkS")
		)
		(fp_line
			(start -0.7874 0.4064)
			(end -0.7874 -0.4064)
			(stroke
				(width 0.1524)
				(type default)
			)
			(layer "F.SilkS")
		)
		(fp_line
			(start 0.7874 -0.4064)
			(end 0.7874 0.4064)
			(stroke
				(width 0.1524)
				(type default)
			)
			(layer "F.SilkS")
		)
		(fp_line
			(start 0.7874 0.4064)
			(end -0.7874 0.4064)
			(stroke
				(width 0.1524)
				(type default)
			)
			(layer "F.SilkS")
		)
		(fp_line
			(start -0.67945 -0.305054)
			(end -0.12065 -0.305054)
			(stroke
				(width 0.1)
				(type default)
			)
			(layer "F.Fab")
		)
		(fp_line
			(start -0.67945 0.3048)
			(end -0.67945 -0.305054)
			(stroke
				(width 0.1)
				(type default)
			)
			(layer "F.Fab")
		)
		(fp_line
			(start -0.12065 -0.305054)
			(end -0.12065 -0.2794)
			(stroke
				(width 0.1)
				(type default)
			)
			(layer "F.Fab")
		)
		(fp_line
			(start -0.12065 -0.2794)
			(end 0.12065 -0.2794)
			(stroke
				(width 0.1)
				(type default)
			)
			(layer "F.Fab")
		)
		(fp_line
			(start -0.12065 0.2794)
			(end -0.12065 0.3048)
			(stroke
				(width 0.1)
				(type default)
			)
			(layer "F.Fab")
		)
		(fp_line
			(start -0.12065 0.3048)
			(end -0.67945 0.3048)
			(stroke
				(width 0.1)
				(type default)
			)
			(layer "F.Fab")
		)
		(fp_line
			(start 0.120396 0.2794)
			(end -0.12065 0.2794)
			(stroke
				(width 0.1)
				(type default)
			)
			(layer "F.Fab")
		)
		(fp_line
			(start 0.120396 0.3048)
			(end 0.120396 0.2794)
			(stroke
				(width 0.1)
				(type default)
			)
			(layer "F.Fab")
		)
		(fp_line
			(start 0.12065 -0.3048)
			(end 0.67945 -0.3048)
			(stroke
				(width 0.1)
				(type default)
			)
			(layer "F.Fab")
		)
		(fp_line
			(start 0.12065 -0.2794)
			(end 0.12065 -0.3048)
			(stroke
				(width 0.1)
				(type default)
			)
			(layer "F.Fab")
		)
		(fp_line
			(start 0.67945 -0.3048)
			(end 0.67945 0.3048)
			(stroke
				(width 0.1)
				(type default)
			)
			(layer "F.Fab")
		)
		(fp_line
			(start 0.67945 0.3048)
			(end 0.120396 0.3048)
			(stroke
				(width 0.1)
				(type default)
			)
			(layer "F.Fab")
		)
		(pad "1" smd circle
			(at -0.40005 0)
			(size 0 0)
			(layers "F.Cu" "F.Mask" "F.Paste")
			(net "P3V3_AUX")
		)
		(pad "2" smd circle
			(at 0.40005 0)
			(size 0 0)
			(layers "F.Cu" "F.Mask" "F.Paste")
			(net "OCP_V3_2_P3V3_ADC_ALERT_R")
		)
	)
	(footprint ""
		(layer "F.Cu")
		(at 448.177412 -30.131258 90)
		(property "Reference" "PC2154"
			(at 0 0 90)
			(layer "F.SilkS")
			(hide yes)
			(effects
				(font
					(size 1.27 1.27)
				)
			)
		)
		(property "Value" ""
			(at 0 0 90)
			(layer "F.Fab")
			(effects
				(font
					(size 1.27 1.27)
				)
			)
		)
		(duplicate_pad_numbers_are_jumpers no)
		(fp_line
			(start 0.7874 -0.4064)
			(end 0.7874 0.4064)
			(stroke
				(width 0.1524)
				(type default)
			)
			(layer "F.SilkS")
		)
		(fp_line
			(start -0.7874 -0.4064)
			(end 0.7874 -0.4064)
			(stroke
				(width 0.1524)
				(type default)
			)
			(layer "F.SilkS")
		)
		(fp_line
			(start 0.7874 0.4064)
			(end -0.7874 0.4064)
			(stroke
				(width 0.1524)
				(type default)
			)
			(layer "F.SilkS")
		)
		(fp_line
			(start -0.7874 0.4064)
			(end -0.7874 -0.4064)
			(stroke
				(width 0.1524)
				(type default)
			)
			(layer "F.SilkS")
		)
		(fp_line
			(start -0.12065 -0.305054)
			(end -0.12065 -0.2794)
			(stroke
				(width 0.1)
				(type default)
			)
			(layer "F.Fab")
		)
		(fp_line
			(start -0.67945 -0.305054)
			(end -0.12065 -0.305054)
			(stroke
				(width 0.1)
				(type default)
			)
			(layer "F.Fab")
		)
		(fp_line
			(start 0.67945 -0.3048)
			(end 0.67945 0.3048)
			(stroke
				(width 0.1)
				(type default)
			)
			(layer "F.Fab")
		)
		(fp_line
			(start 0.12065 -0.3048)
			(end 0.67945 -0.3048)
			(stroke
				(width 0.1)
				(type default)
			)
			(layer "F.Fab")
		)
		(fp_line
			(start 0.12065 -0.2794)
			(end 0.12065 -0.3048)
			(stroke
				(width 0.1)
				(type default)
			)
			(layer "F.Fab")
		)
		(fp_line
			(start -0.12065 -0.2794)
			(end 0.12065 -0.2794)
			(stroke
				(width 0.1)
				(type default)
			)
			(layer "F.Fab")
		)
		(fp_line
			(start 0.120396 0.2794)
			(end -0.12065 0.2794)
			(stroke
				(width 0.1)
				(type default)
			)
			(layer "F.Fab")
		)
		(fp_line
			(start -0.12065 0.2794)
			(end -0.12065 0.3048)
			(stroke
				(width 0.1)
				(type default)
			)
			(layer "F.Fab")
		)
		(fp_line
			(start 0.67945 0.3048)
			(end 0.120396 0.3048)
			(stroke
				(width 0.1)
				(type default)
			)
			(layer "F.Fab")
		)
		(fp_line
			(start 0.120396 0.3048)
			(end 0.120396 0.2794)
			(stroke
				(width 0.1)
				(type default)
			)
			(layer "F.Fab")
		)
		(fp_line
			(start -0.12065 0.3048)
			(end -0.67945 0.3048)
			(stroke
				(width 0.1)
				(type default)
			)
			(layer "F.Fab")
		)
		(fp_line
			(start -0.67945 0.3048)
			(end -0.67945 -0.305054)
			(stroke
				(width 0.1)
				(type default)
			)
			(layer "F.Fab")
		)
		(pad "1" smd circle
			(at -0.40005 0 90)
			(size 0 0)
			(layers "F.Cu" "F.Mask" "F.Paste")
			(net "P12V_AUX")
		)
		(pad "2" smd circle
			(at 0.40005 0 90)
			(size 0 0)
			(layers "F.Cu" "F.Mask" "F.Paste")
			(net "GND")
		)
	)
	(footprint ""
		(layer "F.Cu")
		(at 267.896848 -339.218778 90)
		(property "Reference" "PL16"
			(at -3.302 -3.978148 90)
			(unlocked yes)
			(layer "F.SilkS")
			(effects
				(font
					(size 0.7874 0.5842)
					(thickness 0.1524)
				)
				(justify left)
			)
		)
		(property "Value" ""
			(at 0 0 90)
			(layer "F.Fab")
			(effects
				(font
					(size 1.27 1.27)
				)
			)
		)
		(duplicate_pad_numbers_are_jumpers no)
		(fp_line
			(start 3.24993 -3.24993)
			(end 3.24993 -2.2352)
			(stroke
				(width 0.1524)
				(type default)
			)
			(layer "F.SilkS")
		)
		(fp_line
			(start -3.24993 -3.24993)
			(end 3.24993 -3.24993)
			(stroke
				(width 0.1524)
				(type default)
			)
			(layer "F.SilkS")
		)
		(fp_line
			(start -3.24993 -2.2352)
			(end -3.24993 -3.24993)
			(stroke
				(width 0.1524)
				(type default)
			)
			(layer "F.SilkS")
		)
		(fp_line
			(start 3.24993 2.2352)
			(end 3.24993 3.24993)
			(stroke
				(width 0.1524)
				(type default)
			)
			(layer "F.SilkS")
		)
		(fp_line
			(start 3.24993 3.24993)
			(end -3.24993 3.24993)
			(stroke
				(width 0.1524)
				(type default)
			)
			(layer "F.SilkS")
		)
		(fp_line
			(start -3.24993 3.24993)
			(end -3.24993 2.2352)
			(stroke
				(width 0.1524)
				(type default)
			)
			(layer "F.SilkS")
		)
		(fp_line
			(start 3.24993 -3.24993)
			(end 3.24993 3.24993)
			(stroke
				(width 0.1)
				(type default)
			)
			(layer "F.Fab")
		)
		(fp_line
			(start -3.24993 -3.24993)
			(end 3.24993 -3.24993)
			(stroke
				(width 0.1)
				(type default)
			)
			(layer "F.Fab")
		)
		(fp_line
			(start 3.24993 3.24993)
			(end -3.24993 3.24993)
			(stroke
				(width 0.1)
				(type default)
			)
			(layer "F.Fab")
		)
		(fp_line
			(start -3.24993 3.24993)
			(end -3.24993 -3.24993)
			(stroke
				(width 0.1)
				(type default)
			)
			(layer "F.Fab")
		)
		(pad "1" smd rect
			(at -2.29997 0 90)
			(size 2.0066 4.2164)
			(layers "F.Cu" "F.Mask" "F.Paste")
			(net "IND_PVDDIO_P0_CPL0")
		)
		(pad "2" smd rect
			(at 2.29997 0 90)
			(size 2.0066 4.2164)
			(layers "F.Cu" "F.Mask" "F.Paste")
			(net "GND")
		)
	)
	(footprint ""
		(layer "F.Cu")
		(at 365.835692 -255.554988 180)
		(property "Reference" "C2535"
			(at 0 0 180)
			(layer "F.SilkS")
			(hide yes)
			(effects
				(font
					(size 1.27 1.27)
				)
			)
		)
		(property "Value" ""
			(at 0 0 180)
			(layer "F.Fab")
			(effects
				(font
					(size 1.27 1.27)
				)
			)
		)
		(duplicate_pad_numbers_are_jumpers no)
		(fp_line
			(start 0.7874 0.4064)
			(end -0.7874 0.4064)
			(stroke
				(width 0.1524)
				(type default)
			)
			(layer "F.SilkS")
		)
		(fp_line
			(start 0.7874 -0.4064)
			(end 0.7874 0.4064)
			(stroke
				(width 0.1524)
				(type default)
			)
			(layer "F.SilkS")
		)
		(fp_line
			(start -0.7874 0.4064)
			(end -0.7874 -0.4064)
			(stroke
				(width 0.1524)
				(type default)
			)
			(layer "F.SilkS")
		)
		(fp_line
			(start -0.7874 -0.4064)
			(end 0.7874 -0.4064)
			(stroke
				(width 0.1524)
				(type default)
			)
			(layer "F.SilkS")
		)
		(fp_line
			(start 0.67945 0.3048)
			(end 0.120396 0.3048)
			(stroke
				(width 0.1)
				(type default)
			)
			(layer "F.Fab")
		)
		(fp_line
			(start 0.67945 -0.3048)
			(end 0.67945 0.3048)
			(stroke
				(width 0.1)
				(type default)
			)
			(layer "F.Fab")
		)
		(fp_line
			(start 0.12065 -0.2794)
			(end 0.12065 -0.3048)
			(stroke
				(width 0.1)
				(type default)
			)
			(layer "F.Fab")
		)
		(fp_line
			(start 0.12065 -0.3048)
			(end 0.67945 -0.3048)
			(stroke
				(width 0.1)
				(type default)
			)
			(layer "F.Fab")
		)
		(fp_line
			(start 0.120396 0.3048)
			(end 0.120396 0.2794)
			(stroke
				(width 0.1)
				(type default)
			)
			(layer "F.Fab")
		)
		(fp_line
			(start 0.120396 0.2794)
			(end -0.12065 0.2794)
			(stroke
				(width 0.1)
				(type default)
			)
			(layer "F.Fab")
		)
		(fp_line
			(start -0.12065 0.3048)
			(end -0.67945 0.3048)
			(stroke
				(width 0.1)
				(type default)
			)
			(layer "F.Fab")
		)
		(fp_line
			(start -0.12065 0.2794)
			(end -0.12065 0.3048)
			(stroke
				(width 0.1)
				(type default)
			)
			(layer "F.Fab")
		)
		(fp_line
			(start -0.12065 -0.2794)
			(end 0.12065 -0.2794)
			(stroke
				(width 0.1)
				(type default)
			)
			(layer "F.Fab")
		)
		(fp_line
			(start -0.12065 -0.305054)
			(end -0.12065 -0.2794)
			(stroke
				(width 0.1)
				(type default)
			)
			(layer "F.Fab")
		)
		(fp_line
			(start -0.67945 0.3048)
			(end -0.67945 -0.305054)
			(stroke
				(width 0.1)
				(type default)
			)
			(layer "F.Fab")
		)
		(fp_line
			(start -0.67945 -0.305054)
			(end -0.12065 -0.305054)
			(stroke
				(width 0.1)
				(type default)
			)
			(layer "F.Fab")
		)
		(pad "1" smd circle
			(at -0.40005 0 180)
			(size 0 0)
			(layers "F.Cu" "F.Mask" "F.Paste")
			(net "PVDDCR_SOC_P0")
		)
		(pad "2" smd circle
			(at 0.40005 0 180)
			(size 0 0)
			(layers "F.Cu" "F.Mask" "F.Paste")
			(net "GND")
		)
	)
	(footprint ""
		(layer "F.Cu")
		(at 26.545794 -393.317984 90)
		(property "Reference" "PR6629"
			(at 0 0 90)
			(layer "F.SilkS")
			(hide yes)
			(effects
				(font
					(size 1.27 1.27)
				)
			)
		)
		(property "Value" ""
			(at 0 0 90)
			(layer "F.Fab")
			(effects
				(font
					(size 1.27 1.27)
				)
			)
		)
		(duplicate_pad_numbers_are_jumpers no)
		(fp_line
			(start 0.7874 -0.4064)
			(end 0.7874 0.4064)
			(stroke
				(width 0.1524)
				(type default)
			)
			(layer "F.SilkS")
		)
		(fp_line
			(start -0.7874 -0.4064)
			(end 0.7874 -0.4064)
			(stroke
				(width 0.1524)
				(type default)
			)
			(layer "F.SilkS")
		)
		(fp_line
			(start 0.7874 0.4064)
			(end -0.7874 0.4064)
			(stroke
				(width 0.1524)
				(type default)
			)
			(layer "F.SilkS")
		)
		(fp_line
			(start -0.7874 0.4064)
			(end -0.7874 -0.4064)
			(stroke
				(width 0.1524)
				(type default)
			)
			(layer "F.SilkS")
		)
		(fp_line
			(start -0.12065 -0.305054)
			(end -0.12065 -0.2794)
			(stroke
				(width 0.1)
				(type default)
			)
			(layer "F.Fab")
		)
		(fp_line
			(start -0.67945 -0.305054)
			(end -0.12065 -0.305054)
			(stroke
				(width 0.1)
				(type default)
			)
			(layer "F.Fab")
		)
		(fp_line
			(start 0.67945 -0.3048)
			(end 0.67945 0.3048)
			(stroke
				(width 0.1)
				(type default)
			)
			(layer "F.Fab")
		)
		(fp_line
			(start 0.12065 -0.3048)
			(end 0.67945 -0.3048)
			(stroke
				(width 0.1)
				(type default)
			)
			(layer "F.Fab")
		)
		(fp_line
			(start 0.12065 -0.2794)
			(end 0.12065 -0.3048)
			(stroke
				(width 0.1)
				(type default)
			)
			(layer "F.Fab")
		)
		(fp_line
			(start -0.12065 -0.2794)
			(end 0.12065 -0.2794)
			(stroke
				(width 0.1)
				(type default)
			)
			(layer "F.Fab")
		)
		(fp_line
			(start 0.120396 0.2794)
			(end -0.12065 0.2794)
			(stroke
				(width 0.1)
				(type default)
			)
			(layer "F.Fab")
		)
		(fp_line
			(start -0.12065 0.2794)
			(end -0.12065 0.3048)
			(stroke
				(width 0.1)
				(type default)
			)
			(layer "F.Fab")
		)
		(fp_line
			(start 0.67945 0.3048)
			(end 0.120396 0.3048)
			(stroke
				(width 0.1)
				(type default)
			)
			(layer "F.Fab")
		)
		(fp_line
			(start 0.120396 0.3048)
			(end 0.120396 0.2794)
			(stroke
				(width 0.1)
				(type default)
			)
			(layer "F.Fab")
		)
		(fp_line
			(start -0.12065 0.3048)
			(end -0.67945 0.3048)
			(stroke
				(width 0.1)
				(type default)
			)
			(layer "F.Fab")
		)
		(fp_line
			(start -0.67945 0.3048)
			(end -0.67945 -0.305054)
			(stroke
				(width 0.1)
				(type default)
			)
			(layer "F.Fab")
		)
		(pad "1" smd circle
			(at -0.40005 0 90)
			(size 0 0)
			(layers "F.Cu" "F.Mask" "F.Paste")
			(net "SW_P0V9_RETIMER_CPU1_BOOT2")
		)
		(pad "2" smd circle
			(at 0.40005 0 90)
			(size 0 0)
			(layers "F.Cu" "F.Mask" "F.Paste")
			(net "SW_P0V9_RETIMER_CPU1_BOOT2_RC")
		)
	)
	(footprint ""
		(layer "F.Cu")
		(at 244.327426 -282.075636)
		(property "Reference" "PC6802"
			(at 0 0 0)
			(layer "F.SilkS")
			(hide yes)
			(effects
				(font
					(size 1.27 1.27)
				)
			)
		)
		(property "Value" ""
			(at 0 0 0)
			(layer "F.Fab")
			(effects
				(font
					(size 1.27 1.27)
				)
			)
		)
		(duplicate_pad_numbers_are_jumpers no)
		(fp_line
			(start -1.524 -0.762)
			(end 1.524 -0.762)
			(stroke
				(width 0.1524)
				(type default)
			)
			(layer "F.SilkS")
		)
		(fp_line
			(start -1.524 0.762)
			(end -1.524 -0.762)
			(stroke
				(width 0.1524)
				(type default)
			)
			(layer "F.SilkS")
		)
		(fp_line
			(start 1.524 -0.762)
			(end 1.524 0.762)
			(stroke
				(width 0.1524)
				(type default)
			)
			(layer "F.SilkS")
		)
		(fp_line
			(start 1.524 0.762)
			(end -1.524 0.762)
			(stroke
				(width 0.1524)
				(type default)
			)
			(layer "F.SilkS")
		)
		(fp_line
			(start -1.1049 -0.724916)
			(end -1.1049 0.724916)
			(stroke
				(width 0.1)
				(type default)
			)
			(layer "F.Fab")
		)
		(fp_line
			(start -1.1049 0.724916)
			(end 1.1049 0.724916)
			(stroke
				(width 0.1)
				(type default)
			)
			(layer "F.Fab")
		)
		(fp_line
			(start 1.1049 -0.724916)
			(end -1.1049 -0.724916)
			(stroke
				(width 0.1)
				(type default)
			)
			(layer "F.Fab")
		)
		(fp_line
			(start 1.1049 0.724916)
			(end 1.1049 -0.724916)
			(stroke
				(width 0.1)
				(type default)
			)
			(layer "F.Fab")
		)
		(pad "1" smd rect
			(at -0.889 0 180)
			(size 1.016 1.27)
			(layers "F.Cu" "F.Mask" "F.Paste")
			(net "SW_P12V_AUX_P1V8_RETIMER_CPU0_FLT")
		)
		(pad "2" smd rect
			(at 0.889 0 180)
			(size 1.016 1.27)
			(layers "F.Cu" "F.Mask" "F.Paste")
			(net "GND")
		)
	)
	(footprint ""
		(layer "F.Cu")
		(at 124.633228 -49.153064)
		(property "Reference" "R4452"
			(at 0 0 0)
			(layer "F.SilkS")
			(hide yes)
			(effects
				(font
					(size 1.27 1.27)
				)
			)
		)
		(property "Value" ""
			(at 0 0 0)
			(layer "F.Fab")
			(effects
				(font
					(size 1.27 1.27)
				)
			)
		)
		(duplicate_pad_numbers_are_jumpers no)
		(fp_line
			(start -0.7874 -0.4064)
			(end 0.7874 -0.4064)
			(stroke
				(width 0.1524)
				(type default)
			)
			(layer "F.SilkS")
		)
		(fp_line
			(start -0.7874 0.4064)
			(end -0.7874 -0.4064)
			(stroke
				(width 0.1524)
				(type default)
			)
			(layer "F.SilkS")
		)
		(fp_line
			(start 0.7874 -0.4064)
			(end 0.7874 0.4064)
			(stroke
				(width 0.1524)
				(type default)
			)
			(layer "F.SilkS")
		)
		(fp_line
			(start 0.7874 0.4064)
			(end -0.7874 0.4064)
			(stroke
				(width 0.1524)
				(type default)
			)
			(layer "F.SilkS")
		)
		(fp_line
			(start -0.67945 -0.305054)
			(end -0.12065 -0.305054)
			(stroke
				(width 0.1)
				(type default)
			)
			(layer "F.Fab")
		)
		(fp_line
			(start -0.67945 0.3048)
			(end -0.67945 -0.305054)
			(stroke
				(width 0.1)
				(type default)
			)
			(layer "F.Fab")
		)
		(fp_line
			(start -0.12065 -0.305054)
			(end -0.12065 -0.2794)
			(stroke
				(width 0.1)
				(type default)
			)
			(layer "F.Fab")
		)
		(fp_line
			(start -0.12065 -0.2794)
			(end 0.12065 -0.2794)
			(stroke
				(width 0.1)
				(type default)
			)
			(layer "F.Fab")
		)
		(fp_line
			(start -0.12065 0.2794)
			(end -0.12065 0.3048)
			(stroke
				(width 0.1)
				(type default)
			)
			(layer "F.Fab")
		)
		(fp_line
			(start -0.12065 0.3048)
			(end -0.67945 0.3048)
			(stroke
				(width 0.1)
				(type default)
			)
			(layer "F.Fab")
		)
		(fp_line
			(start 0.120396 0.2794)
			(end -0.12065 0.2794)
			(stroke
				(width 0.1)
				(type default)
			)
			(layer "F.Fab")
		)
		(fp_line
			(start 0.120396 0.3048)
			(end 0.120396 0.2794)
			(stroke
				(width 0.1)
				(type default)
			)
			(layer "F.Fab")
		)
		(fp_line
			(start 0.12065 -0.3048)
			(end 0.67945 -0.3048)
			(stroke
				(width 0.1)
				(type default)
			)
			(layer "F.Fab")
		)
		(fp_line
			(start 0.12065 -0.2794)
			(end 0.12065 -0.3048)
			(stroke
				(width 0.1)
				(type default)
			)
			(layer "F.Fab")
		)
		(fp_line
			(start 0.67945 -0.3048)
			(end 0.67945 0.3048)
			(stroke
				(width 0.1)
				(type default)
			)
			(layer "F.Fab")
		)
		(fp_line
			(start 0.67945 0.3048)
			(end 0.120396 0.3048)
			(stroke
				(width 0.1)
				(type default)
			)
			(layer "F.Fab")
		)
		(pad "1" smd circle
			(at -0.40005 0)
			(size 0 0)
			(layers "F.Cu" "F.Mask" "F.Paste")
			(net "P3V3_AUX")
		)
		(pad "2" smd circle
			(at 0.40005 0)
			(size 0 0)
			(layers "F.Cu" "F.Mask" "F.Paste")
			(net "RST_USB_CPU0_HUB1_R_N")
		)
	)
	(footprint ""
		(layer "F.Cu")
		(at 111.86541 -58.827162)
		(property "Reference" "U160"
			(at -2.482088 -3.213862 0)
			(unlocked yes)
			(layer "F.SilkS")
			(effects
				(font
					(size 0.7874 0.5842)
					(thickness 0.1524)
				)
				(justify left)
			)
		)
		(property "Value" ""
			(at 0 0 0)
			(layer "F.Fab")
			(effects
				(font
					(size 1.27 1.27)
				)
			)
		)
		(duplicate_pad_numbers_are_jumpers no)
		(fp_line
			(start -2.112264 -2.549906)
			(end -0.704088 -2.549906)
			(stroke
				(width 0.1524)
				(type default)
			)
			(layer "F.SilkS")
		)
		(fp_line
			(start -2.112264 2.549906)
			(end -2.112264 -2.549906)
			(stroke
				(width 0.1524)
				(type default)
			)
			(layer "F.SilkS")
		)
		(fp_line
			(start -0.704088 -2.549906)
			(end 0 -1.845818)
			(stroke
				(width 0.1524)
				(type default)
			)
			(layer "F.SilkS")
		)
		(fp_line
			(start 0 -1.845818)
			(end 0.704088 -2.549906)
			(stroke
				(width 0.1524)
				(type default)
			)
			(layer "F.SilkS")
		)
		(fp_line
			(start 0.704088 -2.549906)
			(end 2.112264 -2.549906)
			(stroke
				(width 0.1524)
				(type default)
			)
			(layer "F.SilkS")
		)
		(fp_line
			(start 2.112264 -2.549906)
			(end 2.112264 2.549906)
			(stroke
				(width 0.1524)
				(type default)
			)
			(layer "F.SilkS")
		)
		(fp_line
			(start 2.112264 2.549906)
			(end -2.112264 2.549906)
			(stroke
				(width 0.1524)
				(type default)
			)
			(layer "F.SilkS")
		)
		(fp_poly
			(pts
				(xy -4.917186 -2.8829) (xy -4.917186 -1.8669) (xy -3.901186 -2.3749)
			)
			(stroke
				(width 0)
				(type default)
			)
			(fill yes)
			(layer "F.SilkS")
		)
		(fp_line
			(start -2.249932 -2.549906)
			(end 2.249932 -2.549906)
			(stroke
				(width 0.1)
				(type default)
			)
			(layer "F.Fab")
		)
		(fp_line
			(start -2.249932 2.549906)
			(end -2.249932 -2.549906)
			(stroke
				(width 0.1)
				(type default)
			)
			(layer "F.Fab")
		)
		(fp_line
			(start 2.249932 -2.549906)
			(end 2.249932 2.549906)
			(stroke
				(width 0.1)
				(type default)
			)
			(layer "F.Fab")
		)
		(fp_line
			(start 2.249932 2.549906)
			(end -2.249932 2.549906)
			(stroke
				(width 0.1)
				(type default)
			)
			(layer "F.Fab")
		)
		(fp_poly
			(pts
				(xy -4.917186 -2.8829) (xy -4.917186 -1.8669) (xy -3.901186 -2.3749)
			)
			(stroke
				(width 0)
				(type default)
			)
			(fill yes)
			(layer "F.Fab")
		)
		(pad "1" smd rect
			(at -2.925064 -2.3749 270)
			(size 0.6096 1.3716)
			(layers "F.Cu" "F.Mask" "F.Paste")
			(net "TP_JTAG_SCM_SLOT3_R_TMS")
		)
		(pad "2" smd rect
			(at -2.925064 -1.625092 270)
			(size 0.4064 1.3716)
			(layers "F.Cu" "F.Mask" "F.Paste")
			(net "JTAG_SCM_PLD_R_TMS")
		)
		(pad "3" smd rect
			(at -2.925064 -0.975106 270)
			(size 0.4064 1.3716)
			(layers "F.Cu" "F.Mask" "F.Paste")
			(net "JTAG_SCM_TMS")
		)
		(pad "4" smd rect
			(at -2.925064 -0.32512 270)
			(size 0.4064 1.3716)
			(layers "F.Cu" "F.Mask" "F.Paste")
			(net "JTAG_SCM_PLD_R_TMS")
		)
		(pad "5" smd rect
			(at -2.925064 0.32512 270)
			(size 0.4064 1.3716)
			(layers "F.Cu" "F.Mask" "F.Paste")
			(net "JTAG_SCM_MUX_R_TMS")
		)
		(pad "6" smd rect
			(at -2.925064 0.975106 270)
			(size 0.4064 1.3716)
			(layers "F.Cu" "F.Mask" "F.Paste")
			(net "U160_EN_N")
		)
		(pad "7" smd rect
			(at -2.925064 1.625092 270)
			(size 0.4064 1.3716)
			(layers "F.Cu" "F.Mask" "F.Paste")
			(net "GND")
		)
		(pad "8" smd rect
			(at -2.925064 2.3749 270)
			(size 0.6096 1.3716)
			(layers "F.Cu" "F.Mask" "F.Paste")
			(net "GND")
		)
		(pad "9" smd rect
			(at 2.925064 2.3749 270)
			(size 0.6096 1.3716)
			(layers "F.Cu" "F.Mask" "F.Paste")
			(net "SCM_JTAG_MUX_S1")
		)
		(pad "10" smd rect
			(at 2.925064 1.625092 270)
			(size 0.4064 1.3716)
			(layers "F.Cu" "F.Mask" "F.Paste")
			(net "SCM_JTAG_MUX_S0_R1")
		)
		(pad "11" smd rect
			(at 2.925064 0.975106 270)
			(size 0.4064 1.3716)
			(layers "F.Cu" "F.Mask" "F.Paste")
			(net "JTAG_SCM_PLD_R_TCK")
		)
		(pad "12" smd rect
			(at 2.925064 0.32512 270)
			(size 0.4064 1.3716)
			(layers "F.Cu" "F.Mask" "F.Paste")
			(net "TP_JTAG_SCM_SLOT3_R_TCK")
		)
		(pad "13" smd rect
			(at 2.925064 -0.32512 270)
			(size 0.4064 1.3716)
			(layers "F.Cu" "F.Mask" "F.Paste")
			(net "JTAG_SCM_TCK")
		)
		(pad "14" smd rect
			(at 2.925064 -0.975106 270)
			(size 0.4064 1.3716)
			(layers "F.Cu" "F.Mask" "F.Paste")
			(net "JTAG_SCM_MUX_R_TCK")
		)
		(pad "15" smd rect
			(at 2.925064 -1.625092 270)
			(size 0.4064 1.3716)
			(layers "F.Cu" "F.Mask" "F.Paste")
			(net "JTAG_SCM_PLD_R_TCK")
		)
		(pad "16" smd rect
			(at 2.925064 -2.3749 270)
			(size 0.6096 1.3716)
			(layers "F.Cu" "F.Mask" "F.Paste")
			(net "P3V3_AUX")
		)
	)
	(footprint ""
		(layer "F.Cu")
		(at 364.155228 -29.886656 180)
		(property "Reference" "R1253"
			(at 0 0 180)
			(layer "F.SilkS")
			(hide yes)
			(effects
				(font
					(size 1.27 1.27)
				)
			)
		)
		(property "Value" ""
			(at 0 0 180)
			(layer "F.Fab")
			(effects
				(font
					(size 1.27 1.27)
				)
			)
		)
		(duplicate_pad_numbers_are_jumpers no)
		(fp_line
			(start 0.7874 0.4064)
			(end -0.7874 0.4064)
			(stroke
				(width 0.1524)
				(type default)
			)
			(layer "F.SilkS")
		)
		(fp_line
			(start 0.7874 -0.4064)
			(end 0.7874 0.4064)
			(stroke
				(width 0.1524)
				(type default)
			)
			(layer "F.SilkS")
		)
		(fp_line
			(start -0.7874 0.4064)
			(end -0.7874 -0.4064)
			(stroke
				(width 0.1524)
				(type default)
			)
			(layer "F.SilkS")
		)
		(fp_line
			(start -0.7874 -0.4064)
			(end 0.7874 -0.4064)
			(stroke
				(width 0.1524)
				(type default)
			)
			(layer "F.SilkS")
		)
		(fp_line
			(start 0.67945 0.3048)
			(end 0.120396 0.3048)
			(stroke
				(width 0.1)
				(type default)
			)
			(layer "F.Fab")
		)
		(fp_line
			(start 0.67945 -0.3048)
			(end 0.67945 0.3048)
			(stroke
				(width 0.1)
				(type default)
			)
			(layer "F.Fab")
		)
		(fp_line
			(start 0.12065 -0.2794)
			(end 0.12065 -0.3048)
			(stroke
				(width 0.1)
				(type default)
			)
			(layer "F.Fab")
		)
		(fp_line
			(start 0.12065 -0.3048)
			(end 0.67945 -0.3048)
			(stroke
				(width 0.1)
				(type default)
			)
			(layer "F.Fab")
		)
		(fp_line
			(start 0.120396 0.3048)
			(end 0.120396 0.2794)
			(stroke
				(width 0.1)
				(type default)
			)
			(layer "F.Fab")
		)
		(fp_line
			(start 0.120396 0.2794)
			(end -0.12065 0.2794)
			(stroke
				(width 0.1)
				(type default)
			)
			(layer "F.Fab")
		)
		(fp_line
			(start -0.12065 0.3048)
			(end -0.67945 0.3048)
			(stroke
				(width 0.1)
				(type default)
			)
			(layer "F.Fab")
		)
		(fp_line
			(start -0.12065 0.2794)
			(end -0.12065 0.3048)
			(stroke
				(width 0.1)
				(type default)
			)
			(layer "F.Fab")
		)
		(fp_line
			(start -0.12065 -0.2794)
			(end 0.12065 -0.2794)
			(stroke
				(width 0.1)
				(type default)
			)
			(layer "F.Fab")
		)
		(fp_line
			(start -0.12065 -0.305054)
			(end -0.12065 -0.2794)
			(stroke
				(width 0.1)
				(type default)
			)
			(layer "F.Fab")
		)
		(fp_line
			(start -0.67945 0.3048)
			(end -0.67945 -0.305054)
			(stroke
				(width 0.1)
				(type default)
			)
			(layer "F.Fab")
		)
		(fp_line
			(start -0.67945 -0.305054)
			(end -0.12065 -0.305054)
			(stroke
				(width 0.1)
				(type default)
			)
			(layer "F.Fab")
		)
		(pad "1" smd circle
			(at -0.40005 0 180)
			(size 0 0)
			(layers "F.Cu" "F.Mask" "F.Paste")
			(net "UART_LS_EN_N")
		)
		(pad "2" smd circle
			(at 0.40005 0 180)
			(size 0 0)
			(layers "F.Cu" "F.Mask" "F.Paste")
			(net "UART_LS_EN_R_N")
		)
	)
	(footprint ""
		(layer "F.Cu")
		(at 436.005732 -16.199866 -90)
		(property "Reference" "R41"
			(at 0 0 270)
			(layer "F.SilkS")
			(hide yes)
			(effects
				(font
					(size 1.27 1.27)
				)
			)
		)
		(property "Value" ""
			(at 0 0 270)
			(layer "F.Fab")
			(effects
				(font
					(size 1.27 1.27)
				)
			)
		)
		(duplicate_pad_numbers_are_jumpers no)
		(fp_line
			(start -0.7874 0.4064)
			(end -0.7874 -0.4064)
			(stroke
				(width 0.1524)
				(type default)
			)
			(layer "F.SilkS")
		)
		(fp_line
			(start 0.7874 0.4064)
			(end -0.7874 0.4064)
			(stroke
				(width 0.1524)
				(type default)
			)
			(layer "F.SilkS")
		)
		(fp_line
			(start -0.7874 -0.4064)
			(end 0.7874 -0.4064)
			(stroke
				(width 0.1524)
				(type default)
			)
			(layer "F.SilkS")
		)
		(fp_line
			(start 0.7874 -0.4064)
			(end 0.7874 0.4064)
			(stroke
				(width 0.1524)
				(type default)
			)
			(layer "F.SilkS")
		)
		(fp_line
			(start -0.67945 0.3048)
			(end -0.67945 -0.305054)
			(stroke
				(width 0.1)
				(type default)
			)
			(layer "F.Fab")
		)
		(fp_line
			(start -0.12065 0.3048)
			(end -0.67945 0.3048)
			(stroke
				(width 0.1)
				(type default)
			)
			(layer "F.Fab")
		)
		(fp_line
			(start 0.120396 0.3048)
			(end 0.120396 0.2794)
			(stroke
				(width 0.1)
				(type default)
			)
			(layer "F.Fab")
		)
		(fp_line
			(start 0.67945 0.3048)
			(end 0.120396 0.3048)
			(stroke
				(width 0.1)
				(type default)
			)
			(layer "F.Fab")
		)
		(fp_line
			(start -0.12065 0.2794)
			(end -0.12065 0.3048)
			(stroke
				(width 0.1)
				(type default)
			)
			(layer "F.Fab")
		)
		(fp_line
			(start 0.120396 0.2794)
			(end -0.12065 0.2794)
			(stroke
				(width 0.1)
				(type default)
			)
			(layer "F.Fab")
		)
		(fp_line
			(start -0.12065 -0.2794)
			(end 0.12065 -0.2794)
			(stroke
				(width 0.1)
				(type default)
			)
			(layer "F.Fab")
		)
		(fp_line
			(start 0.12065 -0.2794)
			(end 0.12065 -0.3048)
			(stroke
				(width 0.1)
				(type default)
			)
			(layer "F.Fab")
		)
		(fp_line
			(start 0.12065 -0.3048)
			(end 0.67945 -0.3048)
			(stroke
				(width 0.1)
				(type default)
			)
			(layer "F.Fab")
		)
		(fp_line
			(start 0.67945 -0.3048)
			(end 0.67945 0.3048)
			(stroke
				(width 0.1)
				(type default)
			)
			(layer "F.Fab")
		)
		(fp_line
			(start -0.67945 -0.305054)
			(end -0.12065 -0.305054)
			(stroke
				(width 0.1)
				(type default)
			)
			(layer "F.Fab")
		)
		(fp_line
			(start -0.12065 -0.305054)
			(end -0.12065 -0.2794)
			(stroke
				(width 0.1)
				(type default)
			)
			(layer "F.Fab")
		)
		(pad "1" smd circle
			(at -0.40005 0 270)
			(size 0 0)
			(layers "F.Cu" "F.Mask" "F.Paste")
			(net "OCP_SFF_ISO_BIF2_EN")
		)
		(pad "2" smd circle
			(at 0.40005 0 270)
			(size 0 0)
			(layers "F.Cu" "F.Mask" "F.Paste")
			(net "OCP_SFF_BIF2_R_N")
		)
	)
	(footprint ""
		(layer "F.Cu")
		(at 50.84953 -351.578672 90)
		(property "Reference" "PC435_7"
			(at 0 0 90)
			(layer "F.SilkS")
			(hide yes)
			(effects
				(font
					(size 1.27 1.27)
				)
			)
		)
		(property "Value" ""
			(at 0 0 90)
			(layer "F.Fab")
			(effects
				(font
					(size 1.27 1.27)
				)
			)
		)
		(duplicate_pad_numbers_are_jumpers no)
		(fp_line
			(start 0.7874 -0.4064)
			(end 0.7874 0.4064)
			(stroke
				(width 0.1524)
				(type default)
			)
			(layer "F.SilkS")
		)
		(fp_line
			(start -0.7874 -0.4064)
			(end 0.7874 -0.4064)
			(stroke
				(width 0.1524)
				(type default)
			)
			(layer "F.SilkS")
		)
		(fp_line
			(start 0.7874 0.4064)
			(end -0.7874 0.4064)
			(stroke
				(width 0.1524)
				(type default)
			)
			(layer "F.SilkS")
		)
		(fp_line
			(start -0.7874 0.4064)
			(end -0.7874 -0.4064)
			(stroke
				(width 0.1524)
				(type default)
			)
			(layer "F.SilkS")
		)
		(fp_line
			(start -0.12065 -0.305054)
			(end -0.12065 -0.2794)
			(stroke
				(width 0.1)
				(type default)
			)
			(layer "F.Fab")
		)
		(fp_line
			(start -0.67945 -0.305054)
			(end -0.12065 -0.305054)
			(stroke
				(width 0.1)
				(type default)
			)
			(layer "F.Fab")
		)
		(fp_line
			(start 0.67945 -0.3048)
			(end 0.67945 0.3048)
			(stroke
				(width 0.1)
				(type default)
			)
			(layer "F.Fab")
		)
		(fp_line
			(start 0.12065 -0.3048)
			(end 0.67945 -0.3048)
			(stroke
				(width 0.1)
				(type default)
			)
			(layer "F.Fab")
		)
		(fp_line
			(start 0.12065 -0.2794)
			(end 0.12065 -0.3048)
			(stroke
				(width 0.1)
				(type default)
			)
			(layer "F.Fab")
		)
		(fp_line
			(start -0.12065 -0.2794)
			(end 0.12065 -0.2794)
			(stroke
				(width 0.1)
				(type default)
			)
			(layer "F.Fab")
		)
		(fp_line
			(start 0.120396 0.2794)
			(end -0.12065 0.2794)
			(stroke
				(width 0.1)
				(type default)
			)
			(layer "F.Fab")
		)
		(fp_line
			(start -0.12065 0.2794)
			(end -0.12065 0.3048)
			(stroke
				(width 0.1)
				(type default)
			)
			(layer "F.Fab")
		)
		(fp_line
			(start 0.67945 0.3048)
			(end 0.120396 0.3048)
			(stroke
				(width 0.1)
				(type default)
			)
			(layer "F.Fab")
		)
		(fp_line
			(start 0.120396 0.3048)
			(end 0.120396 0.2794)
			(stroke
				(width 0.1)
				(type default)
			)
			(layer "F.Fab")
		)
		(fp_line
			(start -0.12065 0.3048)
			(end -0.67945 0.3048)
			(stroke
				(width 0.1)
				(type default)
			)
			(layer "F.Fab")
		)
		(fp_line
			(start -0.67945 0.3048)
			(end -0.67945 -0.305054)
			(stroke
				(width 0.1)
				(type default)
			)
			(layer "F.Fab")
		)
		(pad "1" smd circle
			(at -0.40005 0 90)
			(size 0 0)
			(layers "F.Cu" "F.Mask" "F.Paste")
			(net "PVDDCR_CPU1_P1_VCCS")
		)
		(pad "2" smd circle
			(at 0.40005 0 90)
			(size 0 0)
			(layers "F.Cu" "F.Mask" "F.Paste")
			(net "GND")
		)
	)
	(footprint ""
		(layer "F.Cu")
		(at 61.027564 -16.220948 -90)
		(property "Reference" "R3171"
			(at 0 0 270)
			(layer "F.SilkS")
			(hide yes)
			(effects
				(font
					(size 1.27 1.27)
				)
			)
		)
		(property "Value" ""
			(at 0 0 270)
			(layer "F.Fab")
			(effects
				(font
					(size 1.27 1.27)
				)
			)
		)
		(duplicate_pad_numbers_are_jumpers no)
		(fp_line
			(start -0.7874 0.4064)
			(end -0.7874 -0.4064)
			(stroke
				(width 0.1524)
				(type default)
			)
			(layer "F.SilkS")
		)
		(fp_line
			(start 0.7874 0.4064)
			(end -0.7874 0.4064)
			(stroke
				(width 0.1524)
				(type default)
			)
			(layer "F.SilkS")
		)
		(fp_line
			(start -0.7874 -0.4064)
			(end 0.7874 -0.4064)
			(stroke
				(width 0.1524)
				(type default)
			)
			(layer "F.SilkS")
		)
		(fp_line
			(start 0.7874 -0.4064)
			(end 0.7874 0.4064)
			(stroke
				(width 0.1524)
				(type default)
			)
			(layer "F.SilkS")
		)
		(fp_line
			(start -0.67945 0.3048)
			(end -0.67945 -0.305054)
			(stroke
				(width 0.1)
				(type default)
			)
			(layer "F.Fab")
		)
		(fp_line
			(start -0.12065 0.3048)
			(end -0.67945 0.3048)
			(stroke
				(width 0.1)
				(type default)
			)
			(layer "F.Fab")
		)
		(fp_line
			(start 0.120396 0.3048)
			(end 0.120396 0.2794)
			(stroke
				(width 0.1)
				(type default)
			)
			(layer "F.Fab")
		)
		(fp_line
			(start 0.67945 0.3048)
			(end 0.120396 0.3048)
			(stroke
				(width 0.1)
				(type default)
			)
			(layer "F.Fab")
		)
		(fp_line
			(start -0.12065 0.2794)
			(end -0.12065 0.3048)
			(stroke
				(width 0.1)
				(type default)
			)
			(layer "F.Fab")
		)
		(fp_line
			(start 0.120396 0.2794)
			(end -0.12065 0.2794)
			(stroke
				(width 0.1)
				(type default)
			)
			(layer "F.Fab")
		)
		(fp_line
			(start -0.12065 -0.2794)
			(end 0.12065 -0.2794)
			(stroke
				(width 0.1)
				(type default)
			)
			(layer "F.Fab")
		)
		(fp_line
			(start 0.12065 -0.2794)
			(end 0.12065 -0.3048)
			(stroke
				(width 0.1)
				(type default)
			)
			(layer "F.Fab")
		)
		(fp_line
			(start 0.12065 -0.3048)
			(end 0.67945 -0.3048)
			(stroke
				(width 0.1)
				(type default)
			)
			(layer "F.Fab")
		)
		(fp_line
			(start 0.67945 -0.3048)
			(end 0.67945 0.3048)
			(stroke
				(width 0.1)
				(type default)
			)
			(layer "F.Fab")
		)
		(fp_line
			(start -0.67945 -0.305054)
			(end -0.12065 -0.305054)
			(stroke
				(width 0.1)
				(type default)
			)
			(layer "F.Fab")
		)
		(fp_line
			(start -0.12065 -0.305054)
			(end -0.12065 -0.2794)
			(stroke
				(width 0.1)
				(type default)
			)
			(layer "F.Fab")
		)
		(pad "1" smd circle
			(at -0.40005 0 270)
			(size 0 0)
			(layers "F.Cu" "F.Mask" "F.Paste")
			(net "OCP_V3_2_ISO_BIF2_EN")
		)
		(pad "2" smd circle
			(at 0.40005 0 270)
			(size 0 0)
			(layers "F.Cu" "F.Mask" "F.Paste")
			(net "OCP_V3_2_BIF2_R_N")
		)
	)
	(footprint ""
		(layer "F.Cu")
		(at 148.494242 -105.624884 180)
		(property "Reference" "R3298"
			(at 0 0 180)
			(layer "F.SilkS")
			(hide yes)
			(effects
				(font
					(size 1.27 1.27)
				)
			)
		)
		(property "Value" ""
			(at 0 0 180)
			(layer "F.Fab")
			(effects
				(font
					(size 1.27 1.27)
				)
			)
		)
		(duplicate_pad_numbers_are_jumpers no)
		(fp_line
			(start 0.7874 0.4064)
			(end -0.7874 0.4064)
			(stroke
				(width 0.1524)
				(type default)
			)
			(layer "F.SilkS")
		)
		(fp_line
			(start 0.7874 -0.4064)
			(end 0.7874 0.4064)
			(stroke
				(width 0.1524)
				(type default)
			)
			(layer "F.SilkS")
		)
		(fp_line
			(start -0.7874 0.4064)
			(end -0.7874 -0.4064)
			(stroke
				(width 0.1524)
				(type default)
			)
			(layer "F.SilkS")
		)
		(fp_line
			(start -0.7874 -0.4064)
			(end 0.7874 -0.4064)
			(stroke
				(width 0.1524)
				(type default)
			)
			(layer "F.SilkS")
		)
		(fp_line
			(start 0.67945 0.3048)
			(end 0.120396 0.3048)
			(stroke
				(width 0.1)
				(type default)
			)
			(layer "F.Fab")
		)
		(fp_line
			(start 0.67945 -0.3048)
			(end 0.67945 0.3048)
			(stroke
				(width 0.1)
				(type default)
			)
			(layer "F.Fab")
		)
		(fp_line
			(start 0.12065 -0.2794)
			(end 0.12065 -0.3048)
			(stroke
				(width 0.1)
				(type default)
			)
			(layer "F.Fab")
		)
		(fp_line
			(start 0.12065 -0.3048)
			(end 0.67945 -0.3048)
			(stroke
				(width 0.1)
				(type default)
			)
			(layer "F.Fab")
		)
		(fp_line
			(start 0.120396 0.3048)
			(end 0.120396 0.2794)
			(stroke
				(width 0.1)
				(type default)
			)
			(layer "F.Fab")
		)
		(fp_line
			(start 0.120396 0.2794)
			(end -0.12065 0.2794)
			(stroke
				(width 0.1)
				(type default)
			)
			(layer "F.Fab")
		)
		(fp_line
			(start -0.12065 0.3048)
			(end -0.67945 0.3048)
			(stroke
				(width 0.1)
				(type default)
			)
			(layer "F.Fab")
		)
		(fp_line
			(start -0.12065 0.2794)
			(end -0.12065 0.3048)
			(stroke
				(width 0.1)
				(type default)
			)
			(layer "F.Fab")
		)
		(fp_line
			(start -0.12065 -0.2794)
			(end 0.12065 -0.2794)
			(stroke
				(width 0.1)
				(type default)
			)
			(layer "F.Fab")
		)
		(fp_line
			(start -0.12065 -0.305054)
			(end -0.12065 -0.2794)
			(stroke
				(width 0.1)
				(type default)
			)
			(layer "F.Fab")
		)
		(fp_line
			(start -0.67945 0.3048)
			(end -0.67945 -0.305054)
			(stroke
				(width 0.1)
				(type default)
			)
			(layer "F.Fab")
		)
		(fp_line
			(start -0.67945 -0.305054)
			(end -0.12065 -0.305054)
			(stroke
				(width 0.1)
				(type default)
			)
			(layer "F.Fab")
		)
		(pad "1" smd circle
			(at -0.40005 0 180)
			(size 0 0)
			(layers "F.Cu" "F.Mask" "F.Paste")
			(net "P3V3_AUX")
		)
		(pad "2" smd circle
			(at 0.40005 0 180)
			(size 0 0)
			(layers "F.Cu" "F.Mask" "F.Paste")
			(net "HDD_ACTIVITY_BUF_N")
		)
	)
	(footprint ""
		(layer "F.Cu")
		(at 367.812066 -419.29558 90)
		(property "Reference" "U270"
			(at -0.13208 -2.975864 90)
			(unlocked yes)
			(layer "F.SilkS")
			(effects
				(font
					(size 0.7874 0.5842)
					(thickness 0.1524)
				)
				(justify left)
			)
		)
		(property "Value" ""
			(at 0 0 90)
			(layer "F.Fab")
			(effects
				(font
					(size 1.27 1.27)
				)
			)
		)
		(duplicate_pad_numbers_are_jumpers no)
		(fp_line
			(start 3.447796 -2.500122)
			(end 1.484122 -2.500122)
			(stroke
				(width 0.1524)
				(type default)
			)
			(layer "F.SilkS")
		)
		(fp_line
			(start 1.484122 -2.500122)
			(end 0 -1.016)
			(stroke
				(width 0.1524)
				(type default)
			)
			(layer "F.SilkS")
		)
		(fp_line
			(start -1.484122 -2.500122)
			(end -3.447796 -2.500122)
			(stroke
				(width 0.1524)
				(type default)
			)
			(layer "F.SilkS")
		)
		(fp_line
			(start -3.447796 -2.500122)
			(end -3.447796 2.500122)
			(stroke
				(width 0.1524)
				(type default)
			)
			(layer "F.SilkS")
		)
		(fp_line
			(start 0 -1.016)
			(end -1.484122 -2.500122)
			(stroke
				(width 0.1524)
				(type default)
			)
			(layer "F.SilkS")
		)
		(fp_line
			(start 3.447796 2.500122)
			(end 3.447796 -2.500122)
			(stroke
				(width 0.1524)
				(type default)
			)
			(layer "F.SilkS")
		)
		(fp_line
			(start -3.447796 2.500122)
			(end 3.447796 2.500122)
			(stroke
				(width 0.1524)
				(type default)
			)
			(layer "F.SilkS")
		)
		(fp_poly
			(pts
				(xy -1.063244 -3.198876) (xy -0.561848 -2.775966) (xy -1.235456 -2.485898)
			)
			(stroke
				(width 0)
				(type default)
			)
			(fill yes)
			(layer "F.SilkS")
		)
		(fp_line
			(start 1.999996 -2.500122)
			(end -1.999996 -2.500122)
			(stroke
				(width 0.1)
				(type default)
			)
			(layer "F.Fab")
		)
		(fp_line
			(start -1.999996 -2.500122)
			(end -1.999996 2.500122)
			(stroke
				(width 0.1)
				(type default)
			)
			(layer "F.Fab")
		)
		(fp_line
			(start 1.999996 2.500122)
			(end 1.999996 -2.500122)
			(stroke
				(width 0.1)
				(type default)
			)
			(layer "F.Fab")
		)
		(fp_line
			(start -1.999996 2.500122)
			(end 1.999996 2.500122)
			(stroke
				(width 0.1)
				(type default)
			)
			(layer "F.Fab")
		)
		(fp_poly
			(pts
				(xy -4.5974 -2.413) (xy -4.5974 -1.397) (xy -3.5814 -1.905)
			)
			(stroke
				(width 0)
				(type default)
			)
			(fill yes)
			(layer "F.Fab")
		)
		(pad "1" smd rect
			(at -2.649982 -1.905)
			(size 0.6096 1.3208)
			(layers "F.Cu" "F.Mask" "F.Paste")
			(net "SMB_LM75_0_3V3AUX_SDA_R1")
		)
		(pad "2" smd rect
			(at -2.649982 -0.635)
			(size 0.6096 1.3208)
			(layers "F.Cu" "F.Mask" "F.Paste")
			(net "SMB_LM75_0_3V3AUX_SCL_R1")
		)
		(pad "3" smd rect
			(at -2.649982 0.635)
			(size 0.6096 1.3208)
			(layers "F.Cu" "F.Mask" "F.Paste")
			(net "FM_G751_0_ALERT_N")
		)
		(pad "4" smd rect
			(at -2.649982 1.905)
			(size 0.6096 1.3208)
			(layers "F.Cu" "F.Mask" "F.Paste")
			(net "GND")
		)
		(pad "5" smd rect
			(at 2.649982 1.905)
			(size 0.6096 1.3208)
			(layers "F.Cu" "F.Mask" "F.Paste")
			(net "U270_0_ADD2")
		)
		(pad "6" smd rect
			(at 2.649982 0.635)
			(size 0.6096 1.3208)
			(layers "F.Cu" "F.Mask" "F.Paste")
			(net "U270_0_ADD1")
		)
		(pad "7" smd rect
			(at 2.649982 -0.635)
			(size 0.6096 1.3208)
			(layers "F.Cu" "F.Mask" "F.Paste")
			(net "U270_0_ADD0")
		)
		(pad "8" smd rect
			(at 2.649982 -1.905)
			(size 0.6096 1.3208)
			(layers "F.Cu" "F.Mask" "F.Paste")
			(net "P3V3_AUX")
		)
	)
	(footprint ""
		(layer "F.Cu")
		(at 300.538388 -5.077206 180)
		(property "Reference" "J84"
			(at -4.342384 -1.077976 90)
			(unlocked yes)
			(layer "F.SilkS")
			(effects
				(font
					(size 0.7874 0.5842)
					(thickness 0.1524)
				)
				(justify left)
			)
		)
		(property "Value" ""
			(at 0 0 180)
			(layer "F.Fab")
			(effects
				(font
					(size 1.27 1.27)
				)
			)
		)
		(duplicate_pad_numbers_are_jumpers no)
		(fp_line
			(start 1.2192 2.06756)
			(end -1.2192 2.06756)
			(stroke
				(width 0.1524)
				(type default)
			)
			(layer "F.SilkS")
		)
		(fp_line
			(start 1.2192 -2.06756)
			(end 1.2192 2.06756)
			(stroke
				(width 0.1524)
				(type default)
			)
			(layer "F.SilkS")
		)
		(fp_line
			(start -1.2192 2.06756)
			(end -1.2192 -2.06756)
			(stroke
				(width 0.1524)
				(type default)
			)
			(layer "F.SilkS")
		)
		(fp_line
			(start -1.2192 -2.06756)
			(end 1.2192 -2.06756)
			(stroke
				(width 0.1524)
				(type default)
			)
			(layer "F.SilkS")
		)
		(pad "" np_thru_hole circle
			(at -2.8829 -1.27 90)
			(size 1.0414 1.0414)
			(drill 1.0414)
			(layers "*.Cu" "*.Mask")
			(clearance 0.381)
			(thermal_gap 0.381)
		)
		(pad "" np_thru_hole circle
			(at -2.8829 1.27 90)
			(size 1.0414 1.0414)
			(drill 1.0414)
			(layers "*.Cu" "*.Mask")
			(clearance 0.381)
			(thermal_gap 0.381)
		)
		(pad "" np_thru_hole circle
			(at 3.4671 -1.27 90)
			(size 1.0414 1.0414)
			(drill 1.0414)
			(layers "*.Cu" "*.Mask")
			(clearance 0.381)
			(thermal_gap 0.381)
		)
		(pad "" np_thru_hole circle
			(at 3.4671 1.27 90)
			(size 1.0414 1.0414)
			(drill 1.0414)
			(layers "*.Cu" "*.Mask")
			(clearance 0.381)
			(thermal_gap 0.381)
		)
		(pad "1" smd rect
			(at 0.8255 -0.249936 90)
			(size 0.3048 0.508)
			(layers "F.Cu" "F.Mask" "F.Paste")
			(net "DELTA_L_85_10INCH_IN2_DN")
		)
		(pad "2" smd rect
			(at 0.8255 0.249936 90)
			(size 0.3048 0.508)
			(layers "F.Cu" "F.Mask" "F.Paste")
			(net "DELTA_L_85_10INCH_IN2_DP")
		)
		(pad "3" smd circle
			(at 0 0 180)
			(size 0 0)
			(layers "F.Cu" "F.Mask" "F.Paste")
			(net "DELTA_L_GND_1")
		)
		(zone
			(layer "F.Cu")
			(hatch none 0.5)
			(connect_pads
				(clearance 0)
			)
			(min_thickness 0.25)
			(keepout
				(tracks not_allowed)
				(vias allowed)
				(pads allowed)
				(copperpour not_allowed)
				(footprints allowed)
			)
			(placement
				(enabled no)
				(sheetname "")
			)
			(fill
				(thermal_gap 0.5)
				(thermal_bridge_width 0.5)
				(island_removal_mode 0)
			)
			(polygon
				(pts
					(xy 299.420788 -4.528566) (xy 299.420788 -4.62407) (xy 300.017688 -4.62407) (xy 300.017688 -5.03047)
					(xy 299.420788 -5.03047) (xy 299.420788 -5.123942) (xy 300.017688 -5.123942) (xy 300.017688 -5.530342)
					(xy 299.420788 -5.530342) (xy 299.420788 -5.625846) (xy 300.119288 -5.625846) (xy 300.119288 -4.528566)
				)
			)
		)
		(zone
			(layers "F.Cu" "B.Cu" "In1.Cu" "In2.Cu" "In3.Cu" "In4.Cu" "In5.Cu" "In6.Cu"
				"In7.Cu" "In8.Cu" "In9.Cu" "In10.Cu" "In11.Cu" "In12.Cu" "In13.Cu" "In14.Cu"
				"In15.Cu" "In16.Cu"
			)
			(hatch none 0.5)
			(connect_pads
				(clearance 0)
			)
			(min_thickness 0.25)
			(keepout
				(tracks not_allowed)
				(vias allowed)
				(pads allowed)
				(copperpour not_allowed)
				(footprints allowed)
			)
			(placement
				(enabled no)
				(sheetname "")
			)
			(fill
				(thermal_gap 0.5)
				(thermal_bridge_width 0.5)
				(island_removal_mode 0)
			)
			(polygon
				(pts
					(arc
						(start 297.998388 -6.347206)
						(mid 296.144188 -6.347206)
						(end 297.998388 -6.347206)
					)
				)
			)
		)
		(zone
			(layers "F.Cu" "B.Cu" "In1.Cu" "In2.Cu" "In3.Cu" "In4.Cu" "In5.Cu" "In6.Cu"
				"In7.Cu" "In8.Cu" "In9.Cu" "In10.Cu" "In11.Cu" "In12.Cu" "In13.Cu" "In14.Cu"
				"In15.Cu" "In16.Cu"
			)
			(hatch none 0.5)
			(connect_pads
				(clearance 0)
			)
			(min_thickness 0.25)
			(keepout
				(tracks not_allowed)
				(vias allowed)
				(pads allowed)
				(copperpour not_allowed)
				(footprints allowed)
			)
			(placement
				(enabled no)
				(sheetname "")
			)
			(fill
				(thermal_gap 0.5)
				(thermal_bridge_width 0.5)
				(island_removal_mode 0)
			)
			(polygon
				(pts
					(arc
						(start 297.998388 -3.807206)
						(mid 296.144188 -3.807206)
						(end 297.998388 -3.807206)
					)
				)
			)
		)
		(zone
			(layers "F.Cu" "B.Cu" "In1.Cu" "In2.Cu" "In3.Cu" "In4.Cu" "In5.Cu" "In6.Cu"
				"In7.Cu" "In8.Cu" "In9.Cu" "In10.Cu" "In11.Cu" "In12.Cu" "In13.Cu" "In14.Cu"
				"In15.Cu" "In16.Cu"
			)
			(hatch none 0.5)
			(connect_pads
				(clearance 0)
			)
			(min_thickness 0.25)
			(keepout
				(tracks not_allowed)
				(vias allowed)
				(pads allowed)
				(copperpour not_allowed)
				(footprints allowed)
			)
			(placement
				(enabled no)
				(sheetname "")
			)
			(fill
				(thermal_gap 0.5)
				(thermal_bridge_width 0.5)
				(island_removal_mode 0)
			)
			(polygon
				(pts
					(arc
						(start 304.348388 -6.347206)
						(mid 302.494188 -6.347206)
						(end 304.348388 -6.347206)
					)
				)
			)
		)
		(zone
			(layers "F.Cu" "B.Cu" "In1.Cu" "In2.Cu" "In3.Cu" "In4.Cu" "In5.Cu" "In6.Cu"
				"In7.Cu" "In8.Cu" "In9.Cu" "In10.Cu" "In11.Cu" "In12.Cu" "In13.Cu" "In14.Cu"
				"In15.Cu" "In16.Cu"
			)
			(hatch none 0.5)
			(connect_pads
				(clearance 0)
			)
			(min_thickness 0.25)
			(keepout
				(tracks not_allowed)
				(vias allowed)
				(pads allowed)
				(copperpour not_allowed)
				(footprints allowed)
			)
			(placement
				(enabled no)
				(sheetname "")
			)
			(fill
				(thermal_gap 0.5)
				(thermal_bridge_width 0.5)
				(island_removal_mode 0)
			)
			(polygon
				(pts
					(arc
						(start 304.348388 -3.807206)
						(mid 302.494188 -3.807206)
						(end 304.348388 -3.807206)
					)
				)
			)
		)
	)
	(footprint ""
		(layer "F.Cu")
		(at 347.983048 -339.932772 -90)
		(property "Reference" "PC113_C1P0_6"
			(at 0 0 270)
			(layer "F.SilkS")
			(hide yes)
			(effects
				(font
					(size 1.27 1.27)
				)
			)
		)
		(property "Value" ""
			(at 0 0 270)
			(layer "F.Fab")
			(effects
				(font
					(size 1.27 1.27)
				)
			)
		)
		(duplicate_pad_numbers_are_jumpers no)
		(fp_line
			(start -0.7874 0.4064)
			(end -0.7874 -0.4064)
			(stroke
				(width 0.1524)
				(type default)
			)
			(layer "F.SilkS")
		)
		(fp_line
			(start 0.7874 0.4064)
			(end -0.7874 0.4064)
			(stroke
				(width 0.1524)
				(type default)
			)
			(layer "F.SilkS")
		)
		(fp_line
			(start -0.7874 -0.4064)
			(end 0.7874 -0.4064)
			(stroke
				(width 0.1524)
				(type default)
			)
			(layer "F.SilkS")
		)
		(fp_line
			(start 0.7874 -0.4064)
			(end 0.7874 0.4064)
			(stroke
				(width 0.1524)
				(type default)
			)
			(layer "F.SilkS")
		)
		(fp_line
			(start -0.67945 0.3048)
			(end -0.67945 -0.305054)
			(stroke
				(width 0.1)
				(type default)
			)
			(layer "F.Fab")
		)
		(fp_line
			(start -0.12065 0.3048)
			(end -0.67945 0.3048)
			(stroke
				(width 0.1)
				(type default)
			)
			(layer "F.Fab")
		)
		(fp_line
			(start 0.120396 0.3048)
			(end 0.120396 0.2794)
			(stroke
				(width 0.1)
				(type default)
			)
			(layer "F.Fab")
		)
		(fp_line
			(start 0.67945 0.3048)
			(end 0.120396 0.3048)
			(stroke
				(width 0.1)
				(type default)
			)
			(layer "F.Fab")
		)
		(fp_line
			(start -0.12065 0.2794)
			(end -0.12065 0.3048)
			(stroke
				(width 0.1)
				(type default)
			)
			(layer "F.Fab")
		)
		(fp_line
			(start 0.120396 0.2794)
			(end -0.12065 0.2794)
			(stroke
				(width 0.1)
				(type default)
			)
			(layer "F.Fab")
		)
		(fp_line
			(start -0.12065 -0.2794)
			(end 0.12065 -0.2794)
			(stroke
				(width 0.1)
				(type default)
			)
			(layer "F.Fab")
		)
		(fp_line
			(start 0.12065 -0.2794)
			(end 0.12065 -0.3048)
			(stroke
				(width 0.1)
				(type default)
			)
			(layer "F.Fab")
		)
		(fp_line
			(start 0.12065 -0.3048)
			(end 0.67945 -0.3048)
			(stroke
				(width 0.1)
				(type default)
			)
			(layer "F.Fab")
		)
		(fp_line
			(start 0.67945 -0.3048)
			(end 0.67945 0.3048)
			(stroke
				(width 0.1)
				(type default)
			)
			(layer "F.Fab")
		)
		(fp_line
			(start -0.67945 -0.305054)
			(end -0.12065 -0.305054)
			(stroke
				(width 0.1)
				(type default)
			)
			(layer "F.Fab")
		)
		(fp_line
			(start -0.12065 -0.305054)
			(end -0.12065 -0.2794)
			(stroke
				(width 0.1)
				(type default)
			)
			(layer "F.Fab")
		)
		(pad "1" smd circle
			(at -0.40005 0 270)
			(size 0 0)
			(layers "F.Cu" "F.Mask" "F.Paste")
			(net "PVDDCR_CPU1_P0_PVCC")
		)
		(pad "2" smd circle
			(at 0.40005 0 270)
			(size 0 0)
			(layers "F.Cu" "F.Mask" "F.Paste")
			(net "GND")
		)
	)
	(footprint ""
		(layer "F.Cu")
		(at 163.703 -111.216948 180)
		(property "Reference" "R6094"
			(at 0 0 180)
			(layer "F.SilkS")
			(hide yes)
			(effects
				(font
					(size 1.27 1.27)
				)
			)
		)
		(property "Value" ""
			(at 0 0 180)
			(layer "F.Fab")
			(effects
				(font
					(size 1.27 1.27)
				)
			)
		)
		(duplicate_pad_numbers_are_jumpers no)
		(fp_line
			(start 0.7874 0.4064)
			(end -0.7874 0.4064)
			(stroke
				(width 0.1524)
				(type default)
			)
			(layer "F.SilkS")
		)
		(fp_line
			(start 0.7874 -0.4064)
			(end 0.7874 0.4064)
			(stroke
				(width 0.1524)
				(type default)
			)
			(layer "F.SilkS")
		)
		(fp_line
			(start -0.7874 0.4064)
			(end -0.7874 -0.4064)
			(stroke
				(width 0.1524)
				(type default)
			)
			(layer "F.SilkS")
		)
		(fp_line
			(start -0.7874 -0.4064)
			(end 0.7874 -0.4064)
			(stroke
				(width 0.1524)
				(type default)
			)
			(layer "F.SilkS")
		)
		(fp_line
			(start 0.67945 0.3048)
			(end 0.120396 0.3048)
			(stroke
				(width 0.1)
				(type default)
			)
			(layer "F.Fab")
		)
		(fp_line
			(start 0.67945 -0.3048)
			(end 0.67945 0.3048)
			(stroke
				(width 0.1)
				(type default)
			)
			(layer "F.Fab")
		)
		(fp_line
			(start 0.12065 -0.2794)
			(end 0.12065 -0.3048)
			(stroke
				(width 0.1)
				(type default)
			)
			(layer "F.Fab")
		)
		(fp_line
			(start 0.12065 -0.3048)
			(end 0.67945 -0.3048)
			(stroke
				(width 0.1)
				(type default)
			)
			(layer "F.Fab")
		)
		(fp_line
			(start 0.120396 0.3048)
			(end 0.120396 0.2794)
			(stroke
				(width 0.1)
				(type default)
			)
			(layer "F.Fab")
		)
		(fp_line
			(start 0.120396 0.2794)
			(end -0.12065 0.2794)
			(stroke
				(width 0.1)
				(type default)
			)
			(layer "F.Fab")
		)
		(fp_line
			(start -0.12065 0.3048)
			(end -0.67945 0.3048)
			(stroke
				(width 0.1)
				(type default)
			)
			(layer "F.Fab")
		)
		(fp_line
			(start -0.12065 0.2794)
			(end -0.12065 0.3048)
			(stroke
				(width 0.1)
				(type default)
			)
			(layer "F.Fab")
		)
		(fp_line
			(start -0.12065 -0.2794)
			(end 0.12065 -0.2794)
			(stroke
				(width 0.1)
				(type default)
			)
			(layer "F.Fab")
		)
		(fp_line
			(start -0.12065 -0.305054)
			(end -0.12065 -0.2794)
			(stroke
				(width 0.1)
				(type default)
			)
			(layer "F.Fab")
		)
		(fp_line
			(start -0.67945 0.3048)
			(end -0.67945 -0.305054)
			(stroke
				(width 0.1)
				(type default)
			)
			(layer "F.Fab")
		)
		(fp_line
			(start -0.67945 -0.305054)
			(end -0.12065 -0.305054)
			(stroke
				(width 0.1)
				(type default)
			)
			(layer "F.Fab")
		)
		(pad "1" smd circle
			(at -0.40005 0 180)
			(size 0 0)
			(layers "F.Cu" "F.Mask" "F.Paste")
			(net "E1S_0_PERST1_CLKREQ_R_N")
		)
		(pad "2" smd circle
			(at 0.40005 0 180)
			(size 0 0)
			(layers "F.Cu" "F.Mask" "F.Paste")
			(net "E1S_0_PERST1_CLKREQ_N")
		)
	)
	(footprint ""
		(layer "F.Cu")
		(at 93.582998 -47.049944 90)
		(property "Reference" "H75"
			(at -3.856482 -4.516374 0)
			(unlocked yes)
			(layer "F.SilkS")
			(effects
				(font
					(size 0.7874 0.5842)
					(thickness 0.1524)
				)
			)
		)
		(property "Value" ""
			(at 0 0 90)
			(layer "F.Fab")
			(effects
				(font
					(size 1.27 1.27)
				)
			)
		)
		(duplicate_pad_numbers_are_jumpers no)
		(pad "" np_thru_hole circle
			(at 0 0 90)
			(size 0 0)
			(drill oval 3.2004 4.8006)
			(layers "*.Cu" "*.Mask")
			(clearance -1.2192)
			(thermal_gap 0.381)
			(padstack
				(mode front_inner_back)
				(layer "Inner"
					(shape oval)
					(size 3.2004 4.8006)
					(clearance 0.381)
				)
				(layer "B.Cu"
					(shape circle)
					(size 0 0)
					(clearance -1.2192)
				)
			)
		)
		(zone
			(layers "F.Cu" "B.Cu" "In1.Cu" "In2.Cu" "In3.Cu" "In4.Cu" "In5.Cu" "In6.Cu"
				"In7.Cu" "In8.Cu" "In9.Cu" "In10.Cu" "In11.Cu" "In12.Cu" "In13.Cu" "In14.Cu"
				"In15.Cu" "In16.Cu"
			)
			(hatch none 0.5)
			(connect_pads
				(clearance 0)
			)
			(min_thickness 0.25)
			(keepout
				(tracks not_allowed)
				(vias allowed)
				(pads allowed)
				(copperpour not_allowed)
				(footprints allowed)
			)
			(placement
				(enabled no)
				(sheetname "")
			)
			(fill
				(thermal_gap 0.5)
				(thermal_bridge_width 0.5)
				(island_removal_mode 0)
			)
			(polygon
				(pts
					(arc
						(start 94.383098 -49.158144)
						(mid 96.491298 -47.049944)
						(end 94.383098 -44.941744)
					)
					(arc
						(start 92.782898 -44.941744)
						(mid 90.674698 -47.049944)
						(end 92.782898 -49.158144)
					)
				)
			)
		)
		(zone
			(layers "F.Cu" "B.Cu" "In1.Cu" "In2.Cu" "In3.Cu" "In4.Cu" "In5.Cu" "In6.Cu"
				"In7.Cu" "In8.Cu" "In9.Cu" "In10.Cu" "In11.Cu" "In12.Cu" "In13.Cu" "In14.Cu"
				"In15.Cu" "In16.Cu"
			)
			(hatch none 0.5)
			(connect_pads
				(clearance 0)
			)
			(min_thickness 0.25)
			(keepout
				(tracks not_allowed)
				(vias allowed)
				(pads allowed)
				(copperpour not_allowed)
				(footprints allowed)
			)
			(placement
				(enabled no)
				(sheetname "")
			)
			(fill
				(thermal_gap 0.5)
				(thermal_bridge_width 0.5)
				(island_removal_mode 0)
			)
			(polygon
				(pts
					(arc
						(start 94.383098 -50.050192)
						(mid 97.383346 -47.049944)
						(end 94.383098 -44.049696)
					)
					(arc
						(start 92.782898 -44.049696)
						(mid 89.78265 -47.049944)
						(end 92.782898 -50.050192)
					)
				)
			)
		)
	)
	(footprint ""
		(layer "F.Cu")
		(at 147.722844 -375.49963 -90)
		(property "Reference" "C765"
			(at 0 0 270)
			(layer "F.SilkS")
			(hide yes)
			(effects
				(font
					(size 1.27 1.27)
				)
			)
		)
		(property "Value" ""
			(at 0 0 270)
			(layer "F.Fab")
			(effects
				(font
					(size 1.27 1.27)
				)
			)
		)
		(duplicate_pad_numbers_are_jumpers no)
		(fp_line
			(start -0.299974 0.150114)
			(end -0.299974 -0.150114)
			(stroke
				(width 0.1)
				(type default)
			)
			(layer "F.Fab")
		)
		(fp_line
			(start 0.299974 0.150114)
			(end -0.299974 0.150114)
			(stroke
				(width 0.1)
				(type default)
			)
			(layer "F.Fab")
		)
		(fp_line
			(start -0.299974 -0.150114)
			(end 0.299974 -0.150114)
			(stroke
				(width 0.1)
				(type default)
			)
			(layer "F.Fab")
		)
		(fp_line
			(start 0.299974 -0.150114)
			(end 0.299974 0.150114)
			(stroke
				(width 0.1)
				(type default)
			)
			(layer "F.Fab")
		)
		(pad "1" smd rect
			(at -0.2667 0 270)
			(size 0.3048 0.381)
			(layers "F.Cu" "F.Mask" "F.Paste")
			(net "P5E_CPU1_P2_TX_C_DP<4>")
		)
		(pad "2" smd rect
			(at 0.2667 0 270)
			(size 0.3048 0.381)
			(layers "F.Cu" "F.Mask" "F.Paste")
			(net "P5E_CPU1_P2_TX_DP<4>")
		)
	)
	(footprint ""
		(layer "F.Cu")
		(at 150.420324 -115.377468)
		(property "Reference" "R8119"
			(at 0 0 0)
			(layer "F.SilkS")
			(hide yes)
			(effects
				(font
					(size 1.27 1.27)
				)
			)
		)
		(property "Value" ""
			(at 0 0 0)
			(layer "F.Fab")
			(effects
				(font
					(size 1.27 1.27)
				)
			)
		)
		(duplicate_pad_numbers_are_jumpers no)
		(fp_line
			(start -0.7874 -0.4064)
			(end 0.7874 -0.4064)
			(stroke
				(width 0.1524)
				(type default)
			)
			(layer "F.SilkS")
		)
		(fp_line
			(start -0.7874 0.4064)
			(end -0.7874 -0.4064)
			(stroke
				(width 0.1524)
				(type default)
			)
			(layer "F.SilkS")
		)
		(fp_line
			(start 0.7874 -0.4064)
			(end 0.7874 0.4064)
			(stroke
				(width 0.1524)
				(type default)
			)
			(layer "F.SilkS")
		)
		(fp_line
			(start 0.7874 0.4064)
			(end -0.7874 0.4064)
			(stroke
				(width 0.1524)
				(type default)
			)
			(layer "F.SilkS")
		)
		(fp_line
			(start -0.67945 -0.305054)
			(end -0.12065 -0.305054)
			(stroke
				(width 0.1)
				(type default)
			)
			(layer "F.Fab")
		)
		(fp_line
			(start -0.67945 0.3048)
			(end -0.67945 -0.305054)
			(stroke
				(width 0.1)
				(type default)
			)
			(layer "F.Fab")
		)
		(fp_line
			(start -0.12065 -0.305054)
			(end -0.12065 -0.2794)
			(stroke
				(width 0.1)
				(type default)
			)
			(layer "F.Fab")
		)
		(fp_line
			(start -0.12065 -0.2794)
			(end 0.12065 -0.2794)
			(stroke
				(width 0.1)
				(type default)
			)
			(layer "F.Fab")
		)
		(fp_line
			(start -0.12065 0.2794)
			(end -0.12065 0.3048)
			(stroke
				(width 0.1)
				(type default)
			)
			(layer "F.Fab")
		)
		(fp_line
			(start -0.12065 0.3048)
			(end -0.67945 0.3048)
			(stroke
				(width 0.1)
				(type default)
			)
			(layer "F.Fab")
		)
		(fp_line
			(start 0.120396 0.2794)
			(end -0.12065 0.2794)
			(stroke
				(width 0.1)
				(type default)
			)
			(layer "F.Fab")
		)
		(fp_line
			(start 0.120396 0.3048)
			(end 0.120396 0.2794)
			(stroke
				(width 0.1)
				(type default)
			)
			(layer "F.Fab")
		)
		(fp_line
			(start 0.12065 -0.3048)
			(end 0.67945 -0.3048)
			(stroke
				(width 0.1)
				(type default)
			)
			(layer "F.Fab")
		)
		(fp_line
			(start 0.12065 -0.2794)
			(end 0.12065 -0.3048)
			(stroke
				(width 0.1)
				(type default)
			)
			(layer "F.Fab")
		)
		(fp_line
			(start 0.67945 -0.3048)
			(end 0.67945 0.3048)
			(stroke
				(width 0.1)
				(type default)
			)
			(layer "F.Fab")
		)
		(fp_line
			(start 0.67945 0.3048)
			(end 0.120396 0.3048)
			(stroke
				(width 0.1)
				(type default)
			)
			(layer "F.Fab")
		)
		(pad "1" smd circle
			(at -0.40005 0)
			(size 0 0)
			(layers "F.Cu" "F.Mask" "F.Paste")
			(net "P3V3_AUX")
		)
		(pad "2" smd circle
			(at 0.40005 0)
			(size 0 0)
			(layers "F.Cu" "F.Mask" "F.Paste")
			(net "FM_UV_ADR_TRIGGER_N")
		)
	)
	(footprint ""
		(layer "F.Cu")
		(at 74.2696 -383.7432)
		(property "Reference" "R788"
			(at 0 0 0)
			(layer "F.SilkS")
			(hide yes)
			(effects
				(font
					(size 1.27 1.27)
				)
			)
		)
		(property "Value" ""
			(at 0 0 0)
			(layer "F.Fab")
			(effects
				(font
					(size 1.27 1.27)
				)
			)
		)
		(duplicate_pad_numbers_are_jumpers no)
		(fp_line
			(start -0.32512 -0.175006)
			(end 0.32512 -0.175006)
			(stroke
				(width 0.1)
				(type default)
			)
			(layer "F.Fab")
		)
		(fp_line
			(start -0.32512 0.175006)
			(end -0.32512 -0.175006)
			(stroke
				(width 0.1)
				(type default)
			)
			(layer "F.Fab")
		)
		(fp_line
			(start 0.32512 -0.175006)
			(end 0.32512 0.175006)
			(stroke
				(width 0.1)
				(type default)
			)
			(layer "F.Fab")
		)
		(fp_line
			(start 0.32512 0.175006)
			(end -0.32512 0.175006)
			(stroke
				(width 0.1)
				(type default)
			)
			(layer "F.Fab")
		)
		(pad "1" smd rect
			(at -0.2667 0)
			(size 0.3048 0.381)
			(layers "F.Cu" "F.Mask" "F.Paste")
			(net "P1V8_CPU1_RT_1D")
		)
		(pad "2" smd rect
			(at 0.2667 0 180)
			(size 0.3048 0.381)
			(layers "F.Cu" "F.Mask" "F.Paste")
			(net "TEST2_RT_CPU1_P1")
		)
	)
	(footprint ""
		(layer "F.Cu")
		(at 23.816818 -435.925214 180)
		(property "Reference" "C1796"
			(at 0 0 180)
			(layer "F.SilkS")
			(hide yes)
			(effects
				(font
					(size 1.27 1.27)
				)
			)
		)
		(property "Value" ""
			(at 0 0 180)
			(layer "F.Fab")
			(effects
				(font
					(size 1.27 1.27)
				)
			)
		)
		(duplicate_pad_numbers_are_jumpers no)
		(fp_line
			(start 0.7874 0.4064)
			(end -0.7874 0.4064)
			(stroke
				(width 0.1524)
				(type default)
			)
			(layer "F.SilkS")
		)
		(fp_line
			(start 0.7874 -0.4064)
			(end 0.7874 0.4064)
			(stroke
				(width 0.1524)
				(type default)
			)
			(layer "F.SilkS")
		)
		(fp_line
			(start -0.7874 0.4064)
			(end -0.7874 -0.4064)
			(stroke
				(width 0.1524)
				(type default)
			)
			(layer "F.SilkS")
		)
		(fp_line
			(start -0.7874 -0.4064)
			(end 0.7874 -0.4064)
			(stroke
				(width 0.1524)
				(type default)
			)
			(layer "F.SilkS")
		)
		(fp_line
			(start 0.67945 0.3048)
			(end 0.120396 0.3048)
			(stroke
				(width 0.1)
				(type default)
			)
			(layer "F.Fab")
		)
		(fp_line
			(start 0.67945 -0.3048)
			(end 0.67945 0.3048)
			(stroke
				(width 0.1)
				(type default)
			)
			(layer "F.Fab")
		)
		(fp_line
			(start 0.12065 -0.2794)
			(end 0.12065 -0.3048)
			(stroke
				(width 0.1)
				(type default)
			)
			(layer "F.Fab")
		)
		(fp_line
			(start 0.12065 -0.3048)
			(end 0.67945 -0.3048)
			(stroke
				(width 0.1)
				(type default)
			)
			(layer "F.Fab")
		)
		(fp_line
			(start 0.120396 0.3048)
			(end 0.120396 0.2794)
			(stroke
				(width 0.1)
				(type default)
			)
			(layer "F.Fab")
		)
		(fp_line
			(start 0.120396 0.2794)
			(end -0.12065 0.2794)
			(stroke
				(width 0.1)
				(type default)
			)
			(layer "F.Fab")
		)
		(fp_line
			(start -0.12065 0.3048)
			(end -0.67945 0.3048)
			(stroke
				(width 0.1)
				(type default)
			)
			(layer "F.Fab")
		)
		(fp_line
			(start -0.12065 0.2794)
			(end -0.12065 0.3048)
			(stroke
				(width 0.1)
				(type default)
			)
			(layer "F.Fab")
		)
		(fp_line
			(start -0.12065 -0.2794)
			(end 0.12065 -0.2794)
			(stroke
				(width 0.1)
				(type default)
			)
			(layer "F.Fab")
		)
		(fp_line
			(start -0.12065 -0.305054)
			(end -0.12065 -0.2794)
			(stroke
				(width 0.1)
				(type default)
			)
			(layer "F.Fab")
		)
		(fp_line
			(start -0.67945 0.3048)
			(end -0.67945 -0.305054)
			(stroke
				(width 0.1)
				(type default)
			)
			(layer "F.Fab")
		)
		(fp_line
			(start -0.67945 -0.305054)
			(end -0.12065 -0.305054)
			(stroke
				(width 0.1)
				(type default)
			)
			(layer "F.Fab")
		)
		(pad "1" smd circle
			(at -0.40005 0 180)
			(size 0 0)
			(layers "F.Cu" "F.Mask" "F.Paste")
			(net "P3V3_AUX")
		)
		(pad "2" smd circle
			(at 0.40005 0 180)
			(size 0 0)
			(layers "F.Cu" "F.Mask" "F.Paste")
			(net "GND")
		)
	)
	(footprint ""
		(layer "F.Cu")
		(at 99.08794 -335.179416 -90)
		(property "Reference" "PC424_5"
			(at 0 0 270)
			(layer "F.SilkS")
			(hide yes)
			(effects
				(font
					(size 1.27 1.27)
				)
			)
		)
		(property "Value" ""
			(at 0 0 270)
			(layer "F.Fab")
			(effects
				(font
					(size 1.27 1.27)
				)
			)
		)
		(duplicate_pad_numbers_are_jumpers no)
		(fp_line
			(start -0.7874 0.4064)
			(end -0.7874 -0.4064)
			(stroke
				(width 0.1524)
				(type default)
			)
			(layer "F.SilkS")
		)
		(fp_line
			(start 0.7874 0.4064)
			(end -0.7874 0.4064)
			(stroke
				(width 0.1524)
				(type default)
			)
			(layer "F.SilkS")
		)
		(fp_line
			(start -0.7874 -0.4064)
			(end 0.7874 -0.4064)
			(stroke
				(width 0.1524)
				(type default)
			)
			(layer "F.SilkS")
		)
		(fp_line
			(start 0.7874 -0.4064)
			(end 0.7874 0.4064)
			(stroke
				(width 0.1524)
				(type default)
			)
			(layer "F.SilkS")
		)
		(fp_line
			(start -0.67945 0.3048)
			(end -0.67945 -0.305054)
			(stroke
				(width 0.1)
				(type default)
			)
			(layer "F.Fab")
		)
		(fp_line
			(start -0.12065 0.3048)
			(end -0.67945 0.3048)
			(stroke
				(width 0.1)
				(type default)
			)
			(layer "F.Fab")
		)
		(fp_line
			(start 0.120396 0.3048)
			(end 0.120396 0.2794)
			(stroke
				(width 0.1)
				(type default)
			)
			(layer "F.Fab")
		)
		(fp_line
			(start 0.67945 0.3048)
			(end 0.120396 0.3048)
			(stroke
				(width 0.1)
				(type default)
			)
			(layer "F.Fab")
		)
		(fp_line
			(start -0.12065 0.2794)
			(end -0.12065 0.3048)
			(stroke
				(width 0.1)
				(type default)
			)
			(layer "F.Fab")
		)
		(fp_line
			(start 0.120396 0.2794)
			(end -0.12065 0.2794)
			(stroke
				(width 0.1)
				(type default)
			)
			(layer "F.Fab")
		)
		(fp_line
			(start -0.12065 -0.2794)
			(end 0.12065 -0.2794)
			(stroke
				(width 0.1)
				(type default)
			)
			(layer "F.Fab")
		)
		(fp_line
			(start 0.12065 -0.2794)
			(end 0.12065 -0.3048)
			(stroke
				(width 0.1)
				(type default)
			)
			(layer "F.Fab")
		)
		(fp_line
			(start 0.12065 -0.3048)
			(end 0.67945 -0.3048)
			(stroke
				(width 0.1)
				(type default)
			)
			(layer "F.Fab")
		)
		(fp_line
			(start 0.67945 -0.3048)
			(end 0.67945 0.3048)
			(stroke
				(width 0.1)
				(type default)
			)
			(layer "F.Fab")
		)
		(fp_line
			(start -0.67945 -0.305054)
			(end -0.12065 -0.305054)
			(stroke
				(width 0.1)
				(type default)
			)
			(layer "F.Fab")
		)
		(fp_line
			(start -0.12065 -0.305054)
			(end -0.12065 -0.2794)
			(stroke
				(width 0.1)
				(type default)
			)
			(layer "F.Fab")
		)
		(pad "1" smd circle
			(at -0.40005 0 270)
			(size 0 0)
			(layers "F.Cu" "F.Mask" "F.Paste")
			(net "SW_P12V_AUX_PVDDCR_CPU1_P1_FLT")
		)
		(pad "2" smd circle
			(at 0.40005 0 270)
			(size 0 0)
			(layers "F.Cu" "F.Mask" "F.Paste")
			(net "GND")
		)
	)
	(footprint ""
		(layer "F.Cu")
		(at 99.509834 -136.179052)
		(property "Reference" "PQ15"
			(at 1.15316 2.498852 0)
			(unlocked yes)
			(layer "F.SilkS")
			(effects
				(font
					(size 0.7874 0.5842)
					(thickness 0.1524)
				)
			)
		)
		(property "Value" ""
			(at 0 0 0)
			(layer "F.Fab")
			(effects
				(font
					(size 1.27 1.27)
				)
			)
		)
		(duplicate_pad_numbers_are_jumpers no)
		(fp_line
			(start -1.949958 -1.610106)
			(end 1.949958 -1.610106)
			(stroke
				(width 0.1524)
				(type default)
			)
			(layer "F.SilkS")
		)
		(fp_line
			(start -1.949958 1.610106)
			(end -1.949958 -1.610106)
			(stroke
				(width 0.1524)
				(type default)
			)
			(layer "F.SilkS")
		)
		(fp_line
			(start 1.949958 -1.560068)
			(end 1.949958 1.610106)
			(stroke
				(width 0.1524)
				(type default)
			)
			(layer "F.SilkS")
		)
		(fp_line
			(start 1.949958 1.610106)
			(end -1.949958 1.610106)
			(stroke
				(width 0.1524)
				(type default)
			)
			(layer "F.SilkS")
		)
		(fp_line
			(start -0.750062 -1.560068)
			(end 0.750062 -1.560068)
			(stroke
				(width 0.1)
				(type default)
			)
			(layer "F.Fab")
		)
		(fp_line
			(start -0.750062 1.560068)
			(end -0.750062 -1.560068)
			(stroke
				(width 0.1)
				(type default)
			)
			(layer "F.Fab")
		)
		(fp_line
			(start 0.750062 -1.560068)
			(end 0.750062 1.560068)
			(stroke
				(width 0.1)
				(type default)
			)
			(layer "F.Fab")
		)
		(fp_line
			(start 0.750062 1.560068)
			(end -0.750062 1.560068)
			(stroke
				(width 0.1)
				(type default)
			)
			(layer "F.Fab")
		)
		(pad "D" smd rect
			(at 1.100074 0 270)
			(size 1.016 1.4224)
			(layers "F.Cu" "F.Mask" "F.Paste")
			(net "PVDDCR_SOC_P1_EN_GD")
		)
		(pad "G" smd rect
			(at -1.100074 -0.94996 270)
			(size 1.016 1.4224)
			(layers "F.Cu" "F.Mask" "F.Paste")
			(net "PVDDCR_SOC_P1_EN_RC")
		)
		(pad "S" smd rect
			(at -1.100074 0.94996 270)
			(size 1.016 1.4224)
			(layers "F.Cu" "F.Mask" "F.Paste")
			(net "GND")
		)
	)
	(footprint ""
		(layer "F.Cu")
		(at 271.092676 -119.761)
		(property "Reference" "R1315"
			(at 0 0 0)
			(layer "F.SilkS")
			(hide yes)
			(effects
				(font
					(size 1.27 1.27)
				)
			)
		)
		(property "Value" ""
			(at 0 0 0)
			(layer "F.Fab")
			(effects
				(font
					(size 1.27 1.27)
				)
			)
		)
		(duplicate_pad_numbers_are_jumpers no)
		(fp_line
			(start -0.7874 -0.4064)
			(end 0.7874 -0.4064)
			(stroke
				(width 0.1524)
				(type default)
			)
			(layer "F.SilkS")
		)
		(fp_line
			(start -0.7874 0.4064)
			(end -0.7874 -0.4064)
			(stroke
				(width 0.1524)
				(type default)
			)
			(layer "F.SilkS")
		)
		(fp_line
			(start 0.7874 -0.4064)
			(end 0.7874 0.4064)
			(stroke
				(width 0.1524)
				(type default)
			)
			(layer "F.SilkS")
		)
		(fp_line
			(start 0.7874 0.4064)
			(end -0.7874 0.4064)
			(stroke
				(width 0.1524)
				(type default)
			)
			(layer "F.SilkS")
		)
		(fp_line
			(start -0.67945 -0.305054)
			(end -0.12065 -0.305054)
			(stroke
				(width 0.1)
				(type default)
			)
			(layer "F.Fab")
		)
		(fp_line
			(start -0.67945 0.3048)
			(end -0.67945 -0.305054)
			(stroke
				(width 0.1)
				(type default)
			)
			(layer "F.Fab")
		)
		(fp_line
			(start -0.12065 -0.305054)
			(end -0.12065 -0.2794)
			(stroke
				(width 0.1)
				(type default)
			)
			(layer "F.Fab")
		)
		(fp_line
			(start -0.12065 -0.2794)
			(end 0.12065 -0.2794)
			(stroke
				(width 0.1)
				(type default)
			)
			(layer "F.Fab")
		)
		(fp_line
			(start -0.12065 0.2794)
			(end -0.12065 0.3048)
			(stroke
				(width 0.1)
				(type default)
			)
			(layer "F.Fab")
		)
		(fp_line
			(start -0.12065 0.3048)
			(end -0.67945 0.3048)
			(stroke
				(width 0.1)
				(type default)
			)
			(layer "F.Fab")
		)
		(fp_line
			(start 0.120396 0.2794)
			(end -0.12065 0.2794)
			(stroke
				(width 0.1)
				(type default)
			)
			(layer "F.Fab")
		)
		(fp_line
			(start 0.120396 0.3048)
			(end 0.120396 0.2794)
			(stroke
				(width 0.1)
				(type default)
			)
			(layer "F.Fab")
		)
		(fp_line
			(start 0.12065 -0.3048)
			(end 0.67945 -0.3048)
			(stroke
				(width 0.1)
				(type default)
			)
			(layer "F.Fab")
		)
		(fp_line
			(start 0.12065 -0.2794)
			(end 0.12065 -0.3048)
			(stroke
				(width 0.1)
				(type default)
			)
			(layer "F.Fab")
		)
		(fp_line
			(start 0.67945 -0.3048)
			(end 0.67945 0.3048)
			(stroke
				(width 0.1)
				(type default)
			)
			(layer "F.Fab")
		)
		(fp_line
			(start 0.67945 0.3048)
			(end 0.120396 0.3048)
			(stroke
				(width 0.1)
				(type default)
			)
			(layer "F.Fab")
		)
		(pad "1" smd circle
			(at -0.40005 0)
			(size 0 0)
			(layers "F.Cu" "F.Mask" "F.Paste")
			(net "SMB_ADC_SCL")
		)
		(pad "2" smd circle
			(at 0.40005 0)
			(size 0 0)
			(layers "F.Cu" "F.Mask" "F.Paste")
			(net "SMB_ADC_SCL_R")
		)
	)
	(footprint ""
		(layer "F.Cu")
		(at 257.766312 -69.196458 90)
		(property "Reference" "R4072"
			(at 0 0 90)
			(layer "F.SilkS")
			(hide yes)
			(effects
				(font
					(size 1.27 1.27)
				)
			)
		)
		(property "Value" ""
			(at 0 0 90)
			(layer "F.Fab")
			(effects
				(font
					(size 1.27 1.27)
				)
			)
		)
		(duplicate_pad_numbers_are_jumpers no)
		(fp_line
			(start 0.7874 -0.4064)
			(end 0.7874 0.4064)
			(stroke
				(width 0.1524)
				(type default)
			)
			(layer "F.SilkS")
		)
		(fp_line
			(start -0.7874 -0.4064)
			(end 0.7874 -0.4064)
			(stroke
				(width 0.1524)
				(type default)
			)
			(layer "F.SilkS")
		)
		(fp_line
			(start 0.7874 0.4064)
			(end -0.7874 0.4064)
			(stroke
				(width 0.1524)
				(type default)
			)
			(layer "F.SilkS")
		)
		(fp_line
			(start -0.7874 0.4064)
			(end -0.7874 -0.4064)
			(stroke
				(width 0.1524)
				(type default)
			)
			(layer "F.SilkS")
		)
		(fp_line
			(start -0.12065 -0.305054)
			(end -0.12065 -0.2794)
			(stroke
				(width 0.1)
				(type default)
			)
			(layer "F.Fab")
		)
		(fp_line
			(start -0.67945 -0.305054)
			(end -0.12065 -0.305054)
			(stroke
				(width 0.1)
				(type default)
			)
			(layer "F.Fab")
		)
		(fp_line
			(start 0.67945 -0.3048)
			(end 0.67945 0.3048)
			(stroke
				(width 0.1)
				(type default)
			)
			(layer "F.Fab")
		)
		(fp_line
			(start 0.12065 -0.3048)
			(end 0.67945 -0.3048)
			(stroke
				(width 0.1)
				(type default)
			)
			(layer "F.Fab")
		)
		(fp_line
			(start 0.12065 -0.2794)
			(end 0.12065 -0.3048)
			(stroke
				(width 0.1)
				(type default)
			)
			(layer "F.Fab")
		)
		(fp_line
			(start -0.12065 -0.2794)
			(end 0.12065 -0.2794)
			(stroke
				(width 0.1)
				(type default)
			)
			(layer "F.Fab")
		)
		(fp_line
			(start 0.120396 0.2794)
			(end -0.12065 0.2794)
			(stroke
				(width 0.1)
				(type default)
			)
			(layer "F.Fab")
		)
		(fp_line
			(start -0.12065 0.2794)
			(end -0.12065 0.3048)
			(stroke
				(width 0.1)
				(type default)
			)
			(layer "F.Fab")
		)
		(fp_line
			(start 0.67945 0.3048)
			(end 0.120396 0.3048)
			(stroke
				(width 0.1)
				(type default)
			)
			(layer "F.Fab")
		)
		(fp_line
			(start 0.120396 0.3048)
			(end 0.120396 0.2794)
			(stroke
				(width 0.1)
				(type default)
			)
			(layer "F.Fab")
		)
		(fp_line
			(start -0.12065 0.3048)
			(end -0.67945 0.3048)
			(stroke
				(width 0.1)
				(type default)
			)
			(layer "F.Fab")
		)
		(fp_line
			(start -0.67945 0.3048)
			(end -0.67945 -0.305054)
			(stroke
				(width 0.1)
				(type default)
			)
			(layer "F.Fab")
		)
		(pad "1" smd circle
			(at -0.40005 0 90)
			(size 0 0)
			(layers "F.Cu" "F.Mask" "F.Paste")
			(net "P12V_AUX")
		)
		(pad "2" smd circle
			(at 0.40005 0 90)
			(size 0 0)
			(layers "F.Cu" "F.Mask" "F.Paste")
			(net "P3V3_E1S_0_EN_G")
		)
	)
	(footprint ""
		(layer "F.Cu")
		(at 461.957928 -94.317566)
		(property "Reference" "C1840"
			(at 0 0 0)
			(layer "F.SilkS")
			(hide yes)
			(effects
				(font
					(size 1.27 1.27)
				)
			)
		)
		(property "Value" ""
			(at 0 0 0)
			(layer "F.Fab")
			(effects
				(font
					(size 1.27 1.27)
				)
			)
		)
		(duplicate_pad_numbers_are_jumpers no)
		(fp_line
			(start -0.7874 -0.4064)
			(end 0.7874 -0.4064)
			(stroke
				(width 0.1524)
				(type default)
			)
			(layer "F.SilkS")
		)
		(fp_line
			(start -0.7874 0.4064)
			(end -0.7874 -0.4064)
			(stroke
				(width 0.1524)
				(type default)
			)
			(layer "F.SilkS")
		)
		(fp_line
			(start 0.7874 -0.4064)
			(end 0.7874 0.4064)
			(stroke
				(width 0.1524)
				(type default)
			)
			(layer "F.SilkS")
		)
		(fp_line
			(start 0.7874 0.4064)
			(end -0.7874 0.4064)
			(stroke
				(width 0.1524)
				(type default)
			)
			(layer "F.SilkS")
		)
		(fp_line
			(start -0.67945 -0.305054)
			(end -0.12065 -0.305054)
			(stroke
				(width 0.1)
				(type default)
			)
			(layer "F.Fab")
		)
		(fp_line
			(start -0.67945 0.3048)
			(end -0.67945 -0.305054)
			(stroke
				(width 0.1)
				(type default)
			)
			(layer "F.Fab")
		)
		(fp_line
			(start -0.12065 -0.305054)
			(end -0.12065 -0.2794)
			(stroke
				(width 0.1)
				(type default)
			)
			(layer "F.Fab")
		)
		(fp_line
			(start -0.12065 -0.2794)
			(end 0.12065 -0.2794)
			(stroke
				(width 0.1)
				(type default)
			)
			(layer "F.Fab")
		)
		(fp_line
			(start -0.12065 0.2794)
			(end -0.12065 0.3048)
			(stroke
				(width 0.1)
				(type default)
			)
			(layer "F.Fab")
		)
		(fp_line
			(start -0.12065 0.3048)
			(end -0.67945 0.3048)
			(stroke
				(width 0.1)
				(type default)
			)
			(layer "F.Fab")
		)
		(fp_line
			(start 0.120396 0.2794)
			(end -0.12065 0.2794)
			(stroke
				(width 0.1)
				(type default)
			)
			(layer "F.Fab")
		)
		(fp_line
			(start 0.120396 0.3048)
			(end 0.120396 0.2794)
			(stroke
				(width 0.1)
				(type default)
			)
			(layer "F.Fab")
		)
		(fp_line
			(start 0.12065 -0.3048)
			(end 0.67945 -0.3048)
			(stroke
				(width 0.1)
				(type default)
			)
			(layer "F.Fab")
		)
		(fp_line
			(start 0.12065 -0.2794)
			(end 0.12065 -0.3048)
			(stroke
				(width 0.1)
				(type default)
			)
			(layer "F.Fab")
		)
		(fp_line
			(start 0.67945 -0.3048)
			(end 0.67945 0.3048)
			(stroke
				(width 0.1)
				(type default)
			)
			(layer "F.Fab")
		)
		(fp_line
			(start 0.67945 0.3048)
			(end 0.120396 0.3048)
			(stroke
				(width 0.1)
				(type default)
			)
			(layer "F.Fab")
		)
		(pad "1" smd circle
			(at -0.40005 0)
			(size 0 0)
			(layers "F.Cu" "F.Mask" "F.Paste")
			(net "P3V3_AUX")
		)
		(pad "2" smd circle
			(at 0.40005 0)
			(size 0 0)
			(layers "F.Cu" "F.Mask" "F.Paste")
			(net "GND")
		)
	)
	(footprint ""
		(layer "F.Cu")
		(at 70.52691 -325.682864)
		(property "Reference" "PL44"
			(at 2.853944 -16.649446 0)
			(unlocked yes)
			(layer "F.SilkS")
			(effects
				(font
					(size 0.7874 0.5842)
					(thickness 0.1524)
				)
				(justify left)
			)
		)
		(property "Value" ""
			(at 0 0 0)
			(layer "F.Fab")
			(effects
				(font
					(size 1.27 1.27)
				)
			)
		)
		(duplicate_pad_numbers_are_jumpers no)
		(fp_line
			(start -3.750056 -5.500116)
			(end -2.393442 -5.500116)
			(stroke
				(width 0.1524)
				(type default)
			)
			(layer "F.SilkS")
		)
		(fp_line
			(start -3.750056 5.500116)
			(end -3.750056 -5.500116)
			(stroke
				(width 0.1524)
				(type default)
			)
			(layer "F.SilkS")
		)
		(fp_line
			(start -2.393442 5.500116)
			(end -3.750056 5.500116)
			(stroke
				(width 0.1524)
				(type default)
			)
			(layer "F.SilkS")
		)
		(fp_line
			(start 2.393442 5.500116)
			(end 3.750056 5.500116)
			(stroke
				(width 0.1524)
				(type default)
			)
			(layer "F.SilkS")
		)
		(fp_line
			(start 3.750056 -5.500116)
			(end 2.393442 -5.500116)
			(stroke
				(width 0.1524)
				(type default)
			)
			(layer "F.SilkS")
		)
		(fp_line
			(start 3.750056 5.500116)
			(end 3.750056 -5.500116)
			(stroke
				(width 0.1524)
				(type default)
			)
			(layer "F.SilkS")
		)
		(fp_poly
			(pts
				(xy -3.9116 -4.249928) (xy -4.9276 -3.741928) (xy -4.9276 -4.757928)
			)
			(stroke
				(width 0)
				(type default)
			)
			(fill yes)
			(layer "F.SilkS")
		)
		(fp_line
			(start -3.750056 -5.500116)
			(end -3.750056 5.500116)
			(stroke
				(width 0.1)
				(type default)
			)
			(layer "F.Fab")
		)
		(fp_line
			(start -3.750056 5.500116)
			(end 3.750056 5.500116)
			(stroke
				(width 0.1)
				(type default)
			)
			(layer "F.Fab")
		)
		(fp_line
			(start 3.750056 -5.500116)
			(end -3.750056 -5.500116)
			(stroke
				(width 0.1)
				(type default)
			)
			(layer "F.Fab")
		)
		(fp_line
			(start 3.750056 5.500116)
			(end 3.750056 -5.500116)
			(stroke
				(width 0.1)
				(type default)
			)
			(layer "F.Fab")
		)
		(fp_poly
			(pts
				(xy -4.9276 -4.757928) (xy -4.9276 -3.741928) (xy -3.9116 -4.249928)
			)
			(stroke
				(width 0)
				(type default)
			)
			(fill yes)
			(layer "F.Fab")
		)
		(pad "1" smd rect
			(at 0 -4.249928 270)
			(size 2.413 4.5212)
			(layers "F.Cu" "F.Mask" "F.Paste")
			(net "SW_PVDDCR_CPU1_P1_SW3")
		)
		(pad "2" smd rect
			(at 0 -1.175004 270)
			(size 1.3716 4.5212)
			(layers "F.Cu" "F.Mask" "F.Paste")
			(net "IND_CPU1_P1_CPL2")
		)
		(pad "3" smd rect
			(at 0 1.175004 270)
			(size 1.3716 4.5212)
			(layers "F.Cu" "F.Mask" "F.Paste")
			(net "IND_CPU1_P1_CPL3")
		)
		(pad "4" smd rect
			(at 0 4.249928 270)
			(size 2.413 4.5212)
			(layers "F.Cu" "F.Mask" "F.Paste")
			(net "PVDDCR_CPU1_P1")
		)
	)
	(footprint ""
		(layer "F.Cu")
		(at 83.564476 -352.36912 90)
		(property "Reference" "PC390"
			(at -5.43179 -1.903476 0)
			(unlocked yes)
			(layer "F.SilkS")
			(effects
				(font
					(size 0.7874 0.5842)
					(thickness 0.1524)
				)
				(justify left)
			)
		)
		(property "Value" ""
			(at 0 0 90)
			(layer "F.Fab")
			(effects
				(font
					(size 1.27 1.27)
				)
			)
		)
		(duplicate_pad_numbers_are_jumpers no)
		(fp_line
			(start 3.400044 -3.400044)
			(end -2.146046 -3.400044)
			(stroke
				(width 0.1524)
				(type default)
			)
			(layer "F.SilkS")
		)
		(fp_line
			(start -2.146046 -3.400044)
			(end -3.400044 -2.146046)
			(stroke
				(width 0.1524)
				(type default)
			)
			(layer "F.SilkS")
		)
		(fp_line
			(start -3.400044 -2.146046)
			(end -3.400044 -0.9398)
			(stroke
				(width 0.1524)
				(type default)
			)
			(layer "F.SilkS")
		)
		(fp_line
			(start 3.400044 -0.9398)
			(end 3.400044 -3.400044)
			(stroke
				(width 0.1524)
				(type default)
			)
			(layer "F.SilkS")
		)
		(fp_line
			(start 3.400044 0.9398)
			(end 3.400044 3.400044)
			(stroke
				(width 0.1524)
				(type default)
			)
			(layer "F.SilkS")
		)
		(fp_line
			(start -3.400044 2.146046)
			(end -3.400044 0.9398)
			(stroke
				(width 0.1524)
				(type default)
			)
			(layer "F.SilkS")
		)
		(fp_line
			(start 3.400044 3.400044)
			(end -2.146046 3.400044)
			(stroke
				(width 0.1524)
				(type default)
			)
			(layer "F.SilkS")
		)
		(fp_line
			(start -2.146046 3.400044)
			(end -3.400044 2.146046)
			(stroke
				(width 0.1524)
				(type default)
			)
			(layer "F.SilkS")
		)
		(fp_line
			(start 3.400044 -3.400044)
			(end -3.400044 -3.400044)
			(stroke
				(width 0.1)
				(type default)
			)
			(layer "F.Fab")
		)
		(fp_line
			(start -3.400044 -3.400044)
			(end -3.400044 3.400044)
			(stroke
				(width 0.1)
				(type default)
			)
			(layer "F.Fab")
		)
		(fp_line
			(start 3.400044 3.400044)
			(end 3.400044 -3.400044)
			(stroke
				(width 0.1)
				(type default)
			)
			(layer "F.Fab")
		)
		(fp_line
			(start -3.400044 3.400044)
			(end 3.400044 3.400044)
			(stroke
				(width 0.1)
				(type default)
			)
			(layer "F.Fab")
		)
		(pad "1" smd rect
			(at -2.70002 0)
			(size 1.6002 3.5052)
			(layers "F.Cu" "F.Mask" "F.Paste")
			(net "SW_P12V_AUX_PVDDCR_CPU1_P1_FLT")
		)
		(pad "2" smd rect
			(at 2.70002 0)
			(size 1.6002 3.5052)
			(layers "F.Cu" "F.Mask" "F.Paste")
			(net "GND")
		)
	)
	(footprint ""
		(layer "F.Cu")
		(at 317.210186 -361.061 -90)
		(property "Reference" "PC67"
			(at 0 0 270)
			(layer "F.SilkS")
			(hide yes)
			(effects
				(font
					(size 1.27 1.27)
				)
			)
		)
		(property "Value" ""
			(at 0 0 270)
			(layer "F.Fab")
			(effects
				(font
					(size 1.27 1.27)
				)
			)
		)
		(duplicate_pad_numbers_are_jumpers no)
		(fp_line
			(start -0.7874 0.4064)
			(end -0.7874 -0.4064)
			(stroke
				(width 0.1524)
				(type default)
			)
			(layer "F.SilkS")
		)
		(fp_line
			(start 0.7874 0.4064)
			(end -0.7874 0.4064)
			(stroke
				(width 0.1524)
				(type default)
			)
			(layer "F.SilkS")
		)
		(fp_line
			(start -0.7874 -0.4064)
			(end 0.7874 -0.4064)
			(stroke
				(width 0.1524)
				(type default)
			)
			(layer "F.SilkS")
		)
		(fp_line
			(start 0.7874 -0.4064)
			(end 0.7874 0.4064)
			(stroke
				(width 0.1524)
				(type default)
			)
			(layer "F.SilkS")
		)
		(fp_line
			(start -0.67945 0.3048)
			(end -0.67945 -0.305054)
			(stroke
				(width 0.1)
				(type default)
			)
			(layer "F.Fab")
		)
		(fp_line
			(start -0.12065 0.3048)
			(end -0.67945 0.3048)
			(stroke
				(width 0.1)
				(type default)
			)
			(layer "F.Fab")
		)
		(fp_line
			(start 0.120396 0.3048)
			(end 0.120396 0.2794)
			(stroke
				(width 0.1)
				(type default)
			)
			(layer "F.Fab")
		)
		(fp_line
			(start 0.67945 0.3048)
			(end 0.120396 0.3048)
			(stroke
				(width 0.1)
				(type default)
			)
			(layer "F.Fab")
		)
		(fp_line
			(start -0.12065 0.2794)
			(end -0.12065 0.3048)
			(stroke
				(width 0.1)
				(type default)
			)
			(layer "F.Fab")
		)
		(fp_line
			(start 0.120396 0.2794)
			(end -0.12065 0.2794)
			(stroke
				(width 0.1)
				(type default)
			)
			(layer "F.Fab")
		)
		(fp_line
			(start -0.12065 -0.2794)
			(end 0.12065 -0.2794)
			(stroke
				(width 0.1)
				(type default)
			)
			(layer "F.Fab")
		)
		(fp_line
			(start 0.12065 -0.2794)
			(end 0.12065 -0.3048)
			(stroke
				(width 0.1)
				(type default)
			)
			(layer "F.Fab")
		)
		(fp_line
			(start 0.12065 -0.3048)
			(end 0.67945 -0.3048)
			(stroke
				(width 0.1)
				(type default)
			)
			(layer "F.Fab")
		)
		(fp_line
			(start 0.67945 -0.3048)
			(end 0.67945 0.3048)
			(stroke
				(width 0.1)
				(type default)
			)
			(layer "F.Fab")
		)
		(fp_line
			(start -0.67945 -0.305054)
			(end -0.12065 -0.305054)
			(stroke
				(width 0.1)
				(type default)
			)
			(layer "F.Fab")
		)
		(fp_line
			(start -0.12065 -0.305054)
			(end -0.12065 -0.2794)
			(stroke
				(width 0.1)
				(type default)
			)
			(layer "F.Fab")
		)
		(pad "1" smd circle
			(at -0.40005 0 270)
			(size 0 0)
			(layers "F.Cu" "F.Mask" "F.Paste")
			(net "PVDDCR_CPU1_P0_VMON")
		)
		(pad "2" smd circle
			(at 0.40005 0 270)
			(size 0 0)
			(layers "F.Cu" "F.Mask" "F.Paste")
			(net "GND")
		)
	)
	(footprint ""
		(layer "F.Cu")
		(at 319.405 -194.31)
		(property "Reference" "R423"
			(at 0 0 0)
			(layer "F.SilkS")
			(hide yes)
			(effects
				(font
					(size 1.27 1.27)
				)
			)
		)
		(property "Value" ""
			(at 0 0 0)
			(layer "F.Fab")
			(effects
				(font
					(size 1.27 1.27)
				)
			)
		)
		(duplicate_pad_numbers_are_jumpers no)
		(fp_line
			(start -0.7874 -0.4064)
			(end 0.7874 -0.4064)
			(stroke
				(width 0.1524)
				(type default)
			)
			(layer "F.SilkS")
		)
		(fp_line
			(start -0.7874 0.4064)
			(end -0.7874 -0.4064)
			(stroke
				(width 0.1524)
				(type default)
			)
			(layer "F.SilkS")
		)
		(fp_line
			(start 0.7874 -0.4064)
			(end 0.7874 0.4064)
			(stroke
				(width 0.1524)
				(type default)
			)
			(layer "F.SilkS")
		)
		(fp_line
			(start 0.7874 0.4064)
			(end -0.7874 0.4064)
			(stroke
				(width 0.1524)
				(type default)
			)
			(layer "F.SilkS")
		)
		(fp_line
			(start -0.67945 -0.305054)
			(end -0.12065 -0.305054)
			(stroke
				(width 0.1)
				(type default)
			)
			(layer "F.Fab")
		)
		(fp_line
			(start -0.67945 0.3048)
			(end -0.67945 -0.305054)
			(stroke
				(width 0.1)
				(type default)
			)
			(layer "F.Fab")
		)
		(fp_line
			(start -0.12065 -0.305054)
			(end -0.12065 -0.2794)
			(stroke
				(width 0.1)
				(type default)
			)
			(layer "F.Fab")
		)
		(fp_line
			(start -0.12065 -0.2794)
			(end 0.12065 -0.2794)
			(stroke
				(width 0.1)
				(type default)
			)
			(layer "F.Fab")
		)
		(fp_line
			(start -0.12065 0.2794)
			(end -0.12065 0.3048)
			(stroke
				(width 0.1)
				(type default)
			)
			(layer "F.Fab")
		)
		(fp_line
			(start -0.12065 0.3048)
			(end -0.67945 0.3048)
			(stroke
				(width 0.1)
				(type default)
			)
			(layer "F.Fab")
		)
		(fp_line
			(start 0.120396 0.2794)
			(end -0.12065 0.2794)
			(stroke
				(width 0.1)
				(type default)
			)
			(layer "F.Fab")
		)
		(fp_line
			(start 0.120396 0.3048)
			(end 0.120396 0.2794)
			(stroke
				(width 0.1)
				(type default)
			)
			(layer "F.Fab")
		)
		(fp_line
			(start 0.12065 -0.3048)
			(end 0.67945 -0.3048)
			(stroke
				(width 0.1)
				(type default)
			)
			(layer "F.Fab")
		)
		(fp_line
			(start 0.12065 -0.2794)
			(end 0.12065 -0.3048)
			(stroke
				(width 0.1)
				(type default)
			)
			(layer "F.Fab")
		)
		(fp_line
			(start 0.67945 -0.3048)
			(end 0.67945 0.3048)
			(stroke
				(width 0.1)
				(type default)
			)
			(layer "F.Fab")
		)
		(fp_line
			(start 0.67945 0.3048)
			(end 0.120396 0.3048)
			(stroke
				(width 0.1)
				(type default)
			)
			(layer "F.Fab")
		)
		(pad "1" smd circle
			(at -0.40005 0)
			(size 0 0)
			(layers "F.Cu" "F.Mask" "F.Paste")
			(net "PVDD11_S3_P0")
		)
		(pad "2" smd circle
			(at 0.40005 0)
			(size 0 0)
			(layers "F.Cu" "F.Mask" "F.Paste")
			(net "I3C_0_SPD_DDRAF_CPU0_R_SDA")
		)
	)
	(footprint ""
		(layer "F.Cu")
		(at 21.234654 -35.8013)
		(property "Reference" "R1277"
			(at 0 0 0)
			(layer "F.SilkS")
			(hide yes)
			(effects
				(font
					(size 1.27 1.27)
				)
			)
		)
		(property "Value" ""
			(at 0 0 0)
			(layer "F.Fab")
			(effects
				(font
					(size 1.27 1.27)
				)
			)
		)
		(duplicate_pad_numbers_are_jumpers no)
		(fp_line
			(start -0.7874 -0.4064)
			(end 0.7874 -0.4064)
			(stroke
				(width 0.1524)
				(type default)
			)
			(layer "F.SilkS")
		)
		(fp_line
			(start -0.7874 0.4064)
			(end -0.7874 -0.4064)
			(stroke
				(width 0.1524)
				(type default)
			)
			(layer "F.SilkS")
		)
		(fp_line
			(start 0.7874 -0.4064)
			(end 0.7874 0.4064)
			(stroke
				(width 0.1524)
				(type default)
			)
			(layer "F.SilkS")
		)
		(fp_line
			(start 0.7874 0.4064)
			(end -0.7874 0.4064)
			(stroke
				(width 0.1524)
				(type default)
			)
			(layer "F.SilkS")
		)
		(fp_line
			(start -0.67945 -0.305054)
			(end -0.12065 -0.305054)
			(stroke
				(width 0.1)
				(type default)
			)
			(layer "F.Fab")
		)
		(fp_line
			(start -0.67945 0.3048)
			(end -0.67945 -0.305054)
			(stroke
				(width 0.1)
				(type default)
			)
			(layer "F.Fab")
		)
		(fp_line
			(start -0.12065 -0.305054)
			(end -0.12065 -0.2794)
			(stroke
				(width 0.1)
				(type default)
			)
			(layer "F.Fab")
		)
		(fp_line
			(start -0.12065 -0.2794)
			(end 0.12065 -0.2794)
			(stroke
				(width 0.1)
				(type default)
			)
			(layer "F.Fab")
		)
		(fp_line
			(start -0.12065 0.2794)
			(end -0.12065 0.3048)
			(stroke
				(width 0.1)
				(type default)
			)
			(layer "F.Fab")
		)
		(fp_line
			(start -0.12065 0.3048)
			(end -0.67945 0.3048)
			(stroke
				(width 0.1)
				(type default)
			)
			(layer "F.Fab")
		)
		(fp_line
			(start 0.120396 0.2794)
			(end -0.12065 0.2794)
			(stroke
				(width 0.1)
				(type default)
			)
			(layer "F.Fab")
		)
		(fp_line
			(start 0.120396 0.3048)
			(end 0.120396 0.2794)
			(stroke
				(width 0.1)
				(type default)
			)
			(layer "F.Fab")
		)
		(fp_line
			(start 0.12065 -0.3048)
			(end 0.67945 -0.3048)
			(stroke
				(width 0.1)
				(type default)
			)
			(layer "F.Fab")
		)
		(fp_line
			(start 0.12065 -0.2794)
			(end 0.12065 -0.3048)
			(stroke
				(width 0.1)
				(type default)
			)
			(layer "F.Fab")
		)
		(fp_line
			(start 0.67945 -0.3048)
			(end 0.67945 0.3048)
			(stroke
				(width 0.1)
				(type default)
			)
			(layer "F.Fab")
		)
		(fp_line
			(start 0.67945 0.3048)
			(end 0.120396 0.3048)
			(stroke
				(width 0.1)
				(type default)
			)
			(layer "F.Fab")
		)
		(pad "1" smd circle
			(at -0.40005 0)
			(size 0 0)
			(layers "F.Cu" "F.Mask" "F.Paste")
			(net "SMB_INA230_7_3V3AUX_SDA_R")
		)
		(pad "2" smd circle
			(at 0.40005 0)
			(size 0 0)
			(layers "F.Cu" "F.Mask" "F.Paste")
			(net "SMB_INA230_7_3V3AUX_SDA_R1")
		)
	)
	(footprint ""
		(layer "F.Cu")
		(at 315.771022 -36.890706)
		(property "Reference" "R2900"
			(at 0 0 0)
			(layer "F.SilkS")
			(hide yes)
			(effects
				(font
					(size 1.27 1.27)
				)
			)
		)
		(property "Value" ""
			(at 0 0 0)
			(layer "F.Fab")
			(effects
				(font
					(size 1.27 1.27)
				)
			)
		)
		(duplicate_pad_numbers_are_jumpers no)
		(fp_line
			(start -0.7874 -0.4064)
			(end 0.7874 -0.4064)
			(stroke
				(width 0.1524)
				(type default)
			)
			(layer "F.SilkS")
		)
		(fp_line
			(start -0.7874 0.4064)
			(end -0.7874 -0.4064)
			(stroke
				(width 0.1524)
				(type default)
			)
			(layer "F.SilkS")
		)
		(fp_line
			(start 0.7874 -0.4064)
			(end 0.7874 0.4064)
			(stroke
				(width 0.1524)
				(type default)
			)
			(layer "F.SilkS")
		)
		(fp_line
			(start 0.7874 0.4064)
			(end -0.7874 0.4064)
			(stroke
				(width 0.1524)
				(type default)
			)
			(layer "F.SilkS")
		)
		(fp_line
			(start -0.67945 -0.305054)
			(end -0.12065 -0.305054)
			(stroke
				(width 0.1)
				(type default)
			)
			(layer "F.Fab")
		)
		(fp_line
			(start -0.67945 0.3048)
			(end -0.67945 -0.305054)
			(stroke
				(width 0.1)
				(type default)
			)
			(layer "F.Fab")
		)
		(fp_line
			(start -0.12065 -0.305054)
			(end -0.12065 -0.2794)
			(stroke
				(width 0.1)
				(type default)
			)
			(layer "F.Fab")
		)
		(fp_line
			(start -0.12065 -0.2794)
			(end 0.12065 -0.2794)
			(stroke
				(width 0.1)
				(type default)
			)
			(layer "F.Fab")
		)
		(fp_line
			(start -0.12065 0.2794)
			(end -0.12065 0.3048)
			(stroke
				(width 0.1)
				(type default)
			)
			(layer "F.Fab")
		)
		(fp_line
			(start -0.12065 0.3048)
			(end -0.67945 0.3048)
			(stroke
				(width 0.1)
				(type default)
			)
			(layer "F.Fab")
		)
		(fp_line
			(start 0.120396 0.2794)
			(end -0.12065 0.2794)
			(stroke
				(width 0.1)
				(type default)
			)
			(layer "F.Fab")
		)
		(fp_line
			(start 0.120396 0.3048)
			(end 0.120396 0.2794)
			(stroke
				(width 0.1)
				(type default)
			)
			(layer "F.Fab")
		)
		(fp_line
			(start 0.12065 -0.3048)
			(end 0.67945 -0.3048)
			(stroke
				(width 0.1)
				(type default)
			)
			(layer "F.Fab")
		)
		(fp_line
			(start 0.12065 -0.2794)
			(end 0.12065 -0.3048)
			(stroke
				(width 0.1)
				(type default)
			)
			(layer "F.Fab")
		)
		(fp_line
			(start 0.67945 -0.3048)
			(end 0.67945 0.3048)
			(stroke
				(width 0.1)
				(type default)
			)
			(layer "F.Fab")
		)
		(fp_line
			(start 0.67945 0.3048)
			(end 0.120396 0.3048)
			(stroke
				(width 0.1)
				(type default)
			)
			(layer "F.Fab")
		)
		(pad "1" smd circle
			(at -0.40005 0)
			(size 0 0)
			(layers "F.Cu" "F.Mask" "F.Paste")
			(net "MAX11617_VREF")
		)
		(pad "2" smd circle
			(at 0.40005 0)
			(size 0 0)
			(layers "F.Cu" "F.Mask" "F.Paste")
			(net "MAX11617_VREF_R")
		)
	)
	(footprint ""
		(layer "F.Cu")
		(at 416.43046 -358.241092)
		(property "Reference" "PC194"
			(at 0 0 0)
			(layer "F.SilkS")
			(hide yes)
			(effects
				(font
					(size 1.27 1.27)
				)
			)
		)
		(property "Value" ""
			(at 0 0 0)
			(layer "F.Fab")
			(effects
				(font
					(size 1.27 1.27)
				)
			)
		)
		(duplicate_pad_numbers_are_jumpers no)
		(fp_line
			(start -0.7874 -0.4064)
			(end 0.7874 -0.4064)
			(stroke
				(width 0.1524)
				(type default)
			)
			(layer "F.SilkS")
		)
		(fp_line
			(start -0.7874 0.4064)
			(end -0.7874 -0.4064)
			(stroke
				(width 0.1524)
				(type default)
			)
			(layer "F.SilkS")
		)
		(fp_line
			(start 0.7874 -0.4064)
			(end 0.7874 0.4064)
			(stroke
				(width 0.1524)
				(type default)
			)
			(layer "F.SilkS")
		)
		(fp_line
			(start 0.7874 0.4064)
			(end -0.7874 0.4064)
			(stroke
				(width 0.1524)
				(type default)
			)
			(layer "F.SilkS")
		)
		(fp_line
			(start -0.67945 -0.305054)
			(end -0.12065 -0.305054)
			(stroke
				(width 0.1)
				(type default)
			)
			(layer "F.Fab")
		)
		(fp_line
			(start -0.67945 0.3048)
			(end -0.67945 -0.305054)
			(stroke
				(width 0.1)
				(type default)
			)
			(layer "F.Fab")
		)
		(fp_line
			(start -0.12065 -0.305054)
			(end -0.12065 -0.2794)
			(stroke
				(width 0.1)
				(type default)
			)
			(layer "F.Fab")
		)
		(fp_line
			(start -0.12065 -0.2794)
			(end 0.12065 -0.2794)
			(stroke
				(width 0.1)
				(type default)
			)
			(layer "F.Fab")
		)
		(fp_line
			(start -0.12065 0.2794)
			(end -0.12065 0.3048)
			(stroke
				(width 0.1)
				(type default)
			)
			(layer "F.Fab")
		)
		(fp_line
			(start -0.12065 0.3048)
			(end -0.67945 0.3048)
			(stroke
				(width 0.1)
				(type default)
			)
			(layer "F.Fab")
		)
		(fp_line
			(start 0.120396 0.2794)
			(end -0.12065 0.2794)
			(stroke
				(width 0.1)
				(type default)
			)
			(layer "F.Fab")
		)
		(fp_line
			(start 0.120396 0.3048)
			(end 0.120396 0.2794)
			(stroke
				(width 0.1)
				(type default)
			)
			(layer "F.Fab")
		)
		(fp_line
			(start 0.12065 -0.3048)
			(end 0.67945 -0.3048)
			(stroke
				(width 0.1)
				(type default)
			)
			(layer "F.Fab")
		)
		(fp_line
			(start 0.12065 -0.2794)
			(end 0.12065 -0.3048)
			(stroke
				(width 0.1)
				(type default)
			)
			(layer "F.Fab")
		)
		(fp_line
			(start 0.67945 -0.3048)
			(end 0.67945 0.3048)
			(stroke
				(width 0.1)
				(type default)
			)
			(layer "F.Fab")
		)
		(fp_line
			(start 0.67945 0.3048)
			(end 0.120396 0.3048)
			(stroke
				(width 0.1)
				(type default)
			)
			(layer "F.Fab")
		)
		(pad "1" smd circle
			(at -0.40005 0)
			(size 0 0)
			(layers "F.Cu" "F.Mask" "F.Paste")
			(net "VSENSE_PVDD11_S3_P0_R")
		)
		(pad "2" smd circle
			(at 0.40005 0)
			(size 0 0)
			(layers "F.Cu" "F.Mask" "F.Paste")
			(net "VSENSE_VSS_SENSE_C_P0")
		)
	)
	(footprint ""
		(layer "F.Cu")
		(at 157.686502 -348.280228 180)
		(property "Reference" "PR392"
			(at 0 0 180)
			(layer "F.SilkS")
			(hide yes)
			(effects
				(font
					(size 1.27 1.27)
				)
			)
		)
		(property "Value" ""
			(at 0 0 180)
			(layer "F.Fab")
			(effects
				(font
					(size 1.27 1.27)
				)
			)
		)
		(duplicate_pad_numbers_are_jumpers no)
		(fp_line
			(start 0.7874 0.4064)
			(end -0.7874 0.4064)
			(stroke
				(width 0.1524)
				(type default)
			)
			(layer "F.SilkS")
		)
		(fp_line
			(start 0.7874 -0.4064)
			(end 0.7874 0.4064)
			(stroke
				(width 0.1524)
				(type default)
			)
			(layer "F.SilkS")
		)
		(fp_line
			(start -0.7874 0.4064)
			(end -0.7874 -0.4064)
			(stroke
				(width 0.1524)
				(type default)
			)
			(layer "F.SilkS")
		)
		(fp_line
			(start -0.7874 -0.4064)
			(end 0.7874 -0.4064)
			(stroke
				(width 0.1524)
				(type default)
			)
			(layer "F.SilkS")
		)
		(fp_line
			(start 0.67945 0.3048)
			(end 0.120396 0.3048)
			(stroke
				(width 0.1)
				(type default)
			)
			(layer "F.Fab")
		)
		(fp_line
			(start 0.67945 -0.3048)
			(end 0.67945 0.3048)
			(stroke
				(width 0.1)
				(type default)
			)
			(layer "F.Fab")
		)
		(fp_line
			(start 0.12065 -0.2794)
			(end 0.12065 -0.3048)
			(stroke
				(width 0.1)
				(type default)
			)
			(layer "F.Fab")
		)
		(fp_line
			(start 0.12065 -0.3048)
			(end 0.67945 -0.3048)
			(stroke
				(width 0.1)
				(type default)
			)
			(layer "F.Fab")
		)
		(fp_line
			(start 0.120396 0.3048)
			(end 0.120396 0.2794)
			(stroke
				(width 0.1)
				(type default)
			)
			(layer "F.Fab")
		)
		(fp_line
			(start 0.120396 0.2794)
			(end -0.12065 0.2794)
			(stroke
				(width 0.1)
				(type default)
			)
			(layer "F.Fab")
		)
		(fp_line
			(start -0.12065 0.3048)
			(end -0.67945 0.3048)
			(stroke
				(width 0.1)
				(type default)
			)
			(layer "F.Fab")
		)
		(fp_line
			(start -0.12065 0.2794)
			(end -0.12065 0.3048)
			(stroke
				(width 0.1)
				(type default)
			)
			(layer "F.Fab")
		)
		(fp_line
			(start -0.12065 -0.2794)
			(end 0.12065 -0.2794)
			(stroke
				(width 0.1)
				(type default)
			)
			(layer "F.Fab")
		)
		(fp_line
			(start -0.12065 -0.305054)
			(end -0.12065 -0.2794)
			(stroke
				(width 0.1)
				(type default)
			)
			(layer "F.Fab")
		)
		(fp_line
			(start -0.67945 0.3048)
			(end -0.67945 -0.305054)
			(stroke
				(width 0.1)
				(type default)
			)
			(layer "F.Fab")
		)
		(fp_line
			(start -0.67945 -0.305054)
			(end -0.12065 -0.305054)
			(stroke
				(width 0.1)
				(type default)
			)
			(layer "F.Fab")
		)
		(pad "1" smd circle
			(at -0.40005 0 180)
			(size 0 0)
			(layers "F.Cu" "F.Mask" "F.Paste")
			(net "PVDD11_S3_P1_RESET_N_R")
		)
		(pad "2" smd circle
			(at 0.40005 0 180)
			(size 0 0)
			(layers "F.Cu" "F.Mask" "F.Paste")
			(net "PVDD11_S3_P1_RESET_N")
		)
	)
	(footprint ""
		(layer "F.Cu")
		(at 329.223624 -141.591792 90)
		(property "Reference" "PR435"
			(at 0 0 90)
			(layer "F.SilkS")
			(hide yes)
			(effects
				(font
					(size 1.27 1.27)
				)
			)
		)
		(property "Value" ""
			(at 0 0 90)
			(layer "F.Fab")
			(effects
				(font
					(size 1.27 1.27)
				)
			)
		)
		(duplicate_pad_numbers_are_jumpers no)
		(fp_line
			(start 0.7874 -0.4064)
			(end 0.7874 0.4064)
			(stroke
				(width 0.1524)
				(type default)
			)
			(layer "F.SilkS")
		)
		(fp_line
			(start -0.7874 -0.4064)
			(end 0.7874 -0.4064)
			(stroke
				(width 0.1524)
				(type default)
			)
			(layer "F.SilkS")
		)
		(fp_line
			(start 0.7874 0.4064)
			(end -0.7874 0.4064)
			(stroke
				(width 0.1524)
				(type default)
			)
			(layer "F.SilkS")
		)
		(fp_line
			(start -0.7874 0.4064)
			(end -0.7874 -0.4064)
			(stroke
				(width 0.1524)
				(type default)
			)
			(layer "F.SilkS")
		)
		(fp_line
			(start -0.12065 -0.305054)
			(end -0.12065 -0.2794)
			(stroke
				(width 0.1)
				(type default)
			)
			(layer "F.Fab")
		)
		(fp_line
			(start -0.67945 -0.305054)
			(end -0.12065 -0.305054)
			(stroke
				(width 0.1)
				(type default)
			)
			(layer "F.Fab")
		)
		(fp_line
			(start 0.67945 -0.3048)
			(end 0.67945 0.3048)
			(stroke
				(width 0.1)
				(type default)
			)
			(layer "F.Fab")
		)
		(fp_line
			(start 0.12065 -0.3048)
			(end 0.67945 -0.3048)
			(stroke
				(width 0.1)
				(type default)
			)
			(layer "F.Fab")
		)
		(fp_line
			(start 0.12065 -0.2794)
			(end 0.12065 -0.3048)
			(stroke
				(width 0.1)
				(type default)
			)
			(layer "F.Fab")
		)
		(fp_line
			(start -0.12065 -0.2794)
			(end 0.12065 -0.2794)
			(stroke
				(width 0.1)
				(type default)
			)
			(layer "F.Fab")
		)
		(fp_line
			(start 0.120396 0.2794)
			(end -0.12065 0.2794)
			(stroke
				(width 0.1)
				(type default)
			)
			(layer "F.Fab")
		)
		(fp_line
			(start -0.12065 0.2794)
			(end -0.12065 0.3048)
			(stroke
				(width 0.1)
				(type default)
			)
			(layer "F.Fab")
		)
		(fp_line
			(start 0.67945 0.3048)
			(end 0.120396 0.3048)
			(stroke
				(width 0.1)
				(type default)
			)
			(layer "F.Fab")
		)
		(fp_line
			(start 0.120396 0.3048)
			(end 0.120396 0.2794)
			(stroke
				(width 0.1)
				(type default)
			)
			(layer "F.Fab")
		)
		(fp_line
			(start -0.12065 0.3048)
			(end -0.67945 0.3048)
			(stroke
				(width 0.1)
				(type default)
			)
			(layer "F.Fab")
		)
		(fp_line
			(start -0.67945 0.3048)
			(end -0.67945 -0.305054)
			(stroke
				(width 0.1)
				(type default)
			)
			(layer "F.Fab")
		)
		(pad "1" smd circle
			(at -0.40005 0 90)
			(size 0 0)
			(layers "F.Cu" "F.Mask" "F.Paste")
			(net "PVDD18_S5_P0_RGND")
		)
		(pad "2" smd circle
			(at 0.40005 0 90)
			(size 0 0)
			(layers "F.Cu" "F.Mask" "F.Paste")
			(net "VSENSE_PVDD18_S5_P0_DN")
		)
	)
	(footprint ""
		(layer "F.Cu")
		(at 67.021964 -149.721316 -90)
		(property "Reference" "PR8002"
			(at 0 0 270)
			(layer "F.SilkS")
			(hide yes)
			(effects
				(font
					(size 1.27 1.27)
				)
			)
		)
		(property "Value" ""
			(at 0 0 270)
			(layer "F.Fab")
			(effects
				(font
					(size 1.27 1.27)
				)
			)
		)
		(duplicate_pad_numbers_are_jumpers no)
		(fp_line
			(start -0.7874 0.4064)
			(end -0.7874 -0.4064)
			(stroke
				(width 0.1524)
				(type default)
			)
			(layer "F.SilkS")
		)
		(fp_line
			(start 0.7874 0.4064)
			(end -0.7874 0.4064)
			(stroke
				(width 0.1524)
				(type default)
			)
			(layer "F.SilkS")
		)
		(fp_line
			(start -0.7874 -0.4064)
			(end 0.7874 -0.4064)
			(stroke
				(width 0.1524)
				(type default)
			)
			(layer "F.SilkS")
		)
		(fp_line
			(start 0.7874 -0.4064)
			(end 0.7874 0.4064)
			(stroke
				(width 0.1524)
				(type default)
			)
			(layer "F.SilkS")
		)
		(fp_line
			(start -0.67945 0.3048)
			(end -0.67945 -0.305054)
			(stroke
				(width 0.1)
				(type default)
			)
			(layer "F.Fab")
		)
		(fp_line
			(start -0.12065 0.3048)
			(end -0.67945 0.3048)
			(stroke
				(width 0.1)
				(type default)
			)
			(layer "F.Fab")
		)
		(fp_line
			(start 0.120396 0.3048)
			(end 0.120396 0.2794)
			(stroke
				(width 0.1)
				(type default)
			)
			(layer "F.Fab")
		)
		(fp_line
			(start 0.67945 0.3048)
			(end 0.120396 0.3048)
			(stroke
				(width 0.1)
				(type default)
			)
			(layer "F.Fab")
		)
		(fp_line
			(start -0.12065 0.2794)
			(end -0.12065 0.3048)
			(stroke
				(width 0.1)
				(type default)
			)
			(layer "F.Fab")
		)
		(fp_line
			(start 0.120396 0.2794)
			(end -0.12065 0.2794)
			(stroke
				(width 0.1)
				(type default)
			)
			(layer "F.Fab")
		)
		(fp_line
			(start -0.12065 -0.2794)
			(end 0.12065 -0.2794)
			(stroke
				(width 0.1)
				(type default)
			)
			(layer "F.Fab")
		)
		(fp_line
			(start 0.12065 -0.2794)
			(end 0.12065 -0.3048)
			(stroke
				(width 0.1)
				(type default)
			)
			(layer "F.Fab")
		)
		(fp_line
			(start 0.12065 -0.3048)
			(end 0.67945 -0.3048)
			(stroke
				(width 0.1)
				(type default)
			)
			(layer "F.Fab")
		)
		(fp_line
			(start 0.67945 -0.3048)
			(end 0.67945 0.3048)
			(stroke
				(width 0.1)
				(type default)
			)
			(layer "F.Fab")
		)
		(fp_line
			(start -0.67945 -0.305054)
			(end -0.12065 -0.305054)
			(stroke
				(width 0.1)
				(type default)
			)
			(layer "F.Fab")
		)
		(fp_line
			(start -0.12065 -0.305054)
			(end -0.12065 -0.2794)
			(stroke
				(width 0.1)
				(type default)
			)
			(layer "F.Fab")
		)
		(pad "1" smd circle
			(at -0.40005 0 270)
			(size 0 0)
			(layers "F.Cu" "F.Mask" "F.Paste")
			(net "SW_PVDD18_S5_P1_BST")
		)
		(pad "2" smd circle
			(at 0.40005 0 270)
			(size 0 0)
			(layers "F.Cu" "F.Mask" "F.Paste")
			(net "SW_PVDD18_S5_P1_BST_R")
		)
	)
	(footprint ""
		(layer "F.Cu")
		(at 225.429826 -388.160514 -90)
		(property "Reference" "H6002"
			(at 0.127 -6.738112 90)
			(unlocked yes)
			(layer "F.SilkS")
			(effects
				(font
					(size 0.7874 0.5842)
					(thickness 0.1524)
				)
				(justify left)
			)
		)
		(property "Value" ""
			(at 0 0 270)
			(layer "F.Fab")
			(effects
				(font
					(size 1.27 1.27)
				)
			)
		)
		(duplicate_pad_numbers_are_jumpers no)
		(pad "1" thru_hole circle
			(at 0 0 270)
			(size 8.001 8.001)
			(drill 4.2164)
			(layers "*.Cu" "*.Mask")
			(remove_unused_layers no)
			(net "GND")
			(clearance -1.6383)
		)
	)
	(footprint ""
		(layer "F.Cu")
		(at 82.28457 -182.743856 180)
		(property "Reference" "PU4"
			(at -0.19812 -6.65861 0)
			(unlocked yes)
			(layer "F.SilkS")
			(effects
				(font
					(size 0.7874 0.5842)
					(thickness 0.1524)
				)
				(justify left)
			)
		)
		(property "Value" ""
			(at 0 0 180)
			(layer "F.Fab")
			(effects
				(font
					(size 1.27 1.27)
				)
			)
		)
		(duplicate_pad_numbers_are_jumpers no)
		(fp_line
			(start 2.500122 2.999994)
			(end 2.2987 2.999994)
			(stroke
				(width 0.1524)
				(type default)
			)
			(layer "F.SilkS")
		)
		(fp_line
			(start 2.500122 2.339594)
			(end 2.500122 2.999994)
			(stroke
				(width 0.1524)
				(type default)
			)
			(layer "F.SilkS")
		)
		(fp_line
			(start 2.500122 -2.999994)
			(end 2.500122 -2.44348)
			(stroke
				(width 0.1524)
				(type default)
			)
			(layer "F.SilkS")
		)
		(fp_line
			(start 2.31394 -2.999994)
			(end 2.500122 -2.999994)
			(stroke
				(width 0.1524)
				(type default)
			)
			(layer "F.SilkS")
		)
		(fp_line
			(start -2.2987 2.999994)
			(end -2.500122 2.999994)
			(stroke
				(width 0.1524)
				(type default)
			)
			(layer "F.SilkS")
		)
		(fp_line
			(start -2.500122 2.999994)
			(end -2.500122 2.339594)
			(stroke
				(width 0.1524)
				(type default)
			)
			(layer "F.SilkS")
		)
		(fp_line
			(start -2.500122 0.6604)
			(end -2.500122 0.229108)
			(stroke
				(width 0.1524)
				(type default)
			)
			(layer "F.SilkS")
		)
		(fp_line
			(start -2.500122 -2.529078)
			(end -2.500122 -2.999994)
			(stroke
				(width 0.1524)
				(type default)
			)
			(layer "F.SilkS")
		)
		(fp_line
			(start -2.500122 -2.999994)
			(end -2.24409 -2.999994)
			(stroke
				(width 0.1524)
				(type default)
			)
			(layer "F.SilkS")
		)
		(fp_poly
			(pts
				(xy -2.612898 -2.543556) (xy -3.380232 -2.799334) (xy -2.868676 -3.31089)
			)
			(stroke
				(width 0)
				(type default)
			)
			(fill yes)
			(layer "F.SilkS")
		)
		(fp_line
			(start 2.500122 2.999994)
			(end -2.500122 2.999994)
			(stroke
				(width 0.1)
				(type default)
			)
			(layer "F.Fab")
		)
		(fp_line
			(start 2.500122 -2.999994)
			(end 2.500122 2.999994)
			(stroke
				(width 0.1)
				(type default)
			)
			(layer "F.Fab")
		)
		(fp_line
			(start -2.500122 2.999994)
			(end -2.500122 -2.999994)
			(stroke
				(width 0.1)
				(type default)
			)
			(layer "F.Fab")
		)
		(fp_line
			(start -2.500122 -2.999994)
			(end 2.500122 -2.999994)
			(stroke
				(width 0.1)
				(type default)
			)
			(layer "F.Fab")
		)
		(fp_poly
			(pts
				(xy -4.218432 -2.783078) (xy -4.218432 -1.767078) (xy -3.202432 -2.275078)
			)
			(stroke
				(width 0)
				(type default)
			)
			(fill yes)
			(layer "F.Fab")
		)
		(pad "1" smd rect
			(at -2.400046 -2.275078 270)
			(size 0.2286 0.6096)
			(layers "F.Cu" "F.Mask" "F.Paste")
			(net "PVDDCR_CPU0_P1_VOS1")
		)
		(pad "2" smd rect
			(at -2.400046 -1.82499 270)
			(size 0.2286 0.6096)
			(layers "F.Cu" "F.Mask" "F.Paste")
			(net "GND")
		)
		(pad "3" smd rect
			(at -2.400046 -1.374902 270)
			(size 0.2286 0.6096)
			(layers "F.Cu" "F.Mask" "F.Paste")
			(net "PVDDCR_CPU0_P1_VCC1")
		)
		(pad "4" smd rect
			(at -2.400046 -0.925068 270)
			(size 0.2286 0.6096)
			(layers "F.Cu" "F.Mask" "F.Paste")
			(net "PVDDCR_CPU0_P1_PVCC")
		)
		(pad "5" smd rect
			(at -2.400046 -0.47498 270)
			(size 0.2286 0.6096)
			(layers "F.Cu" "F.Mask" "F.Paste")
			(net "GND")
		)
		(pad "6" smd rect
			(at -2.400046 -0.024892 270)
			(size 0.2286 0.6096)
			(layers "F.Cu" "F.Mask" "F.Paste")
			(net "NC_PVDDCR_CPU0_P1_GL1_1")
		)
		(pad "7_9-20_24" smd circle
			(at 0 1.150112 270)
			(size 0 0)
			(layers "F.Cu" "F.Mask" "F.Paste")
			(net "GND")
		)
		(pad "10_19" smd rect
			(at 0 2.899918 270)
			(size 0.6096 4.318)
			(layers "F.Cu" "F.Mask" "F.Paste")
			(net "SW_PVDDCR_CPU0_P1_SW1")
		)
		(pad "25_29" smd rect
			(at 1.549908 -1.279906 90)
			(size 2.0574 2.3114)
			(layers "F.Cu" "F.Mask" "F.Paste")
			(net "SW_P12V_AUX_PVDDCR_CPU0_P1_FLT")
		)
		(pad "30" smd rect
			(at 2.05994 -2.899918 180)
			(size 0.2286 0.6096)
			(layers "F.Cu" "F.Mask" "F.Paste")
			(net "SW_P12V_AUX_PVDDCR_CPU0_P1_FLT")
		)
		(pad "31" smd rect
			(at 1.610106 -2.899918 180)
			(size 0.2286 0.6096)
			(layers "F.Cu" "F.Mask" "F.Paste")
			(net "NC_PVDDCR_CPU0_P1_DNC1")
		)
		(pad "32" smd rect
			(at 1.160018 -2.899918 180)
			(size 0.2286 0.6096)
			(layers "F.Cu" "F.Mask" "F.Paste")
			(net "SW_PVDDCR_CPU0_P1_PH1")
		)
		(pad "33" smd rect
			(at 0.70993 -2.899918 180)
			(size 0.2286 0.6096)
			(layers "F.Cu" "F.Mask" "F.Paste")
			(net "SW_PVDDCR_CPU0_P1_BOOT1")
		)
		(pad "34" smd rect
			(at 0.260096 -2.899918 180)
			(size 0.2286 0.6096)
			(layers "F.Cu" "F.Mask" "F.Paste")
			(net "PVDDCR_CPU0_P1_PWM1")
		)
		(pad "35" smd rect
			(at -0.189992 -2.899918 180)
			(size 0.2286 0.6096)
			(layers "F.Cu" "F.Mask" "F.Paste")
			(net "PVDDCR_CPU0_P1_VCC1")
		)
		(pad "36" smd rect
			(at -0.64008 -2.899918 180)
			(size 0.2286 0.6096)
			(layers "F.Cu" "F.Mask" "F.Paste")
			(net "PVDDCR_CPU0_P1_TEMP0")
		)
		(pad "37" smd rect
			(at -1.089914 -2.899918 180)
			(size 0.2286 0.6096)
			(layers "F.Cu" "F.Mask" "F.Paste")
			(net "PVDDCR_CPU0_P1_LSET1")
		)
		(pad "38" smd rect
			(at -1.540002 -2.899918 180)
			(size 0.2286 0.6096)
			(layers "F.Cu" "F.Mask" "F.Paste")
			(net "PVDDCR_CPU0_P1_IMON1")
		)
		(pad "39" smd rect
			(at -1.99009 -2.899918 180)
			(size 0.2286 0.6096)
			(layers "F.Cu" "F.Mask" "F.Paste")
			(net "PVDDCR_CPU0_P1_VCCS")
		)
		(pad "40" smd rect
			(at -0.87503 -1.27508 180)
			(size 1.7526 1.9558)
			(layers "F.Cu" "F.Mask" "F.Paste")
			(net "GND")
		)
		(pad "41" smd rect
			(at -1.525016 0.249936 90)
			(size 0.3048 0.4572)
			(layers "F.Cu" "F.Mask" "F.Paste")
			(net "NC_PVDDCR_CPU0_P1_GL2_1")
		)
		(zone
			(layer "F.Cu")
			(hatch none 0.5)
			(connect_pads
				(clearance 0)
			)
			(min_thickness 0.25)
			(keepout
				(tracks not_allowed)
				(vias allowed)
				(pads allowed)
				(copperpour not_allowed)
				(footprints allowed)
			)
			(placement
				(enabled no)
				(sheetname "")
			)
			(fill
				(thermal_gap 0.5)
				(thermal_bridge_width 0.5)
				(island_removal_mode 0)
			)
			(polygon
				(pts
					(xy 84.784692 -185.288174) (xy 84.784692 -184.99455) (xy 79.784448 -184.99455) (xy 79.784448 -185.288174)
					(xy 80.07477 -185.288174) (xy 84.49437 -185.288174)
				)
			)
		)
		(zone
			(layer "F.Cu")
			(hatch none 0.5)
			(connect_pads
				(clearance 0)
			)
			(min_thickness 0.25)
			(keepout
				(tracks not_allowed)
				(vias allowed)
				(pads allowed)
				(copperpour not_allowed)
				(footprints allowed)
			)
			(placement
				(enabled no)
				(sheetname "")
			)
			(fill
				(thermal_gap 0.5)
				(thermal_bridge_width 0.5)
				(island_removal_mode 0)
			)
			(polygon
				(pts
					(xy 82.2325 -182.497476) (xy 82.2325 -180.440076) (xy 84.0867 -180.440076) (xy 84.0867 -180.681122)
					(xy 84.329016 -180.681122) (xy 84.329016 -180.199538) (xy 80.431386 -180.199538) (xy 80.431386 -180.38445)
					(xy 81.941162 -180.38445) (xy 81.941162 -182.54345) (xy 79.784448 -182.54345) (xy 79.784448 -182.793132)
					(xy 81.936844 -182.793132)
				)
			)
		)
	)
	(footprint ""
		(layer "F.Cu")
		(at 414.84804 -378.95403 -90)
		(property "Reference" "C850"
			(at 0 0 270)
			(layer "F.SilkS")
			(hide yes)
			(effects
				(font
					(size 1.27 1.27)
				)
			)
		)
		(property "Value" ""
			(at 0 0 270)
			(layer "F.Fab")
			(effects
				(font
					(size 1.27 1.27)
				)
			)
		)
		(duplicate_pad_numbers_are_jumpers no)
		(fp_line
			(start -0.299974 0.150114)
			(end -0.299974 -0.150114)
			(stroke
				(width 0.1)
				(type default)
			)
			(layer "F.Fab")
		)
		(fp_line
			(start 0.299974 0.150114)
			(end -0.299974 0.150114)
			(stroke
				(width 0.1)
				(type default)
			)
			(layer "F.Fab")
		)
		(fp_line
			(start -0.299974 -0.150114)
			(end 0.299974 -0.150114)
			(stroke
				(width 0.1)
				(type default)
			)
			(layer "F.Fab")
		)
		(fp_line
			(start 0.299974 -0.150114)
			(end 0.299974 0.150114)
			(stroke
				(width 0.1)
				(type default)
			)
			(layer "F.Fab")
		)
		(pad "1" smd rect
			(at -0.2667 0 270)
			(size 0.3048 0.381)
			(layers "F.Cu" "F.Mask" "F.Paste")
			(net "P5E_CPU0_P2_TX_C_DN<9>")
		)
		(pad "2" smd rect
			(at 0.2667 0 270)
			(size 0.3048 0.381)
			(layers "F.Cu" "F.Mask" "F.Paste")
			(net "P5E_CPU0_P2_TX_DN<9>")
		)
	)
	(footprint ""
		(layer "F.Cu")
		(at 344.9955 -395.724634)
		(property "Reference" "U6011"
			(at -8.11784 -7.526528 0)
			(unlocked yes)
			(layer "F.SilkS")
			(effects
				(font
					(size 0.7874 0.5842)
					(thickness 0.1524)
				)
				(justify left)
			)
		)
		(property "Value" ""
			(at 0 0 0)
			(layer "F.Fab")
			(effects
				(font
					(size 1.27 1.27)
				)
			)
		)
		(duplicate_pad_numbers_are_jumpers no)
		(fp_line
			(start -11.400028 -4.45008)
			(end -9.7917 -4.45008)
			(stroke
				(width 0.1524)
				(type default)
			)
			(layer "F.SilkS")
		)
		(fp_line
			(start -11.400028 -0.947166)
			(end -11.400028 -4.45008)
			(stroke
				(width 0.1524)
				(type default)
			)
			(layer "F.SilkS")
		)
		(fp_line
			(start -11.400028 4.45008)
			(end -11.400028 0.145034)
			(stroke
				(width 0.1524)
				(type default)
			)
			(layer "F.SilkS")
		)
		(fp_line
			(start -10.0457 4.45008)
			(end -11.400028 4.45008)
			(stroke
				(width 0.1524)
				(type default)
			)
			(layer "F.SilkS")
		)
		(fp_line
			(start 9.6647 -4.45008)
			(end 11.400028 -4.45008)
			(stroke
				(width 0.1524)
				(type default)
			)
			(layer "F.SilkS")
		)
		(fp_line
			(start 11.400028 -4.45008)
			(end 11.400028 4.45008)
			(stroke
				(width 0.1524)
				(type default)
			)
			(layer "F.SilkS")
		)
		(fp_line
			(start 11.400028 4.45008)
			(end 9.7409 4.45008)
			(stroke
				(width 0.1524)
				(type default)
			)
			(layer "F.SilkS")
		)
		(fp_poly
			(pts
				(xy 10.450068 -4.45008) (xy 10.450068 -5.21208) (xy 12.162028 -5.21208) (xy 12.162028 -3.41884)
				(xy 11.400028 -3.41884) (xy 11.400028 -4.45008)
			)
			(stroke
				(width 0)
				(type default)
			)
			(fill yes)
			(layer "F.SilkS")
		)
		(fp_line
			(start -11.400028 -4.45008)
			(end -11.400028 4.45008)
			(stroke
				(width 0.1)
				(type default)
			)
			(layer "F.Fab")
		)
		(fp_line
			(start -11.400028 4.45008)
			(end 11.400028 4.45008)
			(stroke
				(width 0.1)
				(type default)
			)
			(layer "F.Fab")
		)
		(fp_line
			(start 11.400028 -4.45008)
			(end -11.400028 -4.45008)
			(stroke
				(width 0.1)
				(type default)
			)
			(layer "F.Fab")
		)
		(fp_line
			(start 11.400028 4.45008)
			(end 11.400028 -4.45008)
			(stroke
				(width 0.1)
				(type default)
			)
			(layer "F.Fab")
		)
		(fp_poly
			(pts
				(xy 10.450068 -4.45008) (xy 10.450068 -5.21208) (xy 12.162028 -5.21208) (xy 12.162028 -3.41884)
				(xy 11.400028 -3.41884) (xy 11.400028 -4.45008)
			)
			(stroke
				(width 0)
				(type default)
			)
			(fill yes)
			(layer "F.Fab")
		)
		(pad "A1" smd oval
			(at 11.050016 -3.938524)
			(size 0.254 0.3302)
			(layers "F.Cu" "F.Mask" "F.Paste")
			(net "NCF_A1_CPU0_P1_GND")
		)
		(pad "A35" smd oval
			(at 11.050016 3.940048)
			(size 0.254 0.3302)
			(layers "F.Cu" "F.Mask" "F.Paste")
			(net "NCF_CPU0_P1_GND")
		)
		(pad "AA10" smd circle
			(at 7.602728 -1.431798)
			(size 0.381 0.381)
			(layers "F.Cu" "F.Mask" "F.Paste")
			(net "P5E_CPU0_P1_TX_BUF_DN<14>")
		)
		(pad "AA29" smd circle
			(at 7.602728 2.032254)
			(size 0.381 0.381)
			(layers "F.Cu" "F.Mask" "F.Paste")
			(net "P5E_CPU0_P1_RX_DN<14>")
		)
		(pad "AB1" smd oval
			(at 7.450074 -3.938524)
			(size 0.254 0.3302)
			(layers "F.Cu" "F.Mask" "F.Paste")
			(net "P5E_CPU0_P1_RX_BUF_DP<14>")
		)
		(pad "AB35" smd oval
			(at 7.450074 3.940048)
			(size 0.254 0.3302)
			(layers "F.Cu" "F.Mask" "F.Paste")
			(net "P5E_CPU0_P1_TX_C_DN<14>")
		)
		(pad "AC4" smd circle
			(at 7.202678 -2.817368)
			(size 0.381 0.381)
			(layers "F.Cu" "F.Mask" "F.Paste")
			(net "GND")
		)
		(pad "AC13" smd circle
			(at 7.202678 -0.79629)
			(size 0.3048 0.3048)
			(layers "F.Cu" "F.Mask" "F.Paste")
			(net "GND")
		)
		(pad "AC17" smd circle
			(at 7.202678 -0.296164)
			(size 0.3048 0.3048)
			(layers "F.Cu" "F.Mask" "F.Paste")
			(net "P0V9_CPU0_RT1_2A")
		)
		(pad "AC20" smd circle
			(at 7.202678 0.203708)
			(size 0.3048 0.3048)
			(layers "F.Cu" "F.Mask" "F.Paste")
			(net "P0V9_CPU0_RT1_2A")
		)
		(pad "AC22" smd circle
			(at 7.202678 0.703834)
			(size 0.3048 0.3048)
			(layers "F.Cu" "F.Mask" "F.Paste")
			(net "GND")
		)
		(pad "AC32" smd circle
			(at 7.202678 2.724912)
			(size 0.381 0.381)
			(layers "F.Cu" "F.Mask" "F.Paste")
			(net "GND")
		)
		(pad "AD2" smd circle
			(at 7.1501 -3.41884)
			(size 0.3048 0.3048)
			(layers "F.Cu" "F.Mask" "F.Paste")
			(net "GND")
		)
		(pad "AD34" smd circle
			(at 7.1501 3.420364)
			(size 0.3048 0.3048)
			(layers "F.Cu" "F.Mask" "F.Paste")
			(net "GND")
		)
		(pad "AE1" smd oval
			(at 6.849872 -3.938524)
			(size 0.254 0.3302)
			(layers "F.Cu" "F.Mask" "F.Paste")
			(net "GND")
		)
		(pad "AE35" smd oval
			(at 6.849872 3.940048)
			(size 0.254 0.3302)
			(layers "F.Cu" "F.Mask" "F.Paste")
			(net "GND")
		)
		(pad "AF7" smd circle
			(at 6.802628 -2.12471)
			(size 0.381 0.381)
			(layers "F.Cu" "F.Mask" "F.Paste")
			(net "P5E_CPU0_P1_TX_BUF_DP<13>")
		)
		(pad "AF26" smd circle
			(at 6.802628 1.339342)
			(size 0.381 0.381)
			(layers "F.Cu" "F.Mask" "F.Paste")
			(net "P5E_CPU0_P1_RX_DP<13>")
		)
		(pad "AG2" smd circle
			(at 6.549898 -3.41884)
			(size 0.3048 0.3048)
			(layers "F.Cu" "F.Mask" "F.Paste")
			(net "P5E_CPU0_P1_RX_BUF_DN<13>")
		)
		(pad "AG34" smd circle
			(at 6.549898 3.420364)
			(size 0.3048 0.3048)
			(layers "F.Cu" "F.Mask" "F.Paste")
			(net "P5E_CPU0_P1_TX_C_DN<13>")
		)
		(pad "AH10" smd circle
			(at 6.402578 -1.431798)
			(size 0.381 0.381)
			(layers "F.Cu" "F.Mask" "F.Paste")
			(net "P5E_CPU0_P1_TX_BUF_DN<13>")
		)
		(pad "AH29" smd circle
			(at 6.402578 2.032254)
			(size 0.381 0.381)
			(layers "F.Cu" "F.Mask" "F.Paste")
			(net "P5E_CPU0_P1_RX_DN<13>")
		)
		(pad "AJ1" smd oval
			(at 6.249924 -3.938524)
			(size 0.254 0.3302)
			(layers "F.Cu" "F.Mask" "F.Paste")
			(net "P5E_CPU0_P1_RX_BUF_DP<13>")
		)
		(pad "AJ35" smd oval
			(at 6.249924 3.940048)
			(size 0.254 0.3302)
			(layers "F.Cu" "F.Mask" "F.Paste")
			(net "P5E_CPU0_P1_TX_C_DP<13>")
		)
		(pad "AK4" smd circle
			(at 6.002528 -2.817368)
			(size 0.381 0.381)
			(layers "F.Cu" "F.Mask" "F.Paste")
			(net "GND")
		)
		(pad "AK13" smd circle
			(at 6.002528 -0.79629)
			(size 0.3048 0.3048)
			(layers "F.Cu" "F.Mask" "F.Paste")
			(net "GND")
		)
		(pad "AK17" smd circle
			(at 6.002528 -0.296164)
			(size 0.3048 0.3048)
			(layers "F.Cu" "F.Mask" "F.Paste")
			(net "P0V9_CPU0_RT1_2A")
		)
		(pad "AK20" smd circle
			(at 6.002528 0.203708)
			(size 0.3048 0.3048)
			(layers "F.Cu" "F.Mask" "F.Paste")
			(net "P0V9_CPU0_RT1_2A")
		)
		(pad "AK22" smd circle
			(at 6.002528 0.703834)
			(size 0.3048 0.3048)
			(layers "F.Cu" "F.Mask" "F.Paste")
			(net "GND")
		)
		(pad "AK32" smd circle
			(at 6.002528 2.724912)
			(size 0.381 0.381)
			(layers "F.Cu" "F.Mask" "F.Paste")
			(net "GND")
		)
		(pad "AL2" smd circle
			(at 5.94995 -3.41884)
			(size 0.3048 0.3048)
			(layers "F.Cu" "F.Mask" "F.Paste")
			(net "GND")
		)
		(pad "AL34" smd circle
			(at 5.94995 3.420364)
			(size 0.3048 0.3048)
			(layers "F.Cu" "F.Mask" "F.Paste")
			(net "GND")
		)
		(pad "AM1" smd oval
			(at 5.649976 -3.938524)
			(size 0.254 0.3302)
			(layers "F.Cu" "F.Mask" "F.Paste")
			(net "GND")
		)
		(pad "AM35" smd oval
			(at 5.649976 3.940048)
			(size 0.254 0.3302)
			(layers "F.Cu" "F.Mask" "F.Paste")
			(net "GND")
		)
		(pad "AN7" smd circle
			(at 5.602478 -2.12471)
			(size 0.381 0.381)
			(layers "F.Cu" "F.Mask" "F.Paste")
			(net "P5E_CPU0_P1_TX_BUF_DP<12>")
		)
		(pad "AN26" smd circle
			(at 5.602478 1.339342)
			(size 0.381 0.381)
			(layers "F.Cu" "F.Mask" "F.Paste")
			(net "P5E_CPU0_P1_RX_DP<12>")
		)
		(pad "AP2" smd circle
			(at 5.350002 -3.41884)
			(size 0.3048 0.3048)
			(layers "F.Cu" "F.Mask" "F.Paste")
			(net "P5E_CPU0_P1_RX_BUF_DN<12>")
		)
		(pad "AP34" smd circle
			(at 5.350002 3.420364)
			(size 0.3048 0.3048)
			(layers "F.Cu" "F.Mask" "F.Paste")
			(net "P5E_CPU0_P1_TX_C_DN<12>")
		)
		(pad "AR10" smd circle
			(at 5.202682 -1.431798)
			(size 0.381 0.381)
			(layers "F.Cu" "F.Mask" "F.Paste")
			(net "P5E_CPU0_P1_TX_BUF_DN<12>")
		)
		(pad "AR29" smd circle
			(at 5.202682 2.032254)
			(size 0.381 0.381)
			(layers "F.Cu" "F.Mask" "F.Paste")
			(net "P5E_CPU0_P1_RX_DN<12>")
		)
		(pad "AT1" smd oval
			(at 5.050028 -3.938524)
			(size 0.254 0.3302)
			(layers "F.Cu" "F.Mask" "F.Paste")
			(net "P5E_CPU0_P1_RX_BUF_DP<12>")
		)
		(pad "AT35" smd oval
			(at 5.050028 3.940048)
			(size 0.254 0.3302)
			(layers "F.Cu" "F.Mask" "F.Paste")
			(net "P5E_CPU0_P1_TX_C_DP<12>")
		)
		(pad "AU4" smd circle
			(at 4.802632 -2.817368)
			(size 0.381 0.381)
			(layers "F.Cu" "F.Mask" "F.Paste")
			(net "GND")
		)
		(pad "AU13" smd circle
			(at 4.802632 -0.79629)
			(size 0.3048 0.3048)
			(layers "F.Cu" "F.Mask" "F.Paste")
			(net "GND")
		)
		(pad "AU17" smd circle
			(at 4.802632 -0.296164)
			(size 0.3048 0.3048)
			(layers "F.Cu" "F.Mask" "F.Paste")
			(net "P0V9_CPU0_RT1_2A")
		)
		(pad "AU20" smd circle
			(at 4.802632 0.203708)
			(size 0.3048 0.3048)
			(layers "F.Cu" "F.Mask" "F.Paste")
			(net "P0V9_CPU0_RT1_2A")
		)
		(pad "AU22" smd circle
			(at 4.802632 0.703834)
			(size 0.3048 0.3048)
			(layers "F.Cu" "F.Mask" "F.Paste")
			(net "GND")
		)
		(pad "AU32" smd circle
			(at 4.802632 2.724912)
			(size 0.381 0.381)
			(layers "F.Cu" "F.Mask" "F.Paste")
			(net "GND")
		)
		(pad "AV2" smd circle
			(at 4.750054 -3.41884)
			(size 0.3048 0.3048)
			(layers "F.Cu" "F.Mask" "F.Paste")
			(net "GND")
		)
		(pad "AV34" smd circle
			(at 4.750054 3.420364)
			(size 0.3048 0.3048)
			(layers "F.Cu" "F.Mask" "F.Paste")
			(net "GND")
		)
		(pad "AW1" smd oval
			(at 4.45008 -3.938524)
			(size 0.254 0.3302)
			(layers "F.Cu" "F.Mask" "F.Paste")
			(net "GND")
		)
		(pad "AW35" smd oval
			(at 4.45008 3.940048)
			(size 0.254 0.3302)
			(layers "F.Cu" "F.Mask" "F.Paste")
			(net "GND")
		)
		(pad "AY7" smd circle
			(at 4.402582 -2.12471)
			(size 0.381 0.381)
			(layers "F.Cu" "F.Mask" "F.Paste")
			(net "P5E_CPU0_P1_TX_BUF_DP<11>")
		)
		(pad "AY26" smd circle
			(at 4.402582 1.339342)
			(size 0.381 0.381)
			(layers "F.Cu" "F.Mask" "F.Paste")
			(net "P5E_CPU0_P1_RX_DP<11>")
		)
		(pad "B3" smd oval
			(at 10.885932 -2.888488 90)
			(size 0.254 0.3302)
			(layers "F.Cu" "F.Mask" "F.Paste")
			(net "JTAG_TCK_RT_CPU0_P1")
		)
		(pad "B6" smd oval
			(at 10.885932 -2.288286 90)
			(size 0.254 0.3302)
			(layers "F.Cu" "F.Mask" "F.Paste")
			(net "JTAG_TDI_RT_CPU0_P1")
		)
		(pad "B9" smd oval
			(at 10.885932 -1.688338 90)
			(size 0.254 0.3302)
			(layers "F.Cu" "F.Mask" "F.Paste")
			(net "JTAG_TDO_RT_CPU0_P1")
		)
		(pad "B12" smd oval
			(at 10.885932 -1.08839 90)
			(size 0.254 0.3302)
			(layers "F.Cu" "F.Mask" "F.Paste")
			(net "JTAG_TMS_RT_CPU0_P1")
		)
		(pad "B16" smd oval
			(at 10.885932 -0.488442 90)
			(size 0.254 0.3302)
			(layers "F.Cu" "F.Mask" "F.Paste")
			(net "Net_2207")
		)
		(pad "B19" smd oval
			(at 10.885932 0.111506 90)
			(size 0.254 0.3302)
			(layers "F.Cu" "F.Mask" "F.Paste")
			(net "GND")
		)
		(pad "B23" smd oval
			(at 10.885932 0.711708 90)
			(size 0.254 0.3302)
			(layers "F.Cu" "F.Mask" "F.Paste")
			(net "RT_CPU0_P1_ADDR2")
		)
		(pad "B25" smd oval
			(at 10.885932 1.311656 90)
			(size 0.254 0.3302)
			(layers "F.Cu" "F.Mask" "F.Paste")
			(net "RT_CPU0_P1_ADDR3")
		)
		(pad "B28" smd oval
			(at 10.885932 1.911604 90)
			(size 0.254 0.3302)
			(layers "F.Cu" "F.Mask" "F.Paste")
			(net "SMB_RT_CPU0_P1_R2_SDA")
		)
		(pad "B31" smd oval
			(at 10.885932 2.511552 90)
			(size 0.254 0.3302)
			(layers "F.Cu" "F.Mask" "F.Paste")
			(net "SMB_RT_CPU0_P1_R2_SCL")
		)
		(pad "BA2" smd circle
			(at 4.150106 -3.41884)
			(size 0.3048 0.3048)
			(layers "F.Cu" "F.Mask" "F.Paste")
			(net "P5E_CPU0_P1_RX_BUF_DN<11>")
		)
		(pad "BA34" smd circle
			(at 4.150106 3.420364)
			(size 0.3048 0.3048)
			(layers "F.Cu" "F.Mask" "F.Paste")
			(net "P5E_CPU0_P1_TX_C_DN<11>")
		)
		(pad "BB10" smd circle
			(at 4.002532 -1.431798)
			(size 0.381 0.381)
			(layers "F.Cu" "F.Mask" "F.Paste")
			(net "P5E_CPU0_P1_TX_BUF_DN<11>")
		)
		(pad "BB29" smd circle
			(at 4.002532 2.032254)
			(size 0.381 0.381)
			(layers "F.Cu" "F.Mask" "F.Paste")
			(net "P5E_CPU0_P1_RX_DN<11>")
		)
		(pad "BC1" smd oval
			(at 3.849878 -3.938524)
			(size 0.254 0.3302)
			(layers "F.Cu" "F.Mask" "F.Paste")
			(net "P5E_CPU0_P1_RX_BUF_DP<11>")
		)
		(pad "BC35" smd oval
			(at 3.849878 3.940048)
			(size 0.254 0.3302)
			(layers "F.Cu" "F.Mask" "F.Paste")
			(net "P5E_CPU0_P1_TX_C_DP<11>")
		)
		(pad "BD4" smd circle
			(at 3.602482 -2.817368)
			(size 0.381 0.381)
			(layers "F.Cu" "F.Mask" "F.Paste")
			(net "GND")
		)
		(pad "BD13" smd circle
			(at 3.602482 -0.79629)
			(size 0.3048 0.3048)
			(layers "F.Cu" "F.Mask" "F.Paste")
			(net "GND")
		)
		(pad "BD17" smd circle
			(at 3.602482 -0.296164)
			(size 0.3048 0.3048)
			(layers "F.Cu" "F.Mask" "F.Paste")
			(net "P0V9_CPU0_RT1_2A_2D")
		)
		(pad "BD20" smd circle
			(at 3.602482 0.203708)
			(size 0.3048 0.3048)
			(layers "F.Cu" "F.Mask" "F.Paste")
			(net "P0V9_CPU0_RT1_2A_2D")
		)
		(pad "BD22" smd circle
			(at 3.602482 0.703834)
			(size 0.3048 0.3048)
			(layers "F.Cu" "F.Mask" "F.Paste")
			(net "GND")
		)
		(pad "BD32" smd circle
			(at 3.602482 2.724912)
			(size 0.381 0.381)
			(layers "F.Cu" "F.Mask" "F.Paste")
			(net "GND")
		)
		(pad "BE2" smd circle
			(at 3.549904 -3.41884)
			(size 0.3048 0.3048)
			(layers "F.Cu" "F.Mask" "F.Paste")
			(net "GND")
		)
		(pad "BE34" smd circle
			(at 3.549904 3.420364)
			(size 0.3048 0.3048)
			(layers "F.Cu" "F.Mask" "F.Paste")
			(net "GND")
		)
		(pad "BF1" smd oval
			(at 3.24993 -3.938524)
			(size 0.254 0.3302)
			(layers "F.Cu" "F.Mask" "F.Paste")
			(net "GND")
		)
		(pad "BF35" smd oval
			(at 3.24993 3.940048)
			(size 0.254 0.3302)
			(layers "F.Cu" "F.Mask" "F.Paste")
			(net "GND")
		)
		(pad "BG7" smd circle
			(at 3.202686 -2.12471)
			(size 0.381 0.381)
			(layers "F.Cu" "F.Mask" "F.Paste")
			(net "P5E_CPU0_P1_TX_BUF_DP<10>")
		)
		(pad "BG26" smd circle
			(at 3.202686 1.339342)
			(size 0.381 0.381)
			(layers "F.Cu" "F.Mask" "F.Paste")
			(net "P5E_CPU0_P1_RX_DP<10>")
		)
		(pad "BH2" smd circle
			(at 2.949956 -3.41884)
			(size 0.3048 0.3048)
			(layers "F.Cu" "F.Mask" "F.Paste")
			(net "P5E_CPU0_P1_RX_BUF_DN<10>")
		)
		(pad "BH34" smd circle
			(at 2.949956 3.420364)
			(size 0.3048 0.3048)
			(layers "F.Cu" "F.Mask" "F.Paste")
			(net "P5E_CPU0_P1_TX_C_DN<10>")
		)
		(pad "BJ10" smd circle
			(at 2.802636 -1.431798)
			(size 0.381 0.381)
			(layers "F.Cu" "F.Mask" "F.Paste")
			(net "P5E_CPU0_P1_TX_BUF_DN<10>")
		)
		(pad "BJ29" smd circle
			(at 2.802636 2.032254)
			(size 0.381 0.381)
			(layers "F.Cu" "F.Mask" "F.Paste")
			(net "P5E_CPU0_P1_RX_DN<10>")
		)
		(pad "BK1" smd oval
			(at 2.649982 -3.938524)
			(size 0.254 0.3302)
			(layers "F.Cu" "F.Mask" "F.Paste")
			(net "P5E_CPU0_P1_RX_BUF_DP<10>")
		)
		(pad "BK35" smd oval
			(at 2.649982 3.940048)
			(size 0.254 0.3302)
			(layers "F.Cu" "F.Mask" "F.Paste")
			(net "P5E_CPU0_P1_TX_C_DP<10>")
		)
		(pad "BL4" smd circle
			(at 2.402586 -2.817368)
			(size 0.381 0.381)
			(layers "F.Cu" "F.Mask" "F.Paste")
			(net "GND")
		)
		(pad "BL13" smd circle
			(at 2.402586 -0.79629)
			(size 0.3048 0.3048)
			(layers "F.Cu" "F.Mask" "F.Paste")
			(net "GND")
		)
		(pad "BL17" smd circle
			(at 2.402586 -0.296164)
			(size 0.3048 0.3048)
			(layers "F.Cu" "F.Mask" "F.Paste")
			(net "P0V9_CPU0_RT_2D")
		)
		(pad "BL20" smd circle
			(at 2.402586 0.203708)
			(size 0.3048 0.3048)
			(layers "F.Cu" "F.Mask" "F.Paste")
			(net "P0V9_CPU0_RT_2D")
		)
		(pad "BL22" smd circle
			(at 2.402586 0.703834)
			(size 0.3048 0.3048)
			(layers "F.Cu" "F.Mask" "F.Paste")
			(net "GND")
		)
		(pad "BL32" smd circle
			(at 2.402586 2.724912)
			(size 0.381 0.381)
			(layers "F.Cu" "F.Mask" "F.Paste")
			(net "GND")
		)
		(pad "BM2" smd circle
			(at 2.350008 -3.41884)
			(size 0.3048 0.3048)
			(layers "F.Cu" "F.Mask" "F.Paste")
			(net "GND")
		)
		(pad "BM34" smd circle
			(at 2.350008 3.420364)
			(size 0.3048 0.3048)
			(layers "F.Cu" "F.Mask" "F.Paste")
			(net "GND")
		)
		(pad "BN1" smd oval
			(at 2.050034 -3.938524)
			(size 0.254 0.3302)
			(layers "F.Cu" "F.Mask" "F.Paste")
			(net "GND")
		)
		(pad "BN35" smd oval
			(at 2.050034 3.940048)
			(size 0.254 0.3302)
			(layers "F.Cu" "F.Mask" "F.Paste")
			(net "GND")
		)
		(pad "BP7" smd circle
			(at 2.002536 -2.12471)
			(size 0.381 0.381)
			(layers "F.Cu" "F.Mask" "F.Paste")
			(net "P5E_CPU0_P1_TX_BUF_DP<9>")
		)
		(pad "BP26" smd circle
			(at 2.002536 1.339342)
			(size 0.381 0.381)
			(layers "F.Cu" "F.Mask" "F.Paste")
			(net "P5E_CPU0_P1_RX_DP<9>")
		)
		(pad "BR2" smd circle
			(at 1.75006 -3.41884)
			(size 0.3048 0.3048)
			(layers "F.Cu" "F.Mask" "F.Paste")
			(net "P5E_CPU0_P1_RX_BUF_DN<9>")
		)
		(pad "BR34" smd circle
			(at 1.75006 3.420364)
			(size 0.3048 0.3048)
			(layers "F.Cu" "F.Mask" "F.Paste")
			(net "P5E_CPU0_P1_TX_C_DN<9>")
		)
		(pad "BT10" smd circle
			(at 1.602486 -1.431798)
			(size 0.381 0.381)
			(layers "F.Cu" "F.Mask" "F.Paste")
			(net "P5E_CPU0_P1_TX_BUF_DN<9>")
		)
		(pad "BT29" smd circle
			(at 1.602486 2.032254)
			(size 0.381 0.381)
			(layers "F.Cu" "F.Mask" "F.Paste")
			(net "P5E_CPU0_P1_RX_DN<9>")
		)
		(pad "BU1" smd oval
			(at 1.450086 -3.938524)
			(size 0.254 0.3302)
			(layers "F.Cu" "F.Mask" "F.Paste")
			(net "P5E_CPU0_P1_RX_BUF_DP<9>")
		)
		(pad "BU35" smd oval
			(at 1.450086 3.940048)
			(size 0.254 0.3302)
			(layers "F.Cu" "F.Mask" "F.Paste")
			(net "P5E_CPU0_P1_TX_C_DP<9>")
		)
		(pad "BV4" smd circle
			(at 1.20269 -2.817368)
			(size 0.381 0.381)
			(layers "F.Cu" "F.Mask" "F.Paste")
			(net "GND")
		)
		(pad "BV13" smd circle
			(at 1.20269 -0.79629)
			(size 0.3048 0.3048)
			(layers "F.Cu" "F.Mask" "F.Paste")
			(net "GND")
		)
		(pad "BV17" smd circle
			(at 1.20269 -0.296164)
			(size 0.3048 0.3048)
			(layers "F.Cu" "F.Mask" "F.Paste")
			(net "P1V8_CPU0_RT1_1A_1D")
		)
		(pad "BV20" smd circle
			(at 1.20269 0.203708)
			(size 0.3048 0.3048)
			(layers "F.Cu" "F.Mask" "F.Paste")
			(net "P1V8_CPU0_RT1_1A")
		)
		(pad "BV22" smd circle
			(at 1.20269 0.703834)
			(size 0.3048 0.3048)
			(layers "F.Cu" "F.Mask" "F.Paste")
			(net "GND")
		)
		(pad "BV32" smd circle
			(at 1.20269 2.724912)
			(size 0.381 0.381)
			(layers "F.Cu" "F.Mask" "F.Paste")
			(net "GND")
		)
		(pad "BW2" smd circle
			(at 1.150112 -3.41884)
			(size 0.3048 0.3048)
			(layers "F.Cu" "F.Mask" "F.Paste")
			(net "GND")
		)
		(pad "BW34" smd circle
			(at 1.150112 3.420364)
			(size 0.3048 0.3048)
			(layers "F.Cu" "F.Mask" "F.Paste")
			(net "GND")
		)
		(pad "BY1" smd oval
			(at 0.849884 -3.938524)
			(size 0.254 0.3302)
			(layers "F.Cu" "F.Mask" "F.Paste")
			(net "GND")
		)
		(pad "BY35" smd oval
			(at 0.849884 3.940048)
			(size 0.254 0.3302)
			(layers "F.Cu" "F.Mask" "F.Paste")
			(net "GND")
		)
		(pad "C2" smd circle
			(at 10.750042 -3.41884)
			(size 0.3048 0.3048)
			(layers "F.Cu" "F.Mask" "F.Paste")
			(net "NCF_CPU0_P1_GND")
		)
		(pad "C34" smd circle
			(at 10.750042 3.420364)
			(size 0.3048 0.3048)
			(layers "F.Cu" "F.Mask" "F.Paste")
			(net "NCF_CPU0_P1_GND")
		)
		(pad "CA7" smd circle
			(at 0.80264 -2.12471)
			(size 0.381 0.381)
			(layers "F.Cu" "F.Mask" "F.Paste")
			(net "P5E_CPU0_P1_TX_BUF_DP<8>")
		)
		(pad "CA26" smd circle
			(at 0.80264 1.339342)
			(size 0.381 0.381)
			(layers "F.Cu" "F.Mask" "F.Paste")
			(net "P5E_CPU0_P1_RX_DP<8>")
		)
		(pad "CB2" smd circle
			(at 0.54991 -3.41884)
			(size 0.3048 0.3048)
			(layers "F.Cu" "F.Mask" "F.Paste")
			(net "P5E_CPU0_P1_RX_BUF_DN<8>")
		)
		(pad "CB34" smd circle
			(at 0.54991 3.420364)
			(size 0.3048 0.3048)
			(layers "F.Cu" "F.Mask" "F.Paste")
			(net "P5E_CPU0_P1_TX_C_DN<8>")
		)
		(pad "CC10" smd circle
			(at 0.40259 -1.431798)
			(size 0.381 0.381)
			(layers "F.Cu" "F.Mask" "F.Paste")
			(net "P5E_CPU0_P1_TX_BUF_DN<8>")
		)
		(pad "CC29" smd circle
			(at 0.40259 2.032254)
			(size 0.381 0.381)
			(layers "F.Cu" "F.Mask" "F.Paste")
			(net "P5E_CPU0_P1_RX_DN<8>")
		)
		(pad "CD1" smd oval
			(at 0.249936 -3.938524)
			(size 0.254 0.3302)
			(layers "F.Cu" "F.Mask" "F.Paste")
			(net "P5E_CPU0_P1_RX_BUF_DP<8>")
		)
		(pad "CD35" smd oval
			(at 0.249936 3.940048)
			(size 0.254 0.3302)
			(layers "F.Cu" "F.Mask" "F.Paste")
			(net "P5E_CPU0_P1_TX_C_DP<8>")
		)
		(pad "CE4" smd circle
			(at 0.00254 -2.817368)
			(size 0.381 0.381)
			(layers "F.Cu" "F.Mask" "F.Paste")
			(net "GND")
		)
		(pad "CE13" smd circle
			(at 0.00254 -0.79629)
			(size 0.3048 0.3048)
			(layers "F.Cu" "F.Mask" "F.Paste")
			(net "GND")
		)
		(pad "CE17" smd circle
			(at 0.00254 -0.296164)
			(size 0.3048 0.3048)
			(layers "F.Cu" "F.Mask" "F.Paste")
			(net "P1V8_CPU0_RT1_1A")
		)
		(pad "CE20" smd circle
			(at 0.00254 0.203708)
			(size 0.3048 0.3048)
			(layers "F.Cu" "F.Mask" "F.Paste")
			(net "P1V8_CPU0_RT1_1A")
		)
		(pad "CE22" smd circle
			(at 0.00254 0.703834)
			(size 0.3048 0.3048)
			(layers "F.Cu" "F.Mask" "F.Paste")
			(net "GND")
		)
		(pad "CE32" smd circle
			(at 0.00254 2.724912)
			(size 0.381 0.381)
			(layers "F.Cu" "F.Mask" "F.Paste")
			(net "GND")
		)
		(pad "CF2" smd circle
			(at -0.050038 -3.41884)
			(size 0.3048 0.3048)
			(layers "F.Cu" "F.Mask" "F.Paste")
			(net "GND")
		)
		(pad "CF34" smd circle
			(at -0.050038 3.420364)
			(size 0.3048 0.3048)
			(layers "F.Cu" "F.Mask" "F.Paste")
			(net "GND")
		)
		(pad "CG1" smd oval
			(at -0.350012 -3.938524)
			(size 0.254 0.3302)
			(layers "F.Cu" "F.Mask" "F.Paste")
			(net "GND")
		)
		(pad "CG35" smd oval
			(at -0.350012 3.940048)
			(size 0.254 0.3302)
			(layers "F.Cu" "F.Mask" "F.Paste")
			(net "GND")
		)
		(pad "CH7" smd circle
			(at -0.39751 -2.12471)
			(size 0.381 0.381)
			(layers "F.Cu" "F.Mask" "F.Paste")
			(net "P5E_CPU0_P1_TX_BUF_DP<7>")
		)
		(pad "CH26" smd circle
			(at -0.39751 1.339342)
			(size 0.381 0.381)
			(layers "F.Cu" "F.Mask" "F.Paste")
			(net "P5E_CPU0_P1_RX_DP<7>")
		)
		(pad "CJ2" smd circle
			(at -0.649986 -3.41884)
			(size 0.3048 0.3048)
			(layers "F.Cu" "F.Mask" "F.Paste")
			(net "P5E_CPU0_P1_RX_BUF_DN<7>")
		)
		(pad "CJ34" smd circle
			(at -0.649986 3.420364)
			(size 0.3048 0.3048)
			(layers "F.Cu" "F.Mask" "F.Paste")
			(net "P5E_CPU0_P1_TX_C_DN<7>")
		)
		(pad "CK10" smd circle
			(at -0.797306 -1.431798)
			(size 0.381 0.381)
			(layers "F.Cu" "F.Mask" "F.Paste")
			(net "P5E_CPU0_P1_TX_BUF_DN<7>")
		)
		(pad "CK29" smd circle
			(at -0.797306 2.032254)
			(size 0.381 0.381)
			(layers "F.Cu" "F.Mask" "F.Paste")
			(net "P5E_CPU0_P1_RX_DN<7>")
		)
		(pad "CL1" smd oval
			(at -0.94996 -3.938524)
			(size 0.254 0.3302)
			(layers "F.Cu" "F.Mask" "F.Paste")
			(net "P5E_CPU0_P1_RX_BUF_DP<7>")
		)
		(pad "CL35" smd oval
			(at -0.94996 3.940048)
			(size 0.254 0.3302)
			(layers "F.Cu" "F.Mask" "F.Paste")
			(net "P5E_CPU0_P1_TX_C_DP<7>")
		)
		(pad "CM4" smd circle
			(at -1.197356 -2.817368)
			(size 0.381 0.381)
			(layers "F.Cu" "F.Mask" "F.Paste")
			(net "GND")
		)
		(pad "CM13" smd circle
			(at -1.197356 -0.79629)
			(size 0.3048 0.3048)
			(layers "F.Cu" "F.Mask" "F.Paste")
			(net "GND")
		)
		(pad "CM17" smd circle
			(at -1.197356 -0.296164)
			(size 0.3048 0.3048)
			(layers "F.Cu" "F.Mask" "F.Paste")
			(net "P1V8_CPU0_RT1_1A")
		)
		(pad "CM20" smd circle
			(at -1.197356 0.203708)
			(size 0.3048 0.3048)
			(layers "F.Cu" "F.Mask" "F.Paste")
			(net "P1V8_CPU0_RT1_1A")
		)
		(pad "CM22" smd circle
			(at -1.197356 0.703834)
			(size 0.3048 0.3048)
			(layers "F.Cu" "F.Mask" "F.Paste")
			(net "GND")
		)
		(pad "CM32" smd circle
			(at -1.197356 2.724912)
			(size 0.381 0.381)
			(layers "F.Cu" "F.Mask" "F.Paste")
			(net "GND")
		)
		(pad "CN2" smd circle
			(at -1.249934 -3.41884)
			(size 0.3048 0.3048)
			(layers "F.Cu" "F.Mask" "F.Paste")
			(net "GND")
		)
		(pad "CN34" smd circle
			(at -1.249934 3.420364)
			(size 0.3048 0.3048)
			(layers "F.Cu" "F.Mask" "F.Paste")
			(net "GND")
		)
		(pad "CP1" smd oval
			(at -1.549908 -3.938524)
			(size 0.254 0.3302)
			(layers "F.Cu" "F.Mask" "F.Paste")
			(net "GND")
		)
		(pad "CP35" smd oval
			(at -1.549908 3.940048)
			(size 0.254 0.3302)
			(layers "F.Cu" "F.Mask" "F.Paste")
			(net "GND")
		)
		(pad "CR7" smd circle
			(at -1.597406 -2.12471)
			(size 0.381 0.381)
			(layers "F.Cu" "F.Mask" "F.Paste")
			(net "P5E_CPU0_P1_TX_BUF_DP<6>")
		)
		(pad "CR26" smd circle
			(at -1.597406 1.339342)
			(size 0.381 0.381)
			(layers "F.Cu" "F.Mask" "F.Paste")
			(net "P5E_CPU0_P1_RX_DP<6>")
		)
		(pad "CT2" smd circle
			(at -1.849882 -3.41884)
			(size 0.3048 0.3048)
			(layers "F.Cu" "F.Mask" "F.Paste")
			(net "P5E_CPU0_P1_RX_BUF_DN<6>")
		)
		(pad "CT34" smd circle
			(at -1.849882 3.420364)
			(size 0.3048 0.3048)
			(layers "F.Cu" "F.Mask" "F.Paste")
			(net "P5E_CPU0_P1_TX_C_DN<6>")
		)
		(pad "CU10" smd circle
			(at -1.997456 -1.431798)
			(size 0.381 0.381)
			(layers "F.Cu" "F.Mask" "F.Paste")
			(net "P5E_CPU0_P1_TX_BUF_DN<6>")
		)
		(pad "CU29" smd circle
			(at -1.997456 2.032254)
			(size 0.381 0.381)
			(layers "F.Cu" "F.Mask" "F.Paste")
			(net "P5E_CPU0_P1_RX_DN<6>")
		)
		(pad "CV1" smd oval
			(at -2.15011 -3.938524)
			(size 0.254 0.3302)
			(layers "F.Cu" "F.Mask" "F.Paste")
			(net "P5E_CPU0_P1_RX_BUF_DP<6>")
		)
		(pad "CV35" smd oval
			(at -2.15011 3.940048)
			(size 0.254 0.3302)
			(layers "F.Cu" "F.Mask" "F.Paste")
			(net "P5E_CPU0_P1_TX_C_DP<6>")
		)
		(pad "CW4" smd circle
			(at -2.397506 -2.817368)
			(size 0.381 0.381)
			(layers "F.Cu" "F.Mask" "F.Paste")
			(net "GND")
		)
		(pad "CW13" smd circle
			(at -2.397506 -0.79629)
			(size 0.3048 0.3048)
			(layers "F.Cu" "F.Mask" "F.Paste")
			(net "GND")
		)
		(pad "CW17" smd circle
			(at -2.397506 -0.296164)
			(size 0.3048 0.3048)
			(layers "F.Cu" "F.Mask" "F.Paste")
			(net "P0V9_CPU0_RT_2D")
		)
		(pad "CW20" smd circle
			(at -2.397506 0.203708)
			(size 0.3048 0.3048)
			(layers "F.Cu" "F.Mask" "F.Paste")
			(net "P0V9_CPU0_RT_2D")
		)
		(pad "CW22" smd circle
			(at -2.397506 0.703834)
			(size 0.3048 0.3048)
			(layers "F.Cu" "F.Mask" "F.Paste")
			(net "GND")
		)
		(pad "CW32" smd circle
			(at -2.397506 2.724912)
			(size 0.381 0.381)
			(layers "F.Cu" "F.Mask" "F.Paste")
			(net "GND")
		)
		(pad "CY2" smd circle
			(at -2.450084 -3.41884)
			(size 0.3048 0.3048)
			(layers "F.Cu" "F.Mask" "F.Paste")
			(net "GND")
		)
		(pad "CY34" smd circle
			(at -2.450084 3.420364)
			(size 0.3048 0.3048)
			(layers "F.Cu" "F.Mask" "F.Paste")
			(net "GND")
		)
		(pad "D1" smd oval
			(at 10.450068 -3.938524)
			(size 0.254 0.3302)
			(layers "F.Cu" "F.Mask" "F.Paste")
			(net "NCF_CPU0_P1_GND")
		)
		(pad "D35" smd oval
			(at 10.450068 3.940048)
			(size 0.254 0.3302)
			(layers "F.Cu" "F.Mask" "F.Paste")
			(net "NCF_CPU0_P1_GND")
		)
		(pad "DA1" smd oval
			(at -2.750058 -3.938524)
			(size 0.254 0.3302)
			(layers "F.Cu" "F.Mask" "F.Paste")
			(net "GND")
		)
		(pad "DA35" smd oval
			(at -2.750058 3.940048)
			(size 0.254 0.3302)
			(layers "F.Cu" "F.Mask" "F.Paste")
			(net "GND")
		)
		(pad "DB7" smd circle
			(at -2.797302 -2.12471)
			(size 0.381 0.381)
			(layers "F.Cu" "F.Mask" "F.Paste")
			(net "P5E_CPU0_P1_TX_BUF_DP<5>")
		)
		(pad "DB26" smd circle
			(at -2.797302 1.339342)
			(size 0.381 0.381)
			(layers "F.Cu" "F.Mask" "F.Paste")
			(net "P5E_CPU0_P1_RX_DP<5>")
		)
		(pad "DC2" smd circle
			(at -3.050032 -3.41884)
			(size 0.3048 0.3048)
			(layers "F.Cu" "F.Mask" "F.Paste")
			(net "P5E_CPU0_P1_RX_BUF_DN<5>")
		)
		(pad "DC34" smd circle
			(at -3.050032 3.420364)
			(size 0.3048 0.3048)
			(layers "F.Cu" "F.Mask" "F.Paste")
			(net "P5E_CPU0_P1_TX_C_DN<5>")
		)
		(pad "DD10" smd circle
			(at -3.197352 -1.431798)
			(size 0.381 0.381)
			(layers "F.Cu" "F.Mask" "F.Paste")
			(net "P5E_CPU0_P1_TX_BUF_DN<5>")
		)
		(pad "DD29" smd circle
			(at -3.197352 2.032254)
			(size 0.381 0.381)
			(layers "F.Cu" "F.Mask" "F.Paste")
			(net "P5E_CPU0_P1_RX_DN<5>")
		)
		(pad "DE1" smd oval
			(at -3.350006 -3.938524)
			(size 0.254 0.3302)
			(layers "F.Cu" "F.Mask" "F.Paste")
			(net "P5E_CPU0_P1_RX_BUF_DP<5>")
		)
		(pad "DE35" smd oval
			(at -3.350006 3.940048)
			(size 0.254 0.3302)
			(layers "F.Cu" "F.Mask" "F.Paste")
			(net "P5E_CPU0_P1_TX_C_DP<5>")
		)
		(pad "DF4" smd circle
			(at -3.597402 -2.817368)
			(size 0.381 0.381)
			(layers "F.Cu" "F.Mask" "F.Paste")
			(net "GND")
		)
		(pad "DF13" smd circle
			(at -3.597402 -0.79629)
			(size 0.3048 0.3048)
			(layers "F.Cu" "F.Mask" "F.Paste")
			(net "GND")
		)
		(pad "DF17" smd circle
			(at -3.597402 -0.296164)
			(size 0.3048 0.3048)
			(layers "F.Cu" "F.Mask" "F.Paste")
			(net "P0V9_CPU0_RT1_2A_2D")
		)
		(pad "DF20" smd circle
			(at -3.597402 0.203708)
			(size 0.3048 0.3048)
			(layers "F.Cu" "F.Mask" "F.Paste")
			(net "P0V9_CPU0_RT1_2A_2D")
		)
		(pad "DF22" smd circle
			(at -3.597402 0.703834)
			(size 0.3048 0.3048)
			(layers "F.Cu" "F.Mask" "F.Paste")
			(net "GND")
		)
		(pad "DF32" smd circle
			(at -3.597402 2.724912)
			(size 0.381 0.381)
			(layers "F.Cu" "F.Mask" "F.Paste")
			(net "GND")
		)
		(pad "DG2" smd circle
			(at -3.64998 -3.41884)
			(size 0.3048 0.3048)
			(layers "F.Cu" "F.Mask" "F.Paste")
			(net "GND")
		)
		(pad "DG34" smd circle
			(at -3.64998 3.420364)
			(size 0.3048 0.3048)
			(layers "F.Cu" "F.Mask" "F.Paste")
			(net "GND")
		)
		(pad "DH1" smd oval
			(at -3.949954 -3.938524)
			(size 0.254 0.3302)
			(layers "F.Cu" "F.Mask" "F.Paste")
			(net "GND")
		)
		(pad "DH35" smd oval
			(at -3.949954 3.940048)
			(size 0.254 0.3302)
			(layers "F.Cu" "F.Mask" "F.Paste")
			(net "GND")
		)
		(pad "DJ7" smd circle
			(at -3.997452 -2.12471)
			(size 0.381 0.381)
			(layers "F.Cu" "F.Mask" "F.Paste")
			(net "P5E_CPU0_P1_TX_BUF_DP<4>")
		)
		(pad "DJ26" smd circle
			(at -3.997452 1.339342)
			(size 0.381 0.381)
			(layers "F.Cu" "F.Mask" "F.Paste")
			(net "P5E_CPU0_P1_RX_DP<4>")
		)
		(pad "DK2" smd circle
			(at -4.249928 -3.41884)
			(size 0.3048 0.3048)
			(layers "F.Cu" "F.Mask" "F.Paste")
			(net "P5E_CPU0_P1_RX_BUF_DN<4>")
		)
		(pad "DK34" smd circle
			(at -4.249928 3.420364)
			(size 0.3048 0.3048)
			(layers "F.Cu" "F.Mask" "F.Paste")
			(net "P5E_CPU0_P1_TX_C_DN<4>")
		)
		(pad "DL10" smd circle
			(at -4.397502 -1.431798)
			(size 0.381 0.381)
			(layers "F.Cu" "F.Mask" "F.Paste")
			(net "P5E_CPU0_P1_TX_BUF_DN<4>")
		)
		(pad "DL29" smd circle
			(at -4.397502 2.032254)
			(size 0.381 0.381)
			(layers "F.Cu" "F.Mask" "F.Paste")
			(net "P5E_CPU0_P1_RX_DN<4>")
		)
		(pad "DM1" smd oval
			(at -4.549902 -3.938524)
			(size 0.254 0.3302)
			(layers "F.Cu" "F.Mask" "F.Paste")
			(net "P5E_CPU0_P1_RX_BUF_DP<4>")
		)
		(pad "DM35" smd oval
			(at -4.549902 3.940048)
			(size 0.254 0.3302)
			(layers "F.Cu" "F.Mask" "F.Paste")
			(net "P5E_CPU0_P1_TX_C_DP<4>")
		)
		(pad "DN4" smd circle
			(at -4.797298 -2.817368)
			(size 0.381 0.381)
			(layers "F.Cu" "F.Mask" "F.Paste")
			(net "GND")
		)
		(pad "DN13" smd circle
			(at -4.797298 -0.79629)
			(size 0.3048 0.3048)
			(layers "F.Cu" "F.Mask" "F.Paste")
			(net "GND")
		)
		(pad "DN17" smd circle
			(at -4.797298 -0.296164)
			(size 0.3048 0.3048)
			(layers "F.Cu" "F.Mask" "F.Paste")
			(net "P0V9_CPU0_RT1_2A")
		)
		(pad "DN20" smd circle
			(at -4.797298 0.203708)
			(size 0.3048 0.3048)
			(layers "F.Cu" "F.Mask" "F.Paste")
			(net "P0V9_CPU0_RT1_2A")
		)
		(pad "DN22" smd circle
			(at -4.797298 0.703834)
			(size 0.3048 0.3048)
			(layers "F.Cu" "F.Mask" "F.Paste")
			(net "GND")
		)
		(pad "DN32" smd circle
			(at -4.797298 2.724912)
			(size 0.381 0.381)
			(layers "F.Cu" "F.Mask" "F.Paste")
			(net "GND")
		)
		(pad "DP2" smd circle
			(at -4.849876 -3.41884)
			(size 0.3048 0.3048)
			(layers "F.Cu" "F.Mask" "F.Paste")
			(net "GND")
		)
		(pad "DP34" smd circle
			(at -4.849876 3.420364)
			(size 0.3048 0.3048)
			(layers "F.Cu" "F.Mask" "F.Paste")
			(net "GND")
		)
		(pad "DR1" smd oval
			(at -5.150104 -3.938524)
			(size 0.254 0.3302)
			(layers "F.Cu" "F.Mask" "F.Paste")
			(net "GND")
		)
		(pad "DR35" smd oval
			(at -5.150104 3.940048)
			(size 0.254 0.3302)
			(layers "F.Cu" "F.Mask" "F.Paste")
			(net "GND")
		)
		(pad "DT7" smd circle
			(at -5.197348 -2.12471)
			(size 0.381 0.381)
			(layers "F.Cu" "F.Mask" "F.Paste")
			(net "P5E_CPU0_P1_TX_BUF_DP<3>")
		)
		(pad "DT26" smd circle
			(at -5.197348 1.339342)
			(size 0.381 0.381)
			(layers "F.Cu" "F.Mask" "F.Paste")
			(net "P5E_CPU0_P1_RX_DP<3>")
		)
		(pad "DU2" smd circle
			(at -5.450078 -3.41884)
			(size 0.3048 0.3048)
			(layers "F.Cu" "F.Mask" "F.Paste")
			(net "P5E_CPU0_P1_RX_BUF_DN<3>")
		)
		(pad "DU34" smd circle
			(at -5.450078 3.420364)
			(size 0.3048 0.3048)
			(layers "F.Cu" "F.Mask" "F.Paste")
			(net "P5E_CPU0_P1_TX_C_DN<3>")
		)
		(pad "DV10" smd circle
			(at -5.597398 -1.431798)
			(size 0.381 0.381)
			(layers "F.Cu" "F.Mask" "F.Paste")
			(net "P5E_CPU0_P1_TX_BUF_DN<3>")
		)
		(pad "DV29" smd circle
			(at -5.597398 2.032254)
			(size 0.381 0.381)
			(layers "F.Cu" "F.Mask" "F.Paste")
			(net "P5E_CPU0_P1_RX_DN<3>")
		)
		(pad "DW1" smd oval
			(at -5.750052 -3.938524)
			(size 0.254 0.3302)
			(layers "F.Cu" "F.Mask" "F.Paste")
			(net "P5E_CPU0_P1_RX_BUF_DP<3>")
		)
		(pad "DW35" smd oval
			(at -5.750052 3.940048)
			(size 0.254 0.3302)
			(layers "F.Cu" "F.Mask" "F.Paste")
			(net "P5E_CPU0_P1_TX_C_DP<3>")
		)
		(pad "DY4" smd circle
			(at -5.997448 -2.817368)
			(size 0.381 0.381)
			(layers "F.Cu" "F.Mask" "F.Paste")
			(net "GND")
		)
		(pad "DY13" smd circle
			(at -5.997448 -0.79629)
			(size 0.3048 0.3048)
			(layers "F.Cu" "F.Mask" "F.Paste")
			(net "GND")
		)
		(pad "DY17" smd circle
			(at -5.997448 -0.296164)
			(size 0.3048 0.3048)
			(layers "F.Cu" "F.Mask" "F.Paste")
			(net "P0V9_CPU0_RT1_2A")
		)
		(pad "DY20" smd circle
			(at -5.997448 0.203708)
			(size 0.3048 0.3048)
			(layers "F.Cu" "F.Mask" "F.Paste")
			(net "P0V9_CPU0_RT1_2A")
		)
		(pad "DY22" smd circle
			(at -5.997448 0.703834)
			(size 0.3048 0.3048)
			(layers "F.Cu" "F.Mask" "F.Paste")
			(net "GND")
		)
		(pad "DY32" smd circle
			(at -5.997448 2.724912)
			(size 0.381 0.381)
			(layers "F.Cu" "F.Mask" "F.Paste")
			(net "GND")
		)
		(pad "E8" smd circle
			(at 10.366502 -1.988312)
			(size 0.3048 0.3048)
			(layers "F.Cu" "F.Mask" "F.Paste")
			(net "JTAG_TRST_RT_CPU0_P1_N")
		)
		(pad "E11" smd circle
			(at 10.366502 -1.388364)
			(size 0.3048 0.3048)
			(layers "F.Cu" "F.Mask" "F.Paste")
			(net "RXDET_BYP_RT_CPU0_P1")
		)
		(pad "E14" smd circle
			(at 10.366502 -0.788416)
			(size 0.3048 0.3048)
			(layers "F.Cu" "F.Mask" "F.Paste")
			(net "GND")
		)
		(pad "E18" smd circle
			(at 10.366502 -0.188468)
			(size 0.3048 0.3048)
			(layers "F.Cu" "F.Mask" "F.Paste")
			(net "Net_2206")
		)
		(pad "E27" smd circle
			(at 10.366502 1.61163)
			(size 0.3048 0.3048)
			(layers "F.Cu" "F.Mask" "F.Paste")
			(net "GND")
		)
		(pad "E30" smd circle
			(at 10.366502 2.211578)
			(size 0.3048 0.3048)
			(layers "F.Cu" "F.Mask" "F.Paste")
			(net "GND")
		)
		(pad "E33" smd circle
			(at 10.366502 2.811526)
			(size 0.3048 0.3048)
			(layers "F.Cu" "F.Mask" "F.Paste")
			(net "GND")
		)
		(pad "EA2" smd circle
			(at -6.050026 -3.41884)
			(size 0.3048 0.3048)
			(layers "F.Cu" "F.Mask" "F.Paste")
			(net "GND")
		)
		(pad "EA34" smd circle
			(at -6.050026 3.420364)
			(size 0.3048 0.3048)
			(layers "F.Cu" "F.Mask" "F.Paste")
			(net "GND")
		)
		(pad "EB1" smd oval
			(at -6.35 -3.938524)
			(size 0.254 0.3302)
			(layers "F.Cu" "F.Mask" "F.Paste")
			(net "GND")
		)
		(pad "EB35" smd oval
			(at -6.35 3.940048)
			(size 0.254 0.3302)
			(layers "F.Cu" "F.Mask" "F.Paste")
			(net "GND")
		)
		(pad "EC7" smd circle
			(at -6.397498 -2.12471)
			(size 0.381 0.381)
			(layers "F.Cu" "F.Mask" "F.Paste")
			(net "P5E_CPU0_P1_TX_BUF_DP<2>")
		)
		(pad "EC26" smd circle
			(at -6.397498 1.339342)
			(size 0.381 0.381)
			(layers "F.Cu" "F.Mask" "F.Paste")
			(net "P5E_CPU0_P1_RX_DP<2>")
		)
		(pad "ED2" smd circle
			(at -6.649974 -3.41884)
			(size 0.3048 0.3048)
			(layers "F.Cu" "F.Mask" "F.Paste")
			(net "P5E_CPU0_P1_RX_BUF_DN<2>")
		)
		(pad "ED34" smd circle
			(at -6.649974 3.420364)
			(size 0.3048 0.3048)
			(layers "F.Cu" "F.Mask" "F.Paste")
			(net "P5E_CPU0_P1_TX_C_DN<2>")
		)
		(pad "EE10" smd circle
			(at -6.797294 -1.431798)
			(size 0.381 0.381)
			(layers "F.Cu" "F.Mask" "F.Paste")
			(net "P5E_CPU0_P1_TX_BUF_DN<2>")
		)
		(pad "EE29" smd circle
			(at -6.797294 2.032254)
			(size 0.381 0.381)
			(layers "F.Cu" "F.Mask" "F.Paste")
			(net "P5E_CPU0_P1_RX_DN<2>")
		)
		(pad "EF1" smd oval
			(at -6.949948 -3.938524)
			(size 0.254 0.3302)
			(layers "F.Cu" "F.Mask" "F.Paste")
			(net "P5E_CPU0_P1_RX_BUF_DP<2>")
		)
		(pad "EF35" smd oval
			(at -6.949948 3.940048)
			(size 0.254 0.3302)
			(layers "F.Cu" "F.Mask" "F.Paste")
			(net "P5E_CPU0_P1_TX_C_DP<2>")
		)
		(pad "EG4" smd circle
			(at -7.197344 -2.817368)
			(size 0.381 0.381)
			(layers "F.Cu" "F.Mask" "F.Paste")
			(net "GND")
		)
		(pad "EG13" smd circle
			(at -7.197344 -0.79629)
			(size 0.3048 0.3048)
			(layers "F.Cu" "F.Mask" "F.Paste")
			(net "GND")
		)
		(pad "EG17" smd circle
			(at -7.197344 -0.296164)
			(size 0.3048 0.3048)
			(layers "F.Cu" "F.Mask" "F.Paste")
			(net "P0V9_CPU0_RT1_2A")
		)
		(pad "EG20" smd circle
			(at -7.197344 0.203708)
			(size 0.3048 0.3048)
			(layers "F.Cu" "F.Mask" "F.Paste")
			(net "P0V9_CPU0_RT1_2A")
		)
		(pad "EG22" smd circle
			(at -7.197344 0.703834)
			(size 0.3048 0.3048)
			(layers "F.Cu" "F.Mask" "F.Paste")
			(net "GND")
		)
		(pad "EG32" smd circle
			(at -7.197344 2.724912)
			(size 0.381 0.381)
			(layers "F.Cu" "F.Mask" "F.Paste")
			(net "GND")
		)
		(pad "EH2" smd circle
			(at -7.249922 -3.41884)
			(size 0.3048 0.3048)
			(layers "F.Cu" "F.Mask" "F.Paste")
			(net "GND")
		)
		(pad "EH34" smd circle
			(at -7.249922 3.420364)
			(size 0.3048 0.3048)
			(layers "F.Cu" "F.Mask" "F.Paste")
			(net "GND")
		)
		(pad "EJ1" smd oval
			(at -7.549896 -3.938524)
			(size 0.254 0.3302)
			(layers "F.Cu" "F.Mask" "F.Paste")
			(net "GND")
		)
		(pad "EJ35" smd oval
			(at -7.549896 3.940048)
			(size 0.254 0.3302)
			(layers "F.Cu" "F.Mask" "F.Paste")
			(net "GND")
		)
		(pad "EK7" smd circle
			(at -7.597394 -2.12471)
			(size 0.381 0.381)
			(layers "F.Cu" "F.Mask" "F.Paste")
			(net "P5E_CPU0_P1_TX_BUF_DP<1>")
		)
		(pad "EK26" smd circle
			(at -7.597394 1.339342)
			(size 0.381 0.381)
			(layers "F.Cu" "F.Mask" "F.Paste")
			(net "P5E_CPU0_P1_RX_DP<1>")
		)
		(pad "EL2" smd circle
			(at -7.850124 -3.41884)
			(size 0.3048 0.3048)
			(layers "F.Cu" "F.Mask" "F.Paste")
			(net "P5E_CPU0_P1_RX_BUF_DN<1>")
		)
		(pad "EL34" smd circle
			(at -7.850124 3.420364)
			(size 0.3048 0.3048)
			(layers "F.Cu" "F.Mask" "F.Paste")
			(net "P5E_CPU0_P1_TX_C_DP<1>")
		)
		(pad "EM10" smd circle
			(at -7.997444 -1.431798)
			(size 0.381 0.381)
			(layers "F.Cu" "F.Mask" "F.Paste")
			(net "P5E_CPU0_P1_TX_BUF_DN<1>")
		)
		(pad "EM29" smd circle
			(at -7.997444 2.032254)
			(size 0.381 0.381)
			(layers "F.Cu" "F.Mask" "F.Paste")
			(net "P5E_CPU0_P1_RX_DN<1>")
		)
		(pad "EN1" smd oval
			(at -8.150098 -3.938524)
			(size 0.254 0.3302)
			(layers "F.Cu" "F.Mask" "F.Paste")
			(net "P5E_CPU0_P1_RX_BUF_DP<1>")
		)
		(pad "EN35" smd oval
			(at -8.150098 3.940048)
			(size 0.254 0.3302)
			(layers "F.Cu" "F.Mask" "F.Paste")
			(net "P5E_CPU0_P1_TX_C_DN<1>")
		)
		(pad "EP4" smd circle
			(at -8.397494 -2.817368)
			(size 0.381 0.381)
			(layers "F.Cu" "F.Mask" "F.Paste")
			(net "GND")
		)
		(pad "EP13" smd circle
			(at -8.397494 -0.79629)
			(size 0.3048 0.3048)
			(layers "F.Cu" "F.Mask" "F.Paste")
			(net "GND")
		)
		(pad "EP17" smd circle
			(at -8.397494 -0.296164)
			(size 0.3048 0.3048)
			(layers "F.Cu" "F.Mask" "F.Paste")
			(net "P0V9_CPU0_RT1_2A")
		)
		(pad "EP20" smd circle
			(at -8.397494 0.203708)
			(size 0.3048 0.3048)
			(layers "F.Cu" "F.Mask" "F.Paste")
			(net "P0V9_CPU0_RT1_2A")
		)
		(pad "EP22" smd circle
			(at -8.397494 0.703834)
			(size 0.3048 0.3048)
			(layers "F.Cu" "F.Mask" "F.Paste")
			(net "GND")
		)
		(pad "EP32" smd circle
			(at -8.397494 2.724912)
			(size 0.381 0.381)
			(layers "F.Cu" "F.Mask" "F.Paste")
			(net "GND")
		)
		(pad "ER2" smd circle
			(at -8.450072 -3.41884)
			(size 0.3048 0.3048)
			(layers "F.Cu" "F.Mask" "F.Paste")
			(net "GND")
		)
		(pad "ER34" smd circle
			(at -8.450072 3.420364)
			(size 0.3048 0.3048)
			(layers "F.Cu" "F.Mask" "F.Paste")
			(net "GND")
		)
		(pad "ET1" smd oval
			(at -8.750046 -3.938524)
			(size 0.254 0.3302)
			(layers "F.Cu" "F.Mask" "F.Paste")
			(net "GND")
		)
		(pad "ET35" smd oval
			(at -8.750046 3.940048)
			(size 0.254 0.3302)
			(layers "F.Cu" "F.Mask" "F.Paste")
			(net "GND")
		)
		(pad "EU7" smd circle
			(at -8.79729 -2.12471)
			(size 0.381 0.381)
			(layers "F.Cu" "F.Mask" "F.Paste")
			(net "P5E_CPU0_P1_TX_BUF_DP<0>")
		)
		(pad "EU26" smd circle
			(at -8.79729 1.339342)
			(size 0.381 0.381)
			(layers "F.Cu" "F.Mask" "F.Paste")
			(net "P5E_CPU0_P1_RX_DP<0>")
		)
		(pad "EV2" smd circle
			(at -9.05002 -3.41884)
			(size 0.3048 0.3048)
			(layers "F.Cu" "F.Mask" "F.Paste")
			(net "P5E_CPU0_P1_RX_BUF_DN<0>")
		)
		(pad "EV34" smd circle
			(at -9.05002 3.420364)
			(size 0.3048 0.3048)
			(layers "F.Cu" "F.Mask" "F.Paste")
			(net "P5E_CPU0_P1_TX_C_DN<0>")
		)
		(pad "EW10" smd circle
			(at -9.19734 -1.431798)
			(size 0.381 0.381)
			(layers "F.Cu" "F.Mask" "F.Paste")
			(net "P5E_CPU0_P1_TX_BUF_DN<0>")
		)
		(pad "EW29" smd circle
			(at -9.19734 2.032254)
			(size 0.381 0.381)
			(layers "F.Cu" "F.Mask" "F.Paste")
			(net "P5E_CPU0_P1_RX_DN<0>")
		)
		(pad "EY1" smd oval
			(at -9.349994 -3.938524)
			(size 0.254 0.3302)
			(layers "F.Cu" "F.Mask" "F.Paste")
			(net "P5E_CPU0_P1_RX_BUF_DP<0>")
		)
		(pad "EY35" smd oval
			(at -9.349994 3.940048)
			(size 0.254 0.3302)
			(layers "F.Cu" "F.Mask" "F.Paste")
			(net "P5E_CPU0_P1_TX_C_DP<0>")
		)
		(pad "F2" smd circle
			(at 10.150094 -3.41884)
			(size 0.3048 0.3048)
			(layers "F.Cu" "F.Mask" "F.Paste")
			(net "RST_RT_CPU0_P1_PERST_N")
		)
		(pad "F34" smd circle
			(at 10.150094 3.420364)
			(size 0.3048 0.3048)
			(layers "F.Cu" "F.Mask" "F.Paste")
			(net "RT_CPU0_P1_ADDR1")
		)
		(pad "FA15" smd circle
			(at -9.59739 -0.738886)
			(size 0.381 0.381)
			(layers "F.Cu" "F.Mask" "F.Paste")
			(net "GND")
		)
		(pad "FA32" smd circle
			(at -9.59739 2.724912)
			(size 0.381 0.381)
			(layers "F.Cu" "F.Mask" "F.Paste")
			(net "GND")
		)
		(pad "FB2" smd circle
			(at -9.649968 -3.41884)
			(size 0.3048 0.3048)
			(layers "F.Cu" "F.Mask" "F.Paste")
			(net "GND")
		)
		(pad "FB34" smd circle
			(at -9.649968 3.420364)
			(size 0.3048 0.3048)
			(layers "F.Cu" "F.Mask" "F.Paste")
			(net "GND")
		)
		(pad "FC3" smd circle
			(at -9.846818 -2.888488)
			(size 0.3048 0.3048)
			(layers "F.Cu" "F.Mask" "F.Paste")
			(net "GND")
		)
		(pad "FC6" smd circle
			(at -9.846818 -2.288286)
			(size 0.3048 0.3048)
			(layers "F.Cu" "F.Mask" "F.Paste")
			(net "GND")
		)
		(pad "FC9" smd circle
			(at -9.846818 -1.688338)
			(size 0.3048 0.3048)
			(layers "F.Cu" "F.Mask" "F.Paste")
			(net "GND")
		)
		(pad "FC19" smd circle
			(at -9.846818 0.111506)
			(size 0.3048 0.3048)
			(layers "F.Cu" "F.Mask" "F.Paste")
			(net "GND")
		)
		(pad "FC23" smd circle
			(at -9.846818 0.711708)
			(size 0.3048 0.3048)
			(layers "F.Cu" "F.Mask" "F.Paste")
			(net "GND")
		)
		(pad "FC25" smd circle
			(at -9.846818 1.311656)
			(size 0.3048 0.3048)
			(layers "F.Cu" "F.Mask" "F.Paste")
			(net "GND")
		)
		(pad "FC28" smd circle
			(at -9.846818 1.911604)
			(size 0.3048 0.3048)
			(layers "F.Cu" "F.Mask" "F.Paste")
			(net "GND")
		)
		(pad "FD1" smd oval
			(at -9.949942 -3.938524)
			(size 0.254 0.3302)
			(layers "F.Cu" "F.Mask" "F.Paste")
			(net "GND")
		)
		(pad "FD35" smd oval
			(at -9.949942 3.940048)
			(size 0.254 0.3302)
			(layers "F.Cu" "F.Mask" "F.Paste")
			(net "GND")
		)
		(pad "FE2" smd circle
			(at -10.249916 -3.41884)
			(size 0.3048 0.3048)
			(layers "F.Cu" "F.Mask" "F.Paste")
			(net "NCF_CPU0_P1_GND")
		)
		(pad "FE34" smd circle
			(at -10.249916 3.420364)
			(size 0.3048 0.3048)
			(layers "F.Cu" "F.Mask" "F.Paste")
			(net "NCF_CPU0_P1_GND")
		)
		(pad "FF5" smd circle
			(at -10.366248 -2.588514)
			(size 0.3048 0.3048)
			(layers "F.Cu" "F.Mask" "F.Paste")
			(net "SMB_RT_CPU0_P1_ROM_MUX_1D_R_SCL")
		)
		(pad "FF8" smd circle
			(at -10.366248 -1.988312)
			(size 0.3048 0.3048)
			(layers "F.Cu" "F.Mask" "F.Paste")
			(net "JTAG_TEST_MODE_RT_CPU0_P1")
		)
		(pad "FF11" smd circle
			(at -10.366248 -1.388364)
			(size 0.3048 0.3048)
			(layers "F.Cu" "F.Mask" "F.Paste")
			(net "RST_RT_CPU0_P1_RESET_N")
		)
		(pad "FF14" smd circle
			(at -10.366248 -0.788416)
			(size 0.3048 0.3048)
			(layers "F.Cu" "F.Mask" "F.Paste")
			(net "GND")
		)
		(pad "FF18" smd circle
			(at -10.366248 -0.188468)
			(size 0.3048 0.3048)
			(layers "F.Cu" "F.Mask" "F.Paste")
			(net "CLK_100M_RETIMER_CPU0_P1_DN")
		)
		(pad "FF21" smd circle
			(at -10.366248 0.41148)
			(size 0.3048 0.3048)
			(layers "F.Cu" "F.Mask" "F.Paste")
			(net "GND")
		)
		(pad "FF24" smd circle
			(at -10.366248 1.011682)
			(size 0.3048 0.3048)
			(layers "F.Cu" "F.Mask" "F.Paste")
			(net "TEST0_RT_CPU0_P1")
		)
		(pad "FF27" smd circle
			(at -10.366248 1.61163)
			(size 0.3048 0.3048)
			(layers "F.Cu" "F.Mask" "F.Paste")
			(net "TEST1_RT_CPU0_P1")
		)
		(pad "FF30" smd circle
			(at -10.366248 2.211578)
			(size 0.3048 0.3048)
			(layers "F.Cu" "F.Mask" "F.Paste")
			(net "TEST2_RT_CPU0_P1")
		)
		(pad "FF33" smd circle
			(at -10.366248 2.811526)
			(size 0.3048 0.3048)
			(layers "F.Cu" "F.Mask" "F.Paste")
			(net "RT_CPU0_P1_SCAN_MODE")
		)
		(pad "FG1" smd oval
			(at -10.54989 -3.938524)
			(size 0.254 0.3302)
			(layers "F.Cu" "F.Mask" "F.Paste")
			(net "NCF_CPU0_P1_GND")
		)
		(pad "FG35" smd oval
			(at -10.54989 3.940048)
			(size 0.254 0.3302)
			(layers "F.Cu" "F.Mask" "F.Paste")
			(net "NCF_CPU0_P1_GND")
		)
		(pad "FH2" smd circle
			(at -10.850118 -3.41884)
			(size 0.3048 0.3048)
			(layers "F.Cu" "F.Mask" "F.Paste")
			(net "NCF_CPU0_P1_GND")
		)
		(pad "FH34" smd circle
			(at -10.850118 3.420364)
			(size 0.3048 0.3048)
			(layers "F.Cu" "F.Mask" "F.Paste")
			(net "NCF_CPU0_P1_GND")
		)
		(pad "FJ3" smd oval
			(at -10.885932 -2.888488 90)
			(size 0.254 0.3302)
			(layers "F.Cu" "F.Mask" "F.Paste")
			(net "SMB_RT_CPU0_P1_ROM_MUX_1D_R_SDA")
		)
		(pad "FJ6" smd oval
			(at -10.885932 -2.288286 90)
			(size 0.254 0.3302)
			(layers "F.Cu" "F.Mask" "F.Paste")
			(net "Net_2204")
		)
		(pad "FJ9" smd oval
			(at -10.885932 -1.688338 90)
			(size 0.254 0.3302)
			(layers "F.Cu" "F.Mask" "F.Paste")
			(net "MODE_RT_CPU0_P1")
		)
		(pad "FJ12" smd oval
			(at -10.885932 -1.08839 90)
			(size 0.254 0.3302)
			(layers "F.Cu" "F.Mask" "F.Paste")
			(net "GND")
		)
		(pad "FJ16" smd oval
			(at -10.885932 -0.488442 90)
			(size 0.254 0.3302)
			(layers "F.Cu" "F.Mask" "F.Paste")
			(net "CLK_100M_RETIMER_CPU0_P1_DP")
		)
		(pad "FJ19" smd oval
			(at -10.885932 0.111506 90)
			(size 0.254 0.3302)
			(layers "F.Cu" "F.Mask" "F.Paste")
			(net "GND")
		)
		(pad "FJ23" smd oval
			(at -10.885932 0.711708 90)
			(size 0.254 0.3302)
			(layers "F.Cu" "F.Mask" "F.Paste")
			(net "Net_2205")
		)
		(pad "FJ25" smd oval
			(at -10.885932 1.311656 90)
			(size 0.254 0.3302)
			(layers "F.Cu" "F.Mask" "F.Paste")
			(net "GPIO2_RT_CPU0_P1")
		)
		(pad "FJ28" smd oval
			(at -10.885932 1.911604 90)
			(size 0.254 0.3302)
			(layers "F.Cu" "F.Mask" "F.Paste")
			(net "GPIO3_RT_CPU0_P1")
		)
		(pad "FJ31" smd oval
			(at -10.885932 2.511552 90)
			(size 0.254 0.3302)
			(layers "F.Cu" "F.Mask" "F.Paste")
			(net "Net_51")
		)
		(pad "G1" smd oval
			(at 9.85012 -3.938524)
			(size 0.254 0.3302)
			(layers "F.Cu" "F.Mask" "F.Paste")
			(net "RT_CPU0_P1_VQPS")
		)
		(pad "G35" smd oval
			(at 9.85012 3.940048)
			(size 0.254 0.3302)
			(layers "F.Cu" "F.Mask" "F.Paste")
			(net "CLKREQ_RT_CPU0_P1_N")
		)
		(pad "H12" smd circle
			(at 9.846818 -1.08839)
			(size 0.3048 0.3048)
			(layers "F.Cu" "F.Mask" "F.Paste")
			(net "GND")
		)
		(pad "H16" smd circle
			(at 9.846818 -0.488442)
			(size 0.3048 0.3048)
			(layers "F.Cu" "F.Mask" "F.Paste")
			(net "GND")
		)
		(pad "H19" smd circle
			(at 9.846818 0.111506)
			(size 0.3048 0.3048)
			(layers "F.Cu" "F.Mask" "F.Paste")
			(net "GND")
		)
		(pad "H31" smd circle
			(at 9.846818 2.511552)
			(size 0.3048 0.3048)
			(layers "F.Cu" "F.Mask" "F.Paste")
			(net "GND")
		)
		(pad "J4" smd circle
			(at 9.602724 -2.817368)
			(size 0.381 0.381)
			(layers "F.Cu" "F.Mask" "F.Paste")
			(net "GND")
		)
		(pad "J22" smd circle
			(at 9.602724 0.703834)
			(size 0.3048 0.3048)
			(layers "F.Cu" "F.Mask" "F.Paste")
			(net "GND")
		)
		(pad "K2" smd circle
			(at 9.549892 -3.41884)
			(size 0.3048 0.3048)
			(layers "F.Cu" "F.Mask" "F.Paste")
			(net "GND")
		)
		(pad "K34" smd circle
			(at 9.549892 3.420364)
			(size 0.3048 0.3048)
			(layers "F.Cu" "F.Mask" "F.Paste")
			(net "GND")
		)
		(pad "L1" smd oval
			(at 9.249918 -3.938524)
			(size 0.254 0.3302)
			(layers "F.Cu" "F.Mask" "F.Paste")
			(net "GND")
		)
		(pad "L35" smd oval
			(at 9.249918 3.940048)
			(size 0.254 0.3302)
			(layers "F.Cu" "F.Mask" "F.Paste")
			(net "GND")
		)
		(pad "M7" smd circle
			(at 9.202674 -2.12471)
			(size 0.381 0.381)
			(layers "F.Cu" "F.Mask" "F.Paste")
			(net "P5E_CPU0_P1_TX_BUF_DP<15>")
		)
		(pad "M26" smd circle
			(at 9.202674 1.339342)
			(size 0.381 0.381)
			(layers "F.Cu" "F.Mask" "F.Paste")
			(net "P5E_CPU0_P1_RX_DP<15>")
		)
		(pad "N2" smd circle
			(at 8.949944 -3.41884)
			(size 0.3048 0.3048)
			(layers "F.Cu" "F.Mask" "F.Paste")
			(net "P5E_CPU0_P1_RX_BUF_DN<15>")
		)
		(pad "N34" smd circle
			(at 8.949944 3.420364)
			(size 0.3048 0.3048)
			(layers "F.Cu" "F.Mask" "F.Paste")
			(net "P5E_CPU0_P1_TX_C_DN<15>")
		)
		(pad "P10" smd circle
			(at 8.802624 -1.431798)
			(size 0.381 0.381)
			(layers "F.Cu" "F.Mask" "F.Paste")
			(net "P5E_CPU0_P1_TX_BUF_DN<15>")
		)
		(pad "P29" smd circle
			(at 8.802624 2.032254)
			(size 0.381 0.381)
			(layers "F.Cu" "F.Mask" "F.Paste")
			(net "P5E_CPU0_P1_RX_DN<15>")
		)
		(pad "R1" smd oval
			(at 8.64997 -3.938524)
			(size 0.254 0.3302)
			(layers "F.Cu" "F.Mask" "F.Paste")
			(net "P5E_CPU0_P1_RX_BUF_DP<15>")
		)
		(pad "R35" smd oval
			(at 8.64997 3.940048)
			(size 0.254 0.3302)
			(layers "F.Cu" "F.Mask" "F.Paste")
			(net "P5E_CPU0_P1_TX_C_DP<15>")
		)
		(pad "T4" smd circle
			(at 8.402574 -2.817368)
			(size 0.381 0.381)
			(layers "F.Cu" "F.Mask" "F.Paste")
			(net "GND")
		)
		(pad "T13" smd circle
			(at 8.402574 -0.79629)
			(size 0.3048 0.3048)
			(layers "F.Cu" "F.Mask" "F.Paste")
			(net "GND")
		)
		(pad "T17" smd circle
			(at 8.402574 -0.296164)
			(size 0.3048 0.3048)
			(layers "F.Cu" "F.Mask" "F.Paste")
			(net "P0V9_CPU0_RT1_2A")
		)
		(pad "T20" smd circle
			(at 8.402574 0.203708)
			(size 0.3048 0.3048)
			(layers "F.Cu" "F.Mask" "F.Paste")
			(net "P0V9_CPU0_RT1_2A")
		)
		(pad "T22" smd circle
			(at 8.402574 0.703834)
			(size 0.3048 0.3048)
			(layers "F.Cu" "F.Mask" "F.Paste")
			(net "GND")
		)
		(pad "T32" smd circle
			(at 8.402574 2.724912)
			(size 0.381 0.381)
			(layers "F.Cu" "F.Mask" "F.Paste")
			(net "GND")
		)
		(pad "U2" smd circle
			(at 8.349996 -3.41884)
			(size 0.3048 0.3048)
			(layers "F.Cu" "F.Mask" "F.Paste")
			(net "GND")
		)
		(pad "U34" smd circle
			(at 8.349996 3.420364)
			(size 0.3048 0.3048)
			(layers "F.Cu" "F.Mask" "F.Paste")
			(net "GND")
		)
		(pad "V1" smd oval
			(at 8.050022 -3.938524)
			(size 0.254 0.3302)
			(layers "F.Cu" "F.Mask" "F.Paste")
			(net "GND")
		)
		(pad "V35" smd oval
			(at 8.050022 3.940048)
			(size 0.254 0.3302)
			(layers "F.Cu" "F.Mask" "F.Paste")
			(net "GND")
		)
		(pad "W7" smd circle
			(at 8.002524 -2.12471)
			(size 0.381 0.381)
			(layers "F.Cu" "F.Mask" "F.Paste")
			(net "P5E_CPU0_P1_TX_BUF_DP<14>")
		)
		(pad "W26" smd circle
			(at 8.002524 1.339342)
			(size 0.381 0.381)
			(layers "F.Cu" "F.Mask" "F.Paste")
			(net "P5E_CPU0_P1_RX_DP<14>")
		)
		(pad "Y2" smd circle
			(at 7.750048 -3.41884)
			(size 0.3048 0.3048)
			(layers "F.Cu" "F.Mask" "F.Paste")
			(net "P5E_CPU0_P1_RX_BUF_DN<14>")
		)
		(pad "Y34" smd circle
			(at 7.750048 3.420364)
			(size 0.3048 0.3048)
			(layers "F.Cu" "F.Mask" "F.Paste")
			(net "P5E_CPU0_P1_TX_C_DP<14>")
		)
	)
	(footprint ""
		(layer "F.Cu")
		(at 102.390194 -384.10388 180)
		(property "Reference" "R653"
			(at 0 0 180)
			(layer "F.SilkS")
			(hide yes)
			(effects
				(font
					(size 1.27 1.27)
				)
			)
		)
		(property "Value" ""
			(at 0 0 180)
			(layer "F.Fab")
			(effects
				(font
					(size 1.27 1.27)
				)
			)
		)
		(duplicate_pad_numbers_are_jumpers no)
		(fp_line
			(start 0.7874 0.4064)
			(end -0.7874 0.4064)
			(stroke
				(width 0.1524)
				(type default)
			)
			(layer "F.SilkS")
		)
		(fp_line
			(start 0.7874 -0.4064)
			(end 0.7874 0.4064)
			(stroke
				(width 0.1524)
				(type default)
			)
			(layer "F.SilkS")
		)
		(fp_line
			(start -0.7874 0.4064)
			(end -0.7874 -0.4064)
			(stroke
				(width 0.1524)
				(type default)
			)
			(layer "F.SilkS")
		)
		(fp_line
			(start -0.7874 -0.4064)
			(end 0.7874 -0.4064)
			(stroke
				(width 0.1524)
				(type default)
			)
			(layer "F.SilkS")
		)
		(fp_line
			(start 0.67945 0.3048)
			(end 0.120396 0.3048)
			(stroke
				(width 0.1)
				(type default)
			)
			(layer "F.Fab")
		)
		(fp_line
			(start 0.67945 -0.3048)
			(end 0.67945 0.3048)
			(stroke
				(width 0.1)
				(type default)
			)
			(layer "F.Fab")
		)
		(fp_line
			(start 0.12065 -0.2794)
			(end 0.12065 -0.3048)
			(stroke
				(width 0.1)
				(type default)
			)
			(layer "F.Fab")
		)
		(fp_line
			(start 0.12065 -0.3048)
			(end 0.67945 -0.3048)
			(stroke
				(width 0.1)
				(type default)
			)
			(layer "F.Fab")
		)
		(fp_line
			(start 0.120396 0.3048)
			(end 0.120396 0.2794)
			(stroke
				(width 0.1)
				(type default)
			)
			(layer "F.Fab")
		)
		(fp_line
			(start 0.120396 0.2794)
			(end -0.12065 0.2794)
			(stroke
				(width 0.1)
				(type default)
			)
			(layer "F.Fab")
		)
		(fp_line
			(start -0.12065 0.3048)
			(end -0.67945 0.3048)
			(stroke
				(width 0.1)
				(type default)
			)
			(layer "F.Fab")
		)
		(fp_line
			(start -0.12065 0.2794)
			(end -0.12065 0.3048)
			(stroke
				(width 0.1)
				(type default)
			)
			(layer "F.Fab")
		)
		(fp_line
			(start -0.12065 -0.2794)
			(end 0.12065 -0.2794)
			(stroke
				(width 0.1)
				(type default)
			)
			(layer "F.Fab")
		)
		(fp_line
			(start -0.12065 -0.305054)
			(end -0.12065 -0.2794)
			(stroke
				(width 0.1)
				(type default)
			)
			(layer "F.Fab")
		)
		(fp_line
			(start -0.67945 0.3048)
			(end -0.67945 -0.305054)
			(stroke
				(width 0.1)
				(type default)
			)
			(layer "F.Fab")
		)
		(fp_line
			(start -0.67945 -0.305054)
			(end -0.12065 -0.305054)
			(stroke
				(width 0.1)
				(type default)
			)
			(layer "F.Fab")
		)
		(pad "1" smd rect
			(at -0.40005 0)
			(size 0.4572 0.508)
			(layers "F.Cu" "F.Mask" "F.Paste")
			(net "P1V8_CPU1_RT1_1A_1D")
		)
		(pad "2" smd rect
			(at 0.40005 0)
			(size 0.4572 0.508)
			(layers "F.Cu" "F.Mask" "F.Paste")
			(net "P1V8_CPU1_RT1_1A")
		)
	)
	(footprint ""
		(layer "F.Cu")
		(at 391.291318 -78.439264)
		(property "Reference" "R1320"
			(at 0 0 0)
			(layer "F.SilkS")
			(hide yes)
			(effects
				(font
					(size 1.27 1.27)
				)
			)
		)
		(property "Value" ""
			(at 0 0 0)
			(layer "F.Fab")
			(effects
				(font
					(size 1.27 1.27)
				)
			)
		)
		(duplicate_pad_numbers_are_jumpers no)
		(fp_line
			(start -0.7874 -0.4064)
			(end 0.7874 -0.4064)
			(stroke
				(width 0.1524)
				(type default)
			)
			(layer "F.SilkS")
		)
		(fp_line
			(start -0.7874 0.4064)
			(end -0.7874 -0.4064)
			(stroke
				(width 0.1524)
				(type default)
			)
			(layer "F.SilkS")
		)
		(fp_line
			(start 0.7874 -0.4064)
			(end 0.7874 0.4064)
			(stroke
				(width 0.1524)
				(type default)
			)
			(layer "F.SilkS")
		)
		(fp_line
			(start 0.7874 0.4064)
			(end -0.7874 0.4064)
			(stroke
				(width 0.1524)
				(type default)
			)
			(layer "F.SilkS")
		)
		(fp_line
			(start -0.67945 -0.305054)
			(end -0.12065 -0.305054)
			(stroke
				(width 0.1)
				(type default)
			)
			(layer "F.Fab")
		)
		(fp_line
			(start -0.67945 0.3048)
			(end -0.67945 -0.305054)
			(stroke
				(width 0.1)
				(type default)
			)
			(layer "F.Fab")
		)
		(fp_line
			(start -0.12065 -0.305054)
			(end -0.12065 -0.2794)
			(stroke
				(width 0.1)
				(type default)
			)
			(layer "F.Fab")
		)
		(fp_line
			(start -0.12065 -0.2794)
			(end 0.12065 -0.2794)
			(stroke
				(width 0.1)
				(type default)
			)
			(layer "F.Fab")
		)
		(fp_line
			(start -0.12065 0.2794)
			(end -0.12065 0.3048)
			(stroke
				(width 0.1)
				(type default)
			)
			(layer "F.Fab")
		)
		(fp_line
			(start -0.12065 0.3048)
			(end -0.67945 0.3048)
			(stroke
				(width 0.1)
				(type default)
			)
			(layer "F.Fab")
		)
		(fp_line
			(start 0.120396 0.2794)
			(end -0.12065 0.2794)
			(stroke
				(width 0.1)
				(type default)
			)
			(layer "F.Fab")
		)
		(fp_line
			(start 0.120396 0.3048)
			(end 0.120396 0.2794)
			(stroke
				(width 0.1)
				(type default)
			)
			(layer "F.Fab")
		)
		(fp_line
			(start 0.12065 -0.3048)
			(end 0.67945 -0.3048)
			(stroke
				(width 0.1)
				(type default)
			)
			(layer "F.Fab")
		)
		(fp_line
			(start 0.12065 -0.2794)
			(end 0.12065 -0.3048)
			(stroke
				(width 0.1)
				(type default)
			)
			(layer "F.Fab")
		)
		(fp_line
			(start 0.67945 -0.3048)
			(end 0.67945 0.3048)
			(stroke
				(width 0.1)
				(type default)
			)
			(layer "F.Fab")
		)
		(fp_line
			(start 0.67945 0.3048)
			(end 0.120396 0.3048)
			(stroke
				(width 0.1)
				(type default)
			)
			(layer "F.Fab")
		)
		(pad "1" smd circle
			(at -0.40005 0)
			(size 0 0)
			(layers "F.Cu" "F.Mask" "F.Paste")
			(net "P3V3_AUX")
		)
		(pad "2" smd circle
			(at 0.40005 0)
			(size 0 0)
			(layers "F.Cu" "F.Mask" "F.Paste")
			(net "INA230_6_A1")
		)
	)
	(footprint ""
		(layer "F.Cu")
		(at 103.819706 -178.077876 90)
		(property "Reference" "PC291_4"
			(at 0 0 90)
			(layer "F.SilkS")
			(hide yes)
			(effects
				(font
					(size 1.27 1.27)
				)
			)
		)
		(property "Value" ""
			(at 0 0 90)
			(layer "F.Fab")
			(effects
				(font
					(size 1.27 1.27)
				)
			)
		)
		(duplicate_pad_numbers_are_jumpers no)
		(fp_line
			(start 0.7874 -0.4064)
			(end 0.7874 0.4064)
			(stroke
				(width 0.1524)
				(type default)
			)
			(layer "F.SilkS")
		)
		(fp_line
			(start -0.7874 -0.4064)
			(end 0.7874 -0.4064)
			(stroke
				(width 0.1524)
				(type default)
			)
			(layer "F.SilkS")
		)
		(fp_line
			(start 0.7874 0.4064)
			(end -0.7874 0.4064)
			(stroke
				(width 0.1524)
				(type default)
			)
			(layer "F.SilkS")
		)
		(fp_line
			(start -0.7874 0.4064)
			(end -0.7874 -0.4064)
			(stroke
				(width 0.1524)
				(type default)
			)
			(layer "F.SilkS")
		)
		(fp_line
			(start -0.12065 -0.305054)
			(end -0.12065 -0.2794)
			(stroke
				(width 0.1)
				(type default)
			)
			(layer "F.Fab")
		)
		(fp_line
			(start -0.67945 -0.305054)
			(end -0.12065 -0.305054)
			(stroke
				(width 0.1)
				(type default)
			)
			(layer "F.Fab")
		)
		(fp_line
			(start 0.67945 -0.3048)
			(end 0.67945 0.3048)
			(stroke
				(width 0.1)
				(type default)
			)
			(layer "F.Fab")
		)
		(fp_line
			(start 0.12065 -0.3048)
			(end 0.67945 -0.3048)
			(stroke
				(width 0.1)
				(type default)
			)
			(layer "F.Fab")
		)
		(fp_line
			(start 0.12065 -0.2794)
			(end 0.12065 -0.3048)
			(stroke
				(width 0.1)
				(type default)
			)
			(layer "F.Fab")
		)
		(fp_line
			(start -0.12065 -0.2794)
			(end 0.12065 -0.2794)
			(stroke
				(width 0.1)
				(type default)
			)
			(layer "F.Fab")
		)
		(fp_line
			(start 0.120396 0.2794)
			(end -0.12065 0.2794)
			(stroke
				(width 0.1)
				(type default)
			)
			(layer "F.Fab")
		)
		(fp_line
			(start -0.12065 0.2794)
			(end -0.12065 0.3048)
			(stroke
				(width 0.1)
				(type default)
			)
			(layer "F.Fab")
		)
		(fp_line
			(start 0.67945 0.3048)
			(end 0.120396 0.3048)
			(stroke
				(width 0.1)
				(type default)
			)
			(layer "F.Fab")
		)
		(fp_line
			(start 0.120396 0.3048)
			(end 0.120396 0.2794)
			(stroke
				(width 0.1)
				(type default)
			)
			(layer "F.Fab")
		)
		(fp_line
			(start -0.12065 0.3048)
			(end -0.67945 0.3048)
			(stroke
				(width 0.1)
				(type default)
			)
			(layer "F.Fab")
		)
		(fp_line
			(start -0.67945 0.3048)
			(end -0.67945 -0.305054)
			(stroke
				(width 0.1)
				(type default)
			)
			(layer "F.Fab")
		)
		(pad "1" smd circle
			(at -0.40005 0 90)
			(size 0 0)
			(layers "F.Cu" "F.Mask" "F.Paste")
			(net "SW_P12V_AUX_PVDDCR_CPU0_P1_FLT")
		)
		(pad "2" smd circle
			(at 0.40005 0 90)
			(size 0 0)
			(layers "F.Cu" "F.Mask" "F.Paste")
			(net "GND")
		)
	)
	(footprint ""
		(layer "F.Cu")
		(at 49.407318 -351.10547)
		(property "Reference" "PC438_1"
			(at 0 0 0)
			(layer "F.SilkS")
			(hide yes)
			(effects
				(font
					(size 1.27 1.27)
				)
			)
		)
		(property "Value" ""
			(at 0 0 0)
			(layer "F.Fab")
			(effects
				(font
					(size 1.27 1.27)
				)
			)
		)
		(duplicate_pad_numbers_are_jumpers no)
		(fp_line
			(start -0.7874 -0.4064)
			(end 0.7874 -0.4064)
			(stroke
				(width 0.1524)
				(type default)
			)
			(layer "F.SilkS")
		)
		(fp_line
			(start -0.7874 0.4064)
			(end -0.7874 -0.4064)
			(stroke
				(width 0.1524)
				(type default)
			)
			(layer "F.SilkS")
		)
		(fp_line
			(start 0.7874 -0.4064)
			(end 0.7874 0.4064)
			(stroke
				(width 0.1524)
				(type default)
			)
			(layer "F.SilkS")
		)
		(fp_line
			(start 0.7874 0.4064)
			(end -0.7874 0.4064)
			(stroke
				(width 0.1524)
				(type default)
			)
			(layer "F.SilkS")
		)
		(fp_line
			(start -0.67945 -0.305054)
			(end -0.12065 -0.305054)
			(stroke
				(width 0.1)
				(type default)
			)
			(layer "F.Fab")
		)
		(fp_line
			(start -0.67945 0.3048)
			(end -0.67945 -0.305054)
			(stroke
				(width 0.1)
				(type default)
			)
			(layer "F.Fab")
		)
		(fp_line
			(start -0.12065 -0.305054)
			(end -0.12065 -0.2794)
			(stroke
				(width 0.1)
				(type default)
			)
			(layer "F.Fab")
		)
		(fp_line
			(start -0.12065 -0.2794)
			(end 0.12065 -0.2794)
			(stroke
				(width 0.1)
				(type default)
			)
			(layer "F.Fab")
		)
		(fp_line
			(start -0.12065 0.2794)
			(end -0.12065 0.3048)
			(stroke
				(width 0.1)
				(type default)
			)
			(layer "F.Fab")
		)
		(fp_line
			(start -0.12065 0.3048)
			(end -0.67945 0.3048)
			(stroke
				(width 0.1)
				(type default)
			)
			(layer "F.Fab")
		)
		(fp_line
			(start 0.120396 0.2794)
			(end -0.12065 0.2794)
			(stroke
				(width 0.1)
				(type default)
			)
			(layer "F.Fab")
		)
		(fp_line
			(start 0.120396 0.3048)
			(end 0.120396 0.2794)
			(stroke
				(width 0.1)
				(type default)
			)
			(layer "F.Fab")
		)
		(fp_line
			(start 0.12065 -0.3048)
			(end 0.67945 -0.3048)
			(stroke
				(width 0.1)
				(type default)
			)
			(layer "F.Fab")
		)
		(fp_line
			(start 0.12065 -0.2794)
			(end 0.12065 -0.3048)
			(stroke
				(width 0.1)
				(type default)
			)
			(layer "F.Fab")
		)
		(fp_line
			(start 0.67945 -0.3048)
			(end 0.67945 0.3048)
			(stroke
				(width 0.1)
				(type default)
			)
			(layer "F.Fab")
		)
		(fp_line
			(start 0.67945 0.3048)
			(end 0.120396 0.3048)
			(stroke
				(width 0.1)
				(type default)
			)
			(layer "F.Fab")
		)
		(pad "1" smd circle
			(at -0.40005 0)
			(size 0 0)
			(layers "F.Cu" "F.Mask" "F.Paste")
			(net "SW_P12V_AUX_PVDDIO_P1_FLT")
		)
		(pad "2" smd circle
			(at 0.40005 0)
			(size 0 0)
			(layers "F.Cu" "F.Mask" "F.Paste")
			(net "GND")
		)
	)
	(footprint ""
		(layer "F.Cu")
		(at 393.363958 -324.659752)
		(property "Reference" "R450"
			(at 0 0 0)
			(layer "F.SilkS")
			(hide yes)
			(effects
				(font
					(size 1.27 1.27)
				)
			)
		)
		(property "Value" ""
			(at 0 0 0)
			(layer "F.Fab")
			(effects
				(font
					(size 1.27 1.27)
				)
			)
		)
		(duplicate_pad_numbers_are_jumpers no)
		(fp_line
			(start -0.7874 -0.4064)
			(end 0.7874 -0.4064)
			(stroke
				(width 0.1524)
				(type default)
			)
			(layer "F.SilkS")
		)
		(fp_line
			(start -0.7874 0.4064)
			(end -0.7874 -0.4064)
			(stroke
				(width 0.1524)
				(type default)
			)
			(layer "F.SilkS")
		)
		(fp_line
			(start 0.7874 -0.4064)
			(end 0.7874 0.4064)
			(stroke
				(width 0.1524)
				(type default)
			)
			(layer "F.SilkS")
		)
		(fp_line
			(start 0.7874 0.4064)
			(end -0.7874 0.4064)
			(stroke
				(width 0.1524)
				(type default)
			)
			(layer "F.SilkS")
		)
		(fp_line
			(start -0.67945 -0.305054)
			(end -0.12065 -0.305054)
			(stroke
				(width 0.1)
				(type default)
			)
			(layer "F.Fab")
		)
		(fp_line
			(start -0.67945 0.3048)
			(end -0.67945 -0.305054)
			(stroke
				(width 0.1)
				(type default)
			)
			(layer "F.Fab")
		)
		(fp_line
			(start -0.12065 -0.305054)
			(end -0.12065 -0.2794)
			(stroke
				(width 0.1)
				(type default)
			)
			(layer "F.Fab")
		)
		(fp_line
			(start -0.12065 -0.2794)
			(end 0.12065 -0.2794)
			(stroke
				(width 0.1)
				(type default)
			)
			(layer "F.Fab")
		)
		(fp_line
			(start -0.12065 0.2794)
			(end -0.12065 0.3048)
			(stroke
				(width 0.1)
				(type default)
			)
			(layer "F.Fab")
		)
		(fp_line
			(start -0.12065 0.3048)
			(end -0.67945 0.3048)
			(stroke
				(width 0.1)
				(type default)
			)
			(layer "F.Fab")
		)
		(fp_line
			(start 0.120396 0.2794)
			(end -0.12065 0.2794)
			(stroke
				(width 0.1)
				(type default)
			)
			(layer "F.Fab")
		)
		(fp_line
			(start 0.120396 0.3048)
			(end 0.120396 0.2794)
			(stroke
				(width 0.1)
				(type default)
			)
			(layer "F.Fab")
		)
		(fp_line
			(start 0.12065 -0.3048)
			(end 0.67945 -0.3048)
			(stroke
				(width 0.1)
				(type default)
			)
			(layer "F.Fab")
		)
		(fp_line
			(start 0.12065 -0.2794)
			(end 0.12065 -0.3048)
			(stroke
				(width 0.1)
				(type default)
			)
			(layer "F.Fab")
		)
		(fp_line
			(start 0.67945 -0.3048)
			(end 0.67945 0.3048)
			(stroke
				(width 0.1)
				(type default)
			)
			(layer "F.Fab")
		)
		(fp_line
			(start 0.67945 0.3048)
			(end 0.120396 0.3048)
			(stroke
				(width 0.1)
				(type default)
			)
			(layer "F.Fab")
		)
		(pad "1" smd circle
			(at -0.40005 0)
			(size 0 0)
			(layers "F.Cu" "F.Mask" "F.Paste")
			(net "CPU0_SMERR_N")
		)
		(pad "2" smd circle
			(at 0.40005 0)
			(size 0 0)
			(layers "F.Cu" "F.Mask" "F.Paste")
			(net "PVDD18_S5_P0")
		)
	)
	(footprint ""
		(layer "F.Cu")
		(at 141.197838 -167.03167)
		(property "Reference" "TP11"
			(at 1.13792 -0.014732 0)
			(unlocked yes)
			(layer "F.SilkS")
			(effects
				(font
					(size 0.7874 0.5842)
					(thickness 0.1524)
				)
				(justify left)
			)
		)
		(property "Value" ""
			(at 0 0 0)
			(layer "F.Fab")
			(effects
				(font
					(size 1.27 1.27)
				)
			)
		)
		(duplicate_pad_numbers_are_jumpers no)
		(pad "1" smd circle
			(at 0 0)
			(size 0.762 0.762)
			(layers "F.Cu" "F.Mask" "F.Paste")
			(net "VSENSE_VSS_SENSE_A_P1")
		)
	)
	(footprint ""
		(layer "F.Cu")
		(at 112.72774 -394.166852 -90)
		(property "Reference" "R926"
			(at 0 0 270)
			(layer "F.SilkS")
			(hide yes)
			(effects
				(font
					(size 1.27 1.27)
				)
			)
		)
		(property "Value" ""
			(at 0 0 270)
			(layer "F.Fab")
			(effects
				(font
					(size 1.27 1.27)
				)
			)
		)
		(duplicate_pad_numbers_are_jumpers no)
		(fp_line
			(start -0.32512 0.175006)
			(end -0.32512 -0.175006)
			(stroke
				(width 0.1)
				(type default)
			)
			(layer "F.Fab")
		)
		(fp_line
			(start 0.32512 0.175006)
			(end -0.32512 0.175006)
			(stroke
				(width 0.1)
				(type default)
			)
			(layer "F.Fab")
		)
		(fp_line
			(start -0.32512 -0.175006)
			(end 0.32512 -0.175006)
			(stroke
				(width 0.1)
				(type default)
			)
			(layer "F.Fab")
		)
		(fp_line
			(start 0.32512 -0.175006)
			(end 0.32512 0.175006)
			(stroke
				(width 0.1)
				(type default)
			)
			(layer "F.Fab")
		)
		(pad "1" smd rect
			(at -0.2667 0 270)
			(size 0.3048 0.381)
			(layers "F.Cu" "F.Mask" "F.Paste")
			(net "MODE_RT_CPU1_P3")
		)
		(pad "2" smd rect
			(at 0.2667 0 90)
			(size 0.3048 0.381)
			(layers "F.Cu" "F.Mask" "F.Paste")
			(net "GND")
		)
	)
	(footprint ""
		(layer "F.Cu")
		(at 77.64399 -177.627534 90)
		(property "Reference" "PC308_C0P1_5"
			(at 0 0 90)
			(layer "F.SilkS")
			(hide yes)
			(effects
				(font
					(size 1.27 1.27)
				)
			)
		)
		(property "Value" ""
			(at 0 0 90)
			(layer "F.Fab")
			(effects
				(font
					(size 1.27 1.27)
				)
			)
		)
		(duplicate_pad_numbers_are_jumpers no)
		(fp_line
			(start 0.7874 -0.4064)
			(end 0.7874 0.4064)
			(stroke
				(width 0.1524)
				(type default)
			)
			(layer "F.SilkS")
		)
		(fp_line
			(start -0.7874 -0.4064)
			(end 0.7874 -0.4064)
			(stroke
				(width 0.1524)
				(type default)
			)
			(layer "F.SilkS")
		)
		(fp_line
			(start 0.7874 0.4064)
			(end -0.7874 0.4064)
			(stroke
				(width 0.1524)
				(type default)
			)
			(layer "F.SilkS")
		)
		(fp_line
			(start -0.7874 0.4064)
			(end -0.7874 -0.4064)
			(stroke
				(width 0.1524)
				(type default)
			)
			(layer "F.SilkS")
		)
		(fp_line
			(start -0.12065 -0.305054)
			(end -0.12065 -0.2794)
			(stroke
				(width 0.1)
				(type default)
			)
			(layer "F.Fab")
		)
		(fp_line
			(start -0.67945 -0.305054)
			(end -0.12065 -0.305054)
			(stroke
				(width 0.1)
				(type default)
			)
			(layer "F.Fab")
		)
		(fp_line
			(start 0.67945 -0.3048)
			(end 0.67945 0.3048)
			(stroke
				(width 0.1)
				(type default)
			)
			(layer "F.Fab")
		)
		(fp_line
			(start 0.12065 -0.3048)
			(end 0.67945 -0.3048)
			(stroke
				(width 0.1)
				(type default)
			)
			(layer "F.Fab")
		)
		(fp_line
			(start 0.12065 -0.2794)
			(end 0.12065 -0.3048)
			(stroke
				(width 0.1)
				(type default)
			)
			(layer "F.Fab")
		)
		(fp_line
			(start -0.12065 -0.2794)
			(end 0.12065 -0.2794)
			(stroke
				(width 0.1)
				(type default)
			)
			(layer "F.Fab")
		)
		(fp_line
			(start 0.120396 0.2794)
			(end -0.12065 0.2794)
			(stroke
				(width 0.1)
				(type default)
			)
			(layer "F.Fab")
		)
		(fp_line
			(start -0.12065 0.2794)
			(end -0.12065 0.3048)
			(stroke
				(width 0.1)
				(type default)
			)
			(layer "F.Fab")
		)
		(fp_line
			(start 0.67945 0.3048)
			(end 0.120396 0.3048)
			(stroke
				(width 0.1)
				(type default)
			)
			(layer "F.Fab")
		)
		(fp_line
			(start 0.120396 0.3048)
			(end 0.120396 0.2794)
			(stroke
				(width 0.1)
				(type default)
			)
			(layer "F.Fab")
		)
		(fp_line
			(start -0.12065 0.3048)
			(end -0.67945 0.3048)
			(stroke
				(width 0.1)
				(type default)
			)
			(layer "F.Fab")
		)
		(fp_line
			(start -0.67945 0.3048)
			(end -0.67945 -0.305054)
			(stroke
				(width 0.1)
				(type default)
			)
			(layer "F.Fab")
		)
		(pad "1" smd circle
			(at -0.40005 0 90)
			(size 0 0)
			(layers "F.Cu" "F.Mask" "F.Paste")
			(net "PVDDCR_CPU0_P1_PVCC")
		)
		(pad "2" smd circle
			(at 0.40005 0 90)
			(size 0 0)
			(layers "F.Cu" "F.Mask" "F.Paste")
			(net "GND")
		)
	)
	(footprint ""
		(layer "F.Cu")
		(at 138.092688 -386.44068 90)
		(property "Reference" "C434"
			(at 0 0 90)
			(layer "F.SilkS")
			(hide yes)
			(effects
				(font
					(size 1.27 1.27)
				)
			)
		)
		(property "Value" ""
			(at 0 0 90)
			(layer "F.Fab")
			(effects
				(font
					(size 1.27 1.27)
				)
			)
		)
		(duplicate_pad_numbers_are_jumpers no)
		(fp_line
			(start 0.7874 -0.4064)
			(end 0.7874 0.4064)
			(stroke
				(width 0.1524)
				(type default)
			)
			(layer "F.SilkS")
		)
		(fp_line
			(start -0.7874 -0.4064)
			(end 0.7874 -0.4064)
			(stroke
				(width 0.1524)
				(type default)
			)
			(layer "F.SilkS")
		)
		(fp_line
			(start 0.7874 0.4064)
			(end -0.7874 0.4064)
			(stroke
				(width 0.1524)
				(type default)
			)
			(layer "F.SilkS")
		)
		(fp_line
			(start -0.7874 0.4064)
			(end -0.7874 -0.4064)
			(stroke
				(width 0.1524)
				(type default)
			)
			(layer "F.SilkS")
		)
		(fp_line
			(start -0.12065 -0.305054)
			(end -0.12065 -0.2794)
			(stroke
				(width 0.1)
				(type default)
			)
			(layer "F.Fab")
		)
		(fp_line
			(start -0.67945 -0.305054)
			(end -0.12065 -0.305054)
			(stroke
				(width 0.1)
				(type default)
			)
			(layer "F.Fab")
		)
		(fp_line
			(start 0.67945 -0.3048)
			(end 0.67945 0.3048)
			(stroke
				(width 0.1)
				(type default)
			)
			(layer "F.Fab")
		)
		(fp_line
			(start 0.12065 -0.3048)
			(end 0.67945 -0.3048)
			(stroke
				(width 0.1)
				(type default)
			)
			(layer "F.Fab")
		)
		(fp_line
			(start 0.12065 -0.2794)
			(end 0.12065 -0.3048)
			(stroke
				(width 0.1)
				(type default)
			)
			(layer "F.Fab")
		)
		(fp_line
			(start -0.12065 -0.2794)
			(end 0.12065 -0.2794)
			(stroke
				(width 0.1)
				(type default)
			)
			(layer "F.Fab")
		)
		(fp_line
			(start 0.120396 0.2794)
			(end -0.12065 0.2794)
			(stroke
				(width 0.1)
				(type default)
			)
			(layer "F.Fab")
		)
		(fp_line
			(start -0.12065 0.2794)
			(end -0.12065 0.3048)
			(stroke
				(width 0.1)
				(type default)
			)
			(layer "F.Fab")
		)
		(fp_line
			(start 0.67945 0.3048)
			(end 0.120396 0.3048)
			(stroke
				(width 0.1)
				(type default)
			)
			(layer "F.Fab")
		)
		(fp_line
			(start 0.120396 0.3048)
			(end 0.120396 0.2794)
			(stroke
				(width 0.1)
				(type default)
			)
			(layer "F.Fab")
		)
		(fp_line
			(start -0.12065 0.3048)
			(end -0.67945 0.3048)
			(stroke
				(width 0.1)
				(type default)
			)
			(layer "F.Fab")
		)
		(fp_line
			(start -0.67945 0.3048)
			(end -0.67945 -0.305054)
			(stroke
				(width 0.1)
				(type default)
			)
			(layer "F.Fab")
		)
		(pad "1" smd circle
			(at -0.40005 0 90)
			(size 0 0)
			(layers "F.Cu" "F.Mask" "F.Paste")
			(net "P1V8_CPU1_RT_1D")
		)
		(pad "2" smd circle
			(at 0.40005 0 90)
			(size 0 0)
			(layers "F.Cu" "F.Mask" "F.Paste")
			(net "GND")
		)
	)
	(footprint ""
		(layer "F.Cu")
		(at 271.092676 -120.78335 180)
		(property "Reference" "R3703"
			(at 0 0 180)
			(layer "F.SilkS")
			(hide yes)
			(effects
				(font
					(size 1.27 1.27)
				)
			)
		)
		(property "Value" ""
			(at 0 0 180)
			(layer "F.Fab")
			(effects
				(font
					(size 1.27 1.27)
				)
			)
		)
		(duplicate_pad_numbers_are_jumpers no)
		(fp_line
			(start 0.7874 0.4064)
			(end -0.7874 0.4064)
			(stroke
				(width 0.1524)
				(type default)
			)
			(layer "F.SilkS")
		)
		(fp_line
			(start 0.7874 -0.4064)
			(end 0.7874 0.4064)
			(stroke
				(width 0.1524)
				(type default)
			)
			(layer "F.SilkS")
		)
		(fp_line
			(start -0.7874 0.4064)
			(end -0.7874 -0.4064)
			(stroke
				(width 0.1524)
				(type default)
			)
			(layer "F.SilkS")
		)
		(fp_line
			(start -0.7874 -0.4064)
			(end 0.7874 -0.4064)
			(stroke
				(width 0.1524)
				(type default)
			)
			(layer "F.SilkS")
		)
		(fp_line
			(start 0.67945 0.3048)
			(end 0.120396 0.3048)
			(stroke
				(width 0.1)
				(type default)
			)
			(layer "F.Fab")
		)
		(fp_line
			(start 0.67945 -0.3048)
			(end 0.67945 0.3048)
			(stroke
				(width 0.1)
				(type default)
			)
			(layer "F.Fab")
		)
		(fp_line
			(start 0.12065 -0.2794)
			(end 0.12065 -0.3048)
			(stroke
				(width 0.1)
				(type default)
			)
			(layer "F.Fab")
		)
		(fp_line
			(start 0.12065 -0.3048)
			(end 0.67945 -0.3048)
			(stroke
				(width 0.1)
				(type default)
			)
			(layer "F.Fab")
		)
		(fp_line
			(start 0.120396 0.3048)
			(end 0.120396 0.2794)
			(stroke
				(width 0.1)
				(type default)
			)
			(layer "F.Fab")
		)
		(fp_line
			(start 0.120396 0.2794)
			(end -0.12065 0.2794)
			(stroke
				(width 0.1)
				(type default)
			)
			(layer "F.Fab")
		)
		(fp_line
			(start -0.12065 0.3048)
			(end -0.67945 0.3048)
			(stroke
				(width 0.1)
				(type default)
			)
			(layer "F.Fab")
		)
		(fp_line
			(start -0.12065 0.2794)
			(end -0.12065 0.3048)
			(stroke
				(width 0.1)
				(type default)
			)
			(layer "F.Fab")
		)
		(fp_line
			(start -0.12065 -0.2794)
			(end 0.12065 -0.2794)
			(stroke
				(width 0.1)
				(type default)
			)
			(layer "F.Fab")
		)
		(fp_line
			(start -0.12065 -0.305054)
			(end -0.12065 -0.2794)
			(stroke
				(width 0.1)
				(type default)
			)
			(layer "F.Fab")
		)
		(fp_line
			(start -0.67945 0.3048)
			(end -0.67945 -0.305054)
			(stroke
				(width 0.1)
				(type default)
			)
			(layer "F.Fab")
		)
		(fp_line
			(start -0.67945 -0.305054)
			(end -0.12065 -0.305054)
			(stroke
				(width 0.1)
				(type default)
			)
			(layer "F.Fab")
		)
		(pad "1" smd circle
			(at -0.40005 0 180)
			(size 0 0)
			(layers "F.Cu" "F.Mask" "F.Paste")
			(net "P3V3_AUX")
		)
		(pad "2" smd circle
			(at 0.40005 0 180)
			(size 0 0)
			(layers "F.Cu" "F.Mask" "F.Paste")
			(net "PCA9548_PCIE0_ADDR2")
		)
	)
	(footprint ""
		(layer "F.Cu")
		(at 218.336368 -61.072014 180)
		(property "Reference" "PC2218"
			(at 0 0 180)
			(layer "F.SilkS")
			(hide yes)
			(effects
				(font
					(size 1.27 1.27)
				)
			)
		)
		(property "Value" ""
			(at 0 0 180)
			(layer "F.Fab")
			(effects
				(font
					(size 1.27 1.27)
				)
			)
		)
		(duplicate_pad_numbers_are_jumpers no)
		(fp_line
			(start 0.7874 0.4064)
			(end -0.7874 0.4064)
			(stroke
				(width 0.1524)
				(type default)
			)
			(layer "F.SilkS")
		)
		(fp_line
			(start 0.7874 -0.4064)
			(end 0.7874 0.4064)
			(stroke
				(width 0.1524)
				(type default)
			)
			(layer "F.SilkS")
		)
		(fp_line
			(start -0.7874 0.4064)
			(end -0.7874 -0.4064)
			(stroke
				(width 0.1524)
				(type default)
			)
			(layer "F.SilkS")
		)
		(fp_line
			(start -0.7874 -0.4064)
			(end 0.7874 -0.4064)
			(stroke
				(width 0.1524)
				(type default)
			)
			(layer "F.SilkS")
		)
		(fp_line
			(start 0.67945 0.3048)
			(end 0.120396 0.3048)
			(stroke
				(width 0.1)
				(type default)
			)
			(layer "F.Fab")
		)
		(fp_line
			(start 0.67945 -0.3048)
			(end 0.67945 0.3048)
			(stroke
				(width 0.1)
				(type default)
			)
			(layer "F.Fab")
		)
		(fp_line
			(start 0.12065 -0.2794)
			(end 0.12065 -0.3048)
			(stroke
				(width 0.1)
				(type default)
			)
			(layer "F.Fab")
		)
		(fp_line
			(start 0.12065 -0.3048)
			(end 0.67945 -0.3048)
			(stroke
				(width 0.1)
				(type default)
			)
			(layer "F.Fab")
		)
		(fp_line
			(start 0.120396 0.3048)
			(end 0.120396 0.2794)
			(stroke
				(width 0.1)
				(type default)
			)
			(layer "F.Fab")
		)
		(fp_line
			(start 0.120396 0.2794)
			(end -0.12065 0.2794)
			(stroke
				(width 0.1)
				(type default)
			)
			(layer "F.Fab")
		)
		(fp_line
			(start -0.12065 0.3048)
			(end -0.67945 0.3048)
			(stroke
				(width 0.1)
				(type default)
			)
			(layer "F.Fab")
		)
		(fp_line
			(start -0.12065 0.2794)
			(end -0.12065 0.3048)
			(stroke
				(width 0.1)
				(type default)
			)
			(layer "F.Fab")
		)
		(fp_line
			(start -0.12065 -0.2794)
			(end 0.12065 -0.2794)
			(stroke
				(width 0.1)
				(type default)
			)
			(layer "F.Fab")
		)
		(fp_line
			(start -0.12065 -0.305054)
			(end -0.12065 -0.2794)
			(stroke
				(width 0.1)
				(type default)
			)
			(layer "F.Fab")
		)
		(fp_line
			(start -0.67945 0.3048)
			(end -0.67945 -0.305054)
			(stroke
				(width 0.1)
				(type default)
			)
			(layer "F.Fab")
		)
		(fp_line
			(start -0.67945 -0.305054)
			(end -0.12065 -0.305054)
			(stroke
				(width 0.1)
				(type default)
			)
			(layer "F.Fab")
		)
		(pad "1" smd circle
			(at -0.40005 0 180)
			(size 0 0)
			(layers "F.Cu" "F.Mask" "F.Paste")
			(net "P3V3_E1S_0_R")
		)
		(pad "2" smd circle
			(at 0.40005 0 180)
			(size 0 0)
			(layers "F.Cu" "F.Mask" "F.Paste")
			(net "GND")
		)
	)
	(footprint ""
		(layer "F.Cu")
		(at 342.085676 -340.236048)
		(property "Reference" "PR93"
			(at 0 0 0)
			(layer "F.SilkS")
			(hide yes)
			(effects
				(font
					(size 1.27 1.27)
				)
			)
		)
		(property "Value" ""
			(at 0 0 0)
			(layer "F.Fab")
			(effects
				(font
					(size 1.27 1.27)
				)
			)
		)
		(duplicate_pad_numbers_are_jumpers no)
		(fp_line
			(start -0.7874 -0.4064)
			(end 0.7874 -0.4064)
			(stroke
				(width 0.1524)
				(type default)
			)
			(layer "F.SilkS")
		)
		(fp_line
			(start -0.7874 0.4064)
			(end -0.7874 -0.4064)
			(stroke
				(width 0.1524)
				(type default)
			)
			(layer "F.SilkS")
		)
		(fp_line
			(start 0.7874 -0.4064)
			(end 0.7874 0.4064)
			(stroke
				(width 0.1524)
				(type default)
			)
			(layer "F.SilkS")
		)
		(fp_line
			(start 0.7874 0.4064)
			(end -0.7874 0.4064)
			(stroke
				(width 0.1524)
				(type default)
			)
			(layer "F.SilkS")
		)
		(fp_line
			(start -0.67945 -0.305054)
			(end -0.12065 -0.305054)
			(stroke
				(width 0.1)
				(type default)
			)
			(layer "F.Fab")
		)
		(fp_line
			(start -0.67945 0.3048)
			(end -0.67945 -0.305054)
			(stroke
				(width 0.1)
				(type default)
			)
			(layer "F.Fab")
		)
		(fp_line
			(start -0.12065 -0.305054)
			(end -0.12065 -0.2794)
			(stroke
				(width 0.1)
				(type default)
			)
			(layer "F.Fab")
		)
		(fp_line
			(start -0.12065 -0.2794)
			(end 0.12065 -0.2794)
			(stroke
				(width 0.1)
				(type default)
			)
			(layer "F.Fab")
		)
		(fp_line
			(start -0.12065 0.2794)
			(end -0.12065 0.3048)
			(stroke
				(width 0.1)
				(type default)
			)
			(layer "F.Fab")
		)
		(fp_line
			(start -0.12065 0.3048)
			(end -0.67945 0.3048)
			(stroke
				(width 0.1)
				(type default)
			)
			(layer "F.Fab")
		)
		(fp_line
			(start 0.120396 0.2794)
			(end -0.12065 0.2794)
			(stroke
				(width 0.1)
				(type default)
			)
			(layer "F.Fab")
		)
		(fp_line
			(start 0.120396 0.3048)
			(end 0.120396 0.2794)
			(stroke
				(width 0.1)
				(type default)
			)
			(layer "F.Fab")
		)
		(fp_line
			(start 0.12065 -0.3048)
			(end 0.67945 -0.3048)
			(stroke
				(width 0.1)
				(type default)
			)
			(layer "F.Fab")
		)
		(fp_line
			(start 0.12065 -0.2794)
			(end 0.12065 -0.3048)
			(stroke
				(width 0.1)
				(type default)
			)
			(layer "F.Fab")
		)
		(fp_line
			(start 0.67945 -0.3048)
			(end 0.67945 0.3048)
			(stroke
				(width 0.1)
				(type default)
			)
			(layer "F.Fab")
		)
		(fp_line
			(start 0.67945 0.3048)
			(end 0.120396 0.3048)
			(stroke
				(width 0.1)
				(type default)
			)
			(layer "F.Fab")
		)
		(pad "1" smd circle
			(at -0.40005 0)
			(size 0 0)
			(layers "F.Cu" "F.Mask" "F.Paste")
			(net "PVDDCR_CPU1_P0_LSET5")
		)
		(pad "2" smd circle
			(at 0.40005 0)
			(size 0 0)
			(layers "F.Cu" "F.Mask" "F.Paste")
			(net "GND")
		)
	)
	(footprint ""
		(layer "F.Cu")
		(at 153.88463 -95.612458)
		(property "Reference" "U244"
			(at 0.0762 1.95961 0)
			(unlocked yes)
			(layer "F.SilkS")
			(effects
				(font
					(size 0.7874 0.5842)
					(thickness 0.1524)
				)
			)
		)
		(property "Value" ""
			(at 0 0 0)
			(layer "F.Fab")
			(effects
				(font
					(size 1.27 1.27)
				)
			)
		)
		(duplicate_pad_numbers_are_jumpers no)
		(fp_line
			(start -1.7272 1.1176)
			(end -1.7272 -1.1176)
			(stroke
				(width 0.1524)
				(type default)
			)
			(layer "F.SilkS")
		)
		(fp_line
			(start -0.254 -1.1176)
			(end -1.7272 -1.1176)
			(stroke
				(width 0.1524)
				(type default)
			)
			(layer "F.SilkS")
		)
		(fp_line
			(start 0 -0.7366)
			(end -0.254 -1.1176)
			(stroke
				(width 0.1524)
				(type default)
			)
			(layer "F.SilkS")
		)
		(fp_line
			(start 0.254 -1.1176)
			(end 0 -0.7366)
			(stroke
				(width 0.1524)
				(type default)
			)
			(layer "F.SilkS")
		)
		(fp_line
			(start 1.7272 -1.1176)
			(end 0.254 -1.1176)
			(stroke
				(width 0.1524)
				(type default)
			)
			(layer "F.SilkS")
		)
		(fp_line
			(start 1.7272 -1.1176)
			(end 1.7272 1.1176)
			(stroke
				(width 0.1524)
				(type default)
			)
			(layer "F.SilkS")
		)
		(fp_line
			(start 1.7272 1.1176)
			(end -1.7272 1.1176)
			(stroke
				(width 0.1524)
				(type default)
			)
			(layer "F.SilkS")
		)
		(fp_poly
			(pts
				(xy -2.7178 -1.030986) (xy -1.9558 -0.649986) (xy -2.7178 -0.268986)
			)
			(stroke
				(width 0)
				(type default)
			)
			(fill yes)
			(layer "F.SilkS")
		)
		(fp_line
			(start -1.5748 -1.1176)
			(end -1.5748 1.1176)
			(stroke
				(width 0.1)
				(type default)
			)
			(layer "F.Fab")
		)
		(fp_line
			(start -1.5748 1.1176)
			(end 1.5748 1.1176)
			(stroke
				(width 0.1)
				(type default)
			)
			(layer "F.Fab")
		)
		(fp_line
			(start 1.5748 -1.1176)
			(end -1.5748 -1.1176)
			(stroke
				(width 0.1)
				(type default)
			)
			(layer "F.Fab")
		)
		(fp_line
			(start 1.5748 1.1176)
			(end 1.5748 -1.1176)
			(stroke
				(width 0.1)
				(type default)
			)
			(layer "F.Fab")
		)
		(fp_poly
			(pts
				(xy -1.9558 -0.649986) (xy -2.7178 -0.268986) (xy -2.7178 -1.030986)
			)
			(stroke
				(width 0)
				(type default)
			)
			(fill yes)
			(layer "F.Fab")
		)
		(pad "1" smd rect
			(at -0.999998 -0.649986 270)
			(size 0.3556 1.1176)
			(layers "F.Cu" "F.Mask" "F.Paste")
			(net "OCP_SFF_NOT_PRSNT_RBT_ARB_IN")
		)
		(pad "2" smd rect
			(at -0.999998 0 270)
			(size 0.3556 1.1176)
			(layers "F.Cu" "F.Mask" "F.Paste")
			(net "GND")
		)
		(pad "3" smd rect
			(at -0.999998 0.649986 270)
			(size 0.3556 1.1176)
			(layers "F.Cu" "F.Mask" "F.Paste")
			(net "OCP_SFF_RBT_ARB_IN")
		)
		(pad "4" smd rect
			(at 0.999998 0.649986 270)
			(size 0.3556 1.1176)
			(layers "F.Cu" "F.Mask" "F.Paste")
			(net "OCP_SFF_RBT_ARB_IN_MUX1_R")
		)
		(pad "5" smd rect
			(at 0.999998 0 270)
			(size 0.3556 1.1176)
			(layers "F.Cu" "F.Mask" "F.Paste")
			(net "P3V3_AUX")
		)
		(pad "6" smd rect
			(at 0.999998 -0.649986 270)
			(size 0.3556 1.1176)
			(layers "F.Cu" "F.Mask" "F.Paste")
			(net "OCP_SFF_PRSNT_ALL_R3_N")
		)
	)
	(footprint ""
		(layer "F.Cu")
		(at 413.270192 -140.783056)
		(property "Reference" "U326"
			(at 4.306062 0.730758 90)
			(unlocked yes)
			(layer "F.SilkS")
			(effects
				(font
					(size 0.7874 0.5842)
					(thickness 0.1524)
				)
				(justify left)
			)
		)
		(property "Value" ""
			(at 0 0 0)
			(layer "F.Fab")
			(effects
				(font
					(size 1.27 1.27)
				)
			)
		)
		(duplicate_pad_numbers_are_jumpers no)
		(fp_line
			(start -1.549908 -2.050034)
			(end -1.549908 -1.9812)
			(stroke
				(width 0.1524)
				(type default)
			)
			(layer "F.SilkS")
		)
		(fp_line
			(start -1.549908 1.9812)
			(end -1.549908 2.050034)
			(stroke
				(width 0.1524)
				(type default)
			)
			(layer "F.SilkS")
		)
		(fp_line
			(start -1.549908 2.050034)
			(end -0.5842 2.050034)
			(stroke
				(width 0.1524)
				(type default)
			)
			(layer "F.SilkS")
		)
		(fp_line
			(start -0.5842 -2.050034)
			(end -1.549908 -2.050034)
			(stroke
				(width 0.1524)
				(type default)
			)
			(layer "F.SilkS")
		)
		(fp_line
			(start 0 2.050034)
			(end 1.549908 2.050034)
			(stroke
				(width 0.1524)
				(type default)
			)
			(layer "F.SilkS")
		)
		(fp_line
			(start 1.549908 -2.050034)
			(end 0.5842 -2.050034)
			(stroke
				(width 0.1524)
				(type default)
			)
			(layer "F.SilkS")
		)
		(fp_line
			(start 1.549908 -1.9812)
			(end 1.549908 -2.050034)
			(stroke
				(width 0.1524)
				(type default)
			)
			(layer "F.SilkS")
		)
		(fp_line
			(start 1.549908 2.050034)
			(end 1.549908 1.9304)
			(stroke
				(width 0.1524)
				(type default)
			)
			(layer "F.SilkS")
		)
		(fp_poly
			(pts
				(xy -3.364738 -3.2004) (xy -4.083304 -2.482088) (xy -3.005582 -2.122678)
			)
			(stroke
				(width 0)
				(type default)
			)
			(fill yes)
			(layer "F.SilkS")
		)
		(fp_line
			(start -1.549908 -2.050034)
			(end -1.549908 2.050034)
			(stroke
				(width 0.1)
				(type default)
			)
			(layer "F.Fab")
		)
		(fp_line
			(start -1.549908 2.050034)
			(end 1.549908 2.050034)
			(stroke
				(width 0.1)
				(type default)
			)
			(layer "F.Fab")
		)
		(fp_line
			(start 1.549908 -2.050034)
			(end -1.549908 -2.050034)
			(stroke
				(width 0.1)
				(type default)
			)
			(layer "F.Fab")
		)
		(fp_line
			(start 1.549908 2.050034)
			(end 1.549908 -2.050034)
			(stroke
				(width 0.1)
				(type default)
			)
			(layer "F.Fab")
		)
		(fp_poly
			(pts
				(xy -2.9464 -2.208022) (xy -2.9464 -1.192022) (xy -1.9304 -1.700022)
			)
			(stroke
				(width 0)
				(type default)
			)
			(fill yes)
			(layer "F.Fab")
		)
		(pad "1" smd circle
			(at -1.35001 -1.700022)
			(size 0 0)
			(layers "F.Cu" "F.Mask" "F.Paste")
			(net "SW_P5V_AUX_BST")
		)
		(pad "2" smd rect
			(at -1.400048 -1.199896 90)
			(size 0.1778 0.8128)
			(layers "F.Cu" "F.Mask" "F.Paste")
			(net "GND")
		)
		(pad "3" smd rect
			(at -1.400048 -0.8001 90)
			(size 0.1778 0.8128)
			(layers "F.Cu" "F.Mask" "F.Paste")
			(net "P5V_AUX_CS")
		)
		(pad "4" smd rect
			(at -1.400048 -0.40005 90)
			(size 0.1778 0.8128)
			(layers "F.Cu" "F.Mask" "F.Paste")
			(net "P5V_AUX_MODE")
		)
		(pad "5" smd rect
			(at -1.400048 0 90)
			(size 0.1778 0.8128)
			(layers "F.Cu" "F.Mask" "F.Paste")
			(net "P5V_AUX_REF")
		)
		(pad "6" smd rect
			(at -1.400048 0.40005 90)
			(size 0.1778 0.8128)
			(layers "F.Cu" "F.Mask" "F.Paste")
			(net "GND")
		)
		(pad "7" smd rect
			(at -1.400048 0.8001 90)
			(size 0.1778 0.8128)
			(layers "F.Cu" "F.Mask" "F.Paste")
			(net "P5V_AUX_FB")
		)
		(pad "8" smd rect
			(at -1.400048 1.199896 90)
			(size 0.1778 0.8128)
			(layers "F.Cu" "F.Mask" "F.Paste")
			(net "P5V_AUX_EN")
		)
		(pad "9" smd rect
			(at -1.400048 1.700022 90)
			(size 0.3048 0.8128)
			(layers "F.Cu" "F.Mask" "F.Paste")
			(net "PWRGD_P5V_AUX_R")
		)
		(pad "10" smd rect
			(at -0.299974 1.299972)
			(size 0.3048 2.0066)
			(layers "F.Cu" "F.Mask" "F.Paste")
			(net "SW_P5V_AUX_FLT")
		)
		(pad "11_18" smd circle
			(at 1.175004 0.275082)
			(size 0 0)
			(layers "F.Cu" "F.Mask" "F.Paste")
			(net "GND")
		)
		(pad "19" smd rect
			(at 1.400048 -1.700022 270)
			(size 0.3048 0.8128)
			(layers "F.Cu" "F.Mask" "F.Paste")
			(net "P5V_AUX_VCC")
		)
		(pad "20" smd rect
			(at 0.299974 -1.299972)
			(size 0.3048 2.0066)
			(layers "F.Cu" "F.Mask" "F.Paste")
			(net "SW_P5V_AUX_SW")
		)
		(pad "21" smd rect
			(at -0.299974 -1.299972)
			(size 0.3048 2.0066)
			(layers "F.Cu" "F.Mask" "F.Paste")
			(net "SW_P5V_AUX_FLT")
		)
	)
	(footprint ""
		(layer "F.Cu")
		(at 124.323348 -174.509684 180)
		(property "Reference" "PL36"
			(at -0.772668 6.156198 0)
			(unlocked yes)
			(layer "F.SilkS")
			(effects
				(font
					(size 0.7874 0.5842)
					(thickness 0.1524)
				)
				(justify left)
			)
		)
		(property "Value" ""
			(at 0 0 180)
			(layer "F.Fab")
			(effects
				(font
					(size 1.27 1.27)
				)
			)
		)
		(duplicate_pad_numbers_are_jumpers no)
		(fp_line
			(start 3.750056 5.500116)
			(end 3.750056 -5.500116)
			(stroke
				(width 0.1524)
				(type default)
			)
			(layer "F.SilkS")
		)
		(fp_line
			(start 3.750056 -5.500116)
			(end 2.393442 -5.500116)
			(stroke
				(width 0.1524)
				(type default)
			)
			(layer "F.SilkS")
		)
		(fp_line
			(start 2.393442 5.500116)
			(end 3.750056 5.500116)
			(stroke
				(width 0.1524)
				(type default)
			)
			(layer "F.SilkS")
		)
		(fp_line
			(start -2.393442 5.500116)
			(end -3.750056 5.500116)
			(stroke
				(width 0.1524)
				(type default)
			)
			(layer "F.SilkS")
		)
		(fp_line
			(start -3.750056 5.500116)
			(end -3.750056 -5.500116)
			(stroke
				(width 0.1524)
				(type default)
			)
			(layer "F.SilkS")
		)
		(fp_line
			(start -3.750056 -5.500116)
			(end -2.393442 -5.500116)
			(stroke
				(width 0.1524)
				(type default)
			)
			(layer "F.SilkS")
		)
		(fp_poly
			(pts
				(xy -3.9116 -4.249928) (xy -4.3434 -4.034028) (xy -4.3434 -4.465828)
			)
			(stroke
				(width 0)
				(type default)
			)
			(fill yes)
			(layer "F.SilkS")
		)
		(fp_line
			(start 3.750056 5.500116)
			(end 3.750056 -5.500116)
			(stroke
				(width 0.1)
				(type default)
			)
			(layer "F.Fab")
		)
		(fp_line
			(start 3.750056 -5.500116)
			(end -3.750056 -5.500116)
			(stroke
				(width 0.1)
				(type default)
			)
			(layer "F.Fab")
		)
		(fp_line
			(start -3.750056 5.500116)
			(end 3.750056 5.500116)
			(stroke
				(width 0.1)
				(type default)
			)
			(layer "F.Fab")
		)
		(fp_line
			(start -3.750056 -5.500116)
			(end -3.750056 5.500116)
			(stroke
				(width 0.1)
				(type default)
			)
			(layer "F.Fab")
		)
		(fp_poly
			(pts
				(xy -4.9276 -4.757928) (xy -4.9276 -3.741928) (xy -3.9116 -4.249928)
			)
			(stroke
				(width 0)
				(type default)
			)
			(fill yes)
			(layer "F.Fab")
		)
		(pad "1" smd rect
			(at 0 -4.249928 90)
			(size 2.413 4.5212)
			(layers "F.Cu" "F.Mask" "F.Paste")
			(net "SW_PVDDCR_SOC_P1_SW2")
		)
		(pad "2" smd rect
			(at 0 -1.175004 90)
			(size 1.3716 4.5212)
			(layers "F.Cu" "F.Mask" "F.Paste")
			(net "IND_SOC_P1_CPL3")
		)
		(pad "3" smd rect
			(at 0 1.175004 90)
			(size 1.3716 4.5212)
			(layers "F.Cu" "F.Mask" "F.Paste")
			(net "IND_SOC_P1_CPL2")
		)
		(pad "4" smd rect
			(at 0 4.249928 90)
			(size 2.413 4.5212)
			(layers "F.Cu" "F.Mask" "F.Paste")
			(net "PVDDCR_SOC_P1")
		)
	)
	(footprint ""
		(layer "F.Cu")
		(at 182.919878 -351.295462)
		(property "Reference" "PU44"
			(at -5.9436 -7.47141 0)
			(unlocked yes)
			(layer "F.SilkS")
			(effects
				(font
					(size 0.7874 0.5842)
					(thickness 0.1524)
				)
				(justify left)
			)
		)
		(property "Value" ""
			(at 0 0 0)
			(layer "F.Fab")
			(effects
				(font
					(size 1.27 1.27)
				)
			)
		)
		(duplicate_pad_numbers_are_jumpers no)
		(fp_line
			(start -2.500122 -2.999994)
			(end -2.24409 -2.999994)
			(stroke
				(width 0.1524)
				(type default)
			)
			(layer "F.SilkS")
		)
		(fp_line
			(start -2.500122 -2.529078)
			(end -2.500122 -2.999994)
			(stroke
				(width 0.1524)
				(type default)
			)
			(layer "F.SilkS")
		)
		(fp_line
			(start -2.500122 0.6604)
			(end -2.500122 0.229108)
			(stroke
				(width 0.1524)
				(type default)
			)
			(layer "F.SilkS")
		)
		(fp_line
			(start -2.500122 2.999994)
			(end -2.500122 2.339594)
			(stroke
				(width 0.1524)
				(type default)
			)
			(layer "F.SilkS")
		)
		(fp_line
			(start -2.2987 2.999994)
			(end -2.500122 2.999994)
			(stroke
				(width 0.1524)
				(type default)
			)
			(layer "F.SilkS")
		)
		(fp_line
			(start 2.31394 -2.999994)
			(end 2.500122 -2.999994)
			(stroke
				(width 0.1524)
				(type default)
			)
			(layer "F.SilkS")
		)
		(fp_line
			(start 2.500122 -2.999994)
			(end 2.500122 -2.44348)
			(stroke
				(width 0.1524)
				(type default)
			)
			(layer "F.SilkS")
		)
		(fp_line
			(start 2.500122 2.339594)
			(end 2.500122 2.999994)
			(stroke
				(width 0.1524)
				(type default)
			)
			(layer "F.SilkS")
		)
		(fp_line
			(start 2.500122 2.999994)
			(end 2.2987 2.999994)
			(stroke
				(width 0.1524)
				(type default)
			)
			(layer "F.SilkS")
		)
		(fp_poly
			(pts
				(xy -2.732278 -2.41681) (xy -3.405886 -2.641346) (xy -2.956814 -3.090418)
			)
			(stroke
				(width 0)
				(type default)
			)
			(fill yes)
			(layer "F.SilkS")
		)
		(fp_line
			(start -2.500122 -2.999994)
			(end 2.500122 -2.999994)
			(stroke
				(width 0.1)
				(type default)
			)
			(layer "F.Fab")
		)
		(fp_line
			(start -2.500122 2.999994)
			(end -2.500122 -2.999994)
			(stroke
				(width 0.1)
				(type default)
			)
			(layer "F.Fab")
		)
		(fp_line
			(start 2.500122 -2.999994)
			(end 2.500122 2.999994)
			(stroke
				(width 0.1)
				(type default)
			)
			(layer "F.Fab")
		)
		(fp_line
			(start 2.500122 2.999994)
			(end -2.500122 2.999994)
			(stroke
				(width 0.1)
				(type default)
			)
			(layer "F.Fab")
		)
		(fp_poly
			(pts
				(xy -4.218432 -2.783078) (xy -4.218432 -1.767078) (xy -3.202432 -2.275078)
			)
			(stroke
				(width 0)
				(type default)
			)
			(fill yes)
			(layer "F.Fab")
		)
		(pad "1" smd rect
			(at -2.400046 -2.275078 90)
			(size 0.2286 0.6096)
			(layers "F.Cu" "F.Mask" "F.Paste")
			(net "PVDD11_S3_P1_VOS1")
		)
		(pad "2" smd rect
			(at -2.400046 -1.82499 90)
			(size 0.2286 0.6096)
			(layers "F.Cu" "F.Mask" "F.Paste")
			(net "GND")
		)
		(pad "3" smd rect
			(at -2.400046 -1.374902 90)
			(size 0.2286 0.6096)
			(layers "F.Cu" "F.Mask" "F.Paste")
			(net "PVDD11_S3_P1_VCC1")
		)
		(pad "4" smd rect
			(at -2.400046 -0.925068 90)
			(size 0.2286 0.6096)
			(layers "F.Cu" "F.Mask" "F.Paste")
			(net "PVDD11_S3_P1_PVCC")
		)
		(pad "5" smd rect
			(at -2.400046 -0.47498 90)
			(size 0.2286 0.6096)
			(layers "F.Cu" "F.Mask" "F.Paste")
			(net "GND")
		)
		(pad "6" smd rect
			(at -2.400046 -0.024892 90)
			(size 0.2286 0.6096)
			(layers "F.Cu" "F.Mask" "F.Paste")
			(net "NC_PVDD11_S3_P1_GL1_1")
		)
		(pad "7_9-20_24" smd circle
			(at 0 1.150112 90)
			(size 0 0)
			(layers "F.Cu" "F.Mask" "F.Paste")
			(net "GND")
		)
		(pad "10_19" smd rect
			(at 0 2.899918 90)
			(size 0.6096 4.318)
			(layers "F.Cu" "F.Mask" "F.Paste")
			(net "SW_PVDD11_S3_P1_SW1")
		)
		(pad "25_29" smd rect
			(at 1.549908 -1.279906 270)
			(size 2.0574 2.3114)
			(layers "F.Cu" "F.Mask" "F.Paste")
			(net "SW_P12V_AUX_PVDD11_S3_P1_FLT")
		)
		(pad "30" smd rect
			(at 2.05994 -2.899918)
			(size 0.2286 0.6096)
			(layers "F.Cu" "F.Mask" "F.Paste")
			(net "SW_P12V_AUX_PVDD11_S3_P1_FLT")
		)
		(pad "31" smd rect
			(at 1.610106 -2.899918)
			(size 0.2286 0.6096)
			(layers "F.Cu" "F.Mask" "F.Paste")
			(net "NC_PVDD11_S3_P1_DNC1")
		)
		(pad "32" smd rect
			(at 1.160018 -2.899918)
			(size 0.2286 0.6096)
			(layers "F.Cu" "F.Mask" "F.Paste")
			(net "SW_PVDD11_S3_P1_PH1")
		)
		(pad "33" smd rect
			(at 0.70993 -2.899918)
			(size 0.2286 0.6096)
			(layers "F.Cu" "F.Mask" "F.Paste")
			(net "SW_PVDD11_S3_P1_BOOT1")
		)
		(pad "34" smd rect
			(at 0.260096 -2.899918)
			(size 0.2286 0.6096)
			(layers "F.Cu" "F.Mask" "F.Paste")
			(net "PVDD11_S3_P1_PWM1")
		)
		(pad "35" smd rect
			(at -0.189992 -2.899918)
			(size 0.2286 0.6096)
			(layers "F.Cu" "F.Mask" "F.Paste")
			(net "PVDD11_S3_P1_VCC1")
		)
		(pad "36" smd rect
			(at -0.64008 -2.899918)
			(size 0.2286 0.6096)
			(layers "F.Cu" "F.Mask" "F.Paste")
			(net "PVDD11_S3_P1_TEMP0")
		)
		(pad "37" smd rect
			(at -1.089914 -2.899918)
			(size 0.2286 0.6096)
			(layers "F.Cu" "F.Mask" "F.Paste")
			(net "PVDD11_S3_P1_LSET1")
		)
		(pad "38" smd rect
			(at -1.540002 -2.899918)
			(size 0.2286 0.6096)
			(layers "F.Cu" "F.Mask" "F.Paste")
			(net "PVDD11_S3_P1_IMON1")
		)
		(pad "39" smd rect
			(at -1.99009 -2.899918)
			(size 0.2286 0.6096)
			(layers "F.Cu" "F.Mask" "F.Paste")
			(net "PVDD11_S3_P1_VCCS")
		)
		(pad "40" smd rect
			(at -0.87503 -1.27508)
			(size 1.7526 1.9558)
			(layers "F.Cu" "F.Mask" "F.Paste")
			(net "GND")
		)
		(pad "41" smd rect
			(at -1.525016 0.249936 270)
			(size 0.3048 0.4572)
			(layers "F.Cu" "F.Mask" "F.Paste")
			(net "NC_PVDD11_S3_P1_GL2_1")
		)
		(zone
			(layer "F.Cu")
			(hatch none 0.5)
			(connect_pads
				(clearance 0)
			)
			(min_thickness 0.25)
			(keepout
				(tracks not_allowed)
				(vias allowed)
				(pads allowed)
				(copperpour not_allowed)
				(footprints allowed)
			)
			(placement
				(enabled no)
				(sheetname "")
			)
			(fill
				(thermal_gap 0.5)
				(thermal_bridge_width 0.5)
				(island_removal_mode 0)
			)
			(polygon
				(pts
					(xy 180.419756 -348.751398) (xy 180.419756 -349.044768) (xy 185.42 -349.044768) (xy 185.42 -348.295468)
					(xy 185.129678 -348.295468) (xy 185.129678 -348.751144) (xy 180.710078 -348.751144) (xy 180.710078 -348.751398)
				)
			)
		)
		(zone
			(layer "F.Cu")
			(hatch none 0.5)
			(connect_pads
				(clearance 0)
			)
			(min_thickness 0.25)
			(keepout
				(tracks not_allowed)
				(vias allowed)
				(pads allowed)
				(copperpour not_allowed)
				(footprints allowed)
			)
			(placement
				(enabled no)
				(sheetname "")
			)
			(fill
				(thermal_gap 0.5)
				(thermal_bridge_width 0.5)
				(island_removal_mode 0)
			)
			(polygon
				(pts
					(xy 182.971948 -351.541842) (xy 182.971948 -353.599242) (xy 181.117748 -353.599242) (xy 181.117748 -353.358196)
					(xy 180.875432 -353.358196) (xy 180.875432 -353.83978) (xy 184.684924 -353.83978) (xy 184.684924 -353.654868)
					(xy 183.263286 -353.654868) (xy 183.263286 -351.495868) (xy 185.42 -351.495868) (xy 185.42 -351.246186)
					(xy 183.267604 -351.246186)
				)
			)
		)
	)
	(footprint ""
		(layer "F.Cu")
		(at 324.099174 -22.634956 -90)
		(property "Reference" "R5052"
			(at 0 0 270)
			(layer "F.SilkS")
			(hide yes)
			(effects
				(font
					(size 1.27 1.27)
				)
			)
		)
		(property "Value" ""
			(at 0 0 270)
			(layer "F.Fab")
			(effects
				(font
					(size 1.27 1.27)
				)
			)
		)
		(duplicate_pad_numbers_are_jumpers no)
		(fp_line
			(start -0.7874 0.4064)
			(end -0.7874 -0.4064)
			(stroke
				(width 0.1524)
				(type default)
			)
			(layer "F.SilkS")
		)
		(fp_line
			(start 0.7874 0.4064)
			(end -0.7874 0.4064)
			(stroke
				(width 0.1524)
				(type default)
			)
			(layer "F.SilkS")
		)
		(fp_line
			(start -0.7874 -0.4064)
			(end 0.7874 -0.4064)
			(stroke
				(width 0.1524)
				(type default)
			)
			(layer "F.SilkS")
		)
		(fp_line
			(start 0.7874 -0.4064)
			(end 0.7874 0.4064)
			(stroke
				(width 0.1524)
				(type default)
			)
			(layer "F.SilkS")
		)
		(fp_line
			(start -0.67945 0.3048)
			(end -0.67945 -0.305054)
			(stroke
				(width 0.1)
				(type default)
			)
			(layer "F.Fab")
		)
		(fp_line
			(start -0.12065 0.3048)
			(end -0.67945 0.3048)
			(stroke
				(width 0.1)
				(type default)
			)
			(layer "F.Fab")
		)
		(fp_line
			(start 0.120396 0.3048)
			(end 0.120396 0.2794)
			(stroke
				(width 0.1)
				(type default)
			)
			(layer "F.Fab")
		)
		(fp_line
			(start 0.67945 0.3048)
			(end 0.120396 0.3048)
			(stroke
				(width 0.1)
				(type default)
			)
			(layer "F.Fab")
		)
		(fp_line
			(start -0.12065 0.2794)
			(end -0.12065 0.3048)
			(stroke
				(width 0.1)
				(type default)
			)
			(layer "F.Fab")
		)
		(fp_line
			(start 0.120396 0.2794)
			(end -0.12065 0.2794)
			(stroke
				(width 0.1)
				(type default)
			)
			(layer "F.Fab")
		)
		(fp_line
			(start -0.12065 -0.2794)
			(end 0.12065 -0.2794)
			(stroke
				(width 0.1)
				(type default)
			)
			(layer "F.Fab")
		)
		(fp_line
			(start 0.12065 -0.2794)
			(end 0.12065 -0.3048)
			(stroke
				(width 0.1)
				(type default)
			)
			(layer "F.Fab")
		)
		(fp_line
			(start 0.12065 -0.3048)
			(end 0.67945 -0.3048)
			(stroke
				(width 0.1)
				(type default)
			)
			(layer "F.Fab")
		)
		(fp_line
			(start 0.67945 -0.3048)
			(end 0.67945 0.3048)
			(stroke
				(width 0.1)
				(type default)
			)
			(layer "F.Fab")
		)
		(fp_line
			(start -0.67945 -0.305054)
			(end -0.12065 -0.305054)
			(stroke
				(width 0.1)
				(type default)
			)
			(layer "F.Fab")
		)
		(fp_line
			(start -0.12065 -0.305054)
			(end -0.12065 -0.2794)
			(stroke
				(width 0.1)
				(type default)
			)
			(layer "F.Fab")
		)
		(pad "1" smd circle
			(at -0.40005 0 270)
			(size 0 0)
			(layers "F.Cu" "F.Mask" "F.Paste")
			(net "P3V3_RTC_AUX_R")
		)
		(pad "2" smd circle
			(at 0.40005 0 270)
			(size 0 0)
			(layers "F.Cu" "F.Mask" "F.Paste")
			(net "P3V3_RTC_AUX")
		)
	)
	(footprint ""
		(layer "F.Cu")
		(at 85.96757 -182.745634 90)
		(property "Reference" "PC258_C0P1_1"
			(at 0 0 90)
			(layer "F.SilkS")
			(hide yes)
			(effects
				(font
					(size 1.27 1.27)
				)
			)
		)
		(property "Value" ""
			(at 0 0 90)
			(layer "F.Fab")
			(effects
				(font
					(size 1.27 1.27)
				)
			)
		)
		(duplicate_pad_numbers_are_jumpers no)
		(fp_line
			(start 0.7874 -0.4064)
			(end 0.7874 0.4064)
			(stroke
				(width 0.1524)
				(type default)
			)
			(layer "F.SilkS")
		)
		(fp_line
			(start -0.7874 -0.4064)
			(end 0.7874 -0.4064)
			(stroke
				(width 0.1524)
				(type default)
			)
			(layer "F.SilkS")
		)
		(fp_line
			(start 0.7874 0.4064)
			(end -0.7874 0.4064)
			(stroke
				(width 0.1524)
				(type default)
			)
			(layer "F.SilkS")
		)
		(fp_line
			(start -0.7874 0.4064)
			(end -0.7874 -0.4064)
			(stroke
				(width 0.1524)
				(type default)
			)
			(layer "F.SilkS")
		)
		(fp_line
			(start -0.12065 -0.305054)
			(end -0.12065 -0.2794)
			(stroke
				(width 0.1)
				(type default)
			)
			(layer "F.Fab")
		)
		(fp_line
			(start -0.67945 -0.305054)
			(end -0.12065 -0.305054)
			(stroke
				(width 0.1)
				(type default)
			)
			(layer "F.Fab")
		)
		(fp_line
			(start 0.67945 -0.3048)
			(end 0.67945 0.3048)
			(stroke
				(width 0.1)
				(type default)
			)
			(layer "F.Fab")
		)
		(fp_line
			(start 0.12065 -0.3048)
			(end 0.67945 -0.3048)
			(stroke
				(width 0.1)
				(type default)
			)
			(layer "F.Fab")
		)
		(fp_line
			(start 0.12065 -0.2794)
			(end 0.12065 -0.3048)
			(stroke
				(width 0.1)
				(type default)
			)
			(layer "F.Fab")
		)
		(fp_line
			(start -0.12065 -0.2794)
			(end 0.12065 -0.2794)
			(stroke
				(width 0.1)
				(type default)
			)
			(layer "F.Fab")
		)
		(fp_line
			(start 0.120396 0.2794)
			(end -0.12065 0.2794)
			(stroke
				(width 0.1)
				(type default)
			)
			(layer "F.Fab")
		)
		(fp_line
			(start -0.12065 0.2794)
			(end -0.12065 0.3048)
			(stroke
				(width 0.1)
				(type default)
			)
			(layer "F.Fab")
		)
		(fp_line
			(start 0.67945 0.3048)
			(end 0.120396 0.3048)
			(stroke
				(width 0.1)
				(type default)
			)
			(layer "F.Fab")
		)
		(fp_line
			(start 0.120396 0.3048)
			(end 0.120396 0.2794)
			(stroke
				(width 0.1)
				(type default)
			)
			(layer "F.Fab")
		)
		(fp_line
			(start -0.12065 0.3048)
			(end -0.67945 0.3048)
			(stroke
				(width 0.1)
				(type default)
			)
			(layer "F.Fab")
		)
		(fp_line
			(start -0.67945 0.3048)
			(end -0.67945 -0.305054)
			(stroke
				(width 0.1)
				(type default)
			)
			(layer "F.Fab")
		)
		(pad "1" smd circle
			(at -0.40005 0 90)
			(size 0 0)
			(layers "F.Cu" "F.Mask" "F.Paste")
			(net "PVDDCR_CPU0_P1_PVCC")
		)
		(pad "2" smd circle
			(at 0.40005 0 90)
			(size 0 0)
			(layers "F.Cu" "F.Mask" "F.Paste")
			(net "GND")
		)
	)
	(footprint ""
		(layer "F.Cu")
		(at 131.425696 -373.03583 -90)
		(property "Reference" "C1524"
			(at 0 0 270)
			(layer "F.SilkS")
			(hide yes)
			(effects
				(font
					(size 1.27 1.27)
				)
			)
		)
		(property "Value" ""
			(at 0 0 270)
			(layer "F.Fab")
			(effects
				(font
					(size 1.27 1.27)
				)
			)
		)
		(duplicate_pad_numbers_are_jumpers no)
		(fp_line
			(start -0.299974 0.150114)
			(end -0.299974 -0.150114)
			(stroke
				(width 0.1)
				(type default)
			)
			(layer "F.Fab")
		)
		(fp_line
			(start 0.299974 0.150114)
			(end -0.299974 0.150114)
			(stroke
				(width 0.1)
				(type default)
			)
			(layer "F.Fab")
		)
		(fp_line
			(start -0.299974 -0.150114)
			(end 0.299974 -0.150114)
			(stroke
				(width 0.1)
				(type default)
			)
			(layer "F.Fab")
		)
		(fp_line
			(start 0.299974 -0.150114)
			(end 0.299974 0.150114)
			(stroke
				(width 0.1)
				(type default)
			)
			(layer "F.Fab")
		)
		(pad "1" smd rect
			(at -0.2667 0 270)
			(size 0.3048 0.381)
			(layers "F.Cu" "F.Mask" "F.Paste")
			(net "P5E_CPU1_P3_TX_C_DN<11>")
		)
		(pad "2" smd rect
			(at 0.2667 0 270)
			(size 0.3048 0.381)
			(layers "F.Cu" "F.Mask" "F.Paste")
			(net "P5E_CPU1_P3_TX_DN<11>")
		)
	)
	(footprint ""
		(layer "F.Cu")
		(at 168.144444 -370.57203 -90)
		(property "Reference" "C747"
			(at 0 0 270)
			(layer "F.SilkS")
			(hide yes)
			(effects
				(font
					(size 1.27 1.27)
				)
			)
		)
		(property "Value" ""
			(at 0 0 270)
			(layer "F.Fab")
			(effects
				(font
					(size 1.27 1.27)
				)
			)
		)
		(duplicate_pad_numbers_are_jumpers no)
		(fp_line
			(start -0.299974 0.150114)
			(end -0.299974 -0.150114)
			(stroke
				(width 0.1)
				(type default)
			)
			(layer "F.Fab")
		)
		(fp_line
			(start 0.299974 0.150114)
			(end -0.299974 0.150114)
			(stroke
				(width 0.1)
				(type default)
			)
			(layer "F.Fab")
		)
		(fp_line
			(start -0.299974 -0.150114)
			(end 0.299974 -0.150114)
			(stroke
				(width 0.1)
				(type default)
			)
			(layer "F.Fab")
		)
		(fp_line
			(start 0.299974 -0.150114)
			(end 0.299974 0.150114)
			(stroke
				(width 0.1)
				(type default)
			)
			(layer "F.Fab")
		)
		(pad "1" smd rect
			(at -0.2667 0 270)
			(size 0.3048 0.381)
			(layers "F.Cu" "F.Mask" "F.Paste")
			(net "P5E_CPU1_P2_TX_C_DP<13>")
		)
		(pad "2" smd rect
			(at 0.2667 0 270)
			(size 0.3048 0.381)
			(layers "F.Cu" "F.Mask" "F.Paste")
			(net "P5E_CPU1_P2_TX_DP<13>")
		)
	)
	(footprint ""
		(layer "F.Cu")
		(at 452.13905 -49.377346 180)
		(property "Reference" "PR835"
			(at 0 0 180)
			(layer "F.SilkS")
			(hide yes)
			(effects
				(font
					(size 1.27 1.27)
				)
			)
		)
		(property "Value" ""
			(at 0 0 180)
			(layer "F.Fab")
			(effects
				(font
					(size 1.27 1.27)
				)
			)
		)
		(duplicate_pad_numbers_are_jumpers no)
		(fp_line
			(start 0.7874 0.4064)
			(end -0.7874 0.4064)
			(stroke
				(width 0.1524)
				(type default)
			)
			(layer "F.SilkS")
		)
		(fp_line
			(start 0.7874 -0.4064)
			(end 0.7874 0.4064)
			(stroke
				(width 0.1524)
				(type default)
			)
			(layer "F.SilkS")
		)
		(fp_line
			(start -0.7874 0.4064)
			(end -0.7874 -0.4064)
			(stroke
				(width 0.1524)
				(type default)
			)
			(layer "F.SilkS")
		)
		(fp_line
			(start -0.7874 -0.4064)
			(end 0.7874 -0.4064)
			(stroke
				(width 0.1524)
				(type default)
			)
			(layer "F.SilkS")
		)
		(fp_line
			(start 0.67945 0.3048)
			(end 0.120396 0.3048)
			(stroke
				(width 0.1)
				(type default)
			)
			(layer "F.Fab")
		)
		(fp_line
			(start 0.67945 -0.3048)
			(end 0.67945 0.3048)
			(stroke
				(width 0.1)
				(type default)
			)
			(layer "F.Fab")
		)
		(fp_line
			(start 0.12065 -0.2794)
			(end 0.12065 -0.3048)
			(stroke
				(width 0.1)
				(type default)
			)
			(layer "F.Fab")
		)
		(fp_line
			(start 0.12065 -0.3048)
			(end 0.67945 -0.3048)
			(stroke
				(width 0.1)
				(type default)
			)
			(layer "F.Fab")
		)
		(fp_line
			(start 0.120396 0.3048)
			(end 0.120396 0.2794)
			(stroke
				(width 0.1)
				(type default)
			)
			(layer "F.Fab")
		)
		(fp_line
			(start 0.120396 0.2794)
			(end -0.12065 0.2794)
			(stroke
				(width 0.1)
				(type default)
			)
			(layer "F.Fab")
		)
		(fp_line
			(start -0.12065 0.3048)
			(end -0.67945 0.3048)
			(stroke
				(width 0.1)
				(type default)
			)
			(layer "F.Fab")
		)
		(fp_line
			(start -0.12065 0.2794)
			(end -0.12065 0.3048)
			(stroke
				(width 0.1)
				(type default)
			)
			(layer "F.Fab")
		)
		(fp_line
			(start -0.12065 -0.2794)
			(end 0.12065 -0.2794)
			(stroke
				(width 0.1)
				(type default)
			)
			(layer "F.Fab")
		)
		(fp_line
			(start -0.12065 -0.305054)
			(end -0.12065 -0.2794)
			(stroke
				(width 0.1)
				(type default)
			)
			(layer "F.Fab")
		)
		(fp_line
			(start -0.67945 0.3048)
			(end -0.67945 -0.305054)
			(stroke
				(width 0.1)
				(type default)
			)
			(layer "F.Fab")
		)
		(fp_line
			(start -0.67945 -0.305054)
			(end -0.12065 -0.305054)
			(stroke
				(width 0.1)
				(type default)
			)
			(layer "F.Fab")
		)
		(pad "1" smd circle
			(at -0.40005 0 180)
			(size 0 0)
			(layers "F.Cu" "F.Mask" "F.Paste")
			(net "SW_P3V3_AUX_BOOT")
		)
		(pad "2" smd circle
			(at 0.40005 0 180)
			(size 0 0)
			(layers "F.Cu" "F.Mask" "F.Paste")
			(net "SW_P3V3_AUX_BOOT_R")
		)
	)
	(footprint ""
		(layer "F.Cu")
		(at 423.610024 -363.78261)
		(property "Reference" "PC5"
			(at 0 0 0)
			(layer "F.SilkS")
			(hide yes)
			(effects
				(font
					(size 1.27 1.27)
				)
			)
		)
		(property "Value" ""
			(at 0 0 0)
			(layer "F.Fab")
			(effects
				(font
					(size 1.27 1.27)
				)
			)
		)
		(duplicate_pad_numbers_are_jumpers no)
		(fp_line
			(start -0.7874 -0.4064)
			(end 0.7874 -0.4064)
			(stroke
				(width 0.1524)
				(type default)
			)
			(layer "F.SilkS")
		)
		(fp_line
			(start -0.7874 0.4064)
			(end -0.7874 -0.4064)
			(stroke
				(width 0.1524)
				(type default)
			)
			(layer "F.SilkS")
		)
		(fp_line
			(start 0.7874 -0.4064)
			(end 0.7874 0.4064)
			(stroke
				(width 0.1524)
				(type default)
			)
			(layer "F.SilkS")
		)
		(fp_line
			(start 0.7874 0.4064)
			(end -0.7874 0.4064)
			(stroke
				(width 0.1524)
				(type default)
			)
			(layer "F.SilkS")
		)
		(fp_line
			(start -0.67945 -0.305054)
			(end -0.12065 -0.305054)
			(stroke
				(width 0.1)
				(type default)
			)
			(layer "F.Fab")
		)
		(fp_line
			(start -0.67945 0.3048)
			(end -0.67945 -0.305054)
			(stroke
				(width 0.1)
				(type default)
			)
			(layer "F.Fab")
		)
		(fp_line
			(start -0.12065 -0.305054)
			(end -0.12065 -0.2794)
			(stroke
				(width 0.1)
				(type default)
			)
			(layer "F.Fab")
		)
		(fp_line
			(start -0.12065 -0.2794)
			(end 0.12065 -0.2794)
			(stroke
				(width 0.1)
				(type default)
			)
			(layer "F.Fab")
		)
		(fp_line
			(start -0.12065 0.2794)
			(end -0.12065 0.3048)
			(stroke
				(width 0.1)
				(type default)
			)
			(layer "F.Fab")
		)
		(fp_line
			(start -0.12065 0.3048)
			(end -0.67945 0.3048)
			(stroke
				(width 0.1)
				(type default)
			)
			(layer "F.Fab")
		)
		(fp_line
			(start 0.120396 0.2794)
			(end -0.12065 0.2794)
			(stroke
				(width 0.1)
				(type default)
			)
			(layer "F.Fab")
		)
		(fp_line
			(start 0.120396 0.3048)
			(end 0.120396 0.2794)
			(stroke
				(width 0.1)
				(type default)
			)
			(layer "F.Fab")
		)
		(fp_line
			(start 0.12065 -0.3048)
			(end 0.67945 -0.3048)
			(stroke
				(width 0.1)
				(type default)
			)
			(layer "F.Fab")
		)
		(fp_line
			(start 0.12065 -0.2794)
			(end 0.12065 -0.3048)
			(stroke
				(width 0.1)
				(type default)
			)
			(layer "F.Fab")
		)
		(fp_line
			(start 0.67945 -0.3048)
			(end 0.67945 0.3048)
			(stroke
				(width 0.1)
				(type default)
			)
			(layer "F.Fab")
		)
		(fp_line
			(start 0.67945 0.3048)
			(end 0.120396 0.3048)
			(stroke
				(width 0.1)
				(type default)
			)
			(layer "F.Fab")
		)
		(pad "1" smd circle
			(at -0.40005 0)
			(size 0 0)
			(layers "F.Cu" "F.Mask" "F.Paste")
			(net "PVDD11_S3_P0_VINSEN")
		)
		(pad "2" smd circle
			(at 0.40005 0)
			(size 0 0)
			(layers "F.Cu" "F.Mask" "F.Paste")
			(net "GND")
		)
	)
	(footprint ""
		(layer "F.Cu")
		(at 225.420428 -271.407382)
		(property "Reference" "PL6503"
			(at 1.147572 3.337052 0)
			(unlocked yes)
			(layer "F.SilkS")
			(effects
				(font
					(size 0.7874 0.5842)
					(thickness 0.1524)
				)
				(justify left)
			)
		)
		(property "Value" ""
			(at 0 0 0)
			(layer "F.Fab")
			(effects
				(font
					(size 1.27 1.27)
				)
			)
		)
		(duplicate_pad_numbers_are_jumpers no)
		(fp_line
			(start -2.249932 -2.249932)
			(end 2.249932 -2.249932)
			(stroke
				(width 0.1524)
				(type default)
			)
			(layer "F.SilkS")
		)
		(fp_line
			(start -2.249932 -1.3843)
			(end -2.249932 -2.249932)
			(stroke
				(width 0.1524)
				(type default)
			)
			(layer "F.SilkS")
		)
		(fp_line
			(start -2.249932 2.249932)
			(end -2.249932 1.3843)
			(stroke
				(width 0.1524)
				(type default)
			)
			(layer "F.SilkS")
		)
		(fp_line
			(start 2.249932 -2.249932)
			(end 2.249932 -1.3843)
			(stroke
				(width 0.1524)
				(type default)
			)
			(layer "F.SilkS")
		)
		(fp_line
			(start 2.249932 1.3843)
			(end 2.249932 2.249932)
			(stroke
				(width 0.1524)
				(type default)
			)
			(layer "F.SilkS")
		)
		(fp_line
			(start 2.249932 2.249932)
			(end -2.249932 2.249932)
			(stroke
				(width 0.1524)
				(type default)
			)
			(layer "F.SilkS")
		)
		(fp_line
			(start -2.249932 -2.249932)
			(end 2.249932 -2.249932)
			(stroke
				(width 0.1)
				(type default)
			)
			(layer "F.Fab")
		)
		(fp_line
			(start -2.249932 2.249932)
			(end -2.249932 -2.249932)
			(stroke
				(width 0.1)
				(type default)
			)
			(layer "F.Fab")
		)
		(fp_line
			(start 2.249932 -2.249932)
			(end 2.249932 2.249932)
			(stroke
				(width 0.1)
				(type default)
			)
			(layer "F.Fab")
		)
		(fp_line
			(start 2.249932 2.249932)
			(end -2.249932 2.249932)
			(stroke
				(width 0.1)
				(type default)
			)
			(layer "F.Fab")
		)
		(pad "1" smd rect
			(at -1.82499 0)
			(size 1.0668 2.5146)
			(layers "F.Cu" "F.Mask" "F.Paste")
			(net "P12V_AUX")
		)
		(pad "2" smd rect
			(at 1.82499 0)
			(size 1.0668 2.5146)
			(layers "F.Cu" "F.Mask" "F.Paste")
			(net "SW_P12V_AUX_P1V8_RETIMER_CPU1_FLT")
		)
	)
	(footprint ""
		(layer "F.Cu")
		(at 157.995366 -56.331358)
		(property "Reference" "C2013"
			(at 0 0 0)
			(layer "F.SilkS")
			(hide yes)
			(effects
				(font
					(size 1.27 1.27)
				)
			)
		)
		(property "Value" ""
			(at 0 0 0)
			(layer "F.Fab")
			(effects
				(font
					(size 1.27 1.27)
				)
			)
		)
		(duplicate_pad_numbers_are_jumpers no)
		(fp_line
			(start -0.7874 -0.4064)
			(end 0.7874 -0.4064)
			(stroke
				(width 0.1524)
				(type default)
			)
			(layer "F.SilkS")
		)
		(fp_line
			(start -0.7874 0.4064)
			(end -0.7874 -0.4064)
			(stroke
				(width 0.1524)
				(type default)
			)
			(layer "F.SilkS")
		)
		(fp_line
			(start 0.7874 -0.4064)
			(end 0.7874 0.4064)
			(stroke
				(width 0.1524)
				(type default)
			)
			(layer "F.SilkS")
		)
		(fp_line
			(start 0.7874 0.4064)
			(end -0.7874 0.4064)
			(stroke
				(width 0.1524)
				(type default)
			)
			(layer "F.SilkS")
		)
		(fp_line
			(start -0.67945 -0.305054)
			(end -0.12065 -0.305054)
			(stroke
				(width 0.1)
				(type default)
			)
			(layer "F.Fab")
		)
		(fp_line
			(start -0.67945 0.3048)
			(end -0.67945 -0.305054)
			(stroke
				(width 0.1)
				(type default)
			)
			(layer "F.Fab")
		)
		(fp_line
			(start -0.12065 -0.305054)
			(end -0.12065 -0.2794)
			(stroke
				(width 0.1)
				(type default)
			)
			(layer "F.Fab")
		)
		(fp_line
			(start -0.12065 -0.2794)
			(end 0.12065 -0.2794)
			(stroke
				(width 0.1)
				(type default)
			)
			(layer "F.Fab")
		)
		(fp_line
			(start -0.12065 0.2794)
			(end -0.12065 0.3048)
			(stroke
				(width 0.1)
				(type default)
			)
			(layer "F.Fab")
		)
		(fp_line
			(start -0.12065 0.3048)
			(end -0.67945 0.3048)
			(stroke
				(width 0.1)
				(type default)
			)
			(layer "F.Fab")
		)
		(fp_line
			(start 0.120396 0.2794)
			(end -0.12065 0.2794)
			(stroke
				(width 0.1)
				(type default)
			)
			(layer "F.Fab")
		)
		(fp_line
			(start 0.120396 0.3048)
			(end 0.120396 0.2794)
			(stroke
				(width 0.1)
				(type default)
			)
			(layer "F.Fab")
		)
		(fp_line
			(start 0.12065 -0.3048)
			(end 0.67945 -0.3048)
			(stroke
				(width 0.1)
				(type default)
			)
			(layer "F.Fab")
		)
		(fp_line
			(start 0.12065 -0.2794)
			(end 0.12065 -0.3048)
			(stroke
				(width 0.1)
				(type default)
			)
			(layer "F.Fab")
		)
		(fp_line
			(start 0.67945 -0.3048)
			(end 0.67945 0.3048)
			(stroke
				(width 0.1)
				(type default)
			)
			(layer "F.Fab")
		)
		(fp_line
			(start 0.67945 0.3048)
			(end 0.120396 0.3048)
			(stroke
				(width 0.1)
				(type default)
			)
			(layer "F.Fab")
		)
		(pad "1" smd circle
			(at -0.40005 0)
			(size 0 0)
			(layers "F.Cu" "F.Mask" "F.Paste")
			(net "P3V3_AUX")
		)
		(pad "2" smd circle
			(at 0.40005 0)
			(size 0 0)
			(layers "F.Cu" "F.Mask" "F.Paste")
			(net "GND")
		)
	)
	(footprint ""
		(layer "F.Cu")
		(at 364.362238 -411.369764)
		(property "Reference" "R9005"
			(at 0 0 0)
			(layer "F.SilkS")
			(hide yes)
			(effects
				(font
					(size 1.27 1.27)
				)
			)
		)
		(property "Value" ""
			(at 0 0 0)
			(layer "F.Fab")
			(effects
				(font
					(size 1.27 1.27)
				)
			)
		)
		(duplicate_pad_numbers_are_jumpers no)
		(fp_line
			(start -0.7874 -0.4064)
			(end 0.7874 -0.4064)
			(stroke
				(width 0.1524)
				(type default)
			)
			(layer "F.SilkS")
		)
		(fp_line
			(start -0.7874 0.4064)
			(end -0.7874 -0.4064)
			(stroke
				(width 0.1524)
				(type default)
			)
			(layer "F.SilkS")
		)
		(fp_line
			(start 0.7874 -0.4064)
			(end 0.7874 0.4064)
			(stroke
				(width 0.1524)
				(type default)
			)
			(layer "F.SilkS")
		)
		(fp_line
			(start 0.7874 0.4064)
			(end -0.7874 0.4064)
			(stroke
				(width 0.1524)
				(type default)
			)
			(layer "F.SilkS")
		)
		(fp_line
			(start -0.67945 -0.305054)
			(end -0.12065 -0.305054)
			(stroke
				(width 0.1)
				(type default)
			)
			(layer "F.Fab")
		)
		(fp_line
			(start -0.67945 0.3048)
			(end -0.67945 -0.305054)
			(stroke
				(width 0.1)
				(type default)
			)
			(layer "F.Fab")
		)
		(fp_line
			(start -0.12065 -0.305054)
			(end -0.12065 -0.2794)
			(stroke
				(width 0.1)
				(type default)
			)
			(layer "F.Fab")
		)
		(fp_line
			(start -0.12065 -0.2794)
			(end 0.12065 -0.2794)
			(stroke
				(width 0.1)
				(type default)
			)
			(layer "F.Fab")
		)
		(fp_line
			(start -0.12065 0.2794)
			(end -0.12065 0.3048)
			(stroke
				(width 0.1)
				(type default)
			)
			(layer "F.Fab")
		)
		(fp_line
			(start -0.12065 0.3048)
			(end -0.67945 0.3048)
			(stroke
				(width 0.1)
				(type default)
			)
			(layer "F.Fab")
		)
		(fp_line
			(start 0.120396 0.2794)
			(end -0.12065 0.2794)
			(stroke
				(width 0.1)
				(type default)
			)
			(layer "F.Fab")
		)
		(fp_line
			(start 0.120396 0.3048)
			(end 0.120396 0.2794)
			(stroke
				(width 0.1)
				(type default)
			)
			(layer "F.Fab")
		)
		(fp_line
			(start 0.12065 -0.3048)
			(end 0.67945 -0.3048)
			(stroke
				(width 0.1)
				(type default)
			)
			(layer "F.Fab")
		)
		(fp_line
			(start 0.12065 -0.2794)
			(end 0.12065 -0.3048)
			(stroke
				(width 0.1)
				(type default)
			)
			(layer "F.Fab")
		)
		(fp_line
			(start 0.67945 -0.3048)
			(end 0.67945 0.3048)
			(stroke
				(width 0.1)
				(type default)
			)
			(layer "F.Fab")
		)
		(fp_line
			(start 0.67945 0.3048)
			(end 0.120396 0.3048)
			(stroke
				(width 0.1)
				(type default)
			)
			(layer "F.Fab")
		)
		(pad "1" smd circle
			(at -0.40005 0)
			(size 0 0)
			(layers "F.Cu" "F.Mask" "F.Paste")
			(net "P3V3_AUX")
		)
		(pad "2" smd circle
			(at 0.40005 0)
			(size 0 0)
			(layers "F.Cu" "F.Mask" "F.Paste")
			(net "PRSNT_CABLE_SWB_B1_ISO_N")
		)
	)
	(footprint ""
		(layer "F.Cu")
		(at 368.705892 -378.95403 -90)
		(property "Reference" "C894"
			(at 0 0 270)
			(layer "F.SilkS")
			(hide yes)
			(effects
				(font
					(size 1.27 1.27)
				)
			)
		)
		(property "Value" ""
			(at 0 0 270)
			(layer "F.Fab")
			(effects
				(font
					(size 1.27 1.27)
				)
			)
		)
		(duplicate_pad_numbers_are_jumpers no)
		(fp_line
			(start -0.299974 0.150114)
			(end -0.299974 -0.150114)
			(stroke
				(width 0.1)
				(type default)
			)
			(layer "F.Fab")
		)
		(fp_line
			(start 0.299974 0.150114)
			(end -0.299974 0.150114)
			(stroke
				(width 0.1)
				(type default)
			)
			(layer "F.Fab")
		)
		(fp_line
			(start -0.299974 -0.150114)
			(end 0.299974 -0.150114)
			(stroke
				(width 0.1)
				(type default)
			)
			(layer "F.Fab")
		)
		(fp_line
			(start 0.299974 -0.150114)
			(end 0.299974 0.150114)
			(stroke
				(width 0.1)
				(type default)
			)
			(layer "F.Fab")
		)
		(pad "1" smd rect
			(at -0.2667 0 270)
			(size 0.3048 0.381)
			(layers "F.Cu" "F.Mask" "F.Paste")
			(net "P5E_CPU0_P3_TX_C_DN<3>")
		)
		(pad "2" smd rect
			(at 0.2667 0 270)
			(size 0.3048 0.381)
			(layers "F.Cu" "F.Mask" "F.Paste")
			(net "P5E_CPU0_P3_TX_DN<3>")
		)
	)
	(footprint ""
		(layer "F.Cu")
		(at 321.056 -99.187)
		(property "Reference" "R1350"
			(at 0 0 0)
			(layer "F.SilkS")
			(hide yes)
			(effects
				(font
					(size 1.27 1.27)
				)
			)
		)
		(property "Value" ""
			(at 0 0 0)
			(layer "F.Fab")
			(effects
				(font
					(size 1.27 1.27)
				)
			)
		)
		(duplicate_pad_numbers_are_jumpers no)
		(fp_line
			(start -0.7874 -0.4064)
			(end 0.7874 -0.4064)
			(stroke
				(width 0.1524)
				(type default)
			)
			(layer "F.SilkS")
		)
		(fp_line
			(start -0.7874 0.4064)
			(end -0.7874 -0.4064)
			(stroke
				(width 0.1524)
				(type default)
			)
			(layer "F.SilkS")
		)
		(fp_line
			(start 0.7874 -0.4064)
			(end 0.7874 0.4064)
			(stroke
				(width 0.1524)
				(type default)
			)
			(layer "F.SilkS")
		)
		(fp_line
			(start 0.7874 0.4064)
			(end -0.7874 0.4064)
			(stroke
				(width 0.1524)
				(type default)
			)
			(layer "F.SilkS")
		)
		(fp_line
			(start -0.67945 -0.305054)
			(end -0.12065 -0.305054)
			(stroke
				(width 0.1)
				(type default)
			)
			(layer "F.Fab")
		)
		(fp_line
			(start -0.67945 0.3048)
			(end -0.67945 -0.305054)
			(stroke
				(width 0.1)
				(type default)
			)
			(layer "F.Fab")
		)
		(fp_line
			(start -0.12065 -0.305054)
			(end -0.12065 -0.2794)
			(stroke
				(width 0.1)
				(type default)
			)
			(layer "F.Fab")
		)
		(fp_line
			(start -0.12065 -0.2794)
			(end 0.12065 -0.2794)
			(stroke
				(width 0.1)
				(type default)
			)
			(layer "F.Fab")
		)
		(fp_line
			(start -0.12065 0.2794)
			(end -0.12065 0.3048)
			(stroke
				(width 0.1)
				(type default)
			)
			(layer "F.Fab")
		)
		(fp_line
			(start -0.12065 0.3048)
			(end -0.67945 0.3048)
			(stroke
				(width 0.1)
				(type default)
			)
			(layer "F.Fab")
		)
		(fp_line
			(start 0.120396 0.2794)
			(end -0.12065 0.2794)
			(stroke
				(width 0.1)
				(type default)
			)
			(layer "F.Fab")
		)
		(fp_line
			(start 0.120396 0.3048)
			(end 0.120396 0.2794)
			(stroke
				(width 0.1)
				(type default)
			)
			(layer "F.Fab")
		)
		(fp_line
			(start 0.12065 -0.3048)
			(end 0.67945 -0.3048)
			(stroke
				(width 0.1)
				(type default)
			)
			(layer "F.Fab")
		)
		(fp_line
			(start 0.12065 -0.2794)
			(end 0.12065 -0.3048)
			(stroke
				(width 0.1)
				(type default)
			)
			(layer "F.Fab")
		)
		(fp_line
			(start 0.67945 -0.3048)
			(end 0.67945 0.3048)
			(stroke
				(width 0.1)
				(type default)
			)
			(layer "F.Fab")
		)
		(fp_line
			(start 0.67945 0.3048)
			(end 0.120396 0.3048)
			(stroke
				(width 0.1)
				(type default)
			)
			(layer "F.Fab")
		)
		(pad "1" smd circle
			(at -0.40005 0)
			(size 0 0)
			(layers "F.Cu" "F.Mask" "F.Paste")
			(net "INA230_8_A1")
		)
		(pad "2" smd circle
			(at 0.40005 0)
			(size 0 0)
			(layers "F.Cu" "F.Mask" "F.Paste")
			(net "SMB_INA230_8_3V3AUX_SDA_R1")
		)
	)
	(footprint ""
		(layer "F.Cu")
		(at 24.906732 -343.716864 180)
		(property "Reference" "PC176"
			(at 0 0 180)
			(layer "F.SilkS")
			(hide yes)
			(effects
				(font
					(size 1.27 1.27)
				)
			)
		)
		(property "Value" ""
			(at 0 0 180)
			(layer "F.Fab")
			(effects
				(font
					(size 1.27 1.27)
				)
			)
		)
		(duplicate_pad_numbers_are_jumpers no)
		(fp_line
			(start 0.7874 0.4064)
			(end -0.7874 0.4064)
			(stroke
				(width 0.1524)
				(type default)
			)
			(layer "F.SilkS")
		)
		(fp_line
			(start 0.7874 -0.4064)
			(end 0.7874 0.4064)
			(stroke
				(width 0.1524)
				(type default)
			)
			(layer "F.SilkS")
		)
		(fp_line
			(start -0.7874 0.4064)
			(end -0.7874 -0.4064)
			(stroke
				(width 0.1524)
				(type default)
			)
			(layer "F.SilkS")
		)
		(fp_line
			(start -0.7874 -0.4064)
			(end 0.7874 -0.4064)
			(stroke
				(width 0.1524)
				(type default)
			)
			(layer "F.SilkS")
		)
		(fp_line
			(start 0.67945 0.3048)
			(end 0.120396 0.3048)
			(stroke
				(width 0.1)
				(type default)
			)
			(layer "F.Fab")
		)
		(fp_line
			(start 0.67945 -0.3048)
			(end 0.67945 0.3048)
			(stroke
				(width 0.1)
				(type default)
			)
			(layer "F.Fab")
		)
		(fp_line
			(start 0.12065 -0.2794)
			(end 0.12065 -0.3048)
			(stroke
				(width 0.1)
				(type default)
			)
			(layer "F.Fab")
		)
		(fp_line
			(start 0.12065 -0.3048)
			(end 0.67945 -0.3048)
			(stroke
				(width 0.1)
				(type default)
			)
			(layer "F.Fab")
		)
		(fp_line
			(start 0.120396 0.3048)
			(end 0.120396 0.2794)
			(stroke
				(width 0.1)
				(type default)
			)
			(layer "F.Fab")
		)
		(fp_line
			(start 0.120396 0.2794)
			(end -0.12065 0.2794)
			(stroke
				(width 0.1)
				(type default)
			)
			(layer "F.Fab")
		)
		(fp_line
			(start -0.12065 0.3048)
			(end -0.67945 0.3048)
			(stroke
				(width 0.1)
				(type default)
			)
			(layer "F.Fab")
		)
		(fp_line
			(start -0.12065 0.2794)
			(end -0.12065 0.3048)
			(stroke
				(width 0.1)
				(type default)
			)
			(layer "F.Fab")
		)
		(fp_line
			(start -0.12065 -0.2794)
			(end 0.12065 -0.2794)
			(stroke
				(width 0.1)
				(type default)
			)
			(layer "F.Fab")
		)
		(fp_line
			(start -0.12065 -0.305054)
			(end -0.12065 -0.2794)
			(stroke
				(width 0.1)
				(type default)
			)
			(layer "F.Fab")
		)
		(fp_line
			(start -0.67945 0.3048)
			(end -0.67945 -0.305054)
			(stroke
				(width 0.1)
				(type default)
			)
			(layer "F.Fab")
		)
		(fp_line
			(start -0.67945 -0.305054)
			(end -0.12065 -0.305054)
			(stroke
				(width 0.1)
				(type default)
			)
			(layer "F.Fab")
		)
		(pad "1" smd circle
			(at -0.40005 0 180)
			(size 0 0)
			(layers "F.Cu" "F.Mask" "F.Paste")
			(net "SW_PVDDIO_P1_SW4")
		)
		(pad "2" smd circle
			(at 0.40005 0 180)
			(size 0 0)
			(layers "F.Cu" "F.Mask" "F.Paste")
			(net "SW_PVDDIO_P1_SW4_RC")
		)
	)
	(footprint ""
		(layer "F.Cu")
		(at 104.7623 -389.49376)
		(property "Reference" "R1378"
			(at 0 0 0)
			(layer "F.SilkS")
			(hide yes)
			(effects
				(font
					(size 1.27 1.27)
				)
			)
		)
		(property "Value" ""
			(at 0 0 0)
			(layer "F.Fab")
			(effects
				(font
					(size 1.27 1.27)
				)
			)
		)
		(duplicate_pad_numbers_are_jumpers no)
		(fp_line
			(start -0.32512 -0.175006)
			(end 0.32512 -0.175006)
			(stroke
				(width 0.1)
				(type default)
			)
			(layer "F.Fab")
		)
		(fp_line
			(start -0.32512 0.175006)
			(end -0.32512 -0.175006)
			(stroke
				(width 0.1)
				(type default)
			)
			(layer "F.Fab")
		)
		(fp_line
			(start 0.32512 -0.175006)
			(end 0.32512 0.175006)
			(stroke
				(width 0.1)
				(type default)
			)
			(layer "F.Fab")
		)
		(fp_line
			(start 0.32512 0.175006)
			(end -0.32512 0.175006)
			(stroke
				(width 0.1)
				(type default)
			)
			(layer "F.Fab")
		)
		(pad "1" smd rect
			(at -0.2667 0)
			(size 0.3048 0.381)
			(layers "F.Cu" "F.Mask" "F.Paste")
			(net "RXDET_BYP_RT_CPU1_P1")
		)
		(pad "2" smd rect
			(at 0.2667 0 180)
			(size 0.3048 0.381)
			(layers "F.Cu" "F.Mask" "F.Paste")
			(net "GND")
		)
	)
	(footprint ""
		(layer "F.Cu")
		(at 143.352266 -408.517344 -90)
		(property "Reference" "C6711"
			(at 0 0 270)
			(layer "F.SilkS")
			(hide yes)
			(effects
				(font
					(size 1.27 1.27)
				)
			)
		)
		(property "Value" ""
			(at 0 0 270)
			(layer "F.Fab")
			(effects
				(font
					(size 1.27 1.27)
				)
			)
		)
		(duplicate_pad_numbers_are_jumpers no)
		(fp_line
			(start -0.299974 0.150114)
			(end -0.299974 -0.150114)
			(stroke
				(width 0.1)
				(type default)
			)
			(layer "F.Fab")
		)
		(fp_line
			(start 0.299974 0.150114)
			(end -0.299974 0.150114)
			(stroke
				(width 0.1)
				(type default)
			)
			(layer "F.Fab")
		)
		(fp_line
			(start -0.299974 -0.150114)
			(end 0.299974 -0.150114)
			(stroke
				(width 0.1)
				(type default)
			)
			(layer "F.Fab")
		)
		(fp_line
			(start 0.299974 -0.150114)
			(end 0.299974 0.150114)
			(stroke
				(width 0.1)
				(type default)
			)
			(layer "F.Fab")
		)
		(pad "1" smd rect
			(at -0.2667 0 270)
			(size 0.3048 0.381)
			(layers "F.Cu" "F.Mask" "F.Paste")
			(net "P5E_CPU1_P2_TX_BUF_C_DP<9>")
		)
		(pad "2" smd rect
			(at 0.2667 0 270)
			(size 0.3048 0.381)
			(layers "F.Cu" "F.Mask" "F.Paste")
			(net "P5E_CPU1_P2_TX_BUF_DP<9>")
		)
	)
	(footprint ""
		(layer "F.Cu")
		(at 47.18304 -438.753504 -90)
		(property "Reference" "R2912"
			(at 0 0 270)
			(layer "F.SilkS")
			(hide yes)
			(effects
				(font
					(size 1.27 1.27)
				)
			)
		)
		(property "Value" ""
			(at 0 0 270)
			(layer "F.Fab")
			(effects
				(font
					(size 1.27 1.27)
				)
			)
		)
		(duplicate_pad_numbers_are_jumpers no)
		(fp_line
			(start -0.7874 0.4064)
			(end -0.7874 -0.4064)
			(stroke
				(width 0.1524)
				(type default)
			)
			(layer "F.SilkS")
		)
		(fp_line
			(start 0.7874 0.4064)
			(end -0.7874 0.4064)
			(stroke
				(width 0.1524)
				(type default)
			)
			(layer "F.SilkS")
		)
		(fp_line
			(start -0.7874 -0.4064)
			(end 0.7874 -0.4064)
			(stroke
				(width 0.1524)
				(type default)
			)
			(layer "F.SilkS")
		)
		(fp_line
			(start 0.7874 -0.4064)
			(end 0.7874 0.4064)
			(stroke
				(width 0.1524)
				(type default)
			)
			(layer "F.SilkS")
		)
		(fp_line
			(start -0.67945 0.3048)
			(end -0.67945 -0.305054)
			(stroke
				(width 0.1)
				(type default)
			)
			(layer "F.Fab")
		)
		(fp_line
			(start -0.12065 0.3048)
			(end -0.67945 0.3048)
			(stroke
				(width 0.1)
				(type default)
			)
			(layer "F.Fab")
		)
		(fp_line
			(start 0.120396 0.3048)
			(end 0.120396 0.2794)
			(stroke
				(width 0.1)
				(type default)
			)
			(layer "F.Fab")
		)
		(fp_line
			(start 0.67945 0.3048)
			(end 0.120396 0.3048)
			(stroke
				(width 0.1)
				(type default)
			)
			(layer "F.Fab")
		)
		(fp_line
			(start -0.12065 0.2794)
			(end -0.12065 0.3048)
			(stroke
				(width 0.1)
				(type default)
			)
			(layer "F.Fab")
		)
		(fp_line
			(start 0.120396 0.2794)
			(end -0.12065 0.2794)
			(stroke
				(width 0.1)
				(type default)
			)
			(layer "F.Fab")
		)
		(fp_line
			(start -0.12065 -0.2794)
			(end 0.12065 -0.2794)
			(stroke
				(width 0.1)
				(type default)
			)
			(layer "F.Fab")
		)
		(fp_line
			(start 0.12065 -0.2794)
			(end 0.12065 -0.3048)
			(stroke
				(width 0.1)
				(type default)
			)
			(layer "F.Fab")
		)
		(fp_line
			(start 0.12065 -0.3048)
			(end 0.67945 -0.3048)
			(stroke
				(width 0.1)
				(type default)
			)
			(layer "F.Fab")
		)
		(fp_line
			(start 0.67945 -0.3048)
			(end 0.67945 0.3048)
			(stroke
				(width 0.1)
				(type default)
			)
			(layer "F.Fab")
		)
		(fp_line
			(start -0.67945 -0.305054)
			(end -0.12065 -0.305054)
			(stroke
				(width 0.1)
				(type default)
			)
			(layer "F.Fab")
		)
		(fp_line
			(start -0.12065 -0.305054)
			(end -0.12065 -0.2794)
			(stroke
				(width 0.1)
				(type default)
			)
			(layer "F.Fab")
		)
		(pad "1" smd circle
			(at -0.40005 0 270)
			(size 0 0)
			(layers "F.Cu" "F.Mask" "F.Paste")
			(net "P3V3_AUX")
		)
		(pad "2" smd circle
			(at 0.40005 0 270)
			(size 0 0)
			(layers "F.Cu" "F.Mask" "F.Paste")
			(net "FM_GPU_PWR_EN_R1")
		)
	)
	(footprint ""
		(layer "F.Cu")
		(at 211.21116 -16.343122 -90)
		(property "Reference" "R1141"
			(at 0 0 270)
			(layer "F.SilkS")
			(hide yes)
			(effects
				(font
					(size 1.27 1.27)
				)
			)
		)
		(property "Value" ""
			(at 0 0 270)
			(layer "F.Fab")
			(effects
				(font
					(size 1.27 1.27)
				)
			)
		)
		(duplicate_pad_numbers_are_jumpers no)
		(fp_line
			(start -0.7874 0.4064)
			(end -0.7874 -0.4064)
			(stroke
				(width 0.1524)
				(type default)
			)
			(layer "F.SilkS")
		)
		(fp_line
			(start 0.7874 0.4064)
			(end -0.7874 0.4064)
			(stroke
				(width 0.1524)
				(type default)
			)
			(layer "F.SilkS")
		)
		(fp_line
			(start -0.7874 -0.4064)
			(end 0.7874 -0.4064)
			(stroke
				(width 0.1524)
				(type default)
			)
			(layer "F.SilkS")
		)
		(fp_line
			(start 0.7874 -0.4064)
			(end 0.7874 0.4064)
			(stroke
				(width 0.1524)
				(type default)
			)
			(layer "F.SilkS")
		)
		(fp_line
			(start -0.67945 0.3048)
			(end -0.67945 -0.305054)
			(stroke
				(width 0.1)
				(type default)
			)
			(layer "F.Fab")
		)
		(fp_line
			(start -0.12065 0.3048)
			(end -0.67945 0.3048)
			(stroke
				(width 0.1)
				(type default)
			)
			(layer "F.Fab")
		)
		(fp_line
			(start 0.120396 0.3048)
			(end 0.120396 0.2794)
			(stroke
				(width 0.1)
				(type default)
			)
			(layer "F.Fab")
		)
		(fp_line
			(start 0.67945 0.3048)
			(end 0.120396 0.3048)
			(stroke
				(width 0.1)
				(type default)
			)
			(layer "F.Fab")
		)
		(fp_line
			(start -0.12065 0.2794)
			(end -0.12065 0.3048)
			(stroke
				(width 0.1)
				(type default)
			)
			(layer "F.Fab")
		)
		(fp_line
			(start 0.120396 0.2794)
			(end -0.12065 0.2794)
			(stroke
				(width 0.1)
				(type default)
			)
			(layer "F.Fab")
		)
		(fp_line
			(start -0.12065 -0.2794)
			(end 0.12065 -0.2794)
			(stroke
				(width 0.1)
				(type default)
			)
			(layer "F.Fab")
		)
		(fp_line
			(start 0.12065 -0.2794)
			(end 0.12065 -0.3048)
			(stroke
				(width 0.1)
				(type default)
			)
			(layer "F.Fab")
		)
		(fp_line
			(start 0.12065 -0.3048)
			(end 0.67945 -0.3048)
			(stroke
				(width 0.1)
				(type default)
			)
			(layer "F.Fab")
		)
		(fp_line
			(start 0.67945 -0.3048)
			(end 0.67945 0.3048)
			(stroke
				(width 0.1)
				(type default)
			)
			(layer "F.Fab")
		)
		(fp_line
			(start -0.67945 -0.305054)
			(end -0.12065 -0.305054)
			(stroke
				(width 0.1)
				(type default)
			)
			(layer "F.Fab")
		)
		(fp_line
			(start -0.12065 -0.305054)
			(end -0.12065 -0.2794)
			(stroke
				(width 0.1)
				(type default)
			)
			(layer "F.Fab")
		)
		(pad "1" smd circle
			(at -0.40005 0 270)
			(size 0 0)
			(layers "F.Cu" "F.Mask" "F.Paste")
			(net "CLK_50M_NCSI_OCP_1")
		)
		(pad "2" smd circle
			(at 0.40005 0 270)
			(size 0 0)
			(layers "F.Cu" "F.Mask" "F.Paste")
			(net "CLK_50M_NCSI_OCP_SFF")
		)
	)
	(footprint ""
		(layer "F.Cu")
		(at 10.066782 -409.675584 180)
		(property "Reference" "PC514"
			(at 0 0 180)
			(layer "F.SilkS")
			(hide yes)
			(effects
				(font
					(size 1.27 1.27)
				)
			)
		)
		(property "Value" ""
			(at 0 0 180)
			(layer "F.Fab")
			(effects
				(font
					(size 1.27 1.27)
				)
			)
		)
		(duplicate_pad_numbers_are_jumpers no)
		(fp_line
			(start 0.7874 0.4064)
			(end -0.7874 0.4064)
			(stroke
				(width 0.1524)
				(type default)
			)
			(layer "F.SilkS")
		)
		(fp_line
			(start 0.7874 -0.4064)
			(end 0.7874 0.4064)
			(stroke
				(width 0.1524)
				(type default)
			)
			(layer "F.SilkS")
		)
		(fp_line
			(start -0.7874 0.4064)
			(end -0.7874 -0.4064)
			(stroke
				(width 0.1524)
				(type default)
			)
			(layer "F.SilkS")
		)
		(fp_line
			(start -0.7874 -0.4064)
			(end 0.7874 -0.4064)
			(stroke
				(width 0.1524)
				(type default)
			)
			(layer "F.SilkS")
		)
		(fp_line
			(start 0.67945 0.3048)
			(end 0.120396 0.3048)
			(stroke
				(width 0.1)
				(type default)
			)
			(layer "F.Fab")
		)
		(fp_line
			(start 0.67945 -0.3048)
			(end 0.67945 0.3048)
			(stroke
				(width 0.1)
				(type default)
			)
			(layer "F.Fab")
		)
		(fp_line
			(start 0.12065 -0.2794)
			(end 0.12065 -0.3048)
			(stroke
				(width 0.1)
				(type default)
			)
			(layer "F.Fab")
		)
		(fp_line
			(start 0.12065 -0.3048)
			(end 0.67945 -0.3048)
			(stroke
				(width 0.1)
				(type default)
			)
			(layer "F.Fab")
		)
		(fp_line
			(start 0.120396 0.3048)
			(end 0.120396 0.2794)
			(stroke
				(width 0.1)
				(type default)
			)
			(layer "F.Fab")
		)
		(fp_line
			(start 0.120396 0.2794)
			(end -0.12065 0.2794)
			(stroke
				(width 0.1)
				(type default)
			)
			(layer "F.Fab")
		)
		(fp_line
			(start -0.12065 0.3048)
			(end -0.67945 0.3048)
			(stroke
				(width 0.1)
				(type default)
			)
			(layer "F.Fab")
		)
		(fp_line
			(start -0.12065 0.2794)
			(end -0.12065 0.3048)
			(stroke
				(width 0.1)
				(type default)
			)
			(layer "F.Fab")
		)
		(fp_line
			(start -0.12065 -0.2794)
			(end 0.12065 -0.2794)
			(stroke
				(width 0.1)
				(type default)
			)
			(layer "F.Fab")
		)
		(fp_line
			(start -0.12065 -0.305054)
			(end -0.12065 -0.2794)
			(stroke
				(width 0.1)
				(type default)
			)
			(layer "F.Fab")
		)
		(fp_line
			(start -0.67945 0.3048)
			(end -0.67945 -0.305054)
			(stroke
				(width 0.1)
				(type default)
			)
			(layer "F.Fab")
		)
		(fp_line
			(start -0.67945 -0.305054)
			(end -0.12065 -0.305054)
			(stroke
				(width 0.1)
				(type default)
			)
			(layer "F.Fab")
		)
		(pad "1" smd circle
			(at -0.40005 0 180)
			(size 0 0)
			(layers "F.Cu" "F.Mask" "F.Paste")
			(net "P0V9_RETIMER_CPU1_VMON")
		)
		(pad "2" smd circle
			(at 0.40005 0 180)
			(size 0 0)
			(layers "F.Cu" "F.Mask" "F.Paste")
			(net "GND")
		)
	)
	(footprint ""
		(layer "F.Cu")
		(at 468.957914 -42.121836 180)
		(property "Reference" "R4061"
			(at 0 0 180)
			(layer "F.SilkS")
			(hide yes)
			(effects
				(font
					(size 1.27 1.27)
				)
			)
		)
		(property "Value" ""
			(at 0 0 180)
			(layer "F.Fab")
			(effects
				(font
					(size 1.27 1.27)
				)
			)
		)
		(duplicate_pad_numbers_are_jumpers no)
		(fp_line
			(start 0.7874 0.4064)
			(end -0.7874 0.4064)
			(stroke
				(width 0.1524)
				(type default)
			)
			(layer "F.SilkS")
		)
		(fp_line
			(start 0.7874 -0.4064)
			(end 0.7874 0.4064)
			(stroke
				(width 0.1524)
				(type default)
			)
			(layer "F.SilkS")
		)
		(fp_line
			(start -0.7874 0.4064)
			(end -0.7874 -0.4064)
			(stroke
				(width 0.1524)
				(type default)
			)
			(layer "F.SilkS")
		)
		(fp_line
			(start -0.7874 -0.4064)
			(end 0.7874 -0.4064)
			(stroke
				(width 0.1524)
				(type default)
			)
			(layer "F.SilkS")
		)
		(fp_line
			(start 0.67945 0.3048)
			(end 0.120396 0.3048)
			(stroke
				(width 0.1)
				(type default)
			)
			(layer "F.Fab")
		)
		(fp_line
			(start 0.67945 -0.3048)
			(end 0.67945 0.3048)
			(stroke
				(width 0.1)
				(type default)
			)
			(layer "F.Fab")
		)
		(fp_line
			(start 0.12065 -0.2794)
			(end 0.12065 -0.3048)
			(stroke
				(width 0.1)
				(type default)
			)
			(layer "F.Fab")
		)
		(fp_line
			(start 0.12065 -0.3048)
			(end 0.67945 -0.3048)
			(stroke
				(width 0.1)
				(type default)
			)
			(layer "F.Fab")
		)
		(fp_line
			(start 0.120396 0.3048)
			(end 0.120396 0.2794)
			(stroke
				(width 0.1)
				(type default)
			)
			(layer "F.Fab")
		)
		(fp_line
			(start 0.120396 0.2794)
			(end -0.12065 0.2794)
			(stroke
				(width 0.1)
				(type default)
			)
			(layer "F.Fab")
		)
		(fp_line
			(start -0.12065 0.3048)
			(end -0.67945 0.3048)
			(stroke
				(width 0.1)
				(type default)
			)
			(layer "F.Fab")
		)
		(fp_line
			(start -0.12065 0.2794)
			(end -0.12065 0.3048)
			(stroke
				(width 0.1)
				(type default)
			)
			(layer "F.Fab")
		)
		(fp_line
			(start -0.12065 -0.2794)
			(end 0.12065 -0.2794)
			(stroke
				(width 0.1)
				(type default)
			)
			(layer "F.Fab")
		)
		(fp_line
			(start -0.12065 -0.305054)
			(end -0.12065 -0.2794)
			(stroke
				(width 0.1)
				(type default)
			)
			(layer "F.Fab")
		)
		(fp_line
			(start -0.67945 0.3048)
			(end -0.67945 -0.305054)
			(stroke
				(width 0.1)
				(type default)
			)
			(layer "F.Fab")
		)
		(fp_line
			(start -0.67945 -0.305054)
			(end -0.12065 -0.305054)
			(stroke
				(width 0.1)
				(type default)
			)
			(layer "F.Fab")
		)
		(pad "1" smd circle
			(at -0.40005 0 180)
			(size 0 0)
			(layers "F.Cu" "F.Mask" "F.Paste")
			(net "P12V_OCP_SFF_EN_R")
		)
		(pad "2" smd circle
			(at 0.40005 0 180)
			(size 0 0)
			(layers "F.Cu" "F.Mask" "F.Paste")
			(net "P12V_OCP_EN_1_R")
		)
	)
	(footprint ""
		(layer "F.Cu")
		(at 22.036278 -435.948074 180)
		(property "Reference" "R2991"
			(at 0 0 180)
			(layer "F.SilkS")
			(hide yes)
			(effects
				(font
					(size 1.27 1.27)
				)
			)
		)
		(property "Value" ""
			(at 0 0 180)
			(layer "F.Fab")
			(effects
				(font
					(size 1.27 1.27)
				)
			)
		)
		(duplicate_pad_numbers_are_jumpers no)
		(fp_line
			(start 0.7874 0.4064)
			(end -0.7874 0.4064)
			(stroke
				(width 0.1524)
				(type default)
			)
			(layer "F.SilkS")
		)
		(fp_line
			(start 0.7874 -0.4064)
			(end 0.7874 0.4064)
			(stroke
				(width 0.1524)
				(type default)
			)
			(layer "F.SilkS")
		)
		(fp_line
			(start -0.7874 0.4064)
			(end -0.7874 -0.4064)
			(stroke
				(width 0.1524)
				(type default)
			)
			(layer "F.SilkS")
		)
		(fp_line
			(start -0.7874 -0.4064)
			(end 0.7874 -0.4064)
			(stroke
				(width 0.1524)
				(type default)
			)
			(layer "F.SilkS")
		)
		(fp_line
			(start 0.67945 0.3048)
			(end 0.120396 0.3048)
			(stroke
				(width 0.1)
				(type default)
			)
			(layer "F.Fab")
		)
		(fp_line
			(start 0.67945 -0.3048)
			(end 0.67945 0.3048)
			(stroke
				(width 0.1)
				(type default)
			)
			(layer "F.Fab")
		)
		(fp_line
			(start 0.12065 -0.2794)
			(end 0.12065 -0.3048)
			(stroke
				(width 0.1)
				(type default)
			)
			(layer "F.Fab")
		)
		(fp_line
			(start 0.12065 -0.3048)
			(end 0.67945 -0.3048)
			(stroke
				(width 0.1)
				(type default)
			)
			(layer "F.Fab")
		)
		(fp_line
			(start 0.120396 0.3048)
			(end 0.120396 0.2794)
			(stroke
				(width 0.1)
				(type default)
			)
			(layer "F.Fab")
		)
		(fp_line
			(start 0.120396 0.2794)
			(end -0.12065 0.2794)
			(stroke
				(width 0.1)
				(type default)
			)
			(layer "F.Fab")
		)
		(fp_line
			(start -0.12065 0.3048)
			(end -0.67945 0.3048)
			(stroke
				(width 0.1)
				(type default)
			)
			(layer "F.Fab")
		)
		(fp_line
			(start -0.12065 0.2794)
			(end -0.12065 0.3048)
			(stroke
				(width 0.1)
				(type default)
			)
			(layer "F.Fab")
		)
		(fp_line
			(start -0.12065 -0.2794)
			(end 0.12065 -0.2794)
			(stroke
				(width 0.1)
				(type default)
			)
			(layer "F.Fab")
		)
		(fp_line
			(start -0.12065 -0.305054)
			(end -0.12065 -0.2794)
			(stroke
				(width 0.1)
				(type default)
			)
			(layer "F.Fab")
		)
		(fp_line
			(start -0.67945 0.3048)
			(end -0.67945 -0.305054)
			(stroke
				(width 0.1)
				(type default)
			)
			(layer "F.Fab")
		)
		(fp_line
			(start -0.67945 -0.305054)
			(end -0.12065 -0.305054)
			(stroke
				(width 0.1)
				(type default)
			)
			(layer "F.Fab")
		)
		(pad "1" smd circle
			(at -0.40005 0 180)
			(size 0 0)
			(layers "F.Cu" "F.Mask" "F.Paste")
			(net "SMB_2_BMC_GPU_BUF_R_SDA")
		)
		(pad "2" smd circle
			(at 0.40005 0 180)
			(size 0 0)
			(layers "F.Cu" "F.Mask" "F.Paste")
			(net "SMB_2_BMC_GPU_BUF_SDA")
		)
	)
	(footprint ""
		(layer "F.Cu")
		(at 234.300014 -50.55997 180)
		(property "Reference" "J90"
			(at 4.181094 -11.365484 90)
			(unlocked yes)
			(layer "F.SilkS")
			(effects
				(font
					(size 0.7874 0.5842)
					(thickness 0.1524)
				)
			)
		)
		(property "Value" ""
			(at 0 0 180)
			(layer "F.Fab")
			(effects
				(font
					(size 1.27 1.27)
				)
			)
		)
		(duplicate_pad_numbers_are_jumpers no)
		(fp_line
			(start 3.150108 12.115038)
			(end 1.529334 12.115038)
			(stroke
				(width 0.1524)
				(type default)
			)
			(layer "F.SilkS")
		)
		(fp_line
			(start 3.150108 7.86003)
			(end 3.150108 12.115038)
			(stroke
				(width 0.1524)
				(type default)
			)
			(layer "F.SilkS")
		)
		(fp_line
			(start 3.150108 5.95503)
			(end 3.150108 6.71703)
			(stroke
				(width 0.1524)
				(type default)
			)
			(layer "F.SilkS")
		)
		(fp_line
			(start 3.150108 4.17703)
			(end 3.150108 4.93903)
			(stroke
				(width 0.1524)
				(type default)
			)
			(layer "F.SilkS")
		)
		(fp_line
			(start 3.150108 2.39903)
			(end 3.150108 3.28803)
			(stroke
				(width 0.1524)
				(type default)
			)
			(layer "F.SilkS")
		)
		(fp_line
			(start 3.150108 -12.115038)
			(end 3.150108 1.38303)
			(stroke
				(width 0.1524)
				(type default)
			)
			(layer "F.SilkS")
		)
		(fp_line
			(start 3.074924 12.014962)
			(end 1.632204 12.014962)
			(stroke
				(width 0.1524)
				(type default)
			)
			(layer "F.SilkS")
		)
		(fp_line
			(start 3.074924 7.86003)
			(end 3.074924 12.014962)
			(stroke
				(width 0.1524)
				(type default)
			)
			(layer "F.SilkS")
		)
		(fp_line
			(start 3.074924 5.95503)
			(end 3.074924 6.71703)
			(stroke
				(width 0.1524)
				(type default)
			)
			(layer "F.SilkS")
		)
		(fp_line
			(start 3.074924 4.17703)
			(end 3.074924 4.93903)
			(stroke
				(width 0.1524)
				(type default)
			)
			(layer "F.SilkS")
		)
		(fp_line
			(start 3.074924 2.39903)
			(end 3.074924 3.28803)
			(stroke
				(width 0.1524)
				(type default)
			)
			(layer "F.SilkS")
		)
		(fp_line
			(start 3.074924 -12.014962)
			(end 3.074924 1.38303)
			(stroke
				(width 0.1524)
				(type default)
			)
			(layer "F.SilkS")
		)
		(fp_line
			(start 1.632204 -12.014962)
			(end 3.074924 -12.014962)
			(stroke
				(width 0.1524)
				(type default)
			)
			(layer "F.SilkS")
		)
		(fp_line
			(start 1.529334 -12.115038)
			(end 3.150108 -12.115038)
			(stroke
				(width 0.1524)
				(type default)
			)
			(layer "F.SilkS")
		)
		(fp_line
			(start -1.529334 12.115038)
			(end -3.150108 12.115038)
			(stroke
				(width 0.1524)
				(type default)
			)
			(layer "F.SilkS")
		)
		(fp_line
			(start -1.632204 12.014962)
			(end -3.074924 12.014962)
			(stroke
				(width 0.1524)
				(type default)
			)
			(layer "F.SilkS")
		)
		(fp_line
			(start -3.074924 12.014962)
			(end -3.074924 7.73303)
			(stroke
				(width 0.1524)
				(type default)
			)
			(layer "F.SilkS")
		)
		(fp_line
			(start -3.074924 6.84403)
			(end -3.074924 5.95503)
			(stroke
				(width 0.1524)
				(type default)
			)
			(layer "F.SilkS")
		)
		(fp_line
			(start -3.074924 4.93903)
			(end -3.074924 4.17703)
			(stroke
				(width 0.1524)
				(type default)
			)
			(layer "F.SilkS")
		)
		(fp_line
			(start -3.074924 3.16103)
			(end -3.074924 2.39903)
			(stroke
				(width 0.1524)
				(type default)
			)
			(layer "F.SilkS")
		)
		(fp_line
			(start -3.074924 1.38303)
			(end -3.074924 0.62103)
			(stroke
				(width 0.1524)
				(type default)
			)
			(layer "F.SilkS")
		)
		(fp_line
			(start -3.074924 -0.52197)
			(end -3.074924 -12.014962)
			(stroke
				(width 0.1524)
				(type default)
			)
			(layer "F.SilkS")
		)
		(fp_line
			(start -3.074924 -12.014962)
			(end -1.632204 -12.014962)
			(stroke
				(width 0.1524)
				(type default)
			)
			(layer "F.SilkS")
		)
		(fp_line
			(start -3.150108 12.115038)
			(end -3.150108 7.73303)
			(stroke
				(width 0.1524)
				(type default)
			)
			(layer "F.SilkS")
		)
		(fp_line
			(start -3.150108 6.84403)
			(end -3.150108 5.95503)
			(stroke
				(width 0.1524)
				(type default)
			)
			(layer "F.SilkS")
		)
		(fp_line
			(start -3.150108 4.93903)
			(end -3.150108 4.17703)
			(stroke
				(width 0.1524)
				(type default)
			)
			(layer "F.SilkS")
		)
		(fp_line
			(start -3.150108 3.16103)
			(end -3.150108 2.39903)
			(stroke
				(width 0.1524)
				(type default)
			)
			(layer "F.SilkS")
		)
		(fp_line
			(start -3.150108 1.38303)
			(end -3.150108 0.62103)
			(stroke
				(width 0.1524)
				(type default)
			)
			(layer "F.SilkS")
		)
		(fp_line
			(start -3.150108 -0.52197)
			(end -3.150108 -12.115038)
			(stroke
				(width 0.1524)
				(type default)
			)
			(layer "F.SilkS")
		)
		(fp_line
			(start -3.150108 -12.115038)
			(end -1.529334 -12.115038)
			(stroke
				(width 0.1524)
				(type default)
			)
			(layer "F.SilkS")
		)
		(fp_poly
			(pts
				(xy 4.798314 -9.23544) (xy 3.530854 -8.812784) (xy 3.953256 -10.080498)
			)
			(stroke
				(width 0)
				(type default)
			)
			(fill yes)
			(layer "F.SilkS")
		)
		(fp_line
			(start 3.074924 12.014962)
			(end -3.074924 12.014962)
			(stroke
				(width 0.1)
				(type default)
			)
			(layer "F.Fab")
		)
		(fp_line
			(start 3.074924 -12.014962)
			(end 3.074924 12.014962)
			(stroke
				(width 0.1)
				(type default)
			)
			(layer "F.Fab")
		)
		(fp_line
			(start -3.074924 12.014962)
			(end -3.074924 -12.014962)
			(stroke
				(width 0.1)
				(type default)
			)
			(layer "F.Fab")
		)
		(fp_line
			(start -3.074924 -12.014962)
			(end 3.074924 -12.014962)
			(stroke
				(width 0.1)
				(type default)
			)
			(layer "F.Fab")
		)
		(fp_poly
			(pts
				(xy 3.348736 -7.994904) (xy 4.543806 -8.592566) (xy 4.543806 -7.397496)
			)
			(stroke
				(width 0)
				(type default)
			)
			(fill yes)
			(layer "F.Fab")
		)
		(pad "" np_thru_hole circle
			(at -1.75006 -9.815068 90)
			(size 1.1176 1.1176)
			(drill 1.1176)
			(layers "*.Cu" "*.Mask")
			(clearance 0.381)
			(thermal_gap 0.381)
		)
		(pad "" np_thru_hole circle
			(at 0 9.815068 90)
			(size 1.1176 1.1176)
			(drill 1.1176)
			(layers "*.Cu" "*.Mask")
			(clearance 0.381)
			(thermal_gap 0.381)
		)
		(pad "A1" smd rect
			(at 2.29997 -7.994904 90)
			(size 0.381 1.27)
			(layers "F.Cu" "F.Mask" "F.Paste")
			(net "GND")
		)
		(pad "A2" smd rect
			(at 2.29997 -7.394956 90)
			(size 0.381 1.27)
			(layers "F.Cu" "F.Mask" "F.Paste")
			(net "GND")
		)
		(pad "A3" smd rect
			(at 2.29997 -6.795008 90)
			(size 0.381 1.27)
			(layers "F.Cu" "F.Mask" "F.Paste")
			(net "GND")
		)
		(pad "A4" smd rect
			(at 2.29997 -6.19506 90)
			(size 0.381 1.27)
			(layers "F.Cu" "F.Mask" "F.Paste")
			(net "GND")
		)
		(pad "A5" smd rect
			(at 2.29997 -5.595112 90)
			(size 0.381 1.27)
			(layers "F.Cu" "F.Mask" "F.Paste")
			(net "GND")
		)
		(pad "A6" smd rect
			(at 2.29997 -4.99491 90)
			(size 0.381 1.27)
			(layers "F.Cu" "F.Mask" "F.Paste")
			(net "GND")
		)
		(pad "A7" smd rect
			(at 2.29997 -4.394962 90)
			(size 0.381 1.27)
			(layers "F.Cu" "F.Mask" "F.Paste")
			(net "SMB_E1S_3V3AUX_ISO_SCL")
		)
		(pad "A8" smd rect
			(at 2.29997 -3.795014 90)
			(size 0.381 1.27)
			(layers "F.Cu" "F.Mask" "F.Paste")
			(net "SMB_E1S_3V3AUX_ISO_SDA")
		)
		(pad "A9" smd rect
			(at 2.29997 -3.195066 90)
			(size 0.381 1.27)
			(layers "F.Cu" "F.Mask" "F.Paste")
			(net "RST_SMB_E1S_0_N")
		)
		(pad "A10" smd rect
			(at 2.29997 -2.595118 90)
			(size 0.381 1.27)
			(layers "F.Cu" "F.Mask" "F.Paste")
			(net "FM_LED_ACTIVE_E1S_0_BUF")
		)
		(pad "A11" smd rect
			(at 2.29997 -1.994916 90)
			(size 0.381 1.27)
			(layers "F.Cu" "F.Mask" "F.Paste")
			(net "E1S_0_PERST1_CLKREQ_N")
		)
		(pad "A12" smd rect
			(at 2.29997 -1.394968 90)
			(size 0.381 1.27)
			(layers "F.Cu" "F.Mask" "F.Paste")
			(net "E1S_0_PRSNT_N")
		)
		(pad "A13" smd rect
			(at 2.29997 -0.79502 90)
			(size 0.381 1.27)
			(layers "F.Cu" "F.Mask" "F.Paste")
			(net "GND")
		)
		(pad "A14" smd rect
			(at 2.29997 -0.195072 90)
			(size 0.381 1.27)
			(layers "F.Cu" "F.Mask" "F.Paste")
			(net "TP_CLK_100M_E1S_0_DN")
		)
		(pad "A15" smd rect
			(at 2.29997 0.404876 90)
			(size 0.381 1.27)
			(layers "F.Cu" "F.Mask" "F.Paste")
			(net "TP_CLK_100M_E1S_0_DP")
		)
		(pad "A16" smd rect
			(at 2.29997 1.005078 90)
			(size 0.381 1.27)
			(layers "F.Cu" "F.Mask" "F.Paste")
			(net "GND")
		)
		(pad "A17" smd rect
			(at 2.29997 1.605026 90)
			(size 0.381 1.27)
			(layers "F.Cu" "F.Mask" "F.Paste")
			(net "P3E_CPU0_P4_RX_DP<0>")
		)
		(pad "A18" smd rect
			(at 2.29997 2.204974 90)
			(size 0.381 1.27)
			(layers "F.Cu" "F.Mask" "F.Paste")
			(net "P3E_CPU0_P4_RX_DN<0>")
		)
		(pad "A19" smd rect
			(at 2.29997 2.804922 90)
			(size 0.381 1.27)
			(layers "F.Cu" "F.Mask" "F.Paste")
			(net "GND")
		)
		(pad "A20" smd rect
			(at 2.29997 3.405124 90)
			(size 0.381 1.27)
			(layers "F.Cu" "F.Mask" "F.Paste")
			(net "P3E_CPU0_P4_RX_DP<1>")
		)
		(pad "A21" smd rect
			(at 2.29997 4.005072 90)
			(size 0.381 1.27)
			(layers "F.Cu" "F.Mask" "F.Paste")
			(net "P3E_CPU0_P4_RX_DN<1>")
		)
		(pad "A22" smd rect
			(at 2.29997 4.60502 90)
			(size 0.381 1.27)
			(layers "F.Cu" "F.Mask" "F.Paste")
			(net "GND")
		)
		(pad "A23" smd rect
			(at 2.29997 5.204968 90)
			(size 0.381 1.27)
			(layers "F.Cu" "F.Mask" "F.Paste")
			(net "P3E_CPU0_P4_RX_DP<2>")
		)
		(pad "A24" smd rect
			(at 2.29997 5.804916 90)
			(size 0.381 1.27)
			(layers "F.Cu" "F.Mask" "F.Paste")
			(net "P3E_CPU0_P4_RX_DN<2>")
		)
		(pad "A25" smd rect
			(at 2.29997 6.405118 90)
			(size 0.381 1.27)
			(layers "F.Cu" "F.Mask" "F.Paste")
			(net "GND")
		)
		(pad "A26" smd rect
			(at 2.29997 7.005066 90)
			(size 0.381 1.27)
			(layers "F.Cu" "F.Mask" "F.Paste")
			(net "P3E_CPU0_P4_RX_DP<3>")
		)
		(pad "A27" smd rect
			(at 2.29997 7.605014 90)
			(size 0.381 1.27)
			(layers "F.Cu" "F.Mask" "F.Paste")
			(net "P3E_CPU0_P4_RX_DN<3>")
		)
		(pad "A28" smd rect
			(at 2.29997 8.204962 90)
			(size 0.381 1.27)
			(layers "F.Cu" "F.Mask" "F.Paste")
			(net "GND")
		)
		(pad "B1" smd rect
			(at -2.29997 -7.994904 90)
			(size 0.381 1.27)
			(layers "F.Cu" "F.Mask" "F.Paste")
			(net "P12V_E1S_0_R")
		)
		(pad "B2" smd rect
			(at -2.29997 -7.394956 90)
			(size 0.381 1.27)
			(layers "F.Cu" "F.Mask" "F.Paste")
			(net "P12V_E1S_0_R")
		)
		(pad "B3" smd rect
			(at -2.29997 -6.795008 90)
			(size 0.381 1.27)
			(layers "F.Cu" "F.Mask" "F.Paste")
			(net "P12V_E1S_0_R")
		)
		(pad "B4" smd rect
			(at -2.29997 -6.19506 90)
			(size 0.381 1.27)
			(layers "F.Cu" "F.Mask" "F.Paste")
			(net "P12V_E1S_0_R")
		)
		(pad "B5" smd rect
			(at -2.29997 -5.595112 90)
			(size 0.381 1.27)
			(layers "F.Cu" "F.Mask" "F.Paste")
			(net "P12V_E1S_0_R")
		)
		(pad "B6" smd rect
			(at -2.29997 -4.99491 90)
			(size 0.381 1.27)
			(layers "F.Cu" "F.Mask" "F.Paste")
			(net "P12V_E1S_0_R")
		)
		(pad "B7" smd rect
			(at -2.29997 -4.394962 90)
			(size 0.381 1.27)
			(layers "F.Cu" "F.Mask" "F.Paste")
			(net "TP_E1S_0_MFG")
		)
		(pad "B8" smd rect
			(at -2.29997 -3.795014 90)
			(size 0.381 1.27)
			(layers "F.Cu" "F.Mask" "F.Paste")
			(net "TP_E1S_0_RFU")
		)
		(pad "B9" smd rect
			(at -2.29997 -3.195066 90)
			(size 0.381 1.27)
			(layers "F.Cu" "F.Mask" "F.Paste")
			(net "PU_E1S_0_DUALPORT_EN_N")
		)
		(pad "B10" smd rect
			(at -2.29997 -2.595118 90)
			(size 0.381 1.27)
			(layers "F.Cu" "F.Mask" "F.Paste")
			(net "RST_PCIE_E1S_PERST_N")
		)
		(pad "B11" smd rect
			(at -2.29997 -1.994916 90)
			(size 0.381 1.27)
			(layers "F.Cu" "F.Mask" "F.Paste")
			(net "P3V3_E1S_0")
		)
		(pad "B12" smd rect
			(at -2.29997 -1.394968 90)
			(size 0.381 1.27)
			(layers "F.Cu" "F.Mask" "F.Paste")
			(net "E1S_0_PWRDIS")
		)
		(pad "B13" smd rect
			(at -2.29997 -0.79502 90)
			(size 0.381 1.27)
			(layers "F.Cu" "F.Mask" "F.Paste")
			(net "GND")
		)
		(pad "B14" smd rect
			(at -2.29997 -0.195072 90)
			(size 0.381 1.27)
			(layers "F.Cu" "F.Mask" "F.Paste")
			(net "CLK_100M_CPU0_CLK12_DN")
		)
		(pad "B15" smd rect
			(at -2.29997 0.404876 90)
			(size 0.381 1.27)
			(layers "F.Cu" "F.Mask" "F.Paste")
			(net "CLK_100M_CPU0_CLK12_DP")
		)
		(pad "B16" smd rect
			(at -2.29997 1.005078 90)
			(size 0.381 1.27)
			(layers "F.Cu" "F.Mask" "F.Paste")
			(net "GND")
		)
		(pad "B17" smd rect
			(at -2.29997 1.605026 90)
			(size 0.381 1.27)
			(layers "F.Cu" "F.Mask" "F.Paste")
			(net "P3E_CPU0_P4_TX_C_DP<0>")
		)
		(pad "B18" smd rect
			(at -2.29997 2.204974 90)
			(size 0.381 1.27)
			(layers "F.Cu" "F.Mask" "F.Paste")
			(net "P3E_CPU0_P4_TX_C_DN<0>")
		)
		(pad "B19" smd rect
			(at -2.29997 2.804922 90)
			(size 0.381 1.27)
			(layers "F.Cu" "F.Mask" "F.Paste")
			(net "GND")
		)
		(pad "B20" smd rect
			(at -2.29997 3.405124 90)
			(size 0.381 1.27)
			(layers "F.Cu" "F.Mask" "F.Paste")
			(net "P3E_CPU0_P4_TX_C_DP<1>")
		)
		(pad "B21" smd rect
			(at -2.29997 4.005072 90)
			(size 0.381 1.27)
			(layers "F.Cu" "F.Mask" "F.Paste")
			(net "P3E_CPU0_P4_TX_C_DN<1>")
		)
		(pad "B22" smd rect
			(at -2.29997 4.60502 90)
			(size 0.381 1.27)
			(layers "F.Cu" "F.Mask" "F.Paste")
			(net "GND")
		)
		(pad "B23" smd rect
			(at -2.29997 5.204968 90)
			(size 0.381 1.27)
			(layers "F.Cu" "F.Mask" "F.Paste")
			(net "P3E_CPU0_P4_TX_C_DP<2>")
		)
		(pad "B24" smd rect
			(at -2.29997 5.804916 90)
			(size 0.381 1.27)
			(layers "F.Cu" "F.Mask" "F.Paste")
			(net "P3E_CPU0_P4_TX_C_DN<2>")
		)
		(pad "B25" smd rect
			(at -2.29997 6.405118 90)
			(size 0.381 1.27)
			(layers "F.Cu" "F.Mask" "F.Paste")
			(net "GND")
		)
		(pad "B26" smd rect
			(at -2.29997 7.005066 90)
			(size 0.381 1.27)
			(layers "F.Cu" "F.Mask" "F.Paste")
			(net "P3E_CPU0_P4_TX_C_DN<3>")
		)
		(pad "B27" smd rect
			(at -2.29997 7.605014 90)
			(size 0.381 1.27)
			(layers "F.Cu" "F.Mask" "F.Paste")
			(net "P3E_CPU0_P4_TX_C_DP<3>")
		)
		(pad "B28" smd rect
			(at -2.29997 8.204962 90)
			(size 0.381 1.27)
			(layers "F.Cu" "F.Mask" "F.Paste")
			(net "GND")
		)
		(pad "G1" thru_hole oval
			(at 0 -11.364976 90)
			(size 1.6256 3.4798)
			(drill oval 1.1176 2.4638)
			(layers "*.Cu" "*.Mask")
			(remove_unused_layers no)
			(net "GND")
			(clearance 0.127)
			(thermal_gap 0.127)
		)
		(pad "G2" thru_hole oval
			(at 0 11.364976 90)
			(size 1.6256 3.4798)
			(drill oval 1.1176 2.4638)
			(layers "*.Cu" "*.Mask")
			(remove_unused_layers no)
			(net "GND")
			(clearance 0.127)
			(thermal_gap 0.127)
		)
		(zone
			(layer "F.Cu")
			(hatch none 0.5)
			(connect_pads
				(clearance 0)
			)
			(min_thickness 0.25)
			(keepout
				(tracks not_allowed)
				(vias allowed)
				(pads allowed)
				(copperpour not_allowed)
				(footprints allowed)
			)
			(placement
				(enabled no)
				(sheetname "")
			)
			(fill
				(thermal_gap 0.5)
				(thermal_bridge_width 0.5)
				(island_removal_mode 0)
			)
			(polygon
				(pts
					(xy 232.920032 -38.49497) (xy 236.750098 -38.49497) (xy 236.750098 -41.444926) (xy 232.920032 -41.444926)
				)
			)
		)
		(zone
			(layer "F.Cu")
			(hatch none 0.5)
			(connect_pads
				(clearance 0)
			)
			(min_thickness 0.25)
			(keepout
				(tracks not_allowed)
				(vias allowed)
				(pads allowed)
				(copperpour not_allowed)
				(footprints allowed)
			)
			(placement
				(enabled no)
				(sheetname "")
			)
			(fill
				(thermal_gap 0.5)
				(thermal_bridge_width 0.5)
				(island_removal_mode 0)
			)
			(polygon
				(pts
					(xy 232.929938 -59.675014) (xy 235.679996 -59.675014) (xy 235.679996 -62.62497) (xy 232.929938 -62.62497)
				)
			)
		)
		(zone
			(layers "F.Cu" "B.Cu" "In1.Cu" "In2.Cu" "In3.Cu" "In4.Cu" "In5.Cu" "In6.Cu"
				"In7.Cu" "In8.Cu" "In9.Cu" "In10.Cu" "In11.Cu" "In12.Cu" "In13.Cu" "In14.Cu"
				"In15.Cu" "In16.Cu"
			)
			(hatch none 0.5)
			(connect_pads
				(clearance 0)
			)
			(min_thickness 0.25)
			(keepout
				(tracks not_allowed)
				(vias allowed)
				(pads allowed)
				(copperpour not_allowed)
				(footprints allowed)
			)
			(placement
				(enabled no)
				(sheetname "")
			)
			(fill
				(thermal_gap 0.5)
				(thermal_bridge_width 0.5)
				(island_removal_mode 0)
			)
			(polygon
				(pts
					(arc
						(start 235.265214 -60.375038)
						(mid 233.334814 -60.375038)
						(end 235.265214 -60.375038)
					)
				)
			)
		)
		(zone
			(layers "F.Cu" "B.Cu" "In1.Cu" "In2.Cu" "In3.Cu" "In4.Cu" "In5.Cu" "In6.Cu"
				"In7.Cu" "In8.Cu" "In9.Cu" "In10.Cu" "In11.Cu" "In12.Cu" "In13.Cu" "In14.Cu"
				"In15.Cu" "In16.Cu"
			)
			(hatch none 0.5)
			(connect_pads
				(clearance 0)
			)
			(min_thickness 0.25)
			(keepout
				(tracks not_allowed)
				(vias allowed)
				(pads allowed)
				(copperpour not_allowed)
				(footprints allowed)
			)
			(placement
				(enabled no)
				(sheetname "")
			)
			(fill
				(thermal_gap 0.5)
				(thermal_bridge_width 0.5)
				(island_removal_mode 0)
			)
			(polygon
				(pts
					(arc
						(start 237.015274 -40.744902)
						(mid 235.084874 -40.744902)
						(end 237.015274 -40.744902)
					)
				)
			)
		)
	)
	(footprint ""
		(layer "F.Cu")
		(at 178.689 -407.543 180)
		(property "Reference" "R1117"
			(at 0 0 180)
			(layer "F.SilkS")
			(hide yes)
			(effects
				(font
					(size 1.27 1.27)
				)
			)
		)
		(property "Value" ""
			(at 0 0 180)
			(layer "F.Fab")
			(effects
				(font
					(size 1.27 1.27)
				)
			)
		)
		(duplicate_pad_numbers_are_jumpers no)
		(fp_line
			(start 0.7874 0.4064)
			(end -0.7874 0.4064)
			(stroke
				(width 0.1524)
				(type default)
			)
			(layer "F.SilkS")
		)
		(fp_line
			(start 0.7874 -0.4064)
			(end 0.7874 0.4064)
			(stroke
				(width 0.1524)
				(type default)
			)
			(layer "F.SilkS")
		)
		(fp_line
			(start -0.7874 0.4064)
			(end -0.7874 -0.4064)
			(stroke
				(width 0.1524)
				(type default)
			)
			(layer "F.SilkS")
		)
		(fp_line
			(start -0.7874 -0.4064)
			(end 0.7874 -0.4064)
			(stroke
				(width 0.1524)
				(type default)
			)
			(layer "F.SilkS")
		)
		(fp_line
			(start 0.67945 0.3048)
			(end 0.120396 0.3048)
			(stroke
				(width 0.1)
				(type default)
			)
			(layer "F.Fab")
		)
		(fp_line
			(start 0.67945 -0.3048)
			(end 0.67945 0.3048)
			(stroke
				(width 0.1)
				(type default)
			)
			(layer "F.Fab")
		)
		(fp_line
			(start 0.12065 -0.2794)
			(end 0.12065 -0.3048)
			(stroke
				(width 0.1)
				(type default)
			)
			(layer "F.Fab")
		)
		(fp_line
			(start 0.12065 -0.3048)
			(end 0.67945 -0.3048)
			(stroke
				(width 0.1)
				(type default)
			)
			(layer "F.Fab")
		)
		(fp_line
			(start 0.120396 0.3048)
			(end 0.120396 0.2794)
			(stroke
				(width 0.1)
				(type default)
			)
			(layer "F.Fab")
		)
		(fp_line
			(start 0.120396 0.2794)
			(end -0.12065 0.2794)
			(stroke
				(width 0.1)
				(type default)
			)
			(layer "F.Fab")
		)
		(fp_line
			(start -0.12065 0.3048)
			(end -0.67945 0.3048)
			(stroke
				(width 0.1)
				(type default)
			)
			(layer "F.Fab")
		)
		(fp_line
			(start -0.12065 0.2794)
			(end -0.12065 0.3048)
			(stroke
				(width 0.1)
				(type default)
			)
			(layer "F.Fab")
		)
		(fp_line
			(start -0.12065 -0.2794)
			(end 0.12065 -0.2794)
			(stroke
				(width 0.1)
				(type default)
			)
			(layer "F.Fab")
		)
		(fp_line
			(start -0.12065 -0.305054)
			(end -0.12065 -0.2794)
			(stroke
				(width 0.1)
				(type default)
			)
			(layer "F.Fab")
		)
		(fp_line
			(start -0.67945 0.3048)
			(end -0.67945 -0.305054)
			(stroke
				(width 0.1)
				(type default)
			)
			(layer "F.Fab")
		)
		(fp_line
			(start -0.67945 -0.305054)
			(end -0.12065 -0.305054)
			(stroke
				(width 0.1)
				(type default)
			)
			(layer "F.Fab")
		)
		(pad "1" smd circle
			(at -0.40005 0 180)
			(size 0 0)
			(layers "F.Cu" "F.Mask" "F.Paste")
			(net "MB0_P12V_STBY_PWRGD")
		)
		(pad "2" smd circle
			(at 0.40005 0 180)
			(size 0 0)
			(layers "F.Cu" "F.Mask" "F.Paste")
			(net "AGND_HSC")
		)
	)
	(footprint ""
		(layer "F.Cu")
		(at 34.665158 -170.50766)
		(property "Reference" "R1293"
			(at 0 0 0)
			(layer "F.SilkS")
			(hide yes)
			(effects
				(font
					(size 1.27 1.27)
				)
			)
		)
		(property "Value" ""
			(at 0 0 0)
			(layer "F.Fab")
			(effects
				(font
					(size 1.27 1.27)
				)
			)
		)
		(duplicate_pad_numbers_are_jumpers no)
		(fp_line
			(start -0.7874 -0.4064)
			(end 0.7874 -0.4064)
			(stroke
				(width 0.1524)
				(type default)
			)
			(layer "F.SilkS")
		)
		(fp_line
			(start -0.7874 0.4064)
			(end -0.7874 -0.4064)
			(stroke
				(width 0.1524)
				(type default)
			)
			(layer "F.SilkS")
		)
		(fp_line
			(start 0.7874 -0.4064)
			(end 0.7874 0.4064)
			(stroke
				(width 0.1524)
				(type default)
			)
			(layer "F.SilkS")
		)
		(fp_line
			(start 0.7874 0.4064)
			(end -0.7874 0.4064)
			(stroke
				(width 0.1524)
				(type default)
			)
			(layer "F.SilkS")
		)
		(fp_line
			(start -0.67945 -0.305054)
			(end -0.12065 -0.305054)
			(stroke
				(width 0.1)
				(type default)
			)
			(layer "F.Fab")
		)
		(fp_line
			(start -0.67945 0.3048)
			(end -0.67945 -0.305054)
			(stroke
				(width 0.1)
				(type default)
			)
			(layer "F.Fab")
		)
		(fp_line
			(start -0.12065 -0.305054)
			(end -0.12065 -0.2794)
			(stroke
				(width 0.1)
				(type default)
			)
			(layer "F.Fab")
		)
		(fp_line
			(start -0.12065 -0.2794)
			(end 0.12065 -0.2794)
			(stroke
				(width 0.1)
				(type default)
			)
			(layer "F.Fab")
		)
		(fp_line
			(start -0.12065 0.2794)
			(end -0.12065 0.3048)
			(stroke
				(width 0.1)
				(type default)
			)
			(layer "F.Fab")
		)
		(fp_line
			(start -0.12065 0.3048)
			(end -0.67945 0.3048)
			(stroke
				(width 0.1)
				(type default)
			)
			(layer "F.Fab")
		)
		(fp_line
			(start 0.120396 0.2794)
			(end -0.12065 0.2794)
			(stroke
				(width 0.1)
				(type default)
			)
			(layer "F.Fab")
		)
		(fp_line
			(start 0.120396 0.3048)
			(end 0.120396 0.2794)
			(stroke
				(width 0.1)
				(type default)
			)
			(layer "F.Fab")
		)
		(fp_line
			(start 0.12065 -0.3048)
			(end 0.67945 -0.3048)
			(stroke
				(width 0.1)
				(type default)
			)
			(layer "F.Fab")
		)
		(fp_line
			(start 0.12065 -0.2794)
			(end 0.12065 -0.3048)
			(stroke
				(width 0.1)
				(type default)
			)
			(layer "F.Fab")
		)
		(fp_line
			(start 0.67945 -0.3048)
			(end 0.67945 0.3048)
			(stroke
				(width 0.1)
				(type default)
			)
			(layer "F.Fab")
		)
		(fp_line
			(start 0.67945 0.3048)
			(end 0.120396 0.3048)
			(stroke
				(width 0.1)
				(type default)
			)
			(layer "F.Fab")
		)
		(pad "1" smd rect
			(at -0.40005 0 180)
			(size 0.4572 0.508)
			(layers "F.Cu" "F.Mask" "F.Paste")
			(net "I3C_SPD_DDRAF_CPU1_SCL")
		)
		(pad "2" smd rect
			(at 0.40005 0 180)
			(size 0.4572 0.508)
			(layers "F.Cu" "F.Mask" "F.Paste")
			(net "I3C_SPD_DDRAF_CPU1_LVC1_SCL")
		)
	)
	(footprint ""
		(layer "F.Cu")
		(at 31.429706 19.444716 -90)
		(property "Reference" "U26_SRM"
			(at 0 0 270)
			(layer "F.SilkS")
			(hide yes)
			(effects
				(font
					(size 1.27 1.27)
				)
			)
		)
		(property "Value" ""
			(at 0 0 270)
			(layer "F.Fab")
			(effects
				(font
					(size 1.27 1.27)
				)
			)
		)
		(duplicate_pad_numbers_are_jumpers no)
		(pad "1" smd circle
			(at 0 0 270)
			(size 0.762 0.762)
			(layers "F.Cu" "F.Mask" "F.Paste")
			(net "Net_10786")
		)
	)
	(footprint ""
		(layer "F.Cu")
		(at 298.300902 -20.255992 -90)
		(property "Reference" "U167"
			(at -0.130556 1.749552 90)
			(unlocked yes)
			(layer "F.SilkS")
			(effects
				(font
					(size 0.7874 0.5842)
					(thickness 0.1524)
				)
				(justify left)
			)
		)
		(property "Value" ""
			(at 0 0 270)
			(layer "F.Fab")
			(effects
				(font
					(size 1.27 1.27)
				)
			)
		)
		(duplicate_pad_numbers_are_jumpers no)
		(fp_line
			(start -1.538478 1.150874)
			(end 1.538478 1.150874)
			(stroke
				(width 0.1524)
				(type default)
			)
			(layer "F.SilkS")
		)
		(fp_line
			(start 1.538478 1.150874)
			(end 1.538478 -1.150874)
			(stroke
				(width 0.1524)
				(type default)
			)
			(layer "F.SilkS")
		)
		(fp_line
			(start -1.538478 -1.150874)
			(end -1.538478 1.150874)
			(stroke
				(width 0.1524)
				(type default)
			)
			(layer "F.SilkS")
		)
		(fp_line
			(start 1.538478 -1.150874)
			(end -1.538478 -1.150874)
			(stroke
				(width 0.1524)
				(type default)
			)
			(layer "F.SilkS")
		)
		(fp_poly
			(pts
				(xy -1.378966 -1.298448) (xy -2.187194 -1.567942) (xy -1.648206 -2.106676)
			)
			(stroke
				(width 0)
				(type default)
			)
			(fill yes)
			(layer "F.SilkS")
		)
		(fp_line
			(start -0.674878 1.100074)
			(end 0.674878 1.100074)
			(stroke
				(width 0.1)
				(type default)
			)
			(layer "F.Fab")
		)
		(fp_line
			(start 0.674878 1.100074)
			(end 0.674878 -1.100074)
			(stroke
				(width 0.1)
				(type default)
			)
			(layer "F.Fab")
		)
		(fp_line
			(start -0.674878 -1.100074)
			(end -0.674878 1.100074)
			(stroke
				(width 0.1)
				(type default)
			)
			(layer "F.Fab")
		)
		(fp_line
			(start 0.674878 -1.100074)
			(end -0.674878 -1.100074)
			(stroke
				(width 0.1)
				(type default)
			)
			(layer "F.Fab")
		)
		(fp_poly
			(pts
				(xy -2.4384 -1.030986) (xy -2.4384 -0.268986) (xy -1.6764 -0.649986)
			)
			(stroke
				(width 0)
				(type default)
			)
			(fill yes)
			(layer "F.Fab")
		)
		(pad "1" smd rect
			(at -0.94996 -0.649986 180)
			(size 0.7112 0.9144)
			(layers "F.Cu" "F.Mask" "F.Paste")
			(net "GND")
		)
		(pad "2" smd rect
			(at -0.94996 0.649986 180)
			(size 0.7112 0.9144)
			(layers "F.Cu" "F.Mask" "F.Paste")
			(net "P1V5_BAT_IN")
		)
		(pad "3" smd rect
			(at 0.94996 0.649986 180)
			(size 0.7112 0.9144)
			(layers "F.Cu" "F.Mask" "F.Paste")
			(net "P1V5_BAT_OUT")
		)
		(pad "4" smd rect
			(at 0.94996 -0.649986 180)
			(size 0.7112 0.9144)
			(layers "F.Cu" "F.Mask" "F.Paste")
			(net "BAT_LDO_EN")
		)
	)
	(footprint ""
		(layer "F.Cu")
		(at 425.05884 -378.95403 -90)
		(property "Reference" "C842"
			(at 0 0 270)
			(layer "F.SilkS")
			(hide yes)
			(effects
				(font
					(size 1.27 1.27)
				)
			)
		)
		(property "Value" ""
			(at 0 0 270)
			(layer "F.Fab")
			(effects
				(font
					(size 1.27 1.27)
				)
			)
		)
		(duplicate_pad_numbers_are_jumpers no)
		(fp_line
			(start -0.299974 0.150114)
			(end -0.299974 -0.150114)
			(stroke
				(width 0.1)
				(type default)
			)
			(layer "F.Fab")
		)
		(fp_line
			(start 0.299974 0.150114)
			(end -0.299974 0.150114)
			(stroke
				(width 0.1)
				(type default)
			)
			(layer "F.Fab")
		)
		(fp_line
			(start -0.299974 -0.150114)
			(end 0.299974 -0.150114)
			(stroke
				(width 0.1)
				(type default)
			)
			(layer "F.Fab")
		)
		(fp_line
			(start 0.299974 -0.150114)
			(end 0.299974 0.150114)
			(stroke
				(width 0.1)
				(type default)
			)
			(layer "F.Fab")
		)
		(pad "1" smd rect
			(at -0.2667 0 270)
			(size 0.3048 0.381)
			(layers "F.Cu" "F.Mask" "F.Paste")
			(net "P5E_CPU0_P2_TX_C_DN<13>")
		)
		(pad "2" smd rect
			(at 0.2667 0 270)
			(size 0.3048 0.381)
			(layers "F.Cu" "F.Mask" "F.Paste")
			(net "P5E_CPU0_P2_TX_DN<13>")
		)
	)
	(footprint ""
		(layer "F.Cu")
		(at 145.669 -115.443 180)
		(property "Reference" "R8121"
			(at 0 0 180)
			(layer "F.SilkS")
			(hide yes)
			(effects
				(font
					(size 1.27 1.27)
				)
			)
		)
		(property "Value" ""
			(at 0 0 180)
			(layer "F.Fab")
			(effects
				(font
					(size 1.27 1.27)
				)
			)
		)
		(duplicate_pad_numbers_are_jumpers no)
		(fp_line
			(start 0.7874 0.4064)
			(end -0.7874 0.4064)
			(stroke
				(width 0.1524)
				(type default)
			)
			(layer "F.SilkS")
		)
		(fp_line
			(start 0.7874 -0.4064)
			(end 0.7874 0.4064)
			(stroke
				(width 0.1524)
				(type default)
			)
			(layer "F.SilkS")
		)
		(fp_line
			(start -0.7874 0.4064)
			(end -0.7874 -0.4064)
			(stroke
				(width 0.1524)
				(type default)
			)
			(layer "F.SilkS")
		)
		(fp_line
			(start -0.7874 -0.4064)
			(end 0.7874 -0.4064)
			(stroke
				(width 0.1524)
				(type default)
			)
			(layer "F.SilkS")
		)
		(fp_line
			(start 0.67945 0.3048)
			(end 0.120396 0.3048)
			(stroke
				(width 0.1)
				(type default)
			)
			(layer "F.Fab")
		)
		(fp_line
			(start 0.67945 -0.3048)
			(end 0.67945 0.3048)
			(stroke
				(width 0.1)
				(type default)
			)
			(layer "F.Fab")
		)
		(fp_line
			(start 0.12065 -0.2794)
			(end 0.12065 -0.3048)
			(stroke
				(width 0.1)
				(type default)
			)
			(layer "F.Fab")
		)
		(fp_line
			(start 0.12065 -0.3048)
			(end 0.67945 -0.3048)
			(stroke
				(width 0.1)
				(type default)
			)
			(layer "F.Fab")
		)
		(fp_line
			(start 0.120396 0.3048)
			(end 0.120396 0.2794)
			(stroke
				(width 0.1)
				(type default)
			)
			(layer "F.Fab")
		)
		(fp_line
			(start 0.120396 0.2794)
			(end -0.12065 0.2794)
			(stroke
				(width 0.1)
				(type default)
			)
			(layer "F.Fab")
		)
		(fp_line
			(start -0.12065 0.3048)
			(end -0.67945 0.3048)
			(stroke
				(width 0.1)
				(type default)
			)
			(layer "F.Fab")
		)
		(fp_line
			(start -0.12065 0.2794)
			(end -0.12065 0.3048)
			(stroke
				(width 0.1)
				(type default)
			)
			(layer "F.Fab")
		)
		(fp_line
			(start -0.12065 -0.2794)
			(end 0.12065 -0.2794)
			(stroke
				(width 0.1)
				(type default)
			)
			(layer "F.Fab")
		)
		(fp_line
			(start -0.12065 -0.305054)
			(end -0.12065 -0.2794)
			(stroke
				(width 0.1)
				(type default)
			)
			(layer "F.Fab")
		)
		(fp_line
			(start -0.67945 0.3048)
			(end -0.67945 -0.305054)
			(stroke
				(width 0.1)
				(type default)
			)
			(layer "F.Fab")
		)
		(fp_line
			(start -0.67945 -0.305054)
			(end -0.12065 -0.305054)
			(stroke
				(width 0.1)
				(type default)
			)
			(layer "F.Fab")
		)
		(pad "1" smd circle
			(at -0.40005 0 180)
			(size 0 0)
			(layers "F.Cu" "F.Mask" "F.Paste")
			(net "P12V_AUX")
		)
		(pad "2" smd circle
			(at 0.40005 0 180)
			(size 0 0)
			(layers "F.Cu" "F.Mask" "F.Paste")
			(net "P12V_AUX_UV_TRIGGER")
		)
	)
	(footprint ""
		(layer "F.Cu")
		(at 344.3605 -15.979394 90)
		(property "Reference" "R1207"
			(at 0 0 90)
			(layer "F.SilkS")
			(hide yes)
			(effects
				(font
					(size 1.27 1.27)
				)
			)
		)
		(property "Value" ""
			(at 0 0 90)
			(layer "F.Fab")
			(effects
				(font
					(size 1.27 1.27)
				)
			)
		)
		(duplicate_pad_numbers_are_jumpers no)
		(fp_line
			(start 0.7874 -0.4064)
			(end 0.7874 0.4064)
			(stroke
				(width 0.1524)
				(type default)
			)
			(layer "F.SilkS")
		)
		(fp_line
			(start -0.7874 -0.4064)
			(end 0.7874 -0.4064)
			(stroke
				(width 0.1524)
				(type default)
			)
			(layer "F.SilkS")
		)
		(fp_line
			(start 0.7874 0.4064)
			(end -0.7874 0.4064)
			(stroke
				(width 0.1524)
				(type default)
			)
			(layer "F.SilkS")
		)
		(fp_line
			(start -0.7874 0.4064)
			(end -0.7874 -0.4064)
			(stroke
				(width 0.1524)
				(type default)
			)
			(layer "F.SilkS")
		)
		(fp_line
			(start -0.12065 -0.305054)
			(end -0.12065 -0.2794)
			(stroke
				(width 0.1)
				(type default)
			)
			(layer "F.Fab")
		)
		(fp_line
			(start -0.67945 -0.305054)
			(end -0.12065 -0.305054)
			(stroke
				(width 0.1)
				(type default)
			)
			(layer "F.Fab")
		)
		(fp_line
			(start 0.67945 -0.3048)
			(end 0.67945 0.3048)
			(stroke
				(width 0.1)
				(type default)
			)
			(layer "F.Fab")
		)
		(fp_line
			(start 0.12065 -0.3048)
			(end 0.67945 -0.3048)
			(stroke
				(width 0.1)
				(type default)
			)
			(layer "F.Fab")
		)
		(fp_line
			(start 0.12065 -0.2794)
			(end 0.12065 -0.3048)
			(stroke
				(width 0.1)
				(type default)
			)
			(layer "F.Fab")
		)
		(fp_line
			(start -0.12065 -0.2794)
			(end 0.12065 -0.2794)
			(stroke
				(width 0.1)
				(type default)
			)
			(layer "F.Fab")
		)
		(fp_line
			(start 0.120396 0.2794)
			(end -0.12065 0.2794)
			(stroke
				(width 0.1)
				(type default)
			)
			(layer "F.Fab")
		)
		(fp_line
			(start -0.12065 0.2794)
			(end -0.12065 0.3048)
			(stroke
				(width 0.1)
				(type default)
			)
			(layer "F.Fab")
		)
		(fp_line
			(start 0.67945 0.3048)
			(end 0.120396 0.3048)
			(stroke
				(width 0.1)
				(type default)
			)
			(layer "F.Fab")
		)
		(fp_line
			(start 0.120396 0.3048)
			(end 0.120396 0.2794)
			(stroke
				(width 0.1)
				(type default)
			)
			(layer "F.Fab")
		)
		(fp_line
			(start -0.12065 0.3048)
			(end -0.67945 0.3048)
			(stroke
				(width 0.1)
				(type default)
			)
			(layer "F.Fab")
		)
		(fp_line
			(start -0.67945 0.3048)
			(end -0.67945 -0.305054)
			(stroke
				(width 0.1)
				(type default)
			)
			(layer "F.Fab")
		)
		(pad "1" smd circle
			(at -0.40005 0 90)
			(size 0 0)
			(layers "F.Cu" "F.Mask" "F.Paste")
			(net "P5V_STBY_PWR_LED")
		)
		(pad "2" smd circle
			(at 0.40005 0 90)
			(size 0 0)
			(layers "F.Cu" "F.Mask" "F.Paste")
			(net "P5V_AUX")
		)
	)
	(footprint ""
		(layer "F.Cu")
		(at 304.419 -359.283 180)
		(property "Reference" "C8072"
			(at 0 0 180)
			(layer "F.SilkS")
			(hide yes)
			(effects
				(font
					(size 1.27 1.27)
				)
			)
		)
		(property "Value" ""
			(at 0 0 180)
			(layer "F.Fab")
			(effects
				(font
					(size 1.27 1.27)
				)
			)
		)
		(duplicate_pad_numbers_are_jumpers no)
		(fp_line
			(start 0.7874 0.4064)
			(end -0.7874 0.4064)
			(stroke
				(width 0.1524)
				(type default)
			)
			(layer "F.SilkS")
		)
		(fp_line
			(start 0.7874 -0.4064)
			(end 0.7874 0.4064)
			(stroke
				(width 0.1524)
				(type default)
			)
			(layer "F.SilkS")
		)
		(fp_line
			(start -0.7874 0.4064)
			(end -0.7874 -0.4064)
			(stroke
				(width 0.1524)
				(type default)
			)
			(layer "F.SilkS")
		)
		(fp_line
			(start -0.7874 -0.4064)
			(end 0.7874 -0.4064)
			(stroke
				(width 0.1524)
				(type default)
			)
			(layer "F.SilkS")
		)
		(fp_line
			(start 0.67945 0.3048)
			(end 0.120396 0.3048)
			(stroke
				(width 0.1)
				(type default)
			)
			(layer "F.Fab")
		)
		(fp_line
			(start 0.67945 -0.3048)
			(end 0.67945 0.3048)
			(stroke
				(width 0.1)
				(type default)
			)
			(layer "F.Fab")
		)
		(fp_line
			(start 0.12065 -0.2794)
			(end 0.12065 -0.3048)
			(stroke
				(width 0.1)
				(type default)
			)
			(layer "F.Fab")
		)
		(fp_line
			(start 0.12065 -0.3048)
			(end 0.67945 -0.3048)
			(stroke
				(width 0.1)
				(type default)
			)
			(layer "F.Fab")
		)
		(fp_line
			(start 0.120396 0.3048)
			(end 0.120396 0.2794)
			(stroke
				(width 0.1)
				(type default)
			)
			(layer "F.Fab")
		)
		(fp_line
			(start 0.120396 0.2794)
			(end -0.12065 0.2794)
			(stroke
				(width 0.1)
				(type default)
			)
			(layer "F.Fab")
		)
		(fp_line
			(start -0.12065 0.3048)
			(end -0.67945 0.3048)
			(stroke
				(width 0.1)
				(type default)
			)
			(layer "F.Fab")
		)
		(fp_line
			(start -0.12065 0.2794)
			(end -0.12065 0.3048)
			(stroke
				(width 0.1)
				(type default)
			)
			(layer "F.Fab")
		)
		(fp_line
			(start -0.12065 -0.2794)
			(end 0.12065 -0.2794)
			(stroke
				(width 0.1)
				(type default)
			)
			(layer "F.Fab")
		)
		(fp_line
			(start -0.12065 -0.305054)
			(end -0.12065 -0.2794)
			(stroke
				(width 0.1)
				(type default)
			)
			(layer "F.Fab")
		)
		(fp_line
			(start -0.67945 0.3048)
			(end -0.67945 -0.305054)
			(stroke
				(width 0.1)
				(type default)
			)
			(layer "F.Fab")
		)
		(fp_line
			(start -0.67945 -0.305054)
			(end -0.12065 -0.305054)
			(stroke
				(width 0.1)
				(type default)
			)
			(layer "F.Fab")
		)
		(pad "1" smd circle
			(at -0.40005 0 180)
			(size 0 0)
			(layers "F.Cu" "F.Mask" "F.Paste")
			(net "PWRGD_PVDDIO_P0_R")
		)
		(pad "2" smd circle
			(at 0.40005 0 180)
			(size 0 0)
			(layers "F.Cu" "F.Mask" "F.Paste")
			(net "GND")
		)
	)
	(footprint ""
		(layer "F.Cu")
		(at 186.387994 -133.537198 -90)
		(property "Reference" "R1362"
			(at 0 0 270)
			(layer "F.SilkS")
			(hide yes)
			(effects
				(font
					(size 1.27 1.27)
				)
			)
		)
		(property "Value" ""
			(at 0 0 270)
			(layer "F.Fab")
			(effects
				(font
					(size 1.27 1.27)
				)
			)
		)
		(duplicate_pad_numbers_are_jumpers no)
		(fp_line
			(start -0.7874 0.4064)
			(end -0.7874 -0.4064)
			(stroke
				(width 0.1524)
				(type default)
			)
			(layer "F.SilkS")
		)
		(fp_line
			(start 0.7874 0.4064)
			(end -0.7874 0.4064)
			(stroke
				(width 0.1524)
				(type default)
			)
			(layer "F.SilkS")
		)
		(fp_line
			(start -0.7874 -0.4064)
			(end 0.7874 -0.4064)
			(stroke
				(width 0.1524)
				(type default)
			)
			(layer "F.SilkS")
		)
		(fp_line
			(start 0.7874 -0.4064)
			(end 0.7874 0.4064)
			(stroke
				(width 0.1524)
				(type default)
			)
			(layer "F.SilkS")
		)
		(fp_line
			(start -0.67945 0.3048)
			(end -0.67945 -0.305054)
			(stroke
				(width 0.1)
				(type default)
			)
			(layer "F.Fab")
		)
		(fp_line
			(start -0.12065 0.3048)
			(end -0.67945 0.3048)
			(stroke
				(width 0.1)
				(type default)
			)
			(layer "F.Fab")
		)
		(fp_line
			(start 0.120396 0.3048)
			(end 0.120396 0.2794)
			(stroke
				(width 0.1)
				(type default)
			)
			(layer "F.Fab")
		)
		(fp_line
			(start 0.67945 0.3048)
			(end 0.120396 0.3048)
			(stroke
				(width 0.1)
				(type default)
			)
			(layer "F.Fab")
		)
		(fp_line
			(start -0.12065 0.2794)
			(end -0.12065 0.3048)
			(stroke
				(width 0.1)
				(type default)
			)
			(layer "F.Fab")
		)
		(fp_line
			(start 0.120396 0.2794)
			(end -0.12065 0.2794)
			(stroke
				(width 0.1)
				(type default)
			)
			(layer "F.Fab")
		)
		(fp_line
			(start -0.12065 -0.2794)
			(end 0.12065 -0.2794)
			(stroke
				(width 0.1)
				(type default)
			)
			(layer "F.Fab")
		)
		(fp_line
			(start 0.12065 -0.2794)
			(end 0.12065 -0.3048)
			(stroke
				(width 0.1)
				(type default)
			)
			(layer "F.Fab")
		)
		(fp_line
			(start 0.12065 -0.3048)
			(end 0.67945 -0.3048)
			(stroke
				(width 0.1)
				(type default)
			)
			(layer "F.Fab")
		)
		(fp_line
			(start 0.67945 -0.3048)
			(end 0.67945 0.3048)
			(stroke
				(width 0.1)
				(type default)
			)
			(layer "F.Fab")
		)
		(fp_line
			(start -0.67945 -0.305054)
			(end -0.12065 -0.305054)
			(stroke
				(width 0.1)
				(type default)
			)
			(layer "F.Fab")
		)
		(fp_line
			(start -0.12065 -0.305054)
			(end -0.12065 -0.2794)
			(stroke
				(width 0.1)
				(type default)
			)
			(layer "F.Fab")
		)
		(pad "1" smd circle
			(at -0.40005 0 270)
			(size 0 0)
			(layers "F.Cu" "F.Mask" "F.Paste")
			(net "PWRGD_P3V3_R1")
		)
		(pad "2" smd circle
			(at 0.40005 0 270)
			(size 0 0)
			(layers "F.Cu" "F.Mask" "F.Paste")
			(net "PWRGD_P3V3_R2")
		)
	)
	(footprint ""
		(layer "F.Cu")
		(at 48.095154 -375.49963 -90)
		(property "Reference" "C829"
			(at 0 0 270)
			(layer "F.SilkS")
			(hide yes)
			(effects
				(font
					(size 1.27 1.27)
				)
			)
		)
		(property "Value" ""
			(at 0 0 270)
			(layer "F.Fab")
			(effects
				(font
					(size 1.27 1.27)
				)
			)
		)
		(duplicate_pad_numbers_are_jumpers no)
		(fp_line
			(start -0.299974 0.150114)
			(end -0.299974 -0.150114)
			(stroke
				(width 0.1)
				(type default)
			)
			(layer "F.Fab")
		)
		(fp_line
			(start 0.299974 0.150114)
			(end -0.299974 0.150114)
			(stroke
				(width 0.1)
				(type default)
			)
			(layer "F.Fab")
		)
		(fp_line
			(start -0.299974 -0.150114)
			(end 0.299974 -0.150114)
			(stroke
				(width 0.1)
				(type default)
			)
			(layer "F.Fab")
		)
		(fp_line
			(start 0.299974 -0.150114)
			(end 0.299974 0.150114)
			(stroke
				(width 0.1)
				(type default)
			)
			(layer "F.Fab")
		)
		(pad "1" smd rect
			(at -0.2667 0 270)
			(size 0.3048 0.381)
			(layers "F.Cu" "F.Mask" "F.Paste")
			(net "P5E_CPU1_P0_TX_C_DP<4>")
		)
		(pad "2" smd rect
			(at 0.2667 0 270)
			(size 0.3048 0.381)
			(layers "F.Cu" "F.Mask" "F.Paste")
			(net "P5E_CPU1_P0_TX_DP<4>")
		)
	)
	(footprint ""
		(layer "F.Cu")
		(at 184.801256 -96.103948 90)
		(property "Reference" "R6054"
			(at 0 0 90)
			(layer "F.SilkS")
			(hide yes)
			(effects
				(font
					(size 1.27 1.27)
				)
			)
		)
		(property "Value" ""
			(at 0 0 90)
			(layer "F.Fab")
			(effects
				(font
					(size 1.27 1.27)
				)
			)
		)
		(duplicate_pad_numbers_are_jumpers no)
		(fp_line
			(start 0.7874 -0.4064)
			(end 0.7874 0.4064)
			(stroke
				(width 0.1524)
				(type default)
			)
			(layer "F.SilkS")
		)
		(fp_line
			(start -0.7874 -0.4064)
			(end 0.7874 -0.4064)
			(stroke
				(width 0.1524)
				(type default)
			)
			(layer "F.SilkS")
		)
		(fp_line
			(start 0.7874 0.4064)
			(end -0.7874 0.4064)
			(stroke
				(width 0.1524)
				(type default)
			)
			(layer "F.SilkS")
		)
		(fp_line
			(start -0.7874 0.4064)
			(end -0.7874 -0.4064)
			(stroke
				(width 0.1524)
				(type default)
			)
			(layer "F.SilkS")
		)
		(fp_line
			(start -0.12065 -0.305054)
			(end -0.12065 -0.2794)
			(stroke
				(width 0.1)
				(type default)
			)
			(layer "F.Fab")
		)
		(fp_line
			(start -0.67945 -0.305054)
			(end -0.12065 -0.305054)
			(stroke
				(width 0.1)
				(type default)
			)
			(layer "F.Fab")
		)
		(fp_line
			(start 0.67945 -0.3048)
			(end 0.67945 0.3048)
			(stroke
				(width 0.1)
				(type default)
			)
			(layer "F.Fab")
		)
		(fp_line
			(start 0.12065 -0.3048)
			(end 0.67945 -0.3048)
			(stroke
				(width 0.1)
				(type default)
			)
			(layer "F.Fab")
		)
		(fp_line
			(start 0.12065 -0.2794)
			(end 0.12065 -0.3048)
			(stroke
				(width 0.1)
				(type default)
			)
			(layer "F.Fab")
		)
		(fp_line
			(start -0.12065 -0.2794)
			(end 0.12065 -0.2794)
			(stroke
				(width 0.1)
				(type default)
			)
			(layer "F.Fab")
		)
		(fp_line
			(start 0.120396 0.2794)
			(end -0.12065 0.2794)
			(stroke
				(width 0.1)
				(type default)
			)
			(layer "F.Fab")
		)
		(fp_line
			(start -0.12065 0.2794)
			(end -0.12065 0.3048)
			(stroke
				(width 0.1)
				(type default)
			)
			(layer "F.Fab")
		)
		(fp_line
			(start 0.67945 0.3048)
			(end 0.120396 0.3048)
			(stroke
				(width 0.1)
				(type default)
			)
			(layer "F.Fab")
		)
		(fp_line
			(start 0.120396 0.3048)
			(end 0.120396 0.2794)
			(stroke
				(width 0.1)
				(type default)
			)
			(layer "F.Fab")
		)
		(fp_line
			(start -0.12065 0.3048)
			(end -0.67945 0.3048)
			(stroke
				(width 0.1)
				(type default)
			)
			(layer "F.Fab")
		)
		(fp_line
			(start -0.67945 0.3048)
			(end -0.67945 -0.305054)
			(stroke
				(width 0.1)
				(type default)
			)
			(layer "F.Fab")
		)
		(pad "1" smd circle
			(at -0.40005 0 90)
			(size 0 0)
			(layers "F.Cu" "F.Mask" "F.Paste")
			(net "FM_OCP_SFF_PWR_GOOD")
		)
		(pad "2" smd circle
			(at 0.40005 0 90)
			(size 0 0)
			(layers "F.Cu" "F.Mask" "F.Paste")
			(net "PWRGD_OCP_SFF_PWR_GOOD")
		)
	)
	(footprint ""
		(layer "F.Cu")
		(at 369.511326 -43.235118 -90)
		(property "Reference" "R815"
			(at 0 0 270)
			(layer "F.SilkS")
			(hide yes)
			(effects
				(font
					(size 1.27 1.27)
				)
			)
		)
		(property "Value" ""
			(at 0 0 270)
			(layer "F.Fab")
			(effects
				(font
					(size 1.27 1.27)
				)
			)
		)
		(duplicate_pad_numbers_are_jumpers no)
		(fp_line
			(start -0.7874 0.4064)
			(end -0.7874 -0.4064)
			(stroke
				(width 0.1524)
				(type default)
			)
			(layer "F.SilkS")
		)
		(fp_line
			(start 0.7874 0.4064)
			(end -0.7874 0.4064)
			(stroke
				(width 0.1524)
				(type default)
			)
			(layer "F.SilkS")
		)
		(fp_line
			(start -0.7874 -0.4064)
			(end 0.7874 -0.4064)
			(stroke
				(width 0.1524)
				(type default)
			)
			(layer "F.SilkS")
		)
		(fp_line
			(start 0.7874 -0.4064)
			(end 0.7874 0.4064)
			(stroke
				(width 0.1524)
				(type default)
			)
			(layer "F.SilkS")
		)
		(fp_line
			(start -0.67945 0.3048)
			(end -0.67945 -0.305054)
			(stroke
				(width 0.1)
				(type default)
			)
			(layer "F.Fab")
		)
		(fp_line
			(start -0.12065 0.3048)
			(end -0.67945 0.3048)
			(stroke
				(width 0.1)
				(type default)
			)
			(layer "F.Fab")
		)
		(fp_line
			(start 0.120396 0.3048)
			(end 0.120396 0.2794)
			(stroke
				(width 0.1)
				(type default)
			)
			(layer "F.Fab")
		)
		(fp_line
			(start 0.67945 0.3048)
			(end 0.120396 0.3048)
			(stroke
				(width 0.1)
				(type default)
			)
			(layer "F.Fab")
		)
		(fp_line
			(start -0.12065 0.2794)
			(end -0.12065 0.3048)
			(stroke
				(width 0.1)
				(type default)
			)
			(layer "F.Fab")
		)
		(fp_line
			(start 0.120396 0.2794)
			(end -0.12065 0.2794)
			(stroke
				(width 0.1)
				(type default)
			)
			(layer "F.Fab")
		)
		(fp_line
			(start -0.12065 -0.2794)
			(end 0.12065 -0.2794)
			(stroke
				(width 0.1)
				(type default)
			)
			(layer "F.Fab")
		)
		(fp_line
			(start 0.12065 -0.2794)
			(end 0.12065 -0.3048)
			(stroke
				(width 0.1)
				(type default)
			)
			(layer "F.Fab")
		)
		(fp_line
			(start 0.12065 -0.3048)
			(end 0.67945 -0.3048)
			(stroke
				(width 0.1)
				(type default)
			)
			(layer "F.Fab")
		)
		(fp_line
			(start 0.67945 -0.3048)
			(end 0.67945 0.3048)
			(stroke
				(width 0.1)
				(type default)
			)
			(layer "F.Fab")
		)
		(fp_line
			(start -0.67945 -0.305054)
			(end -0.12065 -0.305054)
			(stroke
				(width 0.1)
				(type default)
			)
			(layer "F.Fab")
		)
		(fp_line
			(start -0.12065 -0.305054)
			(end -0.12065 -0.2794)
			(stroke
				(width 0.1)
				(type default)
			)
			(layer "F.Fab")
		)
		(pad "1" smd circle
			(at -0.40005 0 270)
			(size 0 0)
			(layers "F.Cu" "F.Mask" "F.Paste")
			(net "PVDD18_S5_P0")
		)
		(pad "2" smd circle
			(at 0.40005 0 270)
			(size 0 0)
			(layers "F.Cu" "F.Mask" "F.Paste")
			(net "UART_CPU0_SCM_UART1_TX")
		)
	)
	(footprint ""
		(layer "F.Cu")
		(at 325.740776 -388.767828)
		(property "Reference" "C902"
			(at 0 0 0)
			(layer "F.SilkS")
			(hide yes)
			(effects
				(font
					(size 1.27 1.27)
				)
			)
		)
		(property "Value" ""
			(at 0 0 0)
			(layer "F.Fab")
			(effects
				(font
					(size 1.27 1.27)
				)
			)
		)
		(duplicate_pad_numbers_are_jumpers no)
		(fp_line
			(start -0.299974 -0.150114)
			(end 0.299974 -0.150114)
			(stroke
				(width 0.1)
				(type default)
			)
			(layer "F.Fab")
		)
		(fp_line
			(start -0.299974 0.150114)
			(end -0.299974 -0.150114)
			(stroke
				(width 0.1)
				(type default)
			)
			(layer "F.Fab")
		)
		(fp_line
			(start 0.299974 -0.150114)
			(end 0.299974 0.150114)
			(stroke
				(width 0.1)
				(type default)
			)
			(layer "F.Fab")
		)
		(fp_line
			(start 0.299974 0.150114)
			(end -0.299974 0.150114)
			(stroke
				(width 0.1)
				(type default)
			)
			(layer "F.Fab")
		)
		(pad "1" smd rect
			(at -0.2667 0)
			(size 0.3048 0.381)
			(layers "F.Cu" "F.Mask" "F.Paste")
			(net "P5E_CPU0_P0_TX_C_DN<15>")
		)
		(pad "2" smd rect
			(at 0.2667 0)
			(size 0.3048 0.381)
			(layers "F.Cu" "F.Mask" "F.Paste")
			(net "P5E_CPU0_P0_TX_DN<15>")
		)
	)
	(footprint ""
		(layer "F.Cu")
		(at 240.596674 -155.9941)
		(property "Reference" "R1651"
			(at 0 0 0)
			(layer "F.SilkS")
			(hide yes)
			(effects
				(font
					(size 1.27 1.27)
				)
			)
		)
		(property "Value" ""
			(at 0 0 0)
			(layer "F.Fab")
			(effects
				(font
					(size 1.27 1.27)
				)
			)
		)
		(duplicate_pad_numbers_are_jumpers no)
		(fp_line
			(start -0.7874 -0.4064)
			(end 0.7874 -0.4064)
			(stroke
				(width 0.1524)
				(type default)
			)
			(layer "F.SilkS")
		)
		(fp_line
			(start -0.7874 0.4064)
			(end -0.7874 -0.4064)
			(stroke
				(width 0.1524)
				(type default)
			)
			(layer "F.SilkS")
		)
		(fp_line
			(start 0.7874 -0.4064)
			(end 0.7874 0.4064)
			(stroke
				(width 0.1524)
				(type default)
			)
			(layer "F.SilkS")
		)
		(fp_line
			(start 0.7874 0.4064)
			(end -0.7874 0.4064)
			(stroke
				(width 0.1524)
				(type default)
			)
			(layer "F.SilkS")
		)
		(fp_line
			(start -0.67945 -0.305054)
			(end -0.12065 -0.305054)
			(stroke
				(width 0.1)
				(type default)
			)
			(layer "F.Fab")
		)
		(fp_line
			(start -0.67945 0.3048)
			(end -0.67945 -0.305054)
			(stroke
				(width 0.1)
				(type default)
			)
			(layer "F.Fab")
		)
		(fp_line
			(start -0.12065 -0.305054)
			(end -0.12065 -0.2794)
			(stroke
				(width 0.1)
				(type default)
			)
			(layer "F.Fab")
		)
		(fp_line
			(start -0.12065 -0.2794)
			(end 0.12065 -0.2794)
			(stroke
				(width 0.1)
				(type default)
			)
			(layer "F.Fab")
		)
		(fp_line
			(start -0.12065 0.2794)
			(end -0.12065 0.3048)
			(stroke
				(width 0.1)
				(type default)
			)
			(layer "F.Fab")
		)
		(fp_line
			(start -0.12065 0.3048)
			(end -0.67945 0.3048)
			(stroke
				(width 0.1)
				(type default)
			)
			(layer "F.Fab")
		)
		(fp_line
			(start 0.120396 0.2794)
			(end -0.12065 0.2794)
			(stroke
				(width 0.1)
				(type default)
			)
			(layer "F.Fab")
		)
		(fp_line
			(start 0.120396 0.3048)
			(end 0.120396 0.2794)
			(stroke
				(width 0.1)
				(type default)
			)
			(layer "F.Fab")
		)
		(fp_line
			(start 0.12065 -0.3048)
			(end 0.67945 -0.3048)
			(stroke
				(width 0.1)
				(type default)
			)
			(layer "F.Fab")
		)
		(fp_line
			(start 0.12065 -0.2794)
			(end 0.12065 -0.3048)
			(stroke
				(width 0.1)
				(type default)
			)
			(layer "F.Fab")
		)
		(fp_line
			(start 0.67945 -0.3048)
			(end 0.67945 0.3048)
			(stroke
				(width 0.1)
				(type default)
			)
			(layer "F.Fab")
		)
		(fp_line
			(start 0.67945 0.3048)
			(end 0.120396 0.3048)
			(stroke
				(width 0.1)
				(type default)
			)
			(layer "F.Fab")
		)
		(pad "1" smd circle
			(at -0.40005 0)
			(size 0 0)
			(layers "F.Cu" "F.Mask" "F.Paste")
			(net "JTAG_CPU1_R_TDI")
		)
		(pad "2" smd circle
			(at 0.40005 0)
			(size 0 0)
			(layers "F.Cu" "F.Mask" "F.Paste")
			(net "JTAG_CPU1_TDI")
		)
	)
	(footprint ""
		(layer "F.Cu")
		(at 95.38335 -59.80557 180)
		(property "Reference" "PC2147"
			(at 0 0 180)
			(layer "F.SilkS")
			(hide yes)
			(effects
				(font
					(size 1.27 1.27)
				)
			)
		)
		(property "Value" ""
			(at 0 0 180)
			(layer "F.Fab")
			(effects
				(font
					(size 1.27 1.27)
				)
			)
		)
		(duplicate_pad_numbers_are_jumpers no)
		(fp_line
			(start 0.7874 0.4064)
			(end -0.7874 0.4064)
			(stroke
				(width 0.1524)
				(type default)
			)
			(layer "F.SilkS")
		)
		(fp_line
			(start 0.7874 -0.4064)
			(end 0.7874 0.4064)
			(stroke
				(width 0.1524)
				(type default)
			)
			(layer "F.SilkS")
		)
		(fp_line
			(start -0.7874 0.4064)
			(end -0.7874 -0.4064)
			(stroke
				(width 0.1524)
				(type default)
			)
			(layer "F.SilkS")
		)
		(fp_line
			(start -0.7874 -0.4064)
			(end 0.7874 -0.4064)
			(stroke
				(width 0.1524)
				(type default)
			)
			(layer "F.SilkS")
		)
		(fp_line
			(start 0.67945 0.3048)
			(end 0.120396 0.3048)
			(stroke
				(width 0.1)
				(type default)
			)
			(layer "F.Fab")
		)
		(fp_line
			(start 0.67945 -0.3048)
			(end 0.67945 0.3048)
			(stroke
				(width 0.1)
				(type default)
			)
			(layer "F.Fab")
		)
		(fp_line
			(start 0.12065 -0.2794)
			(end 0.12065 -0.3048)
			(stroke
				(width 0.1)
				(type default)
			)
			(layer "F.Fab")
		)
		(fp_line
			(start 0.12065 -0.3048)
			(end 0.67945 -0.3048)
			(stroke
				(width 0.1)
				(type default)
			)
			(layer "F.Fab")
		)
		(fp_line
			(start 0.120396 0.3048)
			(end 0.120396 0.2794)
			(stroke
				(width 0.1)
				(type default)
			)
			(layer "F.Fab")
		)
		(fp_line
			(start 0.120396 0.2794)
			(end -0.12065 0.2794)
			(stroke
				(width 0.1)
				(type default)
			)
			(layer "F.Fab")
		)
		(fp_line
			(start -0.12065 0.3048)
			(end -0.67945 0.3048)
			(stroke
				(width 0.1)
				(type default)
			)
			(layer "F.Fab")
		)
		(fp_line
			(start -0.12065 0.2794)
			(end -0.12065 0.3048)
			(stroke
				(width 0.1)
				(type default)
			)
			(layer "F.Fab")
		)
		(fp_line
			(start -0.12065 -0.2794)
			(end 0.12065 -0.2794)
			(stroke
				(width 0.1)
				(type default)
			)
			(layer "F.Fab")
		)
		(fp_line
			(start -0.12065 -0.305054)
			(end -0.12065 -0.2794)
			(stroke
				(width 0.1)
				(type default)
			)
			(layer "F.Fab")
		)
		(fp_line
			(start -0.67945 0.3048)
			(end -0.67945 -0.305054)
			(stroke
				(width 0.1)
				(type default)
			)
			(layer "F.Fab")
		)
		(fp_line
			(start -0.67945 -0.305054)
			(end -0.12065 -0.305054)
			(stroke
				(width 0.1)
				(type default)
			)
			(layer "F.Fab")
		)
		(pad "1" smd circle
			(at -0.40005 0 180)
			(size 0 0)
			(layers "F.Cu" "F.Mask" "F.Paste")
			(net "GND")
		)
		(pad "2" smd circle
			(at 0.40005 0 180)
			(size 0 0)
			(layers "F.Cu" "F.Mask" "F.Paste")
			(net "P3V3_OCP_REG_2")
		)
	)
	(footprint ""
		(layer "F.Cu")
		(at 447.557652 -17.433798 180)
		(property "Reference" "PR3788"
			(at 0 0 180)
			(layer "F.SilkS")
			(hide yes)
			(effects
				(font
					(size 1.27 1.27)
				)
			)
		)
		(property "Value" ""
			(at 0 0 180)
			(layer "F.Fab")
			(effects
				(font
					(size 1.27 1.27)
				)
			)
		)
		(duplicate_pad_numbers_are_jumpers no)
		(fp_line
			(start 0.7874 0.4064)
			(end -0.7874 0.4064)
			(stroke
				(width 0.1524)
				(type default)
			)
			(layer "F.SilkS")
		)
		(fp_line
			(start 0.7874 -0.4064)
			(end 0.7874 0.4064)
			(stroke
				(width 0.1524)
				(type default)
			)
			(layer "F.SilkS")
		)
		(fp_line
			(start -0.7874 0.4064)
			(end -0.7874 -0.4064)
			(stroke
				(width 0.1524)
				(type default)
			)
			(layer "F.SilkS")
		)
		(fp_line
			(start -0.7874 -0.4064)
			(end 0.7874 -0.4064)
			(stroke
				(width 0.1524)
				(type default)
			)
			(layer "F.SilkS")
		)
		(fp_line
			(start 0.67945 0.3048)
			(end 0.120396 0.3048)
			(stroke
				(width 0.1)
				(type default)
			)
			(layer "F.Fab")
		)
		(fp_line
			(start 0.67945 -0.3048)
			(end 0.67945 0.3048)
			(stroke
				(width 0.1)
				(type default)
			)
			(layer "F.Fab")
		)
		(fp_line
			(start 0.12065 -0.2794)
			(end 0.12065 -0.3048)
			(stroke
				(width 0.1)
				(type default)
			)
			(layer "F.Fab")
		)
		(fp_line
			(start 0.12065 -0.3048)
			(end 0.67945 -0.3048)
			(stroke
				(width 0.1)
				(type default)
			)
			(layer "F.Fab")
		)
		(fp_line
			(start 0.120396 0.3048)
			(end 0.120396 0.2794)
			(stroke
				(width 0.1)
				(type default)
			)
			(layer "F.Fab")
		)
		(fp_line
			(start 0.120396 0.2794)
			(end -0.12065 0.2794)
			(stroke
				(width 0.1)
				(type default)
			)
			(layer "F.Fab")
		)
		(fp_line
			(start -0.12065 0.3048)
			(end -0.67945 0.3048)
			(stroke
				(width 0.1)
				(type default)
			)
			(layer "F.Fab")
		)
		(fp_line
			(start -0.12065 0.2794)
			(end -0.12065 0.3048)
			(stroke
				(width 0.1)
				(type default)
			)
			(layer "F.Fab")
		)
		(fp_line
			(start -0.12065 -0.2794)
			(end 0.12065 -0.2794)
			(stroke
				(width 0.1)
				(type default)
			)
			(layer "F.Fab")
		)
		(fp_line
			(start -0.12065 -0.305054)
			(end -0.12065 -0.2794)
			(stroke
				(width 0.1)
				(type default)
			)
			(layer "F.Fab")
		)
		(fp_line
			(start -0.67945 0.3048)
			(end -0.67945 -0.305054)
			(stroke
				(width 0.1)
				(type default)
			)
			(layer "F.Fab")
		)
		(fp_line
			(start -0.67945 -0.305054)
			(end -0.12065 -0.305054)
			(stroke
				(width 0.1)
				(type default)
			)
			(layer "F.Fab")
		)
		(pad "1" smd circle
			(at -0.40005 0 180)
			(size 0 0)
			(layers "F.Cu" "F.Mask" "F.Paste")
			(net "P12V_OCP_OV_1")
		)
		(pad "2" smd circle
			(at 0.40005 0 180)
			(size 0 0)
			(layers "F.Cu" "F.Mask" "F.Paste")
			(net "GND")
		)
	)
	(footprint ""
		(layer "F.Cu")
		(at 414.792922 -173.084998 180)
		(property "Reference" "PL66"
			(at 0.04445 5.886704 90)
			(unlocked yes)
			(layer "F.SilkS")
			(effects
				(font
					(size 0.7874 0.5842)
					(thickness 0.1524)
				)
				(justify left)
			)
		)
		(property "Value" ""
			(at 0 0 180)
			(layer "F.Fab")
			(effects
				(font
					(size 1.27 1.27)
				)
			)
		)
		(duplicate_pad_numbers_are_jumpers no)
		(fp_line
			(start 3.750056 5.500116)
			(end 3.750056 -5.500116)
			(stroke
				(width 0.1524)
				(type default)
			)
			(layer "F.SilkS")
		)
		(fp_line
			(start 3.750056 -5.500116)
			(end 2.393442 -5.500116)
			(stroke
				(width 0.1524)
				(type default)
			)
			(layer "F.SilkS")
		)
		(fp_line
			(start 2.393442 5.500116)
			(end 3.750056 5.500116)
			(stroke
				(width 0.1524)
				(type default)
			)
			(layer "F.SilkS")
		)
		(fp_line
			(start -2.393442 5.500116)
			(end -3.750056 5.500116)
			(stroke
				(width 0.1524)
				(type default)
			)
			(layer "F.SilkS")
		)
		(fp_line
			(start -3.750056 5.500116)
			(end -3.750056 -5.500116)
			(stroke
				(width 0.1524)
				(type default)
			)
			(layer "F.SilkS")
		)
		(fp_line
			(start -3.750056 -5.500116)
			(end -2.393442 -5.500116)
			(stroke
				(width 0.1524)
				(type default)
			)
			(layer "F.SilkS")
		)
		(fp_poly
			(pts
				(xy -3.9116 -4.249928) (xy -4.434078 -3.988562) (xy -4.434078 -4.511294)
			)
			(stroke
				(width 0)
				(type default)
			)
			(fill yes)
			(layer "F.SilkS")
		)
		(fp_line
			(start 3.750056 5.500116)
			(end 3.750056 -5.500116)
			(stroke
				(width 0.1)
				(type default)
			)
			(layer "F.Fab")
		)
		(fp_line
			(start 3.750056 -5.500116)
			(end -3.750056 -5.500116)
			(stroke
				(width 0.1)
				(type default)
			)
			(layer "F.Fab")
		)
		(fp_line
			(start -3.750056 5.500116)
			(end 3.750056 5.500116)
			(stroke
				(width 0.1)
				(type default)
			)
			(layer "F.Fab")
		)
		(fp_line
			(start -3.750056 -5.500116)
			(end -3.750056 5.500116)
			(stroke
				(width 0.1)
				(type default)
			)
			(layer "F.Fab")
		)
		(fp_poly
			(pts
				(xy -4.9276 -4.757928) (xy -4.9276 -3.741928) (xy -3.9116 -4.249928)
			)
			(stroke
				(width 0)
				(type default)
			)
			(fill yes)
			(layer "F.Fab")
		)
		(pad "1" smd rect
			(at 0 -4.249928 90)
			(size 2.413 4.5212)
			(layers "F.Cu" "F.Mask" "F.Paste")
			(net "SW_PVDDCR_SOC_P0_SW3")
		)
		(pad "2" smd rect
			(at 0 -1.175004 90)
			(size 1.3716 4.5212)
			(layers "F.Cu" "F.Mask" "F.Paste")
			(net "IND_SOC_P0_CPL0")
		)
		(pad "3" smd rect
			(at 0 1.175004 90)
			(size 1.3716 4.5212)
			(layers "F.Cu" "F.Mask" "F.Paste")
			(net "IND_SOC_P0_CPL3")
		)
		(pad "4" smd rect
			(at 0 4.249928 90)
			(size 2.413 4.5212)
			(layers "F.Cu" "F.Mask" "F.Paste")
			(net "PVDDCR_SOC_P0")
		)
	)
	(footprint ""
		(layer "F.Cu")
		(at 113.339372 -403.724618 -90)
		(property "Reference" "R1213"
			(at 0 0 270)
			(layer "F.SilkS")
			(hide yes)
			(effects
				(font
					(size 1.27 1.27)
				)
			)
		)
		(property "Value" ""
			(at 0 0 270)
			(layer "F.Fab")
			(effects
				(font
					(size 1.27 1.27)
				)
			)
		)
		(duplicate_pad_numbers_are_jumpers no)
		(fp_line
			(start -0.32512 0.175006)
			(end -0.32512 -0.175006)
			(stroke
				(width 0.1)
				(type default)
			)
			(layer "F.Fab")
		)
		(fp_line
			(start 0.32512 0.175006)
			(end -0.32512 0.175006)
			(stroke
				(width 0.1)
				(type default)
			)
			(layer "F.Fab")
		)
		(fp_line
			(start -0.32512 -0.175006)
			(end 0.32512 -0.175006)
			(stroke
				(width 0.1)
				(type default)
			)
			(layer "F.Fab")
		)
		(fp_line
			(start 0.32512 -0.175006)
			(end 0.32512 0.175006)
			(stroke
				(width 0.1)
				(type default)
			)
			(layer "F.Fab")
		)
		(pad "1" smd rect
			(at -0.2667 0 270)
			(size 0.3048 0.381)
			(layers "F.Cu" "F.Mask" "F.Paste")
			(net "GND")
		)
		(pad "2" smd rect
			(at 0.2667 0 90)
			(size 0.3048 0.381)
			(layers "F.Cu" "F.Mask" "F.Paste")
			(net "RT_ROM_MUX2_OE_N")
		)
	)
	(footprint ""
		(layer "F.Cu")
		(at 176.154334 -417.406328)
		(property "Reference" "Q9001"
			(at -2.792222 -1.82626 0)
			(unlocked yes)
			(layer "F.SilkS")
			(effects
				(font
					(size 0.7874 0.5842)
					(thickness 0.1524)
				)
				(justify left)
			)
		)
		(property "Value" ""
			(at 0 0 0)
			(layer "F.Fab")
			(effects
				(font
					(size 1.27 1.27)
				)
			)
		)
		(duplicate_pad_numbers_are_jumpers no)
		(fp_line
			(start -1.332738 -1.100074)
			(end -0.4826 -1.100074)
			(stroke
				(width 0.1524)
				(type default)
			)
			(layer "F.SilkS")
		)
		(fp_line
			(start -1.332738 1.100074)
			(end -1.332738 -1.100074)
			(stroke
				(width 0.1524)
				(type default)
			)
			(layer "F.SilkS")
		)
		(fp_line
			(start -0.4826 -1.100074)
			(end 0 -0.541274)
			(stroke
				(width 0.1524)
				(type default)
			)
			(layer "F.SilkS")
		)
		(fp_line
			(start 0 -0.541274)
			(end 0.4826 -1.100074)
			(stroke
				(width 0.1524)
				(type default)
			)
			(layer "F.SilkS")
		)
		(fp_line
			(start 0.4826 -1.100074)
			(end 1.332738 -1.100074)
			(stroke
				(width 0.1524)
				(type default)
			)
			(layer "F.SilkS")
		)
		(fp_line
			(start 1.332738 -1.100074)
			(end 1.332738 1.100074)
			(stroke
				(width 0.1524)
				(type default)
			)
			(layer "F.SilkS")
		)
		(fp_line
			(start 1.332738 1.100074)
			(end -1.332738 1.100074)
			(stroke
				(width 0.1524)
				(type default)
			)
			(layer "F.SilkS")
		)
		(fp_poly
			(pts
				(xy -2.2352 -0.298958) (xy -2.2352 -1.001014) (xy -1.533144 -0.649986)
			)
			(stroke
				(width 0)
				(type default)
			)
			(fill yes)
			(layer "F.SilkS")
		)
		(fp_line
			(start -0.674878 -1.100074)
			(end 0.674878 -1.100074)
			(stroke
				(width 0.1)
				(type default)
			)
			(layer "F.Fab")
		)
		(fp_line
			(start -0.674878 1.100074)
			(end -0.674878 -1.100074)
			(stroke
				(width 0.1)
				(type default)
			)
			(layer "F.Fab")
		)
		(fp_line
			(start 0.674878 -1.100074)
			(end 0.674878 1.100074)
			(stroke
				(width 0.1)
				(type default)
			)
			(layer "F.Fab")
		)
		(fp_line
			(start 0.674878 1.100074)
			(end -0.674878 1.100074)
			(stroke
				(width 0.1)
				(type default)
			)
			(layer "F.Fab")
		)
		(fp_poly
			(pts
				(xy -2.2352 -0.298958) (xy -2.2352 -1.001014) (xy -1.533144 -0.649986)
			)
			(stroke
				(width 0)
				(type default)
			)
			(fill yes)
			(layer "F.Fab")
		)
		(pad "1" smd rect
			(at -0.94996 -0.649986 90)
			(size 0.4318 0.508)
			(layers "F.Cu" "F.Mask" "F.Paste")
			(net "GND")
		)
		(pad "2" smd rect
			(at -0.94996 0 90)
			(size 0.4318 0.508)
			(layers "F.Cu" "F.Mask" "F.Paste")
			(net "PRSNT_CABLE_SWB_B2_N")
		)
		(pad "3" smd rect
			(at -0.94996 0.649986 90)
			(size 0.4318 0.508)
			(layers "F.Cu" "F.Mask" "F.Paste")
			(net "PRSNT_CABLE_SWB_B2_ISO_N")
		)
		(pad "4" smd rect
			(at 0.94996 0.649986 90)
			(size 0.4318 0.508)
			(layers "F.Cu" "F.Mask" "F.Paste")
			(net "GND")
		)
		(pad "5" smd rect
			(at 0.94996 0 90)
			(size 0.4318 0.508)
			(layers "F.Cu" "F.Mask" "F.Paste")
			(net "PRSNT_CABLE_SWB_B2")
		)
		(pad "6" smd rect
			(at 0.94996 -0.649986 90)
			(size 0.4318 0.508)
			(layers "F.Cu" "F.Mask" "F.Paste")
			(net "PRSNT_CABLE_SWB_B2")
		)
	)
	(footprint ""
		(layer "F.Cu")
		(at 82.989674 -165.962076 180)
		(property "Reference" "PC272"
			(at 2.327148 -2.902204 0)
			(unlocked yes)
			(layer "F.SilkS")
			(effects
				(font
					(size 0.7874 0.5842)
					(thickness 0.1524)
				)
				(justify left)
			)
		)
		(property "Value" ""
			(at 0 0 180)
			(layer "F.Fab")
			(effects
				(font
					(size 1.27 1.27)
				)
			)
		)
		(duplicate_pad_numbers_are_jumpers no)
		(fp_line
			(start -3.400044 1.249934)
			(end 3.400044 1.249934)
			(stroke
				(width 0.1524)
				(type default)
			)
			(layer "F.SilkS")
		)
		(fp_circle
			(center 0 1.249934)
			(end -3.400044 1.249934)
			(stroke
				(width 0.1524)
				(type default)
			)
			(fill no)
			(layer "F.SilkS")
		)
		(fp_poly
			(pts
				(arc
					(start 3.400044 1.249934)
					(mid 0 4.649978)
					(end -3.400044 1.249934)
				)
			)
			(stroke
				(width 0)
				(type default)
			)
			(fill yes)
			(layer "F.SilkS")
		)
		(fp_circle
			(center 0 1.249934)
			(end -3.400044 1.249934)
			(stroke
				(width 0.1)
				(type default)
			)
			(fill no)
			(layer "F.Fab")
		)
		(pad "1" thru_hole rect
			(at 0 0 180)
			(size 1.524 1.524)
			(drill 1.016)
			(layers "*.Cu" "*.Mask")
			(remove_unused_layers no)
			(net "SW_P12V_AUX_PVDDCR_CPU0_P1_FLT")
			(clearance 0)
			(padstack
				(mode front_inner_back)
				(layer "Inner"
					(shape circle)
					(size 1.524 1.524)
					(clearance 0)
				)
				(layer "B.Cu"
					(shape rect)
					(size 1.524 1.524)
					(clearance 0)
				)
			)
		)
		(pad "2" thru_hole circle
			(at 0 2.500122 180)
			(size 1.524 1.524)
			(drill 1.016)
			(layers "*.Cu" "*.Mask")
			(remove_unused_layers no)
			(net "GND")
			(clearance 0)
		)
	)
	(footprint ""
		(layer "F.Cu")
		(at 398.595088 -390.77646 180)
		(property "Reference" "C869"
			(at 0 0 180)
			(layer "F.SilkS")
			(hide yes)
			(effects
				(font
					(size 1.27 1.27)
				)
			)
		)
		(property "Value" ""
			(at 0 0 180)
			(layer "F.Fab")
			(effects
				(font
					(size 1.27 1.27)
				)
			)
		)
		(duplicate_pad_numbers_are_jumpers no)
		(fp_line
			(start 0.299974 0.150114)
			(end -0.299974 0.150114)
			(stroke
				(width 0.1)
				(type default)
			)
			(layer "F.Fab")
		)
		(fp_line
			(start 0.299974 -0.150114)
			(end 0.299974 0.150114)
			(stroke
				(width 0.1)
				(type default)
			)
			(layer "F.Fab")
		)
		(fp_line
			(start -0.299974 0.150114)
			(end -0.299974 -0.150114)
			(stroke
				(width 0.1)
				(type default)
			)
			(layer "F.Fab")
		)
		(fp_line
			(start -0.299974 -0.150114)
			(end 0.299974 -0.150114)
			(stroke
				(width 0.1)
				(type default)
			)
			(layer "F.Fab")
		)
		(pad "1" smd rect
			(at -0.2667 0 180)
			(size 0.3048 0.381)
			(layers "F.Cu" "F.Mask" "F.Paste")
			(net "P5E_CPU0_P2_TX_C_DP<0>")
		)
		(pad "2" smd rect
			(at 0.2667 0 180)
			(size 0.3048 0.381)
			(layers "F.Cu" "F.Mask" "F.Paste")
			(net "P5E_CPU0_P2_TX_DP<0>")
		)
	)
	(footprint ""
		(layer "F.Cu")
		(at 419.03904 -381.41783 -90)
		(property "Reference" "C847"
			(at 0 0 270)
			(layer "F.SilkS")
			(hide yes)
			(effects
				(font
					(size 1.27 1.27)
				)
			)
		)
		(property "Value" ""
			(at 0 0 270)
			(layer "F.Fab")
			(effects
				(font
					(size 1.27 1.27)
				)
			)
		)
		(duplicate_pad_numbers_are_jumpers no)
		(fp_line
			(start -0.299974 0.150114)
			(end -0.299974 -0.150114)
			(stroke
				(width 0.1)
				(type default)
			)
			(layer "F.Fab")
		)
		(fp_line
			(start 0.299974 0.150114)
			(end -0.299974 0.150114)
			(stroke
				(width 0.1)
				(type default)
			)
			(layer "F.Fab")
		)
		(fp_line
			(start -0.299974 -0.150114)
			(end 0.299974 -0.150114)
			(stroke
				(width 0.1)
				(type default)
			)
			(layer "F.Fab")
		)
		(fp_line
			(start 0.299974 -0.150114)
			(end 0.299974 0.150114)
			(stroke
				(width 0.1)
				(type default)
			)
			(layer "F.Fab")
		)
		(pad "1" smd rect
			(at -0.2667 0 270)
			(size 0.3048 0.381)
			(layers "F.Cu" "F.Mask" "F.Paste")
			(net "P5E_CPU0_P2_TX_C_DP<11>")
		)
		(pad "2" smd rect
			(at 0.2667 0 270)
			(size 0.3048 0.381)
			(layers "F.Cu" "F.Mask" "F.Paste")
			(net "P5E_CPU0_P2_TX_DP<11>")
		)
	)
	(footprint ""
		(layer "F.Cu")
		(at 212.993732 -112.662208 180)
		(property "Reference" "R132"
			(at 0 0 180)
			(layer "F.SilkS")
			(hide yes)
			(effects
				(font
					(size 1.27 1.27)
				)
			)
		)
		(property "Value" ""
			(at 0 0 180)
			(layer "F.Fab")
			(effects
				(font
					(size 1.27 1.27)
				)
			)
		)
		(duplicate_pad_numbers_are_jumpers no)
		(fp_line
			(start 0.7874 0.4064)
			(end -0.7874 0.4064)
			(stroke
				(width 0.1524)
				(type default)
			)
			(layer "F.SilkS")
		)
		(fp_line
			(start 0.7874 -0.4064)
			(end 0.7874 0.4064)
			(stroke
				(width 0.1524)
				(type default)
			)
			(layer "F.SilkS")
		)
		(fp_line
			(start -0.7874 0.4064)
			(end -0.7874 -0.4064)
			(stroke
				(width 0.1524)
				(type default)
			)
			(layer "F.SilkS")
		)
		(fp_line
			(start -0.7874 -0.4064)
			(end 0.7874 -0.4064)
			(stroke
				(width 0.1524)
				(type default)
			)
			(layer "F.SilkS")
		)
		(fp_line
			(start 0.67945 0.3048)
			(end 0.120396 0.3048)
			(stroke
				(width 0.1)
				(type default)
			)
			(layer "F.Fab")
		)
		(fp_line
			(start 0.67945 -0.3048)
			(end 0.67945 0.3048)
			(stroke
				(width 0.1)
				(type default)
			)
			(layer "F.Fab")
		)
		(fp_line
			(start 0.12065 -0.2794)
			(end 0.12065 -0.3048)
			(stroke
				(width 0.1)
				(type default)
			)
			(layer "F.Fab")
		)
		(fp_line
			(start 0.12065 -0.3048)
			(end 0.67945 -0.3048)
			(stroke
				(width 0.1)
				(type default)
			)
			(layer "F.Fab")
		)
		(fp_line
			(start 0.120396 0.3048)
			(end 0.120396 0.2794)
			(stroke
				(width 0.1)
				(type default)
			)
			(layer "F.Fab")
		)
		(fp_line
			(start 0.120396 0.2794)
			(end -0.12065 0.2794)
			(stroke
				(width 0.1)
				(type default)
			)
			(layer "F.Fab")
		)
		(fp_line
			(start -0.12065 0.3048)
			(end -0.67945 0.3048)
			(stroke
				(width 0.1)
				(type default)
			)
			(layer "F.Fab")
		)
		(fp_line
			(start -0.12065 0.2794)
			(end -0.12065 0.3048)
			(stroke
				(width 0.1)
				(type default)
			)
			(layer "F.Fab")
		)
		(fp_line
			(start -0.12065 -0.2794)
			(end 0.12065 -0.2794)
			(stroke
				(width 0.1)
				(type default)
			)
			(layer "F.Fab")
		)
		(fp_line
			(start -0.12065 -0.305054)
			(end -0.12065 -0.2794)
			(stroke
				(width 0.1)
				(type default)
			)
			(layer "F.Fab")
		)
		(fp_line
			(start -0.67945 0.3048)
			(end -0.67945 -0.305054)
			(stroke
				(width 0.1)
				(type default)
			)
			(layer "F.Fab")
		)
		(fp_line
			(start -0.67945 -0.305054)
			(end -0.12065 -0.305054)
			(stroke
				(width 0.1)
				(type default)
			)
			(layer "F.Fab")
		)
		(pad "1" smd circle
			(at -0.40005 0 180)
			(size 0 0)
			(layers "F.Cu" "F.Mask" "F.Paste")
			(net "FM_APML_MUX2_OE_N")
		)
		(pad "2" smd circle
			(at 0.40005 0 180)
			(size 0 0)
			(layers "F.Cu" "F.Mask" "F.Paste")
			(net "FM_APML_MUX2_OE_R_N")
		)
	)
	(footprint ""
		(layer "F.Cu")
		(at 120.69826 -29.373576)
		(property "Reference" "R6267"
			(at 0 0 0)
			(layer "F.SilkS")
			(hide yes)
			(effects
				(font
					(size 1.27 1.27)
				)
			)
		)
		(property "Value" ""
			(at 0 0 0)
			(layer "F.Fab")
			(effects
				(font
					(size 1.27 1.27)
				)
			)
		)
		(duplicate_pad_numbers_are_jumpers no)
		(fp_line
			(start -0.7874 -0.4064)
			(end 0.7874 -0.4064)
			(stroke
				(width 0.1524)
				(type default)
			)
			(layer "F.SilkS")
		)
		(fp_line
			(start -0.7874 0.4064)
			(end -0.7874 -0.4064)
			(stroke
				(width 0.1524)
				(type default)
			)
			(layer "F.SilkS")
		)
		(fp_line
			(start 0.7874 -0.4064)
			(end 0.7874 0.4064)
			(stroke
				(width 0.1524)
				(type default)
			)
			(layer "F.SilkS")
		)
		(fp_line
			(start 0.7874 0.4064)
			(end -0.7874 0.4064)
			(stroke
				(width 0.1524)
				(type default)
			)
			(layer "F.SilkS")
		)
		(fp_line
			(start -0.67945 -0.305054)
			(end -0.12065 -0.305054)
			(stroke
				(width 0.1)
				(type default)
			)
			(layer "F.Fab")
		)
		(fp_line
			(start -0.67945 0.3048)
			(end -0.67945 -0.305054)
			(stroke
				(width 0.1)
				(type default)
			)
			(layer "F.Fab")
		)
		(fp_line
			(start -0.12065 -0.305054)
			(end -0.12065 -0.2794)
			(stroke
				(width 0.1)
				(type default)
			)
			(layer "F.Fab")
		)
		(fp_line
			(start -0.12065 -0.2794)
			(end 0.12065 -0.2794)
			(stroke
				(width 0.1)
				(type default)
			)
			(layer "F.Fab")
		)
		(fp_line
			(start -0.12065 0.2794)
			(end -0.12065 0.3048)
			(stroke
				(width 0.1)
				(type default)
			)
			(layer "F.Fab")
		)
		(fp_line
			(start -0.12065 0.3048)
			(end -0.67945 0.3048)
			(stroke
				(width 0.1)
				(type default)
			)
			(layer "F.Fab")
		)
		(fp_line
			(start 0.120396 0.2794)
			(end -0.12065 0.2794)
			(stroke
				(width 0.1)
				(type default)
			)
			(layer "F.Fab")
		)
		(fp_line
			(start 0.120396 0.3048)
			(end 0.120396 0.2794)
			(stroke
				(width 0.1)
				(type default)
			)
			(layer "F.Fab")
		)
		(fp_line
			(start 0.12065 -0.3048)
			(end 0.67945 -0.3048)
			(stroke
				(width 0.1)
				(type default)
			)
			(layer "F.Fab")
		)
		(fp_line
			(start 0.12065 -0.2794)
			(end 0.12065 -0.3048)
			(stroke
				(width 0.1)
				(type default)
			)
			(layer "F.Fab")
		)
		(fp_line
			(start 0.67945 -0.3048)
			(end 0.67945 0.3048)
			(stroke
				(width 0.1)
				(type default)
			)
			(layer "F.Fab")
		)
		(fp_line
			(start 0.67945 0.3048)
			(end 0.120396 0.3048)
			(stroke
				(width 0.1)
				(type default)
			)
			(layer "F.Fab")
		)
		(pad "1" smd circle
			(at -0.40005 0)
			(size 0 0)
			(layers "F.Cu" "F.Mask" "F.Paste")
			(net "USB_HUB2_TI_VDD_MRP_USB3DN_TXDP4")
		)
		(pad "2" smd circle
			(at 0.40005 0)
			(size 0 0)
			(layers "F.Cu" "F.Mask" "F.Paste")
			(net "P1V2_CPU0_USB2_DVDD12")
		)
	)
	(footprint ""
		(layer "F.Cu")
		(at 126.804928 -47.121064)
		(property "Reference" "R6205"
			(at 0 0 0)
			(layer "F.SilkS")
			(hide yes)
			(effects
				(font
					(size 1.27 1.27)
				)
			)
		)
		(property "Value" ""
			(at 0 0 0)
			(layer "F.Fab")
			(effects
				(font
					(size 1.27 1.27)
				)
			)
		)
		(duplicate_pad_numbers_are_jumpers no)
		(fp_line
			(start -0.7874 -0.4064)
			(end 0.7874 -0.4064)
			(stroke
				(width 0.1524)
				(type default)
			)
			(layer "F.SilkS")
		)
		(fp_line
			(start -0.7874 0.4064)
			(end -0.7874 -0.4064)
			(stroke
				(width 0.1524)
				(type default)
			)
			(layer "F.SilkS")
		)
		(fp_line
			(start 0.7874 -0.4064)
			(end 0.7874 0.4064)
			(stroke
				(width 0.1524)
				(type default)
			)
			(layer "F.SilkS")
		)
		(fp_line
			(start 0.7874 0.4064)
			(end -0.7874 0.4064)
			(stroke
				(width 0.1524)
				(type default)
			)
			(layer "F.SilkS")
		)
		(fp_line
			(start -0.67945 -0.305054)
			(end -0.12065 -0.305054)
			(stroke
				(width 0.1)
				(type default)
			)
			(layer "F.Fab")
		)
		(fp_line
			(start -0.67945 0.3048)
			(end -0.67945 -0.305054)
			(stroke
				(width 0.1)
				(type default)
			)
			(layer "F.Fab")
		)
		(fp_line
			(start -0.12065 -0.305054)
			(end -0.12065 -0.2794)
			(stroke
				(width 0.1)
				(type default)
			)
			(layer "F.Fab")
		)
		(fp_line
			(start -0.12065 -0.2794)
			(end 0.12065 -0.2794)
			(stroke
				(width 0.1)
				(type default)
			)
			(layer "F.Fab")
		)
		(fp_line
			(start -0.12065 0.2794)
			(end -0.12065 0.3048)
			(stroke
				(width 0.1)
				(type default)
			)
			(layer "F.Fab")
		)
		(fp_line
			(start -0.12065 0.3048)
			(end -0.67945 0.3048)
			(stroke
				(width 0.1)
				(type default)
			)
			(layer "F.Fab")
		)
		(fp_line
			(start 0.120396 0.2794)
			(end -0.12065 0.2794)
			(stroke
				(width 0.1)
				(type default)
			)
			(layer "F.Fab")
		)
		(fp_line
			(start 0.120396 0.3048)
			(end 0.120396 0.2794)
			(stroke
				(width 0.1)
				(type default)
			)
			(layer "F.Fab")
		)
		(fp_line
			(start 0.12065 -0.3048)
			(end 0.67945 -0.3048)
			(stroke
				(width 0.1)
				(type default)
			)
			(layer "F.Fab")
		)
		(fp_line
			(start 0.12065 -0.2794)
			(end 0.12065 -0.3048)
			(stroke
				(width 0.1)
				(type default)
			)
			(layer "F.Fab")
		)
		(fp_line
			(start 0.67945 -0.3048)
			(end 0.67945 0.3048)
			(stroke
				(width 0.1)
				(type default)
			)
			(layer "F.Fab")
		)
		(fp_line
			(start 0.67945 0.3048)
			(end 0.120396 0.3048)
			(stroke
				(width 0.1)
				(type default)
			)
			(layer "F.Fab")
		)
		(pad "1" smd circle
			(at -0.40005 0)
			(size 0 0)
			(layers "F.Cu" "F.Mask" "F.Paste")
			(net "P3V3_AUX")
		)
		(pad "2" smd circle
			(at 0.40005 0)
			(size 0 0)
			(layers "F.Cu" "F.Mask" "F.Paste")
			(net "PU_CPU0_USB_HUB_OVRCURR")
		)
	)
	(footprint ""
		(layer "F.Cu")
		(at 453.719946 -104.249728)
		(property "Reference" "R1906"
			(at 0 0 0)
			(layer "F.SilkS")
			(hide yes)
			(effects
				(font
					(size 1.27 1.27)
				)
			)
		)
		(property "Value" ""
			(at 0 0 0)
			(layer "F.Fab")
			(effects
				(font
					(size 1.27 1.27)
				)
			)
		)
		(duplicate_pad_numbers_are_jumpers no)
		(fp_line
			(start -0.7874 -0.4064)
			(end 0.7874 -0.4064)
			(stroke
				(width 0.1524)
				(type default)
			)
			(layer "F.SilkS")
		)
		(fp_line
			(start -0.7874 0.4064)
			(end -0.7874 -0.4064)
			(stroke
				(width 0.1524)
				(type default)
			)
			(layer "F.SilkS")
		)
		(fp_line
			(start 0.7874 -0.4064)
			(end 0.7874 0.4064)
			(stroke
				(width 0.1524)
				(type default)
			)
			(layer "F.SilkS")
		)
		(fp_line
			(start 0.7874 0.4064)
			(end -0.7874 0.4064)
			(stroke
				(width 0.1524)
				(type default)
			)
			(layer "F.SilkS")
		)
		(fp_line
			(start -0.67945 -0.305054)
			(end -0.12065 -0.305054)
			(stroke
				(width 0.1)
				(type default)
			)
			(layer "F.Fab")
		)
		(fp_line
			(start -0.67945 0.3048)
			(end -0.67945 -0.305054)
			(stroke
				(width 0.1)
				(type default)
			)
			(layer "F.Fab")
		)
		(fp_line
			(start -0.12065 -0.305054)
			(end -0.12065 -0.2794)
			(stroke
				(width 0.1)
				(type default)
			)
			(layer "F.Fab")
		)
		(fp_line
			(start -0.12065 -0.2794)
			(end 0.12065 -0.2794)
			(stroke
				(width 0.1)
				(type default)
			)
			(layer "F.Fab")
		)
		(fp_line
			(start -0.12065 0.2794)
			(end -0.12065 0.3048)
			(stroke
				(width 0.1)
				(type default)
			)
			(layer "F.Fab")
		)
		(fp_line
			(start -0.12065 0.3048)
			(end -0.67945 0.3048)
			(stroke
				(width 0.1)
				(type default)
			)
			(layer "F.Fab")
		)
		(fp_line
			(start 0.120396 0.2794)
			(end -0.12065 0.2794)
			(stroke
				(width 0.1)
				(type default)
			)
			(layer "F.Fab")
		)
		(fp_line
			(start 0.120396 0.3048)
			(end 0.120396 0.2794)
			(stroke
				(width 0.1)
				(type default)
			)
			(layer "F.Fab")
		)
		(fp_line
			(start 0.12065 -0.3048)
			(end 0.67945 -0.3048)
			(stroke
				(width 0.1)
				(type default)
			)
			(layer "F.Fab")
		)
		(fp_line
			(start 0.12065 -0.2794)
			(end 0.12065 -0.3048)
			(stroke
				(width 0.1)
				(type default)
			)
			(layer "F.Fab")
		)
		(fp_line
			(start 0.67945 -0.3048)
			(end 0.67945 0.3048)
			(stroke
				(width 0.1)
				(type default)
			)
			(layer "F.Fab")
		)
		(fp_line
			(start 0.67945 0.3048)
			(end 0.120396 0.3048)
			(stroke
				(width 0.1)
				(type default)
			)
			(layer "F.Fab")
		)
		(pad "1" smd circle
			(at -0.40005 0)
			(size 0 0)
			(layers "F.Cu" "F.Mask" "F.Paste")
			(net "P3V3_AUX")
		)
		(pad "2" smd circle
			(at 0.40005 0)
			(size 0 0)
			(layers "F.Cu" "F.Mask" "F.Paste")
			(net "OCP_SFF_PRSNT2_R_N")
		)
	)
	(footprint ""
		(layer "F.Cu")
		(at 420.833296 -357.688134 -90)
		(property "Reference" "PR34"
			(at 0 0 270)
			(layer "F.SilkS")
			(hide yes)
			(effects
				(font
					(size 1.27 1.27)
				)
			)
		)
		(property "Value" ""
			(at 0 0 270)
			(layer "F.Fab")
			(effects
				(font
					(size 1.27 1.27)
				)
			)
		)
		(duplicate_pad_numbers_are_jumpers no)
		(fp_line
			(start -0.7874 0.4064)
			(end -0.7874 -0.4064)
			(stroke
				(width 0.1524)
				(type default)
			)
			(layer "F.SilkS")
		)
		(fp_line
			(start 0.7874 0.4064)
			(end -0.7874 0.4064)
			(stroke
				(width 0.1524)
				(type default)
			)
			(layer "F.SilkS")
		)
		(fp_line
			(start -0.7874 -0.4064)
			(end 0.7874 -0.4064)
			(stroke
				(width 0.1524)
				(type default)
			)
			(layer "F.SilkS")
		)
		(fp_line
			(start 0.7874 -0.4064)
			(end 0.7874 0.4064)
			(stroke
				(width 0.1524)
				(type default)
			)
			(layer "F.SilkS")
		)
		(fp_line
			(start -0.67945 0.3048)
			(end -0.67945 -0.305054)
			(stroke
				(width 0.1)
				(type default)
			)
			(layer "F.Fab")
		)
		(fp_line
			(start -0.12065 0.3048)
			(end -0.67945 0.3048)
			(stroke
				(width 0.1)
				(type default)
			)
			(layer "F.Fab")
		)
		(fp_line
			(start 0.120396 0.3048)
			(end 0.120396 0.2794)
			(stroke
				(width 0.1)
				(type default)
			)
			(layer "F.Fab")
		)
		(fp_line
			(start 0.67945 0.3048)
			(end 0.120396 0.3048)
			(stroke
				(width 0.1)
				(type default)
			)
			(layer "F.Fab")
		)
		(fp_line
			(start -0.12065 0.2794)
			(end -0.12065 0.3048)
			(stroke
				(width 0.1)
				(type default)
			)
			(layer "F.Fab")
		)
		(fp_line
			(start 0.120396 0.2794)
			(end -0.12065 0.2794)
			(stroke
				(width 0.1)
				(type default)
			)
			(layer "F.Fab")
		)
		(fp_line
			(start -0.12065 -0.2794)
			(end 0.12065 -0.2794)
			(stroke
				(width 0.1)
				(type default)
			)
			(layer "F.Fab")
		)
		(fp_line
			(start 0.12065 -0.2794)
			(end 0.12065 -0.3048)
			(stroke
				(width 0.1)
				(type default)
			)
			(layer "F.Fab")
		)
		(fp_line
			(start 0.12065 -0.3048)
			(end 0.67945 -0.3048)
			(stroke
				(width 0.1)
				(type default)
			)
			(layer "F.Fab")
		)
		(fp_line
			(start 0.67945 -0.3048)
			(end 0.67945 0.3048)
			(stroke
				(width 0.1)
				(type default)
			)
			(layer "F.Fab")
		)
		(fp_line
			(start -0.67945 -0.305054)
			(end -0.12065 -0.305054)
			(stroke
				(width 0.1)
				(type default)
			)
			(layer "F.Fab")
		)
		(fp_line
			(start -0.12065 -0.305054)
			(end -0.12065 -0.2794)
			(stroke
				(width 0.1)
				(type default)
			)
			(layer "F.Fab")
		)
		(pad "1" smd circle
			(at -0.40005 0 270)
			(size 0 0)
			(layers "F.Cu" "F.Mask" "F.Paste")
			(net "NC_PVDD11_S3_P0_IMON5")
		)
		(pad "2" smd circle
			(at 0.40005 0 270)
			(size 0 0)
			(layers "F.Cu" "F.Mask" "F.Paste")
			(net "GND")
		)
	)
	(footprint ""
		(layer "F.Cu")
		(at 160.402016 -10.849864 -90)
		(property "Reference" "J41"
			(at -8.65886 -21.78558 0)
			(unlocked yes)
			(layer "F.SilkS")
			(effects
				(font
					(size 0.7874 0.5842)
					(thickness 0.1524)
				)
				(justify left)
			)
		)
		(property "Value" ""
			(at 0 0 270)
			(layer "F.Fab")
			(effects
				(font
					(size 1.27 1.27)
				)
			)
		)
		(duplicate_pad_numbers_are_jumpers no)
		(fp_line
			(start -7.420102 34.360104)
			(end 6.210046 34.360104)
			(stroke
				(width 0.1524)
				(type default)
			)
			(layer "F.SilkS")
		)
		(fp_line
			(start 6.210046 34.360104)
			(end 6.210046 -34.360104)
			(stroke
				(width 0.1524)
				(type default)
			)
			(layer "F.SilkS")
		)
		(fp_line
			(start -5.5499 33.8201)
			(end 5.5499 33.8201)
			(stroke
				(width 0.1524)
				(type default)
			)
			(layer "F.SilkS")
		)
		(fp_line
			(start 5.5499 33.8201)
			(end 5.5499 -33.8201)
			(stroke
				(width 0.1524)
				(type default)
			)
			(layer "F.SilkS")
		)
		(fp_line
			(start -5.5499 30.97784)
			(end -5.5499 33.8201)
			(stroke
				(width 0.1524)
				(type default)
			)
			(layer "F.SilkS")
		)
		(fp_line
			(start -7.420102 29.007816)
			(end -7.420102 34.360104)
			(stroke
				(width 0.1524)
				(type default)
			)
			(layer "F.SilkS")
		)
		(fp_line
			(start -7.420102 24.994616)
			(end -7.420102 26.950416)
			(stroke
				(width 0.1524)
				(type default)
			)
			(layer "F.SilkS")
		)
		(fp_line
			(start -5.5499 9.8806)
			(end -5.5499 14.13256)
			(stroke
				(width 0.1524)
				(type default)
			)
			(layer "F.SilkS")
		)
		(fp_line
			(start -7.420102 0.636016)
			(end -7.420102 17.958816)
			(stroke
				(width 0.1524)
				(type default)
			)
			(layer "F.SilkS")
		)
		(fp_line
			(start -5.5499 0.636016)
			(end -5.5499 1.4224)
			(stroke
				(width 0.1524)
				(type default)
			)
			(layer "F.SilkS")
		)
		(fp_line
			(start -5.5499 -22.5425)
			(end -5.5499 -18.7833)
			(stroke
				(width 0.1524)
				(type default)
			)
			(layer "F.SilkS")
		)
		(fp_line
			(start -5.5499 -33.8201)
			(end -5.5499 -30.988)
			(stroke
				(width 0.1524)
				(type default)
			)
			(layer "F.SilkS")
		)
		(fp_line
			(start 5.5499 -33.8201)
			(end -5.5499 -33.8201)
			(stroke
				(width 0.1524)
				(type default)
			)
			(layer "F.SilkS")
		)
		(fp_line
			(start -7.420102 -34.360104)
			(end -7.420102 -2.462784)
			(stroke
				(width 0.1524)
				(type default)
			)
			(layer "F.SilkS")
		)
		(fp_line
			(start 6.210046 -34.360104)
			(end -7.420102 -34.360104)
			(stroke
				(width 0.1524)
				(type default)
			)
			(layer "F.SilkS")
		)
		(fp_poly
			(pts
				(xy 4.3942 -17.880838) (xy 4.3942 -18.896838) (xy 3.3782 -18.388838)
			)
			(stroke
				(width 0)
				(type default)
			)
			(fill yes)
			(layer "F.SilkS")
		)
		(fp_line
			(start -5.5499 33.8201)
			(end 5.5499 33.8201)
			(stroke
				(width 0.1)
				(type default)
			)
			(layer "F.Fab")
		)
		(fp_line
			(start 5.5499 33.8201)
			(end 5.5499 -33.8201)
			(stroke
				(width 0.1)
				(type default)
			)
			(layer "F.Fab")
		)
		(fp_line
			(start -5.5499 -33.8201)
			(end -5.5499 33.8201)
			(stroke
				(width 0.1)
				(type default)
			)
			(layer "F.Fab")
		)
		(fp_line
			(start 5.5499 -33.8201)
			(end -5.5499 -33.8201)
			(stroke
				(width 0.1)
				(type default)
			)
			(layer "F.Fab")
		)
		(fp_poly
			(pts
				(xy 7.4168 -17.957038) (xy 7.4168 -18.973038) (xy 6.4008 -18.465038)
			)
			(stroke
				(width 0)
				(type default)
			)
			(fill yes)
			(layer "F.Fab")
		)
		(pad "" np_thru_hole circle
			(at -0.599948 -32.079946 180)
			(size 1.1176 1.1176)
			(drill 1.1176)
			(layers "*.Cu" "*.Mask")
			(clearance 0.381)
			(thermal_gap 0.381)
		)
		(pad "" np_thru_hole circle
			(at 0.40005 32.085026 180)
			(size 1.1176 1.1176)
			(drill 1.1176)
			(layers "*.Cu" "*.Mask")
			(clearance 0.381)
			(thermal_gap 0.381)
		)
		(pad "A1" smd rect
			(at -2.750058 -18.465038 180)
			(size 0.381 1.4478)
			(layers "F.Cu" "F.Mask" "F.Paste")
			(net "SMB_OCP_SFF_3V3AUX_SCL_R0")
		)
		(pad "A2" smd rect
			(at -2.750058 -17.86509 180)
			(size 0.381 1.4478)
			(layers "F.Cu" "F.Mask" "F.Paste")
			(net "SMB_OCP_SFF_3V3AUX_SDA_R0")
		)
		(pad "A3" smd rect
			(at -2.750058 -17.264888 180)
			(size 0.381 1.4478)
			(layers "F.Cu" "F.Mask" "F.Paste")
			(net "SMB_CPU0_CPU1_APML_SCL_R")
		)
		(pad "A4" smd rect
			(at -2.750058 -16.66494 180)
			(size 0.381 1.4478)
			(layers "F.Cu" "F.Mask" "F.Paste")
			(net "SMB_CPU0_CPU1_APML_SDA_R")
		)
		(pad "A5" smd rect
			(at -2.750058 -16.064992 180)
			(size 0.381 1.4478)
			(layers "F.Cu" "F.Mask" "F.Paste")
			(net "SMB_VR_3V3AUX_SCL_R0")
		)
		(pad "A6" smd rect
			(at -2.750058 -15.465044 180)
			(size 0.381 1.4478)
			(layers "F.Cu" "F.Mask" "F.Paste")
			(net "SMB_VR_3V3AUX_SDA_R0")
		)
		(pad "A7" smd rect
			(at -2.750058 -14.865096 180)
			(size 0.381 1.4478)
			(layers "F.Cu" "F.Mask" "F.Paste")
			(net "SMB_CPU0_CPU1_SEC_SCL_R")
		)
		(pad "A8" smd rect
			(at -2.750058 -14.264894 180)
			(size 0.381 1.4478)
			(layers "F.Cu" "F.Mask" "F.Paste")
			(net "SMB_CPU0_CPU1_SEC_SDA_R")
		)
		(pad "A9" smd rect
			(at -2.750058 -13.664946 180)
			(size 0.381 1.4478)
			(layers "F.Cu" "F.Mask" "F.Paste")
			(net "I3C_BMC_SWB_SCL")
		)
		(pad "A10" smd rect
			(at -2.750058 -13.064998 180)
			(size 0.381 1.4478)
			(layers "F.Cu" "F.Mask" "F.Paste")
			(net "I3C_BMC_SWB_SDA")
		)
		(pad "A11" smd rect
			(at -2.750058 -12.46505 180)
			(size 0.381 1.4478)
			(layers "F.Cu" "F.Mask" "F.Paste")
			(net "SMB_OCP_V3_2_3V3AUX_SCL_R0")
		)
		(pad "A12" smd rect
			(at -2.750058 -11.865102 180)
			(size 0.381 1.4478)
			(layers "F.Cu" "F.Mask" "F.Paste")
			(net "SMB_OCP_V3_2_3V3AUX_SDA_R0")
		)
		(pad "A13" smd rect
			(at -2.750058 -11.2649 180)
			(size 0.381 1.4478)
			(layers "F.Cu" "F.Mask" "F.Paste")
			(net "GND")
		)
		(pad "A14" smd rect
			(at -2.750058 -10.664952 180)
			(size 0.381 1.4478)
			(layers "F.Cu" "F.Mask" "F.Paste")
			(net "CLK_100M_CPU0_CLK01_DP")
		)
		(pad "A15" smd rect
			(at -2.750058 -10.065004 180)
			(size 0.381 1.4478)
			(layers "F.Cu" "F.Mask" "F.Paste")
			(net "CLK_100M_CPU0_CLK01_DN")
		)
		(pad "A16" smd rect
			(at -2.750058 -9.465056 180)
			(size 0.381 1.4478)
			(layers "F.Cu" "F.Mask" "F.Paste")
			(net "GND")
		)
		(pad "A17" smd rect
			(at -2.750058 -8.865108 180)
			(size 0.381 1.4478)
			(layers "F.Cu" "F.Mask" "F.Paste")
			(net "P2E_CPU0_P5_TX_C_DP")
		)
		(pad "A18" smd rect
			(at -2.750058 -8.264906 180)
			(size 0.381 1.4478)
			(layers "F.Cu" "F.Mask" "F.Paste")
			(net "P2E_CPU0_P5_TX_C_DN")
		)
		(pad "A19" smd rect
			(at -2.750058 -7.664958 180)
			(size 0.381 1.4478)
			(layers "F.Cu" "F.Mask" "F.Paste")
			(net "GND")
		)
		(pad "A20" smd rect
			(at -2.750058 -7.06501 180)
			(size 0.381 1.4478)
			(layers "F.Cu" "F.Mask" "F.Paste")
			(net "P2E_CPU0_P5_RX_DP")
		)
		(pad "A21" smd rect
			(at -2.750058 -6.465062 180)
			(size 0.381 1.4478)
			(layers "F.Cu" "F.Mask" "F.Paste")
			(net "P2E_CPU0_P5_RX_DN")
		)
		(pad "A22" smd rect
			(at -2.750058 -5.865114 180)
			(size 0.381 1.4478)
			(layers "F.Cu" "F.Mask" "F.Paste")
			(net "GND")
		)
		(pad "A23" smd rect
			(at -2.750058 -5.264912 180)
			(size 0.381 1.4478)
			(layers "F.Cu" "F.Mask" "F.Paste")
			(net "SMB_PCIE0_3V3AUX_SCL")
		)
		(pad "A24" smd rect
			(at -2.750058 -4.664964 180)
			(size 0.381 1.4478)
			(layers "F.Cu" "F.Mask" "F.Paste")
			(net "SMB_PCIE0_3V3AUX_SDA")
		)
		(pad "A25" smd rect
			(at -2.750058 -4.065016 180)
			(size 0.381 1.4478)
			(layers "F.Cu" "F.Mask" "F.Paste")
			(net "SMB_PMBUS_3V3AUX_SCL_R0")
		)
		(pad "A26" smd rect
			(at -2.750058 -3.465068 180)
			(size 0.381 1.4478)
			(layers "F.Cu" "F.Mask" "F.Paste")
			(net "SMB_PMBUS_3V3AUX_SDA_R0")
		)
		(pad "A27" smd rect
			(at -2.750058 -2.86512 180)
			(size 0.381 1.4478)
			(layers "F.Cu" "F.Mask" "F.Paste")
			(net "SMB_1_PLD_3V3AUX_SCL_R3")
		)
		(pad "A28" smd rect
			(at -2.750058 -2.264918 180)
			(size 0.381 1.4478)
			(layers "F.Cu" "F.Mask" "F.Paste")
			(net "SMB_1_PLD_3V3AUX_SDA_R3")
		)
		(pad "A29" smd rect
			(at -2.750058 1.74498 180)
			(size 0.381 1.4478)
			(layers "F.Cu" "F.Mask" "F.Paste")
			(net "SMB_FAN_3V3AUX_SCL")
		)
		(pad "A30" smd rect
			(at -2.750058 2.344928 180)
			(size 0.381 1.4478)
			(layers "F.Cu" "F.Mask" "F.Paste")
			(net "SMB_FAN_3V3AUX_SDA")
		)
		(pad "A31" smd rect
			(at -2.750058 2.944876 180)
			(size 0.381 1.4478)
			(layers "F.Cu" "F.Mask" "F.Paste")
			(net "SMB_PCIE2_3V3AUX_SCL_R0")
		)
		(pad "A32" smd rect
			(at -2.750058 3.545078 180)
			(size 0.381 1.4478)
			(layers "F.Cu" "F.Mask" "F.Paste")
			(net "SMB_PCIE2_3V3AUX_SDA_R0")
		)
		(pad "A33" smd rect
			(at -2.750058 4.145026 180)
			(size 0.381 1.4478)
			(layers "F.Cu" "F.Mask" "F.Paste")
			(net "GND")
		)
		(pad "A34" smd rect
			(at -2.750058 4.744974 180)
			(size 0.381 1.4478)
			(layers "F.Cu" "F.Mask" "F.Paste")
			(net "JTAG_SCM_TCK")
		)
		(pad "A35" smd rect
			(at -2.750058 5.344922 180)
			(size 0.381 1.4478)
			(layers "F.Cu" "F.Mask" "F.Paste")
			(net "JTAG_SCM_TMS")
		)
		(pad "A36" smd rect
			(at -2.750058 5.945124 180)
			(size 0.381 1.4478)
			(layers "F.Cu" "F.Mask" "F.Paste")
			(net "JTAG_SCM_TDI_R")
		)
		(pad "A37" smd rect
			(at -2.750058 6.545072 180)
			(size 0.381 1.4478)
			(layers "F.Cu" "F.Mask" "F.Paste")
			(net "JTAG_SCM_TDO_R")
		)
		(pad "A38" smd rect
			(at -2.750058 7.14502 180)
			(size 0.381 1.4478)
			(layers "F.Cu" "F.Mask" "F.Paste")
			(net "SMB_PCIE3_3V3AUX_SCL_R")
		)
		(pad "A39" smd rect
			(at -2.750058 7.744968 180)
			(size 0.381 1.4478)
			(layers "F.Cu" "F.Mask" "F.Paste")
			(net "SMB_PCIE3_3V3AUX_SDA_R")
		)
		(pad "A40" smd rect
			(at -2.750058 8.344916 180)
			(size 0.381 1.4478)
			(layers "F.Cu" "F.Mask" "F.Paste")
			(net "SMB_HOST_CLK_3V3AUX_SCL_R0")
		)
		(pad "A41" smd rect
			(at -2.750058 8.945118 180)
			(size 0.381 1.4478)
			(layers "F.Cu" "F.Mask" "F.Paste")
			(net "SMB_HOST_CLK_3V3AUX_SDA_R0")
		)
		(pad "A42" smd rect
			(at -2.750058 9.545066 180)
			(size 0.381 1.4478)
			(layers "F.Cu" "F.Mask" "F.Paste")
			(net "GND")
		)
		(pad "A43" smd rect
			(at -2.750058 14.454886 180)
			(size 0.381 1.4478)
			(layers "F.Cu" "F.Mask" "F.Paste")
			(net "FW_RECOVERY")
		)
		(pad "A44" smd rect
			(at -2.750058 15.055088 180)
			(size 0.381 1.4478)
			(layers "F.Cu" "F.Mask" "F.Paste")
			(net "PWRGD_PS_PWROK_R")
		)
		(pad "A45" smd rect
			(at -2.750058 15.655036 180)
			(size 0.381 1.4478)
			(layers "F.Cu" "F.Mask" "F.Paste")
			(net "TP_STBY_EN")
		)
		(pad "A46" smd rect
			(at -2.750058 16.254984 180)
			(size 0.381 1.4478)
			(layers "F.Cu" "F.Mask" "F.Paste")
			(net "RST_MB_STBY_R_N")
		)
		(pad "A47" smd rect
			(at -2.750058 16.854932 180)
			(size 0.381 1.4478)
			(layers "F.Cu" "F.Mask" "F.Paste")
			(net "SCM_SYS_PWRBTN_R_N")
		)
		(pad "A48" smd rect
			(at -2.750058 17.45488 180)
			(size 0.381 1.4478)
			(layers "F.Cu" "F.Mask" "F.Paste")
			(net "SCM_SYS_PWROK_R1")
		)
		(pad "A49" smd rect
			(at -2.750058 18.055082 180)
			(size 0.381 1.4478)
			(layers "F.Cu" "F.Mask" "F.Paste")
			(net "SCM_HDT_DBREQ_N")
		)
		(pad "A50" smd rect
			(at -2.750058 18.65503 180)
			(size 0.381 1.4478)
			(layers "F.Cu" "F.Mask" "F.Paste")
			(net "PU_JTAG_DBP_BMC_PRDY_N")
		)
		(pad "A51" smd rect
			(at -2.750058 19.254978 180)
			(size 0.381 1.4478)
			(layers "F.Cu" "F.Mask" "F.Paste")
			(net "FM_RST_PERST_SCM_N")
		)
		(pad "A52" smd rect
			(at -2.750058 19.854926 180)
			(size 0.381 1.4478)
			(layers "F.Cu" "F.Mask" "F.Paste")
			(net "FM_UARTSW_MSB_R")
		)
		(pad "A53" smd rect
			(at -2.750058 20.455128 180)
			(size 0.381 1.4478)
			(layers "F.Cu" "F.Mask" "F.Paste")
			(net "SCM_ROT_CPU_RST_N")
		)
		(pad "A54" smd rect
			(at -2.750058 21.055076 180)
			(size 0.381 1.4478)
			(layers "F.Cu" "F.Mask" "F.Paste")
			(net "TP_CHASI")
		)
		(pad "A55" smd rect
			(at -2.750058 21.655024 180)
			(size 0.381 1.4478)
			(layers "F.Cu" "F.Mask" "F.Paste")
			(net "FM_UARTSW_LSB_R")
		)
		(pad "A56" smd rect
			(at -2.750058 22.254972 180)
			(size 0.381 1.4478)
			(layers "F.Cu" "F.Mask" "F.Paste")
			(net "IRQ0_A56")
		)
		(pad "A57" smd rect
			(at -2.750058 22.85492 180)
			(size 0.381 1.4478)
			(layers "F.Cu" "F.Mask" "F.Paste")
			(net "FM_SCM_PRSNT1_N")
		)
		(pad "A58" smd rect
			(at -2.750058 23.455122 180)
			(size 0.381 1.4478)
			(layers "F.Cu" "F.Mask" "F.Paste")
			(net "GND")
		)
		(pad "A59" smd rect
			(at -2.750058 24.05507 180)
			(size 0.381 1.4478)
			(layers "F.Cu" "F.Mask" "F.Paste")
			(net "USB3_CPU0_BMC_RX_DP")
		)
		(pad "A60" smd rect
			(at -2.750058 24.655018 180)
			(size 0.381 1.4478)
			(layers "F.Cu" "F.Mask" "F.Paste")
			(net "USB3_CPU0_BMC_RX_DN")
		)
		(pad "A61" smd rect
			(at -2.750058 25.254966 180)
			(size 0.381 1.4478)
			(layers "F.Cu" "F.Mask" "F.Paste")
			(net "GND")
		)
		(pad "A62" smd rect
			(at -2.750058 25.854914 180)
			(size 0.381 1.4478)
			(layers "F.Cu" "F.Mask" "F.Paste")
			(net "TP_PCIE_RXP<1>")
		)
		(pad "A63" smd rect
			(at -2.750058 26.455116 180)
			(size 0.381 1.4478)
			(layers "F.Cu" "F.Mask" "F.Paste")
			(net "TP_PCIE_RXN<1>")
		)
		(pad "A64" smd rect
			(at -2.750058 27.055064 180)
			(size 0.381 1.4478)
			(layers "F.Cu" "F.Mask" "F.Paste")
			(net "GND")
		)
		(pad "A65" smd rect
			(at -2.750058 27.655012 180)
			(size 0.381 1.4478)
			(layers "F.Cu" "F.Mask" "F.Paste")
			(net "P2E_MB_BMC_RX_BUF_DP<0>")
		)
		(pad "A66" smd rect
			(at -2.750058 28.25496 180)
			(size 0.381 1.4478)
			(layers "F.Cu" "F.Mask" "F.Paste")
			(net "P2E_MB_BMC_RX_BUF_DN<0>")
		)
		(pad "A67" smd rect
			(at -2.750058 28.854908 180)
			(size 0.381 1.4478)
			(layers "F.Cu" "F.Mask" "F.Paste")
			(net "GND")
		)
		(pad "A68" smd rect
			(at -2.750058 29.45511 180)
			(size 0.381 1.4478)
			(layers "F.Cu" "F.Mask" "F.Paste")
			(net "CLK_100M_BMC_RC_DP")
		)
		(pad "A69" smd rect
			(at -2.750058 30.055058 180)
			(size 0.381 1.4478)
			(layers "F.Cu" "F.Mask" "F.Paste")
			(net "CLK_100M_BMC_RC_DN")
		)
		(pad "A70" smd rect
			(at -2.750058 30.655006 180)
			(size 0.381 1.4478)
			(layers "F.Cu" "F.Mask" "F.Paste")
			(net "GND")
		)
		(pad "B1" smd rect
			(at -5.700014 -18.465038 180)
			(size 0.381 1.4478)
			(layers "F.Cu" "F.Mask" "F.Paste")
			(net "CLK_ESPI_CPU0_CLK1")
		)
		(pad "B2" smd rect
			(at -5.700014 -17.86509 180)
			(size 0.381 1.4478)
			(layers "F.Cu" "F.Mask" "F.Paste")
			(net "ESPI_CPU0_CS1_N")
		)
		(pad "B3" smd rect
			(at -5.700014 -17.264888 180)
			(size 0.381 1.4478)
			(layers "F.Cu" "F.Mask" "F.Paste")
			(net "ESPI_CPU0_ALERT_N")
		)
		(pad "B4" smd rect
			(at -5.700014 -16.66494 180)
			(size 0.381 1.4478)
			(layers "F.Cu" "F.Mask" "F.Paste")
			(net "RST_ESPI_CPU0_RSTOUT_N")
		)
		(pad "B5" smd rect
			(at -5.700014 -16.064992 180)
			(size 0.381 1.4478)
			(layers "F.Cu" "F.Mask" "F.Paste")
			(net "ESPI_CPU0_D0")
		)
		(pad "B6" smd rect
			(at -5.700014 -15.465044 180)
			(size 0.381 1.4478)
			(layers "F.Cu" "F.Mask" "F.Paste")
			(net "ESPI_CPU0_D1")
		)
		(pad "B7" smd rect
			(at -5.700014 -14.865096 180)
			(size 0.381 1.4478)
			(layers "F.Cu" "F.Mask" "F.Paste")
			(net "ESPI_CPU0_D2")
		)
		(pad "B8" smd rect
			(at -5.700014 -14.264894 180)
			(size 0.381 1.4478)
			(layers "F.Cu" "F.Mask" "F.Paste")
			(net "ESPI_CPU0_D3")
		)
		(pad "B9" smd rect
			(at -5.700014 -13.664946 180)
			(size 0.381 1.4478)
			(layers "F.Cu" "F.Mask" "F.Paste")
			(net "FM_LPC_ESPI_SEL")
		)
		(pad "B10" smd rect
			(at -5.700014 -13.064998 180)
			(size 0.381 1.4478)
			(layers "F.Cu" "F.Mask" "F.Paste")
			(net "GND")
		)
		(pad "B11" smd rect
			(at -5.700014 -12.46505 180)
			(size 0.381 1.4478)
			(layers "F.Cu" "F.Mask" "F.Paste")
			(net "SPI_CPU0_LVC3_SCM_CLK")
		)
		(pad "B12" smd rect
			(at -5.700014 -11.865102 180)
			(size 0.381 1.4478)
			(layers "F.Cu" "F.Mask" "F.Paste")
			(net "SPI_CPU0_LVC3_SCM_CS0_N")
		)
		(pad "B13" smd rect
			(at -5.700014 -11.2649 180)
			(size 0.381 1.4478)
			(layers "F.Cu" "F.Mask" "F.Paste")
			(net "SPI_CPU0_LVC3_SCM_D0")
		)
		(pad "B14" smd rect
			(at -5.700014 -10.664952 180)
			(size 0.381 1.4478)
			(layers "F.Cu" "F.Mask" "F.Paste")
			(net "SPI_CPU0_LVC3_SCM_D1")
		)
		(pad "B15" smd rect
			(at -5.700014 -10.065004 180)
			(size 0.381 1.4478)
			(layers "F.Cu" "F.Mask" "F.Paste")
			(net "SPI_CPU0_LVC3_SCM_D2")
		)
		(pad "B16" smd rect
			(at -5.700014 -9.465056 180)
			(size 0.381 1.4478)
			(layers "F.Cu" "F.Mask" "F.Paste")
			(net "SPI_CPU0_LVC3_SCM_D3")
		)
		(pad "B17" smd rect
			(at -5.700014 -8.865108 180)
			(size 0.381 1.4478)
			(layers "F.Cu" "F.Mask" "F.Paste")
			(net "GND")
		)
		(pad "B18" smd rect
			(at -5.700014 -8.264906 180)
			(size 0.381 1.4478)
			(layers "F.Cu" "F.Mask" "F.Paste")
			(net "CLK_50M_RMII_BMC_OCP")
		)
		(pad "B19" smd rect
			(at -5.700014 -7.664958 180)
			(size 0.381 1.4478)
			(layers "F.Cu" "F.Mask" "F.Paste")
			(net "RMII_OCP_BMC_CRSDV")
		)
		(pad "B20" smd rect
			(at -5.700014 -7.06501 180)
			(size 0.381 1.4478)
			(layers "F.Cu" "F.Mask" "F.Paste")
			(net "RMII_BMC_OCP_TX_EN")
		)
		(pad "B21" smd rect
			(at -5.700014 -6.465062 180)
			(size 0.381 1.4478)
			(layers "F.Cu" "F.Mask" "F.Paste")
			(net "RMII_BMC_OCP_TXD_0")
		)
		(pad "B22" smd rect
			(at -5.700014 -5.865114 180)
			(size 0.381 1.4478)
			(layers "F.Cu" "F.Mask" "F.Paste")
			(net "RMII_BMC_OCP_TXD_1")
		)
		(pad "B23" smd rect
			(at -5.700014 -5.264912 180)
			(size 0.381 1.4478)
			(layers "F.Cu" "F.Mask" "F.Paste")
			(net "RMII_BMC_OCP_RX_ER")
		)
		(pad "B24" smd rect
			(at -5.700014 -4.664964 180)
			(size 0.381 1.4478)
			(layers "F.Cu" "F.Mask" "F.Paste")
			(net "RMII_OCP_BMC_RXD_0")
		)
		(pad "B25" smd rect
			(at -5.700014 -4.065016 180)
			(size 0.381 1.4478)
			(layers "F.Cu" "F.Mask" "F.Paste")
			(net "RMII_OCP_BMC_RXD_1")
		)
		(pad "B26" smd rect
			(at -5.700014 -3.465068 180)
			(size 0.381 1.4478)
			(layers "F.Cu" "F.Mask" "F.Paste")
			(net "GND")
		)
		(pad "B27" smd rect
			(at -5.700014 -2.86512 180)
			(size 0.381 1.4478)
			(layers "F.Cu" "F.Mask" "F.Paste")
			(net "TP_PECI_BMC")
		)
		(pad "B28" smd rect
			(at -5.700014 -2.264918 180)
			(size 0.381 1.4478)
			(layers "F.Cu" "F.Mask" "F.Paste")
			(net "TP_PVCCIO_PECI_BMC")
		)
		(pad "B29" smd rect
			(at -5.700014 1.74498 180)
			(size 0.381 1.4478)
			(layers "F.Cu" "F.Mask" "F.Paste")
			(net "SGPIO_SCM_DO_R_<0>")
		)
		(pad "B30" smd rect
			(at -5.700014 2.344928 180)
			(size 0.381 1.4478)
			(layers "F.Cu" "F.Mask" "F.Paste")
			(net "SGPIO_SCM_CLK_R_<0>")
		)
		(pad "B31" smd rect
			(at -5.700014 2.944876 180)
			(size 0.381 1.4478)
			(layers "F.Cu" "F.Mask" "F.Paste")
			(net "SGPIO_SCM_DI_R_<0>")
		)
		(pad "B32" smd rect
			(at -5.700014 3.545078 180)
			(size 0.381 1.4478)
			(layers "F.Cu" "F.Mask" "F.Paste")
			(net "SGPIO_SCM_LD_R_<0>")
		)
		(pad "B33" smd rect
			(at -5.700014 4.145026 180)
			(size 0.381 1.4478)
			(layers "F.Cu" "F.Mask" "F.Paste")
			(net "GND")
		)
		(pad "B34" smd rect
			(at -5.700014 4.744974 180)
			(size 0.381 1.4478)
			(layers "F.Cu" "F.Mask" "F.Paste")
			(net "SGPIO_SCM_DO_R_<1>")
		)
		(pad "B35" smd rect
			(at -5.700014 5.344922 180)
			(size 0.381 1.4478)
			(layers "F.Cu" "F.Mask" "F.Paste")
			(net "SGPIO_SCM_CLK_R_<1>")
		)
		(pad "B36" smd rect
			(at -5.700014 5.945124 180)
			(size 0.381 1.4478)
			(layers "F.Cu" "F.Mask" "F.Paste")
			(net "SGPIO_SCM_DI_R_<1>")
		)
		(pad "B37" smd rect
			(at -5.700014 6.545072 180)
			(size 0.381 1.4478)
			(layers "F.Cu" "F.Mask" "F.Paste")
			(net "SGPIO_SCM_LD_R_<1>")
		)
		(pad "B38" smd rect
			(at -5.700014 7.14502 180)
			(size 0.381 1.4478)
			(layers "F.Cu" "F.Mask" "F.Paste")
			(net "GND")
		)
		(pad "B39" smd rect
			(at -5.700014 7.744968 180)
			(size 0.381 1.4478)
			(layers "F.Cu" "F.Mask" "F.Paste")
			(net "SGPIO_SCM_RESET_R_N")
		)
		(pad "B40" smd rect
			(at -5.700014 8.344916 180)
			(size 0.381 1.4478)
			(layers "F.Cu" "F.Mask" "F.Paste")
			(net "SGPIO_SCM_INTR_R1_N")
		)
		(pad "B41" smd rect
			(at -5.700014 8.945118 180)
			(size 0.381 1.4478)
			(layers "F.Cu" "F.Mask" "F.Paste")
			(net "SCM_VDD_RTC")
		)
		(pad "B42" smd rect
			(at -5.700014 9.545066 180)
			(size 0.381 1.4478)
			(layers "F.Cu" "F.Mask" "F.Paste")
			(net "FM_AC_PWR_BTN_N")
		)
		(pad "B43" smd rect
			(at -5.700014 14.454886 180)
			(size 0.381 1.4478)
			(layers "F.Cu" "F.Mask" "F.Paste")
			(net "TP_SPI_2_PLD_CLK")
		)
		(pad "B44" smd rect
			(at -5.700014 15.055088 180)
			(size 0.381 1.4478)
			(layers "F.Cu" "F.Mask" "F.Paste")
			(net "TP_SPI_2_PLD_CS_N")
		)
		(pad "B45" smd rect
			(at -5.700014 15.655036 180)
			(size 0.381 1.4478)
			(layers "F.Cu" "F.Mask" "F.Paste")
			(net "TP_SPI_2_PLD_IO0")
		)
		(pad "B46" smd rect
			(at -5.700014 16.254984 180)
			(size 0.381 1.4478)
			(layers "F.Cu" "F.Mask" "F.Paste")
			(net "TP_SPI_2_PLD_IO1")
		)
		(pad "B47" smd rect
			(at -5.700014 16.854932 180)
			(size 0.381 1.4478)
			(layers "F.Cu" "F.Mask" "F.Paste")
			(net "TP_SPI_2_PLD_IO2")
		)
		(pad "B48" smd rect
			(at -5.700014 17.45488 180)
			(size 0.381 1.4478)
			(layers "F.Cu" "F.Mask" "F.Paste")
			(net "TP_SPI_2_PLD_IO3")
		)
		(pad "B49" smd rect
			(at -5.700014 18.055082 180)
			(size 0.381 1.4478)
			(layers "F.Cu" "F.Mask" "F.Paste")
			(net "GND")
		)
		(pad "B50" smd rect
			(at -5.700014 18.65503 180)
			(size 0.381 1.4478)
			(layers "F.Cu" "F.Mask" "F.Paste")
			(net "USB2_HOST_BMC_B_DP")
		)
		(pad "B51" smd rect
			(at -5.700014 19.254978 180)
			(size 0.381 1.4478)
			(layers "F.Cu" "F.Mask" "F.Paste")
			(net "USB2_HOST_BMC_B_DN")
		)
		(pad "B52" smd rect
			(at -5.700014 19.854926 180)
			(size 0.381 1.4478)
			(layers "F.Cu" "F.Mask" "F.Paste")
			(net "GND")
		)
		(pad "B53" smd rect
			(at -5.700014 20.455128 180)
			(size 0.381 1.4478)
			(layers "F.Cu" "F.Mask" "F.Paste")
			(net "USB2_CPU0_P1_DP")
		)
		(pad "B54" smd rect
			(at -5.700014 21.055076 180)
			(size 0.381 1.4478)
			(layers "F.Cu" "F.Mask" "F.Paste")
			(net "USB2_CPU0_P1_DN")
		)
		(pad "B55" smd rect
			(at -5.700014 21.655024 180)
			(size 0.381 1.4478)
			(layers "F.Cu" "F.Mask" "F.Paste")
			(net "GND")
		)
		(pad "B56" smd rect
			(at -5.700014 22.254972 180)
			(size 0.381 1.4478)
			(layers "F.Cu" "F.Mask" "F.Paste")
			(net "USB2_HUB_EXT_DP")
		)
		(pad "B57" smd rect
			(at -5.700014 22.85492 180)
			(size 0.381 1.4478)
			(layers "F.Cu" "F.Mask" "F.Paste")
			(net "USB2_HUB_EXT_DN")
		)
		(pad "B58" smd rect
			(at -5.700014 23.455122 180)
			(size 0.381 1.4478)
			(layers "F.Cu" "F.Mask" "F.Paste")
			(net "GND")
		)
		(pad "B59" smd rect
			(at -5.700014 24.05507 180)
			(size 0.381 1.4478)
			(layers "F.Cu" "F.Mask" "F.Paste")
			(net "USB3_CPU0_BMC_TX_BUF_C_DP")
		)
		(pad "B60" smd rect
			(at -5.700014 24.655018 180)
			(size 0.381 1.4478)
			(layers "F.Cu" "F.Mask" "F.Paste")
			(net "USB3_CPU0_BMC_TX_BUF_C_DN")
		)
		(pad "B61" smd rect
			(at -5.700014 25.254966 180)
			(size 0.381 1.4478)
			(layers "F.Cu" "F.Mask" "F.Paste")
			(net "GND")
		)
		(pad "B62" smd rect
			(at -5.700014 25.854914 180)
			(size 0.381 1.4478)
			(layers "F.Cu" "F.Mask" "F.Paste")
			(net "TP_PCIE_TXP<1>")
		)
		(pad "B63" smd rect
			(at -5.700014 26.455116 180)
			(size 0.381 1.4478)
			(layers "F.Cu" "F.Mask" "F.Paste")
			(net "TP_PCIE_TXN<1>")
		)
		(pad "B64" smd rect
			(at -5.700014 27.055064 180)
			(size 0.381 1.4478)
			(layers "F.Cu" "F.Mask" "F.Paste")
			(net "GND")
		)
		(pad "B65" smd rect
			(at -5.700014 27.655012 180)
			(size 0.381 1.4478)
			(layers "F.Cu" "F.Mask" "F.Paste")
			(net "P2E_MB_BMC_TX_C_DP<0>")
		)
		(pad "B66" smd rect
			(at -5.700014 28.25496 180)
			(size 0.381 1.4478)
			(layers "F.Cu" "F.Mask" "F.Paste")
			(net "P2E_MB_BMC_TX_C_DN<0>")
		)
		(pad "B67" smd rect
			(at -5.700014 28.854908 180)
			(size 0.381 1.4478)
			(layers "F.Cu" "F.Mask" "F.Paste")
			(net "GND")
		)
		(pad "B68" smd rect
			(at -5.700014 29.45511 180)
			(size 0.381 1.4478)
			(layers "F.Cu" "F.Mask" "F.Paste")
			(net "TP_PCIE_TXP<3>")
		)
		(pad "B69" smd rect
			(at -5.700014 30.055058 180)
			(size 0.381 1.4478)
			(layers "F.Cu" "F.Mask" "F.Paste")
			(net "TP_BEEP_LED")
		)
		(pad "B70" smd rect
			(at -5.700014 30.655006 180)
			(size 0.381 1.4478)
			(layers "F.Cu" "F.Mask" "F.Paste")
			(net "GND")
		)
		(pad "G1" thru_hole circle
			(at 2.400046 -32.759904 180)
			(size 1.6256 1.6256)
			(drill 1.1176)
			(layers "*.Cu" "*.Mask")
			(remove_unused_layers no)
			(net "GND")
			(clearance 0)
		)
		(pad "G2" thru_hole circle
			(at 2.400046 -20.379944 180)
			(size 1.6256 1.6256)
			(drill 1.1176)
			(layers "*.Cu" "*.Mask")
			(remove_unused_layers no)
			(net "GND")
			(clearance 0)
		)
		(pad "G3" thru_hole circle
			(at 2.400046 0 180)
			(size 1.6256 1.6256)
			(drill 1.1176)
			(layers "*.Cu" "*.Mask")
			(remove_unused_layers no)
			(net "GND")
			(clearance 0)
		)
		(pad "G4" thru_hole circle
			(at 2.400046 12.5349 180)
			(size 1.6256 1.6256)
			(drill 1.1176)
			(layers "*.Cu" "*.Mask")
			(remove_unused_layers no)
			(net "GND")
			(clearance 0)
		)
		(pad "G5" thru_hole circle
			(at 2.400046 32.759904 180)
			(size 1.6256 1.6256)
			(drill 1.1176)
			(layers "*.Cu" "*.Mask")
			(remove_unused_layers no)
			(net "GND")
			(clearance 0)
		)
		(pad "OA1" smd rect
			(at -2.750058 -30.660086 180)
			(size 0.381 1.4478)
			(layers "F.Cu" "F.Mask" "F.Paste")
			(net "P12V_SCM")
		)
		(pad "OA2" smd rect
			(at -2.750058 -30.059884 180)
			(size 0.381 1.4478)
			(layers "F.Cu" "F.Mask" "F.Paste")
			(net "P12V_SCM")
		)
		(pad "OA3" smd rect
			(at -2.750058 -29.459936 180)
			(size 0.381 1.4478)
			(layers "F.Cu" "F.Mask" "F.Paste")
			(net "GND")
		)
		(pad "OA4" smd rect
			(at -2.750058 -28.859988 180)
			(size 0.381 1.4478)
			(layers "F.Cu" "F.Mask" "F.Paste")
			(net "GND")
		)
		(pad "OA5" smd rect
			(at -2.750058 -28.26004 180)
			(size 0.381 1.4478)
			(layers "F.Cu" "F.Mask" "F.Paste")
			(net "I3C_SCM_0_SCL")
		)
		(pad "OA6" smd rect
			(at -2.750058 -27.660092 180)
			(size 0.381 1.4478)
			(layers "F.Cu" "F.Mask" "F.Paste")
			(net "I3C_SCM_0_SDA")
		)
		(pad "OA7" smd rect
			(at -2.750058 -27.05989 180)
			(size 0.381 1.4478)
			(layers "F.Cu" "F.Mask" "F.Paste")
			(net "I3C_SCM_1_SCL")
		)
		(pad "OA8" smd rect
			(at -2.750058 -26.459942 180)
			(size 0.381 1.4478)
			(layers "F.Cu" "F.Mask" "F.Paste")
			(net "I3C_SCM_1_SDA")
		)
		(pad "OA9" smd rect
			(at -2.750058 -25.859994 180)
			(size 0.381 1.4478)
			(layers "F.Cu" "F.Mask" "F.Paste")
			(net "I3C_SCM_2_SCL")
		)
		(pad "OA10" smd rect
			(at -2.750058 -25.260046 180)
			(size 0.381 1.4478)
			(layers "F.Cu" "F.Mask" "F.Paste")
			(net "I3C_SCM_2_SDA")
		)
		(pad "OA11" smd rect
			(at -2.750058 -24.660098 180)
			(size 0.381 1.4478)
			(layers "F.Cu" "F.Mask" "F.Paste")
			(net "I3C_SCM_3_SCL")
		)
		(pad "OA12" smd rect
			(at -2.750058 -24.059896 180)
			(size 0.381 1.4478)
			(layers "F.Cu" "F.Mask" "F.Paste")
			(net "I3C_SCM_3_SDA")
		)
		(pad "OA13" smd rect
			(at -2.750058 -23.459948 180)
			(size 0.381 1.4478)
			(layers "F.Cu" "F.Mask" "F.Paste")
			(net "GND")
		)
		(pad "OA14" smd rect
			(at -2.750058 -22.86 180)
			(size 0.381 1.4478)
			(layers "F.Cu" "F.Mask" "F.Paste")
			(net "VIRTUAL_RESEAT")
		)
		(pad "OB1" smd rect
			(at -5.700014 -30.660086 180)
			(size 0.381 1.4478)
			(layers "F.Cu" "F.Mask" "F.Paste")
			(net "P12V_SCM")
		)
		(pad "OB2" smd rect
			(at -5.700014 -30.059884 180)
			(size 0.381 1.4478)
			(layers "F.Cu" "F.Mask" "F.Paste")
			(net "P12V_SCM")
		)
		(pad "OB3" smd rect
			(at -5.700014 -29.459936 180)
			(size 0.381 1.4478)
			(layers "F.Cu" "F.Mask" "F.Paste")
			(net "PRSNT0_N")
		)
		(pad "OB4" smd rect
			(at -5.700014 -28.859988 180)
			(size 0.381 1.4478)
			(layers "F.Cu" "F.Mask" "F.Paste")
			(net "GND")
		)
		(pad "OB5" smd rect
			(at -5.700014 -28.26004 180)
			(size 0.381 1.4478)
			(layers "F.Cu" "F.Mask" "F.Paste")
			(net "UART_BMC_BIC_TX")
		)
		(pad "OB6" smd rect
			(at -5.700014 -27.660092 180)
			(size 0.381 1.4478)
			(layers "F.Cu" "F.Mask" "F.Paste")
			(net "UART_BMC_BIC_BUF_RX")
		)
		(pad "OB7" smd rect
			(at -5.700014 -27.05989 180)
			(size 0.381 1.4478)
			(layers "F.Cu" "F.Mask" "F.Paste")
			(net "GND")
		)
		(pad "OB8" smd rect
			(at -5.700014 -26.459942 180)
			(size 0.381 1.4478)
			(layers "F.Cu" "F.Mask" "F.Paste")
			(net "UART_CPU0_SCM_LVC3_UART1_RX")
		)
		(pad "OB9" smd rect
			(at -5.700014 -25.859994 180)
			(size 0.381 1.4478)
			(layers "F.Cu" "F.Mask" "F.Paste")
			(net "UART_CPU0_SCM_LVC3_UART1_R1_TX")
		)
		(pad "OB10" smd rect
			(at -5.700014 -25.260046 180)
			(size 0.381 1.4478)
			(layers "F.Cu" "F.Mask" "F.Paste")
			(net "GND")
		)
		(pad "OB11" smd rect
			(at -5.700014 -24.660098 180)
			(size 0.381 1.4478)
			(layers "F.Cu" "F.Mask" "F.Paste")
			(net "RST_SRST_PLD_BMC_N")
		)
		(pad "OB12" smd rect
			(at -5.700014 -24.059896 180)
			(size 0.381 1.4478)
			(layers "F.Cu" "F.Mask" "F.Paste")
			(net "SPI_CPU0_LVC3_TPM_CS_N")
		)
		(pad "OB13" smd rect
			(at -5.700014 -23.459948 180)
			(size 0.381 1.4478)
			(layers "F.Cu" "F.Mask" "F.Paste")
			(net "FPGA_IO3V3_RSVD_1")
		)
		(pad "OB14" smd rect
			(at -5.700014 -22.86 180)
			(size 0.381 1.4478)
			(layers "F.Cu" "F.Mask" "F.Paste")
			(net "FM_SOL_UART_CH_SEL_R")
		)
		(zone
			(layers "F.Cu" "B.Cu" "In1.Cu" "In2.Cu" "In3.Cu" "In4.Cu" "In5.Cu" "In6.Cu"
				"In7.Cu" "In8.Cu" "In9.Cu" "In10.Cu" "In11.Cu" "In12.Cu" "In13.Cu" "In14.Cu"
				"In15.Cu" "In16.Cu"
			)
			(hatch none 0.5)
			(connect_pads
				(clearance 0)
			)
			(min_thickness 0.25)
			(keepout
				(tracks not_allowed)
				(vias allowed)
				(pads allowed)
				(copperpour not_allowed)
				(footprints allowed)
			)
			(placement
				(enabled no)
				(sheetname "")
			)
			(fill
				(thermal_gap 0.5)
				(thermal_bridge_width 0.5)
				(island_removal_mode 0)
			)
			(polygon
				(pts
					(arc
						(start 129.28219 -10.449814)
						(mid 127.35179 -10.449814)
						(end 129.28219 -10.449814)
					)
				)
			)
		)
		(zone
			(layers "F.Cu" "B.Cu" "In1.Cu" "In2.Cu" "In3.Cu" "In4.Cu" "In5.Cu" "In6.Cu"
				"In7.Cu" "In8.Cu" "In9.Cu" "In10.Cu" "In11.Cu" "In12.Cu" "In13.Cu" "In14.Cu"
				"In15.Cu" "In16.Cu"
			)
			(hatch none 0.5)
			(connect_pads
				(clearance 0)
			)
			(min_thickness 0.25)
			(keepout
				(tracks not_allowed)
				(vias allowed)
				(pads allowed)
				(copperpour not_allowed)
				(footprints allowed)
			)
			(placement
				(enabled no)
				(sheetname "")
			)
			(fill
				(thermal_gap 0.5)
				(thermal_bridge_width 0.5)
				(island_removal_mode 0)
			)
			(polygon
				(pts
					(arc
						(start 193.447162 -11.449812)
						(mid 191.516762 -11.449812)
						(end 193.447162 -11.449812)
					)
				)
			)
		)
	)
	(footprint ""
		(layer "F.Cu")
		(at 64.708024 -40.208708 90)
		(property "Reference" "R4067"
			(at 0 0 90)
			(layer "F.SilkS")
			(hide yes)
			(effects
				(font
					(size 1.27 1.27)
				)
			)
		)
		(property "Value" ""
			(at 0 0 90)
			(layer "F.Fab")
			(effects
				(font
					(size 1.27 1.27)
				)
			)
		)
		(duplicate_pad_numbers_are_jumpers no)
		(fp_line
			(start 0.7874 -0.4064)
			(end 0.7874 0.4064)
			(stroke
				(width 0.1524)
				(type default)
			)
			(layer "F.SilkS")
		)
		(fp_line
			(start -0.7874 -0.4064)
			(end 0.7874 -0.4064)
			(stroke
				(width 0.1524)
				(type default)
			)
			(layer "F.SilkS")
		)
		(fp_line
			(start 0.7874 0.4064)
			(end -0.7874 0.4064)
			(stroke
				(width 0.1524)
				(type default)
			)
			(layer "F.SilkS")
		)
		(fp_line
			(start -0.7874 0.4064)
			(end -0.7874 -0.4064)
			(stroke
				(width 0.1524)
				(type default)
			)
			(layer "F.SilkS")
		)
		(fp_line
			(start -0.12065 -0.305054)
			(end -0.12065 -0.2794)
			(stroke
				(width 0.1)
				(type default)
			)
			(layer "F.Fab")
		)
		(fp_line
			(start -0.67945 -0.305054)
			(end -0.12065 -0.305054)
			(stroke
				(width 0.1)
				(type default)
			)
			(layer "F.Fab")
		)
		(fp_line
			(start 0.67945 -0.3048)
			(end 0.67945 0.3048)
			(stroke
				(width 0.1)
				(type default)
			)
			(layer "F.Fab")
		)
		(fp_line
			(start 0.12065 -0.3048)
			(end 0.67945 -0.3048)
			(stroke
				(width 0.1)
				(type default)
			)
			(layer "F.Fab")
		)
		(fp_line
			(start 0.12065 -0.2794)
			(end 0.12065 -0.3048)
			(stroke
				(width 0.1)
				(type default)
			)
			(layer "F.Fab")
		)
		(fp_line
			(start -0.12065 -0.2794)
			(end 0.12065 -0.2794)
			(stroke
				(width 0.1)
				(type default)
			)
			(layer "F.Fab")
		)
		(fp_line
			(start 0.120396 0.2794)
			(end -0.12065 0.2794)
			(stroke
				(width 0.1)
				(type default)
			)
			(layer "F.Fab")
		)
		(fp_line
			(start -0.12065 0.2794)
			(end -0.12065 0.3048)
			(stroke
				(width 0.1)
				(type default)
			)
			(layer "F.Fab")
		)
		(fp_line
			(start 0.67945 0.3048)
			(end 0.120396 0.3048)
			(stroke
				(width 0.1)
				(type default)
			)
			(layer "F.Fab")
		)
		(fp_line
			(start 0.120396 0.3048)
			(end 0.120396 0.2794)
			(stroke
				(width 0.1)
				(type default)
			)
			(layer "F.Fab")
		)
		(fp_line
			(start -0.12065 0.3048)
			(end -0.67945 0.3048)
			(stroke
				(width 0.1)
				(type default)
			)
			(layer "F.Fab")
		)
		(fp_line
			(start -0.67945 0.3048)
			(end -0.67945 -0.305054)
			(stroke
				(width 0.1)
				(type default)
			)
			(layer "F.Fab")
		)
		(pad "1" smd circle
			(at -0.40005 0 90)
			(size 0 0)
			(layers "F.Cu" "F.Mask" "F.Paste")
			(net "P12V_AUX")
		)
		(pad "2" smd circle
			(at 0.40005 0 90)
			(size 0 0)
			(layers "F.Cu" "F.Mask" "F.Paste")
			(net "P3V3_OCP_2_EN_G")
		)
	)
	(footprint ""
		(layer "F.Cu")
		(at 28.534106 19.444716 -90)
		(property "Reference" "LBL_1"
			(at 0 0 270)
			(layer "F.SilkS")
			(hide yes)
			(effects
				(font
					(size 1.27 1.27)
				)
			)
		)
		(property "Value" ""
			(at 0 0 270)
			(layer "F.Fab")
			(effects
				(font
					(size 1.27 1.27)
				)
			)
		)
		(duplicate_pad_numbers_are_jumpers no)
		(pad "1" smd circle
			(at 0 0 270)
			(size 0.762 0.762)
			(layers "F.Cu" "F.Mask" "F.Paste")
			(net "Net_10817")
		)
	)
	(footprint ""
		(layer "F.Cu")
		(at 156.0957 -387.342634)
		(property "Reference" "U6016"
			(at -8.08609 -8.07466 0)
			(unlocked yes)
			(layer "F.SilkS")
			(effects
				(font
					(size 0.7874 0.5842)
					(thickness 0.1524)
				)
				(justify left)
			)
		)
		(property "Value" ""
			(at 0 0 0)
			(layer "F.Fab")
			(effects
				(font
					(size 1.27 1.27)
				)
			)
		)
		(duplicate_pad_numbers_are_jumpers no)
		(fp_line
			(start -11.400028 -4.45008)
			(end -9.7917 -4.45008)
			(stroke
				(width 0.1524)
				(type default)
			)
			(layer "F.SilkS")
		)
		(fp_line
			(start -11.400028 -0.845566)
			(end -11.400028 -4.45008)
			(stroke
				(width 0.1524)
				(type default)
			)
			(layer "F.SilkS")
		)
		(fp_line
			(start -11.400028 4.45008)
			(end -11.400028 0.145034)
			(stroke
				(width 0.1524)
				(type default)
			)
			(layer "F.SilkS")
		)
		(fp_line
			(start -10.1727 4.45008)
			(end -11.400028 4.45008)
			(stroke
				(width 0.1524)
				(type default)
			)
			(layer "F.SilkS")
		)
		(fp_line
			(start 9.5885 -4.45008)
			(end 11.400028 -4.45008)
			(stroke
				(width 0.1524)
				(type default)
			)
			(layer "F.SilkS")
		)
		(fp_line
			(start 11.400028 -4.45008)
			(end 11.400028 4.45008)
			(stroke
				(width 0.1524)
				(type default)
			)
			(layer "F.SilkS")
		)
		(fp_line
			(start 11.400028 4.45008)
			(end 9.5631 4.45008)
			(stroke
				(width 0.1524)
				(type default)
			)
			(layer "F.SilkS")
		)
		(fp_poly
			(pts
				(xy 10.450068 -4.45008) (xy 10.450068 -5.21208) (xy 12.162028 -5.21208) (xy 12.162028 -3.41884)
				(xy 11.400028 -3.41884) (xy 11.400028 -4.45008)
			)
			(stroke
				(width 0)
				(type default)
			)
			(fill yes)
			(layer "F.SilkS")
		)
		(fp_line
			(start -11.400028 -4.45008)
			(end -11.400028 4.45008)
			(stroke
				(width 0.1)
				(type default)
			)
			(layer "F.Fab")
		)
		(fp_line
			(start -11.400028 4.45008)
			(end 11.400028 4.45008)
			(stroke
				(width 0.1)
				(type default)
			)
			(layer "F.Fab")
		)
		(fp_line
			(start 11.400028 -4.45008)
			(end -11.400028 -4.45008)
			(stroke
				(width 0.1)
				(type default)
			)
			(layer "F.Fab")
		)
		(fp_line
			(start 11.400028 4.45008)
			(end 11.400028 -4.45008)
			(stroke
				(width 0.1)
				(type default)
			)
			(layer "F.Fab")
		)
		(fp_poly
			(pts
				(xy 10.450068 -4.45008) (xy 10.450068 -5.21208) (xy 12.162028 -5.21208) (xy 12.162028 -3.41884)
				(xy 11.400028 -3.41884) (xy 11.400028 -4.45008)
			)
			(stroke
				(width 0)
				(type default)
			)
			(fill yes)
			(layer "F.Fab")
		)
		(pad "A1" smd oval
			(at 11.050016 -3.938524)
			(size 0.254 0.3302)
			(layers "F.Cu" "F.Mask" "F.Paste")
			(net "NCF_A1_CPU1_P2_GND")
		)
		(pad "A35" smd oval
			(at 11.050016 3.940048)
			(size 0.254 0.3302)
			(layers "F.Cu" "F.Mask" "F.Paste")
			(net "NCF_CPU1_P2_GND")
		)
		(pad "AA10" smd circle
			(at 7.602728 -1.431798)
			(size 0.381 0.381)
			(layers "F.Cu" "F.Mask" "F.Paste")
			(net "P5E_CPU1_P2_TX_BUF_DN<14>")
		)
		(pad "AA29" smd circle
			(at 7.602728 2.032254)
			(size 0.381 0.381)
			(layers "F.Cu" "F.Mask" "F.Paste")
			(net "P5E_CPU1_P2_RX_DN<14>")
		)
		(pad "AB1" smd oval
			(at 7.450074 -3.938524)
			(size 0.254 0.3302)
			(layers "F.Cu" "F.Mask" "F.Paste")
			(net "P5E_CPU1_P2_RX_BUF_DP<14>")
		)
		(pad "AB35" smd oval
			(at 7.450074 3.940048)
			(size 0.254 0.3302)
			(layers "F.Cu" "F.Mask" "F.Paste")
			(net "P5E_CPU1_P2_TX_C_DP<14>")
		)
		(pad "AC4" smd circle
			(at 7.202678 -2.817368)
			(size 0.381 0.381)
			(layers "F.Cu" "F.Mask" "F.Paste")
			(net "GND")
		)
		(pad "AC13" smd circle
			(at 7.202678 -0.79629)
			(size 0.3048 0.3048)
			(layers "F.Cu" "F.Mask" "F.Paste")
			(net "GND")
		)
		(pad "AC17" smd circle
			(at 7.202678 -0.296164)
			(size 0.3048 0.3048)
			(layers "F.Cu" "F.Mask" "F.Paste")
			(net "P0V9_CPU1_RT2_2A")
		)
		(pad "AC20" smd circle
			(at 7.202678 0.203708)
			(size 0.3048 0.3048)
			(layers "F.Cu" "F.Mask" "F.Paste")
			(net "P0V9_CPU1_RT2_2A")
		)
		(pad "AC22" smd circle
			(at 7.202678 0.703834)
			(size 0.3048 0.3048)
			(layers "F.Cu" "F.Mask" "F.Paste")
			(net "GND")
		)
		(pad "AC32" smd circle
			(at 7.202678 2.724912)
			(size 0.381 0.381)
			(layers "F.Cu" "F.Mask" "F.Paste")
			(net "GND")
		)
		(pad "AD2" smd circle
			(at 7.1501 -3.41884)
			(size 0.3048 0.3048)
			(layers "F.Cu" "F.Mask" "F.Paste")
			(net "GND")
		)
		(pad "AD34" smd circle
			(at 7.1501 3.420364)
			(size 0.3048 0.3048)
			(layers "F.Cu" "F.Mask" "F.Paste")
			(net "GND")
		)
		(pad "AE1" smd oval
			(at 6.849872 -3.938524)
			(size 0.254 0.3302)
			(layers "F.Cu" "F.Mask" "F.Paste")
			(net "GND")
		)
		(pad "AE35" smd oval
			(at 6.849872 3.940048)
			(size 0.254 0.3302)
			(layers "F.Cu" "F.Mask" "F.Paste")
			(net "GND")
		)
		(pad "AF7" smd circle
			(at 6.802628 -2.12471)
			(size 0.381 0.381)
			(layers "F.Cu" "F.Mask" "F.Paste")
			(net "P5E_CPU1_P2_TX_BUF_DP<13>")
		)
		(pad "AF26" smd circle
			(at 6.802628 1.339342)
			(size 0.381 0.381)
			(layers "F.Cu" "F.Mask" "F.Paste")
			(net "P5E_CPU1_P2_RX_DP<13>")
		)
		(pad "AG2" smd circle
			(at 6.549898 -3.41884)
			(size 0.3048 0.3048)
			(layers "F.Cu" "F.Mask" "F.Paste")
			(net "P5E_CPU1_P2_RX_BUF_DN<13>")
		)
		(pad "AG34" smd circle
			(at 6.549898 3.420364)
			(size 0.3048 0.3048)
			(layers "F.Cu" "F.Mask" "F.Paste")
			(net "P5E_CPU1_P2_TX_C_DN<13>")
		)
		(pad "AH10" smd circle
			(at 6.402578 -1.431798)
			(size 0.381 0.381)
			(layers "F.Cu" "F.Mask" "F.Paste")
			(net "P5E_CPU1_P2_TX_BUF_DN<13>")
		)
		(pad "AH29" smd circle
			(at 6.402578 2.032254)
			(size 0.381 0.381)
			(layers "F.Cu" "F.Mask" "F.Paste")
			(net "P5E_CPU1_P2_RX_DN<13>")
		)
		(pad "AJ1" smd oval
			(at 6.249924 -3.938524)
			(size 0.254 0.3302)
			(layers "F.Cu" "F.Mask" "F.Paste")
			(net "P5E_CPU1_P2_RX_BUF_DP<13>")
		)
		(pad "AJ35" smd oval
			(at 6.249924 3.940048)
			(size 0.254 0.3302)
			(layers "F.Cu" "F.Mask" "F.Paste")
			(net "P5E_CPU1_P2_TX_C_DP<13>")
		)
		(pad "AK4" smd circle
			(at 6.002528 -2.817368)
			(size 0.381 0.381)
			(layers "F.Cu" "F.Mask" "F.Paste")
			(net "GND")
		)
		(pad "AK13" smd circle
			(at 6.002528 -0.79629)
			(size 0.3048 0.3048)
			(layers "F.Cu" "F.Mask" "F.Paste")
			(net "GND")
		)
		(pad "AK17" smd circle
			(at 6.002528 -0.296164)
			(size 0.3048 0.3048)
			(layers "F.Cu" "F.Mask" "F.Paste")
			(net "P0V9_CPU1_RT2_2A")
		)
		(pad "AK20" smd circle
			(at 6.002528 0.203708)
			(size 0.3048 0.3048)
			(layers "F.Cu" "F.Mask" "F.Paste")
			(net "P0V9_CPU1_RT2_2A")
		)
		(pad "AK22" smd circle
			(at 6.002528 0.703834)
			(size 0.3048 0.3048)
			(layers "F.Cu" "F.Mask" "F.Paste")
			(net "GND")
		)
		(pad "AK32" smd circle
			(at 6.002528 2.724912)
			(size 0.381 0.381)
			(layers "F.Cu" "F.Mask" "F.Paste")
			(net "GND")
		)
		(pad "AL2" smd circle
			(at 5.94995 -3.41884)
			(size 0.3048 0.3048)
			(layers "F.Cu" "F.Mask" "F.Paste")
			(net "GND")
		)
		(pad "AL34" smd circle
			(at 5.94995 3.420364)
			(size 0.3048 0.3048)
			(layers "F.Cu" "F.Mask" "F.Paste")
			(net "GND")
		)
		(pad "AM1" smd oval
			(at 5.649976 -3.938524)
			(size 0.254 0.3302)
			(layers "F.Cu" "F.Mask" "F.Paste")
			(net "GND")
		)
		(pad "AM35" smd oval
			(at 5.649976 3.940048)
			(size 0.254 0.3302)
			(layers "F.Cu" "F.Mask" "F.Paste")
			(net "GND")
		)
		(pad "AN7" smd circle
			(at 5.602478 -2.12471)
			(size 0.381 0.381)
			(layers "F.Cu" "F.Mask" "F.Paste")
			(net "P5E_CPU1_P2_TX_BUF_DP<12>")
		)
		(pad "AN26" smd circle
			(at 5.602478 1.339342)
			(size 0.381 0.381)
			(layers "F.Cu" "F.Mask" "F.Paste")
			(net "P5E_CPU1_P2_RX_DP<12>")
		)
		(pad "AP2" smd circle
			(at 5.350002 -3.41884)
			(size 0.3048 0.3048)
			(layers "F.Cu" "F.Mask" "F.Paste")
			(net "P5E_CPU1_P2_RX_BUF_DN<12>")
		)
		(pad "AP34" smd circle
			(at 5.350002 3.420364)
			(size 0.3048 0.3048)
			(layers "F.Cu" "F.Mask" "F.Paste")
			(net "P5E_CPU1_P2_TX_C_DN<12>")
		)
		(pad "AR10" smd circle
			(at 5.202682 -1.431798)
			(size 0.381 0.381)
			(layers "F.Cu" "F.Mask" "F.Paste")
			(net "P5E_CPU1_P2_TX_BUF_DN<12>")
		)
		(pad "AR29" smd circle
			(at 5.202682 2.032254)
			(size 0.381 0.381)
			(layers "F.Cu" "F.Mask" "F.Paste")
			(net "P5E_CPU1_P2_RX_DN<12>")
		)
		(pad "AT1" smd oval
			(at 5.050028 -3.938524)
			(size 0.254 0.3302)
			(layers "F.Cu" "F.Mask" "F.Paste")
			(net "P5E_CPU1_P2_RX_BUF_DP<12>")
		)
		(pad "AT35" smd oval
			(at 5.050028 3.940048)
			(size 0.254 0.3302)
			(layers "F.Cu" "F.Mask" "F.Paste")
			(net "P5E_CPU1_P2_TX_C_DP<12>")
		)
		(pad "AU4" smd circle
			(at 4.802632 -2.817368)
			(size 0.381 0.381)
			(layers "F.Cu" "F.Mask" "F.Paste")
			(net "GND")
		)
		(pad "AU13" smd circle
			(at 4.802632 -0.79629)
			(size 0.3048 0.3048)
			(layers "F.Cu" "F.Mask" "F.Paste")
			(net "GND")
		)
		(pad "AU17" smd circle
			(at 4.802632 -0.296164)
			(size 0.3048 0.3048)
			(layers "F.Cu" "F.Mask" "F.Paste")
			(net "P0V9_CPU1_RT2_2A")
		)
		(pad "AU20" smd circle
			(at 4.802632 0.203708)
			(size 0.3048 0.3048)
			(layers "F.Cu" "F.Mask" "F.Paste")
			(net "P0V9_CPU1_RT2_2A")
		)
		(pad "AU22" smd circle
			(at 4.802632 0.703834)
			(size 0.3048 0.3048)
			(layers "F.Cu" "F.Mask" "F.Paste")
			(net "GND")
		)
		(pad "AU32" smd circle
			(at 4.802632 2.724912)
			(size 0.381 0.381)
			(layers "F.Cu" "F.Mask" "F.Paste")
			(net "GND")
		)
		(pad "AV2" smd circle
			(at 4.750054 -3.41884)
			(size 0.3048 0.3048)
			(layers "F.Cu" "F.Mask" "F.Paste")
			(net "GND")
		)
		(pad "AV34" smd circle
			(at 4.750054 3.420364)
			(size 0.3048 0.3048)
			(layers "F.Cu" "F.Mask" "F.Paste")
			(net "GND")
		)
		(pad "AW1" smd oval
			(at 4.45008 -3.938524)
			(size 0.254 0.3302)
			(layers "F.Cu" "F.Mask" "F.Paste")
			(net "GND")
		)
		(pad "AW35" smd oval
			(at 4.45008 3.940048)
			(size 0.254 0.3302)
			(layers "F.Cu" "F.Mask" "F.Paste")
			(net "GND")
		)
		(pad "AY7" smd circle
			(at 4.402582 -2.12471)
			(size 0.381 0.381)
			(layers "F.Cu" "F.Mask" "F.Paste")
			(net "P5E_CPU1_P2_TX_BUF_DP<11>")
		)
		(pad "AY26" smd circle
			(at 4.402582 1.339342)
			(size 0.381 0.381)
			(layers "F.Cu" "F.Mask" "F.Paste")
			(net "P5E_CPU1_P2_RX_DP<11>")
		)
		(pad "B3" smd oval
			(at 10.885932 -2.888488 90)
			(size 0.254 0.3302)
			(layers "F.Cu" "F.Mask" "F.Paste")
			(net "JTAG_TCK_RT_CPU1_P2")
		)
		(pad "B6" smd oval
			(at 10.885932 -2.288286 90)
			(size 0.254 0.3302)
			(layers "F.Cu" "F.Mask" "F.Paste")
			(net "JTAG_TDI_RT_CPU1_P2")
		)
		(pad "B9" smd oval
			(at 10.885932 -1.688338 90)
			(size 0.254 0.3302)
			(layers "F.Cu" "F.Mask" "F.Paste")
			(net "JTAG_TDO_RT_CPU1_P2")
		)
		(pad "B12" smd oval
			(at 10.885932 -1.08839 90)
			(size 0.254 0.3302)
			(layers "F.Cu" "F.Mask" "F.Paste")
			(net "JTAG_TMS_RT_CPU1_P2")
		)
		(pad "B16" smd oval
			(at 10.885932 -0.488442 90)
			(size 0.254 0.3302)
			(layers "F.Cu" "F.Mask" "F.Paste")
			(net "Net_2225")
		)
		(pad "B19" smd oval
			(at 10.885932 0.111506 90)
			(size 0.254 0.3302)
			(layers "F.Cu" "F.Mask" "F.Paste")
			(net "GND")
		)
		(pad "B23" smd oval
			(at 10.885932 0.711708 90)
			(size 0.254 0.3302)
			(layers "F.Cu" "F.Mask" "F.Paste")
			(net "RT_CPU1_P2_ADDR2")
		)
		(pad "B25" smd oval
			(at 10.885932 1.311656 90)
			(size 0.254 0.3302)
			(layers "F.Cu" "F.Mask" "F.Paste")
			(net "RT_CPU1_P2_ADDR3")
		)
		(pad "B28" smd oval
			(at 10.885932 1.911604 90)
			(size 0.254 0.3302)
			(layers "F.Cu" "F.Mask" "F.Paste")
			(net "SMB_RT_CPU1_P2_R2_SDA")
		)
		(pad "B31" smd oval
			(at 10.885932 2.511552 90)
			(size 0.254 0.3302)
			(layers "F.Cu" "F.Mask" "F.Paste")
			(net "SMB_RT_CPU1_P2_R2_SCL")
		)
		(pad "BA2" smd circle
			(at 4.150106 -3.41884)
			(size 0.3048 0.3048)
			(layers "F.Cu" "F.Mask" "F.Paste")
			(net "P5E_CPU1_P2_RX_BUF_DN<11>")
		)
		(pad "BA34" smd circle
			(at 4.150106 3.420364)
			(size 0.3048 0.3048)
			(layers "F.Cu" "F.Mask" "F.Paste")
			(net "P5E_CPU1_P2_TX_C_DN<11>")
		)
		(pad "BB10" smd circle
			(at 4.002532 -1.431798)
			(size 0.381 0.381)
			(layers "F.Cu" "F.Mask" "F.Paste")
			(net "P5E_CPU1_P2_TX_BUF_DN<11>")
		)
		(pad "BB29" smd circle
			(at 4.002532 2.032254)
			(size 0.381 0.381)
			(layers "F.Cu" "F.Mask" "F.Paste")
			(net "P5E_CPU1_P2_RX_DN<11>")
		)
		(pad "BC1" smd oval
			(at 3.849878 -3.938524)
			(size 0.254 0.3302)
			(layers "F.Cu" "F.Mask" "F.Paste")
			(net "P5E_CPU1_P2_RX_BUF_DP<11>")
		)
		(pad "BC35" smd oval
			(at 3.849878 3.940048)
			(size 0.254 0.3302)
			(layers "F.Cu" "F.Mask" "F.Paste")
			(net "P5E_CPU1_P2_TX_C_DP<11>")
		)
		(pad "BD4" smd circle
			(at 3.602482 -2.817368)
			(size 0.381 0.381)
			(layers "F.Cu" "F.Mask" "F.Paste")
			(net "GND")
		)
		(pad "BD13" smd circle
			(at 3.602482 -0.79629)
			(size 0.3048 0.3048)
			(layers "F.Cu" "F.Mask" "F.Paste")
			(net "GND")
		)
		(pad "BD17" smd circle
			(at 3.602482 -0.296164)
			(size 0.3048 0.3048)
			(layers "F.Cu" "F.Mask" "F.Paste")
			(net "P0V9_CPU1_RT2_2A_2D")
		)
		(pad "BD20" smd circle
			(at 3.602482 0.203708)
			(size 0.3048 0.3048)
			(layers "F.Cu" "F.Mask" "F.Paste")
			(net "P0V9_CPU1_RT2_2A_2D")
		)
		(pad "BD22" smd circle
			(at 3.602482 0.703834)
			(size 0.3048 0.3048)
			(layers "F.Cu" "F.Mask" "F.Paste")
			(net "GND")
		)
		(pad "BD32" smd circle
			(at 3.602482 2.724912)
			(size 0.381 0.381)
			(layers "F.Cu" "F.Mask" "F.Paste")
			(net "GND")
		)
		(pad "BE2" smd circle
			(at 3.549904 -3.41884)
			(size 0.3048 0.3048)
			(layers "F.Cu" "F.Mask" "F.Paste")
			(net "GND")
		)
		(pad "BE34" smd circle
			(at 3.549904 3.420364)
			(size 0.3048 0.3048)
			(layers "F.Cu" "F.Mask" "F.Paste")
			(net "GND")
		)
		(pad "BF1" smd oval
			(at 3.24993 -3.938524)
			(size 0.254 0.3302)
			(layers "F.Cu" "F.Mask" "F.Paste")
			(net "GND")
		)
		(pad "BF35" smd oval
			(at 3.24993 3.940048)
			(size 0.254 0.3302)
			(layers "F.Cu" "F.Mask" "F.Paste")
			(net "GND")
		)
		(pad "BG7" smd circle
			(at 3.202686 -2.12471)
			(size 0.381 0.381)
			(layers "F.Cu" "F.Mask" "F.Paste")
			(net "P5E_CPU1_P2_TX_BUF_DP<10>")
		)
		(pad "BG26" smd circle
			(at 3.202686 1.339342)
			(size 0.381 0.381)
			(layers "F.Cu" "F.Mask" "F.Paste")
			(net "P5E_CPU1_P2_RX_DP<10>")
		)
		(pad "BH2" smd circle
			(at 2.949956 -3.41884)
			(size 0.3048 0.3048)
			(layers "F.Cu" "F.Mask" "F.Paste")
			(net "P5E_CPU1_P2_RX_BUF_DN<10>")
		)
		(pad "BH34" smd circle
			(at 2.949956 3.420364)
			(size 0.3048 0.3048)
			(layers "F.Cu" "F.Mask" "F.Paste")
			(net "P5E_CPU1_P2_TX_C_DN<10>")
		)
		(pad "BJ10" smd circle
			(at 2.802636 -1.431798)
			(size 0.381 0.381)
			(layers "F.Cu" "F.Mask" "F.Paste")
			(net "P5E_CPU1_P2_TX_BUF_DN<10>")
		)
		(pad "BJ29" smd circle
			(at 2.802636 2.032254)
			(size 0.381 0.381)
			(layers "F.Cu" "F.Mask" "F.Paste")
			(net "P5E_CPU1_P2_RX_DN<10>")
		)
		(pad "BK1" smd oval
			(at 2.649982 -3.938524)
			(size 0.254 0.3302)
			(layers "F.Cu" "F.Mask" "F.Paste")
			(net "P5E_CPU1_P2_RX_BUF_DP<10>")
		)
		(pad "BK35" smd oval
			(at 2.649982 3.940048)
			(size 0.254 0.3302)
			(layers "F.Cu" "F.Mask" "F.Paste")
			(net "P5E_CPU1_P2_TX_C_DP<10>")
		)
		(pad "BL4" smd circle
			(at 2.402586 -2.817368)
			(size 0.381 0.381)
			(layers "F.Cu" "F.Mask" "F.Paste")
			(net "GND")
		)
		(pad "BL13" smd circle
			(at 2.402586 -0.79629)
			(size 0.3048 0.3048)
			(layers "F.Cu" "F.Mask" "F.Paste")
			(net "GND")
		)
		(pad "BL17" smd circle
			(at 2.402586 -0.296164)
			(size 0.3048 0.3048)
			(layers "F.Cu" "F.Mask" "F.Paste")
			(net "P0V9_CPU1_RT_2D")
		)
		(pad "BL20" smd circle
			(at 2.402586 0.203708)
			(size 0.3048 0.3048)
			(layers "F.Cu" "F.Mask" "F.Paste")
			(net "P0V9_CPU1_RT_2D")
		)
		(pad "BL22" smd circle
			(at 2.402586 0.703834)
			(size 0.3048 0.3048)
			(layers "F.Cu" "F.Mask" "F.Paste")
			(net "GND")
		)
		(pad "BL32" smd circle
			(at 2.402586 2.724912)
			(size 0.381 0.381)
			(layers "F.Cu" "F.Mask" "F.Paste")
			(net "GND")
		)
		(pad "BM2" smd circle
			(at 2.350008 -3.41884)
			(size 0.3048 0.3048)
			(layers "F.Cu" "F.Mask" "F.Paste")
			(net "GND")
		)
		(pad "BM34" smd circle
			(at 2.350008 3.420364)
			(size 0.3048 0.3048)
			(layers "F.Cu" "F.Mask" "F.Paste")
			(net "GND")
		)
		(pad "BN1" smd oval
			(at 2.050034 -3.938524)
			(size 0.254 0.3302)
			(layers "F.Cu" "F.Mask" "F.Paste")
			(net "GND")
		)
		(pad "BN35" smd oval
			(at 2.050034 3.940048)
			(size 0.254 0.3302)
			(layers "F.Cu" "F.Mask" "F.Paste")
			(net "GND")
		)
		(pad "BP7" smd circle
			(at 2.002536 -2.12471)
			(size 0.381 0.381)
			(layers "F.Cu" "F.Mask" "F.Paste")
			(net "P5E_CPU1_P2_TX_BUF_DP<9>")
		)
		(pad "BP26" smd circle
			(at 2.002536 1.339342)
			(size 0.381 0.381)
			(layers "F.Cu" "F.Mask" "F.Paste")
			(net "P5E_CPU1_P2_RX_DP<9>")
		)
		(pad "BR2" smd circle
			(at 1.75006 -3.41884)
			(size 0.3048 0.3048)
			(layers "F.Cu" "F.Mask" "F.Paste")
			(net "P5E_CPU1_P2_RX_BUF_DN<9>")
		)
		(pad "BR34" smd circle
			(at 1.75006 3.420364)
			(size 0.3048 0.3048)
			(layers "F.Cu" "F.Mask" "F.Paste")
			(net "P5E_CPU1_P2_TX_C_DN<9>")
		)
		(pad "BT10" smd circle
			(at 1.602486 -1.431798)
			(size 0.381 0.381)
			(layers "F.Cu" "F.Mask" "F.Paste")
			(net "P5E_CPU1_P2_TX_BUF_DN<9>")
		)
		(pad "BT29" smd circle
			(at 1.602486 2.032254)
			(size 0.381 0.381)
			(layers "F.Cu" "F.Mask" "F.Paste")
			(net "P5E_CPU1_P2_RX_DN<9>")
		)
		(pad "BU1" smd oval
			(at 1.450086 -3.938524)
			(size 0.254 0.3302)
			(layers "F.Cu" "F.Mask" "F.Paste")
			(net "P5E_CPU1_P2_RX_BUF_DP<9>")
		)
		(pad "BU35" smd oval
			(at 1.450086 3.940048)
			(size 0.254 0.3302)
			(layers "F.Cu" "F.Mask" "F.Paste")
			(net "P5E_CPU1_P2_TX_C_DP<9>")
		)
		(pad "BV4" smd circle
			(at 1.20269 -2.817368)
			(size 0.381 0.381)
			(layers "F.Cu" "F.Mask" "F.Paste")
			(net "GND")
		)
		(pad "BV13" smd circle
			(at 1.20269 -0.79629)
			(size 0.3048 0.3048)
			(layers "F.Cu" "F.Mask" "F.Paste")
			(net "GND")
		)
		(pad "BV17" smd circle
			(at 1.20269 -0.296164)
			(size 0.3048 0.3048)
			(layers "F.Cu" "F.Mask" "F.Paste")
			(net "P1V8_CPU1_RT2_1A_1D")
		)
		(pad "BV20" smd circle
			(at 1.20269 0.203708)
			(size 0.3048 0.3048)
			(layers "F.Cu" "F.Mask" "F.Paste")
			(net "P1V8_CPU1_RT2_1A")
		)
		(pad "BV22" smd circle
			(at 1.20269 0.703834)
			(size 0.3048 0.3048)
			(layers "F.Cu" "F.Mask" "F.Paste")
			(net "GND")
		)
		(pad "BV32" smd circle
			(at 1.20269 2.724912)
			(size 0.381 0.381)
			(layers "F.Cu" "F.Mask" "F.Paste")
			(net "GND")
		)
		(pad "BW2" smd circle
			(at 1.150112 -3.41884)
			(size 0.3048 0.3048)
			(layers "F.Cu" "F.Mask" "F.Paste")
			(net "GND")
		)
		(pad "BW34" smd circle
			(at 1.150112 3.420364)
			(size 0.3048 0.3048)
			(layers "F.Cu" "F.Mask" "F.Paste")
			(net "GND")
		)
		(pad "BY1" smd oval
			(at 0.849884 -3.938524)
			(size 0.254 0.3302)
			(layers "F.Cu" "F.Mask" "F.Paste")
			(net "GND")
		)
		(pad "BY35" smd oval
			(at 0.849884 3.940048)
			(size 0.254 0.3302)
			(layers "F.Cu" "F.Mask" "F.Paste")
			(net "GND")
		)
		(pad "C2" smd circle
			(at 10.750042 -3.41884)
			(size 0.3048 0.3048)
			(layers "F.Cu" "F.Mask" "F.Paste")
			(net "NCF_CPU1_P2_GND")
		)
		(pad "C34" smd circle
			(at 10.750042 3.420364)
			(size 0.3048 0.3048)
			(layers "F.Cu" "F.Mask" "F.Paste")
			(net "NCF_CPU1_P2_GND")
		)
		(pad "CA7" smd circle
			(at 0.80264 -2.12471)
			(size 0.381 0.381)
			(layers "F.Cu" "F.Mask" "F.Paste")
			(net "P5E_CPU1_P2_TX_BUF_DP<8>")
		)
		(pad "CA26" smd circle
			(at 0.80264 1.339342)
			(size 0.381 0.381)
			(layers "F.Cu" "F.Mask" "F.Paste")
			(net "P5E_CPU1_P2_RX_DP<8>")
		)
		(pad "CB2" smd circle
			(at 0.54991 -3.41884)
			(size 0.3048 0.3048)
			(layers "F.Cu" "F.Mask" "F.Paste")
			(net "P5E_CPU1_P2_RX_BUF_DN<8>")
		)
		(pad "CB34" smd circle
			(at 0.54991 3.420364)
			(size 0.3048 0.3048)
			(layers "F.Cu" "F.Mask" "F.Paste")
			(net "P5E_CPU1_P2_TX_C_DN<8>")
		)
		(pad "CC10" smd circle
			(at 0.40259 -1.431798)
			(size 0.381 0.381)
			(layers "F.Cu" "F.Mask" "F.Paste")
			(net "P5E_CPU1_P2_TX_BUF_DN<8>")
		)
		(pad "CC29" smd circle
			(at 0.40259 2.032254)
			(size 0.381 0.381)
			(layers "F.Cu" "F.Mask" "F.Paste")
			(net "P5E_CPU1_P2_RX_DN<8>")
		)
		(pad "CD1" smd oval
			(at 0.249936 -3.938524)
			(size 0.254 0.3302)
			(layers "F.Cu" "F.Mask" "F.Paste")
			(net "P5E_CPU1_P2_RX_BUF_DP<8>")
		)
		(pad "CD35" smd oval
			(at 0.249936 3.940048)
			(size 0.254 0.3302)
			(layers "F.Cu" "F.Mask" "F.Paste")
			(net "P5E_CPU1_P2_TX_C_DP<8>")
		)
		(pad "CE4" smd circle
			(at 0.00254 -2.817368)
			(size 0.381 0.381)
			(layers "F.Cu" "F.Mask" "F.Paste")
			(net "GND")
		)
		(pad "CE13" smd circle
			(at 0.00254 -0.79629)
			(size 0.3048 0.3048)
			(layers "F.Cu" "F.Mask" "F.Paste")
			(net "GND")
		)
		(pad "CE17" smd circle
			(at 0.00254 -0.296164)
			(size 0.3048 0.3048)
			(layers "F.Cu" "F.Mask" "F.Paste")
			(net "P1V8_CPU1_RT2_1A")
		)
		(pad "CE20" smd circle
			(at 0.00254 0.203708)
			(size 0.3048 0.3048)
			(layers "F.Cu" "F.Mask" "F.Paste")
			(net "P1V8_CPU1_RT2_1A")
		)
		(pad "CE22" smd circle
			(at 0.00254 0.703834)
			(size 0.3048 0.3048)
			(layers "F.Cu" "F.Mask" "F.Paste")
			(net "GND")
		)
		(pad "CE32" smd circle
			(at 0.00254 2.724912)
			(size 0.381 0.381)
			(layers "F.Cu" "F.Mask" "F.Paste")
			(net "GND")
		)
		(pad "CF2" smd circle
			(at -0.050038 -3.41884)
			(size 0.3048 0.3048)
			(layers "F.Cu" "F.Mask" "F.Paste")
			(net "GND")
		)
		(pad "CF34" smd circle
			(at -0.050038 3.420364)
			(size 0.3048 0.3048)
			(layers "F.Cu" "F.Mask" "F.Paste")
			(net "GND")
		)
		(pad "CG1" smd oval
			(at -0.350012 -3.938524)
			(size 0.254 0.3302)
			(layers "F.Cu" "F.Mask" "F.Paste")
			(net "GND")
		)
		(pad "CG35" smd oval
			(at -0.350012 3.940048)
			(size 0.254 0.3302)
			(layers "F.Cu" "F.Mask" "F.Paste")
			(net "GND")
		)
		(pad "CH7" smd circle
			(at -0.39751 -2.12471)
			(size 0.381 0.381)
			(layers "F.Cu" "F.Mask" "F.Paste")
			(net "P5E_CPU1_P2_TX_BUF_DP<7>")
		)
		(pad "CH26" smd circle
			(at -0.39751 1.339342)
			(size 0.381 0.381)
			(layers "F.Cu" "F.Mask" "F.Paste")
			(net "P5E_CPU1_P2_RX_DP<7>")
		)
		(pad "CJ2" smd circle
			(at -0.649986 -3.41884)
			(size 0.3048 0.3048)
			(layers "F.Cu" "F.Mask" "F.Paste")
			(net "P5E_CPU1_P2_RX_BUF_DN<7>")
		)
		(pad "CJ34" smd circle
			(at -0.649986 3.420364)
			(size 0.3048 0.3048)
			(layers "F.Cu" "F.Mask" "F.Paste")
			(net "P5E_CPU1_P2_TX_C_DN<7>")
		)
		(pad "CK10" smd circle
			(at -0.797306 -1.431798)
			(size 0.381 0.381)
			(layers "F.Cu" "F.Mask" "F.Paste")
			(net "P5E_CPU1_P2_TX_BUF_DN<7>")
		)
		(pad "CK29" smd circle
			(at -0.797306 2.032254)
			(size 0.381 0.381)
			(layers "F.Cu" "F.Mask" "F.Paste")
			(net "P5E_CPU1_P2_RX_DN<7>")
		)
		(pad "CL1" smd oval
			(at -0.94996 -3.938524)
			(size 0.254 0.3302)
			(layers "F.Cu" "F.Mask" "F.Paste")
			(net "P5E_CPU1_P2_RX_BUF_DP<7>")
		)
		(pad "CL35" smd oval
			(at -0.94996 3.940048)
			(size 0.254 0.3302)
			(layers "F.Cu" "F.Mask" "F.Paste")
			(net "P5E_CPU1_P2_TX_C_DP<7>")
		)
		(pad "CM4" smd circle
			(at -1.197356 -2.817368)
			(size 0.381 0.381)
			(layers "F.Cu" "F.Mask" "F.Paste")
			(net "GND")
		)
		(pad "CM13" smd circle
			(at -1.197356 -0.79629)
			(size 0.3048 0.3048)
			(layers "F.Cu" "F.Mask" "F.Paste")
			(net "GND")
		)
		(pad "CM17" smd circle
			(at -1.197356 -0.296164)
			(size 0.3048 0.3048)
			(layers "F.Cu" "F.Mask" "F.Paste")
			(net "P1V8_CPU1_RT2_1A")
		)
		(pad "CM20" smd circle
			(at -1.197356 0.203708)
			(size 0.3048 0.3048)
			(layers "F.Cu" "F.Mask" "F.Paste")
			(net "P1V8_CPU1_RT2_1A")
		)
		(pad "CM22" smd circle
			(at -1.197356 0.703834)
			(size 0.3048 0.3048)
			(layers "F.Cu" "F.Mask" "F.Paste")
			(net "GND")
		)
		(pad "CM32" smd circle
			(at -1.197356 2.724912)
			(size 0.381 0.381)
			(layers "F.Cu" "F.Mask" "F.Paste")
			(net "GND")
		)
		(pad "CN2" smd circle
			(at -1.249934 -3.41884)
			(size 0.3048 0.3048)
			(layers "F.Cu" "F.Mask" "F.Paste")
			(net "GND")
		)
		(pad "CN34" smd circle
			(at -1.249934 3.420364)
			(size 0.3048 0.3048)
			(layers "F.Cu" "F.Mask" "F.Paste")
			(net "GND")
		)
		(pad "CP1" smd oval
			(at -1.549908 -3.938524)
			(size 0.254 0.3302)
			(layers "F.Cu" "F.Mask" "F.Paste")
			(net "GND")
		)
		(pad "CP35" smd oval
			(at -1.549908 3.940048)
			(size 0.254 0.3302)
			(layers "F.Cu" "F.Mask" "F.Paste")
			(net "GND")
		)
		(pad "CR7" smd circle
			(at -1.597406 -2.12471)
			(size 0.381 0.381)
			(layers "F.Cu" "F.Mask" "F.Paste")
			(net "P5E_CPU1_P2_TX_BUF_DP<6>")
		)
		(pad "CR26" smd circle
			(at -1.597406 1.339342)
			(size 0.381 0.381)
			(layers "F.Cu" "F.Mask" "F.Paste")
			(net "P5E_CPU1_P2_RX_DP<6>")
		)
		(pad "CT2" smd circle
			(at -1.849882 -3.41884)
			(size 0.3048 0.3048)
			(layers "F.Cu" "F.Mask" "F.Paste")
			(net "P5E_CPU1_P2_RX_BUF_DN<6>")
		)
		(pad "CT34" smd circle
			(at -1.849882 3.420364)
			(size 0.3048 0.3048)
			(layers "F.Cu" "F.Mask" "F.Paste")
			(net "P5E_CPU1_P2_TX_C_DN<6>")
		)
		(pad "CU10" smd circle
			(at -1.997456 -1.431798)
			(size 0.381 0.381)
			(layers "F.Cu" "F.Mask" "F.Paste")
			(net "P5E_CPU1_P2_TX_BUF_DN<6>")
		)
		(pad "CU29" smd circle
			(at -1.997456 2.032254)
			(size 0.381 0.381)
			(layers "F.Cu" "F.Mask" "F.Paste")
			(net "P5E_CPU1_P2_RX_DN<6>")
		)
		(pad "CV1" smd oval
			(at -2.15011 -3.938524)
			(size 0.254 0.3302)
			(layers "F.Cu" "F.Mask" "F.Paste")
			(net "P5E_CPU1_P2_RX_BUF_DP<6>")
		)
		(pad "CV35" smd oval
			(at -2.15011 3.940048)
			(size 0.254 0.3302)
			(layers "F.Cu" "F.Mask" "F.Paste")
			(net "P5E_CPU1_P2_TX_C_DP<6>")
		)
		(pad "CW4" smd circle
			(at -2.397506 -2.817368)
			(size 0.381 0.381)
			(layers "F.Cu" "F.Mask" "F.Paste")
			(net "GND")
		)
		(pad "CW13" smd circle
			(at -2.397506 -0.79629)
			(size 0.3048 0.3048)
			(layers "F.Cu" "F.Mask" "F.Paste")
			(net "GND")
		)
		(pad "CW17" smd circle
			(at -2.397506 -0.296164)
			(size 0.3048 0.3048)
			(layers "F.Cu" "F.Mask" "F.Paste")
			(net "P0V9_CPU1_RT_2D")
		)
		(pad "CW20" smd circle
			(at -2.397506 0.203708)
			(size 0.3048 0.3048)
			(layers "F.Cu" "F.Mask" "F.Paste")
			(net "P0V9_CPU1_RT_2D")
		)
		(pad "CW22" smd circle
			(at -2.397506 0.703834)
			(size 0.3048 0.3048)
			(layers "F.Cu" "F.Mask" "F.Paste")
			(net "GND")
		)
		(pad "CW32" smd circle
			(at -2.397506 2.724912)
			(size 0.381 0.381)
			(layers "F.Cu" "F.Mask" "F.Paste")
			(net "GND")
		)
		(pad "CY2" smd circle
			(at -2.450084 -3.41884)
			(size 0.3048 0.3048)
			(layers "F.Cu" "F.Mask" "F.Paste")
			(net "GND")
		)
		(pad "CY34" smd circle
			(at -2.450084 3.420364)
			(size 0.3048 0.3048)
			(layers "F.Cu" "F.Mask" "F.Paste")
			(net "GND")
		)
		(pad "D1" smd oval
			(at 10.450068 -3.938524)
			(size 0.254 0.3302)
			(layers "F.Cu" "F.Mask" "F.Paste")
			(net "NCF_CPU1_P2_GND")
		)
		(pad "D35" smd oval
			(at 10.450068 3.940048)
			(size 0.254 0.3302)
			(layers "F.Cu" "F.Mask" "F.Paste")
			(net "NCF_CPU1_P2_GND")
		)
		(pad "DA1" smd oval
			(at -2.750058 -3.938524)
			(size 0.254 0.3302)
			(layers "F.Cu" "F.Mask" "F.Paste")
			(net "GND")
		)
		(pad "DA35" smd oval
			(at -2.750058 3.940048)
			(size 0.254 0.3302)
			(layers "F.Cu" "F.Mask" "F.Paste")
			(net "GND")
		)
		(pad "DB7" smd circle
			(at -2.797302 -2.12471)
			(size 0.381 0.381)
			(layers "F.Cu" "F.Mask" "F.Paste")
			(net "P5E_CPU1_P2_TX_BUF_DP<5>")
		)
		(pad "DB26" smd circle
			(at -2.797302 1.339342)
			(size 0.381 0.381)
			(layers "F.Cu" "F.Mask" "F.Paste")
			(net "P5E_CPU1_P2_RX_DP<5>")
		)
		(pad "DC2" smd circle
			(at -3.050032 -3.41884)
			(size 0.3048 0.3048)
			(layers "F.Cu" "F.Mask" "F.Paste")
			(net "P5E_CPU1_P2_RX_BUF_DN<5>")
		)
		(pad "DC34" smd circle
			(at -3.050032 3.420364)
			(size 0.3048 0.3048)
			(layers "F.Cu" "F.Mask" "F.Paste")
			(net "P5E_CPU1_P2_TX_C_DN<5>")
		)
		(pad "DD10" smd circle
			(at -3.197352 -1.431798)
			(size 0.381 0.381)
			(layers "F.Cu" "F.Mask" "F.Paste")
			(net "P5E_CPU1_P2_TX_BUF_DN<5>")
		)
		(pad "DD29" smd circle
			(at -3.197352 2.032254)
			(size 0.381 0.381)
			(layers "F.Cu" "F.Mask" "F.Paste")
			(net "P5E_CPU1_P2_RX_DN<5>")
		)
		(pad "DE1" smd oval
			(at -3.350006 -3.938524)
			(size 0.254 0.3302)
			(layers "F.Cu" "F.Mask" "F.Paste")
			(net "P5E_CPU1_P2_RX_BUF_DP<5>")
		)
		(pad "DE35" smd oval
			(at -3.350006 3.940048)
			(size 0.254 0.3302)
			(layers "F.Cu" "F.Mask" "F.Paste")
			(net "P5E_CPU1_P2_TX_C_DP<5>")
		)
		(pad "DF4" smd circle
			(at -3.597402 -2.817368)
			(size 0.381 0.381)
			(layers "F.Cu" "F.Mask" "F.Paste")
			(net "GND")
		)
		(pad "DF13" smd circle
			(at -3.597402 -0.79629)
			(size 0.3048 0.3048)
			(layers "F.Cu" "F.Mask" "F.Paste")
			(net "GND")
		)
		(pad "DF17" smd circle
			(at -3.597402 -0.296164)
			(size 0.3048 0.3048)
			(layers "F.Cu" "F.Mask" "F.Paste")
			(net "P0V9_CPU1_RT2_2A_2D")
		)
		(pad "DF20" smd circle
			(at -3.597402 0.203708)
			(size 0.3048 0.3048)
			(layers "F.Cu" "F.Mask" "F.Paste")
			(net "P0V9_CPU1_RT2_2A_2D")
		)
		(pad "DF22" smd circle
			(at -3.597402 0.703834)
			(size 0.3048 0.3048)
			(layers "F.Cu" "F.Mask" "F.Paste")
			(net "GND")
		)
		(pad "DF32" smd circle
			(at -3.597402 2.724912)
			(size 0.381 0.381)
			(layers "F.Cu" "F.Mask" "F.Paste")
			(net "GND")
		)
		(pad "DG2" smd circle
			(at -3.64998 -3.41884)
			(size 0.3048 0.3048)
			(layers "F.Cu" "F.Mask" "F.Paste")
			(net "GND")
		)
		(pad "DG34" smd circle
			(at -3.64998 3.420364)
			(size 0.3048 0.3048)
			(layers "F.Cu" "F.Mask" "F.Paste")
			(net "GND")
		)
		(pad "DH1" smd oval
			(at -3.949954 -3.938524)
			(size 0.254 0.3302)
			(layers "F.Cu" "F.Mask" "F.Paste")
			(net "GND")
		)
		(pad "DH35" smd oval
			(at -3.949954 3.940048)
			(size 0.254 0.3302)
			(layers "F.Cu" "F.Mask" "F.Paste")
			(net "GND")
		)
		(pad "DJ7" smd circle
			(at -3.997452 -2.12471)
			(size 0.381 0.381)
			(layers "F.Cu" "F.Mask" "F.Paste")
			(net "P5E_CPU1_P2_TX_BUF_DP<4>")
		)
		(pad "DJ26" smd circle
			(at -3.997452 1.339342)
			(size 0.381 0.381)
			(layers "F.Cu" "F.Mask" "F.Paste")
			(net "P5E_CPU1_P2_RX_DP<4>")
		)
		(pad "DK2" smd circle
			(at -4.249928 -3.41884)
			(size 0.3048 0.3048)
			(layers "F.Cu" "F.Mask" "F.Paste")
			(net "P5E_CPU1_P2_RX_BUF_DN<4>")
		)
		(pad "DK34" smd circle
			(at -4.249928 3.420364)
			(size 0.3048 0.3048)
			(layers "F.Cu" "F.Mask" "F.Paste")
			(net "P5E_CPU1_P2_TX_C_DN<4>")
		)
		(pad "DL10" smd circle
			(at -4.397502 -1.431798)
			(size 0.381 0.381)
			(layers "F.Cu" "F.Mask" "F.Paste")
			(net "P5E_CPU1_P2_TX_BUF_DN<4>")
		)
		(pad "DL29" smd circle
			(at -4.397502 2.032254)
			(size 0.381 0.381)
			(layers "F.Cu" "F.Mask" "F.Paste")
			(net "P5E_CPU1_P2_RX_DN<4>")
		)
		(pad "DM1" smd oval
			(at -4.549902 -3.938524)
			(size 0.254 0.3302)
			(layers "F.Cu" "F.Mask" "F.Paste")
			(net "P5E_CPU1_P2_RX_BUF_DP<4>")
		)
		(pad "DM35" smd oval
			(at -4.549902 3.940048)
			(size 0.254 0.3302)
			(layers "F.Cu" "F.Mask" "F.Paste")
			(net "P5E_CPU1_P2_TX_C_DP<4>")
		)
		(pad "DN4" smd circle
			(at -4.797298 -2.817368)
			(size 0.381 0.381)
			(layers "F.Cu" "F.Mask" "F.Paste")
			(net "GND")
		)
		(pad "DN13" smd circle
			(at -4.797298 -0.79629)
			(size 0.3048 0.3048)
			(layers "F.Cu" "F.Mask" "F.Paste")
			(net "GND")
		)
		(pad "DN17" smd circle
			(at -4.797298 -0.296164)
			(size 0.3048 0.3048)
			(layers "F.Cu" "F.Mask" "F.Paste")
			(net "P0V9_CPU1_RT2_2A")
		)
		(pad "DN20" smd circle
			(at -4.797298 0.203708)
			(size 0.3048 0.3048)
			(layers "F.Cu" "F.Mask" "F.Paste")
			(net "P0V9_CPU1_RT2_2A")
		)
		(pad "DN22" smd circle
			(at -4.797298 0.703834)
			(size 0.3048 0.3048)
			(layers "F.Cu" "F.Mask" "F.Paste")
			(net "GND")
		)
		(pad "DN32" smd circle
			(at -4.797298 2.724912)
			(size 0.381 0.381)
			(layers "F.Cu" "F.Mask" "F.Paste")
			(net "GND")
		)
		(pad "DP2" smd circle
			(at -4.849876 -3.41884)
			(size 0.3048 0.3048)
			(layers "F.Cu" "F.Mask" "F.Paste")
			(net "GND")
		)
		(pad "DP34" smd circle
			(at -4.849876 3.420364)
			(size 0.3048 0.3048)
			(layers "F.Cu" "F.Mask" "F.Paste")
			(net "GND")
		)
		(pad "DR1" smd oval
			(at -5.150104 -3.938524)
			(size 0.254 0.3302)
			(layers "F.Cu" "F.Mask" "F.Paste")
			(net "GND")
		)
		(pad "DR35" smd oval
			(at -5.150104 3.940048)
			(size 0.254 0.3302)
			(layers "F.Cu" "F.Mask" "F.Paste")
			(net "GND")
		)
		(pad "DT7" smd circle
			(at -5.197348 -2.12471)
			(size 0.381 0.381)
			(layers "F.Cu" "F.Mask" "F.Paste")
			(net "P5E_CPU1_P2_TX_BUF_DP<3>")
		)
		(pad "DT26" smd circle
			(at -5.197348 1.339342)
			(size 0.381 0.381)
			(layers "F.Cu" "F.Mask" "F.Paste")
			(net "P5E_CPU1_P2_RX_DP<3>")
		)
		(pad "DU2" smd circle
			(at -5.450078 -3.41884)
			(size 0.3048 0.3048)
			(layers "F.Cu" "F.Mask" "F.Paste")
			(net "P5E_CPU1_P2_RX_BUF_DN<3>")
		)
		(pad "DU34" smd circle
			(at -5.450078 3.420364)
			(size 0.3048 0.3048)
			(layers "F.Cu" "F.Mask" "F.Paste")
			(net "P5E_CPU1_P2_TX_C_DN<3>")
		)
		(pad "DV10" smd circle
			(at -5.597398 -1.431798)
			(size 0.381 0.381)
			(layers "F.Cu" "F.Mask" "F.Paste")
			(net "P5E_CPU1_P2_TX_BUF_DN<3>")
		)
		(pad "DV29" smd circle
			(at -5.597398 2.032254)
			(size 0.381 0.381)
			(layers "F.Cu" "F.Mask" "F.Paste")
			(net "P5E_CPU1_P2_RX_DN<3>")
		)
		(pad "DW1" smd oval
			(at -5.750052 -3.938524)
			(size 0.254 0.3302)
			(layers "F.Cu" "F.Mask" "F.Paste")
			(net "P5E_CPU1_P2_RX_BUF_DP<3>")
		)
		(pad "DW35" smd oval
			(at -5.750052 3.940048)
			(size 0.254 0.3302)
			(layers "F.Cu" "F.Mask" "F.Paste")
			(net "P5E_CPU1_P2_TX_C_DP<3>")
		)
		(pad "DY4" smd circle
			(at -5.997448 -2.817368)
			(size 0.381 0.381)
			(layers "F.Cu" "F.Mask" "F.Paste")
			(net "GND")
		)
		(pad "DY13" smd circle
			(at -5.997448 -0.79629)
			(size 0.3048 0.3048)
			(layers "F.Cu" "F.Mask" "F.Paste")
			(net "GND")
		)
		(pad "DY17" smd circle
			(at -5.997448 -0.296164)
			(size 0.3048 0.3048)
			(layers "F.Cu" "F.Mask" "F.Paste")
			(net "P0V9_CPU1_RT2_2A")
		)
		(pad "DY20" smd circle
			(at -5.997448 0.203708)
			(size 0.3048 0.3048)
			(layers "F.Cu" "F.Mask" "F.Paste")
			(net "P0V9_CPU1_RT2_2A")
		)
		(pad "DY22" smd circle
			(at -5.997448 0.703834)
			(size 0.3048 0.3048)
			(layers "F.Cu" "F.Mask" "F.Paste")
			(net "GND")
		)
		(pad "DY32" smd circle
			(at -5.997448 2.724912)
			(size 0.381 0.381)
			(layers "F.Cu" "F.Mask" "F.Paste")
			(net "GND")
		)
		(pad "E8" smd circle
			(at 10.366502 -1.988312)
			(size 0.3048 0.3048)
			(layers "F.Cu" "F.Mask" "F.Paste")
			(net "JTAG_TRST_RT_CPU1_P2_N")
		)
		(pad "E11" smd circle
			(at 10.366502 -1.388364)
			(size 0.3048 0.3048)
			(layers "F.Cu" "F.Mask" "F.Paste")
			(net "RXDET_BYP_RT_CPU1_P2")
		)
		(pad "E14" smd circle
			(at 10.366502 -0.788416)
			(size 0.3048 0.3048)
			(layers "F.Cu" "F.Mask" "F.Paste")
			(net "GND")
		)
		(pad "E18" smd circle
			(at 10.366502 -0.188468)
			(size 0.3048 0.3048)
			(layers "F.Cu" "F.Mask" "F.Paste")
			(net "Net_2224")
		)
		(pad "E27" smd circle
			(at 10.366502 1.61163)
			(size 0.3048 0.3048)
			(layers "F.Cu" "F.Mask" "F.Paste")
			(net "GND")
		)
		(pad "E30" smd circle
			(at 10.366502 2.211578)
			(size 0.3048 0.3048)
			(layers "F.Cu" "F.Mask" "F.Paste")
			(net "GND")
		)
		(pad "E33" smd circle
			(at 10.366502 2.811526)
			(size 0.3048 0.3048)
			(layers "F.Cu" "F.Mask" "F.Paste")
			(net "GND")
		)
		(pad "EA2" smd circle
			(at -6.050026 -3.41884)
			(size 0.3048 0.3048)
			(layers "F.Cu" "F.Mask" "F.Paste")
			(net "GND")
		)
		(pad "EA34" smd circle
			(at -6.050026 3.420364)
			(size 0.3048 0.3048)
			(layers "F.Cu" "F.Mask" "F.Paste")
			(net "GND")
		)
		(pad "EB1" smd oval
			(at -6.35 -3.938524)
			(size 0.254 0.3302)
			(layers "F.Cu" "F.Mask" "F.Paste")
			(net "GND")
		)
		(pad "EB35" smd oval
			(at -6.35 3.940048)
			(size 0.254 0.3302)
			(layers "F.Cu" "F.Mask" "F.Paste")
			(net "GND")
		)
		(pad "EC7" smd circle
			(at -6.397498 -2.12471)
			(size 0.381 0.381)
			(layers "F.Cu" "F.Mask" "F.Paste")
			(net "P5E_CPU1_P2_TX_BUF_DP<2>")
		)
		(pad "EC26" smd circle
			(at -6.397498 1.339342)
			(size 0.381 0.381)
			(layers "F.Cu" "F.Mask" "F.Paste")
			(net "P5E_CPU1_P2_RX_DP<2>")
		)
		(pad "ED2" smd circle
			(at -6.649974 -3.41884)
			(size 0.3048 0.3048)
			(layers "F.Cu" "F.Mask" "F.Paste")
			(net "P5E_CPU1_P2_RX_BUF_DN<2>")
		)
		(pad "ED34" smd circle
			(at -6.649974 3.420364)
			(size 0.3048 0.3048)
			(layers "F.Cu" "F.Mask" "F.Paste")
			(net "P5E_CPU1_P2_TX_C_DN<2>")
		)
		(pad "EE10" smd circle
			(at -6.797294 -1.431798)
			(size 0.381 0.381)
			(layers "F.Cu" "F.Mask" "F.Paste")
			(net "P5E_CPU1_P2_TX_BUF_DN<2>")
		)
		(pad "EE29" smd circle
			(at -6.797294 2.032254)
			(size 0.381 0.381)
			(layers "F.Cu" "F.Mask" "F.Paste")
			(net "P5E_CPU1_P2_RX_DN<2>")
		)
		(pad "EF1" smd oval
			(at -6.949948 -3.938524)
			(size 0.254 0.3302)
			(layers "F.Cu" "F.Mask" "F.Paste")
			(net "P5E_CPU1_P2_RX_BUF_DP<2>")
		)
		(pad "EF35" smd oval
			(at -6.949948 3.940048)
			(size 0.254 0.3302)
			(layers "F.Cu" "F.Mask" "F.Paste")
			(net "P5E_CPU1_P2_TX_C_DP<2>")
		)
		(pad "EG4" smd circle
			(at -7.197344 -2.817368)
			(size 0.381 0.381)
			(layers "F.Cu" "F.Mask" "F.Paste")
			(net "GND")
		)
		(pad "EG13" smd circle
			(at -7.197344 -0.79629)
			(size 0.3048 0.3048)
			(layers "F.Cu" "F.Mask" "F.Paste")
			(net "GND")
		)
		(pad "EG17" smd circle
			(at -7.197344 -0.296164)
			(size 0.3048 0.3048)
			(layers "F.Cu" "F.Mask" "F.Paste")
			(net "P0V9_CPU1_RT2_2A")
		)
		(pad "EG20" smd circle
			(at -7.197344 0.203708)
			(size 0.3048 0.3048)
			(layers "F.Cu" "F.Mask" "F.Paste")
			(net "P0V9_CPU1_RT2_2A")
		)
		(pad "EG22" smd circle
			(at -7.197344 0.703834)
			(size 0.3048 0.3048)
			(layers "F.Cu" "F.Mask" "F.Paste")
			(net "GND")
		)
		(pad "EG32" smd circle
			(at -7.197344 2.724912)
			(size 0.381 0.381)
			(layers "F.Cu" "F.Mask" "F.Paste")
			(net "GND")
		)
		(pad "EH2" smd circle
			(at -7.249922 -3.41884)
			(size 0.3048 0.3048)
			(layers "F.Cu" "F.Mask" "F.Paste")
			(net "GND")
		)
		(pad "EH34" smd circle
			(at -7.249922 3.420364)
			(size 0.3048 0.3048)
			(layers "F.Cu" "F.Mask" "F.Paste")
			(net "GND")
		)
		(pad "EJ1" smd oval
			(at -7.549896 -3.938524)
			(size 0.254 0.3302)
			(layers "F.Cu" "F.Mask" "F.Paste")
			(net "GND")
		)
		(pad "EJ35" smd oval
			(at -7.549896 3.940048)
			(size 0.254 0.3302)
			(layers "F.Cu" "F.Mask" "F.Paste")
			(net "GND")
		)
		(pad "EK7" smd circle
			(at -7.597394 -2.12471)
			(size 0.381 0.381)
			(layers "F.Cu" "F.Mask" "F.Paste")
			(net "P5E_CPU1_P2_TX_BUF_DP<1>")
		)
		(pad "EK26" smd circle
			(at -7.597394 1.339342)
			(size 0.381 0.381)
			(layers "F.Cu" "F.Mask" "F.Paste")
			(net "P5E_CPU1_P2_RX_DP<1>")
		)
		(pad "EL2" smd circle
			(at -7.850124 -3.41884)
			(size 0.3048 0.3048)
			(layers "F.Cu" "F.Mask" "F.Paste")
			(net "P5E_CPU1_P2_RX_BUF_DN<1>")
		)
		(pad "EL34" smd circle
			(at -7.850124 3.420364)
			(size 0.3048 0.3048)
			(layers "F.Cu" "F.Mask" "F.Paste")
			(net "P5E_CPU1_P2_TX_C_DP<1>")
		)
		(pad "EM10" smd circle
			(at -7.997444 -1.431798)
			(size 0.381 0.381)
			(layers "F.Cu" "F.Mask" "F.Paste")
			(net "P5E_CPU1_P2_TX_BUF_DN<1>")
		)
		(pad "EM29" smd circle
			(at -7.997444 2.032254)
			(size 0.381 0.381)
			(layers "F.Cu" "F.Mask" "F.Paste")
			(net "P5E_CPU1_P2_RX_DN<1>")
		)
		(pad "EN1" smd oval
			(at -8.150098 -3.938524)
			(size 0.254 0.3302)
			(layers "F.Cu" "F.Mask" "F.Paste")
			(net "P5E_CPU1_P2_RX_BUF_DP<1>")
		)
		(pad "EN35" smd oval
			(at -8.150098 3.940048)
			(size 0.254 0.3302)
			(layers "F.Cu" "F.Mask" "F.Paste")
			(net "P5E_CPU1_P2_TX_C_DN<1>")
		)
		(pad "EP4" smd circle
			(at -8.397494 -2.817368)
			(size 0.381 0.381)
			(layers "F.Cu" "F.Mask" "F.Paste")
			(net "GND")
		)
		(pad "EP13" smd circle
			(at -8.397494 -0.79629)
			(size 0.3048 0.3048)
			(layers "F.Cu" "F.Mask" "F.Paste")
			(net "GND")
		)
		(pad "EP17" smd circle
			(at -8.397494 -0.296164)
			(size 0.3048 0.3048)
			(layers "F.Cu" "F.Mask" "F.Paste")
			(net "P0V9_CPU1_RT2_2A")
		)
		(pad "EP20" smd circle
			(at -8.397494 0.203708)
			(size 0.3048 0.3048)
			(layers "F.Cu" "F.Mask" "F.Paste")
			(net "P0V9_CPU1_RT2_2A")
		)
		(pad "EP22" smd circle
			(at -8.397494 0.703834)
			(size 0.3048 0.3048)
			(layers "F.Cu" "F.Mask" "F.Paste")
			(net "GND")
		)
		(pad "EP32" smd circle
			(at -8.397494 2.724912)
			(size 0.381 0.381)
			(layers "F.Cu" "F.Mask" "F.Paste")
			(net "GND")
		)
		(pad "ER2" smd circle
			(at -8.450072 -3.41884)
			(size 0.3048 0.3048)
			(layers "F.Cu" "F.Mask" "F.Paste")
			(net "GND")
		)
		(pad "ER34" smd circle
			(at -8.450072 3.420364)
			(size 0.3048 0.3048)
			(layers "F.Cu" "F.Mask" "F.Paste")
			(net "GND")
		)
		(pad "ET1" smd oval
			(at -8.750046 -3.938524)
			(size 0.254 0.3302)
			(layers "F.Cu" "F.Mask" "F.Paste")
			(net "GND")
		)
		(pad "ET35" smd oval
			(at -8.750046 3.940048)
			(size 0.254 0.3302)
			(layers "F.Cu" "F.Mask" "F.Paste")
			(net "GND")
		)
		(pad "EU7" smd circle
			(at -8.79729 -2.12471)
			(size 0.381 0.381)
			(layers "F.Cu" "F.Mask" "F.Paste")
			(net "P5E_CPU1_P2_TX_BUF_DP<0>")
		)
		(pad "EU26" smd circle
			(at -8.79729 1.339342)
			(size 0.381 0.381)
			(layers "F.Cu" "F.Mask" "F.Paste")
			(net "P5E_CPU1_P2_RX_DP<0>")
		)
		(pad "EV2" smd circle
			(at -9.05002 -3.41884)
			(size 0.3048 0.3048)
			(layers "F.Cu" "F.Mask" "F.Paste")
			(net "P5E_CPU1_P2_RX_BUF_DN<0>")
		)
		(pad "EV34" smd circle
			(at -9.05002 3.420364)
			(size 0.3048 0.3048)
			(layers "F.Cu" "F.Mask" "F.Paste")
			(net "P5E_CPU1_P2_TX_C_DN<0>")
		)
		(pad "EW10" smd circle
			(at -9.19734 -1.431798)
			(size 0.381 0.381)
			(layers "F.Cu" "F.Mask" "F.Paste")
			(net "P5E_CPU1_P2_TX_BUF_DN<0>")
		)
		(pad "EW29" smd circle
			(at -9.19734 2.032254)
			(size 0.381 0.381)
			(layers "F.Cu" "F.Mask" "F.Paste")
			(net "P5E_CPU1_P2_RX_DN<0>")
		)
		(pad "EY1" smd oval
			(at -9.349994 -3.938524)
			(size 0.254 0.3302)
			(layers "F.Cu" "F.Mask" "F.Paste")
			(net "P5E_CPU1_P2_RX_BUF_DP<0>")
		)
		(pad "EY35" smd oval
			(at -9.349994 3.940048)
			(size 0.254 0.3302)
			(layers "F.Cu" "F.Mask" "F.Paste")
			(net "P5E_CPU1_P2_TX_C_DP<0>")
		)
		(pad "F2" smd circle
			(at 10.150094 -3.41884)
			(size 0.3048 0.3048)
			(layers "F.Cu" "F.Mask" "F.Paste")
			(net "RST_RT_CPU1_P2_PERST_N")
		)
		(pad "F34" smd circle
			(at 10.150094 3.420364)
			(size 0.3048 0.3048)
			(layers "F.Cu" "F.Mask" "F.Paste")
			(net "RT_CPU1_P2_ADDR1")
		)
		(pad "FA15" smd circle
			(at -9.59739 -0.738886)
			(size 0.381 0.381)
			(layers "F.Cu" "F.Mask" "F.Paste")
			(net "GND")
		)
		(pad "FA32" smd circle
			(at -9.59739 2.724912)
			(size 0.381 0.381)
			(layers "F.Cu" "F.Mask" "F.Paste")
			(net "GND")
		)
		(pad "FB2" smd circle
			(at -9.649968 -3.41884)
			(size 0.3048 0.3048)
			(layers "F.Cu" "F.Mask" "F.Paste")
			(net "GND")
		)
		(pad "FB34" smd circle
			(at -9.649968 3.420364)
			(size 0.3048 0.3048)
			(layers "F.Cu" "F.Mask" "F.Paste")
			(net "GND")
		)
		(pad "FC3" smd circle
			(at -9.846818 -2.888488)
			(size 0.3048 0.3048)
			(layers "F.Cu" "F.Mask" "F.Paste")
			(net "GND")
		)
		(pad "FC6" smd circle
			(at -9.846818 -2.288286)
			(size 0.3048 0.3048)
			(layers "F.Cu" "F.Mask" "F.Paste")
			(net "GND")
		)
		(pad "FC9" smd circle
			(at -9.846818 -1.688338)
			(size 0.3048 0.3048)
			(layers "F.Cu" "F.Mask" "F.Paste")
			(net "GND")
		)
		(pad "FC19" smd circle
			(at -9.846818 0.111506)
			(size 0.3048 0.3048)
			(layers "F.Cu" "F.Mask" "F.Paste")
			(net "GND")
		)
		(pad "FC23" smd circle
			(at -9.846818 0.711708)
			(size 0.3048 0.3048)
			(layers "F.Cu" "F.Mask" "F.Paste")
			(net "GND")
		)
		(pad "FC25" smd circle
			(at -9.846818 1.311656)
			(size 0.3048 0.3048)
			(layers "F.Cu" "F.Mask" "F.Paste")
			(net "GND")
		)
		(pad "FC28" smd circle
			(at -9.846818 1.911604)
			(size 0.3048 0.3048)
			(layers "F.Cu" "F.Mask" "F.Paste")
			(net "GND")
		)
		(pad "FD1" smd oval
			(at -9.949942 -3.938524)
			(size 0.254 0.3302)
			(layers "F.Cu" "F.Mask" "F.Paste")
			(net "GND")
		)
		(pad "FD35" smd oval
			(at -9.949942 3.940048)
			(size 0.254 0.3302)
			(layers "F.Cu" "F.Mask" "F.Paste")
			(net "GND")
		)
		(pad "FE2" smd circle
			(at -10.249916 -3.41884)
			(size 0.3048 0.3048)
			(layers "F.Cu" "F.Mask" "F.Paste")
			(net "NCF_CPU1_P2_GND")
		)
		(pad "FE34" smd circle
			(at -10.249916 3.420364)
			(size 0.3048 0.3048)
			(layers "F.Cu" "F.Mask" "F.Paste")
			(net "NCF_CPU1_P2_GND")
		)
		(pad "FF5" smd circle
			(at -10.366248 -2.588514)
			(size 0.3048 0.3048)
			(layers "F.Cu" "F.Mask" "F.Paste")
			(net "SMB_RT_CPU1_P2_ROM_MUX_1D_R_SCL")
		)
		(pad "FF8" smd circle
			(at -10.366248 -1.988312)
			(size 0.3048 0.3048)
			(layers "F.Cu" "F.Mask" "F.Paste")
			(net "JTAG_TEST_MODE_RT_CPU1_P2")
		)
		(pad "FF11" smd circle
			(at -10.366248 -1.388364)
			(size 0.3048 0.3048)
			(layers "F.Cu" "F.Mask" "F.Paste")
			(net "RST_RT_CPU1_P2_RESET_N")
		)
		(pad "FF14" smd circle
			(at -10.366248 -0.788416)
			(size 0.3048 0.3048)
			(layers "F.Cu" "F.Mask" "F.Paste")
			(net "GND")
		)
		(pad "FF18" smd circle
			(at -10.366248 -0.188468)
			(size 0.3048 0.3048)
			(layers "F.Cu" "F.Mask" "F.Paste")
			(net "CLK_100M_RETIMER_CPU1_P2_DN")
		)
		(pad "FF21" smd circle
			(at -10.366248 0.41148)
			(size 0.3048 0.3048)
			(layers "F.Cu" "F.Mask" "F.Paste")
			(net "GND")
		)
		(pad "FF24" smd circle
			(at -10.366248 1.011682)
			(size 0.3048 0.3048)
			(layers "F.Cu" "F.Mask" "F.Paste")
			(net "TEST0_RT_CPU1_P2")
		)
		(pad "FF27" smd circle
			(at -10.366248 1.61163)
			(size 0.3048 0.3048)
			(layers "F.Cu" "F.Mask" "F.Paste")
			(net "TEST1_RT_CPU1_P2")
		)
		(pad "FF30" smd circle
			(at -10.366248 2.211578)
			(size 0.3048 0.3048)
			(layers "F.Cu" "F.Mask" "F.Paste")
			(net "TEST2_RT_CPU1_P2")
		)
		(pad "FF33" smd circle
			(at -10.366248 2.811526)
			(size 0.3048 0.3048)
			(layers "F.Cu" "F.Mask" "F.Paste")
			(net "RT_CPU1_P2_SCAN_MODE")
		)
		(pad "FG1" smd oval
			(at -10.54989 -3.938524)
			(size 0.254 0.3302)
			(layers "F.Cu" "F.Mask" "F.Paste")
			(net "NCF_CPU1_P2_GND")
		)
		(pad "FG35" smd oval
			(at -10.54989 3.940048)
			(size 0.254 0.3302)
			(layers "F.Cu" "F.Mask" "F.Paste")
			(net "NCF_CPU1_P2_GND")
		)
		(pad "FH2" smd circle
			(at -10.850118 -3.41884)
			(size 0.3048 0.3048)
			(layers "F.Cu" "F.Mask" "F.Paste")
			(net "NCF_CPU1_P2_GND")
		)
		(pad "FH34" smd circle
			(at -10.850118 3.420364)
			(size 0.3048 0.3048)
			(layers "F.Cu" "F.Mask" "F.Paste")
			(net "NCF_CPU1_P2_GND")
		)
		(pad "FJ3" smd oval
			(at -10.885932 -2.888488 90)
			(size 0.254 0.3302)
			(layers "F.Cu" "F.Mask" "F.Paste")
			(net "SMB_RT_CPU1_P2_ROM_MUX_1D_R_SDA")
		)
		(pad "FJ6" smd oval
			(at -10.885932 -2.288286 90)
			(size 0.254 0.3302)
			(layers "F.Cu" "F.Mask" "F.Paste")
			(net "Net_2222")
		)
		(pad "FJ9" smd oval
			(at -10.885932 -1.688338 90)
			(size 0.254 0.3302)
			(layers "F.Cu" "F.Mask" "F.Paste")
			(net "MODE_RT_CPU1_P2")
		)
		(pad "FJ12" smd oval
			(at -10.885932 -1.08839 90)
			(size 0.254 0.3302)
			(layers "F.Cu" "F.Mask" "F.Paste")
			(net "GND")
		)
		(pad "FJ16" smd oval
			(at -10.885932 -0.488442 90)
			(size 0.254 0.3302)
			(layers "F.Cu" "F.Mask" "F.Paste")
			(net "CLK_100M_RETIMER_CPU1_P2_DP")
		)
		(pad "FJ19" smd oval
			(at -10.885932 0.111506 90)
			(size 0.254 0.3302)
			(layers "F.Cu" "F.Mask" "F.Paste")
			(net "GND")
		)
		(pad "FJ23" smd oval
			(at -10.885932 0.711708 90)
			(size 0.254 0.3302)
			(layers "F.Cu" "F.Mask" "F.Paste")
			(net "Net_2223")
		)
		(pad "FJ25" smd oval
			(at -10.885932 1.311656 90)
			(size 0.254 0.3302)
			(layers "F.Cu" "F.Mask" "F.Paste")
			(net "GPIO2_RT_CPU1_P2")
		)
		(pad "FJ28" smd oval
			(at -10.885932 1.911604 90)
			(size 0.254 0.3302)
			(layers "F.Cu" "F.Mask" "F.Paste")
			(net "GPIO3_RT_CPU1_P2")
		)
		(pad "FJ31" smd oval
			(at -10.885932 2.511552 90)
			(size 0.254 0.3302)
			(layers "F.Cu" "F.Mask" "F.Paste")
			(net "Net_56")
		)
		(pad "G1" smd oval
			(at 9.85012 -3.938524)
			(size 0.254 0.3302)
			(layers "F.Cu" "F.Mask" "F.Paste")
			(net "RT_CPU1_P2_VQPS")
		)
		(pad "G35" smd oval
			(at 9.85012 3.940048)
			(size 0.254 0.3302)
			(layers "F.Cu" "F.Mask" "F.Paste")
			(net "CLKREQ_RT_CPU1_P2_N")
		)
		(pad "H12" smd circle
			(at 9.846818 -1.08839)
			(size 0.3048 0.3048)
			(layers "F.Cu" "F.Mask" "F.Paste")
			(net "GND")
		)
		(pad "H16" smd circle
			(at 9.846818 -0.488442)
			(size 0.3048 0.3048)
			(layers "F.Cu" "F.Mask" "F.Paste")
			(net "GND")
		)
		(pad "H19" smd circle
			(at 9.846818 0.111506)
			(size 0.3048 0.3048)
			(layers "F.Cu" "F.Mask" "F.Paste")
			(net "GND")
		)
		(pad "H31" smd circle
			(at 9.846818 2.511552)
			(size 0.3048 0.3048)
			(layers "F.Cu" "F.Mask" "F.Paste")
			(net "GND")
		)
		(pad "J4" smd circle
			(at 9.602724 -2.817368)
			(size 0.381 0.381)
			(layers "F.Cu" "F.Mask" "F.Paste")
			(net "GND")
		)
		(pad "J22" smd circle
			(at 9.602724 0.703834)
			(size 0.3048 0.3048)
			(layers "F.Cu" "F.Mask" "F.Paste")
			(net "GND")
		)
		(pad "K2" smd circle
			(at 9.549892 -3.41884)
			(size 0.3048 0.3048)
			(layers "F.Cu" "F.Mask" "F.Paste")
			(net "GND")
		)
		(pad "K34" smd circle
			(at 9.549892 3.420364)
			(size 0.3048 0.3048)
			(layers "F.Cu" "F.Mask" "F.Paste")
			(net "GND")
		)
		(pad "L1" smd oval
			(at 9.249918 -3.938524)
			(size 0.254 0.3302)
			(layers "F.Cu" "F.Mask" "F.Paste")
			(net "GND")
		)
		(pad "L35" smd oval
			(at 9.249918 3.940048)
			(size 0.254 0.3302)
			(layers "F.Cu" "F.Mask" "F.Paste")
			(net "GND")
		)
		(pad "M7" smd circle
			(at 9.202674 -2.12471)
			(size 0.381 0.381)
			(layers "F.Cu" "F.Mask" "F.Paste")
			(net "P5E_CPU1_P2_TX_BUF_DP<15>")
		)
		(pad "M26" smd circle
			(at 9.202674 1.339342)
			(size 0.381 0.381)
			(layers "F.Cu" "F.Mask" "F.Paste")
			(net "P5E_CPU1_P2_RX_DP<15>")
		)
		(pad "N2" smd circle
			(at 8.949944 -3.41884)
			(size 0.3048 0.3048)
			(layers "F.Cu" "F.Mask" "F.Paste")
			(net "P5E_CPU1_P2_RX_BUF_DN<15>")
		)
		(pad "N34" smd circle
			(at 8.949944 3.420364)
			(size 0.3048 0.3048)
			(layers "F.Cu" "F.Mask" "F.Paste")
			(net "P5E_CPU1_P2_TX_C_DN<15>")
		)
		(pad "P10" smd circle
			(at 8.802624 -1.431798)
			(size 0.381 0.381)
			(layers "F.Cu" "F.Mask" "F.Paste")
			(net "P5E_CPU1_P2_TX_BUF_DN<15>")
		)
		(pad "P29" smd circle
			(at 8.802624 2.032254)
			(size 0.381 0.381)
			(layers "F.Cu" "F.Mask" "F.Paste")
			(net "P5E_CPU1_P2_RX_DN<15>")
		)
		(pad "R1" smd oval
			(at 8.64997 -3.938524)
			(size 0.254 0.3302)
			(layers "F.Cu" "F.Mask" "F.Paste")
			(net "P5E_CPU1_P2_RX_BUF_DP<15>")
		)
		(pad "R35" smd oval
			(at 8.64997 3.940048)
			(size 0.254 0.3302)
			(layers "F.Cu" "F.Mask" "F.Paste")
			(net "P5E_CPU1_P2_TX_C_DP<15>")
		)
		(pad "T4" smd circle
			(at 8.402574 -2.817368)
			(size 0.381 0.381)
			(layers "F.Cu" "F.Mask" "F.Paste")
			(net "GND")
		)
		(pad "T13" smd circle
			(at 8.402574 -0.79629)
			(size 0.3048 0.3048)
			(layers "F.Cu" "F.Mask" "F.Paste")
			(net "GND")
		)
		(pad "T17" smd circle
			(at 8.402574 -0.296164)
			(size 0.3048 0.3048)
			(layers "F.Cu" "F.Mask" "F.Paste")
			(net "P0V9_CPU1_RT2_2A")
		)
		(pad "T20" smd circle
			(at 8.402574 0.203708)
			(size 0.3048 0.3048)
			(layers "F.Cu" "F.Mask" "F.Paste")
			(net "P0V9_CPU1_RT2_2A")
		)
		(pad "T22" smd circle
			(at 8.402574 0.703834)
			(size 0.3048 0.3048)
			(layers "F.Cu" "F.Mask" "F.Paste")
			(net "GND")
		)
		(pad "T32" smd circle
			(at 8.402574 2.724912)
			(size 0.381 0.381)
			(layers "F.Cu" "F.Mask" "F.Paste")
			(net "GND")
		)
		(pad "U2" smd circle
			(at 8.349996 -3.41884)
			(size 0.3048 0.3048)
			(layers "F.Cu" "F.Mask" "F.Paste")
			(net "GND")
		)
		(pad "U34" smd circle
			(at 8.349996 3.420364)
			(size 0.3048 0.3048)
			(layers "F.Cu" "F.Mask" "F.Paste")
			(net "GND")
		)
		(pad "V1" smd oval
			(at 8.050022 -3.938524)
			(size 0.254 0.3302)
			(layers "F.Cu" "F.Mask" "F.Paste")
			(net "GND")
		)
		(pad "V35" smd oval
			(at 8.050022 3.940048)
			(size 0.254 0.3302)
			(layers "F.Cu" "F.Mask" "F.Paste")
			(net "GND")
		)
		(pad "W7" smd circle
			(at 8.002524 -2.12471)
			(size 0.381 0.381)
			(layers "F.Cu" "F.Mask" "F.Paste")
			(net "P5E_CPU1_P2_TX_BUF_DP<14>")
		)
		(pad "W26" smd circle
			(at 8.002524 1.339342)
			(size 0.381 0.381)
			(layers "F.Cu" "F.Mask" "F.Paste")
			(net "P5E_CPU1_P2_RX_DP<14>")
		)
		(pad "Y2" smd circle
			(at 7.750048 -3.41884)
			(size 0.3048 0.3048)
			(layers "F.Cu" "F.Mask" "F.Paste")
			(net "P5E_CPU1_P2_RX_BUF_DN<14>")
		)
		(pad "Y34" smd circle
			(at 7.750048 3.420364)
			(size 0.3048 0.3048)
			(layers "F.Cu" "F.Mask" "F.Paste")
			(net "P5E_CPU1_P2_TX_C_DN<14>")
		)
	)
	(footprint ""
		(layer "F.Cu")
		(at 177.469546 -342.23198 90)
		(property "Reference" "PR395"
			(at 0 0 90)
			(layer "F.SilkS")
			(hide yes)
			(effects
				(font
					(size 1.27 1.27)
				)
			)
		)
		(property "Value" ""
			(at 0 0 90)
			(layer "F.Fab")
			(effects
				(font
					(size 1.27 1.27)
				)
			)
		)
		(duplicate_pad_numbers_are_jumpers no)
		(fp_line
			(start 0.7874 -0.4064)
			(end 0.7874 0.4064)
			(stroke
				(width 0.1524)
				(type default)
			)
			(layer "F.SilkS")
		)
		(fp_line
			(start -0.7874 -0.4064)
			(end 0.7874 -0.4064)
			(stroke
				(width 0.1524)
				(type default)
			)
			(layer "F.SilkS")
		)
		(fp_line
			(start 0.7874 0.4064)
			(end -0.7874 0.4064)
			(stroke
				(width 0.1524)
				(type default)
			)
			(layer "F.SilkS")
		)
		(fp_line
			(start -0.7874 0.4064)
			(end -0.7874 -0.4064)
			(stroke
				(width 0.1524)
				(type default)
			)
			(layer "F.SilkS")
		)
		(fp_line
			(start -0.12065 -0.305054)
			(end -0.12065 -0.2794)
			(stroke
				(width 0.1)
				(type default)
			)
			(layer "F.Fab")
		)
		(fp_line
			(start -0.67945 -0.305054)
			(end -0.12065 -0.305054)
			(stroke
				(width 0.1)
				(type default)
			)
			(layer "F.Fab")
		)
		(fp_line
			(start 0.67945 -0.3048)
			(end 0.67945 0.3048)
			(stroke
				(width 0.1)
				(type default)
			)
			(layer "F.Fab")
		)
		(fp_line
			(start 0.12065 -0.3048)
			(end 0.67945 -0.3048)
			(stroke
				(width 0.1)
				(type default)
			)
			(layer "F.Fab")
		)
		(fp_line
			(start 0.12065 -0.2794)
			(end 0.12065 -0.3048)
			(stroke
				(width 0.1)
				(type default)
			)
			(layer "F.Fab")
		)
		(fp_line
			(start -0.12065 -0.2794)
			(end 0.12065 -0.2794)
			(stroke
				(width 0.1)
				(type default)
			)
			(layer "F.Fab")
		)
		(fp_line
			(start 0.120396 0.2794)
			(end -0.12065 0.2794)
			(stroke
				(width 0.1)
				(type default)
			)
			(layer "F.Fab")
		)
		(fp_line
			(start -0.12065 0.2794)
			(end -0.12065 0.3048)
			(stroke
				(width 0.1)
				(type default)
			)
			(layer "F.Fab")
		)
		(fp_line
			(start 0.67945 0.3048)
			(end 0.120396 0.3048)
			(stroke
				(width 0.1)
				(type default)
			)
			(layer "F.Fab")
		)
		(fp_line
			(start 0.120396 0.3048)
			(end 0.120396 0.2794)
			(stroke
				(width 0.1)
				(type default)
			)
			(layer "F.Fab")
		)
		(fp_line
			(start -0.12065 0.3048)
			(end -0.67945 0.3048)
			(stroke
				(width 0.1)
				(type default)
			)
			(layer "F.Fab")
		)
		(fp_line
			(start -0.67945 0.3048)
			(end -0.67945 -0.305054)
			(stroke
				(width 0.1)
				(type default)
			)
			(layer "F.Fab")
		)
		(pad "1" smd circle
			(at -0.40005 0 90)
			(size 0 0)
			(layers "F.Cu" "F.Mask" "F.Paste")
			(net "PVDD11_S3_P1")
		)
		(pad "2" smd circle
			(at 0.40005 0 90)
			(size 0 0)
			(layers "F.Cu" "F.Mask" "F.Paste")
			(net "GND")
		)
	)
	(footprint ""
		(layer "F.Cu")
		(at 402.151088 -329.762612 180)
		(property "Reference" "R938"
			(at 0 0 180)
			(layer "F.SilkS")
			(hide yes)
			(effects
				(font
					(size 1.27 1.27)
				)
			)
		)
		(property "Value" ""
			(at 0 0 180)
			(layer "F.Fab")
			(effects
				(font
					(size 1.27 1.27)
				)
			)
		)
		(duplicate_pad_numbers_are_jumpers no)
		(fp_line
			(start 0.7874 0.4064)
			(end -0.7874 0.4064)
			(stroke
				(width 0.1524)
				(type default)
			)
			(layer "F.SilkS")
		)
		(fp_line
			(start 0.7874 -0.4064)
			(end 0.7874 0.4064)
			(stroke
				(width 0.1524)
				(type default)
			)
			(layer "F.SilkS")
		)
		(fp_line
			(start -0.7874 0.4064)
			(end -0.7874 -0.4064)
			(stroke
				(width 0.1524)
				(type default)
			)
			(layer "F.SilkS")
		)
		(fp_line
			(start -0.7874 -0.4064)
			(end 0.7874 -0.4064)
			(stroke
				(width 0.1524)
				(type default)
			)
			(layer "F.SilkS")
		)
		(fp_line
			(start 0.67945 0.3048)
			(end 0.120396 0.3048)
			(stroke
				(width 0.1)
				(type default)
			)
			(layer "F.Fab")
		)
		(fp_line
			(start 0.67945 -0.3048)
			(end 0.67945 0.3048)
			(stroke
				(width 0.1)
				(type default)
			)
			(layer "F.Fab")
		)
		(fp_line
			(start 0.12065 -0.2794)
			(end 0.12065 -0.3048)
			(stroke
				(width 0.1)
				(type default)
			)
			(layer "F.Fab")
		)
		(fp_line
			(start 0.12065 -0.3048)
			(end 0.67945 -0.3048)
			(stroke
				(width 0.1)
				(type default)
			)
			(layer "F.Fab")
		)
		(fp_line
			(start 0.120396 0.3048)
			(end 0.120396 0.2794)
			(stroke
				(width 0.1)
				(type default)
			)
			(layer "F.Fab")
		)
		(fp_line
			(start 0.120396 0.2794)
			(end -0.12065 0.2794)
			(stroke
				(width 0.1)
				(type default)
			)
			(layer "F.Fab")
		)
		(fp_line
			(start -0.12065 0.3048)
			(end -0.67945 0.3048)
			(stroke
				(width 0.1)
				(type default)
			)
			(layer "F.Fab")
		)
		(fp_line
			(start -0.12065 0.2794)
			(end -0.12065 0.3048)
			(stroke
				(width 0.1)
				(type default)
			)
			(layer "F.Fab")
		)
		(fp_line
			(start -0.12065 -0.2794)
			(end 0.12065 -0.2794)
			(stroke
				(width 0.1)
				(type default)
			)
			(layer "F.Fab")
		)
		(fp_line
			(start -0.12065 -0.305054)
			(end -0.12065 -0.2794)
			(stroke
				(width 0.1)
				(type default)
			)
			(layer "F.Fab")
		)
		(fp_line
			(start -0.67945 0.3048)
			(end -0.67945 -0.305054)
			(stroke
				(width 0.1)
				(type default)
			)
			(layer "F.Fab")
		)
		(fp_line
			(start -0.67945 -0.305054)
			(end -0.12065 -0.305054)
			(stroke
				(width 0.1)
				(type default)
			)
			(layer "F.Fab")
		)
		(pad "1" smd circle
			(at -0.40005 0 180)
			(size 0 0)
			(layers "F.Cu" "F.Mask" "F.Paste")
			(net "BOOT_RDY_H")
		)
		(pad "2" smd circle
			(at 0.40005 0 180)
			(size 0 0)
			(layers "F.Cu" "F.Mask" "F.Paste")
			(net "PVDD18_S5_P0")
		)
	)
	(footprint ""
		(layer "F.Cu")
		(at 73.96099 -177.625756 180)
		(property "Reference" "PU29"
			(at -0.44958 -6.724142 0)
			(unlocked yes)
			(layer "F.SilkS")
			(effects
				(font
					(size 0.7874 0.5842)
					(thickness 0.1524)
				)
				(justify left)
			)
		)
		(property "Value" ""
			(at 0 0 180)
			(layer "F.Fab")
			(effects
				(font
					(size 1.27 1.27)
				)
			)
		)
		(duplicate_pad_numbers_are_jumpers no)
		(fp_line
			(start 2.500122 2.999994)
			(end 2.2987 2.999994)
			(stroke
				(width 0.1524)
				(type default)
			)
			(layer "F.SilkS")
		)
		(fp_line
			(start 2.500122 2.339594)
			(end 2.500122 2.999994)
			(stroke
				(width 0.1524)
				(type default)
			)
			(layer "F.SilkS")
		)
		(fp_line
			(start 2.500122 -2.999994)
			(end 2.500122 -2.44348)
			(stroke
				(width 0.1524)
				(type default)
			)
			(layer "F.SilkS")
		)
		(fp_line
			(start 2.31394 -2.999994)
			(end 2.500122 -2.999994)
			(stroke
				(width 0.1524)
				(type default)
			)
			(layer "F.SilkS")
		)
		(fp_line
			(start -2.2987 2.999994)
			(end -2.500122 2.999994)
			(stroke
				(width 0.1524)
				(type default)
			)
			(layer "F.SilkS")
		)
		(fp_line
			(start -2.500122 2.999994)
			(end -2.500122 2.339594)
			(stroke
				(width 0.1524)
				(type default)
			)
			(layer "F.SilkS")
		)
		(fp_line
			(start -2.500122 0.6604)
			(end -2.500122 0.229108)
			(stroke
				(width 0.1524)
				(type default)
			)
			(layer "F.SilkS")
		)
		(fp_line
			(start -2.500122 -2.529078)
			(end -2.500122 -2.999994)
			(stroke
				(width 0.1524)
				(type default)
			)
			(layer "F.SilkS")
		)
		(fp_line
			(start -2.500122 -2.999994)
			(end -2.24409 -2.999994)
			(stroke
				(width 0.1524)
				(type default)
			)
			(layer "F.SilkS")
		)
		(fp_poly
			(pts
				(xy -2.765298 -2.452878) (xy -3.438652 -2.677414) (xy -2.989834 -3.126232)
			)
			(stroke
				(width 0)
				(type default)
			)
			(fill yes)
			(layer "F.SilkS")
		)
		(fp_line
			(start 2.500122 2.999994)
			(end -2.500122 2.999994)
			(stroke
				(width 0.1)
				(type default)
			)
			(layer "F.Fab")
		)
		(fp_line
			(start 2.500122 -2.999994)
			(end 2.500122 2.999994)
			(stroke
				(width 0.1)
				(type default)
			)
			(layer "F.Fab")
		)
		(fp_line
			(start -2.500122 2.999994)
			(end -2.500122 -2.999994)
			(stroke
				(width 0.1)
				(type default)
			)
			(layer "F.Fab")
		)
		(fp_line
			(start -2.500122 -2.999994)
			(end 2.500122 -2.999994)
			(stroke
				(width 0.1)
				(type default)
			)
			(layer "F.Fab")
		)
		(fp_poly
			(pts
				(xy -4.218432 -2.783078) (xy -4.218432 -1.767078) (xy -3.202432 -2.275078)
			)
			(stroke
				(width 0)
				(type default)
			)
			(fill yes)
			(layer "F.Fab")
		)
		(pad "1" smd rect
			(at -2.400046 -2.275078 270)
			(size 0.2286 0.6096)
			(layers "F.Cu" "F.Mask" "F.Paste")
			(net "PVDDCR_CPU0_P1_VOS5")
		)
		(pad "2" smd rect
			(at -2.400046 -1.82499 270)
			(size 0.2286 0.6096)
			(layers "F.Cu" "F.Mask" "F.Paste")
			(net "GND")
		)
		(pad "3" smd rect
			(at -2.400046 -1.374902 270)
			(size 0.2286 0.6096)
			(layers "F.Cu" "F.Mask" "F.Paste")
			(net "PVDDCR_CPU0_P1_VCC5")
		)
		(pad "4" smd rect
			(at -2.400046 -0.925068 270)
			(size 0.2286 0.6096)
			(layers "F.Cu" "F.Mask" "F.Paste")
			(net "PVDDCR_CPU0_P1_PVCC")
		)
		(pad "5" smd rect
			(at -2.400046 -0.47498 270)
			(size 0.2286 0.6096)
			(layers "F.Cu" "F.Mask" "F.Paste")
			(net "GND")
		)
		(pad "6" smd rect
			(at -2.400046 -0.024892 270)
			(size 0.2286 0.6096)
			(layers "F.Cu" "F.Mask" "F.Paste")
			(net "NC_PVDDCR_CPU0_P1_GL1_5")
		)
		(pad "7_9-20_24" smd circle
			(at 0 1.150112 270)
			(size 0 0)
			(layers "F.Cu" "F.Mask" "F.Paste")
			(net "GND")
		)
		(pad "10_19" smd rect
			(at 0 2.899918 270)
			(size 0.6096 4.318)
			(layers "F.Cu" "F.Mask" "F.Paste")
			(net "SW_PVDDCR_CPU0_P1_SW5")
		)
		(pad "25_29" smd rect
			(at 1.549908 -1.279906 90)
			(size 2.0574 2.3114)
			(layers "F.Cu" "F.Mask" "F.Paste")
			(net "SW_P12V_AUX_PVDDCR_CPU0_P1_FLT")
		)
		(pad "30" smd rect
			(at 2.05994 -2.899918 180)
			(size 0.2286 0.6096)
			(layers "F.Cu" "F.Mask" "F.Paste")
			(net "SW_P12V_AUX_PVDDCR_CPU0_P1_FLT")
		)
		(pad "31" smd rect
			(at 1.610106 -2.899918 180)
			(size 0.2286 0.6096)
			(layers "F.Cu" "F.Mask" "F.Paste")
			(net "NC_PVDDCR_CPU0_P1_DNC5")
		)
		(pad "32" smd rect
			(at 1.160018 -2.899918 180)
			(size 0.2286 0.6096)
			(layers "F.Cu" "F.Mask" "F.Paste")
			(net "SW_PVDDCR_CPU0_P1_PH5")
		)
		(pad "33" smd rect
			(at 0.70993 -2.899918 180)
			(size 0.2286 0.6096)
			(layers "F.Cu" "F.Mask" "F.Paste")
			(net "SW_PVDDCR_CPU0_P1_BOOT5")
		)
		(pad "34" smd rect
			(at 0.260096 -2.899918 180)
			(size 0.2286 0.6096)
			(layers "F.Cu" "F.Mask" "F.Paste")
			(net "PVDDCR_CPU0_P1_PWM5")
		)
		(pad "35" smd rect
			(at -0.189992 -2.899918 180)
			(size 0.2286 0.6096)
			(layers "F.Cu" "F.Mask" "F.Paste")
			(net "PVDDCR_CPU0_P1_VCC5")
		)
		(pad "36" smd rect
			(at -0.64008 -2.899918 180)
			(size 0.2286 0.6096)
			(layers "F.Cu" "F.Mask" "F.Paste")
			(net "PVDDCR_CPU0_P1_TEMP0")
		)
		(pad "37" smd rect
			(at -1.089914 -2.899918 180)
			(size 0.2286 0.6096)
			(layers "F.Cu" "F.Mask" "F.Paste")
			(net "PVDDCR_CPU0_P1_LSET5")
		)
		(pad "38" smd rect
			(at -1.540002 -2.899918 180)
			(size 0.2286 0.6096)
			(layers "F.Cu" "F.Mask" "F.Paste")
			(net "PVDDCR_CPU0_P1_IMON5")
		)
		(pad "39" smd rect
			(at -1.99009 -2.899918 180)
			(size 0.2286 0.6096)
			(layers "F.Cu" "F.Mask" "F.Paste")
			(net "PVDDCR_CPU0_P1_VCCS")
		)
		(pad "40" smd rect
			(at -0.87503 -1.27508 180)
			(size 1.7526 1.9558)
			(layers "F.Cu" "F.Mask" "F.Paste")
			(net "GND")
		)
		(pad "41" smd rect
			(at -1.525016 0.249936 90)
			(size 0.3048 0.4572)
			(layers "F.Cu" "F.Mask" "F.Paste")
			(net "NC_PVDDCR_CPU0_P1_GL2_5")
		)
		(zone
			(layer "F.Cu")
			(hatch none 0.5)
			(connect_pads
				(clearance 0)
			)
			(min_thickness 0.25)
			(keepout
				(tracks not_allowed)
				(vias allowed)
				(pads allowed)
				(copperpour not_allowed)
				(footprints allowed)
			)
			(placement
				(enabled no)
				(sheetname "")
			)
			(fill
				(thermal_gap 0.5)
				(thermal_bridge_width 0.5)
				(island_removal_mode 0)
			)
			(polygon
				(pts
					(xy 76.461112 -180.170074) (xy 76.461112 -179.87645) (xy 71.460868 -179.87645) (xy 71.460868 -180.170074)
					(xy 71.75119 -180.170074) (xy 76.17079 -180.170074)
				)
			)
		)
		(zone
			(layer "F.Cu")
			(hatch none 0.5)
			(connect_pads
				(clearance 0)
			)
			(min_thickness 0.25)
			(keepout
				(tracks not_allowed)
				(vias allowed)
				(pads allowed)
				(copperpour not_allowed)
				(footprints allowed)
			)
			(placement
				(enabled no)
				(sheetname "")
			)
			(fill
				(thermal_gap 0.5)
				(thermal_bridge_width 0.5)
				(island_removal_mode 0)
			)
			(polygon
				(pts
					(xy 73.90892 -177.37328) (xy 73.90892 -175.321976) (xy 75.76312 -175.321976) (xy 75.76312 -175.563022)
					(xy 76.005436 -175.563022) (xy 76.005436 -175.081438) (xy 72.126348 -175.081438) (xy 72.126348 -175.26635)
					(xy 73.617582 -175.26635) (xy 73.617582 -177.42535) (xy 71.460868 -177.42535) (xy 71.460868 -177.675032)
					(xy 73.607168 -177.675032)
				)
			)
		)
	)
	(footprint ""
		(layer "F.Cu")
		(at 358.384094 -325.310754 180)
		(property "Reference" "TP3"
			(at -0.90424 -0.772668 0)
			(unlocked yes)
			(layer "F.SilkS")
			(effects
				(font
					(size 0.7874 0.5842)
					(thickness 0.1524)
				)
				(justify left)
			)
		)
		(property "Value" ""
			(at 0 0 180)
			(layer "F.Fab")
			(effects
				(font
					(size 1.27 1.27)
				)
			)
		)
		(duplicate_pad_numbers_are_jumpers no)
		(pad "1" smd circle
			(at 0 0 180)
			(size 0.762 0.762)
			(layers "F.Cu" "F.Mask" "F.Paste")
			(net "VSENSE_VSS_SENSE_C_P0")
		)
	)
	(footprint ""
		(layer "F.Cu")
		(at 142.893542 -385.58216)
		(property "Reference" "R875"
			(at 0 0 0)
			(layer "F.SilkS")
			(hide yes)
			(effects
				(font
					(size 1.27 1.27)
				)
			)
		)
		(property "Value" ""
			(at 0 0 0)
			(layer "F.Fab")
			(effects
				(font
					(size 1.27 1.27)
				)
			)
		)
		(duplicate_pad_numbers_are_jumpers no)
		(fp_line
			(start -0.32512 -0.175006)
			(end 0.32512 -0.175006)
			(stroke
				(width 0.1)
				(type default)
			)
			(layer "F.Fab")
		)
		(fp_line
			(start -0.32512 0.175006)
			(end -0.32512 -0.175006)
			(stroke
				(width 0.1)
				(type default)
			)
			(layer "F.Fab")
		)
		(fp_line
			(start 0.32512 -0.175006)
			(end 0.32512 0.175006)
			(stroke
				(width 0.1)
				(type default)
			)
			(layer "F.Fab")
		)
		(fp_line
			(start 0.32512 0.175006)
			(end -0.32512 0.175006)
			(stroke
				(width 0.1)
				(type default)
			)
			(layer "F.Fab")
		)
		(pad "1" smd rect
			(at -0.2667 0)
			(size 0.3048 0.381)
			(layers "F.Cu" "F.Mask" "F.Paste")
			(net "GPIO2_RT_CPU1_P2")
		)
		(pad "2" smd rect
			(at 0.2667 0 180)
			(size 0.3048 0.381)
			(layers "F.Cu" "F.Mask" "F.Paste")
			(net "GND")
		)
	)
	(footprint ""
		(layer "F.Cu")
		(at 352.05543 -432.825652)
		(property "Reference" "R4549"
			(at 0 0 0)
			(layer "F.SilkS")
			(hide yes)
			(effects
				(font
					(size 1.27 1.27)
				)
			)
		)
		(property "Value" ""
			(at 0 0 0)
			(layer "F.Fab")
			(effects
				(font
					(size 1.27 1.27)
				)
			)
		)
		(duplicate_pad_numbers_are_jumpers no)
		(fp_line
			(start -0.7874 -0.4064)
			(end 0.7874 -0.4064)
			(stroke
				(width 0.1524)
				(type default)
			)
			(layer "F.SilkS")
		)
		(fp_line
			(start -0.7874 0.4064)
			(end -0.7874 -0.4064)
			(stroke
				(width 0.1524)
				(type default)
			)
			(layer "F.SilkS")
		)
		(fp_line
			(start 0.7874 -0.4064)
			(end 0.7874 0.4064)
			(stroke
				(width 0.1524)
				(type default)
			)
			(layer "F.SilkS")
		)
		(fp_line
			(start 0.7874 0.4064)
			(end -0.7874 0.4064)
			(stroke
				(width 0.1524)
				(type default)
			)
			(layer "F.SilkS")
		)
		(fp_line
			(start -0.67945 -0.305054)
			(end -0.12065 -0.305054)
			(stroke
				(width 0.1)
				(type default)
			)
			(layer "F.Fab")
		)
		(fp_line
			(start -0.67945 0.3048)
			(end -0.67945 -0.305054)
			(stroke
				(width 0.1)
				(type default)
			)
			(layer "F.Fab")
		)
		(fp_line
			(start -0.12065 -0.305054)
			(end -0.12065 -0.2794)
			(stroke
				(width 0.1)
				(type default)
			)
			(layer "F.Fab")
		)
		(fp_line
			(start -0.12065 -0.2794)
			(end 0.12065 -0.2794)
			(stroke
				(width 0.1)
				(type default)
			)
			(layer "F.Fab")
		)
		(fp_line
			(start -0.12065 0.2794)
			(end -0.12065 0.3048)
			(stroke
				(width 0.1)
				(type default)
			)
			(layer "F.Fab")
		)
		(fp_line
			(start -0.12065 0.3048)
			(end -0.67945 0.3048)
			(stroke
				(width 0.1)
				(type default)
			)
			(layer "F.Fab")
		)
		(fp_line
			(start 0.120396 0.2794)
			(end -0.12065 0.2794)
			(stroke
				(width 0.1)
				(type default)
			)
			(layer "F.Fab")
		)
		(fp_line
			(start 0.120396 0.3048)
			(end 0.120396 0.2794)
			(stroke
				(width 0.1)
				(type default)
			)
			(layer "F.Fab")
		)
		(fp_line
			(start 0.12065 -0.3048)
			(end 0.67945 -0.3048)
			(stroke
				(width 0.1)
				(type default)
			)
			(layer "F.Fab")
		)
		(fp_line
			(start 0.12065 -0.2794)
			(end 0.12065 -0.3048)
			(stroke
				(width 0.1)
				(type default)
			)
			(layer "F.Fab")
		)
		(fp_line
			(start 0.67945 -0.3048)
			(end 0.67945 0.3048)
			(stroke
				(width 0.1)
				(type default)
			)
			(layer "F.Fab")
		)
		(fp_line
			(start 0.67945 0.3048)
			(end 0.120396 0.3048)
			(stroke
				(width 0.1)
				(type default)
			)
			(layer "F.Fab")
		)
		(pad "1" smd circle
			(at -0.40005 0)
			(size 0 0)
			(layers "F.Cu" "F.Mask" "F.Paste")
			(net "P3V3_AUX")
		)
		(pad "2" smd circle
			(at 0.40005 0)
			(size 0 0)
			(layers "F.Cu" "F.Mask" "F.Paste")
			(net "SWB_HSC_EN_BUF_R")
		)
	)
	(footprint ""
		(layer "F.Cu")
		(at 449.044314 -25.10028 -90)
		(property "Reference" "PC2079"
			(at 0 0 270)
			(layer "F.SilkS")
			(hide yes)
			(effects
				(font
					(size 1.27 1.27)
				)
			)
		)
		(property "Value" ""
			(at 0 0 270)
			(layer "F.Fab")
			(effects
				(font
					(size 1.27 1.27)
				)
			)
		)
		(duplicate_pad_numbers_are_jumpers no)
		(fp_line
			(start -0.7874 0.4064)
			(end -0.7874 -0.4064)
			(stroke
				(width 0.1524)
				(type default)
			)
			(layer "F.SilkS")
		)
		(fp_line
			(start 0.7874 0.4064)
			(end -0.7874 0.4064)
			(stroke
				(width 0.1524)
				(type default)
			)
			(layer "F.SilkS")
		)
		(fp_line
			(start -0.7874 -0.4064)
			(end 0.7874 -0.4064)
			(stroke
				(width 0.1524)
				(type default)
			)
			(layer "F.SilkS")
		)
		(fp_line
			(start 0.7874 -0.4064)
			(end 0.7874 0.4064)
			(stroke
				(width 0.1524)
				(type default)
			)
			(layer "F.SilkS")
		)
		(fp_line
			(start -0.67945 0.3048)
			(end -0.67945 -0.305054)
			(stroke
				(width 0.1)
				(type default)
			)
			(layer "F.Fab")
		)
		(fp_line
			(start -0.12065 0.3048)
			(end -0.67945 0.3048)
			(stroke
				(width 0.1)
				(type default)
			)
			(layer "F.Fab")
		)
		(fp_line
			(start 0.120396 0.3048)
			(end 0.120396 0.2794)
			(stroke
				(width 0.1)
				(type default)
			)
			(layer "F.Fab")
		)
		(fp_line
			(start 0.67945 0.3048)
			(end 0.120396 0.3048)
			(stroke
				(width 0.1)
				(type default)
			)
			(layer "F.Fab")
		)
		(fp_line
			(start -0.12065 0.2794)
			(end -0.12065 0.3048)
			(stroke
				(width 0.1)
				(type default)
			)
			(layer "F.Fab")
		)
		(fp_line
			(start 0.120396 0.2794)
			(end -0.12065 0.2794)
			(stroke
				(width 0.1)
				(type default)
			)
			(layer "F.Fab")
		)
		(fp_line
			(start -0.12065 -0.2794)
			(end 0.12065 -0.2794)
			(stroke
				(width 0.1)
				(type default)
			)
			(layer "F.Fab")
		)
		(fp_line
			(start 0.12065 -0.2794)
			(end 0.12065 -0.3048)
			(stroke
				(width 0.1)
				(type default)
			)
			(layer "F.Fab")
		)
		(fp_line
			(start 0.12065 -0.3048)
			(end 0.67945 -0.3048)
			(stroke
				(width 0.1)
				(type default)
			)
			(layer "F.Fab")
		)
		(fp_line
			(start 0.67945 -0.3048)
			(end 0.67945 0.3048)
			(stroke
				(width 0.1)
				(type default)
			)
			(layer "F.Fab")
		)
		(fp_line
			(start -0.67945 -0.305054)
			(end -0.12065 -0.305054)
			(stroke
				(width 0.1)
				(type default)
			)
			(layer "F.Fab")
		)
		(fp_line
			(start -0.12065 -0.305054)
			(end -0.12065 -0.2794)
			(stroke
				(width 0.1)
				(type default)
			)
			(layer "F.Fab")
		)
		(pad "1" smd circle
			(at -0.40005 0 270)
			(size 0 0)
			(layers "F.Cu" "F.Mask" "F.Paste")
			(net "P12V_AUX")
		)
		(pad "2" smd circle
			(at 0.40005 0 270)
			(size 0 0)
			(layers "F.Cu" "F.Mask" "F.Paste")
			(net "GND")
		)
	)
	(footprint ""
		(layer "F.Cu")
		(at 102.751128 -184.427368 -90)
		(property "Reference" "PR522"
			(at 0 0 270)
			(layer "F.SilkS")
			(hide yes)
			(effects
				(font
					(size 1.27 1.27)
				)
			)
		)
		(property "Value" ""
			(at 0 0 270)
			(layer "F.Fab")
			(effects
				(font
					(size 1.27 1.27)
				)
			)
		)
		(duplicate_pad_numbers_are_jumpers no)
		(fp_line
			(start -0.7874 0.4064)
			(end -0.7874 -0.4064)
			(stroke
				(width 0.1524)
				(type default)
			)
			(layer "F.SilkS")
		)
		(fp_line
			(start 0.7874 0.4064)
			(end -0.7874 0.4064)
			(stroke
				(width 0.1524)
				(type default)
			)
			(layer "F.SilkS")
		)
		(fp_line
			(start -0.7874 -0.4064)
			(end 0.7874 -0.4064)
			(stroke
				(width 0.1524)
				(type default)
			)
			(layer "F.SilkS")
		)
		(fp_line
			(start 0.7874 -0.4064)
			(end 0.7874 0.4064)
			(stroke
				(width 0.1524)
				(type default)
			)
			(layer "F.SilkS")
		)
		(fp_line
			(start -0.67945 0.3048)
			(end -0.67945 -0.305054)
			(stroke
				(width 0.1)
				(type default)
			)
			(layer "F.Fab")
		)
		(fp_line
			(start -0.12065 0.3048)
			(end -0.67945 0.3048)
			(stroke
				(width 0.1)
				(type default)
			)
			(layer "F.Fab")
		)
		(fp_line
			(start 0.120396 0.3048)
			(end 0.120396 0.2794)
			(stroke
				(width 0.1)
				(type default)
			)
			(layer "F.Fab")
		)
		(fp_line
			(start 0.67945 0.3048)
			(end 0.120396 0.3048)
			(stroke
				(width 0.1)
				(type default)
			)
			(layer "F.Fab")
		)
		(fp_line
			(start -0.12065 0.2794)
			(end -0.12065 0.3048)
			(stroke
				(width 0.1)
				(type default)
			)
			(layer "F.Fab")
		)
		(fp_line
			(start 0.120396 0.2794)
			(end -0.12065 0.2794)
			(stroke
				(width 0.1)
				(type default)
			)
			(layer "F.Fab")
		)
		(fp_line
			(start -0.12065 -0.2794)
			(end 0.12065 -0.2794)
			(stroke
				(width 0.1)
				(type default)
			)
			(layer "F.Fab")
		)
		(fp_line
			(start 0.12065 -0.2794)
			(end 0.12065 -0.3048)
			(stroke
				(width 0.1)
				(type default)
			)
			(layer "F.Fab")
		)
		(fp_line
			(start 0.12065 -0.3048)
			(end 0.67945 -0.3048)
			(stroke
				(width 0.1)
				(type default)
			)
			(layer "F.Fab")
		)
		(fp_line
			(start 0.67945 -0.3048)
			(end 0.67945 0.3048)
			(stroke
				(width 0.1)
				(type default)
			)
			(layer "F.Fab")
		)
		(fp_line
			(start -0.67945 -0.305054)
			(end -0.12065 -0.305054)
			(stroke
				(width 0.1)
				(type default)
			)
			(layer "F.Fab")
		)
		(fp_line
			(start -0.12065 -0.305054)
			(end -0.12065 -0.2794)
			(stroke
				(width 0.1)
				(type default)
			)
			(layer "F.Fab")
		)
		(pad "1" smd circle
			(at -0.40005 0 270)
			(size 0 0)
			(layers "F.Cu" "F.Mask" "F.Paste")
			(net "SW_PVDDCR_CPU0_P1_SW3_RC")
		)
		(pad "2" smd circle
			(at 0.40005 0 270)
			(size 0 0)
			(layers "F.Cu" "F.Mask" "F.Paste")
			(net "GND")
		)
	)
	(footprint ""
		(layer "F.Cu")
		(at 217.1065 -402.191982 90)
		(property "Reference" "PC3272"
			(at 0 0 90)
			(layer "F.SilkS")
			(hide yes)
			(effects
				(font
					(size 1.27 1.27)
				)
			)
		)
		(property "Value" ""
			(at 0 0 90)
			(layer "F.Fab")
			(effects
				(font
					(size 1.27 1.27)
				)
			)
		)
		(duplicate_pad_numbers_are_jumpers no)
		(fp_line
			(start 0.7874 -0.4064)
			(end 0.7874 0.4064)
			(stroke
				(width 0.1524)
				(type default)
			)
			(layer "F.SilkS")
		)
		(fp_line
			(start -0.7874 -0.4064)
			(end 0.7874 -0.4064)
			(stroke
				(width 0.1524)
				(type default)
			)
			(layer "F.SilkS")
		)
		(fp_line
			(start 0.7874 0.4064)
			(end -0.7874 0.4064)
			(stroke
				(width 0.1524)
				(type default)
			)
			(layer "F.SilkS")
		)
		(fp_line
			(start -0.7874 0.4064)
			(end -0.7874 -0.4064)
			(stroke
				(width 0.1524)
				(type default)
			)
			(layer "F.SilkS")
		)
		(fp_line
			(start -0.12065 -0.305054)
			(end -0.12065 -0.2794)
			(stroke
				(width 0.1)
				(type default)
			)
			(layer "F.Fab")
		)
		(fp_line
			(start -0.67945 -0.305054)
			(end -0.12065 -0.305054)
			(stroke
				(width 0.1)
				(type default)
			)
			(layer "F.Fab")
		)
		(fp_line
			(start 0.67945 -0.3048)
			(end 0.67945 0.3048)
			(stroke
				(width 0.1)
				(type default)
			)
			(layer "F.Fab")
		)
		(fp_line
			(start 0.12065 -0.3048)
			(end 0.67945 -0.3048)
			(stroke
				(width 0.1)
				(type default)
			)
			(layer "F.Fab")
		)
		(fp_line
			(start 0.12065 -0.2794)
			(end 0.12065 -0.3048)
			(stroke
				(width 0.1)
				(type default)
			)
			(layer "F.Fab")
		)
		(fp_line
			(start -0.12065 -0.2794)
			(end 0.12065 -0.2794)
			(stroke
				(width 0.1)
				(type default)
			)
			(layer "F.Fab")
		)
		(fp_line
			(start 0.120396 0.2794)
			(end -0.12065 0.2794)
			(stroke
				(width 0.1)
				(type default)
			)
			(layer "F.Fab")
		)
		(fp_line
			(start -0.12065 0.2794)
			(end -0.12065 0.3048)
			(stroke
				(width 0.1)
				(type default)
			)
			(layer "F.Fab")
		)
		(fp_line
			(start 0.67945 0.3048)
			(end 0.120396 0.3048)
			(stroke
				(width 0.1)
				(type default)
			)
			(layer "F.Fab")
		)
		(fp_line
			(start 0.120396 0.3048)
			(end 0.120396 0.2794)
			(stroke
				(width 0.1)
				(type default)
			)
			(layer "F.Fab")
		)
		(fp_line
			(start -0.12065 0.3048)
			(end -0.67945 0.3048)
			(stroke
				(width 0.1)
				(type default)
			)
			(layer "F.Fab")
		)
		(fp_line
			(start -0.67945 0.3048)
			(end -0.67945 -0.305054)
			(stroke
				(width 0.1)
				(type default)
			)
			(layer "F.Fab")
		)
		(pad "1" smd circle
			(at -0.40005 0 90)
			(size 0 0)
			(layers "F.Cu" "F.Mask" "F.Paste")
			(net "HSC_VDD_R_3")
		)
		(pad "2" smd circle
			(at 0.40005 0 90)
			(size 0 0)
			(layers "F.Cu" "F.Mask" "F.Paste")
			(net "AGND_HSC")
		)
	)
	(footprint ""
		(layer "F.Cu")
		(at 47.768764 -408.517344 -90)
		(property "Reference" "C6630"
			(at 0 0 270)
			(layer "F.SilkS")
			(hide yes)
			(effects
				(font
					(size 1.27 1.27)
				)
			)
		)
		(property "Value" ""
			(at 0 0 270)
			(layer "F.Fab")
			(effects
				(font
					(size 1.27 1.27)
				)
			)
		)
		(duplicate_pad_numbers_are_jumpers no)
		(fp_line
			(start -0.299974 0.150114)
			(end -0.299974 -0.150114)
			(stroke
				(width 0.1)
				(type default)
			)
			(layer "F.Fab")
		)
		(fp_line
			(start 0.299974 0.150114)
			(end -0.299974 0.150114)
			(stroke
				(width 0.1)
				(type default)
			)
			(layer "F.Fab")
		)
		(fp_line
			(start -0.299974 -0.150114)
			(end 0.299974 -0.150114)
			(stroke
				(width 0.1)
				(type default)
			)
			(layer "F.Fab")
		)
		(fp_line
			(start 0.299974 -0.150114)
			(end 0.299974 0.150114)
			(stroke
				(width 0.1)
				(type default)
			)
			(layer "F.Fab")
		)
		(pad "1" smd rect
			(at -0.2667 0 270)
			(size 0.3048 0.381)
			(layers "F.Cu" "F.Mask" "F.Paste")
			(net "P5E_CPU1_P0_TX_BUF_C_DN<0>")
		)
		(pad "2" smd rect
			(at 0.2667 0 270)
			(size 0.3048 0.381)
			(layers "F.Cu" "F.Mask" "F.Paste")
			(net "P5E_CPU1_P0_TX_BUF_DN<0>")
		)
	)
	(footprint ""
		(layer "F.Cu")
		(at 97.177352 -74.76998)
		(property "Reference" "PC1321"
			(at 0 0 0)
			(layer "F.SilkS")
			(hide yes)
			(effects
				(font
					(size 1.27 1.27)
				)
			)
		)
		(property "Value" ""
			(at 0 0 0)
			(layer "F.Fab")
			(effects
				(font
					(size 1.27 1.27)
				)
			)
		)
		(duplicate_pad_numbers_are_jumpers no)
		(fp_line
			(start -0.7874 -0.4064)
			(end 0.7874 -0.4064)
			(stroke
				(width 0.1524)
				(type default)
			)
			(layer "F.SilkS")
		)
		(fp_line
			(start -0.7874 0.4064)
			(end -0.7874 -0.4064)
			(stroke
				(width 0.1524)
				(type default)
			)
			(layer "F.SilkS")
		)
		(fp_line
			(start 0.7874 -0.4064)
			(end 0.7874 0.4064)
			(stroke
				(width 0.1524)
				(type default)
			)
			(layer "F.SilkS")
		)
		(fp_line
			(start 0.7874 0.4064)
			(end -0.7874 0.4064)
			(stroke
				(width 0.1524)
				(type default)
			)
			(layer "F.SilkS")
		)
		(fp_line
			(start -0.67945 -0.305054)
			(end -0.12065 -0.305054)
			(stroke
				(width 0.1)
				(type default)
			)
			(layer "F.Fab")
		)
		(fp_line
			(start -0.67945 0.3048)
			(end -0.67945 -0.305054)
			(stroke
				(width 0.1)
				(type default)
			)
			(layer "F.Fab")
		)
		(fp_line
			(start -0.12065 -0.305054)
			(end -0.12065 -0.2794)
			(stroke
				(width 0.1)
				(type default)
			)
			(layer "F.Fab")
		)
		(fp_line
			(start -0.12065 -0.2794)
			(end 0.12065 -0.2794)
			(stroke
				(width 0.1)
				(type default)
			)
			(layer "F.Fab")
		)
		(fp_line
			(start -0.12065 0.2794)
			(end -0.12065 0.3048)
			(stroke
				(width 0.1)
				(type default)
			)
			(layer "F.Fab")
		)
		(fp_line
			(start -0.12065 0.3048)
			(end -0.67945 0.3048)
			(stroke
				(width 0.1)
				(type default)
			)
			(layer "F.Fab")
		)
		(fp_line
			(start 0.120396 0.2794)
			(end -0.12065 0.2794)
			(stroke
				(width 0.1)
				(type default)
			)
			(layer "F.Fab")
		)
		(fp_line
			(start 0.120396 0.3048)
			(end 0.120396 0.2794)
			(stroke
				(width 0.1)
				(type default)
			)
			(layer "F.Fab")
		)
		(fp_line
			(start 0.12065 -0.3048)
			(end 0.67945 -0.3048)
			(stroke
				(width 0.1)
				(type default)
			)
			(layer "F.Fab")
		)
		(fp_line
			(start 0.12065 -0.2794)
			(end 0.12065 -0.3048)
			(stroke
				(width 0.1)
				(type default)
			)
			(layer "F.Fab")
		)
		(fp_line
			(start 0.67945 -0.3048)
			(end 0.67945 0.3048)
			(stroke
				(width 0.1)
				(type default)
			)
			(layer "F.Fab")
		)
		(fp_line
			(start 0.67945 0.3048)
			(end 0.120396 0.3048)
			(stroke
				(width 0.1)
				(type default)
			)
			(layer "F.Fab")
		)
		(pad "1" smd circle
			(at -0.40005 0)
			(size 0 0)
			(layers "F.Cu" "F.Mask" "F.Paste")
			(net "P3V3_OCP_DVDT_2")
		)
		(pad "2" smd circle
			(at 0.40005 0)
			(size 0 0)
			(layers "F.Cu" "F.Mask" "F.Paste")
			(net "GND")
		)
	)
	(footprint ""
		(layer "F.Cu")
		(at 170.979846 -382.30429)
		(property "Reference" "R892"
			(at 0 0 0)
			(layer "F.SilkS")
			(hide yes)
			(effects
				(font
					(size 1.27 1.27)
				)
			)
		)
		(property "Value" ""
			(at 0 0 0)
			(layer "F.Fab")
			(effects
				(font
					(size 1.27 1.27)
				)
			)
		)
		(duplicate_pad_numbers_are_jumpers no)
		(fp_line
			(start -0.32512 -0.175006)
			(end 0.32512 -0.175006)
			(stroke
				(width 0.1)
				(type default)
			)
			(layer "F.Fab")
		)
		(fp_line
			(start -0.32512 0.175006)
			(end -0.32512 -0.175006)
			(stroke
				(width 0.1)
				(type default)
			)
			(layer "F.Fab")
		)
		(fp_line
			(start 0.32512 -0.175006)
			(end 0.32512 0.175006)
			(stroke
				(width 0.1)
				(type default)
			)
			(layer "F.Fab")
		)
		(fp_line
			(start 0.32512 0.175006)
			(end -0.32512 0.175006)
			(stroke
				(width 0.1)
				(type default)
			)
			(layer "F.Fab")
		)
		(pad "1" smd rect
			(at -0.2667 0)
			(size 0.3048 0.381)
			(layers "F.Cu" "F.Mask" "F.Paste")
			(net "RT_CPU1_P2_ADDR1")
		)
		(pad "2" smd rect
			(at 0.2667 0 180)
			(size 0.3048 0.381)
			(layers "F.Cu" "F.Mask" "F.Paste")
			(net "GND")
		)
	)
	(footprint ""
		(layer "F.Cu")
		(at 420.950136 -355.972364 90)
		(property "Reference" "PC201_1"
			(at 0 0 90)
			(layer "F.SilkS")
			(hide yes)
			(effects
				(font
					(size 1.27 1.27)
				)
			)
		)
		(property "Value" ""
			(at 0 0 90)
			(layer "F.Fab")
			(effects
				(font
					(size 1.27 1.27)
				)
			)
		)
		(duplicate_pad_numbers_are_jumpers no)
		(fp_line
			(start 0.7874 -0.4064)
			(end 0.7874 0.4064)
			(stroke
				(width 0.1524)
				(type default)
			)
			(layer "F.SilkS")
		)
		(fp_line
			(start -0.7874 -0.4064)
			(end 0.7874 -0.4064)
			(stroke
				(width 0.1524)
				(type default)
			)
			(layer "F.SilkS")
		)
		(fp_line
			(start 0.7874 0.4064)
			(end -0.7874 0.4064)
			(stroke
				(width 0.1524)
				(type default)
			)
			(layer "F.SilkS")
		)
		(fp_line
			(start -0.7874 0.4064)
			(end -0.7874 -0.4064)
			(stroke
				(width 0.1524)
				(type default)
			)
			(layer "F.SilkS")
		)
		(fp_line
			(start -0.12065 -0.305054)
			(end -0.12065 -0.2794)
			(stroke
				(width 0.1)
				(type default)
			)
			(layer "F.Fab")
		)
		(fp_line
			(start -0.67945 -0.305054)
			(end -0.12065 -0.305054)
			(stroke
				(width 0.1)
				(type default)
			)
			(layer "F.Fab")
		)
		(fp_line
			(start 0.67945 -0.3048)
			(end 0.67945 0.3048)
			(stroke
				(width 0.1)
				(type default)
			)
			(layer "F.Fab")
		)
		(fp_line
			(start 0.12065 -0.3048)
			(end 0.67945 -0.3048)
			(stroke
				(width 0.1)
				(type default)
			)
			(layer "F.Fab")
		)
		(fp_line
			(start 0.12065 -0.2794)
			(end 0.12065 -0.3048)
			(stroke
				(width 0.1)
				(type default)
			)
			(layer "F.Fab")
		)
		(fp_line
			(start -0.12065 -0.2794)
			(end 0.12065 -0.2794)
			(stroke
				(width 0.1)
				(type default)
			)
			(layer "F.Fab")
		)
		(fp_line
			(start 0.120396 0.2794)
			(end -0.12065 0.2794)
			(stroke
				(width 0.1)
				(type default)
			)
			(layer "F.Fab")
		)
		(fp_line
			(start -0.12065 0.2794)
			(end -0.12065 0.3048)
			(stroke
				(width 0.1)
				(type default)
			)
			(layer "F.Fab")
		)
		(fp_line
			(start 0.67945 0.3048)
			(end 0.120396 0.3048)
			(stroke
				(width 0.1)
				(type default)
			)
			(layer "F.Fab")
		)
		(fp_line
			(start 0.120396 0.3048)
			(end 0.120396 0.2794)
			(stroke
				(width 0.1)
				(type default)
			)
			(layer "F.Fab")
		)
		(fp_line
			(start -0.12065 0.3048)
			(end -0.67945 0.3048)
			(stroke
				(width 0.1)
				(type default)
			)
			(layer "F.Fab")
		)
		(fp_line
			(start -0.67945 0.3048)
			(end -0.67945 -0.305054)
			(stroke
				(width 0.1)
				(type default)
			)
			(layer "F.Fab")
		)
		(pad "1" smd circle
			(at -0.40005 0 90)
			(size 0 0)
			(layers "F.Cu" "F.Mask" "F.Paste")
			(net "PVDD11_S3_P0_VCCS")
		)
		(pad "2" smd circle
			(at 0.40005 0 90)
			(size 0 0)
			(layers "F.Cu" "F.Mask" "F.Paste")
			(net "GND")
		)
	)
	(footprint ""
		(layer "F.Cu")
		(at 95.489522 -136.066784 -90)
		(property "Reference" "C242"
			(at 0 0 270)
			(layer "F.SilkS")
			(hide yes)
			(effects
				(font
					(size 1.27 1.27)
				)
			)
		)
		(property "Value" ""
			(at 0 0 270)
			(layer "F.Fab")
			(effects
				(font
					(size 1.27 1.27)
				)
			)
		)
		(duplicate_pad_numbers_are_jumpers no)
		(fp_line
			(start -0.7874 0.4064)
			(end -0.7874 -0.4064)
			(stroke
				(width 0.1524)
				(type default)
			)
			(layer "F.SilkS")
		)
		(fp_line
			(start 0.7874 0.4064)
			(end -0.7874 0.4064)
			(stroke
				(width 0.1524)
				(type default)
			)
			(layer "F.SilkS")
		)
		(fp_line
			(start -0.7874 -0.4064)
			(end 0.7874 -0.4064)
			(stroke
				(width 0.1524)
				(type default)
			)
			(layer "F.SilkS")
		)
		(fp_line
			(start 0.7874 -0.4064)
			(end 0.7874 0.4064)
			(stroke
				(width 0.1524)
				(type default)
			)
			(layer "F.SilkS")
		)
		(fp_line
			(start -0.67945 0.3048)
			(end -0.67945 -0.305054)
			(stroke
				(width 0.1)
				(type default)
			)
			(layer "F.Fab")
		)
		(fp_line
			(start -0.12065 0.3048)
			(end -0.67945 0.3048)
			(stroke
				(width 0.1)
				(type default)
			)
			(layer "F.Fab")
		)
		(fp_line
			(start 0.120396 0.3048)
			(end 0.120396 0.2794)
			(stroke
				(width 0.1)
				(type default)
			)
			(layer "F.Fab")
		)
		(fp_line
			(start 0.67945 0.3048)
			(end 0.120396 0.3048)
			(stroke
				(width 0.1)
				(type default)
			)
			(layer "F.Fab")
		)
		(fp_line
			(start -0.12065 0.2794)
			(end -0.12065 0.3048)
			(stroke
				(width 0.1)
				(type default)
			)
			(layer "F.Fab")
		)
		(fp_line
			(start 0.120396 0.2794)
			(end -0.12065 0.2794)
			(stroke
				(width 0.1)
				(type default)
			)
			(layer "F.Fab")
		)
		(fp_line
			(start -0.12065 -0.2794)
			(end 0.12065 -0.2794)
			(stroke
				(width 0.1)
				(type default)
			)
			(layer "F.Fab")
		)
		(fp_line
			(start 0.12065 -0.2794)
			(end 0.12065 -0.3048)
			(stroke
				(width 0.1)
				(type default)
			)
			(layer "F.Fab")
		)
		(fp_line
			(start 0.12065 -0.3048)
			(end 0.67945 -0.3048)
			(stroke
				(width 0.1)
				(type default)
			)
			(layer "F.Fab")
		)
		(fp_line
			(start 0.67945 -0.3048)
			(end 0.67945 0.3048)
			(stroke
				(width 0.1)
				(type default)
			)
			(layer "F.Fab")
		)
		(fp_line
			(start -0.67945 -0.305054)
			(end -0.12065 -0.305054)
			(stroke
				(width 0.1)
				(type default)
			)
			(layer "F.Fab")
		)
		(fp_line
			(start -0.12065 -0.305054)
			(end -0.12065 -0.2794)
			(stroke
				(width 0.1)
				(type default)
			)
			(layer "F.Fab")
		)
		(pad "1" smd circle
			(at -0.40005 0 270)
			(size 0 0)
			(layers "F.Cu" "F.Mask" "F.Paste")
			(net "PVDDCR_SOC_P1_EN_RC")
		)
		(pad "2" smd circle
			(at 0.40005 0 270)
			(size 0 0)
			(layers "F.Cu" "F.Mask" "F.Paste")
			(net "GND")
		)
	)
	(footprint ""
		(layer "F.Cu")
		(at 61.874654 -346.721176)
		(property "Reference" "PU36"
			(at -3.200654 -7.455154 0)
			(unlocked yes)
			(layer "F.SilkS")
			(effects
				(font
					(size 0.7874 0.5842)
					(thickness 0.1524)
				)
				(justify left)
			)
		)
		(property "Value" ""
			(at 0 0 0)
			(layer "F.Fab")
			(effects
				(font
					(size 1.27 1.27)
				)
			)
		)
		(duplicate_pad_numbers_are_jumpers no)
		(fp_line
			(start -2.500122 -2.999994)
			(end -2.24409 -2.999994)
			(stroke
				(width 0.1524)
				(type default)
			)
			(layer "F.SilkS")
		)
		(fp_line
			(start -2.500122 -2.529078)
			(end -2.500122 -2.999994)
			(stroke
				(width 0.1524)
				(type default)
			)
			(layer "F.SilkS")
		)
		(fp_line
			(start -2.500122 0.6604)
			(end -2.500122 0.229108)
			(stroke
				(width 0.1524)
				(type default)
			)
			(layer "F.SilkS")
		)
		(fp_line
			(start -2.500122 2.999994)
			(end -2.500122 2.339594)
			(stroke
				(width 0.1524)
				(type default)
			)
			(layer "F.SilkS")
		)
		(fp_line
			(start -2.2987 2.999994)
			(end -2.500122 2.999994)
			(stroke
				(width 0.1524)
				(type default)
			)
			(layer "F.SilkS")
		)
		(fp_line
			(start 2.31394 -2.999994)
			(end 2.500122 -2.999994)
			(stroke
				(width 0.1524)
				(type default)
			)
			(layer "F.SilkS")
		)
		(fp_line
			(start 2.500122 -2.999994)
			(end 2.500122 -2.44348)
			(stroke
				(width 0.1524)
				(type default)
			)
			(layer "F.SilkS")
		)
		(fp_line
			(start 2.500122 2.339594)
			(end 2.500122 2.999994)
			(stroke
				(width 0.1524)
				(type default)
			)
			(layer "F.SilkS")
		)
		(fp_line
			(start 2.500122 2.999994)
			(end 2.2987 2.999994)
			(stroke
				(width 0.1524)
				(type default)
			)
			(layer "F.SilkS")
		)
		(fp_poly
			(pts
				(xy -2.75336 -2.448306) (xy -3.426968 -2.672842) (xy -2.977896 -3.121914)
			)
			(stroke
				(width 0)
				(type default)
			)
			(fill yes)
			(layer "F.SilkS")
		)
		(fp_line
			(start -2.500122 -2.999994)
			(end 2.500122 -2.999994)
			(stroke
				(width 0.1)
				(type default)
			)
			(layer "F.Fab")
		)
		(fp_line
			(start -2.500122 2.999994)
			(end -2.500122 -2.999994)
			(stroke
				(width 0.1)
				(type default)
			)
			(layer "F.Fab")
		)
		(fp_line
			(start 2.500122 -2.999994)
			(end 2.500122 2.999994)
			(stroke
				(width 0.1)
				(type default)
			)
			(layer "F.Fab")
		)
		(fp_line
			(start 2.500122 2.999994)
			(end -2.500122 2.999994)
			(stroke
				(width 0.1)
				(type default)
			)
			(layer "F.Fab")
		)
		(fp_poly
			(pts
				(xy -4.218432 -2.783078) (xy -4.218432 -1.767078) (xy -3.202432 -2.275078)
			)
			(stroke
				(width 0)
				(type default)
			)
			(fill yes)
			(layer "F.Fab")
		)
		(pad "1" smd rect
			(at -2.400046 -2.275078 90)
			(size 0.2286 0.6096)
			(layers "F.Cu" "F.Mask" "F.Paste")
			(net "PVDDCR_CPU1_P1_VOS4")
		)
		(pad "2" smd rect
			(at -2.400046 -1.82499 90)
			(size 0.2286 0.6096)
			(layers "F.Cu" "F.Mask" "F.Paste")
			(net "GND")
		)
		(pad "3" smd rect
			(at -2.400046 -1.374902 90)
			(size 0.2286 0.6096)
			(layers "F.Cu" "F.Mask" "F.Paste")
			(net "PVDDCR_CPU1_P1_VCC4")
		)
		(pad "4" smd rect
			(at -2.400046 -0.925068 90)
			(size 0.2286 0.6096)
			(layers "F.Cu" "F.Mask" "F.Paste")
			(net "PVDDCR_CPU1_P1_PVCC")
		)
		(pad "5" smd rect
			(at -2.400046 -0.47498 90)
			(size 0.2286 0.6096)
			(layers "F.Cu" "F.Mask" "F.Paste")
			(net "GND")
		)
		(pad "6" smd rect
			(at -2.400046 -0.024892 90)
			(size 0.2286 0.6096)
			(layers "F.Cu" "F.Mask" "F.Paste")
			(net "NC_PVDDCR_CPU1_P1_GL1_4")
		)
		(pad "7_9-20_24" smd circle
			(at 0 1.150112 90)
			(size 0 0)
			(layers "F.Cu" "F.Mask" "F.Paste")
			(net "GND")
		)
		(pad "10_19" smd rect
			(at 0 2.899918 90)
			(size 0.6096 4.318)
			(layers "F.Cu" "F.Mask" "F.Paste")
			(net "SW_PVDDCR_CPU1_P1_SW4")
		)
		(pad "25_29" smd rect
			(at 1.549908 -1.279906 270)
			(size 2.0574 2.3114)
			(layers "F.Cu" "F.Mask" "F.Paste")
			(net "SW_P12V_AUX_PVDDCR_CPU1_P1_FLT")
		)
		(pad "30" smd rect
			(at 2.05994 -2.899918)
			(size 0.2286 0.6096)
			(layers "F.Cu" "F.Mask" "F.Paste")
			(net "SW_P12V_AUX_PVDDCR_CPU1_P1_FLT")
		)
		(pad "31" smd rect
			(at 1.610106 -2.899918)
			(size 0.2286 0.6096)
			(layers "F.Cu" "F.Mask" "F.Paste")
			(net "NC_PVDDCR_CPU1_P1_DNC4")
		)
		(pad "32" smd rect
			(at 1.160018 -2.899918)
			(size 0.2286 0.6096)
			(layers "F.Cu" "F.Mask" "F.Paste")
			(net "SW_PVDDCR_CPU1_P1_BOOTR4")
		)
		(pad "33" smd rect
			(at 0.70993 -2.899918)
			(size 0.2286 0.6096)
			(layers "F.Cu" "F.Mask" "F.Paste")
			(net "SW_PVDDCR_CPU1_P1_BOOT4")
		)
		(pad "34" smd rect
			(at 0.260096 -2.899918)
			(size 0.2286 0.6096)
			(layers "F.Cu" "F.Mask" "F.Paste")
			(net "PVDDCR_CPU1_P1_PWM4")
		)
		(pad "35" smd rect
			(at -0.189992 -2.899918)
			(size 0.2286 0.6096)
			(layers "F.Cu" "F.Mask" "F.Paste")
			(net "PVDDCR_CPU1_P1_VCC4")
		)
		(pad "36" smd rect
			(at -0.64008 -2.899918)
			(size 0.2286 0.6096)
			(layers "F.Cu" "F.Mask" "F.Paste")
			(net "PVDDCR_CPU1_P1_TEMP0")
		)
		(pad "37" smd rect
			(at -1.089914 -2.899918)
			(size 0.2286 0.6096)
			(layers "F.Cu" "F.Mask" "F.Paste")
			(net "PVDDCR_CPU1_P1_LSET4")
		)
		(pad "38" smd rect
			(at -1.540002 -2.899918)
			(size 0.2286 0.6096)
			(layers "F.Cu" "F.Mask" "F.Paste")
			(net "PVDDCR_CPU1_P1_IMON4")
		)
		(pad "39" smd rect
			(at -1.99009 -2.899918)
			(size 0.2286 0.6096)
			(layers "F.Cu" "F.Mask" "F.Paste")
			(net "PVDDCR_CPU1_P1_VCCS")
		)
		(pad "40" smd rect
			(at -0.87503 -1.27508)
			(size 1.7526 1.9558)
			(layers "F.Cu" "F.Mask" "F.Paste")
			(net "GND")
		)
		(pad "41" smd rect
			(at -1.525016 0.249936 270)
			(size 0.3048 0.4572)
			(layers "F.Cu" "F.Mask" "F.Paste")
			(net "NC_PVDDCR_CPU1_P1_GL2_4")
		)
		(zone
			(layer "F.Cu")
			(hatch none 0.5)
			(connect_pads
				(clearance 0)
			)
			(min_thickness 0.25)
			(keepout
				(tracks not_allowed)
				(vias allowed)
				(pads allowed)
				(copperpour not_allowed)
				(footprints allowed)
			)
			(placement
				(enabled no)
				(sheetname "")
			)
			(fill
				(thermal_gap 0.5)
				(thermal_bridge_width 0.5)
				(island_removal_mode 0)
			)
			(polygon
				(pts
					(xy 59.374532 -344.141552) (xy 59.374532 -344.470482) (xy 64.374776 -344.470482) (xy 64.374776 -344.136726)
					(xy 64.084454 -344.136726) (xy 64.084454 -344.176858) (xy 59.664854 -344.176858) (xy 59.664854 -344.141552)
				)
			)
		)
		(zone
			(layer "F.Cu")
			(hatch none 0.5)
			(connect_pads
				(clearance 0)
			)
			(min_thickness 0.25)
			(keepout
				(tracks not_allowed)
				(vias allowed)
				(pads allowed)
				(copperpour not_allowed)
				(footprints allowed)
			)
			(placement
				(enabled no)
				(sheetname "")
			)
			(fill
				(thermal_gap 0.5)
				(thermal_bridge_width 0.5)
				(island_removal_mode 0)
			)
			(polygon
				(pts
					(xy 61.926724 -346.967556) (xy 61.926724 -349.024956) (xy 60.072524 -349.024956) (xy 60.072524 -348.78391)
					(xy 59.830208 -348.78391) (xy 59.830208 -349.265494) (xy 63.636652 -349.265494) (xy 63.636652 -349.080582)
					(xy 62.218062 -349.080582) (xy 62.218062 -346.921582) (xy 64.374776 -346.921582) (xy 64.374776 -346.6719)
					(xy 62.22238 -346.6719)
				)
			)
		)
	)
	(footprint ""
		(layer "F.Cu")
		(at 164.740844 -370.57203 -90)
		(property "Reference" "C749"
			(at 0 0 270)
			(layer "F.SilkS")
			(hide yes)
			(effects
				(font
					(size 1.27 1.27)
				)
			)
		)
		(property "Value" ""
			(at 0 0 270)
			(layer "F.Fab")
			(effects
				(font
					(size 1.27 1.27)
				)
			)
		)
		(duplicate_pad_numbers_are_jumpers no)
		(fp_line
			(start -0.299974 0.150114)
			(end -0.299974 -0.150114)
			(stroke
				(width 0.1)
				(type default)
			)
			(layer "F.Fab")
		)
		(fp_line
			(start 0.299974 0.150114)
			(end -0.299974 0.150114)
			(stroke
				(width 0.1)
				(type default)
			)
			(layer "F.Fab")
		)
		(fp_line
			(start -0.299974 -0.150114)
			(end 0.299974 -0.150114)
			(stroke
				(width 0.1)
				(type default)
			)
			(layer "F.Fab")
		)
		(fp_line
			(start 0.299974 -0.150114)
			(end 0.299974 0.150114)
			(stroke
				(width 0.1)
				(type default)
			)
			(layer "F.Fab")
		)
		(pad "1" smd rect
			(at -0.2667 0 270)
			(size 0.3048 0.381)
			(layers "F.Cu" "F.Mask" "F.Paste")
			(net "P5E_CPU1_P2_TX_C_DP<12>")
		)
		(pad "2" smd rect
			(at 0.2667 0 270)
			(size 0.3048 0.381)
			(layers "F.Cu" "F.Mask" "F.Paste")
			(net "P5E_CPU1_P2_TX_DP<12>")
		)
	)
	(footprint ""
		(layer "F.Cu")
		(at 342.799924 -61.999876 180)
		(property "Reference" "J5"
			(at 4.821428 -2.025904 0)
			(unlocked yes)
			(layer "F.SilkS")
			(effects
				(font
					(size 0.7874 0.5842)
					(thickness 0.1524)
				)
			)
		)
		(property "Value" ""
			(at 0 0 180)
			(layer "F.Fab")
			(effects
				(font
					(size 1.27 1.27)
				)
			)
		)
		(duplicate_pad_numbers_are_jumpers no)
		(fp_line
			(start 1.700022 2.739898)
			(end -1.700022 2.739898)
			(stroke
				(width 0.1524)
				(type default)
			)
			(layer "F.SilkS")
		)
		(fp_line
			(start 1.700022 2.4257)
			(end 1.700022 2.739898)
			(stroke
				(width 0.1524)
				(type default)
			)
			(layer "F.SilkS")
		)
		(fp_line
			(start 1.700022 1.1557)
			(end 1.700022 1.3843)
			(stroke
				(width 0.1524)
				(type default)
			)
			(layer "F.SilkS")
		)
		(fp_line
			(start 1.700022 -0.1143)
			(end 1.700022 0.1143)
			(stroke
				(width 0.1524)
				(type default)
			)
			(layer "F.SilkS")
		)
		(fp_line
			(start 1.700022 -1.3843)
			(end 1.700022 -1.1557)
			(stroke
				(width 0.1524)
				(type default)
			)
			(layer "F.SilkS")
		)
		(fp_line
			(start 1.700022 -2.739898)
			(end 1.700022 -2.4257)
			(stroke
				(width 0.1524)
				(type default)
			)
			(layer "F.SilkS")
		)
		(fp_line
			(start -1.700022 2.739898)
			(end -1.700022 2.4257)
			(stroke
				(width 0.1524)
				(type default)
			)
			(layer "F.SilkS")
		)
		(fp_line
			(start -1.700022 1.3843)
			(end -1.700022 1.1557)
			(stroke
				(width 0.1524)
				(type default)
			)
			(layer "F.SilkS")
		)
		(fp_line
			(start -1.700022 0.1143)
			(end -1.700022 -0.1143)
			(stroke
				(width 0.1524)
				(type default)
			)
			(layer "F.SilkS")
		)
		(fp_line
			(start -1.700022 -1.1557)
			(end -1.700022 -1.3843)
			(stroke
				(width 0.1524)
				(type default)
			)
			(layer "F.SilkS")
		)
		(fp_line
			(start -1.700022 -2.4257)
			(end -1.700022 -2.739898)
			(stroke
				(width 0.1524)
				(type default)
			)
			(layer "F.SilkS")
		)
		(fp_line
			(start -1.700022 -2.739898)
			(end 1.700022 -2.739898)
			(stroke
				(width 0.1524)
				(type default)
			)
			(layer "F.SilkS")
		)
		(fp_poly
			(pts
				(xy -3.383534 -1.905) (xy -4.399534 -1.397) (xy -4.399534 -2.413)
			)
			(stroke
				(width 0)
				(type default)
			)
			(fill yes)
			(layer "F.SilkS")
		)
		(fp_line
			(start 1.700022 2.739898)
			(end -1.700022 2.739898)
			(stroke
				(width 0.1)
				(type default)
			)
			(layer "F.Fab")
		)
		(fp_line
			(start 1.700022 -2.739898)
			(end 1.700022 2.739898)
			(stroke
				(width 0.1)
				(type default)
			)
			(layer "F.Fab")
		)
		(fp_line
			(start -1.700022 2.739898)
			(end -1.700022 -2.739898)
			(stroke
				(width 0.1)
				(type default)
			)
			(layer "F.Fab")
		)
		(fp_line
			(start -1.700022 -2.739898)
			(end 1.700022 -2.739898)
			(stroke
				(width 0.1)
				(type default)
			)
			(layer "F.Fab")
		)
		(fp_poly
			(pts
				(xy -4.399534 -2.413) (xy -4.399534 -1.397) (xy -3.383534 -1.905)
			)
			(stroke
				(width 0)
				(type default)
			)
			(fill yes)
			(layer "F.Fab")
		)
		(pad "1" smd rect
			(at -2.050034 -1.905 90)
			(size 0.762 2.413)
			(layers "F.Cu" "F.Mask" "F.Paste")
			(net "CPU0_XTRIG_R1_L4")
		)
		(pad "2" smd rect
			(at 2.050034 -1.905 90)
			(size 0.762 2.413)
			(layers "F.Cu" "F.Mask" "F.Paste")
			(net "GND")
		)
		(pad "3" smd rect
			(at -2.050034 -0.635 90)
			(size 0.762 2.413)
			(layers "F.Cu" "F.Mask" "F.Paste")
			(net "CPU0_XTRIG_R1_L5")
		)
		(pad "4" smd rect
			(at 2.050034 -0.635 90)
			(size 0.762 2.413)
			(layers "F.Cu" "F.Mask" "F.Paste")
			(net "GND")
		)
		(pad "5" smd rect
			(at -2.050034 0.635 90)
			(size 0.762 2.413)
			(layers "F.Cu" "F.Mask" "F.Paste")
			(net "CPU0_XTRIG_R1_L6")
		)
		(pad "6" smd rect
			(at 2.050034 0.635 90)
			(size 0.762 2.413)
			(layers "F.Cu" "F.Mask" "F.Paste")
			(net "GND")
		)
		(pad "7" smd rect
			(at -2.050034 1.905 90)
			(size 0.762 2.413)
			(layers "F.Cu" "F.Mask" "F.Paste")
			(net "CPU0_XTRIG_R1_L7")
		)
		(pad "8" smd rect
			(at 2.050034 1.905 90)
			(size 0.762 2.413)
			(layers "F.Cu" "F.Mask" "F.Paste")
			(net "GND")
		)
	)
	(footprint ""
		(layer "F.Cu")
		(at 171.196 -106.136948 180)
		(property "Reference" "R164"
			(at 0 0 180)
			(layer "F.SilkS")
			(hide yes)
			(effects
				(font
					(size 1.27 1.27)
				)
			)
		)
		(property "Value" ""
			(at 0 0 180)
			(layer "F.Fab")
			(effects
				(font
					(size 1.27 1.27)
				)
			)
		)
		(duplicate_pad_numbers_are_jumpers no)
		(fp_line
			(start 0.7874 0.4064)
			(end -0.7874 0.4064)
			(stroke
				(width 0.1524)
				(type default)
			)
			(layer "F.SilkS")
		)
		(fp_line
			(start 0.7874 -0.4064)
			(end 0.7874 0.4064)
			(stroke
				(width 0.1524)
				(type default)
			)
			(layer "F.SilkS")
		)
		(fp_line
			(start -0.7874 0.4064)
			(end -0.7874 -0.4064)
			(stroke
				(width 0.1524)
				(type default)
			)
			(layer "F.SilkS")
		)
		(fp_line
			(start -0.7874 -0.4064)
			(end 0.7874 -0.4064)
			(stroke
				(width 0.1524)
				(type default)
			)
			(layer "F.SilkS")
		)
		(fp_line
			(start 0.67945 0.3048)
			(end 0.120396 0.3048)
			(stroke
				(width 0.1)
				(type default)
			)
			(layer "F.Fab")
		)
		(fp_line
			(start 0.67945 -0.3048)
			(end 0.67945 0.3048)
			(stroke
				(width 0.1)
				(type default)
			)
			(layer "F.Fab")
		)
		(fp_line
			(start 0.12065 -0.2794)
			(end 0.12065 -0.3048)
			(stroke
				(width 0.1)
				(type default)
			)
			(layer "F.Fab")
		)
		(fp_line
			(start 0.12065 -0.3048)
			(end 0.67945 -0.3048)
			(stroke
				(width 0.1)
				(type default)
			)
			(layer "F.Fab")
		)
		(fp_line
			(start 0.120396 0.3048)
			(end 0.120396 0.2794)
			(stroke
				(width 0.1)
				(type default)
			)
			(layer "F.Fab")
		)
		(fp_line
			(start 0.120396 0.2794)
			(end -0.12065 0.2794)
			(stroke
				(width 0.1)
				(type default)
			)
			(layer "F.Fab")
		)
		(fp_line
			(start -0.12065 0.3048)
			(end -0.67945 0.3048)
			(stroke
				(width 0.1)
				(type default)
			)
			(layer "F.Fab")
		)
		(fp_line
			(start -0.12065 0.2794)
			(end -0.12065 0.3048)
			(stroke
				(width 0.1)
				(type default)
			)
			(layer "F.Fab")
		)
		(fp_line
			(start -0.12065 -0.2794)
			(end 0.12065 -0.2794)
			(stroke
				(width 0.1)
				(type default)
			)
			(layer "F.Fab")
		)
		(fp_line
			(start -0.12065 -0.305054)
			(end -0.12065 -0.2794)
			(stroke
				(width 0.1)
				(type default)
			)
			(layer "F.Fab")
		)
		(fp_line
			(start -0.67945 0.3048)
			(end -0.67945 -0.305054)
			(stroke
				(width 0.1)
				(type default)
			)
			(layer "F.Fab")
		)
		(fp_line
			(start -0.67945 -0.305054)
			(end -0.12065 -0.305054)
			(stroke
				(width 0.1)
				(type default)
			)
			(layer "F.Fab")
		)
		(pad "1" smd circle
			(at -0.40005 0 180)
			(size 0 0)
			(layers "F.Cu" "F.Mask" "F.Paste")
			(net "FM_I3C_CPU0_MUX0_R_SEL")
		)
		(pad "2" smd circle
			(at 0.40005 0 180)
			(size 0 0)
			(layers "F.Cu" "F.Mask" "F.Paste")
			(net "FM_I3C_CPU0_MUX0_SEL")
		)
	)
	(footprint ""
		(layer "F.Cu")
		(at 444.36792 -437.428132 90)
		(property "Reference" "R4165"
			(at 0 0 90)
			(layer "F.SilkS")
			(hide yes)
			(effects
				(font
					(size 1.27 1.27)
				)
			)
		)
		(property "Value" ""
			(at 0 0 90)
			(layer "F.Fab")
			(effects
				(font
					(size 1.27 1.27)
				)
			)
		)
		(duplicate_pad_numbers_are_jumpers no)
		(fp_line
			(start 0.7874 -0.4064)
			(end 0.7874 0.4064)
			(stroke
				(width 0.1524)
				(type default)
			)
			(layer "F.SilkS")
		)
		(fp_line
			(start -0.7874 -0.4064)
			(end 0.7874 -0.4064)
			(stroke
				(width 0.1524)
				(type default)
			)
			(layer "F.SilkS")
		)
		(fp_line
			(start 0.7874 0.4064)
			(end -0.7874 0.4064)
			(stroke
				(width 0.1524)
				(type default)
			)
			(layer "F.SilkS")
		)
		(fp_line
			(start -0.7874 0.4064)
			(end -0.7874 -0.4064)
			(stroke
				(width 0.1524)
				(type default)
			)
			(layer "F.SilkS")
		)
		(fp_line
			(start -0.12065 -0.305054)
			(end -0.12065 -0.2794)
			(stroke
				(width 0.1)
				(type default)
			)
			(layer "F.Fab")
		)
		(fp_line
			(start -0.67945 -0.305054)
			(end -0.12065 -0.305054)
			(stroke
				(width 0.1)
				(type default)
			)
			(layer "F.Fab")
		)
		(fp_line
			(start 0.67945 -0.3048)
			(end 0.67945 0.3048)
			(stroke
				(width 0.1)
				(type default)
			)
			(layer "F.Fab")
		)
		(fp_line
			(start 0.12065 -0.3048)
			(end 0.67945 -0.3048)
			(stroke
				(width 0.1)
				(type default)
			)
			(layer "F.Fab")
		)
		(fp_line
			(start 0.12065 -0.2794)
			(end 0.12065 -0.3048)
			(stroke
				(width 0.1)
				(type default)
			)
			(layer "F.Fab")
		)
		(fp_line
			(start -0.12065 -0.2794)
			(end 0.12065 -0.2794)
			(stroke
				(width 0.1)
				(type default)
			)
			(layer "F.Fab")
		)
		(fp_line
			(start 0.120396 0.2794)
			(end -0.12065 0.2794)
			(stroke
				(width 0.1)
				(type default)
			)
			(layer "F.Fab")
		)
		(fp_line
			(start -0.12065 0.2794)
			(end -0.12065 0.3048)
			(stroke
				(width 0.1)
				(type default)
			)
			(layer "F.Fab")
		)
		(fp_line
			(start 0.67945 0.3048)
			(end 0.120396 0.3048)
			(stroke
				(width 0.1)
				(type default)
			)
			(layer "F.Fab")
		)
		(fp_line
			(start 0.120396 0.3048)
			(end 0.120396 0.2794)
			(stroke
				(width 0.1)
				(type default)
			)
			(layer "F.Fab")
		)
		(fp_line
			(start -0.12065 0.3048)
			(end -0.67945 0.3048)
			(stroke
				(width 0.1)
				(type default)
			)
			(layer "F.Fab")
		)
		(fp_line
			(start -0.67945 0.3048)
			(end -0.67945 -0.305054)
			(stroke
				(width 0.1)
				(type default)
			)
			(layer "F.Fab")
		)
		(pad "1" smd circle
			(at -0.40005 0 90)
			(size 0 0)
			(layers "F.Cu" "F.Mask" "F.Paste")
			(net "P3V3_AUX")
		)
		(pad "2" smd circle
			(at 0.40005 0 90)
			(size 0 0)
			(layers "F.Cu" "F.Mask" "F.Paste")
			(net "GPU_3V3IO_RSVD4_N")
		)
	)
	(footprint ""
		(layer "F.Cu")
		(at 148.494242 -110.731046)
		(property "Reference" "R996"
			(at 0 0 0)
			(layer "F.SilkS")
			(hide yes)
			(effects
				(font
					(size 1.27 1.27)
				)
			)
		)
		(property "Value" ""
			(at 0 0 0)
			(layer "F.Fab")
			(effects
				(font
					(size 1.27 1.27)
				)
			)
		)
		(duplicate_pad_numbers_are_jumpers no)
		(fp_line
			(start -0.7874 -0.4064)
			(end 0.7874 -0.4064)
			(stroke
				(width 0.1524)
				(type default)
			)
			(layer "F.SilkS")
		)
		(fp_line
			(start -0.7874 0.4064)
			(end -0.7874 -0.4064)
			(stroke
				(width 0.1524)
				(type default)
			)
			(layer "F.SilkS")
		)
		(fp_line
			(start 0.7874 -0.4064)
			(end 0.7874 0.4064)
			(stroke
				(width 0.1524)
				(type default)
			)
			(layer "F.SilkS")
		)
		(fp_line
			(start 0.7874 0.4064)
			(end -0.7874 0.4064)
			(stroke
				(width 0.1524)
				(type default)
			)
			(layer "F.SilkS")
		)
		(fp_line
			(start -0.67945 -0.305054)
			(end -0.12065 -0.305054)
			(stroke
				(width 0.1)
				(type default)
			)
			(layer "F.Fab")
		)
		(fp_line
			(start -0.67945 0.3048)
			(end -0.67945 -0.305054)
			(stroke
				(width 0.1)
				(type default)
			)
			(layer "F.Fab")
		)
		(fp_line
			(start -0.12065 -0.305054)
			(end -0.12065 -0.2794)
			(stroke
				(width 0.1)
				(type default)
			)
			(layer "F.Fab")
		)
		(fp_line
			(start -0.12065 -0.2794)
			(end 0.12065 -0.2794)
			(stroke
				(width 0.1)
				(type default)
			)
			(layer "F.Fab")
		)
		(fp_line
			(start -0.12065 0.2794)
			(end -0.12065 0.3048)
			(stroke
				(width 0.1)
				(type default)
			)
			(layer "F.Fab")
		)
		(fp_line
			(start -0.12065 0.3048)
			(end -0.67945 0.3048)
			(stroke
				(width 0.1)
				(type default)
			)
			(layer "F.Fab")
		)
		(fp_line
			(start 0.120396 0.2794)
			(end -0.12065 0.2794)
			(stroke
				(width 0.1)
				(type default)
			)
			(layer "F.Fab")
		)
		(fp_line
			(start 0.120396 0.3048)
			(end 0.120396 0.2794)
			(stroke
				(width 0.1)
				(type default)
			)
			(layer "F.Fab")
		)
		(fp_line
			(start 0.12065 -0.3048)
			(end 0.67945 -0.3048)
			(stroke
				(width 0.1)
				(type default)
			)
			(layer "F.Fab")
		)
		(fp_line
			(start 0.12065 -0.2794)
			(end 0.12065 -0.3048)
			(stroke
				(width 0.1)
				(type default)
			)
			(layer "F.Fab")
		)
		(fp_line
			(start 0.67945 -0.3048)
			(end 0.67945 0.3048)
			(stroke
				(width 0.1)
				(type default)
			)
			(layer "F.Fab")
		)
		(fp_line
			(start 0.67945 0.3048)
			(end 0.120396 0.3048)
			(stroke
				(width 0.1)
				(type default)
			)
			(layer "F.Fab")
		)
		(pad "1" smd circle
			(at -0.40005 0)
			(size 0 0)
			(layers "F.Cu" "F.Mask" "F.Paste")
			(net "P1V8_AUX")
		)
		(pad "2" smd circle
			(at 0.40005 0)
			(size 0 0)
			(layers "F.Cu" "F.Mask" "F.Paste")
			(net "SCM_IRQ_1V8_N")
		)
	)
	(footprint ""
		(layer "F.Cu")
		(at 266.862306 -333.031846)
		(property "Reference" "TP2"
			(at -5.423916 0.05207 0)
			(unlocked yes)
			(layer "F.SilkS")
			(effects
				(font
					(size 0.7874 0.5842)
					(thickness 0.1524)
				)
				(justify left)
			)
		)
		(property "Value" ""
			(at 0 0 0)
			(layer "F.Fab")
			(effects
				(font
					(size 1.27 1.27)
				)
			)
		)
		(duplicate_pad_numbers_are_jumpers no)
		(pad "1" smd circle
			(at 0 0)
			(size 0.762 0.762)
			(layers "F.Cu" "F.Mask" "F.Paste")
			(net "VSENSE_VSS_SENSE_B_P0")
		)
	)
	(footprint ""
		(layer "F.Cu")
		(at 62.47257 -37.307266 180)
		(property "Reference" "Q118"
			(at 1.09982 -1.964944 0)
			(unlocked yes)
			(layer "F.SilkS")
			(effects
				(font
					(size 0.7874 0.5842)
					(thickness 0.1524)
				)
				(justify left)
			)
		)
		(property "Value" ""
			(at 0 0 180)
			(layer "F.Fab")
			(effects
				(font
					(size 1.27 1.27)
				)
			)
		)
		(duplicate_pad_numbers_are_jumpers no)
		(fp_line
			(start 1.332738 1.100074)
			(end -1.332738 1.100074)
			(stroke
				(width 0.1524)
				(type default)
			)
			(layer "F.SilkS")
		)
		(fp_line
			(start 1.332738 -1.100074)
			(end 1.332738 1.100074)
			(stroke
				(width 0.1524)
				(type default)
			)
			(layer "F.SilkS")
		)
		(fp_line
			(start 0.4826 -1.100074)
			(end 1.332738 -1.100074)
			(stroke
				(width 0.1524)
				(type default)
			)
			(layer "F.SilkS")
		)
		(fp_line
			(start 0 -0.541274)
			(end 0.4826 -1.100074)
			(stroke
				(width 0.1524)
				(type default)
			)
			(layer "F.SilkS")
		)
		(fp_line
			(start -0.4826 -1.100074)
			(end 0 -0.541274)
			(stroke
				(width 0.1524)
				(type default)
			)
			(layer "F.SilkS")
		)
		(fp_line
			(start -1.332738 1.100074)
			(end -1.332738 -1.100074)
			(stroke
				(width 0.1524)
				(type default)
			)
			(layer "F.SilkS")
		)
		(fp_line
			(start -1.332738 -1.100074)
			(end -0.4826 -1.100074)
			(stroke
				(width 0.1524)
				(type default)
			)
			(layer "F.SilkS")
		)
		(fp_poly
			(pts
				(xy -1.945132 -0.676402) (xy -2.647188 -0.325374) (xy -2.647188 -1.02743)
			)
			(stroke
				(width 0)
				(type default)
			)
			(fill yes)
			(layer "F.SilkS")
		)
		(fp_line
			(start 0.674878 1.100074)
			(end -0.674878 1.100074)
			(stroke
				(width 0.1)
				(type default)
			)
			(layer "F.Fab")
		)
		(fp_line
			(start 0.674878 -1.100074)
			(end 0.674878 1.100074)
			(stroke
				(width 0.1)
				(type default)
			)
			(layer "F.Fab")
		)
		(fp_line
			(start -0.674878 1.100074)
			(end -0.674878 -1.100074)
			(stroke
				(width 0.1)
				(type default)
			)
			(layer "F.Fab")
		)
		(fp_line
			(start -0.674878 -1.100074)
			(end 0.674878 -1.100074)
			(stroke
				(width 0.1)
				(type default)
			)
			(layer "F.Fab")
		)
		(fp_poly
			(pts
				(xy -2.2352 -0.298958) (xy -2.2352 -1.001014) (xy -1.533144 -0.649986)
			)
			(stroke
				(width 0)
				(type default)
			)
			(fill yes)
			(layer "F.Fab")
		)
		(pad "1" smd rect
			(at -0.94996 -0.649986 270)
			(size 0.4318 0.508)
			(layers "F.Cu" "F.Mask" "F.Paste")
			(net "GND")
		)
		(pad "2" smd rect
			(at -0.94996 0 270)
			(size 0.4318 0.508)
			(layers "F.Cu" "F.Mask" "F.Paste")
			(net "P12V_OCP_EN_2_R")
		)
		(pad "3" smd rect
			(at -0.94996 0.649986 270)
			(size 0.4318 0.508)
			(layers "F.Cu" "F.Mask" "F.Paste")
			(net "P12V_OCP_UV_2_R")
		)
		(pad "4" smd rect
			(at 0.94996 0.649986 270)
			(size 0.4318 0.508)
			(layers "F.Cu" "F.Mask" "F.Paste")
			(net "GND")
		)
		(pad "5" smd rect
			(at 0.94996 0 270)
			(size 0.4318 0.508)
			(layers "F.Cu" "F.Mask" "F.Paste")
			(net "P12V_OCP_2_EN_G")
		)
		(pad "6" smd rect
			(at 0.94996 -0.649986 270)
			(size 0.4318 0.508)
			(layers "F.Cu" "F.Mask" "F.Paste")
			(net "P12V_OCP_2_EN_G")
		)
	)
	(footprint ""
		(layer "F.Cu")
		(at 488.03433 -142.808198 90)
		(property "Reference" "X8010"
			(at -1.947672 1.593342 0)
			(unlocked yes)
			(layer "F.SilkS")
			(effects
				(font
					(size 0.7874 0.5842)
					(thickness 0.1524)
				)
				(justify left)
			)
		)
		(property "Value" ""
			(at 0 0 90)
			(layer "F.Fab")
			(effects
				(font
					(size 1.27 1.27)
				)
			)
		)
		(property "Device Type" "TP_TDR_4P_FTS_TH-TP_TDR_4P_DIP,EMPTY,TP15"
			(at 1.30175 1.27 180)
			(unlocked yes)
			(layer "F.Fab")
			(hide yes)
			(effects
				(font
					(size 0.635 0.4064)
					(thickness 0.1524)
				)
			)
		)
		(property "User Part Number" "N_A"
			(at 1.30175 1.27 180)
			(unlocked yes)
			(layer "Cmts.User")
			(hide yes)
			(effects
				(font
					(size 0.635 0.4064)
					(thickness 0.1524)
				)
			)
		)
		(duplicate_pad_numbers_are_jumpers no)
		(fp_line
			(start 2.54 -1.27)
			(end 0 -1.27)
			(stroke
				(width 0.1524)
				(type default)
			)
			(layer "F.SilkS")
		)
		(fp_line
			(start 0 -1.27)
			(end 0 -0.635)
			(stroke
				(width 0.1524)
				(type default)
			)
			(layer "F.SilkS")
		)
		(fp_line
			(start 2.54 -1.1303)
			(end 2.54 -1.27)
			(stroke
				(width 0.1524)
				(type default)
			)
			(layer "F.SilkS")
		)
		(fp_line
			(start 0 0.635)
			(end 0 1.905)
			(stroke
				(width 0.1524)
				(type default)
			)
			(layer "F.SilkS")
		)
		(fp_line
			(start 2.54 1.4097)
			(end 2.54 1.1303)
			(stroke
				(width 0.1524)
				(type default)
			)
			(layer "F.SilkS")
		)
		(fp_line
			(start 0 3.175)
			(end 0 3.81)
			(stroke
				(width 0.1524)
				(type default)
			)
			(layer "F.SilkS")
		)
		(fp_line
			(start 2.54 3.81)
			(end 2.54 3.6703)
			(stroke
				(width 0.1524)
				(type default)
			)
			(layer "F.SilkS")
		)
		(fp_line
			(start 0 3.81)
			(end 2.54 3.81)
			(stroke
				(width 0.1524)
				(type default)
			)
			(layer "F.SilkS")
		)
		(fp_poly
			(pts
				(xy -2.285746 -0.762) (xy -0.761746 0) (xy -2.285746 0.762)
			)
			(stroke
				(width 0)
				(type default)
			)
			(fill yes)
			(layer "F.SilkS")
		)
		(fp_line
			(start 2.54 -1.27)
			(end 0 -1.27)
			(stroke
				(width 0.1)
				(type default)
			)
			(layer "F.Fab")
		)
		(fp_line
			(start 0 -1.27)
			(end 0 3.81)
			(stroke
				(width 0.1)
				(type default)
			)
			(layer "F.Fab")
		)
		(fp_line
			(start 2.54 3.81)
			(end 2.54 -1.27)
			(stroke
				(width 0.1)
				(type default)
			)
			(layer "F.Fab")
		)
		(fp_line
			(start 0 3.81)
			(end 2.54 3.81)
			(stroke
				(width 0.1)
				(type default)
			)
			(layer "F.Fab")
		)
		(fp_poly
			(pts
				(xy -0.761746 0) (xy -2.285746 -0.762) (xy -2.285746 0.762)
			)
			(stroke
				(width 0)
				(type default)
			)
			(fill yes)
			(layer "F.Fab")
		)
		(pad "1" thru_hole circle
			(at 0 0 90)
			(size 1.0033 1.0033)
			(drill 0.249936)
			(layers "*.Cu" "*.Mask")
			(remove_unused_layers no)
			(net "TDR_DIFF_85_IN3_DN")
			(clearance 0.10795)
			(thermal_gap 0.10795)
			(padstack
				(mode front_inner_back)
				(layer "Inner"
					(shape circle)
					(size 0.8001 0.8001)
					(clearance 0.1524)
				)
				(layer "B.Cu"
					(shape circle)
					(size 1.0033 1.0033)
					(clearance 0.10795)
				)
			)
		)
		(pad "2" thru_hole circle
			(at 2.54 0 90)
			(size 1.9939 1.9939)
			(drill 0.249936)
			(layers "*.Cu" "*.Mask")
			(remove_unused_layers no)
			(net "T1_GND")
			(clearance 0.10795)
			(thermal_gap 0.10795)
			(padstack
				(mode front_inner_back)
				(layer "Inner"
					(shape circle)
					(size 0.8001 0.8001)
					(clearance 0.1524)
				)
				(layer "B.Cu"
					(shape circle)
					(size 1.9939 1.9939)
					(clearance 0.10795)
				)
			)
		)
		(pad "3" thru_hole circle
			(at 2.54 2.54 90)
			(size 1.9939 1.9939)
			(drill 0.249936)
			(layers "*.Cu" "*.Mask")
			(remove_unused_layers no)
			(net "T1_GND")
			(clearance 0.10795)
			(thermal_gap 0.10795)
			(padstack
				(mode front_inner_back)
				(layer "Inner"
					(shape circle)
					(size 0.8001 0.8001)
					(clearance 0.1524)
				)
				(layer "B.Cu"
					(shape circle)
					(size 1.9939 1.9939)
					(clearance 0.10795)
				)
			)
		)
		(pad "4" thru_hole circle
			(at 0 2.54 90)
			(size 1.0033 1.0033)
			(drill 0.249936)
			(layers "*.Cu" "*.Mask")
			(remove_unused_layers no)
			(net "TDR_DIFF_85_IN3_DP")
			(clearance 0.10795)
			(thermal_gap 0.10795)
			(padstack
				(mode front_inner_back)
				(layer "Inner"
					(shape circle)
					(size 0.8001 0.8001)
					(clearance 0.1524)
				)
				(layer "B.Cu"
					(shape circle)
					(size 1.0033 1.0033)
					(clearance 0.10795)
				)
			)
		)
	)
	(footprint ""
		(layer "F.Cu")
		(at 307.470302 -427.141386 -90)
		(property "Reference" "Q133"
			(at 1.452372 -1.958848 90)
			(unlocked yes)
			(layer "F.SilkS")
			(effects
				(font
					(size 0.7874 0.5842)
					(thickness 0.1524)
				)
				(justify left)
			)
		)
		(property "Value" ""
			(at 0 0 270)
			(layer "F.Fab")
			(effects
				(font
					(size 1.27 1.27)
				)
			)
		)
		(duplicate_pad_numbers_are_jumpers no)
		(fp_line
			(start -1.332738 1.100074)
			(end -1.332738 -1.100074)
			(stroke
				(width 0.1524)
				(type default)
			)
			(layer "F.SilkS")
		)
		(fp_line
			(start 1.332738 1.100074)
			(end -1.332738 1.100074)
			(stroke
				(width 0.1524)
				(type default)
			)
			(layer "F.SilkS")
		)
		(fp_line
			(start 0 -0.541274)
			(end 0.4826 -1.100074)
			(stroke
				(width 0.1524)
				(type default)
			)
			(layer "F.SilkS")
		)
		(fp_line
			(start -1.332738 -1.100074)
			(end -0.4826 -1.100074)
			(stroke
				(width 0.1524)
				(type default)
			)
			(layer "F.SilkS")
		)
		(fp_line
			(start -0.4826 -1.100074)
			(end 0 -0.541274)
			(stroke
				(width 0.1524)
				(type default)
			)
			(layer "F.SilkS")
		)
		(fp_line
			(start 0.4826 -1.100074)
			(end 1.332738 -1.100074)
			(stroke
				(width 0.1524)
				(type default)
			)
			(layer "F.SilkS")
		)
		(fp_line
			(start 1.332738 -1.100074)
			(end 1.332738 1.100074)
			(stroke
				(width 0.1524)
				(type default)
			)
			(layer "F.SilkS")
		)
		(fp_poly
			(pts
				(xy -1.532636 -1.148334) (xy -2.277364 -1.396492) (xy -1.780794 -1.893062)
			)
			(stroke
				(width 0)
				(type default)
			)
			(fill yes)
			(layer "F.SilkS")
		)
		(fp_line
			(start -0.674878 1.100074)
			(end -0.674878 -1.100074)
			(stroke
				(width 0.1)
				(type default)
			)
			(layer "F.Fab")
		)
		(fp_line
			(start 0.674878 1.100074)
			(end -0.674878 1.100074)
			(stroke
				(width 0.1)
				(type default)
			)
			(layer "F.Fab")
		)
		(fp_line
			(start -0.674878 -1.100074)
			(end 0.674878 -1.100074)
			(stroke
				(width 0.1)
				(type default)
			)
			(layer "F.Fab")
		)
		(fp_line
			(start 0.674878 -1.100074)
			(end 0.674878 1.100074)
			(stroke
				(width 0.1)
				(type default)
			)
			(layer "F.Fab")
		)
		(fp_poly
			(pts
				(xy -2.2352 -0.298958) (xy -2.2352 -1.001014) (xy -1.533144 -0.649986)
			)
			(stroke
				(width 0)
				(type default)
			)
			(fill yes)
			(layer "F.Fab")
		)
		(pad "1" smd rect
			(at -0.94996 -0.649986)
			(size 0.4318 0.508)
			(layers "F.Cu" "F.Mask" "F.Paste")
			(net "GND")
		)
		(pad "2" smd rect
			(at -0.94996 0)
			(size 0.4318 0.508)
			(layers "F.Cu" "F.Mask" "F.Paste")
			(net "PRSNT_CABLE_GPU_A2_N")
		)
		(pad "3" smd rect
			(at -0.94996 0.649986)
			(size 0.4318 0.508)
			(layers "F.Cu" "F.Mask" "F.Paste")
			(net "PRSNT_CABLE_GPU_A2_ISO_N")
		)
		(pad "4" smd rect
			(at 0.94996 0.649986)
			(size 0.4318 0.508)
			(layers "F.Cu" "F.Mask" "F.Paste")
			(net "GND")
		)
		(pad "5" smd rect
			(at 0.94996 0)
			(size 0.4318 0.508)
			(layers "F.Cu" "F.Mask" "F.Paste")
			(net "PRSNT_CABLE_GPU_A2")
		)
		(pad "6" smd rect
			(at 0.94996 -0.649986)
			(size 0.4318 0.508)
			(layers "F.Cu" "F.Mask" "F.Paste")
			(net "PRSNT_CABLE_GPU_A2")
		)
	)
	(footprint ""
		(layer "F.Cu")
		(at 490.57433 7.610602 -90)
		(property "Reference" "X8004"
			(at -1.859788 4.892802 0)
			(unlocked yes)
			(layer "F.SilkS")
			(effects
				(font
					(size 0.7874 0.5842)
					(thickness 0.1524)
				)
				(justify left)
			)
		)
		(property "Value" ""
			(at 0 0 270)
			(layer "F.Fab")
			(effects
				(font
					(size 1.27 1.27)
				)
			)
		)
		(property "Device Type" "TP_TDR_4P_FTS_TH-TP_TDR_4P_DIP,EMPTY,TP15"
			(at 1.30175 1.27 0)
			(unlocked yes)
			(layer "F.Fab")
			(hide yes)
			(effects
				(font
					(size 0.635 0.4064)
					(thickness 0.1524)
				)
			)
		)
		(property "User Part Number" "N_A"
			(at 1.30175 1.27 0)
			(unlocked yes)
			(layer "Cmts.User")
			(hide yes)
			(effects
				(font
					(size 0.635 0.4064)
					(thickness 0.1524)
				)
			)
		)
		(duplicate_pad_numbers_are_jumpers no)
		(fp_line
			(start 0 3.81)
			(end 2.54 3.81)
			(stroke
				(width 0.1524)
				(type default)
			)
			(layer "F.SilkS")
		)
		(fp_line
			(start 2.54 3.81)
			(end 2.54 3.6703)
			(stroke
				(width 0.1524)
				(type default)
			)
			(layer "F.SilkS")
		)
		(fp_line
			(start 0 3.175)
			(end 0 3.81)
			(stroke
				(width 0.1524)
				(type default)
			)
			(layer "F.SilkS")
		)
		(fp_line
			(start 2.54 1.4097)
			(end 2.54 1.1303)
			(stroke
				(width 0.1524)
				(type default)
			)
			(layer "F.SilkS")
		)
		(fp_line
			(start 0 0.635)
			(end 0 1.905)
			(stroke
				(width 0.1524)
				(type default)
			)
			(layer "F.SilkS")
		)
		(fp_line
			(start 2.54 -1.1303)
			(end 2.54 -1.27)
			(stroke
				(width 0.1524)
				(type default)
			)
			(layer "F.SilkS")
		)
		(fp_line
			(start 0 -1.27)
			(end 0 -0.635)
			(stroke
				(width 0.1524)
				(type default)
			)
			(layer "F.SilkS")
		)
		(fp_line
			(start 2.54 -1.27)
			(end 0 -1.27)
			(stroke
				(width 0.1524)
				(type default)
			)
			(layer "F.SilkS")
		)
		(fp_poly
			(pts
				(xy -2.285746 -0.762) (xy -0.761746 0) (xy -2.285746 0.762)
			)
			(stroke
				(width 0)
				(type default)
			)
			(fill yes)
			(layer "F.SilkS")
		)
		(fp_line
			(start 0 3.81)
			(end 2.54 3.81)
			(stroke
				(width 0.1)
				(type default)
			)
			(layer "F.Fab")
		)
		(fp_line
			(start 2.54 3.81)
			(end 2.54 -1.27)
			(stroke
				(width 0.1)
				(type default)
			)
			(layer "F.Fab")
		)
		(fp_line
			(start 0 -1.27)
			(end 0 3.81)
			(stroke
				(width 0.1)
				(type default)
			)
			(layer "F.Fab")
		)
		(fp_line
			(start 2.54 -1.27)
			(end 0 -1.27)
			(stroke
				(width 0.1)
				(type default)
			)
			(layer "F.Fab")
		)
		(fp_poly
			(pts
				(xy -0.761746 0) (xy -2.285746 -0.762) (xy -2.285746 0.762)
			)
			(stroke
				(width 0)
				(type default)
			)
			(fill yes)
			(layer "F.Fab")
		)
		(pad "1" thru_hole circle
			(at 0 0 270)
			(size 1.0033 1.0033)
			(drill 0.249936)
			(layers "*.Cu" "*.Mask")
			(remove_unused_layers no)
			(net "TDR_DIFF_85_IN3_DP")
			(clearance 0.10795)
			(thermal_gap 0.10795)
			(padstack
				(mode front_inner_back)
				(layer "Inner"
					(shape circle)
					(size 0.8001 0.8001)
					(clearance 0.1524)
				)
				(layer "B.Cu"
					(shape circle)
					(size 1.0033 1.0033)
					(clearance 0.10795)
				)
			)
		)
		(pad "2" thru_hole circle
			(at 2.54 0 270)
			(size 1.9939 1.9939)
			(drill 0.249936)
			(layers "*.Cu" "*.Mask")
			(remove_unused_layers no)
			(net "T1_GND")
			(clearance 0.10795)
			(thermal_gap 0.10795)
			(padstack
				(mode front_inner_back)
				(layer "Inner"
					(shape circle)
					(size 0.8001 0.8001)
					(clearance 0.1524)
				)
				(layer "B.Cu"
					(shape circle)
					(size 1.9939 1.9939)
					(clearance 0.10795)
				)
			)
		)
		(pad "3" thru_hole circle
			(at 2.54 2.54 270)
			(size 1.9939 1.9939)
			(drill 0.249936)
			(layers "*.Cu" "*.Mask")
			(remove_unused_layers no)
			(net "T1_GND")
			(clearance 0.10795)
			(thermal_gap 0.10795)
			(padstack
				(mode front_inner_back)
				(layer "Inner"
					(shape circle)
					(size 0.8001 0.8001)
					(clearance 0.1524)
				)
				(layer "B.Cu"
					(shape circle)
					(size 1.9939 1.9939)
					(clearance 0.10795)
				)
			)
		)
		(pad "4" thru_hole circle
			(at 0 2.54 270)
			(size 1.0033 1.0033)
			(drill 0.249936)
			(layers "*.Cu" "*.Mask")
			(remove_unused_layers no)
			(net "TDR_DIFF_85_IN3_DN")
			(clearance 0.10795)
			(thermal_gap 0.10795)
			(padstack
				(mode front_inner_back)
				(layer "Inner"
					(shape circle)
					(size 0.8001 0.8001)
					(clearance 0.1524)
				)
				(layer "B.Cu"
					(shape circle)
					(size 1.0033 1.0033)
					(clearance 0.10795)
				)
			)
		)
	)
	(footprint ""
		(layer "F.Cu")
		(at 253.506224 -132.337556 180)
		(property "Reference" "R602"
			(at 0 0 180)
			(layer "F.SilkS")
			(hide yes)
			(effects
				(font
					(size 1.27 1.27)
				)
			)
		)
		(property "Value" ""
			(at 0 0 180)
			(layer "F.Fab")
			(effects
				(font
					(size 1.27 1.27)
				)
			)
		)
		(duplicate_pad_numbers_are_jumpers no)
		(fp_line
			(start 0.7874 0.4064)
			(end -0.7874 0.4064)
			(stroke
				(width 0.1524)
				(type default)
			)
			(layer "F.SilkS")
		)
		(fp_line
			(start 0.7874 -0.4064)
			(end 0.7874 0.4064)
			(stroke
				(width 0.1524)
				(type default)
			)
			(layer "F.SilkS")
		)
		(fp_line
			(start -0.7874 0.4064)
			(end -0.7874 -0.4064)
			(stroke
				(width 0.1524)
				(type default)
			)
			(layer "F.SilkS")
		)
		(fp_line
			(start -0.7874 -0.4064)
			(end 0.7874 -0.4064)
			(stroke
				(width 0.1524)
				(type default)
			)
			(layer "F.SilkS")
		)
		(fp_line
			(start 0.67945 0.3048)
			(end 0.120396 0.3048)
			(stroke
				(width 0.1)
				(type default)
			)
			(layer "F.Fab")
		)
		(fp_line
			(start 0.67945 -0.3048)
			(end 0.67945 0.3048)
			(stroke
				(width 0.1)
				(type default)
			)
			(layer "F.Fab")
		)
		(fp_line
			(start 0.12065 -0.2794)
			(end 0.12065 -0.3048)
			(stroke
				(width 0.1)
				(type default)
			)
			(layer "F.Fab")
		)
		(fp_line
			(start 0.12065 -0.3048)
			(end 0.67945 -0.3048)
			(stroke
				(width 0.1)
				(type default)
			)
			(layer "F.Fab")
		)
		(fp_line
			(start 0.120396 0.3048)
			(end 0.120396 0.2794)
			(stroke
				(width 0.1)
				(type default)
			)
			(layer "F.Fab")
		)
		(fp_line
			(start 0.120396 0.2794)
			(end -0.12065 0.2794)
			(stroke
				(width 0.1)
				(type default)
			)
			(layer "F.Fab")
		)
		(fp_line
			(start -0.12065 0.3048)
			(end -0.67945 0.3048)
			(stroke
				(width 0.1)
				(type default)
			)
			(layer "F.Fab")
		)
		(fp_line
			(start -0.12065 0.2794)
			(end -0.12065 0.3048)
			(stroke
				(width 0.1)
				(type default)
			)
			(layer "F.Fab")
		)
		(fp_line
			(start -0.12065 -0.2794)
			(end 0.12065 -0.2794)
			(stroke
				(width 0.1)
				(type default)
			)
			(layer "F.Fab")
		)
		(fp_line
			(start -0.12065 -0.305054)
			(end -0.12065 -0.2794)
			(stroke
				(width 0.1)
				(type default)
			)
			(layer "F.Fab")
		)
		(fp_line
			(start -0.67945 0.3048)
			(end -0.67945 -0.305054)
			(stroke
				(width 0.1)
				(type default)
			)
			(layer "F.Fab")
		)
		(fp_line
			(start -0.67945 -0.305054)
			(end -0.12065 -0.305054)
			(stroke
				(width 0.1)
				(type default)
			)
			(layer "F.Fab")
		)
		(pad "1" smd circle
			(at -0.40005 0 180)
			(size 0 0)
			(layers "F.Cu" "F.Mask" "F.Paste")
			(net "SPI_CPU0_LVC3_CLK")
		)
		(pad "2" smd circle
			(at 0.40005 0 180)
			(size 0 0)
			(layers "F.Cu" "F.Mask" "F.Paste")
			(net "SPI_CPU0_LVC3_SCM_CLK")
		)
	)
	(footprint ""
		(layer "F.Cu")
		(at 167.090344 -344.153998 -90)
		(property "Reference" "PR409"
			(at 0 0 270)
			(layer "F.SilkS")
			(hide yes)
			(effects
				(font
					(size 1.27 1.27)
				)
			)
		)
		(property "Value" ""
			(at 0 0 270)
			(layer "F.Fab")
			(effects
				(font
					(size 1.27 1.27)
				)
			)
		)
		(duplicate_pad_numbers_are_jumpers no)
		(fp_line
			(start -0.7874 0.4064)
			(end -0.7874 -0.4064)
			(stroke
				(width 0.1524)
				(type default)
			)
			(layer "F.SilkS")
		)
		(fp_line
			(start 0.7874 0.4064)
			(end -0.7874 0.4064)
			(stroke
				(width 0.1524)
				(type default)
			)
			(layer "F.SilkS")
		)
		(fp_line
			(start -0.7874 -0.4064)
			(end 0.7874 -0.4064)
			(stroke
				(width 0.1524)
				(type default)
			)
			(layer "F.SilkS")
		)
		(fp_line
			(start 0.7874 -0.4064)
			(end 0.7874 0.4064)
			(stroke
				(width 0.1524)
				(type default)
			)
			(layer "F.SilkS")
		)
		(fp_line
			(start -0.67945 0.3048)
			(end -0.67945 -0.305054)
			(stroke
				(width 0.1)
				(type default)
			)
			(layer "F.Fab")
		)
		(fp_line
			(start -0.12065 0.3048)
			(end -0.67945 0.3048)
			(stroke
				(width 0.1)
				(type default)
			)
			(layer "F.Fab")
		)
		(fp_line
			(start 0.120396 0.3048)
			(end 0.120396 0.2794)
			(stroke
				(width 0.1)
				(type default)
			)
			(layer "F.Fab")
		)
		(fp_line
			(start 0.67945 0.3048)
			(end 0.120396 0.3048)
			(stroke
				(width 0.1)
				(type default)
			)
			(layer "F.Fab")
		)
		(fp_line
			(start -0.12065 0.2794)
			(end -0.12065 0.3048)
			(stroke
				(width 0.1)
				(type default)
			)
			(layer "F.Fab")
		)
		(fp_line
			(start 0.120396 0.2794)
			(end -0.12065 0.2794)
			(stroke
				(width 0.1)
				(type default)
			)
			(layer "F.Fab")
		)
		(fp_line
			(start -0.12065 -0.2794)
			(end 0.12065 -0.2794)
			(stroke
				(width 0.1)
				(type default)
			)
			(layer "F.Fab")
		)
		(fp_line
			(start 0.12065 -0.2794)
			(end 0.12065 -0.3048)
			(stroke
				(width 0.1)
				(type default)
			)
			(layer "F.Fab")
		)
		(fp_line
			(start 0.12065 -0.3048)
			(end 0.67945 -0.3048)
			(stroke
				(width 0.1)
				(type default)
			)
			(layer "F.Fab")
		)
		(fp_line
			(start 0.67945 -0.3048)
			(end 0.67945 0.3048)
			(stroke
				(width 0.1)
				(type default)
			)
			(layer "F.Fab")
		)
		(fp_line
			(start -0.67945 -0.305054)
			(end -0.12065 -0.305054)
			(stroke
				(width 0.1)
				(type default)
			)
			(layer "F.Fab")
		)
		(fp_line
			(start -0.12065 -0.305054)
			(end -0.12065 -0.2794)
			(stroke
				(width 0.1)
				(type default)
			)
			(layer "F.Fab")
		)
		(pad "1" smd circle
			(at -0.40005 0 270)
			(size 0 0)
			(layers "F.Cu" "F.Mask" "F.Paste")
			(net "NC_PVDD11_S3_P1_IMON8")
		)
		(pad "2" smd circle
			(at 0.40005 0 270)
			(size 0 0)
			(layers "F.Cu" "F.Mask" "F.Paste")
			(net "GND")
		)
	)
	(footprint ""
		(layer "F.Cu")
		(at 107.363768 -340.08949 -90)
		(property "Reference" "PC140_6"
			(at 0 0 270)
			(layer "F.SilkS")
			(hide yes)
			(effects
				(font
					(size 1.27 1.27)
				)
			)
		)
		(property "Value" ""
			(at 0 0 270)
			(layer "F.Fab")
			(effects
				(font
					(size 1.27 1.27)
				)
			)
		)
		(duplicate_pad_numbers_are_jumpers no)
		(fp_line
			(start -0.7874 0.4064)
			(end -0.7874 -0.4064)
			(stroke
				(width 0.1524)
				(type default)
			)
			(layer "F.SilkS")
		)
		(fp_line
			(start 0.7874 0.4064)
			(end -0.7874 0.4064)
			(stroke
				(width 0.1524)
				(type default)
			)
			(layer "F.SilkS")
		)
		(fp_line
			(start -0.7874 -0.4064)
			(end 0.7874 -0.4064)
			(stroke
				(width 0.1524)
				(type default)
			)
			(layer "F.SilkS")
		)
		(fp_line
			(start 0.7874 -0.4064)
			(end 0.7874 0.4064)
			(stroke
				(width 0.1524)
				(type default)
			)
			(layer "F.SilkS")
		)
		(fp_line
			(start -0.67945 0.3048)
			(end -0.67945 -0.305054)
			(stroke
				(width 0.1)
				(type default)
			)
			(layer "F.Fab")
		)
		(fp_line
			(start -0.12065 0.3048)
			(end -0.67945 0.3048)
			(stroke
				(width 0.1)
				(type default)
			)
			(layer "F.Fab")
		)
		(fp_line
			(start 0.120396 0.3048)
			(end 0.120396 0.2794)
			(stroke
				(width 0.1)
				(type default)
			)
			(layer "F.Fab")
		)
		(fp_line
			(start 0.67945 0.3048)
			(end 0.120396 0.3048)
			(stroke
				(width 0.1)
				(type default)
			)
			(layer "F.Fab")
		)
		(fp_line
			(start -0.12065 0.2794)
			(end -0.12065 0.3048)
			(stroke
				(width 0.1)
				(type default)
			)
			(layer "F.Fab")
		)
		(fp_line
			(start 0.120396 0.2794)
			(end -0.12065 0.2794)
			(stroke
				(width 0.1)
				(type default)
			)
			(layer "F.Fab")
		)
		(fp_line
			(start -0.12065 -0.2794)
			(end 0.12065 -0.2794)
			(stroke
				(width 0.1)
				(type default)
			)
			(layer "F.Fab")
		)
		(fp_line
			(start 0.12065 -0.2794)
			(end 0.12065 -0.3048)
			(stroke
				(width 0.1)
				(type default)
			)
			(layer "F.Fab")
		)
		(fp_line
			(start 0.12065 -0.3048)
			(end 0.67945 -0.3048)
			(stroke
				(width 0.1)
				(type default)
			)
			(layer "F.Fab")
		)
		(fp_line
			(start 0.67945 -0.3048)
			(end 0.67945 0.3048)
			(stroke
				(width 0.1)
				(type default)
			)
			(layer "F.Fab")
		)
		(fp_line
			(start -0.67945 -0.305054)
			(end -0.12065 -0.305054)
			(stroke
				(width 0.1)
				(type default)
			)
			(layer "F.Fab")
		)
		(fp_line
			(start -0.12065 -0.305054)
			(end -0.12065 -0.2794)
			(stroke
				(width 0.1)
				(type default)
			)
			(layer "F.Fab")
		)
		(pad "1" smd circle
			(at -0.40005 0 270)
			(size 0 0)
			(layers "F.Cu" "F.Mask" "F.Paste")
			(net "SW_P12V_AUX_PVDDCR_CPU1_P1_FLT")
		)
		(pad "2" smd circle
			(at 0.40005 0 270)
			(size 0 0)
			(layers "F.Cu" "F.Mask" "F.Paste")
			(net "GND")
		)
	)
	(footprint ""
		(layer "F.Cu")
		(at 279.022556 -436.223664 90)
		(property "Reference" "R4554"
			(at 0 0 90)
			(layer "F.SilkS")
			(hide yes)
			(effects
				(font
					(size 1.27 1.27)
				)
			)
		)
		(property "Value" ""
			(at 0 0 90)
			(layer "F.Fab")
			(effects
				(font
					(size 1.27 1.27)
				)
			)
		)
		(duplicate_pad_numbers_are_jumpers no)
		(fp_line
			(start 0.7874 -0.4064)
			(end 0.7874 0.4064)
			(stroke
				(width 0.1524)
				(type default)
			)
			(layer "F.SilkS")
		)
		(fp_line
			(start -0.7874 -0.4064)
			(end 0.7874 -0.4064)
			(stroke
				(width 0.1524)
				(type default)
			)
			(layer "F.SilkS")
		)
		(fp_line
			(start 0.7874 0.4064)
			(end -0.7874 0.4064)
			(stroke
				(width 0.1524)
				(type default)
			)
			(layer "F.SilkS")
		)
		(fp_line
			(start -0.7874 0.4064)
			(end -0.7874 -0.4064)
			(stroke
				(width 0.1524)
				(type default)
			)
			(layer "F.SilkS")
		)
		(fp_line
			(start -0.12065 -0.305054)
			(end -0.12065 -0.2794)
			(stroke
				(width 0.1)
				(type default)
			)
			(layer "F.Fab")
		)
		(fp_line
			(start -0.67945 -0.305054)
			(end -0.12065 -0.305054)
			(stroke
				(width 0.1)
				(type default)
			)
			(layer "F.Fab")
		)
		(fp_line
			(start 0.67945 -0.3048)
			(end 0.67945 0.3048)
			(stroke
				(width 0.1)
				(type default)
			)
			(layer "F.Fab")
		)
		(fp_line
			(start 0.12065 -0.3048)
			(end 0.67945 -0.3048)
			(stroke
				(width 0.1)
				(type default)
			)
			(layer "F.Fab")
		)
		(fp_line
			(start 0.12065 -0.2794)
			(end 0.12065 -0.3048)
			(stroke
				(width 0.1)
				(type default)
			)
			(layer "F.Fab")
		)
		(fp_line
			(start -0.12065 -0.2794)
			(end 0.12065 -0.2794)
			(stroke
				(width 0.1)
				(type default)
			)
			(layer "F.Fab")
		)
		(fp_line
			(start 0.120396 0.2794)
			(end -0.12065 0.2794)
			(stroke
				(width 0.1)
				(type default)
			)
			(layer "F.Fab")
		)
		(fp_line
			(start -0.12065 0.2794)
			(end -0.12065 0.3048)
			(stroke
				(width 0.1)
				(type default)
			)
			(layer "F.Fab")
		)
		(fp_line
			(start 0.67945 0.3048)
			(end 0.120396 0.3048)
			(stroke
				(width 0.1)
				(type default)
			)
			(layer "F.Fab")
		)
		(fp_line
			(start 0.120396 0.3048)
			(end 0.120396 0.2794)
			(stroke
				(width 0.1)
				(type default)
			)
			(layer "F.Fab")
		)
		(fp_line
			(start -0.12065 0.3048)
			(end -0.67945 0.3048)
			(stroke
				(width 0.1)
				(type default)
			)
			(layer "F.Fab")
		)
		(fp_line
			(start -0.67945 0.3048)
			(end -0.67945 -0.305054)
			(stroke
				(width 0.1)
				(type default)
			)
			(layer "F.Fab")
		)
		(pad "1" smd circle
			(at -0.40005 0 90)
			(size 0 0)
			(layers "F.Cu" "F.Mask" "F.Paste")
			(net "P3V3_AUX")
		)
		(pad "2" smd circle
			(at 0.40005 0 90)
			(size 0 0)
			(layers "F.Cu" "F.Mask" "F.Paste")
			(net "HPDB_HSC_PWRGD_ISO")
		)
	)
	(footprint ""
		(layer "F.Cu")
		(at 166.624 -129.921 -90)
		(property "Reference" "R494"
			(at 0 0 270)
			(layer "F.SilkS")
			(hide yes)
			(effects
				(font
					(size 1.27 1.27)
				)
			)
		)
		(property "Value" ""
			(at 0 0 270)
			(layer "F.Fab")
			(effects
				(font
					(size 1.27 1.27)
				)
			)
		)
		(duplicate_pad_numbers_are_jumpers no)
		(fp_line
			(start -0.7874 0.4064)
			(end -0.7874 -0.4064)
			(stroke
				(width 0.1524)
				(type default)
			)
			(layer "F.SilkS")
		)
		(fp_line
			(start 0.7874 0.4064)
			(end -0.7874 0.4064)
			(stroke
				(width 0.1524)
				(type default)
			)
			(layer "F.SilkS")
		)
		(fp_line
			(start -0.7874 -0.4064)
			(end 0.7874 -0.4064)
			(stroke
				(width 0.1524)
				(type default)
			)
			(layer "F.SilkS")
		)
		(fp_line
			(start 0.7874 -0.4064)
			(end 0.7874 0.4064)
			(stroke
				(width 0.1524)
				(type default)
			)
			(layer "F.SilkS")
		)
		(fp_line
			(start -0.67945 0.3048)
			(end -0.67945 -0.305054)
			(stroke
				(width 0.1)
				(type default)
			)
			(layer "F.Fab")
		)
		(fp_line
			(start -0.12065 0.3048)
			(end -0.67945 0.3048)
			(stroke
				(width 0.1)
				(type default)
			)
			(layer "F.Fab")
		)
		(fp_line
			(start 0.120396 0.3048)
			(end 0.120396 0.2794)
			(stroke
				(width 0.1)
				(type default)
			)
			(layer "F.Fab")
		)
		(fp_line
			(start 0.67945 0.3048)
			(end 0.120396 0.3048)
			(stroke
				(width 0.1)
				(type default)
			)
			(layer "F.Fab")
		)
		(fp_line
			(start -0.12065 0.2794)
			(end -0.12065 0.3048)
			(stroke
				(width 0.1)
				(type default)
			)
			(layer "F.Fab")
		)
		(fp_line
			(start 0.120396 0.2794)
			(end -0.12065 0.2794)
			(stroke
				(width 0.1)
				(type default)
			)
			(layer "F.Fab")
		)
		(fp_line
			(start -0.12065 -0.2794)
			(end 0.12065 -0.2794)
			(stroke
				(width 0.1)
				(type default)
			)
			(layer "F.Fab")
		)
		(fp_line
			(start 0.12065 -0.2794)
			(end 0.12065 -0.3048)
			(stroke
				(width 0.1)
				(type default)
			)
			(layer "F.Fab")
		)
		(fp_line
			(start 0.12065 -0.3048)
			(end 0.67945 -0.3048)
			(stroke
				(width 0.1)
				(type default)
			)
			(layer "F.Fab")
		)
		(fp_line
			(start 0.67945 -0.3048)
			(end 0.67945 0.3048)
			(stroke
				(width 0.1)
				(type default)
			)
			(layer "F.Fab")
		)
		(fp_line
			(start -0.67945 -0.305054)
			(end -0.12065 -0.305054)
			(stroke
				(width 0.1)
				(type default)
			)
			(layer "F.Fab")
		)
		(fp_line
			(start -0.12065 -0.305054)
			(end -0.12065 -0.2794)
			(stroke
				(width 0.1)
				(type default)
			)
			(layer "F.Fab")
		)
		(pad "1" smd circle
			(at -0.40005 0 270)
			(size 0 0)
			(layers "F.Cu" "F.Mask" "F.Paste")
			(net "PWRGD_P5V_R_N")
		)
		(pad "2" smd circle
			(at 0.40005 0 270)
			(size 0 0)
			(layers "F.Cu" "F.Mask" "F.Paste")
			(net "PWRGD_P5V_N")
		)
	)
	(footprint ""
		(layer "F.Cu")
		(at 156.231844 -373.03583 -90)
		(property "Reference" "C757"
			(at 0 0 270)
			(layer "F.SilkS")
			(hide yes)
			(effects
				(font
					(size 1.27 1.27)
				)
			)
		)
		(property "Value" ""
			(at 0 0 270)
			(layer "F.Fab")
			(effects
				(font
					(size 1.27 1.27)
				)
			)
		)
		(duplicate_pad_numbers_are_jumpers no)
		(fp_line
			(start -0.299974 0.150114)
			(end -0.299974 -0.150114)
			(stroke
				(width 0.1)
				(type default)
			)
			(layer "F.Fab")
		)
		(fp_line
			(start 0.299974 0.150114)
			(end -0.299974 0.150114)
			(stroke
				(width 0.1)
				(type default)
			)
			(layer "F.Fab")
		)
		(fp_line
			(start -0.299974 -0.150114)
			(end 0.299974 -0.150114)
			(stroke
				(width 0.1)
				(type default)
			)
			(layer "F.Fab")
		)
		(fp_line
			(start 0.299974 -0.150114)
			(end 0.299974 0.150114)
			(stroke
				(width 0.1)
				(type default)
			)
			(layer "F.Fab")
		)
		(pad "1" smd rect
			(at -0.2667 0 270)
			(size 0.3048 0.381)
			(layers "F.Cu" "F.Mask" "F.Paste")
			(net "P5E_CPU1_P2_TX_C_DP<8>")
		)
		(pad "2" smd rect
			(at 0.2667 0 270)
			(size 0.3048 0.381)
			(layers "F.Cu" "F.Mask" "F.Paste")
			(net "P5E_CPU1_P2_TX_DP<8>")
		)
	)
	(footprint ""
		(layer "F.Cu")
		(at 208.894426 -106.513376)
		(property "Reference" "R6118"
			(at 0 0 0)
			(layer "F.SilkS")
			(hide yes)
			(effects
				(font
					(size 1.27 1.27)
				)
			)
		)
		(property "Value" ""
			(at 0 0 0)
			(layer "F.Fab")
			(effects
				(font
					(size 1.27 1.27)
				)
			)
		)
		(duplicate_pad_numbers_are_jumpers no)
		(fp_line
			(start -0.7874 -0.4064)
			(end 0.7874 -0.4064)
			(stroke
				(width 0.1524)
				(type default)
			)
			(layer "F.SilkS")
		)
		(fp_line
			(start -0.7874 0.4064)
			(end -0.7874 -0.4064)
			(stroke
				(width 0.1524)
				(type default)
			)
			(layer "F.SilkS")
		)
		(fp_line
			(start 0.7874 -0.4064)
			(end 0.7874 0.4064)
			(stroke
				(width 0.1524)
				(type default)
			)
			(layer "F.SilkS")
		)
		(fp_line
			(start 0.7874 0.4064)
			(end -0.7874 0.4064)
			(stroke
				(width 0.1524)
				(type default)
			)
			(layer "F.SilkS")
		)
		(fp_line
			(start -0.67945 -0.305054)
			(end -0.12065 -0.305054)
			(stroke
				(width 0.1)
				(type default)
			)
			(layer "F.Fab")
		)
		(fp_line
			(start -0.67945 0.3048)
			(end -0.67945 -0.305054)
			(stroke
				(width 0.1)
				(type default)
			)
			(layer "F.Fab")
		)
		(fp_line
			(start -0.12065 -0.305054)
			(end -0.12065 -0.2794)
			(stroke
				(width 0.1)
				(type default)
			)
			(layer "F.Fab")
		)
		(fp_line
			(start -0.12065 -0.2794)
			(end 0.12065 -0.2794)
			(stroke
				(width 0.1)
				(type default)
			)
			(layer "F.Fab")
		)
		(fp_line
			(start -0.12065 0.2794)
			(end -0.12065 0.3048)
			(stroke
				(width 0.1)
				(type default)
			)
			(layer "F.Fab")
		)
		(fp_line
			(start -0.12065 0.3048)
			(end -0.67945 0.3048)
			(stroke
				(width 0.1)
				(type default)
			)
			(layer "F.Fab")
		)
		(fp_line
			(start 0.120396 0.2794)
			(end -0.12065 0.2794)
			(stroke
				(width 0.1)
				(type default)
			)
			(layer "F.Fab")
		)
		(fp_line
			(start 0.120396 0.3048)
			(end 0.120396 0.2794)
			(stroke
				(width 0.1)
				(type default)
			)
			(layer "F.Fab")
		)
		(fp_line
			(start 0.12065 -0.3048)
			(end 0.67945 -0.3048)
			(stroke
				(width 0.1)
				(type default)
			)
			(layer "F.Fab")
		)
		(fp_line
			(start 0.12065 -0.2794)
			(end 0.12065 -0.3048)
			(stroke
				(width 0.1)
				(type default)
			)
			(layer "F.Fab")
		)
		(fp_line
			(start 0.67945 -0.3048)
			(end 0.67945 0.3048)
			(stroke
				(width 0.1)
				(type default)
			)
			(layer "F.Fab")
		)
		(fp_line
			(start 0.67945 0.3048)
			(end 0.120396 0.3048)
			(stroke
				(width 0.1)
				(type default)
			)
			(layer "F.Fab")
		)
		(pad "1" smd circle
			(at -0.40005 0)
			(size 0 0)
			(layers "F.Cu" "F.Mask" "F.Paste")
			(net "PWRGD_P5V_AUX_R3")
		)
		(pad "2" smd circle
			(at 0.40005 0)
			(size 0 0)
			(layers "F.Cu" "F.Mask" "F.Paste")
			(net "PWRGD_P5V_AUX_R2")
		)
	)
	(footprint ""
		(layer "F.Cu")
		(at 441.179966 -418.961824)
		(property "Reference" "PR6531"
			(at 0 0 0)
			(layer "F.SilkS")
			(hide yes)
			(effects
				(font
					(size 1.27 1.27)
				)
			)
		)
		(property "Value" ""
			(at 0 0 0)
			(layer "F.Fab")
			(effects
				(font
					(size 1.27 1.27)
				)
			)
		)
		(duplicate_pad_numbers_are_jumpers no)
		(fp_line
			(start -0.7874 -0.4064)
			(end 0.7874 -0.4064)
			(stroke
				(width 0.1524)
				(type default)
			)
			(layer "F.SilkS")
		)
		(fp_line
			(start -0.7874 0.4064)
			(end -0.7874 -0.4064)
			(stroke
				(width 0.1524)
				(type default)
			)
			(layer "F.SilkS")
		)
		(fp_line
			(start 0.7874 -0.4064)
			(end 0.7874 0.4064)
			(stroke
				(width 0.1524)
				(type default)
			)
			(layer "F.SilkS")
		)
		(fp_line
			(start 0.7874 0.4064)
			(end -0.7874 0.4064)
			(stroke
				(width 0.1524)
				(type default)
			)
			(layer "F.SilkS")
		)
		(fp_line
			(start -0.67945 -0.305054)
			(end -0.12065 -0.305054)
			(stroke
				(width 0.1)
				(type default)
			)
			(layer "F.Fab")
		)
		(fp_line
			(start -0.67945 0.3048)
			(end -0.67945 -0.305054)
			(stroke
				(width 0.1)
				(type default)
			)
			(layer "F.Fab")
		)
		(fp_line
			(start -0.12065 -0.305054)
			(end -0.12065 -0.2794)
			(stroke
				(width 0.1)
				(type default)
			)
			(layer "F.Fab")
		)
		(fp_line
			(start -0.12065 -0.2794)
			(end 0.12065 -0.2794)
			(stroke
				(width 0.1)
				(type default)
			)
			(layer "F.Fab")
		)
		(fp_line
			(start -0.12065 0.2794)
			(end -0.12065 0.3048)
			(stroke
				(width 0.1)
				(type default)
			)
			(layer "F.Fab")
		)
		(fp_line
			(start -0.12065 0.3048)
			(end -0.67945 0.3048)
			(stroke
				(width 0.1)
				(type default)
			)
			(layer "F.Fab")
		)
		(fp_line
			(start 0.120396 0.2794)
			(end -0.12065 0.2794)
			(stroke
				(width 0.1)
				(type default)
			)
			(layer "F.Fab")
		)
		(fp_line
			(start 0.120396 0.3048)
			(end 0.120396 0.2794)
			(stroke
				(width 0.1)
				(type default)
			)
			(layer "F.Fab")
		)
		(fp_line
			(start 0.12065 -0.3048)
			(end 0.67945 -0.3048)
			(stroke
				(width 0.1)
				(type default)
			)
			(layer "F.Fab")
		)
		(fp_line
			(start 0.12065 -0.2794)
			(end 0.12065 -0.3048)
			(stroke
				(width 0.1)
				(type default)
			)
			(layer "F.Fab")
		)
		(fp_line
			(start 0.67945 -0.3048)
			(end 0.67945 0.3048)
			(stroke
				(width 0.1)
				(type default)
			)
			(layer "F.Fab")
		)
		(fp_line
			(start 0.67945 0.3048)
			(end 0.120396 0.3048)
			(stroke
				(width 0.1)
				(type default)
			)
			(layer "F.Fab")
		)
		(pad "1" smd circle
			(at -0.40005 0)
			(size 0 0)
			(layers "F.Cu" "F.Mask" "F.Paste")
			(net "P0V9_RETIMER_CPU0_SENSE_SH_P")
		)
		(pad "2" smd circle
			(at 0.40005 0)
			(size 0 0)
			(layers "F.Cu" "F.Mask" "F.Paste")
			(net "P0V9_RETIMER_CPU0_SENSE_R_P")
		)
	)
	(footprint ""
		(layer "F.Cu")
		(at 421.92194 -109.271308 90)
		(property "Reference" "PC2162"
			(at 0 0 90)
			(layer "F.SilkS")
			(hide yes)
			(effects
				(font
					(size 1.27 1.27)
				)
			)
		)
		(property "Value" ""
			(at 0 0 90)
			(layer "F.Fab")
			(effects
				(font
					(size 1.27 1.27)
				)
			)
		)
		(duplicate_pad_numbers_are_jumpers no)
		(fp_line
			(start 0.7874 -0.4064)
			(end 0.7874 0.4064)
			(stroke
				(width 0.1524)
				(type default)
			)
			(layer "F.SilkS")
		)
		(fp_line
			(start -0.7874 -0.4064)
			(end 0.7874 -0.4064)
			(stroke
				(width 0.1524)
				(type default)
			)
			(layer "F.SilkS")
		)
		(fp_line
			(start 0.7874 0.4064)
			(end -0.7874 0.4064)
			(stroke
				(width 0.1524)
				(type default)
			)
			(layer "F.SilkS")
		)
		(fp_line
			(start -0.7874 0.4064)
			(end -0.7874 -0.4064)
			(stroke
				(width 0.1524)
				(type default)
			)
			(layer "F.SilkS")
		)
		(fp_line
			(start -0.12065 -0.305054)
			(end -0.12065 -0.2794)
			(stroke
				(width 0.1)
				(type default)
			)
			(layer "F.Fab")
		)
		(fp_line
			(start -0.67945 -0.305054)
			(end -0.12065 -0.305054)
			(stroke
				(width 0.1)
				(type default)
			)
			(layer "F.Fab")
		)
		(fp_line
			(start 0.67945 -0.3048)
			(end 0.67945 0.3048)
			(stroke
				(width 0.1)
				(type default)
			)
			(layer "F.Fab")
		)
		(fp_line
			(start 0.12065 -0.3048)
			(end 0.67945 -0.3048)
			(stroke
				(width 0.1)
				(type default)
			)
			(layer "F.Fab")
		)
		(fp_line
			(start 0.12065 -0.2794)
			(end 0.12065 -0.3048)
			(stroke
				(width 0.1)
				(type default)
			)
			(layer "F.Fab")
		)
		(fp_line
			(start -0.12065 -0.2794)
			(end 0.12065 -0.2794)
			(stroke
				(width 0.1)
				(type default)
			)
			(layer "F.Fab")
		)
		(fp_line
			(start 0.120396 0.2794)
			(end -0.12065 0.2794)
			(stroke
				(width 0.1)
				(type default)
			)
			(layer "F.Fab")
		)
		(fp_line
			(start -0.12065 0.2794)
			(end -0.12065 0.3048)
			(stroke
				(width 0.1)
				(type default)
			)
			(layer "F.Fab")
		)
		(fp_line
			(start 0.67945 0.3048)
			(end 0.120396 0.3048)
			(stroke
				(width 0.1)
				(type default)
			)
			(layer "F.Fab")
		)
		(fp_line
			(start 0.120396 0.3048)
			(end 0.120396 0.2794)
			(stroke
				(width 0.1)
				(type default)
			)
			(layer "F.Fab")
		)
		(fp_line
			(start -0.12065 0.3048)
			(end -0.67945 0.3048)
			(stroke
				(width 0.1)
				(type default)
			)
			(layer "F.Fab")
		)
		(fp_line
			(start -0.67945 0.3048)
			(end -0.67945 -0.305054)
			(stroke
				(width 0.1)
				(type default)
			)
			(layer "F.Fab")
		)
		(pad "1" smd circle
			(at -0.40005 0 90)
			(size 0 0)
			(layers "F.Cu" "F.Mask" "F.Paste")
			(net "P3V3_OCP_GATE_1")
		)
		(pad "2" smd circle
			(at 0.40005 0 90)
			(size 0 0)
			(layers "F.Cu" "F.Mask" "F.Paste")
			(net "GND")
		)
	)
	(footprint ""
		(layer "F.Cu")
		(at 298.316142 -404.4188 -90)
		(property "Reference" "L12"
			(at -0.2286 -3.048508 90)
			(unlocked yes)
			(layer "F.SilkS")
			(effects
				(font
					(size 0.7874 0.5842)
					(thickness 0.1524)
				)
				(justify left)
			)
		)
		(property "Value" ""
			(at 0 0 270)
			(layer "F.Fab")
			(effects
				(font
					(size 1.27 1.27)
				)
			)
		)
		(duplicate_pad_numbers_are_jumpers no)
		(fp_line
			(start -2.249932 2.249932)
			(end -2.249932 1.3843)
			(stroke
				(width 0.1524)
				(type default)
			)
			(layer "F.SilkS")
		)
		(fp_line
			(start 2.249932 2.249932)
			(end -2.249932 2.249932)
			(stroke
				(width 0.1524)
				(type default)
			)
			(layer "F.SilkS")
		)
		(fp_line
			(start 2.249932 1.3843)
			(end 2.249932 2.249932)
			(stroke
				(width 0.1524)
				(type default)
			)
			(layer "F.SilkS")
		)
		(fp_line
			(start -2.249932 -1.3843)
			(end -2.249932 -2.249932)
			(stroke
				(width 0.1524)
				(type default)
			)
			(layer "F.SilkS")
		)
		(fp_line
			(start -2.249932 -2.249932)
			(end 2.249932 -2.249932)
			(stroke
				(width 0.1524)
				(type default)
			)
			(layer "F.SilkS")
		)
		(fp_line
			(start 2.249932 -2.249932)
			(end 2.249932 -1.3843)
			(stroke
				(width 0.1524)
				(type default)
			)
			(layer "F.SilkS")
		)
		(fp_line
			(start -2.249932 2.249932)
			(end -2.249932 -2.249932)
			(stroke
				(width 0.1)
				(type default)
			)
			(layer "F.Fab")
		)
		(fp_line
			(start 2.249932 2.249932)
			(end -2.249932 2.249932)
			(stroke
				(width 0.1)
				(type default)
			)
			(layer "F.Fab")
		)
		(fp_line
			(start -2.249932 -2.249932)
			(end 2.249932 -2.249932)
			(stroke
				(width 0.1)
				(type default)
			)
			(layer "F.Fab")
		)
		(fp_line
			(start 2.249932 -2.249932)
			(end 2.249932 2.249932)
			(stroke
				(width 0.1)
				(type default)
			)
			(layer "F.Fab")
		)
		(pad "1" smd rect
			(at -1.82499 0 270)
			(size 1.0668 2.5146)
			(layers "F.Cu" "F.Mask" "F.Paste")
			(net "P0V9_CPU0_RT_2D")
		)
		(pad "2" smd rect
			(at 1.82499 0 270)
			(size 1.0668 2.5146)
			(layers "F.Cu" "F.Mask" "F.Paste")
			(net "P0V9_CPU0_RT0_2A")
		)
	)
	(footprint ""
		(layer "F.Cu")
		(at 252.573536 -120.31345 180)
		(property "Reference" "R1497"
			(at 0 0 180)
			(layer "F.SilkS")
			(hide yes)
			(effects
				(font
					(size 1.27 1.27)
				)
			)
		)
		(property "Value" ""
			(at 0 0 180)
			(layer "F.Fab")
			(effects
				(font
					(size 1.27 1.27)
				)
			)
		)
		(duplicate_pad_numbers_are_jumpers no)
		(fp_line
			(start 0.7874 0.4064)
			(end -0.7874 0.4064)
			(stroke
				(width 0.1524)
				(type default)
			)
			(layer "F.SilkS")
		)
		(fp_line
			(start 0.7874 -0.4064)
			(end 0.7874 0.4064)
			(stroke
				(width 0.1524)
				(type default)
			)
			(layer "F.SilkS")
		)
		(fp_line
			(start -0.7874 0.4064)
			(end -0.7874 -0.4064)
			(stroke
				(width 0.1524)
				(type default)
			)
			(layer "F.SilkS")
		)
		(fp_line
			(start -0.7874 -0.4064)
			(end 0.7874 -0.4064)
			(stroke
				(width 0.1524)
				(type default)
			)
			(layer "F.SilkS")
		)
		(fp_line
			(start 0.67945 0.3048)
			(end 0.120396 0.3048)
			(stroke
				(width 0.1)
				(type default)
			)
			(layer "F.Fab")
		)
		(fp_line
			(start 0.67945 -0.3048)
			(end 0.67945 0.3048)
			(stroke
				(width 0.1)
				(type default)
			)
			(layer "F.Fab")
		)
		(fp_line
			(start 0.12065 -0.2794)
			(end 0.12065 -0.3048)
			(stroke
				(width 0.1)
				(type default)
			)
			(layer "F.Fab")
		)
		(fp_line
			(start 0.12065 -0.3048)
			(end 0.67945 -0.3048)
			(stroke
				(width 0.1)
				(type default)
			)
			(layer "F.Fab")
		)
		(fp_line
			(start 0.120396 0.3048)
			(end 0.120396 0.2794)
			(stroke
				(width 0.1)
				(type default)
			)
			(layer "F.Fab")
		)
		(fp_line
			(start 0.120396 0.2794)
			(end -0.12065 0.2794)
			(stroke
				(width 0.1)
				(type default)
			)
			(layer "F.Fab")
		)
		(fp_line
			(start -0.12065 0.3048)
			(end -0.67945 0.3048)
			(stroke
				(width 0.1)
				(type default)
			)
			(layer "F.Fab")
		)
		(fp_line
			(start -0.12065 0.2794)
			(end -0.12065 0.3048)
			(stroke
				(width 0.1)
				(type default)
			)
			(layer "F.Fab")
		)
		(fp_line
			(start -0.12065 -0.2794)
			(end 0.12065 -0.2794)
			(stroke
				(width 0.1)
				(type default)
			)
			(layer "F.Fab")
		)
		(fp_line
			(start -0.12065 -0.305054)
			(end -0.12065 -0.2794)
			(stroke
				(width 0.1)
				(type default)
			)
			(layer "F.Fab")
		)
		(fp_line
			(start -0.67945 0.3048)
			(end -0.67945 -0.305054)
			(stroke
				(width 0.1)
				(type default)
			)
			(layer "F.Fab")
		)
		(fp_line
			(start -0.67945 -0.305054)
			(end -0.12065 -0.305054)
			(stroke
				(width 0.1)
				(type default)
			)
			(layer "F.Fab")
		)
		(pad "1" smd circle
			(at -0.40005 0 180)
			(size 0 0)
			(layers "F.Cu" "F.Mask" "F.Paste")
			(net "SMB_VR_3V3AUX_SCL")
		)
		(pad "2" smd circle
			(at 0.40005 0 180)
			(size 0 0)
			(layers "F.Cu" "F.Mask" "F.Paste")
			(net "SMB_SCM_2_R3_SCL")
		)
	)
	(footprint ""
		(layer "F.Cu")
		(at 24.765 -359.918)
		(property "Reference" "PR8011"
			(at 0 0 0)
			(layer "F.SilkS")
			(hide yes)
			(effects
				(font
					(size 1.27 1.27)
				)
			)
		)
		(property "Value" ""
			(at 0 0 0)
			(layer "F.Fab")
			(effects
				(font
					(size 1.27 1.27)
				)
			)
		)
		(duplicate_pad_numbers_are_jumpers no)
		(fp_line
			(start -0.7874 -0.4064)
			(end 0.7874 -0.4064)
			(stroke
				(width 0.1524)
				(type default)
			)
			(layer "F.SilkS")
		)
		(fp_line
			(start -0.7874 0.4064)
			(end -0.7874 -0.4064)
			(stroke
				(width 0.1524)
				(type default)
			)
			(layer "F.SilkS")
		)
		(fp_line
			(start 0.7874 -0.4064)
			(end 0.7874 0.4064)
			(stroke
				(width 0.1524)
				(type default)
			)
			(layer "F.SilkS")
		)
		(fp_line
			(start 0.7874 0.4064)
			(end -0.7874 0.4064)
			(stroke
				(width 0.1524)
				(type default)
			)
			(layer "F.SilkS")
		)
		(fp_line
			(start -0.67945 -0.305054)
			(end -0.12065 -0.305054)
			(stroke
				(width 0.1)
				(type default)
			)
			(layer "F.Fab")
		)
		(fp_line
			(start -0.67945 0.3048)
			(end -0.67945 -0.305054)
			(stroke
				(width 0.1)
				(type default)
			)
			(layer "F.Fab")
		)
		(fp_line
			(start -0.12065 -0.305054)
			(end -0.12065 -0.2794)
			(stroke
				(width 0.1)
				(type default)
			)
			(layer "F.Fab")
		)
		(fp_line
			(start -0.12065 -0.2794)
			(end 0.12065 -0.2794)
			(stroke
				(width 0.1)
				(type default)
			)
			(layer "F.Fab")
		)
		(fp_line
			(start -0.12065 0.2794)
			(end -0.12065 0.3048)
			(stroke
				(width 0.1)
				(type default)
			)
			(layer "F.Fab")
		)
		(fp_line
			(start -0.12065 0.3048)
			(end -0.67945 0.3048)
			(stroke
				(width 0.1)
				(type default)
			)
			(layer "F.Fab")
		)
		(fp_line
			(start 0.120396 0.2794)
			(end -0.12065 0.2794)
			(stroke
				(width 0.1)
				(type default)
			)
			(layer "F.Fab")
		)
		(fp_line
			(start 0.120396 0.3048)
			(end 0.120396 0.2794)
			(stroke
				(width 0.1)
				(type default)
			)
			(layer "F.Fab")
		)
		(fp_line
			(start 0.12065 -0.3048)
			(end 0.67945 -0.3048)
			(stroke
				(width 0.1)
				(type default)
			)
			(layer "F.Fab")
		)
		(fp_line
			(start 0.12065 -0.2794)
			(end 0.12065 -0.3048)
			(stroke
				(width 0.1)
				(type default)
			)
			(layer "F.Fab")
		)
		(fp_line
			(start 0.67945 -0.3048)
			(end 0.67945 0.3048)
			(stroke
				(width 0.1)
				(type default)
			)
			(layer "F.Fab")
		)
		(fp_line
			(start 0.67945 0.3048)
			(end 0.120396 0.3048)
			(stroke
				(width 0.1)
				(type default)
			)
			(layer "F.Fab")
		)
		(pad "1" smd circle
			(at -0.40005 0)
			(size 0 0)
			(layers "F.Cu" "F.Mask" "F.Paste")
			(net "SVID_PVDDCR_CPU1_P1_SVC_R")
		)
		(pad "2" smd circle
			(at 0.40005 0)
			(size 0 0)
			(layers "F.Cu" "F.Mask" "F.Paste")
			(net "SVID_PVDDCR_CPU1_P1_SVC_R1")
		)
	)
	(footprint ""
		(layer "F.Cu")
		(at 278.254206 -433.706016 -90)
		(property "Reference" "U308"
			(at 0.740664 -2.003552 0)
			(unlocked yes)
			(layer "F.SilkS")
			(effects
				(font
					(size 0.7874 0.5842)
					(thickness 0.1524)
				)
				(justify left)
			)
		)
		(property "Value" ""
			(at 0 0 270)
			(layer "F.Fab")
			(effects
				(font
					(size 1.27 1.27)
				)
			)
		)
		(duplicate_pad_numbers_are_jumpers no)
		(fp_line
			(start -1.38176 1.100074)
			(end 1.38176 1.100074)
			(stroke
				(width 0.1524)
				(type default)
			)
			(layer "F.SilkS")
		)
		(fp_line
			(start 1.38176 1.100074)
			(end 1.38176 -1.100074)
			(stroke
				(width 0.1524)
				(type default)
			)
			(layer "F.SilkS")
		)
		(fp_line
			(start 0 -0.508)
			(end -0.592074 -1.100074)
			(stroke
				(width 0.1524)
				(type default)
			)
			(layer "F.SilkS")
		)
		(fp_line
			(start -1.38176 -1.100074)
			(end -1.38176 1.100074)
			(stroke
				(width 0.1524)
				(type default)
			)
			(layer "F.SilkS")
		)
		(fp_line
			(start -0.592074 -1.100074)
			(end -1.38176 -1.100074)
			(stroke
				(width 0.1524)
				(type default)
			)
			(layer "F.SilkS")
		)
		(fp_line
			(start 0.592074 -1.100074)
			(end 0 -0.508)
			(stroke
				(width 0.1524)
				(type default)
			)
			(layer "F.SilkS")
		)
		(fp_line
			(start 1.38176 -1.100074)
			(end 0.592074 -1.100074)
			(stroke
				(width 0.1524)
				(type default)
			)
			(layer "F.SilkS")
		)
		(fp_poly
			(pts
				(xy -1.528318 -1.73355) (xy -1.372362 -1.26619) (xy -1.839722 -1.422146)
			)
			(stroke
				(width 0)
				(type default)
			)
			(fill yes)
			(layer "F.SilkS")
		)
		(fp_line
			(start -0.674878 1.100074)
			(end 0.674878 1.100074)
			(stroke
				(width 0.1)
				(type default)
			)
			(layer "F.Fab")
		)
		(fp_line
			(start 0.674878 1.100074)
			(end 0.674878 -1.100074)
			(stroke
				(width 0.1)
				(type default)
			)
			(layer "F.Fab")
		)
		(fp_line
			(start -0.674878 -1.100074)
			(end -0.674878 1.100074)
			(stroke
				(width 0.1)
				(type default)
			)
			(layer "F.Fab")
		)
		(fp_line
			(start 0.674878 -1.100074)
			(end -0.674878 -1.100074)
			(stroke
				(width 0.1)
				(type default)
			)
			(layer "F.Fab")
		)
		(fp_poly
			(pts
				(xy -1.9431 -0.870204) (xy -1.50241 -0.649986) (xy -1.9431 -0.429768)
			)
			(stroke
				(width 0)
				(type default)
			)
			(fill yes)
			(layer "F.Fab")
		)
		(pad "1" smd rect
			(at -0.94996 -0.649986 180)
			(size 0.4318 0.6096)
			(layers "F.Cu" "F.Mask" "F.Paste")
			(net "PWRGD_P3V3_AUX_PDB_R")
		)
		(pad "2" smd rect
			(at -0.94996 0 180)
			(size 0.4318 0.6096)
			(layers "F.Cu" "F.Mask" "F.Paste")
			(net "GND")
		)
		(pad "3" smd rect
			(at -0.94996 0.649986 180)
			(size 0.4318 0.6096)
			(layers "F.Cu" "F.Mask" "F.Paste")
			(net "Net_10754")
		)
		(pad "4" smd rect
			(at 0.94996 0.649986 180)
			(size 0.4318 0.6096)
			(layers "F.Cu" "F.Mask" "F.Paste")
			(net "Net_10753")
		)
		(pad "5" smd rect
			(at 0.94996 0 180)
			(size 0.4318 0.6096)
			(layers "F.Cu" "F.Mask" "F.Paste")
			(net "P3V3_AUX")
		)
		(pad "6" smd rect
			(at 0.94996 -0.649986 180)
			(size 0.4318 0.6096)
			(layers "F.Cu" "F.Mask" "F.Paste")
			(net "PWRGD_P3V3_AUX_PDB_BUF_R")
		)
	)
	(footprint ""
		(layer "F.Cu")
		(at 358.796082 -258.795012)
		(property "Reference" "C2614"
			(at 0 0 0)
			(layer "F.SilkS")
			(hide yes)
			(effects
				(font
					(size 1.27 1.27)
				)
			)
		)
		(property "Value" ""
			(at 0 0 0)
			(layer "F.Fab")
			(effects
				(font
					(size 1.27 1.27)
				)
			)
		)
		(duplicate_pad_numbers_are_jumpers no)
		(fp_line
			(start -0.7874 -0.4064)
			(end 0.7874 -0.4064)
			(stroke
				(width 0.1524)
				(type default)
			)
			(layer "F.SilkS")
		)
		(fp_line
			(start -0.7874 0.4064)
			(end -0.7874 -0.4064)
			(stroke
				(width 0.1524)
				(type default)
			)
			(layer "F.SilkS")
		)
		(fp_line
			(start 0.7874 -0.4064)
			(end 0.7874 0.4064)
			(stroke
				(width 0.1524)
				(type default)
			)
			(layer "F.SilkS")
		)
		(fp_line
			(start 0.7874 0.4064)
			(end -0.7874 0.4064)
			(stroke
				(width 0.1524)
				(type default)
			)
			(layer "F.SilkS")
		)
		(fp_line
			(start -0.67945 -0.305054)
			(end -0.12065 -0.305054)
			(stroke
				(width 0.1)
				(type default)
			)
			(layer "F.Fab")
		)
		(fp_line
			(start -0.67945 0.3048)
			(end -0.67945 -0.305054)
			(stroke
				(width 0.1)
				(type default)
			)
			(layer "F.Fab")
		)
		(fp_line
			(start -0.12065 -0.305054)
			(end -0.12065 -0.2794)
			(stroke
				(width 0.1)
				(type default)
			)
			(layer "F.Fab")
		)
		(fp_line
			(start -0.12065 -0.2794)
			(end 0.12065 -0.2794)
			(stroke
				(width 0.1)
				(type default)
			)
			(layer "F.Fab")
		)
		(fp_line
			(start -0.12065 0.2794)
			(end -0.12065 0.3048)
			(stroke
				(width 0.1)
				(type default)
			)
			(layer "F.Fab")
		)
		(fp_line
			(start -0.12065 0.3048)
			(end -0.67945 0.3048)
			(stroke
				(width 0.1)
				(type default)
			)
			(layer "F.Fab")
		)
		(fp_line
			(start 0.120396 0.2794)
			(end -0.12065 0.2794)
			(stroke
				(width 0.1)
				(type default)
			)
			(layer "F.Fab")
		)
		(fp_line
			(start 0.120396 0.3048)
			(end 0.120396 0.2794)
			(stroke
				(width 0.1)
				(type default)
			)
			(layer "F.Fab")
		)
		(fp_line
			(start 0.12065 -0.3048)
			(end 0.67945 -0.3048)
			(stroke
				(width 0.1)
				(type default)
			)
			(layer "F.Fab")
		)
		(fp_line
			(start 0.12065 -0.2794)
			(end 0.12065 -0.3048)
			(stroke
				(width 0.1)
				(type default)
			)
			(layer "F.Fab")
		)
		(fp_line
			(start 0.67945 -0.3048)
			(end 0.67945 0.3048)
			(stroke
				(width 0.1)
				(type default)
			)
			(layer "F.Fab")
		)
		(fp_line
			(start 0.67945 0.3048)
			(end 0.120396 0.3048)
			(stroke
				(width 0.1)
				(type default)
			)
			(layer "F.Fab")
		)
		(pad "1" smd circle
			(at -0.40005 0)
			(size 0 0)
			(layers "F.Cu" "F.Mask" "F.Paste")
			(net "PVDD11_S3_P0")
		)
		(pad "2" smd circle
			(at 0.40005 0)
			(size 0 0)
			(layers "F.Cu" "F.Mask" "F.Paste")
			(net "GND")
		)
	)
	(footprint ""
		(layer "F.Cu")
		(at 298.967144 -389.86206 180)
		(property "Reference" "C932"
			(at 0 0 180)
			(layer "F.SilkS")
			(hide yes)
			(effects
				(font
					(size 1.27 1.27)
				)
			)
		)
		(property "Value" ""
			(at 0 0 180)
			(layer "F.Fab")
			(effects
				(font
					(size 1.27 1.27)
				)
			)
		)
		(duplicate_pad_numbers_are_jumpers no)
		(fp_line
			(start 0.299974 0.150114)
			(end -0.299974 0.150114)
			(stroke
				(width 0.1)
				(type default)
			)
			(layer "F.Fab")
		)
		(fp_line
			(start 0.299974 -0.150114)
			(end 0.299974 0.150114)
			(stroke
				(width 0.1)
				(type default)
			)
			(layer "F.Fab")
		)
		(fp_line
			(start -0.299974 0.150114)
			(end -0.299974 -0.150114)
			(stroke
				(width 0.1)
				(type default)
			)
			(layer "F.Fab")
		)
		(fp_line
			(start -0.299974 -0.150114)
			(end 0.299974 -0.150114)
			(stroke
				(width 0.1)
				(type default)
			)
			(layer "F.Fab")
		)
		(pad "1" smd rect
			(at -0.2667 0 180)
			(size 0.3048 0.381)
			(layers "F.Cu" "F.Mask" "F.Paste")
			(net "P5E_CPU0_P0_TX_C_DN<0>")
		)
		(pad "2" smd rect
			(at 0.2667 0 180)
			(size 0.3048 0.381)
			(layers "F.Cu" "F.Mask" "F.Paste")
			(net "P5E_CPU0_P0_TX_DN<0>")
		)
	)
	(footprint ""
		(layer "F.Cu")
		(at 74.5236 -385.48056)
		(property "Reference" "R781"
			(at 0 0 0)
			(layer "F.SilkS")
			(hide yes)
			(effects
				(font
					(size 1.27 1.27)
				)
			)
		)
		(property "Value" ""
			(at 0 0 0)
			(layer "F.Fab")
			(effects
				(font
					(size 1.27 1.27)
				)
			)
		)
		(duplicate_pad_numbers_are_jumpers no)
		(fp_line
			(start -0.32512 -0.175006)
			(end 0.32512 -0.175006)
			(stroke
				(width 0.1)
				(type default)
			)
			(layer "F.Fab")
		)
		(fp_line
			(start -0.32512 0.175006)
			(end -0.32512 -0.175006)
			(stroke
				(width 0.1)
				(type default)
			)
			(layer "F.Fab")
		)
		(fp_line
			(start 0.32512 -0.175006)
			(end 0.32512 0.175006)
			(stroke
				(width 0.1)
				(type default)
			)
			(layer "F.Fab")
		)
		(fp_line
			(start 0.32512 0.175006)
			(end -0.32512 0.175006)
			(stroke
				(width 0.1)
				(type default)
			)
			(layer "F.Fab")
		)
		(pad "1" smd rect
			(at -0.2667 0)
			(size 0.3048 0.381)
			(layers "F.Cu" "F.Mask" "F.Paste")
			(net "P1V8_CPU1_RT_1D")
		)
		(pad "2" smd rect
			(at 0.2667 0 180)
			(size 0.3048 0.381)
			(layers "F.Cu" "F.Mask" "F.Paste")
			(net "GPIO2_RT_CPU1_P1")
		)
	)
	(footprint ""
		(layer "F.Cu")
		(at 37.860478 -16.099536 90)
		(property "Reference" "C694"
			(at 0 0 90)
			(layer "F.SilkS")
			(hide yes)
			(effects
				(font
					(size 1.27 1.27)
				)
			)
		)
		(property "Value" ""
			(at 0 0 90)
			(layer "F.Fab")
			(effects
				(font
					(size 1.27 1.27)
				)
			)
		)
		(duplicate_pad_numbers_are_jumpers no)
		(fp_line
			(start 0.299974 -0.150114)
			(end 0.299974 0.150114)
			(stroke
				(width 0.1)
				(type default)
			)
			(layer "F.Fab")
		)
		(fp_line
			(start -0.299974 -0.150114)
			(end 0.299974 -0.150114)
			(stroke
				(width 0.1)
				(type default)
			)
			(layer "F.Fab")
		)
		(fp_line
			(start 0.299974 0.150114)
			(end -0.299974 0.150114)
			(stroke
				(width 0.1)
				(type default)
			)
			(layer "F.Fab")
		)
		(fp_line
			(start -0.299974 0.150114)
			(end -0.299974 -0.150114)
			(stroke
				(width 0.1)
				(type default)
			)
			(layer "F.Fab")
		)
		(pad "1" smd rect
			(at -0.2667 0 90)
			(size 0.3048 0.381)
			(layers "F.Cu" "F.Mask" "F.Paste")
			(net "P5E_CPU1_G1_TX_C_DN<7>")
		)
		(pad "2" smd rect
			(at 0.2667 0 90)
			(size 0.3048 0.381)
			(layers "F.Cu" "F.Mask" "F.Paste")
			(net "P5E_CPU1_G1_TX_DN<7>")
		)
	)
	(footprint ""
		(layer "F.Cu")
		(at 162.5092 -419.0492 90)
		(property "Reference" "R694"
			(at 0 0 90)
			(layer "F.SilkS")
			(hide yes)
			(effects
				(font
					(size 1.27 1.27)
				)
			)
		)
		(property "Value" ""
			(at 0 0 90)
			(layer "F.Fab")
			(effects
				(font
					(size 1.27 1.27)
				)
			)
		)
		(duplicate_pad_numbers_are_jumpers no)
		(fp_line
			(start 0.32512 -0.175006)
			(end 0.32512 0.175006)
			(stroke
				(width 0.1)
				(type default)
			)
			(layer "F.Fab")
		)
		(fp_line
			(start -0.32512 -0.175006)
			(end 0.32512 -0.175006)
			(stroke
				(width 0.1)
				(type default)
			)
			(layer "F.Fab")
		)
		(fp_line
			(start 0.32512 0.175006)
			(end -0.32512 0.175006)
			(stroke
				(width 0.1)
				(type default)
			)
			(layer "F.Fab")
		)
		(fp_line
			(start -0.32512 0.175006)
			(end -0.32512 -0.175006)
			(stroke
				(width 0.1)
				(type default)
			)
			(layer "F.Fab")
		)
		(pad "1" smd rect
			(at -0.2667 0 90)
			(size 0.3048 0.381)
			(layers "F.Cu" "F.Mask" "F.Paste")
			(net "SMB_RT_CPU1_P2_ROM_R_SDA")
		)
		(pad "2" smd rect
			(at 0.2667 0 270)
			(size 0.3048 0.381)
			(layers "F.Cu" "F.Mask" "F.Paste")
			(net "SMB_RT_CPU1_P2_ROM_SDA")
		)
	)
	(footprint ""
		(layer "F.Cu")
		(at 240.854484 -56.527192)
		(property "Reference" "C1992"
			(at 0 0 0)
			(layer "F.SilkS")
			(hide yes)
			(effects
				(font
					(size 1.27 1.27)
				)
			)
		)
		(property "Value" ""
			(at 0 0 0)
			(layer "F.Fab")
			(effects
				(font
					(size 1.27 1.27)
				)
			)
		)
		(duplicate_pad_numbers_are_jumpers no)
		(fp_line
			(start -0.299974 -0.150114)
			(end 0.299974 -0.150114)
			(stroke
				(width 0.1)
				(type default)
			)
			(layer "F.Fab")
		)
		(fp_line
			(start -0.299974 0.150114)
			(end -0.299974 -0.150114)
			(stroke
				(width 0.1)
				(type default)
			)
			(layer "F.Fab")
		)
		(fp_line
			(start 0.299974 -0.150114)
			(end 0.299974 0.150114)
			(stroke
				(width 0.1)
				(type default)
			)
			(layer "F.Fab")
		)
		(fp_line
			(start 0.299974 0.150114)
			(end -0.299974 0.150114)
			(stroke
				(width 0.1)
				(type default)
			)
			(layer "F.Fab")
		)
		(pad "1" smd rect
			(at -0.2667 0)
			(size 0.3048 0.381)
			(layers "F.Cu" "F.Mask" "F.Paste")
			(net "P3E_CPU0_P4_TX_C_DN<2>")
		)
		(pad "2" smd rect
			(at 0.2667 0)
			(size 0.3048 0.381)
			(layers "F.Cu" "F.Mask" "F.Paste")
			(net "P3E_CPU0_P4_TX_DN<2>")
		)
	)
	(footprint ""
		(layer "F.Cu")
		(at 118.287546 -72.91324 -90)
		(property "Reference" "PR6004"
			(at 0 0 270)
			(layer "F.SilkS")
			(hide yes)
			(effects
				(font
					(size 1.27 1.27)
				)
			)
		)
		(property "Value" ""
			(at 0 0 270)
			(layer "F.Fab")
			(effects
				(font
					(size 1.27 1.27)
				)
			)
		)
		(duplicate_pad_numbers_are_jumpers no)
		(fp_line
			(start -0.7874 0.4064)
			(end -0.7874 -0.4064)
			(stroke
				(width 0.1524)
				(type default)
			)
			(layer "F.SilkS")
		)
		(fp_line
			(start 0.7874 0.4064)
			(end -0.7874 0.4064)
			(stroke
				(width 0.1524)
				(type default)
			)
			(layer "F.SilkS")
		)
		(fp_line
			(start -0.7874 -0.4064)
			(end 0.7874 -0.4064)
			(stroke
				(width 0.1524)
				(type default)
			)
			(layer "F.SilkS")
		)
		(fp_line
			(start 0.7874 -0.4064)
			(end 0.7874 0.4064)
			(stroke
				(width 0.1524)
				(type default)
			)
			(layer "F.SilkS")
		)
		(fp_line
			(start -0.67945 0.3048)
			(end -0.67945 -0.305054)
			(stroke
				(width 0.1)
				(type default)
			)
			(layer "F.Fab")
		)
		(fp_line
			(start -0.12065 0.3048)
			(end -0.67945 0.3048)
			(stroke
				(width 0.1)
				(type default)
			)
			(layer "F.Fab")
		)
		(fp_line
			(start 0.120396 0.3048)
			(end 0.120396 0.2794)
			(stroke
				(width 0.1)
				(type default)
			)
			(layer "F.Fab")
		)
		(fp_line
			(start 0.67945 0.3048)
			(end 0.120396 0.3048)
			(stroke
				(width 0.1)
				(type default)
			)
			(layer "F.Fab")
		)
		(fp_line
			(start -0.12065 0.2794)
			(end -0.12065 0.3048)
			(stroke
				(width 0.1)
				(type default)
			)
			(layer "F.Fab")
		)
		(fp_line
			(start 0.120396 0.2794)
			(end -0.12065 0.2794)
			(stroke
				(width 0.1)
				(type default)
			)
			(layer "F.Fab")
		)
		(fp_line
			(start -0.12065 -0.2794)
			(end 0.12065 -0.2794)
			(stroke
				(width 0.1)
				(type default)
			)
			(layer "F.Fab")
		)
		(fp_line
			(start 0.12065 -0.2794)
			(end 0.12065 -0.3048)
			(stroke
				(width 0.1)
				(type default)
			)
			(layer "F.Fab")
		)
		(fp_line
			(start 0.12065 -0.3048)
			(end 0.67945 -0.3048)
			(stroke
				(width 0.1)
				(type default)
			)
			(layer "F.Fab")
		)
		(fp_line
			(start 0.67945 -0.3048)
			(end 0.67945 0.3048)
			(stroke
				(width 0.1)
				(type default)
			)
			(layer "F.Fab")
		)
		(fp_line
			(start -0.67945 -0.305054)
			(end -0.12065 -0.305054)
			(stroke
				(width 0.1)
				(type default)
			)
			(layer "F.Fab")
		)
		(fp_line
			(start -0.12065 -0.305054)
			(end -0.12065 -0.2794)
			(stroke
				(width 0.1)
				(type default)
			)
			(layer "F.Fab")
		)
		(pad "1" smd circle
			(at -0.40005 0 270)
			(size 0 0)
			(layers "F.Cu" "F.Mask" "F.Paste")
			(net "P1V2_AUX_CS")
		)
		(pad "2" smd circle
			(at 0.40005 0 270)
			(size 0 0)
			(layers "F.Cu" "F.Mask" "F.Paste")
			(net "GND")
		)
	)
	(footprint ""
		(layer "F.Cu")
		(at 65.3796 -15.8496 180)
		(property "Reference" "C1831"
			(at 0 0 180)
			(layer "F.SilkS")
			(hide yes)
			(effects
				(font
					(size 1.27 1.27)
				)
			)
		)
		(property "Value" ""
			(at 0 0 180)
			(layer "F.Fab")
			(effects
				(font
					(size 1.27 1.27)
				)
			)
		)
		(duplicate_pad_numbers_are_jumpers no)
		(fp_line
			(start 0.7874 0.4064)
			(end -0.7874 0.4064)
			(stroke
				(width 0.1524)
				(type default)
			)
			(layer "F.SilkS")
		)
		(fp_line
			(start 0.7874 -0.4064)
			(end 0.7874 0.4064)
			(stroke
				(width 0.1524)
				(type default)
			)
			(layer "F.SilkS")
		)
		(fp_line
			(start -0.7874 0.4064)
			(end -0.7874 -0.4064)
			(stroke
				(width 0.1524)
				(type default)
			)
			(layer "F.SilkS")
		)
		(fp_line
			(start -0.7874 -0.4064)
			(end 0.7874 -0.4064)
			(stroke
				(width 0.1524)
				(type default)
			)
			(layer "F.SilkS")
		)
		(fp_line
			(start 0.67945 0.3048)
			(end 0.120396 0.3048)
			(stroke
				(width 0.1)
				(type default)
			)
			(layer "F.Fab")
		)
		(fp_line
			(start 0.67945 -0.3048)
			(end 0.67945 0.3048)
			(stroke
				(width 0.1)
				(type default)
			)
			(layer "F.Fab")
		)
		(fp_line
			(start 0.12065 -0.2794)
			(end 0.12065 -0.3048)
			(stroke
				(width 0.1)
				(type default)
			)
			(layer "F.Fab")
		)
		(fp_line
			(start 0.12065 -0.3048)
			(end 0.67945 -0.3048)
			(stroke
				(width 0.1)
				(type default)
			)
			(layer "F.Fab")
		)
		(fp_line
			(start 0.120396 0.3048)
			(end 0.120396 0.2794)
			(stroke
				(width 0.1)
				(type default)
			)
			(layer "F.Fab")
		)
		(fp_line
			(start 0.120396 0.2794)
			(end -0.12065 0.2794)
			(stroke
				(width 0.1)
				(type default)
			)
			(layer "F.Fab")
		)
		(fp_line
			(start -0.12065 0.3048)
			(end -0.67945 0.3048)
			(stroke
				(width 0.1)
				(type default)
			)
			(layer "F.Fab")
		)
		(fp_line
			(start -0.12065 0.2794)
			(end -0.12065 0.3048)
			(stroke
				(width 0.1)
				(type default)
			)
			(layer "F.Fab")
		)
		(fp_line
			(start -0.12065 -0.2794)
			(end 0.12065 -0.2794)
			(stroke
				(width 0.1)
				(type default)
			)
			(layer "F.Fab")
		)
		(fp_line
			(start -0.12065 -0.305054)
			(end -0.12065 -0.2794)
			(stroke
				(width 0.1)
				(type default)
			)
			(layer "F.Fab")
		)
		(fp_line
			(start -0.67945 0.3048)
			(end -0.67945 -0.305054)
			(stroke
				(width 0.1)
				(type default)
			)
			(layer "F.Fab")
		)
		(fp_line
			(start -0.67945 -0.305054)
			(end -0.12065 -0.305054)
			(stroke
				(width 0.1)
				(type default)
			)
			(layer "F.Fab")
		)
		(pad "1" smd circle
			(at -0.40005 0 180)
			(size 0 0)
			(layers "F.Cu" "F.Mask" "F.Paste")
			(net "P12V_OCP_V3_2_R")
		)
		(pad "2" smd circle
			(at 0.40005 0 180)
			(size 0 0)
			(layers "F.Cu" "F.Mask" "F.Paste")
			(net "GND")
		)
	)
	(footprint ""
		(layer "F.Cu")
		(at 27.178 -357.886 90)
		(property "Reference" "PR245"
			(at 0 0 90)
			(layer "F.SilkS")
			(hide yes)
			(effects
				(font
					(size 1.27 1.27)
				)
			)
		)
		(property "Value" ""
			(at 0 0 90)
			(layer "F.Fab")
			(effects
				(font
					(size 1.27 1.27)
				)
			)
		)
		(duplicate_pad_numbers_are_jumpers no)
		(fp_line
			(start 0.7874 -0.4064)
			(end 0.7874 0.4064)
			(stroke
				(width 0.1524)
				(type default)
			)
			(layer "F.SilkS")
		)
		(fp_line
			(start -0.7874 -0.4064)
			(end 0.7874 -0.4064)
			(stroke
				(width 0.1524)
				(type default)
			)
			(layer "F.SilkS")
		)
		(fp_line
			(start 0.7874 0.4064)
			(end -0.7874 0.4064)
			(stroke
				(width 0.1524)
				(type default)
			)
			(layer "F.SilkS")
		)
		(fp_line
			(start -0.7874 0.4064)
			(end -0.7874 -0.4064)
			(stroke
				(width 0.1524)
				(type default)
			)
			(layer "F.SilkS")
		)
		(fp_line
			(start -0.12065 -0.305054)
			(end -0.12065 -0.2794)
			(stroke
				(width 0.1)
				(type default)
			)
			(layer "F.Fab")
		)
		(fp_line
			(start -0.67945 -0.305054)
			(end -0.12065 -0.305054)
			(stroke
				(width 0.1)
				(type default)
			)
			(layer "F.Fab")
		)
		(fp_line
			(start 0.67945 -0.3048)
			(end 0.67945 0.3048)
			(stroke
				(width 0.1)
				(type default)
			)
			(layer "F.Fab")
		)
		(fp_line
			(start 0.12065 -0.3048)
			(end 0.67945 -0.3048)
			(stroke
				(width 0.1)
				(type default)
			)
			(layer "F.Fab")
		)
		(fp_line
			(start 0.12065 -0.2794)
			(end 0.12065 -0.3048)
			(stroke
				(width 0.1)
				(type default)
			)
			(layer "F.Fab")
		)
		(fp_line
			(start -0.12065 -0.2794)
			(end 0.12065 -0.2794)
			(stroke
				(width 0.1)
				(type default)
			)
			(layer "F.Fab")
		)
		(fp_line
			(start 0.120396 0.2794)
			(end -0.12065 0.2794)
			(stroke
				(width 0.1)
				(type default)
			)
			(layer "F.Fab")
		)
		(fp_line
			(start -0.12065 0.2794)
			(end -0.12065 0.3048)
			(stroke
				(width 0.1)
				(type default)
			)
			(layer "F.Fab")
		)
		(fp_line
			(start 0.67945 0.3048)
			(end 0.120396 0.3048)
			(stroke
				(width 0.1)
				(type default)
			)
			(layer "F.Fab")
		)
		(fp_line
			(start 0.120396 0.3048)
			(end 0.120396 0.2794)
			(stroke
				(width 0.1)
				(type default)
			)
			(layer "F.Fab")
		)
		(fp_line
			(start -0.12065 0.3048)
			(end -0.67945 0.3048)
			(stroke
				(width 0.1)
				(type default)
			)
			(layer "F.Fab")
		)
		(fp_line
			(start -0.67945 0.3048)
			(end -0.67945 -0.305054)
			(stroke
				(width 0.1)
				(type default)
			)
			(layer "F.Fab")
		)
		(pad "1" smd circle
			(at -0.40005 0 90)
			(size 0 0)
			(layers "F.Cu" "F.Mask" "F.Paste")
			(net "VSENSE_PVDDCR_CPU1_P1_DP")
		)
		(pad "2" smd circle
			(at 0.40005 0 90)
			(size 0 0)
			(layers "F.Cu" "F.Mask" "F.Paste")
			(net "VSENSE_PVDDCR_CPU1_P1_VSEN0")
		)
	)
	(footprint ""
		(layer "F.Cu")
		(at 269.023084 -333.045562)
		(property "Reference" "PR50"
			(at 0 0 0)
			(layer "F.SilkS")
			(hide yes)
			(effects
				(font
					(size 1.27 1.27)
				)
			)
		)
		(property "Value" ""
			(at 0 0 0)
			(layer "F.Fab")
			(effects
				(font
					(size 1.27 1.27)
				)
			)
		)
		(duplicate_pad_numbers_are_jumpers no)
		(fp_line
			(start -0.7874 -0.4064)
			(end 0.7874 -0.4064)
			(stroke
				(width 0.1524)
				(type default)
			)
			(layer "F.SilkS")
		)
		(fp_line
			(start -0.7874 0.4064)
			(end -0.7874 -0.4064)
			(stroke
				(width 0.1524)
				(type default)
			)
			(layer "F.SilkS")
		)
		(fp_line
			(start 0.7874 -0.4064)
			(end 0.7874 0.4064)
			(stroke
				(width 0.1524)
				(type default)
			)
			(layer "F.SilkS")
		)
		(fp_line
			(start 0.7874 0.4064)
			(end -0.7874 0.4064)
			(stroke
				(width 0.1524)
				(type default)
			)
			(layer "F.SilkS")
		)
		(fp_line
			(start -0.67945 -0.305054)
			(end -0.12065 -0.305054)
			(stroke
				(width 0.1)
				(type default)
			)
			(layer "F.Fab")
		)
		(fp_line
			(start -0.67945 0.3048)
			(end -0.67945 -0.305054)
			(stroke
				(width 0.1)
				(type default)
			)
			(layer "F.Fab")
		)
		(fp_line
			(start -0.12065 -0.305054)
			(end -0.12065 -0.2794)
			(stroke
				(width 0.1)
				(type default)
			)
			(layer "F.Fab")
		)
		(fp_line
			(start -0.12065 -0.2794)
			(end 0.12065 -0.2794)
			(stroke
				(width 0.1)
				(type default)
			)
			(layer "F.Fab")
		)
		(fp_line
			(start -0.12065 0.2794)
			(end -0.12065 0.3048)
			(stroke
				(width 0.1)
				(type default)
			)
			(layer "F.Fab")
		)
		(fp_line
			(start -0.12065 0.3048)
			(end -0.67945 0.3048)
			(stroke
				(width 0.1)
				(type default)
			)
			(layer "F.Fab")
		)
		(fp_line
			(start 0.120396 0.2794)
			(end -0.12065 0.2794)
			(stroke
				(width 0.1)
				(type default)
			)
			(layer "F.Fab")
		)
		(fp_line
			(start 0.120396 0.3048)
			(end 0.120396 0.2794)
			(stroke
				(width 0.1)
				(type default)
			)
			(layer "F.Fab")
		)
		(fp_line
			(start 0.12065 -0.3048)
			(end 0.67945 -0.3048)
			(stroke
				(width 0.1)
				(type default)
			)
			(layer "F.Fab")
		)
		(fp_line
			(start 0.12065 -0.2794)
			(end 0.12065 -0.3048)
			(stroke
				(width 0.1)
				(type default)
			)
			(layer "F.Fab")
		)
		(fp_line
			(start 0.67945 -0.3048)
			(end 0.67945 0.3048)
			(stroke
				(width 0.1)
				(type default)
			)
			(layer "F.Fab")
		)
		(fp_line
			(start 0.67945 0.3048)
			(end 0.120396 0.3048)
			(stroke
				(width 0.1)
				(type default)
			)
			(layer "F.Fab")
		)
		(pad "1" smd circle
			(at -0.40005 0)
			(size 0 0)
			(layers "F.Cu" "F.Mask" "F.Paste")
			(net "VSENSE_VSS_SENSE_B_P0")
		)
		(pad "2" smd circle
			(at 0.40005 0)
			(size 0 0)
			(layers "F.Cu" "F.Mask" "F.Paste")
			(net "GND")
		)
	)
	(footprint ""
		(layer "F.Cu")
		(at 141.623542 -385.48056)
		(property "Reference" "R874"
			(at 0 0 0)
			(layer "F.SilkS")
			(hide yes)
			(effects
				(font
					(size 1.27 1.27)
				)
			)
		)
		(property "Value" ""
			(at 0 0 0)
			(layer "F.Fab")
			(effects
				(font
					(size 1.27 1.27)
				)
			)
		)
		(duplicate_pad_numbers_are_jumpers no)
		(fp_line
			(start -0.32512 -0.175006)
			(end 0.32512 -0.175006)
			(stroke
				(width 0.1)
				(type default)
			)
			(layer "F.Fab")
		)
		(fp_line
			(start -0.32512 0.175006)
			(end -0.32512 -0.175006)
			(stroke
				(width 0.1)
				(type default)
			)
			(layer "F.Fab")
		)
		(fp_line
			(start 0.32512 -0.175006)
			(end 0.32512 0.175006)
			(stroke
				(width 0.1)
				(type default)
			)
			(layer "F.Fab")
		)
		(fp_line
			(start 0.32512 0.175006)
			(end -0.32512 0.175006)
			(stroke
				(width 0.1)
				(type default)
			)
			(layer "F.Fab")
		)
		(pad "1" smd rect
			(at -0.2667 0)
			(size 0.3048 0.381)
			(layers "F.Cu" "F.Mask" "F.Paste")
			(net "P1V8_CPU1_RT_1D")
		)
		(pad "2" smd rect
			(at 0.2667 0 180)
			(size 0.3048 0.381)
			(layers "F.Cu" "F.Mask" "F.Paste")
			(net "GPIO2_RT_CPU1_P2")
		)
	)
	(footprint ""
		(layer "F.Cu")
		(at 348.93123 -20.136612 -90)
		(property "Reference" "Q12"
			(at -3.219196 -2.33553 90)
			(unlocked yes)
			(layer "F.SilkS")
			(effects
				(font
					(size 0.7874 0.5842)
					(thickness 0.1524)
				)
			)
		)
		(property "Value" ""
			(at 0 0 270)
			(layer "F.Fab")
			(effects
				(font
					(size 1.27 1.27)
				)
			)
		)
		(duplicate_pad_numbers_are_jumpers no)
		(fp_line
			(start -1.8796 1.651)
			(end -1.8796 -1.651)
			(stroke
				(width 0.1524)
				(type default)
			)
			(layer "F.SilkS")
		)
		(fp_line
			(start 1.8796 1.651)
			(end -1.8796 1.651)
			(stroke
				(width 0.1524)
				(type default)
			)
			(layer "F.SilkS")
		)
		(fp_line
			(start -1.8796 -1.651)
			(end 1.8796 -1.651)
			(stroke
				(width 0.1524)
				(type default)
			)
			(layer "F.SilkS")
		)
		(fp_line
			(start 1.8796 -1.651)
			(end 1.8796 1.651)
			(stroke
				(width 0.1524)
				(type default)
			)
			(layer "F.SilkS")
		)
		(fp_line
			(start -0.700024 1.500124)
			(end -0.700024 -1.500124)
			(stroke
				(width 0.1)
				(type default)
			)
			(layer "F.Fab")
		)
		(fp_line
			(start 0.700024 1.500124)
			(end -0.700024 1.500124)
			(stroke
				(width 0.1)
				(type default)
			)
			(layer "F.Fab")
		)
		(fp_line
			(start -0.700024 -1.500124)
			(end 0.700024 -1.500124)
			(stroke
				(width 0.1)
				(type default)
			)
			(layer "F.Fab")
		)
		(fp_line
			(start 0.700024 -1.500124)
			(end 0.700024 1.500124)
			(stroke
				(width 0.1)
				(type default)
			)
			(layer "F.Fab")
		)
		(pad "D" smd rect
			(at 1.119886 0 180)
			(size 1.016 1.2192)
			(layers "F.Cu" "F.Mask" "F.Paste")
			(net "P12V_ALL_PWROK_N")
		)
		(pad "G" smd rect
			(at -1.119886 -0.999998 180)
			(size 1.016 1.2192)
			(layers "F.Cu" "F.Mask" "F.Paste")
			(net "P12V_ALL_PWROK")
		)
		(pad "S" smd rect
			(at -1.119886 0.999998 180)
			(size 1.016 1.2192)
			(layers "F.Cu" "F.Mask" "F.Paste")
			(net "GND")
		)
	)
	(footprint ""
		(layer "F.Cu")
		(at 438.277 -96.357948 90)
		(property "Reference" "C2015"
			(at 0 0 90)
			(layer "F.SilkS")
			(hide yes)
			(effects
				(font
					(size 1.27 1.27)
				)
			)
		)
		(property "Value" ""
			(at 0 0 90)
			(layer "F.Fab")
			(effects
				(font
					(size 1.27 1.27)
				)
			)
		)
		(duplicate_pad_numbers_are_jumpers no)
		(fp_line
			(start 0.7874 -0.4064)
			(end 0.7874 0.4064)
			(stroke
				(width 0.1524)
				(type default)
			)
			(layer "F.SilkS")
		)
		(fp_line
			(start -0.7874 -0.4064)
			(end 0.7874 -0.4064)
			(stroke
				(width 0.1524)
				(type default)
			)
			(layer "F.SilkS")
		)
		(fp_line
			(start 0.7874 0.4064)
			(end -0.7874 0.4064)
			(stroke
				(width 0.1524)
				(type default)
			)
			(layer "F.SilkS")
		)
		(fp_line
			(start -0.7874 0.4064)
			(end -0.7874 -0.4064)
			(stroke
				(width 0.1524)
				(type default)
			)
			(layer "F.SilkS")
		)
		(fp_line
			(start -0.12065 -0.305054)
			(end -0.12065 -0.2794)
			(stroke
				(width 0.1)
				(type default)
			)
			(layer "F.Fab")
		)
		(fp_line
			(start -0.67945 -0.305054)
			(end -0.12065 -0.305054)
			(stroke
				(width 0.1)
				(type default)
			)
			(layer "F.Fab")
		)
		(fp_line
			(start 0.67945 -0.3048)
			(end 0.67945 0.3048)
			(stroke
				(width 0.1)
				(type default)
			)
			(layer "F.Fab")
		)
		(fp_line
			(start 0.12065 -0.3048)
			(end 0.67945 -0.3048)
			(stroke
				(width 0.1)
				(type default)
			)
			(layer "F.Fab")
		)
		(fp_line
			(start 0.12065 -0.2794)
			(end 0.12065 -0.3048)
			(stroke
				(width 0.1)
				(type default)
			)
			(layer "F.Fab")
		)
		(fp_line
			(start -0.12065 -0.2794)
			(end 0.12065 -0.2794)
			(stroke
				(width 0.1)
				(type default)
			)
			(layer "F.Fab")
		)
		(fp_line
			(start 0.120396 0.2794)
			(end -0.12065 0.2794)
			(stroke
				(width 0.1)
				(type default)
			)
			(layer "F.Fab")
		)
		(fp_line
			(start -0.12065 0.2794)
			(end -0.12065 0.3048)
			(stroke
				(width 0.1)
				(type default)
			)
			(layer "F.Fab")
		)
		(fp_line
			(start 0.67945 0.3048)
			(end 0.120396 0.3048)
			(stroke
				(width 0.1)
				(type default)
			)
			(layer "F.Fab")
		)
		(fp_line
			(start 0.120396 0.3048)
			(end 0.120396 0.2794)
			(stroke
				(width 0.1)
				(type default)
			)
			(layer "F.Fab")
		)
		(fp_line
			(start -0.12065 0.3048)
			(end -0.67945 0.3048)
			(stroke
				(width 0.1)
				(type default)
			)
			(layer "F.Fab")
		)
		(fp_line
			(start -0.67945 0.3048)
			(end -0.67945 -0.305054)
			(stroke
				(width 0.1)
				(type default)
			)
			(layer "F.Fab")
		)
		(pad "1" smd circle
			(at -0.40005 0 90)
			(size 0 0)
			(layers "F.Cu" "F.Mask" "F.Paste")
			(net "P3V3_AUX")
		)
		(pad "2" smd circle
			(at 0.40005 0 90)
			(size 0 0)
			(layers "F.Cu" "F.Mask" "F.Paste")
			(net "GND")
		)
	)
	(footprint ""
		(layer "F.Cu")
		(at 122.809 -321.655948 90)
		(property "Reference" "R4305"
			(at 0 0 90)
			(layer "F.SilkS")
			(hide yes)
			(effects
				(font
					(size 1.27 1.27)
				)
			)
		)
		(property "Value" ""
			(at 0 0 90)
			(layer "F.Fab")
			(effects
				(font
					(size 1.27 1.27)
				)
			)
		)
		(duplicate_pad_numbers_are_jumpers no)
		(fp_line
			(start 0.7874 -0.4064)
			(end 0.7874 -0.0508)
			(stroke
				(width 0.1524)
				(type default)
			)
			(layer "F.SilkS")
		)
		(fp_line
			(start -0.7874 -0.4064)
			(end 0.7874 -0.4064)
			(stroke
				(width 0.1524)
				(type default)
			)
			(layer "F.SilkS")
		)
		(fp_line
			(start -0.7874 -0.0508)
			(end -0.7874 -0.4064)
			(stroke
				(width 0.1524)
				(type default)
			)
			(layer "F.SilkS")
		)
		(fp_line
			(start 0.416052 0.4064)
			(end -0.422148 0.4064)
			(stroke
				(width 0.1524)
				(type default)
			)
			(layer "F.SilkS")
		)
		(fp_line
			(start -0.12065 -0.305054)
			(end -0.12065 -0.2794)
			(stroke
				(width 0.1)
				(type default)
			)
			(layer "F.Fab")
		)
		(fp_line
			(start -0.67945 -0.305054)
			(end -0.12065 -0.305054)
			(stroke
				(width 0.1)
				(type default)
			)
			(layer "F.Fab")
		)
		(fp_line
			(start 0.67945 -0.3048)
			(end 0.67945 0.3048)
			(stroke
				(width 0.1)
				(type default)
			)
			(layer "F.Fab")
		)
		(fp_line
			(start 0.12065 -0.3048)
			(end 0.67945 -0.3048)
			(stroke
				(width 0.1)
				(type default)
			)
			(layer "F.Fab")
		)
		(fp_line
			(start 0.12065 -0.2794)
			(end 0.12065 -0.3048)
			(stroke
				(width 0.1)
				(type default)
			)
			(layer "F.Fab")
		)
		(fp_line
			(start -0.12065 -0.2794)
			(end 0.12065 -0.2794)
			(stroke
				(width 0.1)
				(type default)
			)
			(layer "F.Fab")
		)
		(fp_line
			(start 0.120396 0.2794)
			(end -0.12065 0.2794)
			(stroke
				(width 0.1)
				(type default)
			)
			(layer "F.Fab")
		)
		(fp_line
			(start -0.12065 0.2794)
			(end -0.12065 0.3048)
			(stroke
				(width 0.1)
				(type default)
			)
			(layer "F.Fab")
		)
		(fp_line
			(start 0.67945 0.3048)
			(end 0.120396 0.3048)
			(stroke
				(width 0.1)
				(type default)
			)
			(layer "F.Fab")
		)
		(fp_line
			(start 0.120396 0.3048)
			(end 0.120396 0.2794)
			(stroke
				(width 0.1)
				(type default)
			)
			(layer "F.Fab")
		)
		(fp_line
			(start -0.12065 0.3048)
			(end -0.67945 0.3048)
			(stroke
				(width 0.1)
				(type default)
			)
			(layer "F.Fab")
		)
		(fp_line
			(start -0.67945 0.3048)
			(end -0.67945 -0.305054)
			(stroke
				(width 0.1)
				(type default)
			)
			(layer "F.Fab")
		)
		(pad "1" smd circle
			(at -0.40005 0 90)
			(size 0 0)
			(layers "F.Cu" "F.Mask" "F.Paste")
			(net "CLK_100M_CPU1_CLK12_R_DP")
		)
		(pad "2" smd circle
			(at 0.40005 0 90)
			(size 0 0)
			(layers "F.Cu" "F.Mask" "F.Paste")
			(net "CLK_100M_CPU1_CLK12_DP")
		)
	)
	(footprint ""
		(layer "F.Cu")
		(at 112.716056 -340.315042)
		(property "Reference" "H21"
			(at -3.900424 -4.48056 0)
			(unlocked yes)
			(layer "F.SilkS")
			(effects
				(font
					(size 0.7874 0.5842)
					(thickness 0.1524)
				)
				(justify left)
			)
		)
		(property "Value" ""
			(at 0 0 0)
			(layer "F.Fab")
			(effects
				(font
					(size 1.27 1.27)
				)
			)
		)
		(duplicate_pad_numbers_are_jumpers no)
		(pad "1" thru_hole circle
			(at 0 0)
			(size 6.1976 6.1976)
			(drill 3.7338)
			(layers "*.Cu" "*.Mask")
			(remove_unused_layers no)
			(net "GND")
			(clearance -0.9779)
			(padstack
				(mode front_inner_back)
				(layer "Inner"
					(shape circle)
					(size 5.5372 5.5372)
					(clearance -0.6477)
				)
				(layer "B.Cu"
					(shape circle)
					(size 6.1976 6.1976)
					(clearance -0.9779)
				)
			)
		)
	)
	(footprint ""
		(layer "F.Cu")
		(at 127.705104 -55.922164 180)
		(property "Reference" "R6103"
			(at 0 0 180)
			(layer "F.SilkS")
			(hide yes)
			(effects
				(font
					(size 1.27 1.27)
				)
			)
		)
		(property "Value" ""
			(at 0 0 180)
			(layer "F.Fab")
			(effects
				(font
					(size 1.27 1.27)
				)
			)
		)
		(duplicate_pad_numbers_are_jumpers no)
		(fp_line
			(start 0.7874 0.4064)
			(end -0.7874 0.4064)
			(stroke
				(width 0.1524)
				(type default)
			)
			(layer "F.SilkS")
		)
		(fp_line
			(start 0.7874 -0.4064)
			(end 0.7874 0.4064)
			(stroke
				(width 0.1524)
				(type default)
			)
			(layer "F.SilkS")
		)
		(fp_line
			(start -0.7874 0.4064)
			(end -0.7874 -0.4064)
			(stroke
				(width 0.1524)
				(type default)
			)
			(layer "F.SilkS")
		)
		(fp_line
			(start -0.7874 -0.4064)
			(end 0.7874 -0.4064)
			(stroke
				(width 0.1524)
				(type default)
			)
			(layer "F.SilkS")
		)
		(fp_line
			(start 0.67945 0.3048)
			(end 0.120396 0.3048)
			(stroke
				(width 0.1)
				(type default)
			)
			(layer "F.Fab")
		)
		(fp_line
			(start 0.67945 -0.3048)
			(end 0.67945 0.3048)
			(stroke
				(width 0.1)
				(type default)
			)
			(layer "F.Fab")
		)
		(fp_line
			(start 0.12065 -0.2794)
			(end 0.12065 -0.3048)
			(stroke
				(width 0.1)
				(type default)
			)
			(layer "F.Fab")
		)
		(fp_line
			(start 0.12065 -0.3048)
			(end 0.67945 -0.3048)
			(stroke
				(width 0.1)
				(type default)
			)
			(layer "F.Fab")
		)
		(fp_line
			(start 0.120396 0.3048)
			(end 0.120396 0.2794)
			(stroke
				(width 0.1)
				(type default)
			)
			(layer "F.Fab")
		)
		(fp_line
			(start 0.120396 0.2794)
			(end -0.12065 0.2794)
			(stroke
				(width 0.1)
				(type default)
			)
			(layer "F.Fab")
		)
		(fp_line
			(start -0.12065 0.3048)
			(end -0.67945 0.3048)
			(stroke
				(width 0.1)
				(type default)
			)
			(layer "F.Fab")
		)
		(fp_line
			(start -0.12065 0.2794)
			(end -0.12065 0.3048)
			(stroke
				(width 0.1)
				(type default)
			)
			(layer "F.Fab")
		)
		(fp_line
			(start -0.12065 -0.2794)
			(end 0.12065 -0.2794)
			(stroke
				(width 0.1)
				(type default)
			)
			(layer "F.Fab")
		)
		(fp_line
			(start -0.12065 -0.305054)
			(end -0.12065 -0.2794)
			(stroke
				(width 0.1)
				(type default)
			)
			(layer "F.Fab")
		)
		(fp_line
			(start -0.67945 0.3048)
			(end -0.67945 -0.305054)
			(stroke
				(width 0.1)
				(type default)
			)
			(layer "F.Fab")
		)
		(fp_line
			(start -0.67945 -0.305054)
			(end -0.12065 -0.305054)
			(stroke
				(width 0.1)
				(type default)
			)
			(layer "F.Fab")
		)
		(pad "1" smd circle
			(at -0.40005 0 180)
			(size 0 0)
			(layers "F.Cu" "F.Mask" "F.Paste")
			(net "JTAG_CPUX_TDI_R1")
		)
		(pad "2" smd circle
			(at 0.40005 0 180)
			(size 0 0)
			(layers "F.Cu" "F.Mask" "F.Paste")
			(net "JTAG_CPUX_TDI")
		)
	)
	(footprint ""
		(layer "F.Cu")
		(at 65.113154 -370.57203 -90)
		(property "Reference" "C813"
			(at 0 0 270)
			(layer "F.SilkS")
			(hide yes)
			(effects
				(font
					(size 1.27 1.27)
				)
			)
		)
		(property "Value" ""
			(at 0 0 270)
			(layer "F.Fab")
			(effects
				(font
					(size 1.27 1.27)
				)
			)
		)
		(duplicate_pad_numbers_are_jumpers no)
		(fp_line
			(start -0.299974 0.150114)
			(end -0.299974 -0.150114)
			(stroke
				(width 0.1)
				(type default)
			)
			(layer "F.Fab")
		)
		(fp_line
			(start 0.299974 0.150114)
			(end -0.299974 0.150114)
			(stroke
				(width 0.1)
				(type default)
			)
			(layer "F.Fab")
		)
		(fp_line
			(start -0.299974 -0.150114)
			(end 0.299974 -0.150114)
			(stroke
				(width 0.1)
				(type default)
			)
			(layer "F.Fab")
		)
		(fp_line
			(start 0.299974 -0.150114)
			(end 0.299974 0.150114)
			(stroke
				(width 0.1)
				(type default)
			)
			(layer "F.Fab")
		)
		(pad "1" smd rect
			(at -0.2667 0 270)
			(size 0.3048 0.381)
			(layers "F.Cu" "F.Mask" "F.Paste")
			(net "P5E_CPU1_P0_TX_C_DP<12>")
		)
		(pad "2" smd rect
			(at 0.2667 0 270)
			(size 0.3048 0.381)
			(layers "F.Cu" "F.Mask" "F.Paste")
			(net "P5E_CPU1_P0_TX_DP<12>")
		)
	)
	(footprint ""
		(layer "F.Cu")
		(at 403.682962 -62.0395 180)
		(property "Reference" "R478"
			(at 0 0 180)
			(layer "F.SilkS")
			(hide yes)
			(effects
				(font
					(size 1.27 1.27)
				)
			)
		)
		(property "Value" ""
			(at 0 0 180)
			(layer "F.Fab")
			(effects
				(font
					(size 1.27 1.27)
				)
			)
		)
		(duplicate_pad_numbers_are_jumpers no)
		(fp_line
			(start 0.7874 0.4064)
			(end -0.7874 0.4064)
			(stroke
				(width 0.1524)
				(type default)
			)
			(layer "F.SilkS")
		)
		(fp_line
			(start 0.7874 -0.4064)
			(end 0.7874 0.4064)
			(stroke
				(width 0.1524)
				(type default)
			)
			(layer "F.SilkS")
		)
		(fp_line
			(start -0.7874 0.4064)
			(end -0.7874 -0.4064)
			(stroke
				(width 0.1524)
				(type default)
			)
			(layer "F.SilkS")
		)
		(fp_line
			(start -0.7874 -0.4064)
			(end 0.7874 -0.4064)
			(stroke
				(width 0.1524)
				(type default)
			)
			(layer "F.SilkS")
		)
		(fp_line
			(start 0.67945 0.3048)
			(end 0.120396 0.3048)
			(stroke
				(width 0.1)
				(type default)
			)
			(layer "F.Fab")
		)
		(fp_line
			(start 0.67945 -0.3048)
			(end 0.67945 0.3048)
			(stroke
				(width 0.1)
				(type default)
			)
			(layer "F.Fab")
		)
		(fp_line
			(start 0.12065 -0.2794)
			(end 0.12065 -0.3048)
			(stroke
				(width 0.1)
				(type default)
			)
			(layer "F.Fab")
		)
		(fp_line
			(start 0.12065 -0.3048)
			(end 0.67945 -0.3048)
			(stroke
				(width 0.1)
				(type default)
			)
			(layer "F.Fab")
		)
		(fp_line
			(start 0.120396 0.3048)
			(end 0.120396 0.2794)
			(stroke
				(width 0.1)
				(type default)
			)
			(layer "F.Fab")
		)
		(fp_line
			(start 0.120396 0.2794)
			(end -0.12065 0.2794)
			(stroke
				(width 0.1)
				(type default)
			)
			(layer "F.Fab")
		)
		(fp_line
			(start -0.12065 0.3048)
			(end -0.67945 0.3048)
			(stroke
				(width 0.1)
				(type default)
			)
			(layer "F.Fab")
		)
		(fp_line
			(start -0.12065 0.2794)
			(end -0.12065 0.3048)
			(stroke
				(width 0.1)
				(type default)
			)
			(layer "F.Fab")
		)
		(fp_line
			(start -0.12065 -0.2794)
			(end 0.12065 -0.2794)
			(stroke
				(width 0.1)
				(type default)
			)
			(layer "F.Fab")
		)
		(fp_line
			(start -0.12065 -0.305054)
			(end -0.12065 -0.2794)
			(stroke
				(width 0.1)
				(type default)
			)
			(layer "F.Fab")
		)
		(fp_line
			(start -0.67945 0.3048)
			(end -0.67945 -0.305054)
			(stroke
				(width 0.1)
				(type default)
			)
			(layer "F.Fab")
		)
		(fp_line
			(start -0.67945 -0.305054)
			(end -0.12065 -0.305054)
			(stroke
				(width 0.1)
				(type default)
			)
			(layer "F.Fab")
		)
		(pad "1" smd circle
			(at -0.40005 0 180)
			(size 0 0)
			(layers "F.Cu" "F.Mask" "F.Paste")
			(net "CPU0_XTRIG_L5")
		)
		(pad "2" smd circle
			(at 0.40005 0 180)
			(size 0 0)
			(layers "F.Cu" "F.Mask" "F.Paste")
			(net "HDT_CPU0_XTRIG_L5")
		)
	)
	(footprint ""
		(layer "F.Cu")
		(at 366.114076 -75.652122)
		(property "Reference" "ME29"
			(at 0 0 0)
			(layer "F.SilkS")
			(hide yes)
			(effects
				(font
					(size 1.27 1.27)
				)
			)
		)
		(property "Value" ""
			(at 0 0 0)
			(layer "F.Fab")
			(effects
				(font
					(size 1.27 1.27)
				)
			)
		)
		(duplicate_pad_numbers_are_jumpers no)
		(fp_line
			(start 0 -4.99999)
			(end 0 -3.47599)
			(stroke
				(width 0.1524)
				(type default)
			)
			(layer "F.SilkS")
		)
		(fp_line
			(start 0 -1.524)
			(end 0 0)
			(stroke
				(width 0.1524)
				(type default)
			)
			(layer "F.SilkS")
		)
		(fp_line
			(start 0 0)
			(end 1.524 0)
			(stroke
				(width 0.1524)
				(type default)
			)
			(layer "F.SilkS")
		)
		(fp_line
			(start 1.524 -4.99999)
			(end 0 -4.99999)
			(stroke
				(width 0.1524)
				(type default)
			)
			(layer "F.SilkS")
		)
		(fp_line
			(start 13.47597 0)
			(end 14.99997 0)
			(stroke
				(width 0.1524)
				(type default)
			)
			(layer "F.SilkS")
		)
		(fp_line
			(start 14.99997 -4.99999)
			(end 13.47597 -4.99999)
			(stroke
				(width 0.1524)
				(type default)
			)
			(layer "F.SilkS")
		)
		(fp_line
			(start 14.99997 -3.47599)
			(end 14.99997 -4.99999)
			(stroke
				(width 0.1524)
				(type default)
			)
			(layer "F.SilkS")
		)
		(fp_line
			(start 14.99997 0)
			(end 14.99997 -1.524)
			(stroke
				(width 0.1524)
				(type default)
			)
			(layer "F.SilkS")
		)
		(fp_text user "S/N"
			(at 0.1016 -3.54965 0)
			(unlocked yes)
			(layer "F.SilkS")
			(effects
				(font
					(size 1.905 1.4224)
					(thickness 0.1524)
				)
				(justify left)
			)
		)
	)
	(footprint ""
		(layer "F.Cu")
		(at 416.51174 -57.372758)
		(property "Reference" "U240"
			(at -2.3876 -2.250948 0)
			(unlocked yes)
			(layer "F.SilkS")
			(effects
				(font
					(size 0.7874 0.5842)
					(thickness 0.1524)
				)
				(justify left)
			)
		)
		(property "Value" ""
			(at 0 0 0)
			(layer "F.Fab")
			(effects
				(font
					(size 1.27 1.27)
				)
			)
		)
		(duplicate_pad_numbers_are_jumpers no)
		(fp_line
			(start -1.207008 -1.549908)
			(end -1.207008 1.549908)
			(stroke
				(width 0.1524)
				(type default)
			)
			(layer "F.SilkS")
		)
		(fp_line
			(start -1.207008 1.549908)
			(end 1.207008 1.549908)
			(stroke
				(width 0.1524)
				(type default)
			)
			(layer "F.SilkS")
		)
		(fp_line
			(start -0.762508 -1.549908)
			(end -1.207008 -1.549908)
			(stroke
				(width 0.1524)
				(type default)
			)
			(layer "F.SilkS")
		)
		(fp_line
			(start 0 -0.635)
			(end -0.762508 -1.549908)
			(stroke
				(width 0.1524)
				(type default)
			)
			(layer "F.SilkS")
		)
		(fp_line
			(start 0.762508 -1.549908)
			(end 0 -0.635)
			(stroke
				(width 0.1524)
				(type default)
			)
			(layer "F.SilkS")
		)
		(fp_line
			(start 1.207008 -1.549908)
			(end 0.762508 -1.549908)
			(stroke
				(width 0.1524)
				(type default)
			)
			(layer "F.SilkS")
		)
		(fp_line
			(start 1.207008 1.549908)
			(end 1.207008 -1.549908)
			(stroke
				(width 0.1524)
				(type default)
			)
			(layer "F.SilkS")
		)
		(fp_poly
			(pts
				(xy -2.3876 -1.02489) (xy -3.4036 -0.51689) (xy -3.4036 -1.53289)
			)
			(stroke
				(width 0)
				(type default)
			)
			(fill yes)
			(layer "F.SilkS")
		)
		(fp_line
			(start -1.549908 -1.549908)
			(end -1.549908 1.549908)
			(stroke
				(width 0.1)
				(type default)
			)
			(layer "F.Fab")
		)
		(fp_line
			(start -1.549908 1.549908)
			(end 1.549908 1.549908)
			(stroke
				(width 0.1)
				(type default)
			)
			(layer "F.Fab")
		)
		(fp_line
			(start 1.549908 -1.549908)
			(end -1.549908 -1.549908)
			(stroke
				(width 0.1)
				(type default)
			)
			(layer "F.Fab")
		)
		(fp_line
			(start 1.549908 1.549908)
			(end 1.549908 -1.549908)
			(stroke
				(width 0.1)
				(type default)
			)
			(layer "F.Fab")
		)
		(fp_poly
			(pts
				(xy -3.4036 -1.53289) (xy -3.4036 -0.51689) (xy -2.3876 -1.02489)
			)
			(stroke
				(width 0)
				(type default)
			)
			(fill yes)
			(layer "F.Fab")
		)
		(pad "1" smd rect
			(at -1.774952 -1.02489 270)
			(size 0.508 0.8636)
			(layers "F.Cu" "F.Mask" "F.Paste")
			(net "OCP_SFF_PRSNT0_R_N")
		)
		(pad "2" smd rect
			(at -1.774952 -0.32512 270)
			(size 0.4064 0.8636)
			(layers "F.Cu" "F.Mask" "F.Paste")
			(net "OCP_SFF_PRSNT1_R_N")
		)
		(pad "3" smd rect
			(at -1.774952 0.32512 270)
			(size 0.4064 0.8636)
			(layers "F.Cu" "F.Mask" "F.Paste")
			(net "OCP_SFF_PRSNT23_R_N")
		)
		(pad "4" smd rect
			(at -1.774952 1.02489 270)
			(size 0.508 0.8636)
			(layers "F.Cu" "F.Mask" "F.Paste")
			(net "GND")
		)
		(pad "5" smd rect
			(at 1.774952 1.02489 270)
			(size 0.508 0.8636)
			(layers "F.Cu" "F.Mask" "F.Paste")
			(net "OCP_SFF_PRSNT2_R_N")
		)
		(pad "6" smd rect
			(at 1.774952 0.32512 270)
			(size 0.4064 0.8636)
			(layers "F.Cu" "F.Mask" "F.Paste")
			(net "OCP_SFF_PRSNT3_R_N")
		)
		(pad "7" smd rect
			(at 1.774952 -0.32512 270)
			(size 0.4064 0.8636)
			(layers "F.Cu" "F.Mask" "F.Paste")
			(net "OCP_SFF_PRSNT01_R_N")
		)
		(pad "8" smd rect
			(at 1.774952 -1.02489 270)
			(size 0.508 0.8636)
			(layers "F.Cu" "F.Mask" "F.Paste")
			(net "P3V3_AUX")
		)
	)
	(footprint ""
		(layer "F.Cu")
		(at 80.173322 -176.40935)
		(property "Reference" "PC260_1"
			(at 0 0 0)
			(layer "F.SilkS")
			(hide yes)
			(effects
				(font
					(size 1.27 1.27)
				)
			)
		)
		(property "Value" ""
			(at 0 0 0)
			(layer "F.Fab")
			(effects
				(font
					(size 1.27 1.27)
				)
			)
		)
		(duplicate_pad_numbers_are_jumpers no)
		(fp_line
			(start -0.7874 -0.4064)
			(end 0.7874 -0.4064)
			(stroke
				(width 0.1524)
				(type default)
			)
			(layer "F.SilkS")
		)
		(fp_line
			(start -0.7874 0.4064)
			(end -0.7874 -0.4064)
			(stroke
				(width 0.1524)
				(type default)
			)
			(layer "F.SilkS")
		)
		(fp_line
			(start 0.7874 -0.4064)
			(end 0.7874 0.4064)
			(stroke
				(width 0.1524)
				(type default)
			)
			(layer "F.SilkS")
		)
		(fp_line
			(start 0.7874 0.4064)
			(end -0.7874 0.4064)
			(stroke
				(width 0.1524)
				(type default)
			)
			(layer "F.SilkS")
		)
		(fp_line
			(start -0.67945 -0.305054)
			(end -0.12065 -0.305054)
			(stroke
				(width 0.1)
				(type default)
			)
			(layer "F.Fab")
		)
		(fp_line
			(start -0.67945 0.3048)
			(end -0.67945 -0.305054)
			(stroke
				(width 0.1)
				(type default)
			)
			(layer "F.Fab")
		)
		(fp_line
			(start -0.12065 -0.305054)
			(end -0.12065 -0.2794)
			(stroke
				(width 0.1)
				(type default)
			)
			(layer "F.Fab")
		)
		(fp_line
			(start -0.12065 -0.2794)
			(end 0.12065 -0.2794)
			(stroke
				(width 0.1)
				(type default)
			)
			(layer "F.Fab")
		)
		(fp_line
			(start -0.12065 0.2794)
			(end -0.12065 0.3048)
			(stroke
				(width 0.1)
				(type default)
			)
			(layer "F.Fab")
		)
		(fp_line
			(start -0.12065 0.3048)
			(end -0.67945 0.3048)
			(stroke
				(width 0.1)
				(type default)
			)
			(layer "F.Fab")
		)
		(fp_line
			(start 0.120396 0.2794)
			(end -0.12065 0.2794)
			(stroke
				(width 0.1)
				(type default)
			)
			(layer "F.Fab")
		)
		(fp_line
			(start 0.120396 0.3048)
			(end 0.120396 0.2794)
			(stroke
				(width 0.1)
				(type default)
			)
			(layer "F.Fab")
		)
		(fp_line
			(start 0.12065 -0.3048)
			(end 0.67945 -0.3048)
			(stroke
				(width 0.1)
				(type default)
			)
			(layer "F.Fab")
		)
		(fp_line
			(start 0.12065 -0.2794)
			(end 0.12065 -0.3048)
			(stroke
				(width 0.1)
				(type default)
			)
			(layer "F.Fab")
		)
		(fp_line
			(start 0.67945 -0.3048)
			(end 0.67945 0.3048)
			(stroke
				(width 0.1)
				(type default)
			)
			(layer "F.Fab")
		)
		(fp_line
			(start 0.67945 0.3048)
			(end 0.120396 0.3048)
			(stroke
				(width 0.1)
				(type default)
			)
			(layer "F.Fab")
		)
		(pad "1" smd circle
			(at -0.40005 0)
			(size 0 0)
			(layers "F.Cu" "F.Mask" "F.Paste")
			(net "SW_P12V_AUX_PVDDCR_CPU0_P1_FLT")
		)
		(pad "2" smd circle
			(at 0.40005 0)
			(size 0 0)
			(layers "F.Cu" "F.Mask" "F.Paste")
			(net "GND")
		)
	)
	(footprint ""
		(layer "F.Cu")
		(at 380.058422 -416.899344 -90)
		(property "Reference" "C6572"
			(at 0 0 270)
			(layer "F.SilkS")
			(hide yes)
			(effects
				(font
					(size 1.27 1.27)
				)
			)
		)
		(property "Value" ""
			(at 0 0 270)
			(layer "F.Fab")
			(effects
				(font
					(size 1.27 1.27)
				)
			)
		)
		(duplicate_pad_numbers_are_jumpers no)
		(fp_line
			(start -0.299974 0.150114)
			(end -0.299974 -0.150114)
			(stroke
				(width 0.1)
				(type default)
			)
			(layer "F.Fab")
		)
		(fp_line
			(start 0.299974 0.150114)
			(end -0.299974 0.150114)
			(stroke
				(width 0.1)
				(type default)
			)
			(layer "F.Fab")
		)
		(fp_line
			(start -0.299974 -0.150114)
			(end 0.299974 -0.150114)
			(stroke
				(width 0.1)
				(type default)
			)
			(layer "F.Fab")
		)
		(fp_line
			(start 0.299974 -0.150114)
			(end 0.299974 0.150114)
			(stroke
				(width 0.1)
				(type default)
			)
			(layer "F.Fab")
		)
		(pad "1" smd rect
			(at -0.2667 0 270)
			(size 0.3048 0.381)
			(layers "F.Cu" "F.Mask" "F.Paste")
			(net "P5E_CPU0_P2_TX_BUF_C_DN<3>")
		)
		(pad "2" smd rect
			(at 0.2667 0 270)
			(size 0.3048 0.381)
			(layers "F.Cu" "F.Mask" "F.Paste")
			(net "P5E_CPU0_P2_TX_BUF_DN<3>")
		)
	)
	(footprint ""
		(layer "F.Cu")
		(at 372.896892 -381.41783 -90)
		(property "Reference" "C891"
			(at 0 0 270)
			(layer "F.SilkS")
			(hide yes)
			(effects
				(font
					(size 1.27 1.27)
				)
			)
		)
		(property "Value" ""
			(at 0 0 270)
			(layer "F.Fab")
			(effects
				(font
					(size 1.27 1.27)
				)
			)
		)
		(duplicate_pad_numbers_are_jumpers no)
		(fp_line
			(start -0.299974 0.150114)
			(end -0.299974 -0.150114)
			(stroke
				(width 0.1)
				(type default)
			)
			(layer "F.Fab")
		)
		(fp_line
			(start 0.299974 0.150114)
			(end -0.299974 0.150114)
			(stroke
				(width 0.1)
				(type default)
			)
			(layer "F.Fab")
		)
		(fp_line
			(start -0.299974 -0.150114)
			(end 0.299974 -0.150114)
			(stroke
				(width 0.1)
				(type default)
			)
			(layer "F.Fab")
		)
		(fp_line
			(start 0.299974 -0.150114)
			(end 0.299974 0.150114)
			(stroke
				(width 0.1)
				(type default)
			)
			(layer "F.Fab")
		)
		(pad "1" smd rect
			(at -0.2667 0 270)
			(size 0.3048 0.381)
			(layers "F.Cu" "F.Mask" "F.Paste")
			(net "P5E_CPU0_P3_TX_C_DP<5>")
		)
		(pad "2" smd rect
			(at 0.2667 0 270)
			(size 0.3048 0.381)
			(layers "F.Cu" "F.Mask" "F.Paste")
			(net "P5E_CPU0_P3_TX_DP<5>")
		)
	)
	(footprint ""
		(layer "F.Cu")
		(at 225.228912 -277.572978 180)
		(property "Reference" "PC6801"
			(at 3.359912 4.213352 0)
			(unlocked yes)
			(layer "F.SilkS")
			(effects
				(font
					(size 0.7874 0.5842)
					(thickness 0.1524)
				)
				(justify left)
			)
		)
		(property "Value" ""
			(at 0 0 180)
			(layer "F.Fab")
			(effects
				(font
					(size 1.27 1.27)
				)
			)
		)
		(duplicate_pad_numbers_are_jumpers no)
		(fp_line
			(start 3.400044 3.400044)
			(end -2.146046 3.400044)
			(stroke
				(width 0.1524)
				(type default)
			)
			(layer "F.SilkS")
		)
		(fp_line
			(start 3.400044 0.9398)
			(end 3.400044 3.400044)
			(stroke
				(width 0.1524)
				(type default)
			)
			(layer "F.SilkS")
		)
		(fp_line
			(start 3.400044 -0.9398)
			(end 3.400044 -3.400044)
			(stroke
				(width 0.1524)
				(type default)
			)
			(layer "F.SilkS")
		)
		(fp_line
			(start 3.400044 -3.400044)
			(end -2.146046 -3.400044)
			(stroke
				(width 0.1524)
				(type default)
			)
			(layer "F.SilkS")
		)
		(fp_line
			(start -2.146046 3.400044)
			(end -3.400044 2.146046)
			(stroke
				(width 0.1524)
				(type default)
			)
			(layer "F.SilkS")
		)
		(fp_line
			(start -2.146046 -3.400044)
			(end -3.400044 -2.146046)
			(stroke
				(width 0.1524)
				(type default)
			)
			(layer "F.SilkS")
		)
		(fp_line
			(start -3.400044 2.146046)
			(end -3.400044 0.9398)
			(stroke
				(width 0.1524)
				(type default)
			)
			(layer "F.SilkS")
		)
		(fp_line
			(start -3.400044 -2.146046)
			(end -3.400044 -0.9398)
			(stroke
				(width 0.1524)
				(type default)
			)
			(layer "F.SilkS")
		)
		(fp_line
			(start 3.400044 3.400044)
			(end 3.400044 -3.400044)
			(stroke
				(width 0.1)
				(type default)
			)
			(layer "F.Fab")
		)
		(fp_line
			(start 3.400044 -3.400044)
			(end -3.400044 -3.400044)
			(stroke
				(width 0.1)
				(type default)
			)
			(layer "F.Fab")
		)
		(fp_line
			(start -3.400044 3.400044)
			(end 3.400044 3.400044)
			(stroke
				(width 0.1)
				(type default)
			)
			(layer "F.Fab")
		)
		(fp_line
			(start -3.400044 -3.400044)
			(end -3.400044 3.400044)
			(stroke
				(width 0.1)
				(type default)
			)
			(layer "F.Fab")
		)
		(pad "1" smd rect
			(at -2.70002 0 90)
			(size 1.6002 3.5052)
			(layers "F.Cu" "F.Mask" "F.Paste")
			(net "SW_P12V_AUX_P1V8_RETIMER_CPU1_FLT")
		)
		(pad "2" smd rect
			(at 2.70002 0 90)
			(size 1.6002 3.5052)
			(layers "F.Cu" "F.Mask" "F.Paste")
			(net "GND")
		)
	)
	(footprint ""
		(layer "F.Cu")
		(at 331.517498 -144.086834 90)
		(property "Reference" "PC209"
			(at 0 0 90)
			(layer "F.SilkS")
			(hide yes)
			(effects
				(font
					(size 1.27 1.27)
				)
			)
		)
		(property "Value" ""
			(at 0 0 90)
			(layer "F.Fab")
			(effects
				(font
					(size 1.27 1.27)
				)
			)
		)
		(duplicate_pad_numbers_are_jumpers no)
		(fp_line
			(start 0.7874 -0.4064)
			(end 0.7874 0.4064)
			(stroke
				(width 0.1524)
				(type default)
			)
			(layer "F.SilkS")
		)
		(fp_line
			(start -0.7874 -0.4064)
			(end 0.7874 -0.4064)
			(stroke
				(width 0.1524)
				(type default)
			)
			(layer "F.SilkS")
		)
		(fp_line
			(start 0.7874 0.4064)
			(end -0.7874 0.4064)
			(stroke
				(width 0.1524)
				(type default)
			)
			(layer "F.SilkS")
		)
		(fp_line
			(start -0.7874 0.4064)
			(end -0.7874 -0.4064)
			(stroke
				(width 0.1524)
				(type default)
			)
			(layer "F.SilkS")
		)
		(fp_line
			(start -0.12065 -0.305054)
			(end -0.12065 -0.2794)
			(stroke
				(width 0.1)
				(type default)
			)
			(layer "F.Fab")
		)
		(fp_line
			(start -0.67945 -0.305054)
			(end -0.12065 -0.305054)
			(stroke
				(width 0.1)
				(type default)
			)
			(layer "F.Fab")
		)
		(fp_line
			(start 0.67945 -0.3048)
			(end 0.67945 0.3048)
			(stroke
				(width 0.1)
				(type default)
			)
			(layer "F.Fab")
		)
		(fp_line
			(start 0.12065 -0.3048)
			(end 0.67945 -0.3048)
			(stroke
				(width 0.1)
				(type default)
			)
			(layer "F.Fab")
		)
		(fp_line
			(start 0.12065 -0.2794)
			(end 0.12065 -0.3048)
			(stroke
				(width 0.1)
				(type default)
			)
			(layer "F.Fab")
		)
		(fp_line
			(start -0.12065 -0.2794)
			(end 0.12065 -0.2794)
			(stroke
				(width 0.1)
				(type default)
			)
			(layer "F.Fab")
		)
		(fp_line
			(start 0.120396 0.2794)
			(end -0.12065 0.2794)
			(stroke
				(width 0.1)
				(type default)
			)
			(layer "F.Fab")
		)
		(fp_line
			(start -0.12065 0.2794)
			(end -0.12065 0.3048)
			(stroke
				(width 0.1)
				(type default)
			)
			(layer "F.Fab")
		)
		(fp_line
			(start 0.67945 0.3048)
			(end 0.120396 0.3048)
			(stroke
				(width 0.1)
				(type default)
			)
			(layer "F.Fab")
		)
		(fp_line
			(start 0.120396 0.3048)
			(end 0.120396 0.2794)
			(stroke
				(width 0.1)
				(type default)
			)
			(layer "F.Fab")
		)
		(fp_line
			(start -0.12065 0.3048)
			(end -0.67945 0.3048)
			(stroke
				(width 0.1)
				(type default)
			)
			(layer "F.Fab")
		)
		(fp_line
			(start -0.67945 0.3048)
			(end -0.67945 -0.305054)
			(stroke
				(width 0.1)
				(type default)
			)
			(layer "F.Fab")
		)
		(pad "1" smd circle
			(at -0.40005 0 90)
			(size 0 0)
			(layers "F.Cu" "F.Mask" "F.Paste")
			(net "SW_PVDD18_S5_P0_BST_R")
		)
		(pad "2" smd circle
			(at 0.40005 0 90)
			(size 0 0)
			(layers "F.Cu" "F.Mask" "F.Paste")
			(net "SW_PVDD18_S5_P0_SW")
		)
	)
	(footprint ""
		(layer "F.Cu")
		(at 408.541982 -416.899344 -90)
		(property "Reference" "C6589"
			(at 0 0 270)
			(layer "F.SilkS")
			(hide yes)
			(effects
				(font
					(size 1.27 1.27)
				)
			)
		)
		(property "Value" ""
			(at 0 0 270)
			(layer "F.Fab")
			(effects
				(font
					(size 1.27 1.27)
				)
			)
		)
		(duplicate_pad_numbers_are_jumpers no)
		(fp_line
			(start -0.299974 0.150114)
			(end -0.299974 -0.150114)
			(stroke
				(width 0.1)
				(type default)
			)
			(layer "F.Fab")
		)
		(fp_line
			(start 0.299974 0.150114)
			(end -0.299974 0.150114)
			(stroke
				(width 0.1)
				(type default)
			)
			(layer "F.Fab")
		)
		(fp_line
			(start -0.299974 -0.150114)
			(end 0.299974 -0.150114)
			(stroke
				(width 0.1)
				(type default)
			)
			(layer "F.Fab")
		)
		(fp_line
			(start 0.299974 -0.150114)
			(end 0.299974 0.150114)
			(stroke
				(width 0.1)
				(type default)
			)
			(layer "F.Fab")
		)
		(pad "1" smd rect
			(at -0.2667 0 270)
			(size 0.3048 0.381)
			(layers "F.Cu" "F.Mask" "F.Paste")
			(net "P5E_CPU0_P2_TX_BUF_C_DP<12>")
		)
		(pad "2" smd rect
			(at 0.2667 0 270)
			(size 0.3048 0.381)
			(layers "F.Cu" "F.Mask" "F.Paste")
			(net "P5E_CPU0_P2_TX_BUF_DP<12>")
		)
	)
	(footprint ""
		(layer "F.Cu")
		(at 69.741034 -379.471428)
		(property "Reference" "C807"
			(at 0 0 0)
			(layer "F.SilkS")
			(hide yes)
			(effects
				(font
					(size 1.27 1.27)
				)
			)
		)
		(property "Value" ""
			(at 0 0 0)
			(layer "F.Fab")
			(effects
				(font
					(size 1.27 1.27)
				)
			)
		)
		(duplicate_pad_numbers_are_jumpers no)
		(fp_line
			(start -0.299974 -0.150114)
			(end 0.299974 -0.150114)
			(stroke
				(width 0.1)
				(type default)
			)
			(layer "F.Fab")
		)
		(fp_line
			(start -0.299974 0.150114)
			(end -0.299974 -0.150114)
			(stroke
				(width 0.1)
				(type default)
			)
			(layer "F.Fab")
		)
		(fp_line
			(start 0.299974 -0.150114)
			(end 0.299974 0.150114)
			(stroke
				(width 0.1)
				(type default)
			)
			(layer "F.Fab")
		)
		(fp_line
			(start 0.299974 0.150114)
			(end -0.299974 0.150114)
			(stroke
				(width 0.1)
				(type default)
			)
			(layer "F.Fab")
		)
		(pad "1" smd rect
			(at -0.2667 0)
			(size 0.3048 0.381)
			(layers "F.Cu" "F.Mask" "F.Paste")
			(net "P5E_CPU1_P0_TX_C_DP<15>")
		)
		(pad "2" smd rect
			(at 0.2667 0)
			(size 0.3048 0.381)
			(layers "F.Cu" "F.Mask" "F.Paste")
			(net "P5E_CPU1_P0_TX_DP<15>")
		)
	)
	(footprint ""
		(layer "F.Cu")
		(at 233.2228 -285.2928)
		(property "Reference" "PC6522"
			(at 0 0 0)
			(layer "F.SilkS")
			(hide yes)
			(effects
				(font
					(size 1.27 1.27)
				)
			)
		)
		(property "Value" ""
			(at 0 0 0)
			(layer "F.Fab")
			(effects
				(font
					(size 1.27 1.27)
				)
			)
		)
		(duplicate_pad_numbers_are_jumpers no)
		(fp_line
			(start -1.524 -0.762)
			(end 1.524 -0.762)
			(stroke
				(width 0.1524)
				(type default)
			)
			(layer "F.SilkS")
		)
		(fp_line
			(start -1.524 0.762)
			(end -1.524 -0.762)
			(stroke
				(width 0.1524)
				(type default)
			)
			(layer "F.SilkS")
		)
		(fp_line
			(start 1.524 -0.762)
			(end 1.524 0.762)
			(stroke
				(width 0.1524)
				(type default)
			)
			(layer "F.SilkS")
		)
		(fp_line
			(start 1.524 0.762)
			(end -1.524 0.762)
			(stroke
				(width 0.1524)
				(type default)
			)
			(layer "F.SilkS")
		)
		(fp_line
			(start -1.1049 -0.724916)
			(end -1.1049 0.724916)
			(stroke
				(width 0.1)
				(type default)
			)
			(layer "F.Fab")
		)
		(fp_line
			(start -1.1049 0.724916)
			(end 1.1049 0.724916)
			(stroke
				(width 0.1)
				(type default)
			)
			(layer "F.Fab")
		)
		(fp_line
			(start 1.1049 -0.724916)
			(end -1.1049 -0.724916)
			(stroke
				(width 0.1)
				(type default)
			)
			(layer "F.Fab")
		)
		(fp_line
			(start 1.1049 0.724916)
			(end 1.1049 -0.724916)
			(stroke
				(width 0.1)
				(type default)
			)
			(layer "F.Fab")
		)
		(pad "1" smd rect
			(at -0.889 0 180)
			(size 1.016 1.27)
			(layers "F.Cu" "F.Mask" "F.Paste")
			(net "SW_P12V_AUX_P1V8_RETIMER_CPU1_FLT")
		)
		(pad "2" smd rect
			(at 0.889 0 180)
			(size 1.016 1.27)
			(layers "F.Cu" "F.Mask" "F.Paste")
			(net "GND")
		)
	)
	(footprint ""
		(layer "F.Cu")
		(at 396.258796 -410.144468 90)
		(property "Reference" "C7002"
			(at 0 0 90)
			(layer "F.SilkS")
			(hide yes)
			(effects
				(font
					(size 1.27 1.27)
				)
			)
		)
		(property "Value" ""
			(at 0 0 90)
			(layer "F.Fab")
			(effects
				(font
					(size 1.27 1.27)
				)
			)
		)
		(duplicate_pad_numbers_are_jumpers no)
		(fp_line
			(start 1.524 -0.762)
			(end 1.524 0.762)
			(stroke
				(width 0.1524)
				(type default)
			)
			(layer "F.SilkS")
		)
		(fp_line
			(start -1.524 -0.762)
			(end 1.524 -0.762)
			(stroke
				(width 0.1524)
				(type default)
			)
			(layer "F.SilkS")
		)
		(fp_line
			(start 1.524 0.762)
			(end -1.524 0.762)
			(stroke
				(width 0.1524)
				(type default)
			)
			(layer "F.SilkS")
		)
		(fp_line
			(start -1.524 0.762)
			(end -1.524 -0.762)
			(stroke
				(width 0.1524)
				(type default)
			)
			(layer "F.SilkS")
		)
		(fp_line
			(start 1.1049 -0.724916)
			(end -1.1049 -0.724916)
			(stroke
				(width 0.1)
				(type default)
			)
			(layer "F.Fab")
		)
		(fp_line
			(start -1.1049 -0.724916)
			(end -1.1049 0.724916)
			(stroke
				(width 0.1)
				(type default)
			)
			(layer "F.Fab")
		)
		(fp_line
			(start 1.1049 0.724916)
			(end 1.1049 -0.724916)
			(stroke
				(width 0.1)
				(type default)
			)
			(layer "F.Fab")
		)
		(fp_line
			(start -1.1049 0.724916)
			(end 1.1049 0.724916)
			(stroke
				(width 0.1)
				(type default)
			)
			(layer "F.Fab")
		)
		(pad "1" smd rect
			(at -0.889 0 270)
			(size 1.016 1.27)
			(layers "F.Cu" "F.Mask" "F.Paste")
			(net "P0V9_CPU0_RT_2D")
		)
		(pad "2" smd rect
			(at 0.889 0 270)
			(size 1.016 1.27)
			(layers "F.Cu" "F.Mask" "F.Paste")
			(net "GND")
		)
	)
	(footprint ""
		(layer "F.Cu")
		(at 308.716172 -111.60125)
		(property "Reference" "U1"
			(at -2.1082 -3.165348 0)
			(unlocked yes)
			(layer "F.SilkS")
			(effects
				(font
					(size 0.7874 0.5842)
					(thickness 0.1524)
				)
				(justify left)
			)
		)
		(property "Value" ""
			(at 0 0 0)
			(layer "F.Fab")
			(effects
				(font
					(size 1.27 1.27)
				)
			)
		)
		(duplicate_pad_numbers_are_jumpers no)
		(fp_line
			(start -1.8288 -2.500122)
			(end -1.8288 2.500122)
			(stroke
				(width 0.1524)
				(type default)
			)
			(layer "F.SilkS")
		)
		(fp_line
			(start -1.8288 2.500122)
			(end 1.8288 2.500122)
			(stroke
				(width 0.1524)
				(type default)
			)
			(layer "F.SilkS")
		)
		(fp_line
			(start -1.077722 -2.500122)
			(end -1.8288 -2.500122)
			(stroke
				(width 0.1524)
				(type default)
			)
			(layer "F.SilkS")
		)
		(fp_line
			(start 0 -1.4224)
			(end -1.077722 -2.500122)
			(stroke
				(width 0.1524)
				(type default)
			)
			(layer "F.SilkS")
		)
		(fp_line
			(start 1.077722 -2.500122)
			(end 0 -1.4224)
			(stroke
				(width 0.1524)
				(type default)
			)
			(layer "F.SilkS")
		)
		(fp_line
			(start 1.8288 -2.500122)
			(end 1.077722 -2.500122)
			(stroke
				(width 0.1524)
				(type default)
			)
			(layer "F.SilkS")
		)
		(fp_line
			(start 1.8288 2.500122)
			(end 1.8288 -2.500122)
			(stroke
				(width 0.1524)
				(type default)
			)
			(layer "F.SilkS")
		)
		(fp_poly
			(pts
				(xy -3.59791 -2.765044) (xy -4.675632 -3.1242) (xy -3.95732 -3.842766)
			)
			(stroke
				(width 0)
				(type default)
			)
			(fill yes)
			(layer "F.SilkS")
		)
		(fp_line
			(start -1.999996 -2.500122)
			(end -1.999996 2.500122)
			(stroke
				(width 0.1)
				(type default)
			)
			(layer "F.Fab")
		)
		(fp_line
			(start -1.999996 2.500122)
			(end 1.999996 2.500122)
			(stroke
				(width 0.1)
				(type default)
			)
			(layer "F.Fab")
		)
		(fp_line
			(start 1.999996 -2.500122)
			(end -1.999996 -2.500122)
			(stroke
				(width 0.1)
				(type default)
			)
			(layer "F.Fab")
		)
		(fp_line
			(start 1.999996 2.500122)
			(end 1.999996 -2.500122)
			(stroke
				(width 0.1)
				(type default)
			)
			(layer "F.Fab")
		)
		(fp_poly
			(pts
				(xy -4.5085 -2.413) (xy -4.5085 -1.397) (xy -3.4925 -1.905)
			)
			(stroke
				(width 0)
				(type default)
			)
			(fill yes)
			(layer "F.Fab")
		)
		(pad "1" smd rect
			(at -2.599944 -1.905 270)
			(size 0.889 1.27)
			(layers "F.Cu" "F.Mask" "F.Paste")
			(net "CPU_FRU_ADDR0")
		)
		(pad "2" smd rect
			(at -2.599944 -0.635 270)
			(size 0.889 1.27)
			(layers "F.Cu" "F.Mask" "F.Paste")
			(net "CPU_FRU_ADDR1")
		)
		(pad "3" smd rect
			(at -2.599944 0.635 270)
			(size 0.889 1.27)
			(layers "F.Cu" "F.Mask" "F.Paste")
			(net "CPU_FRU_ADDR2")
		)
		(pad "4" smd rect
			(at -2.599944 1.905 270)
			(size 0.889 1.27)
			(layers "F.Cu" "F.Mask" "F.Paste")
			(net "GND")
		)
		(pad "5" smd rect
			(at 2.599944 1.905 270)
			(size 0.889 1.27)
			(layers "F.Cu" "F.Mask" "F.Paste")
			(net "SMB_CPU_FRU_3V3AUX_SDA")
		)
		(pad "6" smd rect
			(at 2.599944 0.635 270)
			(size 0.889 1.27)
			(layers "F.Cu" "F.Mask" "F.Paste")
			(net "SMB_CPU_FRU_3V3AUX_SCL")
		)
		(pad "7" smd rect
			(at 2.599944 -0.635 270)
			(size 0.889 1.27)
			(layers "F.Cu" "F.Mask" "F.Paste")
			(net "PD_CPU_FRU_WP")
		)
		(pad "8" smd rect
			(at 2.599944 -1.905 270)
			(size 0.889 1.27)
			(layers "F.Cu" "F.Mask" "F.Paste")
			(net "P3V3_AUX")
		)
	)
	(footprint ""
		(layer "F.Cu")
		(at 395.794738 -393.9032 90)
		(property "Reference" "R1099"
			(at 0 0 90)
			(layer "F.SilkS")
			(hide yes)
			(effects
				(font
					(size 1.27 1.27)
				)
			)
		)
		(property "Value" ""
			(at 0 0 90)
			(layer "F.Fab")
			(effects
				(font
					(size 1.27 1.27)
				)
			)
		)
		(duplicate_pad_numbers_are_jumpers no)
		(fp_line
			(start 0.32512 -0.175006)
			(end 0.32512 0.175006)
			(stroke
				(width 0.1)
				(type default)
			)
			(layer "F.Fab")
		)
		(fp_line
			(start -0.32512 -0.175006)
			(end 0.32512 -0.175006)
			(stroke
				(width 0.1)
				(type default)
			)
			(layer "F.Fab")
		)
		(fp_line
			(start 0.32512 0.175006)
			(end -0.32512 0.175006)
			(stroke
				(width 0.1)
				(type default)
			)
			(layer "F.Fab")
		)
		(fp_line
			(start -0.32512 0.175006)
			(end -0.32512 -0.175006)
			(stroke
				(width 0.1)
				(type default)
			)
			(layer "F.Fab")
		)
		(pad "1" smd rect
			(at -0.2667 0 90)
			(size 0.3048 0.381)
			(layers "F.Cu" "F.Mask" "F.Paste")
			(net "P1V8_CPU0_RT_1D")
		)
		(pad "2" smd rect
			(at 0.2667 0 270)
			(size 0.3048 0.381)
			(layers "F.Cu" "F.Mask" "F.Paste")
			(net "RT_CPU0_P3_ADDR2")
		)
	)
	(footprint ""
		(layer "F.Cu")
		(at 211.102956 -30.276292 90)
		(property "Reference" "R3613"
			(at 0 0 90)
			(layer "F.SilkS")
			(hide yes)
			(effects
				(font
					(size 1.27 1.27)
				)
			)
		)
		(property "Value" ""
			(at 0 0 90)
			(layer "F.Fab")
			(effects
				(font
					(size 1.27 1.27)
				)
			)
		)
		(duplicate_pad_numbers_are_jumpers no)
		(fp_line
			(start 0.7874 -0.4064)
			(end 0.7874 0.4064)
			(stroke
				(width 0.1524)
				(type default)
			)
			(layer "F.SilkS")
		)
		(fp_line
			(start -0.7874 -0.4064)
			(end 0.7874 -0.4064)
			(stroke
				(width 0.1524)
				(type default)
			)
			(layer "F.SilkS")
		)
		(fp_line
			(start 0.7874 0.4064)
			(end -0.7874 0.4064)
			(stroke
				(width 0.1524)
				(type default)
			)
			(layer "F.SilkS")
		)
		(fp_line
			(start -0.7874 0.4064)
			(end -0.7874 -0.4064)
			(stroke
				(width 0.1524)
				(type default)
			)
			(layer "F.SilkS")
		)
		(fp_line
			(start -0.12065 -0.305054)
			(end -0.12065 -0.2794)
			(stroke
				(width 0.1)
				(type default)
			)
			(layer "F.Fab")
		)
		(fp_line
			(start -0.67945 -0.305054)
			(end -0.12065 -0.305054)
			(stroke
				(width 0.1)
				(type default)
			)
			(layer "F.Fab")
		)
		(fp_line
			(start 0.67945 -0.3048)
			(end 0.67945 0.3048)
			(stroke
				(width 0.1)
				(type default)
			)
			(layer "F.Fab")
		)
		(fp_line
			(start 0.12065 -0.3048)
			(end 0.67945 -0.3048)
			(stroke
				(width 0.1)
				(type default)
			)
			(layer "F.Fab")
		)
		(fp_line
			(start 0.12065 -0.2794)
			(end 0.12065 -0.3048)
			(stroke
				(width 0.1)
				(type default)
			)
			(layer "F.Fab")
		)
		(fp_line
			(start -0.12065 -0.2794)
			(end 0.12065 -0.2794)
			(stroke
				(width 0.1)
				(type default)
			)
			(layer "F.Fab")
		)
		(fp_line
			(start 0.120396 0.2794)
			(end -0.12065 0.2794)
			(stroke
				(width 0.1)
				(type default)
			)
			(layer "F.Fab")
		)
		(fp_line
			(start -0.12065 0.2794)
			(end -0.12065 0.3048)
			(stroke
				(width 0.1)
				(type default)
			)
			(layer "F.Fab")
		)
		(fp_line
			(start 0.67945 0.3048)
			(end 0.120396 0.3048)
			(stroke
				(width 0.1)
				(type default)
			)
			(layer "F.Fab")
		)
		(fp_line
			(start 0.120396 0.3048)
			(end 0.120396 0.2794)
			(stroke
				(width 0.1)
				(type default)
			)
			(layer "F.Fab")
		)
		(fp_line
			(start -0.12065 0.3048)
			(end -0.67945 0.3048)
			(stroke
				(width 0.1)
				(type default)
			)
			(layer "F.Fab")
		)
		(fp_line
			(start -0.67945 0.3048)
			(end -0.67945 -0.305054)
			(stroke
				(width 0.1)
				(type default)
			)
			(layer "F.Fab")
		)
		(pad "1" smd circle
			(at -0.40005 0 90)
			(size 0 0)
			(layers "F.Cu" "F.Mask" "F.Paste")
			(net "GND")
		)
		(pad "2" smd circle
			(at 0.40005 0 90)
			(size 0 0)
			(layers "F.Cu" "F.Mask" "F.Paste")
			(net "INA230_5_A0")
		)
	)
	(footprint ""
		(layer "F.Cu")
		(at 302.60417 -424.9547)
		(property "Reference" "R4137"
			(at 0 0 0)
			(layer "F.SilkS")
			(hide yes)
			(effects
				(font
					(size 1.27 1.27)
				)
			)
		)
		(property "Value" ""
			(at 0 0 0)
			(layer "F.Fab")
			(effects
				(font
					(size 1.27 1.27)
				)
			)
		)
		(duplicate_pad_numbers_are_jumpers no)
		(fp_line
			(start -0.7874 -0.4064)
			(end 0.7874 -0.4064)
			(stroke
				(width 0.1524)
				(type default)
			)
			(layer "F.SilkS")
		)
		(fp_line
			(start -0.7874 0.4064)
			(end -0.7874 -0.4064)
			(stroke
				(width 0.1524)
				(type default)
			)
			(layer "F.SilkS")
		)
		(fp_line
			(start 0.7874 -0.4064)
			(end 0.7874 0.4064)
			(stroke
				(width 0.1524)
				(type default)
			)
			(layer "F.SilkS")
		)
		(fp_line
			(start 0.7874 0.4064)
			(end -0.7874 0.4064)
			(stroke
				(width 0.1524)
				(type default)
			)
			(layer "F.SilkS")
		)
		(fp_line
			(start -0.67945 -0.305054)
			(end -0.12065 -0.305054)
			(stroke
				(width 0.1)
				(type default)
			)
			(layer "F.Fab")
		)
		(fp_line
			(start -0.67945 0.3048)
			(end -0.67945 -0.305054)
			(stroke
				(width 0.1)
				(type default)
			)
			(layer "F.Fab")
		)
		(fp_line
			(start -0.12065 -0.305054)
			(end -0.12065 -0.2794)
			(stroke
				(width 0.1)
				(type default)
			)
			(layer "F.Fab")
		)
		(fp_line
			(start -0.12065 -0.2794)
			(end 0.12065 -0.2794)
			(stroke
				(width 0.1)
				(type default)
			)
			(layer "F.Fab")
		)
		(fp_line
			(start -0.12065 0.2794)
			(end -0.12065 0.3048)
			(stroke
				(width 0.1)
				(type default)
			)
			(layer "F.Fab")
		)
		(fp_line
			(start -0.12065 0.3048)
			(end -0.67945 0.3048)
			(stroke
				(width 0.1)
				(type default)
			)
			(layer "F.Fab")
		)
		(fp_line
			(start 0.120396 0.2794)
			(end -0.12065 0.2794)
			(stroke
				(width 0.1)
				(type default)
			)
			(layer "F.Fab")
		)
		(fp_line
			(start 0.120396 0.3048)
			(end 0.120396 0.2794)
			(stroke
				(width 0.1)
				(type default)
			)
			(layer "F.Fab")
		)
		(fp_line
			(start 0.12065 -0.3048)
			(end 0.67945 -0.3048)
			(stroke
				(width 0.1)
				(type default)
			)
			(layer "F.Fab")
		)
		(fp_line
			(start 0.12065 -0.2794)
			(end 0.12065 -0.3048)
			(stroke
				(width 0.1)
				(type default)
			)
			(layer "F.Fab")
		)
		(fp_line
			(start 0.67945 -0.3048)
			(end 0.67945 0.3048)
			(stroke
				(width 0.1)
				(type default)
			)
			(layer "F.Fab")
		)
		(fp_line
			(start 0.67945 0.3048)
			(end 0.120396 0.3048)
			(stroke
				(width 0.1)
				(type default)
			)
			(layer "F.Fab")
		)
		(pad "1" smd circle
			(at -0.40005 0)
			(size 0 0)
			(layers "F.Cu" "F.Mask" "F.Paste")
			(net "P3V3_AUX")
		)
		(pad "2" smd circle
			(at 0.40005 0)
			(size 0 0)
			(layers "F.Cu" "F.Mask" "F.Paste")
			(net "GPU_3V3IO_RSVD3_FFU_N")
		)
	)
	(footprint ""
		(layer "F.Cu")
		(at 52.78501 -437.642)
		(property "Reference" "R3469"
			(at 0 0 0)
			(layer "F.SilkS")
			(hide yes)
			(effects
				(font
					(size 1.27 1.27)
				)
			)
		)
		(property "Value" ""
			(at 0 0 0)
			(layer "F.Fab")
			(effects
				(font
					(size 1.27 1.27)
				)
			)
		)
		(duplicate_pad_numbers_are_jumpers no)
		(fp_line
			(start -0.7874 -0.4064)
			(end 0.7874 -0.4064)
			(stroke
				(width 0.1524)
				(type default)
			)
			(layer "F.SilkS")
		)
		(fp_line
			(start -0.7874 0.4064)
			(end -0.7874 -0.4064)
			(stroke
				(width 0.1524)
				(type default)
			)
			(layer "F.SilkS")
		)
		(fp_line
			(start 0.7874 -0.4064)
			(end 0.7874 0.4064)
			(stroke
				(width 0.1524)
				(type default)
			)
			(layer "F.SilkS")
		)
		(fp_line
			(start 0.7874 0.4064)
			(end -0.7874 0.4064)
			(stroke
				(width 0.1524)
				(type default)
			)
			(layer "F.SilkS")
		)
		(fp_line
			(start -0.67945 -0.305054)
			(end -0.12065 -0.305054)
			(stroke
				(width 0.1)
				(type default)
			)
			(layer "F.Fab")
		)
		(fp_line
			(start -0.67945 0.3048)
			(end -0.67945 -0.305054)
			(stroke
				(width 0.1)
				(type default)
			)
			(layer "F.Fab")
		)
		(fp_line
			(start -0.12065 -0.305054)
			(end -0.12065 -0.2794)
			(stroke
				(width 0.1)
				(type default)
			)
			(layer "F.Fab")
		)
		(fp_line
			(start -0.12065 -0.2794)
			(end 0.12065 -0.2794)
			(stroke
				(width 0.1)
				(type default)
			)
			(layer "F.Fab")
		)
		(fp_line
			(start -0.12065 0.2794)
			(end -0.12065 0.3048)
			(stroke
				(width 0.1)
				(type default)
			)
			(layer "F.Fab")
		)
		(fp_line
			(start -0.12065 0.3048)
			(end -0.67945 0.3048)
			(stroke
				(width 0.1)
				(type default)
			)
			(layer "F.Fab")
		)
		(fp_line
			(start 0.120396 0.2794)
			(end -0.12065 0.2794)
			(stroke
				(width 0.1)
				(type default)
			)
			(layer "F.Fab")
		)
		(fp_line
			(start 0.120396 0.3048)
			(end 0.120396 0.2794)
			(stroke
				(width 0.1)
				(type default)
			)
			(layer "F.Fab")
		)
		(fp_line
			(start 0.12065 -0.3048)
			(end 0.67945 -0.3048)
			(stroke
				(width 0.1)
				(type default)
			)
			(layer "F.Fab")
		)
		(fp_line
			(start 0.12065 -0.2794)
			(end 0.12065 -0.3048)
			(stroke
				(width 0.1)
				(type default)
			)
			(layer "F.Fab")
		)
		(fp_line
			(start 0.67945 -0.3048)
			(end 0.67945 0.3048)
			(stroke
				(width 0.1)
				(type default)
			)
			(layer "F.Fab")
		)
		(fp_line
			(start 0.67945 0.3048)
			(end 0.120396 0.3048)
			(stroke
				(width 0.1)
				(type default)
			)
			(layer "F.Fab")
		)
		(pad "1" smd circle
			(at -0.40005 0)
			(size 0 0)
			(layers "F.Cu" "F.Mask" "F.Paste")
			(net "RST_PERST_0_SWB_BUF_R_N")
		)
		(pad "2" smd circle
			(at 0.40005 0)
			(size 0 0)
			(layers "F.Cu" "F.Mask" "F.Paste")
			(net "RST_PERST_0_SWB_BUF_N")
		)
	)
	(footprint ""
		(layer "F.Cu")
		(at 343.590626 -416.899344 -90)
		(property "Reference" "C6528"
			(at 0 0 270)
			(layer "F.SilkS")
			(hide yes)
			(effects
				(font
					(size 1.27 1.27)
				)
			)
		)
		(property "Value" ""
			(at 0 0 270)
			(layer "F.Fab")
			(effects
				(font
					(size 1.27 1.27)
				)
			)
		)
		(duplicate_pad_numbers_are_jumpers no)
		(fp_line
			(start -0.299974 0.150114)
			(end -0.299974 -0.150114)
			(stroke
				(width 0.1)
				(type default)
			)
			(layer "F.Fab")
		)
		(fp_line
			(start 0.299974 0.150114)
			(end -0.299974 0.150114)
			(stroke
				(width 0.1)
				(type default)
			)
			(layer "F.Fab")
		)
		(fp_line
			(start -0.299974 -0.150114)
			(end 0.299974 -0.150114)
			(stroke
				(width 0.1)
				(type default)
			)
			(layer "F.Fab")
		)
		(fp_line
			(start 0.299974 -0.150114)
			(end 0.299974 0.150114)
			(stroke
				(width 0.1)
				(type default)
			)
			(layer "F.Fab")
		)
		(pad "1" smd rect
			(at -0.2667 0 270)
			(size 0.3048 0.381)
			(layers "F.Cu" "F.Mask" "F.Paste")
			(net "P5E_CPU0_P0_TX_BUF_C_DN<13>")
		)
		(pad "2" smd rect
			(at 0.2667 0 270)
			(size 0.3048 0.381)
			(layers "F.Cu" "F.Mask" "F.Paste")
			(net "P5E_CPU0_P0_TX_BUF_DN<13>")
		)
	)
	(footprint ""
		(layer "F.Cu")
		(at 117.913912 -17.784064)
		(property "Reference" "C31"
			(at 0 0 0)
			(layer "F.SilkS")
			(hide yes)
			(effects
				(font
					(size 1.27 1.27)
				)
			)
		)
		(property "Value" ""
			(at 0 0 0)
			(layer "F.Fab")
			(effects
				(font
					(size 1.27 1.27)
				)
			)
		)
		(duplicate_pad_numbers_are_jumpers no)
		(fp_line
			(start -0.7874 -0.4064)
			(end 0.7874 -0.4064)
			(stroke
				(width 0.1524)
				(type default)
			)
			(layer "F.SilkS")
		)
		(fp_line
			(start -0.7874 0.4064)
			(end -0.7874 -0.4064)
			(stroke
				(width 0.1524)
				(type default)
			)
			(layer "F.SilkS")
		)
		(fp_line
			(start 0.7874 -0.4064)
			(end 0.7874 0.4064)
			(stroke
				(width 0.1524)
				(type default)
			)
			(layer "F.SilkS")
		)
		(fp_line
			(start 0.7874 0.4064)
			(end -0.7874 0.4064)
			(stroke
				(width 0.1524)
				(type default)
			)
			(layer "F.SilkS")
		)
		(fp_line
			(start -0.67945 -0.305054)
			(end -0.12065 -0.305054)
			(stroke
				(width 0.1)
				(type default)
			)
			(layer "F.Fab")
		)
		(fp_line
			(start -0.67945 0.3048)
			(end -0.67945 -0.305054)
			(stroke
				(width 0.1)
				(type default)
			)
			(layer "F.Fab")
		)
		(fp_line
			(start -0.12065 -0.305054)
			(end -0.12065 -0.2794)
			(stroke
				(width 0.1)
				(type default)
			)
			(layer "F.Fab")
		)
		(fp_line
			(start -0.12065 -0.2794)
			(end 0.12065 -0.2794)
			(stroke
				(width 0.1)
				(type default)
			)
			(layer "F.Fab")
		)
		(fp_line
			(start -0.12065 0.2794)
			(end -0.12065 0.3048)
			(stroke
				(width 0.1)
				(type default)
			)
			(layer "F.Fab")
		)
		(fp_line
			(start -0.12065 0.3048)
			(end -0.67945 0.3048)
			(stroke
				(width 0.1)
				(type default)
			)
			(layer "F.Fab")
		)
		(fp_line
			(start 0.120396 0.2794)
			(end -0.12065 0.2794)
			(stroke
				(width 0.1)
				(type default)
			)
			(layer "F.Fab")
		)
		(fp_line
			(start 0.120396 0.3048)
			(end 0.120396 0.2794)
			(stroke
				(width 0.1)
				(type default)
			)
			(layer "F.Fab")
		)
		(fp_line
			(start 0.12065 -0.3048)
			(end 0.67945 -0.3048)
			(stroke
				(width 0.1)
				(type default)
			)
			(layer "F.Fab")
		)
		(fp_line
			(start 0.12065 -0.2794)
			(end 0.12065 -0.3048)
			(stroke
				(width 0.1)
				(type default)
			)
			(layer "F.Fab")
		)
		(fp_line
			(start 0.67945 -0.3048)
			(end 0.67945 0.3048)
			(stroke
				(width 0.1)
				(type default)
			)
			(layer "F.Fab")
		)
		(fp_line
			(start 0.67945 0.3048)
			(end 0.120396 0.3048)
			(stroke
				(width 0.1)
				(type default)
			)
			(layer "F.Fab")
		)
		(pad "1" smd circle
			(at -0.40005 0)
			(size 0 0)
			(layers "F.Cu" "F.Mask" "F.Paste")
			(net "P3V3_AUX")
		)
		(pad "2" smd circle
			(at 0.40005 0)
			(size 0 0)
			(layers "F.Cu" "F.Mask" "F.Paste")
			(net "GND")
		)
	)
	(footprint ""
		(layer "F.Cu")
		(at 316.935866 -416.899344 -90)
		(property "Reference" "C6509"
			(at 0 0 270)
			(layer "F.SilkS")
			(hide yes)
			(effects
				(font
					(size 1.27 1.27)
				)
			)
		)
		(property "Value" ""
			(at 0 0 270)
			(layer "F.Fab")
			(effects
				(font
					(size 1.27 1.27)
				)
			)
		)
		(duplicate_pad_numbers_are_jumpers no)
		(fp_line
			(start -0.299974 0.150114)
			(end -0.299974 -0.150114)
			(stroke
				(width 0.1)
				(type default)
			)
			(layer "F.Fab")
		)
		(fp_line
			(start 0.299974 0.150114)
			(end -0.299974 0.150114)
			(stroke
				(width 0.1)
				(type default)
			)
			(layer "F.Fab")
		)
		(fp_line
			(start -0.299974 -0.150114)
			(end 0.299974 -0.150114)
			(stroke
				(width 0.1)
				(type default)
			)
			(layer "F.Fab")
		)
		(fp_line
			(start 0.299974 -0.150114)
			(end 0.299974 0.150114)
			(stroke
				(width 0.1)
				(type default)
			)
			(layer "F.Fab")
		)
		(pad "1" smd rect
			(at -0.2667 0 270)
			(size 0.3048 0.381)
			(layers "F.Cu" "F.Mask" "F.Paste")
			(net "P5E_CPU0_P0_TX_BUF_C_DP<4>")
		)
		(pad "2" smd rect
			(at 0.2667 0 270)
			(size 0.3048 0.381)
			(layers "F.Cu" "F.Mask" "F.Paste")
			(net "P5E_CPU0_P0_TX_BUF_DP<4>")
		)
	)
	(footprint ""
		(layer "F.Cu")
		(at 30.949392 -395.641576)
		(property "Reference" "PC6639"
			(at 0 0 0)
			(layer "F.SilkS")
			(hide yes)
			(effects
				(font
					(size 1.27 1.27)
				)
			)
		)
		(property "Value" ""
			(at 0 0 0)
			(layer "F.Fab")
			(effects
				(font
					(size 1.27 1.27)
				)
			)
		)
		(duplicate_pad_numbers_are_jumpers no)
		(fp_line
			(start -1.524 -0.762)
			(end 1.524 -0.762)
			(stroke
				(width 0.1524)
				(type default)
			)
			(layer "F.SilkS")
		)
		(fp_line
			(start -1.524 0.762)
			(end -1.524 -0.762)
			(stroke
				(width 0.1524)
				(type default)
			)
			(layer "F.SilkS")
		)
		(fp_line
			(start 1.524 -0.762)
			(end 1.524 0.762)
			(stroke
				(width 0.1524)
				(type default)
			)
			(layer "F.SilkS")
		)
		(fp_line
			(start 1.524 0.762)
			(end -1.524 0.762)
			(stroke
				(width 0.1524)
				(type default)
			)
			(layer "F.SilkS")
		)
		(fp_line
			(start -1.1049 -0.724916)
			(end -1.1049 0.724916)
			(stroke
				(width 0.1)
				(type default)
			)
			(layer "F.Fab")
		)
		(fp_line
			(start -1.1049 0.724916)
			(end 1.1049 0.724916)
			(stroke
				(width 0.1)
				(type default)
			)
			(layer "F.Fab")
		)
		(fp_line
			(start 1.1049 -0.724916)
			(end -1.1049 -0.724916)
			(stroke
				(width 0.1)
				(type default)
			)
			(layer "F.Fab")
		)
		(fp_line
			(start 1.1049 0.724916)
			(end 1.1049 -0.724916)
			(stroke
				(width 0.1)
				(type default)
			)
			(layer "F.Fab")
		)
		(pad "1" smd rect
			(at -0.889 0 180)
			(size 1.016 1.27)
			(layers "F.Cu" "F.Mask" "F.Paste")
			(net "SW_P12V_AUX_P0V9_RETIMER_CPU1_FLT")
		)
		(pad "2" smd rect
			(at 0.889 0 180)
			(size 1.016 1.27)
			(layers "F.Cu" "F.Mask" "F.Paste")
			(net "GND")
		)
	)
	(footprint ""
		(layer "F.Cu")
		(at 125.095 -321.655948 90)
		(property "Reference" "R3353"
			(at 0 0 90)
			(layer "F.SilkS")
			(hide yes)
			(effects
				(font
					(size 1.27 1.27)
				)
			)
		)
		(property "Value" ""
			(at 0 0 90)
			(layer "F.Fab")
			(effects
				(font
					(size 1.27 1.27)
				)
			)
		)
		(duplicate_pad_numbers_are_jumpers no)
		(fp_line
			(start 0.7874 -0.4064)
			(end 0.7874 0.0508)
			(stroke
				(width 0.1524)
				(type default)
			)
			(layer "F.SilkS")
		)
		(fp_line
			(start -0.7874 -0.4064)
			(end 0.7874 -0.4064)
			(stroke
				(width 0.1524)
				(type default)
			)
			(layer "F.SilkS")
		)
		(fp_line
			(start -0.7874 -0.0508)
			(end -0.7874 -0.4064)
			(stroke
				(width 0.1524)
				(type default)
			)
			(layer "F.SilkS")
		)
		(fp_line
			(start 0.390652 0.4064)
			(end -0.371348 0.4064)
			(stroke
				(width 0.1524)
				(type default)
			)
			(layer "F.SilkS")
		)
		(fp_line
			(start -0.12065 -0.305054)
			(end -0.12065 -0.2794)
			(stroke
				(width 0.1)
				(type default)
			)
			(layer "F.Fab")
		)
		(fp_line
			(start -0.67945 -0.305054)
			(end -0.12065 -0.305054)
			(stroke
				(width 0.1)
				(type default)
			)
			(layer "F.Fab")
		)
		(fp_line
			(start 0.67945 -0.3048)
			(end 0.67945 0.3048)
			(stroke
				(width 0.1)
				(type default)
			)
			(layer "F.Fab")
		)
		(fp_line
			(start 0.12065 -0.3048)
			(end 0.67945 -0.3048)
			(stroke
				(width 0.1)
				(type default)
			)
			(layer "F.Fab")
		)
		(fp_line
			(start 0.12065 -0.2794)
			(end 0.12065 -0.3048)
			(stroke
				(width 0.1)
				(type default)
			)
			(layer "F.Fab")
		)
		(fp_line
			(start -0.12065 -0.2794)
			(end 0.12065 -0.2794)
			(stroke
				(width 0.1)
				(type default)
			)
			(layer "F.Fab")
		)
		(fp_line
			(start 0.120396 0.2794)
			(end -0.12065 0.2794)
			(stroke
				(width 0.1)
				(type default)
			)
			(layer "F.Fab")
		)
		(fp_line
			(start -0.12065 0.2794)
			(end -0.12065 0.3048)
			(stroke
				(width 0.1)
				(type default)
			)
			(layer "F.Fab")
		)
		(fp_line
			(start 0.67945 0.3048)
			(end 0.120396 0.3048)
			(stroke
				(width 0.1)
				(type default)
			)
			(layer "F.Fab")
		)
		(fp_line
			(start 0.120396 0.3048)
			(end 0.120396 0.2794)
			(stroke
				(width 0.1)
				(type default)
			)
			(layer "F.Fab")
		)
		(fp_line
			(start -0.12065 0.3048)
			(end -0.67945 0.3048)
			(stroke
				(width 0.1)
				(type default)
			)
			(layer "F.Fab")
		)
		(fp_line
			(start -0.67945 0.3048)
			(end -0.67945 -0.305054)
			(stroke
				(width 0.1)
				(type default)
			)
			(layer "F.Fab")
		)
		(pad "1" smd circle
			(at -0.40005 0 90)
			(size 0 0)
			(layers "F.Cu" "F.Mask" "F.Paste")
			(net "CLK_100M_CPU1_CLK11_R_DN")
		)
		(pad "2" smd circle
			(at 0.40005 0 90)
			(size 0 0)
			(layers "F.Cu" "F.Mask" "F.Paste")
			(net "CLK_100M_CPU1_CLK11_DN")
		)
	)
	(footprint ""
		(layer "F.Cu")
		(at 394.947394 -58.8645 180)
		(property "Reference" "J54"
			(at -0.614172 -7.543292 0)
			(unlocked yes)
			(layer "F.SilkS")
			(effects
				(font
					(size 0.7874 0.5842)
					(thickness 0.1524)
				)
			)
		)
		(property "Value" ""
			(at 0 0 180)
			(layer "F.Fab")
			(effects
				(font
					(size 1.27 1.27)
				)
			)
		)
		(duplicate_pad_numbers_are_jumpers no)
		(fp_line
			(start 2.249932 6.35)
			(end -2.249932 6.35)
			(stroke
				(width 0.1524)
				(type default)
			)
			(layer "F.SilkS")
		)
		(fp_line
			(start 2.249932 6.2738)
			(end 2.249932 6.35)
			(stroke
				(width 0.1524)
				(type default)
			)
			(layer "F.SilkS")
		)
		(fp_line
			(start 2.249932 5.1562)
			(end 2.249932 5.0038)
			(stroke
				(width 0.1524)
				(type default)
			)
			(layer "F.SilkS")
		)
		(fp_line
			(start 2.249932 3.8862)
			(end 2.249932 3.7338)
			(stroke
				(width 0.1524)
				(type default)
			)
			(layer "F.SilkS")
		)
		(fp_line
			(start 2.249932 2.6162)
			(end 2.249932 2.4638)
			(stroke
				(width 0.1524)
				(type default)
			)
			(layer "F.SilkS")
		)
		(fp_line
			(start 2.249932 1.3462)
			(end 2.249932 1.1938)
			(stroke
				(width 0.1524)
				(type default)
			)
			(layer "F.SilkS")
		)
		(fp_line
			(start 2.249932 0.0762)
			(end 2.249932 -0.0762)
			(stroke
				(width 0.1524)
				(type default)
			)
			(layer "F.SilkS")
		)
		(fp_line
			(start 2.249932 -1.1938)
			(end 2.249932 -1.3462)
			(stroke
				(width 0.1524)
				(type default)
			)
			(layer "F.SilkS")
		)
		(fp_line
			(start 2.249932 -2.4638)
			(end 2.249932 -2.6162)
			(stroke
				(width 0.1524)
				(type default)
			)
			(layer "F.SilkS")
		)
		(fp_line
			(start 2.249932 -3.7338)
			(end 2.249932 -3.8862)
			(stroke
				(width 0.1524)
				(type default)
			)
			(layer "F.SilkS")
		)
		(fp_line
			(start 2.249932 -5.0038)
			(end 2.249932 -5.1562)
			(stroke
				(width 0.1524)
				(type default)
			)
			(layer "F.SilkS")
		)
		(fp_line
			(start 2.249932 -6.35)
			(end 2.249932 -6.2738)
			(stroke
				(width 0.1524)
				(type default)
			)
			(layer "F.SilkS")
		)
		(fp_line
			(start -2.249932 6.35)
			(end -2.249932 6.2738)
			(stroke
				(width 0.1524)
				(type default)
			)
			(layer "F.SilkS")
		)
		(fp_line
			(start -2.249932 5.1562)
			(end -2.249932 5.0038)
			(stroke
				(width 0.1524)
				(type default)
			)
			(layer "F.SilkS")
		)
		(fp_line
			(start -2.249932 3.8862)
			(end -2.249932 3.7338)
			(stroke
				(width 0.1524)
				(type default)
			)
			(layer "F.SilkS")
		)
		(fp_line
			(start -2.249932 2.6162)
			(end -2.249932 2.4638)
			(stroke
				(width 0.1524)
				(type default)
			)
			(layer "F.SilkS")
		)
		(fp_line
			(start -2.249932 1.3462)
			(end -2.249932 1.1938)
			(stroke
				(width 0.1524)
				(type default)
			)
			(layer "F.SilkS")
		)
		(fp_line
			(start -2.249932 0.0762)
			(end -2.249932 -0.0762)
			(stroke
				(width 0.1524)
				(type default)
			)
			(layer "F.SilkS")
		)
		(fp_line
			(start -2.249932 -1.1938)
			(end -2.249932 -1.3462)
			(stroke
				(width 0.1524)
				(type default)
			)
			(layer "F.SilkS")
		)
		(fp_line
			(start -2.249932 -2.4638)
			(end -2.249932 -2.6162)
			(stroke
				(width 0.1524)
				(type default)
			)
			(layer "F.SilkS")
		)
		(fp_line
			(start -2.249932 -3.7338)
			(end -2.249932 -3.8862)
			(stroke
				(width 0.1524)
				(type default)
			)
			(layer "F.SilkS")
		)
		(fp_line
			(start -2.249932 -5.0038)
			(end -2.249932 -5.1562)
			(stroke
				(width 0.1524)
				(type default)
			)
			(layer "F.SilkS")
		)
		(fp_line
			(start -2.249932 -6.2738)
			(end -2.249932 -6.35)
			(stroke
				(width 0.1524)
				(type default)
			)
			(layer "F.SilkS")
		)
		(fp_line
			(start -2.249932 -6.35)
			(end 2.249932 -6.35)
			(stroke
				(width 0.1524)
				(type default)
			)
			(layer "F.SilkS")
		)
		(fp_poly
			(pts
				(xy -3.706114 -5.715) (xy -4.722114 -5.207) (xy -4.722114 -6.223)
			)
			(stroke
				(width 0)
				(type default)
			)
			(fill yes)
			(layer "F.SilkS")
		)
		(fp_line
			(start 2.249932 6.35)
			(end -2.249932 6.35)
			(stroke
				(width 0.1)
				(type default)
			)
			(layer "F.Fab")
		)
		(fp_line
			(start 2.249932 -6.35)
			(end 2.249932 6.35)
			(stroke
				(width 0.1)
				(type default)
			)
			(layer "F.Fab")
		)
		(fp_line
			(start -2.249932 6.35)
			(end -2.249932 -6.35)
			(stroke
				(width 0.1)
				(type default)
			)
			(layer "F.Fab")
		)
		(fp_line
			(start -2.249932 -6.35)
			(end 2.249932 -6.35)
			(stroke
				(width 0.1)
				(type default)
			)
			(layer "F.Fab")
		)
		(fp_poly
			(pts
				(xy -4.722114 -6.223) (xy -4.722114 -5.207) (xy -3.706114 -5.715)
			)
			(stroke
				(width 0)
				(type default)
			)
			(fill yes)
			(layer "F.Fab")
		)
		(pad "1" smd rect
			(at -2.359914 -5.715 90)
			(size 0.8636 2.4384)
			(layers "F.Cu" "F.Mask" "F.Paste")
			(net "PVDD18_S5_P0")
		)
		(pad "2" smd rect
			(at 2.359914 -5.715 90)
			(size 0.8636 2.4384)
			(layers "F.Cu" "F.Mask" "F.Paste")
			(net "HDT_HDR_R_TCK")
		)
		(pad "3" smd rect
			(at -2.359914 -4.445 90)
			(size 0.8636 2.4384)
			(layers "F.Cu" "F.Mask" "F.Paste")
			(net "PRSNT_HDT_R_N")
		)
		(pad "4" smd rect
			(at 2.359914 -4.445 90)
			(size 0.8636 2.4384)
			(layers "F.Cu" "F.Mask" "F.Paste")
			(net "HDT_HDR_R_TMS")
		)
		(pad "5" smd rect
			(at -2.359914 -3.175 90)
			(size 0.8636 2.4384)
			(layers "F.Cu" "F.Mask" "F.Paste")
			(net "GND")
		)
		(pad "6" smd rect
			(at 2.359914 -3.175 90)
			(size 0.8636 2.4384)
			(layers "F.Cu" "F.Mask" "F.Paste")
			(net "HDT_HDR_R_TDI")
		)
		(pad "7" smd rect
			(at -2.359914 -1.905 90)
			(size 0.8636 2.4384)
			(layers "F.Cu" "F.Mask" "F.Paste")
			(net "GND")
		)
		(pad "8" smd rect
			(at 2.359914 -1.905 90)
			(size 0.8636 2.4384)
			(layers "F.Cu" "F.Mask" "F.Paste")
			(net "HDT_HDR_TDO")
		)
		(pad "9" smd rect
			(at -2.359914 -0.635 90)
			(size 0.8636 2.4384)
			(layers "F.Cu" "F.Mask" "F.Paste")
			(net "HDT_HDR_TRST_N_R")
		)
		(pad "10" smd rect
			(at 2.359914 -0.635 90)
			(size 0.8636 2.4384)
			(layers "F.Cu" "F.Mask" "F.Paste")
			(net "HDT_HDR_PWROK")
		)
		(pad "11" smd rect
			(at -2.359914 0.635 90)
			(size 0.8636 2.4384)
			(layers "F.Cu" "F.Mask" "F.Paste")
			(net "HDT_CPU0_XTRIG_L6")
		)
		(pad "12" smd rect
			(at 2.359914 0.635 90)
			(size 0.8636 2.4384)
			(layers "F.Cu" "F.Mask" "F.Paste")
			(net "HDT_HDR_RESET_N")
		)
		(pad "13" smd rect
			(at -2.359914 1.905 90)
			(size 0.8636 2.4384)
			(layers "F.Cu" "F.Mask" "F.Paste")
			(net "HDT_CPU0_XTRIG_L7")
		)
		(pad "14" smd rect
			(at 2.359914 1.905 90)
			(size 0.8636 2.4384)
			(layers "F.Cu" "F.Mask" "F.Paste")
			(net "Net_10739")
		)
		(pad "15" smd rect
			(at -2.359914 3.175 90)
			(size 0.8636 2.4384)
			(layers "F.Cu" "F.Mask" "F.Paste")
			(net "HDT_CPU0_XTRIG_L5")
		)
		(pad "16" smd rect
			(at 2.359914 3.175 90)
			(size 0.8636 2.4384)
			(layers "F.Cu" "F.Mask" "F.Paste")
			(net "HDT_HDR_DBREQ_R_N")
		)
		(pad "17" smd rect
			(at -2.359914 4.445 90)
			(size 0.8636 2.4384)
			(layers "F.Cu" "F.Mask" "F.Paste")
			(net "GND")
		)
		(pad "18" smd rect
			(at 2.359914 4.445 90)
			(size 0.8636 2.4384)
			(layers "F.Cu" "F.Mask" "F.Paste")
			(net "HDT_CPU0_HDT_CONN_TESTEN")
		)
		(pad "19" smd rect
			(at -2.359914 5.715 90)
			(size 0.8636 2.4384)
			(layers "F.Cu" "F.Mask" "F.Paste")
			(net "PVDD18_S5_P0")
		)
		(pad "20" smd rect
			(at 2.359914 5.715 90)
			(size 0.8636 2.4384)
			(layers "F.Cu" "F.Mask" "F.Paste")
			(net "Net_10738")
		)
	)
	(footprint ""
		(layer "F.Cu")
		(at 182.912766 -164.761418 90)
		(property "Reference" "U108"
			(at 0.488188 3.023108 90)
			(unlocked yes)
			(layer "F.SilkS")
			(effects
				(font
					(size 0.7874 0.5842)
					(thickness 0.1524)
				)
			)
		)
		(property "Value" ""
			(at 0 0 90)
			(layer "F.Fab")
			(effects
				(font
					(size 1.27 1.27)
				)
			)
		)
		(duplicate_pad_numbers_are_jumpers no)
		(fp_line
			(start 1.03378 -1.284478)
			(end 1.03378 1.284478)
			(stroke
				(width 0.1524)
				(type default)
			)
			(layer "F.SilkS")
		)
		(fp_line
			(start -1.03378 -1.284478)
			(end 1.03378 -1.284478)
			(stroke
				(width 0.1524)
				(type default)
			)
			(layer "F.SilkS")
		)
		(fp_line
			(start 1.03378 1.284478)
			(end -1.03378 1.284478)
			(stroke
				(width 0.1524)
				(type default)
			)
			(layer "F.SilkS")
		)
		(fp_line
			(start -1.03378 1.284478)
			(end -1.03378 -1.284478)
			(stroke
				(width 0.1524)
				(type default)
			)
			(layer "F.SilkS")
		)
		(fp_poly
			(pts
				(xy -1.806702 -1.052576) (xy -1.201674 -0.750062) (xy -1.806702 -0.447548)
			)
			(stroke
				(width 0)
				(type default)
			)
			(fill yes)
			(layer "F.SilkS")
		)
		(fp_line
			(start 0.774954 -1.02489)
			(end 0.774954 1.02489)
			(stroke
				(width 0.1)
				(type default)
			)
			(layer "F.Fab")
		)
		(fp_line
			(start -0.774954 -1.02489)
			(end 0.774954 -1.02489)
			(stroke
				(width 0.1)
				(type default)
			)
			(layer "F.Fab")
		)
		(fp_line
			(start 0.774954 1.02489)
			(end -0.774954 1.02489)
			(stroke
				(width 0.1)
				(type default)
			)
			(layer "F.Fab")
		)
		(fp_line
			(start -0.774954 1.02489)
			(end -0.774954 -1.02489)
			(stroke
				(width 0.1)
				(type default)
			)
			(layer "F.Fab")
		)
		(fp_poly
			(pts
				(xy -1.201674 -0.750062) (xy -1.806702 -0.447548) (xy -1.806702 -1.052576)
			)
			(stroke
				(width 0)
				(type default)
			)
			(fill yes)
			(layer "F.Fab")
		)
		(pad "1" smd rect
			(at -0.64008 -0.750062 180)
			(size 0.3048 0.5334)
			(layers "F.Cu" "F.Mask" "F.Paste")
			(net "I3C_1_SPD_DDRGL_CPU1_SCL")
		)
		(pad "2" smd rect
			(at -0.64008 -0.249936 180)
			(size 0.254 0.5334)
			(layers "F.Cu" "F.Mask" "F.Paste")
			(net "I3C_1_SPD_DDRGL_CPU1_SDA")
		)
		(pad "3" smd rect
			(at -0.64008 0.249936 180)
			(size 0.254 0.5334)
			(layers "F.Cu" "F.Mask" "F.Paste")
			(net "I3C_SCM_3_R_SCL")
		)
		(pad "4" smd rect
			(at -0.64008 0.750062 180)
			(size 0.3048 0.5334)
			(layers "F.Cu" "F.Mask" "F.Paste")
			(net "I3C_SCM_3_R_SDA")
		)
		(pad "5" smd rect
			(at 0 0.839978 90)
			(size 0.3302 0.635)
			(layers "F.Cu" "F.Mask" "F.Paste")
			(net "GND")
		)
		(pad "6" smd rect
			(at 0.64008 0.750062 180)
			(size 0.3048 0.5334)
			(layers "F.Cu" "F.Mask" "F.Paste")
			(net "FM_I3C_CPU1_MUX1_OE_N")
		)
		(pad "7" smd rect
			(at 0.64008 0.249936 180)
			(size 0.254 0.5334)
			(layers "F.Cu" "F.Mask" "F.Paste")
			(net "I3C_SPD_DDRGL_CPU1_LVC1_SDA")
		)
		(pad "8" smd rect
			(at 0.64008 -0.249936 180)
			(size 0.254 0.5334)
			(layers "F.Cu" "F.Mask" "F.Paste")
			(net "I3C_SPD_DDRGL_CPU1_LVC1_SCL")
		)
		(pad "9" smd rect
			(at 0.64008 -0.750062 180)
			(size 0.3048 0.5334)
			(layers "F.Cu" "F.Mask" "F.Paste")
			(net "FM_I3C_CPU1_MUX1_SEL")
		)
		(pad "10" smd rect
			(at 0 -0.839978 90)
			(size 0.3302 0.635)
			(layers "F.Cu" "F.Mask" "F.Paste")
			(net "P3V3_AUX")
		)
	)
	(footprint ""
		(layer "F.Cu")
		(at 145.669 -117.348)
		(property "Reference" "R8122"
			(at 0 0 0)
			(layer "F.SilkS")
			(hide yes)
			(effects
				(font
					(size 1.27 1.27)
				)
			)
		)
		(property "Value" ""
			(at 0 0 0)
			(layer "F.Fab")
			(effects
				(font
					(size 1.27 1.27)
				)
			)
		)
		(duplicate_pad_numbers_are_jumpers no)
		(fp_line
			(start -0.7874 -0.4064)
			(end 0.7874 -0.4064)
			(stroke
				(width 0.1524)
				(type default)
			)
			(layer "F.SilkS")
		)
		(fp_line
			(start -0.7874 0.4064)
			(end -0.7874 -0.4064)
			(stroke
				(width 0.1524)
				(type default)
			)
			(layer "F.SilkS")
		)
		(fp_line
			(start 0.7874 -0.4064)
			(end 0.7874 0.4064)
			(stroke
				(width 0.1524)
				(type default)
			)
			(layer "F.SilkS")
		)
		(fp_line
			(start 0.7874 0.4064)
			(end -0.7874 0.4064)
			(stroke
				(width 0.1524)
				(type default)
			)
			(layer "F.SilkS")
		)
		(fp_line
			(start -0.67945 -0.305054)
			(end -0.12065 -0.305054)
			(stroke
				(width 0.1)
				(type default)
			)
			(layer "F.Fab")
		)
		(fp_line
			(start -0.67945 0.3048)
			(end -0.67945 -0.305054)
			(stroke
				(width 0.1)
				(type default)
			)
			(layer "F.Fab")
		)
		(fp_line
			(start -0.12065 -0.305054)
			(end -0.12065 -0.2794)
			(stroke
				(width 0.1)
				(type default)
			)
			(layer "F.Fab")
		)
		(fp_line
			(start -0.12065 -0.2794)
			(end 0.12065 -0.2794)
			(stroke
				(width 0.1)
				(type default)
			)
			(layer "F.Fab")
		)
		(fp_line
			(start -0.12065 0.2794)
			(end -0.12065 0.3048)
			(stroke
				(width 0.1)
				(type default)
			)
			(layer "F.Fab")
		)
		(fp_line
			(start -0.12065 0.3048)
			(end -0.67945 0.3048)
			(stroke
				(width 0.1)
				(type default)
			)
			(layer "F.Fab")
		)
		(fp_line
			(start 0.120396 0.2794)
			(end -0.12065 0.2794)
			(stroke
				(width 0.1)
				(type default)
			)
			(layer "F.Fab")
		)
		(fp_line
			(start 0.120396 0.3048)
			(end 0.120396 0.2794)
			(stroke
				(width 0.1)
				(type default)
			)
			(layer "F.Fab")
		)
		(fp_line
			(start 0.12065 -0.3048)
			(end 0.67945 -0.3048)
			(stroke
				(width 0.1)
				(type default)
			)
			(layer "F.Fab")
		)
		(fp_line
			(start 0.12065 -0.2794)
			(end 0.12065 -0.3048)
			(stroke
				(width 0.1)
				(type default)
			)
			(layer "F.Fab")
		)
		(fp_line
			(start 0.67945 -0.3048)
			(end 0.67945 0.3048)
			(stroke
				(width 0.1)
				(type default)
			)
			(layer "F.Fab")
		)
		(fp_line
			(start 0.67945 0.3048)
			(end 0.120396 0.3048)
			(stroke
				(width 0.1)
				(type default)
			)
			(layer "F.Fab")
		)
		(pad "1" smd circle
			(at -0.40005 0)
			(size 0 0)
			(layers "F.Cu" "F.Mask" "F.Paste")
			(net "P12V_AUX_UV_TRIGGER")
		)
		(pad "2" smd circle
			(at 0.40005 0)
			(size 0 0)
			(layers "F.Cu" "F.Mask" "F.Paste")
			(net "GND")
		)
	)
	(footprint ""
		(layer "F.Cu")
		(at 310.411876 -70.098412 90)
		(property "Reference" "D93"
			(at -3.934714 -0.691642 90)
			(unlocked yes)
			(layer "F.SilkS")
			(effects
				(font
					(size 0.7874 0.5842)
					(thickness 0.1524)
				)
				(justify left)
			)
		)
		(property "Value" ""
			(at 0 0 90)
			(layer "F.Fab")
			(effects
				(font
					(size 1.27 1.27)
				)
			)
		)
		(duplicate_pad_numbers_are_jumpers no)
		(fp_line
			(start 1.16078 -0.4826)
			(end 1.16078 0.4826)
			(stroke
				(width 0.1524)
				(type default)
			)
			(layer "F.SilkS")
		)
		(fp_line
			(start 1.03378 -0.4826)
			(end 1.03378 0.4826)
			(stroke
				(width 0.1524)
				(type default)
			)
			(layer "F.SilkS")
		)
		(fp_line
			(start 0.90678 -0.4826)
			(end 0.90678 0.4826)
			(stroke
				(width 0.1524)
				(type default)
			)
			(layer "F.SilkS")
		)
		(fp_line
			(start -0.64008 -0.4826)
			(end 1.16078 -0.4826)
			(stroke
				(width 0.1524)
				(type default)
			)
			(layer "F.SilkS")
		)
		(fp_line
			(start -0.79248 -0.4826)
			(end 1.03378 -0.4826)
			(stroke
				(width 0.1524)
				(type default)
			)
			(layer "F.SilkS")
		)
		(fp_line
			(start -0.89408 -0.4826)
			(end 0.90678 -0.4826)
			(stroke
				(width 0.1524)
				(type default)
			)
			(layer "F.SilkS")
		)
		(fp_line
			(start 1.16078 0.4826)
			(end -0.64008 0.4826)
			(stroke
				(width 0.1524)
				(type default)
			)
			(layer "F.SilkS")
		)
		(fp_line
			(start 1.03378 0.4826)
			(end -0.79248 0.4826)
			(stroke
				(width 0.1524)
				(type default)
			)
			(layer "F.SilkS")
		)
		(fp_line
			(start 0.90678 0.4826)
			(end -0.90678 0.4826)
			(stroke
				(width 0.1524)
				(type default)
			)
			(layer "F.SilkS")
		)
		(fp_line
			(start -0.90678 0.4826)
			(end -0.90678 -0.4699)
			(stroke
				(width 0.1524)
				(type default)
			)
			(layer "F.SilkS")
		)
		(fp_line
			(start 0.499872 -0.249936)
			(end 0.499872 0.249936)
			(stroke
				(width 0.1)
				(type default)
			)
			(layer "F.Fab")
		)
		(fp_line
			(start -0.499872 -0.249936)
			(end 0.499872 -0.249936)
			(stroke
				(width 0.1)
				(type default)
			)
			(layer "F.Fab")
		)
		(fp_line
			(start 0.499872 0.249936)
			(end -0.499872 0.249936)
			(stroke
				(width 0.1)
				(type default)
			)
			(layer "F.Fab")
		)
		(fp_line
			(start -0.499872 0.249936)
			(end -0.499872 -0.249936)
			(stroke
				(width 0.1)
				(type default)
			)
			(layer "F.Fab")
		)
		(pad "A" smd rect
			(at -0.47498 0 90)
			(size 0.6096 0.7112)
			(layers "F.Cu" "F.Mask" "F.Paste")
			(net "LED_RST_RSMRST_PLD_R_N")
		)
		(pad "C" smd rect
			(at 0.47498 0 90)
			(size 0.6096 0.7112)
			(layers "F.Cu" "F.Mask" "F.Paste")
			(net "LED_RST_RSMRST_PLD_R_N_D")
		)
	)
	(footprint ""
		(layer "F.Cu")
		(at 391.291318 -77.423264)
		(property "Reference" "R1306"
			(at 0 0 0)
			(layer "F.SilkS")
			(hide yes)
			(effects
				(font
					(size 1.27 1.27)
				)
			)
		)
		(property "Value" ""
			(at 0 0 0)
			(layer "F.Fab")
			(effects
				(font
					(size 1.27 1.27)
				)
			)
		)
		(duplicate_pad_numbers_are_jumpers no)
		(fp_line
			(start -0.7874 -0.4064)
			(end 0.7874 -0.4064)
			(stroke
				(width 0.1524)
				(type default)
			)
			(layer "F.SilkS")
		)
		(fp_line
			(start -0.7874 0.4064)
			(end -0.7874 -0.4064)
			(stroke
				(width 0.1524)
				(type default)
			)
			(layer "F.SilkS")
		)
		(fp_line
			(start 0.7874 -0.4064)
			(end 0.7874 0.4064)
			(stroke
				(width 0.1524)
				(type default)
			)
			(layer "F.SilkS")
		)
		(fp_line
			(start 0.7874 0.4064)
			(end -0.7874 0.4064)
			(stroke
				(width 0.1524)
				(type default)
			)
			(layer "F.SilkS")
		)
		(fp_line
			(start -0.67945 -0.305054)
			(end -0.12065 -0.305054)
			(stroke
				(width 0.1)
				(type default)
			)
			(layer "F.Fab")
		)
		(fp_line
			(start -0.67945 0.3048)
			(end -0.67945 -0.305054)
			(stroke
				(width 0.1)
				(type default)
			)
			(layer "F.Fab")
		)
		(fp_line
			(start -0.12065 -0.305054)
			(end -0.12065 -0.2794)
			(stroke
				(width 0.1)
				(type default)
			)
			(layer "F.Fab")
		)
		(fp_line
			(start -0.12065 -0.2794)
			(end 0.12065 -0.2794)
			(stroke
				(width 0.1)
				(type default)
			)
			(layer "F.Fab")
		)
		(fp_line
			(start -0.12065 0.2794)
			(end -0.12065 0.3048)
			(stroke
				(width 0.1)
				(type default)
			)
			(layer "F.Fab")
		)
		(fp_line
			(start -0.12065 0.3048)
			(end -0.67945 0.3048)
			(stroke
				(width 0.1)
				(type default)
			)
			(layer "F.Fab")
		)
		(fp_line
			(start 0.120396 0.2794)
			(end -0.12065 0.2794)
			(stroke
				(width 0.1)
				(type default)
			)
			(layer "F.Fab")
		)
		(fp_line
			(start 0.120396 0.3048)
			(end 0.120396 0.2794)
			(stroke
				(width 0.1)
				(type default)
			)
			(layer "F.Fab")
		)
		(fp_line
			(start 0.12065 -0.3048)
			(end 0.67945 -0.3048)
			(stroke
				(width 0.1)
				(type default)
			)
			(layer "F.Fab")
		)
		(fp_line
			(start 0.12065 -0.2794)
			(end 0.12065 -0.3048)
			(stroke
				(width 0.1)
				(type default)
			)
			(layer "F.Fab")
		)
		(fp_line
			(start 0.67945 -0.3048)
			(end 0.67945 0.3048)
			(stroke
				(width 0.1)
				(type default)
			)
			(layer "F.Fab")
		)
		(fp_line
			(start 0.67945 0.3048)
			(end 0.120396 0.3048)
			(stroke
				(width 0.1)
				(type default)
			)
			(layer "F.Fab")
		)
		(pad "1" smd circle
			(at -0.40005 0)
			(size 0 0)
			(layers "F.Cu" "F.Mask" "F.Paste")
			(net "GND")
		)
		(pad "2" smd circle
			(at 0.40005 0)
			(size 0 0)
			(layers "F.Cu" "F.Mask" "F.Paste")
			(net "INA230_6_A1")
		)
	)
	(footprint ""
		(layer "F.Cu")
		(at 191.52362 -421.026082 90)
		(property "Reference" "C1775"
			(at 0 0 90)
			(layer "F.SilkS")
			(hide yes)
			(effects
				(font
					(size 1.27 1.27)
				)
			)
		)
		(property "Value" ""
			(at 0 0 90)
			(layer "F.Fab")
			(effects
				(font
					(size 1.27 1.27)
				)
			)
		)
		(duplicate_pad_numbers_are_jumpers no)
		(fp_line
			(start 0.7874 -0.4064)
			(end 0.7874 0.4064)
			(stroke
				(width 0.1524)
				(type default)
			)
			(layer "F.SilkS")
		)
		(fp_line
			(start -0.7874 -0.4064)
			(end 0.7874 -0.4064)
			(stroke
				(width 0.1524)
				(type default)
			)
			(layer "F.SilkS")
		)
		(fp_line
			(start 0.7874 0.4064)
			(end -0.7874 0.4064)
			(stroke
				(width 0.1524)
				(type default)
			)
			(layer "F.SilkS")
		)
		(fp_line
			(start -0.7874 0.4064)
			(end -0.7874 -0.4064)
			(stroke
				(width 0.1524)
				(type default)
			)
			(layer "F.SilkS")
		)
		(fp_line
			(start -0.12065 -0.305054)
			(end -0.12065 -0.2794)
			(stroke
				(width 0.1)
				(type default)
			)
			(layer "F.Fab")
		)
		(fp_line
			(start -0.67945 -0.305054)
			(end -0.12065 -0.305054)
			(stroke
				(width 0.1)
				(type default)
			)
			(layer "F.Fab")
		)
		(fp_line
			(start 0.67945 -0.3048)
			(end 0.67945 0.3048)
			(stroke
				(width 0.1)
				(type default)
			)
			(layer "F.Fab")
		)
		(fp_line
			(start 0.12065 -0.3048)
			(end 0.67945 -0.3048)
			(stroke
				(width 0.1)
				(type default)
			)
			(layer "F.Fab")
		)
		(fp_line
			(start 0.12065 -0.2794)
			(end 0.12065 -0.3048)
			(stroke
				(width 0.1)
				(type default)
			)
			(layer "F.Fab")
		)
		(fp_line
			(start -0.12065 -0.2794)
			(end 0.12065 -0.2794)
			(stroke
				(width 0.1)
				(type default)
			)
			(layer "F.Fab")
		)
		(fp_line
			(start 0.120396 0.2794)
			(end -0.12065 0.2794)
			(stroke
				(width 0.1)
				(type default)
			)
			(layer "F.Fab")
		)
		(fp_line
			(start -0.12065 0.2794)
			(end -0.12065 0.3048)
			(stroke
				(width 0.1)
				(type default)
			)
			(layer "F.Fab")
		)
		(fp_line
			(start 0.67945 0.3048)
			(end 0.120396 0.3048)
			(stroke
				(width 0.1)
				(type default)
			)
			(layer "F.Fab")
		)
		(fp_line
			(start 0.120396 0.3048)
			(end 0.120396 0.2794)
			(stroke
				(width 0.1)
				(type default)
			)
			(layer "F.Fab")
		)
		(fp_line
			(start -0.12065 0.3048)
			(end -0.67945 0.3048)
			(stroke
				(width 0.1)
				(type default)
			)
			(layer "F.Fab")
		)
		(fp_line
			(start -0.67945 0.3048)
			(end -0.67945 -0.305054)
			(stroke
				(width 0.1)
				(type default)
			)
			(layer "F.Fab")
		)
		(pad "1" smd circle
			(at -0.40005 0 90)
			(size 0 0)
			(layers "F.Cu" "F.Mask" "F.Paste")
			(net "P3V3_AUX")
		)
		(pad "2" smd circle
			(at 0.40005 0 90)
			(size 0 0)
			(layers "F.Cu" "F.Mask" "F.Paste")
			(net "GND")
		)
	)
	(footprint ""
		(layer "F.Cu")
		(at 302.241458 -116.891308 180)
		(property "Reference" "R714"
			(at 0 0 180)
			(layer "F.SilkS")
			(hide yes)
			(effects
				(font
					(size 1.27 1.27)
				)
			)
		)
		(property "Value" ""
			(at 0 0 180)
			(layer "F.Fab")
			(effects
				(font
					(size 1.27 1.27)
				)
			)
		)
		(duplicate_pad_numbers_are_jumpers no)
		(fp_line
			(start 0.7874 0.4064)
			(end -0.7874 0.4064)
			(stroke
				(width 0.1524)
				(type default)
			)
			(layer "F.SilkS")
		)
		(fp_line
			(start 0.7874 -0.4064)
			(end 0.7874 0.4064)
			(stroke
				(width 0.1524)
				(type default)
			)
			(layer "F.SilkS")
		)
		(fp_line
			(start -0.7874 0.4064)
			(end -0.7874 -0.4064)
			(stroke
				(width 0.1524)
				(type default)
			)
			(layer "F.SilkS")
		)
		(fp_line
			(start -0.7874 -0.4064)
			(end 0.7874 -0.4064)
			(stroke
				(width 0.1524)
				(type default)
			)
			(layer "F.SilkS")
		)
		(fp_line
			(start 0.67945 0.3048)
			(end 0.120396 0.3048)
			(stroke
				(width 0.1)
				(type default)
			)
			(layer "F.Fab")
		)
		(fp_line
			(start 0.67945 -0.3048)
			(end 0.67945 0.3048)
			(stroke
				(width 0.1)
				(type default)
			)
			(layer "F.Fab")
		)
		(fp_line
			(start 0.12065 -0.2794)
			(end 0.12065 -0.3048)
			(stroke
				(width 0.1)
				(type default)
			)
			(layer "F.Fab")
		)
		(fp_line
			(start 0.12065 -0.3048)
			(end 0.67945 -0.3048)
			(stroke
				(width 0.1)
				(type default)
			)
			(layer "F.Fab")
		)
		(fp_line
			(start 0.120396 0.3048)
			(end 0.120396 0.2794)
			(stroke
				(width 0.1)
				(type default)
			)
			(layer "F.Fab")
		)
		(fp_line
			(start 0.120396 0.2794)
			(end -0.12065 0.2794)
			(stroke
				(width 0.1)
				(type default)
			)
			(layer "F.Fab")
		)
		(fp_line
			(start -0.12065 0.3048)
			(end -0.67945 0.3048)
			(stroke
				(width 0.1)
				(type default)
			)
			(layer "F.Fab")
		)
		(fp_line
			(start -0.12065 0.2794)
			(end -0.12065 0.3048)
			(stroke
				(width 0.1)
				(type default)
			)
			(layer "F.Fab")
		)
		(fp_line
			(start -0.12065 -0.2794)
			(end 0.12065 -0.2794)
			(stroke
				(width 0.1)
				(type default)
			)
			(layer "F.Fab")
		)
		(fp_line
			(start -0.12065 -0.305054)
			(end -0.12065 -0.2794)
			(stroke
				(width 0.1)
				(type default)
			)
			(layer "F.Fab")
		)
		(fp_line
			(start -0.67945 0.3048)
			(end -0.67945 -0.305054)
			(stroke
				(width 0.1)
				(type default)
			)
			(layer "F.Fab")
		)
		(fp_line
			(start -0.67945 -0.305054)
			(end -0.12065 -0.305054)
			(stroke
				(width 0.1)
				(type default)
			)
			(layer "F.Fab")
		)
		(pad "1" smd circle
			(at -0.40005 0 180)
			(size 0 0)
			(layers "F.Cu" "F.Mask" "F.Paste")
			(net "MB_FRU_ADDR2")
		)
		(pad "2" smd circle
			(at 0.40005 0 180)
			(size 0 0)
			(layers "F.Cu" "F.Mask" "F.Paste")
			(net "GND")
		)
	)
	(footprint ""
		(layer "F.Cu")
		(at 96.21266 -339.681058 90)
		(property "Reference" "PR272"
			(at 0 0 90)
			(layer "F.SilkS")
			(hide yes)
			(effects
				(font
					(size 1.27 1.27)
				)
			)
		)
		(property "Value" ""
			(at 0 0 90)
			(layer "F.Fab")
			(effects
				(font
					(size 1.27 1.27)
				)
			)
		)
		(duplicate_pad_numbers_are_jumpers no)
		(fp_line
			(start 0.7874 -0.4064)
			(end 0.7874 0.4064)
			(stroke
				(width 0.1524)
				(type default)
			)
			(layer "F.SilkS")
		)
		(fp_line
			(start -0.7874 -0.4064)
			(end 0.7874 -0.4064)
			(stroke
				(width 0.1524)
				(type default)
			)
			(layer "F.SilkS")
		)
		(fp_line
			(start 0.7874 0.4064)
			(end -0.7874 0.4064)
			(stroke
				(width 0.1524)
				(type default)
			)
			(layer "F.SilkS")
		)
		(fp_line
			(start -0.7874 0.4064)
			(end -0.7874 -0.4064)
			(stroke
				(width 0.1524)
				(type default)
			)
			(layer "F.SilkS")
		)
		(fp_line
			(start -0.12065 -0.305054)
			(end -0.12065 -0.2794)
			(stroke
				(width 0.1)
				(type default)
			)
			(layer "F.Fab")
		)
		(fp_line
			(start -0.67945 -0.305054)
			(end -0.12065 -0.305054)
			(stroke
				(width 0.1)
				(type default)
			)
			(layer "F.Fab")
		)
		(fp_line
			(start 0.67945 -0.3048)
			(end 0.67945 0.3048)
			(stroke
				(width 0.1)
				(type default)
			)
			(layer "F.Fab")
		)
		(fp_line
			(start 0.12065 -0.3048)
			(end 0.67945 -0.3048)
			(stroke
				(width 0.1)
				(type default)
			)
			(layer "F.Fab")
		)
		(fp_line
			(start 0.12065 -0.2794)
			(end 0.12065 -0.3048)
			(stroke
				(width 0.1)
				(type default)
			)
			(layer "F.Fab")
		)
		(fp_line
			(start -0.12065 -0.2794)
			(end 0.12065 -0.2794)
			(stroke
				(width 0.1)
				(type default)
			)
			(layer "F.Fab")
		)
		(fp_line
			(start 0.120396 0.2794)
			(end -0.12065 0.2794)
			(stroke
				(width 0.1)
				(type default)
			)
			(layer "F.Fab")
		)
		(fp_line
			(start -0.12065 0.2794)
			(end -0.12065 0.3048)
			(stroke
				(width 0.1)
				(type default)
			)
			(layer "F.Fab")
		)
		(fp_line
			(start 0.67945 0.3048)
			(end 0.120396 0.3048)
			(stroke
				(width 0.1)
				(type default)
			)
			(layer "F.Fab")
		)
		(fp_line
			(start 0.120396 0.3048)
			(end 0.120396 0.2794)
			(stroke
				(width 0.1)
				(type default)
			)
			(layer "F.Fab")
		)
		(fp_line
			(start -0.12065 0.3048)
			(end -0.67945 0.3048)
			(stroke
				(width 0.1)
				(type default)
			)
			(layer "F.Fab")
		)
		(fp_line
			(start -0.67945 0.3048)
			(end -0.67945 -0.305054)
			(stroke
				(width 0.1)
				(type default)
			)
			(layer "F.Fab")
		)
		(pad "1" smd circle
			(at -0.40005 0 90)
			(size 0 0)
			(layers "F.Cu" "F.Mask" "F.Paste")
			(net "SW_PVDDCR_CPU1_P1_BOOT5")
		)
		(pad "2" smd circle
			(at 0.40005 0 90)
			(size 0 0)
			(layers "F.Cu" "F.Mask" "F.Paste")
			(net "SW_PVDDCR_CPU1_P1_BOOT5_R")
		)
	)
	(footprint ""
		(layer "F.Cu")
		(at 247.499378 -315.82868 90)
		(property "Reference" "PC6805"
			(at -1.75768 5.257292 90)
			(unlocked yes)
			(layer "F.SilkS")
			(effects
				(font
					(size 0.7874 0.5842)
					(thickness 0.1524)
				)
				(justify left)
			)
		)
		(property "Value" ""
			(at 0 0 90)
			(layer "F.Fab")
			(effects
				(font
					(size 1.27 1.27)
				)
			)
		)
		(duplicate_pad_numbers_are_jumpers no)
		(fp_line
			(start 2.750058 -2.750058)
			(end -1.988058 -2.750058)
			(stroke
				(width 0.1524)
				(type default)
			)
			(layer "F.SilkS")
		)
		(fp_line
			(start -1.988058 -2.750058)
			(end -2.750058 -1.988058)
			(stroke
				(width 0.1524)
				(type default)
			)
			(layer "F.SilkS")
		)
		(fp_line
			(start -2.750058 -1.988058)
			(end -2.750058 -0.9398)
			(stroke
				(width 0.1524)
				(type default)
			)
			(layer "F.SilkS")
		)
		(fp_line
			(start 2.750058 -0.9398)
			(end 2.750058 -2.750058)
			(stroke
				(width 0.1524)
				(type default)
			)
			(layer "F.SilkS")
		)
		(fp_line
			(start -2.750058 0.9398)
			(end -2.750058 1.988058)
			(stroke
				(width 0.1524)
				(type default)
			)
			(layer "F.SilkS")
		)
		(fp_line
			(start -2.750058 1.988058)
			(end -1.988058 2.750058)
			(stroke
				(width 0.1524)
				(type default)
			)
			(layer "F.SilkS")
		)
		(fp_line
			(start 2.750058 2.750058)
			(end 2.750058 0.9398)
			(stroke
				(width 0.1524)
				(type default)
			)
			(layer "F.SilkS")
		)
		(fp_line
			(start -1.988058 2.750058)
			(end 2.750058 2.750058)
			(stroke
				(width 0.1524)
				(type default)
			)
			(layer "F.SilkS")
		)
		(fp_line
			(start 2.750058 -2.750058)
			(end -2.750058 -2.750058)
			(stroke
				(width 0.1)
				(type default)
			)
			(layer "F.Fab")
		)
		(fp_line
			(start -2.750058 -2.750058)
			(end -2.750058 2.750058)
			(stroke
				(width 0.1)
				(type default)
			)
			(layer "F.Fab")
		)
		(fp_line
			(start 2.750058 2.750058)
			(end 2.750058 -2.750058)
			(stroke
				(width 0.1)
				(type default)
			)
			(layer "F.Fab")
		)
		(fp_line
			(start -2.750058 2.750058)
			(end 2.750058 2.750058)
			(stroke
				(width 0.1)
				(type default)
			)
			(layer "F.Fab")
		)
		(pad "1" smd rect
			(at -2.199894 0 180)
			(size 1.6002 3.0226)
			(layers "F.Cu" "F.Mask" "F.Paste")
			(net "P1V8_CPU0_RT_1D")
		)
		(pad "2" smd rect
			(at 2.199894 0 180)
			(size 1.6002 3.0226)
			(layers "F.Cu" "F.Mask" "F.Paste")
			(net "GND")
		)
	)
	(footprint ""
		(layer "F.Cu")
		(at 255.780794 -138.048746 90)
		(property "Reference" "R129"
			(at 0 0 90)
			(layer "F.SilkS")
			(hide yes)
			(effects
				(font
					(size 1.27 1.27)
				)
			)
		)
		(property "Value" ""
			(at 0 0 90)
			(layer "F.Fab")
			(effects
				(font
					(size 1.27 1.27)
				)
			)
		)
		(duplicate_pad_numbers_are_jumpers no)
		(fp_line
			(start 0.7874 -0.4064)
			(end 0.7874 0.4064)
			(stroke
				(width 0.1524)
				(type default)
			)
			(layer "F.SilkS")
		)
		(fp_line
			(start -0.7874 -0.4064)
			(end 0.7874 -0.4064)
			(stroke
				(width 0.1524)
				(type default)
			)
			(layer "F.SilkS")
		)
		(fp_line
			(start 0.7874 0.4064)
			(end -0.7874 0.4064)
			(stroke
				(width 0.1524)
				(type default)
			)
			(layer "F.SilkS")
		)
		(fp_line
			(start -0.7874 0.4064)
			(end -0.7874 -0.4064)
			(stroke
				(width 0.1524)
				(type default)
			)
			(layer "F.SilkS")
		)
		(fp_line
			(start -0.12065 -0.305054)
			(end -0.12065 -0.2794)
			(stroke
				(width 0.1)
				(type default)
			)
			(layer "F.Fab")
		)
		(fp_line
			(start -0.67945 -0.305054)
			(end -0.12065 -0.305054)
			(stroke
				(width 0.1)
				(type default)
			)
			(layer "F.Fab")
		)
		(fp_line
			(start 0.67945 -0.3048)
			(end 0.67945 0.3048)
			(stroke
				(width 0.1)
				(type default)
			)
			(layer "F.Fab")
		)
		(fp_line
			(start 0.12065 -0.3048)
			(end 0.67945 -0.3048)
			(stroke
				(width 0.1)
				(type default)
			)
			(layer "F.Fab")
		)
		(fp_line
			(start 0.12065 -0.2794)
			(end 0.12065 -0.3048)
			(stroke
				(width 0.1)
				(type default)
			)
			(layer "F.Fab")
		)
		(fp_line
			(start -0.12065 -0.2794)
			(end 0.12065 -0.2794)
			(stroke
				(width 0.1)
				(type default)
			)
			(layer "F.Fab")
		)
		(fp_line
			(start 0.120396 0.2794)
			(end -0.12065 0.2794)
			(stroke
				(width 0.1)
				(type default)
			)
			(layer "F.Fab")
		)
		(fp_line
			(start -0.12065 0.2794)
			(end -0.12065 0.3048)
			(stroke
				(width 0.1)
				(type default)
			)
			(layer "F.Fab")
		)
		(fp_line
			(start 0.67945 0.3048)
			(end 0.120396 0.3048)
			(stroke
				(width 0.1)
				(type default)
			)
			(layer "F.Fab")
		)
		(fp_line
			(start 0.120396 0.3048)
			(end 0.120396 0.2794)
			(stroke
				(width 0.1)
				(type default)
			)
			(layer "F.Fab")
		)
		(fp_line
			(start -0.12065 0.3048)
			(end -0.67945 0.3048)
			(stroke
				(width 0.1)
				(type default)
			)
			(layer "F.Fab")
		)
		(fp_line
			(start -0.67945 0.3048)
			(end -0.67945 -0.305054)
			(stroke
				(width 0.1)
				(type default)
			)
			(layer "F.Fab")
		)
		(pad "1" smd circle
			(at -0.40005 0 90)
			(size 0 0)
			(layers "F.Cu" "F.Mask" "F.Paste")
			(net "P3V3_AUX")
		)
		(pad "2" smd circle
			(at 0.40005 0 90)
			(size 0 0)
			(layers "F.Cu" "F.Mask" "F.Paste")
			(net "SPI_CPU0_LVC3_SCM_D3")
		)
	)
	(footprint ""
		(layer "F.Cu")
		(at 122.916696 -375.49963 -90)
		(property "Reference" "C1532"
			(at 0 0 270)
			(layer "F.SilkS")
			(hide yes)
			(effects
				(font
					(size 1.27 1.27)
				)
			)
		)
		(property "Value" ""
			(at 0 0 270)
			(layer "F.Fab")
			(effects
				(font
					(size 1.27 1.27)
				)
			)
		)
		(duplicate_pad_numbers_are_jumpers no)
		(fp_line
			(start -0.299974 0.150114)
			(end -0.299974 -0.150114)
			(stroke
				(width 0.1)
				(type default)
			)
			(layer "F.Fab")
		)
		(fp_line
			(start 0.299974 0.150114)
			(end -0.299974 0.150114)
			(stroke
				(width 0.1)
				(type default)
			)
			(layer "F.Fab")
		)
		(fp_line
			(start -0.299974 -0.150114)
			(end 0.299974 -0.150114)
			(stroke
				(width 0.1)
				(type default)
			)
			(layer "F.Fab")
		)
		(fp_line
			(start 0.299974 -0.150114)
			(end 0.299974 0.150114)
			(stroke
				(width 0.1)
				(type default)
			)
			(layer "F.Fab")
		)
		(pad "1" smd rect
			(at -0.2667 0 270)
			(size 0.3048 0.381)
			(layers "F.Cu" "F.Mask" "F.Paste")
			(net "P5E_CPU1_P3_TX_C_DN<7>")
		)
		(pad "2" smd rect
			(at 0.2667 0 270)
			(size 0.3048 0.381)
			(layers "F.Cu" "F.Mask" "F.Paste")
			(net "P5E_CPU1_P3_TX_DN<7>")
		)
	)
	(footprint ""
		(layer "F.Cu")
		(at 224.21215 -48.78197 180)
		(property "Reference" "R2426"
			(at 0 0 180)
			(layer "F.SilkS")
			(hide yes)
			(effects
				(font
					(size 1.27 1.27)
				)
			)
		)
		(property "Value" ""
			(at 0 0 180)
			(layer "F.Fab")
			(effects
				(font
					(size 1.27 1.27)
				)
			)
		)
		(duplicate_pad_numbers_are_jumpers no)
		(fp_line
			(start 0.7874 0.4064)
			(end -0.7874 0.4064)
			(stroke
				(width 0.1524)
				(type default)
			)
			(layer "F.SilkS")
		)
		(fp_line
			(start 0.7874 -0.4064)
			(end 0.7874 0.4064)
			(stroke
				(width 0.1524)
				(type default)
			)
			(layer "F.SilkS")
		)
		(fp_line
			(start -0.7874 0.4064)
			(end -0.7874 -0.4064)
			(stroke
				(width 0.1524)
				(type default)
			)
			(layer "F.SilkS")
		)
		(fp_line
			(start -0.7874 -0.4064)
			(end 0.7874 -0.4064)
			(stroke
				(width 0.1524)
				(type default)
			)
			(layer "F.SilkS")
		)
		(fp_line
			(start 0.67945 0.3048)
			(end 0.120396 0.3048)
			(stroke
				(width 0.1)
				(type default)
			)
			(layer "F.Fab")
		)
		(fp_line
			(start 0.67945 -0.3048)
			(end 0.67945 0.3048)
			(stroke
				(width 0.1)
				(type default)
			)
			(layer "F.Fab")
		)
		(fp_line
			(start 0.12065 -0.2794)
			(end 0.12065 -0.3048)
			(stroke
				(width 0.1)
				(type default)
			)
			(layer "F.Fab")
		)
		(fp_line
			(start 0.12065 -0.3048)
			(end 0.67945 -0.3048)
			(stroke
				(width 0.1)
				(type default)
			)
			(layer "F.Fab")
		)
		(fp_line
			(start 0.120396 0.3048)
			(end 0.120396 0.2794)
			(stroke
				(width 0.1)
				(type default)
			)
			(layer "F.Fab")
		)
		(fp_line
			(start 0.120396 0.2794)
			(end -0.12065 0.2794)
			(stroke
				(width 0.1)
				(type default)
			)
			(layer "F.Fab")
		)
		(fp_line
			(start -0.12065 0.3048)
			(end -0.67945 0.3048)
			(stroke
				(width 0.1)
				(type default)
			)
			(layer "F.Fab")
		)
		(fp_line
			(start -0.12065 0.2794)
			(end -0.12065 0.3048)
			(stroke
				(width 0.1)
				(type default)
			)
			(layer "F.Fab")
		)
		(fp_line
			(start -0.12065 -0.2794)
			(end 0.12065 -0.2794)
			(stroke
				(width 0.1)
				(type default)
			)
			(layer "F.Fab")
		)
		(fp_line
			(start -0.12065 -0.305054)
			(end -0.12065 -0.2794)
			(stroke
				(width 0.1)
				(type default)
			)
			(layer "F.Fab")
		)
		(fp_line
			(start -0.67945 0.3048)
			(end -0.67945 -0.305054)
			(stroke
				(width 0.1)
				(type default)
			)
			(layer "F.Fab")
		)
		(fp_line
			(start -0.67945 -0.305054)
			(end -0.12065 -0.305054)
			(stroke
				(width 0.1)
				(type default)
			)
			(layer "F.Fab")
		)
		(pad "1" smd circle
			(at -0.40005 0 180)
			(size 0 0)
			(layers "F.Cu" "F.Mask" "F.Paste")
			(net "E1S_0_PERST1_CLKREQ_N")
		)
		(pad "2" smd circle
			(at 0.40005 0 180)
			(size 0 0)
			(layers "F.Cu" "F.Mask" "F.Paste")
			(net "GND")
		)
	)
	(footprint ""
		(layer "F.Cu")
		(at 147.53844 -38.95344)
		(property "Reference" "U235"
			(at -1.44272 2.425192 0)
			(unlocked yes)
			(layer "F.SilkS")
			(effects
				(font
					(size 0.7874 0.5842)
					(thickness 0.1524)
				)
				(justify left)
			)
		)
		(property "Value" ""
			(at 0 0 0)
			(layer "F.Fab")
			(effects
				(font
					(size 1.27 1.27)
				)
			)
		)
		(duplicate_pad_numbers_are_jumpers no)
		(fp_line
			(start -1.463548 -1.549908)
			(end -0.787908 -1.549908)
			(stroke
				(width 0.1524)
				(type default)
			)
			(layer "F.SilkS")
		)
		(fp_line
			(start -1.463548 1.549908)
			(end -1.463548 -1.549908)
			(stroke
				(width 0.1524)
				(type default)
			)
			(layer "F.SilkS")
		)
		(fp_line
			(start -0.787908 -1.549908)
			(end 0 -0.762)
			(stroke
				(width 0.1524)
				(type default)
			)
			(layer "F.SilkS")
		)
		(fp_line
			(start 0 -0.762)
			(end 0.762 -1.549908)
			(stroke
				(width 0.1524)
				(type default)
			)
			(layer "F.SilkS")
		)
		(fp_line
			(start 0.762 -1.549908)
			(end 1.463548 -1.549908)
			(stroke
				(width 0.1524)
				(type default)
			)
			(layer "F.SilkS")
		)
		(fp_line
			(start 1.463548 -1.549908)
			(end 1.463548 1.549908)
			(stroke
				(width 0.1524)
				(type default)
			)
			(layer "F.SilkS")
		)
		(fp_line
			(start 1.463548 1.549908)
			(end -1.463548 1.549908)
			(stroke
				(width 0.1524)
				(type default)
			)
			(layer "F.SilkS")
		)
		(fp_poly
			(pts
				(xy -3.062732 -1.753616) (xy -2.624582 -2.191766) (xy -2.40538 -1.534414)
			)
			(stroke
				(width 0)
				(type default)
			)
			(fill yes)
			(layer "F.SilkS")
		)
		(fp_line
			(start -1.549908 -1.549908)
			(end 1.549908 -1.549908)
			(stroke
				(width 0.1)
				(type default)
			)
			(layer "F.Fab")
		)
		(fp_line
			(start -1.549908 1.549908)
			(end -1.549908 -1.549908)
			(stroke
				(width 0.1)
				(type default)
			)
			(layer "F.Fab")
		)
		(fp_line
			(start 1.549908 -1.549908)
			(end 1.549908 1.549908)
			(stroke
				(width 0.1)
				(type default)
			)
			(layer "F.Fab")
		)
		(fp_line
			(start 1.549908 1.549908)
			(end -1.549908 1.549908)
			(stroke
				(width 0.1)
				(type default)
			)
			(layer "F.Fab")
		)
		(fp_poly
			(pts
				(xy -3.4798 -1.359916) (xy -2.86004 -1.050036) (xy -3.4798 -0.740156)
			)
			(stroke
				(width 0)
				(type default)
			)
			(fill yes)
			(layer "F.Fab")
		)
		(pad "1" smd rect
			(at -2.175002 -1.050036 90)
			(size 0.6096 1.1684)
			(layers "F.Cu" "F.Mask" "F.Paste")
			(net "P3V3_AUX")
		)
		(pad "2" smd rect
			(at -2.175002 -0.32512 90)
			(size 0.4318 1.1684)
			(layers "F.Cu" "F.Mask" "F.Paste")
			(net "SMB_OCP_V3_2_3V3AUX_SCL")
		)
		(pad "3" smd rect
			(at -2.175002 0.32512 90)
			(size 0.4318 1.1684)
			(layers "F.Cu" "F.Mask" "F.Paste")
			(net "SMB_OCP_V3_2_3V3AUX_SDA")
		)
		(pad "4" smd rect
			(at -2.175002 1.050036 90)
			(size 0.6096 1.1684)
			(layers "F.Cu" "F.Mask" "F.Paste")
			(net "GND")
		)
		(pad "5" smd rect
			(at 2.175002 1.050036 90)
			(size 0.6096 1.1684)
			(layers "F.Cu" "F.Mask" "F.Paste")
			(net "HP_LVC3_OCP_V3_2_R_EN")
		)
		(pad "6" smd rect
			(at 2.175002 0.32512 90)
			(size 0.4318 1.1684)
			(layers "F.Cu" "F.Mask" "F.Paste")
			(net "SMB_OCP_V3_2_3V3AUX_BUF_SDA")
		)
		(pad "7" smd rect
			(at 2.175002 -0.32512 90)
			(size 0.4318 1.1684)
			(layers "F.Cu" "F.Mask" "F.Paste")
			(net "SMB_OCP_V3_2_3V3AUX_BUF_SCL")
		)
		(pad "8" smd rect
			(at 2.175002 -1.050036 90)
			(size 0.6096 1.1684)
			(layers "F.Cu" "F.Mask" "F.Paste")
			(net "P3V3_OCP_V3_2")
		)
	)
	(footprint ""
		(layer "F.Cu")
		(at 299.543724 -396.412974 90)
		(property "Reference" "R624"
			(at 0 0 90)
			(layer "F.SilkS")
			(hide yes)
			(effects
				(font
					(size 1.27 1.27)
				)
			)
		)
		(property "Value" ""
			(at 0 0 90)
			(layer "F.Fab")
			(effects
				(font
					(size 1.27 1.27)
				)
			)
		)
		(duplicate_pad_numbers_are_jumpers no)
		(fp_line
			(start 0.32512 -0.175006)
			(end 0.32512 0.175006)
			(stroke
				(width 0.1)
				(type default)
			)
			(layer "F.Fab")
		)
		(fp_line
			(start -0.32512 -0.175006)
			(end 0.32512 -0.175006)
			(stroke
				(width 0.1)
				(type default)
			)
			(layer "F.Fab")
		)
		(fp_line
			(start 0.32512 0.175006)
			(end -0.32512 0.175006)
			(stroke
				(width 0.1)
				(type default)
			)
			(layer "F.Fab")
		)
		(fp_line
			(start -0.32512 0.175006)
			(end -0.32512 -0.175006)
			(stroke
				(width 0.1)
				(type default)
			)
			(layer "F.Fab")
		)
		(pad "1" smd rect
			(at -0.2667 0 90)
			(size 0.3048 0.381)
			(layers "F.Cu" "F.Mask" "F.Paste")
			(net "CLK_100M_RETIMER_CPU0_P0_DP")
		)
		(pad "2" smd rect
			(at 0.2667 0 270)
			(size 0.3048 0.381)
			(layers "F.Cu" "F.Mask" "F.Paste")
			(net "GND")
		)
	)
	(footprint ""
		(layer "F.Cu")
		(at 140.420344 -38.796468)
		(property "Reference" "R6209"
			(at 0 0 0)
			(layer "F.SilkS")
			(hide yes)
			(effects
				(font
					(size 1.27 1.27)
				)
			)
		)
		(property "Value" ""
			(at 0 0 0)
			(layer "F.Fab")
			(effects
				(font
					(size 1.27 1.27)
				)
			)
		)
		(duplicate_pad_numbers_are_jumpers no)
		(fp_line
			(start -0.7874 -0.4064)
			(end 0.7874 -0.4064)
			(stroke
				(width 0.1524)
				(type default)
			)
			(layer "F.SilkS")
		)
		(fp_line
			(start -0.7874 0.4064)
			(end -0.7874 -0.4064)
			(stroke
				(width 0.1524)
				(type default)
			)
			(layer "F.SilkS")
		)
		(fp_line
			(start 0.7874 -0.4064)
			(end 0.7874 0.4064)
			(stroke
				(width 0.1524)
				(type default)
			)
			(layer "F.SilkS")
		)
		(fp_line
			(start 0.7874 0.4064)
			(end -0.7874 0.4064)
			(stroke
				(width 0.1524)
				(type default)
			)
			(layer "F.SilkS")
		)
		(fp_line
			(start -0.67945 -0.305054)
			(end -0.12065 -0.305054)
			(stroke
				(width 0.1)
				(type default)
			)
			(layer "F.Fab")
		)
		(fp_line
			(start -0.67945 0.3048)
			(end -0.67945 -0.305054)
			(stroke
				(width 0.1)
				(type default)
			)
			(layer "F.Fab")
		)
		(fp_line
			(start -0.12065 -0.305054)
			(end -0.12065 -0.2794)
			(stroke
				(width 0.1)
				(type default)
			)
			(layer "F.Fab")
		)
		(fp_line
			(start -0.12065 -0.2794)
			(end 0.12065 -0.2794)
			(stroke
				(width 0.1)
				(type default)
			)
			(layer "F.Fab")
		)
		(fp_line
			(start -0.12065 0.2794)
			(end -0.12065 0.3048)
			(stroke
				(width 0.1)
				(type default)
			)
			(layer "F.Fab")
		)
		(fp_line
			(start -0.12065 0.3048)
			(end -0.67945 0.3048)
			(stroke
				(width 0.1)
				(type default)
			)
			(layer "F.Fab")
		)
		(fp_line
			(start 0.120396 0.2794)
			(end -0.12065 0.2794)
			(stroke
				(width 0.1)
				(type default)
			)
			(layer "F.Fab")
		)
		(fp_line
			(start 0.120396 0.3048)
			(end 0.120396 0.2794)
			(stroke
				(width 0.1)
				(type default)
			)
			(layer "F.Fab")
		)
		(fp_line
			(start 0.12065 -0.3048)
			(end 0.67945 -0.3048)
			(stroke
				(width 0.1)
				(type default)
			)
			(layer "F.Fab")
		)
		(fp_line
			(start 0.12065 -0.2794)
			(end 0.12065 -0.3048)
			(stroke
				(width 0.1)
				(type default)
			)
			(layer "F.Fab")
		)
		(fp_line
			(start 0.67945 -0.3048)
			(end 0.67945 0.3048)
			(stroke
				(width 0.1)
				(type default)
			)
			(layer "F.Fab")
		)
		(fp_line
			(start 0.67945 0.3048)
			(end 0.120396 0.3048)
			(stroke
				(width 0.1)
				(type default)
			)
			(layer "F.Fab")
		)
		(pad "1" smd circle
			(at -0.40005 0)
			(size 0 0)
			(layers "F.Cu" "F.Mask" "F.Paste")
			(net "USB_CPU0_HUB1_VBUS_US")
		)
		(pad "2" smd circle
			(at 0.40005 0)
			(size 0 0)
			(layers "F.Cu" "F.Mask" "F.Paste")
			(net "GND")
		)
	)
	(footprint ""
		(layer "F.Cu")
		(at 204.597 -104.013)
		(property "Reference" "D8003"
			(at -1.405636 -1.31953 0)
			(unlocked yes)
			(layer "F.SilkS")
			(effects
				(font
					(size 0.7874 0.5842)
					(thickness 0.1524)
				)
				(justify left)
			)
		)
		(property "Value" ""
			(at 0 0 0)
			(layer "F.Fab")
			(effects
				(font
					(size 1.27 1.27)
				)
			)
		)
		(duplicate_pad_numbers_are_jumpers no)
		(fp_line
			(start -2.050796 -0.700024)
			(end 2.050796 -0.700024)
			(stroke
				(width 0.1524)
				(type default)
			)
			(layer "F.SilkS")
		)
		(fp_line
			(start -2.050796 0.700024)
			(end -2.050796 -0.700024)
			(stroke
				(width 0.1524)
				(type default)
			)
			(layer "F.SilkS")
		)
		(fp_line
			(start -0.30607 -0.500126)
			(end -0.30607 0.500126)
			(stroke
				(width 0.1524)
				(type default)
			)
			(layer "F.SilkS")
		)
		(fp_line
			(start -0.30607 0.500126)
			(end 0.193802 0)
			(stroke
				(width 0.1524)
				(type default)
			)
			(layer "F.SilkS")
		)
		(fp_line
			(start 0.193802 0)
			(end -0.30607 -0.500126)
			(stroke
				(width 0.1524)
				(type default)
			)
			(layer "F.SilkS")
		)
		(fp_line
			(start 0.293878 -0.500126)
			(end 0.293878 0.500126)
			(stroke
				(width 0.1524)
				(type default)
			)
			(layer "F.SilkS")
		)
		(fp_line
			(start 2.050796 -0.700024)
			(end 2.050796 0.700024)
			(stroke
				(width 0.1524)
				(type default)
			)
			(layer "F.SilkS")
		)
		(fp_line
			(start 2.050796 0.700024)
			(end -2.050796 0.700024)
			(stroke
				(width 0.1524)
				(type default)
			)
			(layer "F.SilkS")
		)
		(fp_line
			(start 2.051304 0.635)
			(end 2.152904 0.635)
			(stroke
				(width 0.1524)
				(type default)
			)
			(layer "F.SilkS")
		)
		(fp_line
			(start 2.051304 0.6985)
			(end 2.051304 0.635)
			(stroke
				(width 0.1524)
				(type default)
			)
			(layer "F.SilkS")
		)
		(fp_line
			(start 2.064004 -0.6985)
			(end 2.229104 -0.6985)
			(stroke
				(width 0.1524)
				(type default)
			)
			(layer "F.SilkS")
		)
		(fp_line
			(start 2.064004 -0.6731)
			(end 2.064004 -0.6985)
			(stroke
				(width 0.1524)
				(type default)
			)
			(layer "F.SilkS")
		)
		(fp_line
			(start 2.152904 -0.6985)
			(end 2.343404 -0.6985)
			(stroke
				(width 0.1524)
				(type default)
			)
			(layer "F.SilkS")
		)
		(fp_line
			(start 2.152904 0.635)
			(end 2.152904 -0.6985)
			(stroke
				(width 0.1524)
				(type default)
			)
			(layer "F.SilkS")
		)
		(fp_line
			(start 2.229104 -0.6985)
			(end 2.229104 0.6985)
			(stroke
				(width 0.1524)
				(type default)
			)
			(layer "F.SilkS")
		)
		(fp_line
			(start 2.229104 0.6985)
			(end 2.051304 0.6985)
			(stroke
				(width 0.1524)
				(type default)
			)
			(layer "F.SilkS")
		)
		(fp_line
			(start 2.343404 -0.6985)
			(end 2.343404 0.6985)
			(stroke
				(width 0.1524)
				(type default)
			)
			(layer "F.SilkS")
		)
		(fp_line
			(start 2.343404 0.6985)
			(end 2.216404 0.6985)
			(stroke
				(width 0.1524)
				(type default)
			)
			(layer "F.SilkS")
		)
		(fp_line
			(start -0.899922 -0.700024)
			(end 0.899922 -0.700024)
			(stroke
				(width 0.1)
				(type default)
			)
			(layer "F.Fab")
		)
		(fp_line
			(start -0.899922 0.700024)
			(end -0.899922 -0.700024)
			(stroke
				(width 0.1)
				(type default)
			)
			(layer "F.Fab")
		)
		(fp_line
			(start 0.899922 -0.700024)
			(end 0.899922 0.700024)
			(stroke
				(width 0.1)
				(type default)
			)
			(layer "F.Fab")
		)
		(fp_line
			(start 0.899922 0.700024)
			(end -0.899922 0.700024)
			(stroke
				(width 0.1)
				(type default)
			)
			(layer "F.Fab")
		)
		(fp_text user "+"
			(at -2.478532 -0.494792 90)
			(unlocked yes)
			(layer "F.SilkS")
			(effects
				(font
					(size 1.905 1.4224)
					(thickness 0.1524)
				)
				(justify left)
			)
		)
		(fp_text user "-"
			(at 3.947414 1.054862 180)
			(unlocked yes)
			(layer "F.SilkS")
			(effects
				(font
					(size 1.905 1.4224)
					(thickness 0.1524)
				)
				(justify left)
			)
		)
		(fp_text user "+"
			(at -3.123946 0.762 90)
			(unlocked yes)
			(layer "F.Fab")
			(effects
				(font
					(size 1.905 1.4224)
					(thickness 0.1524)
				)
				(justify left)
			)
		)
		(fp_text user "-"
			(at 3.880104 0.23495 180)
			(unlocked yes)
			(layer "F.Fab")
			(effects
				(font
					(size 1.905 1.4224)
					(thickness 0.1524)
				)
				(justify left)
			)
		)
		(pad "1" smd rect
			(at -1.199896 0 270)
			(size 0.6604 1.3716)
			(layers "F.Cu" "F.Mask" "F.Paste")
			(net "PWRGD_CHAF_CPU0_R1")
		)
		(pad "2" smd rect
			(at 1.199896 0 90)
			(size 0.6604 1.3716)
			(layers "F.Cu" "F.Mask" "F.Paste")
			(net "P3V3_AUX")
		)
	)
	(footprint ""
		(layer "F.Cu")
		(at 110.149894 -173.31436 -90)
		(property "Reference" "PC285_4"
			(at 0 0 270)
			(layer "F.SilkS")
			(hide yes)
			(effects
				(font
					(size 1.27 1.27)
				)
			)
		)
		(property "Value" ""
			(at 0 0 270)
			(layer "F.Fab")
			(effects
				(font
					(size 1.27 1.27)
				)
			)
		)
		(duplicate_pad_numbers_are_jumpers no)
		(fp_line
			(start -0.7874 0.4064)
			(end -0.7874 -0.4064)
			(stroke
				(width 0.1524)
				(type default)
			)
			(layer "F.SilkS")
		)
		(fp_line
			(start 0.7874 0.4064)
			(end -0.7874 0.4064)
			(stroke
				(width 0.1524)
				(type default)
			)
			(layer "F.SilkS")
		)
		(fp_line
			(start -0.7874 -0.4064)
			(end 0.7874 -0.4064)
			(stroke
				(width 0.1524)
				(type default)
			)
			(layer "F.SilkS")
		)
		(fp_line
			(start 0.7874 -0.4064)
			(end 0.7874 0.4064)
			(stroke
				(width 0.1524)
				(type default)
			)
			(layer "F.SilkS")
		)
		(fp_line
			(start -0.67945 0.3048)
			(end -0.67945 -0.305054)
			(stroke
				(width 0.1)
				(type default)
			)
			(layer "F.Fab")
		)
		(fp_line
			(start -0.12065 0.3048)
			(end -0.67945 0.3048)
			(stroke
				(width 0.1)
				(type default)
			)
			(layer "F.Fab")
		)
		(fp_line
			(start 0.120396 0.3048)
			(end 0.120396 0.2794)
			(stroke
				(width 0.1)
				(type default)
			)
			(layer "F.Fab")
		)
		(fp_line
			(start 0.67945 0.3048)
			(end 0.120396 0.3048)
			(stroke
				(width 0.1)
				(type default)
			)
			(layer "F.Fab")
		)
		(fp_line
			(start -0.12065 0.2794)
			(end -0.12065 0.3048)
			(stroke
				(width 0.1)
				(type default)
			)
			(layer "F.Fab")
		)
		(fp_line
			(start 0.120396 0.2794)
			(end -0.12065 0.2794)
			(stroke
				(width 0.1)
				(type default)
			)
			(layer "F.Fab")
		)
		(fp_line
			(start -0.12065 -0.2794)
			(end 0.12065 -0.2794)
			(stroke
				(width 0.1)
				(type default)
			)
			(layer "F.Fab")
		)
		(fp_line
			(start 0.12065 -0.2794)
			(end 0.12065 -0.3048)
			(stroke
				(width 0.1)
				(type default)
			)
			(layer "F.Fab")
		)
		(fp_line
			(start 0.12065 -0.3048)
			(end 0.67945 -0.3048)
			(stroke
				(width 0.1)
				(type default)
			)
			(layer "F.Fab")
		)
		(fp_line
			(start 0.67945 -0.3048)
			(end 0.67945 0.3048)
			(stroke
				(width 0.1)
				(type default)
			)
			(layer "F.Fab")
		)
		(fp_line
			(start -0.67945 -0.305054)
			(end -0.12065 -0.305054)
			(stroke
				(width 0.1)
				(type default)
			)
			(layer "F.Fab")
		)
		(fp_line
			(start -0.12065 -0.305054)
			(end -0.12065 -0.2794)
			(stroke
				(width 0.1)
				(type default)
			)
			(layer "F.Fab")
		)
		(pad "1" smd circle
			(at -0.40005 0 270)
			(size 0 0)
			(layers "F.Cu" "F.Mask" "F.Paste")
			(net "PVDDCR_CPU0_P1_VCCS")
		)
		(pad "2" smd circle
			(at 0.40005 0 270)
			(size 0 0)
			(layers "F.Cu" "F.Mask" "F.Paste")
			(net "GND")
		)
	)
	(footprint ""
		(layer "F.Cu")
		(at 163.703 -115.280948 180)
		(property "Reference" "R6038"
			(at 0 0 180)
			(layer "F.SilkS")
			(hide yes)
			(effects
				(font
					(size 1.27 1.27)
				)
			)
		)
		(property "Value" ""
			(at 0 0 180)
			(layer "F.Fab")
			(effects
				(font
					(size 1.27 1.27)
				)
			)
		)
		(duplicate_pad_numbers_are_jumpers no)
		(fp_line
			(start 0.7874 0.4064)
			(end -0.7874 0.4064)
			(stroke
				(width 0.1524)
				(type default)
			)
			(layer "F.SilkS")
		)
		(fp_line
			(start 0.7874 -0.4064)
			(end 0.7874 0.4064)
			(stroke
				(width 0.1524)
				(type default)
			)
			(layer "F.SilkS")
		)
		(fp_line
			(start -0.7874 0.4064)
			(end -0.7874 -0.4064)
			(stroke
				(width 0.1524)
				(type default)
			)
			(layer "F.SilkS")
		)
		(fp_line
			(start -0.7874 -0.4064)
			(end 0.7874 -0.4064)
			(stroke
				(width 0.1524)
				(type default)
			)
			(layer "F.SilkS")
		)
		(fp_line
			(start 0.67945 0.3048)
			(end 0.120396 0.3048)
			(stroke
				(width 0.1)
				(type default)
			)
			(layer "F.Fab")
		)
		(fp_line
			(start 0.67945 -0.3048)
			(end 0.67945 0.3048)
			(stroke
				(width 0.1)
				(type default)
			)
			(layer "F.Fab")
		)
		(fp_line
			(start 0.12065 -0.2794)
			(end 0.12065 -0.3048)
			(stroke
				(width 0.1)
				(type default)
			)
			(layer "F.Fab")
		)
		(fp_line
			(start 0.12065 -0.3048)
			(end 0.67945 -0.3048)
			(stroke
				(width 0.1)
				(type default)
			)
			(layer "F.Fab")
		)
		(fp_line
			(start 0.120396 0.3048)
			(end 0.120396 0.2794)
			(stroke
				(width 0.1)
				(type default)
			)
			(layer "F.Fab")
		)
		(fp_line
			(start 0.120396 0.2794)
			(end -0.12065 0.2794)
			(stroke
				(width 0.1)
				(type default)
			)
			(layer "F.Fab")
		)
		(fp_line
			(start -0.12065 0.3048)
			(end -0.67945 0.3048)
			(stroke
				(width 0.1)
				(type default)
			)
			(layer "F.Fab")
		)
		(fp_line
			(start -0.12065 0.2794)
			(end -0.12065 0.3048)
			(stroke
				(width 0.1)
				(type default)
			)
			(layer "F.Fab")
		)
		(fp_line
			(start -0.12065 -0.2794)
			(end 0.12065 -0.2794)
			(stroke
				(width 0.1)
				(type default)
			)
			(layer "F.Fab")
		)
		(fp_line
			(start -0.12065 -0.305054)
			(end -0.12065 -0.2794)
			(stroke
				(width 0.1)
				(type default)
			)
			(layer "F.Fab")
		)
		(fp_line
			(start -0.67945 0.3048)
			(end -0.67945 -0.305054)
			(stroke
				(width 0.1)
				(type default)
			)
			(layer "F.Fab")
		)
		(fp_line
			(start -0.67945 -0.305054)
			(end -0.12065 -0.305054)
			(stroke
				(width 0.1)
				(type default)
			)
			(layer "F.Fab")
		)
		(pad "1" smd circle
			(at -0.40005 0 180)
			(size 0 0)
			(layers "F.Cu" "F.Mask" "F.Paste")
			(net "UV_ALERT_N")
		)
		(pad "2" smd circle
			(at 0.40005 0 180)
			(size 0 0)
			(layers "F.Cu" "F.Mask" "F.Paste")
			(net "IRQ_UV_DETECT_N")
		)
	)
	(footprint ""
		(layer "F.Cu")
		(at 429.171354 -396.119604)
		(property "Reference" "C672"
			(at 0 0 0)
			(layer "F.SilkS")
			(hide yes)
			(effects
				(font
					(size 1.27 1.27)
				)
			)
		)
		(property "Value" ""
			(at 0 0 0)
			(layer "F.Fab")
			(effects
				(font
					(size 1.27 1.27)
				)
			)
		)
		(duplicate_pad_numbers_are_jumpers no)
		(fp_line
			(start -0.7874 -0.4064)
			(end 0.7874 -0.4064)
			(stroke
				(width 0.1524)
				(type default)
			)
			(layer "F.SilkS")
		)
		(fp_line
			(start -0.7874 0.4064)
			(end -0.7874 -0.4064)
			(stroke
				(width 0.1524)
				(type default)
			)
			(layer "F.SilkS")
		)
		(fp_line
			(start 0.7874 -0.4064)
			(end 0.7874 0.4064)
			(stroke
				(width 0.1524)
				(type default)
			)
			(layer "F.SilkS")
		)
		(fp_line
			(start 0.7874 0.4064)
			(end -0.7874 0.4064)
			(stroke
				(width 0.1524)
				(type default)
			)
			(layer "F.SilkS")
		)
		(fp_line
			(start -0.67945 -0.305054)
			(end -0.12065 -0.305054)
			(stroke
				(width 0.1)
				(type default)
			)
			(layer "F.Fab")
		)
		(fp_line
			(start -0.67945 0.3048)
			(end -0.67945 -0.305054)
			(stroke
				(width 0.1)
				(type default)
			)
			(layer "F.Fab")
		)
		(fp_line
			(start -0.12065 -0.305054)
			(end -0.12065 -0.2794)
			(stroke
				(width 0.1)
				(type default)
			)
			(layer "F.Fab")
		)
		(fp_line
			(start -0.12065 -0.2794)
			(end 0.12065 -0.2794)
			(stroke
				(width 0.1)
				(type default)
			)
			(layer "F.Fab")
		)
		(fp_line
			(start -0.12065 0.2794)
			(end -0.12065 0.3048)
			(stroke
				(width 0.1)
				(type default)
			)
			(layer "F.Fab")
		)
		(fp_line
			(start -0.12065 0.3048)
			(end -0.67945 0.3048)
			(stroke
				(width 0.1)
				(type default)
			)
			(layer "F.Fab")
		)
		(fp_line
			(start 0.120396 0.2794)
			(end -0.12065 0.2794)
			(stroke
				(width 0.1)
				(type default)
			)
			(layer "F.Fab")
		)
		(fp_line
			(start 0.120396 0.3048)
			(end 0.120396 0.2794)
			(stroke
				(width 0.1)
				(type default)
			)
			(layer "F.Fab")
		)
		(fp_line
			(start 0.12065 -0.3048)
			(end 0.67945 -0.3048)
			(stroke
				(width 0.1)
				(type default)
			)
			(layer "F.Fab")
		)
		(fp_line
			(start 0.12065 -0.2794)
			(end 0.12065 -0.3048)
			(stroke
				(width 0.1)
				(type default)
			)
			(layer "F.Fab")
		)
		(fp_line
			(start 0.67945 -0.3048)
			(end 0.67945 0.3048)
			(stroke
				(width 0.1)
				(type default)
			)
			(layer "F.Fab")
		)
		(fp_line
			(start 0.67945 0.3048)
			(end 0.120396 0.3048)
			(stroke
				(width 0.1)
				(type default)
			)
			(layer "F.Fab")
		)
		(pad "1" smd circle
			(at -0.40005 0)
			(size 0 0)
			(layers "F.Cu" "F.Mask" "F.Paste")
			(net "P1V8_CPU0_RT_1D")
		)
		(pad "2" smd circle
			(at 0.40005 0)
			(size 0 0)
			(layers "F.Cu" "F.Mask" "F.Paste")
			(net "GND")
		)
	)
	(footprint ""
		(layer "F.Cu")
		(at 124.58827 -32.751268 180)
		(property "Reference" "C6021"
			(at 0 0 180)
			(layer "F.SilkS")
			(hide yes)
			(effects
				(font
					(size 1.27 1.27)
				)
			)
		)
		(property "Value" ""
			(at 0 0 180)
			(layer "F.Fab")
			(effects
				(font
					(size 1.27 1.27)
				)
			)
		)
		(duplicate_pad_numbers_are_jumpers no)
		(fp_line
			(start 0.40005 0.4064)
			(end -0.40005 0.4064)
			(stroke
				(width 0.1524)
				(type default)
			)
			(layer "F.SilkS")
		)
		(fp_line
			(start -0.40005 -0.4064)
			(end 0.40005 -0.4064)
			(stroke
				(width 0.1524)
				(type default)
			)
			(layer "F.SilkS")
		)
		(fp_line
			(start 0.6858 0.3048)
			(end 0.1016 0.3048)
			(stroke
				(width 0.1)
				(type default)
			)
			(layer "F.Fab")
		)
		(fp_line
			(start 0.6858 -0.3048)
			(end 0.6858 0.3048)
			(stroke
				(width 0.1)
				(type default)
			)
			(layer "F.Fab")
		)
		(fp_line
			(start 0.1016 0.3048)
			(end 0.1016 0.2794)
			(stroke
				(width 0.1)
				(type default)
			)
			(layer "F.Fab")
		)
		(fp_line
			(start 0.1016 0.2794)
			(end -0.1016 0.2794)
			(stroke
				(width 0.1)
				(type default)
			)
			(layer "F.Fab")
		)
		(fp_line
			(start 0.1016 -0.2794)
			(end 0.1016 -0.3048)
			(stroke
				(width 0.1)
				(type default)
			)
			(layer "F.Fab")
		)
		(fp_line
			(start 0.1016 -0.3048)
			(end 0.6858 -0.3048)
			(stroke
				(width 0.1)
				(type default)
			)
			(layer "F.Fab")
		)
		(fp_line
			(start -0.1016 0.3048)
			(end -0.6858 0.3048)
			(stroke
				(width 0.1)
				(type default)
			)
			(layer "F.Fab")
		)
		(fp_line
			(start -0.1016 0.2794)
			(end -0.1016 0.3048)
			(stroke
				(width 0.1)
				(type default)
			)
			(layer "F.Fab")
		)
		(fp_line
			(start -0.1016 -0.2794)
			(end 0.1016 -0.2794)
			(stroke
				(width 0.1)
				(type default)
			)
			(layer "F.Fab")
		)
		(fp_line
			(start -0.1016 -0.3048)
			(end -0.1016 -0.2794)
			(stroke
				(width 0.1)
				(type default)
			)
			(layer "F.Fab")
		)
		(fp_line
			(start -0.6858 0.3048)
			(end -0.6858 -0.3048)
			(stroke
				(width 0.1)
				(type default)
			)
			(layer "F.Fab")
		)
		(fp_line
			(start -0.6858 -0.3048)
			(end -0.1016 -0.3048)
			(stroke
				(width 0.1)
				(type default)
			)
			(layer "F.Fab")
		)
		(pad "1" smd rect
			(at -0.40005 0)
			(size 0.4572 0.508)
			(layers "F.Cu" "F.Mask" "F.Paste")
			(net "USB3_CPU0_BMC_RX_DP")
		)
		(pad "2" smd rect
			(at 0.40005 0)
			(size 0.4572 0.508)
			(layers "F.Cu" "F.Mask" "F.Paste")
			(net "USB3_CPU0_BMC_RX_C2_DP")
		)
	)
	(footprint ""
		(layer "F.Cu")
		(at 152.982422 -52.771294 90)
		(property "Reference" "R3573"
			(at 0 0 90)
			(layer "F.SilkS")
			(hide yes)
			(effects
				(font
					(size 1.27 1.27)
				)
			)
		)
		(property "Value" ""
			(at 0 0 90)
			(layer "F.Fab")
			(effects
				(font
					(size 1.27 1.27)
				)
			)
		)
		(duplicate_pad_numbers_are_jumpers no)
		(fp_line
			(start 0.7874 -0.4064)
			(end 0.7874 0.4064)
			(stroke
				(width 0.1524)
				(type default)
			)
			(layer "F.SilkS")
		)
		(fp_line
			(start -0.7874 -0.4064)
			(end 0.7874 -0.4064)
			(stroke
				(width 0.1524)
				(type default)
			)
			(layer "F.SilkS")
		)
		(fp_line
			(start 0.7874 0.4064)
			(end -0.7874 0.4064)
			(stroke
				(width 0.1524)
				(type default)
			)
			(layer "F.SilkS")
		)
		(fp_line
			(start -0.7874 0.4064)
			(end -0.7874 -0.4064)
			(stroke
				(width 0.1524)
				(type default)
			)
			(layer "F.SilkS")
		)
		(fp_line
			(start -0.12065 -0.305054)
			(end -0.12065 -0.2794)
			(stroke
				(width 0.1)
				(type default)
			)
			(layer "F.Fab")
		)
		(fp_line
			(start -0.67945 -0.305054)
			(end -0.12065 -0.305054)
			(stroke
				(width 0.1)
				(type default)
			)
			(layer "F.Fab")
		)
		(fp_line
			(start 0.67945 -0.3048)
			(end 0.67945 0.3048)
			(stroke
				(width 0.1)
				(type default)
			)
			(layer "F.Fab")
		)
		(fp_line
			(start 0.12065 -0.3048)
			(end 0.67945 -0.3048)
			(stroke
				(width 0.1)
				(type default)
			)
			(layer "F.Fab")
		)
		(fp_line
			(start 0.12065 -0.2794)
			(end 0.12065 -0.3048)
			(stroke
				(width 0.1)
				(type default)
			)
			(layer "F.Fab")
		)
		(fp_line
			(start -0.12065 -0.2794)
			(end 0.12065 -0.2794)
			(stroke
				(width 0.1)
				(type default)
			)
			(layer "F.Fab")
		)
		(fp_line
			(start 0.120396 0.2794)
			(end -0.12065 0.2794)
			(stroke
				(width 0.1)
				(type default)
			)
			(layer "F.Fab")
		)
		(fp_line
			(start -0.12065 0.2794)
			(end -0.12065 0.3048)
			(stroke
				(width 0.1)
				(type default)
			)
			(layer "F.Fab")
		)
		(fp_line
			(start 0.67945 0.3048)
			(end 0.120396 0.3048)
			(stroke
				(width 0.1)
				(type default)
			)
			(layer "F.Fab")
		)
		(fp_line
			(start 0.120396 0.3048)
			(end 0.120396 0.2794)
			(stroke
				(width 0.1)
				(type default)
			)
			(layer "F.Fab")
		)
		(fp_line
			(start -0.12065 0.3048)
			(end -0.67945 0.3048)
			(stroke
				(width 0.1)
				(type default)
			)
			(layer "F.Fab")
		)
		(fp_line
			(start -0.67945 0.3048)
			(end -0.67945 -0.305054)
			(stroke
				(width 0.1)
				(type default)
			)
			(layer "F.Fab")
		)
		(pad "1" smd circle
			(at -0.40005 0 90)
			(size 0 0)
			(layers "F.Cu" "F.Mask" "F.Paste")
			(net "SMB_INA230_4_3V3AUX_SDA_R")
		)
		(pad "2" smd circle
			(at 0.40005 0 90)
			(size 0 0)
			(layers "F.Cu" "F.Mask" "F.Paste")
			(net "SMB_INA230_4_3V3AUX_SDA_R1")
		)
	)
	(footprint ""
		(layer "F.Cu")
		(at 120.631712 -72.323452)
		(property "Reference" "PC852"
			(at 0 0 0)
			(layer "F.SilkS")
			(hide yes)
			(effects
				(font
					(size 1.27 1.27)
				)
			)
		)
		(property "Value" ""
			(at 0 0 0)
			(layer "F.Fab")
			(effects
				(font
					(size 1.27 1.27)
				)
			)
		)
		(duplicate_pad_numbers_are_jumpers no)
		(fp_line
			(start -0.7874 -0.4064)
			(end 0.7874 -0.4064)
			(stroke
				(width 0.1524)
				(type default)
			)
			(layer "F.SilkS")
		)
		(fp_line
			(start -0.7874 0.4064)
			(end -0.7874 -0.4064)
			(stroke
				(width 0.1524)
				(type default)
			)
			(layer "F.SilkS")
		)
		(fp_line
			(start 0.7874 -0.4064)
			(end 0.7874 0.4064)
			(stroke
				(width 0.1524)
				(type default)
			)
			(layer "F.SilkS")
		)
		(fp_line
			(start 0.7874 0.4064)
			(end -0.7874 0.4064)
			(stroke
				(width 0.1524)
				(type default)
			)
			(layer "F.SilkS")
		)
		(fp_line
			(start -0.67945 -0.305054)
			(end -0.12065 -0.305054)
			(stroke
				(width 0.1)
				(type default)
			)
			(layer "F.Fab")
		)
		(fp_line
			(start -0.67945 0.3048)
			(end -0.67945 -0.305054)
			(stroke
				(width 0.1)
				(type default)
			)
			(layer "F.Fab")
		)
		(fp_line
			(start -0.12065 -0.305054)
			(end -0.12065 -0.2794)
			(stroke
				(width 0.1)
				(type default)
			)
			(layer "F.Fab")
		)
		(fp_line
			(start -0.12065 -0.2794)
			(end 0.12065 -0.2794)
			(stroke
				(width 0.1)
				(type default)
			)
			(layer "F.Fab")
		)
		(fp_line
			(start -0.12065 0.2794)
			(end -0.12065 0.3048)
			(stroke
				(width 0.1)
				(type default)
			)
			(layer "F.Fab")
		)
		(fp_line
			(start -0.12065 0.3048)
			(end -0.67945 0.3048)
			(stroke
				(width 0.1)
				(type default)
			)
			(layer "F.Fab")
		)
		(fp_line
			(start 0.120396 0.2794)
			(end -0.12065 0.2794)
			(stroke
				(width 0.1)
				(type default)
			)
			(layer "F.Fab")
		)
		(fp_line
			(start 0.120396 0.3048)
			(end 0.120396 0.2794)
			(stroke
				(width 0.1)
				(type default)
			)
			(layer "F.Fab")
		)
		(fp_line
			(start 0.12065 -0.3048)
			(end 0.67945 -0.3048)
			(stroke
				(width 0.1)
				(type default)
			)
			(layer "F.Fab")
		)
		(fp_line
			(start 0.12065 -0.2794)
			(end 0.12065 -0.3048)
			(stroke
				(width 0.1)
				(type default)
			)
			(layer "F.Fab")
		)
		(fp_line
			(start 0.67945 -0.3048)
			(end 0.67945 0.3048)
			(stroke
				(width 0.1)
				(type default)
			)
			(layer "F.Fab")
		)
		(fp_line
			(start 0.67945 0.3048)
			(end 0.120396 0.3048)
			(stroke
				(width 0.1)
				(type default)
			)
			(layer "F.Fab")
		)
		(pad "1" smd circle
			(at -0.40005 0)
			(size 0 0)
			(layers "F.Cu" "F.Mask" "F.Paste")
			(net "P1V2_AUX_FB")
		)
		(pad "2" smd circle
			(at 0.40005 0)
			(size 0 0)
			(layers "F.Cu" "F.Mask" "F.Paste")
			(net "P1V2_AUX")
		)
	)
	(footprint ""
		(layer "F.Cu")
		(at 24.640794 -394.410184)
		(property "Reference" "PR6628"
			(at 0 0 0)
			(layer "F.SilkS")
			(hide yes)
			(effects
				(font
					(size 1.27 1.27)
				)
			)
		)
		(property "Value" ""
			(at 0 0 0)
			(layer "F.Fab")
			(effects
				(font
					(size 1.27 1.27)
				)
			)
		)
		(duplicate_pad_numbers_are_jumpers no)
		(fp_line
			(start -0.7874 -0.4064)
			(end 0.7874 -0.4064)
			(stroke
				(width 0.1524)
				(type default)
			)
			(layer "F.SilkS")
		)
		(fp_line
			(start -0.7874 0.4064)
			(end -0.7874 -0.4064)
			(stroke
				(width 0.1524)
				(type default)
			)
			(layer "F.SilkS")
		)
		(fp_line
			(start 0.7874 -0.4064)
			(end 0.7874 0.4064)
			(stroke
				(width 0.1524)
				(type default)
			)
			(layer "F.SilkS")
		)
		(fp_line
			(start 0.7874 0.4064)
			(end -0.7874 0.4064)
			(stroke
				(width 0.1524)
				(type default)
			)
			(layer "F.SilkS")
		)
		(fp_line
			(start -0.67945 -0.305054)
			(end -0.12065 -0.305054)
			(stroke
				(width 0.1)
				(type default)
			)
			(layer "F.Fab")
		)
		(fp_line
			(start -0.67945 0.3048)
			(end -0.67945 -0.305054)
			(stroke
				(width 0.1)
				(type default)
			)
			(layer "F.Fab")
		)
		(fp_line
			(start -0.12065 -0.305054)
			(end -0.12065 -0.2794)
			(stroke
				(width 0.1)
				(type default)
			)
			(layer "F.Fab")
		)
		(fp_line
			(start -0.12065 -0.2794)
			(end 0.12065 -0.2794)
			(stroke
				(width 0.1)
				(type default)
			)
			(layer "F.Fab")
		)
		(fp_line
			(start -0.12065 0.2794)
			(end -0.12065 0.3048)
			(stroke
				(width 0.1)
				(type default)
			)
			(layer "F.Fab")
		)
		(fp_line
			(start -0.12065 0.3048)
			(end -0.67945 0.3048)
			(stroke
				(width 0.1)
				(type default)
			)
			(layer "F.Fab")
		)
		(fp_line
			(start 0.120396 0.2794)
			(end -0.12065 0.2794)
			(stroke
				(width 0.1)
				(type default)
			)
			(layer "F.Fab")
		)
		(fp_line
			(start 0.120396 0.3048)
			(end 0.120396 0.2794)
			(stroke
				(width 0.1)
				(type default)
			)
			(layer "F.Fab")
		)
		(fp_line
			(start 0.12065 -0.3048)
			(end 0.67945 -0.3048)
			(stroke
				(width 0.1)
				(type default)
			)
			(layer "F.Fab")
		)
		(fp_line
			(start 0.12065 -0.2794)
			(end 0.12065 -0.3048)
			(stroke
				(width 0.1)
				(type default)
			)
			(layer "F.Fab")
		)
		(fp_line
			(start 0.67945 -0.3048)
			(end 0.67945 0.3048)
			(stroke
				(width 0.1)
				(type default)
			)
			(layer "F.Fab")
		)
		(fp_line
			(start 0.67945 0.3048)
			(end 0.120396 0.3048)
			(stroke
				(width 0.1)
				(type default)
			)
			(layer "F.Fab")
		)
		(pad "1" smd circle
			(at -0.40005 0)
			(size 0 0)
			(layers "F.Cu" "F.Mask" "F.Paste")
			(net "P0V9_RETIMER_CPU1_LSET2")
		)
		(pad "2" smd circle
			(at 0.40005 0)
			(size 0 0)
			(layers "F.Cu" "F.Mask" "F.Paste")
			(net "GND")
		)
	)
	(footprint ""
		(layer "F.Cu")
		(at 56.50992 -30.648148)
		(property "Reference" "R3236"
			(at 0 0 0)
			(layer "F.SilkS")
			(hide yes)
			(effects
				(font
					(size 1.27 1.27)
				)
			)
		)
		(property "Value" ""
			(at 0 0 0)
			(layer "F.Fab")
			(effects
				(font
					(size 1.27 1.27)
				)
			)
		)
		(duplicate_pad_numbers_are_jumpers no)
		(fp_line
			(start -0.7874 -0.4064)
			(end 0.7874 -0.4064)
			(stroke
				(width 0.1524)
				(type default)
			)
			(layer "F.SilkS")
		)
		(fp_line
			(start -0.7874 0.4064)
			(end -0.7874 -0.4064)
			(stroke
				(width 0.1524)
				(type default)
			)
			(layer "F.SilkS")
		)
		(fp_line
			(start 0.7874 -0.4064)
			(end 0.7874 0.4064)
			(stroke
				(width 0.1524)
				(type default)
			)
			(layer "F.SilkS")
		)
		(fp_line
			(start 0.7874 0.4064)
			(end -0.7874 0.4064)
			(stroke
				(width 0.1524)
				(type default)
			)
			(layer "F.SilkS")
		)
		(fp_line
			(start -0.67945 -0.305054)
			(end -0.12065 -0.305054)
			(stroke
				(width 0.1)
				(type default)
			)
			(layer "F.Fab")
		)
		(fp_line
			(start -0.67945 0.3048)
			(end -0.67945 -0.305054)
			(stroke
				(width 0.1)
				(type default)
			)
			(layer "F.Fab")
		)
		(fp_line
			(start -0.12065 -0.305054)
			(end -0.12065 -0.2794)
			(stroke
				(width 0.1)
				(type default)
			)
			(layer "F.Fab")
		)
		(fp_line
			(start -0.12065 -0.2794)
			(end 0.12065 -0.2794)
			(stroke
				(width 0.1)
				(type default)
			)
			(layer "F.Fab")
		)
		(fp_line
			(start -0.12065 0.2794)
			(end -0.12065 0.3048)
			(stroke
				(width 0.1)
				(type default)
			)
			(layer "F.Fab")
		)
		(fp_line
			(start -0.12065 0.3048)
			(end -0.67945 0.3048)
			(stroke
				(width 0.1)
				(type default)
			)
			(layer "F.Fab")
		)
		(fp_line
			(start 0.120396 0.2794)
			(end -0.12065 0.2794)
			(stroke
				(width 0.1)
				(type default)
			)
			(layer "F.Fab")
		)
		(fp_line
			(start 0.120396 0.3048)
			(end 0.120396 0.2794)
			(stroke
				(width 0.1)
				(type default)
			)
			(layer "F.Fab")
		)
		(fp_line
			(start 0.12065 -0.3048)
			(end 0.67945 -0.3048)
			(stroke
				(width 0.1)
				(type default)
			)
			(layer "F.Fab")
		)
		(fp_line
			(start 0.12065 -0.2794)
			(end 0.12065 -0.3048)
			(stroke
				(width 0.1)
				(type default)
			)
			(layer "F.Fab")
		)
		(fp_line
			(start 0.67945 -0.3048)
			(end 0.67945 0.3048)
			(stroke
				(width 0.1)
				(type default)
			)
			(layer "F.Fab")
		)
		(fp_line
			(start 0.67945 0.3048)
			(end 0.120396 0.3048)
			(stroke
				(width 0.1)
				(type default)
			)
			(layer "F.Fab")
		)
		(pad "1" smd circle
			(at -0.40005 0)
			(size 0 0)
			(layers "F.Cu" "F.Mask" "F.Paste")
			(net "RST_HP_OCP_V3_2_R_N")
		)
		(pad "2" smd circle
			(at 0.40005 0)
			(size 0 0)
			(layers "F.Cu" "F.Mask" "F.Paste")
			(net "RST_SMB_OCP_V3_2_N")
		)
	)
	(footprint ""
		(layer "F.Cu")
		(at 93.29801 -54.701694)
		(property "Reference" "PR3782"
			(at 0 0 0)
			(layer "F.SilkS")
			(hide yes)
			(effects
				(font
					(size 1.27 1.27)
				)
			)
		)
		(property "Value" ""
			(at 0 0 0)
			(layer "F.Fab")
			(effects
				(font
					(size 1.27 1.27)
				)
			)
		)
		(duplicate_pad_numbers_are_jumpers no)
		(fp_line
			(start -0.7874 -0.4064)
			(end 0.7874 -0.4064)
			(stroke
				(width 0.1524)
				(type default)
			)
			(layer "F.SilkS")
		)
		(fp_line
			(start -0.7874 0.4064)
			(end -0.7874 -0.4064)
			(stroke
				(width 0.1524)
				(type default)
			)
			(layer "F.SilkS")
		)
		(fp_line
			(start 0.7874 -0.4064)
			(end 0.7874 0.4064)
			(stroke
				(width 0.1524)
				(type default)
			)
			(layer "F.SilkS")
		)
		(fp_line
			(start 0.7874 0.4064)
			(end -0.7874 0.4064)
			(stroke
				(width 0.1524)
				(type default)
			)
			(layer "F.SilkS")
		)
		(fp_line
			(start -0.67945 -0.305054)
			(end -0.12065 -0.305054)
			(stroke
				(width 0.1)
				(type default)
			)
			(layer "F.Fab")
		)
		(fp_line
			(start -0.67945 0.3048)
			(end -0.67945 -0.305054)
			(stroke
				(width 0.1)
				(type default)
			)
			(layer "F.Fab")
		)
		(fp_line
			(start -0.12065 -0.305054)
			(end -0.12065 -0.2794)
			(stroke
				(width 0.1)
				(type default)
			)
			(layer "F.Fab")
		)
		(fp_line
			(start -0.12065 -0.2794)
			(end 0.12065 -0.2794)
			(stroke
				(width 0.1)
				(type default)
			)
			(layer "F.Fab")
		)
		(fp_line
			(start -0.12065 0.2794)
			(end -0.12065 0.3048)
			(stroke
				(width 0.1)
				(type default)
			)
			(layer "F.Fab")
		)
		(fp_line
			(start -0.12065 0.3048)
			(end -0.67945 0.3048)
			(stroke
				(width 0.1)
				(type default)
			)
			(layer "F.Fab")
		)
		(fp_line
			(start 0.120396 0.2794)
			(end -0.12065 0.2794)
			(stroke
				(width 0.1)
				(type default)
			)
			(layer "F.Fab")
		)
		(fp_line
			(start 0.120396 0.3048)
			(end 0.120396 0.2794)
			(stroke
				(width 0.1)
				(type default)
			)
			(layer "F.Fab")
		)
		(fp_line
			(start 0.12065 -0.3048)
			(end 0.67945 -0.3048)
			(stroke
				(width 0.1)
				(type default)
			)
			(layer "F.Fab")
		)
		(fp_line
			(start 0.12065 -0.2794)
			(end 0.12065 -0.3048)
			(stroke
				(width 0.1)
				(type default)
			)
			(layer "F.Fab")
		)
		(fp_line
			(start 0.67945 -0.3048)
			(end 0.67945 0.3048)
			(stroke
				(width 0.1)
				(type default)
			)
			(layer "F.Fab")
		)
		(fp_line
			(start 0.67945 0.3048)
			(end 0.120396 0.3048)
			(stroke
				(width 0.1)
				(type default)
			)
			(layer "F.Fab")
		)
		(pad "1" smd circle
			(at -0.40005 0)
			(size 0 0)
			(layers "F.Cu" "F.Mask" "F.Paste")
			(net "P3V3_AUX")
		)
		(pad "2" smd circle
			(at 0.40005 0)
			(size 0 0)
			(layers "F.Cu" "F.Mask" "F.Paste")
			(net "P3V3_OCP_VCC_2")
		)
	)
	(footprint ""
		(layer "F.Cu")
		(at 164.544756 -42.177462)
		(property "Reference" "R155"
			(at 0 0 0)
			(layer "F.SilkS")
			(hide yes)
			(effects
				(font
					(size 1.27 1.27)
				)
			)
		)
		(property "Value" ""
			(at 0 0 0)
			(layer "F.Fab")
			(effects
				(font
					(size 1.27 1.27)
				)
			)
		)
		(duplicate_pad_numbers_are_jumpers no)
		(fp_line
			(start -0.7874 -0.4064)
			(end 0.7874 -0.4064)
			(stroke
				(width 0.1524)
				(type default)
			)
			(layer "F.SilkS")
		)
		(fp_line
			(start -0.7874 0.4064)
			(end -0.7874 -0.4064)
			(stroke
				(width 0.1524)
				(type default)
			)
			(layer "F.SilkS")
		)
		(fp_line
			(start 0.7874 -0.4064)
			(end 0.7874 0.4064)
			(stroke
				(width 0.1524)
				(type default)
			)
			(layer "F.SilkS")
		)
		(fp_line
			(start 0.7874 0.4064)
			(end -0.7874 0.4064)
			(stroke
				(width 0.1524)
				(type default)
			)
			(layer "F.SilkS")
		)
		(fp_line
			(start -0.67945 -0.305054)
			(end -0.12065 -0.305054)
			(stroke
				(width 0.1)
				(type default)
			)
			(layer "F.Fab")
		)
		(fp_line
			(start -0.67945 0.3048)
			(end -0.67945 -0.305054)
			(stroke
				(width 0.1)
				(type default)
			)
			(layer "F.Fab")
		)
		(fp_line
			(start -0.12065 -0.305054)
			(end -0.12065 -0.2794)
			(stroke
				(width 0.1)
				(type default)
			)
			(layer "F.Fab")
		)
		(fp_line
			(start -0.12065 -0.2794)
			(end 0.12065 -0.2794)
			(stroke
				(width 0.1)
				(type default)
			)
			(layer "F.Fab")
		)
		(fp_line
			(start -0.12065 0.2794)
			(end -0.12065 0.3048)
			(stroke
				(width 0.1)
				(type default)
			)
			(layer "F.Fab")
		)
		(fp_line
			(start -0.12065 0.3048)
			(end -0.67945 0.3048)
			(stroke
				(width 0.1)
				(type default)
			)
			(layer "F.Fab")
		)
		(fp_line
			(start 0.120396 0.2794)
			(end -0.12065 0.2794)
			(stroke
				(width 0.1)
				(type default)
			)
			(layer "F.Fab")
		)
		(fp_line
			(start 0.120396 0.3048)
			(end 0.120396 0.2794)
			(stroke
				(width 0.1)
				(type default)
			)
			(layer "F.Fab")
		)
		(fp_line
			(start 0.12065 -0.3048)
			(end 0.67945 -0.3048)
			(stroke
				(width 0.1)
				(type default)
			)
			(layer "F.Fab")
		)
		(fp_line
			(start 0.12065 -0.2794)
			(end 0.12065 -0.3048)
			(stroke
				(width 0.1)
				(type default)
			)
			(layer "F.Fab")
		)
		(fp_line
			(start 0.67945 -0.3048)
			(end 0.67945 0.3048)
			(stroke
				(width 0.1)
				(type default)
			)
			(layer "F.Fab")
		)
		(fp_line
			(start 0.67945 0.3048)
			(end 0.120396 0.3048)
			(stroke
				(width 0.1)
				(type default)
			)
			(layer "F.Fab")
		)
		(pad "1" smd circle
			(at -0.40005 0)
			(size 0 0)
			(layers "F.Cu" "F.Mask" "F.Paste")
			(net "P3V3_AUX")
		)
		(pad "2" smd circle
			(at 0.40005 0)
			(size 0 0)
			(layers "F.Cu" "F.Mask" "F.Paste")
			(net "M2_SSD0_CLKREQ_EN_N_BUF")
		)
	)
	(footprint ""
		(layer "F.Cu")
		(at 171.196 -108.168948 180)
		(property "Reference" "R50"
			(at 0 0 180)
			(layer "F.SilkS")
			(hide yes)
			(effects
				(font
					(size 1.27 1.27)
				)
			)
		)
		(property "Value" ""
			(at 0 0 180)
			(layer "F.Fab")
			(effects
				(font
					(size 1.27 1.27)
				)
			)
		)
		(duplicate_pad_numbers_are_jumpers no)
		(fp_line
			(start 0.7874 0.4064)
			(end -0.7874 0.4064)
			(stroke
				(width 0.1524)
				(type default)
			)
			(layer "F.SilkS")
		)
		(fp_line
			(start 0.7874 -0.4064)
			(end 0.7874 0.4064)
			(stroke
				(width 0.1524)
				(type default)
			)
			(layer "F.SilkS")
		)
		(fp_line
			(start -0.7874 0.4064)
			(end -0.7874 -0.4064)
			(stroke
				(width 0.1524)
				(type default)
			)
			(layer "F.SilkS")
		)
		(fp_line
			(start -0.7874 -0.4064)
			(end 0.7874 -0.4064)
			(stroke
				(width 0.1524)
				(type default)
			)
			(layer "F.SilkS")
		)
		(fp_line
			(start 0.67945 0.3048)
			(end 0.120396 0.3048)
			(stroke
				(width 0.1)
				(type default)
			)
			(layer "F.Fab")
		)
		(fp_line
			(start 0.67945 -0.3048)
			(end 0.67945 0.3048)
			(stroke
				(width 0.1)
				(type default)
			)
			(layer "F.Fab")
		)
		(fp_line
			(start 0.12065 -0.2794)
			(end 0.12065 -0.3048)
			(stroke
				(width 0.1)
				(type default)
			)
			(layer "F.Fab")
		)
		(fp_line
			(start 0.12065 -0.3048)
			(end 0.67945 -0.3048)
			(stroke
				(width 0.1)
				(type default)
			)
			(layer "F.Fab")
		)
		(fp_line
			(start 0.120396 0.3048)
			(end 0.120396 0.2794)
			(stroke
				(width 0.1)
				(type default)
			)
			(layer "F.Fab")
		)
		(fp_line
			(start 0.120396 0.2794)
			(end -0.12065 0.2794)
			(stroke
				(width 0.1)
				(type default)
			)
			(layer "F.Fab")
		)
		(fp_line
			(start -0.12065 0.3048)
			(end -0.67945 0.3048)
			(stroke
				(width 0.1)
				(type default)
			)
			(layer "F.Fab")
		)
		(fp_line
			(start -0.12065 0.2794)
			(end -0.12065 0.3048)
			(stroke
				(width 0.1)
				(type default)
			)
			(layer "F.Fab")
		)
		(fp_line
			(start -0.12065 -0.2794)
			(end 0.12065 -0.2794)
			(stroke
				(width 0.1)
				(type default)
			)
			(layer "F.Fab")
		)
		(fp_line
			(start -0.12065 -0.305054)
			(end -0.12065 -0.2794)
			(stroke
				(width 0.1)
				(type default)
			)
			(layer "F.Fab")
		)
		(fp_line
			(start -0.67945 0.3048)
			(end -0.67945 -0.305054)
			(stroke
				(width 0.1)
				(type default)
			)
			(layer "F.Fab")
		)
		(fp_line
			(start -0.67945 -0.305054)
			(end -0.12065 -0.305054)
			(stroke
				(width 0.1)
				(type default)
			)
			(layer "F.Fab")
		)
		(pad "1" smd circle
			(at -0.40005 0 180)
			(size 0 0)
			(layers "F.Cu" "F.Mask" "F.Paste")
			(net "SCM_JTAG_MUX_R_S1")
		)
		(pad "2" smd circle
			(at 0.40005 0 180)
			(size 0 0)
			(layers "F.Cu" "F.Mask" "F.Paste")
			(net "SCM_JTAG_MUX_S1")
		)
	)
	(footprint ""
		(layer "F.Cu")
		(at 457.684632 -107.018836)
		(property "Reference" "U211"
			(at -1.4732 -1.768348 0)
			(unlocked yes)
			(layer "F.SilkS")
			(effects
				(font
					(size 0.7874 0.5842)
					(thickness 0.1524)
				)
				(justify left)
			)
		)
		(property "Value" ""
			(at 0 0 0)
			(layer "F.Fab")
			(effects
				(font
					(size 1.27 1.27)
				)
			)
		)
		(duplicate_pad_numbers_are_jumpers no)
		(fp_line
			(start -1.38176 -1.100074)
			(end -1.38176 1.100074)
			(stroke
				(width 0.1524)
				(type default)
			)
			(layer "F.SilkS")
		)
		(fp_line
			(start -1.38176 1.100074)
			(end 1.38176 1.100074)
			(stroke
				(width 0.1524)
				(type default)
			)
			(layer "F.SilkS")
		)
		(fp_line
			(start -0.592074 -1.100074)
			(end -1.38176 -1.100074)
			(stroke
				(width 0.1524)
				(type default)
			)
			(layer "F.SilkS")
		)
		(fp_line
			(start 0 -0.508)
			(end -0.592074 -1.100074)
			(stroke
				(width 0.1524)
				(type default)
			)
			(layer "F.SilkS")
		)
		(fp_line
			(start 0.592074 -1.100074)
			(end 0 -0.508)
			(stroke
				(width 0.1524)
				(type default)
			)
			(layer "F.SilkS")
		)
		(fp_line
			(start 1.38176 -1.100074)
			(end 0.592074 -1.100074)
			(stroke
				(width 0.1524)
				(type default)
			)
			(layer "F.SilkS")
		)
		(fp_line
			(start 1.38176 1.100074)
			(end 1.38176 -1.100074)
			(stroke
				(width 0.1524)
				(type default)
			)
			(layer "F.SilkS")
		)
		(fp_poly
			(pts
				(xy -1.9431 -0.429768) (xy -1.9431 -0.870204) (xy -1.50241 -0.649986)
			)
			(stroke
				(width 0)
				(type default)
			)
			(fill yes)
			(layer "F.SilkS")
		)
		(fp_line
			(start -0.674878 -1.100074)
			(end -0.674878 1.100074)
			(stroke
				(width 0.1)
				(type default)
			)
			(layer "F.Fab")
		)
		(fp_line
			(start -0.674878 1.100074)
			(end 0.674878 1.100074)
			(stroke
				(width 0.1)
				(type default)
			)
			(layer "F.Fab")
		)
		(fp_line
			(start 0.674878 -1.100074)
			(end -0.674878 -1.100074)
			(stroke
				(width 0.1)
				(type default)
			)
			(layer "F.Fab")
		)
		(fp_line
			(start 0.674878 1.100074)
			(end 0.674878 -1.100074)
			(stroke
				(width 0.1)
				(type default)
			)
			(layer "F.Fab")
		)
		(fp_poly
			(pts
				(xy -1.9431 -0.870204) (xy -1.50241 -0.649986) (xy -1.9431 -0.429768)
			)
			(stroke
				(width 0)
				(type default)
			)
			(fill yes)
			(layer "F.Fab")
		)
		(pad "1" smd rect
			(at -0.94996 -0.649986 270)
			(size 0.4318 0.6096)
			(layers "F.Cu" "F.Mask" "F.Paste")
			(net "OCP_SFF_PRSNT0_R_N")
		)
		(pad "2" smd rect
			(at -0.94996 0 270)
			(size 0.4318 0.6096)
			(layers "F.Cu" "F.Mask" "F.Paste")
			(net "GND")
		)
		(pad "3" smd rect
			(at -0.94996 0.649986 270)
			(size 0.4318 0.6096)
			(layers "F.Cu" "F.Mask" "F.Paste")
			(net "OCP_SFF_PRSNT1_R_N")
		)
		(pad "4" smd rect
			(at 0.94996 0.649986 270)
			(size 0.4318 0.6096)
			(layers "F.Cu" "F.Mask" "F.Paste")
			(net "HP_LVC3_OCP_V3_1_PRSNT2_N_R")
		)
		(pad "5" smd rect
			(at 0.94996 0 270)
			(size 0.4318 0.6096)
			(layers "F.Cu" "F.Mask" "F.Paste")
			(net "P3V3_AUX")
		)
		(pad "6" smd rect
			(at 0.94996 -0.649986 270)
			(size 0.4318 0.6096)
			(layers "F.Cu" "F.Mask" "F.Paste")
			(net "HP_LVC3_OCP_V3_1_PRSNT2_N_R")
		)
	)
	(footprint ""
		(layer "F.Cu")
		(at 10.066782 -412.215584)
		(property "Reference" "PR6533"
			(at 0 0 0)
			(layer "F.SilkS")
			(hide yes)
			(effects
				(font
					(size 1.27 1.27)
				)
			)
		)
		(property "Value" ""
			(at 0 0 0)
			(layer "F.Fab")
			(effects
				(font
					(size 1.27 1.27)
				)
			)
		)
		(duplicate_pad_numbers_are_jumpers no)
		(fp_line
			(start -0.7874 -0.4064)
			(end 0.7874 -0.4064)
			(stroke
				(width 0.1524)
				(type default)
			)
			(layer "F.SilkS")
		)
		(fp_line
			(start -0.7874 0.4064)
			(end -0.7874 -0.4064)
			(stroke
				(width 0.1524)
				(type default)
			)
			(layer "F.SilkS")
		)
		(fp_line
			(start 0.7874 -0.4064)
			(end 0.7874 0.4064)
			(stroke
				(width 0.1524)
				(type default)
			)
			(layer "F.SilkS")
		)
		(fp_line
			(start 0.7874 0.4064)
			(end -0.7874 0.4064)
			(stroke
				(width 0.1524)
				(type default)
			)
			(layer "F.SilkS")
		)
		(fp_line
			(start -0.67945 -0.305054)
			(end -0.12065 -0.305054)
			(stroke
				(width 0.1)
				(type default)
			)
			(layer "F.Fab")
		)
		(fp_line
			(start -0.67945 0.3048)
			(end -0.67945 -0.305054)
			(stroke
				(width 0.1)
				(type default)
			)
			(layer "F.Fab")
		)
		(fp_line
			(start -0.12065 -0.305054)
			(end -0.12065 -0.2794)
			(stroke
				(width 0.1)
				(type default)
			)
			(layer "F.Fab")
		)
		(fp_line
			(start -0.12065 -0.2794)
			(end 0.12065 -0.2794)
			(stroke
				(width 0.1)
				(type default)
			)
			(layer "F.Fab")
		)
		(fp_line
			(start -0.12065 0.2794)
			(end -0.12065 0.3048)
			(stroke
				(width 0.1)
				(type default)
			)
			(layer "F.Fab")
		)
		(fp_line
			(start -0.12065 0.3048)
			(end -0.67945 0.3048)
			(stroke
				(width 0.1)
				(type default)
			)
			(layer "F.Fab")
		)
		(fp_line
			(start 0.120396 0.2794)
			(end -0.12065 0.2794)
			(stroke
				(width 0.1)
				(type default)
			)
			(layer "F.Fab")
		)
		(fp_line
			(start 0.120396 0.3048)
			(end 0.120396 0.2794)
			(stroke
				(width 0.1)
				(type default)
			)
			(layer "F.Fab")
		)
		(fp_line
			(start 0.12065 -0.3048)
			(end 0.67945 -0.3048)
			(stroke
				(width 0.1)
				(type default)
			)
			(layer "F.Fab")
		)
		(fp_line
			(start 0.12065 -0.2794)
			(end 0.12065 -0.3048)
			(stroke
				(width 0.1)
				(type default)
			)
			(layer "F.Fab")
		)
		(fp_line
			(start 0.67945 -0.3048)
			(end 0.67945 0.3048)
			(stroke
				(width 0.1)
				(type default)
			)
			(layer "F.Fab")
		)
		(fp_line
			(start 0.67945 0.3048)
			(end 0.120396 0.3048)
			(stroke
				(width 0.1)
				(type default)
			)
			(layer "F.Fab")
		)
		(pad "1" smd circle
			(at -0.40005 0)
			(size 0 0)
			(layers "F.Cu" "F.Mask" "F.Paste")
			(net "GND")
		)
		(pad "2" smd circle
			(at 0.40005 0)
			(size 0 0)
			(layers "F.Cu" "F.Mask" "F.Paste")
			(net "P0V9_RETIMER_CPU1_ADDR")
		)
	)
	(footprint ""
		(layer "F.Cu")
		(at 178.71694 -403.484842 180)
		(property "Reference" "PR2149"
			(at 0 0 180)
			(layer "F.SilkS")
			(hide yes)
			(effects
				(font
					(size 1.27 1.27)
				)
			)
		)
		(property "Value" ""
			(at 0 0 180)
			(layer "F.Fab")
			(effects
				(font
					(size 1.27 1.27)
				)
			)
		)
		(duplicate_pad_numbers_are_jumpers no)
		(fp_line
			(start 0.7874 0.4064)
			(end -0.7874 0.4064)
			(stroke
				(width 0.1524)
				(type default)
			)
			(layer "F.SilkS")
		)
		(fp_line
			(start 0.7874 -0.4064)
			(end 0.7874 0.4064)
			(stroke
				(width 0.1524)
				(type default)
			)
			(layer "F.SilkS")
		)
		(fp_line
			(start -0.7874 0.4064)
			(end -0.7874 -0.4064)
			(stroke
				(width 0.1524)
				(type default)
			)
			(layer "F.SilkS")
		)
		(fp_line
			(start -0.7874 -0.4064)
			(end 0.7874 -0.4064)
			(stroke
				(width 0.1524)
				(type default)
			)
			(layer "F.SilkS")
		)
		(fp_line
			(start 0.67945 0.3048)
			(end 0.120396 0.3048)
			(stroke
				(width 0.1)
				(type default)
			)
			(layer "F.Fab")
		)
		(fp_line
			(start 0.67945 -0.3048)
			(end 0.67945 0.3048)
			(stroke
				(width 0.1)
				(type default)
			)
			(layer "F.Fab")
		)
		(fp_line
			(start 0.12065 -0.2794)
			(end 0.12065 -0.3048)
			(stroke
				(width 0.1)
				(type default)
			)
			(layer "F.Fab")
		)
		(fp_line
			(start 0.12065 -0.3048)
			(end 0.67945 -0.3048)
			(stroke
				(width 0.1)
				(type default)
			)
			(layer "F.Fab")
		)
		(fp_line
			(start 0.120396 0.3048)
			(end 0.120396 0.2794)
			(stroke
				(width 0.1)
				(type default)
			)
			(layer "F.Fab")
		)
		(fp_line
			(start 0.120396 0.2794)
			(end -0.12065 0.2794)
			(stroke
				(width 0.1)
				(type default)
			)
			(layer "F.Fab")
		)
		(fp_line
			(start -0.12065 0.3048)
			(end -0.67945 0.3048)
			(stroke
				(width 0.1)
				(type default)
			)
			(layer "F.Fab")
		)
		(fp_line
			(start -0.12065 0.2794)
			(end -0.12065 0.3048)
			(stroke
				(width 0.1)
				(type default)
			)
			(layer "F.Fab")
		)
		(fp_line
			(start -0.12065 -0.2794)
			(end 0.12065 -0.2794)
			(stroke
				(width 0.1)
				(type default)
			)
			(layer "F.Fab")
		)
		(fp_line
			(start -0.12065 -0.305054)
			(end -0.12065 -0.2794)
			(stroke
				(width 0.1)
				(type default)
			)
			(layer "F.Fab")
		)
		(fp_line
			(start -0.67945 0.3048)
			(end -0.67945 -0.305054)
			(stroke
				(width 0.1)
				(type default)
			)
			(layer "F.Fab")
		)
		(fp_line
			(start -0.67945 -0.305054)
			(end -0.12065 -0.305054)
			(stroke
				(width 0.1)
				(type default)
			)
			(layer "F.Fab")
		)
		(pad "1" smd circle
			(at -0.40005 0 180)
			(size 0 0)
			(layers "F.Cu" "F.Mask" "F.Paste")
			(net "HSC_VDD_R")
		)
		(pad "2" smd circle
			(at 0.40005 0 180)
			(size 0 0)
			(layers "F.Cu" "F.Mask" "F.Paste")
			(net "HSC_VDD")
		)
	)
	(footprint ""
		(layer "F.Cu")
		(at 146.939 -121.793)
		(property "Reference" "R8088"
			(at 0 0 0)
			(layer "F.SilkS")
			(hide yes)
			(effects
				(font
					(size 1.27 1.27)
				)
			)
		)
		(property "Value" ""
			(at 0 0 0)
			(layer "F.Fab")
			(effects
				(font
					(size 1.27 1.27)
				)
			)
		)
		(duplicate_pad_numbers_are_jumpers no)
		(fp_line
			(start -0.7874 -0.4064)
			(end 0.7874 -0.4064)
			(stroke
				(width 0.1524)
				(type default)
			)
			(layer "F.SilkS")
		)
		(fp_line
			(start -0.7874 0.4064)
			(end -0.7874 -0.4064)
			(stroke
				(width 0.1524)
				(type default)
			)
			(layer "F.SilkS")
		)
		(fp_line
			(start 0.7874 -0.4064)
			(end 0.7874 0.4064)
			(stroke
				(width 0.1524)
				(type default)
			)
			(layer "F.SilkS")
		)
		(fp_line
			(start 0.7874 0.4064)
			(end -0.7874 0.4064)
			(stroke
				(width 0.1524)
				(type default)
			)
			(layer "F.SilkS")
		)
		(fp_line
			(start -0.67945 -0.305054)
			(end -0.12065 -0.305054)
			(stroke
				(width 0.1)
				(type default)
			)
			(layer "F.Fab")
		)
		(fp_line
			(start -0.67945 0.3048)
			(end -0.67945 -0.305054)
			(stroke
				(width 0.1)
				(type default)
			)
			(layer "F.Fab")
		)
		(fp_line
			(start -0.12065 -0.305054)
			(end -0.12065 -0.2794)
			(stroke
				(width 0.1)
				(type default)
			)
			(layer "F.Fab")
		)
		(fp_line
			(start -0.12065 -0.2794)
			(end 0.12065 -0.2794)
			(stroke
				(width 0.1)
				(type default)
			)
			(layer "F.Fab")
		)
		(fp_line
			(start -0.12065 0.2794)
			(end -0.12065 0.3048)
			(stroke
				(width 0.1)
				(type default)
			)
			(layer "F.Fab")
		)
		(fp_line
			(start -0.12065 0.3048)
			(end -0.67945 0.3048)
			(stroke
				(width 0.1)
				(type default)
			)
			(layer "F.Fab")
		)
		(fp_line
			(start 0.120396 0.2794)
			(end -0.12065 0.2794)
			(stroke
				(width 0.1)
				(type default)
			)
			(layer "F.Fab")
		)
		(fp_line
			(start 0.120396 0.3048)
			(end 0.120396 0.2794)
			(stroke
				(width 0.1)
				(type default)
			)
			(layer "F.Fab")
		)
		(fp_line
			(start 0.12065 -0.3048)
			(end 0.67945 -0.3048)
			(stroke
				(width 0.1)
				(type default)
			)
			(layer "F.Fab")
		)
		(fp_line
			(start 0.12065 -0.2794)
			(end 0.12065 -0.3048)
			(stroke
				(width 0.1)
				(type default)
			)
			(layer "F.Fab")
		)
		(fp_line
			(start 0.67945 -0.3048)
			(end 0.67945 0.3048)
			(stroke
				(width 0.1)
				(type default)
			)
			(layer "F.Fab")
		)
		(fp_line
			(start 0.67945 0.3048)
			(end 0.120396 0.3048)
			(stroke
				(width 0.1)
				(type default)
			)
			(layer "F.Fab")
		)
		(pad "1" smd circle
			(at -0.40005 0)
			(size 0 0)
			(layers "F.Cu" "F.Mask" "F.Paste")
			(net "P3V3_AUX")
		)
		(pad "2" smd circle
			(at 0.40005 0)
			(size 0 0)
			(layers "F.Cu" "F.Mask" "F.Paste")
			(net "PWRGD_CHAF_CPU1_R1")
		)
	)
	(footprint ""
		(layer "F.Cu")
		(at 304.301398 -431.2539)
		(property "Reference" "R4132"
			(at 0 0 0)
			(layer "F.SilkS")
			(hide yes)
			(effects
				(font
					(size 1.27 1.27)
				)
			)
		)
		(property "Value" ""
			(at 0 0 0)
			(layer "F.Fab")
			(effects
				(font
					(size 1.27 1.27)
				)
			)
		)
		(duplicate_pad_numbers_are_jumpers no)
		(fp_line
			(start -0.7874 -0.4064)
			(end 0.7874 -0.4064)
			(stroke
				(width 0.1524)
				(type default)
			)
			(layer "F.SilkS")
		)
		(fp_line
			(start -0.7874 0.4064)
			(end -0.7874 -0.4064)
			(stroke
				(width 0.1524)
				(type default)
			)
			(layer "F.SilkS")
		)
		(fp_line
			(start 0.7874 -0.4064)
			(end 0.7874 0.4064)
			(stroke
				(width 0.1524)
				(type default)
			)
			(layer "F.SilkS")
		)
		(fp_line
			(start 0.7874 0.4064)
			(end -0.7874 0.4064)
			(stroke
				(width 0.1524)
				(type default)
			)
			(layer "F.SilkS")
		)
		(fp_line
			(start -0.67945 -0.305054)
			(end -0.12065 -0.305054)
			(stroke
				(width 0.1)
				(type default)
			)
			(layer "F.Fab")
		)
		(fp_line
			(start -0.67945 0.3048)
			(end -0.67945 -0.305054)
			(stroke
				(width 0.1)
				(type default)
			)
			(layer "F.Fab")
		)
		(fp_line
			(start -0.12065 -0.305054)
			(end -0.12065 -0.2794)
			(stroke
				(width 0.1)
				(type default)
			)
			(layer "F.Fab")
		)
		(fp_line
			(start -0.12065 -0.2794)
			(end 0.12065 -0.2794)
			(stroke
				(width 0.1)
				(type default)
			)
			(layer "F.Fab")
		)
		(fp_line
			(start -0.12065 0.2794)
			(end -0.12065 0.3048)
			(stroke
				(width 0.1)
				(type default)
			)
			(layer "F.Fab")
		)
		(fp_line
			(start -0.12065 0.3048)
			(end -0.67945 0.3048)
			(stroke
				(width 0.1)
				(type default)
			)
			(layer "F.Fab")
		)
		(fp_line
			(start 0.120396 0.2794)
			(end -0.12065 0.2794)
			(stroke
				(width 0.1)
				(type default)
			)
			(layer "F.Fab")
		)
		(fp_line
			(start 0.120396 0.3048)
			(end 0.120396 0.2794)
			(stroke
				(width 0.1)
				(type default)
			)
			(layer "F.Fab")
		)
		(fp_line
			(start 0.12065 -0.3048)
			(end 0.67945 -0.3048)
			(stroke
				(width 0.1)
				(type default)
			)
			(layer "F.Fab")
		)
		(fp_line
			(start 0.12065 -0.2794)
			(end 0.12065 -0.3048)
			(stroke
				(width 0.1)
				(type default)
			)
			(layer "F.Fab")
		)
		(fp_line
			(start 0.67945 -0.3048)
			(end 0.67945 0.3048)
			(stroke
				(width 0.1)
				(type default)
			)
			(layer "F.Fab")
		)
		(fp_line
			(start 0.67945 0.3048)
			(end 0.120396 0.3048)
			(stroke
				(width 0.1)
				(type default)
			)
			(layer "F.Fab")
		)
		(pad "1" smd circle
			(at -0.40005 0)
			(size 0 0)
			(layers "F.Cu" "F.Mask" "F.Paste")
			(net "GPU_3V3IO_RSVD3_FFU")
		)
		(pad "2" smd circle
			(at 0.40005 0)
			(size 0 0)
			(layers "F.Cu" "F.Mask" "F.Paste")
			(net "GND")
		)
	)
	(footprint ""
		(layer "F.Cu")
		(at 38.443662 -424.202098)
		(property "Reference" "R3291"
			(at 0 0 0)
			(layer "F.SilkS")
			(hide yes)
			(effects
				(font
					(size 1.27 1.27)
				)
			)
		)
		(property "Value" ""
			(at 0 0 0)
			(layer "F.Fab")
			(effects
				(font
					(size 1.27 1.27)
				)
			)
		)
		(duplicate_pad_numbers_are_jumpers no)
		(fp_line
			(start -0.7874 -0.4064)
			(end 0.7874 -0.4064)
			(stroke
				(width 0.1524)
				(type default)
			)
			(layer "F.SilkS")
		)
		(fp_line
			(start -0.7874 0.4064)
			(end -0.7874 -0.4064)
			(stroke
				(width 0.1524)
				(type default)
			)
			(layer "F.SilkS")
		)
		(fp_line
			(start 0.7874 -0.4064)
			(end 0.7874 0.4064)
			(stroke
				(width 0.1524)
				(type default)
			)
			(layer "F.SilkS")
		)
		(fp_line
			(start 0.7874 0.4064)
			(end -0.7874 0.4064)
			(stroke
				(width 0.1524)
				(type default)
			)
			(layer "F.SilkS")
		)
		(fp_line
			(start -0.67945 -0.305054)
			(end -0.12065 -0.305054)
			(stroke
				(width 0.1)
				(type default)
			)
			(layer "F.Fab")
		)
		(fp_line
			(start -0.67945 0.3048)
			(end -0.67945 -0.305054)
			(stroke
				(width 0.1)
				(type default)
			)
			(layer "F.Fab")
		)
		(fp_line
			(start -0.12065 -0.305054)
			(end -0.12065 -0.2794)
			(stroke
				(width 0.1)
				(type default)
			)
			(layer "F.Fab")
		)
		(fp_line
			(start -0.12065 -0.2794)
			(end 0.12065 -0.2794)
			(stroke
				(width 0.1)
				(type default)
			)
			(layer "F.Fab")
		)
		(fp_line
			(start -0.12065 0.2794)
			(end -0.12065 0.3048)
			(stroke
				(width 0.1)
				(type default)
			)
			(layer "F.Fab")
		)
		(fp_line
			(start -0.12065 0.3048)
			(end -0.67945 0.3048)
			(stroke
				(width 0.1)
				(type default)
			)
			(layer "F.Fab")
		)
		(fp_line
			(start 0.120396 0.2794)
			(end -0.12065 0.2794)
			(stroke
				(width 0.1)
				(type default)
			)
			(layer "F.Fab")
		)
		(fp_line
			(start 0.120396 0.3048)
			(end 0.120396 0.2794)
			(stroke
				(width 0.1)
				(type default)
			)
			(layer "F.Fab")
		)
		(fp_line
			(start 0.12065 -0.3048)
			(end 0.67945 -0.3048)
			(stroke
				(width 0.1)
				(type default)
			)
			(layer "F.Fab")
		)
		(fp_line
			(start 0.12065 -0.2794)
			(end 0.12065 -0.3048)
			(stroke
				(width 0.1)
				(type default)
			)
			(layer "F.Fab")
		)
		(fp_line
			(start 0.67945 -0.3048)
			(end 0.67945 0.3048)
			(stroke
				(width 0.1)
				(type default)
			)
			(layer "F.Fab")
		)
		(fp_line
			(start 0.67945 0.3048)
			(end 0.120396 0.3048)
			(stroke
				(width 0.1)
				(type default)
			)
			(layer "F.Fab")
		)
		(pad "1" smd circle
			(at -0.40005 0)
			(size 0 0)
			(layers "F.Cu" "F.Mask" "F.Paste")
			(net "PU_TEST")
		)
		(pad "2" smd circle
			(at 0.40005 0)
			(size 0 0)
			(layers "F.Cu" "F.Mask" "F.Paste")
			(net "GND")
		)
	)
	(footprint ""
		(layer "F.Cu")
		(at 28.5369 -421.069008 180)
		(property "Reference" "C1870"
			(at 0 0 180)
			(layer "F.SilkS")
			(hide yes)
			(effects
				(font
					(size 1.27 1.27)
				)
			)
		)
		(property "Value" ""
			(at 0 0 180)
			(layer "F.Fab")
			(effects
				(font
					(size 1.27 1.27)
				)
			)
		)
		(duplicate_pad_numbers_are_jumpers no)
		(fp_line
			(start 0.7874 -0.4064)
			(end 0.7874 0.215392)
			(stroke
				(width 0.1524)
				(type default)
			)
			(layer "F.SilkS")
		)
		(fp_line
			(start -0.3429 0.4064)
			(end -0.7874 0.4064)
			(stroke
				(width 0.1524)
				(type default)
			)
			(layer "F.SilkS")
		)
		(fp_line
			(start -0.7874 -0.4064)
			(end 0.7874 -0.4064)
			(stroke
				(width 0.1524)
				(type default)
			)
			(layer "F.SilkS")
		)
		(fp_line
			(start 0.6858 0.3048)
			(end 0.1016 0.3048)
			(stroke
				(width 0.1)
				(type default)
			)
			(layer "F.Fab")
		)
		(fp_line
			(start 0.6858 -0.3048)
			(end 0.6858 0.3048)
			(stroke
				(width 0.1)
				(type default)
			)
			(layer "F.Fab")
		)
		(fp_line
			(start 0.1016 0.3048)
			(end 0.1016 0.2794)
			(stroke
				(width 0.1)
				(type default)
			)
			(layer "F.Fab")
		)
		(fp_line
			(start 0.1016 0.2794)
			(end -0.1016 0.2794)
			(stroke
				(width 0.1)
				(type default)
			)
			(layer "F.Fab")
		)
		(fp_line
			(start 0.1016 -0.2794)
			(end 0.1016 -0.3048)
			(stroke
				(width 0.1)
				(type default)
			)
			(layer "F.Fab")
		)
		(fp_line
			(start 0.1016 -0.3048)
			(end 0.6858 -0.3048)
			(stroke
				(width 0.1)
				(type default)
			)
			(layer "F.Fab")
		)
		(fp_line
			(start -0.1016 0.3048)
			(end -0.6858 0.3048)
			(stroke
				(width 0.1)
				(type default)
			)
			(layer "F.Fab")
		)
		(fp_line
			(start -0.1016 0.2794)
			(end -0.1016 0.3048)
			(stroke
				(width 0.1)
				(type default)
			)
			(layer "F.Fab")
		)
		(fp_line
			(start -0.1016 -0.2794)
			(end 0.1016 -0.2794)
			(stroke
				(width 0.1)
				(type default)
			)
			(layer "F.Fab")
		)
		(fp_line
			(start -0.1016 -0.3048)
			(end -0.1016 -0.2794)
			(stroke
				(width 0.1)
				(type default)
			)
			(layer "F.Fab")
		)
		(fp_line
			(start -0.6858 0.3048)
			(end -0.6858 -0.3048)
			(stroke
				(width 0.1)
				(type default)
			)
			(layer "F.Fab")
		)
		(fp_line
			(start -0.6858 -0.3048)
			(end -0.1016 -0.3048)
			(stroke
				(width 0.1)
				(type default)
			)
			(layer "F.Fab")
		)
		(pad "1" smd rect
			(at -0.40005 0)
			(size 0.4572 0.508)
			(layers "F.Cu" "F.Mask" "F.Paste")
			(net "P2E_MB_BMC_TX_BUF_DP<0>")
		)
		(pad "2" smd rect
			(at 0.40005 0)
			(size 0.4572 0.508)
			(layers "F.Cu" "F.Mask" "F.Paste")
			(net "P2E_MB_BMC_TX_BUF_C_DP<0>")
		)
	)
	(footprint ""
		(layer "F.Cu")
		(at 191.055498 -425.829476 -90)
		(property "Reference" "R2794"
			(at 0 0 270)
			(layer "F.SilkS")
			(hide yes)
			(effects
				(font
					(size 1.27 1.27)
				)
			)
		)
		(property "Value" ""
			(at 0 0 270)
			(layer "F.Fab")
			(effects
				(font
					(size 1.27 1.27)
				)
			)
		)
		(duplicate_pad_numbers_are_jumpers no)
		(fp_line
			(start -0.7874 0.4064)
			(end -0.7874 -0.4064)
			(stroke
				(width 0.1524)
				(type default)
			)
			(layer "F.SilkS")
		)
		(fp_line
			(start 0.7874 0.4064)
			(end -0.7874 0.4064)
			(stroke
				(width 0.1524)
				(type default)
			)
			(layer "F.SilkS")
		)
		(fp_line
			(start -0.7874 -0.4064)
			(end 0.7874 -0.4064)
			(stroke
				(width 0.1524)
				(type default)
			)
			(layer "F.SilkS")
		)
		(fp_line
			(start 0.7874 -0.4064)
			(end 0.7874 0.4064)
			(stroke
				(width 0.1524)
				(type default)
			)
			(layer "F.SilkS")
		)
		(fp_line
			(start -0.67945 0.3048)
			(end -0.67945 -0.305054)
			(stroke
				(width 0.1)
				(type default)
			)
			(layer "F.Fab")
		)
		(fp_line
			(start -0.12065 0.3048)
			(end -0.67945 0.3048)
			(stroke
				(width 0.1)
				(type default)
			)
			(layer "F.Fab")
		)
		(fp_line
			(start 0.120396 0.3048)
			(end 0.120396 0.2794)
			(stroke
				(width 0.1)
				(type default)
			)
			(layer "F.Fab")
		)
		(fp_line
			(start 0.67945 0.3048)
			(end 0.120396 0.3048)
			(stroke
				(width 0.1)
				(type default)
			)
			(layer "F.Fab")
		)
		(fp_line
			(start -0.12065 0.2794)
			(end -0.12065 0.3048)
			(stroke
				(width 0.1)
				(type default)
			)
			(layer "F.Fab")
		)
		(fp_line
			(start 0.120396 0.2794)
			(end -0.12065 0.2794)
			(stroke
				(width 0.1)
				(type default)
			)
			(layer "F.Fab")
		)
		(fp_line
			(start -0.12065 -0.2794)
			(end 0.12065 -0.2794)
			(stroke
				(width 0.1)
				(type default)
			)
			(layer "F.Fab")
		)
		(fp_line
			(start 0.12065 -0.2794)
			(end 0.12065 -0.3048)
			(stroke
				(width 0.1)
				(type default)
			)
			(layer "F.Fab")
		)
		(fp_line
			(start 0.12065 -0.3048)
			(end 0.67945 -0.3048)
			(stroke
				(width 0.1)
				(type default)
			)
			(layer "F.Fab")
		)
		(fp_line
			(start 0.67945 -0.3048)
			(end 0.67945 0.3048)
			(stroke
				(width 0.1)
				(type default)
			)
			(layer "F.Fab")
		)
		(fp_line
			(start -0.67945 -0.305054)
			(end -0.12065 -0.305054)
			(stroke
				(width 0.1)
				(type default)
			)
			(layer "F.Fab")
		)
		(fp_line
			(start -0.12065 -0.305054)
			(end -0.12065 -0.2794)
			(stroke
				(width 0.1)
				(type default)
			)
			(layer "F.Fab")
		)
		(pad "1" smd circle
			(at -0.40005 0 270)
			(size 0 0)
			(layers "F.Cu" "F.Mask" "F.Paste")
			(net "P3V3_AUX")
		)
		(pad "2" smd circle
			(at 0.40005 0 270)
			(size 0 0)
			(layers "F.Cu" "F.Mask" "F.Paste")
			(net "FM_PDB_BUF_EN_R1")
		)
	)
	(footprint ""
		(layer "F.Cu")
		(at 146.214846 -396.491206 -90)
		(property "Reference" "R871"
			(at 0 0 270)
			(layer "F.SilkS")
			(hide yes)
			(effects
				(font
					(size 1.27 1.27)
				)
			)
		)
		(property "Value" ""
			(at 0 0 270)
			(layer "F.Fab")
			(effects
				(font
					(size 1.27 1.27)
				)
			)
		)
		(duplicate_pad_numbers_are_jumpers no)
		(fp_line
			(start -0.32512 0.175006)
			(end -0.32512 -0.175006)
			(stroke
				(width 0.1)
				(type default)
			)
			(layer "F.Fab")
		)
		(fp_line
			(start 0.32512 0.175006)
			(end -0.32512 0.175006)
			(stroke
				(width 0.1)
				(type default)
			)
			(layer "F.Fab")
		)
		(fp_line
			(start -0.32512 -0.175006)
			(end 0.32512 -0.175006)
			(stroke
				(width 0.1)
				(type default)
			)
			(layer "F.Fab")
		)
		(fp_line
			(start 0.32512 -0.175006)
			(end 0.32512 0.175006)
			(stroke
				(width 0.1)
				(type default)
			)
			(layer "F.Fab")
		)
		(pad "1" smd rect
			(at -0.2667 0 270)
			(size 0.3048 0.381)
			(layers "F.Cu" "F.Mask" "F.Paste")
			(net "P1V8_CPU1_RT_1D")
		)
		(pad "2" smd rect
			(at 0.2667 0 90)
			(size 0.3048 0.381)
			(layers "F.Cu" "F.Mask" "F.Paste")
			(net "JTAG_TEST_MODE_RT_CPU1_P2")
		)
	)
	(footprint ""
		(layer "F.Cu")
		(at 389.462264 6.149848)
		(property "Reference" "J72"
			(at -4.619498 0.932434 90)
			(unlocked yes)
			(layer "F.SilkS")
			(effects
				(font
					(size 0.7874 0.5842)
					(thickness 0.1524)
				)
				(justify left)
			)
		)
		(property "Value" ""
			(at 0 0 0)
			(layer "F.Fab")
			(effects
				(font
					(size 1.27 1.27)
				)
			)
		)
		(duplicate_pad_numbers_are_jumpers no)
		(fp_line
			(start -1.2192 -2.06756)
			(end 1.2192 -2.06756)
			(stroke
				(width 0.1524)
				(type default)
			)
			(layer "F.SilkS")
		)
		(fp_line
			(start -1.2192 2.06756)
			(end -1.2192 -2.06756)
			(stroke
				(width 0.1524)
				(type default)
			)
			(layer "F.SilkS")
		)
		(fp_line
			(start 1.2192 -2.06756)
			(end 1.2192 2.06756)
			(stroke
				(width 0.1524)
				(type default)
			)
			(layer "F.SilkS")
		)
		(fp_line
			(start 1.2192 2.06756)
			(end -1.2192 2.06756)
			(stroke
				(width 0.1524)
				(type default)
			)
			(layer "F.SilkS")
		)
		(pad "" np_thru_hole circle
			(at -2.8829 -1.27 270)
			(size 1.0414 1.0414)
			(drill 1.0414)
			(layers "*.Cu" "*.Mask")
			(clearance 0.381)
			(thermal_gap 0.381)
		)
		(pad "" np_thru_hole circle
			(at -2.8829 1.27 270)
			(size 1.0414 1.0414)
			(drill 1.0414)
			(layers "*.Cu" "*.Mask")
			(clearance 0.381)
			(thermal_gap 0.381)
		)
		(pad "" np_thru_hole circle
			(at 3.4671 -1.27 270)
			(size 1.0414 1.0414)
			(drill 1.0414)
			(layers "*.Cu" "*.Mask")
			(clearance 0.381)
			(thermal_gap 0.381)
		)
		(pad "" np_thru_hole circle
			(at 3.4671 1.27 270)
			(size 1.0414 1.0414)
			(drill 1.0414)
			(layers "*.Cu" "*.Mask")
			(clearance 0.381)
			(thermal_gap 0.381)
		)
		(pad "1" smd rect
			(at 0.8255 -0.249936 270)
			(size 0.3048 0.508)
			(layers "F.Cu" "F.Mask" "F.Paste")
			(net "DELTA_L_85_5INCH_IN2_DN")
		)
		(pad "2" smd rect
			(at 0.8255 0.249936 270)
			(size 0.3048 0.508)
			(layers "F.Cu" "F.Mask" "F.Paste")
			(net "DELTA_L_85_5INCH_IN2_DP")
		)
		(pad "3" smd circle
			(at 0 0)
			(size 0 0)
			(layers "F.Cu" "F.Mask" "F.Paste")
			(net "DELTA_L_GND_1")
		)
		(zone
			(layer "F.Cu")
			(hatch none 0.5)
			(connect_pads
				(clearance 0)
			)
			(min_thickness 0.25)
			(keepout
				(tracks not_allowed)
				(vias allowed)
				(pads allowed)
				(copperpour not_allowed)
				(footprints allowed)
			)
			(placement
				(enabled no)
				(sheetname "")
			)
			(fill
				(thermal_gap 0.5)
				(thermal_bridge_width 0.5)
				(island_removal_mode 0)
			)
			(polygon
				(pts
					(xy 390.579864 5.601208) (xy 390.579864 5.696712) (xy 389.982964 5.696712) (xy 389.982964 6.103112)
					(xy 390.579864 6.103112) (xy 390.579864 6.196584) (xy 389.982964 6.196584) (xy 389.982964 6.602984)
					(xy 390.579864 6.602984) (xy 390.579864 6.698488) (xy 389.881364 6.698488) (xy 389.881364 5.601208)
				)
			)
		)
		(zone
			(layers "F.Cu" "B.Cu" "In1.Cu" "In2.Cu" "In3.Cu" "In4.Cu" "In5.Cu" "In6.Cu"
				"In7.Cu" "In8.Cu" "In9.Cu" "In10.Cu" "In11.Cu" "In12.Cu" "In13.Cu" "In14.Cu"
				"In15.Cu" "In16.Cu"
			)
			(hatch none 0.5)
			(connect_pads
				(clearance 0)
			)
			(min_thickness 0.25)
			(keepout
				(tracks not_allowed)
				(vias allowed)
				(pads allowed)
				(copperpour not_allowed)
				(footprints allowed)
			)
			(placement
				(enabled no)
				(sheetname "")
			)
			(fill
				(thermal_gap 0.5)
				(thermal_bridge_width 0.5)
				(island_removal_mode 0)
			)
			(polygon
				(pts
					(arc
						(start 387.506464 4.879848)
						(mid 385.652264 4.879848)
						(end 387.506464 4.879848)
					)
				)
			)
		)
		(zone
			(layers "F.Cu" "B.Cu" "In1.Cu" "In2.Cu" "In3.Cu" "In4.Cu" "In5.Cu" "In6.Cu"
				"In7.Cu" "In8.Cu" "In9.Cu" "In10.Cu" "In11.Cu" "In12.Cu" "In13.Cu" "In14.Cu"
				"In15.Cu" "In16.Cu"
			)
			(hatch none 0.5)
			(connect_pads
				(clearance 0)
			)
			(min_thickness 0.25)
			(keepout
				(tracks not_allowed)
				(vias allowed)
				(pads allowed)
				(copperpour not_allowed)
				(footprints allowed)
			)
			(placement
				(enabled no)
				(sheetname "")
			)
			(fill
				(thermal_gap 0.5)
				(thermal_bridge_width 0.5)
				(island_removal_mode 0)
			)
			(polygon
				(pts
					(arc
						(start 387.506464 7.419848)
						(mid 385.652264 7.419848)
						(end 387.506464 7.419848)
					)
				)
			)
		)
		(zone
			(layers "F.Cu" "B.Cu" "In1.Cu" "In2.Cu" "In3.Cu" "In4.Cu" "In5.Cu" "In6.Cu"
				"In7.Cu" "In8.Cu" "In9.Cu" "In10.Cu" "In11.Cu" "In12.Cu" "In13.Cu" "In14.Cu"
				"In15.Cu" "In16.Cu"
			)
			(hatch none 0.5)
			(connect_pads
				(clearance 0)
			)
			(min_thickness 0.25)
			(keepout
				(tracks not_allowed)
				(vias allowed)
				(pads allowed)
				(copperpour not_allowed)
				(footprints allowed)
			)
			(placement
				(enabled no)
				(sheetname "")
			)
			(fill
				(thermal_gap 0.5)
				(thermal_bridge_width 0.5)
				(island_removal_mode 0)
			)
			(polygon
				(pts
					(arc
						(start 393.856464 4.879848)
						(mid 392.002264 4.879848)
						(end 393.856464 4.879848)
					)
				)
			)
		)
		(zone
			(layers "F.Cu" "B.Cu" "In1.Cu" "In2.Cu" "In3.Cu" "In4.Cu" "In5.Cu" "In6.Cu"
				"In7.Cu" "In8.Cu" "In9.Cu" "In10.Cu" "In11.Cu" "In12.Cu" "In13.Cu" "In14.Cu"
				"In15.Cu" "In16.Cu"
			)
			(hatch none 0.5)
			(connect_pads
				(clearance 0)
			)
			(min_thickness 0.25)
			(keepout
				(tracks not_allowed)
				(vias allowed)
				(pads allowed)
				(copperpour not_allowed)
				(footprints allowed)
			)
			(placement
				(enabled no)
				(sheetname "")
			)
			(fill
				(thermal_gap 0.5)
				(thermal_bridge_width 0.5)
				(island_removal_mode 0)
			)
			(polygon
				(pts
					(arc
						(start 393.856464 7.419848)
						(mid 392.002264 7.419848)
						(end 393.856464 7.419848)
					)
				)
			)
		)
	)
	(footprint ""
		(layer "F.Cu")
		(at 308.757574 -22.185884 90)
		(property "Reference" "C62"
			(at 0 0 90)
			(layer "F.SilkS")
			(hide yes)
			(effects
				(font
					(size 1.27 1.27)
				)
			)
		)
		(property "Value" ""
			(at 0 0 90)
			(layer "F.Fab")
			(effects
				(font
					(size 1.27 1.27)
				)
			)
		)
		(duplicate_pad_numbers_are_jumpers no)
		(fp_line
			(start 0.7874 -0.4064)
			(end 0.7874 0.4064)
			(stroke
				(width 0.1524)
				(type default)
			)
			(layer "F.SilkS")
		)
		(fp_line
			(start -0.7874 -0.4064)
			(end 0.7874 -0.4064)
			(stroke
				(width 0.1524)
				(type default)
			)
			(layer "F.SilkS")
		)
		(fp_line
			(start 0.7874 0.4064)
			(end -0.7874 0.4064)
			(stroke
				(width 0.1524)
				(type default)
			)
			(layer "F.SilkS")
		)
		(fp_line
			(start -0.7874 0.4064)
			(end -0.7874 -0.4064)
			(stroke
				(width 0.1524)
				(type default)
			)
			(layer "F.SilkS")
		)
		(fp_line
			(start -0.12065 -0.305054)
			(end -0.12065 -0.2794)
			(stroke
				(width 0.1)
				(type default)
			)
			(layer "F.Fab")
		)
		(fp_line
			(start -0.67945 -0.305054)
			(end -0.12065 -0.305054)
			(stroke
				(width 0.1)
				(type default)
			)
			(layer "F.Fab")
		)
		(fp_line
			(start 0.67945 -0.3048)
			(end 0.67945 0.3048)
			(stroke
				(width 0.1)
				(type default)
			)
			(layer "F.Fab")
		)
		(fp_line
			(start 0.12065 -0.3048)
			(end 0.67945 -0.3048)
			(stroke
				(width 0.1)
				(type default)
			)
			(layer "F.Fab")
		)
		(fp_line
			(start 0.12065 -0.2794)
			(end 0.12065 -0.3048)
			(stroke
				(width 0.1)
				(type default)
			)
			(layer "F.Fab")
		)
		(fp_line
			(start -0.12065 -0.2794)
			(end 0.12065 -0.2794)
			(stroke
				(width 0.1)
				(type default)
			)
			(layer "F.Fab")
		)
		(fp_line
			(start 0.120396 0.2794)
			(end -0.12065 0.2794)
			(stroke
				(width 0.1)
				(type default)
			)
			(layer "F.Fab")
		)
		(fp_line
			(start -0.12065 0.2794)
			(end -0.12065 0.3048)
			(stroke
				(width 0.1)
				(type default)
			)
			(layer "F.Fab")
		)
		(fp_line
			(start 0.67945 0.3048)
			(end 0.120396 0.3048)
			(stroke
				(width 0.1)
				(type default)
			)
			(layer "F.Fab")
		)
		(fp_line
			(start 0.120396 0.3048)
			(end 0.120396 0.2794)
			(stroke
				(width 0.1)
				(type default)
			)
			(layer "F.Fab")
		)
		(fp_line
			(start -0.12065 0.3048)
			(end -0.67945 0.3048)
			(stroke
				(width 0.1)
				(type default)
			)
			(layer "F.Fab")
		)
		(fp_line
			(start -0.67945 0.3048)
			(end -0.67945 -0.305054)
			(stroke
				(width 0.1)
				(type default)
			)
			(layer "F.Fab")
		)
		(pad "1" smd circle
			(at -0.40005 0 90)
			(size 0 0)
			(layers "F.Cu" "F.Mask" "F.Paste")
			(net "UART_CPU0_SCM_LVC3_UART1_TX")
		)
		(pad "2" smd circle
			(at 0.40005 0 90)
			(size 0 0)
			(layers "F.Cu" "F.Mask" "F.Paste")
			(net "GND")
		)
	)
	(footprint ""
		(layer "F.Cu")
		(at 137.225786 -408.517344 -90)
		(property "Reference" "C6707"
			(at 0 0 270)
			(layer "F.SilkS")
			(hide yes)
			(effects
				(font
					(size 1.27 1.27)
				)
			)
		)
		(property "Value" ""
			(at 0 0 270)
			(layer "F.Fab")
			(effects
				(font
					(size 1.27 1.27)
				)
			)
		)
		(duplicate_pad_numbers_are_jumpers no)
		(fp_line
			(start -0.299974 0.150114)
			(end -0.299974 -0.150114)
			(stroke
				(width 0.1)
				(type default)
			)
			(layer "F.Fab")
		)
		(fp_line
			(start 0.299974 0.150114)
			(end -0.299974 0.150114)
			(stroke
				(width 0.1)
				(type default)
			)
			(layer "F.Fab")
		)
		(fp_line
			(start -0.299974 -0.150114)
			(end 0.299974 -0.150114)
			(stroke
				(width 0.1)
				(type default)
			)
			(layer "F.Fab")
		)
		(fp_line
			(start 0.299974 -0.150114)
			(end 0.299974 0.150114)
			(stroke
				(width 0.1)
				(type default)
			)
			(layer "F.Fab")
		)
		(pad "1" smd rect
			(at -0.2667 0 270)
			(size 0.3048 0.381)
			(layers "F.Cu" "F.Mask" "F.Paste")
			(net "P5E_CPU1_P2_TX_BUF_C_DP<7>")
		)
		(pad "2" smd rect
			(at 0.2667 0 270)
			(size 0.3048 0.381)
			(layers "F.Cu" "F.Mask" "F.Paste")
			(net "P5E_CPU1_P2_TX_BUF_DP<7>")
		)
	)
	(footprint ""
		(layer "F.Cu")
		(at 453.719946 -102.598728)
		(property "Reference" "R1908"
			(at 0 0 0)
			(layer "F.SilkS")
			(hide yes)
			(effects
				(font
					(size 1.27 1.27)
				)
			)
		)
		(property "Value" ""
			(at 0 0 0)
			(layer "F.Fab")
			(effects
				(font
					(size 1.27 1.27)
				)
			)
		)
		(duplicate_pad_numbers_are_jumpers no)
		(fp_line
			(start -0.7874 -0.4064)
			(end 0.7874 -0.4064)
			(stroke
				(width 0.1524)
				(type default)
			)
			(layer "F.SilkS")
		)
		(fp_line
			(start -0.7874 0.4064)
			(end -0.7874 -0.4064)
			(stroke
				(width 0.1524)
				(type default)
			)
			(layer "F.SilkS")
		)
		(fp_line
			(start 0.7874 -0.4064)
			(end 0.7874 0.4064)
			(stroke
				(width 0.1524)
				(type default)
			)
			(layer "F.SilkS")
		)
		(fp_line
			(start 0.7874 0.4064)
			(end -0.7874 0.4064)
			(stroke
				(width 0.1524)
				(type default)
			)
			(layer "F.SilkS")
		)
		(fp_line
			(start -0.67945 -0.305054)
			(end -0.12065 -0.305054)
			(stroke
				(width 0.1)
				(type default)
			)
			(layer "F.Fab")
		)
		(fp_line
			(start -0.67945 0.3048)
			(end -0.67945 -0.305054)
			(stroke
				(width 0.1)
				(type default)
			)
			(layer "F.Fab")
		)
		(fp_line
			(start -0.12065 -0.305054)
			(end -0.12065 -0.2794)
			(stroke
				(width 0.1)
				(type default)
			)
			(layer "F.Fab")
		)
		(fp_line
			(start -0.12065 -0.2794)
			(end 0.12065 -0.2794)
			(stroke
				(width 0.1)
				(type default)
			)
			(layer "F.Fab")
		)
		(fp_line
			(start -0.12065 0.2794)
			(end -0.12065 0.3048)
			(stroke
				(width 0.1)
				(type default)
			)
			(layer "F.Fab")
		)
		(fp_line
			(start -0.12065 0.3048)
			(end -0.67945 0.3048)
			(stroke
				(width 0.1)
				(type default)
			)
			(layer "F.Fab")
		)
		(fp_line
			(start 0.120396 0.2794)
			(end -0.12065 0.2794)
			(stroke
				(width 0.1)
				(type default)
			)
			(layer "F.Fab")
		)
		(fp_line
			(start 0.120396 0.3048)
			(end 0.120396 0.2794)
			(stroke
				(width 0.1)
				(type default)
			)
			(layer "F.Fab")
		)
		(fp_line
			(start 0.12065 -0.3048)
			(end 0.67945 -0.3048)
			(stroke
				(width 0.1)
				(type default)
			)
			(layer "F.Fab")
		)
		(fp_line
			(start 0.12065 -0.2794)
			(end 0.12065 -0.3048)
			(stroke
				(width 0.1)
				(type default)
			)
			(layer "F.Fab")
		)
		(fp_line
			(start 0.67945 -0.3048)
			(end 0.67945 0.3048)
			(stroke
				(width 0.1)
				(type default)
			)
			(layer "F.Fab")
		)
		(fp_line
			(start 0.67945 0.3048)
			(end 0.120396 0.3048)
			(stroke
				(width 0.1)
				(type default)
			)
			(layer "F.Fab")
		)
		(pad "1" smd circle
			(at -0.40005 0)
			(size 0 0)
			(layers "F.Cu" "F.Mask" "F.Paste")
			(net "P3V3_AUX")
		)
		(pad "2" smd circle
			(at 0.40005 0)
			(size 0 0)
			(layers "F.Cu" "F.Mask" "F.Paste")
			(net "OCP_SFF_PRSNT3_R_N")
		)
	)
	(footprint ""
		(layer "F.Cu")
		(at 345.176094 -339.676232 -90)
		(property "Reference" "PC137"
			(at 0 0 270)
			(layer "F.SilkS")
			(hide yes)
			(effects
				(font
					(size 1.27 1.27)
				)
			)
		)
		(property "Value" ""
			(at 0 0 270)
			(layer "F.Fab")
			(effects
				(font
					(size 1.27 1.27)
				)
			)
		)
		(duplicate_pad_numbers_are_jumpers no)
		(fp_line
			(start -0.7874 0.4064)
			(end -0.7874 -0.4064)
			(stroke
				(width 0.1524)
				(type default)
			)
			(layer "F.SilkS")
		)
		(fp_line
			(start 0.7874 0.4064)
			(end -0.7874 0.4064)
			(stroke
				(width 0.1524)
				(type default)
			)
			(layer "F.SilkS")
		)
		(fp_line
			(start -0.7874 -0.4064)
			(end 0.7874 -0.4064)
			(stroke
				(width 0.1524)
				(type default)
			)
			(layer "F.SilkS")
		)
		(fp_line
			(start 0.7874 -0.4064)
			(end 0.7874 0.4064)
			(stroke
				(width 0.1524)
				(type default)
			)
			(layer "F.SilkS")
		)
		(fp_line
			(start -0.67945 0.3048)
			(end -0.67945 -0.305054)
			(stroke
				(width 0.1)
				(type default)
			)
			(layer "F.Fab")
		)
		(fp_line
			(start -0.12065 0.3048)
			(end -0.67945 0.3048)
			(stroke
				(width 0.1)
				(type default)
			)
			(layer "F.Fab")
		)
		(fp_line
			(start 0.120396 0.3048)
			(end 0.120396 0.2794)
			(stroke
				(width 0.1)
				(type default)
			)
			(layer "F.Fab")
		)
		(fp_line
			(start 0.67945 0.3048)
			(end 0.120396 0.3048)
			(stroke
				(width 0.1)
				(type default)
			)
			(layer "F.Fab")
		)
		(fp_line
			(start -0.12065 0.2794)
			(end -0.12065 0.3048)
			(stroke
				(width 0.1)
				(type default)
			)
			(layer "F.Fab")
		)
		(fp_line
			(start 0.120396 0.2794)
			(end -0.12065 0.2794)
			(stroke
				(width 0.1)
				(type default)
			)
			(layer "F.Fab")
		)
		(fp_line
			(start -0.12065 -0.2794)
			(end 0.12065 -0.2794)
			(stroke
				(width 0.1)
				(type default)
			)
			(layer "F.Fab")
		)
		(fp_line
			(start 0.12065 -0.2794)
			(end 0.12065 -0.3048)
			(stroke
				(width 0.1)
				(type default)
			)
			(layer "F.Fab")
		)
		(fp_line
			(start 0.12065 -0.3048)
			(end 0.67945 -0.3048)
			(stroke
				(width 0.1)
				(type default)
			)
			(layer "F.Fab")
		)
		(fp_line
			(start 0.67945 -0.3048)
			(end 0.67945 0.3048)
			(stroke
				(width 0.1)
				(type default)
			)
			(layer "F.Fab")
		)
		(fp_line
			(start -0.67945 -0.305054)
			(end -0.12065 -0.305054)
			(stroke
				(width 0.1)
				(type default)
			)
			(layer "F.Fab")
		)
		(fp_line
			(start -0.12065 -0.305054)
			(end -0.12065 -0.2794)
			(stroke
				(width 0.1)
				(type default)
			)
			(layer "F.Fab")
		)
		(pad "1" smd circle
			(at -0.40005 0 270)
			(size 0 0)
			(layers "F.Cu" "F.Mask" "F.Paste")
			(net "SW_PVDDCR_CPU1_P0_BOOT5_R")
		)
		(pad "2" smd circle
			(at 0.40005 0 270)
			(size 0 0)
			(layers "F.Cu" "F.Mask" "F.Paste")
			(net "SW_PVDDCR_CPU1_P0_BOOTR5")
		)
	)
	(footprint ""
		(layer "F.Cu")
		(at 251.009912 -54.440582 90)
		(property "Reference" "PC2205"
			(at 0 0 90)
			(layer "F.SilkS")
			(hide yes)
			(effects
				(font
					(size 1.27 1.27)
				)
			)
		)
		(property "Value" ""
			(at 0 0 90)
			(layer "F.Fab")
			(effects
				(font
					(size 1.27 1.27)
				)
			)
		)
		(duplicate_pad_numbers_are_jumpers no)
		(fp_line
			(start 1.2954 -0.5842)
			(end 1.2954 0.5842)
			(stroke
				(width 0.1524)
				(type default)
			)
			(layer "F.SilkS")
		)
		(fp_line
			(start -1.2954 -0.5842)
			(end 1.2954 -0.5842)
			(stroke
				(width 0.1524)
				(type default)
			)
			(layer "F.SilkS")
		)
		(fp_line
			(start 1.2954 0.5842)
			(end -1.2954 0.5842)
			(stroke
				(width 0.1524)
				(type default)
			)
			(layer "F.SilkS")
		)
		(fp_line
			(start -1.2954 0.5842)
			(end -1.2954 -0.5842)
			(stroke
				(width 0.1524)
				(type default)
			)
			(layer "F.SilkS")
		)
		(fp_line
			(start 0.8636 -0.4572)
			(end 0.8636 -0.4064)
			(stroke
				(width 0.1)
				(type default)
			)
			(layer "F.Fab")
		)
		(fp_line
			(start -0.8636 -0.4572)
			(end 0.8636 -0.4572)
			(stroke
				(width 0.1)
				(type default)
			)
			(layer "F.Fab")
		)
		(fp_line
			(start 1.1938 -0.4064)
			(end 1.1938 0.4064)
			(stroke
				(width 0.1)
				(type default)
			)
			(layer "F.Fab")
		)
		(fp_line
			(start 0.8636 -0.4064)
			(end 1.1938 -0.4064)
			(stroke
				(width 0.1)
				(type default)
			)
			(layer "F.Fab")
		)
		(fp_line
			(start -0.8636 -0.4064)
			(end -0.8636 -0.4572)
			(stroke
				(width 0.1)
				(type default)
			)
			(layer "F.Fab")
		)
		(fp_line
			(start -1.1938 -0.4064)
			(end -0.8636 -0.4064)
			(stroke
				(width 0.1)
				(type default)
			)
			(layer "F.Fab")
		)
		(fp_line
			(start 1.1938 0.4064)
			(end 0.8636 0.4064)
			(stroke
				(width 0.1)
				(type default)
			)
			(layer "F.Fab")
		)
		(fp_line
			(start 0.8636 0.4064)
			(end 0.8636 0.4572)
			(stroke
				(width 0.1)
				(type default)
			)
			(layer "F.Fab")
		)
		(fp_line
			(start -0.8636 0.4064)
			(end -1.1938 0.4064)
			(stroke
				(width 0.1)
				(type default)
			)
			(layer "F.Fab")
		)
		(fp_line
			(start -1.1938 0.4064)
			(end -1.1938 -0.4064)
			(stroke
				(width 0.1)
				(type default)
			)
			(layer "F.Fab")
		)
		(fp_line
			(start 0.8636 0.4572)
			(end -0.8636 0.4572)
			(stroke
				(width 0.1)
				(type default)
			)
			(layer "F.Fab")
		)
		(fp_line
			(start -0.8636 0.4572)
			(end -0.8636 0.4064)
			(stroke
				(width 0.1)
				(type default)
			)
			(layer "F.Fab")
		)
		(pad "1" smd rect
			(at -0.7366 0)
			(size 0.7112 0.8128)
			(layers "F.Cu" "F.Mask" "F.Paste")
			(net "P12V_E1S_AVIN_PD_0")
		)
		(pad "2" smd rect
			(at 0.7366 0)
			(size 0.7112 0.8128)
			(layers "F.Cu" "F.Mask" "F.Paste")
			(net "GND")
		)
	)
	(footprint ""
		(layer "F.Cu")
		(at 249.899932 -290.89985)
		(property "Reference" "H12"
			(at 3.83413 0.127254 0)
			(unlocked yes)
			(layer "F.SilkS")
			(effects
				(font
					(size 0.7874 0.5842)
					(thickness 0.1524)
				)
				(justify left)
			)
		)
		(property "Value" ""
			(at 0 0 0)
			(layer "F.Fab")
			(effects
				(font
					(size 1.27 1.27)
				)
			)
		)
		(duplicate_pad_numbers_are_jumpers no)
		(pad "1" thru_hole circle
			(at 0 0)
			(size 6.1976 6.1976)
			(drill 3.7338)
			(layers "*.Cu" "*.Mask")
			(remove_unused_layers no)
			(net "GND")
			(clearance -0.9779)
			(padstack
				(mode front_inner_back)
				(layer "Inner"
					(shape circle)
					(size 5.5372 5.5372)
					(clearance -0.6477)
				)
				(layer "B.Cu"
					(shape circle)
					(size 6.1976 6.1976)
					(clearance -0.9779)
				)
			)
		)
	)
	(footprint ""
		(layer "F.Cu")
		(at 41.492932 -343.716864 180)
		(property "Reference" "PC175"
			(at 0 0 180)
			(layer "F.SilkS")
			(hide yes)
			(effects
				(font
					(size 1.27 1.27)
				)
			)
		)
		(property "Value" ""
			(at 0 0 180)
			(layer "F.Fab")
			(effects
				(font
					(size 1.27 1.27)
				)
			)
		)
		(duplicate_pad_numbers_are_jumpers no)
		(fp_line
			(start 0.7874 0.4064)
			(end -0.7874 0.4064)
			(stroke
				(width 0.1524)
				(type default)
			)
			(layer "F.SilkS")
		)
		(fp_line
			(start 0.7874 -0.4064)
			(end 0.7874 0.4064)
			(stroke
				(width 0.1524)
				(type default)
			)
			(layer "F.SilkS")
		)
		(fp_line
			(start -0.7874 0.4064)
			(end -0.7874 -0.4064)
			(stroke
				(width 0.1524)
				(type default)
			)
			(layer "F.SilkS")
		)
		(fp_line
			(start -0.7874 -0.4064)
			(end 0.7874 -0.4064)
			(stroke
				(width 0.1524)
				(type default)
			)
			(layer "F.SilkS")
		)
		(fp_line
			(start 0.67945 0.3048)
			(end 0.120396 0.3048)
			(stroke
				(width 0.1)
				(type default)
			)
			(layer "F.Fab")
		)
		(fp_line
			(start 0.67945 -0.3048)
			(end 0.67945 0.3048)
			(stroke
				(width 0.1)
				(type default)
			)
			(layer "F.Fab")
		)
		(fp_line
			(start 0.12065 -0.2794)
			(end 0.12065 -0.3048)
			(stroke
				(width 0.1)
				(type default)
			)
			(layer "F.Fab")
		)
		(fp_line
			(start 0.12065 -0.3048)
			(end 0.67945 -0.3048)
			(stroke
				(width 0.1)
				(type default)
			)
			(layer "F.Fab")
		)
		(fp_line
			(start 0.120396 0.3048)
			(end 0.120396 0.2794)
			(stroke
				(width 0.1)
				(type default)
			)
			(layer "F.Fab")
		)
		(fp_line
			(start 0.120396 0.2794)
			(end -0.12065 0.2794)
			(stroke
				(width 0.1)
				(type default)
			)
			(layer "F.Fab")
		)
		(fp_line
			(start -0.12065 0.3048)
			(end -0.67945 0.3048)
			(stroke
				(width 0.1)
				(type default)
			)
			(layer "F.Fab")
		)
		(fp_line
			(start -0.12065 0.2794)
			(end -0.12065 0.3048)
			(stroke
				(width 0.1)
				(type default)
			)
			(layer "F.Fab")
		)
		(fp_line
			(start -0.12065 -0.2794)
			(end 0.12065 -0.2794)
			(stroke
				(width 0.1)
				(type default)
			)
			(layer "F.Fab")
		)
		(fp_line
			(start -0.12065 -0.305054)
			(end -0.12065 -0.2794)
			(stroke
				(width 0.1)
				(type default)
			)
			(layer "F.Fab")
		)
		(fp_line
			(start -0.67945 0.3048)
			(end -0.67945 -0.305054)
			(stroke
				(width 0.1)
				(type default)
			)
			(layer "F.Fab")
		)
		(fp_line
			(start -0.67945 -0.305054)
			(end -0.12065 -0.305054)
			(stroke
				(width 0.1)
				(type default)
			)
			(layer "F.Fab")
		)
		(pad "1" smd circle
			(at -0.40005 0 180)
			(size 0 0)
			(layers "F.Cu" "F.Mask" "F.Paste")
			(net "SW_PVDDIO_P1_SW2")
		)
		(pad "2" smd circle
			(at 0.40005 0 180)
			(size 0 0)
			(layers "F.Cu" "F.Mask" "F.Paste")
			(net "SW_PVDDIO_P1_SW2_RC")
		)
	)
	(footprint ""
		(layer "F.Cu")
		(at 297.554142 -398.2212 180)
		(property "Reference" "R963"
			(at 0 0 180)
			(layer "F.SilkS")
			(hide yes)
			(effects
				(font
					(size 1.27 1.27)
				)
			)
		)
		(property "Value" ""
			(at 0 0 180)
			(layer "F.Fab")
			(effects
				(font
					(size 1.27 1.27)
				)
			)
		)
		(duplicate_pad_numbers_are_jumpers no)
		(fp_line
			(start 0.32512 0.175006)
			(end -0.32512 0.175006)
			(stroke
				(width 0.1)
				(type default)
			)
			(layer "F.Fab")
		)
		(fp_line
			(start 0.32512 -0.175006)
			(end 0.32512 0.175006)
			(stroke
				(width 0.1)
				(type default)
			)
			(layer "F.Fab")
		)
		(fp_line
			(start -0.32512 0.175006)
			(end -0.32512 -0.175006)
			(stroke
				(width 0.1)
				(type default)
			)
			(layer "F.Fab")
		)
		(fp_line
			(start -0.32512 -0.175006)
			(end 0.32512 -0.175006)
			(stroke
				(width 0.1)
				(type default)
			)
			(layer "F.Fab")
		)
		(pad "1" smd rect
			(at -0.2667 0 180)
			(size 0.3048 0.381)
			(layers "F.Cu" "F.Mask" "F.Paste")
			(net "RST_RT_CPU0_P0_RESET_N")
		)
		(pad "2" smd rect
			(at 0.2667 0)
			(size 0.3048 0.381)
			(layers "F.Cu" "F.Mask" "F.Paste")
			(net "RST_RT_CPU0_P0_RESET_R_N")
		)
	)
	(footprint ""
		(layer "F.Cu")
		(at 46.972728 -351.372932 -90)
		(property "Reference" "PC445"
			(at 0 0 270)
			(layer "F.SilkS")
			(hide yes)
			(effects
				(font
					(size 1.27 1.27)
				)
			)
		)
		(property "Value" ""
			(at 0 0 270)
			(layer "F.Fab")
			(effects
				(font
					(size 1.27 1.27)
				)
			)
		)
		(duplicate_pad_numbers_are_jumpers no)
		(fp_line
			(start -0.7874 0.4064)
			(end -0.7874 -0.4064)
			(stroke
				(width 0.1524)
				(type default)
			)
			(layer "F.SilkS")
		)
		(fp_line
			(start 0.7874 0.4064)
			(end -0.7874 0.4064)
			(stroke
				(width 0.1524)
				(type default)
			)
			(layer "F.SilkS")
		)
		(fp_line
			(start -0.7874 -0.4064)
			(end 0.7874 -0.4064)
			(stroke
				(width 0.1524)
				(type default)
			)
			(layer "F.SilkS")
		)
		(fp_line
			(start 0.7874 -0.4064)
			(end 0.7874 0.4064)
			(stroke
				(width 0.1524)
				(type default)
			)
			(layer "F.SilkS")
		)
		(fp_line
			(start -0.67945 0.3048)
			(end -0.67945 -0.305054)
			(stroke
				(width 0.1)
				(type default)
			)
			(layer "F.Fab")
		)
		(fp_line
			(start -0.12065 0.3048)
			(end -0.67945 0.3048)
			(stroke
				(width 0.1)
				(type default)
			)
			(layer "F.Fab")
		)
		(fp_line
			(start 0.120396 0.3048)
			(end 0.120396 0.2794)
			(stroke
				(width 0.1)
				(type default)
			)
			(layer "F.Fab")
		)
		(fp_line
			(start 0.67945 0.3048)
			(end 0.120396 0.3048)
			(stroke
				(width 0.1)
				(type default)
			)
			(layer "F.Fab")
		)
		(fp_line
			(start -0.12065 0.2794)
			(end -0.12065 0.3048)
			(stroke
				(width 0.1)
				(type default)
			)
			(layer "F.Fab")
		)
		(fp_line
			(start 0.120396 0.2794)
			(end -0.12065 0.2794)
			(stroke
				(width 0.1)
				(type default)
			)
			(layer "F.Fab")
		)
		(fp_line
			(start -0.12065 -0.2794)
			(end 0.12065 -0.2794)
			(stroke
				(width 0.1)
				(type default)
			)
			(layer "F.Fab")
		)
		(fp_line
			(start 0.12065 -0.2794)
			(end 0.12065 -0.3048)
			(stroke
				(width 0.1)
				(type default)
			)
			(layer "F.Fab")
		)
		(fp_line
			(start 0.12065 -0.3048)
			(end 0.67945 -0.3048)
			(stroke
				(width 0.1)
				(type default)
			)
			(layer "F.Fab")
		)
		(fp_line
			(start 0.67945 -0.3048)
			(end 0.67945 0.3048)
			(stroke
				(width 0.1)
				(type default)
			)
			(layer "F.Fab")
		)
		(fp_line
			(start -0.67945 -0.305054)
			(end -0.12065 -0.305054)
			(stroke
				(width 0.1)
				(type default)
			)
			(layer "F.Fab")
		)
		(fp_line
			(start -0.12065 -0.305054)
			(end -0.12065 -0.2794)
			(stroke
				(width 0.1)
				(type default)
			)
			(layer "F.Fab")
		)
		(pad "1" smd circle
			(at -0.40005 0 270)
			(size 0 0)
			(layers "F.Cu" "F.Mask" "F.Paste")
			(net "SW_PVDDIO_P1_BOOT2_R")
		)
		(pad "2" smd circle
			(at 0.40005 0 270)
			(size 0 0)
			(layers "F.Cu" "F.Mask" "F.Paste")
			(net "SW_PVDDIO_P1_BOOTR2")
		)
	)
	(footprint ""
		(layer "F.Cu")
		(at 330.922884 -339.35797)
		(property "Reference" "PC85_1"
			(at 0 0 0)
			(layer "F.SilkS")
			(hide yes)
			(effects
				(font
					(size 1.27 1.27)
				)
			)
		)
		(property "Value" ""
			(at 0 0 0)
			(layer "F.Fab")
			(effects
				(font
					(size 1.27 1.27)
				)
			)
		)
		(duplicate_pad_numbers_are_jumpers no)
		(fp_line
			(start -0.7874 -0.4064)
			(end 0.7874 -0.4064)
			(stroke
				(width 0.1524)
				(type default)
			)
			(layer "F.SilkS")
		)
		(fp_line
			(start -0.7874 0.4064)
			(end -0.7874 -0.4064)
			(stroke
				(width 0.1524)
				(type default)
			)
			(layer "F.SilkS")
		)
		(fp_line
			(start 0.7874 -0.4064)
			(end 0.7874 0.4064)
			(stroke
				(width 0.1524)
				(type default)
			)
			(layer "F.SilkS")
		)
		(fp_line
			(start 0.7874 0.4064)
			(end -0.7874 0.4064)
			(stroke
				(width 0.1524)
				(type default)
			)
			(layer "F.SilkS")
		)
		(fp_line
			(start -0.67945 -0.305054)
			(end -0.12065 -0.305054)
			(stroke
				(width 0.1)
				(type default)
			)
			(layer "F.Fab")
		)
		(fp_line
			(start -0.67945 0.3048)
			(end -0.67945 -0.305054)
			(stroke
				(width 0.1)
				(type default)
			)
			(layer "F.Fab")
		)
		(fp_line
			(start -0.12065 -0.305054)
			(end -0.12065 -0.2794)
			(stroke
				(width 0.1)
				(type default)
			)
			(layer "F.Fab")
		)
		(fp_line
			(start -0.12065 -0.2794)
			(end 0.12065 -0.2794)
			(stroke
				(width 0.1)
				(type default)
			)
			(layer "F.Fab")
		)
		(fp_line
			(start -0.12065 0.2794)
			(end -0.12065 0.3048)
			(stroke
				(width 0.1)
				(type default)
			)
			(layer "F.Fab")
		)
		(fp_line
			(start -0.12065 0.3048)
			(end -0.67945 0.3048)
			(stroke
				(width 0.1)
				(type default)
			)
			(layer "F.Fab")
		)
		(fp_line
			(start 0.120396 0.2794)
			(end -0.12065 0.2794)
			(stroke
				(width 0.1)
				(type default)
			)
			(layer "F.Fab")
		)
		(fp_line
			(start 0.120396 0.3048)
			(end 0.120396 0.2794)
			(stroke
				(width 0.1)
				(type default)
			)
			(layer "F.Fab")
		)
		(fp_line
			(start 0.12065 -0.3048)
			(end 0.67945 -0.3048)
			(stroke
				(width 0.1)
				(type default)
			)
			(layer "F.Fab")
		)
		(fp_line
			(start 0.12065 -0.2794)
			(end 0.12065 -0.3048)
			(stroke
				(width 0.1)
				(type default)
			)
			(layer "F.Fab")
		)
		(fp_line
			(start 0.67945 -0.3048)
			(end 0.67945 0.3048)
			(stroke
				(width 0.1)
				(type default)
			)
			(layer "F.Fab")
		)
		(fp_line
			(start 0.67945 0.3048)
			(end 0.120396 0.3048)
			(stroke
				(width 0.1)
				(type default)
			)
			(layer "F.Fab")
		)
		(pad "1" smd circle
			(at -0.40005 0)
			(size 0 0)
			(layers "F.Cu" "F.Mask" "F.Paste")
			(net "SW_P12V_AUX_PVDDCR_CPU1_P0_FLT")
		)
		(pad "2" smd circle
			(at 0.40005 0)
			(size 0 0)
			(layers "F.Cu" "F.Mask" "F.Paste")
			(net "GND")
		)
	)
	(footprint ""
		(layer "F.Cu")
		(at 221.67088 -42.255948)
		(property "Reference" "C1998"
			(at 0 0 0)
			(layer "F.SilkS")
			(hide yes)
			(effects
				(font
					(size 1.27 1.27)
				)
			)
		)
		(property "Value" ""
			(at 0 0 0)
			(layer "F.Fab")
			(effects
				(font
					(size 1.27 1.27)
				)
			)
		)
		(duplicate_pad_numbers_are_jumpers no)
		(fp_line
			(start -0.7874 -0.4064)
			(end 0.7874 -0.4064)
			(stroke
				(width 0.1524)
				(type default)
			)
			(layer "F.SilkS")
		)
		(fp_line
			(start -0.7874 0.4064)
			(end -0.7874 -0.4064)
			(stroke
				(width 0.1524)
				(type default)
			)
			(layer "F.SilkS")
		)
		(fp_line
			(start 0.7874 -0.4064)
			(end 0.7874 0.4064)
			(stroke
				(width 0.1524)
				(type default)
			)
			(layer "F.SilkS")
		)
		(fp_line
			(start 0.7874 0.4064)
			(end -0.7874 0.4064)
			(stroke
				(width 0.1524)
				(type default)
			)
			(layer "F.SilkS")
		)
		(fp_line
			(start -0.67945 -0.305054)
			(end -0.12065 -0.305054)
			(stroke
				(width 0.1)
				(type default)
			)
			(layer "F.Fab")
		)
		(fp_line
			(start -0.67945 0.3048)
			(end -0.67945 -0.305054)
			(stroke
				(width 0.1)
				(type default)
			)
			(layer "F.Fab")
		)
		(fp_line
			(start -0.12065 -0.305054)
			(end -0.12065 -0.2794)
			(stroke
				(width 0.1)
				(type default)
			)
			(layer "F.Fab")
		)
		(fp_line
			(start -0.12065 -0.2794)
			(end 0.12065 -0.2794)
			(stroke
				(width 0.1)
				(type default)
			)
			(layer "F.Fab")
		)
		(fp_line
			(start -0.12065 0.2794)
			(end -0.12065 0.3048)
			(stroke
				(width 0.1)
				(type default)
			)
			(layer "F.Fab")
		)
		(fp_line
			(start -0.12065 0.3048)
			(end -0.67945 0.3048)
			(stroke
				(width 0.1)
				(type default)
			)
			(layer "F.Fab")
		)
		(fp_line
			(start 0.120396 0.2794)
			(end -0.12065 0.2794)
			(stroke
				(width 0.1)
				(type default)
			)
			(layer "F.Fab")
		)
		(fp_line
			(start 0.120396 0.3048)
			(end 0.120396 0.2794)
			(stroke
				(width 0.1)
				(type default)
			)
			(layer "F.Fab")
		)
		(fp_line
			(start 0.12065 -0.3048)
			(end 0.67945 -0.3048)
			(stroke
				(width 0.1)
				(type default)
			)
			(layer "F.Fab")
		)
		(fp_line
			(start 0.12065 -0.2794)
			(end 0.12065 -0.3048)
			(stroke
				(width 0.1)
				(type default)
			)
			(layer "F.Fab")
		)
		(fp_line
			(start 0.67945 -0.3048)
			(end 0.67945 0.3048)
			(stroke
				(width 0.1)
				(type default)
			)
			(layer "F.Fab")
		)
		(fp_line
			(start 0.67945 0.3048)
			(end 0.120396 0.3048)
			(stroke
				(width 0.1)
				(type default)
			)
			(layer "F.Fab")
		)
		(pad "1" smd circle
			(at -0.40005 0)
			(size 0 0)
			(layers "F.Cu" "F.Mask" "F.Paste")
			(net "P3V3_E1S_0")
		)
		(pad "2" smd circle
			(at 0.40005 0)
			(size 0 0)
			(layers "F.Cu" "F.Mask" "F.Paste")
			(net "GND")
		)
	)
	(footprint ""
		(layer "F.Cu")
		(at 20.480782 -411.707584 180)
		(property "Reference" "PR6804"
			(at 0 0 180)
			(layer "F.SilkS")
			(hide yes)
			(effects
				(font
					(size 1.27 1.27)
				)
			)
		)
		(property "Value" ""
			(at 0 0 180)
			(layer "F.Fab")
			(effects
				(font
					(size 1.27 1.27)
				)
			)
		)
		(duplicate_pad_numbers_are_jumpers no)
		(fp_line
			(start 0.7874 0.4064)
			(end -0.7874 0.4064)
			(stroke
				(width 0.1524)
				(type default)
			)
			(layer "F.SilkS")
		)
		(fp_line
			(start 0.7874 -0.4064)
			(end 0.7874 0.4064)
			(stroke
				(width 0.1524)
				(type default)
			)
			(layer "F.SilkS")
		)
		(fp_line
			(start -0.7874 0.4064)
			(end -0.7874 -0.4064)
			(stroke
				(width 0.1524)
				(type default)
			)
			(layer "F.SilkS")
		)
		(fp_line
			(start -0.7874 -0.4064)
			(end 0.7874 -0.4064)
			(stroke
				(width 0.1524)
				(type default)
			)
			(layer "F.SilkS")
		)
		(fp_line
			(start 0.67945 0.3048)
			(end 0.120396 0.3048)
			(stroke
				(width 0.1)
				(type default)
			)
			(layer "F.Fab")
		)
		(fp_line
			(start 0.67945 -0.3048)
			(end 0.67945 0.3048)
			(stroke
				(width 0.1)
				(type default)
			)
			(layer "F.Fab")
		)
		(fp_line
			(start 0.12065 -0.2794)
			(end 0.12065 -0.3048)
			(stroke
				(width 0.1)
				(type default)
			)
			(layer "F.Fab")
		)
		(fp_line
			(start 0.12065 -0.3048)
			(end 0.67945 -0.3048)
			(stroke
				(width 0.1)
				(type default)
			)
			(layer "F.Fab")
		)
		(fp_line
			(start 0.120396 0.3048)
			(end 0.120396 0.2794)
			(stroke
				(width 0.1)
				(type default)
			)
			(layer "F.Fab")
		)
		(fp_line
			(start 0.120396 0.2794)
			(end -0.12065 0.2794)
			(stroke
				(width 0.1)
				(type default)
			)
			(layer "F.Fab")
		)
		(fp_line
			(start -0.12065 0.3048)
			(end -0.67945 0.3048)
			(stroke
				(width 0.1)
				(type default)
			)
			(layer "F.Fab")
		)
		(fp_line
			(start -0.12065 0.2794)
			(end -0.12065 0.3048)
			(stroke
				(width 0.1)
				(type default)
			)
			(layer "F.Fab")
		)
		(fp_line
			(start -0.12065 -0.2794)
			(end 0.12065 -0.2794)
			(stroke
				(width 0.1)
				(type default)
			)
			(layer "F.Fab")
		)
		(fp_line
			(start -0.12065 -0.305054)
			(end -0.12065 -0.2794)
			(stroke
				(width 0.1)
				(type default)
			)
			(layer "F.Fab")
		)
		(fp_line
			(start -0.67945 0.3048)
			(end -0.67945 -0.305054)
			(stroke
				(width 0.1)
				(type default)
			)
			(layer "F.Fab")
		)
		(fp_line
			(start -0.67945 -0.305054)
			(end -0.12065 -0.305054)
			(stroke
				(width 0.1)
				(type default)
			)
			(layer "F.Fab")
		)
		(pad "1" smd circle
			(at -0.40005 0 180)
			(size 0 0)
			(layers "F.Cu" "F.Mask" "F.Paste")
			(net "P3V3_AUX")
		)
		(pad "2" smd circle
			(at 0.40005 0 180)
			(size 0 0)
			(layers "F.Cu" "F.Mask" "F.Paste")
			(net "P0V9_RETIMER_CPU1_SVID_SDA")
		)
	)
	(footprint ""
		(layer "F.Cu")
		(at 432.085496 -109.13745 90)
		(property "Reference" "PR3780"
			(at 0 0 90)
			(layer "F.SilkS")
			(hide yes)
			(effects
				(font
					(size 1.27 1.27)
				)
			)
		)
		(property "Value" ""
			(at 0 0 90)
			(layer "F.Fab")
			(effects
				(font
					(size 1.27 1.27)
				)
			)
		)
		(duplicate_pad_numbers_are_jumpers no)
		(fp_line
			(start 0.7874 -0.4064)
			(end 0.7874 0.4064)
			(stroke
				(width 0.1524)
				(type default)
			)
			(layer "F.SilkS")
		)
		(fp_line
			(start -0.7874 -0.4064)
			(end 0.7874 -0.4064)
			(stroke
				(width 0.1524)
				(type default)
			)
			(layer "F.SilkS")
		)
		(fp_line
			(start 0.7874 0.4064)
			(end -0.7874 0.4064)
			(stroke
				(width 0.1524)
				(type default)
			)
			(layer "F.SilkS")
		)
		(fp_line
			(start -0.7874 0.4064)
			(end -0.7874 -0.4064)
			(stroke
				(width 0.1524)
				(type default)
			)
			(layer "F.SilkS")
		)
		(fp_line
			(start -0.12065 -0.305054)
			(end -0.12065 -0.2794)
			(stroke
				(width 0.1)
				(type default)
			)
			(layer "F.Fab")
		)
		(fp_line
			(start -0.67945 -0.305054)
			(end -0.12065 -0.305054)
			(stroke
				(width 0.1)
				(type default)
			)
			(layer "F.Fab")
		)
		(fp_line
			(start 0.67945 -0.3048)
			(end 0.67945 0.3048)
			(stroke
				(width 0.1)
				(type default)
			)
			(layer "F.Fab")
		)
		(fp_line
			(start 0.12065 -0.3048)
			(end 0.67945 -0.3048)
			(stroke
				(width 0.1)
				(type default)
			)
			(layer "F.Fab")
		)
		(fp_line
			(start 0.12065 -0.2794)
			(end 0.12065 -0.3048)
			(stroke
				(width 0.1)
				(type default)
			)
			(layer "F.Fab")
		)
		(fp_line
			(start -0.12065 -0.2794)
			(end 0.12065 -0.2794)
			(stroke
				(width 0.1)
				(type default)
			)
			(layer "F.Fab")
		)
		(fp_line
			(start 0.120396 0.2794)
			(end -0.12065 0.2794)
			(stroke
				(width 0.1)
				(type default)
			)
			(layer "F.Fab")
		)
		(fp_line
			(start -0.12065 0.2794)
			(end -0.12065 0.3048)
			(stroke
				(width 0.1)
				(type default)
			)
			(layer "F.Fab")
		)
		(fp_line
			(start 0.67945 0.3048)
			(end 0.120396 0.3048)
			(stroke
				(width 0.1)
				(type default)
			)
			(layer "F.Fab")
		)
		(fp_line
			(start 0.120396 0.3048)
			(end 0.120396 0.2794)
			(stroke
				(width 0.1)
				(type default)
			)
			(layer "F.Fab")
		)
		(fp_line
			(start -0.12065 0.3048)
			(end -0.67945 0.3048)
			(stroke
				(width 0.1)
				(type default)
			)
			(layer "F.Fab")
		)
		(fp_line
			(start -0.67945 0.3048)
			(end -0.67945 -0.305054)
			(stroke
				(width 0.1)
				(type default)
			)
			(layer "F.Fab")
		)
		(pad "1" smd circle
			(at -0.40005 0 90)
			(size 0 0)
			(layers "F.Cu" "F.Mask" "F.Paste")
			(net "P3V3_OCP_CB_1")
		)
		(pad "2" smd circle
			(at 0.40005 0 90)
			(size 0 0)
			(layers "F.Cu" "F.Mask" "F.Paste")
			(net "GND")
		)
	)
	(footprint ""
		(layer "F.Cu")
		(at 20.369784 -393.539726)
		(property "Reference" "PC6613_1"
			(at 0 0 0)
			(layer "F.SilkS")
			(hide yes)
			(effects
				(font
					(size 1.27 1.27)
				)
			)
		)
		(property "Value" ""
			(at 0 0 0)
			(layer "F.Fab")
			(effects
				(font
					(size 1.27 1.27)
				)
			)
		)
		(duplicate_pad_numbers_are_jumpers no)
		(fp_line
			(start -0.7874 -0.4064)
			(end 0.7874 -0.4064)
			(stroke
				(width 0.1524)
				(type default)
			)
			(layer "F.SilkS")
		)
		(fp_line
			(start -0.7874 0.4064)
			(end -0.7874 -0.4064)
			(stroke
				(width 0.1524)
				(type default)
			)
			(layer "F.SilkS")
		)
		(fp_line
			(start 0.7874 -0.4064)
			(end 0.7874 0.4064)
			(stroke
				(width 0.1524)
				(type default)
			)
			(layer "F.SilkS")
		)
		(fp_line
			(start 0.7874 0.4064)
			(end -0.7874 0.4064)
			(stroke
				(width 0.1524)
				(type default)
			)
			(layer "F.SilkS")
		)
		(fp_line
			(start -0.67945 -0.305054)
			(end -0.12065 -0.305054)
			(stroke
				(width 0.1)
				(type default)
			)
			(layer "F.Fab")
		)
		(fp_line
			(start -0.67945 0.3048)
			(end -0.67945 -0.305054)
			(stroke
				(width 0.1)
				(type default)
			)
			(layer "F.Fab")
		)
		(fp_line
			(start -0.12065 -0.305054)
			(end -0.12065 -0.2794)
			(stroke
				(width 0.1)
				(type default)
			)
			(layer "F.Fab")
		)
		(fp_line
			(start -0.12065 -0.2794)
			(end 0.12065 -0.2794)
			(stroke
				(width 0.1)
				(type default)
			)
			(layer "F.Fab")
		)
		(fp_line
			(start -0.12065 0.2794)
			(end -0.12065 0.3048)
			(stroke
				(width 0.1)
				(type default)
			)
			(layer "F.Fab")
		)
		(fp_line
			(start -0.12065 0.3048)
			(end -0.67945 0.3048)
			(stroke
				(width 0.1)
				(type default)
			)
			(layer "F.Fab")
		)
		(fp_line
			(start 0.120396 0.2794)
			(end -0.12065 0.2794)
			(stroke
				(width 0.1)
				(type default)
			)
			(layer "F.Fab")
		)
		(fp_line
			(start 0.120396 0.3048)
			(end 0.120396 0.2794)
			(stroke
				(width 0.1)
				(type default)
			)
			(layer "F.Fab")
		)
		(fp_line
			(start 0.12065 -0.3048)
			(end 0.67945 -0.3048)
			(stroke
				(width 0.1)
				(type default)
			)
			(layer "F.Fab")
		)
		(fp_line
			(start 0.12065 -0.2794)
			(end 0.12065 -0.3048)
			(stroke
				(width 0.1)
				(type default)
			)
			(layer "F.Fab")
		)
		(fp_line
			(start 0.67945 -0.3048)
			(end 0.67945 0.3048)
			(stroke
				(width 0.1)
				(type default)
			)
			(layer "F.Fab")
		)
		(fp_line
			(start 0.67945 0.3048)
			(end 0.120396 0.3048)
			(stroke
				(width 0.1)
				(type default)
			)
			(layer "F.Fab")
		)
		(pad "1" smd circle
			(at -0.40005 0)
			(size 0 0)
			(layers "F.Cu" "F.Mask" "F.Paste")
			(net "SW_P12V_AUX_P0V9_RETIMER_CPU1_FLT")
		)
		(pad "2" smd circle
			(at 0.40005 0)
			(size 0 0)
			(layers "F.Cu" "F.Mask" "F.Paste")
			(net "GND")
		)
	)
	(footprint ""
		(layer "F.Cu")
		(at 200.914 -103.505)
		(property "Reference" "R8082"
			(at 0 0 0)
			(layer "F.SilkS")
			(hide yes)
			(effects
				(font
					(size 1.27 1.27)
				)
			)
		)
		(property "Value" ""
			(at 0 0 0)
			(layer "F.Fab")
			(effects
				(font
					(size 1.27 1.27)
				)
			)
		)
		(duplicate_pad_numbers_are_jumpers no)
		(fp_line
			(start -0.7874 -0.4064)
			(end 0.7874 -0.4064)
			(stroke
				(width 0.1524)
				(type default)
			)
			(layer "F.SilkS")
		)
		(fp_line
			(start -0.7874 0.4064)
			(end -0.7874 -0.4064)
			(stroke
				(width 0.1524)
				(type default)
			)
			(layer "F.SilkS")
		)
		(fp_line
			(start 0.7874 -0.4064)
			(end 0.7874 0.4064)
			(stroke
				(width 0.1524)
				(type default)
			)
			(layer "F.SilkS")
		)
		(fp_line
			(start 0.7874 0.4064)
			(end -0.7874 0.4064)
			(stroke
				(width 0.1524)
				(type default)
			)
			(layer "F.SilkS")
		)
		(fp_line
			(start -0.67945 -0.305054)
			(end -0.12065 -0.305054)
			(stroke
				(width 0.1)
				(type default)
			)
			(layer "F.Fab")
		)
		(fp_line
			(start -0.67945 0.3048)
			(end -0.67945 -0.305054)
			(stroke
				(width 0.1)
				(type default)
			)
			(layer "F.Fab")
		)
		(fp_line
			(start -0.12065 -0.305054)
			(end -0.12065 -0.2794)
			(stroke
				(width 0.1)
				(type default)
			)
			(layer "F.Fab")
		)
		(fp_line
			(start -0.12065 -0.2794)
			(end 0.12065 -0.2794)
			(stroke
				(width 0.1)
				(type default)
			)
			(layer "F.Fab")
		)
		(fp_line
			(start -0.12065 0.2794)
			(end -0.12065 0.3048)
			(stroke
				(width 0.1)
				(type default)
			)
			(layer "F.Fab")
		)
		(fp_line
			(start -0.12065 0.3048)
			(end -0.67945 0.3048)
			(stroke
				(width 0.1)
				(type default)
			)
			(layer "F.Fab")
		)
		(fp_line
			(start 0.120396 0.2794)
			(end -0.12065 0.2794)
			(stroke
				(width 0.1)
				(type default)
			)
			(layer "F.Fab")
		)
		(fp_line
			(start 0.120396 0.3048)
			(end 0.120396 0.2794)
			(stroke
				(width 0.1)
				(type default)
			)
			(layer "F.Fab")
		)
		(fp_line
			(start 0.12065 -0.3048)
			(end 0.67945 -0.3048)
			(stroke
				(width 0.1)
				(type default)
			)
			(layer "F.Fab")
		)
		(fp_line
			(start 0.12065 -0.2794)
			(end 0.12065 -0.3048)
			(stroke
				(width 0.1)
				(type default)
			)
			(layer "F.Fab")
		)
		(fp_line
			(start 0.67945 -0.3048)
			(end 0.67945 0.3048)
			(stroke
				(width 0.1)
				(type default)
			)
			(layer "F.Fab")
		)
		(fp_line
			(start 0.67945 0.3048)
			(end 0.120396 0.3048)
			(stroke
				(width 0.1)
				(type default)
			)
			(layer "F.Fab")
		)
		(pad "1" smd circle
			(at -0.40005 0)
			(size 0 0)
			(layers "F.Cu" "F.Mask" "F.Paste")
			(net "P3V3_AUX")
		)
		(pad "2" smd circle
			(at 0.40005 0)
			(size 0 0)
			(layers "F.Cu" "F.Mask" "F.Paste")
			(net "PWRGD_CHAF_CPU0_R1")
		)
	)
	(footprint ""
		(layer "F.Cu")
		(at 196.536564 -69.423788 -90)
		(property "Reference" "PU293"
			(at -3.945128 3.01625 0)
			(unlocked yes)
			(layer "F.SilkS")
			(effects
				(font
					(size 0.7874 0.5842)
					(thickness 0.1524)
				)
			)
		)
		(property "Value" ""
			(at 0 0 270)
			(layer "F.Fab")
			(effects
				(font
					(size 1.27 1.27)
				)
			)
		)
		(duplicate_pad_numbers_are_jumpers no)
		(fp_line
			(start -1.239774 1.495298)
			(end -1.239774 -1.495298)
			(stroke
				(width 0.1524)
				(type default)
			)
			(layer "F.SilkS")
		)
		(fp_line
			(start 1.239774 1.495298)
			(end -1.239774 1.495298)
			(stroke
				(width 0.1524)
				(type default)
			)
			(layer "F.SilkS")
		)
		(fp_line
			(start -1.239774 -1.495298)
			(end 1.239774 -1.495298)
			(stroke
				(width 0.1524)
				(type default)
			)
			(layer "F.SilkS")
		)
		(fp_line
			(start 1.239774 -1.495298)
			(end 1.239774 1.495298)
			(stroke
				(width 0.1524)
				(type default)
			)
			(layer "F.SilkS")
		)
		(fp_poly
			(pts
				(xy -2.047748 -0.638302) (xy -3.163824 -0.849122) (xy -2.54889 -1.657858)
			)
			(stroke
				(width 0)
				(type default)
			)
			(fill yes)
			(layer "F.SilkS")
		)
		(fp_line
			(start -0.8001 1.050036)
			(end -0.8001 -1.050036)
			(stroke
				(width 0.1)
				(type default)
			)
			(layer "F.Fab")
		)
		(fp_line
			(start 0.8001 1.050036)
			(end -0.8001 1.050036)
			(stroke
				(width 0.1)
				(type default)
			)
			(layer "F.Fab")
		)
		(fp_line
			(start -0.8001 -1.050036)
			(end 0.8001 -1.050036)
			(stroke
				(width 0.1)
				(type default)
			)
			(layer "F.Fab")
		)
		(fp_line
			(start 0.8001 -1.050036)
			(end 0.8001 1.050036)
			(stroke
				(width 0.1)
				(type default)
			)
			(layer "F.Fab")
		)
		(fp_poly
			(pts
				(xy -2.458974 -0.508) (xy -2.458974 0.508) (xy -1.442974 0)
			)
			(stroke
				(width 0)
				(type default)
			)
			(fill yes)
			(layer "F.Fab")
		)
		(pad "1_2" smd circle
			(at -0.374904 0)
			(size 0 0)
			(layers "F.Cu" "F.Mask" "F.Paste")
			(net "P3V3_AUX")
		)
		(pad "3" smd rect
			(at -0.499872 0.999998 270)
			(size 0.254 0.7112)
			(layers "F.Cu" "F.Mask" "F.Paste")
			(net "GND")
		)
		(pad "4" smd rect
			(at 0 0.999998 270)
			(size 0.254 0.7112)
			(layers "F.Cu" "F.Mask" "F.Paste")
			(net "P3V3_E1S_ILIMIT_0")
		)
		(pad "5" smd rect
			(at 0.499872 0.999998 270)
			(size 0.254 0.7112)
			(layers "F.Cu" "F.Mask" "F.Paste")
			(net "P3V3_E1S_MODE_0")
		)
		(pad "6_7" smd circle
			(at 0.374904 0 180)
			(size 0 0)
			(layers "F.Cu" "F.Mask" "F.Paste")
			(net "P3V3_E1S_0_R")
		)
		(pad "8" smd rect
			(at 0.499872 -0.999998 270)
			(size 0.254 0.7112)
			(layers "F.Cu" "F.Mask" "F.Paste")
			(net "P3V3_E1S_GATE_0_PU293")
		)
		(pad "9" smd rect
			(at 0 -0.999998 270)
			(size 0.254 0.7112)
			(layers "F.Cu" "F.Mask" "F.Paste")
			(net "P3V3_E1S_EN_0_R2")
		)
		(pad "10" smd rect
			(at -0.499872 -0.999998 270)
			(size 0.254 0.7112)
			(layers "F.Cu" "F.Mask" "F.Paste")
			(net "P3V3_E1S_DVDT_0")
		)
	)
	(footprint ""
		(layer "F.Cu")
		(at 205.262226 -125.817376)
		(property "Reference" "R6061"
			(at 0 0 0)
			(layer "F.SilkS")
			(hide yes)
			(effects
				(font
					(size 1.27 1.27)
				)
			)
		)
		(property "Value" ""
			(at 0 0 0)
			(layer "F.Fab")
			(effects
				(font
					(size 1.27 1.27)
				)
			)
		)
		(duplicate_pad_numbers_are_jumpers no)
		(fp_line
			(start -0.7874 -0.4064)
			(end 0.7874 -0.4064)
			(stroke
				(width 0.1524)
				(type default)
			)
			(layer "F.SilkS")
		)
		(fp_line
			(start -0.7874 0.4064)
			(end -0.7874 -0.4064)
			(stroke
				(width 0.1524)
				(type default)
			)
			(layer "F.SilkS")
		)
		(fp_line
			(start 0.7874 -0.4064)
			(end 0.7874 0.4064)
			(stroke
				(width 0.1524)
				(type default)
			)
			(layer "F.SilkS")
		)
		(fp_line
			(start 0.7874 0.4064)
			(end -0.7874 0.4064)
			(stroke
				(width 0.1524)
				(type default)
			)
			(layer "F.SilkS")
		)
		(fp_line
			(start -0.67945 -0.305054)
			(end -0.12065 -0.305054)
			(stroke
				(width 0.1)
				(type default)
			)
			(layer "F.Fab")
		)
		(fp_line
			(start -0.67945 0.3048)
			(end -0.67945 -0.305054)
			(stroke
				(width 0.1)
				(type default)
			)
			(layer "F.Fab")
		)
		(fp_line
			(start -0.12065 -0.305054)
			(end -0.12065 -0.2794)
			(stroke
				(width 0.1)
				(type default)
			)
			(layer "F.Fab")
		)
		(fp_line
			(start -0.12065 -0.2794)
			(end 0.12065 -0.2794)
			(stroke
				(width 0.1)
				(type default)
			)
			(layer "F.Fab")
		)
		(fp_line
			(start -0.12065 0.2794)
			(end -0.12065 0.3048)
			(stroke
				(width 0.1)
				(type default)
			)
			(layer "F.Fab")
		)
		(fp_line
			(start -0.12065 0.3048)
			(end -0.67945 0.3048)
			(stroke
				(width 0.1)
				(type default)
			)
			(layer "F.Fab")
		)
		(fp_line
			(start 0.120396 0.2794)
			(end -0.12065 0.2794)
			(stroke
				(width 0.1)
				(type default)
			)
			(layer "F.Fab")
		)
		(fp_line
			(start 0.120396 0.3048)
			(end 0.120396 0.2794)
			(stroke
				(width 0.1)
				(type default)
			)
			(layer "F.Fab")
		)
		(fp_line
			(start 0.12065 -0.3048)
			(end 0.67945 -0.3048)
			(stroke
				(width 0.1)
				(type default)
			)
			(layer "F.Fab")
		)
		(fp_line
			(start 0.12065 -0.2794)
			(end 0.12065 -0.3048)
			(stroke
				(width 0.1)
				(type default)
			)
			(layer "F.Fab")
		)
		(fp_line
			(start 0.67945 -0.3048)
			(end 0.67945 0.3048)
			(stroke
				(width 0.1)
				(type default)
			)
			(layer "F.Fab")
		)
		(fp_line
			(start 0.67945 0.3048)
			(end 0.120396 0.3048)
			(stroke
				(width 0.1)
				(type default)
			)
			(layer "F.Fab")
		)
		(pad "1" smd circle
			(at -0.40005 0)
			(size 0 0)
			(layers "F.Cu" "F.Mask" "F.Paste")
			(net "P12V_OCP_V3_2_EN_R")
		)
		(pad "2" smd circle
			(at 0.40005 0)
			(size 0 0)
			(layers "F.Cu" "F.Mask" "F.Paste")
			(net "P3V3_AUX")
		)
	)
	(footprint ""
		(layer "F.Cu")
		(at 197.269608 -107.529376 180)
		(property "Reference" "R225"
			(at 0 0 180)
			(layer "F.SilkS")
			(hide yes)
			(effects
				(font
					(size 1.27 1.27)
				)
			)
		)
		(property "Value" ""
			(at 0 0 180)
			(layer "F.Fab")
			(effects
				(font
					(size 1.27 1.27)
				)
			)
		)
		(duplicate_pad_numbers_are_jumpers no)
		(fp_line
			(start 0.7874 0.4064)
			(end -0.7874 0.4064)
			(stroke
				(width 0.1524)
				(type default)
			)
			(layer "F.SilkS")
		)
		(fp_line
			(start 0.7874 -0.4064)
			(end 0.7874 0.4064)
			(stroke
				(width 0.1524)
				(type default)
			)
			(layer "F.SilkS")
		)
		(fp_line
			(start -0.7874 0.4064)
			(end -0.7874 -0.4064)
			(stroke
				(width 0.1524)
				(type default)
			)
			(layer "F.SilkS")
		)
		(fp_line
			(start -0.7874 -0.4064)
			(end 0.7874 -0.4064)
			(stroke
				(width 0.1524)
				(type default)
			)
			(layer "F.SilkS")
		)
		(fp_line
			(start 0.67945 0.3048)
			(end 0.120396 0.3048)
			(stroke
				(width 0.1)
				(type default)
			)
			(layer "F.Fab")
		)
		(fp_line
			(start 0.67945 -0.3048)
			(end 0.67945 0.3048)
			(stroke
				(width 0.1)
				(type default)
			)
			(layer "F.Fab")
		)
		(fp_line
			(start 0.12065 -0.2794)
			(end 0.12065 -0.3048)
			(stroke
				(width 0.1)
				(type default)
			)
			(layer "F.Fab")
		)
		(fp_line
			(start 0.12065 -0.3048)
			(end 0.67945 -0.3048)
			(stroke
				(width 0.1)
				(type default)
			)
			(layer "F.Fab")
		)
		(fp_line
			(start 0.120396 0.3048)
			(end 0.120396 0.2794)
			(stroke
				(width 0.1)
				(type default)
			)
			(layer "F.Fab")
		)
		(fp_line
			(start 0.120396 0.2794)
			(end -0.12065 0.2794)
			(stroke
				(width 0.1)
				(type default)
			)
			(layer "F.Fab")
		)
		(fp_line
			(start -0.12065 0.3048)
			(end -0.67945 0.3048)
			(stroke
				(width 0.1)
				(type default)
			)
			(layer "F.Fab")
		)
		(fp_line
			(start -0.12065 0.2794)
			(end -0.12065 0.3048)
			(stroke
				(width 0.1)
				(type default)
			)
			(layer "F.Fab")
		)
		(fp_line
			(start -0.12065 -0.2794)
			(end 0.12065 -0.2794)
			(stroke
				(width 0.1)
				(type default)
			)
			(layer "F.Fab")
		)
		(fp_line
			(start -0.12065 -0.305054)
			(end -0.12065 -0.2794)
			(stroke
				(width 0.1)
				(type default)
			)
			(layer "F.Fab")
		)
		(fp_line
			(start -0.67945 0.3048)
			(end -0.67945 -0.305054)
			(stroke
				(width 0.1)
				(type default)
			)
			(layer "F.Fab")
		)
		(fp_line
			(start -0.67945 -0.305054)
			(end -0.12065 -0.305054)
			(stroke
				(width 0.1)
				(type default)
			)
			(layer "F.Fab")
		)
		(pad "1" smd circle
			(at -0.40005 0 180)
			(size 0 0)
			(layers "F.Cu" "F.Mask" "F.Paste")
			(net "PWRGD_PVDD33_S5")
		)
		(pad "2" smd circle
			(at 0.40005 0 180)
			(size 0 0)
			(layers "F.Cu" "F.Mask" "F.Paste")
			(net "FM_PWRGD_PVDD33_S5")
		)
	)
	(footprint ""
		(layer "F.Cu")
		(at 39.95801 -438.531 180)
		(property "Reference" "R3466"
			(at 0 0 180)
			(layer "F.SilkS")
			(hide yes)
			(effects
				(font
					(size 1.27 1.27)
				)
			)
		)
		(property "Value" ""
			(at 0 0 180)
			(layer "F.Fab")
			(effects
				(font
					(size 1.27 1.27)
				)
			)
		)
		(duplicate_pad_numbers_are_jumpers no)
		(fp_line
			(start 0.7874 0.4064)
			(end -0.7874 0.4064)
			(stroke
				(width 0.1524)
				(type default)
			)
			(layer "F.SilkS")
		)
		(fp_line
			(start 0.7874 -0.4064)
			(end 0.7874 0.4064)
			(stroke
				(width 0.1524)
				(type default)
			)
			(layer "F.SilkS")
		)
		(fp_line
			(start -0.7874 0.4064)
			(end -0.7874 -0.4064)
			(stroke
				(width 0.1524)
				(type default)
			)
			(layer "F.SilkS")
		)
		(fp_line
			(start -0.7874 -0.4064)
			(end 0.7874 -0.4064)
			(stroke
				(width 0.1524)
				(type default)
			)
			(layer "F.SilkS")
		)
		(fp_line
			(start 0.67945 0.3048)
			(end 0.120396 0.3048)
			(stroke
				(width 0.1)
				(type default)
			)
			(layer "F.Fab")
		)
		(fp_line
			(start 0.67945 -0.3048)
			(end 0.67945 0.3048)
			(stroke
				(width 0.1)
				(type default)
			)
			(layer "F.Fab")
		)
		(fp_line
			(start 0.12065 -0.2794)
			(end 0.12065 -0.3048)
			(stroke
				(width 0.1)
				(type default)
			)
			(layer "F.Fab")
		)
		(fp_line
			(start 0.12065 -0.3048)
			(end 0.67945 -0.3048)
			(stroke
				(width 0.1)
				(type default)
			)
			(layer "F.Fab")
		)
		(fp_line
			(start 0.120396 0.3048)
			(end 0.120396 0.2794)
			(stroke
				(width 0.1)
				(type default)
			)
			(layer "F.Fab")
		)
		(fp_line
			(start 0.120396 0.2794)
			(end -0.12065 0.2794)
			(stroke
				(width 0.1)
				(type default)
			)
			(layer "F.Fab")
		)
		(fp_line
			(start -0.12065 0.3048)
			(end -0.67945 0.3048)
			(stroke
				(width 0.1)
				(type default)
			)
			(layer "F.Fab")
		)
		(fp_line
			(start -0.12065 0.2794)
			(end -0.12065 0.3048)
			(stroke
				(width 0.1)
				(type default)
			)
			(layer "F.Fab")
		)
		(fp_line
			(start -0.12065 -0.2794)
			(end 0.12065 -0.2794)
			(stroke
				(width 0.1)
				(type default)
			)
			(layer "F.Fab")
		)
		(fp_line
			(start -0.12065 -0.305054)
			(end -0.12065 -0.2794)
			(stroke
				(width 0.1)
				(type default)
			)
			(layer "F.Fab")
		)
		(fp_line
			(start -0.67945 0.3048)
			(end -0.67945 -0.305054)
			(stroke
				(width 0.1)
				(type default)
			)
			(layer "F.Fab")
		)
		(fp_line
			(start -0.67945 -0.305054)
			(end -0.12065 -0.305054)
			(stroke
				(width 0.1)
				(type default)
			)
			(layer "F.Fab")
		)
		(pad "1" smd circle
			(at -0.40005 0 180)
			(size 0 0)
			(layers "F.Cu" "F.Mask" "F.Paste")
			(net "RST_PERST_1_SWB_BUF_R_N")
		)
		(pad "2" smd circle
			(at 0.40005 0 180)
			(size 0 0)
			(layers "F.Cu" "F.Mask" "F.Paste")
			(net "GND")
		)
	)
	(footprint ""
		(layer "F.Cu")
		(at 295.576752 -422.173908 90)
		(property "Reference" "R669"
			(at 0 0 90)
			(layer "F.SilkS")
			(hide yes)
			(effects
				(font
					(size 1.27 1.27)
				)
			)
		)
		(property "Value" ""
			(at 0 0 90)
			(layer "F.Fab")
			(effects
				(font
					(size 1.27 1.27)
				)
			)
		)
		(duplicate_pad_numbers_are_jumpers no)
		(fp_line
			(start 0.32512 -0.175006)
			(end 0.32512 0.175006)
			(stroke
				(width 0.1)
				(type default)
			)
			(layer "F.Fab")
		)
		(fp_line
			(start -0.32512 -0.175006)
			(end 0.32512 -0.175006)
			(stroke
				(width 0.1)
				(type default)
			)
			(layer "F.Fab")
		)
		(fp_line
			(start 0.32512 0.175006)
			(end -0.32512 0.175006)
			(stroke
				(width 0.1)
				(type default)
			)
			(layer "F.Fab")
		)
		(fp_line
			(start -0.32512 0.175006)
			(end -0.32512 -0.175006)
			(stroke
				(width 0.1)
				(type default)
			)
			(layer "F.Fab")
		)
		(pad "1" smd rect
			(at -0.2667 0 90)
			(size 0.3048 0.381)
			(layers "F.Cu" "F.Mask" "F.Paste")
			(net "SMB_RT_CPU0_P0_ROM_R_SDA")
		)
		(pad "2" smd rect
			(at 0.2667 0 270)
			(size 0.3048 0.381)
			(layers "F.Cu" "F.Mask" "F.Paste")
			(net "SMB_RT_CPU0_P0_ROM_SDA")
		)
	)
	(footprint ""
		(layer "F.Cu")
		(at 136.840976 -379.471428)
		(property "Reference" "C49"
			(at 0 0 0)
			(layer "F.SilkS")
			(hide yes)
			(effects
				(font
					(size 1.27 1.27)
				)
			)
		)
		(property "Value" ""
			(at 0 0 0)
			(layer "F.Fab")
			(effects
				(font
					(size 1.27 1.27)
				)
			)
		)
		(duplicate_pad_numbers_are_jumpers no)
		(fp_line
			(start -0.299974 -0.150114)
			(end 0.299974 -0.150114)
			(stroke
				(width 0.1)
				(type default)
			)
			(layer "F.Fab")
		)
		(fp_line
			(start -0.299974 0.150114)
			(end -0.299974 -0.150114)
			(stroke
				(width 0.1)
				(type default)
			)
			(layer "F.Fab")
		)
		(fp_line
			(start 0.299974 -0.150114)
			(end 0.299974 0.150114)
			(stroke
				(width 0.1)
				(type default)
			)
			(layer "F.Fab")
		)
		(fp_line
			(start 0.299974 0.150114)
			(end -0.299974 0.150114)
			(stroke
				(width 0.1)
				(type default)
			)
			(layer "F.Fab")
		)
		(pad "1" smd rect
			(at -0.2667 0)
			(size 0.3048 0.381)
			(layers "F.Cu" "F.Mask" "F.Paste")
			(net "P5E_CPU1_P3_TX_C_DP<15>")
		)
		(pad "2" smd rect
			(at 0.2667 0)
			(size 0.3048 0.381)
			(layers "F.Cu" "F.Mask" "F.Paste")
			(net "P5E_CPU1_P3_TX_DP<15>")
		)
	)
	(footprint ""
		(layer "F.Cu")
		(at 372.937278 -142.488158)
		(property "Reference" "R8298"
			(at 0 0 0)
			(layer "F.SilkS")
			(hide yes)
			(effects
				(font
					(size 1.27 1.27)
				)
			)
		)
		(property "Value" ""
			(at 0 0 0)
			(layer "F.Fab")
			(effects
				(font
					(size 1.27 1.27)
				)
			)
		)
		(duplicate_pad_numbers_are_jumpers no)
		(fp_line
			(start -0.7874 -0.4064)
			(end 0.7874 -0.4064)
			(stroke
				(width 0.1524)
				(type default)
			)
			(layer "F.SilkS")
		)
		(fp_line
			(start -0.7874 0.4064)
			(end -0.7874 -0.4064)
			(stroke
				(width 0.1524)
				(type default)
			)
			(layer "F.SilkS")
		)
		(fp_line
			(start 0.7874 -0.4064)
			(end 0.7874 0.4064)
			(stroke
				(width 0.1524)
				(type default)
			)
			(layer "F.SilkS")
		)
		(fp_line
			(start 0.7874 0.4064)
			(end -0.7874 0.4064)
			(stroke
				(width 0.1524)
				(type default)
			)
			(layer "F.SilkS")
		)
		(fp_line
			(start -0.67945 -0.305054)
			(end -0.12065 -0.305054)
			(stroke
				(width 0.1)
				(type default)
			)
			(layer "F.Fab")
		)
		(fp_line
			(start -0.67945 0.3048)
			(end -0.67945 -0.305054)
			(stroke
				(width 0.1)
				(type default)
			)
			(layer "F.Fab")
		)
		(fp_line
			(start -0.12065 -0.305054)
			(end -0.12065 -0.2794)
			(stroke
				(width 0.1)
				(type default)
			)
			(layer "F.Fab")
		)
		(fp_line
			(start -0.12065 -0.2794)
			(end 0.12065 -0.2794)
			(stroke
				(width 0.1)
				(type default)
			)
			(layer "F.Fab")
		)
		(fp_line
			(start -0.12065 0.2794)
			(end -0.12065 0.3048)
			(stroke
				(width 0.1)
				(type default)
			)
			(layer "F.Fab")
		)
		(fp_line
			(start -0.12065 0.3048)
			(end -0.67945 0.3048)
			(stroke
				(width 0.1)
				(type default)
			)
			(layer "F.Fab")
		)
		(fp_line
			(start 0.120396 0.2794)
			(end -0.12065 0.2794)
			(stroke
				(width 0.1)
				(type default)
			)
			(layer "F.Fab")
		)
		(fp_line
			(start 0.120396 0.3048)
			(end 0.120396 0.2794)
			(stroke
				(width 0.1)
				(type default)
			)
			(layer "F.Fab")
		)
		(fp_line
			(start 0.12065 -0.3048)
			(end 0.67945 -0.3048)
			(stroke
				(width 0.1)
				(type default)
			)
			(layer "F.Fab")
		)
		(fp_line
			(start 0.12065 -0.2794)
			(end 0.12065 -0.3048)
			(stroke
				(width 0.1)
				(type default)
			)
			(layer "F.Fab")
		)
		(fp_line
			(start 0.67945 -0.3048)
			(end 0.67945 0.3048)
			(stroke
				(width 0.1)
				(type default)
			)
			(layer "F.Fab")
		)
		(fp_line
			(start 0.67945 0.3048)
			(end 0.120396 0.3048)
			(stroke
				(width 0.1)
				(type default)
			)
			(layer "F.Fab")
		)
		(pad "1" smd circle
			(at -0.40005 0)
			(size 0 0)
			(layers "F.Cu" "F.Mask" "F.Paste")
			(net "P3V3_AUX")
		)
		(pad "2" smd circle
			(at 0.40005 0)
			(size 0 0)
			(layers "F.Cu" "F.Mask" "F.Paste")
			(net "PWRGD_PVDDCR_SOC_P0_R")
		)
	)
	(footprint ""
		(layer "F.Cu")
		(at 42.967402 -381.48006 180)
		(property "Reference" "C836"
			(at 0 0 180)
			(layer "F.SilkS")
			(hide yes)
			(effects
				(font
					(size 1.27 1.27)
				)
			)
		)
		(property "Value" ""
			(at 0 0 180)
			(layer "F.Fab")
			(effects
				(font
					(size 1.27 1.27)
				)
			)
		)
		(duplicate_pad_numbers_are_jumpers no)
		(fp_line
			(start 0.299974 0.150114)
			(end -0.299974 0.150114)
			(stroke
				(width 0.1)
				(type default)
			)
			(layer "F.Fab")
		)
		(fp_line
			(start 0.299974 -0.150114)
			(end 0.299974 0.150114)
			(stroke
				(width 0.1)
				(type default)
			)
			(layer "F.Fab")
		)
		(fp_line
			(start -0.299974 0.150114)
			(end -0.299974 -0.150114)
			(stroke
				(width 0.1)
				(type default)
			)
			(layer "F.Fab")
		)
		(fp_line
			(start -0.299974 -0.150114)
			(end 0.299974 -0.150114)
			(stroke
				(width 0.1)
				(type default)
			)
			(layer "F.Fab")
		)
		(pad "1" smd rect
			(at -0.2667 0 180)
			(size 0.3048 0.381)
			(layers "F.Cu" "F.Mask" "F.Paste")
			(net "P5E_CPU1_P0_TX_C_DN<0>")
		)
		(pad "2" smd rect
			(at 0.2667 0 180)
			(size 0.3048 0.381)
			(layers "F.Cu" "F.Mask" "F.Paste")
			(net "P5E_CPU1_P0_TX_DN<0>")
		)
	)
	(footprint ""
		(layer "F.Cu")
		(at 323.062346 -416.899344 -90)
		(property "Reference" "C6513"
			(at 0 0 270)
			(layer "F.SilkS")
			(hide yes)
			(effects
				(font
					(size 1.27 1.27)
				)
			)
		)
		(property "Value" ""
			(at 0 0 270)
			(layer "F.Fab")
			(effects
				(font
					(size 1.27 1.27)
				)
			)
		)
		(duplicate_pad_numbers_are_jumpers no)
		(fp_line
			(start -0.299974 0.150114)
			(end -0.299974 -0.150114)
			(stroke
				(width 0.1)
				(type default)
			)
			(layer "F.Fab")
		)
		(fp_line
			(start 0.299974 0.150114)
			(end -0.299974 0.150114)
			(stroke
				(width 0.1)
				(type default)
			)
			(layer "F.Fab")
		)
		(fp_line
			(start -0.299974 -0.150114)
			(end 0.299974 -0.150114)
			(stroke
				(width 0.1)
				(type default)
			)
			(layer "F.Fab")
		)
		(fp_line
			(start 0.299974 -0.150114)
			(end 0.299974 0.150114)
			(stroke
				(width 0.1)
				(type default)
			)
			(layer "F.Fab")
		)
		(pad "1" smd rect
			(at -0.2667 0 270)
			(size 0.3048 0.381)
			(layers "F.Cu" "F.Mask" "F.Paste")
			(net "P5E_CPU0_P0_TX_BUF_C_DP<6>")
		)
		(pad "2" smd rect
			(at 0.2667 0 270)
			(size 0.3048 0.381)
			(layers "F.Cu" "F.Mask" "F.Paste")
			(net "P5E_CPU0_P0_TX_BUF_DP<6>")
		)
	)
	(footprint ""
		(layer "F.Cu")
		(at 109.549946 -52.86248 -90)
		(property "Reference" "R6307"
			(at 0 0 270)
			(layer "F.SilkS")
			(hide yes)
			(effects
				(font
					(size 1.27 1.27)
				)
			)
		)
		(property "Value" ""
			(at 0 0 270)
			(layer "F.Fab")
			(effects
				(font
					(size 1.27 1.27)
				)
			)
		)
		(duplicate_pad_numbers_are_jumpers no)
		(fp_line
			(start -0.7874 0.4064)
			(end -0.7874 -0.4064)
			(stroke
				(width 0.1524)
				(type default)
			)
			(layer "F.SilkS")
		)
		(fp_line
			(start 0.7874 0.4064)
			(end -0.7874 0.4064)
			(stroke
				(width 0.1524)
				(type default)
			)
			(layer "F.SilkS")
		)
		(fp_line
			(start -0.7874 -0.4064)
			(end 0.7874 -0.4064)
			(stroke
				(width 0.1524)
				(type default)
			)
			(layer "F.SilkS")
		)
		(fp_line
			(start 0.7874 -0.4064)
			(end 0.7874 0.4064)
			(stroke
				(width 0.1524)
				(type default)
			)
			(layer "F.SilkS")
		)
		(fp_line
			(start -0.67945 0.3048)
			(end -0.67945 -0.305054)
			(stroke
				(width 0.1)
				(type default)
			)
			(layer "F.Fab")
		)
		(fp_line
			(start -0.12065 0.3048)
			(end -0.67945 0.3048)
			(stroke
				(width 0.1)
				(type default)
			)
			(layer "F.Fab")
		)
		(fp_line
			(start 0.120396 0.3048)
			(end 0.120396 0.2794)
			(stroke
				(width 0.1)
				(type default)
			)
			(layer "F.Fab")
		)
		(fp_line
			(start 0.67945 0.3048)
			(end 0.120396 0.3048)
			(stroke
				(width 0.1)
				(type default)
			)
			(layer "F.Fab")
		)
		(fp_line
			(start -0.12065 0.2794)
			(end -0.12065 0.3048)
			(stroke
				(width 0.1)
				(type default)
			)
			(layer "F.Fab")
		)
		(fp_line
			(start 0.120396 0.2794)
			(end -0.12065 0.2794)
			(stroke
				(width 0.1)
				(type default)
			)
			(layer "F.Fab")
		)
		(fp_line
			(start -0.12065 -0.2794)
			(end 0.12065 -0.2794)
			(stroke
				(width 0.1)
				(type default)
			)
			(layer "F.Fab")
		)
		(fp_line
			(start 0.12065 -0.2794)
			(end 0.12065 -0.3048)
			(stroke
				(width 0.1)
				(type default)
			)
			(layer "F.Fab")
		)
		(fp_line
			(start 0.12065 -0.3048)
			(end 0.67945 -0.3048)
			(stroke
				(width 0.1)
				(type default)
			)
			(layer "F.Fab")
		)
		(fp_line
			(start 0.67945 -0.3048)
			(end 0.67945 0.3048)
			(stroke
				(width 0.1)
				(type default)
			)
			(layer "F.Fab")
		)
		(fp_line
			(start -0.67945 -0.305054)
			(end -0.12065 -0.305054)
			(stroke
				(width 0.1)
				(type default)
			)
			(layer "F.Fab")
		)
		(fp_line
			(start -0.12065 -0.305054)
			(end -0.12065 -0.2794)
			(stroke
				(width 0.1)
				(type default)
			)
			(layer "F.Fab")
		)
		(pad "1" smd circle
			(at -0.40005 0 270)
			(size 0 0)
			(layers "F.Cu" "F.Mask" "F.Paste")
			(net "USB_HUB2_TI_HS_SUSPEND")
		)
		(pad "2" smd circle
			(at 0.40005 0 270)
			(size 0 0)
			(layers "F.Cu" "F.Mask" "F.Paste")
			(net "GND")
		)
	)
	(footprint ""
		(layer "F.Cu")
		(at 323.100446 -99.284536)
		(property "Reference" "R1275"
			(at 0 0 0)
			(layer "F.SilkS")
			(hide yes)
			(effects
				(font
					(size 1.27 1.27)
				)
			)
		)
		(property "Value" ""
			(at 0 0 0)
			(layer "F.Fab")
			(effects
				(font
					(size 1.27 1.27)
				)
			)
		)
		(duplicate_pad_numbers_are_jumpers no)
		(fp_line
			(start -0.7874 -0.4064)
			(end 0.7874 -0.4064)
			(stroke
				(width 0.1524)
				(type default)
			)
			(layer "F.SilkS")
		)
		(fp_line
			(start -0.7874 0.4064)
			(end -0.7874 -0.4064)
			(stroke
				(width 0.1524)
				(type default)
			)
			(layer "F.SilkS")
		)
		(fp_line
			(start 0.7874 -0.4064)
			(end 0.7874 0.4064)
			(stroke
				(width 0.1524)
				(type default)
			)
			(layer "F.SilkS")
		)
		(fp_line
			(start 0.7874 0.4064)
			(end -0.7874 0.4064)
			(stroke
				(width 0.1524)
				(type default)
			)
			(layer "F.SilkS")
		)
		(fp_line
			(start -0.67945 -0.305054)
			(end -0.12065 -0.305054)
			(stroke
				(width 0.1)
				(type default)
			)
			(layer "F.Fab")
		)
		(fp_line
			(start -0.67945 0.3048)
			(end -0.67945 -0.305054)
			(stroke
				(width 0.1)
				(type default)
			)
			(layer "F.Fab")
		)
		(fp_line
			(start -0.12065 -0.305054)
			(end -0.12065 -0.2794)
			(stroke
				(width 0.1)
				(type default)
			)
			(layer "F.Fab")
		)
		(fp_line
			(start -0.12065 -0.2794)
			(end 0.12065 -0.2794)
			(stroke
				(width 0.1)
				(type default)
			)
			(layer "F.Fab")
		)
		(fp_line
			(start -0.12065 0.2794)
			(end -0.12065 0.3048)
			(stroke
				(width 0.1)
				(type default)
			)
			(layer "F.Fab")
		)
		(fp_line
			(start -0.12065 0.3048)
			(end -0.67945 0.3048)
			(stroke
				(width 0.1)
				(type default)
			)
			(layer "F.Fab")
		)
		(fp_line
			(start 0.120396 0.2794)
			(end -0.12065 0.2794)
			(stroke
				(width 0.1)
				(type default)
			)
			(layer "F.Fab")
		)
		(fp_line
			(start 0.120396 0.3048)
			(end 0.120396 0.2794)
			(stroke
				(width 0.1)
				(type default)
			)
			(layer "F.Fab")
		)
		(fp_line
			(start 0.12065 -0.3048)
			(end 0.67945 -0.3048)
			(stroke
				(width 0.1)
				(type default)
			)
			(layer "F.Fab")
		)
		(fp_line
			(start 0.12065 -0.2794)
			(end 0.12065 -0.3048)
			(stroke
				(width 0.1)
				(type default)
			)
			(layer "F.Fab")
		)
		(fp_line
			(start 0.67945 -0.3048)
			(end 0.67945 0.3048)
			(stroke
				(width 0.1)
				(type default)
			)
			(layer "F.Fab")
		)
		(fp_line
			(start 0.67945 0.3048)
			(end 0.120396 0.3048)
			(stroke
				(width 0.1)
				(type default)
			)
			(layer "F.Fab")
		)
		(pad "1" smd circle
			(at -0.40005 0)
			(size 0 0)
			(layers "F.Cu" "F.Mask" "F.Paste")
			(net "SMB_INA230_8_3V3AUX_SDA_R")
		)
		(pad "2" smd circle
			(at 0.40005 0)
			(size 0 0)
			(layers "F.Cu" "F.Mask" "F.Paste")
			(net "SMB_INA230_8_3V3AUX_SDA_R1")
		)
	)
	(footprint ""
		(layer "F.Cu")
		(at 197.269608 -120.991376)
		(property "Reference" "R4147"
			(at 0 0 0)
			(layer "F.SilkS")
			(hide yes)
			(effects
				(font
					(size 1.27 1.27)
				)
			)
		)
		(property "Value" ""
			(at 0 0 0)
			(layer "F.Fab")
			(effects
				(font
					(size 1.27 1.27)
				)
			)
		)
		(duplicate_pad_numbers_are_jumpers no)
		(fp_line
			(start -0.7874 -0.4064)
			(end 0.7874 -0.4064)
			(stroke
				(width 0.1524)
				(type default)
			)
			(layer "F.SilkS")
		)
		(fp_line
			(start -0.7874 0.4064)
			(end -0.7874 -0.4064)
			(stroke
				(width 0.1524)
				(type default)
			)
			(layer "F.SilkS")
		)
		(fp_line
			(start 0.7874 -0.4064)
			(end 0.7874 0.4064)
			(stroke
				(width 0.1524)
				(type default)
			)
			(layer "F.SilkS")
		)
		(fp_line
			(start 0.7874 0.4064)
			(end -0.7874 0.4064)
			(stroke
				(width 0.1524)
				(type default)
			)
			(layer "F.SilkS")
		)
		(fp_line
			(start -0.67945 -0.305054)
			(end -0.12065 -0.305054)
			(stroke
				(width 0.1)
				(type default)
			)
			(layer "F.Fab")
		)
		(fp_line
			(start -0.67945 0.3048)
			(end -0.67945 -0.305054)
			(stroke
				(width 0.1)
				(type default)
			)
			(layer "F.Fab")
		)
		(fp_line
			(start -0.12065 -0.305054)
			(end -0.12065 -0.2794)
			(stroke
				(width 0.1)
				(type default)
			)
			(layer "F.Fab")
		)
		(fp_line
			(start -0.12065 -0.2794)
			(end 0.12065 -0.2794)
			(stroke
				(width 0.1)
				(type default)
			)
			(layer "F.Fab")
		)
		(fp_line
			(start -0.12065 0.2794)
			(end -0.12065 0.3048)
			(stroke
				(width 0.1)
				(type default)
			)
			(layer "F.Fab")
		)
		(fp_line
			(start -0.12065 0.3048)
			(end -0.67945 0.3048)
			(stroke
				(width 0.1)
				(type default)
			)
			(layer "F.Fab")
		)
		(fp_line
			(start 0.120396 0.2794)
			(end -0.12065 0.2794)
			(stroke
				(width 0.1)
				(type default)
			)
			(layer "F.Fab")
		)
		(fp_line
			(start 0.120396 0.3048)
			(end 0.120396 0.2794)
			(stroke
				(width 0.1)
				(type default)
			)
			(layer "F.Fab")
		)
		(fp_line
			(start 0.12065 -0.3048)
			(end 0.67945 -0.3048)
			(stroke
				(width 0.1)
				(type default)
			)
			(layer "F.Fab")
		)
		(fp_line
			(start 0.12065 -0.2794)
			(end 0.12065 -0.3048)
			(stroke
				(width 0.1)
				(type default)
			)
			(layer "F.Fab")
		)
		(fp_line
			(start 0.67945 -0.3048)
			(end 0.67945 0.3048)
			(stroke
				(width 0.1)
				(type default)
			)
			(layer "F.Fab")
		)
		(fp_line
			(start 0.67945 0.3048)
			(end 0.120396 0.3048)
			(stroke
				(width 0.1)
				(type default)
			)
			(layer "F.Fab")
		)
		(pad "1" smd circle
			(at -0.40005 0)
			(size 0 0)
			(layers "F.Cu" "F.Mask" "F.Paste")
			(net "PRSNT_CABLE_GPU_A2_ISO_R_N")
		)
		(pad "2" smd circle
			(at 0.40005 0)
			(size 0 0)
			(layers "F.Cu" "F.Mask" "F.Paste")
			(net "PRSNT_CABLE_GPU_A2_ISO_N")
		)
	)
	(footprint ""
		(layer "F.Cu")
		(at 108.627164 -261.748016 -90)
		(property "Reference" "C2500"
			(at 0 0 270)
			(layer "F.SilkS")
			(hide yes)
			(effects
				(font
					(size 1.27 1.27)
				)
			)
		)
		(property "Value" ""
			(at 0 0 270)
			(layer "F.Fab")
			(effects
				(font
					(size 1.27 1.27)
				)
			)
		)
		(duplicate_pad_numbers_are_jumpers no)
		(fp_line
			(start -0.7874 0.4064)
			(end -0.7874 -0.4064)
			(stroke
				(width 0.1524)
				(type default)
			)
			(layer "F.SilkS")
		)
		(fp_line
			(start 0.7874 0.4064)
			(end -0.7874 0.4064)
			(stroke
				(width 0.1524)
				(type default)
			)
			(layer "F.SilkS")
		)
		(fp_line
			(start -0.7874 -0.4064)
			(end 0.7874 -0.4064)
			(stroke
				(width 0.1524)
				(type default)
			)
			(layer "F.SilkS")
		)
		(fp_line
			(start 0.7874 -0.4064)
			(end 0.7874 0.4064)
			(stroke
				(width 0.1524)
				(type default)
			)
			(layer "F.SilkS")
		)
		(fp_line
			(start -0.67945 0.3048)
			(end -0.67945 -0.305054)
			(stroke
				(width 0.1)
				(type default)
			)
			(layer "F.Fab")
		)
		(fp_line
			(start -0.12065 0.3048)
			(end -0.67945 0.3048)
			(stroke
				(width 0.1)
				(type default)
			)
			(layer "F.Fab")
		)
		(fp_line
			(start 0.120396 0.3048)
			(end 0.120396 0.2794)
			(stroke
				(width 0.1)
				(type default)
			)
			(layer "F.Fab")
		)
		(fp_line
			(start 0.67945 0.3048)
			(end 0.120396 0.3048)
			(stroke
				(width 0.1)
				(type default)
			)
			(layer "F.Fab")
		)
		(fp_line
			(start -0.12065 0.2794)
			(end -0.12065 0.3048)
			(stroke
				(width 0.1)
				(type default)
			)
			(layer "F.Fab")
		)
		(fp_line
			(start 0.120396 0.2794)
			(end -0.12065 0.2794)
			(stroke
				(width 0.1)
				(type default)
			)
			(layer "F.Fab")
		)
		(fp_line
			(start -0.12065 -0.2794)
			(end 0.12065 -0.2794)
			(stroke
				(width 0.1)
				(type default)
			)
			(layer "F.Fab")
		)
		(fp_line
			(start 0.12065 -0.2794)
			(end 0.12065 -0.3048)
			(stroke
				(width 0.1)
				(type default)
			)
			(layer "F.Fab")
		)
		(fp_line
			(start 0.12065 -0.3048)
			(end 0.67945 -0.3048)
			(stroke
				(width 0.1)
				(type default)
			)
			(layer "F.Fab")
		)
		(fp_line
			(start 0.67945 -0.3048)
			(end 0.67945 0.3048)
			(stroke
				(width 0.1)
				(type default)
			)
			(layer "F.Fab")
		)
		(fp_line
			(start -0.67945 -0.305054)
			(end -0.12065 -0.305054)
			(stroke
				(width 0.1)
				(type default)
			)
			(layer "F.Fab")
		)
		(fp_line
			(start -0.12065 -0.305054)
			(end -0.12065 -0.2794)
			(stroke
				(width 0.1)
				(type default)
			)
			(layer "F.Fab")
		)
		(pad "1" smd circle
			(at -0.40005 0 270)
			(size 0 0)
			(layers "F.Cu" "F.Mask" "F.Paste")
			(net "PVDD11_S3_P1")
		)
		(pad "2" smd circle
			(at 0.40005 0 270)
			(size 0 0)
			(layers "F.Cu" "F.Mask" "F.Paste")
			(net "GND")
		)
	)
	(footprint ""
		(layer "F.Cu")
		(at 304.419 -360.426 180)
		(property "Reference" "PC73"
			(at 0 0 180)
			(layer "F.SilkS")
			(hide yes)
			(effects
				(font
					(size 1.27 1.27)
				)
			)
		)
		(property "Value" ""
			(at 0 0 180)
			(layer "F.Fab")
			(effects
				(font
					(size 1.27 1.27)
				)
			)
		)
		(duplicate_pad_numbers_are_jumpers no)
		(fp_line
			(start 0.7874 0.4064)
			(end -0.7874 0.4064)
			(stroke
				(width 0.1524)
				(type default)
			)
			(layer "F.SilkS")
		)
		(fp_line
			(start 0.7874 -0.4064)
			(end 0.7874 0.4064)
			(stroke
				(width 0.1524)
				(type default)
			)
			(layer "F.SilkS")
		)
		(fp_line
			(start -0.7874 0.4064)
			(end -0.7874 -0.4064)
			(stroke
				(width 0.1524)
				(type default)
			)
			(layer "F.SilkS")
		)
		(fp_line
			(start -0.7874 -0.4064)
			(end 0.7874 -0.4064)
			(stroke
				(width 0.1524)
				(type default)
			)
			(layer "F.SilkS")
		)
		(fp_line
			(start 0.67945 0.3048)
			(end 0.120396 0.3048)
			(stroke
				(width 0.1)
				(type default)
			)
			(layer "F.Fab")
		)
		(fp_line
			(start 0.67945 -0.3048)
			(end 0.67945 0.3048)
			(stroke
				(width 0.1)
				(type default)
			)
			(layer "F.Fab")
		)
		(fp_line
			(start 0.12065 -0.2794)
			(end 0.12065 -0.3048)
			(stroke
				(width 0.1)
				(type default)
			)
			(layer "F.Fab")
		)
		(fp_line
			(start 0.12065 -0.3048)
			(end 0.67945 -0.3048)
			(stroke
				(width 0.1)
				(type default)
			)
			(layer "F.Fab")
		)
		(fp_line
			(start 0.120396 0.3048)
			(end 0.120396 0.2794)
			(stroke
				(width 0.1)
				(type default)
			)
			(layer "F.Fab")
		)
		(fp_line
			(start 0.120396 0.2794)
			(end -0.12065 0.2794)
			(stroke
				(width 0.1)
				(type default)
			)
			(layer "F.Fab")
		)
		(fp_line
			(start -0.12065 0.3048)
			(end -0.67945 0.3048)
			(stroke
				(width 0.1)
				(type default)
			)
			(layer "F.Fab")
		)
		(fp_line
			(start -0.12065 0.2794)
			(end -0.12065 0.3048)
			(stroke
				(width 0.1)
				(type default)
			)
			(layer "F.Fab")
		)
		(fp_line
			(start -0.12065 -0.2794)
			(end 0.12065 -0.2794)
			(stroke
				(width 0.1)
				(type default)
			)
			(layer "F.Fab")
		)
		(fp_line
			(start -0.12065 -0.305054)
			(end -0.12065 -0.2794)
			(stroke
				(width 0.1)
				(type default)
			)
			(layer "F.Fab")
		)
		(fp_line
			(start -0.67945 0.3048)
			(end -0.67945 -0.305054)
			(stroke
				(width 0.1)
				(type default)
			)
			(layer "F.Fab")
		)
		(fp_line
			(start -0.67945 -0.305054)
			(end -0.12065 -0.305054)
			(stroke
				(width 0.1)
				(type default)
			)
			(layer "F.Fab")
		)
		(pad "1" smd circle
			(at -0.40005 0 180)
			(size 0 0)
			(layers "F.Cu" "F.Mask" "F.Paste")
			(net "PVDD18_S5_P0")
		)
		(pad "2" smd circle
			(at 0.40005 0 180)
			(size 0 0)
			(layers "F.Cu" "F.Mask" "F.Paste")
			(net "GND")
		)
	)
	(footprint ""
		(layer "F.Cu")
		(at 102.75697 -180.027834 -90)
		(property "Reference" "PC286"
			(at 0 0 270)
			(layer "F.SilkS")
			(hide yes)
			(effects
				(font
					(size 1.27 1.27)
				)
			)
		)
		(property "Value" ""
			(at 0 0 270)
			(layer "F.Fab")
			(effects
				(font
					(size 1.27 1.27)
				)
			)
		)
		(duplicate_pad_numbers_are_jumpers no)
		(fp_line
			(start -0.7874 0.4064)
			(end -0.7874 -0.4064)
			(stroke
				(width 0.1524)
				(type default)
			)
			(layer "F.SilkS")
		)
		(fp_line
			(start -0.235966 0.4064)
			(end -0.7874 0.4064)
			(stroke
				(width 0.1524)
				(type default)
			)
			(layer "F.SilkS")
		)
		(fp_line
			(start 0.7874 0.4064)
			(end 0.373634 0.4064)
			(stroke
				(width 0.1524)
				(type default)
			)
			(layer "F.SilkS")
		)
		(fp_line
			(start -0.7874 -0.4064)
			(end 0.7874 -0.4064)
			(stroke
				(width 0.1524)
				(type default)
			)
			(layer "F.SilkS")
		)
		(fp_line
			(start 0.7874 -0.4064)
			(end 0.7874 0.4064)
			(stroke
				(width 0.1524)
				(type default)
			)
			(layer "F.SilkS")
		)
		(fp_line
			(start -0.67945 0.3048)
			(end -0.67945 -0.305054)
			(stroke
				(width 0.1)
				(type default)
			)
			(layer "F.Fab")
		)
		(fp_line
			(start -0.12065 0.3048)
			(end -0.67945 0.3048)
			(stroke
				(width 0.1)
				(type default)
			)
			(layer "F.Fab")
		)
		(fp_line
			(start 0.120396 0.3048)
			(end 0.120396 0.2794)
			(stroke
				(width 0.1)
				(type default)
			)
			(layer "F.Fab")
		)
		(fp_line
			(start 0.67945 0.3048)
			(end 0.120396 0.3048)
			(stroke
				(width 0.1)
				(type default)
			)
			(layer "F.Fab")
		)
		(fp_line
			(start -0.12065 0.2794)
			(end -0.12065 0.3048)
			(stroke
				(width 0.1)
				(type default)
			)
			(layer "F.Fab")
		)
		(fp_line
			(start 0.120396 0.2794)
			(end -0.12065 0.2794)
			(stroke
				(width 0.1)
				(type default)
			)
			(layer "F.Fab")
		)
		(fp_line
			(start -0.12065 -0.2794)
			(end 0.12065 -0.2794)
			(stroke
				(width 0.1)
				(type default)
			)
			(layer "F.Fab")
		)
		(fp_line
			(start 0.12065 -0.2794)
			(end 0.12065 -0.3048)
			(stroke
				(width 0.1)
				(type default)
			)
			(layer "F.Fab")
		)
		(fp_line
			(start 0.12065 -0.3048)
			(end 0.67945 -0.3048)
			(stroke
				(width 0.1)
				(type default)
			)
			(layer "F.Fab")
		)
		(fp_line
			(start 0.67945 -0.3048)
			(end 0.67945 0.3048)
			(stroke
				(width 0.1)
				(type default)
			)
			(layer "F.Fab")
		)
		(fp_line
			(start -0.67945 -0.305054)
			(end -0.12065 -0.305054)
			(stroke
				(width 0.1)
				(type default)
			)
			(layer "F.Fab")
		)
		(fp_line
			(start -0.12065 -0.305054)
			(end -0.12065 -0.2794)
			(stroke
				(width 0.1)
				(type default)
			)
			(layer "F.Fab")
		)
		(pad "1" smd circle
			(at -0.40005 0 270)
			(size 0 0)
			(layers "F.Cu" "F.Mask" "F.Paste")
			(net "PVDDCR_CPU0_P1_VCC3")
		)
		(pad "2" smd circle
			(at 0.40005 0 270)
			(size 0 0)
			(layers "F.Cu" "F.Mask" "F.Paste")
			(net "GND")
		)
	)
	(footprint ""
		(layer "F.Cu")
		(at 123.206764 -160.5407 -90)
		(property "Reference" "PR210"
			(at 0 0 270)
			(layer "F.SilkS")
			(hide yes)
			(effects
				(font
					(size 1.27 1.27)
				)
			)
		)
		(property "Value" ""
			(at 0 0 270)
			(layer "F.Fab")
			(effects
				(font
					(size 1.27 1.27)
				)
			)
		)
		(duplicate_pad_numbers_are_jumpers no)
		(fp_line
			(start -0.7874 0.4064)
			(end -0.7874 -0.4064)
			(stroke
				(width 0.1524)
				(type default)
			)
			(layer "F.SilkS")
		)
		(fp_line
			(start 0.7874 0.4064)
			(end -0.7874 0.4064)
			(stroke
				(width 0.1524)
				(type default)
			)
			(layer "F.SilkS")
		)
		(fp_line
			(start -0.7874 -0.4064)
			(end 0.7874 -0.4064)
			(stroke
				(width 0.1524)
				(type default)
			)
			(layer "F.SilkS")
		)
		(fp_line
			(start 0.7874 -0.4064)
			(end 0.7874 0.4064)
			(stroke
				(width 0.1524)
				(type default)
			)
			(layer "F.SilkS")
		)
		(fp_line
			(start -0.67945 0.3048)
			(end -0.67945 -0.305054)
			(stroke
				(width 0.1)
				(type default)
			)
			(layer "F.Fab")
		)
		(fp_line
			(start -0.12065 0.3048)
			(end -0.67945 0.3048)
			(stroke
				(width 0.1)
				(type default)
			)
			(layer "F.Fab")
		)
		(fp_line
			(start 0.120396 0.3048)
			(end 0.120396 0.2794)
			(stroke
				(width 0.1)
				(type default)
			)
			(layer "F.Fab")
		)
		(fp_line
			(start 0.67945 0.3048)
			(end 0.120396 0.3048)
			(stroke
				(width 0.1)
				(type default)
			)
			(layer "F.Fab")
		)
		(fp_line
			(start -0.12065 0.2794)
			(end -0.12065 0.3048)
			(stroke
				(width 0.1)
				(type default)
			)
			(layer "F.Fab")
		)
		(fp_line
			(start 0.120396 0.2794)
			(end -0.12065 0.2794)
			(stroke
				(width 0.1)
				(type default)
			)
			(layer "F.Fab")
		)
		(fp_line
			(start -0.12065 -0.2794)
			(end 0.12065 -0.2794)
			(stroke
				(width 0.1)
				(type default)
			)
			(layer "F.Fab")
		)
		(fp_line
			(start 0.12065 -0.2794)
			(end 0.12065 -0.3048)
			(stroke
				(width 0.1)
				(type default)
			)
			(layer "F.Fab")
		)
		(fp_line
			(start 0.12065 -0.3048)
			(end 0.67945 -0.3048)
			(stroke
				(width 0.1)
				(type default)
			)
			(layer "F.Fab")
		)
		(fp_line
			(start 0.67945 -0.3048)
			(end 0.67945 0.3048)
			(stroke
				(width 0.1)
				(type default)
			)
			(layer "F.Fab")
		)
		(fp_line
			(start -0.67945 -0.305054)
			(end -0.12065 -0.305054)
			(stroke
				(width 0.1)
				(type default)
			)
			(layer "F.Fab")
		)
		(fp_line
			(start -0.12065 -0.305054)
			(end -0.12065 -0.2794)
			(stroke
				(width 0.1)
				(type default)
			)
			(layer "F.Fab")
		)
		(pad "1" smd circle
			(at -0.40005 0 270)
			(size 0 0)
			(layers "F.Cu" "F.Mask" "F.Paste")
			(net "SW_PVDDCR_SOC_P1_BOOT2")
		)
		(pad "2" smd circle
			(at 0.40005 0 270)
			(size 0 0)
			(layers "F.Cu" "F.Mask" "F.Paste")
			(net "SW_PVDDCR_SOC_P1_BOOT2_RC")
		)
	)
	(footprint ""
		(layer "F.Cu")
		(at 135.36168 -28.48102 90)
		(property "Reference" "R6197"
			(at 0 0 90)
			(layer "F.SilkS")
			(hide yes)
			(effects
				(font
					(size 1.27 1.27)
				)
			)
		)
		(property "Value" ""
			(at 0 0 90)
			(layer "F.Fab")
			(effects
				(font
					(size 1.27 1.27)
				)
			)
		)
		(duplicate_pad_numbers_are_jumpers no)
		(fp_line
			(start 0.32512 -0.175006)
			(end 0.32512 0.175006)
			(stroke
				(width 0.1)
				(type default)
			)
			(layer "F.Fab")
		)
		(fp_line
			(start -0.32512 -0.175006)
			(end 0.32512 -0.175006)
			(stroke
				(width 0.1)
				(type default)
			)
			(layer "F.Fab")
		)
		(fp_line
			(start 0.32512 0.175006)
			(end -0.32512 0.175006)
			(stroke
				(width 0.1)
				(type default)
			)
			(layer "F.Fab")
		)
		(fp_line
			(start -0.32512 0.175006)
			(end -0.32512 -0.175006)
			(stroke
				(width 0.1)
				(type default)
			)
			(layer "F.Fab")
		)
		(pad "1" smd rect
			(at -0.2667 0 90)
			(size 0.3048 0.381)
			(layers "F.Cu" "F.Mask" "F.Paste")
			(net "USB2_CPU0_P0_HUB2_R_DN")
		)
		(pad "2" smd rect
			(at 0.2667 0 270)
			(size 0.3048 0.381)
			(layers "F.Cu" "F.Mask" "F.Paste")
			(net "USB2_HUB_EXT_DN")
		)
	)
	(footprint ""
		(layer "F.Cu")
		(at 383.771902 -177.88636 -90)
		(property "Reference" "PC544_3"
			(at 0 0 270)
			(layer "F.SilkS")
			(hide yes)
			(effects
				(font
					(size 1.27 1.27)
				)
			)
		)
		(property "Value" ""
			(at 0 0 270)
			(layer "F.Fab")
			(effects
				(font
					(size 1.27 1.27)
				)
			)
		)
		(duplicate_pad_numbers_are_jumpers no)
		(fp_line
			(start -0.7874 0.4064)
			(end -0.7874 -0.4064)
			(stroke
				(width 0.1524)
				(type default)
			)
			(layer "F.SilkS")
		)
		(fp_line
			(start 0.7874 0.4064)
			(end -0.7874 0.4064)
			(stroke
				(width 0.1524)
				(type default)
			)
			(layer "F.SilkS")
		)
		(fp_line
			(start -0.7874 -0.4064)
			(end 0.7874 -0.4064)
			(stroke
				(width 0.1524)
				(type default)
			)
			(layer "F.SilkS")
		)
		(fp_line
			(start 0.7874 -0.4064)
			(end 0.7874 0.4064)
			(stroke
				(width 0.1524)
				(type default)
			)
			(layer "F.SilkS")
		)
		(fp_line
			(start -0.67945 0.3048)
			(end -0.67945 -0.305054)
			(stroke
				(width 0.1)
				(type default)
			)
			(layer "F.Fab")
		)
		(fp_line
			(start -0.12065 0.3048)
			(end -0.67945 0.3048)
			(stroke
				(width 0.1)
				(type default)
			)
			(layer "F.Fab")
		)
		(fp_line
			(start 0.120396 0.3048)
			(end 0.120396 0.2794)
			(stroke
				(width 0.1)
				(type default)
			)
			(layer "F.Fab")
		)
		(fp_line
			(start 0.67945 0.3048)
			(end 0.120396 0.3048)
			(stroke
				(width 0.1)
				(type default)
			)
			(layer "F.Fab")
		)
		(fp_line
			(start -0.12065 0.2794)
			(end -0.12065 0.3048)
			(stroke
				(width 0.1)
				(type default)
			)
			(layer "F.Fab")
		)
		(fp_line
			(start 0.120396 0.2794)
			(end -0.12065 0.2794)
			(stroke
				(width 0.1)
				(type default)
			)
			(layer "F.Fab")
		)
		(fp_line
			(start -0.12065 -0.2794)
			(end 0.12065 -0.2794)
			(stroke
				(width 0.1)
				(type default)
			)
			(layer "F.Fab")
		)
		(fp_line
			(start 0.12065 -0.2794)
			(end 0.12065 -0.3048)
			(stroke
				(width 0.1)
				(type default)
			)
			(layer "F.Fab")
		)
		(fp_line
			(start 0.12065 -0.3048)
			(end 0.67945 -0.3048)
			(stroke
				(width 0.1)
				(type default)
			)
			(layer "F.Fab")
		)
		(fp_line
			(start 0.67945 -0.3048)
			(end 0.67945 0.3048)
			(stroke
				(width 0.1)
				(type default)
			)
			(layer "F.Fab")
		)
		(fp_line
			(start -0.67945 -0.305054)
			(end -0.12065 -0.305054)
			(stroke
				(width 0.1)
				(type default)
			)
			(layer "F.Fab")
		)
		(fp_line
			(start -0.12065 -0.305054)
			(end -0.12065 -0.2794)
			(stroke
				(width 0.1)
				(type default)
			)
			(layer "F.Fab")
		)
		(pad "1" smd circle
			(at -0.40005 0 270)
			(size 0 0)
			(layers "F.Cu" "F.Mask" "F.Paste")
			(net "PVDDCR_CPU0_P0_VCCS")
		)
		(pad "2" smd circle
			(at 0.40005 0 270)
			(size 0 0)
			(layers "F.Cu" "F.Mask" "F.Paste")
			(net "GND")
		)
	)
	(footprint ""
		(layer "F.Cu")
		(at 286.980884 -370.318792 90)
		(property "Reference" "R8047"
			(at 0 0 90)
			(layer "F.SilkS")
			(hide yes)
			(effects
				(font
					(size 1.27 1.27)
				)
			)
		)
		(property "Value" ""
			(at 0 0 90)
			(layer "F.Fab")
			(effects
				(font
					(size 1.27 1.27)
				)
			)
		)
		(duplicate_pad_numbers_are_jumpers no)
		(fp_line
			(start 0.7874 -0.4064)
			(end 0.7874 0.4064)
			(stroke
				(width 0.1524)
				(type default)
			)
			(layer "F.SilkS")
		)
		(fp_line
			(start -0.7874 -0.4064)
			(end 0.7874 -0.4064)
			(stroke
				(width 0.1524)
				(type default)
			)
			(layer "F.SilkS")
		)
		(fp_line
			(start 0.7874 0.4064)
			(end -0.7874 0.4064)
			(stroke
				(width 0.1524)
				(type default)
			)
			(layer "F.SilkS")
		)
		(fp_line
			(start -0.7874 0.4064)
			(end -0.7874 -0.4064)
			(stroke
				(width 0.1524)
				(type default)
			)
			(layer "F.SilkS")
		)
		(fp_line
			(start -0.12065 -0.305054)
			(end -0.12065 -0.2794)
			(stroke
				(width 0.1)
				(type default)
			)
			(layer "F.Fab")
		)
		(fp_line
			(start -0.67945 -0.305054)
			(end -0.12065 -0.305054)
			(stroke
				(width 0.1)
				(type default)
			)
			(layer "F.Fab")
		)
		(fp_line
			(start 0.67945 -0.3048)
			(end 0.67945 0.3048)
			(stroke
				(width 0.1)
				(type default)
			)
			(layer "F.Fab")
		)
		(fp_line
			(start 0.12065 -0.3048)
			(end 0.67945 -0.3048)
			(stroke
				(width 0.1)
				(type default)
			)
			(layer "F.Fab")
		)
		(fp_line
			(start 0.12065 -0.2794)
			(end 0.12065 -0.3048)
			(stroke
				(width 0.1)
				(type default)
			)
			(layer "F.Fab")
		)
		(fp_line
			(start -0.12065 -0.2794)
			(end 0.12065 -0.2794)
			(stroke
				(width 0.1)
				(type default)
			)
			(layer "F.Fab")
		)
		(fp_line
			(start 0.120396 0.2794)
			(end -0.12065 0.2794)
			(stroke
				(width 0.1)
				(type default)
			)
			(layer "F.Fab")
		)
		(fp_line
			(start -0.12065 0.2794)
			(end -0.12065 0.3048)
			(stroke
				(width 0.1)
				(type default)
			)
			(layer "F.Fab")
		)
		(fp_line
			(start 0.67945 0.3048)
			(end 0.120396 0.3048)
			(stroke
				(width 0.1)
				(type default)
			)
			(layer "F.Fab")
		)
		(fp_line
			(start 0.120396 0.3048)
			(end 0.120396 0.2794)
			(stroke
				(width 0.1)
				(type default)
			)
			(layer "F.Fab")
		)
		(fp_line
			(start -0.12065 0.3048)
			(end -0.67945 0.3048)
			(stroke
				(width 0.1)
				(type default)
			)
			(layer "F.Fab")
		)
		(fp_line
			(start -0.67945 0.3048)
			(end -0.67945 -0.305054)
			(stroke
				(width 0.1)
				(type default)
			)
			(layer "F.Fab")
		)
		(pad "1" smd circle
			(at -0.40005 0 90)
			(size 0 0)
			(layers "F.Cu" "F.Mask" "F.Paste")
			(net "PVDDIO_P0_EN")
		)
		(pad "2" smd circle
			(at 0.40005 0 90)
			(size 0 0)
			(layers "F.Cu" "F.Mask" "F.Paste")
			(net "PVDDIO_P0_EN_R")
		)
	)
	(footprint ""
		(layer "F.Cu")
		(at 71.035164 -16.315944)
		(property "Reference" "R1325"
			(at 1.889506 -2.226056 90)
			(unlocked yes)
			(layer "F.SilkS")
			(effects
				(font
					(size 0.7874 0.5842)
					(thickness 0.1524)
				)
				(justify left)
			)
		)
		(property "Value" ""
			(at 0 0 0)
			(layer "F.Fab")
			(effects
				(font
					(size 1.27 1.27)
				)
			)
		)
		(duplicate_pad_numbers_are_jumpers no)
		(fp_line
			(start -3.937508 -1.8796)
			(end -3.937508 1.8796)
			(stroke
				(width 0.1524)
				(type default)
			)
			(layer "F.SilkS")
		)
		(fp_line
			(start -3.937508 1.8796)
			(end 3.937508 1.8796)
			(stroke
				(width 0.1524)
				(type default)
			)
			(layer "F.SilkS")
		)
		(fp_line
			(start 3.937508 -1.8796)
			(end -3.937508 -1.8796)
			(stroke
				(width 0.1524)
				(type default)
			)
			(layer "F.SilkS")
		)
		(fp_line
			(start 3.937508 1.8796)
			(end 3.937508 -1.8796)
			(stroke
				(width 0.1524)
				(type default)
			)
			(layer "F.SilkS")
		)
		(fp_line
			(start -3.275076 -1.674876)
			(end -3.275076 1.674876)
			(stroke
				(width 0.1)
				(type default)
			)
			(layer "F.Fab")
		)
		(fp_line
			(start -3.275076 1.674876)
			(end 3.275076 1.674876)
			(stroke
				(width 0.1)
				(type default)
			)
			(layer "F.Fab")
		)
		(fp_line
			(start 3.275076 -1.674876)
			(end -3.275076 -1.674876)
			(stroke
				(width 0.1)
				(type default)
			)
			(layer "F.Fab")
		)
		(fp_line
			(start 3.275076 1.674876)
			(end 3.275076 -1.674876)
			(stroke
				(width 0.1)
				(type default)
			)
			(layer "F.Fab")
		)
		(pad "1" smd rect
			(at -2.350008 0)
			(size 2.921 3.5052)
			(layers "F.Cu" "F.Mask" "F.Paste")
			(net "P12V_OCP_V3_2_R")
		)
		(pad "2" smd rect
			(at 2.350008 0)
			(size 2.921 3.5052)
			(layers "F.Cu" "F.Mask" "F.Paste")
			(net "P12V_OCP_V3_2")
		)
	)
	(footprint ""
		(layer "F.Cu")
		(at 307.404516 -433.942744 90)
		(property "Reference" "R3464"
			(at 0 0 90)
			(layer "F.SilkS")
			(hide yes)
			(effects
				(font
					(size 1.27 1.27)
				)
			)
		)
		(property "Value" ""
			(at 0 0 90)
			(layer "F.Fab")
			(effects
				(font
					(size 1.27 1.27)
				)
			)
		)
		(duplicate_pad_numbers_are_jumpers no)
		(fp_line
			(start 0.7874 -0.4064)
			(end 0.7874 0.4064)
			(stroke
				(width 0.1524)
				(type default)
			)
			(layer "F.SilkS")
		)
		(fp_line
			(start -0.7874 -0.4064)
			(end 0.7874 -0.4064)
			(stroke
				(width 0.1524)
				(type default)
			)
			(layer "F.SilkS")
		)
		(fp_line
			(start 0.7874 0.4064)
			(end -0.7874 0.4064)
			(stroke
				(width 0.1524)
				(type default)
			)
			(layer "F.SilkS")
		)
		(fp_line
			(start -0.7874 0.4064)
			(end -0.7874 -0.4064)
			(stroke
				(width 0.1524)
				(type default)
			)
			(layer "F.SilkS")
		)
		(fp_line
			(start -0.12065 -0.305054)
			(end -0.12065 -0.2794)
			(stroke
				(width 0.1)
				(type default)
			)
			(layer "F.Fab")
		)
		(fp_line
			(start -0.67945 -0.305054)
			(end -0.12065 -0.305054)
			(stroke
				(width 0.1)
				(type default)
			)
			(layer "F.Fab")
		)
		(fp_line
			(start 0.67945 -0.3048)
			(end 0.67945 0.3048)
			(stroke
				(width 0.1)
				(type default)
			)
			(layer "F.Fab")
		)
		(fp_line
			(start 0.12065 -0.3048)
			(end 0.67945 -0.3048)
			(stroke
				(width 0.1)
				(type default)
			)
			(layer "F.Fab")
		)
		(fp_line
			(start 0.12065 -0.2794)
			(end 0.12065 -0.3048)
			(stroke
				(width 0.1)
				(type default)
			)
			(layer "F.Fab")
		)
		(fp_line
			(start -0.12065 -0.2794)
			(end 0.12065 -0.2794)
			(stroke
				(width 0.1)
				(type default)
			)
			(layer "F.Fab")
		)
		(fp_line
			(start 0.120396 0.2794)
			(end -0.12065 0.2794)
			(stroke
				(width 0.1)
				(type default)
			)
			(layer "F.Fab")
		)
		(fp_line
			(start -0.12065 0.2794)
			(end -0.12065 0.3048)
			(stroke
				(width 0.1)
				(type default)
			)
			(layer "F.Fab")
		)
		(fp_line
			(start 0.67945 0.3048)
			(end 0.120396 0.3048)
			(stroke
				(width 0.1)
				(type default)
			)
			(layer "F.Fab")
		)
		(fp_line
			(start 0.120396 0.3048)
			(end 0.120396 0.2794)
			(stroke
				(width 0.1)
				(type default)
			)
			(layer "F.Fab")
		)
		(fp_line
			(start -0.12065 0.3048)
			(end -0.67945 0.3048)
			(stroke
				(width 0.1)
				(type default)
			)
			(layer "F.Fab")
		)
		(fp_line
			(start -0.67945 0.3048)
			(end -0.67945 -0.305054)
			(stroke
				(width 0.1)
				(type default)
			)
			(layer "F.Fab")
		)
		(pad "1" smd circle
			(at -0.40005 0 90)
			(size 0 0)
			(layers "F.Cu" "F.Mask" "F.Paste")
			(net "P3V3_AUX")
		)
		(pad "2" smd circle
			(at 0.40005 0 90)
			(size 0 0)
			(layers "F.Cu" "F.Mask" "F.Paste")
			(net "GPU_FPGA_OVERT_N")
		)
	)
	(footprint ""
		(layer "F.Cu")
		(at 102.09657 -406.03424 180)
		(property "Reference" "R6788"
			(at 0 0 180)
			(layer "F.SilkS")
			(hide yes)
			(effects
				(font
					(size 1.27 1.27)
				)
			)
		)
		(property "Value" ""
			(at 0 0 180)
			(layer "F.Fab")
			(effects
				(font
					(size 1.27 1.27)
				)
			)
		)
		(duplicate_pad_numbers_are_jumpers no)
		(fp_line
			(start 0.32512 0.175006)
			(end -0.32512 0.175006)
			(stroke
				(width 0.1)
				(type default)
			)
			(layer "F.Fab")
		)
		(fp_line
			(start 0.32512 -0.175006)
			(end 0.32512 0.175006)
			(stroke
				(width 0.1)
				(type default)
			)
			(layer "F.Fab")
		)
		(fp_line
			(start -0.32512 0.175006)
			(end -0.32512 -0.175006)
			(stroke
				(width 0.1)
				(type default)
			)
			(layer "F.Fab")
		)
		(fp_line
			(start -0.32512 -0.175006)
			(end 0.32512 -0.175006)
			(stroke
				(width 0.1)
				(type default)
			)
			(layer "F.Fab")
		)
		(pad "1" smd rect
			(at -0.2667 0 180)
			(size 0.3048 0.381)
			(layers "F.Cu" "F.Mask" "F.Paste")
			(net "U12_E2")
		)
		(pad "2" smd rect
			(at 0.2667 0)
			(size 0.3048 0.381)
			(layers "F.Cu" "F.Mask" "F.Paste")
			(net "GND")
		)
	)
	(footprint ""
		(layer "F.Cu")
		(at 305.819048 -47.037498 180)
		(property "Reference" "R3690"
			(at 0 0 180)
			(layer "F.SilkS")
			(hide yes)
			(effects
				(font
					(size 1.27 1.27)
				)
			)
		)
		(property "Value" ""
			(at 0 0 180)
			(layer "F.Fab")
			(effects
				(font
					(size 1.27 1.27)
				)
			)
		)
		(duplicate_pad_numbers_are_jumpers no)
		(fp_line
			(start 0.7874 0.4064)
			(end -0.7874 0.4064)
			(stroke
				(width 0.1524)
				(type default)
			)
			(layer "F.SilkS")
		)
		(fp_line
			(start 0.7874 -0.4064)
			(end 0.7874 0.4064)
			(stroke
				(width 0.1524)
				(type default)
			)
			(layer "F.SilkS")
		)
		(fp_line
			(start -0.7874 0.4064)
			(end -0.7874 -0.4064)
			(stroke
				(width 0.1524)
				(type default)
			)
			(layer "F.SilkS")
		)
		(fp_line
			(start -0.7874 -0.4064)
			(end 0.7874 -0.4064)
			(stroke
				(width 0.1524)
				(type default)
			)
			(layer "F.SilkS")
		)
		(fp_line
			(start 0.67945 0.3048)
			(end 0.120396 0.3048)
			(stroke
				(width 0.1)
				(type default)
			)
			(layer "F.Fab")
		)
		(fp_line
			(start 0.67945 -0.3048)
			(end 0.67945 0.3048)
			(stroke
				(width 0.1)
				(type default)
			)
			(layer "F.Fab")
		)
		(fp_line
			(start 0.12065 -0.2794)
			(end 0.12065 -0.3048)
			(stroke
				(width 0.1)
				(type default)
			)
			(layer "F.Fab")
		)
		(fp_line
			(start 0.12065 -0.3048)
			(end 0.67945 -0.3048)
			(stroke
				(width 0.1)
				(type default)
			)
			(layer "F.Fab")
		)
		(fp_line
			(start 0.120396 0.3048)
			(end 0.120396 0.2794)
			(stroke
				(width 0.1)
				(type default)
			)
			(layer "F.Fab")
		)
		(fp_line
			(start 0.120396 0.2794)
			(end -0.12065 0.2794)
			(stroke
				(width 0.1)
				(type default)
			)
			(layer "F.Fab")
		)
		(fp_line
			(start -0.12065 0.3048)
			(end -0.67945 0.3048)
			(stroke
				(width 0.1)
				(type default)
			)
			(layer "F.Fab")
		)
		(fp_line
			(start -0.12065 0.2794)
			(end -0.12065 0.3048)
			(stroke
				(width 0.1)
				(type default)
			)
			(layer "F.Fab")
		)
		(fp_line
			(start -0.12065 -0.2794)
			(end 0.12065 -0.2794)
			(stroke
				(width 0.1)
				(type default)
			)
			(layer "F.Fab")
		)
		(fp_line
			(start -0.12065 -0.305054)
			(end -0.12065 -0.2794)
			(stroke
				(width 0.1)
				(type default)
			)
			(layer "F.Fab")
		)
		(fp_line
			(start -0.67945 0.3048)
			(end -0.67945 -0.305054)
			(stroke
				(width 0.1)
				(type default)
			)
			(layer "F.Fab")
		)
		(fp_line
			(start -0.67945 -0.305054)
			(end -0.12065 -0.305054)
			(stroke
				(width 0.1)
				(type default)
			)
			(layer "F.Fab")
		)
		(pad "1" smd circle
			(at -0.40005 0 180)
			(size 0 0)
			(layers "F.Cu" "F.Mask" "F.Paste")
			(net "ADC128_VREF")
		)
		(pad "2" smd circle
			(at 0.40005 0 180)
			(size 0 0)
			(layers "F.Cu" "F.Mask" "F.Paste")
			(net "GND")
		)
	)
	(footprint ""
		(layer "F.Cu")
		(at 93.29801 -53.685694)
		(property "Reference" "PC2140"
			(at 0 0 0)
			(layer "F.SilkS")
			(hide yes)
			(effects
				(font
					(size 1.27 1.27)
				)
			)
		)
		(property "Value" ""
			(at 0 0 0)
			(layer "F.Fab")
			(effects
				(font
					(size 1.27 1.27)
				)
			)
		)
		(duplicate_pad_numbers_are_jumpers no)
		(fp_line
			(start -0.7874 -0.4064)
			(end 0.7874 -0.4064)
			(stroke
				(width 0.1524)
				(type default)
			)
			(layer "F.SilkS")
		)
		(fp_line
			(start -0.7874 0.4064)
			(end -0.7874 -0.4064)
			(stroke
				(width 0.1524)
				(type default)
			)
			(layer "F.SilkS")
		)
		(fp_line
			(start 0.7874 -0.4064)
			(end 0.7874 0.4064)
			(stroke
				(width 0.1524)
				(type default)
			)
			(layer "F.SilkS")
		)
		(fp_line
			(start 0.7874 0.4064)
			(end -0.7874 0.4064)
			(stroke
				(width 0.1524)
				(type default)
			)
			(layer "F.SilkS")
		)
		(fp_line
			(start -0.67945 -0.305054)
			(end -0.12065 -0.305054)
			(stroke
				(width 0.1)
				(type default)
			)
			(layer "F.Fab")
		)
		(fp_line
			(start -0.67945 0.3048)
			(end -0.67945 -0.305054)
			(stroke
				(width 0.1)
				(type default)
			)
			(layer "F.Fab")
		)
		(fp_line
			(start -0.12065 -0.305054)
			(end -0.12065 -0.2794)
			(stroke
				(width 0.1)
				(type default)
			)
			(layer "F.Fab")
		)
		(fp_line
			(start -0.12065 -0.2794)
			(end 0.12065 -0.2794)
			(stroke
				(width 0.1)
				(type default)
			)
			(layer "F.Fab")
		)
		(fp_line
			(start -0.12065 0.2794)
			(end -0.12065 0.3048)
			(stroke
				(width 0.1)
				(type default)
			)
			(layer "F.Fab")
		)
		(fp_line
			(start -0.12065 0.3048)
			(end -0.67945 0.3048)
			(stroke
				(width 0.1)
				(type default)
			)
			(layer "F.Fab")
		)
		(fp_line
			(start 0.120396 0.2794)
			(end -0.12065 0.2794)
			(stroke
				(width 0.1)
				(type default)
			)
			(layer "F.Fab")
		)
		(fp_line
			(start 0.120396 0.3048)
			(end 0.120396 0.2794)
			(stroke
				(width 0.1)
				(type default)
			)
			(layer "F.Fab")
		)
		(fp_line
			(start 0.12065 -0.3048)
			(end 0.67945 -0.3048)
			(stroke
				(width 0.1)
				(type default)
			)
			(layer "F.Fab")
		)
		(fp_line
			(start 0.12065 -0.2794)
			(end 0.12065 -0.3048)
			(stroke
				(width 0.1)
				(type default)
			)
			(layer "F.Fab")
		)
		(fp_line
			(start 0.67945 -0.3048)
			(end 0.67945 0.3048)
			(stroke
				(width 0.1)
				(type default)
			)
			(layer "F.Fab")
		)
		(fp_line
			(start 0.67945 0.3048)
			(end 0.120396 0.3048)
			(stroke
				(width 0.1)
				(type default)
			)
			(layer "F.Fab")
		)
		(pad "1" smd circle
			(at -0.40005 0)
			(size 0 0)
			(layers "F.Cu" "F.Mask" "F.Paste")
			(net "P3V3_AUX")
		)
		(pad "2" smd circle
			(at 0.40005 0)
			(size 0 0)
			(layers "F.Cu" "F.Mask" "F.Paste")
			(net "GND")
		)
	)
	(footprint ""
		(layer "F.Cu")
		(at 358.297988 -409.388818 90)
		(property "Reference" "R3063"
			(at 0 0 90)
			(layer "F.SilkS")
			(hide yes)
			(effects
				(font
					(size 1.27 1.27)
				)
			)
		)
		(property "Value" ""
			(at 0 0 90)
			(layer "F.Fab")
			(effects
				(font
					(size 1.27 1.27)
				)
			)
		)
		(duplicate_pad_numbers_are_jumpers no)
		(fp_line
			(start 0.7874 -0.4064)
			(end 0.7874 0.4064)
			(stroke
				(width 0.1524)
				(type default)
			)
			(layer "F.SilkS")
		)
		(fp_line
			(start -0.7874 -0.4064)
			(end 0.7874 -0.4064)
			(stroke
				(width 0.1524)
				(type default)
			)
			(layer "F.SilkS")
		)
		(fp_line
			(start 0.7874 0.4064)
			(end -0.7874 0.4064)
			(stroke
				(width 0.1524)
				(type default)
			)
			(layer "F.SilkS")
		)
		(fp_line
			(start -0.7874 0.4064)
			(end -0.7874 -0.4064)
			(stroke
				(width 0.1524)
				(type default)
			)
			(layer "F.SilkS")
		)
		(fp_line
			(start -0.12065 -0.305054)
			(end -0.12065 -0.2794)
			(stroke
				(width 0.1)
				(type default)
			)
			(layer "F.Fab")
		)
		(fp_line
			(start -0.67945 -0.305054)
			(end -0.12065 -0.305054)
			(stroke
				(width 0.1)
				(type default)
			)
			(layer "F.Fab")
		)
		(fp_line
			(start 0.67945 -0.3048)
			(end 0.67945 0.3048)
			(stroke
				(width 0.1)
				(type default)
			)
			(layer "F.Fab")
		)
		(fp_line
			(start 0.12065 -0.3048)
			(end 0.67945 -0.3048)
			(stroke
				(width 0.1)
				(type default)
			)
			(layer "F.Fab")
		)
		(fp_line
			(start 0.12065 -0.2794)
			(end 0.12065 -0.3048)
			(stroke
				(width 0.1)
				(type default)
			)
			(layer "F.Fab")
		)
		(fp_line
			(start -0.12065 -0.2794)
			(end 0.12065 -0.2794)
			(stroke
				(width 0.1)
				(type default)
			)
			(layer "F.Fab")
		)
		(fp_line
			(start 0.120396 0.2794)
			(end -0.12065 0.2794)
			(stroke
				(width 0.1)
				(type default)
			)
			(layer "F.Fab")
		)
		(fp_line
			(start -0.12065 0.2794)
			(end -0.12065 0.3048)
			(stroke
				(width 0.1)
				(type default)
			)
			(layer "F.Fab")
		)
		(fp_line
			(start 0.67945 0.3048)
			(end 0.120396 0.3048)
			(stroke
				(width 0.1)
				(type default)
			)
			(layer "F.Fab")
		)
		(fp_line
			(start 0.120396 0.3048)
			(end 0.120396 0.2794)
			(stroke
				(width 0.1)
				(type default)
			)
			(layer "F.Fab")
		)
		(fp_line
			(start -0.12065 0.3048)
			(end -0.67945 0.3048)
			(stroke
				(width 0.1)
				(type default)
			)
			(layer "F.Fab")
		)
		(fp_line
			(start -0.67945 0.3048)
			(end -0.67945 -0.305054)
			(stroke
				(width 0.1)
				(type default)
			)
			(layer "F.Fab")
		)
		(pad "1" smd circle
			(at -0.40005 0 90)
			(size 0 0)
			(layers "F.Cu" "F.Mask" "F.Paste")
			(net "FM_PDB_BUF_EN_R1")
		)
		(pad "2" smd circle
			(at 0.40005 0 90)
			(size 0 0)
			(layers "F.Cu" "F.Mask" "F.Paste")
			(net "FM_UART_EN")
		)
	)
	(footprint ""
		(layer "F.Cu")
		(at 179.959 -137.632948 -90)
		(property "Reference" "R371"
			(at 0 0 270)
			(layer "F.SilkS")
			(hide yes)
			(effects
				(font
					(size 1.27 1.27)
				)
			)
		)
		(property "Value" ""
			(at 0 0 270)
			(layer "F.Fab")
			(effects
				(font
					(size 1.27 1.27)
				)
			)
		)
		(duplicate_pad_numbers_are_jumpers no)
		(fp_line
			(start -0.7874 0.4064)
			(end -0.7874 -0.4064)
			(stroke
				(width 0.1524)
				(type default)
			)
			(layer "F.SilkS")
		)
		(fp_line
			(start 0.7874 0.4064)
			(end -0.7874 0.4064)
			(stroke
				(width 0.1524)
				(type default)
			)
			(layer "F.SilkS")
		)
		(fp_line
			(start -0.7874 -0.4064)
			(end 0.7874 -0.4064)
			(stroke
				(width 0.1524)
				(type default)
			)
			(layer "F.SilkS")
		)
		(fp_line
			(start 0.7874 -0.4064)
			(end 0.7874 0.4064)
			(stroke
				(width 0.1524)
				(type default)
			)
			(layer "F.SilkS")
		)
		(fp_line
			(start -0.67945 0.3048)
			(end -0.67945 -0.305054)
			(stroke
				(width 0.1)
				(type default)
			)
			(layer "F.Fab")
		)
		(fp_line
			(start -0.12065 0.3048)
			(end -0.67945 0.3048)
			(stroke
				(width 0.1)
				(type default)
			)
			(layer "F.Fab")
		)
		(fp_line
			(start 0.120396 0.3048)
			(end 0.120396 0.2794)
			(stroke
				(width 0.1)
				(type default)
			)
			(layer "F.Fab")
		)
		(fp_line
			(start 0.67945 0.3048)
			(end 0.120396 0.3048)
			(stroke
				(width 0.1)
				(type default)
			)
			(layer "F.Fab")
		)
		(fp_line
			(start -0.12065 0.2794)
			(end -0.12065 0.3048)
			(stroke
				(width 0.1)
				(type default)
			)
			(layer "F.Fab")
		)
		(fp_line
			(start 0.120396 0.2794)
			(end -0.12065 0.2794)
			(stroke
				(width 0.1)
				(type default)
			)
			(layer "F.Fab")
		)
		(fp_line
			(start -0.12065 -0.2794)
			(end 0.12065 -0.2794)
			(stroke
				(width 0.1)
				(type default)
			)
			(layer "F.Fab")
		)
		(fp_line
			(start 0.12065 -0.2794)
			(end 0.12065 -0.3048)
			(stroke
				(width 0.1)
				(type default)
			)
			(layer "F.Fab")
		)
		(fp_line
			(start 0.12065 -0.3048)
			(end 0.67945 -0.3048)
			(stroke
				(width 0.1)
				(type default)
			)
			(layer "F.Fab")
		)
		(fp_line
			(start 0.67945 -0.3048)
			(end 0.67945 0.3048)
			(stroke
				(width 0.1)
				(type default)
			)
			(layer "F.Fab")
		)
		(fp_line
			(start -0.67945 -0.305054)
			(end -0.12065 -0.305054)
			(stroke
				(width 0.1)
				(type default)
			)
			(layer "F.Fab")
		)
		(fp_line
			(start -0.12065 -0.305054)
			(end -0.12065 -0.2794)
			(stroke
				(width 0.1)
				(type default)
			)
			(layer "F.Fab")
		)
		(pad "1" smd circle
			(at -0.40005 0 270)
			(size 0 0)
			(layers "F.Cu" "F.Mask" "F.Paste")
			(net "FPGA_DEBUG_LED_CTRL")
		)
		(pad "2" smd circle
			(at 0.40005 0 270)
			(size 0 0)
			(layers "F.Cu" "F.Mask" "F.Paste")
			(net "FM_FPGA_DEBUG_LED_CTRL")
		)
	)
	(footprint ""
		(layer "F.Cu")
		(at 103.495348 -382.6764 180)
		(property "Reference" "R795"
			(at 0 0 180)
			(layer "F.SilkS")
			(hide yes)
			(effects
				(font
					(size 1.27 1.27)
				)
			)
		)
		(property "Value" ""
			(at 0 0 180)
			(layer "F.Fab")
			(effects
				(font
					(size 1.27 1.27)
				)
			)
		)
		(duplicate_pad_numbers_are_jumpers no)
		(fp_line
			(start 0.32512 0.175006)
			(end -0.32512 0.175006)
			(stroke
				(width 0.1)
				(type default)
			)
			(layer "F.Fab")
		)
		(fp_line
			(start 0.32512 -0.175006)
			(end 0.32512 0.175006)
			(stroke
				(width 0.1)
				(type default)
			)
			(layer "F.Fab")
		)
		(fp_line
			(start -0.32512 0.175006)
			(end -0.32512 -0.175006)
			(stroke
				(width 0.1)
				(type default)
			)
			(layer "F.Fab")
		)
		(fp_line
			(start -0.32512 -0.175006)
			(end 0.32512 -0.175006)
			(stroke
				(width 0.1)
				(type default)
			)
			(layer "F.Fab")
		)
		(pad "1" smd rect
			(at -0.2667 0 180)
			(size 0.3048 0.381)
			(layers "F.Cu" "F.Mask" "F.Paste")
			(net "P1V8_CPU1_RT_1D")
		)
		(pad "2" smd rect
			(at 0.2667 0)
			(size 0.3048 0.381)
			(layers "F.Cu" "F.Mask" "F.Paste")
			(net "RT_CPU1_P1_ADDR1")
		)
	)
	(footprint ""
		(layer "F.Cu")
		(at 24.917654 -346.719398 -90)
		(property "Reference" "PC618_IOP1_4"
			(at 0 0 270)
			(layer "F.SilkS")
			(hide yes)
			(effects
				(font
					(size 1.27 1.27)
				)
			)
		)
		(property "Value" ""
			(at 0 0 270)
			(layer "F.Fab")
			(effects
				(font
					(size 1.27 1.27)
				)
			)
		)
		(duplicate_pad_numbers_are_jumpers no)
		(fp_line
			(start -0.7874 0.4064)
			(end -0.7874 -0.4064)
			(stroke
				(width 0.1524)
				(type default)
			)
			(layer "F.SilkS")
		)
		(fp_line
			(start 0.7874 0.4064)
			(end -0.7874 0.4064)
			(stroke
				(width 0.1524)
				(type default)
			)
			(layer "F.SilkS")
		)
		(fp_line
			(start -0.7874 -0.4064)
			(end 0.7874 -0.4064)
			(stroke
				(width 0.1524)
				(type default)
			)
			(layer "F.SilkS")
		)
		(fp_line
			(start 0.7874 -0.4064)
			(end 0.7874 0.4064)
			(stroke
				(width 0.1524)
				(type default)
			)
			(layer "F.SilkS")
		)
		(fp_line
			(start -0.67945 0.3048)
			(end -0.67945 -0.305054)
			(stroke
				(width 0.1)
				(type default)
			)
			(layer "F.Fab")
		)
		(fp_line
			(start -0.12065 0.3048)
			(end -0.67945 0.3048)
			(stroke
				(width 0.1)
				(type default)
			)
			(layer "F.Fab")
		)
		(fp_line
			(start 0.120396 0.3048)
			(end 0.120396 0.2794)
			(stroke
				(width 0.1)
				(type default)
			)
			(layer "F.Fab")
		)
		(fp_line
			(start 0.67945 0.3048)
			(end 0.120396 0.3048)
			(stroke
				(width 0.1)
				(type default)
			)
			(layer "F.Fab")
		)
		(fp_line
			(start -0.12065 0.2794)
			(end -0.12065 0.3048)
			(stroke
				(width 0.1)
				(type default)
			)
			(layer "F.Fab")
		)
		(fp_line
			(start 0.120396 0.2794)
			(end -0.12065 0.2794)
			(stroke
				(width 0.1)
				(type default)
			)
			(layer "F.Fab")
		)
		(fp_line
			(start -0.12065 -0.2794)
			(end 0.12065 -0.2794)
			(stroke
				(width 0.1)
				(type default)
			)
			(layer "F.Fab")
		)
		(fp_line
			(start 0.12065 -0.2794)
			(end 0.12065 -0.3048)
			(stroke
				(width 0.1)
				(type default)
			)
			(layer "F.Fab")
		)
		(fp_line
			(start 0.12065 -0.3048)
			(end 0.67945 -0.3048)
			(stroke
				(width 0.1)
				(type default)
			)
			(layer "F.Fab")
		)
		(fp_line
			(start 0.67945 -0.3048)
			(end 0.67945 0.3048)
			(stroke
				(width 0.1)
				(type default)
			)
			(layer "F.Fab")
		)
		(fp_line
			(start -0.67945 -0.305054)
			(end -0.12065 -0.305054)
			(stroke
				(width 0.1)
				(type default)
			)
			(layer "F.Fab")
		)
		(fp_line
			(start -0.12065 -0.305054)
			(end -0.12065 -0.2794)
			(stroke
				(width 0.1)
				(type default)
			)
			(layer "F.Fab")
		)
		(pad "1" smd circle
			(at -0.40005 0 270)
			(size 0 0)
			(layers "F.Cu" "F.Mask" "F.Paste")
			(net "PVDDCR_CPU1_P1_PVCC")
		)
		(pad "2" smd circle
			(at 0.40005 0 270)
			(size 0 0)
			(layers "F.Cu" "F.Mask" "F.Paste")
			(net "GND")
		)
	)
	(footprint ""
		(layer "F.Cu")
		(at 83.157314 -138.562334)
		(property "Reference" "R703"
			(at 0 0 0)
			(layer "F.SilkS")
			(hide yes)
			(effects
				(font
					(size 1.27 1.27)
				)
			)
		)
		(property "Value" ""
			(at 0 0 0)
			(layer "F.Fab")
			(effects
				(font
					(size 1.27 1.27)
				)
			)
		)
		(duplicate_pad_numbers_are_jumpers no)
		(fp_line
			(start -0.7874 -0.4064)
			(end 0.7874 -0.4064)
			(stroke
				(width 0.1524)
				(type default)
			)
			(layer "F.SilkS")
		)
		(fp_line
			(start -0.7874 0.4064)
			(end -0.7874 -0.4064)
			(stroke
				(width 0.1524)
				(type default)
			)
			(layer "F.SilkS")
		)
		(fp_line
			(start 0.7874 -0.4064)
			(end 0.7874 0.4064)
			(stroke
				(width 0.1524)
				(type default)
			)
			(layer "F.SilkS")
		)
		(fp_line
			(start 0.7874 0.4064)
			(end -0.7874 0.4064)
			(stroke
				(width 0.1524)
				(type default)
			)
			(layer "F.SilkS")
		)
		(fp_line
			(start -0.67945 -0.305054)
			(end -0.12065 -0.305054)
			(stroke
				(width 0.1)
				(type default)
			)
			(layer "F.Fab")
		)
		(fp_line
			(start -0.67945 0.3048)
			(end -0.67945 -0.305054)
			(stroke
				(width 0.1)
				(type default)
			)
			(layer "F.Fab")
		)
		(fp_line
			(start -0.12065 -0.305054)
			(end -0.12065 -0.2794)
			(stroke
				(width 0.1)
				(type default)
			)
			(layer "F.Fab")
		)
		(fp_line
			(start -0.12065 -0.2794)
			(end 0.12065 -0.2794)
			(stroke
				(width 0.1)
				(type default)
			)
			(layer "F.Fab")
		)
		(fp_line
			(start -0.12065 0.2794)
			(end -0.12065 0.3048)
			(stroke
				(width 0.1)
				(type default)
			)
			(layer "F.Fab")
		)
		(fp_line
			(start -0.12065 0.3048)
			(end -0.67945 0.3048)
			(stroke
				(width 0.1)
				(type default)
			)
			(layer "F.Fab")
		)
		(fp_line
			(start 0.120396 0.2794)
			(end -0.12065 0.2794)
			(stroke
				(width 0.1)
				(type default)
			)
			(layer "F.Fab")
		)
		(fp_line
			(start 0.120396 0.3048)
			(end 0.120396 0.2794)
			(stroke
				(width 0.1)
				(type default)
			)
			(layer "F.Fab")
		)
		(fp_line
			(start 0.12065 -0.3048)
			(end 0.67945 -0.3048)
			(stroke
				(width 0.1)
				(type default)
			)
			(layer "F.Fab")
		)
		(fp_line
			(start 0.12065 -0.2794)
			(end 0.12065 -0.3048)
			(stroke
				(width 0.1)
				(type default)
			)
			(layer "F.Fab")
		)
		(fp_line
			(start 0.67945 -0.3048)
			(end 0.67945 0.3048)
			(stroke
				(width 0.1)
				(type default)
			)
			(layer "F.Fab")
		)
		(fp_line
			(start 0.67945 0.3048)
			(end 0.120396 0.3048)
			(stroke
				(width 0.1)
				(type default)
			)
			(layer "F.Fab")
		)
		(pad "1" smd circle
			(at -0.40005 0)
			(size 0 0)
			(layers "F.Cu" "F.Mask" "F.Paste")
			(net "PWRGD_CPU1_PWROK")
		)
		(pad "2" smd circle
			(at 0.40005 0)
			(size 0 0)
			(layers "F.Cu" "F.Mask" "F.Paste")
			(net "GND")
		)
	)
	(footprint ""
		(layer "F.Cu")
		(at 114.299238 -39.40175 -90)
		(property "Reference" "R6286"
			(at 0 0 270)
			(layer "F.SilkS")
			(hide yes)
			(effects
				(font
					(size 1.27 1.27)
				)
			)
		)
		(property "Value" ""
			(at 0 0 270)
			(layer "F.Fab")
			(effects
				(font
					(size 1.27 1.27)
				)
			)
		)
		(duplicate_pad_numbers_are_jumpers no)
		(fp_line
			(start -0.7874 0.4064)
			(end -0.7874 -0.4064)
			(stroke
				(width 0.1524)
				(type default)
			)
			(layer "F.SilkS")
		)
		(fp_line
			(start 0.7874 0.4064)
			(end -0.7874 0.4064)
			(stroke
				(width 0.1524)
				(type default)
			)
			(layer "F.SilkS")
		)
		(fp_line
			(start -0.7874 -0.4064)
			(end 0.7874 -0.4064)
			(stroke
				(width 0.1524)
				(type default)
			)
			(layer "F.SilkS")
		)
		(fp_line
			(start 0.7874 -0.4064)
			(end 0.7874 0.4064)
			(stroke
				(width 0.1524)
				(type default)
			)
			(layer "F.SilkS")
		)
		(fp_line
			(start -0.67945 0.3048)
			(end -0.67945 -0.305054)
			(stroke
				(width 0.1)
				(type default)
			)
			(layer "F.Fab")
		)
		(fp_line
			(start -0.12065 0.3048)
			(end -0.67945 0.3048)
			(stroke
				(width 0.1)
				(type default)
			)
			(layer "F.Fab")
		)
		(fp_line
			(start 0.120396 0.3048)
			(end 0.120396 0.2794)
			(stroke
				(width 0.1)
				(type default)
			)
			(layer "F.Fab")
		)
		(fp_line
			(start 0.67945 0.3048)
			(end 0.120396 0.3048)
			(stroke
				(width 0.1)
				(type default)
			)
			(layer "F.Fab")
		)
		(fp_line
			(start -0.12065 0.2794)
			(end -0.12065 0.3048)
			(stroke
				(width 0.1)
				(type default)
			)
			(layer "F.Fab")
		)
		(fp_line
			(start 0.120396 0.2794)
			(end -0.12065 0.2794)
			(stroke
				(width 0.1)
				(type default)
			)
			(layer "F.Fab")
		)
		(fp_line
			(start -0.12065 -0.2794)
			(end 0.12065 -0.2794)
			(stroke
				(width 0.1)
				(type default)
			)
			(layer "F.Fab")
		)
		(fp_line
			(start 0.12065 -0.2794)
			(end 0.12065 -0.3048)
			(stroke
				(width 0.1)
				(type default)
			)
			(layer "F.Fab")
		)
		(fp_line
			(start 0.12065 -0.3048)
			(end 0.67945 -0.3048)
			(stroke
				(width 0.1)
				(type default)
			)
			(layer "F.Fab")
		)
		(fp_line
			(start 0.67945 -0.3048)
			(end 0.67945 0.3048)
			(stroke
				(width 0.1)
				(type default)
			)
			(layer "F.Fab")
		)
		(fp_line
			(start -0.67945 -0.305054)
			(end -0.12065 -0.305054)
			(stroke
				(width 0.1)
				(type default)
			)
			(layer "F.Fab")
		)
		(fp_line
			(start -0.12065 -0.305054)
			(end -0.12065 -0.2794)
			(stroke
				(width 0.1)
				(type default)
			)
			(layer "F.Fab")
		)
		(pad "1" smd circle
			(at -0.40005 0 270)
			(size 0 0)
			(layers "F.Cu" "F.Mask" "F.Paste")
			(net "USB_HUB2_MRP_VBUS_DET")
		)
		(pad "2" smd circle
			(at 0.40005 0 270)
			(size 0 0)
			(layers "F.Cu" "F.Mask" "F.Paste")
			(net "USB_HUB2_TI_PWRCTL_POL_MRP_VBUS_DET")
		)
	)
	(footprint ""
		(layer "F.Cu")
		(at 429.299116 -109.26699 -90)
		(property "Reference" "PR3789"
			(at 0 0 270)
			(layer "F.SilkS")
			(hide yes)
			(effects
				(font
					(size 1.27 1.27)
				)
			)
		)
		(property "Value" ""
			(at 0 0 270)
			(layer "F.Fab")
			(effects
				(font
					(size 1.27 1.27)
				)
			)
		)
		(duplicate_pad_numbers_are_jumpers no)
		(fp_line
			(start -0.7874 0.4064)
			(end -0.7874 -0.4064)
			(stroke
				(width 0.1524)
				(type default)
			)
			(layer "F.SilkS")
		)
		(fp_line
			(start 0.7874 0.4064)
			(end -0.7874 0.4064)
			(stroke
				(width 0.1524)
				(type default)
			)
			(layer "F.SilkS")
		)
		(fp_line
			(start -0.7874 -0.4064)
			(end 0.7874 -0.4064)
			(stroke
				(width 0.1524)
				(type default)
			)
			(layer "F.SilkS")
		)
		(fp_line
			(start 0.7874 -0.4064)
			(end 0.7874 0.4064)
			(stroke
				(width 0.1524)
				(type default)
			)
			(layer "F.SilkS")
		)
		(fp_line
			(start -0.67945 0.3048)
			(end -0.67945 -0.305054)
			(stroke
				(width 0.1)
				(type default)
			)
			(layer "F.Fab")
		)
		(fp_line
			(start -0.12065 0.3048)
			(end -0.67945 0.3048)
			(stroke
				(width 0.1)
				(type default)
			)
			(layer "F.Fab")
		)
		(fp_line
			(start 0.120396 0.3048)
			(end 0.120396 0.2794)
			(stroke
				(width 0.1)
				(type default)
			)
			(layer "F.Fab")
		)
		(fp_line
			(start 0.67945 0.3048)
			(end 0.120396 0.3048)
			(stroke
				(width 0.1)
				(type default)
			)
			(layer "F.Fab")
		)
		(fp_line
			(start -0.12065 0.2794)
			(end -0.12065 0.3048)
			(stroke
				(width 0.1)
				(type default)
			)
			(layer "F.Fab")
		)
		(fp_line
			(start 0.120396 0.2794)
			(end -0.12065 0.2794)
			(stroke
				(width 0.1)
				(type default)
			)
			(layer "F.Fab")
		)
		(fp_line
			(start -0.12065 -0.2794)
			(end 0.12065 -0.2794)
			(stroke
				(width 0.1)
				(type default)
			)
			(layer "F.Fab")
		)
		(fp_line
			(start 0.12065 -0.2794)
			(end 0.12065 -0.3048)
			(stroke
				(width 0.1)
				(type default)
			)
			(layer "F.Fab")
		)
		(fp_line
			(start 0.12065 -0.3048)
			(end 0.67945 -0.3048)
			(stroke
				(width 0.1)
				(type default)
			)
			(layer "F.Fab")
		)
		(fp_line
			(start 0.67945 -0.3048)
			(end 0.67945 0.3048)
			(stroke
				(width 0.1)
				(type default)
			)
			(layer "F.Fab")
		)
		(fp_line
			(start -0.67945 -0.305054)
			(end -0.12065 -0.305054)
			(stroke
				(width 0.1)
				(type default)
			)
			(layer "F.Fab")
		)
		(fp_line
			(start -0.12065 -0.305054)
			(end -0.12065 -0.2794)
			(stroke
				(width 0.1)
				(type default)
			)
			(layer "F.Fab")
		)
		(pad "1" smd circle
			(at -0.40005 0 270)
			(size 0 0)
			(layers "F.Cu" "F.Mask" "F.Paste")
			(net "P3V3_AUX")
		)
		(pad "2" smd circle
			(at 0.40005 0 270)
			(size 0 0)
			(layers "F.Cu" "F.Mask" "F.Paste")
			(net "P3V3_OCP_UV_1")
		)
	)
	(footprint ""
		(layer "F.Cu")
		(at 212.993732 -111.646208 180)
		(property "Reference" "R134"
			(at 0 0 180)
			(layer "F.SilkS")
			(hide yes)
			(effects
				(font
					(size 1.27 1.27)
				)
			)
		)
		(property "Value" ""
			(at 0 0 180)
			(layer "F.Fab")
			(effects
				(font
					(size 1.27 1.27)
				)
			)
		)
		(duplicate_pad_numbers_are_jumpers no)
		(fp_line
			(start 0.7874 0.4064)
			(end -0.7874 0.4064)
			(stroke
				(width 0.1524)
				(type default)
			)
			(layer "F.SilkS")
		)
		(fp_line
			(start 0.7874 -0.4064)
			(end 0.7874 0.4064)
			(stroke
				(width 0.1524)
				(type default)
			)
			(layer "F.SilkS")
		)
		(fp_line
			(start -0.7874 0.4064)
			(end -0.7874 -0.4064)
			(stroke
				(width 0.1524)
				(type default)
			)
			(layer "F.SilkS")
		)
		(fp_line
			(start -0.7874 -0.4064)
			(end 0.7874 -0.4064)
			(stroke
				(width 0.1524)
				(type default)
			)
			(layer "F.SilkS")
		)
		(fp_line
			(start 0.67945 0.3048)
			(end 0.120396 0.3048)
			(stroke
				(width 0.1)
				(type default)
			)
			(layer "F.Fab")
		)
		(fp_line
			(start 0.67945 -0.3048)
			(end 0.67945 0.3048)
			(stroke
				(width 0.1)
				(type default)
			)
			(layer "F.Fab")
		)
		(fp_line
			(start 0.12065 -0.2794)
			(end 0.12065 -0.3048)
			(stroke
				(width 0.1)
				(type default)
			)
			(layer "F.Fab")
		)
		(fp_line
			(start 0.12065 -0.3048)
			(end 0.67945 -0.3048)
			(stroke
				(width 0.1)
				(type default)
			)
			(layer "F.Fab")
		)
		(fp_line
			(start 0.120396 0.3048)
			(end 0.120396 0.2794)
			(stroke
				(width 0.1)
				(type default)
			)
			(layer "F.Fab")
		)
		(fp_line
			(start 0.120396 0.2794)
			(end -0.12065 0.2794)
			(stroke
				(width 0.1)
				(type default)
			)
			(layer "F.Fab")
		)
		(fp_line
			(start -0.12065 0.3048)
			(end -0.67945 0.3048)
			(stroke
				(width 0.1)
				(type default)
			)
			(layer "F.Fab")
		)
		(fp_line
			(start -0.12065 0.2794)
			(end -0.12065 0.3048)
			(stroke
				(width 0.1)
				(type default)
			)
			(layer "F.Fab")
		)
		(fp_line
			(start -0.12065 -0.2794)
			(end 0.12065 -0.2794)
			(stroke
				(width 0.1)
				(type default)
			)
			(layer "F.Fab")
		)
		(fp_line
			(start -0.12065 -0.305054)
			(end -0.12065 -0.2794)
			(stroke
				(width 0.1)
				(type default)
			)
			(layer "F.Fab")
		)
		(fp_line
			(start -0.67945 0.3048)
			(end -0.67945 -0.305054)
			(stroke
				(width 0.1)
				(type default)
			)
			(layer "F.Fab")
		)
		(fp_line
			(start -0.67945 -0.305054)
			(end -0.12065 -0.305054)
			(stroke
				(width 0.1)
				(type default)
			)
			(layer "F.Fab")
		)
		(pad "1" smd circle
			(at -0.40005 0 180)
			(size 0 0)
			(layers "F.Cu" "F.Mask" "F.Paste")
			(net "FM_APML_MUX2_OE_N")
		)
		(pad "2" smd circle
			(at 0.40005 0 180)
			(size 0 0)
			(layers "F.Cu" "F.Mask" "F.Paste")
			(net "P3V3_AUX")
		)
	)
	(footprint ""
		(layer "F.Cu")
		(at 9.74471 -70.560692)
		(property "Reference" "R3136"
			(at 0 0 0)
			(layer "F.SilkS")
			(hide yes)
			(effects
				(font
					(size 1.27 1.27)
				)
			)
		)
		(property "Value" ""
			(at 0 0 0)
			(layer "F.Fab")
			(effects
				(font
					(size 1.27 1.27)
				)
			)
		)
		(duplicate_pad_numbers_are_jumpers no)
		(fp_line
			(start -0.7874 -0.4064)
			(end 0.7874 -0.4064)
			(stroke
				(width 0.1524)
				(type default)
			)
			(layer "F.SilkS")
		)
		(fp_line
			(start -0.7874 0.4064)
			(end -0.7874 -0.4064)
			(stroke
				(width 0.1524)
				(type default)
			)
			(layer "F.SilkS")
		)
		(fp_line
			(start 0.7874 -0.4064)
			(end 0.7874 0.4064)
			(stroke
				(width 0.1524)
				(type default)
			)
			(layer "F.SilkS")
		)
		(fp_line
			(start 0.7874 0.4064)
			(end -0.7874 0.4064)
			(stroke
				(width 0.1524)
				(type default)
			)
			(layer "F.SilkS")
		)
		(fp_line
			(start -0.67945 -0.305054)
			(end -0.12065 -0.305054)
			(stroke
				(width 0.1)
				(type default)
			)
			(layer "F.Fab")
		)
		(fp_line
			(start -0.67945 0.3048)
			(end -0.67945 -0.305054)
			(stroke
				(width 0.1)
				(type default)
			)
			(layer "F.Fab")
		)
		(fp_line
			(start -0.12065 -0.305054)
			(end -0.12065 -0.2794)
			(stroke
				(width 0.1)
				(type default)
			)
			(layer "F.Fab")
		)
		(fp_line
			(start -0.12065 -0.2794)
			(end 0.12065 -0.2794)
			(stroke
				(width 0.1)
				(type default)
			)
			(layer "F.Fab")
		)
		(fp_line
			(start -0.12065 0.2794)
			(end -0.12065 0.3048)
			(stroke
				(width 0.1)
				(type default)
			)
			(layer "F.Fab")
		)
		(fp_line
			(start -0.12065 0.3048)
			(end -0.67945 0.3048)
			(stroke
				(width 0.1)
				(type default)
			)
			(layer "F.Fab")
		)
		(fp_line
			(start 0.120396 0.2794)
			(end -0.12065 0.2794)
			(stroke
				(width 0.1)
				(type default)
			)
			(layer "F.Fab")
		)
		(fp_line
			(start 0.120396 0.3048)
			(end 0.120396 0.2794)
			(stroke
				(width 0.1)
				(type default)
			)
			(layer "F.Fab")
		)
		(fp_line
			(start 0.12065 -0.3048)
			(end 0.67945 -0.3048)
			(stroke
				(width 0.1)
				(type default)
			)
			(layer "F.Fab")
		)
		(fp_line
			(start 0.12065 -0.2794)
			(end 0.12065 -0.3048)
			(stroke
				(width 0.1)
				(type default)
			)
			(layer "F.Fab")
		)
		(fp_line
			(start 0.67945 -0.3048)
			(end 0.67945 0.3048)
			(stroke
				(width 0.1)
				(type default)
			)
			(layer "F.Fab")
		)
		(fp_line
			(start 0.67945 0.3048)
			(end 0.120396 0.3048)
			(stroke
				(width 0.1)
				(type default)
			)
			(layer "F.Fab")
		)
		(pad "1" smd circle
			(at -0.40005 0)
			(size 0 0)
			(layers "F.Cu" "F.Mask" "F.Paste")
			(net "P3V3_AUX")
		)
		(pad "2" smd circle
			(at 0.40005 0)
			(size 0 0)
			(layers "F.Cu" "F.Mask" "F.Paste")
			(net "OCP_V3_2_PRSNT3_R_N")
		)
	)
	(footprint ""
		(layer "F.Cu")
		(at 208.894426 -112.662208 180)
		(property "Reference" "R5099"
			(at 0 0 180)
			(layer "F.SilkS")
			(hide yes)
			(effects
				(font
					(size 1.27 1.27)
				)
			)
		)
		(property "Value" ""
			(at 0 0 180)
			(layer "F.Fab")
			(effects
				(font
					(size 1.27 1.27)
				)
			)
		)
		(duplicate_pad_numbers_are_jumpers no)
		(fp_line
			(start 0.7874 0.4064)
			(end -0.7874 0.4064)
			(stroke
				(width 0.1524)
				(type default)
			)
			(layer "F.SilkS")
		)
		(fp_line
			(start 0.7874 -0.4064)
			(end 0.7874 0.4064)
			(stroke
				(width 0.1524)
				(type default)
			)
			(layer "F.SilkS")
		)
		(fp_line
			(start -0.7874 0.4064)
			(end -0.7874 -0.4064)
			(stroke
				(width 0.1524)
				(type default)
			)
			(layer "F.SilkS")
		)
		(fp_line
			(start -0.7874 -0.4064)
			(end 0.7874 -0.4064)
			(stroke
				(width 0.1524)
				(type default)
			)
			(layer "F.SilkS")
		)
		(fp_line
			(start 0.67945 0.3048)
			(end 0.120396 0.3048)
			(stroke
				(width 0.1)
				(type default)
			)
			(layer "F.Fab")
		)
		(fp_line
			(start 0.67945 -0.3048)
			(end 0.67945 0.3048)
			(stroke
				(width 0.1)
				(type default)
			)
			(layer "F.Fab")
		)
		(fp_line
			(start 0.12065 -0.2794)
			(end 0.12065 -0.3048)
			(stroke
				(width 0.1)
				(type default)
			)
			(layer "F.Fab")
		)
		(fp_line
			(start 0.12065 -0.3048)
			(end 0.67945 -0.3048)
			(stroke
				(width 0.1)
				(type default)
			)
			(layer "F.Fab")
		)
		(fp_line
			(start 0.120396 0.3048)
			(end 0.120396 0.2794)
			(stroke
				(width 0.1)
				(type default)
			)
			(layer "F.Fab")
		)
		(fp_line
			(start 0.120396 0.2794)
			(end -0.12065 0.2794)
			(stroke
				(width 0.1)
				(type default)
			)
			(layer "F.Fab")
		)
		(fp_line
			(start -0.12065 0.3048)
			(end -0.67945 0.3048)
			(stroke
				(width 0.1)
				(type default)
			)
			(layer "F.Fab")
		)
		(fp_line
			(start -0.12065 0.2794)
			(end -0.12065 0.3048)
			(stroke
				(width 0.1)
				(type default)
			)
			(layer "F.Fab")
		)
		(fp_line
			(start -0.12065 -0.2794)
			(end 0.12065 -0.2794)
			(stroke
				(width 0.1)
				(type default)
			)
			(layer "F.Fab")
		)
		(fp_line
			(start -0.12065 -0.305054)
			(end -0.12065 -0.2794)
			(stroke
				(width 0.1)
				(type default)
			)
			(layer "F.Fab")
		)
		(fp_line
			(start -0.67945 0.3048)
			(end -0.67945 -0.305054)
			(stroke
				(width 0.1)
				(type default)
			)
			(layer "F.Fab")
		)
		(fp_line
			(start -0.67945 -0.305054)
			(end -0.12065 -0.305054)
			(stroke
				(width 0.1)
				(type default)
			)
			(layer "F.Fab")
		)
		(pad "1" smd circle
			(at -0.40005 0 180)
			(size 0 0)
			(layers "F.Cu" "F.Mask" "F.Paste")
			(net "FPGA_DEBUG_SW_SPARE")
		)
		(pad "2" smd circle
			(at 0.40005 0 180)
			(size 0 0)
			(layers "F.Cu" "F.Mask" "F.Paste")
			(net "FM_FPGA_DEBUG_SW_SPARE")
		)
	)
	(footprint ""
		(layer "F.Cu")
		(at 331.662532 -141.36243)
		(property "Reference" "PR417"
			(at 0 0 0)
			(layer "F.SilkS")
			(hide yes)
			(effects
				(font
					(size 1.27 1.27)
				)
			)
		)
		(property "Value" ""
			(at 0 0 0)
			(layer "F.Fab")
			(effects
				(font
					(size 1.27 1.27)
				)
			)
		)
		(duplicate_pad_numbers_are_jumpers no)
		(fp_line
			(start -0.7874 -0.4064)
			(end 0.7874 -0.4064)
			(stroke
				(width 0.1524)
				(type default)
			)
			(layer "F.SilkS")
		)
		(fp_line
			(start -0.7874 0.4064)
			(end -0.7874 -0.4064)
			(stroke
				(width 0.1524)
				(type default)
			)
			(layer "F.SilkS")
		)
		(fp_line
			(start 0.7874 -0.4064)
			(end 0.7874 0.4064)
			(stroke
				(width 0.1524)
				(type default)
			)
			(layer "F.SilkS")
		)
		(fp_line
			(start 0.7874 0.4064)
			(end -0.7874 0.4064)
			(stroke
				(width 0.1524)
				(type default)
			)
			(layer "F.SilkS")
		)
		(fp_line
			(start -0.67945 -0.305054)
			(end -0.12065 -0.305054)
			(stroke
				(width 0.1)
				(type default)
			)
			(layer "F.Fab")
		)
		(fp_line
			(start -0.67945 0.3048)
			(end -0.67945 -0.305054)
			(stroke
				(width 0.1)
				(type default)
			)
			(layer "F.Fab")
		)
		(fp_line
			(start -0.12065 -0.305054)
			(end -0.12065 -0.2794)
			(stroke
				(width 0.1)
				(type default)
			)
			(layer "F.Fab")
		)
		(fp_line
			(start -0.12065 -0.2794)
			(end 0.12065 -0.2794)
			(stroke
				(width 0.1)
				(type default)
			)
			(layer "F.Fab")
		)
		(fp_line
			(start -0.12065 0.2794)
			(end -0.12065 0.3048)
			(stroke
				(width 0.1)
				(type default)
			)
			(layer "F.Fab")
		)
		(fp_line
			(start -0.12065 0.3048)
			(end -0.67945 0.3048)
			(stroke
				(width 0.1)
				(type default)
			)
			(layer "F.Fab")
		)
		(fp_line
			(start 0.120396 0.2794)
			(end -0.12065 0.2794)
			(stroke
				(width 0.1)
				(type default)
			)
			(layer "F.Fab")
		)
		(fp_line
			(start 0.120396 0.3048)
			(end 0.120396 0.2794)
			(stroke
				(width 0.1)
				(type default)
			)
			(layer "F.Fab")
		)
		(fp_line
			(start 0.12065 -0.3048)
			(end 0.67945 -0.3048)
			(stroke
				(width 0.1)
				(type default)
			)
			(layer "F.Fab")
		)
		(fp_line
			(start 0.12065 -0.2794)
			(end 0.12065 -0.3048)
			(stroke
				(width 0.1)
				(type default)
			)
			(layer "F.Fab")
		)
		(fp_line
			(start 0.67945 -0.3048)
			(end 0.67945 0.3048)
			(stroke
				(width 0.1)
				(type default)
			)
			(layer "F.Fab")
		)
		(fp_line
			(start 0.67945 0.3048)
			(end 0.120396 0.3048)
			(stroke
				(width 0.1)
				(type default)
			)
			(layer "F.Fab")
		)
		(pad "1" smd circle
			(at -0.40005 0)
			(size 0 0)
			(layers "F.Cu" "F.Mask" "F.Paste")
			(net "GND")
		)
		(pad "2" smd circle
			(at 0.40005 0)
			(size 0 0)
			(layers "F.Cu" "F.Mask" "F.Paste")
			(net "PVDD18_S5_P0_MODE")
		)
	)
	(footprint ""
		(layer "F.Cu")
		(at 101.948234 -141.20241 180)
		(property "Reference" "PR181"
			(at 0 0 180)
			(layer "F.SilkS")
			(hide yes)
			(effects
				(font
					(size 1.27 1.27)
				)
			)
		)
		(property "Value" ""
			(at 0 0 180)
			(layer "F.Fab")
			(effects
				(font
					(size 1.27 1.27)
				)
			)
		)
		(duplicate_pad_numbers_are_jumpers no)
		(fp_line
			(start 0.7874 0.4064)
			(end -0.7874 0.4064)
			(stroke
				(width 0.1524)
				(type default)
			)
			(layer "F.SilkS")
		)
		(fp_line
			(start 0.7874 -0.4064)
			(end 0.7874 0.4064)
			(stroke
				(width 0.1524)
				(type default)
			)
			(layer "F.SilkS")
		)
		(fp_line
			(start -0.7874 0.4064)
			(end -0.7874 -0.4064)
			(stroke
				(width 0.1524)
				(type default)
			)
			(layer "F.SilkS")
		)
		(fp_line
			(start -0.7874 -0.4064)
			(end 0.7874 -0.4064)
			(stroke
				(width 0.1524)
				(type default)
			)
			(layer "F.SilkS")
		)
		(fp_line
			(start 0.67945 0.3048)
			(end 0.120396 0.3048)
			(stroke
				(width 0.1)
				(type default)
			)
			(layer "F.Fab")
		)
		(fp_line
			(start 0.67945 -0.3048)
			(end 0.67945 0.3048)
			(stroke
				(width 0.1)
				(type default)
			)
			(layer "F.Fab")
		)
		(fp_line
			(start 0.12065 -0.2794)
			(end 0.12065 -0.3048)
			(stroke
				(width 0.1)
				(type default)
			)
			(layer "F.Fab")
		)
		(fp_line
			(start 0.12065 -0.3048)
			(end 0.67945 -0.3048)
			(stroke
				(width 0.1)
				(type default)
			)
			(layer "F.Fab")
		)
		(fp_line
			(start 0.120396 0.3048)
			(end 0.120396 0.2794)
			(stroke
				(width 0.1)
				(type default)
			)
			(layer "F.Fab")
		)
		(fp_line
			(start 0.120396 0.2794)
			(end -0.12065 0.2794)
			(stroke
				(width 0.1)
				(type default)
			)
			(layer "F.Fab")
		)
		(fp_line
			(start -0.12065 0.3048)
			(end -0.67945 0.3048)
			(stroke
				(width 0.1)
				(type default)
			)
			(layer "F.Fab")
		)
		(fp_line
			(start -0.12065 0.2794)
			(end -0.12065 0.3048)
			(stroke
				(width 0.1)
				(type default)
			)
			(layer "F.Fab")
		)
		(fp_line
			(start -0.12065 -0.2794)
			(end 0.12065 -0.2794)
			(stroke
				(width 0.1)
				(type default)
			)
			(layer "F.Fab")
		)
		(fp_line
			(start -0.12065 -0.305054)
			(end -0.12065 -0.2794)
			(stroke
				(width 0.1)
				(type default)
			)
			(layer "F.Fab")
		)
		(fp_line
			(start -0.67945 0.3048)
			(end -0.67945 -0.305054)
			(stroke
				(width 0.1)
				(type default)
			)
			(layer "F.Fab")
		)
		(fp_line
			(start -0.67945 -0.305054)
			(end -0.12065 -0.305054)
			(stroke
				(width 0.1)
				(type default)
			)
			(layer "F.Fab")
		)
		(pad "1" smd circle
			(at -0.40005 0 180)
			(size 0 0)
			(layers "F.Cu" "F.Mask" "F.Paste")
			(net "P12V_AUX")
		)
		(pad "2" smd circle
			(at 0.40005 0 180)
			(size 0 0)
			(layers "F.Cu" "F.Mask" "F.Paste")
			(net "PVDDCR_CPU0_P1_VINSEN")
		)
	)
	(footprint ""
		(layer "F.Cu")
		(at 203.573126 -344.92692)
		(property "Reference" "PC123"
			(at 0 0 0)
			(layer "F.SilkS")
			(hide yes)
			(effects
				(font
					(size 1.27 1.27)
				)
			)
		)
		(property "Value" ""
			(at 0 0 0)
			(layer "F.Fab")
			(effects
				(font
					(size 1.27 1.27)
				)
			)
		)
		(duplicate_pad_numbers_are_jumpers no)
		(fp_line
			(start -1.524 -0.762)
			(end 1.524 -0.762)
			(stroke
				(width 0.1524)
				(type default)
			)
			(layer "F.SilkS")
		)
		(fp_line
			(start -1.524 0.762)
			(end -1.524 -0.762)
			(stroke
				(width 0.1524)
				(type default)
			)
			(layer "F.SilkS")
		)
		(fp_line
			(start 1.524 -0.762)
			(end 1.524 0.762)
			(stroke
				(width 0.1524)
				(type default)
			)
			(layer "F.SilkS")
		)
		(fp_line
			(start 1.524 0.762)
			(end -1.524 0.762)
			(stroke
				(width 0.1524)
				(type default)
			)
			(layer "F.SilkS")
		)
		(fp_line
			(start -1.1049 -0.724916)
			(end -1.1049 0.724916)
			(stroke
				(width 0.1)
				(type default)
			)
			(layer "F.Fab")
		)
		(fp_line
			(start -1.1049 0.724916)
			(end 1.1049 0.724916)
			(stroke
				(width 0.1)
				(type default)
			)
			(layer "F.Fab")
		)
		(fp_line
			(start 1.1049 -0.724916)
			(end -1.1049 -0.724916)
			(stroke
				(width 0.1)
				(type default)
			)
			(layer "F.Fab")
		)
		(fp_line
			(start 1.1049 0.724916)
			(end 1.1049 -0.724916)
			(stroke
				(width 0.1)
				(type default)
			)
			(layer "F.Fab")
		)
		(pad "1" smd rect
			(at -0.889 0 180)
			(size 1.016 1.27)
			(layers "F.Cu" "F.Mask" "F.Paste")
			(net "SW_P12V_AUX_PVDD_33_S5_FLT")
		)
		(pad "2" smd rect
			(at 0.889 0 180)
			(size 1.016 1.27)
			(layers "F.Cu" "F.Mask" "F.Paste")
			(net "GND")
		)
	)
	(footprint ""
		(layer "F.Cu")
		(at 270.48841 -332.609952 90)
		(property "Reference" "PC107"
			(at 0 0 90)
			(layer "F.SilkS")
			(hide yes)
			(effects
				(font
					(size 1.27 1.27)
				)
			)
		)
		(property "Value" ""
			(at 0 0 90)
			(layer "F.Fab")
			(effects
				(font
					(size 1.27 1.27)
				)
			)
		)
		(duplicate_pad_numbers_are_jumpers no)
		(fp_line
			(start 0.7874 -0.4064)
			(end 0.7874 0.4064)
			(stroke
				(width 0.1524)
				(type default)
			)
			(layer "F.SilkS")
		)
		(fp_line
			(start -0.7874 -0.4064)
			(end 0.7874 -0.4064)
			(stroke
				(width 0.1524)
				(type default)
			)
			(layer "F.SilkS")
		)
		(fp_line
			(start 0.7874 0.4064)
			(end -0.7874 0.4064)
			(stroke
				(width 0.1524)
				(type default)
			)
			(layer "F.SilkS")
		)
		(fp_line
			(start -0.7874 0.4064)
			(end -0.7874 -0.4064)
			(stroke
				(width 0.1524)
				(type default)
			)
			(layer "F.SilkS")
		)
		(fp_line
			(start -0.12065 -0.305054)
			(end -0.12065 -0.2794)
			(stroke
				(width 0.1)
				(type default)
			)
			(layer "F.Fab")
		)
		(fp_line
			(start -0.67945 -0.305054)
			(end -0.12065 -0.305054)
			(stroke
				(width 0.1)
				(type default)
			)
			(layer "F.Fab")
		)
		(fp_line
			(start 0.67945 -0.3048)
			(end 0.67945 0.3048)
			(stroke
				(width 0.1)
				(type default)
			)
			(layer "F.Fab")
		)
		(fp_line
			(start 0.12065 -0.3048)
			(end 0.67945 -0.3048)
			(stroke
				(width 0.1)
				(type default)
			)
			(layer "F.Fab")
		)
		(fp_line
			(start 0.12065 -0.2794)
			(end 0.12065 -0.3048)
			(stroke
				(width 0.1)
				(type default)
			)
			(layer "F.Fab")
		)
		(fp_line
			(start -0.12065 -0.2794)
			(end 0.12065 -0.2794)
			(stroke
				(width 0.1)
				(type default)
			)
			(layer "F.Fab")
		)
		(fp_line
			(start 0.120396 0.2794)
			(end -0.12065 0.2794)
			(stroke
				(width 0.1)
				(type default)
			)
			(layer "F.Fab")
		)
		(fp_line
			(start -0.12065 0.2794)
			(end -0.12065 0.3048)
			(stroke
				(width 0.1)
				(type default)
			)
			(layer "F.Fab")
		)
		(fp_line
			(start 0.67945 0.3048)
			(end 0.120396 0.3048)
			(stroke
				(width 0.1)
				(type default)
			)
			(layer "F.Fab")
		)
		(fp_line
			(start 0.120396 0.3048)
			(end 0.120396 0.2794)
			(stroke
				(width 0.1)
				(type default)
			)
			(layer "F.Fab")
		)
		(fp_line
			(start -0.12065 0.3048)
			(end -0.67945 0.3048)
			(stroke
				(width 0.1)
				(type default)
			)
			(layer "F.Fab")
		)
		(fp_line
			(start -0.67945 0.3048)
			(end -0.67945 -0.305054)
			(stroke
				(width 0.1)
				(type default)
			)
			(layer "F.Fab")
		)
		(pad "1" smd circle
			(at -0.40005 0 90)
			(size 0 0)
			(layers "F.Cu" "F.Mask" "F.Paste")
			(net "PVDDIO_P0")
		)
		(pad "2" smd circle
			(at 0.40005 0 90)
			(size 0 0)
			(layers "F.Cu" "F.Mask" "F.Paste")
			(net "GND")
		)
	)
	(footprint ""
		(layer "F.Cu")
		(at 416.817302 -416.899344 -90)
		(property "Reference" "C6596"
			(at 0 0 270)
			(layer "F.SilkS")
			(hide yes)
			(effects
				(font
					(size 1.27 1.27)
				)
			)
		)
		(property "Value" ""
			(at 0 0 270)
			(layer "F.Fab")
			(effects
				(font
					(size 1.27 1.27)
				)
			)
		)
		(duplicate_pad_numbers_are_jumpers no)
		(fp_line
			(start -0.299974 0.150114)
			(end -0.299974 -0.150114)
			(stroke
				(width 0.1)
				(type default)
			)
			(layer "F.Fab")
		)
		(fp_line
			(start 0.299974 0.150114)
			(end -0.299974 0.150114)
			(stroke
				(width 0.1)
				(type default)
			)
			(layer "F.Fab")
		)
		(fp_line
			(start -0.299974 -0.150114)
			(end 0.299974 -0.150114)
			(stroke
				(width 0.1)
				(type default)
			)
			(layer "F.Fab")
		)
		(fp_line
			(start 0.299974 -0.150114)
			(end 0.299974 0.150114)
			(stroke
				(width 0.1)
				(type default)
			)
			(layer "F.Fab")
		)
		(pad "1" smd rect
			(at -0.2667 0 270)
			(size 0.3048 0.381)
			(layers "F.Cu" "F.Mask" "F.Paste")
			(net "P5E_CPU0_P2_TX_BUF_C_DN<15>")
		)
		(pad "2" smd rect
			(at 0.2667 0 270)
			(size 0.3048 0.381)
			(layers "F.Cu" "F.Mask" "F.Paste")
			(net "P5E_CPU0_P2_TX_BUF_DN<15>")
		)
	)
	(footprint ""
		(layer "F.Cu")
		(at 393.795758 -147.663662 -90)
		(property "Reference" "PJ1"
			(at 2.030476 0.681228 0)
			(unlocked yes)
			(layer "F.SilkS")
			(effects
				(font
					(size 0.7874 0.5842)
					(thickness 0.1524)
				)
				(justify left)
			)
		)
		(property "Value" ""
			(at 0 0 270)
			(layer "F.Fab")
			(effects
				(font
					(size 1.27 1.27)
				)
			)
		)
		(duplicate_pad_numbers_are_jumpers no)
		(fp_line
			(start -1.249934 6.400038)
			(end -1.249934 -1.320038)
			(stroke
				(width 0.1524)
				(type default)
			)
			(layer "F.SilkS")
		)
		(fp_line
			(start 1.249934 6.400038)
			(end -1.249934 6.400038)
			(stroke
				(width 0.1524)
				(type default)
			)
			(layer "F.SilkS")
		)
		(fp_line
			(start -1.249934 -1.320038)
			(end 1.249934 -1.320038)
			(stroke
				(width 0.1524)
				(type default)
			)
			(layer "F.SilkS")
		)
		(fp_line
			(start 1.249934 -1.320038)
			(end 1.249934 6.400038)
			(stroke
				(width 0.1524)
				(type default)
			)
			(layer "F.SilkS")
		)
		(fp_poly
			(pts
				(xy -2.5654 -0.556514) (xy -1.452372 0) (xy -2.5654 0.556514)
			)
			(stroke
				(width 0)
				(type default)
			)
			(fill yes)
			(layer "F.SilkS")
		)
		(fp_line
			(start -1.249934 6.400038)
			(end -1.249934 -1.320038)
			(stroke
				(width 0.1)
				(type default)
			)
			(layer "F.Fab")
		)
		(fp_line
			(start 1.249934 6.400038)
			(end -1.249934 6.400038)
			(stroke
				(width 0.1)
				(type default)
			)
			(layer "F.Fab")
		)
		(fp_line
			(start -1.249934 -1.320038)
			(end 1.249934 -1.320038)
			(stroke
				(width 0.1)
				(type default)
			)
			(layer "F.Fab")
		)
		(fp_line
			(start 1.249934 -1.320038)
			(end 1.249934 6.400038)
			(stroke
				(width 0.1)
				(type default)
			)
			(layer "F.Fab")
		)
		(fp_poly
			(pts
				(xy -2.5654 -0.556514) (xy -1.452372 0) (xy -2.5654 0.556514)
			)
			(stroke
				(width 0)
				(type default)
			)
			(fill yes)
			(layer "F.Fab")
		)
		(fp_text user "3"
			(at -2.003806 5.113528 0)
			(unlocked yes)
			(layer "F.SilkS")
			(effects
				(font
					(size 0.7874 0.5842)
					(thickness 0.1524)
				)
			)
		)
		(fp_text user "3"
			(at -1.1557 5.18287 270)
			(unlocked yes)
			(layer "B.SilkS")
			(effects
				(font
					(size 0.7874 0.5842)
					(thickness 0.1524)
				)
				(justify mirror)
			)
		)
		(fp_text user "1"
			(at -1.143 0.02667 270)
			(unlocked yes)
			(layer "B.SilkS")
			(effects
				(font
					(size 0.7874 0.5842)
					(thickness 0.1524)
				)
				(justify mirror)
			)
		)
		(fp_text user "3"
			(at -1.1557 5.18287 270)
			(unlocked yes)
			(layer "B.Fab")
			(effects
				(font
					(size 0.7874 0.5842)
					(thickness 0.1524)
				)
				(justify mirror)
			)
		)
		(fp_text user "1"
			(at -1.143 0.02667 270)
			(unlocked yes)
			(layer "B.Fab")
			(effects
				(font
					(size 0.7874 0.5842)
					(thickness 0.1524)
				)
				(justify mirror)
			)
		)
		(fp_text user "3"
			(at -1.778 5.13207 270)
			(unlocked yes)
			(layer "F.Fab")
			(effects
				(font
					(size 0.7874 0.5842)
					(thickness 0.1524)
				)
			)
		)
		(pad "1" thru_hole rect
			(at 0 0 270)
			(size 1.5494 1.5494)
			(drill 1.0414)
			(layers "*.Cu" "*.Mask")
			(remove_unused_layers no)
			(net "GND")
			(clearance 0)
			(padstack
				(mode front_inner_back)
				(layer "Inner"
					(shape circle)
					(size 1.5494 1.5494)
					(clearance 0)
				)
				(layer "B.Cu"
					(shape rect)
					(size 1.5494 1.5494)
					(clearance 0)
				)
			)
		)
		(pad "2" thru_hole circle
			(at 0 2.54 270)
			(size 1.5494 1.5494)
			(drill 1.0414)
			(layers "*.Cu" "*.Mask")
			(remove_unused_layers no)
			(net "SMB_SCM_2_R3_SDA")
			(clearance 0)
		)
		(pad "3" thru_hole circle
			(at 0 5.08 270)
			(size 1.5494 1.5494)
			(drill 1.0414)
			(layers "*.Cu" "*.Mask")
			(remove_unused_layers no)
			(net "SMB_SCM_2_R3_SCL")
			(clearance 0)
		)
	)
	(footprint ""
		(layer "F.Cu")
		(at 393.363196 -321.632834)
		(property "Reference" "R582"
			(at 0 0 0)
			(layer "F.SilkS")
			(hide yes)
			(effects
				(font
					(size 1.27 1.27)
				)
			)
		)
		(property "Value" ""
			(at 0 0 0)
			(layer "F.Fab")
			(effects
				(font
					(size 1.27 1.27)
				)
			)
		)
		(duplicate_pad_numbers_are_jumpers no)
		(fp_line
			(start -0.7874 -0.4064)
			(end 0.7874 -0.4064)
			(stroke
				(width 0.1524)
				(type default)
			)
			(layer "F.SilkS")
		)
		(fp_line
			(start -0.7874 0.4064)
			(end -0.7874 -0.4064)
			(stroke
				(width 0.1524)
				(type default)
			)
			(layer "F.SilkS")
		)
		(fp_line
			(start 0.7874 -0.4064)
			(end 0.7874 0.4064)
			(stroke
				(width 0.1524)
				(type default)
			)
			(layer "F.SilkS")
		)
		(fp_line
			(start 0.7874 0.4064)
			(end -0.7874 0.4064)
			(stroke
				(width 0.1524)
				(type default)
			)
			(layer "F.SilkS")
		)
		(fp_line
			(start -0.67945 -0.305054)
			(end -0.12065 -0.305054)
			(stroke
				(width 0.1)
				(type default)
			)
			(layer "F.Fab")
		)
		(fp_line
			(start -0.67945 0.3048)
			(end -0.67945 -0.305054)
			(stroke
				(width 0.1)
				(type default)
			)
			(layer "F.Fab")
		)
		(fp_line
			(start -0.12065 -0.305054)
			(end -0.12065 -0.2794)
			(stroke
				(width 0.1)
				(type default)
			)
			(layer "F.Fab")
		)
		(fp_line
			(start -0.12065 -0.2794)
			(end 0.12065 -0.2794)
			(stroke
				(width 0.1)
				(type default)
			)
			(layer "F.Fab")
		)
		(fp_line
			(start -0.12065 0.2794)
			(end -0.12065 0.3048)
			(stroke
				(width 0.1)
				(type default)
			)
			(layer "F.Fab")
		)
		(fp_line
			(start -0.12065 0.3048)
			(end -0.67945 0.3048)
			(stroke
				(width 0.1)
				(type default)
			)
			(layer "F.Fab")
		)
		(fp_line
			(start 0.120396 0.2794)
			(end -0.12065 0.2794)
			(stroke
				(width 0.1)
				(type default)
			)
			(layer "F.Fab")
		)
		(fp_line
			(start 0.120396 0.3048)
			(end 0.120396 0.2794)
			(stroke
				(width 0.1)
				(type default)
			)
			(layer "F.Fab")
		)
		(fp_line
			(start 0.12065 -0.3048)
			(end 0.67945 -0.3048)
			(stroke
				(width 0.1)
				(type default)
			)
			(layer "F.Fab")
		)
		(fp_line
			(start 0.12065 -0.2794)
			(end 0.12065 -0.3048)
			(stroke
				(width 0.1)
				(type default)
			)
			(layer "F.Fab")
		)
		(fp_line
			(start 0.67945 -0.3048)
			(end 0.67945 0.3048)
			(stroke
				(width 0.1)
				(type default)
			)
			(layer "F.Fab")
		)
		(fp_line
			(start 0.67945 0.3048)
			(end 0.120396 0.3048)
			(stroke
				(width 0.1)
				(type default)
			)
			(layer "F.Fab")
		)
		(pad "1" smd circle
			(at -0.40005 0)
			(size 0 0)
			(layers "F.Cu" "F.Mask" "F.Paste")
			(net "GND")
		)
		(pad "2" smd circle
			(at 0.40005 0)
			(size 0 0)
			(layers "F.Cu" "F.Mask" "F.Paste")
			(net "RST_CPU0_RSMRST_N")
		)
	)
	(footprint ""
		(layer "F.Cu")
		(at 68.341494 -164.071046 -90)
		(property "Reference" "PC124_6"
			(at 0 0 270)
			(layer "F.SilkS")
			(hide yes)
			(effects
				(font
					(size 1.27 1.27)
				)
			)
		)
		(property "Value" ""
			(at 0 0 270)
			(layer "F.Fab")
			(effects
				(font
					(size 1.27 1.27)
				)
			)
		)
		(duplicate_pad_numbers_are_jumpers no)
		(fp_line
			(start -0.7874 0.4064)
			(end -0.7874 -0.4064)
			(stroke
				(width 0.1524)
				(type default)
			)
			(layer "F.SilkS")
		)
		(fp_line
			(start 0.7874 0.4064)
			(end -0.7874 0.4064)
			(stroke
				(width 0.1524)
				(type default)
			)
			(layer "F.SilkS")
		)
		(fp_line
			(start -0.7874 -0.4064)
			(end 0.7874 -0.4064)
			(stroke
				(width 0.1524)
				(type default)
			)
			(layer "F.SilkS")
		)
		(fp_line
			(start 0.7874 -0.4064)
			(end 0.7874 0.4064)
			(stroke
				(width 0.1524)
				(type default)
			)
			(layer "F.SilkS")
		)
		(fp_line
			(start -0.67945 0.3048)
			(end -0.67945 -0.305054)
			(stroke
				(width 0.1)
				(type default)
			)
			(layer "F.Fab")
		)
		(fp_line
			(start -0.12065 0.3048)
			(end -0.67945 0.3048)
			(stroke
				(width 0.1)
				(type default)
			)
			(layer "F.Fab")
		)
		(fp_line
			(start 0.120396 0.3048)
			(end 0.120396 0.2794)
			(stroke
				(width 0.1)
				(type default)
			)
			(layer "F.Fab")
		)
		(fp_line
			(start 0.67945 0.3048)
			(end 0.120396 0.3048)
			(stroke
				(width 0.1)
				(type default)
			)
			(layer "F.Fab")
		)
		(fp_line
			(start -0.12065 0.2794)
			(end -0.12065 0.3048)
			(stroke
				(width 0.1)
				(type default)
			)
			(layer "F.Fab")
		)
		(fp_line
			(start 0.120396 0.2794)
			(end -0.12065 0.2794)
			(stroke
				(width 0.1)
				(type default)
			)
			(layer "F.Fab")
		)
		(fp_line
			(start -0.12065 -0.2794)
			(end 0.12065 -0.2794)
			(stroke
				(width 0.1)
				(type default)
			)
			(layer "F.Fab")
		)
		(fp_line
			(start 0.12065 -0.2794)
			(end 0.12065 -0.3048)
			(stroke
				(width 0.1)
				(type default)
			)
			(layer "F.Fab")
		)
		(fp_line
			(start 0.12065 -0.3048)
			(end 0.67945 -0.3048)
			(stroke
				(width 0.1)
				(type default)
			)
			(layer "F.Fab")
		)
		(fp_line
			(start 0.67945 -0.3048)
			(end 0.67945 0.3048)
			(stroke
				(width 0.1)
				(type default)
			)
			(layer "F.Fab")
		)
		(fp_line
			(start -0.67945 -0.305054)
			(end -0.12065 -0.305054)
			(stroke
				(width 0.1)
				(type default)
			)
			(layer "F.Fab")
		)
		(fp_line
			(start -0.12065 -0.305054)
			(end -0.12065 -0.2794)
			(stroke
				(width 0.1)
				(type default)
			)
			(layer "F.Fab")
		)
		(pad "1" smd circle
			(at -0.40005 0 270)
			(size 0 0)
			(layers "F.Cu" "F.Mask" "F.Paste")
			(net "PVDDCR_CPU0_P1_VCCS")
		)
		(pad "2" smd circle
			(at 0.40005 0 270)
			(size 0 0)
			(layers "F.Cu" "F.Mask" "F.Paste")
			(net "GND")
		)
	)
	(footprint ""
		(layer "F.Cu")
		(at 185.928762 -25.899872 180)
		(property "Reference" "PR4004"
			(at 0 0 180)
			(layer "F.SilkS")
			(hide yes)
			(effects
				(font
					(size 1.27 1.27)
				)
			)
		)
		(property "Value" ""
			(at 0 0 180)
			(layer "F.Fab")
			(effects
				(font
					(size 1.27 1.27)
				)
			)
		)
		(duplicate_pad_numbers_are_jumpers no)
		(fp_line
			(start 0.7874 0.4064)
			(end -0.7874 0.4064)
			(stroke
				(width 0.1524)
				(type default)
			)
			(layer "F.SilkS")
		)
		(fp_line
			(start 0.7874 -0.4064)
			(end 0.7874 0.4064)
			(stroke
				(width 0.1524)
				(type default)
			)
			(layer "F.SilkS")
		)
		(fp_line
			(start -0.7874 0.4064)
			(end -0.7874 -0.4064)
			(stroke
				(width 0.1524)
				(type default)
			)
			(layer "F.SilkS")
		)
		(fp_line
			(start -0.7874 -0.4064)
			(end 0.7874 -0.4064)
			(stroke
				(width 0.1524)
				(type default)
			)
			(layer "F.SilkS")
		)
		(fp_line
			(start 0.67945 0.3048)
			(end 0.120396 0.3048)
			(stroke
				(width 0.1)
				(type default)
			)
			(layer "F.Fab")
		)
		(fp_line
			(start 0.67945 -0.3048)
			(end 0.67945 0.3048)
			(stroke
				(width 0.1)
				(type default)
			)
			(layer "F.Fab")
		)
		(fp_line
			(start 0.12065 -0.2794)
			(end 0.12065 -0.3048)
			(stroke
				(width 0.1)
				(type default)
			)
			(layer "F.Fab")
		)
		(fp_line
			(start 0.12065 -0.3048)
			(end 0.67945 -0.3048)
			(stroke
				(width 0.1)
				(type default)
			)
			(layer "F.Fab")
		)
		(fp_line
			(start 0.120396 0.3048)
			(end 0.120396 0.2794)
			(stroke
				(width 0.1)
				(type default)
			)
			(layer "F.Fab")
		)
		(fp_line
			(start 0.120396 0.2794)
			(end -0.12065 0.2794)
			(stroke
				(width 0.1)
				(type default)
			)
			(layer "F.Fab")
		)
		(fp_line
			(start -0.12065 0.3048)
			(end -0.67945 0.3048)
			(stroke
				(width 0.1)
				(type default)
			)
			(layer "F.Fab")
		)
		(fp_line
			(start -0.12065 0.2794)
			(end -0.12065 0.3048)
			(stroke
				(width 0.1)
				(type default)
			)
			(layer "F.Fab")
		)
		(fp_line
			(start -0.12065 -0.2794)
			(end 0.12065 -0.2794)
			(stroke
				(width 0.1)
				(type default)
			)
			(layer "F.Fab")
		)
		(fp_line
			(start -0.12065 -0.305054)
			(end -0.12065 -0.2794)
			(stroke
				(width 0.1)
				(type default)
			)
			(layer "F.Fab")
		)
		(fp_line
			(start -0.67945 0.3048)
			(end -0.67945 -0.305054)
			(stroke
				(width 0.1)
				(type default)
			)
			(layer "F.Fab")
		)
		(fp_line
			(start -0.67945 -0.305054)
			(end -0.12065 -0.305054)
			(stroke
				(width 0.1)
				(type default)
			)
			(layer "F.Fab")
		)
		(pad "1" smd circle
			(at -0.40005 0 180)
			(size 0 0)
			(layers "F.Cu" "F.Mask" "F.Paste")
			(net "P12V_SCM_CB")
		)
		(pad "2" smd circle
			(at 0.40005 0 180)
			(size 0 0)
			(layers "F.Cu" "F.Mask" "F.Paste")
			(net "GND")
		)
	)
	(footprint ""
		(layer "F.Cu")
		(at 156.30779 -98.755708 90)
		(property "Reference" "C1877"
			(at 0 0 90)
			(layer "F.SilkS")
			(hide yes)
			(effects
				(font
					(size 1.27 1.27)
				)
			)
		)
		(property "Value" ""
			(at 0 0 90)
			(layer "F.Fab")
			(effects
				(font
					(size 1.27 1.27)
				)
			)
		)
		(duplicate_pad_numbers_are_jumpers no)
		(fp_line
			(start 0.7874 -0.4064)
			(end 0.7874 0.4064)
			(stroke
				(width 0.1524)
				(type default)
			)
			(layer "F.SilkS")
		)
		(fp_line
			(start -0.7874 -0.4064)
			(end 0.7874 -0.4064)
			(stroke
				(width 0.1524)
				(type default)
			)
			(layer "F.SilkS")
		)
		(fp_line
			(start 0.7874 0.4064)
			(end -0.7874 0.4064)
			(stroke
				(width 0.1524)
				(type default)
			)
			(layer "F.SilkS")
		)
		(fp_line
			(start -0.7874 0.4064)
			(end -0.7874 -0.4064)
			(stroke
				(width 0.1524)
				(type default)
			)
			(layer "F.SilkS")
		)
		(fp_line
			(start -0.12065 -0.305054)
			(end -0.12065 -0.2794)
			(stroke
				(width 0.1)
				(type default)
			)
			(layer "F.Fab")
		)
		(fp_line
			(start -0.67945 -0.305054)
			(end -0.12065 -0.305054)
			(stroke
				(width 0.1)
				(type default)
			)
			(layer "F.Fab")
		)
		(fp_line
			(start 0.67945 -0.3048)
			(end 0.67945 0.3048)
			(stroke
				(width 0.1)
				(type default)
			)
			(layer "F.Fab")
		)
		(fp_line
			(start 0.12065 -0.3048)
			(end 0.67945 -0.3048)
			(stroke
				(width 0.1)
				(type default)
			)
			(layer "F.Fab")
		)
		(fp_line
			(start 0.12065 -0.2794)
			(end 0.12065 -0.3048)
			(stroke
				(width 0.1)
				(type default)
			)
			(layer "F.Fab")
		)
		(fp_line
			(start -0.12065 -0.2794)
			(end 0.12065 -0.2794)
			(stroke
				(width 0.1)
				(type default)
			)
			(layer "F.Fab")
		)
		(fp_line
			(start 0.120396 0.2794)
			(end -0.12065 0.2794)
			(stroke
				(width 0.1)
				(type default)
			)
			(layer "F.Fab")
		)
		(fp_line
			(start -0.12065 0.2794)
			(end -0.12065 0.3048)
			(stroke
				(width 0.1)
				(type default)
			)
			(layer "F.Fab")
		)
		(fp_line
			(start 0.67945 0.3048)
			(end 0.120396 0.3048)
			(stroke
				(width 0.1)
				(type default)
			)
			(layer "F.Fab")
		)
		(fp_line
			(start 0.120396 0.3048)
			(end 0.120396 0.2794)
			(stroke
				(width 0.1)
				(type default)
			)
			(layer "F.Fab")
		)
		(fp_line
			(start -0.12065 0.3048)
			(end -0.67945 0.3048)
			(stroke
				(width 0.1)
				(type default)
			)
			(layer "F.Fab")
		)
		(fp_line
			(start -0.67945 0.3048)
			(end -0.67945 -0.305054)
			(stroke
				(width 0.1)
				(type default)
			)
			(layer "F.Fab")
		)
		(pad "1" smd circle
			(at -0.40005 0 90)
			(size 0 0)
			(layers "F.Cu" "F.Mask" "F.Paste")
			(net "P3V3_AUX")
		)
		(pad "2" smd circle
			(at 0.40005 0 90)
			(size 0 0)
			(layers "F.Cu" "F.Mask" "F.Paste")
			(net "GND")
		)
	)
	(footprint ""
		(layer "F.Cu")
		(at 133.728714 -151.319484)
		(property "Reference" "PR214"
			(at 0 0 0)
			(layer "F.SilkS")
			(hide yes)
			(effects
				(font
					(size 1.27 1.27)
				)
			)
		)
		(property "Value" ""
			(at 0 0 0)
			(layer "F.Fab")
			(effects
				(font
					(size 1.27 1.27)
				)
			)
		)
		(duplicate_pad_numbers_are_jumpers no)
		(fp_line
			(start -0.7874 -0.4064)
			(end 0.7874 -0.4064)
			(stroke
				(width 0.1524)
				(type default)
			)
			(layer "F.SilkS")
		)
		(fp_line
			(start -0.7874 0.4064)
			(end -0.7874 -0.4064)
			(stroke
				(width 0.1524)
				(type default)
			)
			(layer "F.SilkS")
		)
		(fp_line
			(start 0.7874 -0.4064)
			(end 0.7874 0.4064)
			(stroke
				(width 0.1524)
				(type default)
			)
			(layer "F.SilkS")
		)
		(fp_line
			(start 0.7874 0.4064)
			(end -0.7874 0.4064)
			(stroke
				(width 0.1524)
				(type default)
			)
			(layer "F.SilkS")
		)
		(fp_line
			(start -0.67945 -0.305054)
			(end -0.12065 -0.305054)
			(stroke
				(width 0.1)
				(type default)
			)
			(layer "F.Fab")
		)
		(fp_line
			(start -0.67945 0.3048)
			(end -0.67945 -0.305054)
			(stroke
				(width 0.1)
				(type default)
			)
			(layer "F.Fab")
		)
		(fp_line
			(start -0.12065 -0.305054)
			(end -0.12065 -0.2794)
			(stroke
				(width 0.1)
				(type default)
			)
			(layer "F.Fab")
		)
		(fp_line
			(start -0.12065 -0.2794)
			(end 0.12065 -0.2794)
			(stroke
				(width 0.1)
				(type default)
			)
			(layer "F.Fab")
		)
		(fp_line
			(start -0.12065 0.2794)
			(end -0.12065 0.3048)
			(stroke
				(width 0.1)
				(type default)
			)
			(layer "F.Fab")
		)
		(fp_line
			(start -0.12065 0.3048)
			(end -0.67945 0.3048)
			(stroke
				(width 0.1)
				(type default)
			)
			(layer "F.Fab")
		)
		(fp_line
			(start 0.120396 0.2794)
			(end -0.12065 0.2794)
			(stroke
				(width 0.1)
				(type default)
			)
			(layer "F.Fab")
		)
		(fp_line
			(start 0.120396 0.3048)
			(end 0.120396 0.2794)
			(stroke
				(width 0.1)
				(type default)
			)
			(layer "F.Fab")
		)
		(fp_line
			(start 0.12065 -0.3048)
			(end 0.67945 -0.3048)
			(stroke
				(width 0.1)
				(type default)
			)
			(layer "F.Fab")
		)
		(fp_line
			(start 0.12065 -0.2794)
			(end 0.12065 -0.3048)
			(stroke
				(width 0.1)
				(type default)
			)
			(layer "F.Fab")
		)
		(fp_line
			(start 0.67945 -0.3048)
			(end 0.67945 0.3048)
			(stroke
				(width 0.1)
				(type default)
			)
			(layer "F.Fab")
		)
		(fp_line
			(start 0.67945 0.3048)
			(end 0.120396 0.3048)
			(stroke
				(width 0.1)
				(type default)
			)
			(layer "F.Fab")
		)
		(pad "1" smd circle
			(at -0.40005 0)
			(size 0 0)
			(layers "F.Cu" "F.Mask" "F.Paste")
			(net "GND")
		)
		(pad "2" smd circle
			(at 0.40005 0)
			(size 0 0)
			(layers "F.Cu" "F.Mask" "F.Paste")
			(net "PVDDCR_SOC_P1_LSET3")
		)
	)
	(footprint ""
		(layer "F.Cu")
		(at 339.713062 -333.290164 90)
		(property "Reference" "PR158"
			(at 0 0 90)
			(layer "F.SilkS")
			(hide yes)
			(effects
				(font
					(size 1.27 1.27)
				)
			)
		)
		(property "Value" ""
			(at 0 0 90)
			(layer "F.Fab")
			(effects
				(font
					(size 1.27 1.27)
				)
			)
		)
		(duplicate_pad_numbers_are_jumpers no)
		(fp_line
			(start 0.7874 -0.4064)
			(end 0.7874 0.4064)
			(stroke
				(width 0.1524)
				(type default)
			)
			(layer "F.SilkS")
		)
		(fp_line
			(start -0.7874 -0.4064)
			(end 0.7874 -0.4064)
			(stroke
				(width 0.1524)
				(type default)
			)
			(layer "F.SilkS")
		)
		(fp_line
			(start 0.7874 0.4064)
			(end -0.7874 0.4064)
			(stroke
				(width 0.1524)
				(type default)
			)
			(layer "F.SilkS")
		)
		(fp_line
			(start -0.7874 0.4064)
			(end -0.7874 -0.4064)
			(stroke
				(width 0.1524)
				(type default)
			)
			(layer "F.SilkS")
		)
		(fp_line
			(start -0.12065 -0.305054)
			(end -0.12065 -0.2794)
			(stroke
				(width 0.1)
				(type default)
			)
			(layer "F.Fab")
		)
		(fp_line
			(start -0.67945 -0.305054)
			(end -0.12065 -0.305054)
			(stroke
				(width 0.1)
				(type default)
			)
			(layer "F.Fab")
		)
		(fp_line
			(start 0.67945 -0.3048)
			(end 0.67945 0.3048)
			(stroke
				(width 0.1)
				(type default)
			)
			(layer "F.Fab")
		)
		(fp_line
			(start 0.12065 -0.3048)
			(end 0.67945 -0.3048)
			(stroke
				(width 0.1)
				(type default)
			)
			(layer "F.Fab")
		)
		(fp_line
			(start 0.12065 -0.2794)
			(end 0.12065 -0.3048)
			(stroke
				(width 0.1)
				(type default)
			)
			(layer "F.Fab")
		)
		(fp_line
			(start -0.12065 -0.2794)
			(end 0.12065 -0.2794)
			(stroke
				(width 0.1)
				(type default)
			)
			(layer "F.Fab")
		)
		(fp_line
			(start 0.120396 0.2794)
			(end -0.12065 0.2794)
			(stroke
				(width 0.1)
				(type default)
			)
			(layer "F.Fab")
		)
		(fp_line
			(start -0.12065 0.2794)
			(end -0.12065 0.3048)
			(stroke
				(width 0.1)
				(type default)
			)
			(layer "F.Fab")
		)
		(fp_line
			(start 0.67945 0.3048)
			(end 0.120396 0.3048)
			(stroke
				(width 0.1)
				(type default)
			)
			(layer "F.Fab")
		)
		(fp_line
			(start 0.120396 0.3048)
			(end 0.120396 0.2794)
			(stroke
				(width 0.1)
				(type default)
			)
			(layer "F.Fab")
		)
		(fp_line
			(start -0.12065 0.3048)
			(end -0.67945 0.3048)
			(stroke
				(width 0.1)
				(type default)
			)
			(layer "F.Fab")
		)
		(fp_line
			(start -0.67945 0.3048)
			(end -0.67945 -0.305054)
			(stroke
				(width 0.1)
				(type default)
			)
			(layer "F.Fab")
		)
		(pad "1" smd circle
			(at -0.40005 0 90)
			(size 0 0)
			(layers "F.Cu" "F.Mask" "F.Paste")
			(net "SW_PVDDCR_CPU1_P0_SW5_RC")
		)
		(pad "2" smd circle
			(at 0.40005 0 90)
			(size 0 0)
			(layers "F.Cu" "F.Mask" "F.Paste")
			(net "GND")
		)
	)
	(footprint ""
		(layer "F.Cu")
		(at 409.565348 -17.624298 90)
		(property "Reference" "C1794"
			(at 0 0 90)
			(layer "F.SilkS")
			(hide yes)
			(effects
				(font
					(size 1.27 1.27)
				)
			)
		)
		(property "Value" ""
			(at 0 0 90)
			(layer "F.Fab")
			(effects
				(font
					(size 1.27 1.27)
				)
			)
		)
		(duplicate_pad_numbers_are_jumpers no)
		(fp_line
			(start 0.299974 -0.150114)
			(end 0.299974 0.150114)
			(stroke
				(width 0.1)
				(type default)
			)
			(layer "F.Fab")
		)
		(fp_line
			(start -0.299974 -0.150114)
			(end 0.299974 -0.150114)
			(stroke
				(width 0.1)
				(type default)
			)
			(layer "F.Fab")
		)
		(fp_line
			(start 0.299974 0.150114)
			(end -0.299974 0.150114)
			(stroke
				(width 0.1)
				(type default)
			)
			(layer "F.Fab")
		)
		(fp_line
			(start -0.299974 0.150114)
			(end -0.299974 -0.150114)
			(stroke
				(width 0.1)
				(type default)
			)
			(layer "F.Fab")
		)
		(pad "1" smd rect
			(at -0.2667 0 90)
			(size 0.3048 0.381)
			(layers "F.Cu" "F.Mask" "F.Paste")
			(net "P5E_CPU0_G3_TX_C_DN<8>")
		)
		(pad "2" smd rect
			(at 0.2667 0 90)
			(size 0.3048 0.381)
			(layers "F.Cu" "F.Mask" "F.Paste")
			(net "P5E_CPU0_G3_TX_DN<8>")
		)
	)
	(footprint ""
		(layer "F.Cu")
		(at 355.157278 -163.26231)
		(property "Reference" "PC570_5"
			(at 0 0 0)
			(layer "F.SilkS")
			(hide yes)
			(effects
				(font
					(size 1.27 1.27)
				)
			)
		)
		(property "Value" ""
			(at 0 0 0)
			(layer "F.Fab")
			(effects
				(font
					(size 1.27 1.27)
				)
			)
		)
		(duplicate_pad_numbers_are_jumpers no)
		(fp_line
			(start -0.7874 -0.4064)
			(end 0.7874 -0.4064)
			(stroke
				(width 0.1524)
				(type default)
			)
			(layer "F.SilkS")
		)
		(fp_line
			(start -0.7874 0.4064)
			(end -0.7874 -0.4064)
			(stroke
				(width 0.1524)
				(type default)
			)
			(layer "F.SilkS")
		)
		(fp_line
			(start 0.7874 -0.4064)
			(end 0.7874 0.4064)
			(stroke
				(width 0.1524)
				(type default)
			)
			(layer "F.SilkS")
		)
		(fp_line
			(start 0.7874 0.4064)
			(end -0.7874 0.4064)
			(stroke
				(width 0.1524)
				(type default)
			)
			(layer "F.SilkS")
		)
		(fp_line
			(start -0.67945 -0.305054)
			(end -0.12065 -0.305054)
			(stroke
				(width 0.1)
				(type default)
			)
			(layer "F.Fab")
		)
		(fp_line
			(start -0.67945 0.3048)
			(end -0.67945 -0.305054)
			(stroke
				(width 0.1)
				(type default)
			)
			(layer "F.Fab")
		)
		(fp_line
			(start -0.12065 -0.305054)
			(end -0.12065 -0.2794)
			(stroke
				(width 0.1)
				(type default)
			)
			(layer "F.Fab")
		)
		(fp_line
			(start -0.12065 -0.2794)
			(end 0.12065 -0.2794)
			(stroke
				(width 0.1)
				(type default)
			)
			(layer "F.Fab")
		)
		(fp_line
			(start -0.12065 0.2794)
			(end -0.12065 0.3048)
			(stroke
				(width 0.1)
				(type default)
			)
			(layer "F.Fab")
		)
		(fp_line
			(start -0.12065 0.3048)
			(end -0.67945 0.3048)
			(stroke
				(width 0.1)
				(type default)
			)
			(layer "F.Fab")
		)
		(fp_line
			(start 0.120396 0.2794)
			(end -0.12065 0.2794)
			(stroke
				(width 0.1)
				(type default)
			)
			(layer "F.Fab")
		)
		(fp_line
			(start 0.120396 0.3048)
			(end 0.120396 0.2794)
			(stroke
				(width 0.1)
				(type default)
			)
			(layer "F.Fab")
		)
		(fp_line
			(start 0.12065 -0.3048)
			(end 0.67945 -0.3048)
			(stroke
				(width 0.1)
				(type default)
			)
			(layer "F.Fab")
		)
		(fp_line
			(start 0.12065 -0.2794)
			(end 0.12065 -0.3048)
			(stroke
				(width 0.1)
				(type default)
			)
			(layer "F.Fab")
		)
		(fp_line
			(start 0.67945 -0.3048)
			(end 0.67945 0.3048)
			(stroke
				(width 0.1)
				(type default)
			)
			(layer "F.Fab")
		)
		(fp_line
			(start 0.67945 0.3048)
			(end 0.120396 0.3048)
			(stroke
				(width 0.1)
				(type default)
			)
			(layer "F.Fab")
		)
		(pad "1" smd circle
			(at -0.40005 0)
			(size 0 0)
			(layers "F.Cu" "F.Mask" "F.Paste")
			(net "SW_P12V_AUX_PVDDCR_CPU0_P0_FLT")
		)
		(pad "2" smd circle
			(at 0.40005 0)
			(size 0 0)
			(layers "F.Cu" "F.Mask" "F.Paste")
			(net "GND")
		)
	)
	(footprint ""
		(layer "F.Cu")
		(at 450.060314 -25.10028 -90)
		(property "Reference" "PR3792"
			(at 0 0 270)
			(layer "F.SilkS")
			(hide yes)
			(effects
				(font
					(size 1.27 1.27)
				)
			)
		)
		(property "Value" ""
			(at 0 0 270)
			(layer "F.Fab")
			(effects
				(font
					(size 1.27 1.27)
				)
			)
		)
		(duplicate_pad_numbers_are_jumpers no)
		(fp_line
			(start -0.7874 0.4064)
			(end -0.7874 -0.4064)
			(stroke
				(width 0.1524)
				(type default)
			)
			(layer "F.SilkS")
		)
		(fp_line
			(start 0.7874 0.4064)
			(end -0.7874 0.4064)
			(stroke
				(width 0.1524)
				(type default)
			)
			(layer "F.SilkS")
		)
		(fp_line
			(start -0.7874 -0.4064)
			(end 0.7874 -0.4064)
			(stroke
				(width 0.1524)
				(type default)
			)
			(layer "F.SilkS")
		)
		(fp_line
			(start 0.7874 -0.4064)
			(end 0.7874 0.4064)
			(stroke
				(width 0.1524)
				(type default)
			)
			(layer "F.SilkS")
		)
		(fp_line
			(start -0.67945 0.3048)
			(end -0.67945 -0.305054)
			(stroke
				(width 0.1)
				(type default)
			)
			(layer "F.Fab")
		)
		(fp_line
			(start -0.12065 0.3048)
			(end -0.67945 0.3048)
			(stroke
				(width 0.1)
				(type default)
			)
			(layer "F.Fab")
		)
		(fp_line
			(start 0.120396 0.3048)
			(end 0.120396 0.2794)
			(stroke
				(width 0.1)
				(type default)
			)
			(layer "F.Fab")
		)
		(fp_line
			(start 0.67945 0.3048)
			(end 0.120396 0.3048)
			(stroke
				(width 0.1)
				(type default)
			)
			(layer "F.Fab")
		)
		(fp_line
			(start -0.12065 0.2794)
			(end -0.12065 0.3048)
			(stroke
				(width 0.1)
				(type default)
			)
			(layer "F.Fab")
		)
		(fp_line
			(start 0.120396 0.2794)
			(end -0.12065 0.2794)
			(stroke
				(width 0.1)
				(type default)
			)
			(layer "F.Fab")
		)
		(fp_line
			(start -0.12065 -0.2794)
			(end 0.12065 -0.2794)
			(stroke
				(width 0.1)
				(type default)
			)
			(layer "F.Fab")
		)
		(fp_line
			(start 0.12065 -0.2794)
			(end 0.12065 -0.3048)
			(stroke
				(width 0.1)
				(type default)
			)
			(layer "F.Fab")
		)
		(fp_line
			(start 0.12065 -0.3048)
			(end 0.67945 -0.3048)
			(stroke
				(width 0.1)
				(type default)
			)
			(layer "F.Fab")
		)
		(fp_line
			(start 0.67945 -0.3048)
			(end 0.67945 0.3048)
			(stroke
				(width 0.1)
				(type default)
			)
			(layer "F.Fab")
		)
		(fp_line
			(start -0.67945 -0.305054)
			(end -0.12065 -0.305054)
			(stroke
				(width 0.1)
				(type default)
			)
			(layer "F.Fab")
		)
		(fp_line
			(start -0.12065 -0.305054)
			(end -0.12065 -0.2794)
			(stroke
				(width 0.1)
				(type default)
			)
			(layer "F.Fab")
		)
		(pad "1" smd circle
			(at -0.40005 0 270)
			(size 0 0)
			(layers "F.Cu" "F.Mask" "F.Paste")
			(net "P12V_AUX")
		)
		(pad "2" smd circle
			(at 0.40005 0 270)
			(size 0 0)
			(layers "F.Cu" "F.Mask" "F.Paste")
			(net "P12V_OCP_VCC_1")
		)
	)
	(footprint ""
		(layer "F.Cu")
		(at 193.089022 -25.965912 90)
		(property "Reference" "R4013"
			(at 0 0 90)
			(layer "F.SilkS")
			(hide yes)
			(effects
				(font
					(size 1.27 1.27)
				)
			)
		)
		(property "Value" ""
			(at 0 0 90)
			(layer "F.Fab")
			(effects
				(font
					(size 1.27 1.27)
				)
			)
		)
		(duplicate_pad_numbers_are_jumpers no)
		(fp_line
			(start 0.7874 -0.4064)
			(end 0.7874 0.4064)
			(stroke
				(width 0.1524)
				(type default)
			)
			(layer "F.SilkS")
		)
		(fp_line
			(start -0.7874 -0.4064)
			(end 0.7874 -0.4064)
			(stroke
				(width 0.1524)
				(type default)
			)
			(layer "F.SilkS")
		)
		(fp_line
			(start 0.7874 0.4064)
			(end -0.7874 0.4064)
			(stroke
				(width 0.1524)
				(type default)
			)
			(layer "F.SilkS")
		)
		(fp_line
			(start -0.7874 0.4064)
			(end -0.7874 -0.4064)
			(stroke
				(width 0.1524)
				(type default)
			)
			(layer "F.SilkS")
		)
		(fp_line
			(start -0.12065 -0.305054)
			(end -0.12065 -0.2794)
			(stroke
				(width 0.1)
				(type default)
			)
			(layer "F.Fab")
		)
		(fp_line
			(start -0.67945 -0.305054)
			(end -0.12065 -0.305054)
			(stroke
				(width 0.1)
				(type default)
			)
			(layer "F.Fab")
		)
		(fp_line
			(start 0.67945 -0.3048)
			(end 0.67945 0.3048)
			(stroke
				(width 0.1)
				(type default)
			)
			(layer "F.Fab")
		)
		(fp_line
			(start 0.12065 -0.3048)
			(end 0.67945 -0.3048)
			(stroke
				(width 0.1)
				(type default)
			)
			(layer "F.Fab")
		)
		(fp_line
			(start 0.12065 -0.2794)
			(end 0.12065 -0.3048)
			(stroke
				(width 0.1)
				(type default)
			)
			(layer "F.Fab")
		)
		(fp_line
			(start -0.12065 -0.2794)
			(end 0.12065 -0.2794)
			(stroke
				(width 0.1)
				(type default)
			)
			(layer "F.Fab")
		)
		(fp_line
			(start 0.120396 0.2794)
			(end -0.12065 0.2794)
			(stroke
				(width 0.1)
				(type default)
			)
			(layer "F.Fab")
		)
		(fp_line
			(start -0.12065 0.2794)
			(end -0.12065 0.3048)
			(stroke
				(width 0.1)
				(type default)
			)
			(layer "F.Fab")
		)
		(fp_line
			(start 0.67945 0.3048)
			(end 0.120396 0.3048)
			(stroke
				(width 0.1)
				(type default)
			)
			(layer "F.Fab")
		)
		(fp_line
			(start 0.120396 0.3048)
			(end 0.120396 0.2794)
			(stroke
				(width 0.1)
				(type default)
			)
			(layer "F.Fab")
		)
		(fp_line
			(start -0.12065 0.3048)
			(end -0.67945 0.3048)
			(stroke
				(width 0.1)
				(type default)
			)
			(layer "F.Fab")
		)
		(fp_line
			(start -0.67945 0.3048)
			(end -0.67945 -0.305054)
			(stroke
				(width 0.1)
				(type default)
			)
			(layer "F.Fab")
		)
		(pad "1" smd circle
			(at -0.40005 0 90)
			(size 0 0)
			(layers "F.Cu" "F.Mask" "F.Paste")
			(net "P3V3_AUX")
		)
		(pad "2" smd circle
			(at 0.40005 0 90)
			(size 0 0)
			(layers "F.Cu" "F.Mask" "F.Paste")
			(net "P12V_SCM_FAULT_R_N")
		)
	)
	(footprint ""
		(layer "F.Cu")
		(at 115.08359 -417.939982 90)
		(property "Reference" "R3028"
			(at 0 0 90)
			(layer "F.SilkS")
			(hide yes)
			(effects
				(font
					(size 1.27 1.27)
				)
			)
		)
		(property "Value" ""
			(at 0 0 90)
			(layer "F.Fab")
			(effects
				(font
					(size 1.27 1.27)
				)
			)
		)
		(duplicate_pad_numbers_are_jumpers no)
		(fp_line
			(start 0.7874 -0.4064)
			(end 0.7874 0.4064)
			(stroke
				(width 0.1524)
				(type default)
			)
			(layer "F.SilkS")
		)
		(fp_line
			(start -0.7874 -0.4064)
			(end 0.7874 -0.4064)
			(stroke
				(width 0.1524)
				(type default)
			)
			(layer "F.SilkS")
		)
		(fp_line
			(start 0.7874 0.4064)
			(end -0.7874 0.4064)
			(stroke
				(width 0.1524)
				(type default)
			)
			(layer "F.SilkS")
		)
		(fp_line
			(start -0.7874 0.4064)
			(end -0.7874 -0.4064)
			(stroke
				(width 0.1524)
				(type default)
			)
			(layer "F.SilkS")
		)
		(fp_line
			(start -0.12065 -0.305054)
			(end -0.12065 -0.2794)
			(stroke
				(width 0.1)
				(type default)
			)
			(layer "F.Fab")
		)
		(fp_line
			(start -0.67945 -0.305054)
			(end -0.12065 -0.305054)
			(stroke
				(width 0.1)
				(type default)
			)
			(layer "F.Fab")
		)
		(fp_line
			(start 0.67945 -0.3048)
			(end 0.67945 0.3048)
			(stroke
				(width 0.1)
				(type default)
			)
			(layer "F.Fab")
		)
		(fp_line
			(start 0.12065 -0.3048)
			(end 0.67945 -0.3048)
			(stroke
				(width 0.1)
				(type default)
			)
			(layer "F.Fab")
		)
		(fp_line
			(start 0.12065 -0.2794)
			(end 0.12065 -0.3048)
			(stroke
				(width 0.1)
				(type default)
			)
			(layer "F.Fab")
		)
		(fp_line
			(start -0.12065 -0.2794)
			(end 0.12065 -0.2794)
			(stroke
				(width 0.1)
				(type default)
			)
			(layer "F.Fab")
		)
		(fp_line
			(start 0.120396 0.2794)
			(end -0.12065 0.2794)
			(stroke
				(width 0.1)
				(type default)
			)
			(layer "F.Fab")
		)
		(fp_line
			(start -0.12065 0.2794)
			(end -0.12065 0.3048)
			(stroke
				(width 0.1)
				(type default)
			)
			(layer "F.Fab")
		)
		(fp_line
			(start 0.67945 0.3048)
			(end 0.120396 0.3048)
			(stroke
				(width 0.1)
				(type default)
			)
			(layer "F.Fab")
		)
		(fp_line
			(start 0.120396 0.3048)
			(end 0.120396 0.2794)
			(stroke
				(width 0.1)
				(type default)
			)
			(layer "F.Fab")
		)
		(fp_line
			(start -0.12065 0.3048)
			(end -0.67945 0.3048)
			(stroke
				(width 0.1)
				(type default)
			)
			(layer "F.Fab")
		)
		(fp_line
			(start -0.67945 0.3048)
			(end -0.67945 -0.305054)
			(stroke
				(width 0.1)
				(type default)
			)
			(layer "F.Fab")
		)
		(pad "1" smd circle
			(at -0.40005 0 90)
			(size 0 0)
			(layers "F.Cu" "F.Mask" "F.Paste")
			(net "FM_SMB_1_ALERT_GPU_N")
		)
		(pad "2" smd circle
			(at 0.40005 0 90)
			(size 0 0)
			(layers "F.Cu" "F.Mask" "F.Paste")
			(net "GND")
		)
	)
	(footprint ""
		(layer "F.Cu")
		(at 331.055472 -396.146274)
		(property "Reference" "R611"
			(at 0 0 0)
			(layer "F.SilkS")
			(hide yes)
			(effects
				(font
					(size 1.27 1.27)
				)
			)
		)
		(property "Value" ""
			(at 0 0 0)
			(layer "F.Fab")
			(effects
				(font
					(size 1.27 1.27)
				)
			)
		)
		(duplicate_pad_numbers_are_jumpers no)
		(fp_line
			(start -0.32512 -0.175006)
			(end 0.32512 -0.175006)
			(stroke
				(width 0.1)
				(type default)
			)
			(layer "F.Fab")
		)
		(fp_line
			(start -0.32512 0.175006)
			(end -0.32512 -0.175006)
			(stroke
				(width 0.1)
				(type default)
			)
			(layer "F.Fab")
		)
		(fp_line
			(start 0.32512 -0.175006)
			(end 0.32512 0.175006)
			(stroke
				(width 0.1)
				(type default)
			)
			(layer "F.Fab")
		)
		(fp_line
			(start 0.32512 0.175006)
			(end -0.32512 0.175006)
			(stroke
				(width 0.1)
				(type default)
			)
			(layer "F.Fab")
		)
		(pad "1" smd rect
			(at -0.2667 0)
			(size 0.3048 0.381)
			(layers "F.Cu" "F.Mask" "F.Paste")
			(net "CLK_100M_RETIMER_CPU0_P1_R_DP")
		)
		(pad "2" smd rect
			(at 0.2667 0 180)
			(size 0.3048 0.381)
			(layers "F.Cu" "F.Mask" "F.Paste")
			(net "CLK_100M_RETIMER_CPU0_P1_DP")
		)
	)
	(footprint ""
		(layer "F.Cu")
		(at 29.226764 -388.931658 -90)
		(property "Reference" "PC6634_2"
			(at 0 0 270)
			(layer "F.SilkS")
			(hide yes)
			(effects
				(font
					(size 1.27 1.27)
				)
			)
		)
		(property "Value" ""
			(at 0 0 270)
			(layer "F.Fab")
			(effects
				(font
					(size 1.27 1.27)
				)
			)
		)
		(duplicate_pad_numbers_are_jumpers no)
		(fp_line
			(start -0.7874 0.4064)
			(end -0.7874 -0.4064)
			(stroke
				(width 0.1524)
				(type default)
			)
			(layer "F.SilkS")
		)
		(fp_line
			(start 0.7874 0.4064)
			(end -0.7874 0.4064)
			(stroke
				(width 0.1524)
				(type default)
			)
			(layer "F.SilkS")
		)
		(fp_line
			(start -0.7874 -0.4064)
			(end 0.7874 -0.4064)
			(stroke
				(width 0.1524)
				(type default)
			)
			(layer "F.SilkS")
		)
		(fp_line
			(start 0.7874 -0.4064)
			(end 0.7874 0.4064)
			(stroke
				(width 0.1524)
				(type default)
			)
			(layer "F.SilkS")
		)
		(fp_line
			(start -0.67945 0.3048)
			(end -0.67945 -0.305054)
			(stroke
				(width 0.1)
				(type default)
			)
			(layer "F.Fab")
		)
		(fp_line
			(start -0.12065 0.3048)
			(end -0.67945 0.3048)
			(stroke
				(width 0.1)
				(type default)
			)
			(layer "F.Fab")
		)
		(fp_line
			(start 0.120396 0.3048)
			(end 0.120396 0.2794)
			(stroke
				(width 0.1)
				(type default)
			)
			(layer "F.Fab")
		)
		(fp_line
			(start 0.67945 0.3048)
			(end 0.120396 0.3048)
			(stroke
				(width 0.1)
				(type default)
			)
			(layer "F.Fab")
		)
		(fp_line
			(start -0.12065 0.2794)
			(end -0.12065 0.3048)
			(stroke
				(width 0.1)
				(type default)
			)
			(layer "F.Fab")
		)
		(fp_line
			(start 0.120396 0.2794)
			(end -0.12065 0.2794)
			(stroke
				(width 0.1)
				(type default)
			)
			(layer "F.Fab")
		)
		(fp_line
			(start -0.12065 -0.2794)
			(end 0.12065 -0.2794)
			(stroke
				(width 0.1)
				(type default)
			)
			(layer "F.Fab")
		)
		(fp_line
			(start 0.12065 -0.2794)
			(end 0.12065 -0.3048)
			(stroke
				(width 0.1)
				(type default)
			)
			(layer "F.Fab")
		)
		(fp_line
			(start 0.12065 -0.3048)
			(end 0.67945 -0.3048)
			(stroke
				(width 0.1)
				(type default)
			)
			(layer "F.Fab")
		)
		(fp_line
			(start 0.67945 -0.3048)
			(end 0.67945 0.3048)
			(stroke
				(width 0.1)
				(type default)
			)
			(layer "F.Fab")
		)
		(fp_line
			(start -0.67945 -0.305054)
			(end -0.12065 -0.305054)
			(stroke
				(width 0.1)
				(type default)
			)
			(layer "F.Fab")
		)
		(fp_line
			(start -0.12065 -0.305054)
			(end -0.12065 -0.2794)
			(stroke
				(width 0.1)
				(type default)
			)
			(layer "F.Fab")
		)
		(pad "1" smd circle
			(at -0.40005 0 270)
			(size 0 0)
			(layers "F.Cu" "F.Mask" "F.Paste")
			(net "SW_P12V_AUX_P0V9_RETIMER_CPU1_FLT")
		)
		(pad "2" smd circle
			(at 0.40005 0 270)
			(size 0 0)
			(layers "F.Cu" "F.Mask" "F.Paste")
			(net "GND")
		)
	)
	(footprint ""
		(layer "F.Cu")
		(at 197.269608 -123.785376)
		(property "Reference" "R11667"
			(at 0 0 0)
			(layer "F.SilkS")
			(hide yes)
			(effects
				(font
					(size 1.27 1.27)
				)
			)
		)
		(property "Value" ""
			(at 0 0 0)
			(layer "F.Fab")
			(effects
				(font
					(size 1.27 1.27)
				)
			)
		)
		(duplicate_pad_numbers_are_jumpers no)
		(fp_line
			(start -0.7874 -0.4064)
			(end 0.7874 -0.4064)
			(stroke
				(width 0.1524)
				(type default)
			)
			(layer "F.SilkS")
		)
		(fp_line
			(start -0.7874 0.4064)
			(end -0.7874 -0.4064)
			(stroke
				(width 0.1524)
				(type default)
			)
			(layer "F.SilkS")
		)
		(fp_line
			(start 0.7874 -0.4064)
			(end 0.7874 0.4064)
			(stroke
				(width 0.1524)
				(type default)
			)
			(layer "F.SilkS")
		)
		(fp_line
			(start 0.7874 0.4064)
			(end -0.7874 0.4064)
			(stroke
				(width 0.1524)
				(type default)
			)
			(layer "F.SilkS")
		)
		(fp_line
			(start -0.67945 -0.305054)
			(end -0.12065 -0.305054)
			(stroke
				(width 0.1)
				(type default)
			)
			(layer "F.Fab")
		)
		(fp_line
			(start -0.67945 0.3048)
			(end -0.67945 -0.305054)
			(stroke
				(width 0.1)
				(type default)
			)
			(layer "F.Fab")
		)
		(fp_line
			(start -0.12065 -0.305054)
			(end -0.12065 -0.2794)
			(stroke
				(width 0.1)
				(type default)
			)
			(layer "F.Fab")
		)
		(fp_line
			(start -0.12065 -0.2794)
			(end 0.12065 -0.2794)
			(stroke
				(width 0.1)
				(type default)
			)
			(layer "F.Fab")
		)
		(fp_line
			(start -0.12065 0.2794)
			(end -0.12065 0.3048)
			(stroke
				(width 0.1)
				(type default)
			)
			(layer "F.Fab")
		)
		(fp_line
			(start -0.12065 0.3048)
			(end -0.67945 0.3048)
			(stroke
				(width 0.1)
				(type default)
			)
			(layer "F.Fab")
		)
		(fp_line
			(start 0.120396 0.2794)
			(end -0.12065 0.2794)
			(stroke
				(width 0.1)
				(type default)
			)
			(layer "F.Fab")
		)
		(fp_line
			(start 0.120396 0.3048)
			(end 0.120396 0.2794)
			(stroke
				(width 0.1)
				(type default)
			)
			(layer "F.Fab")
		)
		(fp_line
			(start 0.12065 -0.3048)
			(end 0.67945 -0.3048)
			(stroke
				(width 0.1)
				(type default)
			)
			(layer "F.Fab")
		)
		(fp_line
			(start 0.12065 -0.2794)
			(end 0.12065 -0.3048)
			(stroke
				(width 0.1)
				(type default)
			)
			(layer "F.Fab")
		)
		(fp_line
			(start 0.67945 -0.3048)
			(end 0.67945 0.3048)
			(stroke
				(width 0.1)
				(type default)
			)
			(layer "F.Fab")
		)
		(fp_line
			(start 0.67945 0.3048)
			(end 0.120396 0.3048)
			(stroke
				(width 0.1)
				(type default)
			)
			(layer "F.Fab")
		)
		(pad "1" smd circle
			(at -0.40005 0)
			(size 0 0)
			(layers "F.Cu" "F.Mask" "F.Paste")
			(net "FM_SMB_2_ALERT_GPU_ISO_R_N")
		)
		(pad "2" smd circle
			(at 0.40005 0)
			(size 0 0)
			(layers "F.Cu" "F.Mask" "F.Paste")
			(net "FM_SMB_2_ALERT_GPU_ISO_N")
		)
	)
	(footprint ""
		(layer "F.Cu")
		(at 117.895624 -258.405376 180)
		(property "Reference" "C2288"
			(at 0 0 180)
			(layer "F.SilkS")
			(hide yes)
			(effects
				(font
					(size 1.27 1.27)
				)
			)
		)
		(property "Value" ""
			(at 0 0 180)
			(layer "F.Fab")
			(effects
				(font
					(size 1.27 1.27)
				)
			)
		)
		(duplicate_pad_numbers_are_jumpers no)
		(fp_line
			(start 0.7874 0.4064)
			(end -0.7874 0.4064)
			(stroke
				(width 0.1524)
				(type default)
			)
			(layer "F.SilkS")
		)
		(fp_line
			(start 0.7874 -0.4064)
			(end 0.7874 0.4064)
			(stroke
				(width 0.1524)
				(type default)
			)
			(layer "F.SilkS")
		)
		(fp_line
			(start -0.7874 0.4064)
			(end -0.7874 -0.4064)
			(stroke
				(width 0.1524)
				(type default)
			)
			(layer "F.SilkS")
		)
		(fp_line
			(start -0.7874 -0.4064)
			(end 0.7874 -0.4064)
			(stroke
				(width 0.1524)
				(type default)
			)
			(layer "F.SilkS")
		)
		(fp_line
			(start 0.67945 0.3048)
			(end 0.120396 0.3048)
			(stroke
				(width 0.1)
				(type default)
			)
			(layer "F.Fab")
		)
		(fp_line
			(start 0.67945 -0.3048)
			(end 0.67945 0.3048)
			(stroke
				(width 0.1)
				(type default)
			)
			(layer "F.Fab")
		)
		(fp_line
			(start 0.12065 -0.2794)
			(end 0.12065 -0.3048)
			(stroke
				(width 0.1)
				(type default)
			)
			(layer "F.Fab")
		)
		(fp_line
			(start 0.12065 -0.3048)
			(end 0.67945 -0.3048)
			(stroke
				(width 0.1)
				(type default)
			)
			(layer "F.Fab")
		)
		(fp_line
			(start 0.120396 0.3048)
			(end 0.120396 0.2794)
			(stroke
				(width 0.1)
				(type default)
			)
			(layer "F.Fab")
		)
		(fp_line
			(start 0.120396 0.2794)
			(end -0.12065 0.2794)
			(stroke
				(width 0.1)
				(type default)
			)
			(layer "F.Fab")
		)
		(fp_line
			(start -0.12065 0.3048)
			(end -0.67945 0.3048)
			(stroke
				(width 0.1)
				(type default)
			)
			(layer "F.Fab")
		)
		(fp_line
			(start -0.12065 0.2794)
			(end -0.12065 0.3048)
			(stroke
				(width 0.1)
				(type default)
			)
			(layer "F.Fab")
		)
		(fp_line
			(start -0.12065 -0.2794)
			(end 0.12065 -0.2794)
			(stroke
				(width 0.1)
				(type default)
			)
			(layer "F.Fab")
		)
		(fp_line
			(start -0.12065 -0.305054)
			(end -0.12065 -0.2794)
			(stroke
				(width 0.1)
				(type default)
			)
			(layer "F.Fab")
		)
		(fp_line
			(start -0.67945 0.3048)
			(end -0.67945 -0.305054)
			(stroke
				(width 0.1)
				(type default)
			)
			(layer "F.Fab")
		)
		(fp_line
			(start -0.67945 -0.305054)
			(end -0.12065 -0.305054)
			(stroke
				(width 0.1)
				(type default)
			)
			(layer "F.Fab")
		)
		(pad "1" smd circle
			(at -0.40005 0 180)
			(size 0 0)
			(layers "F.Cu" "F.Mask" "F.Paste")
			(net "PVDDCR_SOC_P1")
		)
		(pad "2" smd circle
			(at 0.40005 0 180)
			(size 0 0)
			(layers "F.Cu" "F.Mask" "F.Paste")
			(net "GND")
		)
	)
	(footprint ""
		(layer "F.Cu")
		(at 305.819048 -45.005498)
		(property "Reference" "R3672"
			(at 0 0 0)
			(layer "F.SilkS")
			(hide yes)
			(effects
				(font
					(size 1.27 1.27)
				)
			)
		)
		(property "Value" ""
			(at 0 0 0)
			(layer "F.Fab")
			(effects
				(font
					(size 1.27 1.27)
				)
			)
		)
		(duplicate_pad_numbers_are_jumpers no)
		(fp_line
			(start -0.7874 -0.4064)
			(end 0.7874 -0.4064)
			(stroke
				(width 0.1524)
				(type default)
			)
			(layer "F.SilkS")
		)
		(fp_line
			(start -0.7874 0.4064)
			(end -0.7874 -0.4064)
			(stroke
				(width 0.1524)
				(type default)
			)
			(layer "F.SilkS")
		)
		(fp_line
			(start 0.7874 -0.4064)
			(end 0.7874 0.4064)
			(stroke
				(width 0.1524)
				(type default)
			)
			(layer "F.SilkS")
		)
		(fp_line
			(start 0.7874 0.4064)
			(end -0.7874 0.4064)
			(stroke
				(width 0.1524)
				(type default)
			)
			(layer "F.SilkS")
		)
		(fp_line
			(start -0.67945 -0.305054)
			(end -0.12065 -0.305054)
			(stroke
				(width 0.1)
				(type default)
			)
			(layer "F.Fab")
		)
		(fp_line
			(start -0.67945 0.3048)
			(end -0.67945 -0.305054)
			(stroke
				(width 0.1)
				(type default)
			)
			(layer "F.Fab")
		)
		(fp_line
			(start -0.12065 -0.305054)
			(end -0.12065 -0.2794)
			(stroke
				(width 0.1)
				(type default)
			)
			(layer "F.Fab")
		)
		(fp_line
			(start -0.12065 -0.2794)
			(end 0.12065 -0.2794)
			(stroke
				(width 0.1)
				(type default)
			)
			(layer "F.Fab")
		)
		(fp_line
			(start -0.12065 0.2794)
			(end -0.12065 0.3048)
			(stroke
				(width 0.1)
				(type default)
			)
			(layer "F.Fab")
		)
		(fp_line
			(start -0.12065 0.3048)
			(end -0.67945 0.3048)
			(stroke
				(width 0.1)
				(type default)
			)
			(layer "F.Fab")
		)
		(fp_line
			(start 0.120396 0.2794)
			(end -0.12065 0.2794)
			(stroke
				(width 0.1)
				(type default)
			)
			(layer "F.Fab")
		)
		(fp_line
			(start 0.120396 0.3048)
			(end 0.120396 0.2794)
			(stroke
				(width 0.1)
				(type default)
			)
			(layer "F.Fab")
		)
		(fp_line
			(start 0.12065 -0.3048)
			(end 0.67945 -0.3048)
			(stroke
				(width 0.1)
				(type default)
			)
			(layer "F.Fab")
		)
		(fp_line
			(start 0.12065 -0.2794)
			(end 0.12065 -0.3048)
			(stroke
				(width 0.1)
				(type default)
			)
			(layer "F.Fab")
		)
		(fp_line
			(start 0.67945 -0.3048)
			(end 0.67945 0.3048)
			(stroke
				(width 0.1)
				(type default)
			)
			(layer "F.Fab")
		)
		(fp_line
			(start 0.67945 0.3048)
			(end 0.120396 0.3048)
			(stroke
				(width 0.1)
				(type default)
			)
			(layer "F.Fab")
		)
		(pad "1" smd circle
			(at -0.40005 0)
			(size 0 0)
			(layers "F.Cu" "F.Mask" "F.Paste")
			(net "SMB_SCM_2_R4_SCL")
		)
		(pad "2" smd circle
			(at 0.40005 0)
			(size 0 0)
			(layers "F.Cu" "F.Mask" "F.Paste")
			(net "SMB_SEN_TIC_3V3AUX_SCL")
		)
	)
	(footprint ""
		(layer "F.Cu")
		(at 177.694082 -28.937712 -90)
		(property "Reference" "PU299"
			(at -4.293616 -3.376676 0)
			(unlocked yes)
			(layer "F.SilkS")
			(effects
				(font
					(size 0.7874 0.5842)
					(thickness 0.1524)
				)
				(justify left)
			)
		)
		(property "Value" ""
			(at 0 0 270)
			(layer "F.Fab")
			(effects
				(font
					(size 1.27 1.27)
				)
			)
		)
		(duplicate_pad_numbers_are_jumpers no)
		(fp_line
			(start -1.549908 2.549906)
			(end -0.753872 2.549906)
			(stroke
				(width 0.1524)
				(type default)
			)
			(layer "F.SilkS")
		)
		(fp_line
			(start -0.245872 2.549906)
			(end 0.245872 2.549906)
			(stroke
				(width 0.1524)
				(type default)
			)
			(layer "F.SilkS")
		)
		(fp_line
			(start 0.753872 2.549906)
			(end 1.549908 2.549906)
			(stroke
				(width 0.1524)
				(type default)
			)
			(layer "F.SilkS")
		)
		(fp_line
			(start 1.549908 2.549906)
			(end 1.549908 2.253996)
			(stroke
				(width 0.1524)
				(type default)
			)
			(layer "F.SilkS")
		)
		(fp_line
			(start -1.549908 2.253996)
			(end -1.549908 2.549906)
			(stroke
				(width 0.1524)
				(type default)
			)
			(layer "F.SilkS")
		)
		(fp_line
			(start 1.549908 -2.253996)
			(end 1.549908 -2.549906)
			(stroke
				(width 0.1524)
				(type default)
			)
			(layer "F.SilkS")
		)
		(fp_line
			(start -1.549908 -2.549906)
			(end -1.549908 -2.251964)
			(stroke
				(width 0.1524)
				(type default)
			)
			(layer "F.SilkS")
		)
		(fp_line
			(start -0.752094 -2.549906)
			(end -1.549908 -2.549906)
			(stroke
				(width 0.1524)
				(type default)
			)
			(layer "F.SilkS")
		)
		(fp_line
			(start 0.2413 -2.549906)
			(end -0.2413 -2.549906)
			(stroke
				(width 0.1524)
				(type default)
			)
			(layer "F.SilkS")
		)
		(fp_line
			(start 1.549908 -2.549906)
			(end 0.752094 -2.549906)
			(stroke
				(width 0.1524)
				(type default)
			)
			(layer "F.SilkS")
		)
		(fp_poly
			(pts
				(xy -2.418842 -3.085338) (xy -2.007616 -2.226564) (xy -2.94132 -2.413)
			)
			(stroke
				(width 0)
				(type default)
			)
			(fill yes)
			(layer "F.SilkS")
		)
		(fp_line
			(start -1.549908 2.549906)
			(end 1.549908 2.549906)
			(stroke
				(width 0.1)
				(type default)
			)
			(layer "F.Fab")
		)
		(fp_line
			(start 1.549908 2.549906)
			(end 1.549908 -2.549906)
			(stroke
				(width 0.1)
				(type default)
			)
			(layer "F.Fab")
		)
		(fp_line
			(start -1.549908 -2.549906)
			(end -1.549908 2.549906)
			(stroke
				(width 0.1)
				(type default)
			)
			(layer "F.Fab")
		)
		(fp_line
			(start 1.549908 -2.549906)
			(end -1.549908 -2.549906)
			(stroke
				(width 0.1)
				(type default)
			)
			(layer "F.Fab")
		)
		(fp_poly
			(pts
				(xy -1.891538 -1.999996) (xy -2.7432 -1.574292) (xy -2.7432 -2.4257)
			)
			(stroke
				(width 0)
				(type default)
			)
			(fill yes)
			(layer "F.Fab")
		)
		(fp_text user "11"
			(at 1.1938 7.393432 270)
			(unlocked yes)
			(layer "F.SilkS")
			(effects
				(font
					(size 0.635 0.4064)
					(thickness 0.1524)
				)
			)
		)
		(fp_text user "10"
			(at -1.4224 3.189732 270)
			(unlocked yes)
			(layer "F.SilkS")
			(effects
				(font
					(size 0.635 0.4064)
					(thickness 0.1524)
				)
			)
		)
		(fp_text user "12"
			(at 2.040636 2.75082 180)
			(unlocked yes)
			(layer "F.SilkS")
			(effects
				(font
					(size 0.635 0.4064)
					(thickness 0.1524)
				)
			)
		)
		(fp_text user "9"
			(at -2.592832 2.0828 180)
			(unlocked yes)
			(layer "F.SilkS")
			(effects
				(font
					(size 0.635 0.4064)
					(thickness 0.1524)
				)
			)
		)
		(fp_text user "20"
			(at 3.833368 -2.3876 180)
			(unlocked yes)
			(layer "F.SilkS")
			(effects
				(font
					(size 0.635 0.4064)
					(thickness 0.1524)
				)
			)
		)
		(fp_text user "21_22"
			(at -0.0762 -3.655568 270)
			(unlocked yes)
			(layer "F.SilkS")
			(effects
				(font
					(size 0.635 0.4064)
					(thickness 0.1524)
				)
			)
		)
		(fp_text user "11"
			(at 1.1938 3.329432 270)
			(unlocked yes)
			(layer "F.Fab")
			(effects
				(font
					(size 0.635 0.4064)
					(thickness 0.1524)
				)
			)
		)
		(fp_text user "10"
			(at -1.4224 3.253232 270)
			(unlocked yes)
			(layer "F.Fab")
			(effects
				(font
					(size 0.635 0.4064)
					(thickness 0.1524)
				)
			)
		)
		(fp_text user "12"
			(at 2.207768 2.7178 180)
			(unlocked yes)
			(layer "F.Fab")
			(effects
				(font
					(size 0.635 0.4064)
					(thickness 0.1524)
				)
			)
		)
		(fp_text user "9"
			(at -2.338832 2.5908 180)
			(unlocked yes)
			(layer "F.Fab")
			(effects
				(font
					(size 0.635 0.4064)
					(thickness 0.1524)
				)
			)
		)
		(fp_text user "20"
			(at 2.055368 -2.7686 180)
			(unlocked yes)
			(layer "F.Fab")
			(effects
				(font
					(size 0.635 0.4064)
					(thickness 0.1524)
				)
			)
		)
		(fp_text user "21_22"
			(at -0.0762 -3.401568 270)
			(unlocked yes)
			(layer "F.Fab")
			(effects
				(font
					(size 0.635 0.4064)
					(thickness 0.1524)
				)
			)
		)
		(pad "1" smd circle
			(at -1.374902 -1.999996 180)
			(size 0 0)
			(layers "F.Cu" "F.Mask" "F.Paste")
			(net "P12V_SCM_EN_R2")
		)
		(pad "2" smd rect
			(at -1.400048 -1.500124 180)
			(size 0.254 0.8128)
			(layers "F.Cu" "F.Mask" "F.Paste")
			(net "GND")
		)
		(pad "3" smd rect
			(at -1.400048 -0.999998 180)
			(size 0.254 0.8128)
			(layers "F.Cu" "F.Mask" "F.Paste")
			(net "GND")
		)
		(pad "4" smd rect
			(at -1.400048 -0.499872 180)
			(size 0.254 0.8128)
			(layers "F.Cu" "F.Mask" "F.Paste")
			(net "P12V_SCM_TIMER")
		)
		(pad "5" smd rect
			(at -1.400048 0 180)
			(size 0.254 0.8128)
			(layers "F.Cu" "F.Mask" "F.Paste")
			(net "P12V_SCM_ISET")
		)
		(pad "6" smd rect
			(at -1.400048 0.499872 180)
			(size 0.254 0.8128)
			(layers "F.Cu" "F.Mask" "F.Paste")
			(net "P12V_SCM_SS")
		)
		(pad "7" smd rect
			(at -1.400048 0.999998 180)
			(size 0.254 0.8128)
			(layers "F.Cu" "F.Mask" "F.Paste")
			(net "GND")
		)
		(pad "8" smd rect
			(at -1.400048 1.500124 180)
			(size 0.254 0.8128)
			(layers "F.Cu" "F.Mask" "F.Paste")
			(net "P12V_SCM_IMON")
		)
		(pad "9" smd rect
			(at -1.400048 1.999996 180)
			(size 0.254 0.8128)
			(layers "F.Cu" "F.Mask" "F.Paste")
			(net "P12V_SCM_FLTB_N")
		)
		(pad "10" smd rect
			(at -0.499872 2.400046 270)
			(size 0.254 0.8128)
			(layers "F.Cu" "F.Mask" "F.Paste")
			(net "HP_LVC3_SCM_HSC_PWRGD_R")
		)
		(pad "11" smd rect
			(at 0.499872 2.400046 270)
			(size 0.254 0.8128)
			(layers "F.Cu" "F.Mask" "F.Paste")
			(net "P12V_SCM_OV_FB")
		)
		(pad "12" smd rect
			(at 1.400048 1.999996 180)
			(size 0.254 0.8128)
			(layers "F.Cu" "F.Mask" "F.Paste")
			(net "P12V_SCM_AVIN_PD")
		)
		(pad "13" smd rect
			(at 1.400048 1.500124 180)
			(size 0.254 0.8128)
			(layers "F.Cu" "F.Mask" "F.Paste")
			(net "P12V_SCM_R")
		)
		(pad "14" smd rect
			(at 1.400048 0.999998 180)
			(size 0.254 0.8128)
			(layers "F.Cu" "F.Mask" "F.Paste")
			(net "P12V_SCM_R")
		)
		(pad "15" smd rect
			(at 1.400048 0.499872 180)
			(size 0.254 0.8128)
			(layers "F.Cu" "F.Mask" "F.Paste")
			(net "P12V_SCM_R")
		)
		(pad "16" smd rect
			(at 1.400048 0 180)
			(size 0.254 0.8128)
			(layers "F.Cu" "F.Mask" "F.Paste")
			(net "P12V_SCM_R")
		)
		(pad "17" smd rect
			(at 1.400048 -0.499872 180)
			(size 0.254 0.8128)
			(layers "F.Cu" "F.Mask" "F.Paste")
			(net "P12V_SCM_R")
		)
		(pad "18" smd rect
			(at 1.400048 -0.999998 180)
			(size 0.254 0.8128)
			(layers "F.Cu" "F.Mask" "F.Paste")
			(net "P12V_SCM_R")
		)
		(pad "19" smd rect
			(at 1.400048 -1.500124 180)
			(size 0.254 0.8128)
			(layers "F.Cu" "F.Mask" "F.Paste")
			(net "P12V_SCM_R")
		)
		(pad "20" smd rect
			(at 1.400048 -1.999996 180)
			(size 0.254 0.8128)
			(layers "F.Cu" "F.Mask" "F.Paste")
			(net "P12V_SCM_R")
		)
		(pad "21_22" smd circle
			(at 0.499872 -2.337562 180)
			(size 0 0)
			(layers "F.Cu" "F.Mask" "F.Paste")
			(net "P12V_AUX")
		)
		(pad "23" smd rect
			(at 0 -1.100074 180)
			(size 0.254 1.27)
			(layers "F.Cu" "F.Mask" "F.Paste")
			(net "P12V_AUX")
		)
		(pad "24" smd rect
			(at 0 -0.199898 180)
			(size 0.254 1.27)
			(layers "F.Cu" "F.Mask" "F.Paste")
			(net "P12V_AUX")
		)
		(pad "25" smd rect
			(at 0 0.700024 180)
			(size 0.254 1.27)
			(layers "F.Cu" "F.Mask" "F.Paste")
			(net "P12V_AUX")
		)
		(pad "26" smd rect
			(at 0 1.599946 180)
			(size 0.254 1.27)
			(layers "F.Cu" "F.Mask" "F.Paste")
			(net "P12V_AUX")
		)
	)
	(footprint ""
		(layer "F.Cu")
		(at 339.238844 -381.41783 -90)
		(property "Reference" "C954"
			(at 0 0 270)
			(layer "F.SilkS")
			(hide yes)
			(effects
				(font
					(size 1.27 1.27)
				)
			)
		)
		(property "Value" ""
			(at 0 0 270)
			(layer "F.Fab")
			(effects
				(font
					(size 1.27 1.27)
				)
			)
		)
		(duplicate_pad_numbers_are_jumpers no)
		(fp_line
			(start -0.299974 0.150114)
			(end -0.299974 -0.150114)
			(stroke
				(width 0.1)
				(type default)
			)
			(layer "F.Fab")
		)
		(fp_line
			(start 0.299974 0.150114)
			(end -0.299974 0.150114)
			(stroke
				(width 0.1)
				(type default)
			)
			(layer "F.Fab")
		)
		(fp_line
			(start -0.299974 -0.150114)
			(end 0.299974 -0.150114)
			(stroke
				(width 0.1)
				(type default)
			)
			(layer "F.Fab")
		)
		(fp_line
			(start 0.299974 -0.150114)
			(end 0.299974 0.150114)
			(stroke
				(width 0.1)
				(type default)
			)
			(layer "F.Fab")
		)
		(pad "1" smd rect
			(at -0.2667 0 270)
			(size 0.3048 0.381)
			(layers "F.Cu" "F.Mask" "F.Paste")
			(net "P5E_CPU0_P1_TX_C_DN<5>")
		)
		(pad "2" smd rect
			(at 0.2667 0 270)
			(size 0.3048 0.381)
			(layers "F.Cu" "F.Mask" "F.Paste")
			(net "P5E_CPU0_P1_TX_DN<5>")
		)
	)
	(footprint ""
		(layer "F.Cu")
		(at 63.194438 -28.382722)
		(property "Reference" "R3848"
			(at 0 0 0)
			(layer "F.SilkS")
			(hide yes)
			(effects
				(font
					(size 1.27 1.27)
				)
			)
		)
		(property "Value" ""
			(at 0 0 0)
			(layer "F.Fab")
			(effects
				(font
					(size 1.27 1.27)
				)
			)
		)
		(duplicate_pad_numbers_are_jumpers no)
		(fp_line
			(start -0.7874 -0.4064)
			(end 0.7874 -0.4064)
			(stroke
				(width 0.1524)
				(type default)
			)
			(layer "F.SilkS")
		)
		(fp_line
			(start -0.7874 0.4064)
			(end -0.7874 -0.4064)
			(stroke
				(width 0.1524)
				(type default)
			)
			(layer "F.SilkS")
		)
		(fp_line
			(start 0.7874 -0.4064)
			(end 0.7874 0.4064)
			(stroke
				(width 0.1524)
				(type default)
			)
			(layer "F.SilkS")
		)
		(fp_line
			(start 0.7874 0.4064)
			(end -0.7874 0.4064)
			(stroke
				(width 0.1524)
				(type default)
			)
			(layer "F.SilkS")
		)
		(fp_line
			(start -0.67945 -0.305054)
			(end -0.12065 -0.305054)
			(stroke
				(width 0.1)
				(type default)
			)
			(layer "F.Fab")
		)
		(fp_line
			(start -0.67945 0.3048)
			(end -0.67945 -0.305054)
			(stroke
				(width 0.1)
				(type default)
			)
			(layer "F.Fab")
		)
		(fp_line
			(start -0.12065 -0.305054)
			(end -0.12065 -0.2794)
			(stroke
				(width 0.1)
				(type default)
			)
			(layer "F.Fab")
		)
		(fp_line
			(start -0.12065 -0.2794)
			(end 0.12065 -0.2794)
			(stroke
				(width 0.1)
				(type default)
			)
			(layer "F.Fab")
		)
		(fp_line
			(start -0.12065 0.2794)
			(end -0.12065 0.3048)
			(stroke
				(width 0.1)
				(type default)
			)
			(layer "F.Fab")
		)
		(fp_line
			(start -0.12065 0.3048)
			(end -0.67945 0.3048)
			(stroke
				(width 0.1)
				(type default)
			)
			(layer "F.Fab")
		)
		(fp_line
			(start 0.120396 0.2794)
			(end -0.12065 0.2794)
			(stroke
				(width 0.1)
				(type default)
			)
			(layer "F.Fab")
		)
		(fp_line
			(start 0.120396 0.3048)
			(end 0.120396 0.2794)
			(stroke
				(width 0.1)
				(type default)
			)
			(layer "F.Fab")
		)
		(fp_line
			(start 0.12065 -0.3048)
			(end 0.67945 -0.3048)
			(stroke
				(width 0.1)
				(type default)
			)
			(layer "F.Fab")
		)
		(fp_line
			(start 0.12065 -0.2794)
			(end 0.12065 -0.3048)
			(stroke
				(width 0.1)
				(type default)
			)
			(layer "F.Fab")
		)
		(fp_line
			(start 0.67945 -0.3048)
			(end 0.67945 0.3048)
			(stroke
				(width 0.1)
				(type default)
			)
			(layer "F.Fab")
		)
		(fp_line
			(start 0.67945 0.3048)
			(end 0.120396 0.3048)
			(stroke
				(width 0.1)
				(type default)
			)
			(layer "F.Fab")
		)
		(pad "1" smd circle
			(at -0.40005 0)
			(size 0 0)
			(layers "F.Cu" "F.Mask" "F.Paste")
			(net "P3V3_AUX")
		)
		(pad "2" smd circle
			(at 0.40005 0)
			(size 0 0)
			(layers "F.Cu" "F.Mask" "F.Paste")
			(net "HP_LVC3_OCP_V3_2_P12V_PWRGD")
		)
	)
	(footprint ""
		(layer "F.Cu")
		(at 105.64876 -59.802268)
		(property "Reference" "R1731"
			(at 0 0 0)
			(layer "F.SilkS")
			(hide yes)
			(effects
				(font
					(size 1.27 1.27)
				)
			)
		)
		(property "Value" ""
			(at 0 0 0)
			(layer "F.Fab")
			(effects
				(font
					(size 1.27 1.27)
				)
			)
		)
		(duplicate_pad_numbers_are_jumpers no)
		(fp_line
			(start -0.7874 -0.4064)
			(end 0.7874 -0.4064)
			(stroke
				(width 0.1524)
				(type default)
			)
			(layer "F.SilkS")
		)
		(fp_line
			(start -0.7874 0.4064)
			(end -0.7874 -0.4064)
			(stroke
				(width 0.1524)
				(type default)
			)
			(layer "F.SilkS")
		)
		(fp_line
			(start 0.7874 -0.4064)
			(end 0.7874 0.4064)
			(stroke
				(width 0.1524)
				(type default)
			)
			(layer "F.SilkS")
		)
		(fp_line
			(start 0.7874 0.4064)
			(end -0.7874 0.4064)
			(stroke
				(width 0.1524)
				(type default)
			)
			(layer "F.SilkS")
		)
		(fp_line
			(start -0.67945 -0.305054)
			(end -0.12065 -0.305054)
			(stroke
				(width 0.1)
				(type default)
			)
			(layer "F.Fab")
		)
		(fp_line
			(start -0.67945 0.3048)
			(end -0.67945 -0.305054)
			(stroke
				(width 0.1)
				(type default)
			)
			(layer "F.Fab")
		)
		(fp_line
			(start -0.12065 -0.305054)
			(end -0.12065 -0.2794)
			(stroke
				(width 0.1)
				(type default)
			)
			(layer "F.Fab")
		)
		(fp_line
			(start -0.12065 -0.2794)
			(end 0.12065 -0.2794)
			(stroke
				(width 0.1)
				(type default)
			)
			(layer "F.Fab")
		)
		(fp_line
			(start -0.12065 0.2794)
			(end -0.12065 0.3048)
			(stroke
				(width 0.1)
				(type default)
			)
			(layer "F.Fab")
		)
		(fp_line
			(start -0.12065 0.3048)
			(end -0.67945 0.3048)
			(stroke
				(width 0.1)
				(type default)
			)
			(layer "F.Fab")
		)
		(fp_line
			(start 0.120396 0.2794)
			(end -0.12065 0.2794)
			(stroke
				(width 0.1)
				(type default)
			)
			(layer "F.Fab")
		)
		(fp_line
			(start 0.120396 0.3048)
			(end 0.120396 0.2794)
			(stroke
				(width 0.1)
				(type default)
			)
			(layer "F.Fab")
		)
		(fp_line
			(start 0.12065 -0.3048)
			(end 0.67945 -0.3048)
			(stroke
				(width 0.1)
				(type default)
			)
			(layer "F.Fab")
		)
		(fp_line
			(start 0.12065 -0.2794)
			(end 0.12065 -0.3048)
			(stroke
				(width 0.1)
				(type default)
			)
			(layer "F.Fab")
		)
		(fp_line
			(start 0.67945 -0.3048)
			(end 0.67945 0.3048)
			(stroke
				(width 0.1)
				(type default)
			)
			(layer "F.Fab")
		)
		(fp_line
			(start 0.67945 0.3048)
			(end 0.120396 0.3048)
			(stroke
				(width 0.1)
				(type default)
			)
			(layer "F.Fab")
		)
		(pad "1" smd circle
			(at -0.40005 0)
			(size 0 0)
			(layers "F.Cu" "F.Mask" "F.Paste")
			(net "P3V3_AUX")
		)
		(pad "2" smd circle
			(at 0.40005 0)
			(size 0 0)
			(layers "F.Cu" "F.Mask" "F.Paste")
			(net "JTAG_SCM_TMS")
		)
	)
	(footprint ""
		(layer "F.Cu")
		(at 366.288574 5.082794 180)
		(property "Reference" "J65"
			(at -4.652264 -1.360932 90)
			(unlocked yes)
			(layer "F.SilkS")
			(effects
				(font
					(size 0.7874 0.5842)
					(thickness 0.1524)
				)
				(justify left)
			)
		)
		(property "Value" ""
			(at 0 0 180)
			(layer "F.Fab")
			(effects
				(font
					(size 1.27 1.27)
				)
			)
		)
		(duplicate_pad_numbers_are_jumpers no)
		(fp_line
			(start 1.2192 2.06756)
			(end -1.2192 2.06756)
			(stroke
				(width 0.1524)
				(type default)
			)
			(layer "F.SilkS")
		)
		(fp_line
			(start 1.2192 -2.06756)
			(end 1.2192 2.06756)
			(stroke
				(width 0.1524)
				(type default)
			)
			(layer "F.SilkS")
		)
		(fp_line
			(start -1.2192 2.06756)
			(end -1.2192 -2.06756)
			(stroke
				(width 0.1524)
				(type default)
			)
			(layer "F.SilkS")
		)
		(fp_line
			(start -1.2192 -2.06756)
			(end 1.2192 -2.06756)
			(stroke
				(width 0.1524)
				(type default)
			)
			(layer "F.SilkS")
		)
		(pad "" np_thru_hole circle
			(at -2.8829 -1.27 90)
			(size 1.0414 1.0414)
			(drill 1.0414)
			(layers "*.Cu" "*.Mask")
			(clearance 0.381)
			(thermal_gap 0.381)
		)
		(pad "" np_thru_hole circle
			(at -2.8829 1.27 90)
			(size 1.0414 1.0414)
			(drill 1.0414)
			(layers "*.Cu" "*.Mask")
			(clearance 0.381)
			(thermal_gap 0.381)
		)
		(pad "" np_thru_hole circle
			(at 3.4671 -1.27 90)
			(size 1.0414 1.0414)
			(drill 1.0414)
			(layers "*.Cu" "*.Mask")
			(clearance 0.381)
			(thermal_gap 0.381)
		)
		(pad "" np_thru_hole circle
			(at 3.4671 1.27 90)
			(size 1.0414 1.0414)
			(drill 1.0414)
			(layers "*.Cu" "*.Mask")
			(clearance 0.381)
			(thermal_gap 0.381)
		)
		(pad "1" smd rect
			(at 0.8255 -0.249936 90)
			(size 0.3048 0.508)
			(layers "F.Cu" "F.Mask" "F.Paste")
			(net "DELTA_L_85_5INCH_IN1_DP")
		)
		(pad "2" smd rect
			(at 0.8255 0.249936 90)
			(size 0.3048 0.508)
			(layers "F.Cu" "F.Mask" "F.Paste")
			(net "DELTA_L_85_5INCH_IN1_DN")
		)
		(pad "3" smd circle
			(at 0 0 180)
			(size 0 0)
			(layers "F.Cu" "F.Mask" "F.Paste")
			(net "DELTA_L_GND_1")
		)
		(zone
			(layer "F.Cu")
			(hatch none 0.5)
			(connect_pads
				(clearance 0)
			)
			(min_thickness 0.25)
			(keepout
				(tracks not_allowed)
				(vias allowed)
				(pads allowed)
				(copperpour not_allowed)
				(footprints allowed)
			)
			(placement
				(enabled no)
				(sheetname "")
			)
			(fill
				(thermal_gap 0.5)
				(thermal_bridge_width 0.5)
				(island_removal_mode 0)
			)
			(polygon
				(pts
					(xy 365.170974 5.631434) (xy 365.170974 5.53593) (xy 365.767874 5.53593) (xy 365.767874 5.12953)
					(xy 365.170974 5.12953) (xy 365.170974 5.036058) (xy 365.767874 5.036058) (xy 365.767874 4.629658)
					(xy 365.170974 4.629658) (xy 365.170974 4.534154) (xy 365.869474 4.534154) (xy 365.869474 5.631434)
				)
			)
		)
		(zone
			(layers "F.Cu" "B.Cu" "In1.Cu" "In2.Cu" "In3.Cu" "In4.Cu" "In5.Cu" "In6.Cu"
				"In7.Cu" "In8.Cu" "In9.Cu" "In10.Cu" "In11.Cu" "In12.Cu" "In13.Cu" "In14.Cu"
				"In15.Cu" "In16.Cu"
			)
			(hatch none 0.5)
			(connect_pads
				(clearance 0)
			)
			(min_thickness 0.25)
			(keepout
				(tracks not_allowed)
				(vias allowed)
				(pads allowed)
				(copperpour not_allowed)
				(footprints allowed)
			)
			(placement
				(enabled no)
				(sheetname "")
			)
			(fill
				(thermal_gap 0.5)
				(thermal_bridge_width 0.5)
				(island_removal_mode 0)
			)
			(polygon
				(pts
					(arc
						(start 363.748574 3.812794)
						(mid 361.894374 3.812794)
						(end 363.748574 3.812794)
					)
				)
			)
		)
		(zone
			(layers "F.Cu" "B.Cu" "In1.Cu" "In2.Cu" "In3.Cu" "In4.Cu" "In5.Cu" "In6.Cu"
				"In7.Cu" "In8.Cu" "In9.Cu" "In10.Cu" "In11.Cu" "In12.Cu" "In13.Cu" "In14.Cu"
				"In15.Cu" "In16.Cu"
			)
			(hatch none 0.5)
			(connect_pads
				(clearance 0)
			)
			(min_thickness 0.25)
			(keepout
				(tracks not_allowed)
				(vias allowed)
				(pads allowed)
				(copperpour not_allowed)
				(footprints allowed)
			)
			(placement
				(enabled no)
				(sheetname "")
			)
			(fill
				(thermal_gap 0.5)
				(thermal_bridge_width 0.5)
				(island_removal_mode 0)
			)
			(polygon
				(pts
					(arc
						(start 363.748574 6.352794)
						(mid 361.894374 6.352794)
						(end 363.748574 6.352794)
					)
				)
			)
		)
		(zone
			(layers "F.Cu" "B.Cu" "In1.Cu" "In2.Cu" "In3.Cu" "In4.Cu" "In5.Cu" "In6.Cu"
				"In7.Cu" "In8.Cu" "In9.Cu" "In10.Cu" "In11.Cu" "In12.Cu" "In13.Cu" "In14.Cu"
				"In15.Cu" "In16.Cu"
			)
			(hatch none 0.5)
			(connect_pads
				(clearance 0)
			)
			(min_thickness 0.25)
			(keepout
				(tracks not_allowed)
				(vias allowed)
				(pads allowed)
				(copperpour not_allowed)
				(footprints allowed)
			)
			(placement
				(enabled no)
				(sheetname "")
			)
			(fill
				(thermal_gap 0.5)
				(thermal_bridge_width 0.5)
				(island_removal_mode 0)
			)
			(polygon
				(pts
					(arc
						(start 370.098574 3.812794)
						(mid 368.244374 3.812794)
						(end 370.098574 3.812794)
					)
				)
			)
		)
		(zone
			(layers "F.Cu" "B.Cu" "In1.Cu" "In2.Cu" "In3.Cu" "In4.Cu" "In5.Cu" "In6.Cu"
				"In7.Cu" "In8.Cu" "In9.Cu" "In10.Cu" "In11.Cu" "In12.Cu" "In13.Cu" "In14.Cu"
				"In15.Cu" "In16.Cu"
			)
			(hatch none 0.5)
			(connect_pads
				(clearance 0)
			)
			(min_thickness 0.25)
			(keepout
				(tracks not_allowed)
				(vias allowed)
				(pads allowed)
				(copperpour not_allowed)
				(footprints allowed)
			)
			(placement
				(enabled no)
				(sheetname "")
			)
			(fill
				(thermal_gap 0.5)
				(thermal_bridge_width 0.5)
				(island_removal_mode 0)
			)
			(polygon
				(pts
					(arc
						(start 370.098574 6.352794)
						(mid 368.244374 6.352794)
						(end 370.098574 6.352794)
					)
				)
			)
		)
	)
	(footprint ""
		(layer "F.Cu")
		(at 239.50803 -47.003208 180)
		(property "Reference" "R2317"
			(at 0 0 180)
			(layer "F.SilkS")
			(hide yes)
			(effects
				(font
					(size 1.27 1.27)
				)
			)
		)
		(property "Value" ""
			(at 0 0 180)
			(layer "F.Fab")
			(effects
				(font
					(size 1.27 1.27)
				)
			)
		)
		(duplicate_pad_numbers_are_jumpers no)
		(fp_line
			(start 0.7874 0.4064)
			(end -0.7874 0.4064)
			(stroke
				(width 0.1524)
				(type default)
			)
			(layer "F.SilkS")
		)
		(fp_line
			(start 0.7874 -0.4064)
			(end 0.7874 0.4064)
			(stroke
				(width 0.1524)
				(type default)
			)
			(layer "F.SilkS")
		)
		(fp_line
			(start -0.7874 0.4064)
			(end -0.7874 -0.4064)
			(stroke
				(width 0.1524)
				(type default)
			)
			(layer "F.SilkS")
		)
		(fp_line
			(start -0.7874 -0.4064)
			(end 0.7874 -0.4064)
			(stroke
				(width 0.1524)
				(type default)
			)
			(layer "F.SilkS")
		)
		(fp_line
			(start 0.67945 0.3048)
			(end 0.120396 0.3048)
			(stroke
				(width 0.1)
				(type default)
			)
			(layer "F.Fab")
		)
		(fp_line
			(start 0.67945 -0.3048)
			(end 0.67945 0.3048)
			(stroke
				(width 0.1)
				(type default)
			)
			(layer "F.Fab")
		)
		(fp_line
			(start 0.12065 -0.2794)
			(end 0.12065 -0.3048)
			(stroke
				(width 0.1)
				(type default)
			)
			(layer "F.Fab")
		)
		(fp_line
			(start 0.12065 -0.3048)
			(end 0.67945 -0.3048)
			(stroke
				(width 0.1)
				(type default)
			)
			(layer "F.Fab")
		)
		(fp_line
			(start 0.120396 0.3048)
			(end 0.120396 0.2794)
			(stroke
				(width 0.1)
				(type default)
			)
			(layer "F.Fab")
		)
		(fp_line
			(start 0.120396 0.2794)
			(end -0.12065 0.2794)
			(stroke
				(width 0.1)
				(type default)
			)
			(layer "F.Fab")
		)
		(fp_line
			(start -0.12065 0.3048)
			(end -0.67945 0.3048)
			(stroke
				(width 0.1)
				(type default)
			)
			(layer "F.Fab")
		)
		(fp_line
			(start -0.12065 0.2794)
			(end -0.12065 0.3048)
			(stroke
				(width 0.1)
				(type default)
			)
			(layer "F.Fab")
		)
		(fp_line
			(start -0.12065 -0.2794)
			(end 0.12065 -0.2794)
			(stroke
				(width 0.1)
				(type default)
			)
			(layer "F.Fab")
		)
		(fp_line
			(start -0.12065 -0.305054)
			(end -0.12065 -0.2794)
			(stroke
				(width 0.1)
				(type default)
			)
			(layer "F.Fab")
		)
		(fp_line
			(start -0.67945 0.3048)
			(end -0.67945 -0.305054)
			(stroke
				(width 0.1)
				(type default)
			)
			(layer "F.Fab")
		)
		(fp_line
			(start -0.67945 -0.305054)
			(end -0.12065 -0.305054)
			(stroke
				(width 0.1)
				(type default)
			)
			(layer "F.Fab")
		)
		(pad "1" smd circle
			(at -0.40005 0 180)
			(size 0 0)
			(layers "F.Cu" "F.Mask" "F.Paste")
			(net "P3V3_E1S_0")
		)
		(pad "2" smd circle
			(at 0.40005 0 180)
			(size 0 0)
			(layers "F.Cu" "F.Mask" "F.Paste")
			(net "PU_E1S_0_DUALPORT_EN_N")
		)
	)
	(footprint ""
		(layer "F.Cu")
		(at 430.3776 -16.100298 90)
		(property "Reference" "C1577"
			(at 0 0 90)
			(layer "F.SilkS")
			(hide yes)
			(effects
				(font
					(size 1.27 1.27)
				)
			)
		)
		(property "Value" ""
			(at 0 0 90)
			(layer "F.Fab")
			(effects
				(font
					(size 1.27 1.27)
				)
			)
		)
		(duplicate_pad_numbers_are_jumpers no)
		(fp_line
			(start 0.299974 -0.150114)
			(end 0.299974 0.150114)
			(stroke
				(width 0.1)
				(type default)
			)
			(layer "F.Fab")
		)
		(fp_line
			(start -0.299974 -0.150114)
			(end 0.299974 -0.150114)
			(stroke
				(width 0.1)
				(type default)
			)
			(layer "F.Fab")
		)
		(fp_line
			(start 0.299974 0.150114)
			(end -0.299974 0.150114)
			(stroke
				(width 0.1)
				(type default)
			)
			(layer "F.Fab")
		)
		(fp_line
			(start -0.299974 0.150114)
			(end -0.299974 -0.150114)
			(stroke
				(width 0.1)
				(type default)
			)
			(layer "F.Fab")
		)
		(pad "1" smd rect
			(at -0.2667 0 90)
			(size 0.3048 0.381)
			(layers "F.Cu" "F.Mask" "F.Paste")
			(net "P5E_CPU0_G3_TX_C_DP<1>")
		)
		(pad "2" smd rect
			(at 0.2667 0 90)
			(size 0.3048 0.381)
			(layers "F.Cu" "F.Mask" "F.Paste")
			(net "P5E_CPU0_G3_TX_DP<1>")
		)
	)
	(footprint ""
		(layer "F.Cu")
		(at 352.425254 -344.586306 90)
		(property "Reference" "PR420"
			(at 0 0 90)
			(layer "F.SilkS")
			(hide yes)
			(effects
				(font
					(size 1.27 1.27)
				)
			)
		)
		(property "Value" ""
			(at 0 0 90)
			(layer "F.Fab")
			(effects
				(font
					(size 1.27 1.27)
				)
			)
		)
		(duplicate_pad_numbers_are_jumpers no)
		(fp_line
			(start 0.7874 -0.4064)
			(end 0.7874 0.4064)
			(stroke
				(width 0.1524)
				(type default)
			)
			(layer "F.SilkS")
		)
		(fp_line
			(start -0.7874 -0.4064)
			(end 0.7874 -0.4064)
			(stroke
				(width 0.1524)
				(type default)
			)
			(layer "F.SilkS")
		)
		(fp_line
			(start 0.7874 0.4064)
			(end -0.7874 0.4064)
			(stroke
				(width 0.1524)
				(type default)
			)
			(layer "F.SilkS")
		)
		(fp_line
			(start -0.7874 0.4064)
			(end -0.7874 -0.4064)
			(stroke
				(width 0.1524)
				(type default)
			)
			(layer "F.SilkS")
		)
		(fp_line
			(start -0.12065 -0.305054)
			(end -0.12065 -0.2794)
			(stroke
				(width 0.1)
				(type default)
			)
			(layer "F.Fab")
		)
		(fp_line
			(start -0.67945 -0.305054)
			(end -0.12065 -0.305054)
			(stroke
				(width 0.1)
				(type default)
			)
			(layer "F.Fab")
		)
		(fp_line
			(start 0.67945 -0.3048)
			(end 0.67945 0.3048)
			(stroke
				(width 0.1)
				(type default)
			)
			(layer "F.Fab")
		)
		(fp_line
			(start 0.12065 -0.3048)
			(end 0.67945 -0.3048)
			(stroke
				(width 0.1)
				(type default)
			)
			(layer "F.Fab")
		)
		(fp_line
			(start 0.12065 -0.2794)
			(end 0.12065 -0.3048)
			(stroke
				(width 0.1)
				(type default)
			)
			(layer "F.Fab")
		)
		(fp_line
			(start -0.12065 -0.2794)
			(end 0.12065 -0.2794)
			(stroke
				(width 0.1)
				(type default)
			)
			(layer "F.Fab")
		)
		(fp_line
			(start 0.120396 0.2794)
			(end -0.12065 0.2794)
			(stroke
				(width 0.1)
				(type default)
			)
			(layer "F.Fab")
		)
		(fp_line
			(start -0.12065 0.2794)
			(end -0.12065 0.3048)
			(stroke
				(width 0.1)
				(type default)
			)
			(layer "F.Fab")
		)
		(fp_line
			(start 0.67945 0.3048)
			(end 0.120396 0.3048)
			(stroke
				(width 0.1)
				(type default)
			)
			(layer "F.Fab")
		)
		(fp_line
			(start 0.120396 0.3048)
			(end 0.120396 0.2794)
			(stroke
				(width 0.1)
				(type default)
			)
			(layer "F.Fab")
		)
		(fp_line
			(start -0.12065 0.3048)
			(end -0.67945 0.3048)
			(stroke
				(width 0.1)
				(type default)
			)
			(layer "F.Fab")
		)
		(fp_line
			(start -0.67945 0.3048)
			(end -0.67945 -0.305054)
			(stroke
				(width 0.1)
				(type default)
			)
			(layer "F.Fab")
		)
		(pad "1" smd circle
			(at -0.40005 0 90)
			(size 0 0)
			(layers "F.Cu" "F.Mask" "F.Paste")
			(net "SW_PVDDCR_CPU1_P0_BOOT6")
		)
		(pad "2" smd circle
			(at 0.40005 0 90)
			(size 0 0)
			(layers "F.Cu" "F.Mask" "F.Paste")
			(net "SW_PVDDCR_CPU1_P0_BOOT6_R")
		)
	)
	(footprint ""
		(layer "F.Cu")
		(at 351.151444 -383.88163 -90)
		(property "Reference" "C944"
			(at 0 0 270)
			(layer "F.SilkS")
			(hide yes)
			(effects
				(font
					(size 1.27 1.27)
				)
			)
		)
		(property "Value" ""
			(at 0 0 270)
			(layer "F.Fab")
			(effects
				(font
					(size 1.27 1.27)
				)
			)
		)
		(duplicate_pad_numbers_are_jumpers no)
		(fp_line
			(start -0.299974 0.150114)
			(end -0.299974 -0.150114)
			(stroke
				(width 0.1)
				(type default)
			)
			(layer "F.Fab")
		)
		(fp_line
			(start 0.299974 0.150114)
			(end -0.299974 0.150114)
			(stroke
				(width 0.1)
				(type default)
			)
			(layer "F.Fab")
		)
		(fp_line
			(start -0.299974 -0.150114)
			(end 0.299974 -0.150114)
			(stroke
				(width 0.1)
				(type default)
			)
			(layer "F.Fab")
		)
		(fp_line
			(start 0.299974 -0.150114)
			(end 0.299974 0.150114)
			(stroke
				(width 0.1)
				(type default)
			)
			(layer "F.Fab")
		)
		(pad "1" smd rect
			(at -0.2667 0 270)
			(size 0.3048 0.381)
			(layers "F.Cu" "F.Mask" "F.Paste")
			(net "P5E_CPU0_P1_TX_C_DN<10>")
		)
		(pad "2" smd rect
			(at 0.2667 0 270)
			(size 0.3048 0.381)
			(layers "F.Cu" "F.Mask" "F.Paste")
			(net "P5E_CPU0_P1_TX_DN<10>")
		)
	)
	(footprint ""
		(layer "F.Cu")
		(at 205.159356 -114.249708)
		(property "Reference" "R4556"
			(at 0 0 0)
			(layer "F.SilkS")
			(hide yes)
			(effects
				(font
					(size 1.27 1.27)
				)
			)
		)
		(property "Value" ""
			(at 0 0 0)
			(layer "F.Fab")
			(effects
				(font
					(size 1.27 1.27)
				)
			)
		)
		(duplicate_pad_numbers_are_jumpers no)
		(fp_line
			(start -0.7874 -0.4064)
			(end 0.7874 -0.4064)
			(stroke
				(width 0.1524)
				(type default)
			)
			(layer "F.SilkS")
		)
		(fp_line
			(start -0.7874 0.4064)
			(end -0.7874 -0.4064)
			(stroke
				(width 0.1524)
				(type default)
			)
			(layer "F.SilkS")
		)
		(fp_line
			(start 0.7874 -0.4064)
			(end 0.7874 0.4064)
			(stroke
				(width 0.1524)
				(type default)
			)
			(layer "F.SilkS")
		)
		(fp_line
			(start 0.7874 0.4064)
			(end -0.7874 0.4064)
			(stroke
				(width 0.1524)
				(type default)
			)
			(layer "F.SilkS")
		)
		(fp_line
			(start -0.67945 -0.305054)
			(end -0.12065 -0.305054)
			(stroke
				(width 0.1)
				(type default)
			)
			(layer "F.Fab")
		)
		(fp_line
			(start -0.67945 0.3048)
			(end -0.67945 -0.305054)
			(stroke
				(width 0.1)
				(type default)
			)
			(layer "F.Fab")
		)
		(fp_line
			(start -0.12065 -0.305054)
			(end -0.12065 -0.2794)
			(stroke
				(width 0.1)
				(type default)
			)
			(layer "F.Fab")
		)
		(fp_line
			(start -0.12065 -0.2794)
			(end 0.12065 -0.2794)
			(stroke
				(width 0.1)
				(type default)
			)
			(layer "F.Fab")
		)
		(fp_line
			(start -0.12065 0.2794)
			(end -0.12065 0.3048)
			(stroke
				(width 0.1)
				(type default)
			)
			(layer "F.Fab")
		)
		(fp_line
			(start -0.12065 0.3048)
			(end -0.67945 0.3048)
			(stroke
				(width 0.1)
				(type default)
			)
			(layer "F.Fab")
		)
		(fp_line
			(start 0.120396 0.2794)
			(end -0.12065 0.2794)
			(stroke
				(width 0.1)
				(type default)
			)
			(layer "F.Fab")
		)
		(fp_line
			(start 0.120396 0.3048)
			(end 0.120396 0.2794)
			(stroke
				(width 0.1)
				(type default)
			)
			(layer "F.Fab")
		)
		(fp_line
			(start 0.12065 -0.3048)
			(end 0.67945 -0.3048)
			(stroke
				(width 0.1)
				(type default)
			)
			(layer "F.Fab")
		)
		(fp_line
			(start 0.12065 -0.2794)
			(end 0.12065 -0.3048)
			(stroke
				(width 0.1)
				(type default)
			)
			(layer "F.Fab")
		)
		(fp_line
			(start 0.67945 -0.3048)
			(end 0.67945 0.3048)
			(stroke
				(width 0.1)
				(type default)
			)
			(layer "F.Fab")
		)
		(fp_line
			(start 0.67945 0.3048)
			(end 0.120396 0.3048)
			(stroke
				(width 0.1)
				(type default)
			)
			(layer "F.Fab")
		)
		(pad "1" smd circle
			(at -0.40005 0)
			(size 0 0)
			(layers "F.Cu" "F.Mask" "F.Paste")
			(net "HGX_DETECT_N_R")
		)
		(pad "2" smd circle
			(at 0.40005 0)
			(size 0 0)
			(layers "F.Cu" "F.Mask" "F.Paste")
			(net "HGX_DETECT_N")
		)
	)
	(footprint ""
		(layer "F.Cu")
		(at 260.340094 -141.968728 90)
		(property "Reference" "R605"
			(at 0 0 90)
			(layer "F.SilkS")
			(hide yes)
			(effects
				(font
					(size 1.27 1.27)
				)
			)
		)
		(property "Value" ""
			(at 0 0 90)
			(layer "F.Fab")
			(effects
				(font
					(size 1.27 1.27)
				)
			)
		)
		(duplicate_pad_numbers_are_jumpers no)
		(fp_line
			(start 0.7874 -0.4064)
			(end 0.7874 0.4064)
			(stroke
				(width 0.1524)
				(type default)
			)
			(layer "F.SilkS")
		)
		(fp_line
			(start -0.7874 -0.4064)
			(end 0.7874 -0.4064)
			(stroke
				(width 0.1524)
				(type default)
			)
			(layer "F.SilkS")
		)
		(fp_line
			(start 0.7874 0.4064)
			(end -0.7874 0.4064)
			(stroke
				(width 0.1524)
				(type default)
			)
			(layer "F.SilkS")
		)
		(fp_line
			(start -0.7874 0.4064)
			(end -0.7874 -0.4064)
			(stroke
				(width 0.1524)
				(type default)
			)
			(layer "F.SilkS")
		)
		(fp_line
			(start -0.12065 -0.305054)
			(end -0.12065 -0.2794)
			(stroke
				(width 0.1)
				(type default)
			)
			(layer "F.Fab")
		)
		(fp_line
			(start -0.67945 -0.305054)
			(end -0.12065 -0.305054)
			(stroke
				(width 0.1)
				(type default)
			)
			(layer "F.Fab")
		)
		(fp_line
			(start 0.67945 -0.3048)
			(end 0.67945 0.3048)
			(stroke
				(width 0.1)
				(type default)
			)
			(layer "F.Fab")
		)
		(fp_line
			(start 0.12065 -0.3048)
			(end 0.67945 -0.3048)
			(stroke
				(width 0.1)
				(type default)
			)
			(layer "F.Fab")
		)
		(fp_line
			(start 0.12065 -0.2794)
			(end 0.12065 -0.3048)
			(stroke
				(width 0.1)
				(type default)
			)
			(layer "F.Fab")
		)
		(fp_line
			(start -0.12065 -0.2794)
			(end 0.12065 -0.2794)
			(stroke
				(width 0.1)
				(type default)
			)
			(layer "F.Fab")
		)
		(fp_line
			(start 0.120396 0.2794)
			(end -0.12065 0.2794)
			(stroke
				(width 0.1)
				(type default)
			)
			(layer "F.Fab")
		)
		(fp_line
			(start -0.12065 0.2794)
			(end -0.12065 0.3048)
			(stroke
				(width 0.1)
				(type default)
			)
			(layer "F.Fab")
		)
		(fp_line
			(start 0.67945 0.3048)
			(end 0.120396 0.3048)
			(stroke
				(width 0.1)
				(type default)
			)
			(layer "F.Fab")
		)
		(fp_line
			(start 0.120396 0.3048)
			(end 0.120396 0.2794)
			(stroke
				(width 0.1)
				(type default)
			)
			(layer "F.Fab")
		)
		(fp_line
			(start -0.12065 0.3048)
			(end -0.67945 0.3048)
			(stroke
				(width 0.1)
				(type default)
			)
			(layer "F.Fab")
		)
		(fp_line
			(start -0.67945 0.3048)
			(end -0.67945 -0.305054)
			(stroke
				(width 0.1)
				(type default)
			)
			(layer "F.Fab")
		)
		(pad "1" smd circle
			(at -0.40005 0 90)
			(size 0 0)
			(layers "F.Cu" "F.Mask" "F.Paste")
			(net "SPI_CPU0_LVC3_D1")
		)
		(pad "2" smd circle
			(at 0.40005 0 90)
			(size 0 0)
			(layers "F.Cu" "F.Mask" "F.Paste")
			(net "SPI_CPU0_LVC3_SCM_D1")
		)
	)
	(footprint ""
		(layer "F.Cu")
		(at 336.172556 -131.99745)
		(property "Reference" "PC8002"
			(at 0 0 0)
			(layer "F.SilkS")
			(hide yes)
			(effects
				(font
					(size 1.27 1.27)
				)
			)
		)
		(property "Value" ""
			(at 0 0 0)
			(layer "F.Fab")
			(effects
				(font
					(size 1.27 1.27)
				)
			)
		)
		(duplicate_pad_numbers_are_jumpers no)
		(fp_line
			(start -1.524 -0.762)
			(end 1.524 -0.762)
			(stroke
				(width 0.1524)
				(type default)
			)
			(layer "F.SilkS")
		)
		(fp_line
			(start -1.524 0.762)
			(end -1.524 -0.762)
			(stroke
				(width 0.1524)
				(type default)
			)
			(layer "F.SilkS")
		)
		(fp_line
			(start 1.524 -0.762)
			(end 1.524 0.762)
			(stroke
				(width 0.1524)
				(type default)
			)
			(layer "F.SilkS")
		)
		(fp_line
			(start 1.524 0.762)
			(end -1.524 0.762)
			(stroke
				(width 0.1524)
				(type default)
			)
			(layer "F.SilkS")
		)
		(fp_line
			(start -1.1049 -0.724916)
			(end -1.1049 0.724916)
			(stroke
				(width 0.1)
				(type default)
			)
			(layer "F.Fab")
		)
		(fp_line
			(start -1.1049 0.724916)
			(end 1.1049 0.724916)
			(stroke
				(width 0.1)
				(type default)
			)
			(layer "F.Fab")
		)
		(fp_line
			(start 1.1049 -0.724916)
			(end -1.1049 -0.724916)
			(stroke
				(width 0.1)
				(type default)
			)
			(layer "F.Fab")
		)
		(fp_line
			(start 1.1049 0.724916)
			(end 1.1049 -0.724916)
			(stroke
				(width 0.1)
				(type default)
			)
			(layer "F.Fab")
		)
		(pad "1" smd rect
			(at -0.889 0 180)
			(size 1.016 1.27)
			(layers "F.Cu" "F.Mask" "F.Paste")
			(net "SW_P12V_AUX_PVDD18_S5_P0_FLT")
		)
		(pad "2" smd rect
			(at 0.889 0 180)
			(size 1.016 1.27)
			(layers "F.Cu" "F.Mask" "F.Paste")
			(net "GND")
		)
	)
	(footprint ""
		(layer "F.Cu")
		(at 5.260086 -35.495484 180)
		(property "Reference" ""
			(at 0 0 180)
			(layer "F.SilkS")
			(hide yes)
			(effects
				(font
					(size 1.27 1.27)
				)
			)
		)
		(property "Value" ""
			(at 0 0 180)
			(layer "F.Fab")
			(effects
				(font
					(size 1.27 1.27)
				)
			)
		)
		(duplicate_pad_numbers_are_jumpers no)
		(pad "1" smd circle
			(at 0 0 180)
			(size 0.9906 0.9906)
			(layers "F.Cu" "F.Mask" "F.Paste")
			(net "Net_10726")
		)
		(zone
			(layer "F.Cu")
			(hatch none 0.5)
			(connect_pads
				(clearance 0)
			)
			(min_thickness 0.25)
			(keepout
				(tracks not_allowed)
				(vias allowed)
				(pads allowed)
				(copperpour not_allowed)
				(footprints allowed)
			)
			(placement
				(enabled no)
				(sheetname "")
			)
			(fill
				(thermal_gap 0.5)
				(thermal_bridge_width 0.5)
				(island_removal_mode 0)
			)
			(polygon
				(pts
					(arc
						(start 6.885686 -35.495484)
						(mid 3.634486 -35.495484)
						(end 6.885686 -35.495484)
					)
				)
			)
		)
	)
	(footprint ""
		(layer "F.Cu")
		(at 10.066782 -408.405584 180)
		(property "Reference" "PC819"
			(at 0 0 180)
			(layer "F.SilkS")
			(hide yes)
			(effects
				(font
					(size 1.27 1.27)
				)
			)
		)
		(property "Value" ""
			(at 0 0 180)
			(layer "F.Fab")
			(effects
				(font
					(size 1.27 1.27)
				)
			)
		)
		(duplicate_pad_numbers_are_jumpers no)
		(fp_line
			(start 0.7874 0.4064)
			(end -0.7874 0.4064)
			(stroke
				(width 0.1524)
				(type default)
			)
			(layer "F.SilkS")
		)
		(fp_line
			(start 0.7874 -0.4064)
			(end 0.7874 0.4064)
			(stroke
				(width 0.1524)
				(type default)
			)
			(layer "F.SilkS")
		)
		(fp_line
			(start -0.7874 0.4064)
			(end -0.7874 -0.4064)
			(stroke
				(width 0.1524)
				(type default)
			)
			(layer "F.SilkS")
		)
		(fp_line
			(start -0.7874 -0.4064)
			(end 0.7874 -0.4064)
			(stroke
				(width 0.1524)
				(type default)
			)
			(layer "F.SilkS")
		)
		(fp_line
			(start 0.67945 0.3048)
			(end 0.120396 0.3048)
			(stroke
				(width 0.1)
				(type default)
			)
			(layer "F.Fab")
		)
		(fp_line
			(start 0.67945 -0.3048)
			(end 0.67945 0.3048)
			(stroke
				(width 0.1)
				(type default)
			)
			(layer "F.Fab")
		)
		(fp_line
			(start 0.12065 -0.2794)
			(end 0.12065 -0.3048)
			(stroke
				(width 0.1)
				(type default)
			)
			(layer "F.Fab")
		)
		(fp_line
			(start 0.12065 -0.3048)
			(end 0.67945 -0.3048)
			(stroke
				(width 0.1)
				(type default)
			)
			(layer "F.Fab")
		)
		(fp_line
			(start 0.120396 0.3048)
			(end 0.120396 0.2794)
			(stroke
				(width 0.1)
				(type default)
			)
			(layer "F.Fab")
		)
		(fp_line
			(start 0.120396 0.2794)
			(end -0.12065 0.2794)
			(stroke
				(width 0.1)
				(type default)
			)
			(layer "F.Fab")
		)
		(fp_line
			(start -0.12065 0.3048)
			(end -0.67945 0.3048)
			(stroke
				(width 0.1)
				(type default)
			)
			(layer "F.Fab")
		)
		(fp_line
			(start -0.12065 0.2794)
			(end -0.12065 0.3048)
			(stroke
				(width 0.1)
				(type default)
			)
			(layer "F.Fab")
		)
		(fp_line
			(start -0.12065 -0.2794)
			(end 0.12065 -0.2794)
			(stroke
				(width 0.1)
				(type default)
			)
			(layer "F.Fab")
		)
		(fp_line
			(start -0.12065 -0.305054)
			(end -0.12065 -0.2794)
			(stroke
				(width 0.1)
				(type default)
			)
			(layer "F.Fab")
		)
		(fp_line
			(start -0.67945 0.3048)
			(end -0.67945 -0.305054)
			(stroke
				(width 0.1)
				(type default)
			)
			(layer "F.Fab")
		)
		(fp_line
			(start -0.67945 -0.305054)
			(end -0.12065 -0.305054)
			(stroke
				(width 0.1)
				(type default)
			)
			(layer "F.Fab")
		)
		(pad "1" smd circle
			(at -0.40005 0 180)
			(size 0 0)
			(layers "F.Cu" "F.Mask" "F.Paste")
			(net "P0V9_RETIMER_CPU1_VINSEN")
		)
		(pad "2" smd circle
			(at 0.40005 0 180)
			(size 0 0)
			(layers "F.Cu" "F.Mask" "F.Paste")
			(net "GND")
		)
	)
	(footprint ""
		(layer "F.Cu")
		(at 57.518554 -373.03583 -90)
		(property "Reference" "C820"
			(at 0 0 270)
			(layer "F.SilkS")
			(hide yes)
			(effects
				(font
					(size 1.27 1.27)
				)
			)
		)
		(property "Value" ""
			(at 0 0 270)
			(layer "F.Fab")
			(effects
				(font
					(size 1.27 1.27)
				)
			)
		)
		(duplicate_pad_numbers_are_jumpers no)
		(fp_line
			(start -0.299974 0.150114)
			(end -0.299974 -0.150114)
			(stroke
				(width 0.1)
				(type default)
			)
			(layer "F.Fab")
		)
		(fp_line
			(start 0.299974 0.150114)
			(end -0.299974 0.150114)
			(stroke
				(width 0.1)
				(type default)
			)
			(layer "F.Fab")
		)
		(fp_line
			(start -0.299974 -0.150114)
			(end 0.299974 -0.150114)
			(stroke
				(width 0.1)
				(type default)
			)
			(layer "F.Fab")
		)
		(fp_line
			(start 0.299974 -0.150114)
			(end 0.299974 0.150114)
			(stroke
				(width 0.1)
				(type default)
			)
			(layer "F.Fab")
		)
		(pad "1" smd rect
			(at -0.2667 0 270)
			(size 0.3048 0.381)
			(layers "F.Cu" "F.Mask" "F.Paste")
			(net "P5E_CPU1_P0_TX_C_DN<8>")
		)
		(pad "2" smd rect
			(at 0.2667 0 270)
			(size 0.3048 0.381)
			(layers "F.Cu" "F.Mask" "F.Paste")
			(net "P5E_CPU1_P0_TX_DN<8>")
		)
	)
	(footprint ""
		(layer "F.Cu")
		(at 42.49293 -351.578672 90)
		(property "Reference" "PC436_8"
			(at 0 0 90)
			(layer "F.SilkS")
			(hide yes)
			(effects
				(font
					(size 1.27 1.27)
				)
			)
		)
		(property "Value" ""
			(at 0 0 90)
			(layer "F.Fab")
			(effects
				(font
					(size 1.27 1.27)
				)
			)
		)
		(duplicate_pad_numbers_are_jumpers no)
		(fp_line
			(start 0.7874 -0.4064)
			(end 0.7874 0.4064)
			(stroke
				(width 0.1524)
				(type default)
			)
			(layer "F.SilkS")
		)
		(fp_line
			(start -0.7874 -0.4064)
			(end 0.7874 -0.4064)
			(stroke
				(width 0.1524)
				(type default)
			)
			(layer "F.SilkS")
		)
		(fp_line
			(start 0.7874 0.4064)
			(end -0.7874 0.4064)
			(stroke
				(width 0.1524)
				(type default)
			)
			(layer "F.SilkS")
		)
		(fp_line
			(start -0.7874 0.4064)
			(end -0.7874 -0.4064)
			(stroke
				(width 0.1524)
				(type default)
			)
			(layer "F.SilkS")
		)
		(fp_line
			(start -0.12065 -0.305054)
			(end -0.12065 -0.2794)
			(stroke
				(width 0.1)
				(type default)
			)
			(layer "F.Fab")
		)
		(fp_line
			(start -0.67945 -0.305054)
			(end -0.12065 -0.305054)
			(stroke
				(width 0.1)
				(type default)
			)
			(layer "F.Fab")
		)
		(fp_line
			(start 0.67945 -0.3048)
			(end 0.67945 0.3048)
			(stroke
				(width 0.1)
				(type default)
			)
			(layer "F.Fab")
		)
		(fp_line
			(start 0.12065 -0.3048)
			(end 0.67945 -0.3048)
			(stroke
				(width 0.1)
				(type default)
			)
			(layer "F.Fab")
		)
		(fp_line
			(start 0.12065 -0.2794)
			(end 0.12065 -0.3048)
			(stroke
				(width 0.1)
				(type default)
			)
			(layer "F.Fab")
		)
		(fp_line
			(start -0.12065 -0.2794)
			(end 0.12065 -0.2794)
			(stroke
				(width 0.1)
				(type default)
			)
			(layer "F.Fab")
		)
		(fp_line
			(start 0.120396 0.2794)
			(end -0.12065 0.2794)
			(stroke
				(width 0.1)
				(type default)
			)
			(layer "F.Fab")
		)
		(fp_line
			(start -0.12065 0.2794)
			(end -0.12065 0.3048)
			(stroke
				(width 0.1)
				(type default)
			)
			(layer "F.Fab")
		)
		(fp_line
			(start 0.67945 0.3048)
			(end 0.120396 0.3048)
			(stroke
				(width 0.1)
				(type default)
			)
			(layer "F.Fab")
		)
		(fp_line
			(start 0.120396 0.3048)
			(end 0.120396 0.2794)
			(stroke
				(width 0.1)
				(type default)
			)
			(layer "F.Fab")
		)
		(fp_line
			(start -0.12065 0.3048)
			(end -0.67945 0.3048)
			(stroke
				(width 0.1)
				(type default)
			)
			(layer "F.Fab")
		)
		(fp_line
			(start -0.67945 0.3048)
			(end -0.67945 -0.305054)
			(stroke
				(width 0.1)
				(type default)
			)
			(layer "F.Fab")
		)
		(pad "1" smd circle
			(at -0.40005 0 90)
			(size 0 0)
			(layers "F.Cu" "F.Mask" "F.Paste")
			(net "PVDDCR_CPU1_P1_VCCS")
		)
		(pad "2" smd circle
			(at 0.40005 0 90)
			(size 0 0)
			(layers "F.Cu" "F.Mask" "F.Paste")
			(net "GND")
		)
	)
	(footprint ""
		(layer "F.Cu")
		(at 22.479 -361.061 180)
		(property "Reference" "C309"
			(at 0 0 180)
			(layer "F.SilkS")
			(hide yes)
			(effects
				(font
					(size 1.27 1.27)
				)
			)
		)
		(property "Value" ""
			(at 0 0 180)
			(layer "F.Fab")
			(effects
				(font
					(size 1.27 1.27)
				)
			)
		)
		(duplicate_pad_numbers_are_jumpers no)
		(fp_line
			(start 0.7874 0.4064)
			(end -0.7874 0.4064)
			(stroke
				(width 0.1524)
				(type default)
			)
			(layer "F.SilkS")
		)
		(fp_line
			(start 0.7874 -0.4064)
			(end 0.7874 0.4064)
			(stroke
				(width 0.1524)
				(type default)
			)
			(layer "F.SilkS")
		)
		(fp_line
			(start -0.7874 0.4064)
			(end -0.7874 -0.4064)
			(stroke
				(width 0.1524)
				(type default)
			)
			(layer "F.SilkS")
		)
		(fp_line
			(start -0.7874 -0.4064)
			(end 0.7874 -0.4064)
			(stroke
				(width 0.1524)
				(type default)
			)
			(layer "F.SilkS")
		)
		(fp_line
			(start 0.67945 0.3048)
			(end 0.120396 0.3048)
			(stroke
				(width 0.1)
				(type default)
			)
			(layer "F.Fab")
		)
		(fp_line
			(start 0.67945 -0.3048)
			(end 0.67945 0.3048)
			(stroke
				(width 0.1)
				(type default)
			)
			(layer "F.Fab")
		)
		(fp_line
			(start 0.12065 -0.2794)
			(end 0.12065 -0.3048)
			(stroke
				(width 0.1)
				(type default)
			)
			(layer "F.Fab")
		)
		(fp_line
			(start 0.12065 -0.3048)
			(end 0.67945 -0.3048)
			(stroke
				(width 0.1)
				(type default)
			)
			(layer "F.Fab")
		)
		(fp_line
			(start 0.120396 0.3048)
			(end 0.120396 0.2794)
			(stroke
				(width 0.1)
				(type default)
			)
			(layer "F.Fab")
		)
		(fp_line
			(start 0.120396 0.2794)
			(end -0.12065 0.2794)
			(stroke
				(width 0.1)
				(type default)
			)
			(layer "F.Fab")
		)
		(fp_line
			(start -0.12065 0.3048)
			(end -0.67945 0.3048)
			(stroke
				(width 0.1)
				(type default)
			)
			(layer "F.Fab")
		)
		(fp_line
			(start -0.12065 0.2794)
			(end -0.12065 0.3048)
			(stroke
				(width 0.1)
				(type default)
			)
			(layer "F.Fab")
		)
		(fp_line
			(start -0.12065 -0.2794)
			(end 0.12065 -0.2794)
			(stroke
				(width 0.1)
				(type default)
			)
			(layer "F.Fab")
		)
		(fp_line
			(start -0.12065 -0.305054)
			(end -0.12065 -0.2794)
			(stroke
				(width 0.1)
				(type default)
			)
			(layer "F.Fab")
		)
		(fp_line
			(start -0.67945 0.3048)
			(end -0.67945 -0.305054)
			(stroke
				(width 0.1)
				(type default)
			)
			(layer "F.Fab")
		)
		(fp_line
			(start -0.67945 -0.305054)
			(end -0.12065 -0.305054)
			(stroke
				(width 0.1)
				(type default)
			)
			(layer "F.Fab")
		)
		(pad "1" smd circle
			(at -0.40005 0 180)
			(size 0 0)
			(layers "F.Cu" "F.Mask" "F.Paste")
			(net "SVID_PVDDCR_CPU1_P1_SVD_R")
		)
		(pad "2" smd circle
			(at 0.40005 0 180)
			(size 0 0)
			(layers "F.Cu" "F.Mask" "F.Paste")
			(net "GND")
		)
	)
	(footprint ""
		(layer "F.Cu")
		(at 169.418 -134.493)
		(property "Reference" "R480"
			(at 0 0 0)
			(layer "F.SilkS")
			(hide yes)
			(effects
				(font
					(size 1.27 1.27)
				)
			)
		)
		(property "Value" ""
			(at 0 0 0)
			(layer "F.Fab")
			(effects
				(font
					(size 1.27 1.27)
				)
			)
		)
		(duplicate_pad_numbers_are_jumpers no)
		(fp_line
			(start -0.7874 -0.4064)
			(end 0.7874 -0.4064)
			(stroke
				(width 0.1524)
				(type default)
			)
			(layer "F.SilkS")
		)
		(fp_line
			(start -0.7874 0.4064)
			(end -0.7874 -0.4064)
			(stroke
				(width 0.1524)
				(type default)
			)
			(layer "F.SilkS")
		)
		(fp_line
			(start 0.7874 -0.4064)
			(end 0.7874 0.4064)
			(stroke
				(width 0.1524)
				(type default)
			)
			(layer "F.SilkS")
		)
		(fp_line
			(start 0.7874 0.4064)
			(end -0.7874 0.4064)
			(stroke
				(width 0.1524)
				(type default)
			)
			(layer "F.SilkS")
		)
		(fp_line
			(start -0.67945 -0.305054)
			(end -0.12065 -0.305054)
			(stroke
				(width 0.1)
				(type default)
			)
			(layer "F.Fab")
		)
		(fp_line
			(start -0.67945 0.3048)
			(end -0.67945 -0.305054)
			(stroke
				(width 0.1)
				(type default)
			)
			(layer "F.Fab")
		)
		(fp_line
			(start -0.12065 -0.305054)
			(end -0.12065 -0.2794)
			(stroke
				(width 0.1)
				(type default)
			)
			(layer "F.Fab")
		)
		(fp_line
			(start -0.12065 -0.2794)
			(end 0.12065 -0.2794)
			(stroke
				(width 0.1)
				(type default)
			)
			(layer "F.Fab")
		)
		(fp_line
			(start -0.12065 0.2794)
			(end -0.12065 0.3048)
			(stroke
				(width 0.1)
				(type default)
			)
			(layer "F.Fab")
		)
		(fp_line
			(start -0.12065 0.3048)
			(end -0.67945 0.3048)
			(stroke
				(width 0.1)
				(type default)
			)
			(layer "F.Fab")
		)
		(fp_line
			(start 0.120396 0.2794)
			(end -0.12065 0.2794)
			(stroke
				(width 0.1)
				(type default)
			)
			(layer "F.Fab")
		)
		(fp_line
			(start 0.120396 0.3048)
			(end 0.120396 0.2794)
			(stroke
				(width 0.1)
				(type default)
			)
			(layer "F.Fab")
		)
		(fp_line
			(start 0.12065 -0.3048)
			(end 0.67945 -0.3048)
			(stroke
				(width 0.1)
				(type default)
			)
			(layer "F.Fab")
		)
		(fp_line
			(start 0.12065 -0.2794)
			(end 0.12065 -0.3048)
			(stroke
				(width 0.1)
				(type default)
			)
			(layer "F.Fab")
		)
		(fp_line
			(start 0.67945 -0.3048)
			(end 0.67945 0.3048)
			(stroke
				(width 0.1)
				(type default)
			)
			(layer "F.Fab")
		)
		(fp_line
			(start 0.67945 0.3048)
			(end 0.120396 0.3048)
			(stroke
				(width 0.1)
				(type default)
			)
			(layer "F.Fab")
		)
		(pad "1" smd circle
			(at -0.40005 0)
			(size 0 0)
			(layers "F.Cu" "F.Mask" "F.Paste")
			(net "PWRGD_P5V_R")
		)
		(pad "2" smd circle
			(at 0.40005 0)
			(size 0 0)
			(layers "F.Cu" "F.Mask" "F.Paste")
			(net "GND")
		)
	)
	(footprint ""
		(layer "F.Cu")
		(at 97.745296 -422.43248 90)
		(property "Reference" "C32"
			(at 0 0 90)
			(layer "F.SilkS")
			(hide yes)
			(effects
				(font
					(size 1.27 1.27)
				)
			)
		)
		(property "Value" ""
			(at 0 0 90)
			(layer "F.Fab")
			(effects
				(font
					(size 1.27 1.27)
				)
			)
		)
		(duplicate_pad_numbers_are_jumpers no)
		(fp_line
			(start 0.7874 -0.4064)
			(end 0.7874 0.4064)
			(stroke
				(width 0.1524)
				(type default)
			)
			(layer "F.SilkS")
		)
		(fp_line
			(start -0.7874 -0.4064)
			(end 0.7874 -0.4064)
			(stroke
				(width 0.1524)
				(type default)
			)
			(layer "F.SilkS")
		)
		(fp_line
			(start 0.7874 0.4064)
			(end -0.7874 0.4064)
			(stroke
				(width 0.1524)
				(type default)
			)
			(layer "F.SilkS")
		)
		(fp_line
			(start -0.7874 0.4064)
			(end -0.7874 -0.4064)
			(stroke
				(width 0.1524)
				(type default)
			)
			(layer "F.SilkS")
		)
		(fp_line
			(start -0.12065 -0.305054)
			(end -0.12065 -0.2794)
			(stroke
				(width 0.1)
				(type default)
			)
			(layer "F.Fab")
		)
		(fp_line
			(start -0.67945 -0.305054)
			(end -0.12065 -0.305054)
			(stroke
				(width 0.1)
				(type default)
			)
			(layer "F.Fab")
		)
		(fp_line
			(start 0.67945 -0.3048)
			(end 0.67945 0.3048)
			(stroke
				(width 0.1)
				(type default)
			)
			(layer "F.Fab")
		)
		(fp_line
			(start 0.12065 -0.3048)
			(end 0.67945 -0.3048)
			(stroke
				(width 0.1)
				(type default)
			)
			(layer "F.Fab")
		)
		(fp_line
			(start 0.12065 -0.2794)
			(end 0.12065 -0.3048)
			(stroke
				(width 0.1)
				(type default)
			)
			(layer "F.Fab")
		)
		(fp_line
			(start -0.12065 -0.2794)
			(end 0.12065 -0.2794)
			(stroke
				(width 0.1)
				(type default)
			)
			(layer "F.Fab")
		)
		(fp_line
			(start 0.120396 0.2794)
			(end -0.12065 0.2794)
			(stroke
				(width 0.1)
				(type default)
			)
			(layer "F.Fab")
		)
		(fp_line
			(start -0.12065 0.2794)
			(end -0.12065 0.3048)
			(stroke
				(width 0.1)
				(type default)
			)
			(layer "F.Fab")
		)
		(fp_line
			(start 0.67945 0.3048)
			(end 0.120396 0.3048)
			(stroke
				(width 0.1)
				(type default)
			)
			(layer "F.Fab")
		)
		(fp_line
			(start 0.120396 0.3048)
			(end 0.120396 0.2794)
			(stroke
				(width 0.1)
				(type default)
			)
			(layer "F.Fab")
		)
		(fp_line
			(start -0.12065 0.3048)
			(end -0.67945 0.3048)
			(stroke
				(width 0.1)
				(type default)
			)
			(layer "F.Fab")
		)
		(fp_line
			(start -0.67945 0.3048)
			(end -0.67945 -0.305054)
			(stroke
				(width 0.1)
				(type default)
			)
			(layer "F.Fab")
		)
		(pad "1" smd circle
			(at -0.40005 0 90)
			(size 0 0)
			(layers "F.Cu" "F.Mask" "F.Paste")
			(net "P3V3_AUX")
		)
		(pad "2" smd circle
			(at 0.40005 0 90)
			(size 0 0)
			(layers "F.Cu" "F.Mask" "F.Paste")
			(net "GND")
		)
	)
	(footprint ""
		(layer "F.Cu")
		(at 148.499068 -109.721904 180)
		(property "Reference" "R1654"
			(at 0 0 180)
			(layer "F.SilkS")
			(hide yes)
			(effects
				(font
					(size 1.27 1.27)
				)
			)
		)
		(property "Value" ""
			(at 0 0 180)
			(layer "F.Fab")
			(effects
				(font
					(size 1.27 1.27)
				)
			)
		)
		(duplicate_pad_numbers_are_jumpers no)
		(fp_line
			(start 0.7874 0.4064)
			(end -0.7874 0.4064)
			(stroke
				(width 0.1524)
				(type default)
			)
			(layer "F.SilkS")
		)
		(fp_line
			(start 0.7874 -0.4064)
			(end 0.7874 0.4064)
			(stroke
				(width 0.1524)
				(type default)
			)
			(layer "F.SilkS")
		)
		(fp_line
			(start -0.7874 0.4064)
			(end -0.7874 -0.4064)
			(stroke
				(width 0.1524)
				(type default)
			)
			(layer "F.SilkS")
		)
		(fp_line
			(start -0.7874 -0.4064)
			(end 0.7874 -0.4064)
			(stroke
				(width 0.1524)
				(type default)
			)
			(layer "F.SilkS")
		)
		(fp_line
			(start 0.67945 0.3048)
			(end 0.120396 0.3048)
			(stroke
				(width 0.1)
				(type default)
			)
			(layer "F.Fab")
		)
		(fp_line
			(start 0.67945 -0.3048)
			(end 0.67945 0.3048)
			(stroke
				(width 0.1)
				(type default)
			)
			(layer "F.Fab")
		)
		(fp_line
			(start 0.12065 -0.2794)
			(end 0.12065 -0.3048)
			(stroke
				(width 0.1)
				(type default)
			)
			(layer "F.Fab")
		)
		(fp_line
			(start 0.12065 -0.3048)
			(end 0.67945 -0.3048)
			(stroke
				(width 0.1)
				(type default)
			)
			(layer "F.Fab")
		)
		(fp_line
			(start 0.120396 0.3048)
			(end 0.120396 0.2794)
			(stroke
				(width 0.1)
				(type default)
			)
			(layer "F.Fab")
		)
		(fp_line
			(start 0.120396 0.2794)
			(end -0.12065 0.2794)
			(stroke
				(width 0.1)
				(type default)
			)
			(layer "F.Fab")
		)
		(fp_line
			(start -0.12065 0.3048)
			(end -0.67945 0.3048)
			(stroke
				(width 0.1)
				(type default)
			)
			(layer "F.Fab")
		)
		(fp_line
			(start -0.12065 0.2794)
			(end -0.12065 0.3048)
			(stroke
				(width 0.1)
				(type default)
			)
			(layer "F.Fab")
		)
		(fp_line
			(start -0.12065 -0.2794)
			(end 0.12065 -0.2794)
			(stroke
				(width 0.1)
				(type default)
			)
			(layer "F.Fab")
		)
		(fp_line
			(start -0.12065 -0.305054)
			(end -0.12065 -0.2794)
			(stroke
				(width 0.1)
				(type default)
			)
			(layer "F.Fab")
		)
		(fp_line
			(start -0.67945 0.3048)
			(end -0.67945 -0.305054)
			(stroke
				(width 0.1)
				(type default)
			)
			(layer "F.Fab")
		)
		(fp_line
			(start -0.67945 -0.305054)
			(end -0.12065 -0.305054)
			(stroke
				(width 0.1)
				(type default)
			)
			(layer "F.Fab")
		)
		(pad "1" smd circle
			(at -0.40005 0 180)
			(size 0 0)
			(layers "F.Cu" "F.Mask" "F.Paste")
			(net "VR_P5V_EN_D_R")
		)
		(pad "2" smd circle
			(at 0.40005 0 180)
			(size 0 0)
			(layers "F.Cu" "F.Mask" "F.Paste")
			(net "VR_P5V_EN_D_R1")
		)
	)
	(footprint ""
		(layer "F.Cu")
		(at 174.57674 -129.377948 90)
		(property "Reference" "R4145"
			(at 0 0 90)
			(layer "F.SilkS")
			(hide yes)
			(effects
				(font
					(size 1.27 1.27)
				)
			)
		)
		(property "Value" ""
			(at 0 0 90)
			(layer "F.Fab")
			(effects
				(font
					(size 1.27 1.27)
				)
			)
		)
		(duplicate_pad_numbers_are_jumpers no)
		(fp_line
			(start 0.7874 -0.4064)
			(end 0.7874 0.4064)
			(stroke
				(width 0.1524)
				(type default)
			)
			(layer "F.SilkS")
		)
		(fp_line
			(start -0.7874 -0.4064)
			(end 0.7874 -0.4064)
			(stroke
				(width 0.1524)
				(type default)
			)
			(layer "F.SilkS")
		)
		(fp_line
			(start 0.7874 0.4064)
			(end -0.7874 0.4064)
			(stroke
				(width 0.1524)
				(type default)
			)
			(layer "F.SilkS")
		)
		(fp_line
			(start -0.7874 0.4064)
			(end -0.7874 -0.4064)
			(stroke
				(width 0.1524)
				(type default)
			)
			(layer "F.SilkS")
		)
		(fp_line
			(start -0.12065 -0.305054)
			(end -0.12065 -0.2794)
			(stroke
				(width 0.1)
				(type default)
			)
			(layer "F.Fab")
		)
		(fp_line
			(start -0.67945 -0.305054)
			(end -0.12065 -0.305054)
			(stroke
				(width 0.1)
				(type default)
			)
			(layer "F.Fab")
		)
		(fp_line
			(start 0.67945 -0.3048)
			(end 0.67945 0.3048)
			(stroke
				(width 0.1)
				(type default)
			)
			(layer "F.Fab")
		)
		(fp_line
			(start 0.12065 -0.3048)
			(end 0.67945 -0.3048)
			(stroke
				(width 0.1)
				(type default)
			)
			(layer "F.Fab")
		)
		(fp_line
			(start 0.12065 -0.2794)
			(end 0.12065 -0.3048)
			(stroke
				(width 0.1)
				(type default)
			)
			(layer "F.Fab")
		)
		(fp_line
			(start -0.12065 -0.2794)
			(end 0.12065 -0.2794)
			(stroke
				(width 0.1)
				(type default)
			)
			(layer "F.Fab")
		)
		(fp_line
			(start 0.120396 0.2794)
			(end -0.12065 0.2794)
			(stroke
				(width 0.1)
				(type default)
			)
			(layer "F.Fab")
		)
		(fp_line
			(start -0.12065 0.2794)
			(end -0.12065 0.3048)
			(stroke
				(width 0.1)
				(type default)
			)
			(layer "F.Fab")
		)
		(fp_line
			(start 0.67945 0.3048)
			(end 0.120396 0.3048)
			(stroke
				(width 0.1)
				(type default)
			)
			(layer "F.Fab")
		)
		(fp_line
			(start 0.120396 0.3048)
			(end 0.120396 0.2794)
			(stroke
				(width 0.1)
				(type default)
			)
			(layer "F.Fab")
		)
		(fp_line
			(start -0.12065 0.3048)
			(end -0.67945 0.3048)
			(stroke
				(width 0.1)
				(type default)
			)
			(layer "F.Fab")
		)
		(fp_line
			(start -0.67945 0.3048)
			(end -0.67945 -0.305054)
			(stroke
				(width 0.1)
				(type default)
			)
			(layer "F.Fab")
		)
		(pad "1" smd circle
			(at -0.40005 0 90)
			(size 0 0)
			(layers "F.Cu" "F.Mask" "F.Paste")
			(net "PRSNT_CABLE_GPU_B3_ISO_R_N")
		)
		(pad "2" smd circle
			(at 0.40005 0 90)
			(size 0 0)
			(layers "F.Cu" "F.Mask" "F.Paste")
			(net "PRSNT_CABLE_GPU_B3_ISO_N")
		)
	)
	(footprint ""
		(layer "F.Cu")
		(at 173.171358 -387.737604)
		(property "Reference" "C370"
			(at 0 0 0)
			(layer "F.SilkS")
			(hide yes)
			(effects
				(font
					(size 1.27 1.27)
				)
			)
		)
		(property "Value" ""
			(at 0 0 0)
			(layer "F.Fab")
			(effects
				(font
					(size 1.27 1.27)
				)
			)
		)
		(duplicate_pad_numbers_are_jumpers no)
		(fp_line
			(start -0.7874 -0.4064)
			(end 0.7874 -0.4064)
			(stroke
				(width 0.1524)
				(type default)
			)
			(layer "F.SilkS")
		)
		(fp_line
			(start -0.7874 0.4064)
			(end -0.7874 -0.4064)
			(stroke
				(width 0.1524)
				(type default)
			)
			(layer "F.SilkS")
		)
		(fp_line
			(start 0.7874 -0.4064)
			(end 0.7874 0.4064)
			(stroke
				(width 0.1524)
				(type default)
			)
			(layer "F.SilkS")
		)
		(fp_line
			(start 0.7874 0.4064)
			(end -0.7874 0.4064)
			(stroke
				(width 0.1524)
				(type default)
			)
			(layer "F.SilkS")
		)
		(fp_line
			(start -0.67945 -0.305054)
			(end -0.12065 -0.305054)
			(stroke
				(width 0.1)
				(type default)
			)
			(layer "F.Fab")
		)
		(fp_line
			(start -0.67945 0.3048)
			(end -0.67945 -0.305054)
			(stroke
				(width 0.1)
				(type default)
			)
			(layer "F.Fab")
		)
		(fp_line
			(start -0.12065 -0.305054)
			(end -0.12065 -0.2794)
			(stroke
				(width 0.1)
				(type default)
			)
			(layer "F.Fab")
		)
		(fp_line
			(start -0.12065 -0.2794)
			(end 0.12065 -0.2794)
			(stroke
				(width 0.1)
				(type default)
			)
			(layer "F.Fab")
		)
		(fp_line
			(start -0.12065 0.2794)
			(end -0.12065 0.3048)
			(stroke
				(width 0.1)
				(type default)
			)
			(layer "F.Fab")
		)
		(fp_line
			(start -0.12065 0.3048)
			(end -0.67945 0.3048)
			(stroke
				(width 0.1)
				(type default)
			)
			(layer "F.Fab")
		)
		(fp_line
			(start 0.120396 0.2794)
			(end -0.12065 0.2794)
			(stroke
				(width 0.1)
				(type default)
			)
			(layer "F.Fab")
		)
		(fp_line
			(start 0.120396 0.3048)
			(end 0.120396 0.2794)
			(stroke
				(width 0.1)
				(type default)
			)
			(layer "F.Fab")
		)
		(fp_line
			(start 0.12065 -0.3048)
			(end 0.67945 -0.3048)
			(stroke
				(width 0.1)
				(type default)
			)
			(layer "F.Fab")
		)
		(fp_line
			(start 0.12065 -0.2794)
			(end 0.12065 -0.3048)
			(stroke
				(width 0.1)
				(type default)
			)
			(layer "F.Fab")
		)
		(fp_line
			(start 0.67945 -0.3048)
			(end 0.67945 0.3048)
			(stroke
				(width 0.1)
				(type default)
			)
			(layer "F.Fab")
		)
		(fp_line
			(start 0.67945 0.3048)
			(end 0.120396 0.3048)
			(stroke
				(width 0.1)
				(type default)
			)
			(layer "F.Fab")
		)
		(pad "1" smd circle
			(at -0.40005 0)
			(size 0 0)
			(layers "F.Cu" "F.Mask" "F.Paste")
			(net "P1V8_CPU1_RT_1D")
		)
		(pad "2" smd circle
			(at 0.40005 0)
			(size 0 0)
			(layers "F.Cu" "F.Mask" "F.Paste")
			(net "GND")
		)
	)
	(footprint ""
		(layer "F.Cu")
		(at 192.786 -92.801948 -90)
		(property "Reference" "R6052"
			(at 0 0 270)
			(layer "F.SilkS")
			(hide yes)
			(effects
				(font
					(size 1.27 1.27)
				)
			)
		)
		(property "Value" ""
			(at 0 0 270)
			(layer "F.Fab")
			(effects
				(font
					(size 1.27 1.27)
				)
			)
		)
		(duplicate_pad_numbers_are_jumpers no)
		(fp_line
			(start -0.7874 0.4064)
			(end -0.7874 -0.4064)
			(stroke
				(width 0.1524)
				(type default)
			)
			(layer "F.SilkS")
		)
		(fp_line
			(start 0.7874 0.4064)
			(end -0.7874 0.4064)
			(stroke
				(width 0.1524)
				(type default)
			)
			(layer "F.SilkS")
		)
		(fp_line
			(start -0.7874 -0.4064)
			(end 0.7874 -0.4064)
			(stroke
				(width 0.1524)
				(type default)
			)
			(layer "F.SilkS")
		)
		(fp_line
			(start 0.7874 -0.4064)
			(end 0.7874 0.4064)
			(stroke
				(width 0.1524)
				(type default)
			)
			(layer "F.SilkS")
		)
		(fp_line
			(start -0.67945 0.3048)
			(end -0.67945 -0.305054)
			(stroke
				(width 0.1)
				(type default)
			)
			(layer "F.Fab")
		)
		(fp_line
			(start -0.12065 0.3048)
			(end -0.67945 0.3048)
			(stroke
				(width 0.1)
				(type default)
			)
			(layer "F.Fab")
		)
		(fp_line
			(start 0.120396 0.3048)
			(end 0.120396 0.2794)
			(stroke
				(width 0.1)
				(type default)
			)
			(layer "F.Fab")
		)
		(fp_line
			(start 0.67945 0.3048)
			(end 0.120396 0.3048)
			(stroke
				(width 0.1)
				(type default)
			)
			(layer "F.Fab")
		)
		(fp_line
			(start -0.12065 0.2794)
			(end -0.12065 0.3048)
			(stroke
				(width 0.1)
				(type default)
			)
			(layer "F.Fab")
		)
		(fp_line
			(start 0.120396 0.2794)
			(end -0.12065 0.2794)
			(stroke
				(width 0.1)
				(type default)
			)
			(layer "F.Fab")
		)
		(fp_line
			(start -0.12065 -0.2794)
			(end 0.12065 -0.2794)
			(stroke
				(width 0.1)
				(type default)
			)
			(layer "F.Fab")
		)
		(fp_line
			(start 0.12065 -0.2794)
			(end 0.12065 -0.3048)
			(stroke
				(width 0.1)
				(type default)
			)
			(layer "F.Fab")
		)
		(fp_line
			(start 0.12065 -0.3048)
			(end 0.67945 -0.3048)
			(stroke
				(width 0.1)
				(type default)
			)
			(layer "F.Fab")
		)
		(fp_line
			(start 0.67945 -0.3048)
			(end 0.67945 0.3048)
			(stroke
				(width 0.1)
				(type default)
			)
			(layer "F.Fab")
		)
		(fp_line
			(start -0.67945 -0.305054)
			(end -0.12065 -0.305054)
			(stroke
				(width 0.1)
				(type default)
			)
			(layer "F.Fab")
		)
		(fp_line
			(start -0.12065 -0.305054)
			(end -0.12065 -0.2794)
			(stroke
				(width 0.1)
				(type default)
			)
			(layer "F.Fab")
		)
		(pad "1" smd circle
			(at -0.40005 0 270)
			(size 0 0)
			(layers "F.Cu" "F.Mask" "F.Paste")
			(net "E1S_0_PRSNT_R_N")
		)
		(pad "2" smd circle
			(at 0.40005 0 270)
			(size 0 0)
			(layers "F.Cu" "F.Mask" "F.Paste")
			(net "E1S_0_PRSNT_N")
		)
	)
	(footprint ""
		(layer "F.Cu")
		(at 105.537 -418.973 180)
		(property "Reference" "R3397"
			(at 0 0 180)
			(layer "F.SilkS")
			(hide yes)
			(effects
				(font
					(size 1.27 1.27)
				)
			)
		)
		(property "Value" ""
			(at 0 0 180)
			(layer "F.Fab")
			(effects
				(font
					(size 1.27 1.27)
				)
			)
		)
		(duplicate_pad_numbers_are_jumpers no)
		(fp_line
			(start 0.7874 0.4064)
			(end -0.7874 0.4064)
			(stroke
				(width 0.1524)
				(type default)
			)
			(layer "F.SilkS")
		)
		(fp_line
			(start 0.7874 -0.4064)
			(end 0.7874 0.4064)
			(stroke
				(width 0.1524)
				(type default)
			)
			(layer "F.SilkS")
		)
		(fp_line
			(start -0.7874 0.4064)
			(end -0.7874 -0.4064)
			(stroke
				(width 0.1524)
				(type default)
			)
			(layer "F.SilkS")
		)
		(fp_line
			(start -0.7874 -0.4064)
			(end 0.7874 -0.4064)
			(stroke
				(width 0.1524)
				(type default)
			)
			(layer "F.SilkS")
		)
		(fp_line
			(start 0.67945 0.3048)
			(end 0.120396 0.3048)
			(stroke
				(width 0.1)
				(type default)
			)
			(layer "F.Fab")
		)
		(fp_line
			(start 0.67945 -0.3048)
			(end 0.67945 0.3048)
			(stroke
				(width 0.1)
				(type default)
			)
			(layer "F.Fab")
		)
		(fp_line
			(start 0.12065 -0.2794)
			(end 0.12065 -0.3048)
			(stroke
				(width 0.1)
				(type default)
			)
			(layer "F.Fab")
		)
		(fp_line
			(start 0.12065 -0.3048)
			(end 0.67945 -0.3048)
			(stroke
				(width 0.1)
				(type default)
			)
			(layer "F.Fab")
		)
		(fp_line
			(start 0.120396 0.3048)
			(end 0.120396 0.2794)
			(stroke
				(width 0.1)
				(type default)
			)
			(layer "F.Fab")
		)
		(fp_line
			(start 0.120396 0.2794)
			(end -0.12065 0.2794)
			(stroke
				(width 0.1)
				(type default)
			)
			(layer "F.Fab")
		)
		(fp_line
			(start -0.12065 0.3048)
			(end -0.67945 0.3048)
			(stroke
				(width 0.1)
				(type default)
			)
			(layer "F.Fab")
		)
		(fp_line
			(start -0.12065 0.2794)
			(end -0.12065 0.3048)
			(stroke
				(width 0.1)
				(type default)
			)
			(layer "F.Fab")
		)
		(fp_line
			(start -0.12065 -0.2794)
			(end 0.12065 -0.2794)
			(stroke
				(width 0.1)
				(type default)
			)
			(layer "F.Fab")
		)
		(fp_line
			(start -0.12065 -0.305054)
			(end -0.12065 -0.2794)
			(stroke
				(width 0.1)
				(type default)
			)
			(layer "F.Fab")
		)
		(fp_line
			(start -0.67945 0.3048)
			(end -0.67945 -0.305054)
			(stroke
				(width 0.1)
				(type default)
			)
			(layer "F.Fab")
		)
		(fp_line
			(start -0.67945 -0.305054)
			(end -0.12065 -0.305054)
			(stroke
				(width 0.1)
				(type default)
			)
			(layer "F.Fab")
		)
		(pad "1" smd circle
			(at -0.40005 0 180)
			(size 0 0)
			(layers "F.Cu" "F.Mask" "F.Paste")
			(net "GPU_NVS_PWR_BRAKE_N_R")
		)
		(pad "2" smd circle
			(at 0.40005 0 180)
			(size 0 0)
			(layers "F.Cu" "F.Mask" "F.Paste")
			(net "GPU_NVS_PWR_BRAKE_N_BUF")
		)
	)
	(footprint ""
		(layer "F.Cu")
		(at 259.834126 -98.746056 180)
		(property "Reference" "R1635"
			(at 0 0 180)
			(layer "F.SilkS")
			(hide yes)
			(effects
				(font
					(size 1.27 1.27)
				)
			)
		)
		(property "Value" ""
			(at 0 0 180)
			(layer "F.Fab")
			(effects
				(font
					(size 1.27 1.27)
				)
			)
		)
		(duplicate_pad_numbers_are_jumpers no)
		(fp_line
			(start 0.7874 0.4064)
			(end -0.7874 0.4064)
			(stroke
				(width 0.1524)
				(type default)
			)
			(layer "F.SilkS")
		)
		(fp_line
			(start 0.7874 -0.4064)
			(end 0.7874 0.4064)
			(stroke
				(width 0.1524)
				(type default)
			)
			(layer "F.SilkS")
		)
		(fp_line
			(start -0.7874 0.4064)
			(end -0.7874 -0.4064)
			(stroke
				(width 0.1524)
				(type default)
			)
			(layer "F.SilkS")
		)
		(fp_line
			(start -0.7874 -0.4064)
			(end 0.7874 -0.4064)
			(stroke
				(width 0.1524)
				(type default)
			)
			(layer "F.SilkS")
		)
		(fp_line
			(start 0.67945 0.3048)
			(end 0.120396 0.3048)
			(stroke
				(width 0.1)
				(type default)
			)
			(layer "F.Fab")
		)
		(fp_line
			(start 0.67945 -0.3048)
			(end 0.67945 0.3048)
			(stroke
				(width 0.1)
				(type default)
			)
			(layer "F.Fab")
		)
		(fp_line
			(start 0.12065 -0.2794)
			(end 0.12065 -0.3048)
			(stroke
				(width 0.1)
				(type default)
			)
			(layer "F.Fab")
		)
		(fp_line
			(start 0.12065 -0.3048)
			(end 0.67945 -0.3048)
			(stroke
				(width 0.1)
				(type default)
			)
			(layer "F.Fab")
		)
		(fp_line
			(start 0.120396 0.3048)
			(end 0.120396 0.2794)
			(stroke
				(width 0.1)
				(type default)
			)
			(layer "F.Fab")
		)
		(fp_line
			(start 0.120396 0.2794)
			(end -0.12065 0.2794)
			(stroke
				(width 0.1)
				(type default)
			)
			(layer "F.Fab")
		)
		(fp_line
			(start -0.12065 0.3048)
			(end -0.67945 0.3048)
			(stroke
				(width 0.1)
				(type default)
			)
			(layer "F.Fab")
		)
		(fp_line
			(start -0.12065 0.2794)
			(end -0.12065 0.3048)
			(stroke
				(width 0.1)
				(type default)
			)
			(layer "F.Fab")
		)
		(fp_line
			(start -0.12065 -0.2794)
			(end 0.12065 -0.2794)
			(stroke
				(width 0.1)
				(type default)
			)
			(layer "F.Fab")
		)
		(fp_line
			(start -0.12065 -0.305054)
			(end -0.12065 -0.2794)
			(stroke
				(width 0.1)
				(type default)
			)
			(layer "F.Fab")
		)
		(fp_line
			(start -0.67945 0.3048)
			(end -0.67945 -0.305054)
			(stroke
				(width 0.1)
				(type default)
			)
			(layer "F.Fab")
		)
		(fp_line
			(start -0.67945 -0.305054)
			(end -0.12065 -0.305054)
			(stroke
				(width 0.1)
				(type default)
			)
			(layer "F.Fab")
		)
		(pad "1" smd circle
			(at -0.40005 0 180)
			(size 0 0)
			(layers "F.Cu" "F.Mask" "F.Paste")
			(net "JTAG_TRST_R_N")
		)
		(pad "2" smd circle
			(at 0.40005 0 180)
			(size 0 0)
			(layers "F.Cu" "F.Mask" "F.Paste")
			(net "JTAG_TRST_N")
		)
	)
	(footprint ""
		(layer "F.Cu")
		(at 259.568696 -39.754556 90)
		(property "Reference" "PD114"
			(at -2.56032 1.848612 90)
			(unlocked yes)
			(layer "F.SilkS")
			(effects
				(font
					(size 0.7874 0.5842)
					(thickness 0.1524)
				)
				(justify left)
			)
		)
		(property "Value" ""
			(at 0 0 90)
			(layer "F.Fab")
			(effects
				(font
					(size 1.27 1.27)
				)
			)
		)
		(duplicate_pad_numbers_are_jumpers no)
		(fp_line
			(start 2.631186 -0.999998)
			(end -2.250186 -0.999998)
			(stroke
				(width 0.1524)
				(type default)
			)
			(layer "F.SilkS")
		)
		(fp_line
			(start -2.250186 -0.999998)
			(end -2.250186 0.999998)
			(stroke
				(width 0.1524)
				(type default)
			)
			(layer "F.SilkS")
		)
		(fp_line
			(start 0.381 -0.4318)
			(end 0.381 0.3302)
			(stroke
				(width 0.1524)
				(type default)
			)
			(layer "F.SilkS")
		)
		(fp_line
			(start -0.381 -0.4318)
			(end 0.381 -0.0508)
			(stroke
				(width 0.1524)
				(type default)
			)
			(layer "F.SilkS")
		)
		(fp_line
			(start 0.381 -0.0508)
			(end 0.635 -0.0508)
			(stroke
				(width 0.1524)
				(type default)
			)
			(layer "F.SilkS")
		)
		(fp_line
			(start 0.381 -0.0508)
			(end -0.381 0.3302)
			(stroke
				(width 0.1524)
				(type default)
			)
			(layer "F.SilkS")
		)
		(fp_line
			(start -0.381 -0.0508)
			(end -0.6604 -0.0508)
			(stroke
				(width 0.1524)
				(type default)
			)
			(layer "F.SilkS")
		)
		(fp_line
			(start -0.381 0.3302)
			(end -0.381 -0.4318)
			(stroke
				(width 0.1524)
				(type default)
			)
			(layer "F.SilkS")
		)
		(fp_line
			(start 2.631186 0.999998)
			(end 2.631186 -0.999998)
			(stroke
				(width 0.1524)
				(type default)
			)
			(layer "F.SilkS")
		)
		(fp_line
			(start -2.250186 0.999998)
			(end 2.631186 0.999998)
			(stroke
				(width 0.1524)
				(type default)
			)
			(layer "F.SilkS")
		)
		(fp_rect
			(start 2.1844 -0.9652)
			(end 2.6162 1.016)
			(stroke
				(width 0)
				(type default)
			)
			(fill yes)
			(layer "F.SilkS")
		)
		(fp_line
			(start 1.450086 -0.999998)
			(end -1.450086 -0.999998)
			(stroke
				(width 0.1)
				(type default)
			)
			(layer "F.Fab")
		)
		(fp_line
			(start -1.450086 -0.999998)
			(end -1.450086 0.999998)
			(stroke
				(width 0.1)
				(type default)
			)
			(layer "F.Fab")
		)
		(fp_line
			(start 1.450086 0.999998)
			(end 1.450086 -0.999998)
			(stroke
				(width 0.1)
				(type default)
			)
			(layer "F.Fab")
		)
		(fp_line
			(start -1.450086 0.999998)
			(end 1.450086 0.999998)
			(stroke
				(width 0.1)
				(type default)
			)
			(layer "F.Fab")
		)
		(fp_text user "+"
			(at -3.885946 -0.282448 90)
			(unlocked yes)
			(layer "F.SilkS")
			(effects
				(font
					(size 1.905 1.4224)
					(thickness 0.1524)
				)
				(justify left)
			)
		)
		(fp_text user "-"
			(at 2.4384 -0.22225 90)
			(unlocked yes)
			(layer "F.SilkS")
			(effects
				(font
					(size 1.905 1.4224)
					(thickness 0.1524)
				)
				(justify left)
			)
		)
		(fp_text user "-"
			(at 2.4384 -0.22225 90)
			(unlocked yes)
			(layer "F.Fab")
			(effects
				(font
					(size 1.905 1.4224)
					(thickness 0.1524)
				)
				(justify left)
			)
		)
		(fp_text user "+"
			(at -3.4798 -0.22225 90)
			(unlocked yes)
			(layer "F.Fab")
			(effects
				(font
					(size 1.905 1.4224)
					(thickness 0.1524)
				)
				(justify left)
			)
		)
		(pad "A" smd rect
			(at -1.450086 0 90)
			(size 1.3208 1.4224)
			(layers "F.Cu" "F.Mask" "F.Paste")
			(net "GND")
		)
		(pad "C" smd rect
			(at 1.450086 0 90)
			(size 1.3208 1.4224)
			(layers "F.Cu" "F.Mask" "F.Paste")
			(net "P12V_AUX")
		)
	)
	(footprint ""
		(layer "F.Cu")
		(at 105.960164 -258.405376)
		(property "Reference" "C2260"
			(at 0 0 0)
			(layer "F.SilkS")
			(hide yes)
			(effects
				(font
					(size 1.27 1.27)
				)
			)
		)
		(property "Value" ""
			(at 0 0 0)
			(layer "F.Fab")
			(effects
				(font
					(size 1.27 1.27)
				)
			)
		)
		(duplicate_pad_numbers_are_jumpers no)
		(fp_line
			(start -0.7874 -0.4064)
			(end 0.7874 -0.4064)
			(stroke
				(width 0.1524)
				(type default)
			)
			(layer "F.SilkS")
		)
		(fp_line
			(start -0.7874 0.4064)
			(end -0.7874 -0.4064)
			(stroke
				(width 0.1524)
				(type default)
			)
			(layer "F.SilkS")
		)
		(fp_line
			(start 0.7874 -0.4064)
			(end 0.7874 0.4064)
			(stroke
				(width 0.1524)
				(type default)
			)
			(layer "F.SilkS")
		)
		(fp_line
			(start 0.7874 0.4064)
			(end -0.7874 0.4064)
			(stroke
				(width 0.1524)
				(type default)
			)
			(layer "F.SilkS")
		)
		(fp_line
			(start -0.67945 -0.305054)
			(end -0.12065 -0.305054)
			(stroke
				(width 0.1)
				(type default)
			)
			(layer "F.Fab")
		)
		(fp_line
			(start -0.67945 0.3048)
			(end -0.67945 -0.305054)
			(stroke
				(width 0.1)
				(type default)
			)
			(layer "F.Fab")
		)
		(fp_line
			(start -0.12065 -0.305054)
			(end -0.12065 -0.2794)
			(stroke
				(width 0.1)
				(type default)
			)
			(layer "F.Fab")
		)
		(fp_line
			(start -0.12065 -0.2794)
			(end 0.12065 -0.2794)
			(stroke
				(width 0.1)
				(type default)
			)
			(layer "F.Fab")
		)
		(fp_line
			(start -0.12065 0.2794)
			(end -0.12065 0.3048)
			(stroke
				(width 0.1)
				(type default)
			)
			(layer "F.Fab")
		)
		(fp_line
			(start -0.12065 0.3048)
			(end -0.67945 0.3048)
			(stroke
				(width 0.1)
				(type default)
			)
			(layer "F.Fab")
		)
		(fp_line
			(start 0.120396 0.2794)
			(end -0.12065 0.2794)
			(stroke
				(width 0.1)
				(type default)
			)
			(layer "F.Fab")
		)
		(fp_line
			(start 0.120396 0.3048)
			(end 0.120396 0.2794)
			(stroke
				(width 0.1)
				(type default)
			)
			(layer "F.Fab")
		)
		(fp_line
			(start 0.12065 -0.3048)
			(end 0.67945 -0.3048)
			(stroke
				(width 0.1)
				(type default)
			)
			(layer "F.Fab")
		)
		(fp_line
			(start 0.12065 -0.2794)
			(end 0.12065 -0.3048)
			(stroke
				(width 0.1)
				(type default)
			)
			(layer "F.Fab")
		)
		(fp_line
			(start 0.67945 -0.3048)
			(end 0.67945 0.3048)
			(stroke
				(width 0.1)
				(type default)
			)
			(layer "F.Fab")
		)
		(fp_line
			(start 0.67945 0.3048)
			(end 0.120396 0.3048)
			(stroke
				(width 0.1)
				(type default)
			)
			(layer "F.Fab")
		)
		(pad "1" smd circle
			(at -0.40005 0)
			(size 0 0)
			(layers "F.Cu" "F.Mask" "F.Paste")
			(net "PVDDIO_P1")
		)
		(pad "2" smd circle
			(at 0.40005 0)
			(size 0 0)
			(layers "F.Cu" "F.Mask" "F.Paste")
			(net "GND")
		)
	)
	(footprint ""
		(layer "F.Cu")
		(at 297.688 -108.966 -90)
		(property "Reference" "R1348"
			(at 0 0 270)
			(layer "F.SilkS")
			(hide yes)
			(effects
				(font
					(size 1.27 1.27)
				)
			)
		)
		(property "Value" ""
			(at 0 0 270)
			(layer "F.Fab")
			(effects
				(font
					(size 1.27 1.27)
				)
			)
		)
		(duplicate_pad_numbers_are_jumpers no)
		(fp_line
			(start -0.7874 0.4064)
			(end -0.7874 -0.4064)
			(stroke
				(width 0.1524)
				(type default)
			)
			(layer "F.SilkS")
		)
		(fp_line
			(start 0.7874 0.4064)
			(end -0.7874 0.4064)
			(stroke
				(width 0.1524)
				(type default)
			)
			(layer "F.SilkS")
		)
		(fp_line
			(start -0.7874 -0.4064)
			(end 0.7874 -0.4064)
			(stroke
				(width 0.1524)
				(type default)
			)
			(layer "F.SilkS")
		)
		(fp_line
			(start 0.7874 -0.4064)
			(end 0.7874 0.4064)
			(stroke
				(width 0.1524)
				(type default)
			)
			(layer "F.SilkS")
		)
		(fp_line
			(start -0.67945 0.3048)
			(end -0.67945 -0.305054)
			(stroke
				(width 0.1)
				(type default)
			)
			(layer "F.Fab")
		)
		(fp_line
			(start -0.12065 0.3048)
			(end -0.67945 0.3048)
			(stroke
				(width 0.1)
				(type default)
			)
			(layer "F.Fab")
		)
		(fp_line
			(start 0.120396 0.3048)
			(end 0.120396 0.2794)
			(stroke
				(width 0.1)
				(type default)
			)
			(layer "F.Fab")
		)
		(fp_line
			(start 0.67945 0.3048)
			(end 0.120396 0.3048)
			(stroke
				(width 0.1)
				(type default)
			)
			(layer "F.Fab")
		)
		(fp_line
			(start -0.12065 0.2794)
			(end -0.12065 0.3048)
			(stroke
				(width 0.1)
				(type default)
			)
			(layer "F.Fab")
		)
		(fp_line
			(start 0.120396 0.2794)
			(end -0.12065 0.2794)
			(stroke
				(width 0.1)
				(type default)
			)
			(layer "F.Fab")
		)
		(fp_line
			(start -0.12065 -0.2794)
			(end 0.12065 -0.2794)
			(stroke
				(width 0.1)
				(type default)
			)
			(layer "F.Fab")
		)
		(fp_line
			(start 0.12065 -0.2794)
			(end 0.12065 -0.3048)
			(stroke
				(width 0.1)
				(type default)
			)
			(layer "F.Fab")
		)
		(fp_line
			(start 0.12065 -0.3048)
			(end 0.67945 -0.3048)
			(stroke
				(width 0.1)
				(type default)
			)
			(layer "F.Fab")
		)
		(fp_line
			(start 0.67945 -0.3048)
			(end 0.67945 0.3048)
			(stroke
				(width 0.1)
				(type default)
			)
			(layer "F.Fab")
		)
		(fp_line
			(start -0.67945 -0.305054)
			(end -0.12065 -0.305054)
			(stroke
				(width 0.1)
				(type default)
			)
			(layer "F.Fab")
		)
		(fp_line
			(start -0.12065 -0.305054)
			(end -0.12065 -0.2794)
			(stroke
				(width 0.1)
				(type default)
			)
			(layer "F.Fab")
		)
		(pad "1" smd circle
			(at -0.40005 0 270)
			(size 0 0)
			(layers "F.Cu" "F.Mask" "F.Paste")
			(net "SMB_INA230_3V3AUX_SCL")
		)
		(pad "2" smd circle
			(at 0.40005 0 270)
			(size 0 0)
			(layers "F.Cu" "F.Mask" "F.Paste")
			(net "SMB_INA230_8_3V3AUX_SCL_R")
		)
	)
	(footprint ""
		(layer "F.Cu")
		(at 103.951786 -104.674924 180)
		(property "Reference" ""
			(at 0 0 180)
			(layer "F.SilkS")
			(hide yes)
			(effects
				(font
					(size 1.27 1.27)
				)
			)
		)
		(property "Value" ""
			(at 0 0 180)
			(layer "F.Fab")
			(effects
				(font
					(size 1.27 1.27)
				)
			)
		)
		(duplicate_pad_numbers_are_jumpers no)
		(pad "1" smd circle
			(at 0 0 180)
			(size 0.9906 0.9906)
			(layers "F.Cu" "F.Mask" "F.Paste")
			(net "Net_2238")
		)
		(zone
			(layer "F.Cu")
			(hatch none 0.5)
			(connect_pads
				(clearance 0)
			)
			(min_thickness 0.25)
			(keepout
				(tracks not_allowed)
				(vias allowed)
				(pads allowed)
				(copperpour not_allowed)
				(footprints allowed)
			)
			(placement
				(enabled no)
				(sheetname "")
			)
			(fill
				(thermal_gap 0.5)
				(thermal_bridge_width 0.5)
				(island_removal_mode 0)
			)
			(polygon
				(pts
					(arc
						(start 105.577386 -104.674924)
						(mid 102.326186 -104.674924)
						(end 105.577386 -104.674924)
					)
				)
			)
		)
	)
	(footprint ""
		(layer "F.Cu")
		(at 86.420706 -178.359562 180)
		(property "Reference" "PC261_2"
			(at 0 0 180)
			(layer "F.SilkS")
			(hide yes)
			(effects
				(font
					(size 1.27 1.27)
				)
			)
		)
		(property "Value" ""
			(at 0 0 180)
			(layer "F.Fab")
			(effects
				(font
					(size 1.27 1.27)
				)
			)
		)
		(duplicate_pad_numbers_are_jumpers no)
		(fp_line
			(start 0.7874 0.4064)
			(end -0.7874 0.4064)
			(stroke
				(width 0.1524)
				(type default)
			)
			(layer "F.SilkS")
		)
		(fp_line
			(start 0.7874 -0.4064)
			(end 0.7874 0.4064)
			(stroke
				(width 0.1524)
				(type default)
			)
			(layer "F.SilkS")
		)
		(fp_line
			(start -0.7874 0.4064)
			(end -0.7874 -0.4064)
			(stroke
				(width 0.1524)
				(type default)
			)
			(layer "F.SilkS")
		)
		(fp_line
			(start -0.7874 -0.4064)
			(end 0.7874 -0.4064)
			(stroke
				(width 0.1524)
				(type default)
			)
			(layer "F.SilkS")
		)
		(fp_line
			(start 0.67945 0.3048)
			(end 0.120396 0.3048)
			(stroke
				(width 0.1)
				(type default)
			)
			(layer "F.Fab")
		)
		(fp_line
			(start 0.67945 -0.3048)
			(end 0.67945 0.3048)
			(stroke
				(width 0.1)
				(type default)
			)
			(layer "F.Fab")
		)
		(fp_line
			(start 0.12065 -0.2794)
			(end 0.12065 -0.3048)
			(stroke
				(width 0.1)
				(type default)
			)
			(layer "F.Fab")
		)
		(fp_line
			(start 0.12065 -0.3048)
			(end 0.67945 -0.3048)
			(stroke
				(width 0.1)
				(type default)
			)
			(layer "F.Fab")
		)
		(fp_line
			(start 0.120396 0.3048)
			(end 0.120396 0.2794)
			(stroke
				(width 0.1)
				(type default)
			)
			(layer "F.Fab")
		)
		(fp_line
			(start 0.120396 0.2794)
			(end -0.12065 0.2794)
			(stroke
				(width 0.1)
				(type default)
			)
			(layer "F.Fab")
		)
		(fp_line
			(start -0.12065 0.3048)
			(end -0.67945 0.3048)
			(stroke
				(width 0.1)
				(type default)
			)
			(layer "F.Fab")
		)
		(fp_line
			(start -0.12065 0.2794)
			(end -0.12065 0.3048)
			(stroke
				(width 0.1)
				(type default)
			)
			(layer "F.Fab")
		)
		(fp_line
			(start -0.12065 -0.2794)
			(end 0.12065 -0.2794)
			(stroke
				(width 0.1)
				(type default)
			)
			(layer "F.Fab")
		)
		(fp_line
			(start -0.12065 -0.305054)
			(end -0.12065 -0.2794)
			(stroke
				(width 0.1)
				(type default)
			)
			(layer "F.Fab")
		)
		(fp_line
			(start -0.67945 0.3048)
			(end -0.67945 -0.305054)
			(stroke
				(width 0.1)
				(type default)
			)
			(layer "F.Fab")
		)
		(fp_line
			(start -0.67945 -0.305054)
			(end -0.12065 -0.305054)
			(stroke
				(width 0.1)
				(type default)
			)
			(layer "F.Fab")
		)
		(pad "1" smd circle
			(at -0.40005 0 180)
			(size 0 0)
			(layers "F.Cu" "F.Mask" "F.Paste")
			(net "SW_P12V_AUX_PVDDCR_CPU0_P1_FLT")
		)
		(pad "2" smd circle
			(at 0.40005 0 180)
			(size 0 0)
			(layers "F.Cu" "F.Mask" "F.Paste")
			(net "GND")
		)
	)
	(footprint ""
		(layer "F.Cu")
		(at 366.822736 -403.285452 90)
		(property "Reference" "R1096"
			(at 0 0 90)
			(layer "F.SilkS")
			(hide yes)
			(effects
				(font
					(size 1.27 1.27)
				)
			)
		)
		(property "Value" ""
			(at 0 0 90)
			(layer "F.Fab")
			(effects
				(font
					(size 1.27 1.27)
				)
			)
		)
		(duplicate_pad_numbers_are_jumpers no)
		(fp_line
			(start 0.32512 -0.175006)
			(end 0.32512 0.175006)
			(stroke
				(width 0.1)
				(type default)
			)
			(layer "F.Fab")
		)
		(fp_line
			(start -0.32512 -0.175006)
			(end 0.32512 -0.175006)
			(stroke
				(width 0.1)
				(type default)
			)
			(layer "F.Fab")
		)
		(fp_line
			(start 0.32512 0.175006)
			(end -0.32512 0.175006)
			(stroke
				(width 0.1)
				(type default)
			)
			(layer "F.Fab")
		)
		(fp_line
			(start -0.32512 0.175006)
			(end -0.32512 -0.175006)
			(stroke
				(width 0.1)
				(type default)
			)
			(layer "F.Fab")
		)
		(pad "1" smd rect
			(at -0.2667 0 90)
			(size 0.3048 0.381)
			(layers "F.Cu" "F.Mask" "F.Paste")
			(net "RST_RT_CPU0_P3_RESET_N")
		)
		(pad "2" smd rect
			(at 0.2667 0 270)
			(size 0.3048 0.381)
			(layers "F.Cu" "F.Mask" "F.Paste")
			(net "RST_RT_CPU0_P3_RESET_R_N")
		)
	)
	(footprint ""
		(layer "F.Cu")
		(at 43.265852 -383.7432)
		(property "Reference" "R725"
			(at 0 0 0)
			(layer "F.SilkS")
			(hide yes)
			(effects
				(font
					(size 1.27 1.27)
				)
			)
		)
		(property "Value" ""
			(at 0 0 0)
			(layer "F.Fab")
			(effects
				(font
					(size 1.27 1.27)
				)
			)
		)
		(duplicate_pad_numbers_are_jumpers no)
		(fp_line
			(start -0.32512 -0.175006)
			(end 0.32512 -0.175006)
			(stroke
				(width 0.1)
				(type default)
			)
			(layer "F.Fab")
		)
		(fp_line
			(start -0.32512 0.175006)
			(end -0.32512 -0.175006)
			(stroke
				(width 0.1)
				(type default)
			)
			(layer "F.Fab")
		)
		(fp_line
			(start 0.32512 -0.175006)
			(end 0.32512 0.175006)
			(stroke
				(width 0.1)
				(type default)
			)
			(layer "F.Fab")
		)
		(fp_line
			(start 0.32512 0.175006)
			(end -0.32512 0.175006)
			(stroke
				(width 0.1)
				(type default)
			)
			(layer "F.Fab")
		)
		(pad "1" smd rect
			(at -0.2667 0)
			(size 0.3048 0.381)
			(layers "F.Cu" "F.Mask" "F.Paste")
			(net "TEST2_RT_CPU1_P0")
		)
		(pad "2" smd rect
			(at 0.2667 0 180)
			(size 0.3048 0.381)
			(layers "F.Cu" "F.Mask" "F.Paste")
			(net "GND")
		)
	)
	(footprint ""
		(layer "F.Cu")
		(at 12.99972 -435.600094)
		(property "Reference" "H97"
			(at 4.924044 -4.168394 0)
			(unlocked yes)
			(layer "F.SilkS")
			(effects
				(font
					(size 0.7874 0.5842)
					(thickness 0.1524)
				)
				(justify left)
			)
		)
		(property "Value" ""
			(at 0 0 0)
			(layer "F.Fab")
			(effects
				(font
					(size 1.27 1.27)
				)
			)
		)
		(duplicate_pad_numbers_are_jumpers no)
		(pad "1" thru_hole circle
			(at 0 0)
			(size 10.0076 10.0076)
			(drill 5.6134)
			(layers "*.Cu" "*.Mask")
			(remove_unused_layers no)
			(net "GND")
			(clearance -1.9431)
		)
	)
	(footprint ""
		(layer "F.Cu")
		(at 458.799692 -435.600094)
		(property "Reference" "H103"
			(at -6.63321 -4.534154 0)
			(unlocked yes)
			(layer "F.SilkS")
			(effects
				(font
					(size 0.7874 0.5842)
					(thickness 0.1524)
				)
				(justify left)
			)
		)
		(property "Value" ""
			(at 0 0 0)
			(layer "F.Fab")
			(effects
				(font
					(size 1.27 1.27)
				)
			)
		)
		(duplicate_pad_numbers_are_jumpers no)
		(pad "1" thru_hole circle
			(at 0 0)
			(size 10.0076 10.0076)
			(drill 5.6134)
			(layers "*.Cu" "*.Mask")
			(remove_unused_layers no)
			(net "GND")
			(clearance -1.9431)
		)
	)
	(footprint ""
		(layer "F.Cu")
		(at 73.406 -59.055 -90)
		(property "Reference" "U35"
			(at 0.943102 -2.804668 90)
			(unlocked yes)
			(layer "F.SilkS")
			(effects
				(font
					(size 0.7874 0.5842)
					(thickness 0.1524)
				)
				(justify left)
			)
		)
		(property "Value" ""
			(at 0 0 270)
			(layer "F.Fab")
			(effects
				(font
					(size 1.27 1.27)
				)
			)
		)
		(duplicate_pad_numbers_are_jumpers no)
		(fp_line
			(start -1.733296 1.549908)
			(end 1.733296 1.549908)
			(stroke
				(width 0.1524)
				(type default)
			)
			(layer "F.SilkS")
		)
		(fp_line
			(start 1.733296 1.549908)
			(end 1.733296 -1.549908)
			(stroke
				(width 0.1524)
				(type default)
			)
			(layer "F.SilkS")
		)
		(fp_line
			(start 0 -0.889)
			(end -0.660908 -1.549908)
			(stroke
				(width 0.1524)
				(type default)
			)
			(layer "F.SilkS")
		)
		(fp_line
			(start -1.733296 -1.549908)
			(end -1.733296 1.549908)
			(stroke
				(width 0.1524)
				(type default)
			)
			(layer "F.SilkS")
		)
		(fp_line
			(start -0.660908 -1.549908)
			(end -1.733296 -1.549908)
			(stroke
				(width 0.1524)
				(type default)
			)
			(layer "F.SilkS")
		)
		(fp_line
			(start 0.660908 -1.549908)
			(end 0 -0.889)
			(stroke
				(width 0.1524)
				(type default)
			)
			(layer "F.SilkS")
		)
		(fp_line
			(start 1.733296 -1.549908)
			(end 0.660908 -1.549908)
			(stroke
				(width 0.1524)
				(type default)
			)
			(layer "F.SilkS")
		)
		(fp_poly
			(pts
				(xy -1.80975 -2.293366) (xy -2.223262 -1.998218) (xy -1.721358 -1.73228)
			)
			(stroke
				(width 0)
				(type default)
			)
			(fill yes)
			(layer "F.SilkS")
		)
		(fp_line
			(start -0.849884 1.549908)
			(end 0.849884 1.549908)
			(stroke
				(width 0.1)
				(type default)
			)
			(layer "F.Fab")
		)
		(fp_line
			(start 0.849884 1.549908)
			(end 0.849884 -1.549908)
			(stroke
				(width 0.1)
				(type default)
			)
			(layer "F.Fab")
		)
		(fp_line
			(start -0.849884 -1.549908)
			(end -0.849884 1.549908)
			(stroke
				(width 0.1)
				(type default)
			)
			(layer "F.Fab")
		)
		(fp_line
			(start 0.849884 -1.549908)
			(end -0.849884 -1.549908)
			(stroke
				(width 0.1)
				(type default)
			)
			(layer "F.Fab")
		)
		(fp_poly
			(pts
				(xy -2.4384 -1.20396) (xy -2.4384 -0.69596) (xy -1.9304 -0.94996)
			)
			(stroke
				(width 0)
				(type default)
			)
			(fill yes)
			(layer "F.Fab")
		)
		(pad "1" smd rect
			(at -1.199896 -0.94996 180)
			(size 0.5588 0.8128)
			(layers "F.Cu" "F.Mask" "F.Paste")
			(net "RST_PERST_OCP_V3_2_R_N")
		)
		(pad "2" smd rect
			(at -1.199896 0 180)
			(size 0.5588 0.8128)
			(layers "F.Cu" "F.Mask" "F.Paste")
			(net "HP_LVC3_OCP_V3_2_PWRGD")
		)
		(pad "3" smd rect
			(at -1.199896 0.94996 180)
			(size 0.5588 0.8128)
			(layers "F.Cu" "F.Mask" "F.Paste")
			(net "GND")
		)
		(pad "4" smd rect
			(at 1.199896 0.94996 180)
			(size 0.5588 0.8128)
			(layers "F.Cu" "F.Mask" "F.Paste")
			(net "RST_PERST_OCP_V3_2_BUF_R_N")
		)
		(pad "5" smd rect
			(at 1.199896 -0.94996 180)
			(size 0.5588 0.8128)
			(layers "F.Cu" "F.Mask" "F.Paste")
			(net "P3V3_AUX")
		)
	)
	(footprint ""
		(layer "F.Cu")
		(at 419.597586 -176.338738 -90)
		(property "Reference" "PC599"
			(at 0 0 270)
			(layer "F.SilkS")
			(hide yes)
			(effects
				(font
					(size 1.27 1.27)
				)
			)
		)
		(property "Value" ""
			(at 0 0 270)
			(layer "F.Fab")
			(effects
				(font
					(size 1.27 1.27)
				)
			)
		)
		(duplicate_pad_numbers_are_jumpers no)
		(fp_line
			(start -0.7874 0.4064)
			(end -0.7874 -0.4064)
			(stroke
				(width 0.1524)
				(type default)
			)
			(layer "F.SilkS")
		)
		(fp_line
			(start 0.7874 0.4064)
			(end -0.7874 0.4064)
			(stroke
				(width 0.1524)
				(type default)
			)
			(layer "F.SilkS")
		)
		(fp_line
			(start -0.7874 -0.4064)
			(end 0.7874 -0.4064)
			(stroke
				(width 0.1524)
				(type default)
			)
			(layer "F.SilkS")
		)
		(fp_line
			(start 0.7874 -0.4064)
			(end 0.7874 0.4064)
			(stroke
				(width 0.1524)
				(type default)
			)
			(layer "F.SilkS")
		)
		(fp_line
			(start -0.67945 0.3048)
			(end -0.67945 -0.305054)
			(stroke
				(width 0.1)
				(type default)
			)
			(layer "F.Fab")
		)
		(fp_line
			(start -0.12065 0.3048)
			(end -0.67945 0.3048)
			(stroke
				(width 0.1)
				(type default)
			)
			(layer "F.Fab")
		)
		(fp_line
			(start 0.120396 0.3048)
			(end 0.120396 0.2794)
			(stroke
				(width 0.1)
				(type default)
			)
			(layer "F.Fab")
		)
		(fp_line
			(start 0.67945 0.3048)
			(end 0.120396 0.3048)
			(stroke
				(width 0.1)
				(type default)
			)
			(layer "F.Fab")
		)
		(fp_line
			(start -0.12065 0.2794)
			(end -0.12065 0.3048)
			(stroke
				(width 0.1)
				(type default)
			)
			(layer "F.Fab")
		)
		(fp_line
			(start 0.120396 0.2794)
			(end -0.12065 0.2794)
			(stroke
				(width 0.1)
				(type default)
			)
			(layer "F.Fab")
		)
		(fp_line
			(start -0.12065 -0.2794)
			(end 0.12065 -0.2794)
			(stroke
				(width 0.1)
				(type default)
			)
			(layer "F.Fab")
		)
		(fp_line
			(start 0.12065 -0.2794)
			(end 0.12065 -0.3048)
			(stroke
				(width 0.1)
				(type default)
			)
			(layer "F.Fab")
		)
		(fp_line
			(start 0.12065 -0.3048)
			(end 0.67945 -0.3048)
			(stroke
				(width 0.1)
				(type default)
			)
			(layer "F.Fab")
		)
		(fp_line
			(start 0.67945 -0.3048)
			(end 0.67945 0.3048)
			(stroke
				(width 0.1)
				(type default)
			)
			(layer "F.Fab")
		)
		(fp_line
			(start -0.67945 -0.305054)
			(end -0.12065 -0.305054)
			(stroke
				(width 0.1)
				(type default)
			)
			(layer "F.Fab")
		)
		(fp_line
			(start -0.12065 -0.305054)
			(end -0.12065 -0.2794)
			(stroke
				(width 0.1)
				(type default)
			)
			(layer "F.Fab")
		)
		(pad "1" smd circle
			(at -0.40005 0 270)
			(size 0 0)
			(layers "F.Cu" "F.Mask" "F.Paste")
			(net "PVDDCR_SOC_P0")
		)
		(pad "2" smd circle
			(at 0.40005 0 270)
			(size 0 0)
			(layers "F.Cu" "F.Mask" "F.Paste")
			(net "GND")
		)
	)
	(footprint ""
		(layer "F.Cu")
		(at 119.458486 -428.873412 -90)
		(property "Reference" "U253"
			(at 1.385824 1.781302 90)
			(unlocked yes)
			(layer "F.SilkS")
			(effects
				(font
					(size 0.7874 0.5842)
					(thickness 0.1524)
				)
				(justify left)
			)
		)
		(property "Value" ""
			(at 0 0 270)
			(layer "F.Fab")
			(effects
				(font
					(size 1.27 1.27)
				)
			)
		)
		(duplicate_pad_numbers_are_jumpers no)
		(fp_line
			(start -1.3462 1.100074)
			(end -1.3462 -1.100074)
			(stroke
				(width 0.1524)
				(type default)
			)
			(layer "F.SilkS")
		)
		(fp_line
			(start 1.3462 1.100074)
			(end -1.3462 1.100074)
			(stroke
				(width 0.1524)
				(type default)
			)
			(layer "F.SilkS")
		)
		(fp_line
			(start 0 -0.381)
			(end 0.670052 -1.100074)
			(stroke
				(width 0.1524)
				(type default)
			)
			(layer "F.SilkS")
		)
		(fp_line
			(start -1.3462 -1.100074)
			(end -0.670052 -1.100074)
			(stroke
				(width 0.1524)
				(type default)
			)
			(layer "F.SilkS")
		)
		(fp_line
			(start -0.670052 -1.100074)
			(end 0 -0.381)
			(stroke
				(width 0.1524)
				(type default)
			)
			(layer "F.SilkS")
		)
		(fp_line
			(start 0.670052 -1.100074)
			(end 1.3462 -1.100074)
			(stroke
				(width 0.1524)
				(type default)
			)
			(layer "F.SilkS")
		)
		(fp_line
			(start 1.3462 -1.100074)
			(end 1.3462 1.100074)
			(stroke
				(width 0.1524)
				(type default)
			)
			(layer "F.SilkS")
		)
		(fp_poly
			(pts
				(xy -1.616456 -1.671066) (xy -1.001522 -1.930146) (xy -1.049782 -1.185164)
			)
			(stroke
				(width 0)
				(type default)
			)
			(fill yes)
			(layer "F.SilkS")
		)
		(fp_line
			(start -0.670052 1.100074)
			(end -0.670052 0.8001)
			(stroke
				(width 0.1)
				(type default)
			)
			(layer "F.Fab")
		)
		(fp_line
			(start 0.670052 1.100074)
			(end -0.670052 1.100074)
			(stroke
				(width 0.1)
				(type default)
			)
			(layer "F.Fab")
		)
		(fp_line
			(start -1.100074 0.8001)
			(end -1.100074 -0.8001)
			(stroke
				(width 0.1)
				(type default)
			)
			(layer "F.Fab")
		)
		(fp_line
			(start -0.670052 0.8001)
			(end -1.100074 0.8001)
			(stroke
				(width 0.1)
				(type default)
			)
			(layer "F.Fab")
		)
		(fp_line
			(start -0.670052 0.8001)
			(end -0.670052 -0.8001)
			(stroke
				(width 0.1)
				(type default)
			)
			(layer "F.Fab")
		)
		(fp_line
			(start 0.670052 0.8001)
			(end 0.670052 1.100074)
			(stroke
				(width 0.1)
				(type default)
			)
			(layer "F.Fab")
		)
		(fp_line
			(start 1.100074 0.8001)
			(end 0.670052 0.8001)
			(stroke
				(width 0.1)
				(type default)
			)
			(layer "F.Fab")
		)
		(fp_line
			(start -1.100074 -0.8001)
			(end -0.670052 -0.8001)
			(stroke
				(width 0.1)
				(type default)
			)
			(layer "F.Fab")
		)
		(fp_line
			(start -0.670052 -0.8001)
			(end -0.670052 -1.100074)
			(stroke
				(width 0.1)
				(type default)
			)
			(layer "F.Fab")
		)
		(fp_line
			(start 0.670052 -0.8001)
			(end 0.670052 0.8001)
			(stroke
				(width 0.1)
				(type default)
			)
			(layer "F.Fab")
		)
		(fp_line
			(start 0.670052 -0.8001)
			(end 1.100074 -0.8001)
			(stroke
				(width 0.1)
				(type default)
			)
			(layer "F.Fab")
		)
		(fp_line
			(start 1.100074 -0.8001)
			(end 1.100074 0.8001)
			(stroke
				(width 0.1)
				(type default)
			)
			(layer "F.Fab")
		)
		(fp_line
			(start -0.670052 -1.100074)
			(end 0.670052 -1.100074)
			(stroke
				(width 0.1)
				(type default)
			)
			(layer "F.Fab")
		)
		(fp_line
			(start 0.670052 -1.100074)
			(end 0.670052 -0.8001)
			(stroke
				(width 0.1)
				(type default)
			)
			(layer "F.Fab")
		)
		(fp_poly
			(pts
				(xy -1.524 -0.649986) (xy -2.286 -1.030986) (xy -2.286 -0.268986)
			)
			(stroke
				(width 0)
				(type default)
			)
			(fill yes)
			(layer "F.Fab")
		)
		(pad "1" smd rect
			(at -0.94996 -0.649986 180)
			(size 0.4064 0.508)
			(layers "F.Cu" "F.Mask" "F.Paste")
			(net "GPU_FPGA_BOOT_EN")
		)
		(pad "2" smd rect
			(at -0.94996 0 180)
			(size 0.4064 0.508)
			(layers "F.Cu" "F.Mask" "F.Paste")
			(net "GND")
		)
		(pad "3" smd rect
			(at -0.94996 0.649986 180)
			(size 0.4064 0.508)
			(layers "F.Cu" "F.Mask" "F.Paste")
			(net "GPU_BASE_STBY_EN")
		)
		(pad "4" smd rect
			(at 0.94996 0.649986 180)
			(size 0.4064 0.508)
			(layers "F.Cu" "F.Mask" "F.Paste")
			(net "GPU_BASE_STBY_EN_BUF_R")
		)
		(pad "5" smd rect
			(at 0.94996 0 180)
			(size 0.4064 0.508)
			(layers "F.Cu" "F.Mask" "F.Paste")
			(net "P3V3_AUX")
		)
		(pad "6" smd rect
			(at 0.94996 -0.649986 180)
			(size 0.4064 0.508)
			(layers "F.Cu" "F.Mask" "F.Paste")
			(net "GPU_FPGA_BOOT_EN_BUF_R")
		)
	)
	(footprint ""
		(layer "F.Cu")
		(at 240.792 -285.2928 180)
		(property "Reference" "PC6900"
			(at 0 0 180)
			(layer "F.SilkS")
			(hide yes)
			(effects
				(font
					(size 1.27 1.27)
				)
			)
		)
		(property "Value" ""
			(at 0 0 180)
			(layer "F.Fab")
			(effects
				(font
					(size 1.27 1.27)
				)
			)
		)
		(duplicate_pad_numbers_are_jumpers no)
		(fp_line
			(start 1.524 0.762)
			(end -1.524 0.762)
			(stroke
				(width 0.1524)
				(type default)
			)
			(layer "F.SilkS")
		)
		(fp_line
			(start 1.524 -0.762)
			(end 1.524 0.762)
			(stroke
				(width 0.1524)
				(type default)
			)
			(layer "F.SilkS")
		)
		(fp_line
			(start -1.524 0.762)
			(end -1.524 -0.762)
			(stroke
				(width 0.1524)
				(type default)
			)
			(layer "F.SilkS")
		)
		(fp_line
			(start -1.524 -0.762)
			(end 1.524 -0.762)
			(stroke
				(width 0.1524)
				(type default)
			)
			(layer "F.SilkS")
		)
		(fp_line
			(start 1.1049 0.724916)
			(end 1.1049 -0.724916)
			(stroke
				(width 0.1)
				(type default)
			)
			(layer "F.Fab")
		)
		(fp_line
			(start 1.1049 -0.724916)
			(end -1.1049 -0.724916)
			(stroke
				(width 0.1)
				(type default)
			)
			(layer "F.Fab")
		)
		(fp_line
			(start -1.1049 0.724916)
			(end 1.1049 0.724916)
			(stroke
				(width 0.1)
				(type default)
			)
			(layer "F.Fab")
		)
		(fp_line
			(start -1.1049 -0.724916)
			(end -1.1049 0.724916)
			(stroke
				(width 0.1)
				(type default)
			)
			(layer "F.Fab")
		)
		(pad "1" smd rect
			(at -0.889 0)
			(size 1.016 1.27)
			(layers "F.Cu" "F.Mask" "F.Paste")
			(net "SW_P12V_AUX_P1V8_RETIMER_CPU0_FLT")
		)
		(pad "2" smd rect
			(at 0.889 0)
			(size 1.016 1.27)
			(layers "F.Cu" "F.Mask" "F.Paste")
			(net "GND")
		)
	)
	(footprint ""
		(layer "F.Cu")
		(at 187.221622 -22.727158 -90)
		(property "Reference" "PR4001"
			(at 0 0 270)
			(layer "F.SilkS")
			(hide yes)
			(effects
				(font
					(size 1.27 1.27)
				)
			)
		)
		(property "Value" ""
			(at 0 0 270)
			(layer "F.Fab")
			(effects
				(font
					(size 1.27 1.27)
				)
			)
		)
		(duplicate_pad_numbers_are_jumpers no)
		(fp_line
			(start -0.7874 0.4064)
			(end -0.7874 -0.4064)
			(stroke
				(width 0.1524)
				(type default)
			)
			(layer "F.SilkS")
		)
		(fp_line
			(start 0.7874 0.4064)
			(end -0.7874 0.4064)
			(stroke
				(width 0.1524)
				(type default)
			)
			(layer "F.SilkS")
		)
		(fp_line
			(start -0.7874 -0.4064)
			(end 0.7874 -0.4064)
			(stroke
				(width 0.1524)
				(type default)
			)
			(layer "F.SilkS")
		)
		(fp_line
			(start 0.7874 -0.4064)
			(end 0.7874 0.4064)
			(stroke
				(width 0.1524)
				(type default)
			)
			(layer "F.SilkS")
		)
		(fp_line
			(start -0.67945 0.3048)
			(end -0.67945 -0.305054)
			(stroke
				(width 0.1)
				(type default)
			)
			(layer "F.Fab")
		)
		(fp_line
			(start -0.12065 0.3048)
			(end -0.67945 0.3048)
			(stroke
				(width 0.1)
				(type default)
			)
			(layer "F.Fab")
		)
		(fp_line
			(start 0.120396 0.3048)
			(end 0.120396 0.2794)
			(stroke
				(width 0.1)
				(type default)
			)
			(layer "F.Fab")
		)
		(fp_line
			(start 0.67945 0.3048)
			(end 0.120396 0.3048)
			(stroke
				(width 0.1)
				(type default)
			)
			(layer "F.Fab")
		)
		(fp_line
			(start -0.12065 0.2794)
			(end -0.12065 0.3048)
			(stroke
				(width 0.1)
				(type default)
			)
			(layer "F.Fab")
		)
		(fp_line
			(start 0.120396 0.2794)
			(end -0.12065 0.2794)
			(stroke
				(width 0.1)
				(type default)
			)
			(layer "F.Fab")
		)
		(fp_line
			(start -0.12065 -0.2794)
			(end 0.12065 -0.2794)
			(stroke
				(width 0.1)
				(type default)
			)
			(layer "F.Fab")
		)
		(fp_line
			(start 0.12065 -0.2794)
			(end 0.12065 -0.3048)
			(stroke
				(width 0.1)
				(type default)
			)
			(layer "F.Fab")
		)
		(fp_line
			(start 0.12065 -0.3048)
			(end 0.67945 -0.3048)
			(stroke
				(width 0.1)
				(type default)
			)
			(layer "F.Fab")
		)
		(fp_line
			(start 0.67945 -0.3048)
			(end 0.67945 0.3048)
			(stroke
				(width 0.1)
				(type default)
			)
			(layer "F.Fab")
		)
		(fp_line
			(start -0.67945 -0.305054)
			(end -0.12065 -0.305054)
			(stroke
				(width 0.1)
				(type default)
			)
			(layer "F.Fab")
		)
		(fp_line
			(start -0.12065 -0.305054)
			(end -0.12065 -0.2794)
			(stroke
				(width 0.1)
				(type default)
			)
			(layer "F.Fab")
		)
		(pad "1" smd circle
			(at -0.40005 0 270)
			(size 0 0)
			(layers "F.Cu" "F.Mask" "F.Paste")
			(net "P12V_SCM_UV")
		)
		(pad "2" smd circle
			(at 0.40005 0 270)
			(size 0 0)
			(layers "F.Cu" "F.Mask" "F.Paste")
			(net "P12V_SCM_OV")
		)
	)
	(footprint ""
		(layer "F.Cu")
		(at 368.427 -413.639 90)
		(property "Reference" "R4215"
			(at 0 0 90)
			(layer "F.SilkS")
			(hide yes)
			(effects
				(font
					(size 1.27 1.27)
				)
			)
		)
		(property "Value" ""
			(at 0 0 90)
			(layer "F.Fab")
			(effects
				(font
					(size 1.27 1.27)
				)
			)
		)
		(duplicate_pad_numbers_are_jumpers no)
		(fp_line
			(start 0.7874 -0.4064)
			(end 0.7874 0.4064)
			(stroke
				(width 0.1524)
				(type default)
			)
			(layer "F.SilkS")
		)
		(fp_line
			(start -0.7874 -0.4064)
			(end 0.7874 -0.4064)
			(stroke
				(width 0.1524)
				(type default)
			)
			(layer "F.SilkS")
		)
		(fp_line
			(start 0.7874 0.4064)
			(end -0.7874 0.4064)
			(stroke
				(width 0.1524)
				(type default)
			)
			(layer "F.SilkS")
		)
		(fp_line
			(start -0.7874 0.4064)
			(end -0.7874 -0.4064)
			(stroke
				(width 0.1524)
				(type default)
			)
			(layer "F.SilkS")
		)
		(fp_line
			(start -0.12065 -0.305054)
			(end -0.12065 -0.2794)
			(stroke
				(width 0.1)
				(type default)
			)
			(layer "F.Fab")
		)
		(fp_line
			(start -0.67945 -0.305054)
			(end -0.12065 -0.305054)
			(stroke
				(width 0.1)
				(type default)
			)
			(layer "F.Fab")
		)
		(fp_line
			(start 0.67945 -0.3048)
			(end 0.67945 0.3048)
			(stroke
				(width 0.1)
				(type default)
			)
			(layer "F.Fab")
		)
		(fp_line
			(start 0.12065 -0.3048)
			(end 0.67945 -0.3048)
			(stroke
				(width 0.1)
				(type default)
			)
			(layer "F.Fab")
		)
		(fp_line
			(start 0.12065 -0.2794)
			(end 0.12065 -0.3048)
			(stroke
				(width 0.1)
				(type default)
			)
			(layer "F.Fab")
		)
		(fp_line
			(start -0.12065 -0.2794)
			(end 0.12065 -0.2794)
			(stroke
				(width 0.1)
				(type default)
			)
			(layer "F.Fab")
		)
		(fp_line
			(start 0.120396 0.2794)
			(end -0.12065 0.2794)
			(stroke
				(width 0.1)
				(type default)
			)
			(layer "F.Fab")
		)
		(fp_line
			(start -0.12065 0.2794)
			(end -0.12065 0.3048)
			(stroke
				(width 0.1)
				(type default)
			)
			(layer "F.Fab")
		)
		(fp_line
			(start 0.67945 0.3048)
			(end 0.120396 0.3048)
			(stroke
				(width 0.1)
				(type default)
			)
			(layer "F.Fab")
		)
		(fp_line
			(start 0.120396 0.3048)
			(end 0.120396 0.2794)
			(stroke
				(width 0.1)
				(type default)
			)
			(layer "F.Fab")
		)
		(fp_line
			(start -0.12065 0.3048)
			(end -0.67945 0.3048)
			(stroke
				(width 0.1)
				(type default)
			)
			(layer "F.Fab")
		)
		(fp_line
			(start -0.67945 0.3048)
			(end -0.67945 -0.305054)
			(stroke
				(width 0.1)
				(type default)
			)
			(layer "F.Fab")
		)
		(pad "1" smd circle
			(at -0.40005 0 90)
			(size 0 0)
			(layers "F.Cu" "F.Mask" "F.Paste")
			(net "FM_THERMAL_ALERT_N")
		)
		(pad "2" smd circle
			(at 0.40005 0 90)
			(size 0 0)
			(layers "F.Cu" "F.Mask" "F.Paste")
			(net "FM_G751_0_ALERT_N")
		)
	)
	(footprint ""
		(layer "F.Cu")
		(at 90.209878 -144.88541)
		(property "Reference" "R8165"
			(at 0 0 0)
			(layer "F.SilkS")
			(hide yes)
			(effects
				(font
					(size 1.27 1.27)
				)
			)
		)
		(property "Value" ""
			(at 0 0 0)
			(layer "F.Fab")
			(effects
				(font
					(size 1.27 1.27)
				)
			)
		)
		(duplicate_pad_numbers_are_jumpers no)
		(fp_line
			(start -0.7874 -0.4064)
			(end 0.7874 -0.4064)
			(stroke
				(width 0.1524)
				(type default)
			)
			(layer "F.SilkS")
		)
		(fp_line
			(start -0.7874 0.4064)
			(end -0.7874 -0.4064)
			(stroke
				(width 0.1524)
				(type default)
			)
			(layer "F.SilkS")
		)
		(fp_line
			(start 0.7874 -0.4064)
			(end 0.7874 0.4064)
			(stroke
				(width 0.1524)
				(type default)
			)
			(layer "F.SilkS")
		)
		(fp_line
			(start 0.7874 0.4064)
			(end -0.7874 0.4064)
			(stroke
				(width 0.1524)
				(type default)
			)
			(layer "F.SilkS")
		)
		(fp_line
			(start -0.67945 -0.305054)
			(end -0.12065 -0.305054)
			(stroke
				(width 0.1)
				(type default)
			)
			(layer "F.Fab")
		)
		(fp_line
			(start -0.67945 0.3048)
			(end -0.67945 -0.305054)
			(stroke
				(width 0.1)
				(type default)
			)
			(layer "F.Fab")
		)
		(fp_line
			(start -0.12065 -0.305054)
			(end -0.12065 -0.2794)
			(stroke
				(width 0.1)
				(type default)
			)
			(layer "F.Fab")
		)
		(fp_line
			(start -0.12065 -0.2794)
			(end 0.12065 -0.2794)
			(stroke
				(width 0.1)
				(type default)
			)
			(layer "F.Fab")
		)
		(fp_line
			(start -0.12065 0.2794)
			(end -0.12065 0.3048)
			(stroke
				(width 0.1)
				(type default)
			)
			(layer "F.Fab")
		)
		(fp_line
			(start -0.12065 0.3048)
			(end -0.67945 0.3048)
			(stroke
				(width 0.1)
				(type default)
			)
			(layer "F.Fab")
		)
		(fp_line
			(start 0.120396 0.2794)
			(end -0.12065 0.2794)
			(stroke
				(width 0.1)
				(type default)
			)
			(layer "F.Fab")
		)
		(fp_line
			(start 0.120396 0.3048)
			(end 0.120396 0.2794)
			(stroke
				(width 0.1)
				(type default)
			)
			(layer "F.Fab")
		)
		(fp_line
			(start 0.12065 -0.3048)
			(end 0.67945 -0.3048)
			(stroke
				(width 0.1)
				(type default)
			)
			(layer "F.Fab")
		)
		(fp_line
			(start 0.12065 -0.2794)
			(end 0.12065 -0.3048)
			(stroke
				(width 0.1)
				(type default)
			)
			(layer "F.Fab")
		)
		(fp_line
			(start 0.67945 -0.3048)
			(end 0.67945 0.3048)
			(stroke
				(width 0.1)
				(type default)
			)
			(layer "F.Fab")
		)
		(fp_line
			(start 0.67945 0.3048)
			(end 0.120396 0.3048)
			(stroke
				(width 0.1)
				(type default)
			)
			(layer "F.Fab")
		)
		(pad "1" smd circle
			(at -0.40005 0)
			(size 0 0)
			(layers "F.Cu" "F.Mask" "F.Paste")
			(net "P3V3_AUX")
		)
		(pad "2" smd circle
			(at 0.40005 0)
			(size 0 0)
			(layers "F.Cu" "F.Mask" "F.Paste")
			(net "PWRGD_PVDDCR_SOC_P1_R")
		)
	)
	(footprint ""
		(layer "F.Cu")
		(at 359.709974 -413.859218 90)
		(property "Reference" "U204"
			(at 0.003048 -1.732534 90)
			(unlocked yes)
			(layer "F.SilkS")
			(effects
				(font
					(size 0.7874 0.5842)
					(thickness 0.1524)
				)
				(justify left)
			)
		)
		(property "Value" ""
			(at 0 0 90)
			(layer "F.Fab")
			(effects
				(font
					(size 1.27 1.27)
				)
			)
		)
		(duplicate_pad_numbers_are_jumpers no)
		(fp_line
			(start 1.400048 -1.100074)
			(end -1.400048 -1.100074)
			(stroke
				(width 0.1524)
				(type default)
			)
			(layer "F.SilkS")
		)
		(fp_line
			(start 1.400048 -1.100074)
			(end 1.400048 1.100074)
			(stroke
				(width 0.1524)
				(type default)
			)
			(layer "F.SilkS")
		)
		(fp_line
			(start 1.400048 1.100074)
			(end -1.400048 1.100074)
			(stroke
				(width 0.1524)
				(type default)
			)
			(layer "F.SilkS")
		)
		(fp_line
			(start -1.400048 1.100074)
			(end -1.400048 -1.100074)
			(stroke
				(width 0.1524)
				(type default)
			)
			(layer "F.SilkS")
		)
		(fp_poly
			(pts
				(xy -2.606548 -0.141986) (xy -2.606548 -1.157986) (xy -1.590548 -0.649986)
			)
			(stroke
				(width 0)
				(type default)
			)
			(fill yes)
			(layer "F.SilkS")
		)
		(fp_line
			(start 0.674878 -1.100074)
			(end 0.674878 1.100074)
			(stroke
				(width 0.1)
				(type default)
			)
			(layer "F.Fab")
		)
		(fp_line
			(start -0.674878 -1.100074)
			(end 0.674878 -1.100074)
			(stroke
				(width 0.1)
				(type default)
			)
			(layer "F.Fab")
		)
		(fp_line
			(start 0.674878 1.100074)
			(end -0.674878 1.100074)
			(stroke
				(width 0.1)
				(type default)
			)
			(layer "F.Fab")
		)
		(fp_line
			(start -0.674878 1.100074)
			(end -0.674878 -1.100074)
			(stroke
				(width 0.1)
				(type default)
			)
			(layer "F.Fab")
		)
		(fp_poly
			(pts
				(xy -1.590548 -0.649986) (xy -2.606548 -1.157986) (xy -2.606548 -0.141986)
			)
			(stroke
				(width 0)
				(type default)
			)
			(fill yes)
			(layer "F.Fab")
		)
		(pad "1" smd rect
			(at -0.94996 -0.649986)
			(size 0.4318 0.6096)
			(layers "F.Cu" "F.Mask" "F.Paste")
			(net "FM_UART_EN")
		)
		(pad "2" smd rect
			(at -0.94996 0)
			(size 0.4318 0.6096)
			(layers "F.Cu" "F.Mask" "F.Paste")
			(net "UART_BMC_BIC_R_RX")
		)
		(pad "3" smd rect
			(at -0.94996 0.649986)
			(size 0.4318 0.6096)
			(layers "F.Cu" "F.Mask" "F.Paste")
			(net "GND")
		)
		(pad "4" smd rect
			(at 0.94996 0.649986)
			(size 0.4318 0.6096)
			(layers "F.Cu" "F.Mask" "F.Paste")
			(net "UART_BMC_BIC_R_BUF_RX")
		)
		(pad "5" smd rect
			(at 0.94996 -0.649986)
			(size 0.4318 0.6096)
			(layers "F.Cu" "F.Mask" "F.Paste")
			(net "P3V3_AUX")
		)
	)
	(footprint ""
		(layer "F.Cu")
		(at 414.316418 -367.796064 180)
		(property "Reference" "C5009"
			(at 0 0 180)
			(layer "F.SilkS")
			(hide yes)
			(effects
				(font
					(size 1.27 1.27)
				)
			)
		)
		(property "Value" ""
			(at 0 0 180)
			(layer "F.Fab")
			(effects
				(font
					(size 1.27 1.27)
				)
			)
		)
		(duplicate_pad_numbers_are_jumpers no)
		(fp_line
			(start 0.7874 0.4064)
			(end -0.7874 0.4064)
			(stroke
				(width 0.1524)
				(type default)
			)
			(layer "F.SilkS")
		)
		(fp_line
			(start 0.7874 -0.4064)
			(end 0.7874 0.4064)
			(stroke
				(width 0.1524)
				(type default)
			)
			(layer "F.SilkS")
		)
		(fp_line
			(start -0.7874 0.4064)
			(end -0.7874 -0.4064)
			(stroke
				(width 0.1524)
				(type default)
			)
			(layer "F.SilkS")
		)
		(fp_line
			(start -0.7874 -0.4064)
			(end 0.7874 -0.4064)
			(stroke
				(width 0.1524)
				(type default)
			)
			(layer "F.SilkS")
		)
		(fp_line
			(start 0.67945 0.3048)
			(end 0.120396 0.3048)
			(stroke
				(width 0.1)
				(type default)
			)
			(layer "F.Fab")
		)
		(fp_line
			(start 0.67945 -0.3048)
			(end 0.67945 0.3048)
			(stroke
				(width 0.1)
				(type default)
			)
			(layer "F.Fab")
		)
		(fp_line
			(start 0.12065 -0.2794)
			(end 0.12065 -0.3048)
			(stroke
				(width 0.1)
				(type default)
			)
			(layer "F.Fab")
		)
		(fp_line
			(start 0.12065 -0.3048)
			(end 0.67945 -0.3048)
			(stroke
				(width 0.1)
				(type default)
			)
			(layer "F.Fab")
		)
		(fp_line
			(start 0.120396 0.3048)
			(end 0.120396 0.2794)
			(stroke
				(width 0.1)
				(type default)
			)
			(layer "F.Fab")
		)
		(fp_line
			(start 0.120396 0.2794)
			(end -0.12065 0.2794)
			(stroke
				(width 0.1)
				(type default)
			)
			(layer "F.Fab")
		)
		(fp_line
			(start -0.12065 0.3048)
			(end -0.67945 0.3048)
			(stroke
				(width 0.1)
				(type default)
			)
			(layer "F.Fab")
		)
		(fp_line
			(start -0.12065 0.2794)
			(end -0.12065 0.3048)
			(stroke
				(width 0.1)
				(type default)
			)
			(layer "F.Fab")
		)
		(fp_line
			(start -0.12065 -0.2794)
			(end 0.12065 -0.2794)
			(stroke
				(width 0.1)
				(type default)
			)
			(layer "F.Fab")
		)
		(fp_line
			(start -0.12065 -0.305054)
			(end -0.12065 -0.2794)
			(stroke
				(width 0.1)
				(type default)
			)
			(layer "F.Fab")
		)
		(fp_line
			(start -0.67945 0.3048)
			(end -0.67945 -0.305054)
			(stroke
				(width 0.1)
				(type default)
			)
			(layer "F.Fab")
		)
		(fp_line
			(start -0.67945 -0.305054)
			(end -0.12065 -0.305054)
			(stroke
				(width 0.1)
				(type default)
			)
			(layer "F.Fab")
		)
		(pad "1" smd circle
			(at -0.40005 0 180)
			(size 0 0)
			(layers "F.Cu" "F.Mask" "F.Paste")
			(net "PVDD11_S3_P0_PMALERT")
		)
		(pad "2" smd circle
			(at 0.40005 0 180)
			(size 0 0)
			(layers "F.Cu" "F.Mask" "F.Paste")
			(net "GND")
		)
	)
	(footprint ""
		(layer "F.Cu")
		(at 298.527724 -395.333474)
		(property "Reference" "R596"
			(at 0 0 0)
			(layer "F.SilkS")
			(hide yes)
			(effects
				(font
					(size 1.27 1.27)
				)
			)
		)
		(property "Value" ""
			(at 0 0 0)
			(layer "F.Fab")
			(effects
				(font
					(size 1.27 1.27)
				)
			)
		)
		(duplicate_pad_numbers_are_jumpers no)
		(fp_line
			(start -0.32512 -0.175006)
			(end 0.32512 -0.175006)
			(stroke
				(width 0.1)
				(type default)
			)
			(layer "F.Fab")
		)
		(fp_line
			(start -0.32512 0.175006)
			(end -0.32512 -0.175006)
			(stroke
				(width 0.1)
				(type default)
			)
			(layer "F.Fab")
		)
		(fp_line
			(start 0.32512 -0.175006)
			(end 0.32512 0.175006)
			(stroke
				(width 0.1)
				(type default)
			)
			(layer "F.Fab")
		)
		(fp_line
			(start 0.32512 0.175006)
			(end -0.32512 0.175006)
			(stroke
				(width 0.1)
				(type default)
			)
			(layer "F.Fab")
		)
		(pad "1" smd rect
			(at -0.2667 0)
			(size 0.3048 0.381)
			(layers "F.Cu" "F.Mask" "F.Paste")
			(net "CLK_100M_RETIMER_CPU0_P0_R_DN")
		)
		(pad "2" smd rect
			(at 0.2667 0 180)
			(size 0.3048 0.381)
			(layers "F.Cu" "F.Mask" "F.Paste")
			(net "CLK_100M_RETIMER_CPU0_P0_DN")
		)
	)
	(footprint ""
		(layer "F.Cu")
		(at 107.517946 -52.86248 -90)
		(property "Reference" "R6311"
			(at 0 0 270)
			(layer "F.SilkS")
			(hide yes)
			(effects
				(font
					(size 1.27 1.27)
				)
			)
		)
		(property "Value" ""
			(at 0 0 270)
			(layer "F.Fab")
			(effects
				(font
					(size 1.27 1.27)
				)
			)
		)
		(duplicate_pad_numbers_are_jumpers no)
		(fp_line
			(start -0.7874 0.4064)
			(end -0.7874 -0.4064)
			(stroke
				(width 0.1524)
				(type default)
			)
			(layer "F.SilkS")
		)
		(fp_line
			(start 0.7874 0.4064)
			(end -0.7874 0.4064)
			(stroke
				(width 0.1524)
				(type default)
			)
			(layer "F.SilkS")
		)
		(fp_line
			(start -0.7874 -0.4064)
			(end 0.7874 -0.4064)
			(stroke
				(width 0.1524)
				(type default)
			)
			(layer "F.SilkS")
		)
		(fp_line
			(start 0.7874 -0.4064)
			(end 0.7874 0.4064)
			(stroke
				(width 0.1524)
				(type default)
			)
			(layer "F.SilkS")
		)
		(fp_line
			(start -0.67945 0.3048)
			(end -0.67945 -0.305054)
			(stroke
				(width 0.1)
				(type default)
			)
			(layer "F.Fab")
		)
		(fp_line
			(start -0.12065 0.3048)
			(end -0.67945 0.3048)
			(stroke
				(width 0.1)
				(type default)
			)
			(layer "F.Fab")
		)
		(fp_line
			(start 0.120396 0.3048)
			(end 0.120396 0.2794)
			(stroke
				(width 0.1)
				(type default)
			)
			(layer "F.Fab")
		)
		(fp_line
			(start 0.67945 0.3048)
			(end 0.120396 0.3048)
			(stroke
				(width 0.1)
				(type default)
			)
			(layer "F.Fab")
		)
		(fp_line
			(start -0.12065 0.2794)
			(end -0.12065 0.3048)
			(stroke
				(width 0.1)
				(type default)
			)
			(layer "F.Fab")
		)
		(fp_line
			(start 0.120396 0.2794)
			(end -0.12065 0.2794)
			(stroke
				(width 0.1)
				(type default)
			)
			(layer "F.Fab")
		)
		(fp_line
			(start -0.12065 -0.2794)
			(end 0.12065 -0.2794)
			(stroke
				(width 0.1)
				(type default)
			)
			(layer "F.Fab")
		)
		(fp_line
			(start 0.12065 -0.2794)
			(end 0.12065 -0.3048)
			(stroke
				(width 0.1)
				(type default)
			)
			(layer "F.Fab")
		)
		(fp_line
			(start 0.12065 -0.3048)
			(end 0.67945 -0.3048)
			(stroke
				(width 0.1)
				(type default)
			)
			(layer "F.Fab")
		)
		(fp_line
			(start 0.67945 -0.3048)
			(end 0.67945 0.3048)
			(stroke
				(width 0.1)
				(type default)
			)
			(layer "F.Fab")
		)
		(fp_line
			(start -0.67945 -0.305054)
			(end -0.12065 -0.305054)
			(stroke
				(width 0.1)
				(type default)
			)
			(layer "F.Fab")
		)
		(fp_line
			(start -0.12065 -0.305054)
			(end -0.12065 -0.2794)
			(stroke
				(width 0.1)
				(type default)
			)
			(layer "F.Fab")
		)
		(pad "1" smd circle
			(at -0.40005 0 270)
			(size 0 0)
			(layers "F.Cu" "F.Mask" "F.Paste")
			(net "SMB_USB_CPU0_HUB1_SDA")
		)
		(pad "2" smd circle
			(at 0.40005 0 270)
			(size 0 0)
			(layers "F.Cu" "F.Mask" "F.Paste")
			(net "USB_HUB2_TI_OVERCUR1_MRP_PROG_FUNC4")
		)
	)
	(footprint ""
		(layer "F.Cu")
		(at 46.70806 -99.60864 90)
		(property "Reference" "R896"
			(at 0 0 90)
			(layer "F.SilkS")
			(hide yes)
			(effects
				(font
					(size 1.27 1.27)
				)
			)
		)
		(property "Value" ""
			(at 0 0 90)
			(layer "F.Fab")
			(effects
				(font
					(size 1.27 1.27)
				)
			)
		)
		(duplicate_pad_numbers_are_jumpers no)
		(fp_line
			(start 0.7874 -0.4064)
			(end 0.7874 0.4064)
			(stroke
				(width 0.1524)
				(type default)
			)
			(layer "F.SilkS")
		)
		(fp_line
			(start -0.7874 -0.4064)
			(end 0.7874 -0.4064)
			(stroke
				(width 0.1524)
				(type default)
			)
			(layer "F.SilkS")
		)
		(fp_line
			(start 0.7874 0.4064)
			(end -0.7874 0.4064)
			(stroke
				(width 0.1524)
				(type default)
			)
			(layer "F.SilkS")
		)
		(fp_line
			(start -0.7874 0.4064)
			(end -0.7874 -0.4064)
			(stroke
				(width 0.1524)
				(type default)
			)
			(layer "F.SilkS")
		)
		(fp_line
			(start -0.12065 -0.305054)
			(end -0.12065 -0.2794)
			(stroke
				(width 0.1)
				(type default)
			)
			(layer "F.Fab")
		)
		(fp_line
			(start -0.67945 -0.305054)
			(end -0.12065 -0.305054)
			(stroke
				(width 0.1)
				(type default)
			)
			(layer "F.Fab")
		)
		(fp_line
			(start 0.67945 -0.3048)
			(end 0.67945 0.3048)
			(stroke
				(width 0.1)
				(type default)
			)
			(layer "F.Fab")
		)
		(fp_line
			(start 0.12065 -0.3048)
			(end 0.67945 -0.3048)
			(stroke
				(width 0.1)
				(type default)
			)
			(layer "F.Fab")
		)
		(fp_line
			(start 0.12065 -0.2794)
			(end 0.12065 -0.3048)
			(stroke
				(width 0.1)
				(type default)
			)
			(layer "F.Fab")
		)
		(fp_line
			(start -0.12065 -0.2794)
			(end 0.12065 -0.2794)
			(stroke
				(width 0.1)
				(type default)
			)
			(layer "F.Fab")
		)
		(fp_line
			(start 0.120396 0.2794)
			(end -0.12065 0.2794)
			(stroke
				(width 0.1)
				(type default)
			)
			(layer "F.Fab")
		)
		(fp_line
			(start -0.12065 0.2794)
			(end -0.12065 0.3048)
			(stroke
				(width 0.1)
				(type default)
			)
			(layer "F.Fab")
		)
		(fp_line
			(start 0.67945 0.3048)
			(end 0.120396 0.3048)
			(stroke
				(width 0.1)
				(type default)
			)
			(layer "F.Fab")
		)
		(fp_line
			(start 0.120396 0.3048)
			(end 0.120396 0.2794)
			(stroke
				(width 0.1)
				(type default)
			)
			(layer "F.Fab")
		)
		(fp_line
			(start -0.12065 0.3048)
			(end -0.67945 0.3048)
			(stroke
				(width 0.1)
				(type default)
			)
			(layer "F.Fab")
		)
		(fp_line
			(start -0.67945 0.3048)
			(end -0.67945 -0.305054)
			(stroke
				(width 0.1)
				(type default)
			)
			(layer "F.Fab")
		)
		(pad "1" smd circle
			(at -0.40005 0 90)
			(size 0 0)
			(layers "F.Cu" "F.Mask" "F.Paste")
			(net "P12V_AUX")
		)
		(pad "2" smd circle
			(at 0.40005 0 90)
			(size 0 0)
			(layers "F.Cu" "F.Mask" "F.Paste")
			(net "P3V3_AUX_DSC_VOL")
		)
	)
	(footprint ""
		(layer "F.Cu")
		(at 140.446252 -60.849764 180)
		(property "Reference" "R1744"
			(at 0 0 180)
			(layer "F.SilkS")
			(hide yes)
			(effects
				(font
					(size 1.27 1.27)
				)
			)
		)
		(property "Value" ""
			(at 0 0 180)
			(layer "F.Fab")
			(effects
				(font
					(size 1.27 1.27)
				)
			)
		)
		(duplicate_pad_numbers_are_jumpers no)
		(fp_line
			(start 0.7874 0.4064)
			(end -0.7874 0.4064)
			(stroke
				(width 0.1524)
				(type default)
			)
			(layer "F.SilkS")
		)
		(fp_line
			(start 0.7874 -0.4064)
			(end 0.7874 0.4064)
			(stroke
				(width 0.1524)
				(type default)
			)
			(layer "F.SilkS")
		)
		(fp_line
			(start -0.7874 0.4064)
			(end -0.7874 -0.4064)
			(stroke
				(width 0.1524)
				(type default)
			)
			(layer "F.SilkS")
		)
		(fp_line
			(start -0.7874 -0.4064)
			(end 0.7874 -0.4064)
			(stroke
				(width 0.1524)
				(type default)
			)
			(layer "F.SilkS")
		)
		(fp_line
			(start 0.67945 0.3048)
			(end 0.120396 0.3048)
			(stroke
				(width 0.1)
				(type default)
			)
			(layer "F.Fab")
		)
		(fp_line
			(start 0.67945 -0.3048)
			(end 0.67945 0.3048)
			(stroke
				(width 0.1)
				(type default)
			)
			(layer "F.Fab")
		)
		(fp_line
			(start 0.12065 -0.2794)
			(end 0.12065 -0.3048)
			(stroke
				(width 0.1)
				(type default)
			)
			(layer "F.Fab")
		)
		(fp_line
			(start 0.12065 -0.3048)
			(end 0.67945 -0.3048)
			(stroke
				(width 0.1)
				(type default)
			)
			(layer "F.Fab")
		)
		(fp_line
			(start 0.120396 0.3048)
			(end 0.120396 0.2794)
			(stroke
				(width 0.1)
				(type default)
			)
			(layer "F.Fab")
		)
		(fp_line
			(start 0.120396 0.2794)
			(end -0.12065 0.2794)
			(stroke
				(width 0.1)
				(type default)
			)
			(layer "F.Fab")
		)
		(fp_line
			(start -0.12065 0.3048)
			(end -0.67945 0.3048)
			(stroke
				(width 0.1)
				(type default)
			)
			(layer "F.Fab")
		)
		(fp_line
			(start -0.12065 0.2794)
			(end -0.12065 0.3048)
			(stroke
				(width 0.1)
				(type default)
			)
			(layer "F.Fab")
		)
		(fp_line
			(start -0.12065 -0.2794)
			(end 0.12065 -0.2794)
			(stroke
				(width 0.1)
				(type default)
			)
			(layer "F.Fab")
		)
		(fp_line
			(start -0.12065 -0.305054)
			(end -0.12065 -0.2794)
			(stroke
				(width 0.1)
				(type default)
			)
			(layer "F.Fab")
		)
		(fp_line
			(start -0.67945 0.3048)
			(end -0.67945 -0.305054)
			(stroke
				(width 0.1)
				(type default)
			)
			(layer "F.Fab")
		)
		(fp_line
			(start -0.67945 -0.305054)
			(end -0.12065 -0.305054)
			(stroke
				(width 0.1)
				(type default)
			)
			(layer "F.Fab")
		)
		(pad "1" smd circle
			(at -0.40005 0 180)
			(size 0 0)
			(layers "F.Cu" "F.Mask" "F.Paste")
			(net "P3V3_AUX")
		)
		(pad "2" smd circle
			(at 0.40005 0 180)
			(size 0 0)
			(layers "F.Cu" "F.Mask" "F.Paste")
			(net "JTAG_SCM_MUX_TDI")
		)
	)
	(footprint ""
		(layer "F.Cu")
		(at 426.332396 -392.9888 180)
		(property "Reference" "L18"
			(at 0 0 180)
			(layer "F.SilkS")
			(hide yes)
			(effects
				(font
					(size 1.27 1.27)
				)
			)
		)
		(property "Value" ""
			(at 0 0 180)
			(layer "F.Fab")
			(effects
				(font
					(size 1.27 1.27)
				)
			)
		)
		(duplicate_pad_numbers_are_jumpers no)
		(fp_line
			(start 1.63576 0.8128)
			(end -1.63576 0.8128)
			(stroke
				(width 0.1524)
				(type default)
			)
			(layer "F.SilkS")
		)
		(fp_line
			(start 1.63576 -0.8128)
			(end 1.63576 0.8128)
			(stroke
				(width 0.1524)
				(type default)
			)
			(layer "F.SilkS")
		)
		(fp_line
			(start -1.63576 -0.8128)
			(end 1.63576 -0.8128)
			(stroke
				(width 0.1524)
				(type default)
			)
			(layer "F.SilkS")
		)
		(fp_line
			(start -1.63576 -0.8128)
			(end -1.63576 0.8128)
			(stroke
				(width 0.1524)
				(type default)
			)
			(layer "F.SilkS")
		)
		(fp_line
			(start 1.560576 0.7366)
			(end 1.560576 -0.738632)
			(stroke
				(width 0.1)
				(type default)
			)
			(layer "F.Fab")
		)
		(fp_line
			(start 1.560576 -0.738632)
			(end -1.56083 -0.738632)
			(stroke
				(width 0.1)
				(type default)
			)
			(layer "F.Fab")
		)
		(fp_line
			(start 1.524 0.7366)
			(end 1.560576 0.7366)
			(stroke
				(width 0.1)
				(type default)
			)
			(layer "F.Fab")
		)
		(fp_line
			(start -1.524 0.7366)
			(end 1.524 0.7366)
			(stroke
				(width 0.1)
				(type default)
			)
			(layer "F.Fab")
		)
		(fp_line
			(start -1.56083 0.7366)
			(end -1.524 0.7366)
			(stroke
				(width 0.1)
				(type default)
			)
			(layer "F.Fab")
		)
		(fp_line
			(start -1.56083 -0.738632)
			(end -1.56083 0.7366)
			(stroke
				(width 0.1)
				(type default)
			)
			(layer "F.Fab")
		)
		(pad "1" smd rect
			(at -0.94996 0)
			(size 1.1176 1.3716)
			(layers "F.Cu" "F.Mask" "F.Paste")
			(net "P1V8_CPU0_RT_1D")
		)
		(pad "2" smd rect
			(at 0.94996 0)
			(size 1.1176 1.3716)
			(layers "F.Cu" "F.Mask" "F.Paste")
			(net "P1V8_CPU0_RT2_1A")
		)
	)
	(footprint ""
		(layer "F.Cu")
		(at 200.939908 -105.497376)
		(property "Reference" "R227"
			(at 0 0 0)
			(layer "F.SilkS")
			(hide yes)
			(effects
				(font
					(size 1.27 1.27)
				)
			)
		)
		(property "Value" ""
			(at 0 0 0)
			(layer "F.Fab")
			(effects
				(font
					(size 1.27 1.27)
				)
			)
		)
		(duplicate_pad_numbers_are_jumpers no)
		(fp_line
			(start -0.7874 -0.4064)
			(end 0.7874 -0.4064)
			(stroke
				(width 0.1524)
				(type default)
			)
			(layer "F.SilkS")
		)
		(fp_line
			(start -0.7874 0.4064)
			(end -0.7874 -0.4064)
			(stroke
				(width 0.1524)
				(type default)
			)
			(layer "F.SilkS")
		)
		(fp_line
			(start 0.7874 -0.4064)
			(end 0.7874 0.4064)
			(stroke
				(width 0.1524)
				(type default)
			)
			(layer "F.SilkS")
		)
		(fp_line
			(start 0.7874 0.4064)
			(end -0.7874 0.4064)
			(stroke
				(width 0.1524)
				(type default)
			)
			(layer "F.SilkS")
		)
		(fp_line
			(start -0.67945 -0.305054)
			(end -0.12065 -0.305054)
			(stroke
				(width 0.1)
				(type default)
			)
			(layer "F.Fab")
		)
		(fp_line
			(start -0.67945 0.3048)
			(end -0.67945 -0.305054)
			(stroke
				(width 0.1)
				(type default)
			)
			(layer "F.Fab")
		)
		(fp_line
			(start -0.12065 -0.305054)
			(end -0.12065 -0.2794)
			(stroke
				(width 0.1)
				(type default)
			)
			(layer "F.Fab")
		)
		(fp_line
			(start -0.12065 -0.2794)
			(end 0.12065 -0.2794)
			(stroke
				(width 0.1)
				(type default)
			)
			(layer "F.Fab")
		)
		(fp_line
			(start -0.12065 0.2794)
			(end -0.12065 0.3048)
			(stroke
				(width 0.1)
				(type default)
			)
			(layer "F.Fab")
		)
		(fp_line
			(start -0.12065 0.3048)
			(end -0.67945 0.3048)
			(stroke
				(width 0.1)
				(type default)
			)
			(layer "F.Fab")
		)
		(fp_line
			(start 0.120396 0.2794)
			(end -0.12065 0.2794)
			(stroke
				(width 0.1)
				(type default)
			)
			(layer "F.Fab")
		)
		(fp_line
			(start 0.120396 0.3048)
			(end 0.120396 0.2794)
			(stroke
				(width 0.1)
				(type default)
			)
			(layer "F.Fab")
		)
		(fp_line
			(start 0.12065 -0.3048)
			(end 0.67945 -0.3048)
			(stroke
				(width 0.1)
				(type default)
			)
			(layer "F.Fab")
		)
		(fp_line
			(start 0.12065 -0.2794)
			(end 0.12065 -0.3048)
			(stroke
				(width 0.1)
				(type default)
			)
			(layer "F.Fab")
		)
		(fp_line
			(start 0.67945 -0.3048)
			(end 0.67945 0.3048)
			(stroke
				(width 0.1)
				(type default)
			)
			(layer "F.Fab")
		)
		(fp_line
			(start 0.67945 0.3048)
			(end 0.120396 0.3048)
			(stroke
				(width 0.1)
				(type default)
			)
			(layer "F.Fab")
		)
		(pad "1" smd circle
			(at -0.40005 0)
			(size 0 0)
			(layers "F.Cu" "F.Mask" "F.Paste")
			(net "FM_PVDD11_S3_P0_EN")
		)
		(pad "2" smd circle
			(at 0.40005 0)
			(size 0 0)
			(layers "F.Cu" "F.Mask" "F.Paste")
			(net "PVDD11_S3_P0_EN")
		)
	)
	(footprint ""
		(layer "F.Cu")
		(at 353.185222 -425.295314 180)
		(property "Reference" "R4561"
			(at 0 0 180)
			(layer "F.SilkS")
			(hide yes)
			(effects
				(font
					(size 1.27 1.27)
				)
			)
		)
		(property "Value" ""
			(at 0 0 180)
			(layer "F.Fab")
			(effects
				(font
					(size 1.27 1.27)
				)
			)
		)
		(duplicate_pad_numbers_are_jumpers no)
		(fp_line
			(start 0.7874 0.4064)
			(end -0.7874 0.4064)
			(stroke
				(width 0.1524)
				(type default)
			)
			(layer "F.SilkS")
		)
		(fp_line
			(start 0.7874 -0.4064)
			(end 0.7874 0.4064)
			(stroke
				(width 0.1524)
				(type default)
			)
			(layer "F.SilkS")
		)
		(fp_line
			(start -0.7874 0.4064)
			(end -0.7874 -0.4064)
			(stroke
				(width 0.1524)
				(type default)
			)
			(layer "F.SilkS")
		)
		(fp_line
			(start -0.7874 -0.4064)
			(end 0.7874 -0.4064)
			(stroke
				(width 0.1524)
				(type default)
			)
			(layer "F.SilkS")
		)
		(fp_line
			(start 0.67945 0.3048)
			(end 0.120396 0.3048)
			(stroke
				(width 0.1)
				(type default)
			)
			(layer "F.Fab")
		)
		(fp_line
			(start 0.67945 -0.3048)
			(end 0.67945 0.3048)
			(stroke
				(width 0.1)
				(type default)
			)
			(layer "F.Fab")
		)
		(fp_line
			(start 0.12065 -0.2794)
			(end 0.12065 -0.3048)
			(stroke
				(width 0.1)
				(type default)
			)
			(layer "F.Fab")
		)
		(fp_line
			(start 0.12065 -0.3048)
			(end 0.67945 -0.3048)
			(stroke
				(width 0.1)
				(type default)
			)
			(layer "F.Fab")
		)
		(fp_line
			(start 0.120396 0.3048)
			(end 0.120396 0.2794)
			(stroke
				(width 0.1)
				(type default)
			)
			(layer "F.Fab")
		)
		(fp_line
			(start 0.120396 0.2794)
			(end -0.12065 0.2794)
			(stroke
				(width 0.1)
				(type default)
			)
			(layer "F.Fab")
		)
		(fp_line
			(start -0.12065 0.3048)
			(end -0.67945 0.3048)
			(stroke
				(width 0.1)
				(type default)
			)
			(layer "F.Fab")
		)
		(fp_line
			(start -0.12065 0.2794)
			(end -0.12065 0.3048)
			(stroke
				(width 0.1)
				(type default)
			)
			(layer "F.Fab")
		)
		(fp_line
			(start -0.12065 -0.2794)
			(end 0.12065 -0.2794)
			(stroke
				(width 0.1)
				(type default)
			)
			(layer "F.Fab")
		)
		(fp_line
			(start -0.12065 -0.305054)
			(end -0.12065 -0.2794)
			(stroke
				(width 0.1)
				(type default)
			)
			(layer "F.Fab")
		)
		(fp_line
			(start -0.67945 0.3048)
			(end -0.67945 -0.305054)
			(stroke
				(width 0.1)
				(type default)
			)
			(layer "F.Fab")
		)
		(fp_line
			(start -0.67945 -0.305054)
			(end -0.12065 -0.305054)
			(stroke
				(width 0.1)
				(type default)
			)
			(layer "F.Fab")
		)
		(pad "1" smd circle
			(at -0.40005 0 180)
			(size 0 0)
			(layers "F.Cu" "F.Mask" "F.Paste")
			(net "P3V3_AUX")
		)
		(pad "2" smd circle
			(at 0.40005 0 180)
			(size 0 0)
			(layers "F.Cu" "F.Mask" "F.Paste")
			(net "SWB_HSC_PWRGD_ISO")
		)
	)
	(footprint ""
		(layer "F.Cu")
		(at 47.117 -436.372)
		(property "Reference" "U196"
			(at -3.295396 -4.107942 0)
			(unlocked yes)
			(layer "F.SilkS")
			(effects
				(font
					(size 0.7874 0.5842)
					(thickness 0.1524)
				)
				(justify left)
			)
		)
		(property "Value" ""
			(at 0 0 0)
			(layer "F.Fab")
			(effects
				(font
					(size 1.27 1.27)
				)
			)
		)
		(duplicate_pad_numbers_are_jumpers no)
		(fp_line
			(start -1.3462 -1.100074)
			(end -0.670052 -1.100074)
			(stroke
				(width 0.1524)
				(type default)
			)
			(layer "F.SilkS")
		)
		(fp_line
			(start -1.3462 1.100074)
			(end -1.3462 -1.100074)
			(stroke
				(width 0.1524)
				(type default)
			)
			(layer "F.SilkS")
		)
		(fp_line
			(start -0.670052 -1.100074)
			(end 0 -0.381)
			(stroke
				(width 0.1524)
				(type default)
			)
			(layer "F.SilkS")
		)
		(fp_line
			(start 0 -0.381)
			(end 0.670052 -1.100074)
			(stroke
				(width 0.1524)
				(type default)
			)
			(layer "F.SilkS")
		)
		(fp_line
			(start 0.670052 -1.100074)
			(end 1.3462 -1.100074)
			(stroke
				(width 0.1524)
				(type default)
			)
			(layer "F.SilkS")
		)
		(fp_line
			(start 1.3462 -1.100074)
			(end 1.3462 1.100074)
			(stroke
				(width 0.1524)
				(type default)
			)
			(layer "F.SilkS")
		)
		(fp_line
			(start 1.3462 1.100074)
			(end -1.3462 1.100074)
			(stroke
				(width 0.1524)
				(type default)
			)
			(layer "F.SilkS")
		)
		(fp_poly
			(pts
				(xy -2.29108 -1.452372) (xy -1.752346 -1.991106) (xy -1.482852 -1.182878)
			)
			(stroke
				(width 0)
				(type default)
			)
			(fill yes)
			(layer "F.SilkS")
		)
		(fp_line
			(start -1.100074 -0.8001)
			(end -0.670052 -0.8001)
			(stroke
				(width 0.1)
				(type default)
			)
			(layer "F.Fab")
		)
		(fp_line
			(start -1.100074 0.8001)
			(end -1.100074 -0.8001)
			(stroke
				(width 0.1)
				(type default)
			)
			(layer "F.Fab")
		)
		(fp_line
			(start -0.670052 -1.100074)
			(end 0.670052 -1.100074)
			(stroke
				(width 0.1)
				(type default)
			)
			(layer "F.Fab")
		)
		(fp_line
			(start -0.670052 -0.8001)
			(end -0.670052 -1.100074)
			(stroke
				(width 0.1)
				(type default)
			)
			(layer "F.Fab")
		)
		(fp_line
			(start -0.670052 0.8001)
			(end -1.100074 0.8001)
			(stroke
				(width 0.1)
				(type default)
			)
			(layer "F.Fab")
		)
		(fp_line
			(start -0.670052 0.8001)
			(end -0.670052 -0.8001)
			(stroke
				(width 0.1)
				(type default)
			)
			(layer "F.Fab")
		)
		(fp_line
			(start -0.670052 1.100074)
			(end -0.670052 0.8001)
			(stroke
				(width 0.1)
				(type default)
			)
			(layer "F.Fab")
		)
		(fp_line
			(start 0.670052 -1.100074)
			(end 0.670052 -0.8001)
			(stroke
				(width 0.1)
				(type default)
			)
			(layer "F.Fab")
		)
		(fp_line
			(start 0.670052 -0.8001)
			(end 0.670052 0.8001)
			(stroke
				(width 0.1)
				(type default)
			)
			(layer "F.Fab")
		)
		(fp_line
			(start 0.670052 -0.8001)
			(end 1.100074 -0.8001)
			(stroke
				(width 0.1)
				(type default)
			)
			(layer "F.Fab")
		)
		(fp_line
			(start 0.670052 0.8001)
			(end 0.670052 1.100074)
			(stroke
				(width 0.1)
				(type default)
			)
			(layer "F.Fab")
		)
		(fp_line
			(start 0.670052 1.100074)
			(end -0.670052 1.100074)
			(stroke
				(width 0.1)
				(type default)
			)
			(layer "F.Fab")
		)
		(fp_line
			(start 1.100074 -0.8001)
			(end 1.100074 0.8001)
			(stroke
				(width 0.1)
				(type default)
			)
			(layer "F.Fab")
		)
		(fp_line
			(start 1.100074 0.8001)
			(end 0.670052 0.8001)
			(stroke
				(width 0.1)
				(type default)
			)
			(layer "F.Fab")
		)
		(fp_poly
			(pts
				(xy -1.524 -0.649986) (xy -2.286 -1.030986) (xy -2.286 -0.268986)
			)
			(stroke
				(width 0)
				(type default)
			)
			(fill yes)
			(layer "F.Fab")
		)
		(pad "1" smd rect
			(at -0.94996 -0.649986 270)
			(size 0.4064 0.508)
			(layers "F.Cu" "F.Mask" "F.Paste")
			(net "FM_GPU_PWR_EN_R")
		)
		(pad "2" smd rect
			(at -0.94996 0 270)
			(size 0.4064 0.508)
			(layers "F.Cu" "F.Mask" "F.Paste")
			(net "GND")
		)
		(pad "3" smd rect
			(at -0.94996 0.649986 270)
			(size 0.4064 0.508)
			(layers "F.Cu" "F.Mask" "F.Paste")
			(net "GPU_FPGA_RST_R_N")
		)
		(pad "4" smd rect
			(at 0.94996 0.649986 270)
			(size 0.4064 0.508)
			(layers "F.Cu" "F.Mask" "F.Paste")
			(net "GPU_FPGA_RST_R1_BUF_N")
		)
		(pad "5" smd rect
			(at 0.94996 0 270)
			(size 0.4064 0.508)
			(layers "F.Cu" "F.Mask" "F.Paste")
			(net "P3V3_AUX")
		)
		(pad "6" smd rect
			(at 0.94996 -0.649986 270)
			(size 0.4064 0.508)
			(layers "F.Cu" "F.Mask" "F.Paste")
			(net "FM_GPU_PWR_EN_R1")
		)
	)
	(footprint ""
		(layer "F.Cu")
		(at 316.738 -356.87 90)
		(property "Reference" "PR69"
			(at 0 0 90)
			(layer "F.SilkS")
			(hide yes)
			(effects
				(font
					(size 1.27 1.27)
				)
			)
		)
		(property "Value" ""
			(at 0 0 90)
			(layer "F.Fab")
			(effects
				(font
					(size 1.27 1.27)
				)
			)
		)
		(duplicate_pad_numbers_are_jumpers no)
		(fp_line
			(start 0.7874 -0.4064)
			(end 0.7874 0.4064)
			(stroke
				(width 0.1524)
				(type default)
			)
			(layer "F.SilkS")
		)
		(fp_line
			(start -0.7874 -0.4064)
			(end 0.7874 -0.4064)
			(stroke
				(width 0.1524)
				(type default)
			)
			(layer "F.SilkS")
		)
		(fp_line
			(start 0.7874 0.4064)
			(end -0.7874 0.4064)
			(stroke
				(width 0.1524)
				(type default)
			)
			(layer "F.SilkS")
		)
		(fp_line
			(start -0.7874 0.4064)
			(end -0.7874 -0.4064)
			(stroke
				(width 0.1524)
				(type default)
			)
			(layer "F.SilkS")
		)
		(fp_line
			(start -0.12065 -0.305054)
			(end -0.12065 -0.2794)
			(stroke
				(width 0.1)
				(type default)
			)
			(layer "F.Fab")
		)
		(fp_line
			(start -0.67945 -0.305054)
			(end -0.12065 -0.305054)
			(stroke
				(width 0.1)
				(type default)
			)
			(layer "F.Fab")
		)
		(fp_line
			(start 0.67945 -0.3048)
			(end 0.67945 0.3048)
			(stroke
				(width 0.1)
				(type default)
			)
			(layer "F.Fab")
		)
		(fp_line
			(start 0.12065 -0.3048)
			(end 0.67945 -0.3048)
			(stroke
				(width 0.1)
				(type default)
			)
			(layer "F.Fab")
		)
		(fp_line
			(start 0.12065 -0.2794)
			(end 0.12065 -0.3048)
			(stroke
				(width 0.1)
				(type default)
			)
			(layer "F.Fab")
		)
		(fp_line
			(start -0.12065 -0.2794)
			(end 0.12065 -0.2794)
			(stroke
				(width 0.1)
				(type default)
			)
			(layer "F.Fab")
		)
		(fp_line
			(start 0.120396 0.2794)
			(end -0.12065 0.2794)
			(stroke
				(width 0.1)
				(type default)
			)
			(layer "F.Fab")
		)
		(fp_line
			(start -0.12065 0.2794)
			(end -0.12065 0.3048)
			(stroke
				(width 0.1)
				(type default)
			)
			(layer "F.Fab")
		)
		(fp_line
			(start 0.67945 0.3048)
			(end 0.120396 0.3048)
			(stroke
				(width 0.1)
				(type default)
			)
			(layer "F.Fab")
		)
		(fp_line
			(start 0.120396 0.3048)
			(end 0.120396 0.2794)
			(stroke
				(width 0.1)
				(type default)
			)
			(layer "F.Fab")
		)
		(fp_line
			(start -0.12065 0.3048)
			(end -0.67945 0.3048)
			(stroke
				(width 0.1)
				(type default)
			)
			(layer "F.Fab")
		)
		(fp_line
			(start -0.67945 0.3048)
			(end -0.67945 -0.305054)
			(stroke
				(width 0.1)
				(type default)
			)
			(layer "F.Fab")
		)
		(pad "1" smd circle
			(at -0.40005 0 90)
			(size 0 0)
			(layers "F.Cu" "F.Mask" "F.Paste")
			(net "VSENSE_PVDDIO_P0_DP")
		)
		(pad "2" smd circle
			(at 0.40005 0 90)
			(size 0 0)
			(layers "F.Cu" "F.Mask" "F.Paste")
			(net "VSENSE_PVDDIO_P0_VSEN1")
		)
	)
	(footprint ""
		(layer "F.Cu")
		(at 99.015296 -412.931102 90)
		(property "Reference" "R4178"
			(at 0 0 90)
			(layer "F.SilkS")
			(hide yes)
			(effects
				(font
					(size 1.27 1.27)
				)
			)
		)
		(property "Value" ""
			(at 0 0 90)
			(layer "F.Fab")
			(effects
				(font
					(size 1.27 1.27)
				)
			)
		)
		(duplicate_pad_numbers_are_jumpers no)
		(fp_line
			(start 0.7874 -0.4064)
			(end 0.7874 0.4064)
			(stroke
				(width 0.1524)
				(type default)
			)
			(layer "F.SilkS")
		)
		(fp_line
			(start -0.7874 -0.4064)
			(end 0.7874 -0.4064)
			(stroke
				(width 0.1524)
				(type default)
			)
			(layer "F.SilkS")
		)
		(fp_line
			(start 0.7874 0.4064)
			(end -0.7874 0.4064)
			(stroke
				(width 0.1524)
				(type default)
			)
			(layer "F.SilkS")
		)
		(fp_line
			(start -0.7874 0.4064)
			(end -0.7874 -0.4064)
			(stroke
				(width 0.1524)
				(type default)
			)
			(layer "F.SilkS")
		)
		(fp_line
			(start -0.12065 -0.305054)
			(end -0.12065 -0.2794)
			(stroke
				(width 0.1)
				(type default)
			)
			(layer "F.Fab")
		)
		(fp_line
			(start -0.67945 -0.305054)
			(end -0.12065 -0.305054)
			(stroke
				(width 0.1)
				(type default)
			)
			(layer "F.Fab")
		)
		(fp_line
			(start 0.67945 -0.3048)
			(end 0.67945 0.3048)
			(stroke
				(width 0.1)
				(type default)
			)
			(layer "F.Fab")
		)
		(fp_line
			(start 0.12065 -0.3048)
			(end 0.67945 -0.3048)
			(stroke
				(width 0.1)
				(type default)
			)
			(layer "F.Fab")
		)
		(fp_line
			(start 0.12065 -0.2794)
			(end 0.12065 -0.3048)
			(stroke
				(width 0.1)
				(type default)
			)
			(layer "F.Fab")
		)
		(fp_line
			(start -0.12065 -0.2794)
			(end 0.12065 -0.2794)
			(stroke
				(width 0.1)
				(type default)
			)
			(layer "F.Fab")
		)
		(fp_line
			(start 0.120396 0.2794)
			(end -0.12065 0.2794)
			(stroke
				(width 0.1)
				(type default)
			)
			(layer "F.Fab")
		)
		(fp_line
			(start -0.12065 0.2794)
			(end -0.12065 0.3048)
			(stroke
				(width 0.1)
				(type default)
			)
			(layer "F.Fab")
		)
		(fp_line
			(start 0.67945 0.3048)
			(end 0.120396 0.3048)
			(stroke
				(width 0.1)
				(type default)
			)
			(layer "F.Fab")
		)
		(fp_line
			(start 0.120396 0.3048)
			(end 0.120396 0.2794)
			(stroke
				(width 0.1)
				(type default)
			)
			(layer "F.Fab")
		)
		(fp_line
			(start -0.12065 0.3048)
			(end -0.67945 0.3048)
			(stroke
				(width 0.1)
				(type default)
			)
			(layer "F.Fab")
		)
		(fp_line
			(start -0.67945 0.3048)
			(end -0.67945 -0.305054)
			(stroke
				(width 0.1)
				(type default)
			)
			(layer "F.Fab")
		)
		(pad "1" smd circle
			(at -0.40005 0 90)
			(size 0 0)
			(layers "F.Cu" "F.Mask" "F.Paste")
			(net "SMB_LM75_2_3V3AUX_SCL")
		)
		(pad "2" smd circle
			(at 0.40005 0 90)
			(size 0 0)
			(layers "F.Cu" "F.Mask" "F.Paste")
			(net "SMB_LM75_2_3V3AUX_SCL_R1")
		)
	)
	(footprint ""
		(layer "F.Cu")
		(at 276.481794 -94.789498 180)
		(property "Reference" "C1517"
			(at 0 0 180)
			(layer "F.SilkS")
			(hide yes)
			(effects
				(font
					(size 1.27 1.27)
				)
			)
		)
		(property "Value" ""
			(at 0 0 180)
			(layer "F.Fab")
			(effects
				(font
					(size 1.27 1.27)
				)
			)
		)
		(duplicate_pad_numbers_are_jumpers no)
		(fp_line
			(start 0.7874 0.4064)
			(end -0.7874 0.4064)
			(stroke
				(width 0.1524)
				(type default)
			)
			(layer "F.SilkS")
		)
		(fp_line
			(start 0.7874 -0.4064)
			(end 0.7874 0.4064)
			(stroke
				(width 0.1524)
				(type default)
			)
			(layer "F.SilkS")
		)
		(fp_line
			(start -0.7874 0.4064)
			(end -0.7874 -0.4064)
			(stroke
				(width 0.1524)
				(type default)
			)
			(layer "F.SilkS")
		)
		(fp_line
			(start -0.7874 -0.4064)
			(end 0.7874 -0.4064)
			(stroke
				(width 0.1524)
				(type default)
			)
			(layer "F.SilkS")
		)
		(fp_line
			(start 0.67945 0.3048)
			(end 0.120396 0.3048)
			(stroke
				(width 0.1)
				(type default)
			)
			(layer "F.Fab")
		)
		(fp_line
			(start 0.67945 -0.3048)
			(end 0.67945 0.3048)
			(stroke
				(width 0.1)
				(type default)
			)
			(layer "F.Fab")
		)
		(fp_line
			(start 0.12065 -0.2794)
			(end 0.12065 -0.3048)
			(stroke
				(width 0.1)
				(type default)
			)
			(layer "F.Fab")
		)
		(fp_line
			(start 0.12065 -0.3048)
			(end 0.67945 -0.3048)
			(stroke
				(width 0.1)
				(type default)
			)
			(layer "F.Fab")
		)
		(fp_line
			(start 0.120396 0.3048)
			(end 0.120396 0.2794)
			(stroke
				(width 0.1)
				(type default)
			)
			(layer "F.Fab")
		)
		(fp_line
			(start 0.120396 0.2794)
			(end -0.12065 0.2794)
			(stroke
				(width 0.1)
				(type default)
			)
			(layer "F.Fab")
		)
		(fp_line
			(start -0.12065 0.3048)
			(end -0.67945 0.3048)
			(stroke
				(width 0.1)
				(type default)
			)
			(layer "F.Fab")
		)
		(fp_line
			(start -0.12065 0.2794)
			(end -0.12065 0.3048)
			(stroke
				(width 0.1)
				(type default)
			)
			(layer "F.Fab")
		)
		(fp_line
			(start -0.12065 -0.2794)
			(end 0.12065 -0.2794)
			(stroke
				(width 0.1)
				(type default)
			)
			(layer "F.Fab")
		)
		(fp_line
			(start -0.12065 -0.305054)
			(end -0.12065 -0.2794)
			(stroke
				(width 0.1)
				(type default)
			)
			(layer "F.Fab")
		)
		(fp_line
			(start -0.67945 0.3048)
			(end -0.67945 -0.305054)
			(stroke
				(width 0.1)
				(type default)
			)
			(layer "F.Fab")
		)
		(fp_line
			(start -0.67945 -0.305054)
			(end -0.12065 -0.305054)
			(stroke
				(width 0.1)
				(type default)
			)
			(layer "F.Fab")
		)
		(pad "1" smd circle
			(at -0.40005 0 180)
			(size 0 0)
			(layers "F.Cu" "F.Mask" "F.Paste")
			(net "PVDD18_S5_P1")
		)
		(pad "2" smd circle
			(at 0.40005 0 180)
			(size 0 0)
			(layers "F.Cu" "F.Mask" "F.Paste")
			(net "GND")
		)
	)
	(footprint ""
		(layer "F.Cu")
		(at 212.471508 0.002794)
		(property "Reference" "J75"
			(at -4.427728 1.119632 90)
			(unlocked yes)
			(layer "F.SilkS")
			(effects
				(font
					(size 0.7874 0.5842)
					(thickness 0.1524)
				)
				(justify left)
			)
		)
		(property "Value" ""
			(at 0 0 0)
			(layer "F.Fab")
			(effects
				(font
					(size 1.27 1.27)
				)
			)
		)
		(duplicate_pad_numbers_are_jumpers no)
		(fp_line
			(start -1.2192 -2.06756)
			(end 1.2192 -2.06756)
			(stroke
				(width 0.1524)
				(type default)
			)
			(layer "F.SilkS")
		)
		(fp_line
			(start -1.2192 2.06756)
			(end -1.2192 -2.06756)
			(stroke
				(width 0.1524)
				(type default)
			)
			(layer "F.SilkS")
		)
		(fp_line
			(start 1.2192 -2.06756)
			(end 1.2192 2.06756)
			(stroke
				(width 0.1524)
				(type default)
			)
			(layer "F.SilkS")
		)
		(fp_line
			(start 1.2192 2.06756)
			(end -1.2192 2.06756)
			(stroke
				(width 0.1524)
				(type default)
			)
			(layer "F.SilkS")
		)
		(pad "" np_thru_hole circle
			(at -2.8829 -1.27 270)
			(size 1.0414 1.0414)
			(drill 1.0414)
			(layers "*.Cu" "*.Mask")
			(clearance 0.381)
			(thermal_gap 0.381)
		)
		(pad "" np_thru_hole circle
			(at -2.8829 1.27 270)
			(size 1.0414 1.0414)
			(drill 1.0414)
			(layers "*.Cu" "*.Mask")
			(clearance 0.381)
			(thermal_gap 0.381)
		)
		(pad "" np_thru_hole circle
			(at 3.4671 -1.27 270)
			(size 1.0414 1.0414)
			(drill 1.0414)
			(layers "*.Cu" "*.Mask")
			(clearance 0.381)
			(thermal_gap 0.381)
		)
		(pad "" np_thru_hole circle
			(at 3.4671 1.27 270)
			(size 1.0414 1.0414)
			(drill 1.0414)
			(layers "*.Cu" "*.Mask")
			(clearance 0.381)
			(thermal_gap 0.381)
		)
		(pad "1" smd rect
			(at 0.8255 -0.249936 270)
			(size 0.3048 0.508)
			(layers "F.Cu" "F.Mask" "F.Paste")
			(net "DELTA_L_85_10INCH_TOP_DP")
		)
		(pad "2" smd rect
			(at 0.8255 0.249936 270)
			(size 0.3048 0.508)
			(layers "F.Cu" "F.Mask" "F.Paste")
			(net "DELTA_L_85_10INCH_TOP_DN")
		)
		(pad "3" smd circle
			(at 0 0)
			(size 0 0)
			(layers "F.Cu" "F.Mask" "F.Paste")
			(net "DELTA_L_GND_1")
		)
		(zone
			(layer "F.Cu")
			(hatch none 0.5)
			(connect_pads
				(clearance 0)
			)
			(min_thickness 0.25)
			(keepout
				(tracks not_allowed)
				(vias allowed)
				(pads allowed)
				(copperpour not_allowed)
				(footprints allowed)
			)
			(placement
				(enabled no)
				(sheetname "")
			)
			(fill
				(thermal_gap 0.5)
				(thermal_bridge_width 0.5)
				(island_removal_mode 0)
			)
			(polygon
				(pts
					(xy 213.589108 -0.545846) (xy 213.589108 -0.450342) (xy 212.992208 -0.450342) (xy 212.992208 -0.043942)
					(xy 213.589108 -0.043942) (xy 213.589108 0.04953) (xy 212.992208 0.04953) (xy 212.992208 0.45593)
					(xy 213.589108 0.45593) (xy 213.589108 0.551434) (xy 212.890608 0.551434) (xy 212.890608 -0.545846)
				)
			)
		)
		(zone
			(layers "F.Cu" "B.Cu" "In1.Cu" "In2.Cu" "In3.Cu" "In4.Cu" "In5.Cu" "In6.Cu"
				"In7.Cu" "In8.Cu" "In9.Cu" "In10.Cu" "In11.Cu" "In12.Cu" "In13.Cu" "In14.Cu"
				"In15.Cu" "In16.Cu"
			)
			(hatch none 0.5)
			(connect_pads
				(clearance 0)
			)
			(min_thickness 0.25)
			(keepout
				(tracks not_allowed)
				(vias allowed)
				(pads allowed)
				(copperpour not_allowed)
				(footprints allowed)
			)
			(placement
				(enabled no)
				(sheetname "")
			)
			(fill
				(thermal_gap 0.5)
				(thermal_bridge_width 0.5)
				(island_removal_mode 0)
			)
			(polygon
				(pts
					(arc
						(start 210.515708 -1.267206)
						(mid 208.661508 -1.267206)
						(end 210.515708 -1.267206)
					)
				)
			)
		)
		(zone
			(layers "F.Cu" "B.Cu" "In1.Cu" "In2.Cu" "In3.Cu" "In4.Cu" "In5.Cu" "In6.Cu"
				"In7.Cu" "In8.Cu" "In9.Cu" "In10.Cu" "In11.Cu" "In12.Cu" "In13.Cu" "In14.Cu"
				"In15.Cu" "In16.Cu"
			)
			(hatch none 0.5)
			(connect_pads
				(clearance 0)
			)
			(min_thickness 0.25)
			(keepout
				(tracks not_allowed)
				(vias allowed)
				(pads allowed)
				(copperpour not_allowed)
				(footprints allowed)
			)
			(placement
				(enabled no)
				(sheetname "")
			)
			(fill
				(thermal_gap 0.5)
				(thermal_bridge_width 0.5)
				(island_removal_mode 0)
			)
			(polygon
				(pts
					(arc
						(start 210.515708 1.272794)
						(mid 208.661508 1.272794)
						(end 210.515708 1.272794)
					)
				)
			)
		)
		(zone
			(layers "F.Cu" "B.Cu" "In1.Cu" "In2.Cu" "In3.Cu" "In4.Cu" "In5.Cu" "In6.Cu"
				"In7.Cu" "In8.Cu" "In9.Cu" "In10.Cu" "In11.Cu" "In12.Cu" "In13.Cu" "In14.Cu"
				"In15.Cu" "In16.Cu"
			)
			(hatch none 0.5)
			(connect_pads
				(clearance 0)
			)
			(min_thickness 0.25)
			(keepout
				(tracks not_allowed)
				(vias allowed)
				(pads allowed)
				(copperpour not_allowed)
				(footprints allowed)
			)
			(placement
				(enabled no)
				(sheetname "")
			)
			(fill
				(thermal_gap 0.5)
				(thermal_bridge_width 0.5)
				(island_removal_mode 0)
			)
			(polygon
				(pts
					(arc
						(start 216.865708 -1.267206)
						(mid 215.011508 -1.267206)
						(end 216.865708 -1.267206)
					)
				)
			)
		)
		(zone
			(layers "F.Cu" "B.Cu" "In1.Cu" "In2.Cu" "In3.Cu" "In4.Cu" "In5.Cu" "In6.Cu"
				"In7.Cu" "In8.Cu" "In9.Cu" "In10.Cu" "In11.Cu" "In12.Cu" "In13.Cu" "In14.Cu"
				"In15.Cu" "In16.Cu"
			)
			(hatch none 0.5)
			(connect_pads
				(clearance 0)
			)
			(min_thickness 0.25)
			(keepout
				(tracks not_allowed)
				(vias allowed)
				(pads allowed)
				(copperpour not_allowed)
				(footprints allowed)
			)
			(placement
				(enabled no)
				(sheetname "")
			)
			(fill
				(thermal_gap 0.5)
				(thermal_bridge_width 0.5)
				(island_removal_mode 0)
			)
			(polygon
				(pts
					(arc
						(start 216.865708 1.272794)
						(mid 215.011508 1.272794)
						(end 216.865708 1.272794)
					)
				)
			)
		)
	)
	(footprint ""
		(layer "F.Cu")
		(at 72.6948 -386.7912 90)
		(property "Reference" "R6715"
			(at 0 0 90)
			(layer "F.SilkS")
			(hide yes)
			(effects
				(font
					(size 1.27 1.27)
				)
			)
		)
		(property "Value" ""
			(at 0 0 90)
			(layer "F.Fab")
			(effects
				(font
					(size 1.27 1.27)
				)
			)
		)
		(duplicate_pad_numbers_are_jumpers no)
		(fp_line
			(start 0.32512 -0.175006)
			(end 0.32512 0.175006)
			(stroke
				(width 0.1)
				(type default)
			)
			(layer "F.Fab")
		)
		(fp_line
			(start -0.32512 -0.175006)
			(end 0.32512 -0.175006)
			(stroke
				(width 0.1)
				(type default)
			)
			(layer "F.Fab")
		)
		(fp_line
			(start 0.32512 0.175006)
			(end -0.32512 0.175006)
			(stroke
				(width 0.1)
				(type default)
			)
			(layer "F.Fab")
		)
		(fp_line
			(start -0.32512 0.175006)
			(end -0.32512 -0.175006)
			(stroke
				(width 0.1)
				(type default)
			)
			(layer "F.Fab")
		)
		(pad "1" smd rect
			(at -0.2667 0 90)
			(size 0.3048 0.381)
			(layers "F.Cu" "F.Mask" "F.Paste")
			(net "RT_CPU1_P0_ADDR2")
		)
		(pad "2" smd rect
			(at 0.2667 0 270)
			(size 0.3048 0.381)
			(layers "F.Cu" "F.Mask" "F.Paste")
			(net "GND")
		)
	)
	(footprint ""
		(layer "F.Cu")
		(at 240.096802 -70.143624 90)
		(property "Reference" "R999"
			(at 0 0 90)
			(layer "F.SilkS")
			(hide yes)
			(effects
				(font
					(size 1.27 1.27)
				)
			)
		)
		(property "Value" ""
			(at 0 0 90)
			(layer "F.Fab")
			(effects
				(font
					(size 1.27 1.27)
				)
			)
		)
		(duplicate_pad_numbers_are_jumpers no)
		(fp_line
			(start 0.7874 -0.4064)
			(end 0.7874 0.4064)
			(stroke
				(width 0.1524)
				(type default)
			)
			(layer "F.SilkS")
		)
		(fp_line
			(start -0.7874 -0.4064)
			(end 0.7874 -0.4064)
			(stroke
				(width 0.1524)
				(type default)
			)
			(layer "F.SilkS")
		)
		(fp_line
			(start 0.7874 0.4064)
			(end -0.7874 0.4064)
			(stroke
				(width 0.1524)
				(type default)
			)
			(layer "F.SilkS")
		)
		(fp_line
			(start -0.7874 0.4064)
			(end -0.7874 -0.4064)
			(stroke
				(width 0.1524)
				(type default)
			)
			(layer "F.SilkS")
		)
		(fp_line
			(start -0.12065 -0.305054)
			(end -0.12065 -0.2794)
			(stroke
				(width 0.1)
				(type default)
			)
			(layer "F.Fab")
		)
		(fp_line
			(start -0.67945 -0.305054)
			(end -0.12065 -0.305054)
			(stroke
				(width 0.1)
				(type default)
			)
			(layer "F.Fab")
		)
		(fp_line
			(start 0.67945 -0.3048)
			(end 0.67945 0.3048)
			(stroke
				(width 0.1)
				(type default)
			)
			(layer "F.Fab")
		)
		(fp_line
			(start 0.12065 -0.3048)
			(end 0.67945 -0.3048)
			(stroke
				(width 0.1)
				(type default)
			)
			(layer "F.Fab")
		)
		(fp_line
			(start 0.12065 -0.2794)
			(end 0.12065 -0.3048)
			(stroke
				(width 0.1)
				(type default)
			)
			(layer "F.Fab")
		)
		(fp_line
			(start -0.12065 -0.2794)
			(end 0.12065 -0.2794)
			(stroke
				(width 0.1)
				(type default)
			)
			(layer "F.Fab")
		)
		(fp_line
			(start 0.120396 0.2794)
			(end -0.12065 0.2794)
			(stroke
				(width 0.1)
				(type default)
			)
			(layer "F.Fab")
		)
		(fp_line
			(start -0.12065 0.2794)
			(end -0.12065 0.3048)
			(stroke
				(width 0.1)
				(type default)
			)
			(layer "F.Fab")
		)
		(fp_line
			(start 0.67945 0.3048)
			(end 0.120396 0.3048)
			(stroke
				(width 0.1)
				(type default)
			)
			(layer "F.Fab")
		)
		(fp_line
			(start 0.120396 0.3048)
			(end 0.120396 0.2794)
			(stroke
				(width 0.1)
				(type default)
			)
			(layer "F.Fab")
		)
		(fp_line
			(start -0.12065 0.3048)
			(end -0.67945 0.3048)
			(stroke
				(width 0.1)
				(type default)
			)
			(layer "F.Fab")
		)
		(fp_line
			(start -0.67945 0.3048)
			(end -0.67945 -0.305054)
			(stroke
				(width 0.1)
				(type default)
			)
			(layer "F.Fab")
		)
		(pad "1" smd circle
			(at -0.40005 0 90)
			(size 0 0)
			(layers "F.Cu" "F.Mask" "F.Paste")
			(net "FM_LED_ACTIVE_E1S_0_R")
		)
		(pad "2" smd circle
			(at 0.40005 0 90)
			(size 0 0)
			(layers "F.Cu" "F.Mask" "F.Paste")
			(net "GND")
		)
	)
	(footprint ""
		(layer "F.Cu")
		(at 314.567316 -110.55477 180)
		(property "Reference" "R4"
			(at 0 0 180)
			(layer "F.SilkS")
			(hide yes)
			(effects
				(font
					(size 1.27 1.27)
				)
			)
		)
		(property "Value" ""
			(at 0 0 180)
			(layer "F.Fab")
			(effects
				(font
					(size 1.27 1.27)
				)
			)
		)
		(duplicate_pad_numbers_are_jumpers no)
		(fp_line
			(start 0.7874 0.4064)
			(end -0.7874 0.4064)
			(stroke
				(width 0.1524)
				(type default)
			)
			(layer "F.SilkS")
		)
		(fp_line
			(start 0.7874 -0.4064)
			(end 0.7874 0.4064)
			(stroke
				(width 0.1524)
				(type default)
			)
			(layer "F.SilkS")
		)
		(fp_line
			(start -0.7874 0.4064)
			(end -0.7874 -0.4064)
			(stroke
				(width 0.1524)
				(type default)
			)
			(layer "F.SilkS")
		)
		(fp_line
			(start -0.7874 -0.4064)
			(end 0.7874 -0.4064)
			(stroke
				(width 0.1524)
				(type default)
			)
			(layer "F.SilkS")
		)
		(fp_line
			(start 0.67945 0.3048)
			(end 0.120396 0.3048)
			(stroke
				(width 0.1)
				(type default)
			)
			(layer "F.Fab")
		)
		(fp_line
			(start 0.67945 -0.3048)
			(end 0.67945 0.3048)
			(stroke
				(width 0.1)
				(type default)
			)
			(layer "F.Fab")
		)
		(fp_line
			(start 0.12065 -0.2794)
			(end 0.12065 -0.3048)
			(stroke
				(width 0.1)
				(type default)
			)
			(layer "F.Fab")
		)
		(fp_line
			(start 0.12065 -0.3048)
			(end 0.67945 -0.3048)
			(stroke
				(width 0.1)
				(type default)
			)
			(layer "F.Fab")
		)
		(fp_line
			(start 0.120396 0.3048)
			(end 0.120396 0.2794)
			(stroke
				(width 0.1)
				(type default)
			)
			(layer "F.Fab")
		)
		(fp_line
			(start 0.120396 0.2794)
			(end -0.12065 0.2794)
			(stroke
				(width 0.1)
				(type default)
			)
			(layer "F.Fab")
		)
		(fp_line
			(start -0.12065 0.3048)
			(end -0.67945 0.3048)
			(stroke
				(width 0.1)
				(type default)
			)
			(layer "F.Fab")
		)
		(fp_line
			(start -0.12065 0.2794)
			(end -0.12065 0.3048)
			(stroke
				(width 0.1)
				(type default)
			)
			(layer "F.Fab")
		)
		(fp_line
			(start -0.12065 -0.2794)
			(end 0.12065 -0.2794)
			(stroke
				(width 0.1)
				(type default)
			)
			(layer "F.Fab")
		)
		(fp_line
			(start -0.12065 -0.305054)
			(end -0.12065 -0.2794)
			(stroke
				(width 0.1)
				(type default)
			)
			(layer "F.Fab")
		)
		(fp_line
			(start -0.67945 0.3048)
			(end -0.67945 -0.305054)
			(stroke
				(width 0.1)
				(type default)
			)
			(layer "F.Fab")
		)
		(fp_line
			(start -0.67945 -0.305054)
			(end -0.12065 -0.305054)
			(stroke
				(width 0.1)
				(type default)
			)
			(layer "F.Fab")
		)
		(pad "1" smd circle
			(at -0.40005 0 180)
			(size 0 0)
			(layers "F.Cu" "F.Mask" "F.Paste")
			(net "P3V3_AUX")
		)
		(pad "2" smd circle
			(at 0.40005 0 180)
			(size 0 0)
			(layers "F.Cu" "F.Mask" "F.Paste")
			(net "SMB_CPU_FRU_3V3AUX_SCL")
		)
	)
	(footprint ""
		(layer "F.Cu")
		(at 349.032322 -155.927806)
		(property "Reference" "PR431"
			(at 0 0 0)
			(layer "F.SilkS")
			(hide yes)
			(effects
				(font
					(size 1.27 1.27)
				)
			)
		)
		(property "Value" ""
			(at 0 0 0)
			(layer "F.Fab")
			(effects
				(font
					(size 1.27 1.27)
				)
			)
		)
		(duplicate_pad_numbers_are_jumpers no)
		(fp_line
			(start -0.7874 -0.4064)
			(end 0.7874 -0.4064)
			(stroke
				(width 0.1524)
				(type default)
			)
			(layer "F.SilkS")
		)
		(fp_line
			(start -0.7874 0.4064)
			(end -0.7874 -0.4064)
			(stroke
				(width 0.1524)
				(type default)
			)
			(layer "F.SilkS")
		)
		(fp_line
			(start 0.7874 -0.4064)
			(end 0.7874 0.4064)
			(stroke
				(width 0.1524)
				(type default)
			)
			(layer "F.SilkS")
		)
		(fp_line
			(start 0.7874 0.4064)
			(end -0.7874 0.4064)
			(stroke
				(width 0.1524)
				(type default)
			)
			(layer "F.SilkS")
		)
		(fp_line
			(start -0.67945 -0.305054)
			(end -0.12065 -0.305054)
			(stroke
				(width 0.1)
				(type default)
			)
			(layer "F.Fab")
		)
		(fp_line
			(start -0.67945 0.3048)
			(end -0.67945 -0.305054)
			(stroke
				(width 0.1)
				(type default)
			)
			(layer "F.Fab")
		)
		(fp_line
			(start -0.12065 -0.305054)
			(end -0.12065 -0.2794)
			(stroke
				(width 0.1)
				(type default)
			)
			(layer "F.Fab")
		)
		(fp_line
			(start -0.12065 -0.2794)
			(end 0.12065 -0.2794)
			(stroke
				(width 0.1)
				(type default)
			)
			(layer "F.Fab")
		)
		(fp_line
			(start -0.12065 0.2794)
			(end -0.12065 0.3048)
			(stroke
				(width 0.1)
				(type default)
			)
			(layer "F.Fab")
		)
		(fp_line
			(start -0.12065 0.3048)
			(end -0.67945 0.3048)
			(stroke
				(width 0.1)
				(type default)
			)
			(layer "F.Fab")
		)
		(fp_line
			(start 0.120396 0.2794)
			(end -0.12065 0.2794)
			(stroke
				(width 0.1)
				(type default)
			)
			(layer "F.Fab")
		)
		(fp_line
			(start 0.120396 0.3048)
			(end 0.120396 0.2794)
			(stroke
				(width 0.1)
				(type default)
			)
			(layer "F.Fab")
		)
		(fp_line
			(start 0.12065 -0.3048)
			(end 0.67945 -0.3048)
			(stroke
				(width 0.1)
				(type default)
			)
			(layer "F.Fab")
		)
		(fp_line
			(start 0.12065 -0.2794)
			(end 0.12065 -0.3048)
			(stroke
				(width 0.1)
				(type default)
			)
			(layer "F.Fab")
		)
		(fp_line
			(start 0.67945 -0.3048)
			(end 0.67945 0.3048)
			(stroke
				(width 0.1)
				(type default)
			)
			(layer "F.Fab")
		)
		(fp_line
			(start 0.67945 0.3048)
			(end 0.120396 0.3048)
			(stroke
				(width 0.1)
				(type default)
			)
			(layer "F.Fab")
		)
		(pad "1" smd circle
			(at -0.40005 0)
			(size 0 0)
			(layers "F.Cu" "F.Mask" "F.Paste")
			(net "GND")
		)
		(pad "2" smd circle
			(at 0.40005 0)
			(size 0 0)
			(layers "F.Cu" "F.Mask" "F.Paste")
			(net "PVDDCR_CPU0_P0_LSET6")
		)
	)
	(footprint ""
		(layer "F.Cu")
		(at 138.981942 -385.5212 90)
		(property "Reference" "R902"
			(at 0 0 90)
			(layer "F.SilkS")
			(hide yes)
			(effects
				(font
					(size 1.27 1.27)
				)
			)
		)
		(property "Value" ""
			(at 0 0 90)
			(layer "F.Fab")
			(effects
				(font
					(size 1.27 1.27)
				)
			)
		)
		(duplicate_pad_numbers_are_jumpers no)
		(fp_line
			(start 0.32512 -0.175006)
			(end 0.32512 0.175006)
			(stroke
				(width 0.1)
				(type default)
			)
			(layer "F.Fab")
		)
		(fp_line
			(start -0.32512 -0.175006)
			(end 0.32512 -0.175006)
			(stroke
				(width 0.1)
				(type default)
			)
			(layer "F.Fab")
		)
		(fp_line
			(start 0.32512 0.175006)
			(end -0.32512 0.175006)
			(stroke
				(width 0.1)
				(type default)
			)
			(layer "F.Fab")
		)
		(fp_line
			(start -0.32512 0.175006)
			(end -0.32512 -0.175006)
			(stroke
				(width 0.1)
				(type default)
			)
			(layer "F.Fab")
		)
		(pad "1" smd rect
			(at -0.2667 0 90)
			(size 0.3048 0.381)
			(layers "F.Cu" "F.Mask" "F.Paste")
			(net "P1V8_CPU1_RT_1D")
		)
		(pad "2" smd rect
			(at 0.2667 0 270)
			(size 0.3048 0.381)
			(layers "F.Cu" "F.Mask" "F.Paste")
			(net "RT_CPU1_P3_ADDR3")
		)
	)
	(footprint ""
		(layer "F.Cu")
		(at 148.971 -116.713 -90)
		(property "Reference" "C9004"
			(at 0 0 270)
			(layer "F.SilkS")
			(hide yes)
			(effects
				(font
					(size 1.27 1.27)
				)
			)
		)
		(property "Value" ""
			(at 0 0 270)
			(layer "F.Fab")
			(effects
				(font
					(size 1.27 1.27)
				)
			)
		)
		(duplicate_pad_numbers_are_jumpers no)
		(fp_line
			(start -0.7874 0.4064)
			(end -0.7874 -0.4064)
			(stroke
				(width 0.1524)
				(type default)
			)
			(layer "F.SilkS")
		)
		(fp_line
			(start 0.7874 0.4064)
			(end -0.7874 0.4064)
			(stroke
				(width 0.1524)
				(type default)
			)
			(layer "F.SilkS")
		)
		(fp_line
			(start -0.7874 -0.4064)
			(end 0.7874 -0.4064)
			(stroke
				(width 0.1524)
				(type default)
			)
			(layer "F.SilkS")
		)
		(fp_line
			(start 0.7874 -0.4064)
			(end 0.7874 0.4064)
			(stroke
				(width 0.1524)
				(type default)
			)
			(layer "F.SilkS")
		)
		(fp_line
			(start -0.67945 0.3048)
			(end -0.67945 -0.305054)
			(stroke
				(width 0.1)
				(type default)
			)
			(layer "F.Fab")
		)
		(fp_line
			(start -0.12065 0.3048)
			(end -0.67945 0.3048)
			(stroke
				(width 0.1)
				(type default)
			)
			(layer "F.Fab")
		)
		(fp_line
			(start 0.120396 0.3048)
			(end 0.120396 0.2794)
			(stroke
				(width 0.1)
				(type default)
			)
			(layer "F.Fab")
		)
		(fp_line
			(start 0.67945 0.3048)
			(end 0.120396 0.3048)
			(stroke
				(width 0.1)
				(type default)
			)
			(layer "F.Fab")
		)
		(fp_line
			(start -0.12065 0.2794)
			(end -0.12065 0.3048)
			(stroke
				(width 0.1)
				(type default)
			)
			(layer "F.Fab")
		)
		(fp_line
			(start 0.120396 0.2794)
			(end -0.12065 0.2794)
			(stroke
				(width 0.1)
				(type default)
			)
			(layer "F.Fab")
		)
		(fp_line
			(start -0.12065 -0.2794)
			(end 0.12065 -0.2794)
			(stroke
				(width 0.1)
				(type default)
			)
			(layer "F.Fab")
		)
		(fp_line
			(start 0.12065 -0.2794)
			(end 0.12065 -0.3048)
			(stroke
				(width 0.1)
				(type default)
			)
			(layer "F.Fab")
		)
		(fp_line
			(start 0.12065 -0.3048)
			(end 0.67945 -0.3048)
			(stroke
				(width 0.1)
				(type default)
			)
			(layer "F.Fab")
		)
		(fp_line
			(start 0.67945 -0.3048)
			(end 0.67945 0.3048)
			(stroke
				(width 0.1)
				(type default)
			)
			(layer "F.Fab")
		)
		(fp_line
			(start -0.67945 -0.305054)
			(end -0.12065 -0.305054)
			(stroke
				(width 0.1)
				(type default)
			)
			(layer "F.Fab")
		)
		(fp_line
			(start -0.12065 -0.305054)
			(end -0.12065 -0.2794)
			(stroke
				(width 0.1)
				(type default)
			)
			(layer "F.Fab")
		)
		(pad "1" smd circle
			(at -0.40005 0 270)
			(size 0 0)
			(layers "F.Cu" "F.Mask" "F.Paste")
			(net "U206_VS")
		)
		(pad "2" smd circle
			(at 0.40005 0 270)
			(size 0 0)
			(layers "F.Cu" "F.Mask" "F.Paste")
			(net "GND")
		)
	)
	(footprint ""
		(layer "F.Cu")
		(at 114.299238 -41.17975 -90)
		(property "Reference" "R6289"
			(at 0 0 270)
			(layer "F.SilkS")
			(hide yes)
			(effects
				(font
					(size 1.27 1.27)
				)
			)
		)
		(property "Value" ""
			(at 0 0 270)
			(layer "F.Fab")
			(effects
				(font
					(size 1.27 1.27)
				)
			)
		)
		(duplicate_pad_numbers_are_jumpers no)
		(fp_line
			(start -0.7874 0.4064)
			(end -0.7874 -0.4064)
			(stroke
				(width 0.1524)
				(type default)
			)
			(layer "F.SilkS")
		)
		(fp_line
			(start 0.7874 0.4064)
			(end -0.7874 0.4064)
			(stroke
				(width 0.1524)
				(type default)
			)
			(layer "F.SilkS")
		)
		(fp_line
			(start -0.7874 -0.4064)
			(end 0.7874 -0.4064)
			(stroke
				(width 0.1524)
				(type default)
			)
			(layer "F.SilkS")
		)
		(fp_line
			(start 0.7874 -0.4064)
			(end 0.7874 0.4064)
			(stroke
				(width 0.1524)
				(type default)
			)
			(layer "F.SilkS")
		)
		(fp_line
			(start -0.67945 0.3048)
			(end -0.67945 -0.305054)
			(stroke
				(width 0.1)
				(type default)
			)
			(layer "F.Fab")
		)
		(fp_line
			(start -0.12065 0.3048)
			(end -0.67945 0.3048)
			(stroke
				(width 0.1)
				(type default)
			)
			(layer "F.Fab")
		)
		(fp_line
			(start 0.120396 0.3048)
			(end 0.120396 0.2794)
			(stroke
				(width 0.1)
				(type default)
			)
			(layer "F.Fab")
		)
		(fp_line
			(start 0.67945 0.3048)
			(end 0.120396 0.3048)
			(stroke
				(width 0.1)
				(type default)
			)
			(layer "F.Fab")
		)
		(fp_line
			(start -0.12065 0.2794)
			(end -0.12065 0.3048)
			(stroke
				(width 0.1)
				(type default)
			)
			(layer "F.Fab")
		)
		(fp_line
			(start 0.120396 0.2794)
			(end -0.12065 0.2794)
			(stroke
				(width 0.1)
				(type default)
			)
			(layer "F.Fab")
		)
		(fp_line
			(start -0.12065 -0.2794)
			(end 0.12065 -0.2794)
			(stroke
				(width 0.1)
				(type default)
			)
			(layer "F.Fab")
		)
		(fp_line
			(start 0.12065 -0.2794)
			(end 0.12065 -0.3048)
			(stroke
				(width 0.1)
				(type default)
			)
			(layer "F.Fab")
		)
		(fp_line
			(start 0.12065 -0.3048)
			(end 0.67945 -0.3048)
			(stroke
				(width 0.1)
				(type default)
			)
			(layer "F.Fab")
		)
		(fp_line
			(start 0.67945 -0.3048)
			(end 0.67945 0.3048)
			(stroke
				(width 0.1)
				(type default)
			)
			(layer "F.Fab")
		)
		(fp_line
			(start -0.67945 -0.305054)
			(end -0.12065 -0.305054)
			(stroke
				(width 0.1)
				(type default)
			)
			(layer "F.Fab")
		)
		(fp_line
			(start -0.12065 -0.305054)
			(end -0.12065 -0.2794)
			(stroke
				(width 0.1)
				(type default)
			)
			(layer "F.Fab")
		)
		(pad "1" smd circle
			(at -0.40005 0 270)
			(size 0 0)
			(layers "F.Cu" "F.Mask" "F.Paste")
			(net "P3V3_AUX")
		)
		(pad "2" smd circle
			(at 0.40005 0 270)
			(size 0 0)
			(layers "F.Cu" "F.Mask" "F.Paste")
			(net "USB_HUB2_MRP_VBUS_DET")
		)
	)
	(footprint ""
		(layer "F.Cu")
		(at 279.056592 -346.866464 -90)
		(property "Reference" "PC180_4"
			(at 0 0 270)
			(layer "F.SilkS")
			(hide yes)
			(effects
				(font
					(size 1.27 1.27)
				)
			)
		)
		(property "Value" ""
			(at 0 0 270)
			(layer "F.Fab")
			(effects
				(font
					(size 1.27 1.27)
				)
			)
		)
		(duplicate_pad_numbers_are_jumpers no)
		(fp_line
			(start -0.7874 0.4064)
			(end -0.7874 -0.4064)
			(stroke
				(width 0.1524)
				(type default)
			)
			(layer "F.SilkS")
		)
		(fp_line
			(start 0.7874 0.4064)
			(end -0.7874 0.4064)
			(stroke
				(width 0.1524)
				(type default)
			)
			(layer "F.SilkS")
		)
		(fp_line
			(start -0.7874 -0.4064)
			(end 0.7874 -0.4064)
			(stroke
				(width 0.1524)
				(type default)
			)
			(layer "F.SilkS")
		)
		(fp_line
			(start 0.7874 -0.4064)
			(end 0.7874 0.4064)
			(stroke
				(width 0.1524)
				(type default)
			)
			(layer "F.SilkS")
		)
		(fp_line
			(start -0.67945 0.3048)
			(end -0.67945 -0.305054)
			(stroke
				(width 0.1)
				(type default)
			)
			(layer "F.Fab")
		)
		(fp_line
			(start -0.12065 0.3048)
			(end -0.67945 0.3048)
			(stroke
				(width 0.1)
				(type default)
			)
			(layer "F.Fab")
		)
		(fp_line
			(start 0.120396 0.3048)
			(end 0.120396 0.2794)
			(stroke
				(width 0.1)
				(type default)
			)
			(layer "F.Fab")
		)
		(fp_line
			(start 0.67945 0.3048)
			(end 0.120396 0.3048)
			(stroke
				(width 0.1)
				(type default)
			)
			(layer "F.Fab")
		)
		(fp_line
			(start -0.12065 0.2794)
			(end -0.12065 0.3048)
			(stroke
				(width 0.1)
				(type default)
			)
			(layer "F.Fab")
		)
		(fp_line
			(start 0.120396 0.2794)
			(end -0.12065 0.2794)
			(stroke
				(width 0.1)
				(type default)
			)
			(layer "F.Fab")
		)
		(fp_line
			(start -0.12065 -0.2794)
			(end 0.12065 -0.2794)
			(stroke
				(width 0.1)
				(type default)
			)
			(layer "F.Fab")
		)
		(fp_line
			(start 0.12065 -0.2794)
			(end 0.12065 -0.3048)
			(stroke
				(width 0.1)
				(type default)
			)
			(layer "F.Fab")
		)
		(fp_line
			(start 0.12065 -0.3048)
			(end 0.67945 -0.3048)
			(stroke
				(width 0.1)
				(type default)
			)
			(layer "F.Fab")
		)
		(fp_line
			(start 0.67945 -0.3048)
			(end 0.67945 0.3048)
			(stroke
				(width 0.1)
				(type default)
			)
			(layer "F.Fab")
		)
		(fp_line
			(start -0.67945 -0.305054)
			(end -0.12065 -0.305054)
			(stroke
				(width 0.1)
				(type default)
			)
			(layer "F.Fab")
		)
		(fp_line
			(start -0.12065 -0.305054)
			(end -0.12065 -0.2794)
			(stroke
				(width 0.1)
				(type default)
			)
			(layer "F.Fab")
		)
		(pad "1" smd circle
			(at -0.40005 0 270)
			(size 0 0)
			(layers "F.Cu" "F.Mask" "F.Paste")
			(net "SW_P12V_AUX_PVDDIO_P0_FLT")
		)
		(pad "2" smd circle
			(at 0.40005 0 270)
			(size 0 0)
			(layers "F.Cu" "F.Mask" "F.Paste")
			(net "GND")
		)
	)
	(footprint ""
		(layer "F.Cu")
		(at 110.067344 -375.94286 180)
		(property "Reference" "C1545"
			(at 0 0 180)
			(layer "F.SilkS")
			(hide yes)
			(effects
				(font
					(size 1.27 1.27)
				)
			)
		)
		(property "Value" ""
			(at 0 0 180)
			(layer "F.Fab")
			(effects
				(font
					(size 1.27 1.27)
				)
			)
		)
		(duplicate_pad_numbers_are_jumpers no)
		(fp_line
			(start 0.299974 0.150114)
			(end -0.299974 0.150114)
			(stroke
				(width 0.1)
				(type default)
			)
			(layer "F.Fab")
		)
		(fp_line
			(start 0.299974 -0.150114)
			(end 0.299974 0.150114)
			(stroke
				(width 0.1)
				(type default)
			)
			(layer "F.Fab")
		)
		(fp_line
			(start -0.299974 0.150114)
			(end -0.299974 -0.150114)
			(stroke
				(width 0.1)
				(type default)
			)
			(layer "F.Fab")
		)
		(fp_line
			(start -0.299974 -0.150114)
			(end 0.299974 -0.150114)
			(stroke
				(width 0.1)
				(type default)
			)
			(layer "F.Fab")
		)
		(pad "1" smd rect
			(at -0.2667 0 180)
			(size 0.3048 0.381)
			(layers "F.Cu" "F.Mask" "F.Paste")
			(net "P5E_CPU1_P3_TX_C_DP<1>")
		)
		(pad "2" smd rect
			(at 0.2667 0 180)
			(size 0.3048 0.381)
			(layers "F.Cu" "F.Mask" "F.Paste")
			(net "P5E_CPU1_P3_TX_DP<1>")
		)
	)
	(footprint ""
		(layer "F.Cu")
		(at 151.126444 -370.57203 -90)
		(property "Reference" "C761"
			(at 0 0 270)
			(layer "F.SilkS")
			(hide yes)
			(effects
				(font
					(size 1.27 1.27)
				)
			)
		)
		(property "Value" ""
			(at 0 0 270)
			(layer "F.Fab")
			(effects
				(font
					(size 1.27 1.27)
				)
			)
		)
		(duplicate_pad_numbers_are_jumpers no)
		(fp_line
			(start -0.299974 0.150114)
			(end -0.299974 -0.150114)
			(stroke
				(width 0.1)
				(type default)
			)
			(layer "F.Fab")
		)
		(fp_line
			(start 0.299974 0.150114)
			(end -0.299974 0.150114)
			(stroke
				(width 0.1)
				(type default)
			)
			(layer "F.Fab")
		)
		(fp_line
			(start -0.299974 -0.150114)
			(end 0.299974 -0.150114)
			(stroke
				(width 0.1)
				(type default)
			)
			(layer "F.Fab")
		)
		(fp_line
			(start 0.299974 -0.150114)
			(end 0.299974 0.150114)
			(stroke
				(width 0.1)
				(type default)
			)
			(layer "F.Fab")
		)
		(pad "1" smd rect
			(at -0.2667 0 270)
			(size 0.3048 0.381)
			(layers "F.Cu" "F.Mask" "F.Paste")
			(net "P5E_CPU1_P2_TX_C_DP<6>")
		)
		(pad "2" smd rect
			(at 0.2667 0 270)
			(size 0.3048 0.381)
			(layers "F.Cu" "F.Mask" "F.Paste")
			(net "P5E_CPU1_P2_TX_DP<6>")
		)
	)
	(footprint ""
		(layer "F.Cu")
		(at 461.593946 -107.043728)
		(property "Reference" "C592"
			(at 0 0 0)
			(layer "F.SilkS")
			(hide yes)
			(effects
				(font
					(size 1.27 1.27)
				)
			)
		)
		(property "Value" ""
			(at 0 0 0)
			(layer "F.Fab")
			(effects
				(font
					(size 1.27 1.27)
				)
			)
		)
		(duplicate_pad_numbers_are_jumpers no)
		(fp_line
			(start -0.7874 -0.4064)
			(end 0.7874 -0.4064)
			(stroke
				(width 0.1524)
				(type default)
			)
			(layer "F.SilkS")
		)
		(fp_line
			(start -0.7874 0.4064)
			(end -0.7874 -0.4064)
			(stroke
				(width 0.1524)
				(type default)
			)
			(layer "F.SilkS")
		)
		(fp_line
			(start 0.7874 -0.4064)
			(end 0.7874 0.4064)
			(stroke
				(width 0.1524)
				(type default)
			)
			(layer "F.SilkS")
		)
		(fp_line
			(start 0.7874 0.4064)
			(end -0.7874 0.4064)
			(stroke
				(width 0.1524)
				(type default)
			)
			(layer "F.SilkS")
		)
		(fp_line
			(start -0.67945 -0.305054)
			(end -0.12065 -0.305054)
			(stroke
				(width 0.1)
				(type default)
			)
			(layer "F.Fab")
		)
		(fp_line
			(start -0.67945 0.3048)
			(end -0.67945 -0.305054)
			(stroke
				(width 0.1)
				(type default)
			)
			(layer "F.Fab")
		)
		(fp_line
			(start -0.12065 -0.305054)
			(end -0.12065 -0.2794)
			(stroke
				(width 0.1)
				(type default)
			)
			(layer "F.Fab")
		)
		(fp_line
			(start -0.12065 -0.2794)
			(end 0.12065 -0.2794)
			(stroke
				(width 0.1)
				(type default)
			)
			(layer "F.Fab")
		)
		(fp_line
			(start -0.12065 0.2794)
			(end -0.12065 0.3048)
			(stroke
				(width 0.1)
				(type default)
			)
			(layer "F.Fab")
		)
		(fp_line
			(start -0.12065 0.3048)
			(end -0.67945 0.3048)
			(stroke
				(width 0.1)
				(type default)
			)
			(layer "F.Fab")
		)
		(fp_line
			(start 0.120396 0.2794)
			(end -0.12065 0.2794)
			(stroke
				(width 0.1)
				(type default)
			)
			(layer "F.Fab")
		)
		(fp_line
			(start 0.120396 0.3048)
			(end 0.120396 0.2794)
			(stroke
				(width 0.1)
				(type default)
			)
			(layer "F.Fab")
		)
		(fp_line
			(start 0.12065 -0.3048)
			(end 0.67945 -0.3048)
			(stroke
				(width 0.1)
				(type default)
			)
			(layer "F.Fab")
		)
		(fp_line
			(start 0.12065 -0.2794)
			(end 0.12065 -0.3048)
			(stroke
				(width 0.1)
				(type default)
			)
			(layer "F.Fab")
		)
		(fp_line
			(start 0.67945 -0.3048)
			(end 0.67945 0.3048)
			(stroke
				(width 0.1)
				(type default)
			)
			(layer "F.Fab")
		)
		(fp_line
			(start 0.67945 0.3048)
			(end 0.120396 0.3048)
			(stroke
				(width 0.1)
				(type default)
			)
			(layer "F.Fab")
		)
		(pad "1" smd circle
			(at -0.40005 0)
			(size 0 0)
			(layers "F.Cu" "F.Mask" "F.Paste")
			(net "P3V3_AUX")
		)
		(pad "2" smd circle
			(at 0.40005 0)
			(size 0 0)
			(layers "F.Cu" "F.Mask" "F.Paste")
			(net "GND")
		)
	)
	(footprint ""
		(layer "F.Cu")
		(at 67.672458 -27.889962 -90)
		(property "Reference" "PU206"
			(at 4.33959 1.244346 0)
			(unlocked yes)
			(layer "F.SilkS")
			(effects
				(font
					(size 0.7874 0.5842)
					(thickness 0.1524)
				)
				(justify left)
			)
		)
		(property "Value" ""
			(at 0 0 270)
			(layer "F.Fab")
			(effects
				(font
					(size 1.27 1.27)
				)
			)
		)
		(duplicate_pad_numbers_are_jumpers no)
		(fp_line
			(start -1.549908 2.549906)
			(end -0.753872 2.549906)
			(stroke
				(width 0.1524)
				(type default)
			)
			(layer "F.SilkS")
		)
		(fp_line
			(start -0.245872 2.549906)
			(end 0.245872 2.549906)
			(stroke
				(width 0.1524)
				(type default)
			)
			(layer "F.SilkS")
		)
		(fp_line
			(start 0.753872 2.549906)
			(end 1.549908 2.549906)
			(stroke
				(width 0.1524)
				(type default)
			)
			(layer "F.SilkS")
		)
		(fp_line
			(start 1.549908 2.549906)
			(end 1.549908 2.253996)
			(stroke
				(width 0.1524)
				(type default)
			)
			(layer "F.SilkS")
		)
		(fp_line
			(start -1.549908 2.253996)
			(end -1.549908 2.549906)
			(stroke
				(width 0.1524)
				(type default)
			)
			(layer "F.SilkS")
		)
		(fp_line
			(start 1.549908 -2.253996)
			(end 1.549908 -2.549906)
			(stroke
				(width 0.1524)
				(type default)
			)
			(layer "F.SilkS")
		)
		(fp_line
			(start -1.549908 -2.549906)
			(end -1.549908 -2.251964)
			(stroke
				(width 0.1524)
				(type default)
			)
			(layer "F.SilkS")
		)
		(fp_line
			(start -0.752094 -2.549906)
			(end -1.549908 -2.549906)
			(stroke
				(width 0.1524)
				(type default)
			)
			(layer "F.SilkS")
		)
		(fp_line
			(start 0.2413 -2.549906)
			(end -0.2413 -2.549906)
			(stroke
				(width 0.1524)
				(type default)
			)
			(layer "F.SilkS")
		)
		(fp_line
			(start 1.549908 -2.549906)
			(end 0.752094 -2.549906)
			(stroke
				(width 0.1524)
				(type default)
			)
			(layer "F.SilkS")
		)
		(fp_poly
			(pts
				(xy -2.104644 -3.527298) (xy -1.927606 -2.591562) (xy -2.782062 -3.011424)
			)
			(stroke
				(width 0)
				(type default)
			)
			(fill yes)
			(layer "F.SilkS")
		)
		(fp_line
			(start -1.549908 2.549906)
			(end 1.549908 2.549906)
			(stroke
				(width 0.1)
				(type default)
			)
			(layer "F.Fab")
		)
		(fp_line
			(start 1.549908 2.549906)
			(end 1.549908 -2.549906)
			(stroke
				(width 0.1)
				(type default)
			)
			(layer "F.Fab")
		)
		(fp_line
			(start -1.549908 -2.549906)
			(end -1.549908 2.549906)
			(stroke
				(width 0.1)
				(type default)
			)
			(layer "F.Fab")
		)
		(fp_line
			(start 1.549908 -2.549906)
			(end -1.549908 -2.549906)
			(stroke
				(width 0.1)
				(type default)
			)
			(layer "F.Fab")
		)
		(fp_poly
			(pts
				(xy -1.891538 -1.999996) (xy -2.7432 -1.574292) (xy -2.7432 -2.4257)
			)
			(stroke
				(width 0)
				(type default)
			)
			(fill yes)
			(layer "F.Fab")
		)
		(fp_text user "11"
			(at 2.3368 5.107432 270)
			(unlocked yes)
			(layer "F.SilkS")
			(effects
				(font
					(size 0.635 0.4064)
					(thickness 0.1524)
				)
			)
		)
		(fp_text user "10"
			(at -1.9304 3.126232 270)
			(unlocked yes)
			(layer "F.SilkS")
			(effects
				(font
					(size 0.635 0.4064)
					(thickness 0.1524)
				)
			)
		)
		(fp_text user "9"
			(at -2.592832 2.2098 180)
			(unlocked yes)
			(layer "F.SilkS")
			(effects
				(font
					(size 0.635 0.4064)
					(thickness 0.1524)
				)
			)
		)
		(fp_text user "12"
			(at 2.461768 1.0668 180)
			(unlocked yes)
			(layer "F.SilkS")
			(effects
				(font
					(size 0.635 0.4064)
					(thickness 0.1524)
				)
			)
		)
		(fp_text user "21_22"
			(at -0.0762 -3.401568 270)
			(unlocked yes)
			(layer "F.SilkS")
			(effects
				(font
					(size 0.635 0.4064)
					(thickness 0.1524)
				)
			)
		)
		(fp_text user "20"
			(at 3.706368 -3.5306 180)
			(unlocked yes)
			(layer "F.SilkS")
			(effects
				(font
					(size 0.635 0.4064)
					(thickness 0.1524)
				)
			)
		)
		(fp_text user "11"
			(at 1.1938 3.329432 270)
			(unlocked yes)
			(layer "F.Fab")
			(effects
				(font
					(size 0.635 0.4064)
					(thickness 0.1524)
				)
			)
		)
		(fp_text user "10"
			(at -1.4224 3.253232 270)
			(unlocked yes)
			(layer "F.Fab")
			(effects
				(font
					(size 0.635 0.4064)
					(thickness 0.1524)
				)
			)
		)
		(fp_text user "12"
			(at 2.207768 2.7178 180)
			(unlocked yes)
			(layer "F.Fab")
			(effects
				(font
					(size 0.635 0.4064)
					(thickness 0.1524)
				)
			)
		)
		(fp_text user "9"
			(at -2.338832 2.5908 180)
			(unlocked yes)
			(layer "F.Fab")
			(effects
				(font
					(size 0.635 0.4064)
					(thickness 0.1524)
				)
			)
		)
		(fp_text user "20"
			(at 2.055368 -2.7686 180)
			(unlocked yes)
			(layer "F.Fab")
			(effects
				(font
					(size 0.635 0.4064)
					(thickness 0.1524)
				)
			)
		)
		(fp_text user "21_22"
			(at -0.0762 -3.401568 270)
			(unlocked yes)
			(layer "F.Fab")
			(effects
				(font
					(size 0.635 0.4064)
					(thickness 0.1524)
				)
			)
		)
		(pad "1" smd circle
			(at -1.374902 -1.999996 180)
			(size 0 0)
			(layers "F.Cu" "F.Mask" "F.Paste")
			(net "P12V_OCP_V3_2_EN_2_R3")
		)
		(pad "2" smd rect
			(at -1.400048 -1.500124 180)
			(size 0.254 0.8128)
			(layers "F.Cu" "F.Mask" "F.Paste")
			(net "GND")
		)
		(pad "3" smd rect
			(at -1.400048 -0.999998 180)
			(size 0.254 0.8128)
			(layers "F.Cu" "F.Mask" "F.Paste")
			(net "GND")
		)
		(pad "4" smd rect
			(at -1.400048 -0.499872 180)
			(size 0.254 0.8128)
			(layers "F.Cu" "F.Mask" "F.Paste")
			(net "P12V_OCP_TIMER_2")
		)
		(pad "5" smd rect
			(at -1.400048 0 180)
			(size 0.254 0.8128)
			(layers "F.Cu" "F.Mask" "F.Paste")
			(net "P12V_OCP_ISET_2")
		)
		(pad "6" smd rect
			(at -1.400048 0.499872 180)
			(size 0.254 0.8128)
			(layers "F.Cu" "F.Mask" "F.Paste")
			(net "P12V_OCP_SS_2")
		)
		(pad "7" smd rect
			(at -1.400048 0.999998 180)
			(size 0.254 0.8128)
			(layers "F.Cu" "F.Mask" "F.Paste")
			(net "GND")
		)
		(pad "8" smd rect
			(at -1.400048 1.500124 180)
			(size 0.254 0.8128)
			(layers "F.Cu" "F.Mask" "F.Paste")
			(net "P12V_OCP_IMON_2")
		)
		(pad "9" smd rect
			(at -1.400048 1.999996 180)
			(size 0.254 0.8128)
			(layers "F.Cu" "F.Mask" "F.Paste")
			(net "P12V_OCP_FLTB_2")
		)
		(pad "10" smd rect
			(at -0.499872 2.400046 270)
			(size 0.254 0.8128)
			(layers "F.Cu" "F.Mask" "F.Paste")
			(net "HP_LVC3_OCP_V3_2_P12V_PWRGD")
		)
		(pad "11" smd rect
			(at 0.499872 2.400046 270)
			(size 0.254 0.8128)
			(layers "F.Cu" "F.Mask" "F.Paste")
			(net "P12V_OCP_OV_FB_2")
		)
		(pad "12" smd rect
			(at 1.400048 1.999996 180)
			(size 0.254 0.8128)
			(layers "F.Cu" "F.Mask" "F.Paste")
			(net "P12V_OCP_AVIN_PD_2")
		)
		(pad "13" smd rect
			(at 1.400048 1.500124 180)
			(size 0.254 0.8128)
			(layers "F.Cu" "F.Mask" "F.Paste")
			(net "P12V_OCP_V3_2")
		)
		(pad "14" smd rect
			(at 1.400048 0.999998 180)
			(size 0.254 0.8128)
			(layers "F.Cu" "F.Mask" "F.Paste")
			(net "P12V_OCP_V3_2")
		)
		(pad "15" smd rect
			(at 1.400048 0.499872 180)
			(size 0.254 0.8128)
			(layers "F.Cu" "F.Mask" "F.Paste")
			(net "P12V_OCP_V3_2")
		)
		(pad "16" smd rect
			(at 1.400048 0 180)
			(size 0.254 0.8128)
			(layers "F.Cu" "F.Mask" "F.Paste")
			(net "P12V_OCP_V3_2")
		)
		(pad "17" smd rect
			(at 1.400048 -0.499872 180)
			(size 0.254 0.8128)
			(layers "F.Cu" "F.Mask" "F.Paste")
			(net "P12V_OCP_V3_2")
		)
		(pad "18" smd rect
			(at 1.400048 -0.999998 180)
			(size 0.254 0.8128)
			(layers "F.Cu" "F.Mask" "F.Paste")
			(net "P12V_OCP_V3_2")
		)
		(pad "19" smd rect
			(at 1.400048 -1.500124 180)
			(size 0.254 0.8128)
			(layers "F.Cu" "F.Mask" "F.Paste")
			(net "P12V_OCP_V3_2")
		)
		(pad "20" smd rect
			(at 1.400048 -1.999996 180)
			(size 0.254 0.8128)
			(layers "F.Cu" "F.Mask" "F.Paste")
			(net "P12V_OCP_V3_2")
		)
		(pad "21_22" smd circle
			(at 0.499872 -2.337562 180)
			(size 0 0)
			(layers "F.Cu" "F.Mask" "F.Paste")
			(net "P12V_AUX")
		)
		(pad "23" smd rect
			(at 0 -1.100074 180)
			(size 0.254 1.27)
			(layers "F.Cu" "F.Mask" "F.Paste")
			(net "P12V_AUX")
		)
		(pad "24" smd rect
			(at 0 -0.199898 180)
			(size 0.254 1.27)
			(layers "F.Cu" "F.Mask" "F.Paste")
			(net "P12V_AUX")
		)
		(pad "25" smd rect
			(at 0 0.700024 180)
			(size 0.254 1.27)
			(layers "F.Cu" "F.Mask" "F.Paste")
			(net "P12V_AUX")
		)
		(pad "26" smd rect
			(at 0 1.599946 180)
			(size 0.254 1.27)
			(layers "F.Cu" "F.Mask" "F.Paste")
			(net "P12V_AUX")
		)
	)
	(footprint ""
		(layer "F.Cu")
		(at 197.177406 -40.138604)
		(property "Reference" "R3996"
			(at 0 0 0)
			(layer "F.SilkS")
			(hide yes)
			(effects
				(font
					(size 1.27 1.27)
				)
			)
		)
		(property "Value" ""
			(at 0 0 0)
			(layer "F.Fab")
			(effects
				(font
					(size 1.27 1.27)
				)
			)
		)
		(duplicate_pad_numbers_are_jumpers no)
		(fp_line
			(start -0.7874 -0.4064)
			(end 0.7874 -0.4064)
			(stroke
				(width 0.1524)
				(type default)
			)
			(layer "F.SilkS")
		)
		(fp_line
			(start -0.7874 0.4064)
			(end -0.7874 -0.4064)
			(stroke
				(width 0.1524)
				(type default)
			)
			(layer "F.SilkS")
		)
		(fp_line
			(start 0.7874 -0.4064)
			(end 0.7874 0.4064)
			(stroke
				(width 0.1524)
				(type default)
			)
			(layer "F.SilkS")
		)
		(fp_line
			(start 0.7874 0.4064)
			(end -0.7874 0.4064)
			(stroke
				(width 0.1524)
				(type default)
			)
			(layer "F.SilkS")
		)
		(fp_line
			(start -0.67945 -0.305054)
			(end -0.12065 -0.305054)
			(stroke
				(width 0.1)
				(type default)
			)
			(layer "F.Fab")
		)
		(fp_line
			(start -0.67945 0.3048)
			(end -0.67945 -0.305054)
			(stroke
				(width 0.1)
				(type default)
			)
			(layer "F.Fab")
		)
		(fp_line
			(start -0.12065 -0.305054)
			(end -0.12065 -0.2794)
			(stroke
				(width 0.1)
				(type default)
			)
			(layer "F.Fab")
		)
		(fp_line
			(start -0.12065 -0.2794)
			(end 0.12065 -0.2794)
			(stroke
				(width 0.1)
				(type default)
			)
			(layer "F.Fab")
		)
		(fp_line
			(start -0.12065 0.2794)
			(end -0.12065 0.3048)
			(stroke
				(width 0.1)
				(type default)
			)
			(layer "F.Fab")
		)
		(fp_line
			(start -0.12065 0.3048)
			(end -0.67945 0.3048)
			(stroke
				(width 0.1)
				(type default)
			)
			(layer "F.Fab")
		)
		(fp_line
			(start 0.120396 0.2794)
			(end -0.12065 0.2794)
			(stroke
				(width 0.1)
				(type default)
			)
			(layer "F.Fab")
		)
		(fp_line
			(start 0.120396 0.3048)
			(end 0.120396 0.2794)
			(stroke
				(width 0.1)
				(type default)
			)
			(layer "F.Fab")
		)
		(fp_line
			(start 0.12065 -0.3048)
			(end 0.67945 -0.3048)
			(stroke
				(width 0.1)
				(type default)
			)
			(layer "F.Fab")
		)
		(fp_line
			(start 0.12065 -0.2794)
			(end 0.12065 -0.3048)
			(stroke
				(width 0.1)
				(type default)
			)
			(layer "F.Fab")
		)
		(fp_line
			(start 0.67945 -0.3048)
			(end 0.67945 0.3048)
			(stroke
				(width 0.1)
				(type default)
			)
			(layer "F.Fab")
		)
		(fp_line
			(start 0.67945 0.3048)
			(end 0.120396 0.3048)
			(stroke
				(width 0.1)
				(type default)
			)
			(layer "F.Fab")
		)
		(pad "1" smd circle
			(at -0.40005 0)
			(size 0 0)
			(layers "F.Cu" "F.Mask" "F.Paste")
			(net "VIRTUAL_RESEAT_FPGA_N")
		)
		(pad "2" smd circle
			(at 0.40005 0)
			(size 0 0)
			(layers "F.Cu" "F.Mask" "F.Paste")
			(net "P12V_SCM_EN")
		)
	)
	(footprint ""
		(layer "F.Cu")
		(at 398.437862 -416.899344 -90)
		(property "Reference" "C6584"
			(at 0 0 270)
			(layer "F.SilkS")
			(hide yes)
			(effects
				(font
					(size 1.27 1.27)
				)
			)
		)
		(property "Value" ""
			(at 0 0 270)
			(layer "F.Fab")
			(effects
				(font
					(size 1.27 1.27)
				)
			)
		)
		(duplicate_pad_numbers_are_jumpers no)
		(fp_line
			(start -0.299974 0.150114)
			(end -0.299974 -0.150114)
			(stroke
				(width 0.1)
				(type default)
			)
			(layer "F.Fab")
		)
		(fp_line
			(start 0.299974 0.150114)
			(end -0.299974 0.150114)
			(stroke
				(width 0.1)
				(type default)
			)
			(layer "F.Fab")
		)
		(fp_line
			(start -0.299974 -0.150114)
			(end 0.299974 -0.150114)
			(stroke
				(width 0.1)
				(type default)
			)
			(layer "F.Fab")
		)
		(fp_line
			(start 0.299974 -0.150114)
			(end 0.299974 0.150114)
			(stroke
				(width 0.1)
				(type default)
			)
			(layer "F.Fab")
		)
		(pad "1" smd rect
			(at -0.2667 0 270)
			(size 0.3048 0.381)
			(layers "F.Cu" "F.Mask" "F.Paste")
			(net "P5E_CPU0_P2_TX_BUF_C_DN<9>")
		)
		(pad "2" smd rect
			(at 0.2667 0 270)
			(size 0.3048 0.381)
			(layers "F.Cu" "F.Mask" "F.Paste")
			(net "P5E_CPU0_P2_TX_BUF_DN<9>")
		)
	)
	(footprint ""
		(layer "F.Cu")
		(at 127.659892 -168.196768)
		(property "Reference" "PC149"
			(at 0 0 0)
			(layer "F.SilkS")
			(hide yes)
			(effects
				(font
					(size 1.27 1.27)
				)
			)
		)
		(property "Value" ""
			(at 0 0 0)
			(layer "F.Fab")
			(effects
				(font
					(size 1.27 1.27)
				)
			)
		)
		(duplicate_pad_numbers_are_jumpers no)
		(fp_line
			(start -0.7874 -0.4064)
			(end 0.7874 -0.4064)
			(stroke
				(width 0.1524)
				(type default)
			)
			(layer "F.SilkS")
		)
		(fp_line
			(start -0.7874 0.4064)
			(end -0.7874 -0.4064)
			(stroke
				(width 0.1524)
				(type default)
			)
			(layer "F.SilkS")
		)
		(fp_line
			(start 0.7874 -0.4064)
			(end 0.7874 0.4064)
			(stroke
				(width 0.1524)
				(type default)
			)
			(layer "F.SilkS")
		)
		(fp_line
			(start 0.7874 0.4064)
			(end -0.7874 0.4064)
			(stroke
				(width 0.1524)
				(type default)
			)
			(layer "F.SilkS")
		)
		(fp_line
			(start -0.67945 -0.305054)
			(end -0.12065 -0.305054)
			(stroke
				(width 0.1)
				(type default)
			)
			(layer "F.Fab")
		)
		(fp_line
			(start -0.67945 0.3048)
			(end -0.67945 -0.305054)
			(stroke
				(width 0.1)
				(type default)
			)
			(layer "F.Fab")
		)
		(fp_line
			(start -0.12065 -0.305054)
			(end -0.12065 -0.2794)
			(stroke
				(width 0.1)
				(type default)
			)
			(layer "F.Fab")
		)
		(fp_line
			(start -0.12065 -0.2794)
			(end 0.12065 -0.2794)
			(stroke
				(width 0.1)
				(type default)
			)
			(layer "F.Fab")
		)
		(fp_line
			(start -0.12065 0.2794)
			(end -0.12065 0.3048)
			(stroke
				(width 0.1)
				(type default)
			)
			(layer "F.Fab")
		)
		(fp_line
			(start -0.12065 0.3048)
			(end -0.67945 0.3048)
			(stroke
				(width 0.1)
				(type default)
			)
			(layer "F.Fab")
		)
		(fp_line
			(start 0.120396 0.2794)
			(end -0.12065 0.2794)
			(stroke
				(width 0.1)
				(type default)
			)
			(layer "F.Fab")
		)
		(fp_line
			(start 0.120396 0.3048)
			(end 0.120396 0.2794)
			(stroke
				(width 0.1)
				(type default)
			)
			(layer "F.Fab")
		)
		(fp_line
			(start 0.12065 -0.3048)
			(end 0.67945 -0.3048)
			(stroke
				(width 0.1)
				(type default)
			)
			(layer "F.Fab")
		)
		(fp_line
			(start 0.12065 -0.2794)
			(end 0.12065 -0.3048)
			(stroke
				(width 0.1)
				(type default)
			)
			(layer "F.Fab")
		)
		(fp_line
			(start 0.67945 -0.3048)
			(end 0.67945 0.3048)
			(stroke
				(width 0.1)
				(type default)
			)
			(layer "F.Fab")
		)
		(fp_line
			(start 0.67945 0.3048)
			(end 0.120396 0.3048)
			(stroke
				(width 0.1)
				(type default)
			)
			(layer "F.Fab")
		)
		(pad "1" smd circle
			(at -0.40005 0)
			(size 0 0)
			(layers "F.Cu" "F.Mask" "F.Paste")
			(net "SW_PVDDCR_SOC_P1_SW2")
		)
		(pad "2" smd circle
			(at 0.40005 0)
			(size 0 0)
			(layers "F.Cu" "F.Mask" "F.Paste")
			(net "SW_PVDDCR_SOC_P1_SW2_RC")
		)
	)
	(footprint ""
		(layer "F.Cu")
		(at 501.233948 7.574534 -90)
		(property "Reference" "X8009"
			(at -1.815338 4.793488 0)
			(unlocked yes)
			(layer "F.SilkS")
			(effects
				(font
					(size 0.7874 0.5842)
					(thickness 0.1524)
				)
				(justify left)
			)
		)
		(property "Value" ""
			(at 0 0 270)
			(layer "F.Fab")
			(effects
				(font
					(size 1.27 1.27)
				)
			)
		)
		(property "Device Type" "TP_TDR_4P_FTS_TH-TP_TDR_4P_DIP,EMPTY,TP15"
			(at 1.30175 1.27 0)
			(unlocked yes)
			(layer "F.Fab")
			(hide yes)
			(effects
				(font
					(size 0.635 0.4064)
					(thickness 0.1524)
				)
			)
		)
		(property "User Part Number" "N_A"
			(at 1.30175 1.27 0)
			(unlocked yes)
			(layer "Cmts.User")
			(hide yes)
			(effects
				(font
					(size 0.635 0.4064)
					(thickness 0.1524)
				)
			)
		)
		(duplicate_pad_numbers_are_jumpers no)
		(fp_line
			(start 0 3.81)
			(end 2.54 3.81)
			(stroke
				(width 0.1524)
				(type default)
			)
			(layer "F.SilkS")
		)
		(fp_line
			(start 2.54 3.81)
			(end 2.54 3.6703)
			(stroke
				(width 0.1524)
				(type default)
			)
			(layer "F.SilkS")
		)
		(fp_line
			(start 0 3.175)
			(end 0 3.81)
			(stroke
				(width 0.1524)
				(type default)
			)
			(layer "F.SilkS")
		)
		(fp_line
			(start 2.54 1.4097)
			(end 2.54 1.1303)
			(stroke
				(width 0.1524)
				(type default)
			)
			(layer "F.SilkS")
		)
		(fp_line
			(start 0 0.635)
			(end 0 1.905)
			(stroke
				(width 0.1524)
				(type default)
			)
			(layer "F.SilkS")
		)
		(fp_line
			(start 2.54 -1.1303)
			(end 2.54 -1.27)
			(stroke
				(width 0.1524)
				(type default)
			)
			(layer "F.SilkS")
		)
		(fp_line
			(start 0 -1.27)
			(end 0 -0.635)
			(stroke
				(width 0.1524)
				(type default)
			)
			(layer "F.SilkS")
		)
		(fp_line
			(start 2.54 -1.27)
			(end 0 -1.27)
			(stroke
				(width 0.1524)
				(type default)
			)
			(layer "F.SilkS")
		)
		(fp_poly
			(pts
				(xy -2.285746 -0.762) (xy -0.761746 0) (xy -2.285746 0.762)
			)
			(stroke
				(width 0)
				(type default)
			)
			(fill yes)
			(layer "F.SilkS")
		)
		(fp_line
			(start 0 3.81)
			(end 2.54 3.81)
			(stroke
				(width 0.1)
				(type default)
			)
			(layer "F.Fab")
		)
		(fp_line
			(start 2.54 3.81)
			(end 2.54 -1.27)
			(stroke
				(width 0.1)
				(type default)
			)
			(layer "F.Fab")
		)
		(fp_line
			(start 0 -1.27)
			(end 0 3.81)
			(stroke
				(width 0.1)
				(type default)
			)
			(layer "F.Fab")
		)
		(fp_line
			(start 2.54 -1.27)
			(end 0 -1.27)
			(stroke
				(width 0.1)
				(type default)
			)
			(layer "F.Fab")
		)
		(fp_poly
			(pts
				(xy -0.761746 0) (xy -2.285746 -0.762) (xy -2.285746 0.762)
			)
			(stroke
				(width 0)
				(type default)
			)
			(fill yes)
			(layer "F.Fab")
		)
		(pad "1" thru_hole circle
			(at 0 0 270)
			(size 1.0033 1.0033)
			(drill 0.249936)
			(layers "*.Cu" "*.Mask")
			(remove_unused_layers no)
			(net "TDR_DIFF_85_IN2_DN")
			(clearance 0.10795)
			(thermal_gap 0.10795)
			(padstack
				(mode front_inner_back)
				(layer "Inner"
					(shape circle)
					(size 0.8001 0.8001)
					(clearance 0.1524)
				)
				(layer "B.Cu"
					(shape circle)
					(size 1.0033 1.0033)
					(clearance 0.10795)
				)
			)
		)
		(pad "2" thru_hole circle
			(at 2.54 0 270)
			(size 1.9939 1.9939)
			(drill 0.249936)
			(layers "*.Cu" "*.Mask")
			(remove_unused_layers no)
			(net "T1_GND")
			(clearance 0.10795)
			(thermal_gap 0.10795)
			(padstack
				(mode front_inner_back)
				(layer "Inner"
					(shape circle)
					(size 0.8001 0.8001)
					(clearance 0.1524)
				)
				(layer "B.Cu"
					(shape circle)
					(size 1.9939 1.9939)
					(clearance 0.10795)
				)
			)
		)
		(pad "3" thru_hole circle
			(at 2.54 2.54 270)
			(size 1.9939 1.9939)
			(drill 0.249936)
			(layers "*.Cu" "*.Mask")
			(remove_unused_layers no)
			(net "T1_GND")
			(clearance 0.10795)
			(thermal_gap 0.10795)
			(padstack
				(mode front_inner_back)
				(layer "Inner"
					(shape circle)
					(size 0.8001 0.8001)
					(clearance 0.1524)
				)
				(layer "B.Cu"
					(shape circle)
					(size 1.9939 1.9939)
					(clearance 0.10795)
				)
			)
		)
		(pad "4" thru_hole circle
			(at 0 2.54 270)
			(size 1.0033 1.0033)
			(drill 0.249936)
			(layers "*.Cu" "*.Mask")
			(remove_unused_layers no)
			(net "TDR_DIFF_85_IN2_DP")
			(clearance 0.10795)
			(thermal_gap 0.10795)
			(padstack
				(mode front_inner_back)
				(layer "Inner"
					(shape circle)
					(size 0.8001 0.8001)
					(clearance 0.1524)
				)
				(layer "B.Cu"
					(shape circle)
					(size 1.0033 1.0033)
					(clearance 0.10795)
				)
			)
		)
	)
	(footprint ""
		(layer "F.Cu")
		(at 403.682962 -57.2135 180)
		(property "Reference" "R1620"
			(at 0 0 180)
			(layer "F.SilkS")
			(hide yes)
			(effects
				(font
					(size 1.27 1.27)
				)
			)
		)
		(property "Value" ""
			(at 0 0 180)
			(layer "F.Fab")
			(effects
				(font
					(size 1.27 1.27)
				)
			)
		)
		(duplicate_pad_numbers_are_jumpers no)
		(fp_line
			(start 0.7874 0.4064)
			(end -0.7874 0.4064)
			(stroke
				(width 0.1524)
				(type default)
			)
			(layer "F.SilkS")
		)
		(fp_line
			(start 0.7874 -0.4064)
			(end 0.7874 0.4064)
			(stroke
				(width 0.1524)
				(type default)
			)
			(layer "F.SilkS")
		)
		(fp_line
			(start -0.7874 0.4064)
			(end -0.7874 -0.4064)
			(stroke
				(width 0.1524)
				(type default)
			)
			(layer "F.SilkS")
		)
		(fp_line
			(start -0.7874 -0.4064)
			(end 0.7874 -0.4064)
			(stroke
				(width 0.1524)
				(type default)
			)
			(layer "F.SilkS")
		)
		(fp_line
			(start 0.67945 0.3048)
			(end 0.120396 0.3048)
			(stroke
				(width 0.1)
				(type default)
			)
			(layer "F.Fab")
		)
		(fp_line
			(start 0.67945 -0.3048)
			(end 0.67945 0.3048)
			(stroke
				(width 0.1)
				(type default)
			)
			(layer "F.Fab")
		)
		(fp_line
			(start 0.12065 -0.2794)
			(end 0.12065 -0.3048)
			(stroke
				(width 0.1)
				(type default)
			)
			(layer "F.Fab")
		)
		(fp_line
			(start 0.12065 -0.3048)
			(end 0.67945 -0.3048)
			(stroke
				(width 0.1)
				(type default)
			)
			(layer "F.Fab")
		)
		(fp_line
			(start 0.120396 0.3048)
			(end 0.120396 0.2794)
			(stroke
				(width 0.1)
				(type default)
			)
			(layer "F.Fab")
		)
		(fp_line
			(start 0.120396 0.2794)
			(end -0.12065 0.2794)
			(stroke
				(width 0.1)
				(type default)
			)
			(layer "F.Fab")
		)
		(fp_line
			(start -0.12065 0.3048)
			(end -0.67945 0.3048)
			(stroke
				(width 0.1)
				(type default)
			)
			(layer "F.Fab")
		)
		(fp_line
			(start -0.12065 0.2794)
			(end -0.12065 0.3048)
			(stroke
				(width 0.1)
				(type default)
			)
			(layer "F.Fab")
		)
		(fp_line
			(start -0.12065 -0.2794)
			(end 0.12065 -0.2794)
			(stroke
				(width 0.1)
				(type default)
			)
			(layer "F.Fab")
		)
		(fp_line
			(start -0.12065 -0.305054)
			(end -0.12065 -0.2794)
			(stroke
				(width 0.1)
				(type default)
			)
			(layer "F.Fab")
		)
		(fp_line
			(start -0.67945 0.3048)
			(end -0.67945 -0.305054)
			(stroke
				(width 0.1)
				(type default)
			)
			(layer "F.Fab")
		)
		(fp_line
			(start -0.67945 -0.305054)
			(end -0.12065 -0.305054)
			(stroke
				(width 0.1)
				(type default)
			)
			(layer "F.Fab")
		)
		(pad "1" smd circle
			(at -0.40005 0 180)
			(size 0 0)
			(layers "F.Cu" "F.Mask" "F.Paste")
			(net "HDT_HDR_TRST_N")
		)
		(pad "2" smd circle
			(at 0.40005 0 180)
			(size 0 0)
			(layers "F.Cu" "F.Mask" "F.Paste")
			(net "HDT_HDR_TRST_N_R")
		)
	)
	(footprint ""
		(layer "F.Cu")
		(at 110.365794 -383.7432)
		(property "Reference" "R923"
			(at 0 0 0)
			(layer "F.SilkS")
			(hide yes)
			(effects
				(font
					(size 1.27 1.27)
				)
			)
		)
		(property "Value" ""
			(at 0 0 0)
			(layer "F.Fab")
			(effects
				(font
					(size 1.27 1.27)
				)
			)
		)
		(duplicate_pad_numbers_are_jumpers no)
		(fp_line
			(start -0.32512 -0.175006)
			(end 0.32512 -0.175006)
			(stroke
				(width 0.1)
				(type default)
			)
			(layer "F.Fab")
		)
		(fp_line
			(start -0.32512 0.175006)
			(end -0.32512 -0.175006)
			(stroke
				(width 0.1)
				(type default)
			)
			(layer "F.Fab")
		)
		(fp_line
			(start 0.32512 -0.175006)
			(end 0.32512 0.175006)
			(stroke
				(width 0.1)
				(type default)
			)
			(layer "F.Fab")
		)
		(fp_line
			(start 0.32512 0.175006)
			(end -0.32512 0.175006)
			(stroke
				(width 0.1)
				(type default)
			)
			(layer "F.Fab")
		)
		(pad "1" smd rect
			(at -0.2667 0)
			(size 0.3048 0.381)
			(layers "F.Cu" "F.Mask" "F.Paste")
			(net "TEST2_RT_CPU1_P3")
		)
		(pad "2" smd rect
			(at 0.2667 0 180)
			(size 0.3048 0.381)
			(layers "F.Cu" "F.Mask" "F.Paste")
			(net "GND")
		)
	)
	(footprint ""
		(layer "F.Cu")
		(at 13.21816 -381.202438 90)
		(property "Reference" "PC6623"
			(at 0 0 90)
			(layer "F.SilkS")
			(hide yes)
			(effects
				(font
					(size 1.27 1.27)
				)
			)
		)
		(property "Value" ""
			(at 0 0 90)
			(layer "F.Fab")
			(effects
				(font
					(size 1.27 1.27)
				)
			)
		)
		(duplicate_pad_numbers_are_jumpers no)
		(fp_line
			(start 0.7874 -0.4064)
			(end 0.7874 0.4064)
			(stroke
				(width 0.1524)
				(type default)
			)
			(layer "F.SilkS")
		)
		(fp_line
			(start -0.7874 -0.4064)
			(end 0.7874 -0.4064)
			(stroke
				(width 0.1524)
				(type default)
			)
			(layer "F.SilkS")
		)
		(fp_line
			(start 0.7874 0.4064)
			(end -0.7874 0.4064)
			(stroke
				(width 0.1524)
				(type default)
			)
			(layer "F.SilkS")
		)
		(fp_line
			(start -0.7874 0.4064)
			(end -0.7874 -0.4064)
			(stroke
				(width 0.1524)
				(type default)
			)
			(layer "F.SilkS")
		)
		(fp_line
			(start -0.12065 -0.305054)
			(end -0.12065 -0.2794)
			(stroke
				(width 0.1)
				(type default)
			)
			(layer "F.Fab")
		)
		(fp_line
			(start -0.67945 -0.305054)
			(end -0.12065 -0.305054)
			(stroke
				(width 0.1)
				(type default)
			)
			(layer "F.Fab")
		)
		(fp_line
			(start 0.67945 -0.3048)
			(end 0.67945 0.3048)
			(stroke
				(width 0.1)
				(type default)
			)
			(layer "F.Fab")
		)
		(fp_line
			(start 0.12065 -0.3048)
			(end 0.67945 -0.3048)
			(stroke
				(width 0.1)
				(type default)
			)
			(layer "F.Fab")
		)
		(fp_line
			(start 0.12065 -0.2794)
			(end 0.12065 -0.3048)
			(stroke
				(width 0.1)
				(type default)
			)
			(layer "F.Fab")
		)
		(fp_line
			(start -0.12065 -0.2794)
			(end 0.12065 -0.2794)
			(stroke
				(width 0.1)
				(type default)
			)
			(layer "F.Fab")
		)
		(fp_line
			(start 0.120396 0.2794)
			(end -0.12065 0.2794)
			(stroke
				(width 0.1)
				(type default)
			)
			(layer "F.Fab")
		)
		(fp_line
			(start -0.12065 0.2794)
			(end -0.12065 0.3048)
			(stroke
				(width 0.1)
				(type default)
			)
			(layer "F.Fab")
		)
		(fp_line
			(start 0.67945 0.3048)
			(end 0.120396 0.3048)
			(stroke
				(width 0.1)
				(type default)
			)
			(layer "F.Fab")
		)
		(fp_line
			(start 0.120396 0.3048)
			(end 0.120396 0.2794)
			(stroke
				(width 0.1)
				(type default)
			)
			(layer "F.Fab")
		)
		(fp_line
			(start -0.12065 0.3048)
			(end -0.67945 0.3048)
			(stroke
				(width 0.1)
				(type default)
			)
			(layer "F.Fab")
		)
		(fp_line
			(start -0.67945 0.3048)
			(end -0.67945 -0.305054)
			(stroke
				(width 0.1)
				(type default)
			)
			(layer "F.Fab")
		)
		(pad "1" smd circle
			(at -0.40005 0 90)
			(size 0 0)
			(layers "F.Cu" "F.Mask" "F.Paste")
			(net "P0V9_CPU1_RT_2D")
		)
		(pad "2" smd circle
			(at 0.40005 0 90)
			(size 0 0)
			(layers "F.Cu" "F.Mask" "F.Paste")
			(net "GND")
		)
	)
	(footprint ""
		(layer "F.Cu")
		(at 432.01336 -361.827826 180)
		(property "Reference" "PC220"
			(at 1.87452 -2.965704 0)
			(unlocked yes)
			(layer "F.SilkS")
			(effects
				(font
					(size 0.7874 0.5842)
					(thickness 0.1524)
				)
				(justify left)
			)
		)
		(property "Value" ""
			(at 0 0 180)
			(layer "F.Fab")
			(effects
				(font
					(size 1.27 1.27)
				)
			)
		)
		(duplicate_pad_numbers_are_jumpers no)
		(fp_line
			(start -3.400044 1.249934)
			(end 3.400044 1.249934)
			(stroke
				(width 0.1524)
				(type default)
			)
			(layer "F.SilkS")
		)
		(fp_circle
			(center 0 1.249934)
			(end -3.400044 1.249934)
			(stroke
				(width 0.1524)
				(type default)
			)
			(fill no)
			(layer "F.SilkS")
		)
		(fp_poly
			(pts
				(arc
					(start 3.400044 1.249934)
					(mid 0 4.649978)
					(end -3.400044 1.249934)
				)
			)
			(stroke
				(width 0)
				(type default)
			)
			(fill yes)
			(layer "F.SilkS")
		)
		(fp_circle
			(center 0 1.249934)
			(end -3.400044 1.249934)
			(stroke
				(width 0.1)
				(type default)
			)
			(fill no)
			(layer "F.Fab")
		)
		(pad "1" thru_hole rect
			(at 0 0 180)
			(size 1.524 1.524)
			(drill 1.016)
			(layers "*.Cu" "*.Mask")
			(remove_unused_layers no)
			(net "SW_P12V_AUX_PVDD11_S3_P0_FLT")
			(clearance 0)
			(padstack
				(mode front_inner_back)
				(layer "Inner"
					(shape circle)
					(size 1.524 1.524)
					(clearance 0)
				)
				(layer "B.Cu"
					(shape rect)
					(size 1.524 1.524)
					(clearance 0)
				)
			)
		)
		(pad "2" thru_hole circle
			(at 0 2.500122 180)
			(size 1.524 1.524)
			(drill 1.016)
			(layers "*.Cu" "*.Mask")
			(remove_unused_layers no)
			(net "GND")
			(clearance 0)
		)
	)
	(footprint ""
		(layer "F.Cu")
		(at 449.955666 -380.13767 -90)
		(property "Reference" "PC6574"
			(at 4.75234 2.153666 0)
			(unlocked yes)
			(layer "F.SilkS")
			(effects
				(font
					(size 0.7874 0.5842)
					(thickness 0.1524)
				)
				(justify left)
			)
		)
		(property "Value" ""
			(at 0 0 270)
			(layer "F.Fab")
			(effects
				(font
					(size 1.27 1.27)
				)
			)
		)
		(duplicate_pad_numbers_are_jumpers no)
		(fp_line
			(start -1.988058 2.750058)
			(end 2.750058 2.750058)
			(stroke
				(width 0.1524)
				(type default)
			)
			(layer "F.SilkS")
		)
		(fp_line
			(start 2.750058 2.750058)
			(end 2.750058 0.9398)
			(stroke
				(width 0.1524)
				(type default)
			)
			(layer "F.SilkS")
		)
		(fp_line
			(start -2.750058 1.988058)
			(end -1.988058 2.750058)
			(stroke
				(width 0.1524)
				(type default)
			)
			(layer "F.SilkS")
		)
		(fp_line
			(start -2.750058 0.9398)
			(end -2.750058 1.988058)
			(stroke
				(width 0.1524)
				(type default)
			)
			(layer "F.SilkS")
		)
		(fp_line
			(start 2.750058 -0.9398)
			(end 2.750058 -2.750058)
			(stroke
				(width 0.1524)
				(type default)
			)
			(layer "F.SilkS")
		)
		(fp_line
			(start -2.750058 -1.988058)
			(end -2.750058 -0.9398)
			(stroke
				(width 0.1524)
				(type default)
			)
			(layer "F.SilkS")
		)
		(fp_line
			(start -1.988058 -2.750058)
			(end -2.750058 -1.988058)
			(stroke
				(width 0.1524)
				(type default)
			)
			(layer "F.SilkS")
		)
		(fp_line
			(start 2.750058 -2.750058)
			(end -1.988058 -2.750058)
			(stroke
				(width 0.1524)
				(type default)
			)
			(layer "F.SilkS")
		)
		(fp_line
			(start -2.750058 2.750058)
			(end 2.750058 2.750058)
			(stroke
				(width 0.1)
				(type default)
			)
			(layer "F.Fab")
		)
		(fp_line
			(start 2.750058 2.750058)
			(end 2.750058 -2.750058)
			(stroke
				(width 0.1)
				(type default)
			)
			(layer "F.Fab")
		)
		(fp_line
			(start -2.750058 -2.750058)
			(end -2.750058 2.750058)
			(stroke
				(width 0.1)
				(type default)
			)
			(layer "F.Fab")
		)
		(fp_line
			(start 2.750058 -2.750058)
			(end -2.750058 -2.750058)
			(stroke
				(width 0.1)
				(type default)
			)
			(layer "F.Fab")
		)
		(pad "1" smd rect
			(at -2.199894 0)
			(size 1.6002 3.0226)
			(layers "F.Cu" "F.Mask" "F.Paste")
			(net "P0V9_CPU0_RT_2D")
		)
		(pad "2" smd rect
			(at 2.199894 0)
			(size 1.6002 3.0226)
			(layers "F.Cu" "F.Mask" "F.Paste")
			(net "GND")
		)
	)
	(footprint ""
		(layer "F.Cu")
		(at 239.374426 -294.978074 90)
		(property "Reference" "PC6507"
			(at 0 0 90)
			(layer "F.SilkS")
			(hide yes)
			(effects
				(font
					(size 1.27 1.27)
				)
			)
		)
		(property "Value" ""
			(at 0 0 90)
			(layer "F.Fab")
			(effects
				(font
					(size 1.27 1.27)
				)
			)
		)
		(duplicate_pad_numbers_are_jumpers no)
		(fp_line
			(start 0.7874 -0.4064)
			(end 0.7874 0.4064)
			(stroke
				(width 0.1524)
				(type default)
			)
			(layer "F.SilkS")
		)
		(fp_line
			(start -0.7874 -0.4064)
			(end 0.7874 -0.4064)
			(stroke
				(width 0.1524)
				(type default)
			)
			(layer "F.SilkS")
		)
		(fp_line
			(start 0.7874 0.4064)
			(end -0.7874 0.4064)
			(stroke
				(width 0.1524)
				(type default)
			)
			(layer "F.SilkS")
		)
		(fp_line
			(start -0.7874 0.4064)
			(end -0.7874 -0.4064)
			(stroke
				(width 0.1524)
				(type default)
			)
			(layer "F.SilkS")
		)
		(fp_line
			(start -0.12065 -0.305054)
			(end -0.12065 -0.2794)
			(stroke
				(width 0.1)
				(type default)
			)
			(layer "F.Fab")
		)
		(fp_line
			(start -0.67945 -0.305054)
			(end -0.12065 -0.305054)
			(stroke
				(width 0.1)
				(type default)
			)
			(layer "F.Fab")
		)
		(fp_line
			(start 0.67945 -0.3048)
			(end 0.67945 0.3048)
			(stroke
				(width 0.1)
				(type default)
			)
			(layer "F.Fab")
		)
		(fp_line
			(start 0.12065 -0.3048)
			(end 0.67945 -0.3048)
			(stroke
				(width 0.1)
				(type default)
			)
			(layer "F.Fab")
		)
		(fp_line
			(start 0.12065 -0.2794)
			(end 0.12065 -0.3048)
			(stroke
				(width 0.1)
				(type default)
			)
			(layer "F.Fab")
		)
		(fp_line
			(start -0.12065 -0.2794)
			(end 0.12065 -0.2794)
			(stroke
				(width 0.1)
				(type default)
			)
			(layer "F.Fab")
		)
		(fp_line
			(start 0.120396 0.2794)
			(end -0.12065 0.2794)
			(stroke
				(width 0.1)
				(type default)
			)
			(layer "F.Fab")
		)
		(fp_line
			(start -0.12065 0.2794)
			(end -0.12065 0.3048)
			(stroke
				(width 0.1)
				(type default)
			)
			(layer "F.Fab")
		)
		(fp_line
			(start 0.67945 0.3048)
			(end 0.120396 0.3048)
			(stroke
				(width 0.1)
				(type default)
			)
			(layer "F.Fab")
		)
		(fp_line
			(start 0.120396 0.3048)
			(end 0.120396 0.2794)
			(stroke
				(width 0.1)
				(type default)
			)
			(layer "F.Fab")
		)
		(fp_line
			(start -0.12065 0.3048)
			(end -0.67945 0.3048)
			(stroke
				(width 0.1)
				(type default)
			)
			(layer "F.Fab")
		)
		(fp_line
			(start -0.67945 0.3048)
			(end -0.67945 -0.305054)
			(stroke
				(width 0.1)
				(type default)
			)
			(layer "F.Fab")
		)
		(pad "1" smd circle
			(at -0.40005 0 90)
			(size 0 0)
			(layers "F.Cu" "F.Mask" "F.Paste")
			(net "SW_P1V8_RETIMER_CPU0_BST_R")
		)
		(pad "2" smd circle
			(at 0.40005 0 90)
			(size 0 0)
			(layers "F.Cu" "F.Mask" "F.Paste")
			(net "SW_P1V8_RETIMER_CPU0_SW")
		)
	)
	(footprint ""
		(layer "F.Cu")
		(at 98.550222 -36.305998)
		(property "Reference" "C1824"
			(at 0 0 0)
			(layer "F.SilkS")
			(hide yes)
			(effects
				(font
					(size 1.27 1.27)
				)
			)
		)
		(property "Value" ""
			(at 0 0 0)
			(layer "F.Fab")
			(effects
				(font
					(size 1.27 1.27)
				)
			)
		)
		(duplicate_pad_numbers_are_jumpers no)
		(fp_line
			(start -0.7874 -0.4064)
			(end 0.7874 -0.4064)
			(stroke
				(width 0.1524)
				(type default)
			)
			(layer "F.SilkS")
		)
		(fp_line
			(start -0.7874 0.4064)
			(end -0.7874 -0.4064)
			(stroke
				(width 0.1524)
				(type default)
			)
			(layer "F.SilkS")
		)
		(fp_line
			(start 0.7874 -0.4064)
			(end 0.7874 0.4064)
			(stroke
				(width 0.1524)
				(type default)
			)
			(layer "F.SilkS")
		)
		(fp_line
			(start 0.7874 0.4064)
			(end -0.7874 0.4064)
			(stroke
				(width 0.1524)
				(type default)
			)
			(layer "F.SilkS")
		)
		(fp_line
			(start -0.67945 -0.305054)
			(end -0.12065 -0.305054)
			(stroke
				(width 0.1)
				(type default)
			)
			(layer "F.Fab")
		)
		(fp_line
			(start -0.67945 0.3048)
			(end -0.67945 -0.305054)
			(stroke
				(width 0.1)
				(type default)
			)
			(layer "F.Fab")
		)
		(fp_line
			(start -0.12065 -0.305054)
			(end -0.12065 -0.2794)
			(stroke
				(width 0.1)
				(type default)
			)
			(layer "F.Fab")
		)
		(fp_line
			(start -0.12065 -0.2794)
			(end 0.12065 -0.2794)
			(stroke
				(width 0.1)
				(type default)
			)
			(layer "F.Fab")
		)
		(fp_line
			(start -0.12065 0.2794)
			(end -0.12065 0.3048)
			(stroke
				(width 0.1)
				(type default)
			)
			(layer "F.Fab")
		)
		(fp_line
			(start -0.12065 0.3048)
			(end -0.67945 0.3048)
			(stroke
				(width 0.1)
				(type default)
			)
			(layer "F.Fab")
		)
		(fp_line
			(start 0.120396 0.2794)
			(end -0.12065 0.2794)
			(stroke
				(width 0.1)
				(type default)
			)
			(layer "F.Fab")
		)
		(fp_line
			(start 0.120396 0.3048)
			(end 0.120396 0.2794)
			(stroke
				(width 0.1)
				(type default)
			)
			(layer "F.Fab")
		)
		(fp_line
			(start 0.12065 -0.3048)
			(end 0.67945 -0.3048)
			(stroke
				(width 0.1)
				(type default)
			)
			(layer "F.Fab")
		)
		(fp_line
			(start 0.12065 -0.2794)
			(end 0.12065 -0.3048)
			(stroke
				(width 0.1)
				(type default)
			)
			(layer "F.Fab")
		)
		(fp_line
			(start 0.67945 -0.3048)
			(end 0.67945 0.3048)
			(stroke
				(width 0.1)
				(type default)
			)
			(layer "F.Fab")
		)
		(fp_line
			(start 0.67945 0.3048)
			(end 0.120396 0.3048)
			(stroke
				(width 0.1)
				(type default)
			)
			(layer "F.Fab")
		)
		(pad "1" smd circle
			(at -0.40005 0)
			(size 0 0)
			(layers "F.Cu" "F.Mask" "F.Paste")
			(net "P3V3_AUX")
		)
		(pad "2" smd circle
			(at 0.40005 0)
			(size 0 0)
			(layers "F.Cu" "F.Mask" "F.Paste")
			(net "GND")
		)
	)
	(footprint ""
		(layer "F.Cu")
		(at 178.71694 -398.404842 180)
		(property "Reference" "PR1133"
			(at 0 0 180)
			(layer "F.SilkS")
			(hide yes)
			(effects
				(font
					(size 1.27 1.27)
				)
			)
		)
		(property "Value" ""
			(at 0 0 180)
			(layer "F.Fab")
			(effects
				(font
					(size 1.27 1.27)
				)
			)
		)
		(duplicate_pad_numbers_are_jumpers no)
		(fp_line
			(start 0.7874 0.4064)
			(end -0.7874 0.4064)
			(stroke
				(width 0.1524)
				(type default)
			)
			(layer "F.SilkS")
		)
		(fp_line
			(start 0.7874 -0.4064)
			(end 0.7874 0.4064)
			(stroke
				(width 0.1524)
				(type default)
			)
			(layer "F.SilkS")
		)
		(fp_line
			(start -0.7874 0.4064)
			(end -0.7874 -0.4064)
			(stroke
				(width 0.1524)
				(type default)
			)
			(layer "F.SilkS")
		)
		(fp_line
			(start -0.7874 -0.4064)
			(end 0.7874 -0.4064)
			(stroke
				(width 0.1524)
				(type default)
			)
			(layer "F.SilkS")
		)
		(fp_line
			(start 0.67945 0.3048)
			(end 0.120396 0.3048)
			(stroke
				(width 0.1)
				(type default)
			)
			(layer "F.Fab")
		)
		(fp_line
			(start 0.67945 -0.3048)
			(end 0.67945 0.3048)
			(stroke
				(width 0.1)
				(type default)
			)
			(layer "F.Fab")
		)
		(fp_line
			(start 0.12065 -0.2794)
			(end 0.12065 -0.3048)
			(stroke
				(width 0.1)
				(type default)
			)
			(layer "F.Fab")
		)
		(fp_line
			(start 0.12065 -0.3048)
			(end 0.67945 -0.3048)
			(stroke
				(width 0.1)
				(type default)
			)
			(layer "F.Fab")
		)
		(fp_line
			(start 0.120396 0.3048)
			(end 0.120396 0.2794)
			(stroke
				(width 0.1)
				(type default)
			)
			(layer "F.Fab")
		)
		(fp_line
			(start 0.120396 0.2794)
			(end -0.12065 0.2794)
			(stroke
				(width 0.1)
				(type default)
			)
			(layer "F.Fab")
		)
		(fp_line
			(start -0.12065 0.3048)
			(end -0.67945 0.3048)
			(stroke
				(width 0.1)
				(type default)
			)
			(layer "F.Fab")
		)
		(fp_line
			(start -0.12065 0.2794)
			(end -0.12065 0.3048)
			(stroke
				(width 0.1)
				(type default)
			)
			(layer "F.Fab")
		)
		(fp_line
			(start -0.12065 -0.2794)
			(end 0.12065 -0.2794)
			(stroke
				(width 0.1)
				(type default)
			)
			(layer "F.Fab")
		)
		(fp_line
			(start -0.12065 -0.305054)
			(end -0.12065 -0.2794)
			(stroke
				(width 0.1)
				(type default)
			)
			(layer "F.Fab")
		)
		(fp_line
			(start -0.67945 0.3048)
			(end -0.67945 -0.305054)
			(stroke
				(width 0.1)
				(type default)
			)
			(layer "F.Fab")
		)
		(fp_line
			(start -0.67945 -0.305054)
			(end -0.12065 -0.305054)
			(stroke
				(width 0.1)
				(type default)
			)
			(layer "F.Fab")
		)
		(pad "1" smd circle
			(at -0.40005 0 180)
			(size 0 0)
			(layers "F.Cu" "F.Mask" "F.Paste")
			(net "HSC_IMON")
		)
		(pad "2" smd circle
			(at 0.40005 0 180)
			(size 0 0)
			(layers "F.Cu" "F.Mask" "F.Paste")
			(net "AGND_HSC")
		)
	)
	(footprint ""
		(layer "F.Cu")
		(at 386.211826 -58.7375 180)
		(property "Reference" "R1628"
			(at 0 0 180)
			(layer "F.SilkS")
			(hide yes)
			(effects
				(font
					(size 1.27 1.27)
				)
			)
		)
		(property "Value" ""
			(at 0 0 180)
			(layer "F.Fab")
			(effects
				(font
					(size 1.27 1.27)
				)
			)
		)
		(duplicate_pad_numbers_are_jumpers no)
		(fp_line
			(start 0.7874 0.4064)
			(end -0.7874 0.4064)
			(stroke
				(width 0.1524)
				(type default)
			)
			(layer "F.SilkS")
		)
		(fp_line
			(start 0.7874 -0.4064)
			(end 0.7874 0.4064)
			(stroke
				(width 0.1524)
				(type default)
			)
			(layer "F.SilkS")
		)
		(fp_line
			(start -0.7874 0.4064)
			(end -0.7874 -0.4064)
			(stroke
				(width 0.1524)
				(type default)
			)
			(layer "F.SilkS")
		)
		(fp_line
			(start -0.7874 -0.4064)
			(end 0.7874 -0.4064)
			(stroke
				(width 0.1524)
				(type default)
			)
			(layer "F.SilkS")
		)
		(fp_line
			(start 0.67945 0.3048)
			(end 0.120396 0.3048)
			(stroke
				(width 0.1)
				(type default)
			)
			(layer "F.Fab")
		)
		(fp_line
			(start 0.67945 -0.3048)
			(end 0.67945 0.3048)
			(stroke
				(width 0.1)
				(type default)
			)
			(layer "F.Fab")
		)
		(fp_line
			(start 0.12065 -0.2794)
			(end 0.12065 -0.3048)
			(stroke
				(width 0.1)
				(type default)
			)
			(layer "F.Fab")
		)
		(fp_line
			(start 0.12065 -0.3048)
			(end 0.67945 -0.3048)
			(stroke
				(width 0.1)
				(type default)
			)
			(layer "F.Fab")
		)
		(fp_line
			(start 0.120396 0.3048)
			(end 0.120396 0.2794)
			(stroke
				(width 0.1)
				(type default)
			)
			(layer "F.Fab")
		)
		(fp_line
			(start 0.120396 0.2794)
			(end -0.12065 0.2794)
			(stroke
				(width 0.1)
				(type default)
			)
			(layer "F.Fab")
		)
		(fp_line
			(start -0.12065 0.3048)
			(end -0.67945 0.3048)
			(stroke
				(width 0.1)
				(type default)
			)
			(layer "F.Fab")
		)
		(fp_line
			(start -0.12065 0.2794)
			(end -0.12065 0.3048)
			(stroke
				(width 0.1)
				(type default)
			)
			(layer "F.Fab")
		)
		(fp_line
			(start -0.12065 -0.2794)
			(end 0.12065 -0.2794)
			(stroke
				(width 0.1)
				(type default)
			)
			(layer "F.Fab")
		)
		(fp_line
			(start -0.12065 -0.305054)
			(end -0.12065 -0.2794)
			(stroke
				(width 0.1)
				(type default)
			)
			(layer "F.Fab")
		)
		(fp_line
			(start -0.67945 0.3048)
			(end -0.67945 -0.305054)
			(stroke
				(width 0.1)
				(type default)
			)
			(layer "F.Fab")
		)
		(fp_line
			(start -0.67945 -0.305054)
			(end -0.12065 -0.305054)
			(stroke
				(width 0.1)
				(type default)
			)
			(layer "F.Fab")
		)
		(pad "1" smd circle
			(at -0.40005 0 180)
			(size 0 0)
			(layers "F.Cu" "F.Mask" "F.Paste")
			(net "PVDD18_S5_P0")
		)
		(pad "2" smd circle
			(at 0.40005 0 180)
			(size 0 0)
			(layers "F.Cu" "F.Mask" "F.Paste")
			(net "HDT_HDR_TDO")
		)
	)
	(footprint ""
		(layer "F.Cu")
		(at 191.135 -137.632948 90)
		(property "Reference" "R937"
			(at 0 0 90)
			(layer "F.SilkS")
			(hide yes)
			(effects
				(font
					(size 1.27 1.27)
				)
			)
		)
		(property "Value" ""
			(at 0 0 90)
			(layer "F.Fab")
			(effects
				(font
					(size 1.27 1.27)
				)
			)
		)
		(duplicate_pad_numbers_are_jumpers no)
		(fp_line
			(start 0.7874 -0.4064)
			(end 0.7874 0.4064)
			(stroke
				(width 0.1524)
				(type default)
			)
			(layer "F.SilkS")
		)
		(fp_line
			(start -0.7874 -0.4064)
			(end 0.7874 -0.4064)
			(stroke
				(width 0.1524)
				(type default)
			)
			(layer "F.SilkS")
		)
		(fp_line
			(start 0.7874 0.4064)
			(end -0.7874 0.4064)
			(stroke
				(width 0.1524)
				(type default)
			)
			(layer "F.SilkS")
		)
		(fp_line
			(start -0.7874 0.4064)
			(end -0.7874 -0.4064)
			(stroke
				(width 0.1524)
				(type default)
			)
			(layer "F.SilkS")
		)
		(fp_line
			(start -0.12065 -0.305054)
			(end -0.12065 -0.2794)
			(stroke
				(width 0.1)
				(type default)
			)
			(layer "F.Fab")
		)
		(fp_line
			(start -0.67945 -0.305054)
			(end -0.12065 -0.305054)
			(stroke
				(width 0.1)
				(type default)
			)
			(layer "F.Fab")
		)
		(fp_line
			(start 0.67945 -0.3048)
			(end 0.67945 0.3048)
			(stroke
				(width 0.1)
				(type default)
			)
			(layer "F.Fab")
		)
		(fp_line
			(start 0.12065 -0.3048)
			(end 0.67945 -0.3048)
			(stroke
				(width 0.1)
				(type default)
			)
			(layer "F.Fab")
		)
		(fp_line
			(start 0.12065 -0.2794)
			(end 0.12065 -0.3048)
			(stroke
				(width 0.1)
				(type default)
			)
			(layer "F.Fab")
		)
		(fp_line
			(start -0.12065 -0.2794)
			(end 0.12065 -0.2794)
			(stroke
				(width 0.1)
				(type default)
			)
			(layer "F.Fab")
		)
		(fp_line
			(start 0.120396 0.2794)
			(end -0.12065 0.2794)
			(stroke
				(width 0.1)
				(type default)
			)
			(layer "F.Fab")
		)
		(fp_line
			(start -0.12065 0.2794)
			(end -0.12065 0.3048)
			(stroke
				(width 0.1)
				(type default)
			)
			(layer "F.Fab")
		)
		(fp_line
			(start 0.67945 0.3048)
			(end 0.120396 0.3048)
			(stroke
				(width 0.1)
				(type default)
			)
			(layer "F.Fab")
		)
		(fp_line
			(start 0.120396 0.3048)
			(end 0.120396 0.2794)
			(stroke
				(width 0.1)
				(type default)
			)
			(layer "F.Fab")
		)
		(fp_line
			(start -0.12065 0.3048)
			(end -0.67945 0.3048)
			(stroke
				(width 0.1)
				(type default)
			)
			(layer "F.Fab")
		)
		(fp_line
			(start -0.67945 0.3048)
			(end -0.67945 -0.305054)
			(stroke
				(width 0.1)
				(type default)
			)
			(layer "F.Fab")
		)
		(pad "1" smd circle
			(at -0.40005 0 90)
			(size 0 0)
			(layers "F.Cu" "F.Mask" "F.Paste")
			(net "FM_BIOS_POST_CMPLT_BUF_R_N")
		)
		(pad "2" smd circle
			(at 0.40005 0 90)
			(size 0 0)
			(layers "F.Cu" "F.Mask" "F.Paste")
			(net "FM_BIOS_POST_CMPLT_BUF_N")
		)
	)
	(footprint ""
		(layer "F.Cu")
		(at 297.486324 -117.942614 180)
		(property "Reference" "R3396"
			(at 0 0 180)
			(layer "F.SilkS")
			(hide yes)
			(effects
				(font
					(size 1.27 1.27)
				)
			)
		)
		(property "Value" ""
			(at 0 0 180)
			(layer "F.Fab")
			(effects
				(font
					(size 1.27 1.27)
				)
			)
		)
		(duplicate_pad_numbers_are_jumpers no)
		(fp_line
			(start 0.7874 0.4064)
			(end -0.7874 0.4064)
			(stroke
				(width 0.1524)
				(type default)
			)
			(layer "F.SilkS")
		)
		(fp_line
			(start 0.7874 -0.4064)
			(end 0.7874 0.4064)
			(stroke
				(width 0.1524)
				(type default)
			)
			(layer "F.SilkS")
		)
		(fp_line
			(start -0.7874 0.4064)
			(end -0.7874 -0.4064)
			(stroke
				(width 0.1524)
				(type default)
			)
			(layer "F.SilkS")
		)
		(fp_line
			(start -0.7874 -0.4064)
			(end 0.7874 -0.4064)
			(stroke
				(width 0.1524)
				(type default)
			)
			(layer "F.SilkS")
		)
		(fp_line
			(start 0.67945 0.3048)
			(end 0.120396 0.3048)
			(stroke
				(width 0.1)
				(type default)
			)
			(layer "F.Fab")
		)
		(fp_line
			(start 0.67945 -0.3048)
			(end 0.67945 0.3048)
			(stroke
				(width 0.1)
				(type default)
			)
			(layer "F.Fab")
		)
		(fp_line
			(start 0.12065 -0.2794)
			(end 0.12065 -0.3048)
			(stroke
				(width 0.1)
				(type default)
			)
			(layer "F.Fab")
		)
		(fp_line
			(start 0.12065 -0.3048)
			(end 0.67945 -0.3048)
			(stroke
				(width 0.1)
				(type default)
			)
			(layer "F.Fab")
		)
		(fp_line
			(start 0.120396 0.3048)
			(end 0.120396 0.2794)
			(stroke
				(width 0.1)
				(type default)
			)
			(layer "F.Fab")
		)
		(fp_line
			(start 0.120396 0.2794)
			(end -0.12065 0.2794)
			(stroke
				(width 0.1)
				(type default)
			)
			(layer "F.Fab")
		)
		(fp_line
			(start -0.12065 0.3048)
			(end -0.67945 0.3048)
			(stroke
				(width 0.1)
				(type default)
			)
			(layer "F.Fab")
		)
		(fp_line
			(start -0.12065 0.2794)
			(end -0.12065 0.3048)
			(stroke
				(width 0.1)
				(type default)
			)
			(layer "F.Fab")
		)
		(fp_line
			(start -0.12065 -0.2794)
			(end 0.12065 -0.2794)
			(stroke
				(width 0.1)
				(type default)
			)
			(layer "F.Fab")
		)
		(fp_line
			(start -0.12065 -0.305054)
			(end -0.12065 -0.2794)
			(stroke
				(width 0.1)
				(type default)
			)
			(layer "F.Fab")
		)
		(fp_line
			(start -0.67945 0.3048)
			(end -0.67945 -0.305054)
			(stroke
				(width 0.1)
				(type default)
			)
			(layer "F.Fab")
		)
		(fp_line
			(start -0.67945 -0.305054)
			(end -0.12065 -0.305054)
			(stroke
				(width 0.1)
				(type default)
			)
			(layer "F.Fab")
		)
		(pad "1" smd circle
			(at -0.40005 0 180)
			(size 0 0)
			(layers "F.Cu" "F.Mask" "F.Paste")
			(net "P3V3_AUX")
		)
		(pad "2" smd circle
			(at 0.40005 0 180)
			(size 0 0)
			(layers "F.Cu" "F.Mask" "F.Paste")
			(net "SMB_INA230_3V3AUX_SDA")
		)
	)
	(footprint ""
		(layer "F.Cu")
		(at 366.089692 -381.41783 -90)
		(property "Reference" "C897"
			(at 0 0 270)
			(layer "F.SilkS")
			(hide yes)
			(effects
				(font
					(size 1.27 1.27)
				)
			)
		)
		(property "Value" ""
			(at 0 0 270)
			(layer "F.Fab")
			(effects
				(font
					(size 1.27 1.27)
				)
			)
		)
		(duplicate_pad_numbers_are_jumpers no)
		(fp_line
			(start -0.299974 0.150114)
			(end -0.299974 -0.150114)
			(stroke
				(width 0.1)
				(type default)
			)
			(layer "F.Fab")
		)
		(fp_line
			(start 0.299974 0.150114)
			(end -0.299974 0.150114)
			(stroke
				(width 0.1)
				(type default)
			)
			(layer "F.Fab")
		)
		(fp_line
			(start -0.299974 -0.150114)
			(end 0.299974 -0.150114)
			(stroke
				(width 0.1)
				(type default)
			)
			(layer "F.Fab")
		)
		(fp_line
			(start 0.299974 -0.150114)
			(end 0.299974 0.150114)
			(stroke
				(width 0.1)
				(type default)
			)
			(layer "F.Fab")
		)
		(pad "1" smd rect
			(at -0.2667 0 270)
			(size 0.3048 0.381)
			(layers "F.Cu" "F.Mask" "F.Paste")
			(net "P5E_CPU0_P3_TX_C_DP<2>")
		)
		(pad "2" smd rect
			(at 0.2667 0 270)
			(size 0.3048 0.381)
			(layers "F.Cu" "F.Mask" "F.Paste")
			(net "P5E_CPU0_P3_TX_DP<2>")
		)
	)
	(footprint ""
		(layer "F.Cu")
		(at 326.81926 -325.656448)
		(property "Reference" "PL11"
			(at 0.313944 -15.887446 0)
			(unlocked yes)
			(layer "F.SilkS")
			(effects
				(font
					(size 0.7874 0.5842)
					(thickness 0.1524)
				)
				(justify left)
			)
		)
		(property "Value" ""
			(at 0 0 0)
			(layer "F.Fab")
			(effects
				(font
					(size 1.27 1.27)
				)
			)
		)
		(duplicate_pad_numbers_are_jumpers no)
		(fp_line
			(start -3.750056 -5.500116)
			(end -2.393442 -5.500116)
			(stroke
				(width 0.1524)
				(type default)
			)
			(layer "F.SilkS")
		)
		(fp_line
			(start -3.750056 5.500116)
			(end -3.750056 -5.500116)
			(stroke
				(width 0.1524)
				(type default)
			)
			(layer "F.SilkS")
		)
		(fp_line
			(start -2.393442 5.500116)
			(end -3.750056 5.500116)
			(stroke
				(width 0.1524)
				(type default)
			)
			(layer "F.SilkS")
		)
		(fp_line
			(start 2.393442 5.500116)
			(end 3.750056 5.500116)
			(stroke
				(width 0.1524)
				(type default)
			)
			(layer "F.SilkS")
		)
		(fp_line
			(start 3.750056 -5.500116)
			(end 2.393442 -5.500116)
			(stroke
				(width 0.1524)
				(type default)
			)
			(layer "F.SilkS")
		)
		(fp_line
			(start 3.750056 5.500116)
			(end 3.750056 -5.500116)
			(stroke
				(width 0.1524)
				(type default)
			)
			(layer "F.SilkS")
		)
		(fp_poly
			(pts
				(xy -3.9116 -4.249928) (xy -4.3434 -4.034028) (xy -4.3434 -4.465828)
			)
			(stroke
				(width 0)
				(type default)
			)
			(fill yes)
			(layer "F.SilkS")
		)
		(fp_line
			(start -3.750056 -5.500116)
			(end -3.750056 5.500116)
			(stroke
				(width 0.1)
				(type default)
			)
			(layer "F.Fab")
		)
		(fp_line
			(start -3.750056 5.500116)
			(end 3.750056 5.500116)
			(stroke
				(width 0.1)
				(type default)
			)
			(layer "F.Fab")
		)
		(fp_line
			(start 3.750056 -5.500116)
			(end -3.750056 -5.500116)
			(stroke
				(width 0.1)
				(type default)
			)
			(layer "F.Fab")
		)
		(fp_line
			(start 3.750056 5.500116)
			(end 3.750056 -5.500116)
			(stroke
				(width 0.1)
				(type default)
			)
			(layer "F.Fab")
		)
		(fp_poly
			(pts
				(xy -4.9276 -4.757928) (xy -4.9276 -3.741928) (xy -3.9116 -4.249928)
			)
			(stroke
				(width 0)
				(type default)
			)
			(fill yes)
			(layer "F.Fab")
		)
		(pad "1" smd rect
			(at 0 -4.249928 270)
			(size 2.413 4.5212)
			(layers "F.Cu" "F.Mask" "F.Paste")
			(net "SW_PVDDCR_CPU1_P0_SW2")
		)
		(pad "2" smd rect
			(at 0 -1.175004 270)
			(size 1.3716 4.5212)
			(layers "F.Cu" "F.Mask" "F.Paste")
			(net "IND_CPU1_P0_CPL1")
		)
		(pad "3" smd rect
			(at 0 1.175004 270)
			(size 1.3716 4.5212)
			(layers "F.Cu" "F.Mask" "F.Paste")
			(net "IND_CPU1_P0_CPL2")
		)
		(pad "4" smd rect
			(at 0 4.249928 270)
			(size 2.413 4.5212)
			(layers "F.Cu" "F.Mask" "F.Paste")
			(net "PVDDCR_CPU1_P0")
		)
	)
	(footprint ""
		(layer "F.Cu")
		(at 105.222548 -385.5212 90)
		(property "Reference" "R745"
			(at 0 0 90)
			(layer "F.SilkS")
			(hide yes)
			(effects
				(font
					(size 1.27 1.27)
				)
			)
		)
		(property "Value" ""
			(at 0 0 90)
			(layer "F.Fab")
			(effects
				(font
					(size 1.27 1.27)
				)
			)
		)
		(duplicate_pad_numbers_are_jumpers no)
		(fp_line
			(start 0.32512 -0.175006)
			(end 0.32512 0.175006)
			(stroke
				(width 0.1)
				(type default)
			)
			(layer "F.Fab")
		)
		(fp_line
			(start -0.32512 -0.175006)
			(end 0.32512 -0.175006)
			(stroke
				(width 0.1)
				(type default)
			)
			(layer "F.Fab")
		)
		(fp_line
			(start 0.32512 0.175006)
			(end -0.32512 0.175006)
			(stroke
				(width 0.1)
				(type default)
			)
			(layer "F.Fab")
		)
		(fp_line
			(start -0.32512 0.175006)
			(end -0.32512 -0.175006)
			(stroke
				(width 0.1)
				(type default)
			)
			(layer "F.Fab")
		)
		(pad "1" smd rect
			(at -0.2667 0 90)
			(size 0.3048 0.381)
			(layers "F.Cu" "F.Mask" "F.Paste")
			(net "P1V8_CPU1_RT_1D")
		)
		(pad "2" smd rect
			(at 0.2667 0 270)
			(size 0.3048 0.381)
			(layers "F.Cu" "F.Mask" "F.Paste")
			(net "RT_CPU1_P1_ADDR2")
		)
	)
	(footprint ""
		(layer "F.Cu")
		(at 409.450794 -142.009368 180)
		(property "Reference" "PR8089"
			(at 0 0 180)
			(layer "F.SilkS")
			(hide yes)
			(effects
				(font
					(size 1.27 1.27)
				)
			)
		)
		(property "Value" ""
			(at 0 0 180)
			(layer "F.Fab")
			(effects
				(font
					(size 1.27 1.27)
				)
			)
		)
		(duplicate_pad_numbers_are_jumpers no)
		(fp_line
			(start 0.7874 0.4064)
			(end -0.7874 0.4064)
			(stroke
				(width 0.1524)
				(type default)
			)
			(layer "F.SilkS")
		)
		(fp_line
			(start 0.7874 -0.4064)
			(end 0.7874 0.4064)
			(stroke
				(width 0.1524)
				(type default)
			)
			(layer "F.SilkS")
		)
		(fp_line
			(start -0.7874 0.4064)
			(end -0.7874 -0.4064)
			(stroke
				(width 0.1524)
				(type default)
			)
			(layer "F.SilkS")
		)
		(fp_line
			(start -0.7874 -0.4064)
			(end 0.7874 -0.4064)
			(stroke
				(width 0.1524)
				(type default)
			)
			(layer "F.SilkS")
		)
		(fp_line
			(start 0.67945 0.3048)
			(end 0.120396 0.3048)
			(stroke
				(width 0.1)
				(type default)
			)
			(layer "F.Fab")
		)
		(fp_line
			(start 0.67945 -0.3048)
			(end 0.67945 0.3048)
			(stroke
				(width 0.1)
				(type default)
			)
			(layer "F.Fab")
		)
		(fp_line
			(start 0.12065 -0.2794)
			(end 0.12065 -0.3048)
			(stroke
				(width 0.1)
				(type default)
			)
			(layer "F.Fab")
		)
		(fp_line
			(start 0.12065 -0.3048)
			(end 0.67945 -0.3048)
			(stroke
				(width 0.1)
				(type default)
			)
			(layer "F.Fab")
		)
		(fp_line
			(start 0.120396 0.3048)
			(end 0.120396 0.2794)
			(stroke
				(width 0.1)
				(type default)
			)
			(layer "F.Fab")
		)
		(fp_line
			(start 0.120396 0.2794)
			(end -0.12065 0.2794)
			(stroke
				(width 0.1)
				(type default)
			)
			(layer "F.Fab")
		)
		(fp_line
			(start -0.12065 0.3048)
			(end -0.67945 0.3048)
			(stroke
				(width 0.1)
				(type default)
			)
			(layer "F.Fab")
		)
		(fp_line
			(start -0.12065 0.2794)
			(end -0.12065 0.3048)
			(stroke
				(width 0.1)
				(type default)
			)
			(layer "F.Fab")
		)
		(fp_line
			(start -0.12065 -0.2794)
			(end 0.12065 -0.2794)
			(stroke
				(width 0.1)
				(type default)
			)
			(layer "F.Fab")
		)
		(fp_line
			(start -0.12065 -0.305054)
			(end -0.12065 -0.2794)
			(stroke
				(width 0.1)
				(type default)
			)
			(layer "F.Fab")
		)
		(fp_line
			(start -0.67945 0.3048)
			(end -0.67945 -0.305054)
			(stroke
				(width 0.1)
				(type default)
			)
			(layer "F.Fab")
		)
		(fp_line
			(start -0.67945 -0.305054)
			(end -0.12065 -0.305054)
			(stroke
				(width 0.1)
				(type default)
			)
			(layer "F.Fab")
		)
		(pad "1" smd circle
			(at -0.40005 0 180)
			(size 0 0)
			(layers "F.Cu" "F.Mask" "F.Paste")
			(net "P5V_AUX_CS")
		)
		(pad "2" smd circle
			(at 0.40005 0 180)
			(size 0 0)
			(layers "F.Cu" "F.Mask" "F.Paste")
			(net "GND")
		)
	)
	(footprint ""
		(layer "F.Cu")
		(at 423.64406 -342.281764 -90)
		(property "Reference" "PL23"
			(at -2.142236 4.77139 90)
			(unlocked yes)
			(layer "F.SilkS")
			(effects
				(font
					(size 0.7874 0.5842)
					(thickness 0.1524)
				)
				(justify left)
			)
		)
		(property "Value" ""
			(at 0 0 270)
			(layer "F.Fab")
			(effects
				(font
					(size 1.27 1.27)
				)
			)
		)
		(duplicate_pad_numbers_are_jumpers no)
		(fp_line
			(start -4.99999 3.849878)
			(end -4.99999 2.23901)
			(stroke
				(width 0.1524)
				(type default)
			)
			(layer "F.SilkS")
		)
		(fp_line
			(start 4.99999 3.849878)
			(end -4.99999 3.849878)
			(stroke
				(width 0.1524)
				(type default)
			)
			(layer "F.SilkS")
		)
		(fp_line
			(start 4.99999 2.23901)
			(end 4.99999 3.849878)
			(stroke
				(width 0.1524)
				(type default)
			)
			(layer "F.SilkS")
		)
		(fp_line
			(start -4.99999 -2.23901)
			(end -4.99999 -3.849878)
			(stroke
				(width 0.1524)
				(type default)
			)
			(layer "F.SilkS")
		)
		(fp_line
			(start -4.99999 -3.849878)
			(end 4.99999 -3.849878)
			(stroke
				(width 0.1524)
				(type default)
			)
			(layer "F.SilkS")
		)
		(fp_line
			(start 4.99999 -3.849878)
			(end 4.99999 -2.23901)
			(stroke
				(width 0.1524)
				(type default)
			)
			(layer "F.SilkS")
		)
		(fp_line
			(start -4.99999 3.849878)
			(end -4.99999 -3.849878)
			(stroke
				(width 0.1)
				(type default)
			)
			(layer "F.Fab")
		)
		(fp_line
			(start 4.99999 3.849878)
			(end -4.99999 3.849878)
			(stroke
				(width 0.1)
				(type default)
			)
			(layer "F.Fab")
		)
		(fp_line
			(start -4.99999 -3.849878)
			(end 4.99999 -3.849878)
			(stroke
				(width 0.1)
				(type default)
			)
			(layer "F.Fab")
		)
		(fp_line
			(start 4.99999 -3.849878)
			(end 4.99999 3.849878)
			(stroke
				(width 0.1)
				(type default)
			)
			(layer "F.Fab")
		)
		(pad "1" smd rect
			(at -3.299968 0 270)
			(size 3.302 4.2164)
			(layers "F.Cu" "F.Mask" "F.Paste")
			(net "SW_PVDD11_S3_P0_SW1")
		)
		(pad "2" smd rect
			(at 3.299968 0 270)
			(size 3.302 4.2164)
			(layers "F.Cu" "F.Mask" "F.Paste")
			(net "PVDD11_S3_P0")
		)
	)
	(footprint ""
		(layer "F.Cu")
		(at 120.396 -423.672 180)
		(property "Reference" "R3390"
			(at 0 0 180)
			(layer "F.SilkS")
			(hide yes)
			(effects
				(font
					(size 1.27 1.27)
				)
			)
		)
		(property "Value" ""
			(at 0 0 180)
			(layer "F.Fab")
			(effects
				(font
					(size 1.27 1.27)
				)
			)
		)
		(duplicate_pad_numbers_are_jumpers no)
		(fp_line
			(start 0.7874 0.4064)
			(end -0.7874 0.4064)
			(stroke
				(width 0.1524)
				(type default)
			)
			(layer "F.SilkS")
		)
		(fp_line
			(start 0.7874 -0.4064)
			(end 0.7874 0.4064)
			(stroke
				(width 0.1524)
				(type default)
			)
			(layer "F.SilkS")
		)
		(fp_line
			(start -0.7874 0.4064)
			(end -0.7874 -0.4064)
			(stroke
				(width 0.1524)
				(type default)
			)
			(layer "F.SilkS")
		)
		(fp_line
			(start -0.7874 -0.4064)
			(end 0.7874 -0.4064)
			(stroke
				(width 0.1524)
				(type default)
			)
			(layer "F.SilkS")
		)
		(fp_line
			(start 0.67945 0.3048)
			(end 0.120396 0.3048)
			(stroke
				(width 0.1)
				(type default)
			)
			(layer "F.Fab")
		)
		(fp_line
			(start 0.67945 -0.3048)
			(end 0.67945 0.3048)
			(stroke
				(width 0.1)
				(type default)
			)
			(layer "F.Fab")
		)
		(fp_line
			(start 0.12065 -0.2794)
			(end 0.12065 -0.3048)
			(stroke
				(width 0.1)
				(type default)
			)
			(layer "F.Fab")
		)
		(fp_line
			(start 0.12065 -0.3048)
			(end 0.67945 -0.3048)
			(stroke
				(width 0.1)
				(type default)
			)
			(layer "F.Fab")
		)
		(fp_line
			(start 0.120396 0.3048)
			(end 0.120396 0.2794)
			(stroke
				(width 0.1)
				(type default)
			)
			(layer "F.Fab")
		)
		(fp_line
			(start 0.120396 0.2794)
			(end -0.12065 0.2794)
			(stroke
				(width 0.1)
				(type default)
			)
			(layer "F.Fab")
		)
		(fp_line
			(start -0.12065 0.3048)
			(end -0.67945 0.3048)
			(stroke
				(width 0.1)
				(type default)
			)
			(layer "F.Fab")
		)
		(fp_line
			(start -0.12065 0.2794)
			(end -0.12065 0.3048)
			(stroke
				(width 0.1)
				(type default)
			)
			(layer "F.Fab")
		)
		(fp_line
			(start -0.12065 -0.2794)
			(end 0.12065 -0.2794)
			(stroke
				(width 0.1)
				(type default)
			)
			(layer "F.Fab")
		)
		(fp_line
			(start -0.12065 -0.305054)
			(end -0.12065 -0.2794)
			(stroke
				(width 0.1)
				(type default)
			)
			(layer "F.Fab")
		)
		(fp_line
			(start -0.67945 0.3048)
			(end -0.67945 -0.305054)
			(stroke
				(width 0.1)
				(type default)
			)
			(layer "F.Fab")
		)
		(fp_line
			(start -0.67945 -0.305054)
			(end -0.12065 -0.305054)
			(stroke
				(width 0.1)
				(type default)
			)
			(layer "F.Fab")
		)
		(pad "1" smd circle
			(at -0.40005 0 180)
			(size 0 0)
			(layers "F.Cu" "F.Mask" "F.Paste")
			(net "GPU_FPGA_BOOT_EN_BUF_R")
		)
		(pad "2" smd circle
			(at 0.40005 0 180)
			(size 0 0)
			(layers "F.Cu" "F.Mask" "F.Paste")
			(net "GPU_FPGA_BOOT_EN_BUF")
		)
	)
	(footprint ""
		(layer "F.Cu")
		(at 77.215746 -395.436852 -90)
		(property "Reference" "R758"
			(at 0 0 270)
			(layer "F.SilkS")
			(hide yes)
			(effects
				(font
					(size 1.27 1.27)
				)
			)
		)
		(property "Value" ""
			(at 0 0 270)
			(layer "F.Fab")
			(effects
				(font
					(size 1.27 1.27)
				)
			)
		)
		(duplicate_pad_numbers_are_jumpers no)
		(fp_line
			(start -0.32512 0.175006)
			(end -0.32512 -0.175006)
			(stroke
				(width 0.1)
				(type default)
			)
			(layer "F.Fab")
		)
		(fp_line
			(start 0.32512 0.175006)
			(end -0.32512 0.175006)
			(stroke
				(width 0.1)
				(type default)
			)
			(layer "F.Fab")
		)
		(fp_line
			(start -0.32512 -0.175006)
			(end 0.32512 -0.175006)
			(stroke
				(width 0.1)
				(type default)
			)
			(layer "F.Fab")
		)
		(fp_line
			(start 0.32512 -0.175006)
			(end 0.32512 0.175006)
			(stroke
				(width 0.1)
				(type default)
			)
			(layer "F.Fab")
		)
		(pad "1" smd rect
			(at -0.2667 0 270)
			(size 0.3048 0.381)
			(layers "F.Cu" "F.Mask" "F.Paste")
			(net "P1V8_CPU1_RT_1D")
		)
		(pad "2" smd rect
			(at 0.2667 0 90)
			(size 0.3048 0.381)
			(layers "F.Cu" "F.Mask" "F.Paste")
			(net "RST_RT_CPU1_P1_RESET_R_N")
		)
	)
	(footprint ""
		(layer "F.Cu")
		(at 132.694172 -36.873434 180)
		(property "Reference" "U6001"
			(at -4.192016 6.04266 0)
			(unlocked yes)
			(layer "F.SilkS")
			(effects
				(font
					(size 0.7874 0.5842)
					(thickness 0.1524)
				)
				(justify left)
			)
		)
		(property "Value" ""
			(at 0 0 180)
			(layer "F.Fab")
			(effects
				(font
					(size 1.27 1.27)
				)
			)
		)
		(duplicate_pad_numbers_are_jumpers no)
		(fp_line
			(start 4.6863 3.2004)
			(end 5.1181 3.2004)
			(stroke
				(width 0.1524)
				(type default)
			)
			(layer "F.SilkS")
		)
		(fp_line
			(start 4.6863 -0.7874)
			(end 5.1181 -0.7874)
			(stroke
				(width 0.1524)
				(type default)
			)
			(layer "F.SilkS")
		)
		(fp_line
			(start 4.6736 1.1938)
			(end 5.4356 1.1938)
			(stroke
				(width 0.1524)
				(type default)
			)
			(layer "F.SilkS")
		)
		(fp_line
			(start 4.6736 -2.794)
			(end 5.4356 -2.794)
			(stroke
				(width 0.1524)
				(type default)
			)
			(layer "F.SilkS")
		)
		(fp_line
			(start 4.05003 4.05003)
			(end 4.05003 3.429)
			(stroke
				(width 0.1524)
				(type default)
			)
			(layer "F.SilkS")
		)
		(fp_line
			(start 4.05003 -3.429)
			(end 4.05003 -4.05003)
			(stroke
				(width 0.1524)
				(type default)
			)
			(layer "F.SilkS")
		)
		(fp_line
			(start 4.05003 -4.05003)
			(end 3.429 -4.05003)
			(stroke
				(width 0.1524)
				(type default)
			)
			(layer "F.SilkS")
		)
		(fp_line
			(start 3.429 4.05003)
			(end 4.05003 4.05003)
			(stroke
				(width 0.1524)
				(type default)
			)
			(layer "F.SilkS")
		)
		(fp_line
			(start 1.9812 -4.6609)
			(end 1.9812 -5.0927)
			(stroke
				(width 0.1524)
				(type default)
			)
			(layer "F.SilkS")
		)
		(fp_line
			(start 1.6002 4.6736)
			(end 1.6002 5.4356)
			(stroke
				(width 0.1524)
				(type default)
			)
			(layer "F.SilkS")
		)
		(fp_line
			(start 0 -5.4356)
			(end 0 -4.6736)
			(stroke
				(width 0.1524)
				(type default)
			)
			(layer "F.SilkS")
		)
		(fp_line
			(start -0.381 4.6609)
			(end -0.381 5.0927)
			(stroke
				(width 0.1524)
				(type default)
			)
			(layer "F.SilkS")
		)
		(fp_line
			(start -2.0066 -4.6609)
			(end -2.0066 -5.0927)
			(stroke
				(width 0.1524)
				(type default)
			)
			(layer "F.SilkS")
		)
		(fp_line
			(start -2.3876 4.6736)
			(end -2.3876 5.4356)
			(stroke
				(width 0.1524)
				(type default)
			)
			(layer "F.SilkS")
		)
		(fp_line
			(start -3.429 -4.05003)
			(end -4.05003 -4.05003)
			(stroke
				(width 0.1524)
				(type default)
			)
			(layer "F.SilkS")
		)
		(fp_line
			(start -4.05003 4.05003)
			(end -3.429 4.05003)
			(stroke
				(width 0.1524)
				(type default)
			)
			(layer "F.SilkS")
		)
		(fp_line
			(start -4.05003 3.429)
			(end -4.05003 4.05003)
			(stroke
				(width 0.1524)
				(type default)
			)
			(layer "F.SilkS")
		)
		(fp_line
			(start -4.05003 -4.05003)
			(end -4.05003 -3.429)
			(stroke
				(width 0.1524)
				(type default)
			)
			(layer "F.SilkS")
		)
		(fp_line
			(start -5.0927 -1.5748)
			(end -4.6609 -1.5748)
			(stroke
				(width 0.1524)
				(type default)
			)
			(layer "F.SilkS")
		)
		(fp_line
			(start -5.1181 2.413)
			(end -4.6863 2.413)
			(stroke
				(width 0.1524)
				(type default)
			)
			(layer "F.SilkS")
		)
		(fp_line
			(start -5.4356 0.4064)
			(end -4.6736 0.4064)
			(stroke
				(width 0.1524)
				(type default)
			)
			(layer "F.SilkS")
		)
		(fp_poly
			(pts
				(xy -6.895592 -2.588514) (xy -6.895592 -3.604514) (xy -5.879592 -3.096514)
			)
			(stroke
				(width 0)
				(type default)
			)
			(fill yes)
			(layer "F.SilkS")
		)
		(fp_line
			(start 4.6863 3.2004)
			(end 5.1181 3.2004)
			(stroke
				(width 0.1)
				(type default)
			)
			(layer "F.Fab")
		)
		(fp_line
			(start 4.6863 -0.7874)
			(end 5.1181 -0.7874)
			(stroke
				(width 0.1)
				(type default)
			)
			(layer "F.Fab")
		)
		(fp_line
			(start 4.6736 1.1938)
			(end 5.4356 1.1938)
			(stroke
				(width 0.1)
				(type default)
			)
			(layer "F.Fab")
		)
		(fp_line
			(start 4.6736 -2.794)
			(end 5.4356 -2.794)
			(stroke
				(width 0.1)
				(type default)
			)
			(layer "F.Fab")
		)
		(fp_line
			(start 4.05003 4.05003)
			(end 4.05003 -4.05003)
			(stroke
				(width 0.1)
				(type default)
			)
			(layer "F.Fab")
		)
		(fp_line
			(start 4.05003 -4.05003)
			(end -4.05003 -4.05003)
			(stroke
				(width 0.1)
				(type default)
			)
			(layer "F.Fab")
		)
		(fp_line
			(start 1.9812 -4.6609)
			(end 1.9812 -5.0927)
			(stroke
				(width 0.1)
				(type default)
			)
			(layer "F.Fab")
		)
		(fp_line
			(start 1.6002 4.6736)
			(end 1.6002 5.4356)
			(stroke
				(width 0.1)
				(type default)
			)
			(layer "F.Fab")
		)
		(fp_line
			(start 0 -5.4356)
			(end 0 -4.6736)
			(stroke
				(width 0.1)
				(type default)
			)
			(layer "F.Fab")
		)
		(fp_line
			(start -0.381 4.6609)
			(end -0.381 5.0927)
			(stroke
				(width 0.1)
				(type default)
			)
			(layer "F.Fab")
		)
		(fp_line
			(start -2.0066 -4.6609)
			(end -2.0066 -5.0927)
			(stroke
				(width 0.1)
				(type default)
			)
			(layer "F.Fab")
		)
		(fp_line
			(start -2.3876 4.6736)
			(end -2.3876 5.4356)
			(stroke
				(width 0.1)
				(type default)
			)
			(layer "F.Fab")
		)
		(fp_line
			(start -4.05003 4.05003)
			(end 4.05003 4.05003)
			(stroke
				(width 0.1)
				(type default)
			)
			(layer "F.Fab")
		)
		(fp_line
			(start -4.05003 -4.05003)
			(end -4.05003 4.05003)
			(stroke
				(width 0.1)
				(type default)
			)
			(layer "F.Fab")
		)
		(fp_line
			(start -5.0927 -1.5748)
			(end -4.6609 -1.5748)
			(stroke
				(width 0.1)
				(type default)
			)
			(layer "F.Fab")
		)
		(fp_line
			(start -5.1181 2.413)
			(end -4.6863 2.413)
			(stroke
				(width 0.1)
				(type default)
			)
			(layer "F.Fab")
		)
		(fp_line
			(start -5.4356 0.4064)
			(end -4.6736 0.4064)
			(stroke
				(width 0.1)
				(type default)
			)
			(layer "F.Fab")
		)
		(fp_poly
			(pts
				(xy -5.6896 -2.691892) (xy -5.6896 -3.707892) (xy -4.6736 -3.199892)
			)
			(stroke
				(width 0)
				(type default)
			)
			(fill yes)
			(layer "F.Fab")
		)
		(fp_text user "35"
			(at 5.085842 4.165092 270)
			(unlocked yes)
			(layer "F.SilkS")
			(effects
				(font
					(size 0.635 0.4064)
					(thickness 0.1524)
				)
			)
		)
		(fp_text user "51"
			(at 4.958842 -4.368292 270)
			(unlocked yes)
			(layer "F.SilkS")
			(effects
				(font
					(size 0.635 0.4064)
					(thickness 0.1524)
				)
			)
		)
		(fp_text user "34"
			(at 4.241292 5.390642 180)
			(unlocked yes)
			(layer "F.SilkS")
			(effects
				(font
					(size 0.635 0.4064)
					(thickness 0.1524)
				)
			)
		)
		(fp_text user "52"
			(at 3.961892 -5.174742 180)
			(unlocked yes)
			(layer "F.SilkS")
			(effects
				(font
					(size 0.635 0.4064)
					(thickness 0.1524)
				)
			)
		)
		(fp_text user "68"
			(at -4.038092 -5.047742 180)
			(unlocked yes)
			(layer "F.SilkS")
			(effects
				(font
					(size 0.635 0.4064)
					(thickness 0.1524)
				)
			)
		)
		(fp_text user "18"
			(at -4.241292 5.009642 180)
			(unlocked yes)
			(layer "F.SilkS")
			(effects
				(font
					(size 0.635 0.4064)
					(thickness 0.1524)
				)
			)
		)
		(fp_text user "17"
			(at -5.123942 3.885692 270)
			(unlocked yes)
			(layer "F.SilkS")
			(effects
				(font
					(size 0.635 0.4064)
					(thickness 0.1524)
				)
			)
		)
		(fp_text user "35"
			(at 5.271262 4.038092 270)
			(unlocked yes)
			(layer "F.Fab")
			(effects
				(font
					(size 0.7874 0.5842)
					(thickness 0.1524)
				)
			)
		)
		(fp_text user "51"
			(at 5.271262 -3.733292 270)
			(unlocked yes)
			(layer "F.Fab")
			(effects
				(font
					(size 0.7874 0.5842)
					(thickness 0.1524)
				)
			)
		)
		(fp_text user "52"
			(at 3.707892 -5.116322 180)
			(unlocked yes)
			(layer "F.Fab")
			(effects
				(font
					(size 0.7874 0.5842)
					(thickness 0.1524)
				)
			)
		)
		(fp_text user "34"
			(at 3.606292 5.195062 180)
			(unlocked yes)
			(layer "F.Fab")
			(effects
				(font
					(size 0.7874 0.5842)
					(thickness 0.1524)
				)
			)
		)
		(fp_text user "18"
			(at -3.606292 5.195062 180)
			(unlocked yes)
			(layer "F.Fab")
			(effects
				(font
					(size 0.7874 0.5842)
					(thickness 0.1524)
				)
			)
		)
		(fp_text user "68"
			(at -3.657092 -5.116322 180)
			(unlocked yes)
			(layer "F.Fab")
			(effects
				(font
					(size 0.7874 0.5842)
					(thickness 0.1524)
				)
			)
		)
		(fp_text user "17"
			(at -5.192522 3.631692 270)
			(unlocked yes)
			(layer "F.Fab")
			(effects
				(font
					(size 0.7874 0.5842)
					(thickness 0.1524)
				)
			)
		)
		(pad "1" smd rect
			(at -3.999992 -3.199892 270)
			(size 0.1778 1.016)
			(layers "F.Cu" "F.Mask" "F.Paste")
			(net "P1V2_CPU0_USB_DVDD12")
		)
		(pad "2" smd rect
			(at -3.849878 -2.800096 270)
			(size 0.1778 1.3208)
			(layers "F.Cu" "F.Mask" "F.Paste")
			(net "USB_CPU0_HUB1_RREF_USB2")
		)
		(pad "3" smd rect
			(at -3.849878 -2.400046 270)
			(size 0.1778 1.3208)
			(layers "F.Cu" "F.Mask" "F.Paste")
			(net "P1V2_CPU0_USB_DVDD12")
		)
		(pad "4" smd rect
			(at -3.849878 -1.999996 270)
			(size 0.1778 1.3208)
			(layers "F.Cu" "F.Mask" "F.Paste")
			(net "P3V3_AUX_CPU0_USB_AVDD33")
		)
		(pad "5" smd rect
			(at -3.849878 -1.599946 270)
			(size 0.1778 1.3208)
			(layers "F.Cu" "F.Mask" "F.Paste")
			(net "USB3_CPU0_BMC_RX_HUB1_DN")
		)
		(pad "6" smd rect
			(at -3.849878 -1.199896 270)
			(size 0.1778 1.3208)
			(layers "F.Cu" "F.Mask" "F.Paste")
			(net "USB3_CPU0_BMC_RX_HUB1_DP")
		)
		(pad "7" smd rect
			(at -3.849878 -0.8001 270)
			(size 0.1778 1.3208)
			(layers "F.Cu" "F.Mask" "F.Paste")
			(net "P1V2_AUX")
		)
		(pad "8" smd rect
			(at -3.849878 -0.40005 270)
			(size 0.1778 1.3208)
			(layers "F.Cu" "F.Mask" "F.Paste")
			(net "USB3_CPU0_BMC_TX_C1_DN")
		)
		(pad "9" smd rect
			(at -3.849878 0 270)
			(size 0.1778 1.3208)
			(layers "F.Cu" "F.Mask" "F.Paste")
			(net "USB3_CPU0_BMC_TX_C1_DP")
		)
		(pad "10" smd rect
			(at -3.849878 0.40005 270)
			(size 0.1778 1.3208)
			(layers "F.Cu" "F.Mask" "F.Paste")
			(net "P1V2_AUX")
		)
		(pad "11" smd rect
			(at -3.849878 0.8001 270)
			(size 0.1778 1.3208)
			(layers "F.Cu" "F.Mask" "F.Paste")
			(net "Net_10799")
		)
		(pad "12" smd rect
			(at -3.849878 1.199896 270)
			(size 0.1778 1.3208)
			(layers "F.Cu" "F.Mask" "F.Paste")
			(net "Net_10800")
		)
		(pad "13" smd rect
			(at -3.849878 1.599946 270)
			(size 0.1778 1.3208)
			(layers "F.Cu" "F.Mask" "F.Paste")
			(net "P1V2_AUX")
		)
		(pad "14" smd rect
			(at -3.849878 1.999996 270)
			(size 0.1778 1.3208)
			(layers "F.Cu" "F.Mask" "F.Paste")
			(net "Net_10802")
		)
		(pad "15" smd rect
			(at -3.849878 2.400046 270)
			(size 0.1778 1.3208)
			(layers "F.Cu" "F.Mask" "F.Paste")
			(net "Net_10801")
		)
		(pad "16" smd rect
			(at -3.849878 2.800096 270)
			(size 0.1778 1.3208)
			(layers "F.Cu" "F.Mask" "F.Paste")
			(net "P1V2_AUX")
		)
		(pad "17" smd rect
			(at -3.999992 3.199892 270)
			(size 0.1778 1.016)
			(layers "F.Cu" "F.Mask" "F.Paste")
			(net "USB_CPU0_HUB1_VBUS_US")
		)
		(pad "18" smd rect
			(at -3.199892 3.999992 180)
			(size 0.1778 1.016)
			(layers "F.Cu" "F.Mask" "F.Paste")
			(net "USB_CPU0_HUB1_VBUS_DS")
		)
		(pad "19" smd rect
			(at -2.800096 3.849878 180)
			(size 0.1778 1.3208)
			(layers "F.Cu" "F.Mask" "F.Paste")
			(net "P1V2_CPU0_USB_DVDD12")
		)
		(pad "20" smd rect
			(at -2.400046 3.849878 180)
			(size 0.1778 1.3208)
			(layers "F.Cu" "F.Mask" "F.Paste")
			(net "TP_CPU0_USB_HUB1_SUSPEND")
		)
		(pad "21" smd rect
			(at -1.999996 3.849878 180)
			(size 0.1778 1.3208)
			(layers "F.Cu" "F.Mask" "F.Paste")
			(net "PU_CPU0_USB_HUB_RESERVED1")
		)
		(pad "22" smd rect
			(at -1.599946 3.849878 180)
			(size 0.1778 1.3208)
			(layers "F.Cu" "F.Mask" "F.Paste")
			(net "PU_CPU0_USB_HUB_RESERVED2")
		)
		(pad "23" smd rect
			(at -1.199896 3.849878 180)
			(size 0.1778 1.3208)
			(layers "F.Cu" "F.Mask" "F.Paste")
			(net "USB_CPU0_HUB1_MODE_SEL0")
		)
		(pad "24" smd rect
			(at -0.8001 3.849878 180)
			(size 0.1778 1.3208)
			(layers "F.Cu" "F.Mask" "F.Paste")
			(net "USB_CPU0_HUB1_MODE_SEL1")
		)
		(pad "25" smd rect
			(at -0.40005 3.849878 180)
			(size 0.1778 1.3208)
			(layers "F.Cu" "F.Mask" "F.Paste")
			(net "Net_10798")
		)
		(pad "26" smd rect
			(at 0 3.849878 180)
			(size 0.1778 1.3208)
			(layers "F.Cu" "F.Mask" "F.Paste")
			(net "USB_CPU0_HUB1_RREF_SS")
		)
		(pad "27" smd rect
			(at 0.40005 3.849878 180)
			(size 0.1778 1.3208)
			(layers "F.Cu" "F.Mask" "F.Paste")
			(net "P1V2_CPU0_USB_DVDD12")
		)
		(pad "28" smd rect
			(at 0.8001 3.849878 180)
			(size 0.1778 1.3208)
			(layers "F.Cu" "F.Mask" "F.Paste")
			(net "P3V3_AUX")
		)
		(pad "29" smd rect
			(at 1.199896 3.849878 180)
			(size 0.1778 1.3208)
			(layers "F.Cu" "F.Mask" "F.Paste")
			(net "PU_CPU0_USB_HUB_PWR_EN")
		)
		(pad "30" smd rect
			(at 1.599946 3.849878 180)
			(size 0.1778 1.3208)
			(layers "F.Cu" "F.Mask" "F.Paste")
			(net "PU_CPU0_USB_HUB_OVRCURR")
		)
		(pad "31" smd rect
			(at 1.999996 3.849878 180)
			(size 0.1778 1.3208)
			(layers "F.Cu" "F.Mask" "F.Paste")
			(net "RST_USB_CPU0_HUB1_R_N")
		)
		(pad "32" smd rect
			(at 2.400046 3.849878 180)
			(size 0.1778 1.3208)
			(layers "F.Cu" "F.Mask" "F.Paste")
			(net "SMB_USB_CPU0_HUB1_SCL")
		)
		(pad "33" smd rect
			(at 2.800096 3.849878 180)
			(size 0.1778 1.3208)
			(layers "F.Cu" "F.Mask" "F.Paste")
			(net "SMB_USB_CPU0_HUB1_SDA")
		)
		(pad "34" smd rect
			(at 3.199892 3.999992 180)
			(size 0.1778 1.016)
			(layers "F.Cu" "F.Mask" "F.Paste")
			(net "P1V2_AUX")
		)
		(pad "35" smd rect
			(at 3.999992 3.199892 270)
			(size 0.1778 1.016)
			(layers "F.Cu" "F.Mask" "F.Paste")
			(net "Net_10807")
		)
		(pad "36" smd rect
			(at 3.849878 2.800096 270)
			(size 0.1778 1.3208)
			(layers "F.Cu" "F.Mask" "F.Paste")
			(net "Net_10808")
		)
		(pad "37" smd rect
			(at 3.849878 2.400046 270)
			(size 0.1778 1.3208)
			(layers "F.Cu" "F.Mask" "F.Paste")
			(net "P1V2_AUX")
		)
		(pad "38" smd rect
			(at 3.849878 1.999996 270)
			(size 0.1778 1.3208)
			(layers "F.Cu" "F.Mask" "F.Paste")
			(net "Net_10805")
		)
		(pad "39" smd rect
			(at 3.849878 1.599946 270)
			(size 0.1778 1.3208)
			(layers "F.Cu" "F.Mask" "F.Paste")
			(net "Net_10806")
		)
		(pad "40" smd rect
			(at 3.849878 1.199896 270)
			(size 0.1778 1.3208)
			(layers "F.Cu" "F.Mask" "F.Paste")
			(net "GND")
		)
		(pad "41" smd rect
			(at 3.849878 0.8001 270)
			(size 0.1778 1.3208)
			(layers "F.Cu" "F.Mask" "F.Paste")
			(net "Net_10811")
		)
		(pad "42" smd rect
			(at 3.849878 0.40005 270)
			(size 0.1778 1.3208)
			(layers "F.Cu" "F.Mask" "F.Paste")
			(net "Net_10812")
		)
		(pad "43" smd rect
			(at 3.849878 0 270)
			(size 0.1778 1.3208)
			(layers "F.Cu" "F.Mask" "F.Paste")
			(net "P1V2_AUX")
		)
		(pad "44" smd rect
			(at 3.849878 -0.40005 270)
			(size 0.1778 1.3208)
			(layers "F.Cu" "F.Mask" "F.Paste")
			(net "Net_10814")
		)
		(pad "45" smd rect
			(at 3.849878 -0.8001 270)
			(size 0.1778 1.3208)
			(layers "F.Cu" "F.Mask" "F.Paste")
			(net "Net_10813")
		)
		(pad "46" smd rect
			(at 3.849878 -1.199896 270)
			(size 0.1778 1.3208)
			(layers "F.Cu" "F.Mask" "F.Paste")
			(net "P1V2_AUX")
		)
		(pad "47" smd rect
			(at 3.849878 -1.599946 270)
			(size 0.1778 1.3208)
			(layers "F.Cu" "F.Mask" "F.Paste")
			(net "USB3_CPU0_BMC_HUB1_TX_DP")
		)
		(pad "48" smd rect
			(at 3.849878 -1.999996 270)
			(size 0.1778 1.3208)
			(layers "F.Cu" "F.Mask" "F.Paste")
			(net "USB3_CPU0_BMC_HUB1_TX_DN")
		)
		(pad "49" smd rect
			(at 3.849878 -2.400046 270)
			(size 0.1778 1.3208)
			(layers "F.Cu" "F.Mask" "F.Paste")
			(net "P1V2_AUX")
		)
		(pad "50" smd rect
			(at 3.849878 -2.800096 270)
			(size 0.1778 1.3208)
			(layers "F.Cu" "F.Mask" "F.Paste")
			(net "USB3_CPU0_BMC_RX_C1_DN")
		)
		(pad "51" smd rect
			(at 3.999992 -3.199892 270)
			(size 0.1778 1.016)
			(layers "F.Cu" "F.Mask" "F.Paste")
			(net "USB3_CPU0_BMC_RX_C1_DP")
		)
		(pad "52" smd rect
			(at 3.199892 -3.999992 180)
			(size 0.1778 1.016)
			(layers "F.Cu" "F.Mask" "F.Paste")
			(net "P1V2_AUX")
		)
		(pad "53" smd rect
			(at 2.800096 -3.849878 180)
			(size 0.1778 1.3208)
			(layers "F.Cu" "F.Mask" "F.Paste")
			(net "P1V2_AUX")
		)
		(pad "54" smd rect
			(at 2.400046 -3.849878 180)
			(size 0.1778 1.3208)
			(layers "F.Cu" "F.Mask" "F.Paste")
			(net "XTAL_USB_CPU0_HUB1_XOUT")
		)
		(pad "55" smd rect
			(at 1.999996 -3.849878 180)
			(size 0.1778 1.3208)
			(layers "F.Cu" "F.Mask" "F.Paste")
			(net "XTAL_USB_CPU0_HUB1_XIN")
		)
		(pad "56" smd rect
			(at 1.599946 -3.849878 180)
			(size 0.1778 1.3208)
			(layers "F.Cu" "F.Mask" "F.Paste")
			(net "P3V3_AUX")
		)
		(pad "57" smd rect
			(at 1.199896 -3.849878 180)
			(size 0.1778 1.3208)
			(layers "F.Cu" "F.Mask" "F.Paste")
			(net "USB2_CPU0_P0_R1_DP")
		)
		(pad "58" smd rect
			(at 0.8001 -3.849878 180)
			(size 0.1778 1.3208)
			(layers "F.Cu" "F.Mask" "F.Paste")
			(net "USB2_CPU0_P0_R1_DN")
		)
		(pad "59" smd rect
			(at 0.40005 -3.849878 180)
			(size 0.1778 1.3208)
			(layers "F.Cu" "F.Mask" "F.Paste")
			(net "USB2_CPU0_P0_HUB1_R_DN")
		)
		(pad "60" smd rect
			(at 0 -3.849878 180)
			(size 0.1778 1.3208)
			(layers "F.Cu" "F.Mask" "F.Paste")
			(net "USB2_CPU0_P0_HUB1_R_DP")
		)
		(pad "61" smd rect
			(at -0.40005 -3.849878 180)
			(size 0.1778 1.3208)
			(layers "F.Cu" "F.Mask" "F.Paste")
			(net "P3V3_AUX")
		)
		(pad "62" smd rect
			(at -0.8001 -3.849878 180)
			(size 0.1778 1.3208)
			(layers "F.Cu" "F.Mask" "F.Paste")
			(net "Net_10815")
		)
		(pad "63" smd rect
			(at -1.199896 -3.849878 180)
			(size 0.1778 1.3208)
			(layers "F.Cu" "F.Mask" "F.Paste")
			(net "Net_10816")
		)
		(pad "64" smd rect
			(at -1.599946 -3.849878 180)
			(size 0.1778 1.3208)
			(layers "F.Cu" "F.Mask" "F.Paste")
			(net "Net_10810")
		)
		(pad "65" smd rect
			(at -1.999996 -3.849878 180)
			(size 0.1778 1.3208)
			(layers "F.Cu" "F.Mask" "F.Paste")
			(net "Net_10809")
		)
		(pad "66" smd rect
			(at -2.400046 -3.849878 180)
			(size 0.1778 1.3208)
			(layers "F.Cu" "F.Mask" "F.Paste")
			(net "P3V3_AUX")
		)
		(pad "67" smd rect
			(at -2.800096 -3.849878 180)
			(size 0.1778 1.3208)
			(layers "F.Cu" "F.Mask" "F.Paste")
			(net "Net_10803")
		)
		(pad "68" smd rect
			(at -3.199892 -3.999992 180)
			(size 0.1778 1.016)
			(layers "F.Cu" "F.Mask" "F.Paste")
			(net "Net_10804")
		)
		(pad "TH" smd rect
			(at 0 0 180)
			(size 5.207 5.207)
			(layers "F.Cu" "F.Mask" "F.Paste")
			(net "GND")
		)
		(zone
			(layer "F.Cu")
			(hatch none 0.5)
			(connect_pads
				(clearance 0)
			)
			(min_thickness 0.25)
			(keepout
				(tracks not_allowed)
				(vias allowed)
				(pads allowed)
				(copperpour not_allowed)
				(footprints allowed)
			)
			(placement
				(enabled no)
				(sheetname "")
			)
			(fill
				(thermal_gap 0.5)
				(thermal_bridge_width 0.5)
				(island_removal_mode 0)
			)
			(polygon
				(pts
					(xy 135.818372 -34.206434) (xy 135.818372 -33.927034) (xy 136.123172 -33.927034) (xy 136.123172 -33.444434)
					(xy 135.640572 -33.444434) (xy 135.640572 -33.749234) (xy 129.747772 -33.749234) (xy 129.747772 -33.444434)
					(xy 129.265172 -33.444434) (xy 129.265172 -33.927034) (xy 129.569972 -33.927034) (xy 129.569972 -39.819834)
					(xy 129.265172 -39.819834) (xy 129.265172 -40.302434) (xy 129.747772 -40.302434) (xy 129.747772 -39.997634)
					(xy 135.640572 -39.997634) (xy 135.640572 -40.302434) (xy 136.123172 -40.302434) (xy 136.123172 -39.819834)
					(xy 135.818372 -39.819834) (xy 135.818372 -34.231834) (xy 135.361172 -34.231834) (xy 135.361172 -39.540434)
					(xy 130.027172 -39.540434) (xy 130.027172 -34.206434)
				)
			)
		)
	)
	(footprint ""
		(layer "F.Cu")
		(at 20.148042 -389.007858 -90)
		(property "Reference" "PC6612_1"
			(at 0 0 270)
			(layer "F.SilkS")
			(hide yes)
			(effects
				(font
					(size 1.27 1.27)
				)
			)
		)
		(property "Value" ""
			(at 0 0 270)
			(layer "F.Fab")
			(effects
				(font
					(size 1.27 1.27)
				)
			)
		)
		(duplicate_pad_numbers_are_jumpers no)
		(fp_line
			(start -0.7874 0.4064)
			(end -0.7874 -0.4064)
			(stroke
				(width 0.1524)
				(type default)
			)
			(layer "F.SilkS")
		)
		(fp_line
			(start 0.7874 0.4064)
			(end -0.7874 0.4064)
			(stroke
				(width 0.1524)
				(type default)
			)
			(layer "F.SilkS")
		)
		(fp_line
			(start -0.7874 -0.4064)
			(end 0.7874 -0.4064)
			(stroke
				(width 0.1524)
				(type default)
			)
			(layer "F.SilkS")
		)
		(fp_line
			(start 0.7874 -0.4064)
			(end 0.7874 0.4064)
			(stroke
				(width 0.1524)
				(type default)
			)
			(layer "F.SilkS")
		)
		(fp_line
			(start -0.67945 0.3048)
			(end -0.67945 -0.305054)
			(stroke
				(width 0.1)
				(type default)
			)
			(layer "F.Fab")
		)
		(fp_line
			(start -0.12065 0.3048)
			(end -0.67945 0.3048)
			(stroke
				(width 0.1)
				(type default)
			)
			(layer "F.Fab")
		)
		(fp_line
			(start 0.120396 0.3048)
			(end 0.120396 0.2794)
			(stroke
				(width 0.1)
				(type default)
			)
			(layer "F.Fab")
		)
		(fp_line
			(start 0.67945 0.3048)
			(end 0.120396 0.3048)
			(stroke
				(width 0.1)
				(type default)
			)
			(layer "F.Fab")
		)
		(fp_line
			(start -0.12065 0.2794)
			(end -0.12065 0.3048)
			(stroke
				(width 0.1)
				(type default)
			)
			(layer "F.Fab")
		)
		(fp_line
			(start 0.120396 0.2794)
			(end -0.12065 0.2794)
			(stroke
				(width 0.1)
				(type default)
			)
			(layer "F.Fab")
		)
		(fp_line
			(start -0.12065 -0.2794)
			(end 0.12065 -0.2794)
			(stroke
				(width 0.1)
				(type default)
			)
			(layer "F.Fab")
		)
		(fp_line
			(start 0.12065 -0.2794)
			(end 0.12065 -0.3048)
			(stroke
				(width 0.1)
				(type default)
			)
			(layer "F.Fab")
		)
		(fp_line
			(start 0.12065 -0.3048)
			(end 0.67945 -0.3048)
			(stroke
				(width 0.1)
				(type default)
			)
			(layer "F.Fab")
		)
		(fp_line
			(start 0.67945 -0.3048)
			(end 0.67945 0.3048)
			(stroke
				(width 0.1)
				(type default)
			)
			(layer "F.Fab")
		)
		(fp_line
			(start -0.67945 -0.305054)
			(end -0.12065 -0.305054)
			(stroke
				(width 0.1)
				(type default)
			)
			(layer "F.Fab")
		)
		(fp_line
			(start -0.12065 -0.305054)
			(end -0.12065 -0.2794)
			(stroke
				(width 0.1)
				(type default)
			)
			(layer "F.Fab")
		)
		(pad "1" smd circle
			(at -0.40005 0 270)
			(size 0 0)
			(layers "F.Cu" "F.Mask" "F.Paste")
			(net "SW_P12V_AUX_P0V9_RETIMER_CPU1_FLT")
		)
		(pad "2" smd circle
			(at 0.40005 0 270)
			(size 0 0)
			(layers "F.Cu" "F.Mask" "F.Paste")
			(net "GND")
		)
	)
	(footprint ""
		(layer "F.Cu")
		(at 360.76001 -418.329618 180)
		(property "Reference" "R4173"
			(at 0 0 180)
			(layer "F.SilkS")
			(hide yes)
			(effects
				(font
					(size 1.27 1.27)
				)
			)
		)
		(property "Value" ""
			(at 0 0 180)
			(layer "F.Fab")
			(effects
				(font
					(size 1.27 1.27)
				)
			)
		)
		(duplicate_pad_numbers_are_jumpers no)
		(fp_line
			(start 0.7874 0.4064)
			(end -0.7874 0.4064)
			(stroke
				(width 0.1524)
				(type default)
			)
			(layer "F.SilkS")
		)
		(fp_line
			(start 0.7874 -0.4064)
			(end 0.7874 0.4064)
			(stroke
				(width 0.1524)
				(type default)
			)
			(layer "F.SilkS")
		)
		(fp_line
			(start -0.7874 0.4064)
			(end -0.7874 -0.4064)
			(stroke
				(width 0.1524)
				(type default)
			)
			(layer "F.SilkS")
		)
		(fp_line
			(start -0.7874 -0.4064)
			(end 0.7874 -0.4064)
			(stroke
				(width 0.1524)
				(type default)
			)
			(layer "F.SilkS")
		)
		(fp_line
			(start 0.67945 0.3048)
			(end 0.120396 0.3048)
			(stroke
				(width 0.1)
				(type default)
			)
			(layer "F.Fab")
		)
		(fp_line
			(start 0.67945 -0.3048)
			(end 0.67945 0.3048)
			(stroke
				(width 0.1)
				(type default)
			)
			(layer "F.Fab")
		)
		(fp_line
			(start 0.12065 -0.2794)
			(end 0.12065 -0.3048)
			(stroke
				(width 0.1)
				(type default)
			)
			(layer "F.Fab")
		)
		(fp_line
			(start 0.12065 -0.3048)
			(end 0.67945 -0.3048)
			(stroke
				(width 0.1)
				(type default)
			)
			(layer "F.Fab")
		)
		(fp_line
			(start 0.120396 0.3048)
			(end 0.120396 0.2794)
			(stroke
				(width 0.1)
				(type default)
			)
			(layer "F.Fab")
		)
		(fp_line
			(start 0.120396 0.2794)
			(end -0.12065 0.2794)
			(stroke
				(width 0.1)
				(type default)
			)
			(layer "F.Fab")
		)
		(fp_line
			(start -0.12065 0.3048)
			(end -0.67945 0.3048)
			(stroke
				(width 0.1)
				(type default)
			)
			(layer "F.Fab")
		)
		(fp_line
			(start -0.12065 0.2794)
			(end -0.12065 0.3048)
			(stroke
				(width 0.1)
				(type default)
			)
			(layer "F.Fab")
		)
		(fp_line
			(start -0.12065 -0.2794)
			(end 0.12065 -0.2794)
			(stroke
				(width 0.1)
				(type default)
			)
			(layer "F.Fab")
		)
		(fp_line
			(start -0.12065 -0.305054)
			(end -0.12065 -0.2794)
			(stroke
				(width 0.1)
				(type default)
			)
			(layer "F.Fab")
		)
		(fp_line
			(start -0.67945 0.3048)
			(end -0.67945 -0.305054)
			(stroke
				(width 0.1)
				(type default)
			)
			(layer "F.Fab")
		)
		(fp_line
			(start -0.67945 -0.305054)
			(end -0.12065 -0.305054)
			(stroke
				(width 0.1)
				(type default)
			)
			(layer "F.Fab")
		)
		(pad "1" smd circle
			(at -0.40005 0 180)
			(size 0 0)
			(layers "F.Cu" "F.Mask" "F.Paste")
			(net "P3V3_AUX")
		)
		(pad "2" smd circle
			(at 0.40005 0 180)
			(size 0 0)
			(layers "F.Cu" "F.Mask" "F.Paste")
			(net "UART_BMC_BIC_R_BUF_RX")
		)
	)
	(footprint ""
		(layer "F.Cu")
		(at 109.949996 -401.329906 -90)
		(property "Reference" "U19"
			(at 4.252468 -3.081782 90)
			(unlocked yes)
			(layer "F.SilkS")
			(effects
				(font
					(size 0.7874 0.5842)
					(thickness 0.1524)
				)
				(justify left)
			)
		)
		(property "Value" ""
			(at 0 0 270)
			(layer "F.Fab")
			(effects
				(font
					(size 1.27 1.27)
				)
			)
		)
		(duplicate_pad_numbers_are_jumpers no)
		(fp_line
			(start -1.8288 2.500122)
			(end 1.8288 2.500122)
			(stroke
				(width 0.1524)
				(type default)
			)
			(layer "F.SilkS")
		)
		(fp_line
			(start 1.8288 2.500122)
			(end 1.8288 -2.500122)
			(stroke
				(width 0.1524)
				(type default)
			)
			(layer "F.SilkS")
		)
		(fp_line
			(start 0 -1.4224)
			(end -1.077722 -2.500122)
			(stroke
				(width 0.1524)
				(type default)
			)
			(layer "F.SilkS")
		)
		(fp_line
			(start -1.8288 -2.500122)
			(end -1.8288 2.500122)
			(stroke
				(width 0.1524)
				(type default)
			)
			(layer "F.SilkS")
		)
		(fp_line
			(start -1.077722 -2.500122)
			(end -1.8288 -2.500122)
			(stroke
				(width 0.1524)
				(type default)
			)
			(layer "F.SilkS")
		)
		(fp_line
			(start 1.077722 -2.500122)
			(end 0 -1.4224)
			(stroke
				(width 0.1524)
				(type default)
			)
			(layer "F.SilkS")
		)
		(fp_line
			(start 1.8288 -2.500122)
			(end 1.077722 -2.500122)
			(stroke
				(width 0.1524)
				(type default)
			)
			(layer "F.SilkS")
		)
		(fp_poly
			(pts
				(xy -4.5085 -2.413) (xy -4.5085 -1.397) (xy -3.4925 -1.905)
			)
			(stroke
				(width 0)
				(type default)
			)
			(fill yes)
			(layer "F.SilkS")
		)
		(fp_line
			(start -1.999996 2.500122)
			(end 1.999996 2.500122)
			(stroke
				(width 0.1)
				(type default)
			)
			(layer "F.Fab")
		)
		(fp_line
			(start 1.999996 2.500122)
			(end 1.999996 -2.500122)
			(stroke
				(width 0.1)
				(type default)
			)
			(layer "F.Fab")
		)
		(fp_line
			(start -1.999996 -2.500122)
			(end -1.999996 2.500122)
			(stroke
				(width 0.1)
				(type default)
			)
			(layer "F.Fab")
		)
		(fp_line
			(start 1.999996 -2.500122)
			(end -1.999996 -2.500122)
			(stroke
				(width 0.1)
				(type default)
			)
			(layer "F.Fab")
		)
		(fp_poly
			(pts
				(xy -4.5085 -2.413) (xy -4.5085 -1.397) (xy -3.4925 -1.905)
			)
			(stroke
				(width 0)
				(type default)
			)
			(fill yes)
			(layer "F.Fab")
		)
		(pad "1" smd rect
			(at -2.599944 -1.905 180)
			(size 0.889 1.27)
			(layers "F.Cu" "F.Mask" "F.Paste")
			(net "Net_10837")
		)
		(pad "2" smd rect
			(at -2.599944 -0.635 180)
			(size 0.889 1.27)
			(layers "F.Cu" "F.Mask" "F.Paste")
			(net "Net_10836")
		)
		(pad "3" smd rect
			(at -2.599944 0.635 180)
			(size 0.889 1.27)
			(layers "F.Cu" "F.Mask" "F.Paste")
			(net "U19_E2")
		)
		(pad "4" smd rect
			(at -2.599944 1.905 180)
			(size 0.889 1.27)
			(layers "F.Cu" "F.Mask" "F.Paste")
			(net "GND")
		)
		(pad "5" smd rect
			(at 2.599944 1.905 180)
			(size 0.889 1.27)
			(layers "F.Cu" "F.Mask" "F.Paste")
			(net "SMB_RT_CPU1_P1_ROM_SDA")
		)
		(pad "6" smd rect
			(at 2.599944 0.635 180)
			(size 0.889 1.27)
			(layers "F.Cu" "F.Mask" "F.Paste")
			(net "SMB_RT_CPU1_P1_ROM_SCL")
		)
		(pad "7" smd rect
			(at 2.599944 -0.635 180)
			(size 0.889 1.27)
			(layers "F.Cu" "F.Mask" "F.Paste")
			(net "GND")
		)
		(pad "8" smd rect
			(at 2.599944 -1.905 180)
			(size 0.889 1.27)
			(layers "F.Cu" "F.Mask" "F.Paste")
			(net "P1V8_CPU1_RT_1D")
		)
	)
	(footprint ""
		(layer "F.Cu")
		(at 20.416012 -358.30637 90)
		(property "Reference" "R8224"
			(at 0 0 90)
			(layer "F.SilkS")
			(hide yes)
			(effects
				(font
					(size 1.27 1.27)
				)
			)
		)
		(property "Value" ""
			(at 0 0 90)
			(layer "F.Fab")
			(effects
				(font
					(size 1.27 1.27)
				)
			)
		)
		(duplicate_pad_numbers_are_jumpers no)
		(fp_line
			(start 0.7874 -0.4064)
			(end 0.7874 0.4064)
			(stroke
				(width 0.1524)
				(type default)
			)
			(layer "F.SilkS")
		)
		(fp_line
			(start -0.7874 -0.4064)
			(end 0.7874 -0.4064)
			(stroke
				(width 0.1524)
				(type default)
			)
			(layer "F.SilkS")
		)
		(fp_line
			(start 0.7874 0.4064)
			(end -0.7874 0.4064)
			(stroke
				(width 0.1524)
				(type default)
			)
			(layer "F.SilkS")
		)
		(fp_line
			(start -0.7874 0.4064)
			(end -0.7874 -0.4064)
			(stroke
				(width 0.1524)
				(type default)
			)
			(layer "F.SilkS")
		)
		(fp_line
			(start -0.12065 -0.305054)
			(end -0.12065 -0.2794)
			(stroke
				(width 0.1)
				(type default)
			)
			(layer "F.Fab")
		)
		(fp_line
			(start -0.67945 -0.305054)
			(end -0.12065 -0.305054)
			(stroke
				(width 0.1)
				(type default)
			)
			(layer "F.Fab")
		)
		(fp_line
			(start 0.67945 -0.3048)
			(end 0.67945 0.3048)
			(stroke
				(width 0.1)
				(type default)
			)
			(layer "F.Fab")
		)
		(fp_line
			(start 0.12065 -0.3048)
			(end 0.67945 -0.3048)
			(stroke
				(width 0.1)
				(type default)
			)
			(layer "F.Fab")
		)
		(fp_line
			(start 0.12065 -0.2794)
			(end 0.12065 -0.3048)
			(stroke
				(width 0.1)
				(type default)
			)
			(layer "F.Fab")
		)
		(fp_line
			(start -0.12065 -0.2794)
			(end 0.12065 -0.2794)
			(stroke
				(width 0.1)
				(type default)
			)
			(layer "F.Fab")
		)
		(fp_line
			(start 0.120396 0.2794)
			(end -0.12065 0.2794)
			(stroke
				(width 0.1)
				(type default)
			)
			(layer "F.Fab")
		)
		(fp_line
			(start -0.12065 0.2794)
			(end -0.12065 0.3048)
			(stroke
				(width 0.1)
				(type default)
			)
			(layer "F.Fab")
		)
		(fp_line
			(start 0.67945 0.3048)
			(end 0.120396 0.3048)
			(stroke
				(width 0.1)
				(type default)
			)
			(layer "F.Fab")
		)
		(fp_line
			(start 0.120396 0.3048)
			(end 0.120396 0.2794)
			(stroke
				(width 0.1)
				(type default)
			)
			(layer "F.Fab")
		)
		(fp_line
			(start -0.12065 0.3048)
			(end -0.67945 0.3048)
			(stroke
				(width 0.1)
				(type default)
			)
			(layer "F.Fab")
		)
		(fp_line
			(start -0.67945 0.3048)
			(end -0.67945 -0.305054)
			(stroke
				(width 0.1)
				(type default)
			)
			(layer "F.Fab")
		)
		(pad "1" smd circle
			(at -0.40005 0 90)
			(size 0 0)
			(layers "F.Cu" "F.Mask" "F.Paste")
			(net "PVDDIO_P1_EN")
		)
		(pad "2" smd circle
			(at 0.40005 0 90)
			(size 0 0)
			(layers "F.Cu" "F.Mask" "F.Paste")
			(net "PVDDIO_P1_EN_R")
		)
	)
	(footprint ""
		(layer "F.Cu")
		(at 103.505 -419.989)
		(property "Reference" "R3493"
			(at 0 0 0)
			(layer "F.SilkS")
			(hide yes)
			(effects
				(font
					(size 1.27 1.27)
				)
			)
		)
		(property "Value" ""
			(at 0 0 0)
			(layer "F.Fab")
			(effects
				(font
					(size 1.27 1.27)
				)
			)
		)
		(duplicate_pad_numbers_are_jumpers no)
		(fp_line
			(start -0.7874 -0.4064)
			(end 0.7874 -0.4064)
			(stroke
				(width 0.1524)
				(type default)
			)
			(layer "F.SilkS")
		)
		(fp_line
			(start -0.7874 0.4064)
			(end -0.7874 -0.4064)
			(stroke
				(width 0.1524)
				(type default)
			)
			(layer "F.SilkS")
		)
		(fp_line
			(start 0.7874 -0.4064)
			(end 0.7874 0.4064)
			(stroke
				(width 0.1524)
				(type default)
			)
			(layer "F.SilkS")
		)
		(fp_line
			(start 0.7874 0.4064)
			(end -0.7874 0.4064)
			(stroke
				(width 0.1524)
				(type default)
			)
			(layer "F.SilkS")
		)
		(fp_line
			(start -0.67945 -0.305054)
			(end -0.12065 -0.305054)
			(stroke
				(width 0.1)
				(type default)
			)
			(layer "F.Fab")
		)
		(fp_line
			(start -0.67945 0.3048)
			(end -0.67945 -0.305054)
			(stroke
				(width 0.1)
				(type default)
			)
			(layer "F.Fab")
		)
		(fp_line
			(start -0.12065 -0.305054)
			(end -0.12065 -0.2794)
			(stroke
				(width 0.1)
				(type default)
			)
			(layer "F.Fab")
		)
		(fp_line
			(start -0.12065 -0.2794)
			(end 0.12065 -0.2794)
			(stroke
				(width 0.1)
				(type default)
			)
			(layer "F.Fab")
		)
		(fp_line
			(start -0.12065 0.2794)
			(end -0.12065 0.3048)
			(stroke
				(width 0.1)
				(type default)
			)
			(layer "F.Fab")
		)
		(fp_line
			(start -0.12065 0.3048)
			(end -0.67945 0.3048)
			(stroke
				(width 0.1)
				(type default)
			)
			(layer "F.Fab")
		)
		(fp_line
			(start 0.120396 0.2794)
			(end -0.12065 0.2794)
			(stroke
				(width 0.1)
				(type default)
			)
			(layer "F.Fab")
		)
		(fp_line
			(start 0.120396 0.3048)
			(end 0.120396 0.2794)
			(stroke
				(width 0.1)
				(type default)
			)
			(layer "F.Fab")
		)
		(fp_line
			(start 0.12065 -0.3048)
			(end 0.67945 -0.3048)
			(stroke
				(width 0.1)
				(type default)
			)
			(layer "F.Fab")
		)
		(fp_line
			(start 0.12065 -0.2794)
			(end 0.12065 -0.3048)
			(stroke
				(width 0.1)
				(type default)
			)
			(layer "F.Fab")
		)
		(fp_line
			(start 0.67945 -0.3048)
			(end 0.67945 0.3048)
			(stroke
				(width 0.1)
				(type default)
			)
			(layer "F.Fab")
		)
		(fp_line
			(start 0.67945 0.3048)
			(end 0.120396 0.3048)
			(stroke
				(width 0.1)
				(type default)
			)
			(layer "F.Fab")
		)
		(pad "1" smd circle
			(at -0.40005 0)
			(size 0 0)
			(layers "F.Cu" "F.Mask" "F.Paste")
			(net "GPU_FPGA_EROT_RST_BUF_R_N")
		)
		(pad "2" smd circle
			(at 0.40005 0)
			(size 0 0)
			(layers "F.Cu" "F.Mask" "F.Paste")
			(net "GND")
		)
	)
	(footprint ""
		(layer "F.Cu")
		(at 83.239102 -373.03583 -90)
		(property "Reference" "C730"
			(at 0 0 270)
			(layer "F.SilkS")
			(hide yes)
			(effects
				(font
					(size 1.27 1.27)
				)
			)
		)
		(property "Value" ""
			(at 0 0 270)
			(layer "F.Fab")
			(effects
				(font
					(size 1.27 1.27)
				)
			)
		)
		(duplicate_pad_numbers_are_jumpers no)
		(fp_line
			(start -0.299974 0.150114)
			(end -0.299974 -0.150114)
			(stroke
				(width 0.1)
				(type default)
			)
			(layer "F.Fab")
		)
		(fp_line
			(start 0.299974 0.150114)
			(end -0.299974 0.150114)
			(stroke
				(width 0.1)
				(type default)
			)
			(layer "F.Fab")
		)
		(fp_line
			(start -0.299974 -0.150114)
			(end 0.299974 -0.150114)
			(stroke
				(width 0.1)
				(type default)
			)
			(layer "F.Fab")
		)
		(fp_line
			(start 0.299974 -0.150114)
			(end 0.299974 0.150114)
			(stroke
				(width 0.1)
				(type default)
			)
			(layer "F.Fab")
		)
		(pad "1" smd rect
			(at -0.2667 0 270)
			(size 0.3048 0.381)
			(layers "F.Cu" "F.Mask" "F.Paste")
			(net "P5E_CPU1_P1_TX_C_DN<5>")
		)
		(pad "2" smd rect
			(at 0.2667 0 270)
			(size 0.3048 0.381)
			(layers "F.Cu" "F.Mask" "F.Paste")
			(net "P5E_CPU1_P1_TX_DN<5>")
		)
	)
	(footprint ""
		(layer "F.Cu")
		(at 281.94 -430.022 -90)
		(property "Reference" "L19"
			(at 0 0 270)
			(layer "F.SilkS")
			(hide yes)
			(effects
				(font
					(size 1.27 1.27)
				)
			)
		)
		(property "Value" ""
			(at 0 0 270)
			(layer "F.Fab")
			(effects
				(font
					(size 1.27 1.27)
				)
			)
		)
		(duplicate_pad_numbers_are_jumpers no)
		(fp_line
			(start 1.63576 0.8128)
			(end -1.63576 0.8128)
			(stroke
				(width 0.1524)
				(type default)
			)
			(layer "F.SilkS")
		)
		(fp_line
			(start -1.63576 -0.8128)
			(end -1.63576 0.8128)
			(stroke
				(width 0.1524)
				(type default)
			)
			(layer "F.SilkS")
		)
		(fp_line
			(start -1.63576 -0.8128)
			(end 1.63576 -0.8128)
			(stroke
				(width 0.1524)
				(type default)
			)
			(layer "F.SilkS")
		)
		(fp_line
			(start 1.63576 -0.8128)
			(end 1.63576 0.8128)
			(stroke
				(width 0.1524)
				(type default)
			)
			(layer "F.SilkS")
		)
		(fp_line
			(start -1.56083 0.7366)
			(end -1.524 0.7366)
			(stroke
				(width 0.1)
				(type default)
			)
			(layer "F.Fab")
		)
		(fp_line
			(start -1.524 0.7366)
			(end 1.524 0.7366)
			(stroke
				(width 0.1)
				(type default)
			)
			(layer "F.Fab")
		)
		(fp_line
			(start 1.524 0.7366)
			(end 1.560576 0.7366)
			(stroke
				(width 0.1)
				(type default)
			)
			(layer "F.Fab")
		)
		(fp_line
			(start 1.560576 0.7366)
			(end 1.560576 -0.738632)
			(stroke
				(width 0.1)
				(type default)
			)
			(layer "F.Fab")
		)
		(fp_line
			(start -1.56083 -0.738632)
			(end -1.56083 0.7366)
			(stroke
				(width 0.1)
				(type default)
			)
			(layer "F.Fab")
		)
		(fp_line
			(start 1.560576 -0.738632)
			(end -1.56083 -0.738632)
			(stroke
				(width 0.1)
				(type default)
			)
			(layer "F.Fab")
		)
		(pad "1" smd rect
			(at -0.94996 0 90)
			(size 1.1176 1.3716)
			(layers "F.Cu" "F.Mask" "F.Paste")
			(net "P3V3_AUX")
		)
		(pad "2" smd rect
			(at 0.94996 0 90)
			(size 1.1176 1.3716)
			(layers "F.Cu" "F.Mask" "F.Paste")
			(net "P3V3_9ZXL045_P0")
		)
	)
	(footprint ""
		(layer "F.Cu")
		(at 198.926196 -412.947612)
		(property "Reference" "ME4"
			(at 0 0 0)
			(layer "F.SilkS")
			(hide yes)
			(effects
				(font
					(size 1.27 1.27)
				)
			)
		)
		(property "Value" ""
			(at 0 0 0)
			(layer "F.Fab")
			(effects
				(font
					(size 1.27 1.27)
				)
			)
		)
		(duplicate_pad_numbers_are_jumpers no)
		(fp_line
			(start 0 -5.999988)
			(end 0 -4.475988)
			(stroke
				(width 0.1524)
				(type default)
			)
			(layer "F.SilkS")
		)
		(fp_line
			(start 0 -1.524)
			(end 0 0)
			(stroke
				(width 0.1524)
				(type default)
			)
			(layer "F.SilkS")
		)
		(fp_line
			(start 0 0)
			(end 1.524 0)
			(stroke
				(width 0.1524)
				(type default)
			)
			(layer "F.SilkS")
		)
		(fp_line
			(start 1.524 -5.999988)
			(end 0 -5.999988)
			(stroke
				(width 0.1524)
				(type default)
			)
			(layer "F.SilkS")
		)
		(fp_line
			(start 25.475946 -5.999988)
			(end 26.999946 -5.999988)
			(stroke
				(width 0.1524)
				(type default)
			)
			(layer "F.SilkS")
		)
		(fp_line
			(start 26.999946 -5.999988)
			(end 26.999946 -4.475988)
			(stroke
				(width 0.1524)
				(type default)
			)
			(layer "F.SilkS")
		)
		(fp_line
			(start 26.999946 -1.524)
			(end 26.999946 0)
			(stroke
				(width 0.1524)
				(type default)
			)
			(layer "F.SilkS")
		)
		(fp_line
			(start 26.999946 0)
			(end 25.475946 0)
			(stroke
				(width 0.1524)
				(type default)
			)
			(layer "F.SilkS")
		)
		(fp_text user "S/N"
			(at 0.2032 -4.59105 0)
			(unlocked yes)
			(layer "F.SilkS")
			(effects
				(font
					(size 1.905 1.4224)
					(thickness 0.1524)
				)
				(justify left)
			)
		)
	)
	(footprint ""
		(layer "F.Cu")
		(at 308.420516 -439.276744 -90)
		(property "Reference" "R4141"
			(at 0 0 270)
			(layer "F.SilkS")
			(hide yes)
			(effects
				(font
					(size 1.27 1.27)
				)
			)
		)
		(property "Value" ""
			(at 0 0 270)
			(layer "F.Fab")
			(effects
				(font
					(size 1.27 1.27)
				)
			)
		)
		(duplicate_pad_numbers_are_jumpers no)
		(fp_line
			(start -0.7874 0.4064)
			(end -0.7874 -0.4064)
			(stroke
				(width 0.1524)
				(type default)
			)
			(layer "F.SilkS")
		)
		(fp_line
			(start 0.7874 0.4064)
			(end -0.7874 0.4064)
			(stroke
				(width 0.1524)
				(type default)
			)
			(layer "F.SilkS")
		)
		(fp_line
			(start -0.7874 -0.4064)
			(end 0.7874 -0.4064)
			(stroke
				(width 0.1524)
				(type default)
			)
			(layer "F.SilkS")
		)
		(fp_line
			(start 0.7874 -0.4064)
			(end 0.7874 0.4064)
			(stroke
				(width 0.1524)
				(type default)
			)
			(layer "F.SilkS")
		)
		(fp_line
			(start -0.67945 0.3048)
			(end -0.67945 -0.305054)
			(stroke
				(width 0.1)
				(type default)
			)
			(layer "F.Fab")
		)
		(fp_line
			(start -0.12065 0.3048)
			(end -0.67945 0.3048)
			(stroke
				(width 0.1)
				(type default)
			)
			(layer "F.Fab")
		)
		(fp_line
			(start 0.120396 0.3048)
			(end 0.120396 0.2794)
			(stroke
				(width 0.1)
				(type default)
			)
			(layer "F.Fab")
		)
		(fp_line
			(start 0.67945 0.3048)
			(end 0.120396 0.3048)
			(stroke
				(width 0.1)
				(type default)
			)
			(layer "F.Fab")
		)
		(fp_line
			(start -0.12065 0.2794)
			(end -0.12065 0.3048)
			(stroke
				(width 0.1)
				(type default)
			)
			(layer "F.Fab")
		)
		(fp_line
			(start 0.120396 0.2794)
			(end -0.12065 0.2794)
			(stroke
				(width 0.1)
				(type default)
			)
			(layer "F.Fab")
		)
		(fp_line
			(start -0.12065 -0.2794)
			(end 0.12065 -0.2794)
			(stroke
				(width 0.1)
				(type default)
			)
			(layer "F.Fab")
		)
		(fp_line
			(start 0.12065 -0.2794)
			(end 0.12065 -0.3048)
			(stroke
				(width 0.1)
				(type default)
			)
			(layer "F.Fab")
		)
		(fp_line
			(start 0.12065 -0.3048)
			(end 0.67945 -0.3048)
			(stroke
				(width 0.1)
				(type default)
			)
			(layer "F.Fab")
		)
		(fp_line
			(start 0.67945 -0.3048)
			(end 0.67945 0.3048)
			(stroke
				(width 0.1)
				(type default)
			)
			(layer "F.Fab")
		)
		(fp_line
			(start -0.67945 -0.305054)
			(end -0.12065 -0.305054)
			(stroke
				(width 0.1)
				(type default)
			)
			(layer "F.Fab")
		)
		(fp_line
			(start -0.12065 -0.305054)
			(end -0.12065 -0.2794)
			(stroke
				(width 0.1)
				(type default)
			)
			(layer "F.Fab")
		)
		(pad "1" smd circle
			(at -0.40005 0 270)
			(size 0 0)
			(layers "F.Cu" "F.Mask" "F.Paste")
			(net "P3V3_AUX")
		)
		(pad "2" smd circle
			(at 0.40005 0 270)
			(size 0 0)
			(layers "F.Cu" "F.Mask" "F.Paste")
			(net "GPU_3V3IO_RSVD5_FFU_ISO")
		)
	)
	(footprint ""
		(layer "F.Cu")
		(at 420.658544 -423.744644 90)
		(property "Reference" "R682"
			(at 0 0 90)
			(layer "F.SilkS")
			(hide yes)
			(effects
				(font
					(size 1.27 1.27)
				)
			)
		)
		(property "Value" ""
			(at 0 0 90)
			(layer "F.Fab")
			(effects
				(font
					(size 1.27 1.27)
				)
			)
		)
		(duplicate_pad_numbers_are_jumpers no)
		(fp_line
			(start 0.32512 -0.175006)
			(end 0.32512 0.175006)
			(stroke
				(width 0.1)
				(type default)
			)
			(layer "F.Fab")
		)
		(fp_line
			(start -0.32512 -0.175006)
			(end 0.32512 -0.175006)
			(stroke
				(width 0.1)
				(type default)
			)
			(layer "F.Fab")
		)
		(fp_line
			(start 0.32512 0.175006)
			(end -0.32512 0.175006)
			(stroke
				(width 0.1)
				(type default)
			)
			(layer "F.Fab")
		)
		(fp_line
			(start -0.32512 0.175006)
			(end -0.32512 -0.175006)
			(stroke
				(width 0.1)
				(type default)
			)
			(layer "F.Fab")
		)
		(pad "1" smd rect
			(at -0.2667 0 90)
			(size 0.3048 0.381)
			(layers "F.Cu" "F.Mask" "F.Paste")
			(net "SMB_RT_CPU0_P2_ROM_R_SCL")
		)
		(pad "2" smd rect
			(at 0.2667 0 270)
			(size 0.3048 0.381)
			(layers "F.Cu" "F.Mask" "F.Paste")
			(net "SMB_RT_CPU0_P2_ROM_SCL")
		)
	)
	(footprint ""
		(layer "F.Cu")
		(at 70.382892 -47.049944)
		(property "Reference" "H31"
			(at -1.7272 -4.511548 0)
			(unlocked yes)
			(layer "B.SilkS")
			(effects
				(font
					(size 0.7874 0.5842)
					(thickness 0.1524)
				)
				(justify left mirror)
			)
		)
		(property "Value" ""
			(at 0 0 0)
			(layer "F.Fab")
			(effects
				(font
					(size 1.27 1.27)
				)
			)
		)
		(duplicate_pad_numbers_are_jumpers no)
		(pad "1" thru_hole circle
			(at 0 0)
			(size 4.5212 4.5212)
			(drill 3.81)
			(layers "*.Cu" "*.Mask")
			(remove_unused_layers no)
			(net "GND")
			(clearance -0.1016)
			(padstack
				(mode front_inner_back)
				(layer "Inner"
					(shape circle)
					(size 5.6134 5.6134)
					(clearance -0.6477)
				)
				(layer "B.Cu"
					(shape circle)
					(size 8.001 8.001)
					(clearance -1.8415)
				)
			)
		)
	)
	(footprint ""
		(layer "F.Cu")
		(at 34.870136 -389.439912)
		(property "Reference" "H5"
			(at -0.69088 -4.273804 0)
			(unlocked yes)
			(layer "F.SilkS")
			(effects
				(font
					(size 0.7874 0.5842)
					(thickness 0.1524)
				)
				(justify left)
			)
		)
		(property "Value" ""
			(at 0 0 0)
			(layer "F.Fab")
			(effects
				(font
					(size 1.27 1.27)
				)
			)
		)
		(duplicate_pad_numbers_are_jumpers no)
		(pad "1" thru_hole circle
			(at 0 0)
			(size 6.1976 6.1976)
			(drill 3.7338)
			(layers "*.Cu" "*.Mask")
			(remove_unused_layers no)
			(net "GND")
			(clearance -0.9779)
			(padstack
				(mode front_inner_back)
				(layer "Inner"
					(shape circle)
					(size 5.5372 5.5372)
					(clearance -0.6477)
				)
				(layer "B.Cu"
					(shape circle)
					(size 6.1976 6.1976)
					(clearance -0.9779)
				)
			)
		)
	)
	(footprint ""
		(layer "F.Cu")
		(at 97.239328 -339.681058 -90)
		(property "Reference" "PC428"
			(at 0 0 270)
			(layer "F.SilkS")
			(hide yes)
			(effects
				(font
					(size 1.27 1.27)
				)
			)
		)
		(property "Value" ""
			(at 0 0 270)
			(layer "F.Fab")
			(effects
				(font
					(size 1.27 1.27)
				)
			)
		)
		(duplicate_pad_numbers_are_jumpers no)
		(fp_line
			(start -0.7874 0.4064)
			(end -0.7874 -0.4064)
			(stroke
				(width 0.1524)
				(type default)
			)
			(layer "F.SilkS")
		)
		(fp_line
			(start 0.7874 0.4064)
			(end -0.7874 0.4064)
			(stroke
				(width 0.1524)
				(type default)
			)
			(layer "F.SilkS")
		)
		(fp_line
			(start -0.7874 -0.4064)
			(end 0.7874 -0.4064)
			(stroke
				(width 0.1524)
				(type default)
			)
			(layer "F.SilkS")
		)
		(fp_line
			(start 0.7874 -0.4064)
			(end 0.7874 0.4064)
			(stroke
				(width 0.1524)
				(type default)
			)
			(layer "F.SilkS")
		)
		(fp_line
			(start -0.67945 0.3048)
			(end -0.67945 -0.305054)
			(stroke
				(width 0.1)
				(type default)
			)
			(layer "F.Fab")
		)
		(fp_line
			(start -0.12065 0.3048)
			(end -0.67945 0.3048)
			(stroke
				(width 0.1)
				(type default)
			)
			(layer "F.Fab")
		)
		(fp_line
			(start 0.120396 0.3048)
			(end 0.120396 0.2794)
			(stroke
				(width 0.1)
				(type default)
			)
			(layer "F.Fab")
		)
		(fp_line
			(start 0.67945 0.3048)
			(end 0.120396 0.3048)
			(stroke
				(width 0.1)
				(type default)
			)
			(layer "F.Fab")
		)
		(fp_line
			(start -0.12065 0.2794)
			(end -0.12065 0.3048)
			(stroke
				(width 0.1)
				(type default)
			)
			(layer "F.Fab")
		)
		(fp_line
			(start 0.120396 0.2794)
			(end -0.12065 0.2794)
			(stroke
				(width 0.1)
				(type default)
			)
			(layer "F.Fab")
		)
		(fp_line
			(start -0.12065 -0.2794)
			(end 0.12065 -0.2794)
			(stroke
				(width 0.1)
				(type default)
			)
			(layer "F.Fab")
		)
		(fp_line
			(start 0.12065 -0.2794)
			(end 0.12065 -0.3048)
			(stroke
				(width 0.1)
				(type default)
			)
			(layer "F.Fab")
		)
		(fp_line
			(start 0.12065 -0.3048)
			(end 0.67945 -0.3048)
			(stroke
				(width 0.1)
				(type default)
			)
			(layer "F.Fab")
		)
		(fp_line
			(start 0.67945 -0.3048)
			(end 0.67945 0.3048)
			(stroke
				(width 0.1)
				(type default)
			)
			(layer "F.Fab")
		)
		(fp_line
			(start -0.67945 -0.305054)
			(end -0.12065 -0.305054)
			(stroke
				(width 0.1)
				(type default)
			)
			(layer "F.Fab")
		)
		(fp_line
			(start -0.12065 -0.305054)
			(end -0.12065 -0.2794)
			(stroke
				(width 0.1)
				(type default)
			)
			(layer "F.Fab")
		)
		(pad "1" smd circle
			(at -0.40005 0 270)
			(size 0 0)
			(layers "F.Cu" "F.Mask" "F.Paste")
			(net "SW_PVDDCR_CPU1_P1_BOOT5_R")
		)
		(pad "2" smd circle
			(at 0.40005 0 270)
			(size 0 0)
			(layers "F.Cu" "F.Mask" "F.Paste")
			(net "SW_PVDDCR_CPU1_P1_BOOTR5")
		)
	)
	(footprint ""
		(layer "F.Cu")
		(at 410.8196 -77.513434 90)
		(property "Reference" "C1862"
			(at 0 0 90)
			(layer "F.SilkS")
			(hide yes)
			(effects
				(font
					(size 1.27 1.27)
				)
			)
		)
		(property "Value" ""
			(at 0 0 90)
			(layer "F.Fab")
			(effects
				(font
					(size 1.27 1.27)
				)
			)
		)
		(duplicate_pad_numbers_are_jumpers no)
		(fp_line
			(start 0.7874 -0.4064)
			(end 0.7874 0.4064)
			(stroke
				(width 0.1524)
				(type default)
			)
			(layer "F.SilkS")
		)
		(fp_line
			(start -0.7874 -0.4064)
			(end 0.7874 -0.4064)
			(stroke
				(width 0.1524)
				(type default)
			)
			(layer "F.SilkS")
		)
		(fp_line
			(start 0.7874 0.4064)
			(end -0.7874 0.4064)
			(stroke
				(width 0.1524)
				(type default)
			)
			(layer "F.SilkS")
		)
		(fp_line
			(start -0.7874 0.4064)
			(end -0.7874 -0.4064)
			(stroke
				(width 0.1524)
				(type default)
			)
			(layer "F.SilkS")
		)
		(fp_line
			(start -0.12065 -0.305054)
			(end -0.12065 -0.2794)
			(stroke
				(width 0.1)
				(type default)
			)
			(layer "F.Fab")
		)
		(fp_line
			(start -0.67945 -0.305054)
			(end -0.12065 -0.305054)
			(stroke
				(width 0.1)
				(type default)
			)
			(layer "F.Fab")
		)
		(fp_line
			(start 0.67945 -0.3048)
			(end 0.67945 0.3048)
			(stroke
				(width 0.1)
				(type default)
			)
			(layer "F.Fab")
		)
		(fp_line
			(start 0.12065 -0.3048)
			(end 0.67945 -0.3048)
			(stroke
				(width 0.1)
				(type default)
			)
			(layer "F.Fab")
		)
		(fp_line
			(start 0.12065 -0.2794)
			(end 0.12065 -0.3048)
			(stroke
				(width 0.1)
				(type default)
			)
			(layer "F.Fab")
		)
		(fp_line
			(start -0.12065 -0.2794)
			(end 0.12065 -0.2794)
			(stroke
				(width 0.1)
				(type default)
			)
			(layer "F.Fab")
		)
		(fp_line
			(start 0.120396 0.2794)
			(end -0.12065 0.2794)
			(stroke
				(width 0.1)
				(type default)
			)
			(layer "F.Fab")
		)
		(fp_line
			(start -0.12065 0.2794)
			(end -0.12065 0.3048)
			(stroke
				(width 0.1)
				(type default)
			)
			(layer "F.Fab")
		)
		(fp_line
			(start 0.67945 0.3048)
			(end 0.120396 0.3048)
			(stroke
				(width 0.1)
				(type default)
			)
			(layer "F.Fab")
		)
		(fp_line
			(start 0.120396 0.3048)
			(end 0.120396 0.2794)
			(stroke
				(width 0.1)
				(type default)
			)
			(layer "F.Fab")
		)
		(fp_line
			(start -0.12065 0.3048)
			(end -0.67945 0.3048)
			(stroke
				(width 0.1)
				(type default)
			)
			(layer "F.Fab")
		)
		(fp_line
			(start -0.67945 0.3048)
			(end -0.67945 -0.305054)
			(stroke
				(width 0.1)
				(type default)
			)
			(layer "F.Fab")
		)
		(pad "1" smd circle
			(at -0.40005 0 90)
			(size 0 0)
			(layers "F.Cu" "F.Mask" "F.Paste")
			(net "P3V3_OCP_SFF")
		)
		(pad "2" smd circle
			(at 0.40005 0 90)
			(size 0 0)
			(layers "F.Cu" "F.Mask" "F.Paste")
			(net "GND")
		)
	)
	(footprint ""
		(layer "F.Cu")
		(at 82.324702 -373.03583 -90)
		(property "Reference" "C731"
			(at 0 0 270)
			(layer "F.SilkS")
			(hide yes)
			(effects
				(font
					(size 1.27 1.27)
				)
			)
		)
		(property "Value" ""
			(at 0 0 270)
			(layer "F.Fab")
			(effects
				(font
					(size 1.27 1.27)
				)
			)
		)
		(duplicate_pad_numbers_are_jumpers no)
		(fp_line
			(start -0.299974 0.150114)
			(end -0.299974 -0.150114)
			(stroke
				(width 0.1)
				(type default)
			)
			(layer "F.Fab")
		)
		(fp_line
			(start 0.299974 0.150114)
			(end -0.299974 0.150114)
			(stroke
				(width 0.1)
				(type default)
			)
			(layer "F.Fab")
		)
		(fp_line
			(start -0.299974 -0.150114)
			(end 0.299974 -0.150114)
			(stroke
				(width 0.1)
				(type default)
			)
			(layer "F.Fab")
		)
		(fp_line
			(start 0.299974 -0.150114)
			(end 0.299974 0.150114)
			(stroke
				(width 0.1)
				(type default)
			)
			(layer "F.Fab")
		)
		(pad "1" smd rect
			(at -0.2667 0 270)
			(size 0.3048 0.381)
			(layers "F.Cu" "F.Mask" "F.Paste")
			(net "P5E_CPU1_P1_TX_C_DP<5>")
		)
		(pad "2" smd rect
			(at 0.2667 0 270)
			(size 0.3048 0.381)
			(layers "F.Cu" "F.Mask" "F.Paste")
			(net "P5E_CPU1_P1_TX_DP<5>")
		)
	)
	(footprint ""
		(layer "F.Cu")
		(at 183.079898 -160.612074 90)
		(property "Reference" "R5021"
			(at 0 0 90)
			(layer "F.SilkS")
			(hide yes)
			(effects
				(font
					(size 1.27 1.27)
				)
			)
		)
		(property "Value" ""
			(at 0 0 90)
			(layer "F.Fab")
			(effects
				(font
					(size 1.27 1.27)
				)
			)
		)
		(duplicate_pad_numbers_are_jumpers no)
		(fp_line
			(start 0.7874 -0.4064)
			(end 0.7874 0.4064)
			(stroke
				(width 0.1524)
				(type default)
			)
			(layer "F.SilkS")
		)
		(fp_line
			(start -0.7874 -0.4064)
			(end 0.7874 -0.4064)
			(stroke
				(width 0.1524)
				(type default)
			)
			(layer "F.SilkS")
		)
		(fp_line
			(start 0.7874 0.4064)
			(end -0.7874 0.4064)
			(stroke
				(width 0.1524)
				(type default)
			)
			(layer "F.SilkS")
		)
		(fp_line
			(start -0.7874 0.4064)
			(end -0.7874 -0.4064)
			(stroke
				(width 0.1524)
				(type default)
			)
			(layer "F.SilkS")
		)
		(fp_line
			(start -0.12065 -0.305054)
			(end -0.12065 -0.2794)
			(stroke
				(width 0.1)
				(type default)
			)
			(layer "F.Fab")
		)
		(fp_line
			(start -0.67945 -0.305054)
			(end -0.12065 -0.305054)
			(stroke
				(width 0.1)
				(type default)
			)
			(layer "F.Fab")
		)
		(fp_line
			(start 0.67945 -0.3048)
			(end 0.67945 0.3048)
			(stroke
				(width 0.1)
				(type default)
			)
			(layer "F.Fab")
		)
		(fp_line
			(start 0.12065 -0.3048)
			(end 0.67945 -0.3048)
			(stroke
				(width 0.1)
				(type default)
			)
			(layer "F.Fab")
		)
		(fp_line
			(start 0.12065 -0.2794)
			(end 0.12065 -0.3048)
			(stroke
				(width 0.1)
				(type default)
			)
			(layer "F.Fab")
		)
		(fp_line
			(start -0.12065 -0.2794)
			(end 0.12065 -0.2794)
			(stroke
				(width 0.1)
				(type default)
			)
			(layer "F.Fab")
		)
		(fp_line
			(start 0.120396 0.2794)
			(end -0.12065 0.2794)
			(stroke
				(width 0.1)
				(type default)
			)
			(layer "F.Fab")
		)
		(fp_line
			(start -0.12065 0.2794)
			(end -0.12065 0.3048)
			(stroke
				(width 0.1)
				(type default)
			)
			(layer "F.Fab")
		)
		(fp_line
			(start 0.67945 0.3048)
			(end 0.120396 0.3048)
			(stroke
				(width 0.1)
				(type default)
			)
			(layer "F.Fab")
		)
		(fp_line
			(start 0.120396 0.3048)
			(end 0.120396 0.2794)
			(stroke
				(width 0.1)
				(type default)
			)
			(layer "F.Fab")
		)
		(fp_line
			(start -0.12065 0.3048)
			(end -0.67945 0.3048)
			(stroke
				(width 0.1)
				(type default)
			)
			(layer "F.Fab")
		)
		(fp_line
			(start -0.67945 0.3048)
			(end -0.67945 -0.305054)
			(stroke
				(width 0.1)
				(type default)
			)
			(layer "F.Fab")
		)
		(pad "1" smd circle
			(at -0.40005 0 90)
			(size 0 0)
			(layers "F.Cu" "F.Mask" "F.Paste")
			(net "PVDD11_S3_P1")
		)
		(pad "2" smd circle
			(at 0.40005 0 90)
			(size 0 0)
			(layers "F.Cu" "F.Mask" "F.Paste")
			(net "I3C_SCM_3_R_SDA")
		)
	)
	(footprint ""
		(layer "F.Cu")
		(at 348.972124 -344.792046 90)
		(property "Reference" "PC111_6"
			(at 0 0 90)
			(layer "F.SilkS")
			(hide yes)
			(effects
				(font
					(size 1.27 1.27)
				)
			)
		)
		(property "Value" ""
			(at 0 0 90)
			(layer "F.Fab")
			(effects
				(font
					(size 1.27 1.27)
				)
			)
		)
		(duplicate_pad_numbers_are_jumpers no)
		(fp_line
			(start 0.7874 -0.4064)
			(end 0.7874 0.4064)
			(stroke
				(width 0.1524)
				(type default)
			)
			(layer "F.SilkS")
		)
		(fp_line
			(start -0.7874 -0.4064)
			(end 0.7874 -0.4064)
			(stroke
				(width 0.1524)
				(type default)
			)
			(layer "F.SilkS")
		)
		(fp_line
			(start 0.7874 0.4064)
			(end -0.7874 0.4064)
			(stroke
				(width 0.1524)
				(type default)
			)
			(layer "F.SilkS")
		)
		(fp_line
			(start -0.7874 0.4064)
			(end -0.7874 -0.4064)
			(stroke
				(width 0.1524)
				(type default)
			)
			(layer "F.SilkS")
		)
		(fp_line
			(start -0.12065 -0.305054)
			(end -0.12065 -0.2794)
			(stroke
				(width 0.1)
				(type default)
			)
			(layer "F.Fab")
		)
		(fp_line
			(start -0.67945 -0.305054)
			(end -0.12065 -0.305054)
			(stroke
				(width 0.1)
				(type default)
			)
			(layer "F.Fab")
		)
		(fp_line
			(start 0.67945 -0.3048)
			(end 0.67945 0.3048)
			(stroke
				(width 0.1)
				(type default)
			)
			(layer "F.Fab")
		)
		(fp_line
			(start 0.12065 -0.3048)
			(end 0.67945 -0.3048)
			(stroke
				(width 0.1)
				(type default)
			)
			(layer "F.Fab")
		)
		(fp_line
			(start 0.12065 -0.2794)
			(end 0.12065 -0.3048)
			(stroke
				(width 0.1)
				(type default)
			)
			(layer "F.Fab")
		)
		(fp_line
			(start -0.12065 -0.2794)
			(end 0.12065 -0.2794)
			(stroke
				(width 0.1)
				(type default)
			)
			(layer "F.Fab")
		)
		(fp_line
			(start 0.120396 0.2794)
			(end -0.12065 0.2794)
			(stroke
				(width 0.1)
				(type default)
			)
			(layer "F.Fab")
		)
		(fp_line
			(start -0.12065 0.2794)
			(end -0.12065 0.3048)
			(stroke
				(width 0.1)
				(type default)
			)
			(layer "F.Fab")
		)
		(fp_line
			(start 0.67945 0.3048)
			(end 0.120396 0.3048)
			(stroke
				(width 0.1)
				(type default)
			)
			(layer "F.Fab")
		)
		(fp_line
			(start 0.120396 0.3048)
			(end 0.120396 0.2794)
			(stroke
				(width 0.1)
				(type default)
			)
			(layer "F.Fab")
		)
		(fp_line
			(start -0.12065 0.3048)
			(end -0.67945 0.3048)
			(stroke
				(width 0.1)
				(type default)
			)
			(layer "F.Fab")
		)
		(fp_line
			(start -0.67945 0.3048)
			(end -0.67945 -0.305054)
			(stroke
				(width 0.1)
				(type default)
			)
			(layer "F.Fab")
		)
		(pad "1" smd circle
			(at -0.40005 0 90)
			(size 0 0)
			(layers "F.Cu" "F.Mask" "F.Paste")
			(net "PVDDCR_CPU1_P0_VCCS")
		)
		(pad "2" smd circle
			(at 0.40005 0 90)
			(size 0 0)
			(layers "F.Cu" "F.Mask" "F.Paste")
			(net "GND")
		)
	)
	(footprint ""
		(layer "F.Cu")
		(at 66.929 -55.245 180)
		(property "Reference" "R1179"
			(at 0 0 180)
			(layer "F.SilkS")
			(hide yes)
			(effects
				(font
					(size 1.27 1.27)
				)
			)
		)
		(property "Value" ""
			(at 0 0 180)
			(layer "F.Fab")
			(effects
				(font
					(size 1.27 1.27)
				)
			)
		)
		(duplicate_pad_numbers_are_jumpers no)
		(fp_line
			(start 0.7874 0.4064)
			(end -0.7874 0.4064)
			(stroke
				(width 0.1524)
				(type default)
			)
			(layer "F.SilkS")
		)
		(fp_line
			(start 0.7874 -0.4064)
			(end 0.7874 0.4064)
			(stroke
				(width 0.1524)
				(type default)
			)
			(layer "F.SilkS")
		)
		(fp_line
			(start -0.7874 0.4064)
			(end -0.7874 -0.4064)
			(stroke
				(width 0.1524)
				(type default)
			)
			(layer "F.SilkS")
		)
		(fp_line
			(start -0.7874 -0.4064)
			(end 0.7874 -0.4064)
			(stroke
				(width 0.1524)
				(type default)
			)
			(layer "F.SilkS")
		)
		(fp_line
			(start 0.67945 0.3048)
			(end 0.120396 0.3048)
			(stroke
				(width 0.1)
				(type default)
			)
			(layer "F.Fab")
		)
		(fp_line
			(start 0.67945 -0.3048)
			(end 0.67945 0.3048)
			(stroke
				(width 0.1)
				(type default)
			)
			(layer "F.Fab")
		)
		(fp_line
			(start 0.12065 -0.2794)
			(end 0.12065 -0.3048)
			(stroke
				(width 0.1)
				(type default)
			)
			(layer "F.Fab")
		)
		(fp_line
			(start 0.12065 -0.3048)
			(end 0.67945 -0.3048)
			(stroke
				(width 0.1)
				(type default)
			)
			(layer "F.Fab")
		)
		(fp_line
			(start 0.120396 0.3048)
			(end 0.120396 0.2794)
			(stroke
				(width 0.1)
				(type default)
			)
			(layer "F.Fab")
		)
		(fp_line
			(start 0.120396 0.2794)
			(end -0.12065 0.2794)
			(stroke
				(width 0.1)
				(type default)
			)
			(layer "F.Fab")
		)
		(fp_line
			(start -0.12065 0.3048)
			(end -0.67945 0.3048)
			(stroke
				(width 0.1)
				(type default)
			)
			(layer "F.Fab")
		)
		(fp_line
			(start -0.12065 0.2794)
			(end -0.12065 0.3048)
			(stroke
				(width 0.1)
				(type default)
			)
			(layer "F.Fab")
		)
		(fp_line
			(start -0.12065 -0.2794)
			(end 0.12065 -0.2794)
			(stroke
				(width 0.1)
				(type default)
			)
			(layer "F.Fab")
		)
		(fp_line
			(start -0.12065 -0.305054)
			(end -0.12065 -0.2794)
			(stroke
				(width 0.1)
				(type default)
			)
			(layer "F.Fab")
		)
		(fp_line
			(start -0.67945 0.3048)
			(end -0.67945 -0.305054)
			(stroke
				(width 0.1)
				(type default)
			)
			(layer "F.Fab")
		)
		(fp_line
			(start -0.67945 -0.305054)
			(end -0.12065 -0.305054)
			(stroke
				(width 0.1)
				(type default)
			)
			(layer "F.Fab")
		)
		(pad "1" smd circle
			(at -0.40005 0 180)
			(size 0 0)
			(layers "F.Cu" "F.Mask" "F.Paste")
			(net "FM_OCP_V3_2_AUX_PWR_R_EN")
		)
		(pad "2" smd circle
			(at 0.40005 0 180)
			(size 0 0)
			(layers "F.Cu" "F.Mask" "F.Paste")
			(net "FM_OCP_V3_2_AUX_PWR_EN")
		)
	)
	(footprint ""
		(layer "F.Cu")
		(at 402.214842 -404.873206 -90)
		(property "Reference" "R1066"
			(at 0 0 270)
			(layer "F.SilkS")
			(hide yes)
			(effects
				(font
					(size 1.27 1.27)
				)
			)
		)
		(property "Value" ""
			(at 0 0 270)
			(layer "F.Fab")
			(effects
				(font
					(size 1.27 1.27)
				)
			)
		)
		(duplicate_pad_numbers_are_jumpers no)
		(fp_line
			(start -0.32512 0.175006)
			(end -0.32512 -0.175006)
			(stroke
				(width 0.1)
				(type default)
			)
			(layer "F.Fab")
		)
		(fp_line
			(start 0.32512 0.175006)
			(end -0.32512 0.175006)
			(stroke
				(width 0.1)
				(type default)
			)
			(layer "F.Fab")
		)
		(fp_line
			(start -0.32512 -0.175006)
			(end 0.32512 -0.175006)
			(stroke
				(width 0.1)
				(type default)
			)
			(layer "F.Fab")
		)
		(fp_line
			(start 0.32512 -0.175006)
			(end 0.32512 0.175006)
			(stroke
				(width 0.1)
				(type default)
			)
			(layer "F.Fab")
		)
		(pad "1" smd rect
			(at -0.2667 0 270)
			(size 0.3048 0.381)
			(layers "F.Cu" "F.Mask" "F.Paste")
			(net "P1V8_CPU0_RT_1D")
		)
		(pad "2" smd rect
			(at 0.2667 0 90)
			(size 0.3048 0.381)
			(layers "F.Cu" "F.Mask" "F.Paste")
			(net "JTAG_TEST_MODE_RT_CPU0_P2")
		)
	)
	(footprint ""
		(layer "F.Cu")
		(at 45.932344 -419.700964)
		(property "Reference" "R1466"
			(at 0 0 0)
			(layer "F.SilkS")
			(hide yes)
			(effects
				(font
					(size 1.27 1.27)
				)
			)
		)
		(property "Value" ""
			(at 0 0 0)
			(layer "F.Fab")
			(effects
				(font
					(size 1.27 1.27)
				)
			)
		)
		(duplicate_pad_numbers_are_jumpers no)
		(fp_line
			(start -0.32512 -0.175006)
			(end 0.32512 -0.175006)
			(stroke
				(width 0.1)
				(type default)
			)
			(layer "F.Fab")
		)
		(fp_line
			(start -0.32512 0.175006)
			(end -0.32512 -0.175006)
			(stroke
				(width 0.1)
				(type default)
			)
			(layer "F.Fab")
		)
		(fp_line
			(start 0.32512 -0.175006)
			(end 0.32512 0.175006)
			(stroke
				(width 0.1)
				(type default)
			)
			(layer "F.Fab")
		)
		(fp_line
			(start 0.32512 0.175006)
			(end -0.32512 0.175006)
			(stroke
				(width 0.1)
				(type default)
			)
			(layer "F.Fab")
		)
		(pad "1" smd rect
			(at -0.2667 0)
			(size 0.3048 0.381)
			(layers "F.Cu" "F.Mask" "F.Paste")
			(net "P1V8_CPU1_RT_1D")
		)
		(pad "2" smd rect
			(at 0.2667 0 180)
			(size 0.3048 0.381)
			(layers "F.Cu" "F.Mask" "F.Paste")
			(net "JTAG_TDO_RT_CPU1_P0")
		)
	)
	(footprint ""
		(layer "F.Cu")
		(at 53.866542 -360.473498)
		(property "Reference" "PC438"
			(at 0 0 0)
			(layer "F.SilkS")
			(hide yes)
			(effects
				(font
					(size 1.27 1.27)
				)
			)
		)
		(property "Value" ""
			(at 0 0 0)
			(layer "F.Fab")
			(effects
				(font
					(size 1.27 1.27)
				)
			)
		)
		(duplicate_pad_numbers_are_jumpers no)
		(fp_line
			(start -0.7874 -0.4064)
			(end 0.7874 -0.4064)
			(stroke
				(width 0.1524)
				(type default)
			)
			(layer "F.SilkS")
		)
		(fp_line
			(start -0.7874 0.4064)
			(end -0.7874 -0.4064)
			(stroke
				(width 0.1524)
				(type default)
			)
			(layer "F.SilkS")
		)
		(fp_line
			(start 0.7874 -0.4064)
			(end 0.7874 0.4064)
			(stroke
				(width 0.1524)
				(type default)
			)
			(layer "F.SilkS")
		)
		(fp_line
			(start 0.7874 0.4064)
			(end -0.7874 0.4064)
			(stroke
				(width 0.1524)
				(type default)
			)
			(layer "F.SilkS")
		)
		(fp_line
			(start -0.67945 -0.305054)
			(end -0.12065 -0.305054)
			(stroke
				(width 0.1)
				(type default)
			)
			(layer "F.Fab")
		)
		(fp_line
			(start -0.67945 0.3048)
			(end -0.67945 -0.305054)
			(stroke
				(width 0.1)
				(type default)
			)
			(layer "F.Fab")
		)
		(fp_line
			(start -0.12065 -0.305054)
			(end -0.12065 -0.2794)
			(stroke
				(width 0.1)
				(type default)
			)
			(layer "F.Fab")
		)
		(fp_line
			(start -0.12065 -0.2794)
			(end 0.12065 -0.2794)
			(stroke
				(width 0.1)
				(type default)
			)
			(layer "F.Fab")
		)
		(fp_line
			(start -0.12065 0.2794)
			(end -0.12065 0.3048)
			(stroke
				(width 0.1)
				(type default)
			)
			(layer "F.Fab")
		)
		(fp_line
			(start -0.12065 0.3048)
			(end -0.67945 0.3048)
			(stroke
				(width 0.1)
				(type default)
			)
			(layer "F.Fab")
		)
		(fp_line
			(start 0.120396 0.2794)
			(end -0.12065 0.2794)
			(stroke
				(width 0.1)
				(type default)
			)
			(layer "F.Fab")
		)
		(fp_line
			(start 0.120396 0.3048)
			(end 0.120396 0.2794)
			(stroke
				(width 0.1)
				(type default)
			)
			(layer "F.Fab")
		)
		(fp_line
			(start 0.12065 -0.3048)
			(end 0.67945 -0.3048)
			(stroke
				(width 0.1)
				(type default)
			)
			(layer "F.Fab")
		)
		(fp_line
			(start 0.12065 -0.2794)
			(end 0.12065 -0.3048)
			(stroke
				(width 0.1)
				(type default)
			)
			(layer "F.Fab")
		)
		(fp_line
			(start 0.67945 -0.3048)
			(end 0.67945 0.3048)
			(stroke
				(width 0.1)
				(type default)
			)
			(layer "F.Fab")
		)
		(fp_line
			(start 0.67945 0.3048)
			(end 0.120396 0.3048)
			(stroke
				(width 0.1)
				(type default)
			)
			(layer "F.Fab")
		)
		(pad "1" smd circle
			(at -0.40005 0)
			(size 0 0)
			(layers "F.Cu" "F.Mask" "F.Paste")
			(net "P12V_AUX")
		)
		(pad "2" smd circle
			(at 0.40005 0)
			(size 0 0)
			(layers "F.Cu" "F.Mask" "F.Paste")
			(net "GND")
		)
	)
	(footprint ""
		(layer "F.Cu")
		(at 372.937278 -145.536158 180)
		(property "Reference" "R8293"
			(at 0 0 180)
			(layer "F.SilkS")
			(hide yes)
			(effects
				(font
					(size 1.27 1.27)
				)
			)
		)
		(property "Value" ""
			(at 0 0 180)
			(layer "F.Fab")
			(effects
				(font
					(size 1.27 1.27)
				)
			)
		)
		(duplicate_pad_numbers_are_jumpers no)
		(fp_line
			(start 0.7874 0.4064)
			(end -0.7874 0.4064)
			(stroke
				(width 0.1524)
				(type default)
			)
			(layer "F.SilkS")
		)
		(fp_line
			(start 0.7874 -0.4064)
			(end 0.7874 0.4064)
			(stroke
				(width 0.1524)
				(type default)
			)
			(layer "F.SilkS")
		)
		(fp_line
			(start -0.7874 0.4064)
			(end -0.7874 -0.4064)
			(stroke
				(width 0.1524)
				(type default)
			)
			(layer "F.SilkS")
		)
		(fp_line
			(start -0.7874 -0.4064)
			(end 0.7874 -0.4064)
			(stroke
				(width 0.1524)
				(type default)
			)
			(layer "F.SilkS")
		)
		(fp_line
			(start 0.67945 0.3048)
			(end 0.120396 0.3048)
			(stroke
				(width 0.1)
				(type default)
			)
			(layer "F.Fab")
		)
		(fp_line
			(start 0.67945 -0.3048)
			(end 0.67945 0.3048)
			(stroke
				(width 0.1)
				(type default)
			)
			(layer "F.Fab")
		)
		(fp_line
			(start 0.12065 -0.2794)
			(end 0.12065 -0.3048)
			(stroke
				(width 0.1)
				(type default)
			)
			(layer "F.Fab")
		)
		(fp_line
			(start 0.12065 -0.3048)
			(end 0.67945 -0.3048)
			(stroke
				(width 0.1)
				(type default)
			)
			(layer "F.Fab")
		)
		(fp_line
			(start 0.120396 0.3048)
			(end 0.120396 0.2794)
			(stroke
				(width 0.1)
				(type default)
			)
			(layer "F.Fab")
		)
		(fp_line
			(start 0.120396 0.2794)
			(end -0.12065 0.2794)
			(stroke
				(width 0.1)
				(type default)
			)
			(layer "F.Fab")
		)
		(fp_line
			(start -0.12065 0.3048)
			(end -0.67945 0.3048)
			(stroke
				(width 0.1)
				(type default)
			)
			(layer "F.Fab")
		)
		(fp_line
			(start -0.12065 0.2794)
			(end -0.12065 0.3048)
			(stroke
				(width 0.1)
				(type default)
			)
			(layer "F.Fab")
		)
		(fp_line
			(start -0.12065 -0.2794)
			(end 0.12065 -0.2794)
			(stroke
				(width 0.1)
				(type default)
			)
			(layer "F.Fab")
		)
		(fp_line
			(start -0.12065 -0.305054)
			(end -0.12065 -0.2794)
			(stroke
				(width 0.1)
				(type default)
			)
			(layer "F.Fab")
		)
		(fp_line
			(start -0.67945 0.3048)
			(end -0.67945 -0.305054)
			(stroke
				(width 0.1)
				(type default)
			)
			(layer "F.Fab")
		)
		(fp_line
			(start -0.67945 -0.305054)
			(end -0.12065 -0.305054)
			(stroke
				(width 0.1)
				(type default)
			)
			(layer "F.Fab")
		)
		(pad "1" smd circle
			(at -0.40005 0 180)
			(size 0 0)
			(layers "F.Cu" "F.Mask" "F.Paste")
			(net "PVDD18_S5_P0")
		)
		(pad "2" smd circle
			(at 0.40005 0 180)
			(size 0 0)
			(layers "F.Cu" "F.Mask" "F.Paste")
			(net "SVID_PVDDCR_CPU0_P0_SVC_R")
		)
	)
	(footprint ""
		(layer "F.Cu")
		(at 214.86241 -26.111454 90)
		(property "Reference" "OSC1"
			(at 2.590546 -0.070612 0)
			(unlocked yes)
			(layer "F.SilkS")
			(effects
				(font
					(size 0.7874 0.5842)
					(thickness 0.1524)
				)
				(justify left)
			)
		)
		(property "Value" ""
			(at 0 0 90)
			(layer "F.Fab")
			(effects
				(font
					(size 1.27 1.27)
				)
			)
		)
		(duplicate_pad_numbers_are_jumpers no)
		(fp_line
			(start 1.546098 -1.94945)
			(end -1.546098 -1.94945)
			(stroke
				(width 0.1524)
				(type default)
			)
			(layer "F.SilkS")
		)
		(fp_line
			(start -1.546098 -1.94945)
			(end -1.546098 1.94945)
			(stroke
				(width 0.1524)
				(type default)
			)
			(layer "F.SilkS")
		)
		(fp_line
			(start 1.546098 1.94945)
			(end 1.546098 -1.94945)
			(stroke
				(width 0.1524)
				(type default)
			)
			(layer "F.SilkS")
		)
		(fp_line
			(start -1.546098 1.94945)
			(end 1.546098 1.94945)
			(stroke
				(width 0.1524)
				(type default)
			)
			(layer "F.SilkS")
		)
		(fp_poly
			(pts
				(xy -1.085596 -2.087372) (xy -0.450596 -3.408172) (xy -1.568196 -3.408172)
			)
			(stroke
				(width 0)
				(type default)
			)
			(fill yes)
			(layer "F.SilkS")
		)
		(fp_line
			(start 1.299972 -1.649984)
			(end 1.299972 1.649984)
			(stroke
				(width 0.1)
				(type default)
			)
			(layer "F.Fab")
		)
		(fp_line
			(start -1.299972 -1.649984)
			(end 1.299972 -1.649984)
			(stroke
				(width 0.1)
				(type default)
			)
			(layer "F.Fab")
		)
		(fp_line
			(start 1.299972 1.649984)
			(end -1.299972 1.649984)
			(stroke
				(width 0.1)
				(type default)
			)
			(layer "F.Fab")
		)
		(fp_line
			(start -1.299972 1.649984)
			(end -1.299972 -1.649984)
			(stroke
				(width 0.1)
				(type default)
			)
			(layer "F.Fab")
		)
		(fp_poly
			(pts
				(xy -1.768094 -1.059942) (xy -3.088894 -1.694942) (xy -3.088894 -0.577342)
			)
			(stroke
				(width 0)
				(type default)
			)
			(fill yes)
			(layer "F.Fab")
		)
		(pad "1" smd rect
			(at -0.8001 -1.059942 90)
			(size 1.2192 1.4986)
			(layers "F.Cu" "F.Mask" "F.Paste")
			(net "CLK_50M_EN")
		)
		(pad "2" smd rect
			(at -0.8001 1.059942 270)
			(size 1.2192 1.4986)
			(layers "F.Cu" "F.Mask" "F.Paste")
			(net "GND")
		)
		(pad "3" smd rect
			(at 0.8001 1.059942 90)
			(size 1.2192 1.4986)
			(layers "F.Cu" "F.Mask" "F.Paste")
			(net "CLK_50M_RMII")
		)
		(pad "4" smd rect
			(at 0.8001 -1.059942 90)
			(size 1.2192 1.4986)
			(layers "F.Cu" "F.Mask" "F.Paste")
			(net "P3V3_AUX")
		)
	)
	(footprint ""
		(layer "F.Cu")
		(at 430.2379 -400.987768 -90)
		(property "Reference" "R1055"
			(at 0 0 270)
			(layer "F.SilkS")
			(hide yes)
			(effects
				(font
					(size 1.27 1.27)
				)
			)
		)
		(property "Value" ""
			(at 0 0 270)
			(layer "F.Fab")
			(effects
				(font
					(size 1.27 1.27)
				)
			)
		)
		(duplicate_pad_numbers_are_jumpers no)
		(fp_line
			(start -0.32512 0.175006)
			(end -0.32512 -0.175006)
			(stroke
				(width 0.1)
				(type default)
			)
			(layer "F.Fab")
		)
		(fp_line
			(start 0.32512 0.175006)
			(end -0.32512 0.175006)
			(stroke
				(width 0.1)
				(type default)
			)
			(layer "F.Fab")
		)
		(fp_line
			(start -0.32512 -0.175006)
			(end 0.32512 -0.175006)
			(stroke
				(width 0.1)
				(type default)
			)
			(layer "F.Fab")
		)
		(fp_line
			(start 0.32512 -0.175006)
			(end 0.32512 0.175006)
			(stroke
				(width 0.1)
				(type default)
			)
			(layer "F.Fab")
		)
		(pad "1" smd rect
			(at -0.2667 0 270)
			(size 0.3048 0.381)
			(layers "F.Cu" "F.Mask" "F.Paste")
			(net "P1V8_CPU0_RT_1D")
		)
		(pad "2" smd rect
			(at 0.2667 0 90)
			(size 0.3048 0.381)
			(layers "F.Cu" "F.Mask" "F.Paste")
			(net "RT_CPU0_P2_ADDR3")
		)
	)
	(footprint ""
		(layer "F.Cu")
		(at 75.081638 -337.658202 90)
		(property "Reference" "PC370"
			(at 0 0 90)
			(layer "F.SilkS")
			(hide yes)
			(effects
				(font
					(size 1.27 1.27)
				)
			)
		)
		(property "Value" ""
			(at 0 0 90)
			(layer "F.Fab")
			(effects
				(font
					(size 1.27 1.27)
				)
			)
		)
		(duplicate_pad_numbers_are_jumpers no)
		(fp_line
			(start 0.7874 -0.4064)
			(end 0.7874 0.4064)
			(stroke
				(width 0.1524)
				(type default)
			)
			(layer "F.SilkS")
		)
		(fp_line
			(start -0.7874 -0.4064)
			(end 0.7874 -0.4064)
			(stroke
				(width 0.1524)
				(type default)
			)
			(layer "F.SilkS")
		)
		(fp_line
			(start 0.7874 0.4064)
			(end 0.415798 0.4064)
			(stroke
				(width 0.1524)
				(type default)
			)
			(layer "F.SilkS")
		)
		(fp_line
			(start -0.447802 0.4064)
			(end -0.7874 0.4064)
			(stroke
				(width 0.1524)
				(type default)
			)
			(layer "F.SilkS")
		)
		(fp_line
			(start -0.7874 0.4064)
			(end -0.7874 -0.4064)
			(stroke
				(width 0.1524)
				(type default)
			)
			(layer "F.SilkS")
		)
		(fp_line
			(start -0.12065 -0.305054)
			(end -0.12065 -0.2794)
			(stroke
				(width 0.1)
				(type default)
			)
			(layer "F.Fab")
		)
		(fp_line
			(start -0.67945 -0.305054)
			(end -0.12065 -0.305054)
			(stroke
				(width 0.1)
				(type default)
			)
			(layer "F.Fab")
		)
		(fp_line
			(start 0.67945 -0.3048)
			(end 0.67945 0.3048)
			(stroke
				(width 0.1)
				(type default)
			)
			(layer "F.Fab")
		)
		(fp_line
			(start 0.12065 -0.3048)
			(end 0.67945 -0.3048)
			(stroke
				(width 0.1)
				(type default)
			)
			(layer "F.Fab")
		)
		(fp_line
			(start 0.12065 -0.2794)
			(end 0.12065 -0.3048)
			(stroke
				(width 0.1)
				(type default)
			)
			(layer "F.Fab")
		)
		(fp_line
			(start -0.12065 -0.2794)
			(end 0.12065 -0.2794)
			(stroke
				(width 0.1)
				(type default)
			)
			(layer "F.Fab")
		)
		(fp_line
			(start 0.120396 0.2794)
			(end -0.12065 0.2794)
			(stroke
				(width 0.1)
				(type default)
			)
			(layer "F.Fab")
		)
		(fp_line
			(start -0.12065 0.2794)
			(end -0.12065 0.3048)
			(stroke
				(width 0.1)
				(type default)
			)
			(layer "F.Fab")
		)
		(fp_line
			(start 0.67945 0.3048)
			(end 0.120396 0.3048)
			(stroke
				(width 0.1)
				(type default)
			)
			(layer "F.Fab")
		)
		(fp_line
			(start 0.120396 0.3048)
			(end 0.120396 0.2794)
			(stroke
				(width 0.1)
				(type default)
			)
			(layer "F.Fab")
		)
		(fp_line
			(start -0.12065 0.3048)
			(end -0.67945 0.3048)
			(stroke
				(width 0.1)
				(type default)
			)
			(layer "F.Fab")
		)
		(fp_line
			(start -0.67945 0.3048)
			(end -0.67945 -0.305054)
			(stroke
				(width 0.1)
				(type default)
			)
			(layer "F.Fab")
		)
		(pad "1" smd circle
			(at -0.40005 0 90)
			(size 0 0)
			(layers "F.Cu" "F.Mask" "F.Paste")
			(net "PVDDCR_CPU1_P1_VCC2")
		)
		(pad "2" smd circle
			(at 0.40005 0 90)
			(size 0 0)
			(layers "F.Cu" "F.Mask" "F.Paste")
			(net "GND")
		)
	)
	(footprint ""
		(layer "F.Cu")
		(at 425.54144 -438.214008 90)
		(property "Reference" "R2834"
			(at 0 0 90)
			(layer "F.SilkS")
			(hide yes)
			(effects
				(font
					(size 1.27 1.27)
				)
			)
		)
		(property "Value" ""
			(at 0 0 90)
			(layer "F.Fab")
			(effects
				(font
					(size 1.27 1.27)
				)
			)
		)
		(duplicate_pad_numbers_are_jumpers no)
		(fp_line
			(start 0.7874 -0.4064)
			(end 0.7874 0.4064)
			(stroke
				(width 0.1524)
				(type default)
			)
			(layer "F.SilkS")
		)
		(fp_line
			(start -0.7874 -0.4064)
			(end 0.7874 -0.4064)
			(stroke
				(width 0.1524)
				(type default)
			)
			(layer "F.SilkS")
		)
		(fp_line
			(start 0.7874 0.4064)
			(end -0.7874 0.4064)
			(stroke
				(width 0.1524)
				(type default)
			)
			(layer "F.SilkS")
		)
		(fp_line
			(start -0.7874 0.4064)
			(end -0.7874 -0.4064)
			(stroke
				(width 0.1524)
				(type default)
			)
			(layer "F.SilkS")
		)
		(fp_line
			(start -0.12065 -0.305054)
			(end -0.12065 -0.2794)
			(stroke
				(width 0.1)
				(type default)
			)
			(layer "F.Fab")
		)
		(fp_line
			(start -0.67945 -0.305054)
			(end -0.12065 -0.305054)
			(stroke
				(width 0.1)
				(type default)
			)
			(layer "F.Fab")
		)
		(fp_line
			(start 0.67945 -0.3048)
			(end 0.67945 0.3048)
			(stroke
				(width 0.1)
				(type default)
			)
			(layer "F.Fab")
		)
		(fp_line
			(start 0.12065 -0.3048)
			(end 0.67945 -0.3048)
			(stroke
				(width 0.1)
				(type default)
			)
			(layer "F.Fab")
		)
		(fp_line
			(start 0.12065 -0.2794)
			(end 0.12065 -0.3048)
			(stroke
				(width 0.1)
				(type default)
			)
			(layer "F.Fab")
		)
		(fp_line
			(start -0.12065 -0.2794)
			(end 0.12065 -0.2794)
			(stroke
				(width 0.1)
				(type default)
			)
			(layer "F.Fab")
		)
		(fp_line
			(start 0.120396 0.2794)
			(end -0.12065 0.2794)
			(stroke
				(width 0.1)
				(type default)
			)
			(layer "F.Fab")
		)
		(fp_line
			(start -0.12065 0.2794)
			(end -0.12065 0.3048)
			(stroke
				(width 0.1)
				(type default)
			)
			(layer "F.Fab")
		)
		(fp_line
			(start 0.67945 0.3048)
			(end 0.120396 0.3048)
			(stroke
				(width 0.1)
				(type default)
			)
			(layer "F.Fab")
		)
		(fp_line
			(start 0.120396 0.3048)
			(end 0.120396 0.2794)
			(stroke
				(width 0.1)
				(type default)
			)
			(layer "F.Fab")
		)
		(fp_line
			(start -0.12065 0.3048)
			(end -0.67945 0.3048)
			(stroke
				(width 0.1)
				(type default)
			)
			(layer "F.Fab")
		)
		(fp_line
			(start -0.67945 0.3048)
			(end -0.67945 -0.305054)
			(stroke
				(width 0.1)
				(type default)
			)
			(layer "F.Fab")
		)
		(pad "1" smd circle
			(at -0.40005 0 90)
			(size 0 0)
			(layers "F.Cu" "F.Mask" "F.Paste")
			(net "P3V3_AUX")
		)
		(pad "2" smd circle
			(at 0.40005 0 90)
			(size 0 0)
			(layers "F.Cu" "F.Mask" "F.Paste")
			(net "RST_BMC_FROM_SWB")
		)
	)
	(footprint ""
		(layer "F.Cu")
		(at 140.208 -114.554)
		(property "Reference" "R8120"
			(at 0 0 0)
			(layer "F.SilkS")
			(hide yes)
			(effects
				(font
					(size 1.27 1.27)
				)
			)
		)
		(property "Value" ""
			(at 0 0 0)
			(layer "F.Fab")
			(effects
				(font
					(size 1.27 1.27)
				)
			)
		)
		(duplicate_pad_numbers_are_jumpers no)
		(fp_line
			(start -0.7874 -0.4064)
			(end 0.7874 -0.4064)
			(stroke
				(width 0.1524)
				(type default)
			)
			(layer "F.SilkS")
		)
		(fp_line
			(start -0.7874 0.4064)
			(end -0.7874 -0.4064)
			(stroke
				(width 0.1524)
				(type default)
			)
			(layer "F.SilkS")
		)
		(fp_line
			(start 0.7874 -0.4064)
			(end 0.7874 0.4064)
			(stroke
				(width 0.1524)
				(type default)
			)
			(layer "F.SilkS")
		)
		(fp_line
			(start 0.7874 0.4064)
			(end -0.7874 0.4064)
			(stroke
				(width 0.1524)
				(type default)
			)
			(layer "F.SilkS")
		)
		(fp_line
			(start -0.67945 -0.305054)
			(end -0.12065 -0.305054)
			(stroke
				(width 0.1)
				(type default)
			)
			(layer "F.Fab")
		)
		(fp_line
			(start -0.67945 0.3048)
			(end -0.67945 -0.305054)
			(stroke
				(width 0.1)
				(type default)
			)
			(layer "F.Fab")
		)
		(fp_line
			(start -0.12065 -0.305054)
			(end -0.12065 -0.2794)
			(stroke
				(width 0.1)
				(type default)
			)
			(layer "F.Fab")
		)
		(fp_line
			(start -0.12065 -0.2794)
			(end 0.12065 -0.2794)
			(stroke
				(width 0.1)
				(type default)
			)
			(layer "F.Fab")
		)
		(fp_line
			(start -0.12065 0.2794)
			(end -0.12065 0.3048)
			(stroke
				(width 0.1)
				(type default)
			)
			(layer "F.Fab")
		)
		(fp_line
			(start -0.12065 0.3048)
			(end -0.67945 0.3048)
			(stroke
				(width 0.1)
				(type default)
			)
			(layer "F.Fab")
		)
		(fp_line
			(start 0.120396 0.2794)
			(end -0.12065 0.2794)
			(stroke
				(width 0.1)
				(type default)
			)
			(layer "F.Fab")
		)
		(fp_line
			(start 0.120396 0.3048)
			(end 0.120396 0.2794)
			(stroke
				(width 0.1)
				(type default)
			)
			(layer "F.Fab")
		)
		(fp_line
			(start 0.12065 -0.3048)
			(end 0.67945 -0.3048)
			(stroke
				(width 0.1)
				(type default)
			)
			(layer "F.Fab")
		)
		(fp_line
			(start 0.12065 -0.2794)
			(end 0.12065 -0.3048)
			(stroke
				(width 0.1)
				(type default)
			)
			(layer "F.Fab")
		)
		(fp_line
			(start 0.67945 -0.3048)
			(end 0.67945 0.3048)
			(stroke
				(width 0.1)
				(type default)
			)
			(layer "F.Fab")
		)
		(fp_line
			(start 0.67945 0.3048)
			(end 0.120396 0.3048)
			(stroke
				(width 0.1)
				(type default)
			)
			(layer "F.Fab")
		)
		(pad "1" smd circle
			(at -0.40005 0)
			(size 0 0)
			(layers "F.Cu" "F.Mask" "F.Paste")
			(net "P3V3_AUX")
		)
		(pad "2" smd circle
			(at 0.40005 0)
			(size 0 0)
			(layers "F.Cu" "F.Mask" "F.Paste")
			(net "UV_P2V5_COMP")
		)
	)
	(footprint ""
		(layer "F.Cu")
		(at 365.835692 -260.305042 180)
		(property "Reference" "C2139"
			(at 0 0 180)
			(layer "F.SilkS")
			(hide yes)
			(effects
				(font
					(size 1.27 1.27)
				)
			)
		)
		(property "Value" ""
			(at 0 0 180)
			(layer "F.Fab")
			(effects
				(font
					(size 1.27 1.27)
				)
			)
		)
		(duplicate_pad_numbers_are_jumpers no)
		(fp_line
			(start 0.7874 0.4064)
			(end -0.7874 0.4064)
			(stroke
				(width 0.1524)
				(type default)
			)
			(layer "F.SilkS")
		)
		(fp_line
			(start 0.7874 -0.4064)
			(end 0.7874 0.4064)
			(stroke
				(width 0.1524)
				(type default)
			)
			(layer "F.SilkS")
		)
		(fp_line
			(start -0.7874 0.4064)
			(end -0.7874 -0.4064)
			(stroke
				(width 0.1524)
				(type default)
			)
			(layer "F.SilkS")
		)
		(fp_line
			(start -0.7874 -0.4064)
			(end 0.7874 -0.4064)
			(stroke
				(width 0.1524)
				(type default)
			)
			(layer "F.SilkS")
		)
		(fp_line
			(start 0.67945 0.3048)
			(end 0.120396 0.3048)
			(stroke
				(width 0.1)
				(type default)
			)
			(layer "F.Fab")
		)
		(fp_line
			(start 0.67945 -0.3048)
			(end 0.67945 0.3048)
			(stroke
				(width 0.1)
				(type default)
			)
			(layer "F.Fab")
		)
		(fp_line
			(start 0.12065 -0.2794)
			(end 0.12065 -0.3048)
			(stroke
				(width 0.1)
				(type default)
			)
			(layer "F.Fab")
		)
		(fp_line
			(start 0.12065 -0.3048)
			(end 0.67945 -0.3048)
			(stroke
				(width 0.1)
				(type default)
			)
			(layer "F.Fab")
		)
		(fp_line
			(start 0.120396 0.3048)
			(end 0.120396 0.2794)
			(stroke
				(width 0.1)
				(type default)
			)
			(layer "F.Fab")
		)
		(fp_line
			(start 0.120396 0.2794)
			(end -0.12065 0.2794)
			(stroke
				(width 0.1)
				(type default)
			)
			(layer "F.Fab")
		)
		(fp_line
			(start -0.12065 0.3048)
			(end -0.67945 0.3048)
			(stroke
				(width 0.1)
				(type default)
			)
			(layer "F.Fab")
		)
		(fp_line
			(start -0.12065 0.2794)
			(end -0.12065 0.3048)
			(stroke
				(width 0.1)
				(type default)
			)
			(layer "F.Fab")
		)
		(fp_line
			(start -0.12065 -0.2794)
			(end 0.12065 -0.2794)
			(stroke
				(width 0.1)
				(type default)
			)
			(layer "F.Fab")
		)
		(fp_line
			(start -0.12065 -0.305054)
			(end -0.12065 -0.2794)
			(stroke
				(width 0.1)
				(type default)
			)
			(layer "F.Fab")
		)
		(fp_line
			(start -0.67945 0.3048)
			(end -0.67945 -0.305054)
			(stroke
				(width 0.1)
				(type default)
			)
			(layer "F.Fab")
		)
		(fp_line
			(start -0.67945 -0.305054)
			(end -0.12065 -0.305054)
			(stroke
				(width 0.1)
				(type default)
			)
			(layer "F.Fab")
		)
		(pad "1" smd circle
			(at -0.40005 0 180)
			(size 0 0)
			(layers "F.Cu" "F.Mask" "F.Paste")
			(net "PVDDCR_SOC_P0")
		)
		(pad "2" smd circle
			(at 0.40005 0 180)
			(size 0 0)
			(layers "F.Cu" "F.Mask" "F.Paste")
			(net "GND")
		)
	)
	(footprint ""
		(layer "F.Cu")
		(at 143.46047 -80.977486 180)
		(property "Reference" "PC6008"
			(at 0 0 180)
			(layer "F.SilkS")
			(hide yes)
			(effects
				(font
					(size 1.27 1.27)
				)
			)
		)
		(property "Value" ""
			(at 0 0 180)
			(layer "F.Fab")
			(effects
				(font
					(size 1.27 1.27)
				)
			)
		)
		(duplicate_pad_numbers_are_jumpers no)
		(fp_line
			(start 0.7874 0.4064)
			(end -0.7874 0.4064)
			(stroke
				(width 0.1524)
				(type default)
			)
			(layer "F.SilkS")
		)
		(fp_line
			(start 0.7874 -0.4064)
			(end 0.7874 0.4064)
			(stroke
				(width 0.1524)
				(type default)
			)
			(layer "F.SilkS")
		)
		(fp_line
			(start -0.7874 0.4064)
			(end -0.7874 -0.4064)
			(stroke
				(width 0.1524)
				(type default)
			)
			(layer "F.SilkS")
		)
		(fp_line
			(start -0.7874 -0.4064)
			(end 0.7874 -0.4064)
			(stroke
				(width 0.1524)
				(type default)
			)
			(layer "F.SilkS")
		)
		(fp_line
			(start 0.67945 0.3048)
			(end 0.120396 0.3048)
			(stroke
				(width 0.1)
				(type default)
			)
			(layer "F.Fab")
		)
		(fp_line
			(start 0.67945 -0.3048)
			(end 0.67945 0.3048)
			(stroke
				(width 0.1)
				(type default)
			)
			(layer "F.Fab")
		)
		(fp_line
			(start 0.12065 -0.2794)
			(end 0.12065 -0.3048)
			(stroke
				(width 0.1)
				(type default)
			)
			(layer "F.Fab")
		)
		(fp_line
			(start 0.12065 -0.3048)
			(end 0.67945 -0.3048)
			(stroke
				(width 0.1)
				(type default)
			)
			(layer "F.Fab")
		)
		(fp_line
			(start 0.120396 0.3048)
			(end 0.120396 0.2794)
			(stroke
				(width 0.1)
				(type default)
			)
			(layer "F.Fab")
		)
		(fp_line
			(start 0.120396 0.2794)
			(end -0.12065 0.2794)
			(stroke
				(width 0.1)
				(type default)
			)
			(layer "F.Fab")
		)
		(fp_line
			(start -0.12065 0.3048)
			(end -0.67945 0.3048)
			(stroke
				(width 0.1)
				(type default)
			)
			(layer "F.Fab")
		)
		(fp_line
			(start -0.12065 0.2794)
			(end -0.12065 0.3048)
			(stroke
				(width 0.1)
				(type default)
			)
			(layer "F.Fab")
		)
		(fp_line
			(start -0.12065 -0.2794)
			(end 0.12065 -0.2794)
			(stroke
				(width 0.1)
				(type default)
			)
			(layer "F.Fab")
		)
		(fp_line
			(start -0.12065 -0.305054)
			(end -0.12065 -0.2794)
			(stroke
				(width 0.1)
				(type default)
			)
			(layer "F.Fab")
		)
		(fp_line
			(start -0.67945 0.3048)
			(end -0.67945 -0.305054)
			(stroke
				(width 0.1)
				(type default)
			)
			(layer "F.Fab")
		)
		(fp_line
			(start -0.67945 -0.305054)
			(end -0.12065 -0.305054)
			(stroke
				(width 0.1)
				(type default)
			)
			(layer "F.Fab")
		)
		(pad "1" smd circle
			(at -0.40005 0 180)
			(size 0 0)
			(layers "F.Cu" "F.Mask" "F.Paste")
			(net "P1V8_AUX_VCC")
		)
		(pad "2" smd circle
			(at 0.40005 0 180)
			(size 0 0)
			(layers "F.Cu" "F.Mask" "F.Paste")
			(net "GND")
		)
	)
	(footprint ""
		(layer "F.Cu")
		(at 391.268458 -404.0124 -90)
		(property "Reference" "R1088"
			(at 0 0 270)
			(layer "F.SilkS")
			(hide yes)
			(effects
				(font
					(size 1.27 1.27)
				)
			)
		)
		(property "Value" ""
			(at 0 0 270)
			(layer "F.Fab")
			(effects
				(font
					(size 1.27 1.27)
				)
			)
		)
		(duplicate_pad_numbers_are_jumpers no)
		(fp_line
			(start -0.32512 0.175006)
			(end -0.32512 -0.175006)
			(stroke
				(width 0.1)
				(type default)
			)
			(layer "F.Fab")
		)
		(fp_line
			(start 0.32512 0.175006)
			(end -0.32512 0.175006)
			(stroke
				(width 0.1)
				(type default)
			)
			(layer "F.Fab")
		)
		(fp_line
			(start -0.32512 -0.175006)
			(end 0.32512 -0.175006)
			(stroke
				(width 0.1)
				(type default)
			)
			(layer "F.Fab")
		)
		(fp_line
			(start 0.32512 -0.175006)
			(end 0.32512 0.175006)
			(stroke
				(width 0.1)
				(type default)
			)
			(layer "F.Fab")
		)
		(pad "1" smd rect
			(at -0.2667 0 270)
			(size 0.3048 0.381)
			(layers "F.Cu" "F.Mask" "F.Paste")
			(net "RST_RT_CPU0_P3_PERST_N")
		)
		(pad "2" smd rect
			(at 0.2667 0 90)
			(size 0.3048 0.381)
			(layers "F.Cu" "F.Mask" "F.Paste")
			(net "RST_RT_CPU0_P3_PERST_R_N")
		)
	)
	(footprint ""
		(layer "F.Cu")
		(at 412.481268 -71.812912)
		(property "Reference" "R1135"
			(at 0 0 0)
			(layer "F.SilkS")
			(hide yes)
			(effects
				(font
					(size 1.27 1.27)
				)
			)
		)
		(property "Value" ""
			(at 0 0 0)
			(layer "F.Fab")
			(effects
				(font
					(size 1.27 1.27)
				)
			)
		)
		(duplicate_pad_numbers_are_jumpers no)
		(fp_line
			(start -0.7874 -0.4064)
			(end 0.7874 -0.4064)
			(stroke
				(width 0.1524)
				(type default)
			)
			(layer "F.SilkS")
		)
		(fp_line
			(start -0.7874 0.4064)
			(end -0.7874 -0.4064)
			(stroke
				(width 0.1524)
				(type default)
			)
			(layer "F.SilkS")
		)
		(fp_line
			(start 0.7874 -0.4064)
			(end 0.7874 0.4064)
			(stroke
				(width 0.1524)
				(type default)
			)
			(layer "F.SilkS")
		)
		(fp_line
			(start 0.7874 0.4064)
			(end -0.7874 0.4064)
			(stroke
				(width 0.1524)
				(type default)
			)
			(layer "F.SilkS")
		)
		(fp_line
			(start -0.67945 -0.305054)
			(end -0.12065 -0.305054)
			(stroke
				(width 0.1)
				(type default)
			)
			(layer "F.Fab")
		)
		(fp_line
			(start -0.67945 0.3048)
			(end -0.67945 -0.305054)
			(stroke
				(width 0.1)
				(type default)
			)
			(layer "F.Fab")
		)
		(fp_line
			(start -0.12065 -0.305054)
			(end -0.12065 -0.2794)
			(stroke
				(width 0.1)
				(type default)
			)
			(layer "F.Fab")
		)
		(fp_line
			(start -0.12065 -0.2794)
			(end 0.12065 -0.2794)
			(stroke
				(width 0.1)
				(type default)
			)
			(layer "F.Fab")
		)
		(fp_line
			(start -0.12065 0.2794)
			(end -0.12065 0.3048)
			(stroke
				(width 0.1)
				(type default)
			)
			(layer "F.Fab")
		)
		(fp_line
			(start -0.12065 0.3048)
			(end -0.67945 0.3048)
			(stroke
				(width 0.1)
				(type default)
			)
			(layer "F.Fab")
		)
		(fp_line
			(start 0.120396 0.2794)
			(end -0.12065 0.2794)
			(stroke
				(width 0.1)
				(type default)
			)
			(layer "F.Fab")
		)
		(fp_line
			(start 0.120396 0.3048)
			(end 0.120396 0.2794)
			(stroke
				(width 0.1)
				(type default)
			)
			(layer "F.Fab")
		)
		(fp_line
			(start 0.12065 -0.3048)
			(end 0.67945 -0.3048)
			(stroke
				(width 0.1)
				(type default)
			)
			(layer "F.Fab")
		)
		(fp_line
			(start 0.12065 -0.2794)
			(end 0.12065 -0.3048)
			(stroke
				(width 0.1)
				(type default)
			)
			(layer "F.Fab")
		)
		(fp_line
			(start 0.67945 -0.3048)
			(end 0.67945 0.3048)
			(stroke
				(width 0.1)
				(type default)
			)
			(layer "F.Fab")
		)
		(fp_line
			(start 0.67945 0.3048)
			(end 0.120396 0.3048)
			(stroke
				(width 0.1)
				(type default)
			)
			(layer "F.Fab")
		)
		(pad "1" smd circle
			(at -0.40005 0)
			(size 0 0)
			(layers "F.Cu" "F.Mask" "F.Paste")
			(net "HP_LVC3_OCP_V3_1_R_EN")
		)
		(pad "2" smd circle
			(at 0.40005 0)
			(size 0 0)
			(layers "F.Cu" "F.Mask" "F.Paste")
			(net "HP_LVC3_OCP_V3_1_P12V_PWRGD")
		)
	)
	(footprint ""
		(layer "F.Cu")
		(at 36.195 -360.045 180)
		(property "Reference" "PC361"
			(at 0 0 180)
			(layer "F.SilkS")
			(hide yes)
			(effects
				(font
					(size 1.27 1.27)
				)
			)
		)
		(property "Value" ""
			(at 0 0 180)
			(layer "F.Fab")
			(effects
				(font
					(size 1.27 1.27)
				)
			)
		)
		(duplicate_pad_numbers_are_jumpers no)
		(fp_line
			(start 0.7874 0.4064)
			(end -0.7874 0.4064)
			(stroke
				(width 0.1524)
				(type default)
			)
			(layer "F.SilkS")
		)
		(fp_line
			(start 0.7874 -0.4064)
			(end 0.7874 0.4064)
			(stroke
				(width 0.1524)
				(type default)
			)
			(layer "F.SilkS")
		)
		(fp_line
			(start -0.7874 0.4064)
			(end -0.7874 -0.4064)
			(stroke
				(width 0.1524)
				(type default)
			)
			(layer "F.SilkS")
		)
		(fp_line
			(start -0.7874 -0.4064)
			(end 0.7874 -0.4064)
			(stroke
				(width 0.1524)
				(type default)
			)
			(layer "F.SilkS")
		)
		(fp_line
			(start 0.67945 0.3048)
			(end 0.120396 0.3048)
			(stroke
				(width 0.1)
				(type default)
			)
			(layer "F.Fab")
		)
		(fp_line
			(start 0.67945 -0.3048)
			(end 0.67945 0.3048)
			(stroke
				(width 0.1)
				(type default)
			)
			(layer "F.Fab")
		)
		(fp_line
			(start 0.12065 -0.2794)
			(end 0.12065 -0.3048)
			(stroke
				(width 0.1)
				(type default)
			)
			(layer "F.Fab")
		)
		(fp_line
			(start 0.12065 -0.3048)
			(end 0.67945 -0.3048)
			(stroke
				(width 0.1)
				(type default)
			)
			(layer "F.Fab")
		)
		(fp_line
			(start 0.120396 0.3048)
			(end 0.120396 0.2794)
			(stroke
				(width 0.1)
				(type default)
			)
			(layer "F.Fab")
		)
		(fp_line
			(start 0.120396 0.2794)
			(end -0.12065 0.2794)
			(stroke
				(width 0.1)
				(type default)
			)
			(layer "F.Fab")
		)
		(fp_line
			(start -0.12065 0.3048)
			(end -0.67945 0.3048)
			(stroke
				(width 0.1)
				(type default)
			)
			(layer "F.Fab")
		)
		(fp_line
			(start -0.12065 0.2794)
			(end -0.12065 0.3048)
			(stroke
				(width 0.1)
				(type default)
			)
			(layer "F.Fab")
		)
		(fp_line
			(start -0.12065 -0.2794)
			(end 0.12065 -0.2794)
			(stroke
				(width 0.1)
				(type default)
			)
			(layer "F.Fab")
		)
		(fp_line
			(start -0.12065 -0.305054)
			(end -0.12065 -0.2794)
			(stroke
				(width 0.1)
				(type default)
			)
			(layer "F.Fab")
		)
		(fp_line
			(start -0.67945 0.3048)
			(end -0.67945 -0.305054)
			(stroke
				(width 0.1)
				(type default)
			)
			(layer "F.Fab")
		)
		(fp_line
			(start -0.67945 -0.305054)
			(end -0.12065 -0.305054)
			(stroke
				(width 0.1)
				(type default)
			)
			(layer "F.Fab")
		)
		(pad "1" smd circle
			(at -0.40005 0 180)
			(size 0 0)
			(layers "F.Cu" "F.Mask" "F.Paste")
			(net "VSENSE_PVDDIO_P1_VSEN1")
		)
		(pad "2" smd circle
			(at 0.40005 0 180)
			(size 0 0)
			(layers "F.Cu" "F.Mask" "F.Paste")
			(net "VSENSE_VSS_SENSE_B_P1")
		)
	)
	(footprint ""
		(layer "F.Cu")
		(at 117.792754 -76.987654 90)
		(property "Reference" "PC6013"
			(at 0 0 90)
			(layer "F.SilkS")
			(hide yes)
			(effects
				(font
					(size 1.27 1.27)
				)
			)
		)
		(property "Value" ""
			(at 0 0 90)
			(layer "F.Fab")
			(effects
				(font
					(size 1.27 1.27)
				)
			)
		)
		(duplicate_pad_numbers_are_jumpers no)
		(fp_line
			(start 1.524 -0.762)
			(end 1.524 0.762)
			(stroke
				(width 0.1524)
				(type default)
			)
			(layer "F.SilkS")
		)
		(fp_line
			(start -1.524 -0.762)
			(end 1.524 -0.762)
			(stroke
				(width 0.1524)
				(type default)
			)
			(layer "F.SilkS")
		)
		(fp_line
			(start 1.524 0.762)
			(end -1.524 0.762)
			(stroke
				(width 0.1524)
				(type default)
			)
			(layer "F.SilkS")
		)
		(fp_line
			(start -1.524 0.762)
			(end -1.524 -0.762)
			(stroke
				(width 0.1524)
				(type default)
			)
			(layer "F.SilkS")
		)
		(fp_line
			(start 1.1049 -0.724916)
			(end -1.1049 -0.724916)
			(stroke
				(width 0.1)
				(type default)
			)
			(layer "F.Fab")
		)
		(fp_line
			(start -1.1049 -0.724916)
			(end -1.1049 0.724916)
			(stroke
				(width 0.1)
				(type default)
			)
			(layer "F.Fab")
		)
		(fp_line
			(start 1.1049 0.724916)
			(end 1.1049 -0.724916)
			(stroke
				(width 0.1)
				(type default)
			)
			(layer "F.Fab")
		)
		(fp_line
			(start -1.1049 0.724916)
			(end 1.1049 0.724916)
			(stroke
				(width 0.1)
				(type default)
			)
			(layer "F.Fab")
		)
		(pad "1" smd rect
			(at -0.889 0 270)
			(size 1.016 1.27)
			(layers "F.Cu" "F.Mask" "F.Paste")
			(net "SW_P12V_AUX_P1V2_AUX_FLT")
		)
		(pad "2" smd rect
			(at 0.889 0 270)
			(size 1.016 1.27)
			(layers "F.Cu" "F.Mask" "F.Paste")
			(net "GND")
		)
	)
	(footprint ""
		(layer "F.Cu")
		(at 159.07893 -352.668078 -90)
		(property "Reference" "R8383"
			(at 0 0 270)
			(layer "F.SilkS")
			(hide yes)
			(effects
				(font
					(size 1.27 1.27)
				)
			)
		)
		(property "Value" ""
			(at 0 0 270)
			(layer "F.Fab")
			(effects
				(font
					(size 1.27 1.27)
				)
			)
		)
		(duplicate_pad_numbers_are_jumpers no)
		(fp_line
			(start -0.7874 0.4064)
			(end -0.7874 -0.4064)
			(stroke
				(width 0.1524)
				(type default)
			)
			(layer "F.SilkS")
		)
		(fp_line
			(start 0.7874 0.4064)
			(end -0.7874 0.4064)
			(stroke
				(width 0.1524)
				(type default)
			)
			(layer "F.SilkS")
		)
		(fp_line
			(start -0.7874 -0.4064)
			(end 0.7874 -0.4064)
			(stroke
				(width 0.1524)
				(type default)
			)
			(layer "F.SilkS")
		)
		(fp_line
			(start 0.7874 -0.4064)
			(end 0.7874 0.4064)
			(stroke
				(width 0.1524)
				(type default)
			)
			(layer "F.SilkS")
		)
		(fp_line
			(start -0.67945 0.3048)
			(end -0.67945 -0.305054)
			(stroke
				(width 0.1)
				(type default)
			)
			(layer "F.Fab")
		)
		(fp_line
			(start -0.12065 0.3048)
			(end -0.67945 0.3048)
			(stroke
				(width 0.1)
				(type default)
			)
			(layer "F.Fab")
		)
		(fp_line
			(start 0.120396 0.3048)
			(end 0.120396 0.2794)
			(stroke
				(width 0.1)
				(type default)
			)
			(layer "F.Fab")
		)
		(fp_line
			(start 0.67945 0.3048)
			(end 0.120396 0.3048)
			(stroke
				(width 0.1)
				(type default)
			)
			(layer "F.Fab")
		)
		(fp_line
			(start -0.12065 0.2794)
			(end -0.12065 0.3048)
			(stroke
				(width 0.1)
				(type default)
			)
			(layer "F.Fab")
		)
		(fp_line
			(start 0.120396 0.2794)
			(end -0.12065 0.2794)
			(stroke
				(width 0.1)
				(type default)
			)
			(layer "F.Fab")
		)
		(fp_line
			(start -0.12065 -0.2794)
			(end 0.12065 -0.2794)
			(stroke
				(width 0.1)
				(type default)
			)
			(layer "F.Fab")
		)
		(fp_line
			(start 0.12065 -0.2794)
			(end 0.12065 -0.3048)
			(stroke
				(width 0.1)
				(type default)
			)
			(layer "F.Fab")
		)
		(fp_line
			(start 0.12065 -0.3048)
			(end 0.67945 -0.3048)
			(stroke
				(width 0.1)
				(type default)
			)
			(layer "F.Fab")
		)
		(fp_line
			(start 0.67945 -0.3048)
			(end 0.67945 0.3048)
			(stroke
				(width 0.1)
				(type default)
			)
			(layer "F.Fab")
		)
		(fp_line
			(start -0.67945 -0.305054)
			(end -0.12065 -0.305054)
			(stroke
				(width 0.1)
				(type default)
			)
			(layer "F.Fab")
		)
		(fp_line
			(start -0.12065 -0.305054)
			(end -0.12065 -0.2794)
			(stroke
				(width 0.1)
				(type default)
			)
			(layer "F.Fab")
		)
		(pad "1" smd circle
			(at -0.40005 0 270)
			(size 0 0)
			(layers "F.Cu" "F.Mask" "F.Paste")
			(net "PVDD11_S3_P1_PMALERT")
		)
		(pad "2" smd circle
			(at 0.40005 0 270)
			(size 0 0)
			(layers "F.Cu" "F.Mask" "F.Paste")
			(net "PVDD11_S3_P1_PMALERT_R")
		)
	)
	(footprint ""
		(layer "F.Cu")
		(at 305.175158 -439.877962 180)
		(property "Reference" "R4138"
			(at 0 0 180)
			(layer "F.SilkS")
			(hide yes)
			(effects
				(font
					(size 1.27 1.27)
				)
			)
		)
		(property "Value" ""
			(at 0 0 180)
			(layer "F.Fab")
			(effects
				(font
					(size 1.27 1.27)
				)
			)
		)
		(duplicate_pad_numbers_are_jumpers no)
		(fp_line
			(start 0.7874 0.4064)
			(end -0.7874 0.4064)
			(stroke
				(width 0.1524)
				(type default)
			)
			(layer "F.SilkS")
		)
		(fp_line
			(start 0.7874 -0.4064)
			(end 0.7874 0.4064)
			(stroke
				(width 0.1524)
				(type default)
			)
			(layer "F.SilkS")
		)
		(fp_line
			(start -0.7874 0.4064)
			(end -0.7874 -0.4064)
			(stroke
				(width 0.1524)
				(type default)
			)
			(layer "F.SilkS")
		)
		(fp_line
			(start -0.7874 -0.4064)
			(end 0.7874 -0.4064)
			(stroke
				(width 0.1524)
				(type default)
			)
			(layer "F.SilkS")
		)
		(fp_line
			(start 0.67945 0.3048)
			(end 0.120396 0.3048)
			(stroke
				(width 0.1)
				(type default)
			)
			(layer "F.Fab")
		)
		(fp_line
			(start 0.67945 -0.3048)
			(end 0.67945 0.3048)
			(stroke
				(width 0.1)
				(type default)
			)
			(layer "F.Fab")
		)
		(fp_line
			(start 0.12065 -0.2794)
			(end 0.12065 -0.3048)
			(stroke
				(width 0.1)
				(type default)
			)
			(layer "F.Fab")
		)
		(fp_line
			(start 0.12065 -0.3048)
			(end 0.67945 -0.3048)
			(stroke
				(width 0.1)
				(type default)
			)
			(layer "F.Fab")
		)
		(fp_line
			(start 0.120396 0.3048)
			(end 0.120396 0.2794)
			(stroke
				(width 0.1)
				(type default)
			)
			(layer "F.Fab")
		)
		(fp_line
			(start 0.120396 0.2794)
			(end -0.12065 0.2794)
			(stroke
				(width 0.1)
				(type default)
			)
			(layer "F.Fab")
		)
		(fp_line
			(start -0.12065 0.3048)
			(end -0.67945 0.3048)
			(stroke
				(width 0.1)
				(type default)
			)
			(layer "F.Fab")
		)
		(fp_line
			(start -0.12065 0.2794)
			(end -0.12065 0.3048)
			(stroke
				(width 0.1)
				(type default)
			)
			(layer "F.Fab")
		)
		(fp_line
			(start -0.12065 -0.2794)
			(end 0.12065 -0.2794)
			(stroke
				(width 0.1)
				(type default)
			)
			(layer "F.Fab")
		)
		(fp_line
			(start -0.12065 -0.305054)
			(end -0.12065 -0.2794)
			(stroke
				(width 0.1)
				(type default)
			)
			(layer "F.Fab")
		)
		(fp_line
			(start -0.67945 0.3048)
			(end -0.67945 -0.305054)
			(stroke
				(width 0.1)
				(type default)
			)
			(layer "F.Fab")
		)
		(fp_line
			(start -0.67945 -0.305054)
			(end -0.12065 -0.305054)
			(stroke
				(width 0.1)
				(type default)
			)
			(layer "F.Fab")
		)
		(pad "1" smd circle
			(at -0.40005 0 180)
			(size 0 0)
			(layers "F.Cu" "F.Mask" "F.Paste")
			(net "P3V3_AUX")
		)
		(pad "2" smd circle
			(at 0.40005 0 180)
			(size 0 0)
			(layers "F.Cu" "F.Mask" "F.Paste")
			(net "GPU_3V3IO_RSVD5_FFU_N")
		)
	)
	(footprint ""
		(layer "F.Cu")
		(at 177.927 -137.632948 90)
		(property "Reference" "R18"
			(at 0 0 90)
			(layer "F.SilkS")
			(hide yes)
			(effects
				(font
					(size 1.27 1.27)
				)
			)
		)
		(property "Value" ""
			(at 0 0 90)
			(layer "F.Fab")
			(effects
				(font
					(size 1.27 1.27)
				)
			)
		)
		(duplicate_pad_numbers_are_jumpers no)
		(fp_line
			(start 0.7874 -0.4064)
			(end 0.7874 0.4064)
			(stroke
				(width 0.1524)
				(type default)
			)
			(layer "F.SilkS")
		)
		(fp_line
			(start -0.7874 -0.4064)
			(end 0.7874 -0.4064)
			(stroke
				(width 0.1524)
				(type default)
			)
			(layer "F.SilkS")
		)
		(fp_line
			(start 0.7874 0.4064)
			(end -0.7874 0.4064)
			(stroke
				(width 0.1524)
				(type default)
			)
			(layer "F.SilkS")
		)
		(fp_line
			(start -0.7874 0.4064)
			(end -0.7874 -0.4064)
			(stroke
				(width 0.1524)
				(type default)
			)
			(layer "F.SilkS")
		)
		(fp_line
			(start -0.12065 -0.305054)
			(end -0.12065 -0.2794)
			(stroke
				(width 0.1)
				(type default)
			)
			(layer "F.Fab")
		)
		(fp_line
			(start -0.67945 -0.305054)
			(end -0.12065 -0.305054)
			(stroke
				(width 0.1)
				(type default)
			)
			(layer "F.Fab")
		)
		(fp_line
			(start 0.67945 -0.3048)
			(end 0.67945 0.3048)
			(stroke
				(width 0.1)
				(type default)
			)
			(layer "F.Fab")
		)
		(fp_line
			(start 0.12065 -0.3048)
			(end 0.67945 -0.3048)
			(stroke
				(width 0.1)
				(type default)
			)
			(layer "F.Fab")
		)
		(fp_line
			(start 0.12065 -0.2794)
			(end 0.12065 -0.3048)
			(stroke
				(width 0.1)
				(type default)
			)
			(layer "F.Fab")
		)
		(fp_line
			(start -0.12065 -0.2794)
			(end 0.12065 -0.2794)
			(stroke
				(width 0.1)
				(type default)
			)
			(layer "F.Fab")
		)
		(fp_line
			(start 0.120396 0.2794)
			(end -0.12065 0.2794)
			(stroke
				(width 0.1)
				(type default)
			)
			(layer "F.Fab")
		)
		(fp_line
			(start -0.12065 0.2794)
			(end -0.12065 0.3048)
			(stroke
				(width 0.1)
				(type default)
			)
			(layer "F.Fab")
		)
		(fp_line
			(start 0.67945 0.3048)
			(end 0.120396 0.3048)
			(stroke
				(width 0.1)
				(type default)
			)
			(layer "F.Fab")
		)
		(fp_line
			(start 0.120396 0.3048)
			(end 0.120396 0.2794)
			(stroke
				(width 0.1)
				(type default)
			)
			(layer "F.Fab")
		)
		(fp_line
			(start -0.12065 0.3048)
			(end -0.67945 0.3048)
			(stroke
				(width 0.1)
				(type default)
			)
			(layer "F.Fab")
		)
		(fp_line
			(start -0.67945 0.3048)
			(end -0.67945 -0.305054)
			(stroke
				(width 0.1)
				(type default)
			)
			(layer "F.Fab")
		)
		(pad "1" smd circle
			(at -0.40005 0 90)
			(size 0 0)
			(layers "F.Cu" "F.Mask" "F.Paste")
			(net "RST_CPU1_PERST0_N")
		)
		(pad "2" smd circle
			(at 0.40005 0 90)
			(size 0 0)
			(layers "F.Cu" "F.Mask" "F.Paste")
			(net "GND")
		)
	)
	(footprint ""
		(layer "F.Cu")
		(at 416.136836 -142.185898 -90)
		(property "Reference" "PC1848"
			(at 0 0 270)
			(layer "F.SilkS")
			(hide yes)
			(effects
				(font
					(size 1.27 1.27)
				)
			)
		)
		(property "Value" ""
			(at 0 0 270)
			(layer "F.Fab")
			(effects
				(font
					(size 1.27 1.27)
				)
			)
		)
		(duplicate_pad_numbers_are_jumpers no)
		(fp_line
			(start -0.7874 0.4064)
			(end -0.7874 -0.4064)
			(stroke
				(width 0.1524)
				(type default)
			)
			(layer "F.SilkS")
		)
		(fp_line
			(start 0.7874 0.4064)
			(end -0.7874 0.4064)
			(stroke
				(width 0.1524)
				(type default)
			)
			(layer "F.SilkS")
		)
		(fp_line
			(start -0.7874 -0.4064)
			(end 0.7874 -0.4064)
			(stroke
				(width 0.1524)
				(type default)
			)
			(layer "F.SilkS")
		)
		(fp_line
			(start 0.7874 -0.4064)
			(end 0.7874 0.4064)
			(stroke
				(width 0.1524)
				(type default)
			)
			(layer "F.SilkS")
		)
		(fp_line
			(start -0.67945 0.3048)
			(end -0.67945 -0.305054)
			(stroke
				(width 0.1)
				(type default)
			)
			(layer "F.Fab")
		)
		(fp_line
			(start -0.12065 0.3048)
			(end -0.67945 0.3048)
			(stroke
				(width 0.1)
				(type default)
			)
			(layer "F.Fab")
		)
		(fp_line
			(start 0.120396 0.3048)
			(end 0.120396 0.2794)
			(stroke
				(width 0.1)
				(type default)
			)
			(layer "F.Fab")
		)
		(fp_line
			(start 0.67945 0.3048)
			(end 0.120396 0.3048)
			(stroke
				(width 0.1)
				(type default)
			)
			(layer "F.Fab")
		)
		(fp_line
			(start -0.12065 0.2794)
			(end -0.12065 0.3048)
			(stroke
				(width 0.1)
				(type default)
			)
			(layer "F.Fab")
		)
		(fp_line
			(start 0.120396 0.2794)
			(end -0.12065 0.2794)
			(stroke
				(width 0.1)
				(type default)
			)
			(layer "F.Fab")
		)
		(fp_line
			(start -0.12065 -0.2794)
			(end 0.12065 -0.2794)
			(stroke
				(width 0.1)
				(type default)
			)
			(layer "F.Fab")
		)
		(fp_line
			(start 0.12065 -0.2794)
			(end 0.12065 -0.3048)
			(stroke
				(width 0.1)
				(type default)
			)
			(layer "F.Fab")
		)
		(fp_line
			(start 0.12065 -0.3048)
			(end 0.67945 -0.3048)
			(stroke
				(width 0.1)
				(type default)
			)
			(layer "F.Fab")
		)
		(fp_line
			(start 0.67945 -0.3048)
			(end 0.67945 0.3048)
			(stroke
				(width 0.1)
				(type default)
			)
			(layer "F.Fab")
		)
		(fp_line
			(start -0.67945 -0.305054)
			(end -0.12065 -0.305054)
			(stroke
				(width 0.1)
				(type default)
			)
			(layer "F.Fab")
		)
		(fp_line
			(start -0.12065 -0.305054)
			(end -0.12065 -0.2794)
			(stroke
				(width 0.1)
				(type default)
			)
			(layer "F.Fab")
		)
		(pad "1" smd circle
			(at -0.40005 0 270)
			(size 0 0)
			(layers "F.Cu" "F.Mask" "F.Paste")
			(net "P5V_AUX_VCC")
		)
		(pad "2" smd circle
			(at 0.40005 0 270)
			(size 0 0)
			(layers "F.Cu" "F.Mask" "F.Paste")
			(net "GND")
		)
	)
	(footprint ""
		(layer "F.Cu")
		(at 14.82471 -139.25804 -90)
		(property "Reference" "R4080"
			(at 0 0 270)
			(layer "F.SilkS")
			(hide yes)
			(effects
				(font
					(size 1.27 1.27)
				)
			)
		)
		(property "Value" ""
			(at 0 0 270)
			(layer "F.Fab")
			(effects
				(font
					(size 1.27 1.27)
				)
			)
		)
		(duplicate_pad_numbers_are_jumpers no)
		(fp_line
			(start -0.7874 0.4064)
			(end -0.7874 -0.4064)
			(stroke
				(width 0.1524)
				(type default)
			)
			(layer "F.SilkS")
		)
		(fp_line
			(start 0.7874 0.4064)
			(end -0.7874 0.4064)
			(stroke
				(width 0.1524)
				(type default)
			)
			(layer "F.SilkS")
		)
		(fp_line
			(start -0.7874 -0.4064)
			(end 0.7874 -0.4064)
			(stroke
				(width 0.1524)
				(type default)
			)
			(layer "F.SilkS")
		)
		(fp_line
			(start 0.7874 -0.4064)
			(end 0.7874 0.4064)
			(stroke
				(width 0.1524)
				(type default)
			)
			(layer "F.SilkS")
		)
		(fp_line
			(start -0.67945 0.3048)
			(end -0.67945 -0.305054)
			(stroke
				(width 0.1)
				(type default)
			)
			(layer "F.Fab")
		)
		(fp_line
			(start -0.12065 0.3048)
			(end -0.67945 0.3048)
			(stroke
				(width 0.1)
				(type default)
			)
			(layer "F.Fab")
		)
		(fp_line
			(start 0.120396 0.3048)
			(end 0.120396 0.2794)
			(stroke
				(width 0.1)
				(type default)
			)
			(layer "F.Fab")
		)
		(fp_line
			(start 0.67945 0.3048)
			(end 0.120396 0.3048)
			(stroke
				(width 0.1)
				(type default)
			)
			(layer "F.Fab")
		)
		(fp_line
			(start -0.12065 0.2794)
			(end -0.12065 0.3048)
			(stroke
				(width 0.1)
				(type default)
			)
			(layer "F.Fab")
		)
		(fp_line
			(start 0.120396 0.2794)
			(end -0.12065 0.2794)
			(stroke
				(width 0.1)
				(type default)
			)
			(layer "F.Fab")
		)
		(fp_line
			(start -0.12065 -0.2794)
			(end 0.12065 -0.2794)
			(stroke
				(width 0.1)
				(type default)
			)
			(layer "F.Fab")
		)
		(fp_line
			(start 0.12065 -0.2794)
			(end 0.12065 -0.3048)
			(stroke
				(width 0.1)
				(type default)
			)
			(layer "F.Fab")
		)
		(fp_line
			(start 0.12065 -0.3048)
			(end 0.67945 -0.3048)
			(stroke
				(width 0.1)
				(type default)
			)
			(layer "F.Fab")
		)
		(fp_line
			(start 0.67945 -0.3048)
			(end 0.67945 0.3048)
			(stroke
				(width 0.1)
				(type default)
			)
			(layer "F.Fab")
		)
		(fp_line
			(start -0.67945 -0.305054)
			(end -0.12065 -0.305054)
			(stroke
				(width 0.1)
				(type default)
			)
			(layer "F.Fab")
		)
		(fp_line
			(start -0.12065 -0.305054)
			(end -0.12065 -0.2794)
			(stroke
				(width 0.1)
				(type default)
			)
			(layer "F.Fab")
		)
		(pad "1" smd circle
			(at -0.40005 0 270)
			(size 0 0)
			(layers "F.Cu" "F.Mask" "F.Paste")
			(net "P3V3_AUX")
		)
		(pad "2" smd circle
			(at 0.40005 0 270)
			(size 0 0)
			(layers "F.Cu" "F.Mask" "F.Paste")
			(net "P3V3_PWRGD_CLKGEN")
		)
	)
	(footprint ""
		(layer "F.Cu")
		(at 181.648608 -413.786574 90)
		(property "Reference" "R2922"
			(at 0 0 90)
			(layer "F.SilkS")
			(hide yes)
			(effects
				(font
					(size 1.27 1.27)
				)
			)
		)
		(property "Value" ""
			(at 0 0 90)
			(layer "F.Fab")
			(effects
				(font
					(size 1.27 1.27)
				)
			)
		)
		(duplicate_pad_numbers_are_jumpers no)
		(fp_line
			(start 0.7874 -0.4064)
			(end 0.7874 0.4064)
			(stroke
				(width 0.1524)
				(type default)
			)
			(layer "F.SilkS")
		)
		(fp_line
			(start -0.7874 -0.4064)
			(end 0.7874 -0.4064)
			(stroke
				(width 0.1524)
				(type default)
			)
			(layer "F.SilkS")
		)
		(fp_line
			(start 0.7874 0.4064)
			(end -0.7874 0.4064)
			(stroke
				(width 0.1524)
				(type default)
			)
			(layer "F.SilkS")
		)
		(fp_line
			(start -0.7874 0.4064)
			(end -0.7874 -0.4064)
			(stroke
				(width 0.1524)
				(type default)
			)
			(layer "F.SilkS")
		)
		(fp_line
			(start -0.12065 -0.305054)
			(end -0.12065 -0.2794)
			(stroke
				(width 0.1)
				(type default)
			)
			(layer "F.Fab")
		)
		(fp_line
			(start -0.67945 -0.305054)
			(end -0.12065 -0.305054)
			(stroke
				(width 0.1)
				(type default)
			)
			(layer "F.Fab")
		)
		(fp_line
			(start 0.67945 -0.3048)
			(end 0.67945 0.3048)
			(stroke
				(width 0.1)
				(type default)
			)
			(layer "F.Fab")
		)
		(fp_line
			(start 0.12065 -0.3048)
			(end 0.67945 -0.3048)
			(stroke
				(width 0.1)
				(type default)
			)
			(layer "F.Fab")
		)
		(fp_line
			(start 0.12065 -0.2794)
			(end 0.12065 -0.3048)
			(stroke
				(width 0.1)
				(type default)
			)
			(layer "F.Fab")
		)
		(fp_line
			(start -0.12065 -0.2794)
			(end 0.12065 -0.2794)
			(stroke
				(width 0.1)
				(type default)
			)
			(layer "F.Fab")
		)
		(fp_line
			(start 0.120396 0.2794)
			(end -0.12065 0.2794)
			(stroke
				(width 0.1)
				(type default)
			)
			(layer "F.Fab")
		)
		(fp_line
			(start -0.12065 0.2794)
			(end -0.12065 0.3048)
			(stroke
				(width 0.1)
				(type default)
			)
			(layer "F.Fab")
		)
		(fp_line
			(start 0.67945 0.3048)
			(end 0.120396 0.3048)
			(stroke
				(width 0.1)
				(type default)
			)
			(layer "F.Fab")
		)
		(fp_line
			(start 0.120396 0.3048)
			(end 0.120396 0.2794)
			(stroke
				(width 0.1)
				(type default)
			)
			(layer "F.Fab")
		)
		(fp_line
			(start -0.12065 0.3048)
			(end -0.67945 0.3048)
			(stroke
				(width 0.1)
				(type default)
			)
			(layer "F.Fab")
		)
		(fp_line
			(start -0.67945 0.3048)
			(end -0.67945 -0.305054)
			(stroke
				(width 0.1)
				(type default)
			)
			(layer "F.Fab")
		)
		(pad "1" smd circle
			(at -0.40005 0 90)
			(size 0 0)
			(layers "F.Cu" "F.Mask" "F.Paste")
			(net "RST_SMB_SWITCH_N")
		)
		(pad "2" smd circle
			(at 0.40005 0 90)
			(size 0 0)
			(layers "F.Cu" "F.Mask" "F.Paste")
			(net "PU_RST_SMB_U181_N")
		)
	)
	(footprint ""
		(layer "F.Cu")
		(at 356.29596 -257.744976)
		(property "Reference" "C2525"
			(at 0 0 0)
			(layer "F.SilkS")
			(hide yes)
			(effects
				(font
					(size 1.27 1.27)
				)
			)
		)
		(property "Value" ""
			(at 0 0 0)
			(layer "F.Fab")
			(effects
				(font
					(size 1.27 1.27)
				)
			)
		)
		(duplicate_pad_numbers_are_jumpers no)
		(fp_line
			(start -0.7874 -0.4064)
			(end 0.7874 -0.4064)
			(stroke
				(width 0.1524)
				(type default)
			)
			(layer "F.SilkS")
		)
		(fp_line
			(start -0.7874 0.4064)
			(end -0.7874 -0.4064)
			(stroke
				(width 0.1524)
				(type default)
			)
			(layer "F.SilkS")
		)
		(fp_line
			(start 0.7874 -0.4064)
			(end 0.7874 0.4064)
			(stroke
				(width 0.1524)
				(type default)
			)
			(layer "F.SilkS")
		)
		(fp_line
			(start 0.7874 0.4064)
			(end -0.7874 0.4064)
			(stroke
				(width 0.1524)
				(type default)
			)
			(layer "F.SilkS")
		)
		(fp_line
			(start -0.67945 -0.305054)
			(end -0.12065 -0.305054)
			(stroke
				(width 0.1)
				(type default)
			)
			(layer "F.Fab")
		)
		(fp_line
			(start -0.67945 0.3048)
			(end -0.67945 -0.305054)
			(stroke
				(width 0.1)
				(type default)
			)
			(layer "F.Fab")
		)
		(fp_line
			(start -0.12065 -0.305054)
			(end -0.12065 -0.2794)
			(stroke
				(width 0.1)
				(type default)
			)
			(layer "F.Fab")
		)
		(fp_line
			(start -0.12065 -0.2794)
			(end 0.12065 -0.2794)
			(stroke
				(width 0.1)
				(type default)
			)
			(layer "F.Fab")
		)
		(fp_line
			(start -0.12065 0.2794)
			(end -0.12065 0.3048)
			(stroke
				(width 0.1)
				(type default)
			)
			(layer "F.Fab")
		)
		(fp_line
			(start -0.12065 0.3048)
			(end -0.67945 0.3048)
			(stroke
				(width 0.1)
				(type default)
			)
			(layer "F.Fab")
		)
		(fp_line
			(start 0.120396 0.2794)
			(end -0.12065 0.2794)
			(stroke
				(width 0.1)
				(type default)
			)
			(layer "F.Fab")
		)
		(fp_line
			(start 0.120396 0.3048)
			(end 0.120396 0.2794)
			(stroke
				(width 0.1)
				(type default)
			)
			(layer "F.Fab")
		)
		(fp_line
			(start 0.12065 -0.3048)
			(end 0.67945 -0.3048)
			(stroke
				(width 0.1)
				(type default)
			)
			(layer "F.Fab")
		)
		(fp_line
			(start 0.12065 -0.2794)
			(end 0.12065 -0.3048)
			(stroke
				(width 0.1)
				(type default)
			)
			(layer "F.Fab")
		)
		(fp_line
			(start 0.67945 -0.3048)
			(end 0.67945 0.3048)
			(stroke
				(width 0.1)
				(type default)
			)
			(layer "F.Fab")
		)
		(fp_line
			(start 0.67945 0.3048)
			(end 0.120396 0.3048)
			(stroke
				(width 0.1)
				(type default)
			)
			(layer "F.Fab")
		)
		(pad "1" smd circle
			(at -0.40005 0)
			(size 0 0)
			(layers "F.Cu" "F.Mask" "F.Paste")
			(net "PVDD18_S5_P0")
		)
		(pad "2" smd circle
			(at 0.40005 0)
			(size 0 0)
			(layers "F.Cu" "F.Mask" "F.Paste")
			(net "GND")
		)
	)
	(footprint ""
		(layer "F.Cu")
		(at 300.538388 5.082794 180)
		(property "Reference" "J85"
			(at -4.414774 -1.317498 90)
			(unlocked yes)
			(layer "F.SilkS")
			(effects
				(font
					(size 0.7874 0.5842)
					(thickness 0.1524)
				)
				(justify left)
			)
		)
		(property "Value" ""
			(at 0 0 180)
			(layer "F.Fab")
			(effects
				(font
					(size 1.27 1.27)
				)
			)
		)
		(duplicate_pad_numbers_are_jumpers no)
		(fp_line
			(start 1.2192 2.06756)
			(end -1.2192 2.06756)
			(stroke
				(width 0.1524)
				(type default)
			)
			(layer "F.SilkS")
		)
		(fp_line
			(start 1.2192 -2.06756)
			(end 1.2192 2.06756)
			(stroke
				(width 0.1524)
				(type default)
			)
			(layer "F.SilkS")
		)
		(fp_line
			(start -1.2192 2.06756)
			(end -1.2192 -2.06756)
			(stroke
				(width 0.1524)
				(type default)
			)
			(layer "F.SilkS")
		)
		(fp_line
			(start -1.2192 -2.06756)
			(end 1.2192 -2.06756)
			(stroke
				(width 0.1524)
				(type default)
			)
			(layer "F.SilkS")
		)
		(pad "" np_thru_hole circle
			(at -2.8829 -1.27 90)
			(size 1.0414 1.0414)
			(drill 1.0414)
			(layers "*.Cu" "*.Mask")
			(clearance 0.381)
			(thermal_gap 0.381)
		)
		(pad "" np_thru_hole circle
			(at -2.8829 1.27 90)
			(size 1.0414 1.0414)
			(drill 1.0414)
			(layers "*.Cu" "*.Mask")
			(clearance 0.381)
			(thermal_gap 0.381)
		)
		(pad "" np_thru_hole circle
			(at 3.4671 -1.27 90)
			(size 1.0414 1.0414)
			(drill 1.0414)
			(layers "*.Cu" "*.Mask")
			(clearance 0.381)
			(thermal_gap 0.381)
		)
		(pad "" np_thru_hole circle
			(at 3.4671 1.27 90)
			(size 1.0414 1.0414)
			(drill 1.0414)
			(layers "*.Cu" "*.Mask")
			(clearance 0.381)
			(thermal_gap 0.381)
		)
		(pad "1" smd rect
			(at 0.8255 -0.249936 90)
			(size 0.3048 0.508)
			(layers "F.Cu" "F.Mask" "F.Paste")
			(net "DELTA_L_85_10INCH_IN3_DN")
		)
		(pad "2" smd rect
			(at 0.8255 0.249936 90)
			(size 0.3048 0.508)
			(layers "F.Cu" "F.Mask" "F.Paste")
			(net "DELTA_L_85_10INCH_IN3_DP")
		)
		(pad "3" smd circle
			(at 0 0 180)
			(size 0 0)
			(layers "F.Cu" "F.Mask" "F.Paste")
			(net "DELTA_L_GND_1")
		)
		(zone
			(layer "F.Cu")
			(hatch none 0.5)
			(connect_pads
				(clearance 0)
			)
			(min_thickness 0.25)
			(keepout
				(tracks not_allowed)
				(vias allowed)
				(pads allowed)
				(copperpour not_allowed)
				(footprints allowed)
			)
			(placement
				(enabled no)
				(sheetname "")
			)
			(fill
				(thermal_gap 0.5)
				(thermal_bridge_width 0.5)
				(island_removal_mode 0)
			)
			(polygon
				(pts
					(xy 299.420788 5.631434) (xy 299.420788 5.53593) (xy 300.017688 5.53593) (xy 300.017688 5.12953)
					(xy 299.420788 5.12953) (xy 299.420788 5.036058) (xy 300.017688 5.036058) (xy 300.017688 4.629658)
					(xy 299.420788 4.629658) (xy 299.420788 4.534154) (xy 300.119288 4.534154) (xy 300.119288 5.631434)
				)
			)
		)
		(zone
			(layers "F.Cu" "B.Cu" "In1.Cu" "In2.Cu" "In3.Cu" "In4.Cu" "In5.Cu" "In6.Cu"
				"In7.Cu" "In8.Cu" "In9.Cu" "In10.Cu" "In11.Cu" "In12.Cu" "In13.Cu" "In14.Cu"
				"In15.Cu" "In16.Cu"
			)
			(hatch none 0.5)
			(connect_pads
				(clearance 0)
			)
			(min_thickness 0.25)
			(keepout
				(tracks not_allowed)
				(vias allowed)
				(pads allowed)
				(copperpour not_allowed)
				(footprints allowed)
			)
			(placement
				(enabled no)
				(sheetname "")
			)
			(fill
				(thermal_gap 0.5)
				(thermal_bridge_width 0.5)
				(island_removal_mode 0)
			)
			(polygon
				(pts
					(arc
						(start 297.998388 3.812794)
						(mid 296.144188 3.812794)
						(end 297.998388 3.812794)
					)
				)
			)
		)
		(zone
			(layers "F.Cu" "B.Cu" "In1.Cu" "In2.Cu" "In3.Cu" "In4.Cu" "In5.Cu" "In6.Cu"
				"In7.Cu" "In8.Cu" "In9.Cu" "In10.Cu" "In11.Cu" "In12.Cu" "In13.Cu" "In14.Cu"
				"In15.Cu" "In16.Cu"
			)
			(hatch none 0.5)
			(connect_pads
				(clearance 0)
			)
			(min_thickness 0.25)
			(keepout
				(tracks not_allowed)
				(vias allowed)
				(pads allowed)
				(copperpour not_allowed)
				(footprints allowed)
			)
			(placement
				(enabled no)
				(sheetname "")
			)
			(fill
				(thermal_gap 0.5)
				(thermal_bridge_width 0.5)
				(island_removal_mode 0)
			)
			(polygon
				(pts
					(arc
						(start 297.998388 6.352794)
						(mid 296.144188 6.352794)
						(end 297.998388 6.352794)
					)
				)
			)
		)
		(zone
			(layers "F.Cu" "B.Cu" "In1.Cu" "In2.Cu" "In3.Cu" "In4.Cu" "In5.Cu" "In6.Cu"
				"In7.Cu" "In8.Cu" "In9.Cu" "In10.Cu" "In11.Cu" "In12.Cu" "In13.Cu" "In14.Cu"
				"In15.Cu" "In16.Cu"
			)
			(hatch none 0.5)
			(connect_pads
				(clearance 0)
			)
			(min_thickness 0.25)
			(keepout
				(tracks not_allowed)
				(vias allowed)
				(pads allowed)
				(copperpour not_allowed)
				(footprints allowed)
			)
			(placement
				(enabled no)
				(sheetname "")
			)
			(fill
				(thermal_gap 0.5)
				(thermal_bridge_width 0.5)
				(island_removal_mode 0)
			)
			(polygon
				(pts
					(arc
						(start 304.348388 3.812794)
						(mid 302.494188 3.812794)
						(end 304.348388 3.812794)
					)
				)
			)
		)
		(zone
			(layers "F.Cu" "B.Cu" "In1.Cu" "In2.Cu" "In3.Cu" "In4.Cu" "In5.Cu" "In6.Cu"
				"In7.Cu" "In8.Cu" "In9.Cu" "In10.Cu" "In11.Cu" "In12.Cu" "In13.Cu" "In14.Cu"
				"In15.Cu" "In16.Cu"
			)
			(hatch none 0.5)
			(connect_pads
				(clearance 0)
			)
			(min_thickness 0.25)
			(keepout
				(tracks not_allowed)
				(vias allowed)
				(pads allowed)
				(copperpour not_allowed)
				(footprints allowed)
			)
			(placement
				(enabled no)
				(sheetname "")
			)
			(fill
				(thermal_gap 0.5)
				(thermal_bridge_width 0.5)
				(island_removal_mode 0)
			)
			(polygon
				(pts
					(arc
						(start 304.348388 6.352794)
						(mid 302.494188 6.352794)
						(end 304.348388 6.352794)
					)
				)
			)
		)
	)
	(footprint ""
		(layer "F.Cu")
		(at 155.306522 -191.361314 -90)
		(property "Reference" "R3194"
			(at 0 0 270)
			(layer "F.SilkS")
			(hide yes)
			(effects
				(font
					(size 1.27 1.27)
				)
			)
		)
		(property "Value" ""
			(at 0 0 270)
			(layer "F.Fab")
			(effects
				(font
					(size 1.27 1.27)
				)
			)
		)
		(duplicate_pad_numbers_are_jumpers no)
		(fp_line
			(start -0.7874 0.4064)
			(end -0.7874 -0.039878)
			(stroke
				(width 0.1524)
				(type default)
			)
			(layer "F.SilkS")
		)
		(fp_line
			(start 0.7874 0.4064)
			(end -0.7874 0.4064)
			(stroke
				(width 0.1524)
				(type default)
			)
			(layer "F.SilkS")
		)
		(fp_line
			(start 0.7874 -0.065278)
			(end 0.7874 0.4064)
			(stroke
				(width 0.1524)
				(type default)
			)
			(layer "F.SilkS")
		)
		(fp_line
			(start -0.383286 -0.4064)
			(end 0.353314 -0.4064)
			(stroke
				(width 0.1524)
				(type default)
			)
			(layer "F.SilkS")
		)
		(fp_line
			(start -0.67945 0.3048)
			(end -0.67945 -0.305054)
			(stroke
				(width 0.1)
				(type default)
			)
			(layer "F.Fab")
		)
		(fp_line
			(start -0.12065 0.3048)
			(end -0.67945 0.3048)
			(stroke
				(width 0.1)
				(type default)
			)
			(layer "F.Fab")
		)
		(fp_line
			(start 0.120396 0.3048)
			(end 0.120396 0.2794)
			(stroke
				(width 0.1)
				(type default)
			)
			(layer "F.Fab")
		)
		(fp_line
			(start 0.67945 0.3048)
			(end 0.120396 0.3048)
			(stroke
				(width 0.1)
				(type default)
			)
			(layer "F.Fab")
		)
		(fp_line
			(start -0.12065 0.2794)
			(end -0.12065 0.3048)
			(stroke
				(width 0.1)
				(type default)
			)
			(layer "F.Fab")
		)
		(fp_line
			(start 0.120396 0.2794)
			(end -0.12065 0.2794)
			(stroke
				(width 0.1)
				(type default)
			)
			(layer "F.Fab")
		)
		(fp_line
			(start -0.12065 -0.2794)
			(end 0.12065 -0.2794)
			(stroke
				(width 0.1)
				(type default)
			)
			(layer "F.Fab")
		)
		(fp_line
			(start 0.12065 -0.2794)
			(end 0.12065 -0.3048)
			(stroke
				(width 0.1)
				(type default)
			)
			(layer "F.Fab")
		)
		(fp_line
			(start 0.12065 -0.3048)
			(end 0.67945 -0.3048)
			(stroke
				(width 0.1)
				(type default)
			)
			(layer "F.Fab")
		)
		(fp_line
			(start 0.67945 -0.3048)
			(end 0.67945 0.3048)
			(stroke
				(width 0.1)
				(type default)
			)
			(layer "F.Fab")
		)
		(fp_line
			(start -0.67945 -0.305054)
			(end -0.12065 -0.305054)
			(stroke
				(width 0.1)
				(type default)
			)
			(layer "F.Fab")
		)
		(fp_line
			(start -0.12065 -0.305054)
			(end -0.12065 -0.2794)
			(stroke
				(width 0.1)
				(type default)
			)
			(layer "F.Fab")
		)
		(pad "1" smd circle
			(at -0.40005 0 270)
			(size 0 0)
			(layers "F.Cu" "F.Mask" "F.Paste")
			(net "CLK_100M_CPU1_CLK02_R_DP")
		)
		(pad "2" smd circle
			(at 0.40005 0 270)
			(size 0 0)
			(layers "F.Cu" "F.Mask" "F.Paste")
			(net "CLK_100M_CPU1_CLK02_DP")
		)
	)
	(footprint ""
		(layer "F.Cu")
		(at 351.407222 -424.279314 180)
		(property "Reference" "R4559"
			(at 0 0 180)
			(layer "F.SilkS")
			(hide yes)
			(effects
				(font
					(size 1.27 1.27)
				)
			)
		)
		(property "Value" ""
			(at 0 0 180)
			(layer "F.Fab")
			(effects
				(font
					(size 1.27 1.27)
				)
			)
		)
		(duplicate_pad_numbers_are_jumpers no)
		(fp_line
			(start 0.7874 0.4064)
			(end -0.7874 0.4064)
			(stroke
				(width 0.1524)
				(type default)
			)
			(layer "F.SilkS")
		)
		(fp_line
			(start 0.7874 -0.4064)
			(end 0.7874 0.4064)
			(stroke
				(width 0.1524)
				(type default)
			)
			(layer "F.SilkS")
		)
		(fp_line
			(start -0.7874 0.4064)
			(end -0.7874 -0.4064)
			(stroke
				(width 0.1524)
				(type default)
			)
			(layer "F.SilkS")
		)
		(fp_line
			(start -0.7874 -0.4064)
			(end 0.7874 -0.4064)
			(stroke
				(width 0.1524)
				(type default)
			)
			(layer "F.SilkS")
		)
		(fp_line
			(start 0.67945 0.3048)
			(end 0.120396 0.3048)
			(stroke
				(width 0.1)
				(type default)
			)
			(layer "F.Fab")
		)
		(fp_line
			(start 0.67945 -0.3048)
			(end 0.67945 0.3048)
			(stroke
				(width 0.1)
				(type default)
			)
			(layer "F.Fab")
		)
		(fp_line
			(start 0.12065 -0.2794)
			(end 0.12065 -0.3048)
			(stroke
				(width 0.1)
				(type default)
			)
			(layer "F.Fab")
		)
		(fp_line
			(start 0.12065 -0.3048)
			(end 0.67945 -0.3048)
			(stroke
				(width 0.1)
				(type default)
			)
			(layer "F.Fab")
		)
		(fp_line
			(start 0.120396 0.3048)
			(end 0.120396 0.2794)
			(stroke
				(width 0.1)
				(type default)
			)
			(layer "F.Fab")
		)
		(fp_line
			(start 0.120396 0.2794)
			(end -0.12065 0.2794)
			(stroke
				(width 0.1)
				(type default)
			)
			(layer "F.Fab")
		)
		(fp_line
			(start -0.12065 0.3048)
			(end -0.67945 0.3048)
			(stroke
				(width 0.1)
				(type default)
			)
			(layer "F.Fab")
		)
		(fp_line
			(start -0.12065 0.2794)
			(end -0.12065 0.3048)
			(stroke
				(width 0.1)
				(type default)
			)
			(layer "F.Fab")
		)
		(fp_line
			(start -0.12065 -0.2794)
			(end 0.12065 -0.2794)
			(stroke
				(width 0.1)
				(type default)
			)
			(layer "F.Fab")
		)
		(fp_line
			(start -0.12065 -0.305054)
			(end -0.12065 -0.2794)
			(stroke
				(width 0.1)
				(type default)
			)
			(layer "F.Fab")
		)
		(fp_line
			(start -0.67945 0.3048)
			(end -0.67945 -0.305054)
			(stroke
				(width 0.1)
				(type default)
			)
			(layer "F.Fab")
		)
		(fp_line
			(start -0.67945 -0.305054)
			(end -0.12065 -0.305054)
			(stroke
				(width 0.1)
				(type default)
			)
			(layer "F.Fab")
		)
		(pad "1" smd circle
			(at -0.40005 0 180)
			(size 0 0)
			(layers "F.Cu" "F.Mask" "F.Paste")
			(net "SWB_HSC_PWRGD")
		)
		(pad "2" smd circle
			(at 0.40005 0 180)
			(size 0 0)
			(layers "F.Cu" "F.Mask" "F.Paste")
			(net "GND")
		)
	)
	(footprint ""
		(layer "F.Cu")
		(at 192.913 -100.294948 90)
		(property "Reference" "R222"
			(at 0 0 90)
			(layer "F.SilkS")
			(hide yes)
			(effects
				(font
					(size 1.27 1.27)
				)
			)
		)
		(property "Value" ""
			(at 0 0 90)
			(layer "F.Fab")
			(effects
				(font
					(size 1.27 1.27)
				)
			)
		)
		(duplicate_pad_numbers_are_jumpers no)
		(fp_line
			(start 0.7874 -0.4064)
			(end 0.7874 0.4064)
			(stroke
				(width 0.1524)
				(type default)
			)
			(layer "F.SilkS")
		)
		(fp_line
			(start -0.7874 -0.4064)
			(end 0.7874 -0.4064)
			(stroke
				(width 0.1524)
				(type default)
			)
			(layer "F.SilkS")
		)
		(fp_line
			(start 0.7874 0.4064)
			(end -0.7874 0.4064)
			(stroke
				(width 0.1524)
				(type default)
			)
			(layer "F.SilkS")
		)
		(fp_line
			(start -0.7874 0.4064)
			(end -0.7874 -0.4064)
			(stroke
				(width 0.1524)
				(type default)
			)
			(layer "F.SilkS")
		)
		(fp_line
			(start -0.12065 -0.305054)
			(end -0.12065 -0.2794)
			(stroke
				(width 0.1)
				(type default)
			)
			(layer "F.Fab")
		)
		(fp_line
			(start -0.67945 -0.305054)
			(end -0.12065 -0.305054)
			(stroke
				(width 0.1)
				(type default)
			)
			(layer "F.Fab")
		)
		(fp_line
			(start 0.67945 -0.3048)
			(end 0.67945 0.3048)
			(stroke
				(width 0.1)
				(type default)
			)
			(layer "F.Fab")
		)
		(fp_line
			(start 0.12065 -0.3048)
			(end 0.67945 -0.3048)
			(stroke
				(width 0.1)
				(type default)
			)
			(layer "F.Fab")
		)
		(fp_line
			(start 0.12065 -0.2794)
			(end 0.12065 -0.3048)
			(stroke
				(width 0.1)
				(type default)
			)
			(layer "F.Fab")
		)
		(fp_line
			(start -0.12065 -0.2794)
			(end 0.12065 -0.2794)
			(stroke
				(width 0.1)
				(type default)
			)
			(layer "F.Fab")
		)
		(fp_line
			(start 0.120396 0.2794)
			(end -0.12065 0.2794)
			(stroke
				(width 0.1)
				(type default)
			)
			(layer "F.Fab")
		)
		(fp_line
			(start -0.12065 0.2794)
			(end -0.12065 0.3048)
			(stroke
				(width 0.1)
				(type default)
			)
			(layer "F.Fab")
		)
		(fp_line
			(start 0.67945 0.3048)
			(end 0.120396 0.3048)
			(stroke
				(width 0.1)
				(type default)
			)
			(layer "F.Fab")
		)
		(fp_line
			(start 0.120396 0.3048)
			(end 0.120396 0.2794)
			(stroke
				(width 0.1)
				(type default)
			)
			(layer "F.Fab")
		)
		(fp_line
			(start -0.12065 0.3048)
			(end -0.67945 0.3048)
			(stroke
				(width 0.1)
				(type default)
			)
			(layer "F.Fab")
		)
		(fp_line
			(start -0.67945 0.3048)
			(end -0.67945 -0.305054)
			(stroke
				(width 0.1)
				(type default)
			)
			(layer "F.Fab")
		)
		(pad "1" smd circle
			(at -0.40005 0 90)
			(size 0 0)
			(layers "F.Cu" "F.Mask" "F.Paste")
			(net "CPU0_SP5R3")
		)
		(pad "2" smd circle
			(at 0.40005 0 90)
			(size 0 0)
			(layers "F.Cu" "F.Mask" "F.Paste")
			(net "FM_CPU0_SP5R3")
		)
	)
	(footprint ""
		(layer "F.Cu")
		(at 363.72292 -400.903694)
		(property "Reference" "L23"
			(at -2.3876 -2.969768 0)
			(unlocked yes)
			(layer "F.SilkS")
			(effects
				(font
					(size 0.7874 0.5842)
					(thickness 0.1524)
				)
				(justify left)
			)
		)
		(property "Value" ""
			(at 0 0 0)
			(layer "F.Fab")
			(effects
				(font
					(size 1.27 1.27)
				)
			)
		)
		(duplicate_pad_numbers_are_jumpers no)
		(fp_line
			(start -2.249932 -2.249932)
			(end 2.249932 -2.249932)
			(stroke
				(width 0.1524)
				(type default)
			)
			(layer "F.SilkS")
		)
		(fp_line
			(start -2.249932 -1.3843)
			(end -2.249932 -2.249932)
			(stroke
				(width 0.1524)
				(type default)
			)
			(layer "F.SilkS")
		)
		(fp_line
			(start -2.249932 2.249932)
			(end -2.249932 1.3843)
			(stroke
				(width 0.1524)
				(type default)
			)
			(layer "F.SilkS")
		)
		(fp_line
			(start 2.249932 -2.249932)
			(end 2.249932 -1.3843)
			(stroke
				(width 0.1524)
				(type default)
			)
			(layer "F.SilkS")
		)
		(fp_line
			(start 2.249932 1.3843)
			(end 2.249932 2.249932)
			(stroke
				(width 0.1524)
				(type default)
			)
			(layer "F.SilkS")
		)
		(fp_line
			(start 2.249932 2.249932)
			(end -2.249932 2.249932)
			(stroke
				(width 0.1524)
				(type default)
			)
			(layer "F.SilkS")
		)
		(fp_line
			(start -2.249932 -2.249932)
			(end 2.249932 -2.249932)
			(stroke
				(width 0.1)
				(type default)
			)
			(layer "F.Fab")
		)
		(fp_line
			(start -2.249932 2.249932)
			(end -2.249932 -2.249932)
			(stroke
				(width 0.1)
				(type default)
			)
			(layer "F.Fab")
		)
		(fp_line
			(start 2.249932 -2.249932)
			(end 2.249932 2.249932)
			(stroke
				(width 0.1)
				(type default)
			)
			(layer "F.Fab")
		)
		(fp_line
			(start 2.249932 2.249932)
			(end -2.249932 2.249932)
			(stroke
				(width 0.1)
				(type default)
			)
			(layer "F.Fab")
		)
		(pad "1" smd rect
			(at -1.82499 0)
			(size 1.0668 2.5146)
			(layers "F.Cu" "F.Mask" "F.Paste")
			(net "P0V9_CPU0_RT_2D")
		)
		(pad "2" smd rect
			(at 1.82499 0)
			(size 1.0668 2.5146)
			(layers "F.Cu" "F.Mask" "F.Paste")
			(net "P0V9_CPU0_RT3_2A")
		)
	)
	(footprint ""
		(layer "F.Cu")
		(at 468.957914 -41.105836)
		(property "Reference" "R6045"
			(at 0 0 0)
			(layer "F.SilkS")
			(hide yes)
			(effects
				(font
					(size 1.27 1.27)
				)
			)
		)
		(property "Value" ""
			(at 0 0 0)
			(layer "F.Fab")
			(effects
				(font
					(size 1.27 1.27)
				)
			)
		)
		(duplicate_pad_numbers_are_jumpers no)
		(fp_line
			(start -0.7874 -0.4064)
			(end 0.7874 -0.4064)
			(stroke
				(width 0.1524)
				(type default)
			)
			(layer "F.SilkS")
		)
		(fp_line
			(start -0.7874 0.4064)
			(end -0.7874 -0.4064)
			(stroke
				(width 0.1524)
				(type default)
			)
			(layer "F.SilkS")
		)
		(fp_line
			(start 0.7874 -0.4064)
			(end 0.7874 0.4064)
			(stroke
				(width 0.1524)
				(type default)
			)
			(layer "F.SilkS")
		)
		(fp_line
			(start 0.7874 0.4064)
			(end -0.7874 0.4064)
			(stroke
				(width 0.1524)
				(type default)
			)
			(layer "F.SilkS")
		)
		(fp_line
			(start -0.67945 -0.305054)
			(end -0.12065 -0.305054)
			(stroke
				(width 0.1)
				(type default)
			)
			(layer "F.Fab")
		)
		(fp_line
			(start -0.67945 0.3048)
			(end -0.67945 -0.305054)
			(stroke
				(width 0.1)
				(type default)
			)
			(layer "F.Fab")
		)
		(fp_line
			(start -0.12065 -0.305054)
			(end -0.12065 -0.2794)
			(stroke
				(width 0.1)
				(type default)
			)
			(layer "F.Fab")
		)
		(fp_line
			(start -0.12065 -0.2794)
			(end 0.12065 -0.2794)
			(stroke
				(width 0.1)
				(type default)
			)
			(layer "F.Fab")
		)
		(fp_line
			(start -0.12065 0.2794)
			(end -0.12065 0.3048)
			(stroke
				(width 0.1)
				(type default)
			)
			(layer "F.Fab")
		)
		(fp_line
			(start -0.12065 0.3048)
			(end -0.67945 0.3048)
			(stroke
				(width 0.1)
				(type default)
			)
			(layer "F.Fab")
		)
		(fp_line
			(start 0.120396 0.2794)
			(end -0.12065 0.2794)
			(stroke
				(width 0.1)
				(type default)
			)
			(layer "F.Fab")
		)
		(fp_line
			(start 0.120396 0.3048)
			(end 0.120396 0.2794)
			(stroke
				(width 0.1)
				(type default)
			)
			(layer "F.Fab")
		)
		(fp_line
			(start 0.12065 -0.3048)
			(end 0.67945 -0.3048)
			(stroke
				(width 0.1)
				(type default)
			)
			(layer "F.Fab")
		)
		(fp_line
			(start 0.12065 -0.2794)
			(end 0.12065 -0.3048)
			(stroke
				(width 0.1)
				(type default)
			)
			(layer "F.Fab")
		)
		(fp_line
			(start 0.67945 -0.3048)
			(end 0.67945 0.3048)
			(stroke
				(width 0.1)
				(type default)
			)
			(layer "F.Fab")
		)
		(fp_line
			(start 0.67945 0.3048)
			(end 0.120396 0.3048)
			(stroke
				(width 0.1)
				(type default)
			)
			(layer "F.Fab")
		)
		(pad "1" smd circle
			(at -0.40005 0)
			(size 0 0)
			(layers "F.Cu" "F.Mask" "F.Paste")
			(net "P12V_OCP_EN_1_R")
		)
		(pad "2" smd circle
			(at 0.40005 0)
			(size 0 0)
			(layers "F.Cu" "F.Mask" "F.Paste")
			(net "GND")
		)
	)
	(footprint ""
		(layer "F.Cu")
		(at 178.943 -140.172948 90)
		(property "Reference" "R19"
			(at 0 0 90)
			(layer "F.SilkS")
			(hide yes)
			(effects
				(font
					(size 1.27 1.27)
				)
			)
		)
		(property "Value" ""
			(at 0 0 90)
			(layer "F.Fab")
			(effects
				(font
					(size 1.27 1.27)
				)
			)
		)
		(duplicate_pad_numbers_are_jumpers no)
		(fp_line
			(start 0.7874 -0.4064)
			(end 0.7874 0.4064)
			(stroke
				(width 0.1524)
				(type default)
			)
			(layer "F.SilkS")
		)
		(fp_line
			(start -0.7874 -0.4064)
			(end 0.7874 -0.4064)
			(stroke
				(width 0.1524)
				(type default)
			)
			(layer "F.SilkS")
		)
		(fp_line
			(start 0.7874 0.4064)
			(end -0.7874 0.4064)
			(stroke
				(width 0.1524)
				(type default)
			)
			(layer "F.SilkS")
		)
		(fp_line
			(start -0.7874 0.4064)
			(end -0.7874 -0.4064)
			(stroke
				(width 0.1524)
				(type default)
			)
			(layer "F.SilkS")
		)
		(fp_line
			(start -0.12065 -0.305054)
			(end -0.12065 -0.2794)
			(stroke
				(width 0.1)
				(type default)
			)
			(layer "F.Fab")
		)
		(fp_line
			(start -0.67945 -0.305054)
			(end -0.12065 -0.305054)
			(stroke
				(width 0.1)
				(type default)
			)
			(layer "F.Fab")
		)
		(fp_line
			(start 0.67945 -0.3048)
			(end 0.67945 0.3048)
			(stroke
				(width 0.1)
				(type default)
			)
			(layer "F.Fab")
		)
		(fp_line
			(start 0.12065 -0.3048)
			(end 0.67945 -0.3048)
			(stroke
				(width 0.1)
				(type default)
			)
			(layer "F.Fab")
		)
		(fp_line
			(start 0.12065 -0.2794)
			(end 0.12065 -0.3048)
			(stroke
				(width 0.1)
				(type default)
			)
			(layer "F.Fab")
		)
		(fp_line
			(start -0.12065 -0.2794)
			(end 0.12065 -0.2794)
			(stroke
				(width 0.1)
				(type default)
			)
			(layer "F.Fab")
		)
		(fp_line
			(start 0.120396 0.2794)
			(end -0.12065 0.2794)
			(stroke
				(width 0.1)
				(type default)
			)
			(layer "F.Fab")
		)
		(fp_line
			(start -0.12065 0.2794)
			(end -0.12065 0.3048)
			(stroke
				(width 0.1)
				(type default)
			)
			(layer "F.Fab")
		)
		(fp_line
			(start 0.67945 0.3048)
			(end 0.120396 0.3048)
			(stroke
				(width 0.1)
				(type default)
			)
			(layer "F.Fab")
		)
		(fp_line
			(start 0.120396 0.3048)
			(end 0.120396 0.2794)
			(stroke
				(width 0.1)
				(type default)
			)
			(layer "F.Fab")
		)
		(fp_line
			(start -0.12065 0.3048)
			(end -0.67945 0.3048)
			(stroke
				(width 0.1)
				(type default)
			)
			(layer "F.Fab")
		)
		(fp_line
			(start -0.67945 0.3048)
			(end -0.67945 -0.305054)
			(stroke
				(width 0.1)
				(type default)
			)
			(layer "F.Fab")
		)
		(pad "1" smd circle
			(at -0.40005 0 90)
			(size 0 0)
			(layers "F.Cu" "F.Mask" "F.Paste")
			(net "RST_CPU1_PERST1_N")
		)
		(pad "2" smd circle
			(at 0.40005 0 90)
			(size 0 0)
			(layers "F.Cu" "F.Mask" "F.Paste")
			(net "GND")
		)
	)
	(footprint ""
		(layer "F.Cu")
		(at 243.74475 -50.335434)
		(property "Reference" "R1292"
			(at 0 0 0)
			(layer "F.SilkS")
			(hide yes)
			(effects
				(font
					(size 1.27 1.27)
				)
			)
		)
		(property "Value" ""
			(at 0 0 0)
			(layer "F.Fab")
			(effects
				(font
					(size 1.27 1.27)
				)
			)
		)
		(duplicate_pad_numbers_are_jumpers no)
		(fp_line
			(start -0.7874 -0.4064)
			(end 0.7874 -0.4064)
			(stroke
				(width 0.1524)
				(type default)
			)
			(layer "F.SilkS")
		)
		(fp_line
			(start -0.7874 0.4064)
			(end -0.7874 -0.4064)
			(stroke
				(width 0.1524)
				(type default)
			)
			(layer "F.SilkS")
		)
		(fp_line
			(start 0.7874 -0.4064)
			(end 0.7874 0.4064)
			(stroke
				(width 0.1524)
				(type default)
			)
			(layer "F.SilkS")
		)
		(fp_line
			(start 0.7874 0.4064)
			(end -0.7874 0.4064)
			(stroke
				(width 0.1524)
				(type default)
			)
			(layer "F.SilkS")
		)
		(fp_line
			(start -0.67945 -0.305054)
			(end -0.12065 -0.305054)
			(stroke
				(width 0.1)
				(type default)
			)
			(layer "F.Fab")
		)
		(fp_line
			(start -0.67945 0.3048)
			(end -0.67945 -0.305054)
			(stroke
				(width 0.1)
				(type default)
			)
			(layer "F.Fab")
		)
		(fp_line
			(start -0.12065 -0.305054)
			(end -0.12065 -0.2794)
			(stroke
				(width 0.1)
				(type default)
			)
			(layer "F.Fab")
		)
		(fp_line
			(start -0.12065 -0.2794)
			(end 0.12065 -0.2794)
			(stroke
				(width 0.1)
				(type default)
			)
			(layer "F.Fab")
		)
		(fp_line
			(start -0.12065 0.2794)
			(end -0.12065 0.3048)
			(stroke
				(width 0.1)
				(type default)
			)
			(layer "F.Fab")
		)
		(fp_line
			(start -0.12065 0.3048)
			(end -0.67945 0.3048)
			(stroke
				(width 0.1)
				(type default)
			)
			(layer "F.Fab")
		)
		(fp_line
			(start 0.120396 0.2794)
			(end -0.12065 0.2794)
			(stroke
				(width 0.1)
				(type default)
			)
			(layer "F.Fab")
		)
		(fp_line
			(start 0.120396 0.3048)
			(end 0.120396 0.2794)
			(stroke
				(width 0.1)
				(type default)
			)
			(layer "F.Fab")
		)
		(fp_line
			(start 0.12065 -0.3048)
			(end 0.67945 -0.3048)
			(stroke
				(width 0.1)
				(type default)
			)
			(layer "F.Fab")
		)
		(fp_line
			(start 0.12065 -0.2794)
			(end 0.12065 -0.3048)
			(stroke
				(width 0.1)
				(type default)
			)
			(layer "F.Fab")
		)
		(fp_line
			(start 0.67945 -0.3048)
			(end 0.67945 0.3048)
			(stroke
				(width 0.1)
				(type default)
			)
			(layer "F.Fab")
		)
		(fp_line
			(start 0.67945 0.3048)
			(end 0.120396 0.3048)
			(stroke
				(width 0.1)
				(type default)
			)
			(layer "F.Fab")
		)
		(pad "1" smd circle
			(at -0.40005 0)
			(size 0 0)
			(layers "F.Cu" "F.Mask" "F.Paste")
			(net "P12V_E1S_0_R")
		)
		(pad "2" smd circle
			(at 0.40005 0)
			(size 0 0)
			(layers "F.Cu" "F.Mask" "F.Paste")
			(net "VSENSE_P12V_INA230_8_INN")
		)
	)
	(footprint ""
		(layer "F.Cu")
		(at 83.054444 -152.093676 180)
		(property "Reference" "PL26"
			(at 0 0 180)
			(layer "F.SilkS")
			(hide yes)
			(effects
				(font
					(size 1.27 1.27)
				)
			)
		)
		(property "Value" ""
			(at 0 0 180)
			(layer "F.Fab")
			(effects
				(font
					(size 1.27 1.27)
				)
			)
		)
		(duplicate_pad_numbers_are_jumpers no)
		(fp_line
			(start 1.27 0.5842)
			(end 1.27 -0.5842)
			(stroke
				(width 0.1524)
				(type default)
			)
			(layer "F.SilkS")
		)
		(fp_line
			(start 1.27 0.5842)
			(end -1.27 0.5842)
			(stroke
				(width 0.1524)
				(type default)
			)
			(layer "F.SilkS")
		)
		(fp_line
			(start -1.27 0.5842)
			(end -1.27 -0.5842)
			(stroke
				(width 0.1524)
				(type default)
			)
			(layer "F.SilkS")
		)
		(fp_line
			(start -1.27 -0.5588)
			(end -1.27 -0.5842)
			(stroke
				(width 0.1524)
				(type default)
			)
			(layer "F.SilkS")
		)
		(fp_line
			(start -1.27 -0.5842)
			(end 1.27 -0.5842)
			(stroke
				(width 0.1524)
				(type default)
			)
			(layer "F.SilkS")
		)
		(fp_line
			(start 1.1938 0.4064)
			(end 0.9144 0.4064)
			(stroke
				(width 0.1)
				(type default)
			)
			(layer "F.Fab")
		)
		(fp_line
			(start 1.1938 -0.406654)
			(end 1.1938 0.4064)
			(stroke
				(width 0.1)
				(type default)
			)
			(layer "F.Fab")
		)
		(fp_line
			(start 0.9144 0.508)
			(end -0.9144 0.508)
			(stroke
				(width 0.1)
				(type default)
			)
			(layer "F.Fab")
		)
		(fp_line
			(start 0.9144 0.4064)
			(end 0.9144 0.508)
			(stroke
				(width 0.1)
				(type default)
			)
			(layer "F.Fab")
		)
		(fp_line
			(start 0.9144 -0.406654)
			(end 1.1938 -0.406654)
			(stroke
				(width 0.1)
				(type default)
			)
			(layer "F.Fab")
		)
		(fp_line
			(start 0.9144 -0.508)
			(end 0.9144 -0.406654)
			(stroke
				(width 0.1)
				(type default)
			)
			(layer "F.Fab")
		)
		(fp_line
			(start -0.9144 0.508)
			(end -0.9144 0.406654)
			(stroke
				(width 0.1)
				(type default)
			)
			(layer "F.Fab")
		)
		(fp_line
			(start -0.9144 0.406654)
			(end -1.194308 0.406654)
			(stroke
				(width 0.1)
				(type default)
			)
			(layer "F.Fab")
		)
		(fp_line
			(start -0.9144 -0.406654)
			(end -0.9144 -0.508)
			(stroke
				(width 0.1)
				(type default)
			)
			(layer "F.Fab")
		)
		(fp_line
			(start -0.9144 -0.508)
			(end 0.9144 -0.508)
			(stroke
				(width 0.1)
				(type default)
			)
			(layer "F.Fab")
		)
		(fp_line
			(start -1.194308 0.406654)
			(end -1.194308 -0.406654)
			(stroke
				(width 0.1)
				(type default)
			)
			(layer "F.Fab")
		)
		(fp_line
			(start -1.194308 -0.406654)
			(end -0.9144 -0.406654)
			(stroke
				(width 0.1)
				(type default)
			)
			(layer "F.Fab")
		)
		(pad "1" smd rect
			(at -0.7366 0 90)
			(size 0.7112 0.8128)
			(layers "F.Cu" "F.Mask" "F.Paste")
			(net "P12V_AUX")
		)
		(pad "2" smd rect
			(at 0.7366 0 90)
			(size 0.7112 0.8128)
			(layers "F.Cu" "F.Mask" "F.Paste")
			(net "SW_P12V_AUX_PVDD18_S5_P1_FLT")
		)
	)
	(footprint ""
		(layer "F.Cu")
		(at 47.462694 -17.623536 90)
		(property "Reference" "C701"
			(at 0 0 90)
			(layer "F.SilkS")
			(hide yes)
			(effects
				(font
					(size 1.27 1.27)
				)
			)
		)
		(property "Value" ""
			(at 0 0 90)
			(layer "F.Fab")
			(effects
				(font
					(size 1.27 1.27)
				)
			)
		)
		(duplicate_pad_numbers_are_jumpers no)
		(fp_line
			(start 0.299974 -0.150114)
			(end 0.299974 0.150114)
			(stroke
				(width 0.1)
				(type default)
			)
			(layer "F.Fab")
		)
		(fp_line
			(start -0.299974 -0.150114)
			(end 0.299974 -0.150114)
			(stroke
				(width 0.1)
				(type default)
			)
			(layer "F.Fab")
		)
		(fp_line
			(start 0.299974 0.150114)
			(end -0.299974 0.150114)
			(stroke
				(width 0.1)
				(type default)
			)
			(layer "F.Fab")
		)
		(fp_line
			(start -0.299974 0.150114)
			(end -0.299974 -0.150114)
			(stroke
				(width 0.1)
				(type default)
			)
			(layer "F.Fab")
		)
		(pad "1" smd rect
			(at -0.2667 0 90)
			(size 0.3048 0.381)
			(layers "F.Cu" "F.Mask" "F.Paste")
			(net "P5E_CPU1_G1_TX_C_DP<4>")
		)
		(pad "2" smd rect
			(at 0.2667 0 90)
			(size 0.3048 0.381)
			(layers "F.Cu" "F.Mask" "F.Paste")
			(net "P5E_CPU1_G1_TX_DP<4>")
		)
	)
	(footprint ""
		(layer "F.Cu")
		(at 290.399724 -403.086062)
		(property "Reference" "U15"
			(at -0.024384 -3.107436 0)
			(unlocked yes)
			(layer "F.SilkS")
			(effects
				(font
					(size 0.7874 0.5842)
					(thickness 0.1524)
				)
				(justify left)
			)
		)
		(property "Value" ""
			(at 0 0 0)
			(layer "F.Fab")
			(effects
				(font
					(size 1.27 1.27)
				)
			)
		)
		(duplicate_pad_numbers_are_jumpers no)
		(fp_line
			(start -1.8288 -2.500122)
			(end -1.8288 2.500122)
			(stroke
				(width 0.1524)
				(type default)
			)
			(layer "F.SilkS")
		)
		(fp_line
			(start -1.8288 2.500122)
			(end 1.8288 2.500122)
			(stroke
				(width 0.1524)
				(type default)
			)
			(layer "F.SilkS")
		)
		(fp_line
			(start -1.077722 -2.500122)
			(end -1.8288 -2.500122)
			(stroke
				(width 0.1524)
				(type default)
			)
			(layer "F.SilkS")
		)
		(fp_line
			(start 0 -1.4224)
			(end -1.077722 -2.500122)
			(stroke
				(width 0.1524)
				(type default)
			)
			(layer "F.SilkS")
		)
		(fp_line
			(start 1.077722 -2.500122)
			(end 0 -1.4224)
			(stroke
				(width 0.1524)
				(type default)
			)
			(layer "F.SilkS")
		)
		(fp_line
			(start 1.8288 -2.500122)
			(end 1.077722 -2.500122)
			(stroke
				(width 0.1524)
				(type default)
			)
			(layer "F.SilkS")
		)
		(fp_line
			(start 1.8288 2.500122)
			(end 1.8288 -2.500122)
			(stroke
				(width 0.1524)
				(type default)
			)
			(layer "F.SilkS")
		)
		(fp_poly
			(pts
				(xy -1.170432 -3.243326) (xy -2.085594 -3.684778) (xy -2.069592 -2.54889)
			)
			(stroke
				(width 0)
				(type default)
			)
			(fill yes)
			(layer "F.SilkS")
		)
		(fp_line
			(start -1.999996 -2.500122)
			(end -1.999996 2.500122)
			(stroke
				(width 0.1)
				(type default)
			)
			(layer "F.Fab")
		)
		(fp_line
			(start -1.999996 2.500122)
			(end 1.999996 2.500122)
			(stroke
				(width 0.1)
				(type default)
			)
			(layer "F.Fab")
		)
		(fp_line
			(start 1.999996 -2.500122)
			(end -1.999996 -2.500122)
			(stroke
				(width 0.1)
				(type default)
			)
			(layer "F.Fab")
		)
		(fp_line
			(start 1.999996 2.500122)
			(end 1.999996 -2.500122)
			(stroke
				(width 0.1)
				(type default)
			)
			(layer "F.Fab")
		)
		(fp_poly
			(pts
				(xy -4.5085 -2.413) (xy -4.5085 -1.397) (xy -3.4925 -1.905)
			)
			(stroke
				(width 0)
				(type default)
			)
			(fill yes)
			(layer "F.Fab")
		)
		(pad "1" smd rect
			(at -2.599944 -1.905 270)
			(size 0.889 1.27)
			(layers "F.Cu" "F.Mask" "F.Paste")
			(net "Net_10843")
		)
		(pad "2" smd rect
			(at -2.599944 -0.635 270)
			(size 0.889 1.27)
			(layers "F.Cu" "F.Mask" "F.Paste")
			(net "Net_10842")
		)
		(pad "3" smd rect
			(at -2.599944 0.635 270)
			(size 0.889 1.27)
			(layers "F.Cu" "F.Mask" "F.Paste")
			(net "U15_E2")
		)
		(pad "4" smd rect
			(at -2.599944 1.905 270)
			(size 0.889 1.27)
			(layers "F.Cu" "F.Mask" "F.Paste")
			(net "GND")
		)
		(pad "5" smd rect
			(at 2.599944 1.905 270)
			(size 0.889 1.27)
			(layers "F.Cu" "F.Mask" "F.Paste")
			(net "SMB_RT_CPU0_P1_ROM_SDA")
		)
		(pad "6" smd rect
			(at 2.599944 0.635 270)
			(size 0.889 1.27)
			(layers "F.Cu" "F.Mask" "F.Paste")
			(net "SMB_RT_CPU0_P1_ROM_SCL")
		)
		(pad "7" smd rect
			(at 2.599944 -0.635 270)
			(size 0.889 1.27)
			(layers "F.Cu" "F.Mask" "F.Paste")
			(net "GND")
		)
		(pad "8" smd rect
			(at 2.599944 -1.905 270)
			(size 0.889 1.27)
			(layers "F.Cu" "F.Mask" "F.Paste")
			(net "P1V8_CPU0_RT_1D")
		)
	)
	(footprint ""
		(layer "F.Cu")
		(at 252.83287 -42.055542 -90)
		(property "Reference" "PU294"
			(at -0.455168 -1.924812 0)
			(unlocked yes)
			(layer "F.SilkS")
			(effects
				(font
					(size 0.7874 0.5842)
					(thickness 0.1524)
				)
				(justify left)
			)
		)
		(property "Value" ""
			(at 0 0 270)
			(layer "F.Fab")
			(effects
				(font
					(size 1.27 1.27)
				)
			)
		)
		(duplicate_pad_numbers_are_jumpers no)
		(fp_line
			(start -1.774952 1.039876)
			(end 1.774952 1.039876)
			(stroke
				(width 0.1524)
				(type default)
			)
			(layer "F.SilkS")
		)
		(fp_line
			(start 1.774952 1.039876)
			(end 1.774952 -1.039876)
			(stroke
				(width 0.1524)
				(type default)
			)
			(layer "F.SilkS")
		)
		(fp_line
			(start -1.774952 -1.039876)
			(end -1.774952 1.039876)
			(stroke
				(width 0.1524)
				(type default)
			)
			(layer "F.SilkS")
		)
		(fp_line
			(start 1.774952 -1.039876)
			(end -1.774952 -1.039876)
			(stroke
				(width 0.1524)
				(type default)
			)
			(layer "F.SilkS")
		)
		(fp_poly
			(pts
				(xy -0.999998 -1.801876) (xy -0.999998 -1.039876) (xy -1.769872 -1.039876) (xy -1.769872 -0.249936)
				(xy -2.531872 -0.249936) (xy -2.531872 -1.801876)
			)
			(stroke
				(width 0)
				(type default)
			)
			(fill yes)
			(layer "F.SilkS")
		)
		(fp_line
			(start -1.769872 1.039876)
			(end 1.769872 1.039876)
			(stroke
				(width 0.1)
				(type default)
			)
			(layer "F.Fab")
		)
		(fp_line
			(start 1.769872 1.039876)
			(end 1.769872 -1.039876)
			(stroke
				(width 0.1)
				(type default)
			)
			(layer "F.Fab")
		)
		(fp_line
			(start -1.769872 -1.039876)
			(end -1.769872 1.039876)
			(stroke
				(width 0.1)
				(type default)
			)
			(layer "F.Fab")
		)
		(fp_line
			(start 1.769872 -1.039876)
			(end -1.769872 -1.039876)
			(stroke
				(width 0.1)
				(type default)
			)
			(layer "F.Fab")
		)
		(fp_poly
			(pts
				(xy -1.769872 -1.039876) (xy -0.999998 -1.039876) (xy -0.999998 -1.801876) (xy -2.531872 -1.801876)
				(xy -2.531872 -0.249936) (xy -1.769872 -0.249936)
			)
			(stroke
				(width 0)
				(type default)
			)
			(fill yes)
			(layer "F.Fab")
		)
		(pad "A1" smd circle
			(at -1.500124 -0.750062 270)
			(size 0.2286 0.2286)
			(layers "F.Cu" "F.Mask" "F.Paste")
			(net "P12V_E1S_SENSE_0")
		)
		(pad "A2" smd circle
			(at -0.999998 -0.750062 270)
			(size 0.2286 0.2286)
			(layers "F.Cu" "F.Mask" "F.Paste")
			(net "P12V_E1S_VCC_0")
		)
		(pad "A3" smd circle
			(at -0.499872 -0.750062 270)
			(size 0.2286 0.2286)
			(layers "F.Cu" "F.Mask" "F.Paste")
			(net "P12V_AUX")
		)
		(pad "A4" smd circle
			(at 0 -0.750062 270)
			(size 0.2286 0.2286)
			(layers "F.Cu" "F.Mask" "F.Paste")
			(net "P12V_E1S_0")
		)
		(pad "A5" smd circle
			(at 0.499872 -0.750062 270)
			(size 0.2286 0.2286)
			(layers "F.Cu" "F.Mask" "F.Paste")
			(net "P12V_AUX")
		)
		(pad "A6" smd circle
			(at 0.999998 -0.750062 270)
			(size 0.2286 0.2286)
			(layers "F.Cu" "F.Mask" "F.Paste")
			(net "P12V_E1S_GATE_0")
		)
		(pad "A7" smd circle
			(at 1.500124 -0.750062 270)
			(size 0.2286 0.2286)
			(layers "F.Cu" "F.Mask" "F.Paste")
			(net "GND")
		)
		(pad "B1" smd circle
			(at -1.500124 -0.249936 270)
			(size 0.2286 0.2286)
			(layers "F.Cu" "F.Mask" "F.Paste")
			(net "P12V_E1S_CB_0")
		)
		(pad "B2" smd circle
			(at -0.999998 -0.249936 270)
			(size 0.2286 0.2286)
			(layers "F.Cu" "F.Mask" "F.Paste")
			(net "GND")
		)
		(pad "B3" smd circle
			(at -0.499872 -0.249936 270)
			(size 0.2286 0.2286)
			(layers "F.Cu" "F.Mask" "F.Paste")
			(net "P12V_AUX")
		)
		(pad "B4" smd circle
			(at 0 -0.249936 270)
			(size 0.2286 0.2286)
			(layers "F.Cu" "F.Mask" "F.Paste")
			(net "P12V_E1S_0")
		)
		(pad "B5" smd circle
			(at 0.499872 -0.249936 270)
			(size 0.2286 0.2286)
			(layers "F.Cu" "F.Mask" "F.Paste")
			(net "P12V_AUX")
		)
		(pad "B6" smd circle
			(at 0.999998 -0.249936 270)
			(size 0.2286 0.2286)
			(layers "F.Cu" "F.Mask" "F.Paste")
			(net "P12V_E1S_0")
		)
		(pad "B7" smd circle
			(at 1.500124 -0.249936 270)
			(size 0.2286 0.2286)
			(layers "F.Cu" "F.Mask" "F.Paste")
			(net "GND")
		)
		(pad "C1" smd circle
			(at -1.500124 0.249936 270)
			(size 0.2286 0.2286)
			(layers "F.Cu" "F.Mask" "F.Paste")
			(net "GND")
		)
		(pad "C2" smd circle
			(at -0.999998 0.249936 270)
			(size 0.2286 0.2286)
			(layers "F.Cu" "F.Mask" "F.Paste")
			(net "GND")
		)
		(pad "C3" smd circle
			(at -0.499872 0.249936 270)
			(size 0.2286 0.2286)
			(layers "F.Cu" "F.Mask" "F.Paste")
			(net "P12V_AUX")
		)
		(pad "C4" smd circle
			(at 0 0.249936 270)
			(size 0.2286 0.2286)
			(layers "F.Cu" "F.Mask" "F.Paste")
			(net "P12V_E1S_0")
		)
		(pad "C5" smd circle
			(at 0.499872 0.249936 270)
			(size 0.2286 0.2286)
			(layers "F.Cu" "F.Mask" "F.Paste")
			(net "P12V_AUX")
		)
		(pad "C6" smd circle
			(at 0.999998 0.249936 270)
			(size 0.2286 0.2286)
			(layers "F.Cu" "F.Mask" "F.Paste")
			(net "P12V_E1S_0")
		)
		(pad "C7" smd circle
			(at 1.500124 0.249936 270)
			(size 0.2286 0.2286)
			(layers "F.Cu" "F.Mask" "F.Paste")
			(net "P12V_E1S_FAULT_0")
		)
		(pad "D1" smd circle
			(at -1.500124 0.750062 270)
			(size 0.2286 0.2286)
			(layers "F.Cu" "F.Mask" "F.Paste")
			(net "P12V_E1S_REG_0")
		)
		(pad "D2" smd circle
			(at -0.999998 0.750062 270)
			(size 0.2286 0.2286)
			(layers "F.Cu" "F.Mask" "F.Paste")
			(net "P12V_E1S_UV_0")
		)
		(pad "D3" smd circle
			(at -0.499872 0.750062 270)
			(size 0.2286 0.2286)
			(layers "F.Cu" "F.Mask" "F.Paste")
			(net "P12V_E1S_OV_0")
		)
		(pad "D4" smd circle
			(at 0 0.750062 270)
			(size 0.2286 0.2286)
			(layers "F.Cu" "F.Mask" "F.Paste")
			(net "P12V_E1S_0")
		)
		(pad "D5" smd circle
			(at 0.499872 0.750062 270)
			(size 0.2286 0.2286)
			(layers "F.Cu" "F.Mask" "F.Paste")
			(net "P12V_AUX")
		)
		(pad "D6" smd circle
			(at 0.999998 0.750062 270)
			(size 0.2286 0.2286)
			(layers "F.Cu" "F.Mask" "F.Paste")
			(net "P12V_E1S_0")
		)
		(pad "D7" smd circle
			(at 1.500124 0.750062 270)
			(size 0.2286 0.2286)
			(layers "F.Cu" "F.Mask" "F.Paste")
			(net "P12V_E1S_PWRGD_0")
		)
	)
	(footprint ""
		(layer "F.Cu")
		(at 111.952024 -65.092072)
		(property "Reference" "U6003"
			(at -2.1082 -3.165348 0)
			(unlocked yes)
			(layer "F.SilkS")
			(effects
				(font
					(size 0.7874 0.5842)
					(thickness 0.1524)
				)
				(justify left)
			)
		)
		(property "Value" ""
			(at 0 0 0)
			(layer "F.Fab")
			(effects
				(font
					(size 1.27 1.27)
				)
			)
		)
		(duplicate_pad_numbers_are_jumpers no)
		(fp_line
			(start -1.8288 -2.500122)
			(end -1.8288 2.500122)
			(stroke
				(width 0.1524)
				(type default)
			)
			(layer "F.SilkS")
		)
		(fp_line
			(start -1.8288 2.500122)
			(end 1.8288 2.500122)
			(stroke
				(width 0.1524)
				(type default)
			)
			(layer "F.SilkS")
		)
		(fp_line
			(start -1.077722 -2.500122)
			(end -1.8288 -2.500122)
			(stroke
				(width 0.1524)
				(type default)
			)
			(layer "F.SilkS")
		)
		(fp_line
			(start 0 -1.4224)
			(end -1.077722 -2.500122)
			(stroke
				(width 0.1524)
				(type default)
			)
			(layer "F.SilkS")
		)
		(fp_line
			(start 1.077722 -2.500122)
			(end 0 -1.4224)
			(stroke
				(width 0.1524)
				(type default)
			)
			(layer "F.SilkS")
		)
		(fp_line
			(start 1.8288 -2.500122)
			(end 1.077722 -2.500122)
			(stroke
				(width 0.1524)
				(type default)
			)
			(layer "F.SilkS")
		)
		(fp_line
			(start 1.8288 2.500122)
			(end 1.8288 -2.500122)
			(stroke
				(width 0.1524)
				(type default)
			)
			(layer "F.SilkS")
		)
		(fp_poly
			(pts
				(xy -2.313178 -3.971798) (xy -3.329178 -3.971798) (xy -2.821178 -2.955798)
			)
			(stroke
				(width 0)
				(type default)
			)
			(fill yes)
			(layer "F.SilkS")
		)
		(fp_line
			(start -1.999996 -2.500122)
			(end -1.999996 2.500122)
			(stroke
				(width 0.1)
				(type default)
			)
			(layer "F.Fab")
		)
		(fp_line
			(start -1.999996 2.500122)
			(end 1.999996 2.500122)
			(stroke
				(width 0.1)
				(type default)
			)
			(layer "F.Fab")
		)
		(fp_line
			(start 1.999996 -2.500122)
			(end -1.999996 -2.500122)
			(stroke
				(width 0.1)
				(type default)
			)
			(layer "F.Fab")
		)
		(fp_line
			(start 1.999996 2.500122)
			(end 1.999996 -2.500122)
			(stroke
				(width 0.1)
				(type default)
			)
			(layer "F.Fab")
		)
		(fp_poly
			(pts
				(xy -4.5085 -2.413) (xy -4.5085 -1.397) (xy -3.4925 -1.905)
			)
			(stroke
				(width 0)
				(type default)
			)
			(fill yes)
			(layer "F.Fab")
		)
		(pad "1" smd rect
			(at -2.599944 -1.905 270)
			(size 0.889 1.27)
			(layers "F.Cu" "F.Mask" "F.Paste")
			(net "USB_CPU0_ADD_A0")
		)
		(pad "2" smd rect
			(at -2.599944 -0.635 270)
			(size 0.889 1.27)
			(layers "F.Cu" "F.Mask" "F.Paste")
			(net "USB_CPU0_ADD_A1")
		)
		(pad "3" smd rect
			(at -2.599944 0.635 270)
			(size 0.889 1.27)
			(layers "F.Cu" "F.Mask" "F.Paste")
			(net "USB_CPU0_ADD_A2")
		)
		(pad "4" smd rect
			(at -2.599944 1.905 270)
			(size 0.889 1.27)
			(layers "F.Cu" "F.Mask" "F.Paste")
			(net "GND")
		)
		(pad "5" smd rect
			(at 2.599944 1.905 270)
			(size 0.889 1.27)
			(layers "F.Cu" "F.Mask" "F.Paste")
			(net "SMB_USB_CPU0_HUB1_SDA_R2")
		)
		(pad "6" smd rect
			(at 2.599944 0.635 270)
			(size 0.889 1.27)
			(layers "F.Cu" "F.Mask" "F.Paste")
			(net "SMB_USB_CPU0_HUB1_SCL_R2")
		)
		(pad "7" smd rect
			(at 2.599944 -0.635 270)
			(size 0.889 1.27)
			(layers "F.Cu" "F.Mask" "F.Paste")
			(net "PD_USB_CPU0_WP")
		)
		(pad "8" smd rect
			(at 2.599944 -1.905 270)
			(size 0.889 1.27)
			(layers "F.Cu" "F.Mask" "F.Paste")
			(net "P3V3_AUX")
		)
	)
	(footprint ""
		(layer "F.Cu")
		(at 341.578184 -172.311822 180)
		(property "Reference" "PR294"
			(at 0 0 180)
			(layer "F.SilkS")
			(hide yes)
			(effects
				(font
					(size 1.27 1.27)
				)
			)
		)
		(property "Value" ""
			(at 0 0 180)
			(layer "F.Fab")
			(effects
				(font
					(size 1.27 1.27)
				)
			)
		)
		(duplicate_pad_numbers_are_jumpers no)
		(fp_line
			(start 0.7874 0.4064)
			(end -0.7874 0.4064)
			(stroke
				(width 0.1524)
				(type default)
			)
			(layer "F.SilkS")
		)
		(fp_line
			(start 0.7874 -0.4064)
			(end 0.7874 0.4064)
			(stroke
				(width 0.1524)
				(type default)
			)
			(layer "F.SilkS")
		)
		(fp_line
			(start -0.7874 0.4064)
			(end -0.7874 -0.4064)
			(stroke
				(width 0.1524)
				(type default)
			)
			(layer "F.SilkS")
		)
		(fp_line
			(start -0.7874 -0.4064)
			(end 0.7874 -0.4064)
			(stroke
				(width 0.1524)
				(type default)
			)
			(layer "F.SilkS")
		)
		(fp_line
			(start 0.67945 0.3048)
			(end 0.120396 0.3048)
			(stroke
				(width 0.1)
				(type default)
			)
			(layer "F.Fab")
		)
		(fp_line
			(start 0.67945 -0.3048)
			(end 0.67945 0.3048)
			(stroke
				(width 0.1)
				(type default)
			)
			(layer "F.Fab")
		)
		(fp_line
			(start 0.12065 -0.2794)
			(end 0.12065 -0.3048)
			(stroke
				(width 0.1)
				(type default)
			)
			(layer "F.Fab")
		)
		(fp_line
			(start 0.12065 -0.3048)
			(end 0.67945 -0.3048)
			(stroke
				(width 0.1)
				(type default)
			)
			(layer "F.Fab")
		)
		(fp_line
			(start 0.120396 0.3048)
			(end 0.120396 0.2794)
			(stroke
				(width 0.1)
				(type default)
			)
			(layer "F.Fab")
		)
		(fp_line
			(start 0.120396 0.2794)
			(end -0.12065 0.2794)
			(stroke
				(width 0.1)
				(type default)
			)
			(layer "F.Fab")
		)
		(fp_line
			(start -0.12065 0.3048)
			(end -0.67945 0.3048)
			(stroke
				(width 0.1)
				(type default)
			)
			(layer "F.Fab")
		)
		(fp_line
			(start -0.12065 0.2794)
			(end -0.12065 0.3048)
			(stroke
				(width 0.1)
				(type default)
			)
			(layer "F.Fab")
		)
		(fp_line
			(start -0.12065 -0.2794)
			(end 0.12065 -0.2794)
			(stroke
				(width 0.1)
				(type default)
			)
			(layer "F.Fab")
		)
		(fp_line
			(start -0.12065 -0.305054)
			(end -0.12065 -0.2794)
			(stroke
				(width 0.1)
				(type default)
			)
			(layer "F.Fab")
		)
		(fp_line
			(start -0.67945 0.3048)
			(end -0.67945 -0.305054)
			(stroke
				(width 0.1)
				(type default)
			)
			(layer "F.Fab")
		)
		(fp_line
			(start -0.67945 -0.305054)
			(end -0.12065 -0.305054)
			(stroke
				(width 0.1)
				(type default)
			)
			(layer "F.Fab")
		)
		(pad "1" smd circle
			(at -0.40005 0 180)
			(size 0 0)
			(layers "F.Cu" "F.Mask" "F.Paste")
			(net "PVDDCR_CPU0_P0")
		)
		(pad "2" smd circle
			(at 0.40005 0 180)
			(size 0 0)
			(layers "F.Cu" "F.Mask" "F.Paste")
			(net "VSENSE_PVDDCR_CPU0_P0_DP")
		)
	)
	(footprint ""
		(layer "F.Cu")
		(at 342.966294 -161.056574 90)
		(property "Reference" "PC153_6"
			(at 0 0 90)
			(layer "F.SilkS")
			(hide yes)
			(effects
				(font
					(size 1.27 1.27)
				)
			)
		)
		(property "Value" ""
			(at 0 0 90)
			(layer "F.Fab")
			(effects
				(font
					(size 1.27 1.27)
				)
			)
		)
		(duplicate_pad_numbers_are_jumpers no)
		(fp_line
			(start 0.7874 -0.4064)
			(end 0.7874 0.4064)
			(stroke
				(width 0.1524)
				(type default)
			)
			(layer "F.SilkS")
		)
		(fp_line
			(start -0.7874 -0.4064)
			(end 0.7874 -0.4064)
			(stroke
				(width 0.1524)
				(type default)
			)
			(layer "F.SilkS")
		)
		(fp_line
			(start 0.7874 0.4064)
			(end -0.7874 0.4064)
			(stroke
				(width 0.1524)
				(type default)
			)
			(layer "F.SilkS")
		)
		(fp_line
			(start -0.7874 0.4064)
			(end -0.7874 -0.4064)
			(stroke
				(width 0.1524)
				(type default)
			)
			(layer "F.SilkS")
		)
		(fp_line
			(start -0.12065 -0.305054)
			(end -0.12065 -0.2794)
			(stroke
				(width 0.1)
				(type default)
			)
			(layer "F.Fab")
		)
		(fp_line
			(start -0.67945 -0.305054)
			(end -0.12065 -0.305054)
			(stroke
				(width 0.1)
				(type default)
			)
			(layer "F.Fab")
		)
		(fp_line
			(start 0.67945 -0.3048)
			(end 0.67945 0.3048)
			(stroke
				(width 0.1)
				(type default)
			)
			(layer "F.Fab")
		)
		(fp_line
			(start 0.12065 -0.3048)
			(end 0.67945 -0.3048)
			(stroke
				(width 0.1)
				(type default)
			)
			(layer "F.Fab")
		)
		(fp_line
			(start 0.12065 -0.2794)
			(end 0.12065 -0.3048)
			(stroke
				(width 0.1)
				(type default)
			)
			(layer "F.Fab")
		)
		(fp_line
			(start -0.12065 -0.2794)
			(end 0.12065 -0.2794)
			(stroke
				(width 0.1)
				(type default)
			)
			(layer "F.Fab")
		)
		(fp_line
			(start 0.120396 0.2794)
			(end -0.12065 0.2794)
			(stroke
				(width 0.1)
				(type default)
			)
			(layer "F.Fab")
		)
		(fp_line
			(start -0.12065 0.2794)
			(end -0.12065 0.3048)
			(stroke
				(width 0.1)
				(type default)
			)
			(layer "F.Fab")
		)
		(fp_line
			(start 0.67945 0.3048)
			(end 0.120396 0.3048)
			(stroke
				(width 0.1)
				(type default)
			)
			(layer "F.Fab")
		)
		(fp_line
			(start 0.120396 0.3048)
			(end 0.120396 0.2794)
			(stroke
				(width 0.1)
				(type default)
			)
			(layer "F.Fab")
		)
		(fp_line
			(start -0.12065 0.3048)
			(end -0.67945 0.3048)
			(stroke
				(width 0.1)
				(type default)
			)
			(layer "F.Fab")
		)
		(fp_line
			(start -0.67945 0.3048)
			(end -0.67945 -0.305054)
			(stroke
				(width 0.1)
				(type default)
			)
			(layer "F.Fab")
		)
		(pad "1" smd circle
			(at -0.40005 0 90)
			(size 0 0)
			(layers "F.Cu" "F.Mask" "F.Paste")
			(net "SW_P12V_AUX_PVDDCR_CPU0_P0_FLT")
		)
		(pad "2" smd circle
			(at 0.40005 0 90)
			(size 0 0)
			(layers "F.Cu" "F.Mask" "F.Paste")
			(net "GND")
		)
	)
	(footprint ""
		(layer "F.Cu")
		(at 166.624 -131.953 -90)
		(property "Reference" "R492"
			(at 0 0 270)
			(layer "F.SilkS")
			(hide yes)
			(effects
				(font
					(size 1.27 1.27)
				)
			)
		)
		(property "Value" ""
			(at 0 0 270)
			(layer "F.Fab")
			(effects
				(font
					(size 1.27 1.27)
				)
			)
		)
		(duplicate_pad_numbers_are_jumpers no)
		(fp_line
			(start -0.7874 0.4064)
			(end -0.7874 -0.4064)
			(stroke
				(width 0.1524)
				(type default)
			)
			(layer "F.SilkS")
		)
		(fp_line
			(start 0.7874 0.4064)
			(end -0.7874 0.4064)
			(stroke
				(width 0.1524)
				(type default)
			)
			(layer "F.SilkS")
		)
		(fp_line
			(start -0.7874 -0.4064)
			(end 0.7874 -0.4064)
			(stroke
				(width 0.1524)
				(type default)
			)
			(layer "F.SilkS")
		)
		(fp_line
			(start 0.7874 -0.4064)
			(end 0.7874 0.4064)
			(stroke
				(width 0.1524)
				(type default)
			)
			(layer "F.SilkS")
		)
		(fp_line
			(start -0.67945 0.3048)
			(end -0.67945 -0.305054)
			(stroke
				(width 0.1)
				(type default)
			)
			(layer "F.Fab")
		)
		(fp_line
			(start -0.12065 0.3048)
			(end -0.67945 0.3048)
			(stroke
				(width 0.1)
				(type default)
			)
			(layer "F.Fab")
		)
		(fp_line
			(start 0.120396 0.3048)
			(end 0.120396 0.2794)
			(stroke
				(width 0.1)
				(type default)
			)
			(layer "F.Fab")
		)
		(fp_line
			(start 0.67945 0.3048)
			(end 0.120396 0.3048)
			(stroke
				(width 0.1)
				(type default)
			)
			(layer "F.Fab")
		)
		(fp_line
			(start -0.12065 0.2794)
			(end -0.12065 0.3048)
			(stroke
				(width 0.1)
				(type default)
			)
			(layer "F.Fab")
		)
		(fp_line
			(start 0.120396 0.2794)
			(end -0.12065 0.2794)
			(stroke
				(width 0.1)
				(type default)
			)
			(layer "F.Fab")
		)
		(fp_line
			(start -0.12065 -0.2794)
			(end 0.12065 -0.2794)
			(stroke
				(width 0.1)
				(type default)
			)
			(layer "F.Fab")
		)
		(fp_line
			(start 0.12065 -0.2794)
			(end 0.12065 -0.3048)
			(stroke
				(width 0.1)
				(type default)
			)
			(layer "F.Fab")
		)
		(fp_line
			(start 0.12065 -0.3048)
			(end 0.67945 -0.3048)
			(stroke
				(width 0.1)
				(type default)
			)
			(layer "F.Fab")
		)
		(fp_line
			(start 0.67945 -0.3048)
			(end 0.67945 0.3048)
			(stroke
				(width 0.1)
				(type default)
			)
			(layer "F.Fab")
		)
		(fp_line
			(start -0.67945 -0.305054)
			(end -0.12065 -0.305054)
			(stroke
				(width 0.1)
				(type default)
			)
			(layer "F.Fab")
		)
		(fp_line
			(start -0.12065 -0.305054)
			(end -0.12065 -0.2794)
			(stroke
				(width 0.1)
				(type default)
			)
			(layer "F.Fab")
		)
		(pad "1" smd circle
			(at -0.40005 0 270)
			(size 0 0)
			(layers "F.Cu" "F.Mask" "F.Paste")
			(net "P3V3_AUX")
		)
		(pad "2" smd circle
			(at 0.40005 0 270)
			(size 0 0)
			(layers "F.Cu" "F.Mask" "F.Paste")
			(net "PWRGD_P5V_R_N")
		)
	)
	(footprint ""
		(layer "F.Cu")
		(at 194.911472 -422.671748 90)
		(property "Reference" "R8102"
			(at 0 0 90)
			(layer "F.SilkS")
			(hide yes)
			(effects
				(font
					(size 1.27 1.27)
				)
			)
		)
		(property "Value" ""
			(at 0 0 90)
			(layer "F.Fab")
			(effects
				(font
					(size 1.27 1.27)
				)
			)
		)
		(duplicate_pad_numbers_are_jumpers no)
		(fp_line
			(start 0.7874 -0.4064)
			(end 0.7874 0.4064)
			(stroke
				(width 0.1524)
				(type default)
			)
			(layer "F.SilkS")
		)
		(fp_line
			(start -0.7874 -0.4064)
			(end 0.7874 -0.4064)
			(stroke
				(width 0.1524)
				(type default)
			)
			(layer "F.SilkS")
		)
		(fp_line
			(start 0.7874 0.4064)
			(end -0.7874 0.4064)
			(stroke
				(width 0.1524)
				(type default)
			)
			(layer "F.SilkS")
		)
		(fp_line
			(start -0.7874 0.4064)
			(end -0.7874 -0.4064)
			(stroke
				(width 0.1524)
				(type default)
			)
			(layer "F.SilkS")
		)
		(fp_line
			(start -0.12065 -0.305054)
			(end -0.12065 -0.2794)
			(stroke
				(width 0.1)
				(type default)
			)
			(layer "F.Fab")
		)
		(fp_line
			(start -0.67945 -0.305054)
			(end -0.12065 -0.305054)
			(stroke
				(width 0.1)
				(type default)
			)
			(layer "F.Fab")
		)
		(fp_line
			(start 0.67945 -0.3048)
			(end 0.67945 0.3048)
			(stroke
				(width 0.1)
				(type default)
			)
			(layer "F.Fab")
		)
		(fp_line
			(start 0.12065 -0.3048)
			(end 0.67945 -0.3048)
			(stroke
				(width 0.1)
				(type default)
			)
			(layer "F.Fab")
		)
		(fp_line
			(start 0.12065 -0.2794)
			(end 0.12065 -0.3048)
			(stroke
				(width 0.1)
				(type default)
			)
			(layer "F.Fab")
		)
		(fp_line
			(start -0.12065 -0.2794)
			(end 0.12065 -0.2794)
			(stroke
				(width 0.1)
				(type default)
			)
			(layer "F.Fab")
		)
		(fp_line
			(start 0.120396 0.2794)
			(end -0.12065 0.2794)
			(stroke
				(width 0.1)
				(type default)
			)
			(layer "F.Fab")
		)
		(fp_line
			(start -0.12065 0.2794)
			(end -0.12065 0.3048)
			(stroke
				(width 0.1)
				(type default)
			)
			(layer "F.Fab")
		)
		(fp_line
			(start 0.67945 0.3048)
			(end 0.120396 0.3048)
			(stroke
				(width 0.1)
				(type default)
			)
			(layer "F.Fab")
		)
		(fp_line
			(start 0.120396 0.3048)
			(end 0.120396 0.2794)
			(stroke
				(width 0.1)
				(type default)
			)
			(layer "F.Fab")
		)
		(fp_line
			(start -0.12065 0.3048)
			(end -0.67945 0.3048)
			(stroke
				(width 0.1)
				(type default)
			)
			(layer "F.Fab")
		)
		(fp_line
			(start -0.67945 0.3048)
			(end -0.67945 -0.305054)
			(stroke
				(width 0.1)
				(type default)
			)
			(layer "F.Fab")
		)
		(pad "1" smd circle
			(at -0.40005 0 90)
			(size 0 0)
			(layers "F.Cu" "F.Mask" "F.Paste")
			(net "FM_AC_PWR_BTN_R_N")
		)
		(pad "2" smd circle
			(at 0.40005 0 90)
			(size 0 0)
			(layers "F.Cu" "F.Mask" "F.Paste")
			(net "FM_AC_PWR_BTN_PDB_N")
		)
	)
	(footprint ""
		(layer "F.Cu")
		(at 142.617444 -373.03583 -90)
		(property "Reference" "C769"
			(at 0 0 270)
			(layer "F.SilkS")
			(hide yes)
			(effects
				(font
					(size 1.27 1.27)
				)
			)
		)
		(property "Value" ""
			(at 0 0 270)
			(layer "F.Fab")
			(effects
				(font
					(size 1.27 1.27)
				)
			)
		)
		(duplicate_pad_numbers_are_jumpers no)
		(fp_line
			(start -0.299974 0.150114)
			(end -0.299974 -0.150114)
			(stroke
				(width 0.1)
				(type default)
			)
			(layer "F.Fab")
		)
		(fp_line
			(start 0.299974 0.150114)
			(end -0.299974 0.150114)
			(stroke
				(width 0.1)
				(type default)
			)
			(layer "F.Fab")
		)
		(fp_line
			(start -0.299974 -0.150114)
			(end 0.299974 -0.150114)
			(stroke
				(width 0.1)
				(type default)
			)
			(layer "F.Fab")
		)
		(fp_line
			(start 0.299974 -0.150114)
			(end 0.299974 0.150114)
			(stroke
				(width 0.1)
				(type default)
			)
			(layer "F.Fab")
		)
		(pad "1" smd rect
			(at -0.2667 0 270)
			(size 0.3048 0.381)
			(layers "F.Cu" "F.Mask" "F.Paste")
			(net "P5E_CPU1_P2_TX_C_DP<2>")
		)
		(pad "2" smd rect
			(at 0.2667 0 270)
			(size 0.3048 0.381)
			(layers "F.Cu" "F.Mask" "F.Paste")
			(net "P5E_CPU1_P2_TX_DP<2>")
		)
	)
	(footprint ""
		(layer "F.Cu")
		(at 362.265976 -256.012188 90)
		(property "Reference" "C2159"
			(at 0 0 90)
			(layer "F.SilkS")
			(hide yes)
			(effects
				(font
					(size 1.27 1.27)
				)
			)
		)
		(property "Value" ""
			(at 0 0 90)
			(layer "F.Fab")
			(effects
				(font
					(size 1.27 1.27)
				)
			)
		)
		(duplicate_pad_numbers_are_jumpers no)
		(fp_line
			(start 0.7874 -0.4064)
			(end 0.7874 0.4064)
			(stroke
				(width 0.1524)
				(type default)
			)
			(layer "F.SilkS")
		)
		(fp_line
			(start -0.7874 -0.4064)
			(end 0.7874 -0.4064)
			(stroke
				(width 0.1524)
				(type default)
			)
			(layer "F.SilkS")
		)
		(fp_line
			(start 0.7874 0.4064)
			(end -0.7874 0.4064)
			(stroke
				(width 0.1524)
				(type default)
			)
			(layer "F.SilkS")
		)
		(fp_line
			(start -0.7874 0.4064)
			(end -0.7874 -0.4064)
			(stroke
				(width 0.1524)
				(type default)
			)
			(layer "F.SilkS")
		)
		(fp_line
			(start -0.12065 -0.305054)
			(end -0.12065 -0.2794)
			(stroke
				(width 0.1)
				(type default)
			)
			(layer "F.Fab")
		)
		(fp_line
			(start -0.67945 -0.305054)
			(end -0.12065 -0.305054)
			(stroke
				(width 0.1)
				(type default)
			)
			(layer "F.Fab")
		)
		(fp_line
			(start 0.67945 -0.3048)
			(end 0.67945 0.3048)
			(stroke
				(width 0.1)
				(type default)
			)
			(layer "F.Fab")
		)
		(fp_line
			(start 0.12065 -0.3048)
			(end 0.67945 -0.3048)
			(stroke
				(width 0.1)
				(type default)
			)
			(layer "F.Fab")
		)
		(fp_line
			(start 0.12065 -0.2794)
			(end 0.12065 -0.3048)
			(stroke
				(width 0.1)
				(type default)
			)
			(layer "F.Fab")
		)
		(fp_line
			(start -0.12065 -0.2794)
			(end 0.12065 -0.2794)
			(stroke
				(width 0.1)
				(type default)
			)
			(layer "F.Fab")
		)
		(fp_line
			(start 0.120396 0.2794)
			(end -0.12065 0.2794)
			(stroke
				(width 0.1)
				(type default)
			)
			(layer "F.Fab")
		)
		(fp_line
			(start -0.12065 0.2794)
			(end -0.12065 0.3048)
			(stroke
				(width 0.1)
				(type default)
			)
			(layer "F.Fab")
		)
		(fp_line
			(start 0.67945 0.3048)
			(end 0.120396 0.3048)
			(stroke
				(width 0.1)
				(type default)
			)
			(layer "F.Fab")
		)
		(fp_line
			(start 0.120396 0.3048)
			(end 0.120396 0.2794)
			(stroke
				(width 0.1)
				(type default)
			)
			(layer "F.Fab")
		)
		(fp_line
			(start -0.12065 0.3048)
			(end -0.67945 0.3048)
			(stroke
				(width 0.1)
				(type default)
			)
			(layer "F.Fab")
		)
		(fp_line
			(start -0.67945 0.3048)
			(end -0.67945 -0.305054)
			(stroke
				(width 0.1)
				(type default)
			)
			(layer "F.Fab")
		)
		(pad "1" smd circle
			(at -0.40005 0 90)
			(size 0 0)
			(layers "F.Cu" "F.Mask" "F.Paste")
			(net "PVDDCR_SOC_P0")
		)
		(pad "2" smd circle
			(at 0.40005 0 90)
			(size 0 0)
			(layers "F.Cu" "F.Mask" "F.Paste")
			(net "GND")
		)
	)
	(footprint ""
		(layer "F.Cu")
		(at 205.232 -131.064)
		(property "Reference" "R490"
			(at 0 0 0)
			(layer "F.SilkS")
			(hide yes)
			(effects
				(font
					(size 1.27 1.27)
				)
			)
		)
		(property "Value" ""
			(at 0 0 0)
			(layer "F.Fab")
			(effects
				(font
					(size 1.27 1.27)
				)
			)
		)
		(duplicate_pad_numbers_are_jumpers no)
		(fp_line
			(start -0.7874 -0.4064)
			(end 0.7874 -0.4064)
			(stroke
				(width 0.1524)
				(type default)
			)
			(layer "F.SilkS")
		)
		(fp_line
			(start -0.7874 0.4064)
			(end -0.7874 -0.4064)
			(stroke
				(width 0.1524)
				(type default)
			)
			(layer "F.SilkS")
		)
		(fp_line
			(start 0.7874 -0.4064)
			(end 0.7874 0.4064)
			(stroke
				(width 0.1524)
				(type default)
			)
			(layer "F.SilkS")
		)
		(fp_line
			(start 0.7874 0.4064)
			(end -0.7874 0.4064)
			(stroke
				(width 0.1524)
				(type default)
			)
			(layer "F.SilkS")
		)
		(fp_line
			(start -0.67945 -0.305054)
			(end -0.12065 -0.305054)
			(stroke
				(width 0.1)
				(type default)
			)
			(layer "F.Fab")
		)
		(fp_line
			(start -0.67945 0.3048)
			(end -0.67945 -0.305054)
			(stroke
				(width 0.1)
				(type default)
			)
			(layer "F.Fab")
		)
		(fp_line
			(start -0.12065 -0.305054)
			(end -0.12065 -0.2794)
			(stroke
				(width 0.1)
				(type default)
			)
			(layer "F.Fab")
		)
		(fp_line
			(start -0.12065 -0.2794)
			(end 0.12065 -0.2794)
			(stroke
				(width 0.1)
				(type default)
			)
			(layer "F.Fab")
		)
		(fp_line
			(start -0.12065 0.2794)
			(end -0.12065 0.3048)
			(stroke
				(width 0.1)
				(type default)
			)
			(layer "F.Fab")
		)
		(fp_line
			(start -0.12065 0.3048)
			(end -0.67945 0.3048)
			(stroke
				(width 0.1)
				(type default)
			)
			(layer "F.Fab")
		)
		(fp_line
			(start 0.120396 0.2794)
			(end -0.12065 0.2794)
			(stroke
				(width 0.1)
				(type default)
			)
			(layer "F.Fab")
		)
		(fp_line
			(start 0.120396 0.3048)
			(end 0.120396 0.2794)
			(stroke
				(width 0.1)
				(type default)
			)
			(layer "F.Fab")
		)
		(fp_line
			(start 0.12065 -0.3048)
			(end 0.67945 -0.3048)
			(stroke
				(width 0.1)
				(type default)
			)
			(layer "F.Fab")
		)
		(fp_line
			(start 0.12065 -0.2794)
			(end 0.12065 -0.3048)
			(stroke
				(width 0.1)
				(type default)
			)
			(layer "F.Fab")
		)
		(fp_line
			(start 0.67945 -0.3048)
			(end 0.67945 0.3048)
			(stroke
				(width 0.1)
				(type default)
			)
			(layer "F.Fab")
		)
		(fp_line
			(start 0.67945 0.3048)
			(end 0.120396 0.3048)
			(stroke
				(width 0.1)
				(type default)
			)
			(layer "F.Fab")
		)
		(pad "1" smd circle
			(at -0.40005 0)
			(size 0 0)
			(layers "F.Cu" "F.Mask" "F.Paste")
			(net "PWRGD_P5V_R")
		)
		(pad "2" smd circle
			(at 0.40005 0)
			(size 0 0)
			(layers "F.Cu" "F.Mask" "F.Paste")
			(net "SW_P3V3_EN_R")
		)
	)
	(footprint ""
		(layer "F.Cu")
		(at 376.35815 -180.078634 -90)
		(property "Reference" "PC476"
			(at 0 0 270)
			(layer "F.SilkS")
			(hide yes)
			(effects
				(font
					(size 1.27 1.27)
				)
			)
		)
		(property "Value" ""
			(at 0 0 270)
			(layer "F.Fab")
			(effects
				(font
					(size 1.27 1.27)
				)
			)
		)
		(duplicate_pad_numbers_are_jumpers no)
		(fp_line
			(start -0.7874 0.4064)
			(end -0.7874 -0.4064)
			(stroke
				(width 0.1524)
				(type default)
			)
			(layer "F.SilkS")
		)
		(fp_line
			(start -0.210566 0.4064)
			(end -0.7874 0.4064)
			(stroke
				(width 0.1524)
				(type default)
			)
			(layer "F.SilkS")
		)
		(fp_line
			(start 0.7874 0.4064)
			(end 0.399034 0.4064)
			(stroke
				(width 0.1524)
				(type default)
			)
			(layer "F.SilkS")
		)
		(fp_line
			(start -0.7874 -0.4064)
			(end 0.7874 -0.4064)
			(stroke
				(width 0.1524)
				(type default)
			)
			(layer "F.SilkS")
		)
		(fp_line
			(start 0.7874 -0.4064)
			(end 0.7874 0.4064)
			(stroke
				(width 0.1524)
				(type default)
			)
			(layer "F.SilkS")
		)
		(fp_line
			(start -0.67945 0.3048)
			(end -0.67945 -0.305054)
			(stroke
				(width 0.1)
				(type default)
			)
			(layer "F.Fab")
		)
		(fp_line
			(start -0.12065 0.3048)
			(end -0.67945 0.3048)
			(stroke
				(width 0.1)
				(type default)
			)
			(layer "F.Fab")
		)
		(fp_line
			(start 0.120396 0.3048)
			(end 0.120396 0.2794)
			(stroke
				(width 0.1)
				(type default)
			)
			(layer "F.Fab")
		)
		(fp_line
			(start 0.67945 0.3048)
			(end 0.120396 0.3048)
			(stroke
				(width 0.1)
				(type default)
			)
			(layer "F.Fab")
		)
		(fp_line
			(start -0.12065 0.2794)
			(end -0.12065 0.3048)
			(stroke
				(width 0.1)
				(type default)
			)
			(layer "F.Fab")
		)
		(fp_line
			(start 0.120396 0.2794)
			(end -0.12065 0.2794)
			(stroke
				(width 0.1)
				(type default)
			)
			(layer "F.Fab")
		)
		(fp_line
			(start -0.12065 -0.2794)
			(end 0.12065 -0.2794)
			(stroke
				(width 0.1)
				(type default)
			)
			(layer "F.Fab")
		)
		(fp_line
			(start 0.12065 -0.2794)
			(end 0.12065 -0.3048)
			(stroke
				(width 0.1)
				(type default)
			)
			(layer "F.Fab")
		)
		(fp_line
			(start 0.12065 -0.3048)
			(end 0.67945 -0.3048)
			(stroke
				(width 0.1)
				(type default)
			)
			(layer "F.Fab")
		)
		(fp_line
			(start 0.67945 -0.3048)
			(end 0.67945 0.3048)
			(stroke
				(width 0.1)
				(type default)
			)
			(layer "F.Fab")
		)
		(fp_line
			(start -0.67945 -0.305054)
			(end -0.12065 -0.305054)
			(stroke
				(width 0.1)
				(type default)
			)
			(layer "F.Fab")
		)
		(fp_line
			(start -0.12065 -0.305054)
			(end -0.12065 -0.2794)
			(stroke
				(width 0.1)
				(type default)
			)
			(layer "F.Fab")
		)
		(pad "1" smd circle
			(at -0.40005 0 270)
			(size 0 0)
			(layers "F.Cu" "F.Mask" "F.Paste")
			(net "PVDDCR_CPU0_P0_VCC2")
		)
		(pad "2" smd circle
			(at 0.40005 0 270)
			(size 0 0)
			(layers "F.Cu" "F.Mask" "F.Paste")
			(net "GND")
		)
	)
	(footprint ""
		(layer "F.Cu")
		(at 48.523652 -400.419316 -90)
		(property "Reference" "C229"
			(at 0 0 270)
			(layer "F.SilkS")
			(hide yes)
			(effects
				(font
					(size 1.27 1.27)
				)
			)
		)
		(property "Value" ""
			(at 0 0 270)
			(layer "F.Fab")
			(effects
				(font
					(size 1.27 1.27)
				)
			)
		)
		(duplicate_pad_numbers_are_jumpers no)
		(fp_line
			(start -1.524 0.762)
			(end -1.524 -0.762)
			(stroke
				(width 0.1524)
				(type default)
			)
			(layer "F.SilkS")
		)
		(fp_line
			(start 1.524 0.762)
			(end -1.524 0.762)
			(stroke
				(width 0.1524)
				(type default)
			)
			(layer "F.SilkS")
		)
		(fp_line
			(start -1.524 -0.762)
			(end 1.524 -0.762)
			(stroke
				(width 0.1524)
				(type default)
			)
			(layer "F.SilkS")
		)
		(fp_line
			(start 1.524 -0.762)
			(end 1.524 0.762)
			(stroke
				(width 0.1524)
				(type default)
			)
			(layer "F.SilkS")
		)
		(fp_line
			(start -1.1049 0.724916)
			(end 1.1049 0.724916)
			(stroke
				(width 0.1)
				(type default)
			)
			(layer "F.Fab")
		)
		(fp_line
			(start 1.1049 0.724916)
			(end 1.1049 -0.724916)
			(stroke
				(width 0.1)
				(type default)
			)
			(layer "F.Fab")
		)
		(fp_line
			(start -1.1049 -0.724916)
			(end -1.1049 0.724916)
			(stroke
				(width 0.1)
				(type default)
			)
			(layer "F.Fab")
		)
		(fp_line
			(start 1.1049 -0.724916)
			(end -1.1049 -0.724916)
			(stroke
				(width 0.1)
				(type default)
			)
			(layer "F.Fab")
		)
		(pad "1" smd rect
			(at -0.889 0 90)
			(size 1.016 1.27)
			(layers "F.Cu" "F.Mask" "F.Paste")
			(net "P0V9_CPU1_RT_2D")
		)
		(pad "2" smd rect
			(at 0.889 0 90)
			(size 1.016 1.27)
			(layers "F.Cu" "F.Mask" "F.Paste")
			(net "GND")
		)
	)
	(footprint ""
		(layer "F.Cu")
		(at 127.121666 -408.517344 -90)
		(property "Reference" "C6702"
			(at 0 0 270)
			(layer "F.SilkS")
			(hide yes)
			(effects
				(font
					(size 1.27 1.27)
				)
			)
		)
		(property "Value" ""
			(at 0 0 270)
			(layer "F.Fab")
			(effects
				(font
					(size 1.27 1.27)
				)
			)
		)
		(duplicate_pad_numbers_are_jumpers no)
		(fp_line
			(start -0.299974 0.150114)
			(end -0.299974 -0.150114)
			(stroke
				(width 0.1)
				(type default)
			)
			(layer "F.Fab")
		)
		(fp_line
			(start 0.299974 0.150114)
			(end -0.299974 0.150114)
			(stroke
				(width 0.1)
				(type default)
			)
			(layer "F.Fab")
		)
		(fp_line
			(start -0.299974 -0.150114)
			(end 0.299974 -0.150114)
			(stroke
				(width 0.1)
				(type default)
			)
			(layer "F.Fab")
		)
		(fp_line
			(start 0.299974 -0.150114)
			(end 0.299974 0.150114)
			(stroke
				(width 0.1)
				(type default)
			)
			(layer "F.Fab")
		)
		(pad "1" smd rect
			(at -0.2667 0 270)
			(size 0.3048 0.381)
			(layers "F.Cu" "F.Mask" "F.Paste")
			(net "P5E_CPU1_P2_TX_BUF_C_DN<4>")
		)
		(pad "2" smd rect
			(at 0.2667 0 270)
			(size 0.3048 0.381)
			(layers "F.Cu" "F.Mask" "F.Paste")
			(net "P5E_CPU1_P2_TX_BUF_DN<4>")
		)
	)
	(footprint ""
		(layer "F.Cu")
		(at 398.750028 -440.489848)
		(property "Reference" "J105"
			(at 19.875754 19.509486 0)
			(unlocked yes)
			(layer "F.SilkS")
			(effects
				(font
					(size 0.7874 0.5842)
					(thickness 0.1524)
				)
				(justify left)
			)
		)
		(property "Value" ""
			(at 0 0 0)
			(layer "F.Fab")
			(effects
				(font
					(size 1.27 1.27)
				)
			)
		)
		(duplicate_pad_numbers_are_jumpers no)
		(fp_line
			(start -4.249928 22.400006)
			(end -4.249928 -0.484124)
			(stroke
				(width 0.1524)
				(type default)
			)
			(layer "F.SilkS")
		)
		(fp_line
			(start -3.576828 22.400006)
			(end -4.249928 22.400006)
			(stroke
				(width 0.1524)
				(type default)
			)
			(layer "F.SilkS")
		)
		(fp_line
			(start -1.249934 -1.500124)
			(end 15.649956 -1.500124)
			(stroke
				(width 0.1524)
				(type default)
			)
			(layer "F.SilkS")
		)
		(fp_line
			(start -1.249934 17.071848)
			(end -1.249934 19.400012)
			(stroke
				(width 0.1524)
				(type default)
			)
			(layer "F.SilkS")
		)
		(fp_line
			(start -1.249934 19.400012)
			(end -0.605028 19.400012)
			(stroke
				(width 0.1524)
				(type default)
			)
			(layer "F.SilkS")
		)
		(fp_line
			(start -0.528828 22.400006)
			(end -2.179828 22.400006)
			(stroke
				(width 0.1524)
				(type default)
			)
			(layer "F.SilkS")
		)
		(fp_line
			(start 0.0254 -0.9144)
			(end 1.0414 -0.9144)
			(stroke
				(width 0.1524)
				(type default)
			)
			(layer "F.SilkS")
		)
		(fp_line
			(start 0.5334 -1.4224)
			(end 0.0254 -0.9144)
			(stroke
				(width 0.1524)
				(type default)
			)
			(layer "F.SilkS")
		)
		(fp_line
			(start 0.5334 -1.4224)
			(end 0.5334 -0.5588)
			(stroke
				(width 0.1524)
				(type default)
			)
			(layer "F.SilkS")
		)
		(fp_line
			(start 0.5334 -0.5588)
			(end 1.8034 -0.5588)
			(stroke
				(width 0.1524)
				(type default)
			)
			(layer "F.SilkS")
		)
		(fp_line
			(start 0.944372 19.400012)
			(end 2.392172 19.400012)
			(stroke
				(width 0.1524)
				(type default)
			)
			(layer "F.SilkS")
		)
		(fp_line
			(start 1.0414 -0.9144)
			(end 0.5334 -1.4224)
			(stroke
				(width 0.1524)
				(type default)
			)
			(layer "F.SilkS")
		)
		(fp_line
			(start 1.8034 -0.5588)
			(end 2.032 -0.7874)
			(stroke
				(width 0.1524)
				(type default)
			)
			(layer "F.SilkS")
		)
		(fp_line
			(start 2.493772 22.400006)
			(end 0.842772 22.400006)
			(stroke
				(width 0.1524)
				(type default)
			)
			(layer "F.SilkS")
		)
		(fp_line
			(start 3.992372 19.400012)
			(end 5.440172 19.400012)
			(stroke
				(width 0.1524)
				(type default)
			)
			(layer "F.SilkS")
		)
		(fp_line
			(start 5.592572 22.400006)
			(end 3.865372 22.400006)
			(stroke
				(width 0.1524)
				(type default)
			)
			(layer "F.SilkS")
		)
		(fp_line
			(start 7.091172 19.400012)
			(end 8.513572 19.400012)
			(stroke
				(width 0.1524)
				(type default)
			)
			(layer "F.SilkS")
		)
		(fp_line
			(start 8.615172 22.400006)
			(end 6.938772 22.400006)
			(stroke
				(width 0.1524)
				(type default)
			)
			(layer "F.SilkS")
		)
		(fp_line
			(start 10.113772 19.400012)
			(end 11.561572 19.400012)
			(stroke
				(width 0.1524)
				(type default)
			)
			(layer "F.SilkS")
		)
		(fp_line
			(start 11.713972 22.400006)
			(end 10.012172 22.400006)
			(stroke
				(width 0.1524)
				(type default)
			)
			(layer "F.SilkS")
		)
		(fp_line
			(start 13.187172 19.400012)
			(end 14.609572 19.400012)
			(stroke
				(width 0.1524)
				(type default)
			)
			(layer "F.SilkS")
		)
		(fp_line
			(start 14.761972 22.400006)
			(end 13.110972 22.400006)
			(stroke
				(width 0.1524)
				(type default)
			)
			(layer "F.SilkS")
		)
		(fp_line
			(start 15.649956 19.400012)
			(end 15.649956 -0.484124)
			(stroke
				(width 0.1524)
				(type default)
			)
			(layer "F.SilkS")
		)
		(fp_line
			(start 17.886172 22.400006)
			(end 16.108172 22.400006)
			(stroke
				(width 0.1524)
				(type default)
			)
			(layer "F.SilkS")
		)
		(fp_line
			(start 18.64995 -0.484124)
			(end 18.64995 19.103848)
			(stroke
				(width 0.1524)
				(type default)
			)
			(layer "F.SilkS")
		)
		(fp_poly
			(pts
				(xy -0.892048 0) (xy -1.908048 0.508) (xy -1.908048 -0.508)
			)
			(stroke
				(width 0)
				(type default)
			)
			(fill yes)
			(layer "F.SilkS")
		)
		(fp_line
			(start -4.249928 -11.999976)
			(end 18.64995 -11.999976)
			(stroke
				(width 0.1524)
				(type default)
			)
			(layer "B.SilkS")
		)
		(fp_line
			(start -4.249928 21.593048)
			(end -4.249928 -11.999976)
			(stroke
				(width 0.1524)
				(type default)
			)
			(layer "B.SilkS")
		)
		(fp_line
			(start -2.103628 22.400006)
			(end -3.754628 22.400006)
			(stroke
				(width 0.1524)
				(type default)
			)
			(layer "B.SilkS")
		)
		(fp_line
			(start 0.868172 22.400006)
			(end -0.605028 22.400006)
			(stroke
				(width 0.1524)
				(type default)
			)
			(layer "B.SilkS")
		)
		(fp_line
			(start 3.992372 22.400006)
			(end 2.493772 22.400006)
			(stroke
				(width 0.1524)
				(type default)
			)
			(layer "B.SilkS")
		)
		(fp_line
			(start 7.065772 22.400006)
			(end 5.465572 22.400006)
			(stroke
				(width 0.1524)
				(type default)
			)
			(layer "B.SilkS")
		)
		(fp_line
			(start 10.088372 22.400006)
			(end 8.691372 22.400006)
			(stroke
				(width 0.1524)
				(type default)
			)
			(layer "B.SilkS")
		)
		(fp_line
			(start 13.212572 22.400006)
			(end 11.713972 22.400006)
			(stroke
				(width 0.1524)
				(type default)
			)
			(layer "B.SilkS")
		)
		(fp_line
			(start 16.260572 22.400006)
			(end 14.787372 22.400006)
			(stroke
				(width 0.1524)
				(type default)
			)
			(layer "B.SilkS")
		)
		(fp_line
			(start 18.64995 -11.999976)
			(end 18.64995 22.400006)
			(stroke
				(width 0.1524)
				(type default)
			)
			(layer "B.SilkS")
		)
		(fp_line
			(start 18.64995 22.400006)
			(end 17.733772 22.400006)
			(stroke
				(width 0.1524)
				(type default)
			)
			(layer "B.SilkS")
		)
		(fp_line
			(start -4.249928 -11.999976)
			(end 18.64995 -11.999976)
			(stroke
				(width 0.1)
				(type default)
			)
			(layer "B.Fab")
		)
		(fp_line
			(start -4.249928 22.400006)
			(end -4.249928 -11.999976)
			(stroke
				(width 0.1)
				(type default)
			)
			(layer "B.Fab")
		)
		(fp_line
			(start 18.64995 -11.999976)
			(end 18.64995 22.400006)
			(stroke
				(width 0.1)
				(type default)
			)
			(layer "B.Fab")
		)
		(fp_line
			(start 18.64995 22.400006)
			(end -4.249928 22.400006)
			(stroke
				(width 0.1)
				(type default)
			)
			(layer "B.Fab")
		)
		(fp_line
			(start -1.249934 -8.999982)
			(end -1.249934 19.400012)
			(stroke
				(width 0.1)
				(type default)
			)
			(layer "F.Fab")
		)
		(fp_line
			(start -1.249934 19.400012)
			(end 15.649956 19.400012)
			(stroke
				(width 0.1)
				(type default)
			)
			(layer "F.Fab")
		)
		(fp_line
			(start 15.649956 -8.999982)
			(end -1.249934 -8.999982)
			(stroke
				(width 0.1)
				(type default)
			)
			(layer "F.Fab")
		)
		(fp_line
			(start 15.649956 19.400012)
			(end 15.649956 -8.999982)
			(stroke
				(width 0.1)
				(type default)
			)
			(layer "F.Fab")
		)
		(fp_poly
			(pts
				(xy -2.670048 -0.508) (xy -2.670048 0.508) (xy -1.654048 0)
			)
			(stroke
				(width 0)
				(type default)
			)
			(fill yes)
			(layer "F.Fab")
		)
		(fp_text user "1"
			(at -0.629158 19.992848 90)
			(unlocked yes)
			(layer "F.SilkS")
			(effects
				(font
					(size 0.7874 0.5842)
					(thickness 0.1524)
				)
			)
		)
		(fp_text user "2"
			(at 2.111248 19.8628 90)
			(unlocked yes)
			(layer "F.SilkS")
			(effects
				(font
					(size 0.7874 0.5842)
					(thickness 0.1524)
				)
			)
		)
		(fp_text user "EDGE OF DAUGHTER CARD"
			(at 2.2479 -0.899668 0)
			(unlocked yes)
			(layer "F.SilkS")
			(effects
				(font
					(size 0.635 0.4064)
					(thickness 0.1524)
				)
				(justify left)
			)
		)
		(fp_text user "3"
			(at 4.298442 19.942048 90)
			(unlocked yes)
			(layer "F.SilkS")
			(effects
				(font
					(size 0.7874 0.5842)
					(thickness 0.1524)
				)
			)
		)
		(fp_text user "4"
			(at 7.143242 20.043648 90)
			(unlocked yes)
			(layer "F.SilkS")
			(effects
				(font
					(size 0.7874 0.5842)
					(thickness 0.1524)
				)
			)
		)
		(fp_text user "5"
			(at 8.337042 19.992848 90)
			(unlocked yes)
			(layer "F.SilkS")
			(effects
				(font
					(size 0.7874 0.5842)
					(thickness 0.1524)
				)
			)
		)
		(fp_text user "6"
			(at 10.318242 20.069048 90)
			(unlocked yes)
			(layer "F.SilkS")
			(effects
				(font
					(size 0.7874 0.5842)
					(thickness 0.1524)
				)
			)
		)
		(fp_text user "7"
			(at 11.613642 20.043648 90)
			(unlocked yes)
			(layer "F.SilkS")
			(effects
				(font
					(size 0.7874 0.5842)
					(thickness 0.1524)
				)
			)
		)
		(fp_text user "8"
			(at 14.077442 20.094448 90)
			(unlocked yes)
			(layer "F.SilkS")
			(effects
				(font
					(size 0.7874 0.5842)
					(thickness 0.1524)
				)
			)
		)
		(fp_text user "B"
			(at 16.397478 1.199896 90)
			(unlocked yes)
			(layer "F.SilkS")
			(effects
				(font
					(size 0.7874 0.5842)
					(thickness 0.1524)
				)
			)
		)
		(fp_text user "C"
			(at 16.397478 2.400046 90)
			(unlocked yes)
			(layer "F.SilkS")
			(effects
				(font
					(size 0.7874 0.5842)
					(thickness 0.1524)
				)
			)
		)
		(fp_text user "D"
			(at 16.397478 3.599942 90)
			(unlocked yes)
			(layer "F.SilkS")
			(effects
				(font
					(size 0.7874 0.5842)
					(thickness 0.1524)
				)
			)
		)
		(fp_text user "E"
			(at 16.397478 4.800092 90)
			(unlocked yes)
			(layer "F.SilkS")
			(effects
				(font
					(size 0.7874 0.5842)
					(thickness 0.1524)
				)
			)
		)
		(fp_text user "F"
			(at 16.397478 5.999988 90)
			(unlocked yes)
			(layer "F.SilkS")
			(effects
				(font
					(size 0.7874 0.5842)
					(thickness 0.1524)
				)
			)
		)
		(fp_text user "G"
			(at 16.397478 7.199884 90)
			(unlocked yes)
			(layer "F.SilkS")
			(effects
				(font
					(size 0.7874 0.5842)
					(thickness 0.1524)
				)
			)
		)
		(fp_text user "H"
			(at 16.397478 8.400034 90)
			(unlocked yes)
			(layer "F.SilkS")
			(effects
				(font
					(size 0.7874 0.5842)
					(thickness 0.1524)
				)
			)
		)
		(fp_text user "I"
			(at 16.397478 9.59993 90)
			(unlocked yes)
			(layer "F.SilkS")
			(effects
				(font
					(size 0.7874 0.5842)
					(thickness 0.1524)
				)
			)
		)
		(fp_text user "J"
			(at 16.397478 10.80008 90)
			(unlocked yes)
			(layer "F.SilkS")
			(effects
				(font
					(size 0.7874 0.5842)
					(thickness 0.1524)
				)
			)
		)
		(fp_text user "K"
			(at 16.397478 11.999976 90)
			(unlocked yes)
			(layer "F.SilkS")
			(effects
				(font
					(size 0.7874 0.5842)
					(thickness 0.1524)
				)
			)
		)
		(fp_text user "L"
			(at 16.397478 13.200126 90)
			(unlocked yes)
			(layer "F.SilkS")
			(effects
				(font
					(size 0.7874 0.5842)
					(thickness 0.1524)
				)
			)
		)
		(fp_text user "M"
			(at 16.397478 14.400022 90)
			(unlocked yes)
			(layer "F.SilkS")
			(effects
				(font
					(size 0.7874 0.5842)
					(thickness 0.1524)
				)
			)
		)
		(fp_text user "N"
			(at 16.397478 15.599918 90)
			(unlocked yes)
			(layer "F.SilkS")
			(effects
				(font
					(size 0.7874 0.5842)
					(thickness 0.1524)
				)
			)
		)
		(fp_text user "PRESS-FIT"
			(at 17.897856 7.926578 90)
			(unlocked yes)
			(layer "F.SilkS")
			(effects
				(font
					(size 0.7874 0.5842)
					(thickness 0.1524)
				)
				(justify left)
			)
		)
		(fp_text user "A"
			(at -1.199134 0 90)
			(unlocked yes)
			(layer "B.SilkS")
			(effects
				(font
					(size 0.7874 0.5842)
					(thickness 0.1524)
				)
				(justify mirror)
			)
		)
		(fp_text user "G"
			(at -1.173734 7.4168 90)
			(unlocked yes)
			(layer "B.SilkS")
			(effects
				(font
					(size 0.7874 0.5842)
					(thickness 0.1524)
				)
				(justify mirror)
			)
		)
		(fp_text user "H"
			(at -1.148334 8.636 90)
			(unlocked yes)
			(layer "B.SilkS")
			(effects
				(font
					(size 0.7874 0.5842)
					(thickness 0.1524)
				)
				(justify mirror)
			)
		)
		(fp_text user "B"
			(at -1.14681 1.326896 90)
			(unlocked yes)
			(layer "B.SilkS")
			(effects
				(font
					(size 0.7874 0.5842)
					(thickness 0.1524)
				)
				(justify mirror)
			)
		)
		(fp_text user "C"
			(at -1.14681 2.527046 90)
			(unlocked yes)
			(layer "B.SilkS")
			(effects
				(font
					(size 0.7874 0.5842)
					(thickness 0.1524)
				)
				(justify mirror)
			)
		)
		(fp_text user "D"
			(at -1.14681 3.726942 90)
			(unlocked yes)
			(layer "B.SilkS")
			(effects
				(font
					(size 0.7874 0.5842)
					(thickness 0.1524)
				)
				(justify mirror)
			)
		)
		(fp_text user "E"
			(at -1.14681 4.927092 90)
			(unlocked yes)
			(layer "B.SilkS")
			(effects
				(font
					(size 0.7874 0.5842)
					(thickness 0.1524)
				)
				(justify mirror)
			)
		)
		(fp_text user "F"
			(at -1.14681 6.126988 90)
			(unlocked yes)
			(layer "B.SilkS")
			(effects
				(font
					(size 0.7874 0.5842)
					(thickness 0.1524)
				)
				(justify mirror)
			)
		)
		(fp_text user "I"
			(at -1.14681 9.72693 90)
			(unlocked yes)
			(layer "B.SilkS")
			(effects
				(font
					(size 0.7874 0.5842)
					(thickness 0.1524)
				)
				(justify mirror)
			)
		)
		(fp_text user "J"
			(at -1.14681 10.92708 90)
			(unlocked yes)
			(layer "B.SilkS")
			(effects
				(font
					(size 0.7874 0.5842)
					(thickness 0.1524)
				)
				(justify mirror)
			)
		)
		(fp_text user "K"
			(at -1.14681 12.126976 90)
			(unlocked yes)
			(layer "B.SilkS")
			(effects
				(font
					(size 0.7874 0.5842)
					(thickness 0.1524)
				)
				(justify mirror)
			)
		)
		(fp_text user "L"
			(at -1.14681 13.327126 90)
			(unlocked yes)
			(layer "B.SilkS")
			(effects
				(font
					(size 0.7874 0.5842)
					(thickness 0.1524)
				)
				(justify mirror)
			)
		)
		(fp_text user "M"
			(at -1.14681 14.527022 90)
			(unlocked yes)
			(layer "B.SilkS")
			(effects
				(font
					(size 0.7874 0.5842)
					(thickness 0.1524)
				)
				(justify mirror)
			)
		)
		(fp_text user "N"
			(at -1.14681 15.726918 90)
			(unlocked yes)
			(layer "B.SilkS")
			(effects
				(font
					(size 0.7874 0.5842)
					(thickness 0.1524)
				)
				(justify mirror)
			)
		)
		(fp_text user "1"
			(at 0.060452 16.764 90)
			(unlocked yes)
			(layer "B.SilkS")
			(effects
				(font
					(size 0.7874 0.5842)
					(thickness 0.1524)
				)
				(justify mirror)
			)
		)
		(fp_text user "2"
			(at 2.060448 16.764 90)
			(unlocked yes)
			(layer "B.SilkS")
			(effects
				(font
					(size 0.7874 0.5842)
					(thickness 0.1524)
				)
				(justify mirror)
			)
		)
		(fp_text user "3"
			(at 4.060444 16.764 90)
			(unlocked yes)
			(layer "B.SilkS")
			(effects
				(font
					(size 0.7874 0.5842)
					(thickness 0.1524)
				)
				(justify mirror)
			)
		)
		(fp_text user "4"
			(at 6.06044 16.764 90)
			(unlocked yes)
			(layer "B.SilkS")
			(effects
				(font
					(size 0.7874 0.5842)
					(thickness 0.1524)
				)
				(justify mirror)
			)
		)
		(fp_text user "5"
			(at 8.060436 16.764 90)
			(unlocked yes)
			(layer "B.SilkS")
			(effects
				(font
					(size 0.7874 0.5842)
					(thickness 0.1524)
				)
				(justify mirror)
			)
		)
		(fp_text user "6"
			(at 10.060432 16.764 90)
			(unlocked yes)
			(layer "B.SilkS")
			(effects
				(font
					(size 0.7874 0.5842)
					(thickness 0.1524)
				)
				(justify mirror)
			)
		)
		(fp_text user "7"
			(at 12.060428 16.764 90)
			(unlocked yes)
			(layer "B.SilkS")
			(effects
				(font
					(size 0.7874 0.5842)
					(thickness 0.1524)
				)
				(justify mirror)
			)
		)
		(fp_text user "8"
			(at 14.060424 16.764 90)
			(unlocked yes)
			(layer "B.SilkS")
			(effects
				(font
					(size 0.7874 0.5842)
					(thickness 0.1524)
				)
				(justify mirror)
			)
		)
		(fp_text user "PRESS-FIT"
			(at 17.23771 -0.0762 90)
			(unlocked yes)
			(layer "B.SilkS")
			(effects
				(font
					(size 1.905 1.4224)
					(thickness 0.1524)
				)
				(justify left mirror)
			)
		)
		(fp_text user "A"
			(at -1.199134 0 90)
			(unlocked yes)
			(layer "B.Fab")
			(effects
				(font
					(size 0.7874 0.5842)
					(thickness 0.1524)
				)
				(justify mirror)
			)
		)
		(fp_text user "G"
			(at -1.173734 7.4168 90)
			(unlocked yes)
			(layer "B.Fab")
			(effects
				(font
					(size 0.7874 0.5842)
					(thickness 0.1524)
				)
				(justify mirror)
			)
		)
		(fp_text user "H"
			(at -1.148334 8.636 90)
			(unlocked yes)
			(layer "B.Fab")
			(effects
				(font
					(size 0.7874 0.5842)
					(thickness 0.1524)
				)
				(justify mirror)
			)
		)
		(fp_text user "B"
			(at -1.14681 1.326896 90)
			(unlocked yes)
			(layer "B.Fab")
			(effects
				(font
					(size 0.7874 0.5842)
					(thickness 0.1524)
				)
				(justify mirror)
			)
		)
		(fp_text user "C"
			(at -1.14681 2.527046 90)
			(unlocked yes)
			(layer "B.Fab")
			(effects
				(font
					(size 0.7874 0.5842)
					(thickness 0.1524)
				)
				(justify mirror)
			)
		)
		(fp_text user "D"
			(at -1.14681 3.726942 90)
			(unlocked yes)
			(layer "B.Fab")
			(effects
				(font
					(size 0.7874 0.5842)
					(thickness 0.1524)
				)
				(justify mirror)
			)
		)
		(fp_text user "E"
			(at -1.14681 4.927092 90)
			(unlocked yes)
			(layer "B.Fab")
			(effects
				(font
					(size 0.7874 0.5842)
					(thickness 0.1524)
				)
				(justify mirror)
			)
		)
		(fp_text user "F"
			(at -1.14681 6.126988 90)
			(unlocked yes)
			(layer "B.Fab")
			(effects
				(font
					(size 0.7874 0.5842)
					(thickness 0.1524)
				)
				(justify mirror)
			)
		)
		(fp_text user "I"
			(at -1.14681 9.72693 90)
			(unlocked yes)
			(layer "B.Fab")
			(effects
				(font
					(size 0.7874 0.5842)
					(thickness 0.1524)
				)
				(justify mirror)
			)
		)
		(fp_text user "J"
			(at -1.14681 10.92708 90)
			(unlocked yes)
			(layer "B.Fab")
			(effects
				(font
					(size 0.7874 0.5842)
					(thickness 0.1524)
				)
				(justify mirror)
			)
		)
		(fp_text user "K"
			(at -1.14681 12.126976 90)
			(unlocked yes)
			(layer "B.Fab")
			(effects
				(font
					(size 0.7874 0.5842)
					(thickness 0.1524)
				)
				(justify mirror)
			)
		)
		(fp_text user "L"
			(at -1.14681 13.327126 90)
			(unlocked yes)
			(layer "B.Fab")
			(effects
				(font
					(size 0.7874 0.5842)
					(thickness 0.1524)
				)
				(justify mirror)
			)
		)
		(fp_text user "M"
			(at -1.14681 14.527022 90)
			(unlocked yes)
			(layer "B.Fab")
			(effects
				(font
					(size 0.7874 0.5842)
					(thickness 0.1524)
				)
				(justify mirror)
			)
		)
		(fp_text user "N"
			(at -1.14681 15.726918 90)
			(unlocked yes)
			(layer "B.Fab")
			(effects
				(font
					(size 0.7874 0.5842)
					(thickness 0.1524)
				)
				(justify mirror)
			)
		)
		(fp_text user "1"
			(at 0.060452 16.764 90)
			(unlocked yes)
			(layer "B.Fab")
			(effects
				(font
					(size 0.7874 0.5842)
					(thickness 0.1524)
				)
				(justify mirror)
			)
		)
		(fp_text user "2"
			(at 2.060448 16.764 90)
			(unlocked yes)
			(layer "B.Fab")
			(effects
				(font
					(size 0.7874 0.5842)
					(thickness 0.1524)
				)
				(justify mirror)
			)
		)
		(fp_text user "3"
			(at 4.060444 16.764 90)
			(unlocked yes)
			(layer "B.Fab")
			(effects
				(font
					(size 0.7874 0.5842)
					(thickness 0.1524)
				)
				(justify mirror)
			)
		)
		(fp_text user "4"
			(at 6.06044 16.764 90)
			(unlocked yes)
			(layer "B.Fab")
			(effects
				(font
					(size 0.7874 0.5842)
					(thickness 0.1524)
				)
				(justify mirror)
			)
		)
		(fp_text user "5"
			(at 8.060436 16.764 90)
			(unlocked yes)
			(layer "B.Fab")
			(effects
				(font
					(size 0.7874 0.5842)
					(thickness 0.1524)
				)
				(justify mirror)
			)
		)
		(fp_text user "6"
			(at 10.060432 16.764 90)
			(unlocked yes)
			(layer "B.Fab")
			(effects
				(font
					(size 0.7874 0.5842)
					(thickness 0.1524)
				)
				(justify mirror)
			)
		)
		(fp_text user "7"
			(at 12.060428 16.764 90)
			(unlocked yes)
			(layer "B.Fab")
			(effects
				(font
					(size 0.7874 0.5842)
					(thickness 0.1524)
				)
				(justify mirror)
			)
		)
		(fp_text user "8"
			(at 14.060424 16.764 90)
			(unlocked yes)
			(layer "B.Fab")
			(effects
				(font
					(size 0.7874 0.5842)
					(thickness 0.1524)
				)
				(justify mirror)
			)
		)
		(fp_text user "PRESS-FIT"
			(at 17.23771 -0.0762 90)
			(unlocked yes)
			(layer "B.Fab")
			(effects
				(font
					(size 1.905 1.4224)
					(thickness 0.1524)
				)
				(justify left mirror)
			)
		)
		(fp_text user "B"
			(at -2.253742 1.199896 90)
			(unlocked yes)
			(layer "F.Fab")
			(effects
				(font
					(size 0.7874 0.5842)
					(thickness 0.1524)
				)
			)
		)
		(fp_text user "C"
			(at -2.253742 2.400046 90)
			(unlocked yes)
			(layer "F.Fab")
			(effects
				(font
					(size 0.7874 0.5842)
					(thickness 0.1524)
				)
			)
		)
		(fp_text user "D"
			(at -2.253742 3.599942 90)
			(unlocked yes)
			(layer "F.Fab")
			(effects
				(font
					(size 0.7874 0.5842)
					(thickness 0.1524)
				)
			)
		)
		(fp_text user "E"
			(at -2.253742 4.800092 90)
			(unlocked yes)
			(layer "F.Fab")
			(effects
				(font
					(size 0.7874 0.5842)
					(thickness 0.1524)
				)
			)
		)
		(fp_text user "F"
			(at -2.253742 5.999988 90)
			(unlocked yes)
			(layer "F.Fab")
			(effects
				(font
					(size 0.7874 0.5842)
					(thickness 0.1524)
				)
			)
		)
		(fp_text user "G"
			(at -2.253742 7.199884 90)
			(unlocked yes)
			(layer "F.Fab")
			(effects
				(font
					(size 0.7874 0.5842)
					(thickness 0.1524)
				)
			)
		)
		(fp_text user "H"
			(at -2.253742 8.400034 90)
			(unlocked yes)
			(layer "F.Fab")
			(effects
				(font
					(size 0.7874 0.5842)
					(thickness 0.1524)
				)
			)
		)
		(fp_text user "I"
			(at -2.253742 9.59993 90)
			(unlocked yes)
			(layer "F.Fab")
			(effects
				(font
					(size 0.7874 0.5842)
					(thickness 0.1524)
				)
			)
		)
		(fp_text user "J"
			(at -2.253742 10.80008 90)
			(unlocked yes)
			(layer "F.Fab")
			(effects
				(font
					(size 0.7874 0.5842)
					(thickness 0.1524)
				)
			)
		)
		(fp_text user "K"
			(at -2.253742 11.999976 90)
			(unlocked yes)
			(layer "F.Fab")
			(effects
				(font
					(size 0.7874 0.5842)
					(thickness 0.1524)
				)
			)
		)
		(fp_text user "L"
			(at -2.253742 13.200126 90)
			(unlocked yes)
			(layer "F.Fab")
			(effects
				(font
					(size 0.7874 0.5842)
					(thickness 0.1524)
				)
			)
		)
		(fp_text user "M"
			(at -2.253742 14.400022 90)
			(unlocked yes)
			(layer "F.Fab")
			(effects
				(font
					(size 0.7874 0.5842)
					(thickness 0.1524)
				)
			)
		)
		(fp_text user "N"
			(at -2.253742 15.599918 90)
			(unlocked yes)
			(layer "F.Fab")
			(effects
				(font
					(size 0.7874 0.5842)
					(thickness 0.1524)
				)
			)
		)
		(fp_text user "1"
			(at 0.111252 19.8628 90)
			(unlocked yes)
			(layer "F.Fab")
			(effects
				(font
					(size 0.7874 0.5842)
					(thickness 0.1524)
				)
			)
		)
		(fp_text user "2"
			(at 2.111248 19.8628 90)
			(unlocked yes)
			(layer "F.Fab")
			(effects
				(font
					(size 0.7874 0.5842)
					(thickness 0.1524)
				)
			)
		)
		(fp_text user "3"
			(at 4.111244 19.8628 90)
			(unlocked yes)
			(layer "F.Fab")
			(effects
				(font
					(size 0.7874 0.5842)
					(thickness 0.1524)
				)
			)
		)
		(fp_text user "4"
			(at 6.11124 19.8628 90)
			(unlocked yes)
			(layer "F.Fab")
			(effects
				(font
					(size 0.7874 0.5842)
					(thickness 0.1524)
				)
			)
		)
		(fp_text user "5"
			(at 8.111236 19.8628 90)
			(unlocked yes)
			(layer "F.Fab")
			(effects
				(font
					(size 0.7874 0.5842)
					(thickness 0.1524)
				)
			)
		)
		(fp_text user "6"
			(at 10.111232 19.8628 90)
			(unlocked yes)
			(layer "F.Fab")
			(effects
				(font
					(size 0.7874 0.5842)
					(thickness 0.1524)
				)
			)
		)
		(fp_text user "7"
			(at 12.111228 19.8628 90)
			(unlocked yes)
			(layer "F.Fab")
			(effects
				(font
					(size 0.7874 0.5842)
					(thickness 0.1524)
				)
			)
		)
		(fp_text user "8"
			(at 14.111224 19.8628 90)
			(unlocked yes)
			(layer "F.Fab")
			(effects
				(font
					(size 0.7874 0.5842)
					(thickness 0.1524)
				)
			)
		)
		(fp_text user "PRESS-FIT"
			(at 17.240758 16.521684 90)
			(unlocked yes)
			(layer "F.Fab")
			(effects
				(font
					(size 1.905 1.4224)
					(thickness 0.1524)
				)
				(justify left)
			)
		)
		(pad "A1" thru_hole rect
			(at 0 0 180)
			(size 0.766318 0.766318)
			(drill 0.359918)
			(layers "*.Cu" "*.Mask")
			(remove_unused_layers no)
			(net "GPU_3V3IO_RSVD4")
			(clearance 0.0508)
			(thermal_gap 0.0508)
			(padstack
				(mode front_inner_back)
				(layer "Inner"
					(shape circle)
					(size 0.766318 0.766318)
					(clearance 0.0508)
				)
				(layer "B.Cu"
					(shape rect)
					(size 0.766318 0.766318)
					(clearance 0.0508)
				)
			)
		)
		(pad "A2" thru_hole circle
			(at 1.999996 0.199898 180)
			(size 0.906272 0.906272)
			(drill 0.499872)
			(layers "*.Cu" "*.Mask")
			(remove_unused_layers no)
			(net "GND")
			(clearance 0.0508)
			(thermal_gap 0.0508)
		)
		(pad "A3" thru_hole circle
			(at 3.999992 0 180)
			(size 0.766318 0.766318)
			(drill 0.359918)
			(layers "*.Cu" "*.Mask")
			(remove_unused_layers no)
			(net "GPU_WP_HW_CTRL_ISO_N")
			(clearance 0.0508)
			(thermal_gap 0.0508)
		)
		(pad "A4" thru_hole circle
			(at 5.999988 0.199898 180)
			(size 0.906272 0.906272)
			(drill 0.499872)
			(layers "*.Cu" "*.Mask")
			(remove_unused_layers no)
			(net "GND")
			(clearance 0.0508)
			(thermal_gap 0.0508)
		)
		(pad "A5" thru_hole circle
			(at 7.999984 0 180)
			(size 0.766318 0.766318)
			(drill 0.359918)
			(layers "*.Cu" "*.Mask")
			(remove_unused_layers no)
			(net "GPU_3V3IO_RSVD3")
			(clearance 0.0508)
			(thermal_gap 0.0508)
		)
		(pad "A6" thru_hole circle
			(at 9.99998 0.199898 180)
			(size 0.906272 0.906272)
			(drill 0.499872)
			(layers "*.Cu" "*.Mask")
			(remove_unused_layers no)
			(net "GND")
			(clearance 0.0508)
			(thermal_gap 0.0508)
		)
		(pad "A7" thru_hole circle
			(at 11.999976 0 180)
			(size 0.766318 0.766318)
			(drill 0.359918)
			(layers "*.Cu" "*.Mask")
			(remove_unused_layers no)
			(net "GPU_3V3IO_RSVD1")
			(clearance 0.0508)
			(thermal_gap 0.0508)
		)
		(pad "A8" thru_hole circle
			(at 13.999972 0.199898 180)
			(size 0.906272 0.906272)
			(drill 0.499872)
			(layers "*.Cu" "*.Mask")
			(remove_unused_layers no)
			(net "GND")
			(clearance 0.0508)
			(thermal_gap 0.0508)
		)
		(pad "B1" thru_hole circle
			(at 0 1.199896 180)
			(size 0.906272 0.906272)
			(drill 0.499872)
			(layers "*.Cu" "*.Mask")
			(remove_unused_layers no)
			(net "GND")
			(clearance 0.0508)
			(thermal_gap 0.0508)
		)
		(pad "B3" thru_hole circle
			(at 3.999992 1.199896 180)
			(size 0.906272 0.906272)
			(drill 0.499872)
			(layers "*.Cu" "*.Mask")
			(remove_unused_layers no)
			(net "GND")
			(clearance 0.0508)
			(thermal_gap 0.0508)
		)
		(pad "B5" thru_hole circle
			(at 7.999984 1.199896 180)
			(size 0.906272 0.906272)
			(drill 0.499872)
			(layers "*.Cu" "*.Mask")
			(remove_unused_layers no)
			(net "GND")
			(clearance 0.0508)
			(thermal_gap 0.0508)
		)
		(pad "B7" thru_hole circle
			(at 11.999976 1.199896 180)
			(size 0.906272 0.906272)
			(drill 0.499872)
			(layers "*.Cu" "*.Mask")
			(remove_unused_layers no)
			(net "GND")
			(clearance 0.0508)
			(thermal_gap 0.0508)
		)
		(pad "D2" thru_hole circle
			(at 1.999996 3.800094 180)
			(size 0.906272 0.906272)
			(drill 0.499872)
			(layers "*.Cu" "*.Mask")
			(remove_unused_layers no)
			(net "GND")
			(clearance 0.0508)
			(thermal_gap 0.0508)
		)
		(pad "D4" thru_hole circle
			(at 5.999988 3.800094 180)
			(size 0.906272 0.906272)
			(drill 0.499872)
			(layers "*.Cu" "*.Mask")
			(remove_unused_layers no)
			(net "GND")
			(clearance 0.0508)
			(thermal_gap 0.0508)
		)
		(pad "D6" thru_hole circle
			(at 9.99998 3.800094 180)
			(size 0.906272 0.906272)
			(drill 0.499872)
			(layers "*.Cu" "*.Mask")
			(remove_unused_layers no)
			(net "GND")
			(clearance 0.0508)
			(thermal_gap 0.0508)
		)
		(pad "D8" thru_hole circle
			(at 13.999972 3.800094 180)
			(size 0.906272 0.906272)
			(drill 0.499872)
			(layers "*.Cu" "*.Mask")
			(remove_unused_layers no)
			(net "GND")
			(clearance 0.0508)
			(thermal_gap 0.0508)
		)
		(pad "E1" thru_hole circle
			(at 0 4.800092 180)
			(size 0.906272 0.906272)
			(drill 0.499872)
			(layers "*.Cu" "*.Mask")
			(remove_unused_layers no)
			(net "GND")
			(clearance 0.0508)
			(thermal_gap 0.0508)
		)
		(pad "E3" thru_hole circle
			(at 3.999992 4.800092 180)
			(size 0.906272 0.906272)
			(drill 0.499872)
			(layers "*.Cu" "*.Mask")
			(remove_unused_layers no)
			(net "GND")
			(clearance 0.0508)
			(thermal_gap 0.0508)
		)
		(pad "E5" thru_hole circle
			(at 7.999984 4.800092 180)
			(size 0.906272 0.906272)
			(drill 0.499872)
			(layers "*.Cu" "*.Mask")
			(remove_unused_layers no)
			(net "GND")
			(clearance 0.0508)
			(thermal_gap 0.0508)
		)
		(pad "E7" thru_hole circle
			(at 11.999976 4.800092 180)
			(size 0.906272 0.906272)
			(drill 0.499872)
			(layers "*.Cu" "*.Mask")
			(remove_unused_layers no)
			(net "GND")
			(clearance 0.0508)
			(thermal_gap 0.0508)
		)
		(pad "G2" thru_hole circle
			(at 1.999996 7.400036 180)
			(size 0.906272 0.906272)
			(drill 0.499872)
			(layers "*.Cu" "*.Mask")
			(remove_unused_layers no)
			(net "GND")
			(clearance 0.0508)
			(thermal_gap 0.0508)
		)
		(pad "G4" thru_hole circle
			(at 5.999988 7.400036 180)
			(size 0.906272 0.906272)
			(drill 0.499872)
			(layers "*.Cu" "*.Mask")
			(remove_unused_layers no)
			(net "GND")
			(clearance 0.0508)
			(thermal_gap 0.0508)
		)
		(pad "G6" thru_hole circle
			(at 9.99998 7.400036 180)
			(size 0.906272 0.906272)
			(drill 0.499872)
			(layers "*.Cu" "*.Mask")
			(remove_unused_layers no)
			(net "GND")
			(clearance 0.0508)
			(thermal_gap 0.0508)
		)
		(pad "G8" thru_hole circle
			(at 13.999972 7.400036 180)
			(size 0.906272 0.906272)
			(drill 0.499872)
			(layers "*.Cu" "*.Mask")
			(remove_unused_layers no)
			(net "GND")
			(clearance 0.0508)
			(thermal_gap 0.0508)
		)
		(pad "H1" thru_hole circle
			(at 0 8.400034 180)
			(size 0.906272 0.906272)
			(drill 0.499872)
			(layers "*.Cu" "*.Mask")
			(remove_unused_layers no)
			(net "GND")
			(clearance 0.0508)
			(thermal_gap 0.0508)
		)
		(pad "H3" thru_hole circle
			(at 3.999992 8.400034 180)
			(size 0.906272 0.906272)
			(drill 0.499872)
			(layers "*.Cu" "*.Mask")
			(remove_unused_layers no)
			(net "GND")
			(clearance 0.0508)
			(thermal_gap 0.0508)
		)
		(pad "H5" thru_hole circle
			(at 7.999984 8.400034 180)
			(size 0.906272 0.906272)
			(drill 0.499872)
			(layers "*.Cu" "*.Mask")
			(remove_unused_layers no)
			(net "GND")
			(clearance 0.0508)
			(thermal_gap 0.0508)
		)
		(pad "H7" thru_hole circle
			(at 11.999976 8.400034 180)
			(size 0.906272 0.906272)
			(drill 0.499872)
			(layers "*.Cu" "*.Mask")
			(remove_unused_layers no)
			(net "GND")
			(clearance 0.0508)
			(thermal_gap 0.0508)
		)
		(pad "J2" thru_hole circle
			(at 1.999996 10.999978 180)
			(size 0.906272 0.906272)
			(drill 0.499872)
			(layers "*.Cu" "*.Mask")
			(remove_unused_layers no)
			(net "GND")
			(clearance 0.0508)
			(thermal_gap 0.0508)
		)
		(pad "J4" thru_hole circle
			(at 5.999988 10.999978 180)
			(size 0.906272 0.906272)
			(drill 0.499872)
			(layers "*.Cu" "*.Mask")
			(remove_unused_layers no)
			(net "GND")
			(clearance 0.0508)
			(thermal_gap 0.0508)
		)
		(pad "J6" thru_hole circle
			(at 9.99998 10.999978 180)
			(size 0.906272 0.906272)
			(drill 0.499872)
			(layers "*.Cu" "*.Mask")
			(remove_unused_layers no)
			(net "GND")
			(clearance 0.0508)
			(thermal_gap 0.0508)
		)
		(pad "J8" thru_hole circle
			(at 13.999972 10.999978 180)
			(size 0.906272 0.906272)
			(drill 0.499872)
			(layers "*.Cu" "*.Mask")
			(remove_unused_layers no)
			(net "GND")
			(clearance 0.0508)
			(thermal_gap 0.0508)
		)
		(pad "K1" thru_hole circle
			(at 0 11.999976 180)
			(size 0.906272 0.906272)
			(drill 0.499872)
			(layers "*.Cu" "*.Mask")
			(remove_unused_layers no)
			(net "GND")
			(clearance 0.0508)
			(thermal_gap 0.0508)
		)
		(pad "K3" thru_hole circle
			(at 3.999992 11.999976 180)
			(size 0.906272 0.906272)
			(drill 0.499872)
			(layers "*.Cu" "*.Mask")
			(remove_unused_layers no)
			(net "GND")
			(clearance 0.0508)
			(thermal_gap 0.0508)
		)
		(pad "K5" thru_hole circle
			(at 7.999984 11.999976 180)
			(size 0.906272 0.906272)
			(drill 0.499872)
			(layers "*.Cu" "*.Mask")
			(remove_unused_layers no)
			(net "GND")
			(clearance 0.0508)
			(thermal_gap 0.0508)
		)
		(pad "K7" thru_hole circle
			(at 11.999976 11.999976 180)
			(size 0.906272 0.906272)
			(drill 0.499872)
			(layers "*.Cu" "*.Mask")
			(remove_unused_layers no)
			(net "GND")
			(clearance 0.0508)
			(thermal_gap 0.0508)
		)
		(pad "M2" thru_hole circle
			(at 1.999996 14.59992 180)
			(size 0.906272 0.906272)
			(drill 0.499872)
			(layers "*.Cu" "*.Mask")
			(remove_unused_layers no)
			(net "GND")
			(clearance 0.0508)
			(thermal_gap 0.0508)
		)
		(pad "M4" thru_hole circle
			(at 5.999988 14.59992 180)
			(size 0.906272 0.906272)
			(drill 0.499872)
			(layers "*.Cu" "*.Mask")
			(remove_unused_layers no)
			(net "GND")
			(clearance 0.0508)
			(thermal_gap 0.0508)
		)
		(pad "M6" thru_hole circle
			(at 9.99998 14.59992 180)
			(size 0.906272 0.906272)
			(drill 0.499872)
			(layers "*.Cu" "*.Mask")
			(remove_unused_layers no)
			(net "GND")
			(clearance 0.0508)
			(thermal_gap 0.0508)
		)
		(pad "M8" thru_hole circle
			(at 13.999972 14.59992 180)
			(size 0.906272 0.906272)
			(drill 0.499872)
			(layers "*.Cu" "*.Mask")
			(remove_unused_layers no)
			(net "GND")
			(clearance 0.0508)
			(thermal_gap 0.0508)
		)
		(pad "N1" thru_hole circle
			(at 0 15.599918 180)
			(size 0.906272 0.906272)
			(drill 0.499872)
			(layers "*.Cu" "*.Mask")
			(remove_unused_layers no)
			(net "GND")
			(clearance 0.0508)
			(thermal_gap 0.0508)
		)
		(pad "N2" thru_hole circle
			(at 1.999996 15.80007 180)
			(size 0.766318 0.766318)
			(drill 0.359918)
			(layers "*.Cu" "*.Mask")
			(remove_unused_layers no)
			(net "FM_SWB_PWR_EN_R_BUF")
			(clearance 0.0508)
			(thermal_gap 0.0508)
		)
		(pad "N3" thru_hole circle
			(at 3.999992 15.599918 180)
			(size 0.906272 0.906272)
			(drill 0.499872)
			(layers "*.Cu" "*.Mask")
			(remove_unused_layers no)
			(net "GND")
			(clearance 0.0508)
			(thermal_gap 0.0508)
		)
		(pad "N4" thru_hole circle
			(at 5.999988 15.80007 180)
			(size 0.766318 0.766318)
			(drill 0.359918)
			(layers "*.Cu" "*.Mask")
			(remove_unused_layers no)
			(net "FM_SWB_BIC_READY_N")
			(clearance 0.0508)
			(thermal_gap 0.0508)
		)
		(pad "N5" thru_hole circle
			(at 7.999984 15.599918 180)
			(size 0.906272 0.906272)
			(drill 0.499872)
			(layers "*.Cu" "*.Mask")
			(remove_unused_layers no)
			(net "GND")
			(clearance 0.0508)
			(thermal_gap 0.0508)
		)
		(pad "N6" thru_hole circle
			(at 9.99998 15.80007 180)
			(size 0.766318 0.766318)
			(drill 0.359918)
			(layers "*.Cu" "*.Mask")
			(remove_unused_layers no)
			(net "RST_SWB_BIC_BUF_N")
			(clearance 0.0508)
			(thermal_gap 0.0508)
		)
		(pad "N7" thru_hole circle
			(at 11.999976 15.599918 180)
			(size 0.906272 0.906272)
			(drill 0.499872)
			(layers "*.Cu" "*.Mask")
			(remove_unused_layers no)
			(net "GND")
			(clearance 0.0508)
			(thermal_gap 0.0508)
		)
		(pad "N8" thru_hole circle
			(at 13.999972 15.80007 180)
			(size 0.766318 0.766318)
			(drill 0.359918)
			(layers "*.Cu" "*.Mask")
			(remove_unused_layers no)
			(net "RST_BMC_FROM_SWB_N")
			(clearance 0.0508)
			(thermal_gap 0.0508)
		)
		(zone
			(layer "B.Cu")
			(hatch none 0.5)
			(connect_pads
				(clearance 0)
			)
			(min_thickness 0.25)
			(keepout
				(tracks allowed)
				(vias not_allowed)
				(pads allowed)
				(copperpour not_allowed)
				(footprints allowed)
			)
			(placement
				(enabled no)
				(sheetname "")
			)
			(fill
				(thermal_gap 0.5)
				(thermal_bridge_width 0.5)
				(island_removal_mode 0)
			)
			(polygon
				(pts
					(xy 398.242028 -424.246548) (xy 413.266128 -424.246548) (xy 413.266128 -440.934348) (xy 398.242028 -440.934348)
				)
			)
		)
	)
	(footprint ""
		(layer "F.Cu")
		(at 229.87 -285.64713 180)
		(property "Reference" "PC6903"
			(at 0 0 180)
			(layer "F.SilkS")
			(hide yes)
			(effects
				(font
					(size 1.27 1.27)
				)
			)
		)
		(property "Value" ""
			(at 0 0 180)
			(layer "F.Fab")
			(effects
				(font
					(size 1.27 1.27)
				)
			)
		)
		(duplicate_pad_numbers_are_jumpers no)
		(fp_line
			(start 1.524 0.762)
			(end -1.524 0.762)
			(stroke
				(width 0.1524)
				(type default)
			)
			(layer "F.SilkS")
		)
		(fp_line
			(start 1.524 -0.762)
			(end 1.524 0.762)
			(stroke
				(width 0.1524)
				(type default)
			)
			(layer "F.SilkS")
		)
		(fp_line
			(start -1.524 0.762)
			(end -1.524 -0.762)
			(stroke
				(width 0.1524)
				(type default)
			)
			(layer "F.SilkS")
		)
		(fp_line
			(start -1.524 -0.762)
			(end 1.524 -0.762)
			(stroke
				(width 0.1524)
				(type default)
			)
			(layer "F.SilkS")
		)
		(fp_line
			(start 1.1049 0.724916)
			(end 1.1049 -0.724916)
			(stroke
				(width 0.1)
				(type default)
			)
			(layer "F.Fab")
		)
		(fp_line
			(start 1.1049 -0.724916)
			(end -1.1049 -0.724916)
			(stroke
				(width 0.1)
				(type default)
			)
			(layer "F.Fab")
		)
		(fp_line
			(start -1.1049 0.724916)
			(end 1.1049 0.724916)
			(stroke
				(width 0.1)
				(type default)
			)
			(layer "F.Fab")
		)
		(fp_line
			(start -1.1049 -0.724916)
			(end -1.1049 0.724916)
			(stroke
				(width 0.1)
				(type default)
			)
			(layer "F.Fab")
		)
		(pad "1" smd rect
			(at -0.889 0)
			(size 1.016 1.27)
			(layers "F.Cu" "F.Mask" "F.Paste")
			(net "SW_P12V_AUX_P1V8_RETIMER_CPU1_FLT")
		)
		(pad "2" smd rect
			(at 0.889 0)
			(size 1.016 1.27)
			(layers "F.Cu" "F.Mask" "F.Paste")
			(net "GND")
		)
	)
	(footprint ""
		(layer "F.Cu")
		(at 312.958226 -416.899344 -90)
		(property "Reference" "C6508"
			(at 0 0 270)
			(layer "F.SilkS")
			(hide yes)
			(effects
				(font
					(size 1.27 1.27)
				)
			)
		)
		(property "Value" ""
			(at 0 0 270)
			(layer "F.Fab")
			(effects
				(font
					(size 1.27 1.27)
				)
			)
		)
		(duplicate_pad_numbers_are_jumpers no)
		(fp_line
			(start -0.299974 0.150114)
			(end -0.299974 -0.150114)
			(stroke
				(width 0.1)
				(type default)
			)
			(layer "F.Fab")
		)
		(fp_line
			(start 0.299974 0.150114)
			(end -0.299974 0.150114)
			(stroke
				(width 0.1)
				(type default)
			)
			(layer "F.Fab")
		)
		(fp_line
			(start -0.299974 -0.150114)
			(end 0.299974 -0.150114)
			(stroke
				(width 0.1)
				(type default)
			)
			(layer "F.Fab")
		)
		(fp_line
			(start 0.299974 -0.150114)
			(end 0.299974 0.150114)
			(stroke
				(width 0.1)
				(type default)
			)
			(layer "F.Fab")
		)
		(pad "1" smd rect
			(at -0.2667 0 270)
			(size 0.3048 0.381)
			(layers "F.Cu" "F.Mask" "F.Paste")
			(net "P5E_CPU0_P0_TX_BUF_C_DN<3>")
		)
		(pad "2" smd rect
			(at 0.2667 0 270)
			(size 0.3048 0.381)
			(layers "F.Cu" "F.Mask" "F.Paste")
			(net "P5E_CPU0_P0_TX_BUF_DN<3>")
		)
	)
	(footprint ""
		(layer "F.Cu")
		(at 329.686412 -40.00373)
		(property "Reference" "L15"
			(at 0 0 0)
			(layer "F.SilkS")
			(hide yes)
			(effects
				(font
					(size 1.27 1.27)
				)
			)
		)
		(property "Value" ""
			(at 0 0 0)
			(layer "F.Fab")
			(effects
				(font
					(size 1.27 1.27)
				)
			)
		)
		(duplicate_pad_numbers_are_jumpers no)
		(fp_line
			(start -1.27 -0.5842)
			(end 1.27 -0.5842)
			(stroke
				(width 0.1524)
				(type default)
			)
			(layer "F.SilkS")
		)
		(fp_line
			(start -1.27 -0.5588)
			(end -1.27 -0.5842)
			(stroke
				(width 0.1524)
				(type default)
			)
			(layer "F.SilkS")
		)
		(fp_line
			(start -1.27 0.5842)
			(end -1.27 -0.5842)
			(stroke
				(width 0.1524)
				(type default)
			)
			(layer "F.SilkS")
		)
		(fp_line
			(start 1.27 0.5842)
			(end -1.27 0.5842)
			(stroke
				(width 0.1524)
				(type default)
			)
			(layer "F.SilkS")
		)
		(fp_line
			(start 1.27 0.5842)
			(end 1.27 -0.5842)
			(stroke
				(width 0.1524)
				(type default)
			)
			(layer "F.SilkS")
		)
		(fp_line
			(start -1.194308 -0.406654)
			(end -0.9144 -0.406654)
			(stroke
				(width 0.1)
				(type default)
			)
			(layer "F.Fab")
		)
		(fp_line
			(start -1.194308 0.406654)
			(end -1.194308 -0.406654)
			(stroke
				(width 0.1)
				(type default)
			)
			(layer "F.Fab")
		)
		(fp_line
			(start -0.9144 -0.508)
			(end 0.9144 -0.508)
			(stroke
				(width 0.1)
				(type default)
			)
			(layer "F.Fab")
		)
		(fp_line
			(start -0.9144 -0.406654)
			(end -0.9144 -0.508)
			(stroke
				(width 0.1)
				(type default)
			)
			(layer "F.Fab")
		)
		(fp_line
			(start -0.9144 0.406654)
			(end -1.194308 0.406654)
			(stroke
				(width 0.1)
				(type default)
			)
			(layer "F.Fab")
		)
		(fp_line
			(start -0.9144 0.508)
			(end -0.9144 0.406654)
			(stroke
				(width 0.1)
				(type default)
			)
			(layer "F.Fab")
		)
		(fp_line
			(start 0.9144 -0.508)
			(end 0.9144 -0.406654)
			(stroke
				(width 0.1)
				(type default)
			)
			(layer "F.Fab")
		)
		(fp_line
			(start 0.9144 -0.406654)
			(end 1.1938 -0.406654)
			(stroke
				(width 0.1)
				(type default)
			)
			(layer "F.Fab")
		)
		(fp_line
			(start 0.9144 0.4064)
			(end 0.9144 0.508)
			(stroke
				(width 0.1)
				(type default)
			)
			(layer "F.Fab")
		)
		(fp_line
			(start 0.9144 0.508)
			(end -0.9144 0.508)
			(stroke
				(width 0.1)
				(type default)
			)
			(layer "F.Fab")
		)
		(fp_line
			(start 1.1938 -0.406654)
			(end 1.1938 0.4064)
			(stroke
				(width 0.1)
				(type default)
			)
			(layer "F.Fab")
		)
		(fp_line
			(start 1.1938 0.4064)
			(end 0.9144 0.4064)
			(stroke
				(width 0.1)
				(type default)
			)
			(layer "F.Fab")
		)
		(pad "1" smd rect
			(at -0.7366 0 270)
			(size 0.7112 0.8128)
			(layers "F.Cu" "F.Mask" "F.Paste")
			(net "P3V3_MAX11617_VDD")
		)
		(pad "2" smd rect
			(at 0.7366 0 270)
			(size 0.7112 0.8128)
			(layers "F.Cu" "F.Mask" "F.Paste")
			(net "P3V3_AUX")
		)
	)
	(footprint ""
		(layer "F.Cu")
		(at 283.112718 -388.71652 90)
		(property "Reference" "R6231"
			(at 0 0 90)
			(layer "F.SilkS")
			(hide yes)
			(effects
				(font
					(size 1.27 1.27)
				)
			)
		)
		(property "Value" ""
			(at 0 0 90)
			(layer "F.Fab")
			(effects
				(font
					(size 1.27 1.27)
				)
			)
		)
		(duplicate_pad_numbers_are_jumpers no)
		(fp_line
			(start 0.7874 -0.4064)
			(end 0.7874 0.4064)
			(stroke
				(width 0.1524)
				(type default)
			)
			(layer "F.SilkS")
		)
		(fp_line
			(start -0.7874 -0.4064)
			(end 0.7874 -0.4064)
			(stroke
				(width 0.1524)
				(type default)
			)
			(layer "F.SilkS")
		)
		(fp_line
			(start 0.7874 0.4064)
			(end -0.7874 0.4064)
			(stroke
				(width 0.1524)
				(type default)
			)
			(layer "F.SilkS")
		)
		(fp_line
			(start -0.7874 0.4064)
			(end -0.7874 -0.4064)
			(stroke
				(width 0.1524)
				(type default)
			)
			(layer "F.SilkS")
		)
		(fp_line
			(start -0.12065 -0.305054)
			(end -0.12065 -0.2794)
			(stroke
				(width 0.1)
				(type default)
			)
			(layer "F.Fab")
		)
		(fp_line
			(start -0.67945 -0.305054)
			(end -0.12065 -0.305054)
			(stroke
				(width 0.1)
				(type default)
			)
			(layer "F.Fab")
		)
		(fp_line
			(start 0.67945 -0.3048)
			(end 0.67945 0.3048)
			(stroke
				(width 0.1)
				(type default)
			)
			(layer "F.Fab")
		)
		(fp_line
			(start 0.12065 -0.3048)
			(end 0.67945 -0.3048)
			(stroke
				(width 0.1)
				(type default)
			)
			(layer "F.Fab")
		)
		(fp_line
			(start 0.12065 -0.2794)
			(end 0.12065 -0.3048)
			(stroke
				(width 0.1)
				(type default)
			)
			(layer "F.Fab")
		)
		(fp_line
			(start -0.12065 -0.2794)
			(end 0.12065 -0.2794)
			(stroke
				(width 0.1)
				(type default)
			)
			(layer "F.Fab")
		)
		(fp_line
			(start 0.120396 0.2794)
			(end -0.12065 0.2794)
			(stroke
				(width 0.1)
				(type default)
			)
			(layer "F.Fab")
		)
		(fp_line
			(start -0.12065 0.2794)
			(end -0.12065 0.3048)
			(stroke
				(width 0.1)
				(type default)
			)
			(layer "F.Fab")
		)
		(fp_line
			(start 0.67945 0.3048)
			(end 0.120396 0.3048)
			(stroke
				(width 0.1)
				(type default)
			)
			(layer "F.Fab")
		)
		(fp_line
			(start 0.120396 0.3048)
			(end 0.120396 0.2794)
			(stroke
				(width 0.1)
				(type default)
			)
			(layer "F.Fab")
		)
		(fp_line
			(start -0.12065 0.3048)
			(end -0.67945 0.3048)
			(stroke
				(width 0.1)
				(type default)
			)
			(layer "F.Fab")
		)
		(fp_line
			(start -0.67945 0.3048)
			(end -0.67945 -0.305054)
			(stroke
				(width 0.1)
				(type default)
			)
			(layer "F.Fab")
		)
		(pad "1" smd circle
			(at -0.40005 0 90)
			(size 0 0)
			(layers "F.Cu" "F.Mask" "F.Paste")
			(net "P3V3_AUX")
		)
		(pad "2" smd circle
			(at 0.40005 0 90)
			(size 0 0)
			(layers "F.Cu" "F.Mask" "F.Paste")
			(net "SMB_P12V_HSC_SCL")
		)
	)
	(footprint ""
		(layer "F.Cu")
		(at 227.7745 -402.191982 90)
		(property "Reference" "PC2223"
			(at 0 0 90)
			(layer "F.SilkS")
			(hide yes)
			(effects
				(font
					(size 1.27 1.27)
				)
			)
		)
		(property "Value" ""
			(at 0 0 90)
			(layer "F.Fab")
			(effects
				(font
					(size 1.27 1.27)
				)
			)
		)
		(duplicate_pad_numbers_are_jumpers no)
		(fp_line
			(start 0.7874 -0.4064)
			(end 0.7874 0.4064)
			(stroke
				(width 0.1524)
				(type default)
			)
			(layer "F.SilkS")
		)
		(fp_line
			(start -0.7874 -0.4064)
			(end 0.7874 -0.4064)
			(stroke
				(width 0.1524)
				(type default)
			)
			(layer "F.SilkS")
		)
		(fp_line
			(start 0.7874 0.4064)
			(end -0.7874 0.4064)
			(stroke
				(width 0.1524)
				(type default)
			)
			(layer "F.SilkS")
		)
		(fp_line
			(start -0.7874 0.4064)
			(end -0.7874 -0.4064)
			(stroke
				(width 0.1524)
				(type default)
			)
			(layer "F.SilkS")
		)
		(fp_line
			(start -0.12065 -0.305054)
			(end -0.12065 -0.2794)
			(stroke
				(width 0.1)
				(type default)
			)
			(layer "F.Fab")
		)
		(fp_line
			(start -0.67945 -0.305054)
			(end -0.12065 -0.305054)
			(stroke
				(width 0.1)
				(type default)
			)
			(layer "F.Fab")
		)
		(fp_line
			(start 0.67945 -0.3048)
			(end 0.67945 0.3048)
			(stroke
				(width 0.1)
				(type default)
			)
			(layer "F.Fab")
		)
		(fp_line
			(start 0.12065 -0.3048)
			(end 0.67945 -0.3048)
			(stroke
				(width 0.1)
				(type default)
			)
			(layer "F.Fab")
		)
		(fp_line
			(start 0.12065 -0.2794)
			(end 0.12065 -0.3048)
			(stroke
				(width 0.1)
				(type default)
			)
			(layer "F.Fab")
		)
		(fp_line
			(start -0.12065 -0.2794)
			(end 0.12065 -0.2794)
			(stroke
				(width 0.1)
				(type default)
			)
			(layer "F.Fab")
		)
		(fp_line
			(start 0.120396 0.2794)
			(end -0.12065 0.2794)
			(stroke
				(width 0.1)
				(type default)
			)
			(layer "F.Fab")
		)
		(fp_line
			(start -0.12065 0.2794)
			(end -0.12065 0.3048)
			(stroke
				(width 0.1)
				(type default)
			)
			(layer "F.Fab")
		)
		(fp_line
			(start 0.67945 0.3048)
			(end 0.120396 0.3048)
			(stroke
				(width 0.1)
				(type default)
			)
			(layer "F.Fab")
		)
		(fp_line
			(start 0.120396 0.3048)
			(end 0.120396 0.2794)
			(stroke
				(width 0.1)
				(type default)
			)
			(layer "F.Fab")
		)
		(fp_line
			(start -0.12065 0.3048)
			(end -0.67945 0.3048)
			(stroke
				(width 0.1)
				(type default)
			)
			(layer "F.Fab")
		)
		(fp_line
			(start -0.67945 0.3048)
			(end -0.67945 -0.305054)
			(stroke
				(width 0.1)
				(type default)
			)
			(layer "F.Fab")
		)
		(pad "1" smd circle
			(at -0.40005 0 90)
			(size 0 0)
			(layers "F.Cu" "F.Mask" "F.Paste")
			(net "HSC_VDD_R_4")
		)
		(pad "2" smd circle
			(at 0.40005 0 90)
			(size 0 0)
			(layers "F.Cu" "F.Mask" "F.Paste")
			(net "AGND_HSC")
		)
	)
	(footprint ""
		(layer "F.Cu")
		(at 142.748 -114.554)
		(property "Reference" "C8020"
			(at 0 0 0)
			(layer "F.SilkS")
			(hide yes)
			(effects
				(font
					(size 1.27 1.27)
				)
			)
		)
		(property "Value" ""
			(at 0 0 0)
			(layer "F.Fab")
			(effects
				(font
					(size 1.27 1.27)
				)
			)
		)
		(duplicate_pad_numbers_are_jumpers no)
		(fp_line
			(start -0.7874 -0.4064)
			(end 0.7874 -0.4064)
			(stroke
				(width 0.1524)
				(type default)
			)
			(layer "F.SilkS")
		)
		(fp_line
			(start -0.7874 0.4064)
			(end -0.7874 -0.4064)
			(stroke
				(width 0.1524)
				(type default)
			)
			(layer "F.SilkS")
		)
		(fp_line
			(start 0.7874 -0.4064)
			(end 0.7874 0.4064)
			(stroke
				(width 0.1524)
				(type default)
			)
			(layer "F.SilkS")
		)
		(fp_line
			(start 0.7874 0.4064)
			(end -0.7874 0.4064)
			(stroke
				(width 0.1524)
				(type default)
			)
			(layer "F.SilkS")
		)
		(fp_line
			(start -0.67945 -0.305054)
			(end -0.12065 -0.305054)
			(stroke
				(width 0.1)
				(type default)
			)
			(layer "F.Fab")
		)
		(fp_line
			(start -0.67945 0.3048)
			(end -0.67945 -0.305054)
			(stroke
				(width 0.1)
				(type default)
			)
			(layer "F.Fab")
		)
		(fp_line
			(start -0.12065 -0.305054)
			(end -0.12065 -0.2794)
			(stroke
				(width 0.1)
				(type default)
			)
			(layer "F.Fab")
		)
		(fp_line
			(start -0.12065 -0.2794)
			(end 0.12065 -0.2794)
			(stroke
				(width 0.1)
				(type default)
			)
			(layer "F.Fab")
		)
		(fp_line
			(start -0.12065 0.2794)
			(end -0.12065 0.3048)
			(stroke
				(width 0.1)
				(type default)
			)
			(layer "F.Fab")
		)
		(fp_line
			(start -0.12065 0.3048)
			(end -0.67945 0.3048)
			(stroke
				(width 0.1)
				(type default)
			)
			(layer "F.Fab")
		)
		(fp_line
			(start 0.120396 0.2794)
			(end -0.12065 0.2794)
			(stroke
				(width 0.1)
				(type default)
			)
			(layer "F.Fab")
		)
		(fp_line
			(start 0.120396 0.3048)
			(end 0.120396 0.2794)
			(stroke
				(width 0.1)
				(type default)
			)
			(layer "F.Fab")
		)
		(fp_line
			(start 0.12065 -0.3048)
			(end 0.67945 -0.3048)
			(stroke
				(width 0.1)
				(type default)
			)
			(layer "F.Fab")
		)
		(fp_line
			(start 0.12065 -0.2794)
			(end 0.12065 -0.3048)
			(stroke
				(width 0.1)
				(type default)
			)
			(layer "F.Fab")
		)
		(fp_line
			(start 0.67945 -0.3048)
			(end 0.67945 0.3048)
			(stroke
				(width 0.1)
				(type default)
			)
			(layer "F.Fab")
		)
		(fp_line
			(start 0.67945 0.3048)
			(end 0.120396 0.3048)
			(stroke
				(width 0.1)
				(type default)
			)
			(layer "F.Fab")
		)
		(pad "1" smd circle
			(at -0.40005 0)
			(size 0 0)
			(layers "F.Cu" "F.Mask" "F.Paste")
			(net "UV_P2V5_COMP")
		)
		(pad "2" smd circle
			(at 0.40005 0)
			(size 0 0)
			(layers "F.Cu" "F.Mask" "F.Paste")
			(net "GND")
		)
	)
	(footprint ""
		(layer "F.Cu")
		(at 151.13 -114.173 180)
		(property "Reference" "R1338"
			(at 0 0 180)
			(layer "F.SilkS")
			(hide yes)
			(effects
				(font
					(size 1.27 1.27)
				)
			)
		)
		(property "Value" ""
			(at 0 0 180)
			(layer "F.Fab")
			(effects
				(font
					(size 1.27 1.27)
				)
			)
		)
		(duplicate_pad_numbers_are_jumpers no)
		(fp_line
			(start 0.7874 0.4064)
			(end -0.7874 0.4064)
			(stroke
				(width 0.1524)
				(type default)
			)
			(layer "F.SilkS")
		)
		(fp_line
			(start 0.7874 -0.4064)
			(end 0.7874 0.4064)
			(stroke
				(width 0.1524)
				(type default)
			)
			(layer "F.SilkS")
		)
		(fp_line
			(start -0.7874 0.4064)
			(end -0.7874 -0.4064)
			(stroke
				(width 0.1524)
				(type default)
			)
			(layer "F.SilkS")
		)
		(fp_line
			(start -0.7874 -0.4064)
			(end 0.7874 -0.4064)
			(stroke
				(width 0.1524)
				(type default)
			)
			(layer "F.SilkS")
		)
		(fp_line
			(start 0.67945 0.3048)
			(end 0.120396 0.3048)
			(stroke
				(width 0.1)
				(type default)
			)
			(layer "F.Fab")
		)
		(fp_line
			(start 0.67945 -0.3048)
			(end 0.67945 0.3048)
			(stroke
				(width 0.1)
				(type default)
			)
			(layer "F.Fab")
		)
		(fp_line
			(start 0.12065 -0.2794)
			(end 0.12065 -0.3048)
			(stroke
				(width 0.1)
				(type default)
			)
			(layer "F.Fab")
		)
		(fp_line
			(start 0.12065 -0.3048)
			(end 0.67945 -0.3048)
			(stroke
				(width 0.1)
				(type default)
			)
			(layer "F.Fab")
		)
		(fp_line
			(start 0.120396 0.3048)
			(end 0.120396 0.2794)
			(stroke
				(width 0.1)
				(type default)
			)
			(layer "F.Fab")
		)
		(fp_line
			(start 0.120396 0.2794)
			(end -0.12065 0.2794)
			(stroke
				(width 0.1)
				(type default)
			)
			(layer "F.Fab")
		)
		(fp_line
			(start -0.12065 0.3048)
			(end -0.67945 0.3048)
			(stroke
				(width 0.1)
				(type default)
			)
			(layer "F.Fab")
		)
		(fp_line
			(start -0.12065 0.2794)
			(end -0.12065 0.3048)
			(stroke
				(width 0.1)
				(type default)
			)
			(layer "F.Fab")
		)
		(fp_line
			(start -0.12065 -0.2794)
			(end 0.12065 -0.2794)
			(stroke
				(width 0.1)
				(type default)
			)
			(layer "F.Fab")
		)
		(fp_line
			(start -0.12065 -0.305054)
			(end -0.12065 -0.2794)
			(stroke
				(width 0.1)
				(type default)
			)
			(layer "F.Fab")
		)
		(fp_line
			(start -0.67945 0.3048)
			(end -0.67945 -0.305054)
			(stroke
				(width 0.1)
				(type default)
			)
			(layer "F.Fab")
		)
		(fp_line
			(start -0.67945 -0.305054)
			(end -0.12065 -0.305054)
			(stroke
				(width 0.1)
				(type default)
			)
			(layer "F.Fab")
		)
		(pad "1" smd circle
			(at -0.40005 0 180)
			(size 0 0)
			(layers "F.Cu" "F.Mask" "F.Paste")
			(net "P3V3_AUX")
		)
		(pad "2" smd circle
			(at 0.40005 0 180)
			(size 0 0)
			(layers "F.Cu" "F.Mask" "F.Paste")
			(net "SCM_IRQ_N")
		)
	)
	(footprint ""
		(layer "F.Cu")
		(at 69.098668 -382.951228)
		(property "Reference" "ME10"
			(at 0 0 0)
			(layer "F.SilkS")
			(hide yes)
			(effects
				(font
					(size 1.27 1.27)
				)
			)
		)
		(property "Value" ""
			(at 0 0 0)
			(layer "F.Fab")
			(effects
				(font
					(size 1.27 1.27)
				)
			)
		)
		(duplicate_pad_numbers_are_jumpers no)
	)
	(footprint ""
		(layer "F.Cu")
		(at 197.269608 -109.561376 180)
		(property "Reference" "R280"
			(at 0 0 180)
			(layer "F.SilkS")
			(hide yes)
			(effects
				(font
					(size 1.27 1.27)
				)
			)
		)
		(property "Value" ""
			(at 0 0 180)
			(layer "F.Fab")
			(effects
				(font
					(size 1.27 1.27)
				)
			)
		)
		(duplicate_pad_numbers_are_jumpers no)
		(fp_line
			(start 0.7874 0.4064)
			(end -0.7874 0.4064)
			(stroke
				(width 0.1524)
				(type default)
			)
			(layer "F.SilkS")
		)
		(fp_line
			(start 0.7874 -0.4064)
			(end 0.7874 0.4064)
			(stroke
				(width 0.1524)
				(type default)
			)
			(layer "F.SilkS")
		)
		(fp_line
			(start -0.7874 0.4064)
			(end -0.7874 -0.4064)
			(stroke
				(width 0.1524)
				(type default)
			)
			(layer "F.SilkS")
		)
		(fp_line
			(start -0.7874 -0.4064)
			(end 0.7874 -0.4064)
			(stroke
				(width 0.1524)
				(type default)
			)
			(layer "F.SilkS")
		)
		(fp_line
			(start 0.67945 0.3048)
			(end 0.120396 0.3048)
			(stroke
				(width 0.1)
				(type default)
			)
			(layer "F.Fab")
		)
		(fp_line
			(start 0.67945 -0.3048)
			(end 0.67945 0.3048)
			(stroke
				(width 0.1)
				(type default)
			)
			(layer "F.Fab")
		)
		(fp_line
			(start 0.12065 -0.2794)
			(end 0.12065 -0.3048)
			(stroke
				(width 0.1)
				(type default)
			)
			(layer "F.Fab")
		)
		(fp_line
			(start 0.12065 -0.3048)
			(end 0.67945 -0.3048)
			(stroke
				(width 0.1)
				(type default)
			)
			(layer "F.Fab")
		)
		(fp_line
			(start 0.120396 0.3048)
			(end 0.120396 0.2794)
			(stroke
				(width 0.1)
				(type default)
			)
			(layer "F.Fab")
		)
		(fp_line
			(start 0.120396 0.2794)
			(end -0.12065 0.2794)
			(stroke
				(width 0.1)
				(type default)
			)
			(layer "F.Fab")
		)
		(fp_line
			(start -0.12065 0.3048)
			(end -0.67945 0.3048)
			(stroke
				(width 0.1)
				(type default)
			)
			(layer "F.Fab")
		)
		(fp_line
			(start -0.12065 0.2794)
			(end -0.12065 0.3048)
			(stroke
				(width 0.1)
				(type default)
			)
			(layer "F.Fab")
		)
		(fp_line
			(start -0.12065 -0.2794)
			(end 0.12065 -0.2794)
			(stroke
				(width 0.1)
				(type default)
			)
			(layer "F.Fab")
		)
		(fp_line
			(start -0.12065 -0.305054)
			(end -0.12065 -0.2794)
			(stroke
				(width 0.1)
				(type default)
			)
			(layer "F.Fab")
		)
		(fp_line
			(start -0.67945 0.3048)
			(end -0.67945 -0.305054)
			(stroke
				(width 0.1)
				(type default)
			)
			(layer "F.Fab")
		)
		(fp_line
			(start -0.67945 -0.305054)
			(end -0.12065 -0.305054)
			(stroke
				(width 0.1)
				(type default)
			)
			(layer "F.Fab")
		)
		(pad "1" smd circle
			(at -0.40005 0 180)
			(size 0 0)
			(layers "F.Cu" "F.Mask" "F.Paste")
			(net "PWRGD_PVDD11_S3_P1")
		)
		(pad "2" smd circle
			(at 0.40005 0 180)
			(size 0 0)
			(layers "F.Cu" "F.Mask" "F.Paste")
			(net "FM_PWRGD_PVDD11_S3_P1")
		)
	)
	(footprint ""
		(layer "F.Cu")
		(at 186.055 -129.377948 90)
		(property "Reference" "R250"
			(at 0 0 90)
			(layer "F.SilkS")
			(hide yes)
			(effects
				(font
					(size 1.27 1.27)
				)
			)
		)
		(property "Value" ""
			(at 0 0 90)
			(layer "F.Fab")
			(effects
				(font
					(size 1.27 1.27)
				)
			)
		)
		(duplicate_pad_numbers_are_jumpers no)
		(fp_line
			(start 0.7874 -0.4064)
			(end 0.7874 0.4064)
			(stroke
				(width 0.1524)
				(type default)
			)
			(layer "F.SilkS")
		)
		(fp_line
			(start -0.7874 -0.4064)
			(end 0.7874 -0.4064)
			(stroke
				(width 0.1524)
				(type default)
			)
			(layer "F.SilkS")
		)
		(fp_line
			(start 0.7874 0.4064)
			(end -0.7874 0.4064)
			(stroke
				(width 0.1524)
				(type default)
			)
			(layer "F.SilkS")
		)
		(fp_line
			(start -0.7874 0.4064)
			(end -0.7874 -0.4064)
			(stroke
				(width 0.1524)
				(type default)
			)
			(layer "F.SilkS")
		)
		(fp_line
			(start -0.12065 -0.305054)
			(end -0.12065 -0.2794)
			(stroke
				(width 0.1)
				(type default)
			)
			(layer "F.Fab")
		)
		(fp_line
			(start -0.67945 -0.305054)
			(end -0.12065 -0.305054)
			(stroke
				(width 0.1)
				(type default)
			)
			(layer "F.Fab")
		)
		(fp_line
			(start 0.67945 -0.3048)
			(end 0.67945 0.3048)
			(stroke
				(width 0.1)
				(type default)
			)
			(layer "F.Fab")
		)
		(fp_line
			(start 0.12065 -0.3048)
			(end 0.67945 -0.3048)
			(stroke
				(width 0.1)
				(type default)
			)
			(layer "F.Fab")
		)
		(fp_line
			(start 0.12065 -0.2794)
			(end 0.12065 -0.3048)
			(stroke
				(width 0.1)
				(type default)
			)
			(layer "F.Fab")
		)
		(fp_line
			(start -0.12065 -0.2794)
			(end 0.12065 -0.2794)
			(stroke
				(width 0.1)
				(type default)
			)
			(layer "F.Fab")
		)
		(fp_line
			(start 0.120396 0.2794)
			(end -0.12065 0.2794)
			(stroke
				(width 0.1)
				(type default)
			)
			(layer "F.Fab")
		)
		(fp_line
			(start -0.12065 0.2794)
			(end -0.12065 0.3048)
			(stroke
				(width 0.1)
				(type default)
			)
			(layer "F.Fab")
		)
		(fp_line
			(start 0.67945 0.3048)
			(end 0.120396 0.3048)
			(stroke
				(width 0.1)
				(type default)
			)
			(layer "F.Fab")
		)
		(fp_line
			(start 0.120396 0.3048)
			(end 0.120396 0.2794)
			(stroke
				(width 0.1)
				(type default)
			)
			(layer "F.Fab")
		)
		(fp_line
			(start -0.12065 0.3048)
			(end -0.67945 0.3048)
			(stroke
				(width 0.1)
				(type default)
			)
			(layer "F.Fab")
		)
		(fp_line
			(start -0.67945 0.3048)
			(end -0.67945 -0.305054)
			(stroke
				(width 0.1)
				(type default)
			)
			(layer "F.Fab")
		)
		(pad "1" smd circle
			(at -0.40005 0 90)
			(size 0 0)
			(layers "F.Cu" "F.Mask" "F.Paste")
			(net "FM_CPU0_SMERR_N")
		)
		(pad "2" smd circle
			(at 0.40005 0 90)
			(size 0 0)
			(layers "F.Cu" "F.Mask" "F.Paste")
			(net "CPU0_SMERR_N")
		)
	)
	(footprint ""
		(layer "F.Cu")
		(at 439.029602 -427.09211 180)
		(property "Reference" "C101"
			(at 0 0 180)
			(layer "F.SilkS")
			(hide yes)
			(effects
				(font
					(size 1.27 1.27)
				)
			)
		)
		(property "Value" ""
			(at 0 0 180)
			(layer "F.Fab")
			(effects
				(font
					(size 1.27 1.27)
				)
			)
		)
		(duplicate_pad_numbers_are_jumpers no)
		(fp_line
			(start 0.7874 0.4064)
			(end -0.7874 0.4064)
			(stroke
				(width 0.1524)
				(type default)
			)
			(layer "F.SilkS")
		)
		(fp_line
			(start 0.7874 -0.4064)
			(end 0.7874 0.4064)
			(stroke
				(width 0.1524)
				(type default)
			)
			(layer "F.SilkS")
		)
		(fp_line
			(start -0.7874 0.4064)
			(end -0.7874 -0.4064)
			(stroke
				(width 0.1524)
				(type default)
			)
			(layer "F.SilkS")
		)
		(fp_line
			(start -0.7874 -0.4064)
			(end 0.7874 -0.4064)
			(stroke
				(width 0.1524)
				(type default)
			)
			(layer "F.SilkS")
		)
		(fp_line
			(start 0.67945 0.3048)
			(end 0.120396 0.3048)
			(stroke
				(width 0.1)
				(type default)
			)
			(layer "F.Fab")
		)
		(fp_line
			(start 0.67945 -0.3048)
			(end 0.67945 0.3048)
			(stroke
				(width 0.1)
				(type default)
			)
			(layer "F.Fab")
		)
		(fp_line
			(start 0.12065 -0.2794)
			(end 0.12065 -0.3048)
			(stroke
				(width 0.1)
				(type default)
			)
			(layer "F.Fab")
		)
		(fp_line
			(start 0.12065 -0.3048)
			(end 0.67945 -0.3048)
			(stroke
				(width 0.1)
				(type default)
			)
			(layer "F.Fab")
		)
		(fp_line
			(start 0.120396 0.3048)
			(end 0.120396 0.2794)
			(stroke
				(width 0.1)
				(type default)
			)
			(layer "F.Fab")
		)
		(fp_line
			(start 0.120396 0.2794)
			(end -0.12065 0.2794)
			(stroke
				(width 0.1)
				(type default)
			)
			(layer "F.Fab")
		)
		(fp_line
			(start -0.12065 0.3048)
			(end -0.67945 0.3048)
			(stroke
				(width 0.1)
				(type default)
			)
			(layer "F.Fab")
		)
		(fp_line
			(start -0.12065 0.2794)
			(end -0.12065 0.3048)
			(stroke
				(width 0.1)
				(type default)
			)
			(layer "F.Fab")
		)
		(fp_line
			(start -0.12065 -0.2794)
			(end 0.12065 -0.2794)
			(stroke
				(width 0.1)
				(type default)
			)
			(layer "F.Fab")
		)
		(fp_line
			(start -0.12065 -0.305054)
			(end -0.12065 -0.2794)
			(stroke
				(width 0.1)
				(type default)
			)
			(layer "F.Fab")
		)
		(fp_line
			(start -0.67945 0.3048)
			(end -0.67945 -0.305054)
			(stroke
				(width 0.1)
				(type default)
			)
			(layer "F.Fab")
		)
		(fp_line
			(start -0.67945 -0.305054)
			(end -0.12065 -0.305054)
			(stroke
				(width 0.1)
				(type default)
			)
			(layer "F.Fab")
		)
		(pad "1" smd circle
			(at -0.40005 0 180)
			(size 0 0)
			(layers "F.Cu" "F.Mask" "F.Paste")
			(net "PWRGD_P0V9_RETIMER_CPU0_R")
		)
		(pad "2" smd circle
			(at 0.40005 0 180)
			(size 0 0)
			(layers "F.Cu" "F.Mask" "F.Paste")
			(net "GND")
		)
	)
	(footprint ""
		(layer "F.Cu")
		(at 16.796258 -427.580298 -90)
		(property "Reference" "R6169"
			(at 0 0 270)
			(layer "F.SilkS")
			(hide yes)
			(effects
				(font
					(size 1.27 1.27)
				)
			)
		)
		(property "Value" ""
			(at 0 0 270)
			(layer "F.Fab")
			(effects
				(font
					(size 1.27 1.27)
				)
			)
		)
		(duplicate_pad_numbers_are_jumpers no)
		(fp_line
			(start -0.7874 0.4064)
			(end -0.7874 -0.4064)
			(stroke
				(width 0.1524)
				(type default)
			)
			(layer "F.SilkS")
		)
		(fp_line
			(start 0.7874 0.4064)
			(end -0.7874 0.4064)
			(stroke
				(width 0.1524)
				(type default)
			)
			(layer "F.SilkS")
		)
		(fp_line
			(start -0.7874 -0.4064)
			(end 0.7874 -0.4064)
			(stroke
				(width 0.1524)
				(type default)
			)
			(layer "F.SilkS")
		)
		(fp_line
			(start 0.7874 -0.4064)
			(end 0.7874 0.4064)
			(stroke
				(width 0.1524)
				(type default)
			)
			(layer "F.SilkS")
		)
		(fp_line
			(start -0.67945 0.3048)
			(end -0.67945 -0.305054)
			(stroke
				(width 0.1)
				(type default)
			)
			(layer "F.Fab")
		)
		(fp_line
			(start -0.12065 0.3048)
			(end -0.67945 0.3048)
			(stroke
				(width 0.1)
				(type default)
			)
			(layer "F.Fab")
		)
		(fp_line
			(start 0.120396 0.3048)
			(end 0.120396 0.2794)
			(stroke
				(width 0.1)
				(type default)
			)
			(layer "F.Fab")
		)
		(fp_line
			(start 0.67945 0.3048)
			(end 0.120396 0.3048)
			(stroke
				(width 0.1)
				(type default)
			)
			(layer "F.Fab")
		)
		(fp_line
			(start -0.12065 0.2794)
			(end -0.12065 0.3048)
			(stroke
				(width 0.1)
				(type default)
			)
			(layer "F.Fab")
		)
		(fp_line
			(start 0.120396 0.2794)
			(end -0.12065 0.2794)
			(stroke
				(width 0.1)
				(type default)
			)
			(layer "F.Fab")
		)
		(fp_line
			(start -0.12065 -0.2794)
			(end 0.12065 -0.2794)
			(stroke
				(width 0.1)
				(type default)
			)
			(layer "F.Fab")
		)
		(fp_line
			(start 0.12065 -0.2794)
			(end 0.12065 -0.3048)
			(stroke
				(width 0.1)
				(type default)
			)
			(layer "F.Fab")
		)
		(fp_line
			(start 0.12065 -0.3048)
			(end 0.67945 -0.3048)
			(stroke
				(width 0.1)
				(type default)
			)
			(layer "F.Fab")
		)
		(fp_line
			(start 0.67945 -0.3048)
			(end 0.67945 0.3048)
			(stroke
				(width 0.1)
				(type default)
			)
			(layer "F.Fab")
		)
		(fp_line
			(start -0.67945 -0.305054)
			(end -0.12065 -0.305054)
			(stroke
				(width 0.1)
				(type default)
			)
			(layer "F.Fab")
		)
		(fp_line
			(start -0.12065 -0.305054)
			(end -0.12065 -0.2794)
			(stroke
				(width 0.1)
				(type default)
			)
			(layer "F.Fab")
		)
		(pad "1" smd circle
			(at -0.40005 0 270)
			(size 0 0)
			(layers "F.Cu" "F.Mask" "F.Paste")
			(net "P3V3_AUX")
		)
		(pad "2" smd circle
			(at 0.40005 0 270)
			(size 0 0)
			(layers "F.Cu" "F.Mask" "F.Paste")
			(net "FM_P2E_BUF2_VODA_DB")
		)
	)
	(footprint ""
		(layer "F.Cu")
		(at 274.56638 -421.883332)
		(property "Reference" "JP4003"
			(at -3.4417 8.750808 90)
			(unlocked yes)
			(layer "F.SilkS")
			(effects
				(font
					(size 0.7874 0.5842)
					(thickness 0.1524)
				)
				(justify left)
			)
		)
		(property "Value" ""
			(at 0 0 0)
			(layer "F.Fab")
			(effects
				(font
					(size 1.27 1.27)
				)
			)
		)
		(duplicate_pad_numbers_are_jumpers no)
		(fp_line
			(start -1.249934 -1.320038)
			(end 1.249934 -1.320038)
			(stroke
				(width 0.1524)
				(type default)
			)
			(layer "F.SilkS")
		)
		(fp_line
			(start -1.249934 6.400038)
			(end -1.249934 -1.320038)
			(stroke
				(width 0.1524)
				(type default)
			)
			(layer "F.SilkS")
		)
		(fp_line
			(start 1.249934 -1.320038)
			(end 1.249934 6.400038)
			(stroke
				(width 0.1524)
				(type default)
			)
			(layer "F.SilkS")
		)
		(fp_line
			(start 1.249934 6.400038)
			(end -1.249934 6.400038)
			(stroke
				(width 0.1524)
				(type default)
			)
			(layer "F.SilkS")
		)
		(fp_poly
			(pts
				(xy -2.5654 0.556514) (xy -2.5654 -0.556514) (xy -1.452372 0)
			)
			(stroke
				(width 0)
				(type default)
			)
			(fill yes)
			(layer "F.SilkS")
		)
		(fp_line
			(start -1.249934 -1.320038)
			(end 1.249934 -1.320038)
			(stroke
				(width 0.1)
				(type default)
			)
			(layer "F.Fab")
		)
		(fp_line
			(start -1.249934 6.400038)
			(end -1.249934 -1.320038)
			(stroke
				(width 0.1)
				(type default)
			)
			(layer "F.Fab")
		)
		(fp_line
			(start 1.249934 -1.320038)
			(end 1.249934 6.400038)
			(stroke
				(width 0.1)
				(type default)
			)
			(layer "F.Fab")
		)
		(fp_line
			(start 1.249934 6.400038)
			(end -1.249934 6.400038)
			(stroke
				(width 0.1)
				(type default)
			)
			(layer "F.Fab")
		)
		(fp_poly
			(pts
				(xy -2.5654 -0.556514) (xy -1.452372 0) (xy -2.5654 0.556514)
			)
			(stroke
				(width 0)
				(type default)
			)
			(fill yes)
			(layer "F.Fab")
		)
		(fp_text user "3"
			(at -2.007362 5.130292 90)
			(unlocked yes)
			(layer "F.SilkS")
			(effects
				(font
					(size 0.7874 0.5842)
					(thickness 0.1524)
				)
			)
		)
		(fp_text user "3"
			(at -1.1557 5.18287 0)
			(unlocked yes)
			(layer "B.SilkS")
			(effects
				(font
					(size 0.7874 0.5842)
					(thickness 0.1524)
				)
				(justify mirror)
			)
		)
		(fp_text user "1"
			(at -1.143 0.02667 0)
			(unlocked yes)
			(layer "B.SilkS")
			(effects
				(font
					(size 0.7874 0.5842)
					(thickness 0.1524)
				)
				(justify mirror)
			)
		)
		(fp_text user "3"
			(at -1.1557 5.18287 0)
			(unlocked yes)
			(layer "B.Fab")
			(effects
				(font
					(size 0.7874 0.5842)
					(thickness 0.1524)
				)
				(justify mirror)
			)
		)
		(fp_text user "1"
			(at -1.143 0.02667 0)
			(unlocked yes)
			(layer "B.Fab")
			(effects
				(font
					(size 0.7874 0.5842)
					(thickness 0.1524)
				)
				(justify mirror)
			)
		)
		(fp_text user "3"
			(at -1.778 5.13207 0)
			(unlocked yes)
			(layer "F.Fab")
			(effects
				(font
					(size 0.7874 0.5842)
					(thickness 0.1524)
				)
			)
		)
		(pad "1" thru_hole rect
			(at 0 0)
			(size 1.5494 1.5494)
			(drill 1.0414)
			(layers "*.Cu" "*.Mask")
			(remove_unused_layers no)
			(net "Net_10750")
			(clearance 0)
			(padstack
				(mode front_inner_back)
				(layer "Inner"
					(shape circle)
					(size 1.5494 1.5494)
					(clearance 0)
				)
				(layer "B.Cu"
					(shape rect)
					(size 1.5494 1.5494)
					(clearance 0)
				)
			)
		)
		(pad "2" thru_hole circle
			(at 0 2.54)
			(size 1.5494 1.5494)
			(drill 1.0414)
			(layers "*.Cu" "*.Mask")
			(remove_unused_layers no)
			(net "PDB_PRSNT_R_N")
			(clearance 0)
		)
		(pad "3" thru_hole circle
			(at 0 5.08)
			(size 1.5494 1.5494)
			(drill 1.0414)
			(layers "*.Cu" "*.Mask")
			(remove_unused_layers no)
			(net "GND")
			(clearance 0)
		)
	)
	(footprint ""
		(layer "F.Cu")
		(at 257.242056 -119.92737 180)
		(property "Reference" "R3716"
			(at 0 0 180)
			(layer "F.SilkS")
			(hide yes)
			(effects
				(font
					(size 1.27 1.27)
				)
			)
		)
		(property "Value" ""
			(at 0 0 180)
			(layer "F.Fab")
			(effects
				(font
					(size 1.27 1.27)
				)
			)
		)
		(duplicate_pad_numbers_are_jumpers no)
		(fp_line
			(start 0.7874 0.4064)
			(end -0.7874 0.4064)
			(stroke
				(width 0.1524)
				(type default)
			)
			(layer "F.SilkS")
		)
		(fp_line
			(start 0.7874 -0.4064)
			(end 0.7874 0.4064)
			(stroke
				(width 0.1524)
				(type default)
			)
			(layer "F.SilkS")
		)
		(fp_line
			(start -0.7874 0.4064)
			(end -0.7874 -0.4064)
			(stroke
				(width 0.1524)
				(type default)
			)
			(layer "F.SilkS")
		)
		(fp_line
			(start -0.7874 -0.4064)
			(end 0.7874 -0.4064)
			(stroke
				(width 0.1524)
				(type default)
			)
			(layer "F.SilkS")
		)
		(fp_line
			(start 0.67945 0.3048)
			(end 0.120396 0.3048)
			(stroke
				(width 0.1)
				(type default)
			)
			(layer "F.Fab")
		)
		(fp_line
			(start 0.67945 -0.3048)
			(end 0.67945 0.3048)
			(stroke
				(width 0.1)
				(type default)
			)
			(layer "F.Fab")
		)
		(fp_line
			(start 0.12065 -0.2794)
			(end 0.12065 -0.3048)
			(stroke
				(width 0.1)
				(type default)
			)
			(layer "F.Fab")
		)
		(fp_line
			(start 0.12065 -0.3048)
			(end 0.67945 -0.3048)
			(stroke
				(width 0.1)
				(type default)
			)
			(layer "F.Fab")
		)
		(fp_line
			(start 0.120396 0.3048)
			(end 0.120396 0.2794)
			(stroke
				(width 0.1)
				(type default)
			)
			(layer "F.Fab")
		)
		(fp_line
			(start 0.120396 0.2794)
			(end -0.12065 0.2794)
			(stroke
				(width 0.1)
				(type default)
			)
			(layer "F.Fab")
		)
		(fp_line
			(start -0.12065 0.3048)
			(end -0.67945 0.3048)
			(stroke
				(width 0.1)
				(type default)
			)
			(layer "F.Fab")
		)
		(fp_line
			(start -0.12065 0.2794)
			(end -0.12065 0.3048)
			(stroke
				(width 0.1)
				(type default)
			)
			(layer "F.Fab")
		)
		(fp_line
			(start -0.12065 -0.2794)
			(end 0.12065 -0.2794)
			(stroke
				(width 0.1)
				(type default)
			)
			(layer "F.Fab")
		)
		(fp_line
			(start -0.12065 -0.305054)
			(end -0.12065 -0.2794)
			(stroke
				(width 0.1)
				(type default)
			)
			(layer "F.Fab")
		)
		(fp_line
			(start -0.67945 0.3048)
			(end -0.67945 -0.305054)
			(stroke
				(width 0.1)
				(type default)
			)
			(layer "F.Fab")
		)
		(fp_line
			(start -0.67945 -0.305054)
			(end -0.12065 -0.305054)
			(stroke
				(width 0.1)
				(type default)
			)
			(layer "F.Fab")
		)
		(pad "1" smd circle
			(at -0.40005 0 180)
			(size 0 0)
			(layers "F.Cu" "F.Mask" "F.Paste")
			(net "SMB_LM75_0_3V3AUX_SDA_R")
		)
		(pad "2" smd circle
			(at 0.40005 0 180)
			(size 0 0)
			(layers "F.Cu" "F.Mask" "F.Paste")
			(net "SMB_LM75_0_3V3AUX_SDA")
		)
	)
	(footprint ""
		(layer "F.Cu")
		(at 254.592836 -121.71045)
		(property "Reference" "R3723"
			(at 0 0 0)
			(layer "F.SilkS")
			(hide yes)
			(effects
				(font
					(size 1.27 1.27)
				)
			)
		)
		(property "Value" ""
			(at 0 0 0)
			(layer "F.Fab")
			(effects
				(font
					(size 1.27 1.27)
				)
			)
		)
		(duplicate_pad_numbers_are_jumpers no)
		(fp_line
			(start -0.7874 -0.4064)
			(end 0.7874 -0.4064)
			(stroke
				(width 0.1524)
				(type default)
			)
			(layer "F.SilkS")
		)
		(fp_line
			(start -0.7874 0.4064)
			(end -0.7874 -0.4064)
			(stroke
				(width 0.1524)
				(type default)
			)
			(layer "F.SilkS")
		)
		(fp_line
			(start 0.7874 -0.4064)
			(end 0.7874 0.4064)
			(stroke
				(width 0.1524)
				(type default)
			)
			(layer "F.SilkS")
		)
		(fp_line
			(start 0.7874 0.4064)
			(end -0.7874 0.4064)
			(stroke
				(width 0.1524)
				(type default)
			)
			(layer "F.SilkS")
		)
		(fp_line
			(start -0.67945 -0.305054)
			(end -0.12065 -0.305054)
			(stroke
				(width 0.1)
				(type default)
			)
			(layer "F.Fab")
		)
		(fp_line
			(start -0.67945 0.3048)
			(end -0.67945 -0.305054)
			(stroke
				(width 0.1)
				(type default)
			)
			(layer "F.Fab")
		)
		(fp_line
			(start -0.12065 -0.305054)
			(end -0.12065 -0.2794)
			(stroke
				(width 0.1)
				(type default)
			)
			(layer "F.Fab")
		)
		(fp_line
			(start -0.12065 -0.2794)
			(end 0.12065 -0.2794)
			(stroke
				(width 0.1)
				(type default)
			)
			(layer "F.Fab")
		)
		(fp_line
			(start -0.12065 0.2794)
			(end -0.12065 0.3048)
			(stroke
				(width 0.1)
				(type default)
			)
			(layer "F.Fab")
		)
		(fp_line
			(start -0.12065 0.3048)
			(end -0.67945 0.3048)
			(stroke
				(width 0.1)
				(type default)
			)
			(layer "F.Fab")
		)
		(fp_line
			(start 0.120396 0.2794)
			(end -0.12065 0.2794)
			(stroke
				(width 0.1)
				(type default)
			)
			(layer "F.Fab")
		)
		(fp_line
			(start 0.120396 0.3048)
			(end 0.120396 0.2794)
			(stroke
				(width 0.1)
				(type default)
			)
			(layer "F.Fab")
		)
		(fp_line
			(start 0.12065 -0.3048)
			(end 0.67945 -0.3048)
			(stroke
				(width 0.1)
				(type default)
			)
			(layer "F.Fab")
		)
		(fp_line
			(start 0.12065 -0.2794)
			(end 0.12065 -0.3048)
			(stroke
				(width 0.1)
				(type default)
			)
			(layer "F.Fab")
		)
		(fp_line
			(start 0.67945 -0.3048)
			(end 0.67945 0.3048)
			(stroke
				(width 0.1)
				(type default)
			)
			(layer "F.Fab")
		)
		(fp_line
			(start 0.67945 0.3048)
			(end 0.120396 0.3048)
			(stroke
				(width 0.1)
				(type default)
			)
			(layer "F.Fab")
		)
		(pad "1" smd circle
			(at -0.40005 0)
			(size 0 0)
			(layers "F.Cu" "F.Mask" "F.Paste")
			(net "P3V3_AUX")
		)
		(pad "2" smd circle
			(at 0.40005 0)
			(size 0 0)
			(layers "F.Cu" "F.Mask" "F.Paste")
			(net "SMB_VR_3V3AUX_SCL")
		)
	)
	(footprint ""
		(layer "F.Cu")
		(at 118.618 -431.038)
		(property "Reference" "R3451"
			(at 0 0 0)
			(layer "F.SilkS")
			(hide yes)
			(effects
				(font
					(size 1.27 1.27)
				)
			)
		)
		(property "Value" ""
			(at 0 0 0)
			(layer "F.Fab")
			(effects
				(font
					(size 1.27 1.27)
				)
			)
		)
		(duplicate_pad_numbers_are_jumpers no)
		(fp_line
			(start -0.7874 -0.4064)
			(end 0.7874 -0.4064)
			(stroke
				(width 0.1524)
				(type default)
			)
			(layer "F.SilkS")
		)
		(fp_line
			(start -0.7874 0.4064)
			(end -0.7874 -0.4064)
			(stroke
				(width 0.1524)
				(type default)
			)
			(layer "F.SilkS")
		)
		(fp_line
			(start 0.7874 -0.4064)
			(end 0.7874 0.4064)
			(stroke
				(width 0.1524)
				(type default)
			)
			(layer "F.SilkS")
		)
		(fp_line
			(start 0.7874 0.4064)
			(end -0.7874 0.4064)
			(stroke
				(width 0.1524)
				(type default)
			)
			(layer "F.SilkS")
		)
		(fp_line
			(start -0.67945 -0.305054)
			(end -0.12065 -0.305054)
			(stroke
				(width 0.1)
				(type default)
			)
			(layer "F.Fab")
		)
		(fp_line
			(start -0.67945 0.3048)
			(end -0.67945 -0.305054)
			(stroke
				(width 0.1)
				(type default)
			)
			(layer "F.Fab")
		)
		(fp_line
			(start -0.12065 -0.305054)
			(end -0.12065 -0.2794)
			(stroke
				(width 0.1)
				(type default)
			)
			(layer "F.Fab")
		)
		(fp_line
			(start -0.12065 -0.2794)
			(end 0.12065 -0.2794)
			(stroke
				(width 0.1)
				(type default)
			)
			(layer "F.Fab")
		)
		(fp_line
			(start -0.12065 0.2794)
			(end -0.12065 0.3048)
			(stroke
				(width 0.1)
				(type default)
			)
			(layer "F.Fab")
		)
		(fp_line
			(start -0.12065 0.3048)
			(end -0.67945 0.3048)
			(stroke
				(width 0.1)
				(type default)
			)
			(layer "F.Fab")
		)
		(fp_line
			(start 0.120396 0.2794)
			(end -0.12065 0.2794)
			(stroke
				(width 0.1)
				(type default)
			)
			(layer "F.Fab")
		)
		(fp_line
			(start 0.120396 0.3048)
			(end 0.120396 0.2794)
			(stroke
				(width 0.1)
				(type default)
			)
			(layer "F.Fab")
		)
		(fp_line
			(start 0.12065 -0.3048)
			(end 0.67945 -0.3048)
			(stroke
				(width 0.1)
				(type default)
			)
			(layer "F.Fab")
		)
		(fp_line
			(start 0.12065 -0.2794)
			(end 0.12065 -0.3048)
			(stroke
				(width 0.1)
				(type default)
			)
			(layer "F.Fab")
		)
		(fp_line
			(start 0.67945 -0.3048)
			(end 0.67945 0.3048)
			(stroke
				(width 0.1)
				(type default)
			)
			(layer "F.Fab")
		)
		(fp_line
			(start 0.67945 0.3048)
			(end 0.120396 0.3048)
			(stroke
				(width 0.1)
				(type default)
			)
			(layer "F.Fab")
		)
		(pad "1" smd circle
			(at -0.40005 0)
			(size 0 0)
			(layers "F.Cu" "F.Mask" "F.Paste")
			(net "P3V3_AUX")
		)
		(pad "2" smd circle
			(at 0.40005 0)
			(size 0 0)
			(layers "F.Cu" "F.Mask" "F.Paste")
			(net "GPU_BASE_STBY_EN")
		)
	)
	(footprint ""
		(layer "F.Cu")
		(at 407.627582 -416.899344 -90)
		(property "Reference" "C6590"
			(at 0 0 270)
			(layer "F.SilkS")
			(hide yes)
			(effects
				(font
					(size 1.27 1.27)
				)
			)
		)
		(property "Value" ""
			(at 0 0 270)
			(layer "F.Fab")
			(effects
				(font
					(size 1.27 1.27)
				)
			)
		)
		(duplicate_pad_numbers_are_jumpers no)
		(fp_line
			(start -0.299974 0.150114)
			(end -0.299974 -0.150114)
			(stroke
				(width 0.1)
				(type default)
			)
			(layer "F.Fab")
		)
		(fp_line
			(start 0.299974 0.150114)
			(end -0.299974 0.150114)
			(stroke
				(width 0.1)
				(type default)
			)
			(layer "F.Fab")
		)
		(fp_line
			(start -0.299974 -0.150114)
			(end 0.299974 -0.150114)
			(stroke
				(width 0.1)
				(type default)
			)
			(layer "F.Fab")
		)
		(fp_line
			(start 0.299974 -0.150114)
			(end 0.299974 0.150114)
			(stroke
				(width 0.1)
				(type default)
			)
			(layer "F.Fab")
		)
		(pad "1" smd rect
			(at -0.2667 0 270)
			(size 0.3048 0.381)
			(layers "F.Cu" "F.Mask" "F.Paste")
			(net "P5E_CPU0_P2_TX_BUF_C_DN<12>")
		)
		(pad "2" smd rect
			(at 0.2667 0 270)
			(size 0.3048 0.381)
			(layers "F.Cu" "F.Mask" "F.Paste")
			(net "P5E_CPU0_P2_TX_BUF_DN<12>")
		)
	)
	(footprint ""
		(layer "F.Cu")
		(at 88.505284 -408.517344 -90)
		(property "Reference" "C6655"
			(at 0 0 270)
			(layer "F.SilkS")
			(hide yes)
			(effects
				(font
					(size 1.27 1.27)
				)
			)
		)
		(property "Value" ""
			(at 0 0 270)
			(layer "F.Fab")
			(effects
				(font
					(size 1.27 1.27)
				)
			)
		)
		(duplicate_pad_numbers_are_jumpers no)
		(fp_line
			(start -0.299974 0.150114)
			(end -0.299974 -0.150114)
			(stroke
				(width 0.1)
				(type default)
			)
			(layer "F.Fab")
		)
		(fp_line
			(start 0.299974 0.150114)
			(end -0.299974 0.150114)
			(stroke
				(width 0.1)
				(type default)
			)
			(layer "F.Fab")
		)
		(fp_line
			(start -0.299974 -0.150114)
			(end 0.299974 -0.150114)
			(stroke
				(width 0.1)
				(type default)
			)
			(layer "F.Fab")
		)
		(fp_line
			(start 0.299974 -0.150114)
			(end 0.299974 0.150114)
			(stroke
				(width 0.1)
				(type default)
			)
			(layer "F.Fab")
		)
		(pad "1" smd rect
			(at -0.2667 0 270)
			(size 0.3048 0.381)
			(layers "F.Cu" "F.Mask" "F.Paste")
			(net "P5E_CPU1_P0_TX_BUF_C_DP<13>")
		)
		(pad "2" smd rect
			(at 0.2667 0 270)
			(size 0.3048 0.381)
			(layers "F.Cu" "F.Mask" "F.Paste")
			(net "P5E_CPU1_P0_TX_BUF_DP<13>")
		)
	)
	(footprint ""
		(layer "F.Cu")
		(at 9.74471 -79.480664)
		(property "Reference" "R3133"
			(at 0 0 0)
			(layer "F.SilkS")
			(hide yes)
			(effects
				(font
					(size 1.27 1.27)
				)
			)
		)
		(property "Value" ""
			(at 0 0 0)
			(layer "F.Fab")
			(effects
				(font
					(size 1.27 1.27)
				)
			)
		)
		(duplicate_pad_numbers_are_jumpers no)
		(fp_line
			(start -0.7874 -0.4064)
			(end 0.7874 -0.4064)
			(stroke
				(width 0.1524)
				(type default)
			)
			(layer "F.SilkS")
		)
		(fp_line
			(start -0.7874 0.4064)
			(end -0.7874 -0.4064)
			(stroke
				(width 0.1524)
				(type default)
			)
			(layer "F.SilkS")
		)
		(fp_line
			(start 0.7874 -0.4064)
			(end 0.7874 0.4064)
			(stroke
				(width 0.1524)
				(type default)
			)
			(layer "F.SilkS")
		)
		(fp_line
			(start 0.7874 0.4064)
			(end -0.7874 0.4064)
			(stroke
				(width 0.1524)
				(type default)
			)
			(layer "F.SilkS")
		)
		(fp_line
			(start -0.67945 -0.305054)
			(end -0.12065 -0.305054)
			(stroke
				(width 0.1)
				(type default)
			)
			(layer "F.Fab")
		)
		(fp_line
			(start -0.67945 0.3048)
			(end -0.67945 -0.305054)
			(stroke
				(width 0.1)
				(type default)
			)
			(layer "F.Fab")
		)
		(fp_line
			(start -0.12065 -0.305054)
			(end -0.12065 -0.2794)
			(stroke
				(width 0.1)
				(type default)
			)
			(layer "F.Fab")
		)
		(fp_line
			(start -0.12065 -0.2794)
			(end 0.12065 -0.2794)
			(stroke
				(width 0.1)
				(type default)
			)
			(layer "F.Fab")
		)
		(fp_line
			(start -0.12065 0.2794)
			(end -0.12065 0.3048)
			(stroke
				(width 0.1)
				(type default)
			)
			(layer "F.Fab")
		)
		(fp_line
			(start -0.12065 0.3048)
			(end -0.67945 0.3048)
			(stroke
				(width 0.1)
				(type default)
			)
			(layer "F.Fab")
		)
		(fp_line
			(start 0.120396 0.2794)
			(end -0.12065 0.2794)
			(stroke
				(width 0.1)
				(type default)
			)
			(layer "F.Fab")
		)
		(fp_line
			(start 0.120396 0.3048)
			(end 0.120396 0.2794)
			(stroke
				(width 0.1)
				(type default)
			)
			(layer "F.Fab")
		)
		(fp_line
			(start 0.12065 -0.3048)
			(end 0.67945 -0.3048)
			(stroke
				(width 0.1)
				(type default)
			)
			(layer "F.Fab")
		)
		(fp_line
			(start 0.12065 -0.2794)
			(end 0.12065 -0.3048)
			(stroke
				(width 0.1)
				(type default)
			)
			(layer "F.Fab")
		)
		(fp_line
			(start 0.67945 -0.3048)
			(end 0.67945 0.3048)
			(stroke
				(width 0.1)
				(type default)
			)
			(layer "F.Fab")
		)
		(fp_line
			(start 0.67945 0.3048)
			(end 0.120396 0.3048)
			(stroke
				(width 0.1)
				(type default)
			)
			(layer "F.Fab")
		)
		(pad "1" smd circle
			(at -0.40005 0)
			(size 0 0)
			(layers "F.Cu" "F.Mask" "F.Paste")
			(net "P3V3_AUX")
		)
		(pad "2" smd circle
			(at 0.40005 0)
			(size 0 0)
			(layers "F.Cu" "F.Mask" "F.Paste")
			(net "OCP_V3_2_PRSNT0_R_N")
		)
	)
	(footprint ""
		(layer "F.Cu")
		(at 323.374512 -409.15082 180)
		(property "Reference" "C7000"
			(at -5.053076 -1.373632 0)
			(unlocked yes)
			(layer "F.SilkS")
			(effects
				(font
					(size 0.7874 0.5842)
					(thickness 0.1524)
				)
				(justify left)
			)
		)
		(property "Value" ""
			(at 0 0 180)
			(layer "F.Fab")
			(effects
				(font
					(size 1.27 1.27)
				)
			)
		)
		(duplicate_pad_numbers_are_jumpers no)
		(fp_line
			(start 4.53898 2.15011)
			(end -4.53898 2.15011)
			(stroke
				(width 0.1524)
				(type default)
			)
			(layer "F.SilkS")
		)
		(fp_line
			(start 4.53898 -2.15011)
			(end 4.53898 2.15011)
			(stroke
				(width 0.1524)
				(type default)
			)
			(layer "F.SilkS")
		)
		(fp_line
			(start -4.53898 2.15011)
			(end -4.53898 -2.15011)
			(stroke
				(width 0.1524)
				(type default)
			)
			(layer "F.SilkS")
		)
		(fp_line
			(start -4.53898 -2.15011)
			(end 4.53898 -2.15011)
			(stroke
				(width 0.1524)
				(type default)
			)
			(layer "F.SilkS")
		)
		(fp_line
			(start -4.53898 -2.150618)
			(end -4.539742 2.152142)
			(stroke
				(width 0.1524)
				(type default)
			)
			(layer "F.SilkS")
		)
		(fp_line
			(start -4.69138 -2.150618)
			(end -4.692396 2.161032)
			(stroke
				(width 0.1524)
				(type default)
			)
			(layer "F.SilkS")
		)
		(fp_line
			(start -4.83108 2.150364)
			(end -4.447794 2.149348)
			(stroke
				(width 0.1524)
				(type default)
			)
			(layer "F.SilkS")
		)
		(fp_line
			(start -4.84378 -2.150618)
			(end -4.53898 -2.150618)
			(stroke
				(width 0.1524)
				(type default)
			)
			(layer "F.SilkS")
		)
		(fp_line
			(start -4.84378 -2.150618)
			(end -4.842256 2.163064)
			(stroke
				(width 0.1524)
				(type default)
			)
			(layer "F.SilkS")
		)
		(fp_line
			(start 3.64998 2.15011)
			(end -3.64998 2.15011)
			(stroke
				(width 0.1)
				(type default)
			)
			(layer "F.Fab")
		)
		(fp_line
			(start 3.64998 -2.15011)
			(end 3.64998 2.15011)
			(stroke
				(width 0.1)
				(type default)
			)
			(layer "F.Fab")
		)
		(fp_line
			(start -3.64998 2.15011)
			(end -3.64998 -2.15011)
			(stroke
				(width 0.1)
				(type default)
			)
			(layer "F.Fab")
		)
		(fp_line
			(start -3.64998 -2.15011)
			(end 3.64998 -2.15011)
			(stroke
				(width 0.1)
				(type default)
			)
			(layer "F.Fab")
		)
		(fp_text user "-"
			(at 6.26745 2.685288 0)
			(unlocked yes)
			(layer "F.SilkS")
			(effects
				(font
					(size 1.905 1.4224)
					(thickness 0.1524)
				)
				(justify left)
			)
		)
		(fp_text user "+"
			(at -4.515612 2.609342 180)
			(unlocked yes)
			(layer "F.SilkS")
			(effects
				(font
					(size 1.905 1.4224)
					(thickness 0.1524)
				)
				(justify left)
			)
		)
		(fp_text user "-"
			(at 4.313174 -0.094488 180)
			(unlocked yes)
			(layer "F.Fab")
			(effects
				(font
					(size 1.905 1.4224)
					(thickness 0.1524)
				)
				(justify left)
			)
		)
		(fp_text user "+"
			(at -6.214872 -0.337058 180)
			(unlocked yes)
			(layer "F.Fab")
			(effects
				(font
					(size 1.905 1.4224)
					(thickness 0.1524)
				)
				(justify left)
			)
		)
		(pad "1" smd rect
			(at -3.199892 0 180)
			(size 2.413 2.8194)
			(layers "F.Cu" "F.Mask" "F.Paste")
			(net "P0V9_CPU0_RT_2D")
		)
		(pad "2" smd rect
			(at 3.199892 0 180)
			(size 2.413 2.8194)
			(layers "F.Cu" "F.Mask" "F.Paste")
			(net "GND")
		)
	)
	(footprint ""
		(layer "F.Cu")
		(at 400.315684 -402.548852 -90)
		(property "Reference" "R1062"
			(at 0 0 270)
			(layer "F.SilkS")
			(hide yes)
			(effects
				(font
					(size 1.27 1.27)
				)
			)
		)
		(property "Value" ""
			(at 0 0 270)
			(layer "F.Fab")
			(effects
				(font
					(size 1.27 1.27)
				)
			)
		)
		(duplicate_pad_numbers_are_jumpers no)
		(fp_line
			(start -0.32512 0.175006)
			(end -0.32512 -0.175006)
			(stroke
				(width 0.1)
				(type default)
			)
			(layer "F.Fab")
		)
		(fp_line
			(start 0.32512 0.175006)
			(end -0.32512 0.175006)
			(stroke
				(width 0.1)
				(type default)
			)
			(layer "F.Fab")
		)
		(fp_line
			(start -0.32512 -0.175006)
			(end 0.32512 -0.175006)
			(stroke
				(width 0.1)
				(type default)
			)
			(layer "F.Fab")
		)
		(fp_line
			(start 0.32512 -0.175006)
			(end 0.32512 0.175006)
			(stroke
				(width 0.1)
				(type default)
			)
			(layer "F.Fab")
		)
		(pad "1" smd rect
			(at -0.2667 0 270)
			(size 0.3048 0.381)
			(layers "F.Cu" "F.Mask" "F.Paste")
			(net "RST_RT_CPU0_P2_RESET_R_N")
		)
		(pad "2" smd rect
			(at 0.2667 0 90)
			(size 0.3048 0.381)
			(layers "F.Cu" "F.Mask" "F.Paste")
			(net "GND")
		)
	)
	(footprint ""
		(layer "F.Cu")
		(at 365.794798 -428.28591 180)
		(property "Reference" "R684"
			(at 0 0 180)
			(layer "F.SilkS")
			(hide yes)
			(effects
				(font
					(size 1.27 1.27)
				)
			)
		)
		(property "Value" ""
			(at 0 0 180)
			(layer "F.Fab")
			(effects
				(font
					(size 1.27 1.27)
				)
			)
		)
		(duplicate_pad_numbers_are_jumpers no)
		(fp_line
			(start 0.32512 0.175006)
			(end -0.32512 0.175006)
			(stroke
				(width 0.1)
				(type default)
			)
			(layer "F.Fab")
		)
		(fp_line
			(start 0.32512 -0.175006)
			(end 0.32512 0.175006)
			(stroke
				(width 0.1)
				(type default)
			)
			(layer "F.Fab")
		)
		(fp_line
			(start -0.32512 0.175006)
			(end -0.32512 -0.175006)
			(stroke
				(width 0.1)
				(type default)
			)
			(layer "F.Fab")
		)
		(fp_line
			(start -0.32512 -0.175006)
			(end 0.32512 -0.175006)
			(stroke
				(width 0.1)
				(type default)
			)
			(layer "F.Fab")
		)
		(pad "1" smd rect
			(at -0.2667 0 180)
			(size 0.3048 0.381)
			(layers "F.Cu" "F.Mask" "F.Paste")
			(net "SMB_RT_CPU0_P3_ROM_MUX_1D_SCL")
		)
		(pad "2" smd rect
			(at 0.2667 0)
			(size 0.3048 0.381)
			(layers "F.Cu" "F.Mask" "F.Paste")
			(net "SMB_RT_CPU0_P3_ROM_MUX_1D_R_SCL")
		)
	)
	(footprint ""
		(layer "F.Cu")
		(at 367.504726 -27.904694 -90)
		(property "Reference" "C363"
			(at 0 0 270)
			(layer "F.SilkS")
			(hide yes)
			(effects
				(font
					(size 1.27 1.27)
				)
			)
		)
		(property "Value" ""
			(at 0 0 270)
			(layer "F.Fab")
			(effects
				(font
					(size 1.27 1.27)
				)
			)
		)
		(duplicate_pad_numbers_are_jumpers no)
		(fp_line
			(start -0.7874 0.4064)
			(end -0.7874 -0.4064)
			(stroke
				(width 0.1524)
				(type default)
			)
			(layer "F.SilkS")
		)
		(fp_line
			(start 0.7874 0.4064)
			(end -0.7874 0.4064)
			(stroke
				(width 0.1524)
				(type default)
			)
			(layer "F.SilkS")
		)
		(fp_line
			(start -0.7874 -0.4064)
			(end 0.7874 -0.4064)
			(stroke
				(width 0.1524)
				(type default)
			)
			(layer "F.SilkS")
		)
		(fp_line
			(start 0.7874 -0.4064)
			(end 0.7874 0.4064)
			(stroke
				(width 0.1524)
				(type default)
			)
			(layer "F.SilkS")
		)
		(fp_line
			(start -0.67945 0.3048)
			(end -0.67945 -0.305054)
			(stroke
				(width 0.1)
				(type default)
			)
			(layer "F.Fab")
		)
		(fp_line
			(start -0.12065 0.3048)
			(end -0.67945 0.3048)
			(stroke
				(width 0.1)
				(type default)
			)
			(layer "F.Fab")
		)
		(fp_line
			(start 0.120396 0.3048)
			(end 0.120396 0.2794)
			(stroke
				(width 0.1)
				(type default)
			)
			(layer "F.Fab")
		)
		(fp_line
			(start 0.67945 0.3048)
			(end 0.120396 0.3048)
			(stroke
				(width 0.1)
				(type default)
			)
			(layer "F.Fab")
		)
		(fp_line
			(start -0.12065 0.2794)
			(end -0.12065 0.3048)
			(stroke
				(width 0.1)
				(type default)
			)
			(layer "F.Fab")
		)
		(fp_line
			(start 0.120396 0.2794)
			(end -0.12065 0.2794)
			(stroke
				(width 0.1)
				(type default)
			)
			(layer "F.Fab")
		)
		(fp_line
			(start -0.12065 -0.2794)
			(end 0.12065 -0.2794)
			(stroke
				(width 0.1)
				(type default)
			)
			(layer "F.Fab")
		)
		(fp_line
			(start 0.12065 -0.2794)
			(end 0.12065 -0.3048)
			(stroke
				(width 0.1)
				(type default)
			)
			(layer "F.Fab")
		)
		(fp_line
			(start 0.12065 -0.3048)
			(end 0.67945 -0.3048)
			(stroke
				(width 0.1)
				(type default)
			)
			(layer "F.Fab")
		)
		(fp_line
			(start 0.67945 -0.3048)
			(end 0.67945 0.3048)
			(stroke
				(width 0.1)
				(type default)
			)
			(layer "F.Fab")
		)
		(fp_line
			(start -0.67945 -0.305054)
			(end -0.12065 -0.305054)
			(stroke
				(width 0.1)
				(type default)
			)
			(layer "F.Fab")
		)
		(fp_line
			(start -0.12065 -0.305054)
			(end -0.12065 -0.2794)
			(stroke
				(width 0.1)
				(type default)
			)
			(layer "F.Fab")
		)
		(pad "1" smd circle
			(at -0.40005 0 270)
			(size 0 0)
			(layers "F.Cu" "F.Mask" "F.Paste")
			(net "UART_CPU0_LVC3_UART0_TX")
		)
		(pad "2" smd circle
			(at 0.40005 0 270)
			(size 0 0)
			(layers "F.Cu" "F.Mask" "F.Paste")
			(net "GND")
		)
	)
	(footprint ""
		(layer "F.Cu")
		(at 425.121324 -396.748 90)
		(property "Reference" "C668"
			(at 0 0 90)
			(layer "F.SilkS")
			(hide yes)
			(effects
				(font
					(size 1.27 1.27)
				)
			)
		)
		(property "Value" ""
			(at 0 0 90)
			(layer "F.Fab")
			(effects
				(font
					(size 1.27 1.27)
				)
			)
		)
		(duplicate_pad_numbers_are_jumpers no)
		(fp_line
			(start 0.7874 -0.4064)
			(end 0.7874 0.4064)
			(stroke
				(width 0.1524)
				(type default)
			)
			(layer "F.SilkS")
		)
		(fp_line
			(start -0.7874 -0.4064)
			(end 0.7874 -0.4064)
			(stroke
				(width 0.1524)
				(type default)
			)
			(layer "F.SilkS")
		)
		(fp_line
			(start 0.7874 0.4064)
			(end -0.7874 0.4064)
			(stroke
				(width 0.1524)
				(type default)
			)
			(layer "F.SilkS")
		)
		(fp_line
			(start -0.7874 0.4064)
			(end -0.7874 -0.4064)
			(stroke
				(width 0.1524)
				(type default)
			)
			(layer "F.SilkS")
		)
		(fp_line
			(start -0.12065 -0.305054)
			(end -0.12065 -0.2794)
			(stroke
				(width 0.1)
				(type default)
			)
			(layer "F.Fab")
		)
		(fp_line
			(start -0.67945 -0.305054)
			(end -0.12065 -0.305054)
			(stroke
				(width 0.1)
				(type default)
			)
			(layer "F.Fab")
		)
		(fp_line
			(start 0.67945 -0.3048)
			(end 0.67945 0.3048)
			(stroke
				(width 0.1)
				(type default)
			)
			(layer "F.Fab")
		)
		(fp_line
			(start 0.12065 -0.3048)
			(end 0.67945 -0.3048)
			(stroke
				(width 0.1)
				(type default)
			)
			(layer "F.Fab")
		)
		(fp_line
			(start 0.12065 -0.2794)
			(end 0.12065 -0.3048)
			(stroke
				(width 0.1)
				(type default)
			)
			(layer "F.Fab")
		)
		(fp_line
			(start -0.12065 -0.2794)
			(end 0.12065 -0.2794)
			(stroke
				(width 0.1)
				(type default)
			)
			(layer "F.Fab")
		)
		(fp_line
			(start 0.120396 0.2794)
			(end -0.12065 0.2794)
			(stroke
				(width 0.1)
				(type default)
			)
			(layer "F.Fab")
		)
		(fp_line
			(start -0.12065 0.2794)
			(end -0.12065 0.3048)
			(stroke
				(width 0.1)
				(type default)
			)
			(layer "F.Fab")
		)
		(fp_line
			(start 0.67945 0.3048)
			(end 0.120396 0.3048)
			(stroke
				(width 0.1)
				(type default)
			)
			(layer "F.Fab")
		)
		(fp_line
			(start 0.120396 0.3048)
			(end 0.120396 0.2794)
			(stroke
				(width 0.1)
				(type default)
			)
			(layer "F.Fab")
		)
		(fp_line
			(start -0.12065 0.3048)
			(end -0.67945 0.3048)
			(stroke
				(width 0.1)
				(type default)
			)
			(layer "F.Fab")
		)
		(fp_line
			(start -0.67945 0.3048)
			(end -0.67945 -0.305054)
			(stroke
				(width 0.1)
				(type default)
			)
			(layer "F.Fab")
		)
		(pad "1" smd circle
			(at -0.40005 0 90)
			(size 0 0)
			(layers "F.Cu" "F.Mask" "F.Paste")
			(net "P1V8_CPU0_RT2_1A")
		)
		(pad "2" smd circle
			(at 0.40005 0 90)
			(size 0 0)
			(layers "F.Cu" "F.Mask" "F.Paste")
			(net "GND")
		)
	)
	(footprint ""
		(layer "F.Cu")
		(at 162.052 -107.696 90)
		(property "Reference" "C9005"
			(at 0 0 90)
			(layer "F.SilkS")
			(hide yes)
			(effects
				(font
					(size 1.27 1.27)
				)
			)
		)
		(property "Value" ""
			(at 0 0 90)
			(layer "F.Fab")
			(effects
				(font
					(size 1.27 1.27)
				)
			)
		)
		(duplicate_pad_numbers_are_jumpers no)
		(fp_line
			(start 0.7874 -0.4064)
			(end 0.7874 0.4064)
			(stroke
				(width 0.1524)
				(type default)
			)
			(layer "F.SilkS")
		)
		(fp_line
			(start -0.7874 -0.4064)
			(end 0.7874 -0.4064)
			(stroke
				(width 0.1524)
				(type default)
			)
			(layer "F.SilkS")
		)
		(fp_line
			(start 0.7874 0.4064)
			(end -0.7874 0.4064)
			(stroke
				(width 0.1524)
				(type default)
			)
			(layer "F.SilkS")
		)
		(fp_line
			(start -0.7874 0.4064)
			(end -0.7874 -0.4064)
			(stroke
				(width 0.1524)
				(type default)
			)
			(layer "F.SilkS")
		)
		(fp_line
			(start -0.12065 -0.305054)
			(end -0.12065 -0.2794)
			(stroke
				(width 0.1)
				(type default)
			)
			(layer "F.Fab")
		)
		(fp_line
			(start -0.67945 -0.305054)
			(end -0.12065 -0.305054)
			(stroke
				(width 0.1)
				(type default)
			)
			(layer "F.Fab")
		)
		(fp_line
			(start 0.67945 -0.3048)
			(end 0.67945 0.3048)
			(stroke
				(width 0.1)
				(type default)
			)
			(layer "F.Fab")
		)
		(fp_line
			(start 0.12065 -0.3048)
			(end 0.67945 -0.3048)
			(stroke
				(width 0.1)
				(type default)
			)
			(layer "F.Fab")
		)
		(fp_line
			(start 0.12065 -0.2794)
			(end 0.12065 -0.3048)
			(stroke
				(width 0.1)
				(type default)
			)
			(layer "F.Fab")
		)
		(fp_line
			(start -0.12065 -0.2794)
			(end 0.12065 -0.2794)
			(stroke
				(width 0.1)
				(type default)
			)
			(layer "F.Fab")
		)
		(fp_line
			(start 0.120396 0.2794)
			(end -0.12065 0.2794)
			(stroke
				(width 0.1)
				(type default)
			)
			(layer "F.Fab")
		)
		(fp_line
			(start -0.12065 0.2794)
			(end -0.12065 0.3048)
			(stroke
				(width 0.1)
				(type default)
			)
			(layer "F.Fab")
		)
		(fp_line
			(start 0.67945 0.3048)
			(end 0.120396 0.3048)
			(stroke
				(width 0.1)
				(type default)
			)
			(layer "F.Fab")
		)
		(fp_line
			(start 0.120396 0.3048)
			(end 0.120396 0.2794)
			(stroke
				(width 0.1)
				(type default)
			)
			(layer "F.Fab")
		)
		(fp_line
			(start -0.12065 0.3048)
			(end -0.67945 0.3048)
			(stroke
				(width 0.1)
				(type default)
			)
			(layer "F.Fab")
		)
		(fp_line
			(start -0.67945 0.3048)
			(end -0.67945 -0.305054)
			(stroke
				(width 0.1)
				(type default)
			)
			(layer "F.Fab")
		)
		(pad "1" smd circle
			(at -0.40005 0 90)
			(size 0 0)
			(layers "F.Cu" "F.Mask" "F.Paste")
			(net "IRQ_HSC_FAULT_BUF_N")
		)
		(pad "2" smd circle
			(at 0.40005 0 90)
			(size 0 0)
			(layers "F.Cu" "F.Mask" "F.Paste")
			(net "GND")
		)
	)
	(footprint ""
		(layer "F.Cu")
		(at 329.838558 -38.409118)
		(property "Reference" "C1768"
			(at 0 0 0)
			(layer "F.SilkS")
			(hide yes)
			(effects
				(font
					(size 1.27 1.27)
				)
			)
		)
		(property "Value" ""
			(at 0 0 0)
			(layer "F.Fab")
			(effects
				(font
					(size 1.27 1.27)
				)
			)
		)
		(duplicate_pad_numbers_are_jumpers no)
		(fp_line
			(start -1.524 -0.762)
			(end 1.524 -0.762)
			(stroke
				(width 0.1524)
				(type default)
			)
			(layer "F.SilkS")
		)
		(fp_line
			(start -1.524 0.762)
			(end -1.524 -0.762)
			(stroke
				(width 0.1524)
				(type default)
			)
			(layer "F.SilkS")
		)
		(fp_line
			(start 1.524 -0.762)
			(end 1.524 0.762)
			(stroke
				(width 0.1524)
				(type default)
			)
			(layer "F.SilkS")
		)
		(fp_line
			(start 1.524 0.762)
			(end -1.524 0.762)
			(stroke
				(width 0.1524)
				(type default)
			)
			(layer "F.SilkS")
		)
		(fp_line
			(start -1.1049 -0.724916)
			(end -1.1049 0.724916)
			(stroke
				(width 0.1)
				(type default)
			)
			(layer "F.Fab")
		)
		(fp_line
			(start -1.1049 0.724916)
			(end 1.1049 0.724916)
			(stroke
				(width 0.1)
				(type default)
			)
			(layer "F.Fab")
		)
		(fp_line
			(start 1.1049 -0.724916)
			(end -1.1049 -0.724916)
			(stroke
				(width 0.1)
				(type default)
			)
			(layer "F.Fab")
		)
		(fp_line
			(start 1.1049 0.724916)
			(end 1.1049 -0.724916)
			(stroke
				(width 0.1)
				(type default)
			)
			(layer "F.Fab")
		)
		(pad "1" smd rect
			(at -0.889 0 180)
			(size 1.016 1.27)
			(layers "F.Cu" "F.Mask" "F.Paste")
			(net "P3V3_MAX11617_VDD")
		)
		(pad "2" smd rect
			(at 0.889 0 180)
			(size 1.016 1.27)
			(layers "F.Cu" "F.Mask" "F.Paste")
			(net "GND")
		)
	)
	(footprint ""
		(layer "F.Cu")
		(at 393.353798 -320.627756 180)
		(property "Reference" "C5023"
			(at 0 0 180)
			(layer "F.SilkS")
			(hide yes)
			(effects
				(font
					(size 1.27 1.27)
				)
			)
		)
		(property "Value" ""
			(at 0 0 180)
			(layer "F.Fab")
			(effects
				(font
					(size 1.27 1.27)
				)
			)
		)
		(duplicate_pad_numbers_are_jumpers no)
		(fp_line
			(start 0.7874 0.4064)
			(end -0.7874 0.4064)
			(stroke
				(width 0.1524)
				(type default)
			)
			(layer "F.SilkS")
		)
		(fp_line
			(start 0.7874 -0.4064)
			(end 0.7874 0.4064)
			(stroke
				(width 0.1524)
				(type default)
			)
			(layer "F.SilkS")
		)
		(fp_line
			(start -0.7874 0.4064)
			(end -0.7874 -0.4064)
			(stroke
				(width 0.1524)
				(type default)
			)
			(layer "F.SilkS")
		)
		(fp_line
			(start -0.7874 -0.4064)
			(end 0.7874 -0.4064)
			(stroke
				(width 0.1524)
				(type default)
			)
			(layer "F.SilkS")
		)
		(fp_line
			(start 0.67945 0.3048)
			(end 0.120396 0.3048)
			(stroke
				(width 0.1)
				(type default)
			)
			(layer "F.Fab")
		)
		(fp_line
			(start 0.67945 -0.3048)
			(end 0.67945 0.3048)
			(stroke
				(width 0.1)
				(type default)
			)
			(layer "F.Fab")
		)
		(fp_line
			(start 0.12065 -0.2794)
			(end 0.12065 -0.3048)
			(stroke
				(width 0.1)
				(type default)
			)
			(layer "F.Fab")
		)
		(fp_line
			(start 0.12065 -0.3048)
			(end 0.67945 -0.3048)
			(stroke
				(width 0.1)
				(type default)
			)
			(layer "F.Fab")
		)
		(fp_line
			(start 0.120396 0.3048)
			(end 0.120396 0.2794)
			(stroke
				(width 0.1)
				(type default)
			)
			(layer "F.Fab")
		)
		(fp_line
			(start 0.120396 0.2794)
			(end -0.12065 0.2794)
			(stroke
				(width 0.1)
				(type default)
			)
			(layer "F.Fab")
		)
		(fp_line
			(start -0.12065 0.3048)
			(end -0.67945 0.3048)
			(stroke
				(width 0.1)
				(type default)
			)
			(layer "F.Fab")
		)
		(fp_line
			(start -0.12065 0.2794)
			(end -0.12065 0.3048)
			(stroke
				(width 0.1)
				(type default)
			)
			(layer "F.Fab")
		)
		(fp_line
			(start -0.12065 -0.2794)
			(end 0.12065 -0.2794)
			(stroke
				(width 0.1)
				(type default)
			)
			(layer "F.Fab")
		)
		(fp_line
			(start -0.12065 -0.305054)
			(end -0.12065 -0.2794)
			(stroke
				(width 0.1)
				(type default)
			)
			(layer "F.Fab")
		)
		(fp_line
			(start -0.67945 0.3048)
			(end -0.67945 -0.305054)
			(stroke
				(width 0.1)
				(type default)
			)
			(layer "F.Fab")
		)
		(fp_line
			(start -0.67945 -0.305054)
			(end -0.12065 -0.305054)
			(stroke
				(width 0.1)
				(type default)
			)
			(layer "F.Fab")
		)
		(pad "1" smd circle
			(at -0.40005 0 180)
			(size 0 0)
			(layers "F.Cu" "F.Mask" "F.Paste")
			(net "RST_CPU0_RSMRST_N")
		)
		(pad "2" smd circle
			(at 0.40005 0 180)
			(size 0 0)
			(layers "F.Cu" "F.Mask" "F.Paste")
			(net "GND")
		)
	)
	(footprint ""
		(layer "F.Cu")
		(at 51.435 -435.61)
		(property "Reference" "U252"
			(at -1.821434 -3.3528 0)
			(unlocked yes)
			(layer "F.SilkS")
			(effects
				(font
					(size 0.7874 0.5842)
					(thickness 0.1524)
				)
				(justify left)
			)
		)
		(property "Value" ""
			(at 0 0 0)
			(layer "F.Fab")
			(effects
				(font
					(size 1.27 1.27)
				)
			)
		)
		(duplicate_pad_numbers_are_jumpers no)
		(fp_line
			(start -1.3462 -1.100074)
			(end -0.670052 -1.100074)
			(stroke
				(width 0.1524)
				(type default)
			)
			(layer "F.SilkS")
		)
		(fp_line
			(start -1.3462 1.100074)
			(end -1.3462 -1.100074)
			(stroke
				(width 0.1524)
				(type default)
			)
			(layer "F.SilkS")
		)
		(fp_line
			(start -0.670052 -1.100074)
			(end 0 -0.381)
			(stroke
				(width 0.1524)
				(type default)
			)
			(layer "F.SilkS")
		)
		(fp_line
			(start 0 -0.381)
			(end 0.670052 -1.100074)
			(stroke
				(width 0.1524)
				(type default)
			)
			(layer "F.SilkS")
		)
		(fp_line
			(start 0.670052 -1.100074)
			(end 1.3462 -1.100074)
			(stroke
				(width 0.1524)
				(type default)
			)
			(layer "F.SilkS")
		)
		(fp_line
			(start 1.3462 -1.100074)
			(end 1.3462 1.100074)
			(stroke
				(width 0.1524)
				(type default)
			)
			(layer "F.SilkS")
		)
		(fp_line
			(start 1.3462 1.100074)
			(end -1.3462 1.100074)
			(stroke
				(width 0.1524)
				(type default)
			)
			(layer "F.SilkS")
		)
		(fp_poly
			(pts
				(xy -2.953512 -1.926844) (xy -2.52095 -2.554224) (xy -2.109978 -1.807972)
			)
			(stroke
				(width 0)
				(type default)
			)
			(fill yes)
			(layer "F.SilkS")
		)
		(fp_line
			(start -1.100074 -0.8001)
			(end -0.670052 -0.8001)
			(stroke
				(width 0.1)
				(type default)
			)
			(layer "F.Fab")
		)
		(fp_line
			(start -1.100074 0.8001)
			(end -1.100074 -0.8001)
			(stroke
				(width 0.1)
				(type default)
			)
			(layer "F.Fab")
		)
		(fp_line
			(start -0.670052 -1.100074)
			(end 0.670052 -1.100074)
			(stroke
				(width 0.1)
				(type default)
			)
			(layer "F.Fab")
		)
		(fp_line
			(start -0.670052 -0.8001)
			(end -0.670052 -1.100074)
			(stroke
				(width 0.1)
				(type default)
			)
			(layer "F.Fab")
		)
		(fp_line
			(start -0.670052 0.8001)
			(end -1.100074 0.8001)
			(stroke
				(width 0.1)
				(type default)
			)
			(layer "F.Fab")
		)
		(fp_line
			(start -0.670052 0.8001)
			(end -0.670052 -0.8001)
			(stroke
				(width 0.1)
				(type default)
			)
			(layer "F.Fab")
		)
		(fp_line
			(start -0.670052 1.100074)
			(end -0.670052 0.8001)
			(stroke
				(width 0.1)
				(type default)
			)
			(layer "F.Fab")
		)
		(fp_line
			(start 0.670052 -1.100074)
			(end 0.670052 -0.8001)
			(stroke
				(width 0.1)
				(type default)
			)
			(layer "F.Fab")
		)
		(fp_line
			(start 0.670052 -0.8001)
			(end 0.670052 0.8001)
			(stroke
				(width 0.1)
				(type default)
			)
			(layer "F.Fab")
		)
		(fp_line
			(start 0.670052 -0.8001)
			(end 1.100074 -0.8001)
			(stroke
				(width 0.1)
				(type default)
			)
			(layer "F.Fab")
		)
		(fp_line
			(start 0.670052 0.8001)
			(end 0.670052 1.100074)
			(stroke
				(width 0.1)
				(type default)
			)
			(layer "F.Fab")
		)
		(fp_line
			(start 0.670052 1.100074)
			(end -0.670052 1.100074)
			(stroke
				(width 0.1)
				(type default)
			)
			(layer "F.Fab")
		)
		(fp_line
			(start 1.100074 -0.8001)
			(end 1.100074 0.8001)
			(stroke
				(width 0.1)
				(type default)
			)
			(layer "F.Fab")
		)
		(fp_line
			(start 1.100074 0.8001)
			(end 0.670052 0.8001)
			(stroke
				(width 0.1)
				(type default)
			)
			(layer "F.Fab")
		)
		(fp_poly
			(pts
				(xy -1.524 -0.649986) (xy -2.286 -1.030986) (xy -2.286 -0.268986)
			)
			(stroke
				(width 0)
				(type default)
			)
			(fill yes)
			(layer "F.Fab")
		)
		(pad "1" smd rect
			(at -0.94996 -0.649986 270)
			(size 0.4064 0.508)
			(layers "F.Cu" "F.Mask" "F.Paste")
			(net "RST_PERST_CPU1_SWB_R_N")
		)
		(pad "2" smd rect
			(at -0.94996 0 270)
			(size 0.4064 0.508)
			(layers "F.Cu" "F.Mask" "F.Paste")
			(net "GND")
		)
		(pad "3" smd rect
			(at -0.94996 0.649986 270)
			(size 0.4064 0.508)
			(layers "F.Cu" "F.Mask" "F.Paste")
			(net "RST_PERST_CPU1_SWB_1_R_N")
		)
		(pad "4" smd rect
			(at 0.94996 0.649986 270)
			(size 0.4064 0.508)
			(layers "F.Cu" "F.Mask" "F.Paste")
			(net "RST_PERST_2_SWB_BUF_R_N")
		)
		(pad "5" smd rect
			(at 0.94996 0 270)
			(size 0.4064 0.508)
			(layers "F.Cu" "F.Mask" "F.Paste")
			(net "P3V3_AUX")
		)
		(pad "6" smd rect
			(at 0.94996 -0.649986 270)
			(size 0.4064 0.508)
			(layers "F.Cu" "F.Mask" "F.Paste")
			(net "RST_PERST_0_SWB_BUF_R_N")
		)
	)
	(footprint ""
		(layer "F.Cu")
		(at 105.960164 -260.305296)
		(property "Reference" "C2274"
			(at 0 0 0)
			(layer "F.SilkS")
			(hide yes)
			(effects
				(font
					(size 1.27 1.27)
				)
			)
		)
		(property "Value" ""
			(at 0 0 0)
			(layer "F.Fab")
			(effects
				(font
					(size 1.27 1.27)
				)
			)
		)
		(duplicate_pad_numbers_are_jumpers no)
		(fp_line
			(start -0.7874 -0.4064)
			(end 0.7874 -0.4064)
			(stroke
				(width 0.1524)
				(type default)
			)
			(layer "F.SilkS")
		)
		(fp_line
			(start -0.7874 0.4064)
			(end -0.7874 -0.4064)
			(stroke
				(width 0.1524)
				(type default)
			)
			(layer "F.SilkS")
		)
		(fp_line
			(start 0.7874 -0.4064)
			(end 0.7874 0.4064)
			(stroke
				(width 0.1524)
				(type default)
			)
			(layer "F.SilkS")
		)
		(fp_line
			(start 0.7874 0.4064)
			(end -0.7874 0.4064)
			(stroke
				(width 0.1524)
				(type default)
			)
			(layer "F.SilkS")
		)
		(fp_line
			(start -0.67945 -0.305054)
			(end -0.12065 -0.305054)
			(stroke
				(width 0.1)
				(type default)
			)
			(layer "F.Fab")
		)
		(fp_line
			(start -0.67945 0.3048)
			(end -0.67945 -0.305054)
			(stroke
				(width 0.1)
				(type default)
			)
			(layer "F.Fab")
		)
		(fp_line
			(start -0.12065 -0.305054)
			(end -0.12065 -0.2794)
			(stroke
				(width 0.1)
				(type default)
			)
			(layer "F.Fab")
		)
		(fp_line
			(start -0.12065 -0.2794)
			(end 0.12065 -0.2794)
			(stroke
				(width 0.1)
				(type default)
			)
			(layer "F.Fab")
		)
		(fp_line
			(start -0.12065 0.2794)
			(end -0.12065 0.3048)
			(stroke
				(width 0.1)
				(type default)
			)
			(layer "F.Fab")
		)
		(fp_line
			(start -0.12065 0.3048)
			(end -0.67945 0.3048)
			(stroke
				(width 0.1)
				(type default)
			)
			(layer "F.Fab")
		)
		(fp_line
			(start 0.120396 0.2794)
			(end -0.12065 0.2794)
			(stroke
				(width 0.1)
				(type default)
			)
			(layer "F.Fab")
		)
		(fp_line
			(start 0.120396 0.3048)
			(end 0.120396 0.2794)
			(stroke
				(width 0.1)
				(type default)
			)
			(layer "F.Fab")
		)
		(fp_line
			(start 0.12065 -0.3048)
			(end 0.67945 -0.3048)
			(stroke
				(width 0.1)
				(type default)
			)
			(layer "F.Fab")
		)
		(fp_line
			(start 0.12065 -0.2794)
			(end 0.12065 -0.3048)
			(stroke
				(width 0.1)
				(type default)
			)
			(layer "F.Fab")
		)
		(fp_line
			(start 0.67945 -0.3048)
			(end 0.67945 0.3048)
			(stroke
				(width 0.1)
				(type default)
			)
			(layer "F.Fab")
		)
		(fp_line
			(start 0.67945 0.3048)
			(end 0.120396 0.3048)
			(stroke
				(width 0.1)
				(type default)
			)
			(layer "F.Fab")
		)
		(pad "1" smd circle
			(at -0.40005 0)
			(size 0 0)
			(layers "F.Cu" "F.Mask" "F.Paste")
			(net "PVDDIO_P1")
		)
		(pad "2" smd circle
			(at 0.40005 0)
			(size 0 0)
			(layers "F.Cu" "F.Mask" "F.Paste")
			(net "GND")
		)
	)
	(footprint ""
		(layer "F.Cu")
		(at 423.62374 -359.836212 180)
		(property "Reference" "R124"
			(at 0 0 180)
			(layer "F.SilkS")
			(hide yes)
			(effects
				(font
					(size 1.27 1.27)
				)
			)
		)
		(property "Value" ""
			(at 0 0 180)
			(layer "F.Fab")
			(effects
				(font
					(size 1.27 1.27)
				)
			)
		)
		(duplicate_pad_numbers_are_jumpers no)
		(fp_line
			(start 0.7874 0.4064)
			(end -0.7874 0.4064)
			(stroke
				(width 0.1524)
				(type default)
			)
			(layer "F.SilkS")
		)
		(fp_line
			(start 0.7874 -0.4064)
			(end 0.7874 0.4064)
			(stroke
				(width 0.1524)
				(type default)
			)
			(layer "F.SilkS")
		)
		(fp_line
			(start -0.7874 0.4064)
			(end -0.7874 -0.4064)
			(stroke
				(width 0.1524)
				(type default)
			)
			(layer "F.SilkS")
		)
		(fp_line
			(start -0.7874 -0.4064)
			(end 0.7874 -0.4064)
			(stroke
				(width 0.1524)
				(type default)
			)
			(layer "F.SilkS")
		)
		(fp_line
			(start 0.67945 0.3048)
			(end 0.120396 0.3048)
			(stroke
				(width 0.1)
				(type default)
			)
			(layer "F.Fab")
		)
		(fp_line
			(start 0.67945 -0.3048)
			(end 0.67945 0.3048)
			(stroke
				(width 0.1)
				(type default)
			)
			(layer "F.Fab")
		)
		(fp_line
			(start 0.12065 -0.2794)
			(end 0.12065 -0.3048)
			(stroke
				(width 0.1)
				(type default)
			)
			(layer "F.Fab")
		)
		(fp_line
			(start 0.12065 -0.3048)
			(end 0.67945 -0.3048)
			(stroke
				(width 0.1)
				(type default)
			)
			(layer "F.Fab")
		)
		(fp_line
			(start 0.120396 0.3048)
			(end 0.120396 0.2794)
			(stroke
				(width 0.1)
				(type default)
			)
			(layer "F.Fab")
		)
		(fp_line
			(start 0.120396 0.2794)
			(end -0.12065 0.2794)
			(stroke
				(width 0.1)
				(type default)
			)
			(layer "F.Fab")
		)
		(fp_line
			(start -0.12065 0.3048)
			(end -0.67945 0.3048)
			(stroke
				(width 0.1)
				(type default)
			)
			(layer "F.Fab")
		)
		(fp_line
			(start -0.12065 0.2794)
			(end -0.12065 0.3048)
			(stroke
				(width 0.1)
				(type default)
			)
			(layer "F.Fab")
		)
		(fp_line
			(start -0.12065 -0.2794)
			(end 0.12065 -0.2794)
			(stroke
				(width 0.1)
				(type default)
			)
			(layer "F.Fab")
		)
		(fp_line
			(start -0.12065 -0.305054)
			(end -0.12065 -0.2794)
			(stroke
				(width 0.1)
				(type default)
			)
			(layer "F.Fab")
		)
		(fp_line
			(start -0.67945 0.3048)
			(end -0.67945 -0.305054)
			(stroke
				(width 0.1)
				(type default)
			)
			(layer "F.Fab")
		)
		(fp_line
			(start -0.67945 -0.305054)
			(end -0.12065 -0.305054)
			(stroke
				(width 0.1)
				(type default)
			)
			(layer "F.Fab")
		)
		(pad "1" smd circle
			(at -0.40005 0 180)
			(size 0 0)
			(layers "F.Cu" "F.Mask" "F.Paste")
			(net "PVDD18_S5_P0")
		)
		(pad "2" smd circle
			(at 0.40005 0 180)
			(size 0 0)
			(layers "F.Cu" "F.Mask" "F.Paste")
			(net "PVDD11_S3_P0_OCP_N_R")
		)
	)
	(footprint ""
		(layer "F.Cu")
		(at 166.548308 -352.278442 90)
		(property "Reference" "PC95"
			(at 0 0 90)
			(layer "F.SilkS")
			(hide yes)
			(effects
				(font
					(size 1.27 1.27)
				)
			)
		)
		(property "Value" ""
			(at 0 0 90)
			(layer "F.Fab")
			(effects
				(font
					(size 1.27 1.27)
				)
			)
		)
		(duplicate_pad_numbers_are_jumpers no)
		(fp_line
			(start 0.7874 -0.4064)
			(end 0.7874 0.4064)
			(stroke
				(width 0.1524)
				(type default)
			)
			(layer "F.SilkS")
		)
		(fp_line
			(start -0.7874 -0.4064)
			(end 0.7874 -0.4064)
			(stroke
				(width 0.1524)
				(type default)
			)
			(layer "F.SilkS")
		)
		(fp_line
			(start 0.7874 0.4064)
			(end -0.7874 0.4064)
			(stroke
				(width 0.1524)
				(type default)
			)
			(layer "F.SilkS")
		)
		(fp_line
			(start -0.7874 0.4064)
			(end -0.7874 -0.4064)
			(stroke
				(width 0.1524)
				(type default)
			)
			(layer "F.SilkS")
		)
		(fp_line
			(start -0.12065 -0.305054)
			(end -0.12065 -0.2794)
			(stroke
				(width 0.1)
				(type default)
			)
			(layer "F.Fab")
		)
		(fp_line
			(start -0.67945 -0.305054)
			(end -0.12065 -0.305054)
			(stroke
				(width 0.1)
				(type default)
			)
			(layer "F.Fab")
		)
		(fp_line
			(start 0.67945 -0.3048)
			(end 0.67945 0.3048)
			(stroke
				(width 0.1)
				(type default)
			)
			(layer "F.Fab")
		)
		(fp_line
			(start 0.12065 -0.3048)
			(end 0.67945 -0.3048)
			(stroke
				(width 0.1)
				(type default)
			)
			(layer "F.Fab")
		)
		(fp_line
			(start 0.12065 -0.2794)
			(end 0.12065 -0.3048)
			(stroke
				(width 0.1)
				(type default)
			)
			(layer "F.Fab")
		)
		(fp_line
			(start -0.12065 -0.2794)
			(end 0.12065 -0.2794)
			(stroke
				(width 0.1)
				(type default)
			)
			(layer "F.Fab")
		)
		(fp_line
			(start 0.120396 0.2794)
			(end -0.12065 0.2794)
			(stroke
				(width 0.1)
				(type default)
			)
			(layer "F.Fab")
		)
		(fp_line
			(start -0.12065 0.2794)
			(end -0.12065 0.3048)
			(stroke
				(width 0.1)
				(type default)
			)
			(layer "F.Fab")
		)
		(fp_line
			(start 0.67945 0.3048)
			(end 0.120396 0.3048)
			(stroke
				(width 0.1)
				(type default)
			)
			(layer "F.Fab")
		)
		(fp_line
			(start 0.120396 0.3048)
			(end 0.120396 0.2794)
			(stroke
				(width 0.1)
				(type default)
			)
			(layer "F.Fab")
		)
		(fp_line
			(start -0.12065 0.3048)
			(end -0.67945 0.3048)
			(stroke
				(width 0.1)
				(type default)
			)
			(layer "F.Fab")
		)
		(fp_line
			(start -0.67945 0.3048)
			(end -0.67945 -0.305054)
			(stroke
				(width 0.1)
				(type default)
			)
			(layer "F.Fab")
		)
		(pad "1" smd circle
			(at -0.40005 0 90)
			(size 0 0)
			(layers "F.Cu" "F.Mask" "F.Paste")
			(net "PVDD11_S3_P1_VCC")
		)
		(pad "2" smd circle
			(at 0.40005 0 90)
			(size 0 0)
			(layers "F.Cu" "F.Mask" "F.Paste")
			(net "GND")
		)
	)
	(footprint ""
		(layer "F.Cu")
		(at 330.371958 -193.163952 -90)
		(property "Reference" "R416"
			(at 0 0 270)
			(layer "F.SilkS")
			(hide yes)
			(effects
				(font
					(size 1.27 1.27)
				)
			)
		)
		(property "Value" ""
			(at 0 0 270)
			(layer "F.Fab")
			(effects
				(font
					(size 1.27 1.27)
				)
			)
		)
		(duplicate_pad_numbers_are_jumpers no)
		(fp_line
			(start -0.7874 0.4064)
			(end -0.7874 -0.4064)
			(stroke
				(width 0.1524)
				(type default)
			)
			(layer "F.SilkS")
		)
		(fp_line
			(start 0.7874 0.4064)
			(end -0.7874 0.4064)
			(stroke
				(width 0.1524)
				(type default)
			)
			(layer "F.SilkS")
		)
		(fp_line
			(start -0.7874 -0.4064)
			(end 0.7874 -0.4064)
			(stroke
				(width 0.1524)
				(type default)
			)
			(layer "F.SilkS")
		)
		(fp_line
			(start 0.7874 -0.4064)
			(end 0.7874 0.4064)
			(stroke
				(width 0.1524)
				(type default)
			)
			(layer "F.SilkS")
		)
		(fp_line
			(start -0.67945 0.3048)
			(end -0.67945 -0.305054)
			(stroke
				(width 0.1)
				(type default)
			)
			(layer "F.Fab")
		)
		(fp_line
			(start -0.12065 0.3048)
			(end -0.67945 0.3048)
			(stroke
				(width 0.1)
				(type default)
			)
			(layer "F.Fab")
		)
		(fp_line
			(start 0.120396 0.3048)
			(end 0.120396 0.2794)
			(stroke
				(width 0.1)
				(type default)
			)
			(layer "F.Fab")
		)
		(fp_line
			(start 0.67945 0.3048)
			(end 0.120396 0.3048)
			(stroke
				(width 0.1)
				(type default)
			)
			(layer "F.Fab")
		)
		(fp_line
			(start -0.12065 0.2794)
			(end -0.12065 0.3048)
			(stroke
				(width 0.1)
				(type default)
			)
			(layer "F.Fab")
		)
		(fp_line
			(start 0.120396 0.2794)
			(end -0.12065 0.2794)
			(stroke
				(width 0.1)
				(type default)
			)
			(layer "F.Fab")
		)
		(fp_line
			(start -0.12065 -0.2794)
			(end 0.12065 -0.2794)
			(stroke
				(width 0.1)
				(type default)
			)
			(layer "F.Fab")
		)
		(fp_line
			(start 0.12065 -0.2794)
			(end 0.12065 -0.3048)
			(stroke
				(width 0.1)
				(type default)
			)
			(layer "F.Fab")
		)
		(fp_line
			(start 0.12065 -0.3048)
			(end 0.67945 -0.3048)
			(stroke
				(width 0.1)
				(type default)
			)
			(layer "F.Fab")
		)
		(fp_line
			(start 0.67945 -0.3048)
			(end 0.67945 0.3048)
			(stroke
				(width 0.1)
				(type default)
			)
			(layer "F.Fab")
		)
		(fp_line
			(start -0.67945 -0.305054)
			(end -0.12065 -0.305054)
			(stroke
				(width 0.1)
				(type default)
			)
			(layer "F.Fab")
		)
		(fp_line
			(start -0.12065 -0.305054)
			(end -0.12065 -0.2794)
			(stroke
				(width 0.1)
				(type default)
			)
			(layer "F.Fab")
		)
		(pad "1" smd circle
			(at -0.40005 0 270)
			(size 0 0)
			(layers "F.Cu" "F.Mask" "F.Paste")
			(net "CPU0_XTRIG_L7")
		)
		(pad "2" smd circle
			(at 0.40005 0 270)
			(size 0 0)
			(layers "F.Cu" "F.Mask" "F.Paste")
			(net "PVDD18_S5_P0")
		)
	)
	(footprint ""
		(layer "F.Cu")
		(at 52.143406 -152.20823 180)
		(property "Reference" "PC83"
			(at 0 0 180)
			(layer "F.SilkS")
			(hide yes)
			(effects
				(font
					(size 1.27 1.27)
				)
			)
		)
		(property "Value" ""
			(at 0 0 180)
			(layer "F.Fab")
			(effects
				(font
					(size 1.27 1.27)
				)
			)
		)
		(duplicate_pad_numbers_are_jumpers no)
		(fp_line
			(start 1.524 0.762)
			(end -1.524 0.762)
			(stroke
				(width 0.1524)
				(type default)
			)
			(layer "F.SilkS")
		)
		(fp_line
			(start 1.524 -0.762)
			(end 1.524 0.762)
			(stroke
				(width 0.1524)
				(type default)
			)
			(layer "F.SilkS")
		)
		(fp_line
			(start -1.524 0.762)
			(end -1.524 -0.762)
			(stroke
				(width 0.1524)
				(type default)
			)
			(layer "F.SilkS")
		)
		(fp_line
			(start -1.524 -0.762)
			(end 1.524 -0.762)
			(stroke
				(width 0.1524)
				(type default)
			)
			(layer "F.SilkS")
		)
		(fp_line
			(start 1.1049 0.724916)
			(end 1.1049 -0.724916)
			(stroke
				(width 0.1)
				(type default)
			)
			(layer "F.Fab")
		)
		(fp_line
			(start 1.1049 -0.724916)
			(end -1.1049 -0.724916)
			(stroke
				(width 0.1)
				(type default)
			)
			(layer "F.Fab")
		)
		(fp_line
			(start -1.1049 0.724916)
			(end 1.1049 0.724916)
			(stroke
				(width 0.1)
				(type default)
			)
			(layer "F.Fab")
		)
		(fp_line
			(start -1.1049 -0.724916)
			(end -1.1049 0.724916)
			(stroke
				(width 0.1)
				(type default)
			)
			(layer "F.Fab")
		)
		(pad "1" smd rect
			(at -0.889 0)
			(size 1.016 1.27)
			(layers "F.Cu" "F.Mask" "F.Paste")
			(net "PVDD18_S5_P1")
		)
		(pad "2" smd rect
			(at 0.889 0)
			(size 1.016 1.27)
			(layers "F.Cu" "F.Mask" "F.Paste")
			(net "GND")
		)
	)
	(footprint ""
		(layer "F.Cu")
		(at 28.274772 -432.477164)
		(property "Reference" "U194"
			(at -4.766818 -2.04216 0)
			(unlocked yes)
			(layer "F.SilkS")
			(effects
				(font
					(size 0.7874 0.5842)
					(thickness 0.1524)
				)
				(justify left)
			)
		)
		(property "Value" ""
			(at 0 0 0)
			(layer "F.Fab")
			(effects
				(font
					(size 1.27 1.27)
				)
			)
		)
		(duplicate_pad_numbers_are_jumpers no)
		(fp_line
			(start -1.3716 -1.524)
			(end -0.508 -1.524)
			(stroke
				(width 0.1524)
				(type default)
			)
			(layer "F.SilkS")
		)
		(fp_line
			(start -1.3716 1.524)
			(end -1.3716 -1.524)
			(stroke
				(width 0.1524)
				(type default)
			)
			(layer "F.SilkS")
		)
		(fp_line
			(start -0.508 -1.524)
			(end 0 -1.016)
			(stroke
				(width 0.1524)
				(type default)
			)
			(layer "F.SilkS")
		)
		(fp_line
			(start 0 -1.016)
			(end 0.508 -1.524)
			(stroke
				(width 0.1524)
				(type default)
			)
			(layer "F.SilkS")
		)
		(fp_line
			(start 0.508 -1.524)
			(end 1.3716 -1.524)
			(stroke
				(width 0.1524)
				(type default)
			)
			(layer "F.SilkS")
		)
		(fp_line
			(start 1.3716 -1.524)
			(end 1.3716 1.524)
			(stroke
				(width 0.1524)
				(type default)
			)
			(layer "F.SilkS")
		)
		(fp_line
			(start 1.3716 1.524)
			(end -1.3716 1.524)
			(stroke
				(width 0.1524)
				(type default)
			)
			(layer "F.SilkS")
		)
		(fp_poly
			(pts
				(xy -3.651758 -1.010666) (xy -3.47345 -1.609598) (xy -3.03657 -1.137158)
			)
			(stroke
				(width 0)
				(type default)
			)
			(fill yes)
			(layer "F.SilkS")
		)
		(fp_line
			(start -2.54 -1.0668)
			(end -1.5494 -1.0668)
			(stroke
				(width 0.1)
				(type default)
			)
			(layer "F.Fab")
		)
		(fp_line
			(start -2.54 1.0668)
			(end -2.54 -1.0668)
			(stroke
				(width 0.1)
				(type default)
			)
			(layer "F.Fab")
		)
		(fp_line
			(start -1.5494 -1.524)
			(end 1.5494 -1.524)
			(stroke
				(width 0.1)
				(type default)
			)
			(layer "F.Fab")
		)
		(fp_line
			(start -1.5494 -1.0668)
			(end -1.5494 -1.524)
			(stroke
				(width 0.1)
				(type default)
			)
			(layer "F.Fab")
		)
		(fp_line
			(start -1.5494 1.0668)
			(end -2.54 1.0668)
			(stroke
				(width 0.1)
				(type default)
			)
			(layer "F.Fab")
		)
		(fp_line
			(start -1.5494 1.0668)
			(end -1.5494 -1.0668)
			(stroke
				(width 0.1)
				(type default)
			)
			(layer "F.Fab")
		)
		(fp_line
			(start -1.5494 1.524)
			(end -1.5494 1.0668)
			(stroke
				(width 0.1)
				(type default)
			)
			(layer "F.Fab")
		)
		(fp_line
			(start 1.5494 -1.524)
			(end 1.5494 -1.0668)
			(stroke
				(width 0.1)
				(type default)
			)
			(layer "F.Fab")
		)
		(fp_line
			(start 1.5494 -1.0668)
			(end 1.5494 1.0668)
			(stroke
				(width 0.1)
				(type default)
			)
			(layer "F.Fab")
		)
		(fp_line
			(start 1.5494 -1.0668)
			(end 2.54 -1.0668)
			(stroke
				(width 0.1)
				(type default)
			)
			(layer "F.Fab")
		)
		(fp_line
			(start 1.5494 1.0668)
			(end 1.5494 1.524)
			(stroke
				(width 0.1)
				(type default)
			)
			(layer "F.Fab")
		)
		(fp_line
			(start 1.5494 1.524)
			(end -1.5494 1.524)
			(stroke
				(width 0.1)
				(type default)
			)
			(layer "F.Fab")
		)
		(fp_line
			(start 2.54 -1.0668)
			(end 2.54 1.0668)
			(stroke
				(width 0.1)
				(type default)
			)
			(layer "F.Fab")
		)
		(fp_line
			(start 2.54 1.0668)
			(end 1.5494 1.0668)
			(stroke
				(width 0.1)
				(type default)
			)
			(layer "F.Fab")
		)
		(fp_poly
			(pts
				(xy -3.60172 -0.719328) (xy -3.60172 -1.344168) (xy -3.048 -1.016)
			)
			(stroke
				(width 0)
				(type default)
			)
			(fill yes)
			(layer "F.Fab")
		)
		(pad "1" smd rect
			(at -2.232406 -0.975106 270)
			(size 0.3556 1.4224)
			(layers "F.Cu" "F.Mask" "F.Paste")
			(net "SMB_BMC_GPU_EN_R1")
		)
		(pad "2" smd rect
			(at -2.232406 -0.32512 270)
			(size 0.3556 1.4224)
			(layers "F.Cu" "F.Mask" "F.Paste")
			(net "SMB_1_BMC_GPU_BUF_R_SCL")
		)
		(pad "3" smd rect
			(at -2.232406 0.32512 270)
			(size 0.3556 1.4224)
			(layers "F.Cu" "F.Mask" "F.Paste")
			(net "SMB_1_BMC_GPU_R_SCL")
		)
		(pad "4" smd rect
			(at -2.232406 0.975106 270)
			(size 0.3556 1.4224)
			(layers "F.Cu" "F.Mask" "F.Paste")
			(net "GND")
		)
		(pad "5" smd rect
			(at 2.232406 0.975106 270)
			(size 0.3556 1.4224)
			(layers "F.Cu" "F.Mask" "F.Paste")
			(net "Net_10760")
		)
		(pad "6" smd rect
			(at 2.232406 0.32512 270)
			(size 0.3556 1.4224)
			(layers "F.Cu" "F.Mask" "F.Paste")
			(net "SMB_1_BMC_GPU_R_SDA")
		)
		(pad "7" smd rect
			(at 2.232406 -0.32512 270)
			(size 0.3556 1.4224)
			(layers "F.Cu" "F.Mask" "F.Paste")
			(net "SMB_1_BMC_GPU_BUF_R_SDA")
		)
		(pad "8" smd rect
			(at 2.232406 -0.975106 270)
			(size 0.3556 1.4224)
			(layers "F.Cu" "F.Mask" "F.Paste")
			(net "P3V3_AUX")
		)
	)
	(footprint ""
		(layer "F.Cu")
		(at 414.529778 -163.76777 180)
		(property "Reference" "PU51"
			(at 5.373624 -4.878324 0)
			(unlocked yes)
			(layer "F.SilkS")
			(effects
				(font
					(size 0.7874 0.5842)
					(thickness 0.1524)
				)
				(justify left)
			)
		)
		(property "Value" ""
			(at 0 0 180)
			(layer "F.Fab")
			(effects
				(font
					(size 1.27 1.27)
				)
			)
		)
		(duplicate_pad_numbers_are_jumpers no)
		(fp_line
			(start 2.500122 2.999994)
			(end 2.2987 2.999994)
			(stroke
				(width 0.1524)
				(type default)
			)
			(layer "F.SilkS")
		)
		(fp_line
			(start 2.500122 2.339594)
			(end 2.500122 2.999994)
			(stroke
				(width 0.1524)
				(type default)
			)
			(layer "F.SilkS")
		)
		(fp_line
			(start 2.500122 -2.999994)
			(end 2.500122 -2.44348)
			(stroke
				(width 0.1524)
				(type default)
			)
			(layer "F.SilkS")
		)
		(fp_line
			(start 2.31394 -2.999994)
			(end 2.500122 -2.999994)
			(stroke
				(width 0.1524)
				(type default)
			)
			(layer "F.SilkS")
		)
		(fp_line
			(start -2.2987 2.999994)
			(end -2.500122 2.999994)
			(stroke
				(width 0.1524)
				(type default)
			)
			(layer "F.SilkS")
		)
		(fp_line
			(start -2.500122 2.999994)
			(end -2.500122 2.339594)
			(stroke
				(width 0.1524)
				(type default)
			)
			(layer "F.SilkS")
		)
		(fp_line
			(start -2.500122 0.6604)
			(end -2.500122 0.229108)
			(stroke
				(width 0.1524)
				(type default)
			)
			(layer "F.SilkS")
		)
		(fp_line
			(start -2.500122 -2.529078)
			(end -2.500122 -2.999994)
			(stroke
				(width 0.1524)
				(type default)
			)
			(layer "F.SilkS")
		)
		(fp_line
			(start -2.500122 -2.999994)
			(end -2.24409 -2.999994)
			(stroke
				(width 0.1524)
				(type default)
			)
			(layer "F.SilkS")
		)
		(fp_poly
			(pts
				(xy -2.637028 -2.515362) (xy -3.35026 -2.753106) (xy -2.874518 -3.228594)
			)
			(stroke
				(width 0)
				(type default)
			)
			(fill yes)
			(layer "F.SilkS")
		)
		(fp_line
			(start 2.500122 2.999994)
			(end -2.500122 2.999994)
			(stroke
				(width 0.1)
				(type default)
			)
			(layer "F.Fab")
		)
		(fp_line
			(start 2.500122 -2.999994)
			(end 2.500122 2.999994)
			(stroke
				(width 0.1)
				(type default)
			)
			(layer "F.Fab")
		)
		(fp_line
			(start -2.500122 2.999994)
			(end -2.500122 -2.999994)
			(stroke
				(width 0.1)
				(type default)
			)
			(layer "F.Fab")
		)
		(fp_line
			(start -2.500122 -2.999994)
			(end 2.500122 -2.999994)
			(stroke
				(width 0.1)
				(type default)
			)
			(layer "F.Fab")
		)
		(fp_poly
			(pts
				(xy -4.218432 -2.783078) (xy -4.218432 -1.767078) (xy -3.202432 -2.275078)
			)
			(stroke
				(width 0)
				(type default)
			)
			(fill yes)
			(layer "F.Fab")
		)
		(pad "1" smd rect
			(at -2.400046 -2.275078 270)
			(size 0.2286 0.6096)
			(layers "F.Cu" "F.Mask" "F.Paste")
			(net "PVDDCR_SOC_P0_VOS3")
		)
		(pad "2" smd rect
			(at -2.400046 -1.82499 270)
			(size 0.2286 0.6096)
			(layers "F.Cu" "F.Mask" "F.Paste")
			(net "GND")
		)
		(pad "3" smd rect
			(at -2.400046 -1.374902 270)
			(size 0.2286 0.6096)
			(layers "F.Cu" "F.Mask" "F.Paste")
			(net "PVDDCR_SOC_P0_VCC3")
		)
		(pad "4" smd rect
			(at -2.400046 -0.925068 270)
			(size 0.2286 0.6096)
			(layers "F.Cu" "F.Mask" "F.Paste")
			(net "PVDDCR_CPU0_P0_PVCC")
		)
		(pad "5" smd rect
			(at -2.400046 -0.47498 270)
			(size 0.2286 0.6096)
			(layers "F.Cu" "F.Mask" "F.Paste")
			(net "GND")
		)
		(pad "6" smd rect
			(at -2.400046 -0.024892 270)
			(size 0.2286 0.6096)
			(layers "F.Cu" "F.Mask" "F.Paste")
			(net "NC_PVDDCR_SOC_P0_GL1_3")
		)
		(pad "7_9-20_24" smd circle
			(at 0 1.150112 270)
			(size 0 0)
			(layers "F.Cu" "F.Mask" "F.Paste")
			(net "GND")
		)
		(pad "10_19" smd rect
			(at 0 2.899918 270)
			(size 0.6096 4.318)
			(layers "F.Cu" "F.Mask" "F.Paste")
			(net "SW_PVDDCR_SOC_P0_SW3")
		)
		(pad "25_29" smd rect
			(at 1.549908 -1.279906 90)
			(size 2.0574 2.3114)
			(layers "F.Cu" "F.Mask" "F.Paste")
			(net "SW_P12V_AUX_PVDDCR_SOC_P0_FLT")
		)
		(pad "30" smd rect
			(at 2.05994 -2.899918 180)
			(size 0.2286 0.6096)
			(layers "F.Cu" "F.Mask" "F.Paste")
			(net "SW_P12V_AUX_PVDDCR_SOC_P0_FLT")
		)
		(pad "31" smd rect
			(at 1.610106 -2.899918 180)
			(size 0.2286 0.6096)
			(layers "F.Cu" "F.Mask" "F.Paste")
			(net "NC_PVDDCR_SOC_P0_DNC3")
		)
		(pad "32" smd rect
			(at 1.160018 -2.899918 180)
			(size 0.2286 0.6096)
			(layers "F.Cu" "F.Mask" "F.Paste")
			(net "SW_PVDDCR_SOC_P0_PH3")
		)
		(pad "33" smd rect
			(at 0.70993 -2.899918 180)
			(size 0.2286 0.6096)
			(layers "F.Cu" "F.Mask" "F.Paste")
			(net "SW_PVDDCR_SOC_P0_BOOT3")
		)
		(pad "34" smd rect
			(at 0.260096 -2.899918 180)
			(size 0.2286 0.6096)
			(layers "F.Cu" "F.Mask" "F.Paste")
			(net "PVDDCR_SOC_P0_PWM3")
		)
		(pad "35" smd rect
			(at -0.189992 -2.899918 180)
			(size 0.2286 0.6096)
			(layers "F.Cu" "F.Mask" "F.Paste")
			(net "PVDDCR_SOC_P0_VCC3")
		)
		(pad "36" smd rect
			(at -0.64008 -2.899918 180)
			(size 0.2286 0.6096)
			(layers "F.Cu" "F.Mask" "F.Paste")
			(net "PVDDCR_SOC_P0_TEMP1")
		)
		(pad "37" smd rect
			(at -1.089914 -2.899918 180)
			(size 0.2286 0.6096)
			(layers "F.Cu" "F.Mask" "F.Paste")
			(net "PVDDCR_SOC_P0_LSET3")
		)
		(pad "38" smd rect
			(at -1.540002 -2.899918 180)
			(size 0.2286 0.6096)
			(layers "F.Cu" "F.Mask" "F.Paste")
			(net "PVDDCR_SOC_P0_IMON3")
		)
		(pad "39" smd rect
			(at -1.99009 -2.899918 180)
			(size 0.2286 0.6096)
			(layers "F.Cu" "F.Mask" "F.Paste")
			(net "PVDDCR_CPU0_P0_VCCS")
		)
		(pad "40" smd rect
			(at -0.87503 -1.27508 180)
			(size 1.7526 1.9558)
			(layers "F.Cu" "F.Mask" "F.Paste")
			(net "GND")
		)
		(pad "41" smd rect
			(at -1.525016 0.249936 90)
			(size 0.3048 0.4572)
			(layers "F.Cu" "F.Mask" "F.Paste")
			(net "NC_PVDDCR_SOC_P0_GL2_3")
		)
		(zone
			(layer "F.Cu")
			(hatch none 0.5)
			(connect_pads
				(clearance 0)
			)
			(min_thickness 0.25)
			(keepout
				(tracks not_allowed)
				(vias allowed)
				(pads allowed)
				(copperpour not_allowed)
				(footprints allowed)
			)
			(placement
				(enabled no)
				(sheetname "")
			)
			(fill
				(thermal_gap 0.5)
				(thermal_bridge_width 0.5)
				(island_removal_mode 0)
			)
			(polygon
				(pts
					(xy 417.0299 -166.345108) (xy 417.0299 -166.018464) (xy 412.029656 -166.018464) (xy 412.029656 -166.331646)
					(xy 412.319978 -166.331646) (xy 412.319978 -166.312088) (xy 416.739578 -166.312088) (xy 416.739578 -166.345108)
				)
			)
		)
		(zone
			(layer "F.Cu")
			(hatch none 0.5)
			(connect_pads
				(clearance 0)
			)
			(min_thickness 0.25)
			(keepout
				(tracks not_allowed)
				(vias allowed)
				(pads allowed)
				(copperpour not_allowed)
				(footprints allowed)
			)
			(placement
				(enabled no)
				(sheetname "")
			)
			(fill
				(thermal_gap 0.5)
				(thermal_bridge_width 0.5)
				(island_removal_mode 0)
			)
			(polygon
				(pts
					(xy 414.477708 -163.52139) (xy 414.477708 -161.46399) (xy 416.331908 -161.46399) (xy 416.331908 -161.705036)
					(xy 416.574224 -161.705036) (xy 416.574224 -161.223452) (xy 412.722822 -161.223452) (xy 412.722822 -161.408364)
					(xy 414.18637 -161.408364) (xy 414.18637 -163.567364) (xy 412.029656 -163.567364) (xy 412.029656 -163.817046)
					(xy 414.182052 -163.817046)
				)
			)
		)
	)
	(footprint ""
		(layer "F.Cu")
		(at 259.070094 -141.968728 90)
		(property "Reference" "R604"
			(at 0 0 90)
			(layer "F.SilkS")
			(hide yes)
			(effects
				(font
					(size 1.27 1.27)
				)
			)
		)
		(property "Value" ""
			(at 0 0 90)
			(layer "F.Fab")
			(effects
				(font
					(size 1.27 1.27)
				)
			)
		)
		(duplicate_pad_numbers_are_jumpers no)
		(fp_line
			(start 0.7874 -0.4064)
			(end 0.7874 0.4064)
			(stroke
				(width 0.1524)
				(type default)
			)
			(layer "F.SilkS")
		)
		(fp_line
			(start -0.7874 -0.4064)
			(end 0.7874 -0.4064)
			(stroke
				(width 0.1524)
				(type default)
			)
			(layer "F.SilkS")
		)
		(fp_line
			(start 0.7874 0.4064)
			(end -0.7874 0.4064)
			(stroke
				(width 0.1524)
				(type default)
			)
			(layer "F.SilkS")
		)
		(fp_line
			(start -0.7874 0.4064)
			(end -0.7874 -0.4064)
			(stroke
				(width 0.1524)
				(type default)
			)
			(layer "F.SilkS")
		)
		(fp_line
			(start -0.12065 -0.305054)
			(end -0.12065 -0.2794)
			(stroke
				(width 0.1)
				(type default)
			)
			(layer "F.Fab")
		)
		(fp_line
			(start -0.67945 -0.305054)
			(end -0.12065 -0.305054)
			(stroke
				(width 0.1)
				(type default)
			)
			(layer "F.Fab")
		)
		(fp_line
			(start 0.67945 -0.3048)
			(end 0.67945 0.3048)
			(stroke
				(width 0.1)
				(type default)
			)
			(layer "F.Fab")
		)
		(fp_line
			(start 0.12065 -0.3048)
			(end 0.67945 -0.3048)
			(stroke
				(width 0.1)
				(type default)
			)
			(layer "F.Fab")
		)
		(fp_line
			(start 0.12065 -0.2794)
			(end 0.12065 -0.3048)
			(stroke
				(width 0.1)
				(type default)
			)
			(layer "F.Fab")
		)
		(fp_line
			(start -0.12065 -0.2794)
			(end 0.12065 -0.2794)
			(stroke
				(width 0.1)
				(type default)
			)
			(layer "F.Fab")
		)
		(fp_line
			(start 0.120396 0.2794)
			(end -0.12065 0.2794)
			(stroke
				(width 0.1)
				(type default)
			)
			(layer "F.Fab")
		)
		(fp_line
			(start -0.12065 0.2794)
			(end -0.12065 0.3048)
			(stroke
				(width 0.1)
				(type default)
			)
			(layer "F.Fab")
		)
		(fp_line
			(start 0.67945 0.3048)
			(end 0.120396 0.3048)
			(stroke
				(width 0.1)
				(type default)
			)
			(layer "F.Fab")
		)
		(fp_line
			(start 0.120396 0.3048)
			(end 0.120396 0.2794)
			(stroke
				(width 0.1)
				(type default)
			)
			(layer "F.Fab")
		)
		(fp_line
			(start -0.12065 0.3048)
			(end -0.67945 0.3048)
			(stroke
				(width 0.1)
				(type default)
			)
			(layer "F.Fab")
		)
		(fp_line
			(start -0.67945 0.3048)
			(end -0.67945 -0.305054)
			(stroke
				(width 0.1)
				(type default)
			)
			(layer "F.Fab")
		)
		(pad "1" smd circle
			(at -0.40005 0 90)
			(size 0 0)
			(layers "F.Cu" "F.Mask" "F.Paste")
			(net "SPI_CPU0_LVC3_D0")
		)
		(pad "2" smd circle
			(at 0.40005 0 90)
			(size 0 0)
			(layers "F.Cu" "F.Mask" "F.Paste")
			(net "SPI_CPU0_LVC3_SCM_D0")
		)
	)
	(footprint ""
		(layer "F.Cu")
		(at 185.49874 -133.548882 -90)
		(property "Reference" "R219"
			(at 0 0 270)
			(layer "F.SilkS")
			(hide yes)
			(effects
				(font
					(size 1.27 1.27)
				)
			)
		)
		(property "Value" ""
			(at 0 0 270)
			(layer "F.Fab")
			(effects
				(font
					(size 1.27 1.27)
				)
			)
		)
		(duplicate_pad_numbers_are_jumpers no)
		(fp_line
			(start -0.7874 0.4064)
			(end -0.7874 -0.4064)
			(stroke
				(width 0.1524)
				(type default)
			)
			(layer "F.SilkS")
		)
		(fp_line
			(start 0.7874 0.4064)
			(end -0.7874 0.4064)
			(stroke
				(width 0.1524)
				(type default)
			)
			(layer "F.SilkS")
		)
		(fp_line
			(start -0.7874 -0.4064)
			(end 0.7874 -0.4064)
			(stroke
				(width 0.1524)
				(type default)
			)
			(layer "F.SilkS")
		)
		(fp_line
			(start 0.7874 -0.4064)
			(end 0.7874 0.4064)
			(stroke
				(width 0.1524)
				(type default)
			)
			(layer "F.SilkS")
		)
		(fp_line
			(start -0.67945 0.3048)
			(end -0.67945 -0.305054)
			(stroke
				(width 0.1)
				(type default)
			)
			(layer "F.Fab")
		)
		(fp_line
			(start -0.12065 0.3048)
			(end -0.67945 0.3048)
			(stroke
				(width 0.1)
				(type default)
			)
			(layer "F.Fab")
		)
		(fp_line
			(start 0.120396 0.3048)
			(end 0.120396 0.2794)
			(stroke
				(width 0.1)
				(type default)
			)
			(layer "F.Fab")
		)
		(fp_line
			(start 0.67945 0.3048)
			(end 0.120396 0.3048)
			(stroke
				(width 0.1)
				(type default)
			)
			(layer "F.Fab")
		)
		(fp_line
			(start -0.12065 0.2794)
			(end -0.12065 0.3048)
			(stroke
				(width 0.1)
				(type default)
			)
			(layer "F.Fab")
		)
		(fp_line
			(start 0.120396 0.2794)
			(end -0.12065 0.2794)
			(stroke
				(width 0.1)
				(type default)
			)
			(layer "F.Fab")
		)
		(fp_line
			(start -0.12065 -0.2794)
			(end 0.12065 -0.2794)
			(stroke
				(width 0.1)
				(type default)
			)
			(layer "F.Fab")
		)
		(fp_line
			(start 0.12065 -0.2794)
			(end 0.12065 -0.3048)
			(stroke
				(width 0.1)
				(type default)
			)
			(layer "F.Fab")
		)
		(fp_line
			(start 0.12065 -0.3048)
			(end 0.67945 -0.3048)
			(stroke
				(width 0.1)
				(type default)
			)
			(layer "F.Fab")
		)
		(fp_line
			(start 0.67945 -0.3048)
			(end 0.67945 0.3048)
			(stroke
				(width 0.1)
				(type default)
			)
			(layer "F.Fab")
		)
		(fp_line
			(start -0.67945 -0.305054)
			(end -0.12065 -0.305054)
			(stroke
				(width 0.1)
				(type default)
			)
			(layer "F.Fab")
		)
		(fp_line
			(start -0.12065 -0.305054)
			(end -0.12065 -0.2794)
			(stroke
				(width 0.1)
				(type default)
			)
			(layer "F.Fab")
		)
		(pad "1" smd circle
			(at -0.40005 0 270)
			(size 0 0)
			(layers "F.Cu" "F.Mask" "F.Paste")
			(net "CPU0_NMI_SYNC_FLOOD_N")
		)
		(pad "2" smd circle
			(at 0.40005 0 270)
			(size 0 0)
			(layers "F.Cu" "F.Mask" "F.Paste")
			(net "FM_CPU0_NMI_SYNC_FLOOD_N")
		)
	)
	(footprint ""
		(layer "F.Cu")
		(at 102.6668 -396.6972 90)
		(property "Reference" "R673"
			(at 0 0 90)
			(layer "F.SilkS")
			(hide yes)
			(effects
				(font
					(size 1.27 1.27)
				)
			)
		)
		(property "Value" ""
			(at 0 0 90)
			(layer "F.Fab")
			(effects
				(font
					(size 1.27 1.27)
				)
			)
		)
		(duplicate_pad_numbers_are_jumpers no)
		(fp_line
			(start 0.32512 -0.175006)
			(end 0.32512 0.175006)
			(stroke
				(width 0.1)
				(type default)
			)
			(layer "F.Fab")
		)
		(fp_line
			(start -0.32512 -0.175006)
			(end 0.32512 -0.175006)
			(stroke
				(width 0.1)
				(type default)
			)
			(layer "F.Fab")
		)
		(fp_line
			(start 0.32512 0.175006)
			(end -0.32512 0.175006)
			(stroke
				(width 0.1)
				(type default)
			)
			(layer "F.Fab")
		)
		(fp_line
			(start -0.32512 0.175006)
			(end -0.32512 -0.175006)
			(stroke
				(width 0.1)
				(type default)
			)
			(layer "F.Fab")
		)
		(pad "1" smd rect
			(at -0.2667 0 90)
			(size 0.3048 0.381)
			(layers "F.Cu" "F.Mask" "F.Paste")
			(net "SMB_RT_CPU1_P0_ROM_R_SDA")
		)
		(pad "2" smd rect
			(at 0.2667 0 270)
			(size 0.3048 0.381)
			(layers "F.Cu" "F.Mask" "F.Paste")
			(net "SMB_RT_CPU1_P0_ROM_SDA")
		)
	)
	(footprint ""
		(layer "F.Cu")
		(at 42.3672 -378.71654)
		(property "Reference" "R674"
			(at 0 0 0)
			(layer "F.SilkS")
			(hide yes)
			(effects
				(font
					(size 1.27 1.27)
				)
			)
		)
		(property "Value" ""
			(at 0 0 0)
			(layer "F.Fab")
			(effects
				(font
					(size 1.27 1.27)
				)
			)
		)
		(duplicate_pad_numbers_are_jumpers no)
		(fp_line
			(start -0.32512 -0.175006)
			(end 0.32512 -0.175006)
			(stroke
				(width 0.1)
				(type default)
			)
			(layer "F.Fab")
		)
		(fp_line
			(start -0.32512 0.175006)
			(end -0.32512 -0.175006)
			(stroke
				(width 0.1)
				(type default)
			)
			(layer "F.Fab")
		)
		(fp_line
			(start 0.32512 -0.175006)
			(end 0.32512 0.175006)
			(stroke
				(width 0.1)
				(type default)
			)
			(layer "F.Fab")
		)
		(fp_line
			(start 0.32512 0.175006)
			(end -0.32512 0.175006)
			(stroke
				(width 0.1)
				(type default)
			)
			(layer "F.Fab")
		)
		(pad "1" smd rect
			(at -0.2667 0)
			(size 0.3048 0.381)
			(layers "F.Cu" "F.Mask" "F.Paste")
			(net "SMB_RT_CPU1_P0_ROM_MUX_1D_SCL")
		)
		(pad "2" smd rect
			(at 0.2667 0 180)
			(size 0.3048 0.381)
			(layers "F.Cu" "F.Mask" "F.Paste")
			(net "SMB_RT_CPU1_P0_ROM_MUX_1D_R_SCL")
		)
	)
	(footprint ""
		(layer "F.Cu")
		(at 335.05902 -334.973676)
		(property "Reference" "PU13"
			(at -2.95402 -7.772654 0)
			(unlocked yes)
			(layer "F.SilkS")
			(effects
				(font
					(size 0.7874 0.5842)
					(thickness 0.1524)
				)
				(justify left)
			)
		)
		(property "Value" ""
			(at 0 0 0)
			(layer "F.Fab")
			(effects
				(font
					(size 1.27 1.27)
				)
			)
		)
		(duplicate_pad_numbers_are_jumpers no)
		(fp_line
			(start -2.500122 -2.999994)
			(end -2.24409 -2.999994)
			(stroke
				(width 0.1524)
				(type default)
			)
			(layer "F.SilkS")
		)
		(fp_line
			(start -2.500122 -2.529078)
			(end -2.500122 -2.999994)
			(stroke
				(width 0.1524)
				(type default)
			)
			(layer "F.SilkS")
		)
		(fp_line
			(start -2.500122 0.6604)
			(end -2.500122 0.229108)
			(stroke
				(width 0.1524)
				(type default)
			)
			(layer "F.SilkS")
		)
		(fp_line
			(start -2.500122 2.999994)
			(end -2.500122 2.339594)
			(stroke
				(width 0.1524)
				(type default)
			)
			(layer "F.SilkS")
		)
		(fp_line
			(start -2.2987 2.999994)
			(end -2.500122 2.999994)
			(stroke
				(width 0.1524)
				(type default)
			)
			(layer "F.SilkS")
		)
		(fp_line
			(start 2.31394 -2.999994)
			(end 2.500122 -2.999994)
			(stroke
				(width 0.1524)
				(type default)
			)
			(layer "F.SilkS")
		)
		(fp_line
			(start 2.500122 -2.999994)
			(end 2.500122 -2.44348)
			(stroke
				(width 0.1524)
				(type default)
			)
			(layer "F.SilkS")
		)
		(fp_line
			(start 2.500122 2.339594)
			(end 2.500122 2.999994)
			(stroke
				(width 0.1524)
				(type default)
			)
			(layer "F.SilkS")
		)
		(fp_line
			(start 2.500122 2.999994)
			(end 2.2987 2.999994)
			(stroke
				(width 0.1524)
				(type default)
			)
			(layer "F.SilkS")
		)
		(fp_poly
			(pts
				(xy -2.77114 -2.42824) (xy -3.444748 -2.652776) (xy -2.995676 -3.101848)
			)
			(stroke
				(width 0)
				(type default)
			)
			(fill yes)
			(layer "F.SilkS")
		)
		(fp_line
			(start -2.500122 -2.999994)
			(end 2.500122 -2.999994)
			(stroke
				(width 0.1)
				(type default)
			)
			(layer "F.Fab")
		)
		(fp_line
			(start -2.500122 2.999994)
			(end -2.500122 -2.999994)
			(stroke
				(width 0.1)
				(type default)
			)
			(layer "F.Fab")
		)
		(fp_line
			(start 2.500122 -2.999994)
			(end 2.500122 2.999994)
			(stroke
				(width 0.1)
				(type default)
			)
			(layer "F.Fab")
		)
		(fp_line
			(start 2.500122 2.999994)
			(end -2.500122 2.999994)
			(stroke
				(width 0.1)
				(type default)
			)
			(layer "F.Fab")
		)
		(fp_poly
			(pts
				(xy -4.218432 -2.783078) (xy -4.218432 -1.767078) (xy -3.202432 -2.275078)
			)
			(stroke
				(width 0)
				(type default)
			)
			(fill yes)
			(layer "F.Fab")
		)
		(pad "1" smd rect
			(at -2.400046 -2.275078 90)
			(size 0.2286 0.6096)
			(layers "F.Cu" "F.Mask" "F.Paste")
			(net "PVDDCR_CPU1_P0_VOS1")
		)
		(pad "2" smd rect
			(at -2.400046 -1.82499 90)
			(size 0.2286 0.6096)
			(layers "F.Cu" "F.Mask" "F.Paste")
			(net "GND")
		)
		(pad "3" smd rect
			(at -2.400046 -1.374902 90)
			(size 0.2286 0.6096)
			(layers "F.Cu" "F.Mask" "F.Paste")
			(net "PVDDCR_CPU1_P0_VCC1")
		)
		(pad "4" smd rect
			(at -2.400046 -0.925068 90)
			(size 0.2286 0.6096)
			(layers "F.Cu" "F.Mask" "F.Paste")
			(net "PVDDCR_CPU1_P0_PVCC")
		)
		(pad "5" smd rect
			(at -2.400046 -0.47498 90)
			(size 0.2286 0.6096)
			(layers "F.Cu" "F.Mask" "F.Paste")
			(net "GND")
		)
		(pad "6" smd rect
			(at -2.400046 -0.024892 90)
			(size 0.2286 0.6096)
			(layers "F.Cu" "F.Mask" "F.Paste")
			(net "NC_PVDDCR_CPU1_P0_GL1_1")
		)
		(pad "7_9-20_24" smd circle
			(at 0 1.150112 90)
			(size 0 0)
			(layers "F.Cu" "F.Mask" "F.Paste")
			(net "GND")
		)
		(pad "10_19" smd rect
			(at 0 2.899918 90)
			(size 0.6096 4.318)
			(layers "F.Cu" "F.Mask" "F.Paste")
			(net "SW_PVDDCR_CPU1_P0_SW1")
		)
		(pad "25_29" smd rect
			(at 1.549908 -1.279906 270)
			(size 2.0574 2.3114)
			(layers "F.Cu" "F.Mask" "F.Paste")
			(net "SW_P12V_AUX_PVDDCR_CPU1_P0_FLT")
		)
		(pad "30" smd rect
			(at 2.05994 -2.899918)
			(size 0.2286 0.6096)
			(layers "F.Cu" "F.Mask" "F.Paste")
			(net "SW_P12V_AUX_PVDDCR_CPU1_P0_FLT")
		)
		(pad "31" smd rect
			(at 1.610106 -2.899918)
			(size 0.2286 0.6096)
			(layers "F.Cu" "F.Mask" "F.Paste")
			(net "NC_PVDDCR_CPU1_P0_DNC1")
		)
		(pad "32" smd rect
			(at 1.160018 -2.899918)
			(size 0.2286 0.6096)
			(layers "F.Cu" "F.Mask" "F.Paste")
			(net "SW_PVDDCR_CPU1_P0_BOOTR1")
		)
		(pad "33" smd rect
			(at 0.70993 -2.899918)
			(size 0.2286 0.6096)
			(layers "F.Cu" "F.Mask" "F.Paste")
			(net "SW_PVDDCR_CPU1_P0_BOOT1")
		)
		(pad "34" smd rect
			(at 0.260096 -2.899918)
			(size 0.2286 0.6096)
			(layers "F.Cu" "F.Mask" "F.Paste")
			(net "PVDDCR_CPU1_P0_PWM1")
		)
		(pad "35" smd rect
			(at -0.189992 -2.899918)
			(size 0.2286 0.6096)
			(layers "F.Cu" "F.Mask" "F.Paste")
			(net "PVDDCR_CPU1_P0_VCC1")
		)
		(pad "36" smd rect
			(at -0.64008 -2.899918)
			(size 0.2286 0.6096)
			(layers "F.Cu" "F.Mask" "F.Paste")
			(net "PVDDCR_CPU1_P0_TEMP0")
		)
		(pad "37" smd rect
			(at -1.089914 -2.899918)
			(size 0.2286 0.6096)
			(layers "F.Cu" "F.Mask" "F.Paste")
			(net "PVDDCR_CPU1_P0_LSET1")
		)
		(pad "38" smd rect
			(at -1.540002 -2.899918)
			(size 0.2286 0.6096)
			(layers "F.Cu" "F.Mask" "F.Paste")
			(net "PVDDCR_CPU1_P0_IMON1")
		)
		(pad "39" smd rect
			(at -1.99009 -2.899918)
			(size 0.2286 0.6096)
			(layers "F.Cu" "F.Mask" "F.Paste")
			(net "PVDDCR_CPU1_P0_VCCS")
		)
		(pad "40" smd rect
			(at -0.87503 -1.27508)
			(size 1.7526 1.9558)
			(layers "F.Cu" "F.Mask" "F.Paste")
			(net "GND")
		)
		(pad "41" smd rect
			(at -1.525016 0.249936 270)
			(size 0.3048 0.4572)
			(layers "F.Cu" "F.Mask" "F.Paste")
			(net "NC_PVDDCR_CPU1_P0_GL2_1")
		)
		(zone
			(layer "F.Cu")
			(hatch none 0.5)
			(connect_pads
				(clearance 0)
			)
			(min_thickness 0.25)
			(keepout
				(tracks not_allowed)
				(vias allowed)
				(pads allowed)
				(copperpour not_allowed)
				(footprints allowed)
			)
			(placement
				(enabled no)
				(sheetname "")
			)
			(fill
				(thermal_gap 0.5)
				(thermal_bridge_width 0.5)
				(island_removal_mode 0)
			)
			(polygon
				(pts
					(xy 332.558898 -332.3971) (xy 332.558898 -332.722982) (xy 337.559142 -332.722982) (xy 337.559142 -332.41234)
					(xy 337.26882 -332.41234) (xy 337.26882 -332.429358) (xy 332.84922 -332.429358) (xy 332.84922 -332.3971)
				)
			)
		)
		(zone
			(layer "F.Cu")
			(hatch none 0.5)
			(connect_pads
				(clearance 0)
			)
			(min_thickness 0.25)
			(keepout
				(tracks not_allowed)
				(vias allowed)
				(pads allowed)
				(copperpour not_allowed)
				(footprints allowed)
			)
			(placement
				(enabled no)
				(sheetname "")
			)
			(fill
				(thermal_gap 0.5)
				(thermal_bridge_width 0.5)
				(island_removal_mode 0)
			)
			(polygon
				(pts
					(xy 335.11109 -335.220056) (xy 335.11109 -337.277456) (xy 333.25689 -337.277456) (xy 333.25689 -337.03641)
					(xy 333.014574 -337.03641) (xy 333.014574 -337.517994) (xy 336.841846 -337.517994) (xy 336.841846 -337.333082)
					(xy 335.402428 -337.333082) (xy 335.402428 -335.174082) (xy 337.559142 -335.174082) (xy 337.559142 -334.9244)
					(xy 335.406746 -334.9244)
				)
			)
		)
	)
	(footprint ""
		(layer "F.Cu")
		(at 102.75697 -182.694834 90)
		(property "Reference" "PC288_C0P1_3"
			(at 0 0 90)
			(layer "F.SilkS")
			(hide yes)
			(effects
				(font
					(size 1.27 1.27)
				)
			)
		)
		(property "Value" ""
			(at 0 0 90)
			(layer "F.Fab")
			(effects
				(font
					(size 1.27 1.27)
				)
			)
		)
		(duplicate_pad_numbers_are_jumpers no)
		(fp_line
			(start 0.7874 -0.4064)
			(end 0.7874 0.4064)
			(stroke
				(width 0.1524)
				(type default)
			)
			(layer "F.SilkS")
		)
		(fp_line
			(start -0.7874 -0.4064)
			(end 0.7874 -0.4064)
			(stroke
				(width 0.1524)
				(type default)
			)
			(layer "F.SilkS")
		)
		(fp_line
			(start 0.7874 0.4064)
			(end -0.7874 0.4064)
			(stroke
				(width 0.1524)
				(type default)
			)
			(layer "F.SilkS")
		)
		(fp_line
			(start -0.7874 0.4064)
			(end -0.7874 -0.4064)
			(stroke
				(width 0.1524)
				(type default)
			)
			(layer "F.SilkS")
		)
		(fp_line
			(start -0.12065 -0.305054)
			(end -0.12065 -0.2794)
			(stroke
				(width 0.1)
				(type default)
			)
			(layer "F.Fab")
		)
		(fp_line
			(start -0.67945 -0.305054)
			(end -0.12065 -0.305054)
			(stroke
				(width 0.1)
				(type default)
			)
			(layer "F.Fab")
		)
		(fp_line
			(start 0.67945 -0.3048)
			(end 0.67945 0.3048)
			(stroke
				(width 0.1)
				(type default)
			)
			(layer "F.Fab")
		)
		(fp_line
			(start 0.12065 -0.3048)
			(end 0.67945 -0.3048)
			(stroke
				(width 0.1)
				(type default)
			)
			(layer "F.Fab")
		)
		(fp_line
			(start 0.12065 -0.2794)
			(end 0.12065 -0.3048)
			(stroke
				(width 0.1)
				(type default)
			)
			(layer "F.Fab")
		)
		(fp_line
			(start -0.12065 -0.2794)
			(end 0.12065 -0.2794)
			(stroke
				(width 0.1)
				(type default)
			)
			(layer "F.Fab")
		)
		(fp_line
			(start 0.120396 0.2794)
			(end -0.12065 0.2794)
			(stroke
				(width 0.1)
				(type default)
			)
			(layer "F.Fab")
		)
		(fp_line
			(start -0.12065 0.2794)
			(end -0.12065 0.3048)
			(stroke
				(width 0.1)
				(type default)
			)
			(layer "F.Fab")
		)
		(fp_line
			(start 0.67945 0.3048)
			(end 0.120396 0.3048)
			(stroke
				(width 0.1)
				(type default)
			)
			(layer "F.Fab")
		)
		(fp_line
			(start 0.120396 0.3048)
			(end 0.120396 0.2794)
			(stroke
				(width 0.1)
				(type default)
			)
			(layer "F.Fab")
		)
		(fp_line
			(start -0.12065 0.3048)
			(end -0.67945 0.3048)
			(stroke
				(width 0.1)
				(type default)
			)
			(layer "F.Fab")
		)
		(fp_line
			(start -0.67945 0.3048)
			(end -0.67945 -0.305054)
			(stroke
				(width 0.1)
				(type default)
			)
			(layer "F.Fab")
		)
		(pad "1" smd circle
			(at -0.40005 0 90)
			(size 0 0)
			(layers "F.Cu" "F.Mask" "F.Paste")
			(net "PVDDCR_CPU0_P1_PVCC")
		)
		(pad "2" smd circle
			(at 0.40005 0 90)
			(size 0 0)
			(layers "F.Cu" "F.Mask" "F.Paste")
			(net "GND")
		)
	)
	(footprint ""
		(layer "F.Cu")
		(at 169.38879 -103.31577 90)
		(property "Reference" "R6185"
			(at 0 0 90)
			(layer "F.SilkS")
			(hide yes)
			(effects
				(font
					(size 1.27 1.27)
				)
			)
		)
		(property "Value" ""
			(at 0 0 90)
			(layer "F.Fab")
			(effects
				(font
					(size 1.27 1.27)
				)
			)
		)
		(duplicate_pad_numbers_are_jumpers no)
		(fp_line
			(start 0.7874 -0.4064)
			(end 0.7874 0.4064)
			(stroke
				(width 0.1524)
				(type default)
			)
			(layer "F.SilkS")
		)
		(fp_line
			(start -0.7874 -0.4064)
			(end 0.7874 -0.4064)
			(stroke
				(width 0.1524)
				(type default)
			)
			(layer "F.SilkS")
		)
		(fp_line
			(start 0.7874 0.4064)
			(end -0.7874 0.4064)
			(stroke
				(width 0.1524)
				(type default)
			)
			(layer "F.SilkS")
		)
		(fp_line
			(start -0.7874 0.4064)
			(end -0.7874 -0.4064)
			(stroke
				(width 0.1524)
				(type default)
			)
			(layer "F.SilkS")
		)
		(fp_line
			(start -0.12065 -0.305054)
			(end -0.12065 -0.2794)
			(stroke
				(width 0.1)
				(type default)
			)
			(layer "F.Fab")
		)
		(fp_line
			(start -0.67945 -0.305054)
			(end -0.12065 -0.305054)
			(stroke
				(width 0.1)
				(type default)
			)
			(layer "F.Fab")
		)
		(fp_line
			(start 0.67945 -0.3048)
			(end 0.67945 0.3048)
			(stroke
				(width 0.1)
				(type default)
			)
			(layer "F.Fab")
		)
		(fp_line
			(start 0.12065 -0.3048)
			(end 0.67945 -0.3048)
			(stroke
				(width 0.1)
				(type default)
			)
			(layer "F.Fab")
		)
		(fp_line
			(start 0.12065 -0.2794)
			(end 0.12065 -0.3048)
			(stroke
				(width 0.1)
				(type default)
			)
			(layer "F.Fab")
		)
		(fp_line
			(start -0.12065 -0.2794)
			(end 0.12065 -0.2794)
			(stroke
				(width 0.1)
				(type default)
			)
			(layer "F.Fab")
		)
		(fp_line
			(start 0.120396 0.2794)
			(end -0.12065 0.2794)
			(stroke
				(width 0.1)
				(type default)
			)
			(layer "F.Fab")
		)
		(fp_line
			(start -0.12065 0.2794)
			(end -0.12065 0.3048)
			(stroke
				(width 0.1)
				(type default)
			)
			(layer "F.Fab")
		)
		(fp_line
			(start 0.67945 0.3048)
			(end 0.120396 0.3048)
			(stroke
				(width 0.1)
				(type default)
			)
			(layer "F.Fab")
		)
		(fp_line
			(start 0.120396 0.3048)
			(end 0.120396 0.2794)
			(stroke
				(width 0.1)
				(type default)
			)
			(layer "F.Fab")
		)
		(fp_line
			(start -0.12065 0.3048)
			(end -0.67945 0.3048)
			(stroke
				(width 0.1)
				(type default)
			)
			(layer "F.Fab")
		)
		(fp_line
			(start -0.67945 0.3048)
			(end -0.67945 -0.305054)
			(stroke
				(width 0.1)
				(type default)
			)
			(layer "F.Fab")
		)
		(pad "1" smd circle
			(at -0.40005 0 90)
			(size 0 0)
			(layers "F.Cu" "F.Mask" "F.Paste")
			(net "FM_SEC_MUX_OE_N")
		)
		(pad "2" smd circle
			(at 0.40005 0 90)
			(size 0 0)
			(layers "F.Cu" "F.Mask" "F.Paste")
			(net "GND")
		)
	)
	(footprint ""
		(layer "F.Cu")
		(at 208.894426 -105.497376)
		(property "Reference" "R6051"
			(at 0 0 0)
			(layer "F.SilkS")
			(hide yes)
			(effects
				(font
					(size 1.27 1.27)
				)
			)
		)
		(property "Value" ""
			(at 0 0 0)
			(layer "F.Fab")
			(effects
				(font
					(size 1.27 1.27)
				)
			)
		)
		(duplicate_pad_numbers_are_jumpers no)
		(fp_line
			(start -0.7874 -0.4064)
			(end 0.7874 -0.4064)
			(stroke
				(width 0.1524)
				(type default)
			)
			(layer "F.SilkS")
		)
		(fp_line
			(start -0.7874 0.4064)
			(end -0.7874 -0.4064)
			(stroke
				(width 0.1524)
				(type default)
			)
			(layer "F.SilkS")
		)
		(fp_line
			(start 0.7874 -0.4064)
			(end 0.7874 0.4064)
			(stroke
				(width 0.1524)
				(type default)
			)
			(layer "F.SilkS")
		)
		(fp_line
			(start 0.7874 0.4064)
			(end -0.7874 0.4064)
			(stroke
				(width 0.1524)
				(type default)
			)
			(layer "F.SilkS")
		)
		(fp_line
			(start -0.67945 -0.305054)
			(end -0.12065 -0.305054)
			(stroke
				(width 0.1)
				(type default)
			)
			(layer "F.Fab")
		)
		(fp_line
			(start -0.67945 0.3048)
			(end -0.67945 -0.305054)
			(stroke
				(width 0.1)
				(type default)
			)
			(layer "F.Fab")
		)
		(fp_line
			(start -0.12065 -0.305054)
			(end -0.12065 -0.2794)
			(stroke
				(width 0.1)
				(type default)
			)
			(layer "F.Fab")
		)
		(fp_line
			(start -0.12065 -0.2794)
			(end 0.12065 -0.2794)
			(stroke
				(width 0.1)
				(type default)
			)
			(layer "F.Fab")
		)
		(fp_line
			(start -0.12065 0.2794)
			(end -0.12065 0.3048)
			(stroke
				(width 0.1)
				(type default)
			)
			(layer "F.Fab")
		)
		(fp_line
			(start -0.12065 0.3048)
			(end -0.67945 0.3048)
			(stroke
				(width 0.1)
				(type default)
			)
			(layer "F.Fab")
		)
		(fp_line
			(start 0.120396 0.2794)
			(end -0.12065 0.2794)
			(stroke
				(width 0.1)
				(type default)
			)
			(layer "F.Fab")
		)
		(fp_line
			(start 0.120396 0.3048)
			(end 0.120396 0.2794)
			(stroke
				(width 0.1)
				(type default)
			)
			(layer "F.Fab")
		)
		(fp_line
			(start 0.12065 -0.3048)
			(end 0.67945 -0.3048)
			(stroke
				(width 0.1)
				(type default)
			)
			(layer "F.Fab")
		)
		(fp_line
			(start 0.12065 -0.2794)
			(end 0.12065 -0.3048)
			(stroke
				(width 0.1)
				(type default)
			)
			(layer "F.Fab")
		)
		(fp_line
			(start 0.67945 -0.3048)
			(end 0.67945 0.3048)
			(stroke
				(width 0.1)
				(type default)
			)
			(layer "F.Fab")
		)
		(fp_line
			(start 0.67945 0.3048)
			(end 0.120396 0.3048)
			(stroke
				(width 0.1)
				(type default)
			)
			(layer "F.Fab")
		)
		(pad "1" smd circle
			(at -0.40005 0)
			(size 0 0)
			(layers "F.Cu" "F.Mask" "F.Paste")
			(net "P12V_OCP_V3_1_PWRGD")
		)
		(pad "2" smd circle
			(at 0.40005 0)
			(size 0 0)
			(layers "F.Cu" "F.Mask" "F.Paste")
			(net "P12V_OCP_V3_1_PLD_PWRGD")
		)
	)
	(footprint ""
		(layer "F.Cu")
		(at 73.843134 -186.942984 180)
		(property "Reference" "PL33"
			(at 4.778756 2.166366 90)
			(unlocked yes)
			(layer "F.SilkS")
			(effects
				(font
					(size 0.7874 0.5842)
					(thickness 0.1524)
				)
				(justify left)
			)
		)
		(property "Value" ""
			(at 0 0 180)
			(layer "F.Fab")
			(effects
				(font
					(size 1.27 1.27)
				)
			)
		)
		(duplicate_pad_numbers_are_jumpers no)
		(fp_line
			(start 3.750056 5.500116)
			(end 3.750056 -5.500116)
			(stroke
				(width 0.1524)
				(type default)
			)
			(layer "F.SilkS")
		)
		(fp_line
			(start 3.750056 -5.500116)
			(end 2.393442 -5.500116)
			(stroke
				(width 0.1524)
				(type default)
			)
			(layer "F.SilkS")
		)
		(fp_line
			(start 2.393442 5.500116)
			(end 3.750056 5.500116)
			(stroke
				(width 0.1524)
				(type default)
			)
			(layer "F.SilkS")
		)
		(fp_line
			(start -2.393442 5.500116)
			(end -3.750056 5.500116)
			(stroke
				(width 0.1524)
				(type default)
			)
			(layer "F.SilkS")
		)
		(fp_line
			(start -3.750056 5.500116)
			(end -3.750056 -5.500116)
			(stroke
				(width 0.1524)
				(type default)
			)
			(layer "F.SilkS")
		)
		(fp_line
			(start -3.750056 -5.500116)
			(end -2.393442 -5.500116)
			(stroke
				(width 0.1524)
				(type default)
			)
			(layer "F.SilkS")
		)
		(fp_poly
			(pts
				(xy -4.04114 -3.352546) (xy -4.400296 -2.274824) (xy -5.118862 -2.993136)
			)
			(stroke
				(width 0)
				(type default)
			)
			(fill yes)
			(layer "F.SilkS")
		)
		(fp_line
			(start 3.750056 5.500116)
			(end 3.750056 -5.500116)
			(stroke
				(width 0.1)
				(type default)
			)
			(layer "F.Fab")
		)
		(fp_line
			(start 3.750056 -5.500116)
			(end -3.750056 -5.500116)
			(stroke
				(width 0.1)
				(type default)
			)
			(layer "F.Fab")
		)
		(fp_line
			(start -3.750056 5.500116)
			(end 3.750056 5.500116)
			(stroke
				(width 0.1)
				(type default)
			)
			(layer "F.Fab")
		)
		(fp_line
			(start -3.750056 -5.500116)
			(end -3.750056 5.500116)
			(stroke
				(width 0.1)
				(type default)
			)
			(layer "F.Fab")
		)
		(fp_poly
			(pts
				(xy -4.9276 -4.757928) (xy -4.9276 -3.741928) (xy -3.9116 -4.249928)
			)
			(stroke
				(width 0)
				(type default)
			)
			(fill yes)
			(layer "F.Fab")
		)
		(pad "1" smd rect
			(at 0 -4.249928 90)
			(size 2.413 4.5212)
			(layers "F.Cu" "F.Mask" "F.Paste")
			(net "SW_PVDDCR_CPU0_P1_SW5")
		)
		(pad "2" smd rect
			(at 0 -1.175004 90)
			(size 1.3716 4.5212)
			(layers "F.Cu" "F.Mask" "F.Paste")
			(net "IND_CPU0_P1_CPL6")
		)
		(pad "3" smd rect
			(at 0 1.175004 90)
			(size 1.3716 4.5212)
			(layers "F.Cu" "F.Mask" "F.Paste")
			(net "IND_CPU0_P1_CPL5")
		)
		(pad "4" smd rect
			(at 0 4.249928 90)
			(size 2.413 4.5212)
			(layers "F.Cu" "F.Mask" "F.Paste")
			(net "PVDDCR_CPU0_P1")
		)
	)
	(footprint ""
		(layer "F.Cu")
		(at 141.369542 -383.7432)
		(property "Reference" "R882"
			(at 0 0 0)
			(layer "F.SilkS")
			(hide yes)
			(effects
				(font
					(size 1.27 1.27)
				)
			)
		)
		(property "Value" ""
			(at 0 0 0)
			(layer "F.Fab")
			(effects
				(font
					(size 1.27 1.27)
				)
			)
		)
		(duplicate_pad_numbers_are_jumpers no)
		(fp_line
			(start -0.32512 -0.175006)
			(end 0.32512 -0.175006)
			(stroke
				(width 0.1)
				(type default)
			)
			(layer "F.Fab")
		)
		(fp_line
			(start -0.32512 0.175006)
			(end -0.32512 -0.175006)
			(stroke
				(width 0.1)
				(type default)
			)
			(layer "F.Fab")
		)
		(fp_line
			(start 0.32512 -0.175006)
			(end 0.32512 0.175006)
			(stroke
				(width 0.1)
				(type default)
			)
			(layer "F.Fab")
		)
		(fp_line
			(start 0.32512 0.175006)
			(end -0.32512 0.175006)
			(stroke
				(width 0.1)
				(type default)
			)
			(layer "F.Fab")
		)
		(pad "1" smd rect
			(at -0.2667 0)
			(size 0.3048 0.381)
			(layers "F.Cu" "F.Mask" "F.Paste")
			(net "P1V8_CPU1_RT_1D")
		)
		(pad "2" smd rect
			(at 0.2667 0 180)
			(size 0.3048 0.381)
			(layers "F.Cu" "F.Mask" "F.Paste")
			(net "TEST2_RT_CPU1_P2")
		)
	)
	(footprint ""
		(layer "F.Cu")
		(at 45.212 -170.815 180)
		(property "Reference" "R563"
			(at 0 0 180)
			(layer "F.SilkS")
			(hide yes)
			(effects
				(font
					(size 1.27 1.27)
				)
			)
		)
		(property "Value" ""
			(at 0 0 180)
			(layer "F.Fab")
			(effects
				(font
					(size 1.27 1.27)
				)
			)
		)
		(duplicate_pad_numbers_are_jumpers no)
		(fp_line
			(start 0.7874 0.4064)
			(end -0.7874 0.4064)
			(stroke
				(width 0.1524)
				(type default)
			)
			(layer "F.SilkS")
		)
		(fp_line
			(start 0.7874 -0.4064)
			(end 0.7874 0.4064)
			(stroke
				(width 0.1524)
				(type default)
			)
			(layer "F.SilkS")
		)
		(fp_line
			(start -0.7874 0.4064)
			(end -0.7874 -0.4064)
			(stroke
				(width 0.1524)
				(type default)
			)
			(layer "F.SilkS")
		)
		(fp_line
			(start -0.7874 -0.4064)
			(end 0.7874 -0.4064)
			(stroke
				(width 0.1524)
				(type default)
			)
			(layer "F.SilkS")
		)
		(fp_line
			(start 0.67945 0.3048)
			(end 0.120396 0.3048)
			(stroke
				(width 0.1)
				(type default)
			)
			(layer "F.Fab")
		)
		(fp_line
			(start 0.67945 -0.3048)
			(end 0.67945 0.3048)
			(stroke
				(width 0.1)
				(type default)
			)
			(layer "F.Fab")
		)
		(fp_line
			(start 0.12065 -0.2794)
			(end 0.12065 -0.3048)
			(stroke
				(width 0.1)
				(type default)
			)
			(layer "F.Fab")
		)
		(fp_line
			(start 0.12065 -0.3048)
			(end 0.67945 -0.3048)
			(stroke
				(width 0.1)
				(type default)
			)
			(layer "F.Fab")
		)
		(fp_line
			(start 0.120396 0.3048)
			(end 0.120396 0.2794)
			(stroke
				(width 0.1)
				(type default)
			)
			(layer "F.Fab")
		)
		(fp_line
			(start 0.120396 0.2794)
			(end -0.12065 0.2794)
			(stroke
				(width 0.1)
				(type default)
			)
			(layer "F.Fab")
		)
		(fp_line
			(start -0.12065 0.3048)
			(end -0.67945 0.3048)
			(stroke
				(width 0.1)
				(type default)
			)
			(layer "F.Fab")
		)
		(fp_line
			(start -0.12065 0.2794)
			(end -0.12065 0.3048)
			(stroke
				(width 0.1)
				(type default)
			)
			(layer "F.Fab")
		)
		(fp_line
			(start -0.12065 -0.2794)
			(end 0.12065 -0.2794)
			(stroke
				(width 0.1)
				(type default)
			)
			(layer "F.Fab")
		)
		(fp_line
			(start -0.12065 -0.305054)
			(end -0.12065 -0.2794)
			(stroke
				(width 0.1)
				(type default)
			)
			(layer "F.Fab")
		)
		(fp_line
			(start -0.67945 0.3048)
			(end -0.67945 -0.305054)
			(stroke
				(width 0.1)
				(type default)
			)
			(layer "F.Fab")
		)
		(fp_line
			(start -0.67945 -0.305054)
			(end -0.12065 -0.305054)
			(stroke
				(width 0.1)
				(type default)
			)
			(layer "F.Fab")
		)
		(pad "1" smd circle
			(at -0.40005 0 180)
			(size 0 0)
			(layers "F.Cu" "F.Mask" "F.Paste")
			(net "PVDD11_S3_P1")
		)
		(pad "2" smd circle
			(at 0.40005 0 180)
			(size 0 0)
			(layers "F.Cu" "F.Mask" "F.Paste")
			(net "I3C_0_SPD_DDRAF_CPU1_R_SCL")
		)
	)
	(footprint ""
		(layer "F.Cu")
		(at 232.517442 -315.82868 90)
		(property "Reference" "PC6532"
			(at -1.50368 3.729228 90)
			(unlocked yes)
			(layer "F.SilkS")
			(effects
				(font
					(size 0.7874 0.5842)
					(thickness 0.1524)
				)
				(justify left)
			)
		)
		(property "Value" ""
			(at 0 0 90)
			(layer "F.Fab")
			(effects
				(font
					(size 1.27 1.27)
				)
			)
		)
		(duplicate_pad_numbers_are_jumpers no)
		(fp_line
			(start 2.750058 -2.750058)
			(end -1.988058 -2.750058)
			(stroke
				(width 0.1524)
				(type default)
			)
			(layer "F.SilkS")
		)
		(fp_line
			(start -1.988058 -2.750058)
			(end -2.750058 -1.988058)
			(stroke
				(width 0.1524)
				(type default)
			)
			(layer "F.SilkS")
		)
		(fp_line
			(start -2.750058 -1.988058)
			(end -2.750058 -0.9398)
			(stroke
				(width 0.1524)
				(type default)
			)
			(layer "F.SilkS")
		)
		(fp_line
			(start 2.750058 -0.9398)
			(end 2.750058 -2.750058)
			(stroke
				(width 0.1524)
				(type default)
			)
			(layer "F.SilkS")
		)
		(fp_line
			(start -2.750058 0.9398)
			(end -2.750058 1.988058)
			(stroke
				(width 0.1524)
				(type default)
			)
			(layer "F.SilkS")
		)
		(fp_line
			(start -2.750058 1.988058)
			(end -1.988058 2.750058)
			(stroke
				(width 0.1524)
				(type default)
			)
			(layer "F.SilkS")
		)
		(fp_line
			(start 2.750058 2.750058)
			(end 2.750058 0.9398)
			(stroke
				(width 0.1524)
				(type default)
			)
			(layer "F.SilkS")
		)
		(fp_line
			(start -1.988058 2.750058)
			(end 2.750058 2.750058)
			(stroke
				(width 0.1524)
				(type default)
			)
			(layer "F.SilkS")
		)
		(fp_line
			(start 2.750058 -2.750058)
			(end -2.750058 -2.750058)
			(stroke
				(width 0.1)
				(type default)
			)
			(layer "F.Fab")
		)
		(fp_line
			(start -2.750058 -2.750058)
			(end -2.750058 2.750058)
			(stroke
				(width 0.1)
				(type default)
			)
			(layer "F.Fab")
		)
		(fp_line
			(start 2.750058 2.750058)
			(end 2.750058 -2.750058)
			(stroke
				(width 0.1)
				(type default)
			)
			(layer "F.Fab")
		)
		(fp_line
			(start -2.750058 2.750058)
			(end 2.750058 2.750058)
			(stroke
				(width 0.1)
				(type default)
			)
			(layer "F.Fab")
		)
		(pad "1" smd rect
			(at -2.199894 0 180)
			(size 1.6002 3.0226)
			(layers "F.Cu" "F.Mask" "F.Paste")
			(net "P1V8_CPU1_RT_1D")
		)
		(pad "2" smd rect
			(at 2.199894 0 180)
			(size 1.6002 3.0226)
			(layers "F.Cu" "F.Mask" "F.Paste")
			(net "GND")
		)
	)
	(footprint ""
		(layer "F.Cu")
		(at 102.961948 -381.7874 180)
		(property "Reference" "R1376"
			(at 0 0 180)
			(layer "F.SilkS")
			(hide yes)
			(effects
				(font
					(size 1.27 1.27)
				)
			)
		)
		(property "Value" ""
			(at 0 0 180)
			(layer "F.Fab")
			(effects
				(font
					(size 1.27 1.27)
				)
			)
		)
		(duplicate_pad_numbers_are_jumpers no)
		(fp_line
			(start 0.32512 0.175006)
			(end -0.32512 0.175006)
			(stroke
				(width 0.1)
				(type default)
			)
			(layer "F.Fab")
		)
		(fp_line
			(start 0.32512 -0.175006)
			(end 0.32512 0.175006)
			(stroke
				(width 0.1)
				(type default)
			)
			(layer "F.Fab")
		)
		(fp_line
			(start -0.32512 0.175006)
			(end -0.32512 -0.175006)
			(stroke
				(width 0.1)
				(type default)
			)
			(layer "F.Fab")
		)
		(fp_line
			(start -0.32512 -0.175006)
			(end 0.32512 -0.175006)
			(stroke
				(width 0.1)
				(type default)
			)
			(layer "F.Fab")
		)
		(pad "1" smd rect
			(at -0.2667 0 180)
			(size 0.3048 0.381)
			(layers "F.Cu" "F.Mask" "F.Paste")
			(net "CLKREQ_RT_CPU1_P1_N")
		)
		(pad "2" smd rect
			(at 0.2667 0)
			(size 0.3048 0.381)
			(layers "F.Cu" "F.Mask" "F.Paste")
			(net "GND")
		)
	)
	(footprint ""
		(layer "F.Cu")
		(at 275.539962 -337.399122)
		(property "Reference" "PL20"
			(at -1.854962 -15.888208 0)
			(unlocked yes)
			(layer "F.SilkS")
			(effects
				(font
					(size 0.7874 0.5842)
					(thickness 0.1524)
				)
				(justify left)
			)
		)
		(property "Value" ""
			(at 0 0 0)
			(layer "F.Fab")
			(effects
				(font
					(size 1.27 1.27)
				)
			)
		)
		(duplicate_pad_numbers_are_jumpers no)
		(fp_line
			(start -3.750056 -5.500116)
			(end -2.393442 -5.500116)
			(stroke
				(width 0.1524)
				(type default)
			)
			(layer "F.SilkS")
		)
		(fp_line
			(start -3.750056 5.500116)
			(end -3.750056 -5.500116)
			(stroke
				(width 0.1524)
				(type default)
			)
			(layer "F.SilkS")
		)
		(fp_line
			(start -2.393442 5.500116)
			(end -3.750056 5.500116)
			(stroke
				(width 0.1524)
				(type default)
			)
			(layer "F.SilkS")
		)
		(fp_line
			(start 2.393442 5.500116)
			(end 3.750056 5.500116)
			(stroke
				(width 0.1524)
				(type default)
			)
			(layer "F.SilkS")
		)
		(fp_line
			(start 3.750056 -5.500116)
			(end 2.393442 -5.500116)
			(stroke
				(width 0.1524)
				(type default)
			)
			(layer "F.SilkS")
		)
		(fp_line
			(start 3.750056 5.500116)
			(end 3.750056 -5.500116)
			(stroke
				(width 0.1524)
				(type default)
			)
			(layer "F.SilkS")
		)
		(fp_poly
			(pts
				(xy -3.965448 -5.22478) (xy -4.42341 -5.377434) (xy -4.118102 -5.682742)
			)
			(stroke
				(width 0)
				(type default)
			)
			(fill yes)
			(layer "F.SilkS")
		)
		(fp_line
			(start -3.750056 -5.500116)
			(end -3.750056 5.500116)
			(stroke
				(width 0.1)
				(type default)
			)
			(layer "F.Fab")
		)
		(fp_line
			(start -3.750056 5.500116)
			(end 3.750056 5.500116)
			(stroke
				(width 0.1)
				(type default)
			)
			(layer "F.Fab")
		)
		(fp_line
			(start 3.750056 -5.500116)
			(end -3.750056 -5.500116)
			(stroke
				(width 0.1)
				(type default)
			)
			(layer "F.Fab")
		)
		(fp_line
			(start 3.750056 5.500116)
			(end 3.750056 -5.500116)
			(stroke
				(width 0.1)
				(type default)
			)
			(layer "F.Fab")
		)
		(fp_poly
			(pts
				(xy -4.9276 -4.757928) (xy -4.9276 -3.741928) (xy -3.9116 -4.249928)
			)
			(stroke
				(width 0)
				(type default)
			)
			(fill yes)
			(layer "F.Fab")
		)
		(pad "1" smd rect
			(at 0 -4.249928 270)
			(size 2.413 4.5212)
			(layers "F.Cu" "F.Mask" "F.Paste")
			(net "SW_PVDDIO_P0_SW4")
		)
		(pad "2" smd rect
			(at 0 -1.175004 270)
			(size 1.3716 4.5212)
			(layers "F.Cu" "F.Mask" "F.Paste")
			(net "IND_PVDDIO_P0_CPL0")
		)
		(pad "3" smd rect
			(at 0 1.175004 270)
			(size 1.3716 4.5212)
			(layers "F.Cu" "F.Mask" "F.Paste")
			(net "IND_PVDDIO_P0_CPL4")
		)
		(pad "4" smd rect
			(at 0 4.249928 270)
			(size 2.413 4.5212)
			(layers "F.Cu" "F.Mask" "F.Paste")
			(net "PVDDIO_P0")
		)
	)
	(footprint ""
		(layer "F.Cu")
		(at 171.196 -107.152948 180)
		(property "Reference" "R170"
			(at 0 0 180)
			(layer "F.SilkS")
			(hide yes)
			(effects
				(font
					(size 1.27 1.27)
				)
			)
		)
		(property "Value" ""
			(at 0 0 180)
			(layer "F.Fab")
			(effects
				(font
					(size 1.27 1.27)
				)
			)
		)
		(duplicate_pad_numbers_are_jumpers no)
		(fp_line
			(start 0.7874 0.4064)
			(end -0.7874 0.4064)
			(stroke
				(width 0.1524)
				(type default)
			)
			(layer "F.SilkS")
		)
		(fp_line
			(start 0.7874 -0.4064)
			(end 0.7874 0.4064)
			(stroke
				(width 0.1524)
				(type default)
			)
			(layer "F.SilkS")
		)
		(fp_line
			(start -0.7874 0.4064)
			(end -0.7874 -0.4064)
			(stroke
				(width 0.1524)
				(type default)
			)
			(layer "F.SilkS")
		)
		(fp_line
			(start -0.7874 -0.4064)
			(end 0.7874 -0.4064)
			(stroke
				(width 0.1524)
				(type default)
			)
			(layer "F.SilkS")
		)
		(fp_line
			(start 0.67945 0.3048)
			(end 0.120396 0.3048)
			(stroke
				(width 0.1)
				(type default)
			)
			(layer "F.Fab")
		)
		(fp_line
			(start 0.67945 -0.3048)
			(end 0.67945 0.3048)
			(stroke
				(width 0.1)
				(type default)
			)
			(layer "F.Fab")
		)
		(fp_line
			(start 0.12065 -0.2794)
			(end 0.12065 -0.3048)
			(stroke
				(width 0.1)
				(type default)
			)
			(layer "F.Fab")
		)
		(fp_line
			(start 0.12065 -0.3048)
			(end 0.67945 -0.3048)
			(stroke
				(width 0.1)
				(type default)
			)
			(layer "F.Fab")
		)
		(fp_line
			(start 0.120396 0.3048)
			(end 0.120396 0.2794)
			(stroke
				(width 0.1)
				(type default)
			)
			(layer "F.Fab")
		)
		(fp_line
			(start 0.120396 0.2794)
			(end -0.12065 0.2794)
			(stroke
				(width 0.1)
				(type default)
			)
			(layer "F.Fab")
		)
		(fp_line
			(start -0.12065 0.3048)
			(end -0.67945 0.3048)
			(stroke
				(width 0.1)
				(type default)
			)
			(layer "F.Fab")
		)
		(fp_line
			(start -0.12065 0.2794)
			(end -0.12065 0.3048)
			(stroke
				(width 0.1)
				(type default)
			)
			(layer "F.Fab")
		)
		(fp_line
			(start -0.12065 -0.2794)
			(end 0.12065 -0.2794)
			(stroke
				(width 0.1)
				(type default)
			)
			(layer "F.Fab")
		)
		(fp_line
			(start -0.12065 -0.305054)
			(end -0.12065 -0.2794)
			(stroke
				(width 0.1)
				(type default)
			)
			(layer "F.Fab")
		)
		(fp_line
			(start -0.67945 0.3048)
			(end -0.67945 -0.305054)
			(stroke
				(width 0.1)
				(type default)
			)
			(layer "F.Fab")
		)
		(fp_line
			(start -0.67945 -0.305054)
			(end -0.12065 -0.305054)
			(stroke
				(width 0.1)
				(type default)
			)
			(layer "F.Fab")
		)
		(pad "1" smd circle
			(at -0.40005 0 180)
			(size 0 0)
			(layers "F.Cu" "F.Mask" "F.Paste")
			(net "FM_I3C_CPU1_MUX0_R_SEL")
		)
		(pad "2" smd circle
			(at 0.40005 0 180)
			(size 0 0)
			(layers "F.Cu" "F.Mask" "F.Paste")
			(net "FM_I3C_CPU1_MUX0_SEL")
		)
	)
	(footprint ""
		(layer "F.Cu")
		(at 435.997858 -106.76636 180)
		(property "Reference" "PR3798"
			(at 0 0 180)
			(layer "F.SilkS")
			(hide yes)
			(effects
				(font
					(size 1.27 1.27)
				)
			)
		)
		(property "Value" ""
			(at 0 0 180)
			(layer "F.Fab")
			(effects
				(font
					(size 1.27 1.27)
				)
			)
		)
		(duplicate_pad_numbers_are_jumpers no)
		(fp_line
			(start 0.7874 0.4064)
			(end -0.7874 0.4064)
			(stroke
				(width 0.1524)
				(type default)
			)
			(layer "F.SilkS")
		)
		(fp_line
			(start 0.7874 -0.4064)
			(end 0.7874 0.4064)
			(stroke
				(width 0.1524)
				(type default)
			)
			(layer "F.SilkS")
		)
		(fp_line
			(start -0.7874 0.4064)
			(end -0.7874 -0.4064)
			(stroke
				(width 0.1524)
				(type default)
			)
			(layer "F.SilkS")
		)
		(fp_line
			(start -0.7874 -0.4064)
			(end 0.7874 -0.4064)
			(stroke
				(width 0.1524)
				(type default)
			)
			(layer "F.SilkS")
		)
		(fp_line
			(start 0.67945 0.3048)
			(end 0.120396 0.3048)
			(stroke
				(width 0.1)
				(type default)
			)
			(layer "F.Fab")
		)
		(fp_line
			(start 0.67945 -0.3048)
			(end 0.67945 0.3048)
			(stroke
				(width 0.1)
				(type default)
			)
			(layer "F.Fab")
		)
		(fp_line
			(start 0.12065 -0.2794)
			(end 0.12065 -0.3048)
			(stroke
				(width 0.1)
				(type default)
			)
			(layer "F.Fab")
		)
		(fp_line
			(start 0.12065 -0.3048)
			(end 0.67945 -0.3048)
			(stroke
				(width 0.1)
				(type default)
			)
			(layer "F.Fab")
		)
		(fp_line
			(start 0.120396 0.3048)
			(end 0.120396 0.2794)
			(stroke
				(width 0.1)
				(type default)
			)
			(layer "F.Fab")
		)
		(fp_line
			(start 0.120396 0.2794)
			(end -0.12065 0.2794)
			(stroke
				(width 0.1)
				(type default)
			)
			(layer "F.Fab")
		)
		(fp_line
			(start -0.12065 0.3048)
			(end -0.67945 0.3048)
			(stroke
				(width 0.1)
				(type default)
			)
			(layer "F.Fab")
		)
		(fp_line
			(start -0.12065 0.2794)
			(end -0.12065 0.3048)
			(stroke
				(width 0.1)
				(type default)
			)
			(layer "F.Fab")
		)
		(fp_line
			(start -0.12065 -0.2794)
			(end 0.12065 -0.2794)
			(stroke
				(width 0.1)
				(type default)
			)
			(layer "F.Fab")
		)
		(fp_line
			(start -0.12065 -0.305054)
			(end -0.12065 -0.2794)
			(stroke
				(width 0.1)
				(type default)
			)
			(layer "F.Fab")
		)
		(fp_line
			(start -0.67945 0.3048)
			(end -0.67945 -0.305054)
			(stroke
				(width 0.1)
				(type default)
			)
			(layer "F.Fab")
		)
		(fp_line
			(start -0.67945 -0.305054)
			(end -0.12065 -0.305054)
			(stroke
				(width 0.1)
				(type default)
			)
			(layer "F.Fab")
		)
		(pad "1" smd circle
			(at -0.40005 0 180)
			(size 0 0)
			(layers "F.Cu" "F.Mask" "F.Paste")
			(net "P3V3_AUX")
		)
		(pad "2" smd circle
			(at 0.40005 0 180)
			(size 0 0)
			(layers "F.Cu" "F.Mask" "F.Paste")
			(net "P3V3_OCP_VCC_1")
		)
	)
	(footprint ""
		(layer "F.Cu")
		(at 341.56904 -171.308522)
		(property "Reference" "PR295"
			(at 0 0 0)
			(layer "F.SilkS")
			(hide yes)
			(effects
				(font
					(size 1.27 1.27)
				)
			)
		)
		(property "Value" ""
			(at 0 0 0)
			(layer "F.Fab")
			(effects
				(font
					(size 1.27 1.27)
				)
			)
		)
		(duplicate_pad_numbers_are_jumpers no)
		(fp_line
			(start -0.7874 -0.4064)
			(end 0.7874 -0.4064)
			(stroke
				(width 0.1524)
				(type default)
			)
			(layer "F.SilkS")
		)
		(fp_line
			(start -0.7874 0.4064)
			(end -0.7874 -0.4064)
			(stroke
				(width 0.1524)
				(type default)
			)
			(layer "F.SilkS")
		)
		(fp_line
			(start 0.7874 -0.4064)
			(end 0.7874 0.4064)
			(stroke
				(width 0.1524)
				(type default)
			)
			(layer "F.SilkS")
		)
		(fp_line
			(start 0.7874 0.4064)
			(end -0.7874 0.4064)
			(stroke
				(width 0.1524)
				(type default)
			)
			(layer "F.SilkS")
		)
		(fp_line
			(start -0.67945 -0.305054)
			(end -0.12065 -0.305054)
			(stroke
				(width 0.1)
				(type default)
			)
			(layer "F.Fab")
		)
		(fp_line
			(start -0.67945 0.3048)
			(end -0.67945 -0.305054)
			(stroke
				(width 0.1)
				(type default)
			)
			(layer "F.Fab")
		)
		(fp_line
			(start -0.12065 -0.305054)
			(end -0.12065 -0.2794)
			(stroke
				(width 0.1)
				(type default)
			)
			(layer "F.Fab")
		)
		(fp_line
			(start -0.12065 -0.2794)
			(end 0.12065 -0.2794)
			(stroke
				(width 0.1)
				(type default)
			)
			(layer "F.Fab")
		)
		(fp_line
			(start -0.12065 0.2794)
			(end -0.12065 0.3048)
			(stroke
				(width 0.1)
				(type default)
			)
			(layer "F.Fab")
		)
		(fp_line
			(start -0.12065 0.3048)
			(end -0.67945 0.3048)
			(stroke
				(width 0.1)
				(type default)
			)
			(layer "F.Fab")
		)
		(fp_line
			(start 0.120396 0.2794)
			(end -0.12065 0.2794)
			(stroke
				(width 0.1)
				(type default)
			)
			(layer "F.Fab")
		)
		(fp_line
			(start 0.120396 0.3048)
			(end 0.120396 0.2794)
			(stroke
				(width 0.1)
				(type default)
			)
			(layer "F.Fab")
		)
		(fp_line
			(start 0.12065 -0.3048)
			(end 0.67945 -0.3048)
			(stroke
				(width 0.1)
				(type default)
			)
			(layer "F.Fab")
		)
		(fp_line
			(start 0.12065 -0.2794)
			(end 0.12065 -0.3048)
			(stroke
				(width 0.1)
				(type default)
			)
			(layer "F.Fab")
		)
		(fp_line
			(start 0.67945 -0.3048)
			(end 0.67945 0.3048)
			(stroke
				(width 0.1)
				(type default)
			)
			(layer "F.Fab")
		)
		(fp_line
			(start 0.67945 0.3048)
			(end 0.120396 0.3048)
			(stroke
				(width 0.1)
				(type default)
			)
			(layer "F.Fab")
		)
		(pad "1" smd circle
			(at -0.40005 0)
			(size 0 0)
			(layers "F.Cu" "F.Mask" "F.Paste")
			(net "VSENSE_VSS_SENSE_A_P0")
		)
		(pad "2" smd circle
			(at 0.40005 0)
			(size 0 0)
			(layers "F.Cu" "F.Mask" "F.Paste")
			(net "GND")
		)
	)
	(footprint ""
		(layer "F.Cu")
		(at 212.118956 -30.276292 -90)
		(property "Reference" "R3561"
			(at 0 0 270)
			(layer "F.SilkS")
			(hide yes)
			(effects
				(font
					(size 1.27 1.27)
				)
			)
		)
		(property "Value" ""
			(at 0 0 270)
			(layer "F.Fab")
			(effects
				(font
					(size 1.27 1.27)
				)
			)
		)
		(duplicate_pad_numbers_are_jumpers no)
		(fp_line
			(start -0.7874 0.4064)
			(end -0.7874 -0.4064)
			(stroke
				(width 0.1524)
				(type default)
			)
			(layer "F.SilkS")
		)
		(fp_line
			(start 0.7874 0.4064)
			(end -0.7874 0.4064)
			(stroke
				(width 0.1524)
				(type default)
			)
			(layer "F.SilkS")
		)
		(fp_line
			(start -0.7874 -0.4064)
			(end 0.7874 -0.4064)
			(stroke
				(width 0.1524)
				(type default)
			)
			(layer "F.SilkS")
		)
		(fp_line
			(start 0.7874 -0.4064)
			(end 0.7874 0.4064)
			(stroke
				(width 0.1524)
				(type default)
			)
			(layer "F.SilkS")
		)
		(fp_line
			(start -0.67945 0.3048)
			(end -0.67945 -0.305054)
			(stroke
				(width 0.1)
				(type default)
			)
			(layer "F.Fab")
		)
		(fp_line
			(start -0.12065 0.3048)
			(end -0.67945 0.3048)
			(stroke
				(width 0.1)
				(type default)
			)
			(layer "F.Fab")
		)
		(fp_line
			(start 0.120396 0.3048)
			(end 0.120396 0.2794)
			(stroke
				(width 0.1)
				(type default)
			)
			(layer "F.Fab")
		)
		(fp_line
			(start 0.67945 0.3048)
			(end 0.120396 0.3048)
			(stroke
				(width 0.1)
				(type default)
			)
			(layer "F.Fab")
		)
		(fp_line
			(start -0.12065 0.2794)
			(end -0.12065 0.3048)
			(stroke
				(width 0.1)
				(type default)
			)
			(layer "F.Fab")
		)
		(fp_line
			(start 0.120396 0.2794)
			(end -0.12065 0.2794)
			(stroke
				(width 0.1)
				(type default)
			)
			(layer "F.Fab")
		)
		(fp_line
			(start -0.12065 -0.2794)
			(end 0.12065 -0.2794)
			(stroke
				(width 0.1)
				(type default)
			)
			(layer "F.Fab")
		)
		(fp_line
			(start 0.12065 -0.2794)
			(end 0.12065 -0.3048)
			(stroke
				(width 0.1)
				(type default)
			)
			(layer "F.Fab")
		)
		(fp_line
			(start 0.12065 -0.3048)
			(end 0.67945 -0.3048)
			(stroke
				(width 0.1)
				(type default)
			)
			(layer "F.Fab")
		)
		(fp_line
			(start 0.67945 -0.3048)
			(end 0.67945 0.3048)
			(stroke
				(width 0.1)
				(type default)
			)
			(layer "F.Fab")
		)
		(fp_line
			(start -0.67945 -0.305054)
			(end -0.12065 -0.305054)
			(stroke
				(width 0.1)
				(type default)
			)
			(layer "F.Fab")
		)
		(fp_line
			(start -0.12065 -0.305054)
			(end -0.12065 -0.2794)
			(stroke
				(width 0.1)
				(type default)
			)
			(layer "F.Fab")
		)
		(pad "1" smd circle
			(at -0.40005 0 270)
			(size 0 0)
			(layers "F.Cu" "F.Mask" "F.Paste")
			(net "P12V_SCM_ADC_ALERT_R")
		)
		(pad "2" smd circle
			(at 0.40005 0 270)
			(size 0 0)
			(layers "F.Cu" "F.Mask" "F.Paste")
			(net "P12V_SCM_ADC_ALERT")
		)
	)
	(footprint ""
		(layer "F.Cu")
		(at 179.939442 -26.240232)
		(property "Reference" "PC2241"
			(at 0 0 0)
			(layer "F.SilkS")
			(hide yes)
			(effects
				(font
					(size 1.27 1.27)
				)
			)
		)
		(property "Value" ""
			(at 0 0 0)
			(layer "F.Fab")
			(effects
				(font
					(size 1.27 1.27)
				)
			)
		)
		(duplicate_pad_numbers_are_jumpers no)
		(fp_line
			(start -0.7874 -0.4064)
			(end 0.7874 -0.4064)
			(stroke
				(width 0.1524)
				(type default)
			)
			(layer "F.SilkS")
		)
		(fp_line
			(start -0.7874 0.4064)
			(end -0.7874 -0.4064)
			(stroke
				(width 0.1524)
				(type default)
			)
			(layer "F.SilkS")
		)
		(fp_line
			(start 0.7874 -0.4064)
			(end 0.7874 0.4064)
			(stroke
				(width 0.1524)
				(type default)
			)
			(layer "F.SilkS")
		)
		(fp_line
			(start 0.7874 0.4064)
			(end -0.7874 0.4064)
			(stroke
				(width 0.1524)
				(type default)
			)
			(layer "F.SilkS")
		)
		(fp_line
			(start -0.67945 -0.305054)
			(end -0.12065 -0.305054)
			(stroke
				(width 0.1)
				(type default)
			)
			(layer "F.Fab")
		)
		(fp_line
			(start -0.67945 0.3048)
			(end -0.67945 -0.305054)
			(stroke
				(width 0.1)
				(type default)
			)
			(layer "F.Fab")
		)
		(fp_line
			(start -0.12065 -0.305054)
			(end -0.12065 -0.2794)
			(stroke
				(width 0.1)
				(type default)
			)
			(layer "F.Fab")
		)
		(fp_line
			(start -0.12065 -0.2794)
			(end 0.12065 -0.2794)
			(stroke
				(width 0.1)
				(type default)
			)
			(layer "F.Fab")
		)
		(fp_line
			(start -0.12065 0.2794)
			(end -0.12065 0.3048)
			(stroke
				(width 0.1)
				(type default)
			)
			(layer "F.Fab")
		)
		(fp_line
			(start -0.12065 0.3048)
			(end -0.67945 0.3048)
			(stroke
				(width 0.1)
				(type default)
			)
			(layer "F.Fab")
		)
		(fp_line
			(start 0.120396 0.2794)
			(end -0.12065 0.2794)
			(stroke
				(width 0.1)
				(type default)
			)
			(layer "F.Fab")
		)
		(fp_line
			(start 0.120396 0.3048)
			(end 0.120396 0.2794)
			(stroke
				(width 0.1)
				(type default)
			)
			(layer "F.Fab")
		)
		(fp_line
			(start 0.12065 -0.3048)
			(end 0.67945 -0.3048)
			(stroke
				(width 0.1)
				(type default)
			)
			(layer "F.Fab")
		)
		(fp_line
			(start 0.12065 -0.2794)
			(end 0.12065 -0.3048)
			(stroke
				(width 0.1)
				(type default)
			)
			(layer "F.Fab")
		)
		(fp_line
			(start 0.67945 -0.3048)
			(end 0.67945 0.3048)
			(stroke
				(width 0.1)
				(type default)
			)
			(layer "F.Fab")
		)
		(fp_line
			(start 0.67945 0.3048)
			(end 0.120396 0.3048)
			(stroke
				(width 0.1)
				(type default)
			)
			(layer "F.Fab")
		)
		(pad "1" smd circle
			(at -0.40005 0)
			(size 0 0)
			(layers "F.Cu" "F.Mask" "F.Paste")
			(net "P12V_SCM_R")
		)
		(pad "2" smd circle
			(at 0.40005 0)
			(size 0 0)
			(layers "F.Cu" "F.Mask" "F.Paste")
			(net "GND")
		)
	)
	(footprint ""
		(layer "F.Cu")
		(at 54.902354 -375.49963 -90)
		(property "Reference" "C823"
			(at 0 0 270)
			(layer "F.SilkS")
			(hide yes)
			(effects
				(font
					(size 1.27 1.27)
				)
			)
		)
		(property "Value" ""
			(at 0 0 270)
			(layer "F.Fab")
			(effects
				(font
					(size 1.27 1.27)
				)
			)
		)
		(duplicate_pad_numbers_are_jumpers no)
		(fp_line
			(start -0.299974 0.150114)
			(end -0.299974 -0.150114)
			(stroke
				(width 0.1)
				(type default)
			)
			(layer "F.Fab")
		)
		(fp_line
			(start 0.299974 0.150114)
			(end -0.299974 0.150114)
			(stroke
				(width 0.1)
				(type default)
			)
			(layer "F.Fab")
		)
		(fp_line
			(start -0.299974 -0.150114)
			(end 0.299974 -0.150114)
			(stroke
				(width 0.1)
				(type default)
			)
			(layer "F.Fab")
		)
		(fp_line
			(start 0.299974 -0.150114)
			(end 0.299974 0.150114)
			(stroke
				(width 0.1)
				(type default)
			)
			(layer "F.Fab")
		)
		(pad "1" smd rect
			(at -0.2667 0 270)
			(size 0.3048 0.381)
			(layers "F.Cu" "F.Mask" "F.Paste")
			(net "P5E_CPU1_P0_TX_C_DP<7>")
		)
		(pad "2" smd rect
			(at 0.2667 0 270)
			(size 0.3048 0.381)
			(layers "F.Cu" "F.Mask" "F.Paste")
			(net "P5E_CPU1_P0_TX_DP<7>")
		)
	)
	(footprint ""
		(layer "F.Cu")
		(at 366.403128 -324.29704 90)
		(property "Reference" "R2659"
			(at 0 0 90)
			(layer "F.SilkS")
			(hide yes)
			(effects
				(font
					(size 1.27 1.27)
				)
			)
		)
		(property "Value" ""
			(at 0 0 90)
			(layer "F.Fab")
			(effects
				(font
					(size 1.27 1.27)
				)
			)
		)
		(duplicate_pad_numbers_are_jumpers no)
		(fp_line
			(start -0.34544 -0.4064)
			(end 0.39116 -0.4064)
			(stroke
				(width 0.1524)
				(type default)
			)
			(layer "F.SilkS")
		)
		(fp_line
			(start 0.7874 0.017272)
			(end 0.7874 0.4064)
			(stroke
				(width 0.1524)
				(type default)
			)
			(layer "F.SilkS")
		)
		(fp_line
			(start 0.7874 0.4064)
			(end -0.7874 0.4064)
			(stroke
				(width 0.1524)
				(type default)
			)
			(layer "F.SilkS")
		)
		(fp_line
			(start -0.7874 0.4064)
			(end -0.7874 0.068072)
			(stroke
				(width 0.1524)
				(type default)
			)
			(layer "F.SilkS")
		)
		(fp_line
			(start -0.12065 -0.305054)
			(end -0.12065 -0.2794)
			(stroke
				(width 0.1)
				(type default)
			)
			(layer "F.Fab")
		)
		(fp_line
			(start -0.67945 -0.305054)
			(end -0.12065 -0.305054)
			(stroke
				(width 0.1)
				(type default)
			)
			(layer "F.Fab")
		)
		(fp_line
			(start 0.67945 -0.3048)
			(end 0.67945 0.3048)
			(stroke
				(width 0.1)
				(type default)
			)
			(layer "F.Fab")
		)
		(fp_line
			(start 0.12065 -0.3048)
			(end 0.67945 -0.3048)
			(stroke
				(width 0.1)
				(type default)
			)
			(layer "F.Fab")
		)
		(fp_line
			(start 0.12065 -0.2794)
			(end 0.12065 -0.3048)
			(stroke
				(width 0.1)
				(type default)
			)
			(layer "F.Fab")
		)
		(fp_line
			(start -0.12065 -0.2794)
			(end 0.12065 -0.2794)
			(stroke
				(width 0.1)
				(type default)
			)
			(layer "F.Fab")
		)
		(fp_line
			(start 0.120396 0.2794)
			(end -0.12065 0.2794)
			(stroke
				(width 0.1)
				(type default)
			)
			(layer "F.Fab")
		)
		(fp_line
			(start -0.12065 0.2794)
			(end -0.12065 0.3048)
			(stroke
				(width 0.1)
				(type default)
			)
			(layer "F.Fab")
		)
		(fp_line
			(start 0.67945 0.3048)
			(end 0.120396 0.3048)
			(stroke
				(width 0.1)
				(type default)
			)
			(layer "F.Fab")
		)
		(fp_line
			(start 0.120396 0.3048)
			(end 0.120396 0.2794)
			(stroke
				(width 0.1)
				(type default)
			)
			(layer "F.Fab")
		)
		(fp_line
			(start -0.12065 0.3048)
			(end -0.67945 0.3048)
			(stroke
				(width 0.1)
				(type default)
			)
			(layer "F.Fab")
		)
		(fp_line
			(start -0.67945 0.3048)
			(end -0.67945 -0.305054)
			(stroke
				(width 0.1)
				(type default)
			)
			(layer "F.Fab")
		)
		(pad "1" smd circle
			(at -0.40005 0 90)
			(size 0 0)
			(layers "F.Cu" "F.Mask" "F.Paste")
			(net "CLK_100M_CPU0_CLK11_R_DP")
		)
		(pad "2" smd circle
			(at 0.40005 0 90)
			(size 0 0)
			(layers "F.Cu" "F.Mask" "F.Paste")
			(net "CLK_100M_CPU0_CLK11_DP")
		)
	)
	(footprint ""
		(layer "F.Cu")
		(at 24.804878 -17.623536 90)
		(property "Reference" "C685"
			(at 0 0 90)
			(layer "F.SilkS")
			(hide yes)
			(effects
				(font
					(size 1.27 1.27)
				)
			)
		)
		(property "Value" ""
			(at 0 0 90)
			(layer "F.Fab")
			(effects
				(font
					(size 1.27 1.27)
				)
			)
		)
		(duplicate_pad_numbers_are_jumpers no)
		(fp_line
			(start 0.299974 -0.150114)
			(end 0.299974 0.150114)
			(stroke
				(width 0.1)
				(type default)
			)
			(layer "F.Fab")
		)
		(fp_line
			(start -0.299974 -0.150114)
			(end 0.299974 -0.150114)
			(stroke
				(width 0.1)
				(type default)
			)
			(layer "F.Fab")
		)
		(fp_line
			(start 0.299974 0.150114)
			(end -0.299974 0.150114)
			(stroke
				(width 0.1)
				(type default)
			)
			(layer "F.Fab")
		)
		(fp_line
			(start -0.299974 0.150114)
			(end -0.299974 -0.150114)
			(stroke
				(width 0.1)
				(type default)
			)
			(layer "F.Fab")
		)
		(pad "1" smd rect
			(at -0.2667 0 90)
			(size 0.3048 0.381)
			(layers "F.Cu" "F.Mask" "F.Paste")
			(net "P5E_CPU1_G1_TX_C_DP<12>")
		)
		(pad "2" smd rect
			(at 0.2667 0 90)
			(size 0.3048 0.381)
			(layers "F.Cu" "F.Mask" "F.Paste")
			(net "P5E_CPU1_G1_TX_DP<12>")
		)
	)
	(footprint ""
		(layer "F.Cu")
		(at 413.977582 -333.271114)
		(property "Reference" "TP8"
			(at -5.141722 -0.386588 0)
			(unlocked yes)
			(layer "F.SilkS")
			(effects
				(font
					(size 0.7874 0.5842)
					(thickness 0.1524)
				)
				(justify left)
			)
		)
		(property "Value" ""
			(at 0 0 0)
			(layer "F.Fab")
			(effects
				(font
					(size 1.27 1.27)
				)
			)
		)
		(duplicate_pad_numbers_are_jumpers no)
		(pad "1" smd circle
			(at 0 0)
			(size 0.762 0.762)
			(layers "F.Cu" "F.Mask" "F.Paste")
			(net "VSENSE_PVDD11_S3_P0_DP")
		)
	)
	(footprint ""
		(layer "F.Cu")
		(at 393.092178 -182.745634 90)
		(property "Reference" "PC549_C0P0_4"
			(at 0 0 90)
			(layer "F.SilkS")
			(hide yes)
			(effects
				(font
					(size 1.27 1.27)
				)
			)
		)
		(property "Value" ""
			(at 0 0 90)
			(layer "F.Fab")
			(effects
				(font
					(size 1.27 1.27)
				)
			)
		)
		(duplicate_pad_numbers_are_jumpers no)
		(fp_line
			(start 0.7874 -0.4064)
			(end 0.7874 0.4064)
			(stroke
				(width 0.1524)
				(type default)
			)
			(layer "F.SilkS")
		)
		(fp_line
			(start -0.7874 -0.4064)
			(end 0.7874 -0.4064)
			(stroke
				(width 0.1524)
				(type default)
			)
			(layer "F.SilkS")
		)
		(fp_line
			(start 0.7874 0.4064)
			(end -0.7874 0.4064)
			(stroke
				(width 0.1524)
				(type default)
			)
			(layer "F.SilkS")
		)
		(fp_line
			(start -0.7874 0.4064)
			(end -0.7874 -0.4064)
			(stroke
				(width 0.1524)
				(type default)
			)
			(layer "F.SilkS")
		)
		(fp_line
			(start -0.12065 -0.305054)
			(end -0.12065 -0.2794)
			(stroke
				(width 0.1)
				(type default)
			)
			(layer "F.Fab")
		)
		(fp_line
			(start -0.67945 -0.305054)
			(end -0.12065 -0.305054)
			(stroke
				(width 0.1)
				(type default)
			)
			(layer "F.Fab")
		)
		(fp_line
			(start 0.67945 -0.3048)
			(end 0.67945 0.3048)
			(stroke
				(width 0.1)
				(type default)
			)
			(layer "F.Fab")
		)
		(fp_line
			(start 0.12065 -0.3048)
			(end 0.67945 -0.3048)
			(stroke
				(width 0.1)
				(type default)
			)
			(layer "F.Fab")
		)
		(fp_line
			(start 0.12065 -0.2794)
			(end 0.12065 -0.3048)
			(stroke
				(width 0.1)
				(type default)
			)
			(layer "F.Fab")
		)
		(fp_line
			(start -0.12065 -0.2794)
			(end 0.12065 -0.2794)
			(stroke
				(width 0.1)
				(type default)
			)
			(layer "F.Fab")
		)
		(fp_line
			(start 0.120396 0.2794)
			(end -0.12065 0.2794)
			(stroke
				(width 0.1)
				(type default)
			)
			(layer "F.Fab")
		)
		(fp_line
			(start -0.12065 0.2794)
			(end -0.12065 0.3048)
			(stroke
				(width 0.1)
				(type default)
			)
			(layer "F.Fab")
		)
		(fp_line
			(start 0.67945 0.3048)
			(end 0.120396 0.3048)
			(stroke
				(width 0.1)
				(type default)
			)
			(layer "F.Fab")
		)
		(fp_line
			(start 0.120396 0.3048)
			(end 0.120396 0.2794)
			(stroke
				(width 0.1)
				(type default)
			)
			(layer "F.Fab")
		)
		(fp_line
			(start -0.12065 0.3048)
			(end -0.67945 0.3048)
			(stroke
				(width 0.1)
				(type default)
			)
			(layer "F.Fab")
		)
		(fp_line
			(start -0.67945 0.3048)
			(end -0.67945 -0.305054)
			(stroke
				(width 0.1)
				(type default)
			)
			(layer "F.Fab")
		)
		(pad "1" smd circle
			(at -0.40005 0 90)
			(size 0 0)
			(layers "F.Cu" "F.Mask" "F.Paste")
			(net "PVDDCR_CPU0_P0_PVCC")
		)
		(pad "2" smd circle
			(at 0.40005 0 90)
			(size 0 0)
			(layers "F.Cu" "F.Mask" "F.Paste")
			(net "GND")
		)
	)
	(footprint ""
		(layer "F.Cu")
		(at 419.95344 -381.41783 -90)
		(property "Reference" "C846"
			(at 0 0 270)
			(layer "F.SilkS")
			(hide yes)
			(effects
				(font
					(size 1.27 1.27)
				)
			)
		)
		(property "Value" ""
			(at 0 0 270)
			(layer "F.Fab")
			(effects
				(font
					(size 1.27 1.27)
				)
			)
		)
		(duplicate_pad_numbers_are_jumpers no)
		(fp_line
			(start -0.299974 0.150114)
			(end -0.299974 -0.150114)
			(stroke
				(width 0.1)
				(type default)
			)
			(layer "F.Fab")
		)
		(fp_line
			(start 0.299974 0.150114)
			(end -0.299974 0.150114)
			(stroke
				(width 0.1)
				(type default)
			)
			(layer "F.Fab")
		)
		(fp_line
			(start -0.299974 -0.150114)
			(end 0.299974 -0.150114)
			(stroke
				(width 0.1)
				(type default)
			)
			(layer "F.Fab")
		)
		(fp_line
			(start 0.299974 -0.150114)
			(end 0.299974 0.150114)
			(stroke
				(width 0.1)
				(type default)
			)
			(layer "F.Fab")
		)
		(pad "1" smd rect
			(at -0.2667 0 270)
			(size 0.3048 0.381)
			(layers "F.Cu" "F.Mask" "F.Paste")
			(net "P5E_CPU0_P2_TX_C_DN<11>")
		)
		(pad "2" smd rect
			(at 0.2667 0 270)
			(size 0.3048 0.381)
			(layers "F.Cu" "F.Mask" "F.Paste")
			(net "P5E_CPU0_P2_TX_DN<11>")
		)
	)
	(footprint ""
		(layer "F.Cu")
		(at 322.603876 -70.098412 90)
		(property "Reference" "D73"
			(at -3.934714 -0.691642 90)
			(unlocked yes)
			(layer "F.SilkS")
			(effects
				(font
					(size 0.7874 0.5842)
					(thickness 0.1524)
				)
				(justify left)
			)
		)
		(property "Value" ""
			(at 0 0 90)
			(layer "F.Fab")
			(effects
				(font
					(size 1.27 1.27)
				)
			)
		)
		(duplicate_pad_numbers_are_jumpers no)
		(fp_line
			(start 1.16078 -0.4826)
			(end 1.16078 0.4826)
			(stroke
				(width 0.1524)
				(type default)
			)
			(layer "F.SilkS")
		)
		(fp_line
			(start 1.03378 -0.4826)
			(end 1.03378 0.4826)
			(stroke
				(width 0.1524)
				(type default)
			)
			(layer "F.SilkS")
		)
		(fp_line
			(start 0.90678 -0.4826)
			(end 0.90678 0.4826)
			(stroke
				(width 0.1524)
				(type default)
			)
			(layer "F.SilkS")
		)
		(fp_line
			(start -0.64008 -0.4826)
			(end 1.16078 -0.4826)
			(stroke
				(width 0.1524)
				(type default)
			)
			(layer "F.SilkS")
		)
		(fp_line
			(start -0.79248 -0.4826)
			(end 1.03378 -0.4826)
			(stroke
				(width 0.1524)
				(type default)
			)
			(layer "F.SilkS")
		)
		(fp_line
			(start -0.89408 -0.4826)
			(end 0.90678 -0.4826)
			(stroke
				(width 0.1524)
				(type default)
			)
			(layer "F.SilkS")
		)
		(fp_line
			(start 1.16078 0.4826)
			(end -0.64008 0.4826)
			(stroke
				(width 0.1524)
				(type default)
			)
			(layer "F.SilkS")
		)
		(fp_line
			(start 1.03378 0.4826)
			(end -0.79248 0.4826)
			(stroke
				(width 0.1524)
				(type default)
			)
			(layer "F.SilkS")
		)
		(fp_line
			(start 0.90678 0.4826)
			(end -0.90678 0.4826)
			(stroke
				(width 0.1524)
				(type default)
			)
			(layer "F.SilkS")
		)
		(fp_line
			(start -0.90678 0.4826)
			(end -0.90678 -0.4699)
			(stroke
				(width 0.1524)
				(type default)
			)
			(layer "F.SilkS")
		)
		(fp_line
			(start 0.499872 -0.249936)
			(end 0.499872 0.249936)
			(stroke
				(width 0.1)
				(type default)
			)
			(layer "F.Fab")
		)
		(fp_line
			(start -0.499872 -0.249936)
			(end 0.499872 -0.249936)
			(stroke
				(width 0.1)
				(type default)
			)
			(layer "F.Fab")
		)
		(fp_line
			(start 0.499872 0.249936)
			(end -0.499872 0.249936)
			(stroke
				(width 0.1)
				(type default)
			)
			(layer "F.Fab")
		)
		(fp_line
			(start -0.499872 0.249936)
			(end -0.499872 -0.249936)
			(stroke
				(width 0.1)
				(type default)
			)
			(layer "F.Fab")
		)
		(pad "A" smd rect
			(at -0.47498 0 90)
			(size 0.6096 0.7112)
			(layers "F.Cu" "F.Mask" "F.Paste")
			(net "LED_PWRGD_PVDD33_S5_R")
		)
		(pad "C" smd rect
			(at 0.47498 0 90)
			(size 0.6096 0.7112)
			(layers "F.Cu" "F.Mask" "F.Paste")
			(net "LED_PWRGD_PVDD33_S5_D")
		)
	)
	(footprint ""
		(layer "F.Cu")
		(at 436.526432 -26.056336 90)
		(property "Reference" "PR3840"
			(at 0 0 90)
			(layer "F.SilkS")
			(hide yes)
			(effects
				(font
					(size 1.27 1.27)
				)
			)
		)
		(property "Value" ""
			(at 0 0 90)
			(layer "F.Fab")
			(effects
				(font
					(size 1.27 1.27)
				)
			)
		)
		(duplicate_pad_numbers_are_jumpers no)
		(fp_line
			(start 0.7874 -0.4064)
			(end 0.7874 0.4064)
			(stroke
				(width 0.1524)
				(type default)
			)
			(layer "F.SilkS")
		)
		(fp_line
			(start -0.7874 -0.4064)
			(end 0.7874 -0.4064)
			(stroke
				(width 0.1524)
				(type default)
			)
			(layer "F.SilkS")
		)
		(fp_line
			(start 0.7874 0.4064)
			(end -0.7874 0.4064)
			(stroke
				(width 0.1524)
				(type default)
			)
			(layer "F.SilkS")
		)
		(fp_line
			(start -0.7874 0.4064)
			(end -0.7874 -0.4064)
			(stroke
				(width 0.1524)
				(type default)
			)
			(layer "F.SilkS")
		)
		(fp_line
			(start -0.12065 -0.305054)
			(end -0.12065 -0.2794)
			(stroke
				(width 0.1)
				(type default)
			)
			(layer "F.Fab")
		)
		(fp_line
			(start -0.67945 -0.305054)
			(end -0.12065 -0.305054)
			(stroke
				(width 0.1)
				(type default)
			)
			(layer "F.Fab")
		)
		(fp_line
			(start 0.67945 -0.3048)
			(end 0.67945 0.3048)
			(stroke
				(width 0.1)
				(type default)
			)
			(layer "F.Fab")
		)
		(fp_line
			(start 0.12065 -0.3048)
			(end 0.67945 -0.3048)
			(stroke
				(width 0.1)
				(type default)
			)
			(layer "F.Fab")
		)
		(fp_line
			(start 0.12065 -0.2794)
			(end 0.12065 -0.3048)
			(stroke
				(width 0.1)
				(type default)
			)
			(layer "F.Fab")
		)
		(fp_line
			(start -0.12065 -0.2794)
			(end 0.12065 -0.2794)
			(stroke
				(width 0.1)
				(type default)
			)
			(layer "F.Fab")
		)
		(fp_line
			(start 0.120396 0.2794)
			(end -0.12065 0.2794)
			(stroke
				(width 0.1)
				(type default)
			)
			(layer "F.Fab")
		)
		(fp_line
			(start -0.12065 0.2794)
			(end -0.12065 0.3048)
			(stroke
				(width 0.1)
				(type default)
			)
			(layer "F.Fab")
		)
		(fp_line
			(start 0.67945 0.3048)
			(end 0.120396 0.3048)
			(stroke
				(width 0.1)
				(type default)
			)
			(layer "F.Fab")
		)
		(fp_line
			(start 0.120396 0.3048)
			(end 0.120396 0.2794)
			(stroke
				(width 0.1)
				(type default)
			)
			(layer "F.Fab")
		)
		(fp_line
			(start -0.12065 0.3048)
			(end -0.67945 0.3048)
			(stroke
				(width 0.1)
				(type default)
			)
			(layer "F.Fab")
		)
		(fp_line
			(start -0.67945 0.3048)
			(end -0.67945 -0.305054)
			(stroke
				(width 0.1)
				(type default)
			)
			(layer "F.Fab")
		)
		(pad "1" smd circle
			(at -0.40005 0 90)
			(size 0 0)
			(layers "F.Cu" "F.Mask" "F.Paste")
			(net "P12V_OCP_SFF")
		)
		(pad "2" smd circle
			(at 0.40005 0 90)
			(size 0 0)
			(layers "F.Cu" "F.Mask" "F.Paste")
			(net "P12V_OCP_OV_FB_1")
		)
	)
	(footprint ""
		(layer "F.Cu")
		(at 136.652 -113.157)
		(property "Reference" "C8019"
			(at 0 0 0)
			(layer "F.SilkS")
			(hide yes)
			(effects
				(font
					(size 1.27 1.27)
				)
			)
		)
		(property "Value" ""
			(at 0 0 0)
			(layer "F.Fab")
			(effects
				(font
					(size 1.27 1.27)
				)
			)
		)
		(duplicate_pad_numbers_are_jumpers no)
		(fp_line
			(start -0.7874 -0.4064)
			(end 0.7874 -0.4064)
			(stroke
				(width 0.1524)
				(type default)
			)
			(layer "F.SilkS")
		)
		(fp_line
			(start -0.7874 0.4064)
			(end -0.7874 -0.4064)
			(stroke
				(width 0.1524)
				(type default)
			)
			(layer "F.SilkS")
		)
		(fp_line
			(start 0.7874 -0.4064)
			(end 0.7874 0.4064)
			(stroke
				(width 0.1524)
				(type default)
			)
			(layer "F.SilkS")
		)
		(fp_line
			(start 0.7874 0.4064)
			(end -0.7874 0.4064)
			(stroke
				(width 0.1524)
				(type default)
			)
			(layer "F.SilkS")
		)
		(fp_line
			(start -0.67945 -0.305054)
			(end -0.12065 -0.305054)
			(stroke
				(width 0.1)
				(type default)
			)
			(layer "F.Fab")
		)
		(fp_line
			(start -0.67945 0.3048)
			(end -0.67945 -0.305054)
			(stroke
				(width 0.1)
				(type default)
			)
			(layer "F.Fab")
		)
		(fp_line
			(start -0.12065 -0.305054)
			(end -0.12065 -0.2794)
			(stroke
				(width 0.1)
				(type default)
			)
			(layer "F.Fab")
		)
		(fp_line
			(start -0.12065 -0.2794)
			(end 0.12065 -0.2794)
			(stroke
				(width 0.1)
				(type default)
			)
			(layer "F.Fab")
		)
		(fp_line
			(start -0.12065 0.2794)
			(end -0.12065 0.3048)
			(stroke
				(width 0.1)
				(type default)
			)
			(layer "F.Fab")
		)
		(fp_line
			(start -0.12065 0.3048)
			(end -0.67945 0.3048)
			(stroke
				(width 0.1)
				(type default)
			)
			(layer "F.Fab")
		)
		(fp_line
			(start 0.120396 0.2794)
			(end -0.12065 0.2794)
			(stroke
				(width 0.1)
				(type default)
			)
			(layer "F.Fab")
		)
		(fp_line
			(start 0.120396 0.3048)
			(end 0.120396 0.2794)
			(stroke
				(width 0.1)
				(type default)
			)
			(layer "F.Fab")
		)
		(fp_line
			(start 0.12065 -0.3048)
			(end 0.67945 -0.3048)
			(stroke
				(width 0.1)
				(type default)
			)
			(layer "F.Fab")
		)
		(fp_line
			(start 0.12065 -0.2794)
			(end 0.12065 -0.3048)
			(stroke
				(width 0.1)
				(type default)
			)
			(layer "F.Fab")
		)
		(fp_line
			(start 0.67945 -0.3048)
			(end 0.67945 0.3048)
			(stroke
				(width 0.1)
				(type default)
			)
			(layer "F.Fab")
		)
		(fp_line
			(start 0.67945 0.3048)
			(end 0.120396 0.3048)
			(stroke
				(width 0.1)
				(type default)
			)
			(layer "F.Fab")
		)
		(pad "1" smd circle
			(at -0.40005 0)
			(size 0 0)
			(layers "F.Cu" "F.Mask" "F.Paste")
			(net "P12V_AUX")
		)
		(pad "2" smd circle
			(at 0.40005 0)
			(size 0 0)
			(layers "F.Cu" "F.Mask" "F.Paste")
			(net "GND")
		)
	)
	(footprint ""
		(layer "F.Cu")
		(at 333.629 -160.909 90)
		(property "Reference" "PC115"
			(at -0.889 -3.52933 90)
			(unlocked yes)
			(layer "F.SilkS")
			(effects
				(font
					(size 0.7874 0.5842)
					(thickness 0.1524)
				)
				(justify left)
			)
		)
		(property "Value" ""
			(at 0 0 90)
			(layer "F.Fab")
			(effects
				(font
					(size 1.27 1.27)
				)
			)
		)
		(duplicate_pad_numbers_are_jumpers no)
		(fp_line
			(start 2.750058 -2.750058)
			(end -1.988058 -2.750058)
			(stroke
				(width 0.1524)
				(type default)
			)
			(layer "F.SilkS")
		)
		(fp_line
			(start -1.988058 -2.750058)
			(end -2.750058 -1.988058)
			(stroke
				(width 0.1524)
				(type default)
			)
			(layer "F.SilkS")
		)
		(fp_line
			(start -2.750058 -1.988058)
			(end -2.750058 -0.9398)
			(stroke
				(width 0.1524)
				(type default)
			)
			(layer "F.SilkS")
		)
		(fp_line
			(start 2.750058 -0.9398)
			(end 2.750058 -2.750058)
			(stroke
				(width 0.1524)
				(type default)
			)
			(layer "F.SilkS")
		)
		(fp_line
			(start -2.750058 0.9398)
			(end -2.750058 1.988058)
			(stroke
				(width 0.1524)
				(type default)
			)
			(layer "F.SilkS")
		)
		(fp_line
			(start -2.750058 1.988058)
			(end -1.988058 2.750058)
			(stroke
				(width 0.1524)
				(type default)
			)
			(layer "F.SilkS")
		)
		(fp_line
			(start 2.750058 2.750058)
			(end 2.750058 0.9398)
			(stroke
				(width 0.1524)
				(type default)
			)
			(layer "F.SilkS")
		)
		(fp_line
			(start -1.988058 2.750058)
			(end 2.750058 2.750058)
			(stroke
				(width 0.1524)
				(type default)
			)
			(layer "F.SilkS")
		)
		(fp_line
			(start 2.750058 -2.750058)
			(end -2.750058 -2.750058)
			(stroke
				(width 0.1)
				(type default)
			)
			(layer "F.Fab")
		)
		(fp_line
			(start -2.750058 -2.750058)
			(end -2.750058 2.750058)
			(stroke
				(width 0.1)
				(type default)
			)
			(layer "F.Fab")
		)
		(fp_line
			(start 2.750058 2.750058)
			(end 2.750058 -2.750058)
			(stroke
				(width 0.1)
				(type default)
			)
			(layer "F.Fab")
		)
		(fp_line
			(start -2.750058 2.750058)
			(end 2.750058 2.750058)
			(stroke
				(width 0.1)
				(type default)
			)
			(layer "F.Fab")
		)
		(pad "1" smd rect
			(at -2.199894 0 180)
			(size 1.6002 3.0226)
			(layers "F.Cu" "F.Mask" "F.Paste")
			(net "PVDD18_S5_P0")
		)
		(pad "2" smd rect
			(at 2.199894 0 180)
			(size 1.6002 3.0226)
			(layers "F.Cu" "F.Mask" "F.Paste")
			(net "GND")
		)
	)
	(footprint ""
		(layer "F.Cu")
		(at 63.15075 -193.594228)
		(property "Reference" "TP14"
			(at 0 0 0)
			(layer "F.SilkS")
			(hide yes)
			(effects
				(font
					(size 1.27 1.27)
				)
			)
		)
		(property "Value" ""
			(at 0 0 0)
			(layer "F.Fab")
			(effects
				(font
					(size 1.27 1.27)
				)
			)
		)
		(duplicate_pad_numbers_are_jumpers no)
		(pad "1" smd circle
			(at 0 0)
			(size 0.762 0.762)
			(layers "F.Cu" "F.Mask" "F.Paste")
			(net "VSENSE_PVDD18_S5_P1_DN")
		)
	)
	(footprint ""
		(layer "F.Cu")
		(at 303.861724 -406.133808)
		(property "Reference" "C556"
			(at 0 0 0)
			(layer "F.SilkS")
			(hide yes)
			(effects
				(font
					(size 1.27 1.27)
				)
			)
		)
		(property "Value" ""
			(at 0 0 0)
			(layer "F.Fab")
			(effects
				(font
					(size 1.27 1.27)
				)
			)
		)
		(duplicate_pad_numbers_are_jumpers no)
		(fp_line
			(start -1.524 -0.762)
			(end 1.524 -0.762)
			(stroke
				(width 0.1524)
				(type default)
			)
			(layer "F.SilkS")
		)
		(fp_line
			(start -1.524 0.762)
			(end -1.524 -0.762)
			(stroke
				(width 0.1524)
				(type default)
			)
			(layer "F.SilkS")
		)
		(fp_line
			(start 1.524 -0.762)
			(end 1.524 0.762)
			(stroke
				(width 0.1524)
				(type default)
			)
			(layer "F.SilkS")
		)
		(fp_line
			(start 1.524 0.762)
			(end -1.524 0.762)
			(stroke
				(width 0.1524)
				(type default)
			)
			(layer "F.SilkS")
		)
		(fp_line
			(start -1.1049 -0.724916)
			(end -1.1049 0.724916)
			(stroke
				(width 0.1)
				(type default)
			)
			(layer "F.Fab")
		)
		(fp_line
			(start -1.1049 0.724916)
			(end 1.1049 0.724916)
			(stroke
				(width 0.1)
				(type default)
			)
			(layer "F.Fab")
		)
		(fp_line
			(start 1.1049 -0.724916)
			(end -1.1049 -0.724916)
			(stroke
				(width 0.1)
				(type default)
			)
			(layer "F.Fab")
		)
		(fp_line
			(start 1.1049 0.724916)
			(end 1.1049 -0.724916)
			(stroke
				(width 0.1)
				(type default)
			)
			(layer "F.Fab")
		)
		(pad "1" smd rect
			(at -0.889 0 180)
			(size 1.016 1.27)
			(layers "F.Cu" "F.Mask" "F.Paste")
			(net "P0V9_CPU0_RT0_2A")
		)
		(pad "2" smd rect
			(at 0.889 0 180)
			(size 1.016 1.27)
			(layers "F.Cu" "F.Mask" "F.Paste")
			(net "GND")
		)
	)
	(footprint ""
		(layer "F.Cu")
		(at 90.819478 -149.96541 180)
		(property "Reference" "PR151"
			(at 0 0 180)
			(layer "F.SilkS")
			(hide yes)
			(effects
				(font
					(size 1.27 1.27)
				)
			)
		)
		(property "Value" ""
			(at 0 0 180)
			(layer "F.Fab")
			(effects
				(font
					(size 1.27 1.27)
				)
			)
		)
		(duplicate_pad_numbers_are_jumpers no)
		(fp_line
			(start 0.7874 0.4064)
			(end -0.7874 0.4064)
			(stroke
				(width 0.1524)
				(type default)
			)
			(layer "F.SilkS")
		)
		(fp_line
			(start 0.7874 -0.4064)
			(end 0.7874 0.4064)
			(stroke
				(width 0.1524)
				(type default)
			)
			(layer "F.SilkS")
		)
		(fp_line
			(start -0.7874 0.4064)
			(end -0.7874 -0.4064)
			(stroke
				(width 0.1524)
				(type default)
			)
			(layer "F.SilkS")
		)
		(fp_line
			(start -0.7874 -0.4064)
			(end 0.7874 -0.4064)
			(stroke
				(width 0.1524)
				(type default)
			)
			(layer "F.SilkS")
		)
		(fp_line
			(start 0.67945 0.3048)
			(end 0.120396 0.3048)
			(stroke
				(width 0.1)
				(type default)
			)
			(layer "F.Fab")
		)
		(fp_line
			(start 0.67945 -0.3048)
			(end 0.67945 0.3048)
			(stroke
				(width 0.1)
				(type default)
			)
			(layer "F.Fab")
		)
		(fp_line
			(start 0.12065 -0.2794)
			(end 0.12065 -0.3048)
			(stroke
				(width 0.1)
				(type default)
			)
			(layer "F.Fab")
		)
		(fp_line
			(start 0.12065 -0.3048)
			(end 0.67945 -0.3048)
			(stroke
				(width 0.1)
				(type default)
			)
			(layer "F.Fab")
		)
		(fp_line
			(start 0.120396 0.3048)
			(end 0.120396 0.2794)
			(stroke
				(width 0.1)
				(type default)
			)
			(layer "F.Fab")
		)
		(fp_line
			(start 0.120396 0.2794)
			(end -0.12065 0.2794)
			(stroke
				(width 0.1)
				(type default)
			)
			(layer "F.Fab")
		)
		(fp_line
			(start -0.12065 0.3048)
			(end -0.67945 0.3048)
			(stroke
				(width 0.1)
				(type default)
			)
			(layer "F.Fab")
		)
		(fp_line
			(start -0.12065 0.2794)
			(end -0.12065 0.3048)
			(stroke
				(width 0.1)
				(type default)
			)
			(layer "F.Fab")
		)
		(fp_line
			(start -0.12065 -0.2794)
			(end 0.12065 -0.2794)
			(stroke
				(width 0.1)
				(type default)
			)
			(layer "F.Fab")
		)
		(fp_line
			(start -0.12065 -0.305054)
			(end -0.12065 -0.2794)
			(stroke
				(width 0.1)
				(type default)
			)
			(layer "F.Fab")
		)
		(fp_line
			(start -0.67945 0.3048)
			(end -0.67945 -0.305054)
			(stroke
				(width 0.1)
				(type default)
			)
			(layer "F.Fab")
		)
		(fp_line
			(start -0.67945 -0.305054)
			(end -0.12065 -0.305054)
			(stroke
				(width 0.1)
				(type default)
			)
			(layer "F.Fab")
		)
		(pad "1" smd circle
			(at -0.40005 0 180)
			(size 0 0)
			(layers "F.Cu" "F.Mask" "F.Paste")
			(net "PVDD18_S5_P1")
		)
		(pad "2" smd circle
			(at 0.40005 0 180)
			(size 0 0)
			(layers "F.Cu" "F.Mask" "F.Paste")
			(net "SVID_PVDDCR_CPU0_P1_SVTI")
		)
	)
	(footprint ""
		(layer "F.Cu")
		(at 180.824378 -153.632662 -90)
		(property "Reference" "C42"
			(at 0 0 270)
			(layer "F.SilkS")
			(hide yes)
			(effects
				(font
					(size 1.27 1.27)
				)
			)
		)
		(property "Value" ""
			(at 0 0 270)
			(layer "F.Fab")
			(effects
				(font
					(size 1.27 1.27)
				)
			)
		)
		(duplicate_pad_numbers_are_jumpers no)
		(fp_line
			(start -0.7874 0.4064)
			(end -0.7874 -0.4064)
			(stroke
				(width 0.1524)
				(type default)
			)
			(layer "F.SilkS")
		)
		(fp_line
			(start 0.7874 0.4064)
			(end -0.7874 0.4064)
			(stroke
				(width 0.1524)
				(type default)
			)
			(layer "F.SilkS")
		)
		(fp_line
			(start -0.7874 -0.4064)
			(end 0.7874 -0.4064)
			(stroke
				(width 0.1524)
				(type default)
			)
			(layer "F.SilkS")
		)
		(fp_line
			(start 0.7874 -0.4064)
			(end 0.7874 0.4064)
			(stroke
				(width 0.1524)
				(type default)
			)
			(layer "F.SilkS")
		)
		(fp_line
			(start -0.67945 0.3048)
			(end -0.67945 -0.305054)
			(stroke
				(width 0.1)
				(type default)
			)
			(layer "F.Fab")
		)
		(fp_line
			(start -0.12065 0.3048)
			(end -0.67945 0.3048)
			(stroke
				(width 0.1)
				(type default)
			)
			(layer "F.Fab")
		)
		(fp_line
			(start 0.120396 0.3048)
			(end 0.120396 0.2794)
			(stroke
				(width 0.1)
				(type default)
			)
			(layer "F.Fab")
		)
		(fp_line
			(start 0.67945 0.3048)
			(end 0.120396 0.3048)
			(stroke
				(width 0.1)
				(type default)
			)
			(layer "F.Fab")
		)
		(fp_line
			(start -0.12065 0.2794)
			(end -0.12065 0.3048)
			(stroke
				(width 0.1)
				(type default)
			)
			(layer "F.Fab")
		)
		(fp_line
			(start 0.120396 0.2794)
			(end -0.12065 0.2794)
			(stroke
				(width 0.1)
				(type default)
			)
			(layer "F.Fab")
		)
		(fp_line
			(start -0.12065 -0.2794)
			(end 0.12065 -0.2794)
			(stroke
				(width 0.1)
				(type default)
			)
			(layer "F.Fab")
		)
		(fp_line
			(start 0.12065 -0.2794)
			(end 0.12065 -0.3048)
			(stroke
				(width 0.1)
				(type default)
			)
			(layer "F.Fab")
		)
		(fp_line
			(start 0.12065 -0.3048)
			(end 0.67945 -0.3048)
			(stroke
				(width 0.1)
				(type default)
			)
			(layer "F.Fab")
		)
		(fp_line
			(start 0.67945 -0.3048)
			(end 0.67945 0.3048)
			(stroke
				(width 0.1)
				(type default)
			)
			(layer "F.Fab")
		)
		(fp_line
			(start -0.67945 -0.305054)
			(end -0.12065 -0.305054)
			(stroke
				(width 0.1)
				(type default)
			)
			(layer "F.Fab")
		)
		(fp_line
			(start -0.12065 -0.305054)
			(end -0.12065 -0.2794)
			(stroke
				(width 0.1)
				(type default)
			)
			(layer "F.Fab")
		)
		(pad "1" smd circle
			(at -0.40005 0 270)
			(size 0 0)
			(layers "F.Cu" "F.Mask" "F.Paste")
			(net "PVDD18_S5_P0")
		)
		(pad "2" smd circle
			(at 0.40005 0 270)
			(size 0 0)
			(layers "F.Cu" "F.Mask" "F.Paste")
			(net "GND")
		)
	)
	(footprint ""
		(layer "F.Cu")
		(at 201.636884 -337.480148)
		(property "Reference" "PC126"
			(at 0 0 0)
			(layer "F.SilkS")
			(hide yes)
			(effects
				(font
					(size 1.27 1.27)
				)
			)
		)
		(property "Value" ""
			(at 0 0 0)
			(layer "F.Fab")
			(effects
				(font
					(size 1.27 1.27)
				)
			)
		)
		(duplicate_pad_numbers_are_jumpers no)
		(fp_line
			(start -0.7874 -0.4064)
			(end 0.7874 -0.4064)
			(stroke
				(width 0.1524)
				(type default)
			)
			(layer "F.SilkS")
		)
		(fp_line
			(start -0.7874 0.4064)
			(end -0.7874 -0.4064)
			(stroke
				(width 0.1524)
				(type default)
			)
			(layer "F.SilkS")
		)
		(fp_line
			(start 0.7874 -0.4064)
			(end 0.7874 0.4064)
			(stroke
				(width 0.1524)
				(type default)
			)
			(layer "F.SilkS")
		)
		(fp_line
			(start 0.7874 0.4064)
			(end -0.7874 0.4064)
			(stroke
				(width 0.1524)
				(type default)
			)
			(layer "F.SilkS")
		)
		(fp_line
			(start -0.67945 -0.305054)
			(end -0.12065 -0.305054)
			(stroke
				(width 0.1)
				(type default)
			)
			(layer "F.Fab")
		)
		(fp_line
			(start -0.67945 0.3048)
			(end -0.67945 -0.305054)
			(stroke
				(width 0.1)
				(type default)
			)
			(layer "F.Fab")
		)
		(fp_line
			(start -0.12065 -0.305054)
			(end -0.12065 -0.2794)
			(stroke
				(width 0.1)
				(type default)
			)
			(layer "F.Fab")
		)
		(fp_line
			(start -0.12065 -0.2794)
			(end 0.12065 -0.2794)
			(stroke
				(width 0.1)
				(type default)
			)
			(layer "F.Fab")
		)
		(fp_line
			(start -0.12065 0.2794)
			(end -0.12065 0.3048)
			(stroke
				(width 0.1)
				(type default)
			)
			(layer "F.Fab")
		)
		(fp_line
			(start -0.12065 0.3048)
			(end -0.67945 0.3048)
			(stroke
				(width 0.1)
				(type default)
			)
			(layer "F.Fab")
		)
		(fp_line
			(start 0.120396 0.2794)
			(end -0.12065 0.2794)
			(stroke
				(width 0.1)
				(type default)
			)
			(layer "F.Fab")
		)
		(fp_line
			(start 0.120396 0.3048)
			(end 0.120396 0.2794)
			(stroke
				(width 0.1)
				(type default)
			)
			(layer "F.Fab")
		)
		(fp_line
			(start 0.12065 -0.3048)
			(end 0.67945 -0.3048)
			(stroke
				(width 0.1)
				(type default)
			)
			(layer "F.Fab")
		)
		(fp_line
			(start 0.12065 -0.2794)
			(end 0.12065 -0.3048)
			(stroke
				(width 0.1)
				(type default)
			)
			(layer "F.Fab")
		)
		(fp_line
			(start 0.67945 -0.3048)
			(end 0.67945 0.3048)
			(stroke
				(width 0.1)
				(type default)
			)
			(layer "F.Fab")
		)
		(fp_line
			(start 0.67945 0.3048)
			(end 0.120396 0.3048)
			(stroke
				(width 0.1)
				(type default)
			)
			(layer "F.Fab")
		)
		(pad "1" smd circle
			(at -0.40005 0)
			(size 0 0)
			(layers "F.Cu" "F.Mask" "F.Paste")
			(net "SW_P12V_AUX_PVDD_33_S5_FLT")
		)
		(pad "2" smd circle
			(at 0.40005 0)
			(size 0 0)
			(layers "F.Cu" "F.Mask" "F.Paste")
			(net "GND")
		)
	)
	(footprint ""
		(layer "F.Cu")
		(at 124.633228 -48.137064)
		(property "Reference" "R4451"
			(at 0 0 0)
			(layer "F.SilkS")
			(hide yes)
			(effects
				(font
					(size 1.27 1.27)
				)
			)
		)
		(property "Value" ""
			(at 0 0 0)
			(layer "F.Fab")
			(effects
				(font
					(size 1.27 1.27)
				)
			)
		)
		(duplicate_pad_numbers_are_jumpers no)
		(fp_line
			(start -0.7874 -0.4064)
			(end 0.7874 -0.4064)
			(stroke
				(width 0.1524)
				(type default)
			)
			(layer "F.SilkS")
		)
		(fp_line
			(start -0.7874 0.4064)
			(end -0.7874 -0.4064)
			(stroke
				(width 0.1524)
				(type default)
			)
			(layer "F.SilkS")
		)
		(fp_line
			(start 0.7874 -0.4064)
			(end 0.7874 0.4064)
			(stroke
				(width 0.1524)
				(type default)
			)
			(layer "F.SilkS")
		)
		(fp_line
			(start 0.7874 0.4064)
			(end -0.7874 0.4064)
			(stroke
				(width 0.1524)
				(type default)
			)
			(layer "F.SilkS")
		)
		(fp_line
			(start -0.67945 -0.305054)
			(end -0.12065 -0.305054)
			(stroke
				(width 0.1)
				(type default)
			)
			(layer "F.Fab")
		)
		(fp_line
			(start -0.67945 0.3048)
			(end -0.67945 -0.305054)
			(stroke
				(width 0.1)
				(type default)
			)
			(layer "F.Fab")
		)
		(fp_line
			(start -0.12065 -0.305054)
			(end -0.12065 -0.2794)
			(stroke
				(width 0.1)
				(type default)
			)
			(layer "F.Fab")
		)
		(fp_line
			(start -0.12065 -0.2794)
			(end 0.12065 -0.2794)
			(stroke
				(width 0.1)
				(type default)
			)
			(layer "F.Fab")
		)
		(fp_line
			(start -0.12065 0.2794)
			(end -0.12065 0.3048)
			(stroke
				(width 0.1)
				(type default)
			)
			(layer "F.Fab")
		)
		(fp_line
			(start -0.12065 0.3048)
			(end -0.67945 0.3048)
			(stroke
				(width 0.1)
				(type default)
			)
			(layer "F.Fab")
		)
		(fp_line
			(start 0.120396 0.2794)
			(end -0.12065 0.2794)
			(stroke
				(width 0.1)
				(type default)
			)
			(layer "F.Fab")
		)
		(fp_line
			(start 0.120396 0.3048)
			(end 0.120396 0.2794)
			(stroke
				(width 0.1)
				(type default)
			)
			(layer "F.Fab")
		)
		(fp_line
			(start 0.12065 -0.3048)
			(end 0.67945 -0.3048)
			(stroke
				(width 0.1)
				(type default)
			)
			(layer "F.Fab")
		)
		(fp_line
			(start 0.12065 -0.2794)
			(end 0.12065 -0.3048)
			(stroke
				(width 0.1)
				(type default)
			)
			(layer "F.Fab")
		)
		(fp_line
			(start 0.67945 -0.3048)
			(end 0.67945 0.3048)
			(stroke
				(width 0.1)
				(type default)
			)
			(layer "F.Fab")
		)
		(fp_line
			(start 0.67945 0.3048)
			(end 0.120396 0.3048)
			(stroke
				(width 0.1)
				(type default)
			)
			(layer "F.Fab")
		)
		(pad "1" smd circle
			(at -0.40005 0)
			(size 0 0)
			(layers "F.Cu" "F.Mask" "F.Paste")
			(net "RST_USB_HUB_N")
		)
		(pad "2" smd circle
			(at 0.40005 0)
			(size 0 0)
			(layers "F.Cu" "F.Mask" "F.Paste")
			(net "RST_USB_CPU0_HUB1_R_N")
		)
	)
	(footprint ""
		(layer "F.Cu")
		(at 34.74593 -255.560322 180)
		(property "Reference" "J30"
			(at 3.12293 -81.850992 0)
			(unlocked yes)
			(layer "F.SilkS")
			(effects
				(font
					(size 0.7874 0.5842)
					(thickness 0.1524)
				)
			)
		)
		(property "Value" ""
			(at 0 0 180)
			(layer "F.Fab")
			(effects
				(font
					(size 1.27 1.27)
				)
			)
		)
		(duplicate_pad_numbers_are_jumpers no)
		(fp_line
			(start 3.24993 -81.000092)
			(end 3.24993 75.401678)
			(stroke
				(width 0.1524)
				(type default)
			)
			(layer "F.SilkS")
		)
		(fp_line
			(start 1.37541 -81.000092)
			(end 3.24993 -81.000092)
			(stroke
				(width 0.1524)
				(type default)
			)
			(layer "F.SilkS")
		)
		(fp_line
			(start -3.24993 75.401678)
			(end -3.24993 -81.000092)
			(stroke
				(width 0.1524)
				(type default)
			)
			(layer "F.SilkS")
		)
		(fp_line
			(start -3.24993 72.499982)
			(end 3.24993 72.499982)
			(stroke
				(width 0.1524)
				(type default)
			)
			(layer "F.SilkS")
		)
		(fp_line
			(start -3.24993 -72.499982)
			(end 3.24993 -72.499982)
			(stroke
				(width 0.1524)
				(type default)
			)
			(layer "F.SilkS")
		)
		(fp_line
			(start -3.24993 -81.000092)
			(end -1.13411 -81.000092)
			(stroke
				(width 0.1524)
				(type default)
			)
			(layer "F.SilkS")
		)
		(fp_poly
			(pts
				(xy -3.687826 -64.816228) (xy -3.095498 -63.846964) (xy -4.226306 -63.95466)
			)
			(stroke
				(width 0)
				(type default)
			)
			(fill yes)
			(layer "F.SilkS")
		)
		(fp_line
			(start 3.24993 81.000092)
			(end -3.24993 81.000092)
			(stroke
				(width 0.1)
				(type default)
			)
			(layer "F.Fab")
		)
		(fp_line
			(start 3.24993 -81.000092)
			(end 3.24993 81.000092)
			(stroke
				(width 0.1)
				(type default)
			)
			(layer "F.Fab")
		)
		(fp_line
			(start -3.24993 81.000092)
			(end -3.24993 -81.000092)
			(stroke
				(width 0.1)
				(type default)
			)
			(layer "F.Fab")
		)
		(fp_line
			(start -3.24993 72.499982)
			(end 3.24993 72.499982)
			(stroke
				(width 0.1)
				(type default)
			)
			(layer "F.Fab")
		)
		(fp_line
			(start -3.24993 71.000112)
			(end 3.24993 71.000112)
			(stroke
				(width 0.1)
				(type default)
			)
			(layer "F.Fab")
		)
		(fp_line
			(start -3.24993 -71.000112)
			(end 3.24993 -71.000112)
			(stroke
				(width 0.1)
				(type default)
			)
			(layer "F.Fab")
		)
		(fp_line
			(start -3.24993 -72.499982)
			(end 3.24993 -72.499982)
			(stroke
				(width 0.1)
				(type default)
			)
			(layer "F.Fab")
		)
		(fp_line
			(start -3.24993 -81.000092)
			(end 3.24993 -81.000092)
			(stroke
				(width 0.1)
				(type default)
			)
			(layer "F.Fab")
		)
		(fp_poly
			(pts
				(xy -3.41503 -63.324994) (xy -4.43103 -62.816994) (xy -4.43103 -63.832994)
			)
			(stroke
				(width 0)
				(type default)
			)
			(fill yes)
			(layer "F.Fab")
		)
		(pad "1" smd rect
			(at -2.050034 -63.324994 90)
			(size 0.519938 1.4986)
			(layers "F.Cu" "F.Mask" "F.Paste")
			(net "P12V_MEM_CPU1")
		)
		(pad "2" smd rect
			(at -2.050034 -62.47511 90)
			(size 0.519938 1.4986)
			(layers "F.Cu" "F.Mask" "F.Paste")
			(net "Net_2298")
		)
		(pad "3" smd rect
			(at -2.050034 -61.624972 90)
			(size 0.519938 1.4986)
			(layers "F.Cu" "F.Mask" "F.Paste")
			(net "P3V3_AUX")
		)
		(pad "4" smd rect
			(at -2.050034 -60.775088 90)
			(size 0.519938 1.4986)
			(layers "F.Cu" "F.Mask" "F.Paste")
			(net "I3C_SPD_DDRD_CPU1_SCL")
		)
		(pad "5" smd rect
			(at -2.050034 -59.92495 90)
			(size 0.519938 1.4986)
			(layers "F.Cu" "F.Mask" "F.Paste")
			(net "I3C_SPD_DDRD_CPU1_SDA")
		)
		(pad "6" smd rect
			(at -2.050034 -59.075066 90)
			(size 0.519938 1.4986)
			(layers "F.Cu" "F.Mask" "F.Paste")
			(net "GND")
		)
		(pad "7" smd rect
			(at -2.050034 -58.224928 90)
			(size 0.519938 1.4986)
			(layers "F.Cu" "F.Mask" "F.Paste")
			(net "M_D_CPU1_SA_DQ<0>")
		)
		(pad "8" smd rect
			(at -2.050034 -57.375044 90)
			(size 0.519938 1.4986)
			(layers "F.Cu" "F.Mask" "F.Paste")
			(net "GND")
		)
		(pad "9" smd rect
			(at -2.050034 -56.524906 90)
			(size 0.519938 1.4986)
			(layers "F.Cu" "F.Mask" "F.Paste")
			(net "M_D_CPU1_SA_DQ<1>")
		)
		(pad "10" smd rect
			(at -2.050034 -55.675022 90)
			(size 0.519938 1.4986)
			(layers "F.Cu" "F.Mask" "F.Paste")
			(net "GND")
		)
		(pad "11" smd rect
			(at -2.050034 -54.824884 90)
			(size 0.519938 1.4986)
			(layers "F.Cu" "F.Mask" "F.Paste")
			(net "M_D_CPU1_SA_DQS_DP<0>")
		)
		(pad "12" smd rect
			(at -2.050034 -53.975 90)
			(size 0.519938 1.4986)
			(layers "F.Cu" "F.Mask" "F.Paste")
			(net "M_D_CPU1_SA_DQS_DN<0>")
		)
		(pad "13" smd rect
			(at -2.050034 -53.125116 90)
			(size 0.519938 1.4986)
			(layers "F.Cu" "F.Mask" "F.Paste")
			(net "GND")
		)
		(pad "14" smd rect
			(at -2.050034 -52.274978 90)
			(size 0.519938 1.4986)
			(layers "F.Cu" "F.Mask" "F.Paste")
			(net "M_D_CPU1_SA_DQ<4>")
		)
		(pad "15" smd rect
			(at -2.050034 -51.425094 90)
			(size 0.519938 1.4986)
			(layers "F.Cu" "F.Mask" "F.Paste")
			(net "GND")
		)
		(pad "16" smd rect
			(at -2.050034 -50.574956 90)
			(size 0.519938 1.4986)
			(layers "F.Cu" "F.Mask" "F.Paste")
			(net "M_D_CPU1_SA_DQ<5>")
		)
		(pad "17" smd rect
			(at -2.050034 -49.725072 90)
			(size 0.519938 1.4986)
			(layers "F.Cu" "F.Mask" "F.Paste")
			(net "GND")
		)
		(pad "18" smd rect
			(at -2.050034 -48.874934 90)
			(size 0.519938 1.4986)
			(layers "F.Cu" "F.Mask" "F.Paste")
			(net "M_D_CPU1_SA_DQ<8>")
		)
		(pad "19" smd rect
			(at -2.050034 -48.02505 90)
			(size 0.519938 1.4986)
			(layers "F.Cu" "F.Mask" "F.Paste")
			(net "GND")
		)
		(pad "20" smd rect
			(at -2.050034 -47.174912 90)
			(size 0.519938 1.4986)
			(layers "F.Cu" "F.Mask" "F.Paste")
			(net "M_D_CPU1_SA_DQ<9>")
		)
		(pad "21" smd rect
			(at -2.050034 -46.325028 90)
			(size 0.519938 1.4986)
			(layers "F.Cu" "F.Mask" "F.Paste")
			(net "GND")
		)
		(pad "22" smd rect
			(at -2.050034 -45.47489 90)
			(size 0.519938 1.4986)
			(layers "F.Cu" "F.Mask" "F.Paste")
			(net "M_D_CPU1_SA_DQS_DP<1>")
		)
		(pad "23" smd rect
			(at -2.050034 -44.625006 90)
			(size 0.519938 1.4986)
			(layers "F.Cu" "F.Mask" "F.Paste")
			(net "M_D_CPU1_SA_DQS_DN<1>")
		)
		(pad "24" smd rect
			(at -2.050034 -43.775122 90)
			(size 0.519938 1.4986)
			(layers "F.Cu" "F.Mask" "F.Paste")
			(net "GND")
		)
		(pad "25" smd rect
			(at -2.050034 -42.924984 90)
			(size 0.519938 1.4986)
			(layers "F.Cu" "F.Mask" "F.Paste")
			(net "M_D_CPU1_SA_DQ<12>")
		)
		(pad "26" smd rect
			(at -2.050034 -42.0751 90)
			(size 0.519938 1.4986)
			(layers "F.Cu" "F.Mask" "F.Paste")
			(net "GND")
		)
		(pad "27" smd rect
			(at -2.050034 -41.224962 90)
			(size 0.519938 1.4986)
			(layers "F.Cu" "F.Mask" "F.Paste")
			(net "M_D_CPU1_SA_DQ<13>")
		)
		(pad "28" smd rect
			(at -2.050034 -40.375078 90)
			(size 0.519938 1.4986)
			(layers "F.Cu" "F.Mask" "F.Paste")
			(net "GND")
		)
		(pad "29" smd rect
			(at -2.050034 -39.52494 90)
			(size 0.519938 1.4986)
			(layers "F.Cu" "F.Mask" "F.Paste")
			(net "M_D_CPU1_SA_DQ<16>")
		)
		(pad "30" smd rect
			(at -2.050034 -38.675056 90)
			(size 0.519938 1.4986)
			(layers "F.Cu" "F.Mask" "F.Paste")
			(net "GND")
		)
		(pad "31" smd rect
			(at -2.050034 -37.824918 90)
			(size 0.519938 1.4986)
			(layers "F.Cu" "F.Mask" "F.Paste")
			(net "M_D_CPU1_SA_DQ<17>")
		)
		(pad "32" smd rect
			(at -2.050034 -36.975034 90)
			(size 0.519938 1.4986)
			(layers "F.Cu" "F.Mask" "F.Paste")
			(net "GND")
		)
		(pad "33" smd rect
			(at -2.050034 -36.124896 90)
			(size 0.519938 1.4986)
			(layers "F.Cu" "F.Mask" "F.Paste")
			(net "M_D_CPU1_SA_DQS_DP<2>")
		)
		(pad "34" smd rect
			(at -2.050034 -35.275012 90)
			(size 0.519938 1.4986)
			(layers "F.Cu" "F.Mask" "F.Paste")
			(net "M_D_CPU1_SA_DQS_DN<2>")
		)
		(pad "35" smd rect
			(at -2.050034 -34.425128 90)
			(size 0.519938 1.4986)
			(layers "F.Cu" "F.Mask" "F.Paste")
			(net "GND")
		)
		(pad "36" smd rect
			(at -2.050034 -33.57499 90)
			(size 0.519938 1.4986)
			(layers "F.Cu" "F.Mask" "F.Paste")
			(net "M_D_CPU1_SA_DQ<20>")
		)
		(pad "37" smd rect
			(at -2.050034 -32.725106 90)
			(size 0.519938 1.4986)
			(layers "F.Cu" "F.Mask" "F.Paste")
			(net "GND")
		)
		(pad "38" smd rect
			(at -2.050034 -31.874968 90)
			(size 0.519938 1.4986)
			(layers "F.Cu" "F.Mask" "F.Paste")
			(net "M_D_CPU1_SA_DQ<21>")
		)
		(pad "39" smd rect
			(at -2.050034 -31.025084 90)
			(size 0.519938 1.4986)
			(layers "F.Cu" "F.Mask" "F.Paste")
			(net "GND")
		)
		(pad "40" smd rect
			(at -2.050034 -30.174946 90)
			(size 0.519938 1.4986)
			(layers "F.Cu" "F.Mask" "F.Paste")
			(net "M_D_CPU1_SA_DQ<24>")
		)
		(pad "41" smd rect
			(at -2.050034 -29.325062 90)
			(size 0.519938 1.4986)
			(layers "F.Cu" "F.Mask" "F.Paste")
			(net "GND")
		)
		(pad "42" smd rect
			(at -2.050034 -28.474924 90)
			(size 0.519938 1.4986)
			(layers "F.Cu" "F.Mask" "F.Paste")
			(net "M_D_CPU1_SA_DQ<25>")
		)
		(pad "43" smd rect
			(at -2.050034 -27.62504 90)
			(size 0.519938 1.4986)
			(layers "F.Cu" "F.Mask" "F.Paste")
			(net "GND")
		)
		(pad "44" smd rect
			(at -2.050034 -26.774902 90)
			(size 0.519938 1.4986)
			(layers "F.Cu" "F.Mask" "F.Paste")
			(net "M_D_CPU1_SA_DQS_DP<3>")
		)
		(pad "45" smd rect
			(at -2.050034 -25.925018 90)
			(size 0.519938 1.4986)
			(layers "F.Cu" "F.Mask" "F.Paste")
			(net "M_D_CPU1_SA_DQS_DN<3>")
		)
		(pad "46" smd rect
			(at -2.050034 -25.07488 90)
			(size 0.519938 1.4986)
			(layers "F.Cu" "F.Mask" "F.Paste")
			(net "GND")
		)
		(pad "47" smd rect
			(at -2.050034 -24.224996 90)
			(size 0.519938 1.4986)
			(layers "F.Cu" "F.Mask" "F.Paste")
			(net "M_D_CPU1_SA_DQ<28>")
		)
		(pad "48" smd rect
			(at -2.050034 -23.375112 90)
			(size 0.519938 1.4986)
			(layers "F.Cu" "F.Mask" "F.Paste")
			(net "GND")
		)
		(pad "49" smd rect
			(at -2.050034 -22.524974 90)
			(size 0.519938 1.4986)
			(layers "F.Cu" "F.Mask" "F.Paste")
			(net "M_D_CPU1_SA_DQ<29>")
		)
		(pad "50" smd rect
			(at -2.050034 -21.67509 90)
			(size 0.519938 1.4986)
			(layers "F.Cu" "F.Mask" "F.Paste")
			(net "GND")
		)
		(pad "51" smd rect
			(at -2.050034 -20.824952 90)
			(size 0.519938 1.4986)
			(layers "F.Cu" "F.Mask" "F.Paste")
			(net "M_D_CPU1_SA_CB<0>")
		)
		(pad "52" smd rect
			(at -2.050034 -19.975068 90)
			(size 0.519938 1.4986)
			(layers "F.Cu" "F.Mask" "F.Paste")
			(net "GND")
		)
		(pad "53" smd rect
			(at -2.050034 -19.12493 90)
			(size 0.519938 1.4986)
			(layers "F.Cu" "F.Mask" "F.Paste")
			(net "M_D_CPU1_SA_CB<1>")
		)
		(pad "54" smd rect
			(at -2.050034 -18.275046 90)
			(size 0.519938 1.4986)
			(layers "F.Cu" "F.Mask" "F.Paste")
			(net "GND")
		)
		(pad "55" smd rect
			(at -2.050034 -17.424908 90)
			(size 0.519938 1.4986)
			(layers "F.Cu" "F.Mask" "F.Paste")
			(net "M_D_CPU1_SA_DQS_DP<4>")
		)
		(pad "56" smd rect
			(at -2.050034 -16.575024 90)
			(size 0.519938 1.4986)
			(layers "F.Cu" "F.Mask" "F.Paste")
			(net "M_D_CPU1_SA_DQS_DN<4>")
		)
		(pad "57" smd rect
			(at -2.050034 -15.724886 90)
			(size 0.519938 1.4986)
			(layers "F.Cu" "F.Mask" "F.Paste")
			(net "GND")
		)
		(pad "58" smd rect
			(at -2.050034 -14.875002 90)
			(size 0.519938 1.4986)
			(layers "F.Cu" "F.Mask" "F.Paste")
			(net "M_D_CPU1_SA_CB<4>")
		)
		(pad "59" smd rect
			(at -2.050034 -14.025118 90)
			(size 0.519938 1.4986)
			(layers "F.Cu" "F.Mask" "F.Paste")
			(net "GND")
		)
		(pad "60" smd rect
			(at -2.050034 -13.17498 90)
			(size 0.519938 1.4986)
			(layers "F.Cu" "F.Mask" "F.Paste")
			(net "M_D_CPU1_SA_CB<5>")
		)
		(pad "61" smd rect
			(at -2.050034 -12.325096 90)
			(size 0.519938 1.4986)
			(layers "F.Cu" "F.Mask" "F.Paste")
			(net "GND")
		)
		(pad "62" smd rect
			(at -2.050034 -11.474958 90)
			(size 0.519938 1.4986)
			(layers "F.Cu" "F.Mask" "F.Paste")
			(net "M_D_CPU1_ALERT_N")
		)
		(pad "63" smd rect
			(at -2.050034 -10.625074 90)
			(size 0.519938 1.4986)
			(layers "F.Cu" "F.Mask" "F.Paste")
			(net "GND")
		)
		(pad "64" smd rect
			(at -2.050034 -9.774936 90)
			(size 0.519938 1.4986)
			(layers "F.Cu" "F.Mask" "F.Paste")
			(net "M_D_CPU1_SA_CS_N<0>")
		)
		(pad "65" smd rect
			(at -2.050034 -8.925052 90)
			(size 0.519938 1.4986)
			(layers "F.Cu" "F.Mask" "F.Paste")
			(net "GND")
		)
		(pad "66" smd rect
			(at -2.050034 -8.074914 90)
			(size 0.519938 1.4986)
			(layers "F.Cu" "F.Mask" "F.Paste")
			(net "M_D_CPU1_SA_CA<0>")
		)
		(pad "67" smd rect
			(at -2.050034 -7.22503 90)
			(size 0.519938 1.4986)
			(layers "F.Cu" "F.Mask" "F.Paste")
			(net "GND")
		)
		(pad "68" smd rect
			(at -2.050034 -6.374892 90)
			(size 0.519938 1.4986)
			(layers "F.Cu" "F.Mask" "F.Paste")
			(net "M_D_CPU1_SA_CA<2>")
		)
		(pad "69" smd rect
			(at -2.050034 -5.525008 90)
			(size 0.519938 1.4986)
			(layers "F.Cu" "F.Mask" "F.Paste")
			(net "GND")
		)
		(pad "70" smd rect
			(at -2.050034 -4.675124 90)
			(size 0.519938 1.4986)
			(layers "F.Cu" "F.Mask" "F.Paste")
			(net "M_D_CPU1_SA_CA<4>")
		)
		(pad "71" smd rect
			(at -2.050034 -3.824986 90)
			(size 0.519938 1.4986)
			(layers "F.Cu" "F.Mask" "F.Paste")
			(net "GND")
		)
		(pad "72" smd rect
			(at -2.050034 -2.975102 90)
			(size 0.519938 1.4986)
			(layers "F.Cu" "F.Mask" "F.Paste")
			(net "M_D_CPU1_SA_CA<6>")
		)
		(pad "73" smd rect
			(at -2.050034 -2.124964 90)
			(size 0.519938 1.4986)
			(layers "F.Cu" "F.Mask" "F.Paste")
			(net "GND")
		)
		(pad "74" smd rect
			(at -2.050034 -1.27508 90)
			(size 0.519938 1.4986)
			(layers "F.Cu" "F.Mask" "F.Paste")
			(net "M_D_CPU1_SA_PAR")
		)
		(pad "75" smd rect
			(at -2.050034 -0.424942 90)
			(size 0.519938 1.4986)
			(layers "F.Cu" "F.Mask" "F.Paste")
			(net "GND")
		)
		(pad "76" smd rect
			(at -2.050034 5.525008 90)
			(size 0.519938 1.4986)
			(layers "F.Cu" "F.Mask" "F.Paste")
			(net "M_D_CPU1_SB_CA<0>")
		)
		(pad "77" smd rect
			(at -2.050034 6.374892 90)
			(size 0.519938 1.4986)
			(layers "F.Cu" "F.Mask" "F.Paste")
			(net "GND")
		)
		(pad "78" smd rect
			(at -2.050034 7.22503 90)
			(size 0.519938 1.4986)
			(layers "F.Cu" "F.Mask" "F.Paste")
			(net "M_D_CPU1_SB_CA<2>")
		)
		(pad "79" smd rect
			(at -2.050034 8.074914 90)
			(size 0.519938 1.4986)
			(layers "F.Cu" "F.Mask" "F.Paste")
			(net "GND")
		)
		(pad "80" smd rect
			(at -2.050034 8.925052 90)
			(size 0.519938 1.4986)
			(layers "F.Cu" "F.Mask" "F.Paste")
			(net "M_D_CPU1_SB_CA<4>")
		)
		(pad "81" smd rect
			(at -2.050034 9.774936 90)
			(size 0.519938 1.4986)
			(layers "F.Cu" "F.Mask" "F.Paste")
			(net "GND")
		)
		(pad "82" smd rect
			(at -2.050034 10.625074 90)
			(size 0.519938 1.4986)
			(layers "F.Cu" "F.Mask" "F.Paste")
			(net "M_D_CPU1_SB_CA<6>")
		)
		(pad "83" smd rect
			(at -2.050034 11.474958 90)
			(size 0.519938 1.4986)
			(layers "F.Cu" "F.Mask" "F.Paste")
			(net "GND")
		)
		(pad "84" smd rect
			(at -2.050034 12.325096 90)
			(size 0.519938 1.4986)
			(layers "F.Cu" "F.Mask" "F.Paste")
			(net "M_D_CPU1_SB_CS_N<0>")
		)
		(pad "85" smd rect
			(at -2.050034 13.17498 90)
			(size 0.519938 1.4986)
			(layers "F.Cu" "F.Mask" "F.Paste")
			(net "GND")
		)
		(pad "86" smd rect
			(at -2.050034 14.025118 90)
			(size 0.519938 1.4986)
			(layers "F.Cu" "F.Mask" "F.Paste")
			(net "M_D_CPU1_SA_RSP<0>")
		)
		(pad "87" smd rect
			(at -2.050034 14.875002 90)
			(size 0.519938 1.4986)
			(layers "F.Cu" "F.Mask" "F.Paste")
			(net "M_D_CPU1_SB_RSP<0>")
		)
		(pad "88" smd rect
			(at -2.050034 15.724886 90)
			(size 0.519938 1.4986)
			(layers "F.Cu" "F.Mask" "F.Paste")
			(net "GND")
		)
		(pad "89" smd rect
			(at -2.050034 16.575024 90)
			(size 0.519938 1.4986)
			(layers "F.Cu" "F.Mask" "F.Paste")
			(net "M_D_CPU1_SB_CB<4>")
		)
		(pad "90" smd rect
			(at -2.050034 17.424908 90)
			(size 0.519938 1.4986)
			(layers "F.Cu" "F.Mask" "F.Paste")
			(net "GND")
		)
		(pad "91" smd rect
			(at -2.050034 18.275046 90)
			(size 0.519938 1.4986)
			(layers "F.Cu" "F.Mask" "F.Paste")
			(net "M_D_CPU1_SB_CB<5>")
		)
		(pad "92" smd rect
			(at -2.050034 19.12493 90)
			(size 0.519938 1.4986)
			(layers "F.Cu" "F.Mask" "F.Paste")
			(net "GND")
		)
		(pad "93" smd rect
			(at -2.050034 19.975068 90)
			(size 0.519938 1.4986)
			(layers "F.Cu" "F.Mask" "F.Paste")
			(net "M_D_CPU1_SB_DQS_DP<9>")
		)
		(pad "94" smd rect
			(at -2.050034 20.824952 90)
			(size 0.519938 1.4986)
			(layers "F.Cu" "F.Mask" "F.Paste")
			(net "M_D_CPU1_SB_DQS_DN<9>")
		)
		(pad "95" smd rect
			(at -2.050034 21.67509 90)
			(size 0.519938 1.4986)
			(layers "F.Cu" "F.Mask" "F.Paste")
			(net "GND")
		)
		(pad "96" smd rect
			(at -2.050034 22.524974 90)
			(size 0.519938 1.4986)
			(layers "F.Cu" "F.Mask" "F.Paste")
			(net "M_D_CPU1_SB_CB<0>")
		)
		(pad "97" smd rect
			(at -2.050034 23.375112 90)
			(size 0.519938 1.4986)
			(layers "F.Cu" "F.Mask" "F.Paste")
			(net "GND")
		)
		(pad "98" smd rect
			(at -2.050034 24.224996 90)
			(size 0.519938 1.4986)
			(layers "F.Cu" "F.Mask" "F.Paste")
			(net "M_D_CPU1_SB_CB<1>")
		)
		(pad "99" smd rect
			(at -2.050034 25.07488 90)
			(size 0.519938 1.4986)
			(layers "F.Cu" "F.Mask" "F.Paste")
			(net "GND")
		)
		(pad "100" smd rect
			(at -2.050034 25.925018 90)
			(size 0.519938 1.4986)
			(layers "F.Cu" "F.Mask" "F.Paste")
			(net "M_D_CPU1_SB_DQ<0>")
		)
		(pad "101" smd rect
			(at -2.050034 26.774902 90)
			(size 0.519938 1.4986)
			(layers "F.Cu" "F.Mask" "F.Paste")
			(net "GND")
		)
		(pad "102" smd rect
			(at -2.050034 27.62504 90)
			(size 0.519938 1.4986)
			(layers "F.Cu" "F.Mask" "F.Paste")
			(net "M_D_CPU1_SB_DQ<1>")
		)
		(pad "103" smd rect
			(at -2.050034 28.474924 90)
			(size 0.519938 1.4986)
			(layers "F.Cu" "F.Mask" "F.Paste")
			(net "GND")
		)
		(pad "104" smd rect
			(at -2.050034 29.325062 90)
			(size 0.519938 1.4986)
			(layers "F.Cu" "F.Mask" "F.Paste")
			(net "M_D_CPU1_SB_DQS_DP<0>")
		)
		(pad "105" smd rect
			(at -2.050034 30.174946 90)
			(size 0.519938 1.4986)
			(layers "F.Cu" "F.Mask" "F.Paste")
			(net "M_D_CPU1_SB_DQS_DN<0>")
		)
		(pad "106" smd rect
			(at -2.050034 31.025084 90)
			(size 0.519938 1.4986)
			(layers "F.Cu" "F.Mask" "F.Paste")
			(net "GND")
		)
		(pad "107" smd rect
			(at -2.050034 31.874968 90)
			(size 0.519938 1.4986)
			(layers "F.Cu" "F.Mask" "F.Paste")
			(net "M_D_CPU1_SB_DQ<4>")
		)
		(pad "108" smd rect
			(at -2.050034 32.725106 90)
			(size 0.519938 1.4986)
			(layers "F.Cu" "F.Mask" "F.Paste")
			(net "GND")
		)
		(pad "109" smd rect
			(at -2.050034 33.57499 90)
			(size 0.519938 1.4986)
			(layers "F.Cu" "F.Mask" "F.Paste")
			(net "M_D_CPU1_SB_DQ<5>")
		)
		(pad "110" smd rect
			(at -2.050034 34.425128 90)
			(size 0.519938 1.4986)
			(layers "F.Cu" "F.Mask" "F.Paste")
			(net "GND")
		)
		(pad "111" smd rect
			(at -2.050034 35.275012 90)
			(size 0.519938 1.4986)
			(layers "F.Cu" "F.Mask" "F.Paste")
			(net "M_D_CPU1_SB_DQ<8>")
		)
		(pad "112" smd rect
			(at -2.050034 36.124896 90)
			(size 0.519938 1.4986)
			(layers "F.Cu" "F.Mask" "F.Paste")
			(net "GND")
		)
		(pad "113" smd rect
			(at -2.050034 36.975034 90)
			(size 0.519938 1.4986)
			(layers "F.Cu" "F.Mask" "F.Paste")
			(net "M_D_CPU1_SB_DQ<9>")
		)
		(pad "114" smd rect
			(at -2.050034 37.824918 90)
			(size 0.519938 1.4986)
			(layers "F.Cu" "F.Mask" "F.Paste")
			(net "GND")
		)
		(pad "115" smd rect
			(at -2.050034 38.675056 90)
			(size 0.519938 1.4986)
			(layers "F.Cu" "F.Mask" "F.Paste")
			(net "M_D_CPU1_SB_DQS_DP<1>")
		)
		(pad "116" smd rect
			(at -2.050034 39.52494 90)
			(size 0.519938 1.4986)
			(layers "F.Cu" "F.Mask" "F.Paste")
			(net "M_D_CPU1_SB_DQS_DN<1>")
		)
		(pad "117" smd rect
			(at -2.050034 40.375078 90)
			(size 0.519938 1.4986)
			(layers "F.Cu" "F.Mask" "F.Paste")
			(net "GND")
		)
		(pad "118" smd rect
			(at -2.050034 41.224962 90)
			(size 0.519938 1.4986)
			(layers "F.Cu" "F.Mask" "F.Paste")
			(net "M_D_CPU1_SB_DQ<12>")
		)
		(pad "119" smd rect
			(at -2.050034 42.0751 90)
			(size 0.519938 1.4986)
			(layers "F.Cu" "F.Mask" "F.Paste")
			(net "GND")
		)
		(pad "120" smd rect
			(at -2.050034 42.924984 90)
			(size 0.519938 1.4986)
			(layers "F.Cu" "F.Mask" "F.Paste")
			(net "M_D_CPU1_SB_DQ<13>")
		)
		(pad "121" smd rect
			(at -2.050034 43.775122 90)
			(size 0.519938 1.4986)
			(layers "F.Cu" "F.Mask" "F.Paste")
			(net "GND")
		)
		(pad "122" smd rect
			(at -2.050034 44.625006 90)
			(size 0.519938 1.4986)
			(layers "F.Cu" "F.Mask" "F.Paste")
			(net "M_D_CPU1_SB_DQ<16>")
		)
		(pad "123" smd rect
			(at -2.050034 45.47489 90)
			(size 0.519938 1.4986)
			(layers "F.Cu" "F.Mask" "F.Paste")
			(net "GND")
		)
		(pad "124" smd rect
			(at -2.050034 46.325028 90)
			(size 0.519938 1.4986)
			(layers "F.Cu" "F.Mask" "F.Paste")
			(net "M_D_CPU1_SB_DQ<17>")
		)
		(pad "125" smd rect
			(at -2.050034 47.174912 90)
			(size 0.519938 1.4986)
			(layers "F.Cu" "F.Mask" "F.Paste")
			(net "GND")
		)
		(pad "126" smd rect
			(at -2.050034 48.02505 90)
			(size 0.519938 1.4986)
			(layers "F.Cu" "F.Mask" "F.Paste")
			(net "M_D_CPU1_SB_DQS_DP<2>")
		)
		(pad "127" smd rect
			(at -2.050034 48.874934 90)
			(size 0.519938 1.4986)
			(layers "F.Cu" "F.Mask" "F.Paste")
			(net "M_D_CPU1_SB_DQS_DN<2>")
		)
		(pad "128" smd rect
			(at -2.050034 49.725072 90)
			(size 0.519938 1.4986)
			(layers "F.Cu" "F.Mask" "F.Paste")
			(net "GND")
		)
		(pad "129" smd rect
			(at -2.050034 50.574956 90)
			(size 0.519938 1.4986)
			(layers "F.Cu" "F.Mask" "F.Paste")
			(net "M_D_CPU1_SB_DQ<20>")
		)
		(pad "130" smd rect
			(at -2.050034 51.425094 90)
			(size 0.519938 1.4986)
			(layers "F.Cu" "F.Mask" "F.Paste")
			(net "GND")
		)
		(pad "131" smd rect
			(at -2.050034 52.274978 90)
			(size 0.519938 1.4986)
			(layers "F.Cu" "F.Mask" "F.Paste")
			(net "M_D_CPU1_SB_DQ<21>")
		)
		(pad "132" smd rect
			(at -2.050034 53.125116 90)
			(size 0.519938 1.4986)
			(layers "F.Cu" "F.Mask" "F.Paste")
			(net "GND")
		)
		(pad "133" smd rect
			(at -2.050034 53.975 90)
			(size 0.519938 1.4986)
			(layers "F.Cu" "F.Mask" "F.Paste")
			(net "M_D_CPU1_SB_DQ<24>")
		)
		(pad "134" smd rect
			(at -2.050034 54.824884 90)
			(size 0.519938 1.4986)
			(layers "F.Cu" "F.Mask" "F.Paste")
			(net "GND")
		)
		(pad "135" smd rect
			(at -2.050034 55.675022 90)
			(size 0.519938 1.4986)
			(layers "F.Cu" "F.Mask" "F.Paste")
			(net "M_D_CPU1_SB_DQ<25>")
		)
		(pad "136" smd rect
			(at -2.050034 56.524906 90)
			(size 0.519938 1.4986)
			(layers "F.Cu" "F.Mask" "F.Paste")
			(net "GND")
		)
		(pad "137" smd rect
			(at -2.050034 57.375044 90)
			(size 0.519938 1.4986)
			(layers "F.Cu" "F.Mask" "F.Paste")
			(net "M_D_CPU1_SB_DQS_DP<3>")
		)
		(pad "138" smd rect
			(at -2.050034 58.224928 90)
			(size 0.519938 1.4986)
			(layers "F.Cu" "F.Mask" "F.Paste")
			(net "M_D_CPU1_SB_DQS_DN<3>")
		)
		(pad "139" smd rect
			(at -2.050034 59.075066 90)
			(size 0.519938 1.4986)
			(layers "F.Cu" "F.Mask" "F.Paste")
			(net "GND")
		)
		(pad "140" smd rect
			(at -2.050034 59.92495 90)
			(size 0.519938 1.4986)
			(layers "F.Cu" "F.Mask" "F.Paste")
			(net "M_D_CPU1_SB_DQ<28>")
		)
		(pad "141" smd rect
			(at -2.050034 60.775088 90)
			(size 0.519938 1.4986)
			(layers "F.Cu" "F.Mask" "F.Paste")
			(net "GND")
		)
		(pad "142" smd rect
			(at -2.050034 61.624972 90)
			(size 0.519938 1.4986)
			(layers "F.Cu" "F.Mask" "F.Paste")
			(net "M_D_CPU1_SB_DQ<29>")
		)
		(pad "143" smd rect
			(at -2.050034 62.47511 90)
			(size 0.519938 1.4986)
			(layers "F.Cu" "F.Mask" "F.Paste")
			(net "GND")
		)
		(pad "144" smd rect
			(at -2.050034 63.324994 90)
			(size 0.519938 1.4986)
			(layers "F.Cu" "F.Mask" "F.Paste")
			(net "Net_2299")
		)
		(pad "145" smd rect
			(at 2.050034 -63.324994 90)
			(size 0.519938 1.4986)
			(layers "F.Cu" "F.Mask" "F.Paste")
			(net "P12V_MEM_CPU1")
		)
		(pad "146" smd rect
			(at 2.050034 -62.47511 90)
			(size 0.519938 1.4986)
			(layers "F.Cu" "F.Mask" "F.Paste")
			(net "P12V_MEM_CPU1")
		)
		(pad "147" smd rect
			(at 2.050034 -61.624972 90)
			(size 0.519938 1.4986)
			(layers "F.Cu" "F.Mask" "F.Paste")
			(net "PWRGD_CHD_CPU1_DIMM")
		)
		(pad "148" smd rect
			(at 2.050034 -60.775088 90)
			(size 0.519938 1.4986)
			(layers "F.Cu" "F.Mask" "F.Paste")
			(net "PD_CHD_CPU1_DIMM_SAA")
		)
		(pad "149" smd rect
			(at 2.050034 -59.92495 90)
			(size 0.519938 1.4986)
			(layers "F.Cu" "F.Mask" "F.Paste")
			(net "Net_2300")
		)
		(pad "150" smd rect
			(at 2.050034 -59.075066 90)
			(size 0.519938 1.4986)
			(layers "F.Cu" "F.Mask" "F.Paste")
			(net "Net_2301")
		)
		(pad "151" smd rect
			(at 2.050034 -58.224928 90)
			(size 0.519938 1.4986)
			(layers "F.Cu" "F.Mask" "F.Paste")
			(net "GND")
		)
		(pad "152" smd rect
			(at 2.050034 -57.375044 90)
			(size 0.519938 1.4986)
			(layers "F.Cu" "F.Mask" "F.Paste")
			(net "M_D_CPU1_SA_DQ<2>")
		)
		(pad "153" smd rect
			(at 2.050034 -56.524906 90)
			(size 0.519938 1.4986)
			(layers "F.Cu" "F.Mask" "F.Paste")
			(net "GND")
		)
		(pad "154" smd rect
			(at 2.050034 -55.675022 90)
			(size 0.519938 1.4986)
			(layers "F.Cu" "F.Mask" "F.Paste")
			(net "M_D_CPU1_SA_DQ<3>")
		)
		(pad "155" smd rect
			(at 2.050034 -54.824884 90)
			(size 0.519938 1.4986)
			(layers "F.Cu" "F.Mask" "F.Paste")
			(net "GND")
		)
		(pad "156" smd rect
			(at 2.050034 -53.975 90)
			(size 0.519938 1.4986)
			(layers "F.Cu" "F.Mask" "F.Paste")
			(net "M_D_CPU1_SA_DQS_DN<5>")
		)
		(pad "157" smd rect
			(at 2.050034 -53.125116 90)
			(size 0.519938 1.4986)
			(layers "F.Cu" "F.Mask" "F.Paste")
			(net "M_D_CPU1_SA_DQS_DP<5>")
		)
		(pad "158" smd rect
			(at 2.050034 -52.274978 90)
			(size 0.519938 1.4986)
			(layers "F.Cu" "F.Mask" "F.Paste")
			(net "GND")
		)
		(pad "159" smd rect
			(at 2.050034 -51.425094 90)
			(size 0.519938 1.4986)
			(layers "F.Cu" "F.Mask" "F.Paste")
			(net "M_D_CPU1_SA_DQ<6>")
		)
		(pad "160" smd rect
			(at 2.050034 -50.574956 90)
			(size 0.519938 1.4986)
			(layers "F.Cu" "F.Mask" "F.Paste")
			(net "GND")
		)
		(pad "161" smd rect
			(at 2.050034 -49.725072 90)
			(size 0.519938 1.4986)
			(layers "F.Cu" "F.Mask" "F.Paste")
			(net "M_D_CPU1_SA_DQ<7>")
		)
		(pad "162" smd rect
			(at 2.050034 -48.874934 90)
			(size 0.519938 1.4986)
			(layers "F.Cu" "F.Mask" "F.Paste")
			(net "GND")
		)
		(pad "163" smd rect
			(at 2.050034 -48.02505 90)
			(size 0.519938 1.4986)
			(layers "F.Cu" "F.Mask" "F.Paste")
			(net "M_D_CPU1_SA_DQ<10>")
		)
		(pad "164" smd rect
			(at 2.050034 -47.174912 90)
			(size 0.519938 1.4986)
			(layers "F.Cu" "F.Mask" "F.Paste")
			(net "GND")
		)
		(pad "165" smd rect
			(at 2.050034 -46.325028 90)
			(size 0.519938 1.4986)
			(layers "F.Cu" "F.Mask" "F.Paste")
			(net "M_D_CPU1_SA_DQ<11>")
		)
		(pad "166" smd rect
			(at 2.050034 -45.47489 90)
			(size 0.519938 1.4986)
			(layers "F.Cu" "F.Mask" "F.Paste")
			(net "GND")
		)
		(pad "167" smd rect
			(at 2.050034 -44.625006 90)
			(size 0.519938 1.4986)
			(layers "F.Cu" "F.Mask" "F.Paste")
			(net "M_D_CPU1_SA_DQS_DN<6>")
		)
		(pad "168" smd rect
			(at 2.050034 -43.775122 90)
			(size 0.519938 1.4986)
			(layers "F.Cu" "F.Mask" "F.Paste")
			(net "M_D_CPU1_SA_DQS_DP<6>")
		)
		(pad "169" smd rect
			(at 2.050034 -42.924984 90)
			(size 0.519938 1.4986)
			(layers "F.Cu" "F.Mask" "F.Paste")
			(net "GND")
		)
		(pad "170" smd rect
			(at 2.050034 -42.0751 90)
			(size 0.519938 1.4986)
			(layers "F.Cu" "F.Mask" "F.Paste")
			(net "M_D_CPU1_SA_DQ<14>")
		)
		(pad "171" smd rect
			(at 2.050034 -41.224962 90)
			(size 0.519938 1.4986)
			(layers "F.Cu" "F.Mask" "F.Paste")
			(net "GND")
		)
		(pad "172" smd rect
			(at 2.050034 -40.375078 90)
			(size 0.519938 1.4986)
			(layers "F.Cu" "F.Mask" "F.Paste")
			(net "M_D_CPU1_SA_DQ<15>")
		)
		(pad "173" smd rect
			(at 2.050034 -39.52494 90)
			(size 0.519938 1.4986)
			(layers "F.Cu" "F.Mask" "F.Paste")
			(net "GND")
		)
		(pad "174" smd rect
			(at 2.050034 -38.675056 90)
			(size 0.519938 1.4986)
			(layers "F.Cu" "F.Mask" "F.Paste")
			(net "M_D_CPU1_SA_DQ<18>")
		)
		(pad "175" smd rect
			(at 2.050034 -37.824918 90)
			(size 0.519938 1.4986)
			(layers "F.Cu" "F.Mask" "F.Paste")
			(net "GND")
		)
		(pad "176" smd rect
			(at 2.050034 -36.975034 90)
			(size 0.519938 1.4986)
			(layers "F.Cu" "F.Mask" "F.Paste")
			(net "M_D_CPU1_SA_DQ<19>")
		)
		(pad "177" smd rect
			(at 2.050034 -36.124896 90)
			(size 0.519938 1.4986)
			(layers "F.Cu" "F.Mask" "F.Paste")
			(net "GND")
		)
		(pad "178" smd rect
			(at 2.050034 -35.275012 90)
			(size 0.519938 1.4986)
			(layers "F.Cu" "F.Mask" "F.Paste")
			(net "M_D_CPU1_SA_DQS_DN<7>")
		)
		(pad "179" smd rect
			(at 2.050034 -34.425128 90)
			(size 0.519938 1.4986)
			(layers "F.Cu" "F.Mask" "F.Paste")
			(net "M_D_CPU1_SA_DQS_DP<7>")
		)
		(pad "180" smd rect
			(at 2.050034 -33.57499 90)
			(size 0.519938 1.4986)
			(layers "F.Cu" "F.Mask" "F.Paste")
			(net "GND")
		)
		(pad "181" smd rect
			(at 2.050034 -32.725106 90)
			(size 0.519938 1.4986)
			(layers "F.Cu" "F.Mask" "F.Paste")
			(net "M_D_CPU1_SA_DQ<22>")
		)
		(pad "182" smd rect
			(at 2.050034 -31.874968 90)
			(size 0.519938 1.4986)
			(layers "F.Cu" "F.Mask" "F.Paste")
			(net "GND")
		)
		(pad "183" smd rect
			(at 2.050034 -31.025084 90)
			(size 0.519938 1.4986)
			(layers "F.Cu" "F.Mask" "F.Paste")
			(net "M_D_CPU1_SA_DQ<23>")
		)
		(pad "184" smd rect
			(at 2.050034 -30.174946 90)
			(size 0.519938 1.4986)
			(layers "F.Cu" "F.Mask" "F.Paste")
			(net "GND")
		)
		(pad "185" smd rect
			(at 2.050034 -29.325062 90)
			(size 0.519938 1.4986)
			(layers "F.Cu" "F.Mask" "F.Paste")
			(net "M_D_CPU1_SA_DQ<26>")
		)
		(pad "186" smd rect
			(at 2.050034 -28.474924 90)
			(size 0.519938 1.4986)
			(layers "F.Cu" "F.Mask" "F.Paste")
			(net "GND")
		)
		(pad "187" smd rect
			(at 2.050034 -27.62504 90)
			(size 0.519938 1.4986)
			(layers "F.Cu" "F.Mask" "F.Paste")
			(net "M_D_CPU1_SA_DQ<27>")
		)
		(pad "188" smd rect
			(at 2.050034 -26.774902 90)
			(size 0.519938 1.4986)
			(layers "F.Cu" "F.Mask" "F.Paste")
			(net "GND")
		)
		(pad "189" smd rect
			(at 2.050034 -25.925018 90)
			(size 0.519938 1.4986)
			(layers "F.Cu" "F.Mask" "F.Paste")
			(net "M_D_CPU1_SA_DQS_DN<8>")
		)
		(pad "190" smd rect
			(at 2.050034 -25.07488 90)
			(size 0.519938 1.4986)
			(layers "F.Cu" "F.Mask" "F.Paste")
			(net "M_D_CPU1_SA_DQS_DP<8>")
		)
		(pad "191" smd rect
			(at 2.050034 -24.224996 90)
			(size 0.519938 1.4986)
			(layers "F.Cu" "F.Mask" "F.Paste")
			(net "GND")
		)
		(pad "192" smd rect
			(at 2.050034 -23.375112 90)
			(size 0.519938 1.4986)
			(layers "F.Cu" "F.Mask" "F.Paste")
			(net "M_D_CPU1_SA_DQ<30>")
		)
		(pad "193" smd rect
			(at 2.050034 -22.524974 90)
			(size 0.519938 1.4986)
			(layers "F.Cu" "F.Mask" "F.Paste")
			(net "GND")
		)
		(pad "194" smd rect
			(at 2.050034 -21.67509 90)
			(size 0.519938 1.4986)
			(layers "F.Cu" "F.Mask" "F.Paste")
			(net "M_D_CPU1_SA_DQ<31>")
		)
		(pad "195" smd rect
			(at 2.050034 -20.824952 90)
			(size 0.519938 1.4986)
			(layers "F.Cu" "F.Mask" "F.Paste")
			(net "GND")
		)
		(pad "196" smd rect
			(at 2.050034 -19.975068 90)
			(size 0.519938 1.4986)
			(layers "F.Cu" "F.Mask" "F.Paste")
			(net "M_D_CPU1_SA_CB<2>")
		)
		(pad "197" smd rect
			(at 2.050034 -19.12493 90)
			(size 0.519938 1.4986)
			(layers "F.Cu" "F.Mask" "F.Paste")
			(net "GND")
		)
		(pad "198" smd rect
			(at 2.050034 -18.275046 90)
			(size 0.519938 1.4986)
			(layers "F.Cu" "F.Mask" "F.Paste")
			(net "M_D_CPU1_SA_CB<3>")
		)
		(pad "199" smd rect
			(at 2.050034 -17.424908 90)
			(size 0.519938 1.4986)
			(layers "F.Cu" "F.Mask" "F.Paste")
			(net "GND")
		)
		(pad "200" smd rect
			(at 2.050034 -16.575024 90)
			(size 0.519938 1.4986)
			(layers "F.Cu" "F.Mask" "F.Paste")
			(net "M_D_CPU1_SA_DQS_DN<9>")
		)
		(pad "201" smd rect
			(at 2.050034 -15.724886 90)
			(size 0.519938 1.4986)
			(layers "F.Cu" "F.Mask" "F.Paste")
			(net "M_D_CPU1_SA_DQS_DP<9>")
		)
		(pad "202" smd rect
			(at 2.050034 -14.875002 90)
			(size 0.519938 1.4986)
			(layers "F.Cu" "F.Mask" "F.Paste")
			(net "GND")
		)
		(pad "203" smd rect
			(at 2.050034 -14.025118 90)
			(size 0.519938 1.4986)
			(layers "F.Cu" "F.Mask" "F.Paste")
			(net "M_D_CPU1_SA_CB<6>")
		)
		(pad "204" smd rect
			(at 2.050034 -13.17498 90)
			(size 0.519938 1.4986)
			(layers "F.Cu" "F.Mask" "F.Paste")
			(net "GND")
		)
		(pad "205" smd rect
			(at 2.050034 -12.325096 90)
			(size 0.519938 1.4986)
			(layers "F.Cu" "F.Mask" "F.Paste")
			(net "M_D_CPU1_SA_CB<7>")
		)
		(pad "206" smd rect
			(at 2.050034 -11.474958 90)
			(size 0.519938 1.4986)
			(layers "F.Cu" "F.Mask" "F.Paste")
			(net "GND")
		)
		(pad "207" smd rect
			(at 2.050034 -10.625074 90)
			(size 0.519938 1.4986)
			(layers "F.Cu" "F.Mask" "F.Paste")
			(net "M_D_CPU1_RESET_N")
		)
		(pad "208" smd rect
			(at 2.050034 -9.774936 90)
			(size 0.519938 1.4986)
			(layers "F.Cu" "F.Mask" "F.Paste")
			(net "GND")
		)
		(pad "209" smd rect
			(at 2.050034 -8.925052 90)
			(size 0.519938 1.4986)
			(layers "F.Cu" "F.Mask" "F.Paste")
			(net "M_D_CPU1_SA_CS_N<1>")
		)
		(pad "210" smd rect
			(at 2.050034 -8.074914 90)
			(size 0.519938 1.4986)
			(layers "F.Cu" "F.Mask" "F.Paste")
			(net "GND")
		)
		(pad "211" smd rect
			(at 2.050034 -7.22503 90)
			(size 0.519938 1.4986)
			(layers "F.Cu" "F.Mask" "F.Paste")
			(net "M_D_CPU1_SA_CA<1>")
		)
		(pad "212" smd rect
			(at 2.050034 -6.374892 90)
			(size 0.519938 1.4986)
			(layers "F.Cu" "F.Mask" "F.Paste")
			(net "GND")
		)
		(pad "213" smd rect
			(at 2.050034 -5.525008 90)
			(size 0.519938 1.4986)
			(layers "F.Cu" "F.Mask" "F.Paste")
			(net "M_D_CPU1_SA_CA<3>")
		)
		(pad "214" smd rect
			(at 2.050034 -4.675124 90)
			(size 0.519938 1.4986)
			(layers "F.Cu" "F.Mask" "F.Paste")
			(net "GND")
		)
		(pad "215" smd rect
			(at 2.050034 -3.824986 90)
			(size 0.519938 1.4986)
			(layers "F.Cu" "F.Mask" "F.Paste")
			(net "M_D_CPU1_SA_CA<5>")
		)
		(pad "216" smd rect
			(at 2.050034 -2.975102 90)
			(size 0.519938 1.4986)
			(layers "F.Cu" "F.Mask" "F.Paste")
			(net "GND")
		)
		(pad "217" smd rect
			(at 2.050034 -2.124964 90)
			(size 0.519938 1.4986)
			(layers "F.Cu" "F.Mask" "F.Paste")
			(net "M_D_CPU1_CLK_DP<0>")
		)
		(pad "218" smd rect
			(at 2.050034 -1.27508 90)
			(size 0.519938 1.4986)
			(layers "F.Cu" "F.Mask" "F.Paste")
			(net "M_D_CPU1_CLK_DN<0>")
		)
		(pad "219" smd rect
			(at 2.050034 -0.424942 90)
			(size 0.519938 1.4986)
			(layers "F.Cu" "F.Mask" "F.Paste")
			(net "GND")
		)
		(pad "220" smd rect
			(at 2.050034 5.525008 90)
			(size 0.519938 1.4986)
			(layers "F.Cu" "F.Mask" "F.Paste")
			(net "Net_2302")
		)
		(pad "221" smd rect
			(at 2.050034 6.374892 90)
			(size 0.519938 1.4986)
			(layers "F.Cu" "F.Mask" "F.Paste")
			(net "M_D_CPU1_SB_CA<1>")
		)
		(pad "222" smd rect
			(at 2.050034 7.22503 90)
			(size 0.519938 1.4986)
			(layers "F.Cu" "F.Mask" "F.Paste")
			(net "GND")
		)
		(pad "223" smd rect
			(at 2.050034 8.074914 90)
			(size 0.519938 1.4986)
			(layers "F.Cu" "F.Mask" "F.Paste")
			(net "M_D_CPU1_SB_CA<3>")
		)
		(pad "224" smd rect
			(at 2.050034 8.925052 90)
			(size 0.519938 1.4986)
			(layers "F.Cu" "F.Mask" "F.Paste")
			(net "GND")
		)
		(pad "225" smd rect
			(at 2.050034 9.774936 90)
			(size 0.519938 1.4986)
			(layers "F.Cu" "F.Mask" "F.Paste")
			(net "M_D_CPU1_SB_CA<5>")
		)
		(pad "226" smd rect
			(at 2.050034 10.625074 90)
			(size 0.519938 1.4986)
			(layers "F.Cu" "F.Mask" "F.Paste")
			(net "GND")
		)
		(pad "227" smd rect
			(at 2.050034 11.474958 90)
			(size 0.519938 1.4986)
			(layers "F.Cu" "F.Mask" "F.Paste")
			(net "M_D_CPU1_SB_PAR")
		)
		(pad "228" smd rect
			(at 2.050034 12.325096 90)
			(size 0.519938 1.4986)
			(layers "F.Cu" "F.Mask" "F.Paste")
			(net "GND")
		)
		(pad "229" smd rect
			(at 2.050034 13.17498 90)
			(size 0.519938 1.4986)
			(layers "F.Cu" "F.Mask" "F.Paste")
			(net "M_D_CPU1_SB_CS_N<1>")
		)
		(pad "230" smd rect
			(at 2.050034 14.025118 90)
			(size 0.519938 1.4986)
			(layers "F.Cu" "F.Mask" "F.Paste")
			(net "GND")
		)
		(pad "231" smd rect
			(at 2.050034 14.875002 90)
			(size 0.519938 1.4986)
			(layers "F.Cu" "F.Mask" "F.Paste")
			(net "Net_2303")
		)
		(pad "232" smd rect
			(at 2.050034 15.724886 90)
			(size 0.519938 1.4986)
			(layers "F.Cu" "F.Mask" "F.Paste")
			(net "Net_2304")
		)
		(pad "233" smd rect
			(at 2.050034 16.575024 90)
			(size 0.519938 1.4986)
			(layers "F.Cu" "F.Mask" "F.Paste")
			(net "GND")
		)
		(pad "234" smd rect
			(at 2.050034 17.424908 90)
			(size 0.519938 1.4986)
			(layers "F.Cu" "F.Mask" "F.Paste")
			(net "M_D_CPU1_SB_CB<6>")
		)
		(pad "235" smd rect
			(at 2.050034 18.275046 90)
			(size 0.519938 1.4986)
			(layers "F.Cu" "F.Mask" "F.Paste")
			(net "GND")
		)
		(pad "236" smd rect
			(at 2.050034 19.12493 90)
			(size 0.519938 1.4986)
			(layers "F.Cu" "F.Mask" "F.Paste")
			(net "M_D_CPU1_SB_CB<7>")
		)
		(pad "237" smd rect
			(at 2.050034 19.975068 90)
			(size 0.519938 1.4986)
			(layers "F.Cu" "F.Mask" "F.Paste")
			(net "GND")
		)
		(pad "238" smd rect
			(at 2.050034 20.824952 90)
			(size 0.519938 1.4986)
			(layers "F.Cu" "F.Mask" "F.Paste")
			(net "M_D_CPU1_SB_DQS_DN<4>")
		)
		(pad "239" smd rect
			(at 2.050034 21.67509 90)
			(size 0.519938 1.4986)
			(layers "F.Cu" "F.Mask" "F.Paste")
			(net "M_D_CPU1_SB_DQS_DP<4>")
		)
		(pad "240" smd rect
			(at 2.050034 22.524974 90)
			(size 0.519938 1.4986)
			(layers "F.Cu" "F.Mask" "F.Paste")
			(net "GND")
		)
		(pad "241" smd rect
			(at 2.050034 23.375112 90)
			(size 0.519938 1.4986)
			(layers "F.Cu" "F.Mask" "F.Paste")
			(net "M_D_CPU1_SB_CB<2>")
		)
		(pad "242" smd rect
			(at 2.050034 24.224996 90)
			(size 0.519938 1.4986)
			(layers "F.Cu" "F.Mask" "F.Paste")
			(net "GND")
		)
		(pad "243" smd rect
			(at 2.050034 25.07488 90)
			(size 0.519938 1.4986)
			(layers "F.Cu" "F.Mask" "F.Paste")
			(net "M_D_CPU1_SB_CB<3>")
		)
		(pad "244" smd rect
			(at 2.050034 25.925018 90)
			(size 0.519938 1.4986)
			(layers "F.Cu" "F.Mask" "F.Paste")
			(net "GND")
		)
		(pad "245" smd rect
			(at 2.050034 26.774902 90)
			(size 0.519938 1.4986)
			(layers "F.Cu" "F.Mask" "F.Paste")
			(net "M_D_CPU1_SB_DQ<2>")
		)
		(pad "246" smd rect
			(at 2.050034 27.62504 90)
			(size 0.519938 1.4986)
			(layers "F.Cu" "F.Mask" "F.Paste")
			(net "GND")
		)
		(pad "247" smd rect
			(at 2.050034 28.474924 90)
			(size 0.519938 1.4986)
			(layers "F.Cu" "F.Mask" "F.Paste")
			(net "M_D_CPU1_SB_DQ<3>")
		)
		(pad "248" smd rect
			(at 2.050034 29.325062 90)
			(size 0.519938 1.4986)
			(layers "F.Cu" "F.Mask" "F.Paste")
			(net "GND")
		)
		(pad "249" smd rect
			(at 2.050034 30.174946 90)
			(size 0.519938 1.4986)
			(layers "F.Cu" "F.Mask" "F.Paste")
			(net "M_D_CPU1_SB_DQS_DN<5>")
		)
		(pad "250" smd rect
			(at 2.050034 31.025084 90)
			(size 0.519938 1.4986)
			(layers "F.Cu" "F.Mask" "F.Paste")
			(net "M_D_CPU1_SB_DQS_DP<5>")
		)
		(pad "251" smd rect
			(at 2.050034 31.874968 90)
			(size 0.519938 1.4986)
			(layers "F.Cu" "F.Mask" "F.Paste")
			(net "GND")
		)
		(pad "252" smd rect
			(at 2.050034 32.725106 90)
			(size 0.519938 1.4986)
			(layers "F.Cu" "F.Mask" "F.Paste")
			(net "M_D_CPU1_SB_DQ<6>")
		)
		(pad "253" smd rect
			(at 2.050034 33.57499 90)
			(size 0.519938 1.4986)
			(layers "F.Cu" "F.Mask" "F.Paste")
			(net "GND")
		)
		(pad "254" smd rect
			(at 2.050034 34.425128 90)
			(size 0.519938 1.4986)
			(layers "F.Cu" "F.Mask" "F.Paste")
			(net "M_D_CPU1_SB_DQ<7>")
		)
		(pad "255" smd rect
			(at 2.050034 35.275012 90)
			(size 0.519938 1.4986)
			(layers "F.Cu" "F.Mask" "F.Paste")
			(net "GND")
		)
		(pad "256" smd rect
			(at 2.050034 36.124896 90)
			(size 0.519938 1.4986)
			(layers "F.Cu" "F.Mask" "F.Paste")
			(net "M_D_CPU1_SB_DQ<10>")
		)
		(pad "257" smd rect
			(at 2.050034 36.975034 90)
			(size 0.519938 1.4986)
			(layers "F.Cu" "F.Mask" "F.Paste")
			(net "GND")
		)
		(pad "258" smd rect
			(at 2.050034 37.824918 90)
			(size 0.519938 1.4986)
			(layers "F.Cu" "F.Mask" "F.Paste")
			(net "M_D_CPU1_SB_DQ<11>")
		)
		(pad "259" smd rect
			(at 2.050034 38.675056 90)
			(size 0.519938 1.4986)
			(layers "F.Cu" "F.Mask" "F.Paste")
			(net "GND")
		)
		(pad "260" smd rect
			(at 2.050034 39.52494 90)
			(size 0.519938 1.4986)
			(layers "F.Cu" "F.Mask" "F.Paste")
			(net "M_D_CPU1_SB_DQS_DN<6>")
		)
		(pad "261" smd rect
			(at 2.050034 40.375078 90)
			(size 0.519938 1.4986)
			(layers "F.Cu" "F.Mask" "F.Paste")
			(net "M_D_CPU1_SB_DQS_DP<6>")
		)
		(pad "262" smd rect
			(at 2.050034 41.224962 90)
			(size 0.519938 1.4986)
			(layers "F.Cu" "F.Mask" "F.Paste")
			(net "GND")
		)
		(pad "263" smd rect
			(at 2.050034 42.0751 90)
			(size 0.519938 1.4986)
			(layers "F.Cu" "F.Mask" "F.Paste")
			(net "M_D_CPU1_SB_DQ<14>")
		)
		(pad "264" smd rect
			(at 2.050034 42.924984 90)
			(size 0.519938 1.4986)
			(layers "F.Cu" "F.Mask" "F.Paste")
			(net "GND")
		)
		(pad "265" smd rect
			(at 2.050034 43.775122 90)
			(size 0.519938 1.4986)
			(layers "F.Cu" "F.Mask" "F.Paste")
			(net "M_D_CPU1_SB_DQ<15>")
		)
		(pad "266" smd rect
			(at 2.050034 44.625006 90)
			(size 0.519938 1.4986)
			(layers "F.Cu" "F.Mask" "F.Paste")
			(net "GND")
		)
		(pad "267" smd rect
			(at 2.050034 45.47489 90)
			(size 0.519938 1.4986)
			(layers "F.Cu" "F.Mask" "F.Paste")
			(net "M_D_CPU1_SB_DQ<18>")
		)
		(pad "268" smd rect
			(at 2.050034 46.325028 90)
			(size 0.519938 1.4986)
			(layers "F.Cu" "F.Mask" "F.Paste")
			(net "GND")
		)
		(pad "269" smd rect
			(at 2.050034 47.174912 90)
			(size 0.519938 1.4986)
			(layers "F.Cu" "F.Mask" "F.Paste")
			(net "M_D_CPU1_SB_DQ<19>")
		)
		(pad "270" smd rect
			(at 2.050034 48.02505 90)
			(size 0.519938 1.4986)
			(layers "F.Cu" "F.Mask" "F.Paste")
			(net "GND")
		)
		(pad "271" smd rect
			(at 2.050034 48.874934 90)
			(size 0.519938 1.4986)
			(layers "F.Cu" "F.Mask" "F.Paste")
			(net "M_D_CPU1_SB_DQS_DN<7>")
		)
		(pad "272" smd rect
			(at 2.050034 49.725072 90)
			(size 0.519938 1.4986)
			(layers "F.Cu" "F.Mask" "F.Paste")
			(net "M_D_CPU1_SB_DQS_DP<7>")
		)
		(pad "273" smd rect
			(at 2.050034 50.574956 90)
			(size 0.519938 1.4986)
			(layers "F.Cu" "F.Mask" "F.Paste")
			(net "GND")
		)
		(pad "274" smd rect
			(at 2.050034 51.425094 90)
			(size 0.519938 1.4986)
			(layers "F.Cu" "F.Mask" "F.Paste")
			(net "M_D_CPU1_SB_DQ<22>")
		)
		(pad "275" smd rect
			(at 2.050034 52.274978 90)
			(size 0.519938 1.4986)
			(layers "F.Cu" "F.Mask" "F.Paste")
			(net "GND")
		)
		(pad "276" smd rect
			(at 2.050034 53.125116 90)
			(size 0.519938 1.4986)
			(layers "F.Cu" "F.Mask" "F.Paste")
			(net "M_D_CPU1_SB_DQ<23>")
		)
		(pad "277" smd rect
			(at 2.050034 53.975 90)
			(size 0.519938 1.4986)
			(layers "F.Cu" "F.Mask" "F.Paste")
			(net "GND")
		)
		(pad "278" smd rect
			(at 2.050034 54.824884 90)
			(size 0.519938 1.4986)
			(layers "F.Cu" "F.Mask" "F.Paste")
			(net "M_D_CPU1_SB_DQ<26>")
		)
		(pad "279" smd rect
			(at 2.050034 55.675022 90)
			(size 0.519938 1.4986)
			(layers "F.Cu" "F.Mask" "F.Paste")
			(net "GND")
		)
		(pad "280" smd rect
			(at 2.050034 56.524906 90)
			(size 0.519938 1.4986)
			(layers "F.Cu" "F.Mask" "F.Paste")
			(net "M_D_CPU1_SB_DQ<27>")
		)
		(pad "281" smd rect
			(at 2.050034 57.375044 90)
			(size 0.519938 1.4986)
			(layers "F.Cu" "F.Mask" "F.Paste")
			(net "GND")
		)
		(pad "282" smd rect
			(at 2.050034 58.224928 90)
			(size 0.519938 1.4986)
			(layers "F.Cu" "F.Mask" "F.Paste")
			(net "M_D_CPU1_SB_DQS_DN<8>")
		)
		(pad "283" smd rect
			(at 2.050034 59.075066 90)
			(size 0.519938 1.4986)
			(layers "F.Cu" "F.Mask" "F.Paste")
			(net "M_D_CPU1_SB_DQS_DP<8>")
		)
		(pad "284" smd rect
			(at 2.050034 59.92495 90)
			(size 0.519938 1.4986)
			(layers "F.Cu" "F.Mask" "F.Paste")
			(net "GND")
		)
		(pad "285" smd rect
			(at 2.050034 60.775088 90)
			(size 0.519938 1.4986)
			(layers "F.Cu" "F.Mask" "F.Paste")
			(net "M_D_CPU1_SB_DQ<30>")
		)
		(pad "286" smd rect
			(at 2.050034 61.624972 90)
			(size 0.519938 1.4986)
			(layers "F.Cu" "F.Mask" "F.Paste")
			(net "GND")
		)
		(pad "287" smd rect
			(at 2.050034 62.47511 90)
			(size 0.519938 1.4986)
			(layers "F.Cu" "F.Mask" "F.Paste")
			(net "M_D_CPU1_SB_DQ<31>")
		)
		(pad "288" smd rect
			(at 2.050034 63.324994 90)
			(size 0.519938 1.4986)
			(layers "F.Cu" "F.Mask" "F.Paste")
			(net "GND")
		)
		(pad "G1" thru_hole oval
			(at 0 -68.97497 90)
			(size 1.7272 3.4798)
			(drill oval 1.2192 2.4638)
			(layers "*.Cu" "*.Mask")
			(remove_unused_layers no)
			(net "GND")
			(clearance 0.127)
			(thermal_gap 0.127)
		)
		(pad "G2" thru_hole oval
			(at 0 3.875024 90)
			(size 1.7272 3.4798)
			(drill oval 1.2192 2.4638)
			(layers "*.Cu" "*.Mask")
			(remove_unused_layers no)
			(net "GND")
			(clearance 0.127)
			(thermal_gap 0.127)
		)
		(pad "G3" thru_hole oval
			(at 0 68.97497 90)
			(size 1.7272 3.4798)
			(drill oval 1.2192 2.4638)
			(layers "*.Cu" "*.Mask")
			(remove_unused_layers no)
			(net "GND")
			(clearance 0.127)
			(thermal_gap 0.127)
		)
	)
	(footprint ""
		(layer "F.Cu")
		(at 78.764638 -334.99298)
		(property "Reference" "PU5"
			(at -0.659638 -8.51535 0)
			(unlocked yes)
			(layer "F.SilkS")
			(effects
				(font
					(size 0.7874 0.5842)
					(thickness 0.1524)
				)
				(justify left)
			)
		)
		(property "Value" ""
			(at 0 0 0)
			(layer "F.Fab")
			(effects
				(font
					(size 1.27 1.27)
				)
			)
		)
		(duplicate_pad_numbers_are_jumpers no)
		(fp_line
			(start -2.500122 -2.999994)
			(end -2.24409 -2.999994)
			(stroke
				(width 0.1524)
				(type default)
			)
			(layer "F.SilkS")
		)
		(fp_line
			(start -2.500122 -2.529078)
			(end -2.500122 -2.999994)
			(stroke
				(width 0.1524)
				(type default)
			)
			(layer "F.SilkS")
		)
		(fp_line
			(start -2.500122 0.6604)
			(end -2.500122 0.229108)
			(stroke
				(width 0.1524)
				(type default)
			)
			(layer "F.SilkS")
		)
		(fp_line
			(start -2.500122 2.999994)
			(end -2.500122 2.339594)
			(stroke
				(width 0.1524)
				(type default)
			)
			(layer "F.SilkS")
		)
		(fp_line
			(start -2.2987 2.999994)
			(end -2.500122 2.999994)
			(stroke
				(width 0.1524)
				(type default)
			)
			(layer "F.SilkS")
		)
		(fp_line
			(start 2.31394 -2.999994)
			(end 2.500122 -2.999994)
			(stroke
				(width 0.1524)
				(type default)
			)
			(layer "F.SilkS")
		)
		(fp_line
			(start 2.500122 -2.999994)
			(end 2.500122 -2.44348)
			(stroke
				(width 0.1524)
				(type default)
			)
			(layer "F.SilkS")
		)
		(fp_line
			(start 2.500122 2.339594)
			(end 2.500122 2.999994)
			(stroke
				(width 0.1524)
				(type default)
			)
			(layer "F.SilkS")
		)
		(fp_line
			(start 2.500122 2.999994)
			(end 2.2987 2.999994)
			(stroke
				(width 0.1524)
				(type default)
			)
			(layer "F.SilkS")
		)
		(fp_poly
			(pts
				(xy -2.7686 -2.321306) (xy -3.441954 -2.545842) (xy -2.993136 -2.994914)
			)
			(stroke
				(width 0)
				(type default)
			)
			(fill yes)
			(layer "F.SilkS")
		)
		(fp_line
			(start -2.500122 -2.999994)
			(end 2.500122 -2.999994)
			(stroke
				(width 0.1)
				(type default)
			)
			(layer "F.Fab")
		)
		(fp_line
			(start -2.500122 2.999994)
			(end -2.500122 -2.999994)
			(stroke
				(width 0.1)
				(type default)
			)
			(layer "F.Fab")
		)
		(fp_line
			(start 2.500122 -2.999994)
			(end 2.500122 2.999994)
			(stroke
				(width 0.1)
				(type default)
			)
			(layer "F.Fab")
		)
		(fp_line
			(start 2.500122 2.999994)
			(end -2.500122 2.999994)
			(stroke
				(width 0.1)
				(type default)
			)
			(layer "F.Fab")
		)
		(fp_poly
			(pts
				(xy -4.218432 -2.783078) (xy -4.218432 -1.767078) (xy -3.202432 -2.275078)
			)
			(stroke
				(width 0)
				(type default)
			)
			(fill yes)
			(layer "F.Fab")
		)
		(pad "1" smd rect
			(at -2.400046 -2.275078 90)
			(size 0.2286 0.6096)
			(layers "F.Cu" "F.Mask" "F.Paste")
			(net "PVDDCR_CPU1_P1_VOS2")
		)
		(pad "2" smd rect
			(at -2.400046 -1.82499 90)
			(size 0.2286 0.6096)
			(layers "F.Cu" "F.Mask" "F.Paste")
			(net "GND")
		)
		(pad "3" smd rect
			(at -2.400046 -1.374902 90)
			(size 0.2286 0.6096)
			(layers "F.Cu" "F.Mask" "F.Paste")
			(net "PVDDCR_CPU1_P1_VCC2")
		)
		(pad "4" smd rect
			(at -2.400046 -0.925068 90)
			(size 0.2286 0.6096)
			(layers "F.Cu" "F.Mask" "F.Paste")
			(net "PVDDCR_CPU1_P1_PVCC")
		)
		(pad "5" smd rect
			(at -2.400046 -0.47498 90)
			(size 0.2286 0.6096)
			(layers "F.Cu" "F.Mask" "F.Paste")
			(net "GND")
		)
		(pad "6" smd rect
			(at -2.400046 -0.024892 90)
			(size 0.2286 0.6096)
			(layers "F.Cu" "F.Mask" "F.Paste")
			(net "NC_PVDDCR_CPU1_P1_GL1_2")
		)
		(pad "7_9-20_24" smd circle
			(at 0 1.150112 90)
			(size 0 0)
			(layers "F.Cu" "F.Mask" "F.Paste")
			(net "GND")
		)
		(pad "10_19" smd rect
			(at 0 2.899918 90)
			(size 0.6096 4.318)
			(layers "F.Cu" "F.Mask" "F.Paste")
			(net "SW_PVDDCR_CPU1_P1_SW2")
		)
		(pad "25_29" smd rect
			(at 1.549908 -1.279906 270)
			(size 2.0574 2.3114)
			(layers "F.Cu" "F.Mask" "F.Paste")
			(net "SW_P12V_AUX_PVDDCR_CPU1_P1_FLT")
		)
		(pad "30" smd rect
			(at 2.05994 -2.899918)
			(size 0.2286 0.6096)
			(layers "F.Cu" "F.Mask" "F.Paste")
			(net "SW_P12V_AUX_PVDDCR_CPU1_P1_FLT")
		)
		(pad "31" smd rect
			(at 1.610106 -2.899918)
			(size 0.2286 0.6096)
			(layers "F.Cu" "F.Mask" "F.Paste")
			(net "NC_PVDDCR_CPU1_P1_DNC2")
		)
		(pad "32" smd rect
			(at 1.160018 -2.899918)
			(size 0.2286 0.6096)
			(layers "F.Cu" "F.Mask" "F.Paste")
			(net "SW_PVDDCR_CPU1_P1_BOOTR2")
		)
		(pad "33" smd rect
			(at 0.70993 -2.899918)
			(size 0.2286 0.6096)
			(layers "F.Cu" "F.Mask" "F.Paste")
			(net "SW_PVDDCR_CPU1_P1_BOOT2")
		)
		(pad "34" smd rect
			(at 0.260096 -2.899918)
			(size 0.2286 0.6096)
			(layers "F.Cu" "F.Mask" "F.Paste")
			(net "PVDDCR_CPU1_P1_PWM2")
		)
		(pad "35" smd rect
			(at -0.189992 -2.899918)
			(size 0.2286 0.6096)
			(layers "F.Cu" "F.Mask" "F.Paste")
			(net "PVDDCR_CPU1_P1_VCC2")
		)
		(pad "36" smd rect
			(at -0.64008 -2.899918)
			(size 0.2286 0.6096)
			(layers "F.Cu" "F.Mask" "F.Paste")
			(net "PVDDCR_CPU1_P1_TEMP0")
		)
		(pad "37" smd rect
			(at -1.089914 -2.899918)
			(size 0.2286 0.6096)
			(layers "F.Cu" "F.Mask" "F.Paste")
			(net "PVDDCR_CPU1_P1_LSET2")
		)
		(pad "38" smd rect
			(at -1.540002 -2.899918)
			(size 0.2286 0.6096)
			(layers "F.Cu" "F.Mask" "F.Paste")
			(net "PVDDCR_CPU1_P1_IMON2")
		)
		(pad "39" smd rect
			(at -1.99009 -2.899918)
			(size 0.2286 0.6096)
			(layers "F.Cu" "F.Mask" "F.Paste")
			(net "PVDDCR_CPU1_P1_VCCS")
		)
		(pad "40" smd rect
			(at -0.87503 -1.27508)
			(size 1.7526 1.9558)
			(layers "F.Cu" "F.Mask" "F.Paste")
			(net "GND")
		)
		(pad "41" smd rect
			(at -1.525016 0.249936 270)
			(size 0.3048 0.4572)
			(layers "F.Cu" "F.Mask" "F.Paste")
			(net "NC_PVDDCR_CPU1_P1_GL2_2")
		)
		(zone
			(layer "F.Cu")
			(hatch none 0.5)
			(connect_pads
				(clearance 0)
			)
			(min_thickness 0.25)
			(keepout
				(tracks not_allowed)
				(vias allowed)
				(pads allowed)
				(copperpour not_allowed)
				(footprints allowed)
			)
			(placement
				(enabled no)
				(sheetname "")
			)
			(fill
				(thermal_gap 0.5)
				(thermal_bridge_width 0.5)
				(island_removal_mode 0)
			)
			(polygon
				(pts
					(xy 76.264516 -332.394052) (xy 76.264516 -332.742286) (xy 81.26476 -332.742286) (xy 81.26476 -332.420976)
					(xy 80.974438 -332.420976) (xy 80.974438 -332.448662) (xy 76.554838 -332.448662) (xy 76.554838 -332.394052)
				)
			)
		)
		(zone
			(layer "F.Cu")
			(hatch none 0.5)
			(connect_pads
				(clearance 0)
			)
			(min_thickness 0.25)
			(keepout
				(tracks not_allowed)
				(vias allowed)
				(pads allowed)
				(copperpour not_allowed)
				(footprints allowed)
			)
			(placement
				(enabled no)
				(sheetname "")
			)
			(fill
				(thermal_gap 0.5)
				(thermal_bridge_width 0.5)
				(island_removal_mode 0)
			)
			(polygon
				(pts
					(xy 78.816708 -335.23936) (xy 78.816708 -337.29676) (xy 76.962508 -337.29676) (xy 76.962508 -337.055714)
					(xy 76.720192 -337.055714) (xy 76.720192 -337.537298) (xy 80.504538 -337.537298) (xy 80.504538 -337.352386)
					(xy 79.108046 -337.352386) (xy 79.108046 -335.193386) (xy 81.26476 -335.193386) (xy 81.26476 -334.943704)
					(xy 79.112364 -334.943704)
				)
			)
		)
	)
	(footprint ""
		(layer "F.Cu")
		(at 413.754062 -416.899344 -90)
		(property "Reference" "C6594"
			(at 0 0 270)
			(layer "F.SilkS")
			(hide yes)
			(effects
				(font
					(size 1.27 1.27)
				)
			)
		)
		(property "Value" ""
			(at 0 0 270)
			(layer "F.Fab")
			(effects
				(font
					(size 1.27 1.27)
				)
			)
		)
		(duplicate_pad_numbers_are_jumpers no)
		(fp_line
			(start -0.299974 0.150114)
			(end -0.299974 -0.150114)
			(stroke
				(width 0.1)
				(type default)
			)
			(layer "F.Fab")
		)
		(fp_line
			(start 0.299974 0.150114)
			(end -0.299974 0.150114)
			(stroke
				(width 0.1)
				(type default)
			)
			(layer "F.Fab")
		)
		(fp_line
			(start -0.299974 -0.150114)
			(end 0.299974 -0.150114)
			(stroke
				(width 0.1)
				(type default)
			)
			(layer "F.Fab")
		)
		(fp_line
			(start 0.299974 -0.150114)
			(end 0.299974 0.150114)
			(stroke
				(width 0.1)
				(type default)
			)
			(layer "F.Fab")
		)
		(pad "1" smd rect
			(at -0.2667 0 270)
			(size 0.3048 0.381)
			(layers "F.Cu" "F.Mask" "F.Paste")
			(net "P5E_CPU0_P2_TX_BUF_C_DN<14>")
		)
		(pad "2" smd rect
			(at 0.2667 0 270)
			(size 0.3048 0.381)
			(layers "F.Cu" "F.Mask" "F.Paste")
			(net "P5E_CPU0_P2_TX_BUF_DN<14>")
		)
	)
	(footprint ""
		(layer "F.Cu")
		(at 373.811292 -381.41783 -90)
		(property "Reference" "C890"
			(at 0 0 270)
			(layer "F.SilkS")
			(hide yes)
			(effects
				(font
					(size 1.27 1.27)
				)
			)
		)
		(property "Value" ""
			(at 0 0 270)
			(layer "F.Fab")
			(effects
				(font
					(size 1.27 1.27)
				)
			)
		)
		(duplicate_pad_numbers_are_jumpers no)
		(fp_line
			(start -0.299974 0.150114)
			(end -0.299974 -0.150114)
			(stroke
				(width 0.1)
				(type default)
			)
			(layer "F.Fab")
		)
		(fp_line
			(start 0.299974 0.150114)
			(end -0.299974 0.150114)
			(stroke
				(width 0.1)
				(type default)
			)
			(layer "F.Fab")
		)
		(fp_line
			(start -0.299974 -0.150114)
			(end 0.299974 -0.150114)
			(stroke
				(width 0.1)
				(type default)
			)
			(layer "F.Fab")
		)
		(fp_line
			(start 0.299974 -0.150114)
			(end 0.299974 0.150114)
			(stroke
				(width 0.1)
				(type default)
			)
			(layer "F.Fab")
		)
		(pad "1" smd rect
			(at -0.2667 0 270)
			(size 0.3048 0.381)
			(layers "F.Cu" "F.Mask" "F.Paste")
			(net "P5E_CPU0_P3_TX_C_DN<5>")
		)
		(pad "2" smd rect
			(at 0.2667 0 270)
			(size 0.3048 0.381)
			(layers "F.Cu" "F.Mask" "F.Paste")
			(net "P5E_CPU0_P3_TX_DN<5>")
		)
	)
	(footprint ""
		(layer "F.Cu")
		(at 52.413154 -370.57203 -90)
		(property "Reference" "C824"
			(at 0 0 270)
			(layer "F.SilkS")
			(hide yes)
			(effects
				(font
					(size 1.27 1.27)
				)
			)
		)
		(property "Value" ""
			(at 0 0 270)
			(layer "F.Fab")
			(effects
				(font
					(size 1.27 1.27)
				)
			)
		)
		(duplicate_pad_numbers_are_jumpers no)
		(fp_line
			(start -0.299974 0.150114)
			(end -0.299974 -0.150114)
			(stroke
				(width 0.1)
				(type default)
			)
			(layer "F.Fab")
		)
		(fp_line
			(start 0.299974 0.150114)
			(end -0.299974 0.150114)
			(stroke
				(width 0.1)
				(type default)
			)
			(layer "F.Fab")
		)
		(fp_line
			(start -0.299974 -0.150114)
			(end 0.299974 -0.150114)
			(stroke
				(width 0.1)
				(type default)
			)
			(layer "F.Fab")
		)
		(fp_line
			(start 0.299974 -0.150114)
			(end 0.299974 0.150114)
			(stroke
				(width 0.1)
				(type default)
			)
			(layer "F.Fab")
		)
		(pad "1" smd rect
			(at -0.2667 0 270)
			(size 0.3048 0.381)
			(layers "F.Cu" "F.Mask" "F.Paste")
			(net "P5E_CPU1_P0_TX_C_DN<6>")
		)
		(pad "2" smd rect
			(at 0.2667 0 270)
			(size 0.3048 0.381)
			(layers "F.Cu" "F.Mask" "F.Paste")
			(net "P5E_CPU1_P0_TX_DN<6>")
		)
	)
	(footprint ""
		(layer "F.Cu")
		(at 227.59162 -291.863526 180)
		(property "Reference" "PC6537"
			(at 0 0 180)
			(layer "F.SilkS")
			(hide yes)
			(effects
				(font
					(size 1.27 1.27)
				)
			)
		)
		(property "Value" ""
			(at 0 0 180)
			(layer "F.Fab")
			(effects
				(font
					(size 1.27 1.27)
				)
			)
		)
		(duplicate_pad_numbers_are_jumpers no)
		(fp_line
			(start 0.7874 0.4064)
			(end -0.7874 0.4064)
			(stroke
				(width 0.1524)
				(type default)
			)
			(layer "F.SilkS")
		)
		(fp_line
			(start 0.7874 -0.4064)
			(end 0.7874 0.4064)
			(stroke
				(width 0.1524)
				(type default)
			)
			(layer "F.SilkS")
		)
		(fp_line
			(start -0.7874 0.4064)
			(end -0.7874 -0.4064)
			(stroke
				(width 0.1524)
				(type default)
			)
			(layer "F.SilkS")
		)
		(fp_line
			(start -0.7874 -0.4064)
			(end 0.7874 -0.4064)
			(stroke
				(width 0.1524)
				(type default)
			)
			(layer "F.SilkS")
		)
		(fp_line
			(start 0.67945 0.3048)
			(end 0.120396 0.3048)
			(stroke
				(width 0.1)
				(type default)
			)
			(layer "F.Fab")
		)
		(fp_line
			(start 0.67945 -0.3048)
			(end 0.67945 0.3048)
			(stroke
				(width 0.1)
				(type default)
			)
			(layer "F.Fab")
		)
		(fp_line
			(start 0.12065 -0.2794)
			(end 0.12065 -0.3048)
			(stroke
				(width 0.1)
				(type default)
			)
			(layer "F.Fab")
		)
		(fp_line
			(start 0.12065 -0.3048)
			(end 0.67945 -0.3048)
			(stroke
				(width 0.1)
				(type default)
			)
			(layer "F.Fab")
		)
		(fp_line
			(start 0.120396 0.3048)
			(end 0.120396 0.2794)
			(stroke
				(width 0.1)
				(type default)
			)
			(layer "F.Fab")
		)
		(fp_line
			(start 0.120396 0.2794)
			(end -0.12065 0.2794)
			(stroke
				(width 0.1)
				(type default)
			)
			(layer "F.Fab")
		)
		(fp_line
			(start -0.12065 0.3048)
			(end -0.67945 0.3048)
			(stroke
				(width 0.1)
				(type default)
			)
			(layer "F.Fab")
		)
		(fp_line
			(start -0.12065 0.2794)
			(end -0.12065 0.3048)
			(stroke
				(width 0.1)
				(type default)
			)
			(layer "F.Fab")
		)
		(fp_line
			(start -0.12065 -0.2794)
			(end 0.12065 -0.2794)
			(stroke
				(width 0.1)
				(type default)
			)
			(layer "F.Fab")
		)
		(fp_line
			(start -0.12065 -0.305054)
			(end -0.12065 -0.2794)
			(stroke
				(width 0.1)
				(type default)
			)
			(layer "F.Fab")
		)
		(fp_line
			(start -0.67945 0.3048)
			(end -0.67945 -0.305054)
			(stroke
				(width 0.1)
				(type default)
			)
			(layer "F.Fab")
		)
		(fp_line
			(start -0.67945 -0.305054)
			(end -0.12065 -0.305054)
			(stroke
				(width 0.1)
				(type default)
			)
			(layer "F.Fab")
		)
		(pad "1" smd circle
			(at -0.40005 0 180)
			(size 0 0)
			(layers "F.Cu" "F.Mask" "F.Paste")
			(net "P1V8_RETIMER_CPU1_REF")
		)
		(pad "2" smd circle
			(at 0.40005 0 180)
			(size 0 0)
			(layers "F.Cu" "F.Mask" "F.Paste")
			(net "GND")
		)
	)
	(footprint ""
		(layer "F.Cu")
		(at 347.690694 -170.457114 180)
		(property "Reference" "PL70"
			(at 3.709924 7.921498 0)
			(unlocked yes)
			(layer "F.SilkS")
			(effects
				(font
					(size 0.7874 0.5842)
					(thickness 0.1524)
				)
				(justify left)
			)
		)
		(property "Value" ""
			(at 0 0 180)
			(layer "F.Fab")
			(effects
				(font
					(size 1.27 1.27)
				)
			)
		)
		(duplicate_pad_numbers_are_jumpers no)
		(fp_line
			(start 3.750056 5.500116)
			(end 3.750056 -5.500116)
			(stroke
				(width 0.1524)
				(type default)
			)
			(layer "F.SilkS")
		)
		(fp_line
			(start 3.750056 -5.500116)
			(end 2.393442 -5.500116)
			(stroke
				(width 0.1524)
				(type default)
			)
			(layer "F.SilkS")
		)
		(fp_line
			(start 2.393442 5.500116)
			(end 3.750056 5.500116)
			(stroke
				(width 0.1524)
				(type default)
			)
			(layer "F.SilkS")
		)
		(fp_line
			(start -2.393442 5.500116)
			(end -3.750056 5.500116)
			(stroke
				(width 0.1524)
				(type default)
			)
			(layer "F.SilkS")
		)
		(fp_line
			(start -3.750056 5.500116)
			(end -3.750056 -5.500116)
			(stroke
				(width 0.1524)
				(type default)
			)
			(layer "F.SilkS")
		)
		(fp_line
			(start -3.750056 -5.500116)
			(end -2.393442 -5.500116)
			(stroke
				(width 0.1524)
				(type default)
			)
			(layer "F.SilkS")
		)
		(fp_poly
			(pts
				(xy -3.962908 -5.305044) (xy -4.978908 -4.797044) (xy -4.978908 -5.813044)
			)
			(stroke
				(width 0)
				(type default)
			)
			(fill yes)
			(layer "F.SilkS")
		)
		(fp_line
			(start 3.750056 5.500116)
			(end 3.750056 -5.500116)
			(stroke
				(width 0.1)
				(type default)
			)
			(layer "F.Fab")
		)
		(fp_line
			(start 3.750056 -5.500116)
			(end -3.750056 -5.500116)
			(stroke
				(width 0.1)
				(type default)
			)
			(layer "F.Fab")
		)
		(fp_line
			(start -3.750056 5.500116)
			(end 3.750056 5.500116)
			(stroke
				(width 0.1)
				(type default)
			)
			(layer "F.Fab")
		)
		(fp_line
			(start -3.750056 -5.500116)
			(end -3.750056 5.500116)
			(stroke
				(width 0.1)
				(type default)
			)
			(layer "F.Fab")
		)
		(fp_poly
			(pts
				(xy -4.9276 -4.757928) (xy -4.9276 -3.741928) (xy -3.9116 -4.249928)
			)
			(stroke
				(width 0)
				(type default)
			)
			(fill yes)
			(layer "F.Fab")
		)
		(pad "1" smd rect
			(at 0 -4.249928 90)
			(size 2.413 4.5212)
			(layers "F.Cu" "F.Mask" "F.Paste")
			(net "SW_PVDDCR_CPU0_P0_SW6")
		)
		(pad "2" smd rect
			(at 0 -1.175004 90)
			(size 1.3716 4.5212)
			(layers "F.Cu" "F.Mask" "F.Paste")
			(net "IND_CPU0_P0_CPL0")
		)
		(pad "3" smd rect
			(at 0 1.175004 90)
			(size 1.3716 4.5212)
			(layers "F.Cu" "F.Mask" "F.Paste")
			(net "IND_CPU0_P0_CPL6")
		)
		(pad "4" smd rect
			(at 0 4.249928 90)
			(size 2.413 4.5212)
			(layers "F.Cu" "F.Mask" "F.Paste")
			(net "PVDDCR_CPU0_P0")
		)
	)
	(footprint ""
		(layer "F.Cu")
		(at 252.222 -38.683946 180)
		(property "Reference" "R3978"
			(at 0 0 180)
			(layer "F.SilkS")
			(hide yes)
			(effects
				(font
					(size 1.27 1.27)
				)
			)
		)
		(property "Value" ""
			(at 0 0 180)
			(layer "F.Fab")
			(effects
				(font
					(size 1.27 1.27)
				)
			)
		)
		(duplicate_pad_numbers_are_jumpers no)
		(fp_line
			(start 0.7874 0.4064)
			(end -0.7874 0.4064)
			(stroke
				(width 0.1524)
				(type default)
			)
			(layer "F.SilkS")
		)
		(fp_line
			(start 0.7874 -0.4064)
			(end 0.7874 0.4064)
			(stroke
				(width 0.1524)
				(type default)
			)
			(layer "F.SilkS")
		)
		(fp_line
			(start -0.7874 0.4064)
			(end -0.7874 -0.4064)
			(stroke
				(width 0.1524)
				(type default)
			)
			(layer "F.SilkS")
		)
		(fp_line
			(start -0.7874 -0.4064)
			(end 0.7874 -0.4064)
			(stroke
				(width 0.1524)
				(type default)
			)
			(layer "F.SilkS")
		)
		(fp_line
			(start 0.67945 0.3048)
			(end 0.120396 0.3048)
			(stroke
				(width 0.1)
				(type default)
			)
			(layer "F.Fab")
		)
		(fp_line
			(start 0.67945 -0.3048)
			(end 0.67945 0.3048)
			(stroke
				(width 0.1)
				(type default)
			)
			(layer "F.Fab")
		)
		(fp_line
			(start 0.12065 -0.2794)
			(end 0.12065 -0.3048)
			(stroke
				(width 0.1)
				(type default)
			)
			(layer "F.Fab")
		)
		(fp_line
			(start 0.12065 -0.3048)
			(end 0.67945 -0.3048)
			(stroke
				(width 0.1)
				(type default)
			)
			(layer "F.Fab")
		)
		(fp_line
			(start 0.120396 0.3048)
			(end 0.120396 0.2794)
			(stroke
				(width 0.1)
				(type default)
			)
			(layer "F.Fab")
		)
		(fp_line
			(start 0.120396 0.2794)
			(end -0.12065 0.2794)
			(stroke
				(width 0.1)
				(type default)
			)
			(layer "F.Fab")
		)
		(fp_line
			(start -0.12065 0.3048)
			(end -0.67945 0.3048)
			(stroke
				(width 0.1)
				(type default)
			)
			(layer "F.Fab")
		)
		(fp_line
			(start -0.12065 0.2794)
			(end -0.12065 0.3048)
			(stroke
				(width 0.1)
				(type default)
			)
			(layer "F.Fab")
		)
		(fp_line
			(start -0.12065 -0.2794)
			(end 0.12065 -0.2794)
			(stroke
				(width 0.1)
				(type default)
			)
			(layer "F.Fab")
		)
		(fp_line
			(start -0.12065 -0.305054)
			(end -0.12065 -0.2794)
			(stroke
				(width 0.1)
				(type default)
			)
			(layer "F.Fab")
		)
		(fp_line
			(start -0.67945 0.3048)
			(end -0.67945 -0.305054)
			(stroke
				(width 0.1)
				(type default)
			)
			(layer "F.Fab")
		)
		(fp_line
			(start -0.67945 -0.305054)
			(end -0.12065 -0.305054)
			(stroke
				(width 0.1)
				(type default)
			)
			(layer "F.Fab")
		)
		(pad "1" smd circle
			(at -0.40005 0 180)
			(size 0 0)
			(layers "F.Cu" "F.Mask" "F.Paste")
			(net "P3V3_AUX")
		)
		(pad "2" smd circle
			(at 0.40005 0 180)
			(size 0 0)
			(layers "F.Cu" "F.Mask" "F.Paste")
			(net "HP_LVC3_E1S_0_HSC_PWRGD")
		)
	)
	(footprint ""
		(layer "F.Cu")
		(at 151.182832 -77.752956)
		(property "Reference" "PL6000"
			(at -5.397754 -4.964684 0)
			(unlocked yes)
			(layer "F.SilkS")
			(effects
				(font
					(size 0.7874 0.5842)
					(thickness 0.1524)
				)
				(justify left)
			)
		)
		(property "Value" ""
			(at 0 0 0)
			(layer "F.Fab")
			(effects
				(font
					(size 1.27 1.27)
				)
			)
		)
		(duplicate_pad_numbers_are_jumpers no)
		(fp_line
			(start -3.6576 -3.350006)
			(end 3.64998 -3.350006)
			(stroke
				(width 0.1524)
				(type default)
			)
			(layer "F.SilkS")
		)
		(fp_line
			(start -3.64998 -1.8034)
			(end -3.64998 -3.350006)
			(stroke
				(width 0.1524)
				(type default)
			)
			(layer "F.SilkS")
		)
		(fp_line
			(start -3.64998 3.350006)
			(end -3.64998 1.8288)
			(stroke
				(width 0.1524)
				(type default)
			)
			(layer "F.SilkS")
		)
		(fp_line
			(start 3.64998 -3.350006)
			(end 3.64998 -1.8034)
			(stroke
				(width 0.1524)
				(type default)
			)
			(layer "F.SilkS")
		)
		(fp_line
			(start 3.64998 1.8034)
			(end 3.64998 3.350006)
			(stroke
				(width 0.1524)
				(type default)
			)
			(layer "F.SilkS")
		)
		(fp_line
			(start 3.64998 3.350006)
			(end -3.64998 3.350006)
			(stroke
				(width 0.1524)
				(type default)
			)
			(layer "F.SilkS")
		)
		(fp_line
			(start -3.64998 -3.350006)
			(end 3.64998 -3.350006)
			(stroke
				(width 0.1)
				(type default)
			)
			(layer "F.Fab")
		)
		(fp_line
			(start -3.64998 3.350006)
			(end -3.64998 -3.350006)
			(stroke
				(width 0.1)
				(type default)
			)
			(layer "F.Fab")
		)
		(fp_line
			(start 3.64998 -3.350006)
			(end 3.64998 3.350006)
			(stroke
				(width 0.1)
				(type default)
			)
			(layer "F.Fab")
		)
		(fp_line
			(start 3.64998 3.350006)
			(end -3.64998 3.350006)
			(stroke
				(width 0.1)
				(type default)
			)
			(layer "F.Fab")
		)
		(pad "1" smd rect
			(at -2.92481 0)
			(size 2.15392 3.302)
			(layers "F.Cu" "F.Mask" "F.Paste")
			(net "SW_P1V8_AUX_PH")
		)
		(pad "2" smd rect
			(at 2.92481 0)
			(size 2.15392 3.302)
			(layers "F.Cu" "F.Mask" "F.Paste")
			(net "P1V8_AUX")
		)
	)
	(footprint ""
		(layer "F.Cu")
		(at 130.231642 -71.303134 180)
		(property "Reference" "PC6022"
			(at 0 0 180)
			(layer "F.SilkS")
			(hide yes)
			(effects
				(font
					(size 1.27 1.27)
				)
			)
		)
		(property "Value" ""
			(at 0 0 180)
			(layer "F.Fab")
			(effects
				(font
					(size 1.27 1.27)
				)
			)
		)
		(duplicate_pad_numbers_are_jumpers no)
		(fp_line
			(start 0.7874 0.4064)
			(end -0.7874 0.4064)
			(stroke
				(width 0.1524)
				(type default)
			)
			(layer "F.SilkS")
		)
		(fp_line
			(start 0.7874 -0.4064)
			(end 0.7874 0.4064)
			(stroke
				(width 0.1524)
				(type default)
			)
			(layer "F.SilkS")
		)
		(fp_line
			(start -0.7874 0.4064)
			(end -0.7874 -0.4064)
			(stroke
				(width 0.1524)
				(type default)
			)
			(layer "F.SilkS")
		)
		(fp_line
			(start -0.7874 -0.4064)
			(end 0.7874 -0.4064)
			(stroke
				(width 0.1524)
				(type default)
			)
			(layer "F.SilkS")
		)
		(fp_line
			(start 0.67945 0.3048)
			(end 0.120396 0.3048)
			(stroke
				(width 0.1)
				(type default)
			)
			(layer "F.Fab")
		)
		(fp_line
			(start 0.67945 -0.3048)
			(end 0.67945 0.3048)
			(stroke
				(width 0.1)
				(type default)
			)
			(layer "F.Fab")
		)
		(fp_line
			(start 0.12065 -0.2794)
			(end 0.12065 -0.3048)
			(stroke
				(width 0.1)
				(type default)
			)
			(layer "F.Fab")
		)
		(fp_line
			(start 0.12065 -0.3048)
			(end 0.67945 -0.3048)
			(stroke
				(width 0.1)
				(type default)
			)
			(layer "F.Fab")
		)
		(fp_line
			(start 0.120396 0.3048)
			(end 0.120396 0.2794)
			(stroke
				(width 0.1)
				(type default)
			)
			(layer "F.Fab")
		)
		(fp_line
			(start 0.120396 0.2794)
			(end -0.12065 0.2794)
			(stroke
				(width 0.1)
				(type default)
			)
			(layer "F.Fab")
		)
		(fp_line
			(start -0.12065 0.3048)
			(end -0.67945 0.3048)
			(stroke
				(width 0.1)
				(type default)
			)
			(layer "F.Fab")
		)
		(fp_line
			(start -0.12065 0.2794)
			(end -0.12065 0.3048)
			(stroke
				(width 0.1)
				(type default)
			)
			(layer "F.Fab")
		)
		(fp_line
			(start -0.12065 -0.2794)
			(end 0.12065 -0.2794)
			(stroke
				(width 0.1)
				(type default)
			)
			(layer "F.Fab")
		)
		(fp_line
			(start -0.12065 -0.305054)
			(end -0.12065 -0.2794)
			(stroke
				(width 0.1)
				(type default)
			)
			(layer "F.Fab")
		)
		(fp_line
			(start -0.67945 0.3048)
			(end -0.67945 -0.305054)
			(stroke
				(width 0.1)
				(type default)
			)
			(layer "F.Fab")
		)
		(fp_line
			(start -0.67945 -0.305054)
			(end -0.12065 -0.305054)
			(stroke
				(width 0.1)
				(type default)
			)
			(layer "F.Fab")
		)
		(pad "1" smd circle
			(at -0.40005 0 180)
			(size 0 0)
			(layers "F.Cu" "F.Mask" "F.Paste")
			(net "P1V2_AUX")
		)
		(pad "2" smd circle
			(at 0.40005 0 180)
			(size 0 0)
			(layers "F.Cu" "F.Mask" "F.Paste")
			(net "GND")
		)
	)
	(footprint ""
		(layer "F.Cu")
		(at 360.76001 -417.313618)
		(property "Reference" "R3036"
			(at 0 0 0)
			(layer "F.SilkS")
			(hide yes)
			(effects
				(font
					(size 1.27 1.27)
				)
			)
		)
		(property "Value" ""
			(at 0 0 0)
			(layer "F.Fab")
			(effects
				(font
					(size 1.27 1.27)
				)
			)
		)
		(duplicate_pad_numbers_are_jumpers no)
		(fp_line
			(start -0.7874 -0.4064)
			(end 0.7874 -0.4064)
			(stroke
				(width 0.1524)
				(type default)
			)
			(layer "F.SilkS")
		)
		(fp_line
			(start -0.7874 0.4064)
			(end -0.7874 -0.4064)
			(stroke
				(width 0.1524)
				(type default)
			)
			(layer "F.SilkS")
		)
		(fp_line
			(start 0.7874 -0.4064)
			(end 0.7874 0.4064)
			(stroke
				(width 0.1524)
				(type default)
			)
			(layer "F.SilkS")
		)
		(fp_line
			(start 0.7874 0.4064)
			(end -0.7874 0.4064)
			(stroke
				(width 0.1524)
				(type default)
			)
			(layer "F.SilkS")
		)
		(fp_line
			(start -0.67945 -0.305054)
			(end -0.12065 -0.305054)
			(stroke
				(width 0.1)
				(type default)
			)
			(layer "F.Fab")
		)
		(fp_line
			(start -0.67945 0.3048)
			(end -0.67945 -0.305054)
			(stroke
				(width 0.1)
				(type default)
			)
			(layer "F.Fab")
		)
		(fp_line
			(start -0.12065 -0.305054)
			(end -0.12065 -0.2794)
			(stroke
				(width 0.1)
				(type default)
			)
			(layer "F.Fab")
		)
		(fp_line
			(start -0.12065 -0.2794)
			(end 0.12065 -0.2794)
			(stroke
				(width 0.1)
				(type default)
			)
			(layer "F.Fab")
		)
		(fp_line
			(start -0.12065 0.2794)
			(end -0.12065 0.3048)
			(stroke
				(width 0.1)
				(type default)
			)
			(layer "F.Fab")
		)
		(fp_line
			(start -0.12065 0.3048)
			(end -0.67945 0.3048)
			(stroke
				(width 0.1)
				(type default)
			)
			(layer "F.Fab")
		)
		(fp_line
			(start 0.120396 0.2794)
			(end -0.12065 0.2794)
			(stroke
				(width 0.1)
				(type default)
			)
			(layer "F.Fab")
		)
		(fp_line
			(start 0.120396 0.3048)
			(end 0.120396 0.2794)
			(stroke
				(width 0.1)
				(type default)
			)
			(layer "F.Fab")
		)
		(fp_line
			(start 0.12065 -0.3048)
			(end 0.67945 -0.3048)
			(stroke
				(width 0.1)
				(type default)
			)
			(layer "F.Fab")
		)
		(fp_line
			(start 0.12065 -0.2794)
			(end 0.12065 -0.3048)
			(stroke
				(width 0.1)
				(type default)
			)
			(layer "F.Fab")
		)
		(fp_line
			(start 0.67945 -0.3048)
			(end 0.67945 0.3048)
			(stroke
				(width 0.1)
				(type default)
			)
			(layer "F.Fab")
		)
		(fp_line
			(start 0.67945 0.3048)
			(end 0.120396 0.3048)
			(stroke
				(width 0.1)
				(type default)
			)
			(layer "F.Fab")
		)
		(pad "1" smd circle
			(at -0.40005 0)
			(size 0 0)
			(layers "F.Cu" "F.Mask" "F.Paste")
			(net "UART_BMC_BIC_R_BUF_RX")
		)
		(pad "2" smd circle
			(at 0.40005 0)
			(size 0 0)
			(layers "F.Cu" "F.Mask" "F.Paste")
			(net "UART_BMC_BIC_BUF_RX")
		)
	)
	(footprint ""
		(layer "F.Cu")
		(at 260.99008 -138.848846 180)
		(property "Reference" "U54"
			(at 1.0033 -2.747264 0)
			(unlocked yes)
			(layer "F.SilkS")
			(effects
				(font
					(size 0.7874 0.5842)
					(thickness 0.1524)
				)
				(justify left)
			)
		)
		(property "Value" ""
			(at 0 0 180)
			(layer "F.Fab")
			(effects
				(font
					(size 1.27 1.27)
				)
			)
		)
		(duplicate_pad_numbers_are_jumpers no)
		(fp_line
			(start 1.145286 1.2954)
			(end 1.145286 -1.2954)
			(stroke
				(width 0.1524)
				(type default)
			)
			(layer "F.SilkS")
		)
		(fp_line
			(start 1.145286 -1.2954)
			(end -1.145286 -1.2954)
			(stroke
				(width 0.1524)
				(type default)
			)
			(layer "F.SilkS")
		)
		(fp_line
			(start -1.145286 1.2954)
			(end 1.145286 1.2954)
			(stroke
				(width 0.1524)
				(type default)
			)
			(layer "F.SilkS")
		)
		(fp_line
			(start -1.145286 -1.2954)
			(end -1.145286 1.2954)
			(stroke
				(width 0.1524)
				(type default)
			)
			(layer "F.SilkS")
		)
		(fp_poly
			(pts
				(xy -0.804926 -1.442466) (xy -1.058926 -1.950466) (xy -0.550926 -1.950466)
			)
			(stroke
				(width 0)
				(type default)
			)
			(fill yes)
			(layer "F.SilkS")
		)
		(fp_line
			(start 0.87503 1.02489)
			(end 0.87503 -1.02489)
			(stroke
				(width 0.1)
				(type default)
			)
			(layer "F.Fab")
		)
		(fp_line
			(start 0.87503 -1.02489)
			(end -0.87503 -1.02489)
			(stroke
				(width 0.1)
				(type default)
			)
			(layer "F.Fab")
		)
		(fp_line
			(start -0.87503 1.02489)
			(end 0.87503 1.02489)
			(stroke
				(width 0.1)
				(type default)
			)
			(layer "F.Fab")
		)
		(fp_line
			(start -0.87503 -1.02489)
			(end -0.87503 1.02489)
			(stroke
				(width 0.1)
				(type default)
			)
			(layer "F.Fab")
		)
		(fp_poly
			(pts
				(xy -1.9304 -1.0541) (xy -1.9304 -0.5461) (xy -1.4224 -0.8001)
			)
			(stroke
				(width 0)
				(type default)
			)
			(fill yes)
			(layer "F.Fab")
		)
		(pad "1" smd rect
			(at -0.649986 -0.8001 270)
			(size 0.1778 0.7112)
			(layers "F.Cu" "F.Mask" "F.Paste")
			(net "PVDD18_S5_P0")
		)
		(pad "2" smd rect
			(at -0.649986 -0.40005 270)
			(size 0.1778 0.7112)
			(layers "F.Cu" "F.Mask" "F.Paste")
			(net "SPI_CPU0_R1_D3")
		)
		(pad "3" smd rect
			(at -0.649986 0 270)
			(size 0.1778 0.7112)
			(layers "F.Cu" "F.Mask" "F.Paste")
			(net "SPI_CPU0_R1_D2")
		)
		(pad "4" smd rect
			(at -0.649986 0.40005 270)
			(size 0.1778 0.7112)
			(layers "F.Cu" "F.Mask" "F.Paste")
			(net "SPI_CPU0_R1_D0")
		)
		(pad "5" smd rect
			(at -0.649986 0.8001 270)
			(size 0.1778 0.7112)
			(layers "F.Cu" "F.Mask" "F.Paste")
			(net "SPI_CPU0_R1_D1")
		)
		(pad "6" smd rect
			(at 0 0.8001 180)
			(size 0.1778 0.7112)
			(layers "F.Cu" "F.Mask" "F.Paste")
			(net "GND")
		)
		(pad "7" smd rect
			(at 0.649986 0.8001 270)
			(size 0.1778 0.7112)
			(layers "F.Cu" "F.Mask" "F.Paste")
			(net "SPI_CPU0_LVC3_D1")
		)
		(pad "8" smd rect
			(at 0.649986 0.40005 270)
			(size 0.1778 0.7112)
			(layers "F.Cu" "F.Mask" "F.Paste")
			(net "SPI_CPU0_LVC3_D0")
		)
		(pad "9" smd rect
			(at 0.649986 0 270)
			(size 0.1778 0.7112)
			(layers "F.Cu" "F.Mask" "F.Paste")
			(net "SPI_CPU0_LVC3_D2")
		)
		(pad "10" smd rect
			(at 0.649986 -0.40005 270)
			(size 0.1778 0.7112)
			(layers "F.Cu" "F.Mask" "F.Paste")
			(net "SPI_CPU0_LVC3_D3")
		)
		(pad "11" smd rect
			(at 0.649986 -0.8001 270)
			(size 0.1778 0.7112)
			(layers "F.Cu" "F.Mask" "F.Paste")
			(net "P3V3_AUX")
		)
		(pad "12" smd rect
			(at 0 -0.8001 180)
			(size 0.1778 0.7112)
			(layers "F.Cu" "F.Mask" "F.Paste")
			(net "ROM_LS_EN")
		)
	)
	(footprint ""
		(layer "F.Cu")
		(at 62.559438 -31.887922 90)
		(property "Reference" "R3873"
			(at 0 0 90)
			(layer "F.SilkS")
			(hide yes)
			(effects
				(font
					(size 1.27 1.27)
				)
			)
		)
		(property "Value" ""
			(at 0 0 90)
			(layer "F.Fab")
			(effects
				(font
					(size 1.27 1.27)
				)
			)
		)
		(duplicate_pad_numbers_are_jumpers no)
		(fp_line
			(start 0.7874 -0.4064)
			(end 0.7874 0.4064)
			(stroke
				(width 0.1524)
				(type default)
			)
			(layer "F.SilkS")
		)
		(fp_line
			(start -0.7874 -0.4064)
			(end 0.7874 -0.4064)
			(stroke
				(width 0.1524)
				(type default)
			)
			(layer "F.SilkS")
		)
		(fp_line
			(start 0.7874 0.4064)
			(end -0.7874 0.4064)
			(stroke
				(width 0.1524)
				(type default)
			)
			(layer "F.SilkS")
		)
		(fp_line
			(start -0.7874 0.4064)
			(end -0.7874 -0.4064)
			(stroke
				(width 0.1524)
				(type default)
			)
			(layer "F.SilkS")
		)
		(fp_line
			(start -0.12065 -0.305054)
			(end -0.12065 -0.2794)
			(stroke
				(width 0.1)
				(type default)
			)
			(layer "F.Fab")
		)
		(fp_line
			(start -0.67945 -0.305054)
			(end -0.12065 -0.305054)
			(stroke
				(width 0.1)
				(type default)
			)
			(layer "F.Fab")
		)
		(fp_line
			(start 0.67945 -0.3048)
			(end 0.67945 0.3048)
			(stroke
				(width 0.1)
				(type default)
			)
			(layer "F.Fab")
		)
		(fp_line
			(start 0.12065 -0.3048)
			(end 0.67945 -0.3048)
			(stroke
				(width 0.1)
				(type default)
			)
			(layer "F.Fab")
		)
		(fp_line
			(start 0.12065 -0.2794)
			(end 0.12065 -0.3048)
			(stroke
				(width 0.1)
				(type default)
			)
			(layer "F.Fab")
		)
		(fp_line
			(start -0.12065 -0.2794)
			(end 0.12065 -0.2794)
			(stroke
				(width 0.1)
				(type default)
			)
			(layer "F.Fab")
		)
		(fp_line
			(start 0.120396 0.2794)
			(end -0.12065 0.2794)
			(stroke
				(width 0.1)
				(type default)
			)
			(layer "F.Fab")
		)
		(fp_line
			(start -0.12065 0.2794)
			(end -0.12065 0.3048)
			(stroke
				(width 0.1)
				(type default)
			)
			(layer "F.Fab")
		)
		(fp_line
			(start 0.67945 0.3048)
			(end 0.120396 0.3048)
			(stroke
				(width 0.1)
				(type default)
			)
			(layer "F.Fab")
		)
		(fp_line
			(start 0.120396 0.3048)
			(end 0.120396 0.2794)
			(stroke
				(width 0.1)
				(type default)
			)
			(layer "F.Fab")
		)
		(fp_line
			(start -0.12065 0.3048)
			(end -0.67945 0.3048)
			(stroke
				(width 0.1)
				(type default)
			)
			(layer "F.Fab")
		)
		(fp_line
			(start -0.67945 0.3048)
			(end -0.67945 -0.305054)
			(stroke
				(width 0.1)
				(type default)
			)
			(layer "F.Fab")
		)
		(pad "1" smd circle
			(at -0.40005 0 90)
			(size 0 0)
			(layers "F.Cu" "F.Mask" "F.Paste")
			(net "P12V_OCP_IMON_2")
		)
		(pad "2" smd circle
			(at 0.40005 0 90)
			(size 0 0)
			(layers "F.Cu" "F.Mask" "F.Paste")
			(net "P12V_OCP_V3_2_ISENSE_MPS_MAM")
		)
	)
	(footprint ""
		(layer "F.Cu")
		(at 68.212462 -38.405562 180)
		(property "Reference" "R3620"
			(at 0 0 180)
			(layer "F.SilkS")
			(hide yes)
			(effects
				(font
					(size 1.27 1.27)
				)
			)
		)
		(property "Value" ""
			(at 0 0 180)
			(layer "F.Fab")
			(effects
				(font
					(size 1.27 1.27)
				)
			)
		)
		(duplicate_pad_numbers_are_jumpers no)
		(fp_line
			(start 0.7874 0.4064)
			(end -0.7874 0.4064)
			(stroke
				(width 0.1524)
				(type default)
			)
			(layer "F.SilkS")
		)
		(fp_line
			(start 0.7874 -0.4064)
			(end 0.7874 0.4064)
			(stroke
				(width 0.1524)
				(type default)
			)
			(layer "F.SilkS")
		)
		(fp_line
			(start -0.7874 0.4064)
			(end -0.7874 -0.4064)
			(stroke
				(width 0.1524)
				(type default)
			)
			(layer "F.SilkS")
		)
		(fp_line
			(start -0.7874 -0.4064)
			(end 0.7874 -0.4064)
			(stroke
				(width 0.1524)
				(type default)
			)
			(layer "F.SilkS")
		)
		(fp_line
			(start 0.67945 0.3048)
			(end 0.120396 0.3048)
			(stroke
				(width 0.1)
				(type default)
			)
			(layer "F.Fab")
		)
		(fp_line
			(start 0.67945 -0.3048)
			(end 0.67945 0.3048)
			(stroke
				(width 0.1)
				(type default)
			)
			(layer "F.Fab")
		)
		(fp_line
			(start 0.12065 -0.2794)
			(end 0.12065 -0.3048)
			(stroke
				(width 0.1)
				(type default)
			)
			(layer "F.Fab")
		)
		(fp_line
			(start 0.12065 -0.3048)
			(end 0.67945 -0.3048)
			(stroke
				(width 0.1)
				(type default)
			)
			(layer "F.Fab")
		)
		(fp_line
			(start 0.120396 0.3048)
			(end 0.120396 0.2794)
			(stroke
				(width 0.1)
				(type default)
			)
			(layer "F.Fab")
		)
		(fp_line
			(start 0.120396 0.2794)
			(end -0.12065 0.2794)
			(stroke
				(width 0.1)
				(type default)
			)
			(layer "F.Fab")
		)
		(fp_line
			(start -0.12065 0.3048)
			(end -0.67945 0.3048)
			(stroke
				(width 0.1)
				(type default)
			)
			(layer "F.Fab")
		)
		(fp_line
			(start -0.12065 0.2794)
			(end -0.12065 0.3048)
			(stroke
				(width 0.1)
				(type default)
			)
			(layer "F.Fab")
		)
		(fp_line
			(start -0.12065 -0.2794)
			(end 0.12065 -0.2794)
			(stroke
				(width 0.1)
				(type default)
			)
			(layer "F.Fab")
		)
		(fp_line
			(start -0.12065 -0.305054)
			(end -0.12065 -0.2794)
			(stroke
				(width 0.1)
				(type default)
			)
			(layer "F.Fab")
		)
		(fp_line
			(start -0.67945 0.3048)
			(end -0.67945 -0.305054)
			(stroke
				(width 0.1)
				(type default)
			)
			(layer "F.Fab")
		)
		(fp_line
			(start -0.67945 -0.305054)
			(end -0.12065 -0.305054)
			(stroke
				(width 0.1)
				(type default)
			)
			(layer "F.Fab")
		)
		(pad "1" smd circle
			(at -0.40005 0 180)
			(size 0 0)
			(layers "F.Cu" "F.Mask" "F.Paste")
			(net "INA230_3_A0")
		)
		(pad "2" smd circle
			(at 0.40005 0 180)
			(size 0 0)
			(layers "F.Cu" "F.Mask" "F.Paste")
			(net "SMB_INA230_3_3V3AUX_SCL_R1")
		)
	)
	(footprint ""
		(layer "F.Cu")
		(at 185.322464 -426.405294 -90)
		(property "Reference" "R3518"
			(at 0 0 270)
			(layer "F.SilkS")
			(hide yes)
			(effects
				(font
					(size 1.27 1.27)
				)
			)
		)
		(property "Value" ""
			(at 0 0 270)
			(layer "F.Fab")
			(effects
				(font
					(size 1.27 1.27)
				)
			)
		)
		(duplicate_pad_numbers_are_jumpers no)
		(fp_line
			(start -0.7874 0.4064)
			(end -0.7874 -0.4064)
			(stroke
				(width 0.1524)
				(type default)
			)
			(layer "F.SilkS")
		)
		(fp_line
			(start 0.7874 0.4064)
			(end -0.7874 0.4064)
			(stroke
				(width 0.1524)
				(type default)
			)
			(layer "F.SilkS")
		)
		(fp_line
			(start -0.7874 -0.4064)
			(end 0.7874 -0.4064)
			(stroke
				(width 0.1524)
				(type default)
			)
			(layer "F.SilkS")
		)
		(fp_line
			(start 0.7874 -0.4064)
			(end 0.7874 0.4064)
			(stroke
				(width 0.1524)
				(type default)
			)
			(layer "F.SilkS")
		)
		(fp_line
			(start -0.67945 0.3048)
			(end -0.67945 -0.305054)
			(stroke
				(width 0.1)
				(type default)
			)
			(layer "F.Fab")
		)
		(fp_line
			(start -0.12065 0.3048)
			(end -0.67945 0.3048)
			(stroke
				(width 0.1)
				(type default)
			)
			(layer "F.Fab")
		)
		(fp_line
			(start 0.120396 0.3048)
			(end 0.120396 0.2794)
			(stroke
				(width 0.1)
				(type default)
			)
			(layer "F.Fab")
		)
		(fp_line
			(start 0.67945 0.3048)
			(end 0.120396 0.3048)
			(stroke
				(width 0.1)
				(type default)
			)
			(layer "F.Fab")
		)
		(fp_line
			(start -0.12065 0.2794)
			(end -0.12065 0.3048)
			(stroke
				(width 0.1)
				(type default)
			)
			(layer "F.Fab")
		)
		(fp_line
			(start 0.120396 0.2794)
			(end -0.12065 0.2794)
			(stroke
				(width 0.1)
				(type default)
			)
			(layer "F.Fab")
		)
		(fp_line
			(start -0.12065 -0.2794)
			(end 0.12065 -0.2794)
			(stroke
				(width 0.1)
				(type default)
			)
			(layer "F.Fab")
		)
		(fp_line
			(start 0.12065 -0.2794)
			(end 0.12065 -0.3048)
			(stroke
				(width 0.1)
				(type default)
			)
			(layer "F.Fab")
		)
		(fp_line
			(start 0.12065 -0.3048)
			(end 0.67945 -0.3048)
			(stroke
				(width 0.1)
				(type default)
			)
			(layer "F.Fab")
		)
		(fp_line
			(start 0.67945 -0.3048)
			(end 0.67945 0.3048)
			(stroke
				(width 0.1)
				(type default)
			)
			(layer "F.Fab")
		)
		(fp_line
			(start -0.67945 -0.305054)
			(end -0.12065 -0.305054)
			(stroke
				(width 0.1)
				(type default)
			)
			(layer "F.Fab")
		)
		(fp_line
			(start -0.12065 -0.305054)
			(end -0.12065 -0.2794)
			(stroke
				(width 0.1)
				(type default)
			)
			(layer "F.Fab")
		)
		(pad "1" smd circle
			(at -0.40005 0 270)
			(size 0 0)
			(layers "F.Cu" "F.Mask" "F.Paste")
			(net "GPU_PEX_STRAP0")
		)
		(pad "2" smd circle
			(at 0.40005 0 270)
			(size 0 0)
			(layers "F.Cu" "F.Mask" "F.Paste")
			(net "GPU_PEX_STRAP0_R")
		)
	)
	(footprint ""
		(layer "F.Cu")
		(at 102.87 -426.466 90)
		(property "Reference" "R3489"
			(at 0 0 90)
			(layer "F.SilkS")
			(hide yes)
			(effects
				(font
					(size 1.27 1.27)
				)
			)
		)
		(property "Value" ""
			(at 0 0 90)
			(layer "F.Fab")
			(effects
				(font
					(size 1.27 1.27)
				)
			)
		)
		(duplicate_pad_numbers_are_jumpers no)
		(fp_line
			(start 0.7874 -0.4064)
			(end 0.7874 0.4064)
			(stroke
				(width 0.1524)
				(type default)
			)
			(layer "F.SilkS")
		)
		(fp_line
			(start -0.7874 -0.4064)
			(end 0.7874 -0.4064)
			(stroke
				(width 0.1524)
				(type default)
			)
			(layer "F.SilkS")
		)
		(fp_line
			(start 0.7874 0.4064)
			(end -0.7874 0.4064)
			(stroke
				(width 0.1524)
				(type default)
			)
			(layer "F.SilkS")
		)
		(fp_line
			(start -0.7874 0.4064)
			(end -0.7874 -0.4064)
			(stroke
				(width 0.1524)
				(type default)
			)
			(layer "F.SilkS")
		)
		(fp_line
			(start -0.12065 -0.305054)
			(end -0.12065 -0.2794)
			(stroke
				(width 0.1)
				(type default)
			)
			(layer "F.Fab")
		)
		(fp_line
			(start -0.67945 -0.305054)
			(end -0.12065 -0.305054)
			(stroke
				(width 0.1)
				(type default)
			)
			(layer "F.Fab")
		)
		(fp_line
			(start 0.67945 -0.3048)
			(end 0.67945 0.3048)
			(stroke
				(width 0.1)
				(type default)
			)
			(layer "F.Fab")
		)
		(fp_line
			(start 0.12065 -0.3048)
			(end 0.67945 -0.3048)
			(stroke
				(width 0.1)
				(type default)
			)
			(layer "F.Fab")
		)
		(fp_line
			(start 0.12065 -0.2794)
			(end 0.12065 -0.3048)
			(stroke
				(width 0.1)
				(type default)
			)
			(layer "F.Fab")
		)
		(fp_line
			(start -0.12065 -0.2794)
			(end 0.12065 -0.2794)
			(stroke
				(width 0.1)
				(type default)
			)
			(layer "F.Fab")
		)
		(fp_line
			(start 0.120396 0.2794)
			(end -0.12065 0.2794)
			(stroke
				(width 0.1)
				(type default)
			)
			(layer "F.Fab")
		)
		(fp_line
			(start -0.12065 0.2794)
			(end -0.12065 0.3048)
			(stroke
				(width 0.1)
				(type default)
			)
			(layer "F.Fab")
		)
		(fp_line
			(start 0.67945 0.3048)
			(end 0.120396 0.3048)
			(stroke
				(width 0.1)
				(type default)
			)
			(layer "F.Fab")
		)
		(fp_line
			(start 0.120396 0.3048)
			(end 0.120396 0.2794)
			(stroke
				(width 0.1)
				(type default)
			)
			(layer "F.Fab")
		)
		(fp_line
			(start -0.12065 0.3048)
			(end -0.67945 0.3048)
			(stroke
				(width 0.1)
				(type default)
			)
			(layer "F.Fab")
		)
		(fp_line
			(start -0.67945 0.3048)
			(end -0.67945 -0.305054)
			(stroke
				(width 0.1)
				(type default)
			)
			(layer "F.Fab")
		)
		(pad "1" smd circle
			(at -0.40005 0 90)
			(size 0 0)
			(layers "F.Cu" "F.Mask" "F.Paste")
			(net "GPU_FPGA_EROT_RST_N")
		)
		(pad "2" smd circle
			(at 0.40005 0 90)
			(size 0 0)
			(layers "F.Cu" "F.Mask" "F.Paste")
			(net "GND")
		)
	)
	(footprint ""
		(layer "F.Cu")
		(at 366.06734 -390.77646 180)
		(property "Reference" "C901"
			(at 0 0 180)
			(layer "F.SilkS")
			(hide yes)
			(effects
				(font
					(size 1.27 1.27)
				)
			)
		)
		(property "Value" ""
			(at 0 0 180)
			(layer "F.Fab")
			(effects
				(font
					(size 1.27 1.27)
				)
			)
		)
		(duplicate_pad_numbers_are_jumpers no)
		(fp_line
			(start 0.299974 0.150114)
			(end -0.299974 0.150114)
			(stroke
				(width 0.1)
				(type default)
			)
			(layer "F.Fab")
		)
		(fp_line
			(start 0.299974 -0.150114)
			(end 0.299974 0.150114)
			(stroke
				(width 0.1)
				(type default)
			)
			(layer "F.Fab")
		)
		(fp_line
			(start -0.299974 0.150114)
			(end -0.299974 -0.150114)
			(stroke
				(width 0.1)
				(type default)
			)
			(layer "F.Fab")
		)
		(fp_line
			(start -0.299974 -0.150114)
			(end 0.299974 -0.150114)
			(stroke
				(width 0.1)
				(type default)
			)
			(layer "F.Fab")
		)
		(pad "1" smd rect
			(at -0.2667 0 180)
			(size 0.3048 0.381)
			(layers "F.Cu" "F.Mask" "F.Paste")
			(net "P5E_CPU0_P3_TX_C_DP<0>")
		)
		(pad "2" smd rect
			(at 0.2667 0 180)
			(size 0.3048 0.381)
			(layers "F.Cu" "F.Mask" "F.Paste")
			(net "P5E_CPU0_P3_TX_DP<0>")
		)
	)
	(footprint ""
		(layer "F.Cu")
		(at 52.23891 -351.932748)
		(property "Reference" "PR275"
			(at 0 0 0)
			(layer "F.SilkS")
			(hide yes)
			(effects
				(font
					(size 1.27 1.27)
				)
			)
		)
		(property "Value" ""
			(at 0 0 0)
			(layer "F.Fab")
			(effects
				(font
					(size 1.27 1.27)
				)
			)
		)
		(duplicate_pad_numbers_are_jumpers no)
		(fp_line
			(start -0.7874 -0.4064)
			(end 0.7874 -0.4064)
			(stroke
				(width 0.1524)
				(type default)
			)
			(layer "F.SilkS")
		)
		(fp_line
			(start -0.7874 0.4064)
			(end -0.7874 -0.4064)
			(stroke
				(width 0.1524)
				(type default)
			)
			(layer "F.SilkS")
		)
		(fp_line
			(start 0.7874 -0.4064)
			(end 0.7874 0.4064)
			(stroke
				(width 0.1524)
				(type default)
			)
			(layer "F.SilkS")
		)
		(fp_line
			(start 0.7874 0.4064)
			(end -0.7874 0.4064)
			(stroke
				(width 0.1524)
				(type default)
			)
			(layer "F.SilkS")
		)
		(fp_line
			(start -0.67945 -0.305054)
			(end -0.12065 -0.305054)
			(stroke
				(width 0.1)
				(type default)
			)
			(layer "F.Fab")
		)
		(fp_line
			(start -0.67945 0.3048)
			(end -0.67945 -0.305054)
			(stroke
				(width 0.1)
				(type default)
			)
			(layer "F.Fab")
		)
		(fp_line
			(start -0.12065 -0.305054)
			(end -0.12065 -0.2794)
			(stroke
				(width 0.1)
				(type default)
			)
			(layer "F.Fab")
		)
		(fp_line
			(start -0.12065 -0.2794)
			(end 0.12065 -0.2794)
			(stroke
				(width 0.1)
				(type default)
			)
			(layer "F.Fab")
		)
		(fp_line
			(start -0.12065 0.2794)
			(end -0.12065 0.3048)
			(stroke
				(width 0.1)
				(type default)
			)
			(layer "F.Fab")
		)
		(fp_line
			(start -0.12065 0.3048)
			(end -0.67945 0.3048)
			(stroke
				(width 0.1)
				(type default)
			)
			(layer "F.Fab")
		)
		(fp_line
			(start 0.120396 0.2794)
			(end -0.12065 0.2794)
			(stroke
				(width 0.1)
				(type default)
			)
			(layer "F.Fab")
		)
		(fp_line
			(start 0.120396 0.3048)
			(end 0.120396 0.2794)
			(stroke
				(width 0.1)
				(type default)
			)
			(layer "F.Fab")
		)
		(fp_line
			(start 0.12065 -0.3048)
			(end 0.67945 -0.3048)
			(stroke
				(width 0.1)
				(type default)
			)
			(layer "F.Fab")
		)
		(fp_line
			(start 0.12065 -0.2794)
			(end 0.12065 -0.3048)
			(stroke
				(width 0.1)
				(type default)
			)
			(layer "F.Fab")
		)
		(fp_line
			(start 0.67945 -0.3048)
			(end 0.67945 0.3048)
			(stroke
				(width 0.1)
				(type default)
			)
			(layer "F.Fab")
		)
		(fp_line
			(start 0.67945 0.3048)
			(end 0.120396 0.3048)
			(stroke
				(width 0.1)
				(type default)
			)
			(layer "F.Fab")
		)
		(pad "1" smd circle
			(at -0.40005 0)
			(size 0 0)
			(layers "F.Cu" "F.Mask" "F.Paste")
			(net "PVDDIO_P1_LSET1")
		)
		(pad "2" smd circle
			(at 0.40005 0)
			(size 0 0)
			(layers "F.Cu" "F.Mask" "F.Paste")
			(net "GND")
		)
	)
	(footprint ""
		(layer "F.Cu")
		(at 426.469556 -397.135604 180)
		(property "Reference" "R1046"
			(at 0 0 180)
			(layer "F.SilkS")
			(hide yes)
			(effects
				(font
					(size 1.27 1.27)
				)
			)
		)
		(property "Value" ""
			(at 0 0 180)
			(layer "F.Fab")
			(effects
				(font
					(size 1.27 1.27)
				)
			)
		)
		(duplicate_pad_numbers_are_jumpers no)
		(fp_line
			(start 0.7874 0.4064)
			(end -0.7874 0.4064)
			(stroke
				(width 0.1524)
				(type default)
			)
			(layer "F.SilkS")
		)
		(fp_line
			(start 0.7874 -0.4064)
			(end 0.7874 0.4064)
			(stroke
				(width 0.1524)
				(type default)
			)
			(layer "F.SilkS")
		)
		(fp_line
			(start -0.7874 0.4064)
			(end -0.7874 -0.4064)
			(stroke
				(width 0.1524)
				(type default)
			)
			(layer "F.SilkS")
		)
		(fp_line
			(start -0.7874 -0.4064)
			(end 0.7874 -0.4064)
			(stroke
				(width 0.1524)
				(type default)
			)
			(layer "F.SilkS")
		)
		(fp_line
			(start 0.67945 0.3048)
			(end 0.120396 0.3048)
			(stroke
				(width 0.1)
				(type default)
			)
			(layer "F.Fab")
		)
		(fp_line
			(start 0.67945 -0.3048)
			(end 0.67945 0.3048)
			(stroke
				(width 0.1)
				(type default)
			)
			(layer "F.Fab")
		)
		(fp_line
			(start 0.12065 -0.2794)
			(end 0.12065 -0.3048)
			(stroke
				(width 0.1)
				(type default)
			)
			(layer "F.Fab")
		)
		(fp_line
			(start 0.12065 -0.3048)
			(end 0.67945 -0.3048)
			(stroke
				(width 0.1)
				(type default)
			)
			(layer "F.Fab")
		)
		(fp_line
			(start 0.120396 0.3048)
			(end 0.120396 0.2794)
			(stroke
				(width 0.1)
				(type default)
			)
			(layer "F.Fab")
		)
		(fp_line
			(start 0.120396 0.2794)
			(end -0.12065 0.2794)
			(stroke
				(width 0.1)
				(type default)
			)
			(layer "F.Fab")
		)
		(fp_line
			(start -0.12065 0.3048)
			(end -0.67945 0.3048)
			(stroke
				(width 0.1)
				(type default)
			)
			(layer "F.Fab")
		)
		(fp_line
			(start -0.12065 0.2794)
			(end -0.12065 0.3048)
			(stroke
				(width 0.1)
				(type default)
			)
			(layer "F.Fab")
		)
		(fp_line
			(start -0.12065 -0.2794)
			(end 0.12065 -0.2794)
			(stroke
				(width 0.1)
				(type default)
			)
			(layer "F.Fab")
		)
		(fp_line
			(start -0.12065 -0.305054)
			(end -0.12065 -0.2794)
			(stroke
				(width 0.1)
				(type default)
			)
			(layer "F.Fab")
		)
		(fp_line
			(start -0.67945 0.3048)
			(end -0.67945 -0.305054)
			(stroke
				(width 0.1)
				(type default)
			)
			(layer "F.Fab")
		)
		(fp_line
			(start -0.67945 -0.305054)
			(end -0.12065 -0.305054)
			(stroke
				(width 0.1)
				(type default)
			)
			(layer "F.Fab")
		)
		(pad "1" smd rect
			(at -0.40005 0)
			(size 0.4572 0.508)
			(layers "F.Cu" "F.Mask" "F.Paste")
			(net "P1V8_CPU0_RT2_1A_1D")
		)
		(pad "2" smd rect
			(at 0.40005 0)
			(size 0.4572 0.508)
			(layers "F.Cu" "F.Mask" "F.Paste")
			(net "P1V8_CPU0_RT2_1A")
		)
	)
	(footprint ""
		(layer "F.Cu")
		(at 353.1108 -407.8732 90)
		(property "Reference" "R1472"
			(at 0 0 90)
			(layer "F.SilkS")
			(hide yes)
			(effects
				(font
					(size 1.27 1.27)
				)
			)
		)
		(property "Value" ""
			(at 0 0 90)
			(layer "F.Fab")
			(effects
				(font
					(size 1.27 1.27)
				)
			)
		)
		(duplicate_pad_numbers_are_jumpers no)
		(fp_line
			(start 0.32512 -0.175006)
			(end 0.32512 0.175006)
			(stroke
				(width 0.1)
				(type default)
			)
			(layer "F.Fab")
		)
		(fp_line
			(start -0.32512 -0.175006)
			(end 0.32512 -0.175006)
			(stroke
				(width 0.1)
				(type default)
			)
			(layer "F.Fab")
		)
		(fp_line
			(start 0.32512 0.175006)
			(end -0.32512 0.175006)
			(stroke
				(width 0.1)
				(type default)
			)
			(layer "F.Fab")
		)
		(fp_line
			(start -0.32512 0.175006)
			(end -0.32512 -0.175006)
			(stroke
				(width 0.1)
				(type default)
			)
			(layer "F.Fab")
		)
		(pad "1" smd rect
			(at -0.2667 0 90)
			(size 0.3048 0.381)
			(layers "F.Cu" "F.Mask" "F.Paste")
			(net "P1V8_CPU0_RT_1D")
		)
		(pad "2" smd rect
			(at 0.2667 0 270)
			(size 0.3048 0.381)
			(layers "F.Cu" "F.Mask" "F.Paste")
			(net "JTAG_TDO_RT_CPU0_P1")
		)
	)
	(footprint ""
		(layer "F.Cu")
		(at 138.426952 -59.83224 180)
		(property "Reference" "R1728"
			(at 0 0 180)
			(layer "F.SilkS")
			(hide yes)
			(effects
				(font
					(size 1.27 1.27)
				)
			)
		)
		(property "Value" ""
			(at 0 0 180)
			(layer "F.Fab")
			(effects
				(font
					(size 1.27 1.27)
				)
			)
		)
		(duplicate_pad_numbers_are_jumpers no)
		(fp_line
			(start 0.7874 0.4064)
			(end -0.7874 0.4064)
			(stroke
				(width 0.1524)
				(type default)
			)
			(layer "F.SilkS")
		)
		(fp_line
			(start 0.7874 -0.4064)
			(end 0.7874 0.4064)
			(stroke
				(width 0.1524)
				(type default)
			)
			(layer "F.SilkS")
		)
		(fp_line
			(start -0.7874 0.4064)
			(end -0.7874 -0.4064)
			(stroke
				(width 0.1524)
				(type default)
			)
			(layer "F.SilkS")
		)
		(fp_line
			(start -0.7874 -0.4064)
			(end 0.7874 -0.4064)
			(stroke
				(width 0.1524)
				(type default)
			)
			(layer "F.SilkS")
		)
		(fp_line
			(start 0.67945 0.3048)
			(end 0.120396 0.3048)
			(stroke
				(width 0.1)
				(type default)
			)
			(layer "F.Fab")
		)
		(fp_line
			(start 0.67945 -0.3048)
			(end 0.67945 0.3048)
			(stroke
				(width 0.1)
				(type default)
			)
			(layer "F.Fab")
		)
		(fp_line
			(start 0.12065 -0.2794)
			(end 0.12065 -0.3048)
			(stroke
				(width 0.1)
				(type default)
			)
			(layer "F.Fab")
		)
		(fp_line
			(start 0.12065 -0.3048)
			(end 0.67945 -0.3048)
			(stroke
				(width 0.1)
				(type default)
			)
			(layer "F.Fab")
		)
		(fp_line
			(start 0.120396 0.3048)
			(end 0.120396 0.2794)
			(stroke
				(width 0.1)
				(type default)
			)
			(layer "F.Fab")
		)
		(fp_line
			(start 0.120396 0.2794)
			(end -0.12065 0.2794)
			(stroke
				(width 0.1)
				(type default)
			)
			(layer "F.Fab")
		)
		(fp_line
			(start -0.12065 0.3048)
			(end -0.67945 0.3048)
			(stroke
				(width 0.1)
				(type default)
			)
			(layer "F.Fab")
		)
		(fp_line
			(start -0.12065 0.2794)
			(end -0.12065 0.3048)
			(stroke
				(width 0.1)
				(type default)
			)
			(layer "F.Fab")
		)
		(fp_line
			(start -0.12065 -0.2794)
			(end 0.12065 -0.2794)
			(stroke
				(width 0.1)
				(type default)
			)
			(layer "F.Fab")
		)
		(fp_line
			(start -0.12065 -0.305054)
			(end -0.12065 -0.2794)
			(stroke
				(width 0.1)
				(type default)
			)
			(layer "F.Fab")
		)
		(fp_line
			(start -0.67945 0.3048)
			(end -0.67945 -0.305054)
			(stroke
				(width 0.1)
				(type default)
			)
			(layer "F.Fab")
		)
		(fp_line
			(start -0.67945 -0.305054)
			(end -0.12065 -0.305054)
			(stroke
				(width 0.1)
				(type default)
			)
			(layer "F.Fab")
		)
		(pad "1" smd circle
			(at -0.40005 0 180)
			(size 0 0)
			(layers "F.Cu" "F.Mask" "F.Paste")
			(net "P3V3_AUX")
		)
		(pad "2" smd circle
			(at 0.40005 0 180)
			(size 0 0)
			(layers "F.Cu" "F.Mask" "F.Paste")
			(net "JTAG_SCM_TDI")
		)
	)
	(footprint ""
		(layer "F.Cu")
		(at 453.169782 -39.95674 90)
		(property "Reference" "R1486"
			(at 0 0 90)
			(layer "F.SilkS")
			(hide yes)
			(effects
				(font
					(size 1.27 1.27)
				)
			)
		)
		(property "Value" ""
			(at 0 0 90)
			(layer "F.Fab")
			(effects
				(font
					(size 1.27 1.27)
				)
			)
		)
		(duplicate_pad_numbers_are_jumpers no)
		(fp_line
			(start 0.7874 -0.4064)
			(end 0.7874 0.4064)
			(stroke
				(width 0.1524)
				(type default)
			)
			(layer "F.SilkS")
		)
		(fp_line
			(start -0.7874 -0.4064)
			(end 0.7874 -0.4064)
			(stroke
				(width 0.1524)
				(type default)
			)
			(layer "F.SilkS")
		)
		(fp_line
			(start 0.7874 0.4064)
			(end -0.7874 0.4064)
			(stroke
				(width 0.1524)
				(type default)
			)
			(layer "F.SilkS")
		)
		(fp_line
			(start -0.7874 0.4064)
			(end -0.7874 -0.4064)
			(stroke
				(width 0.1524)
				(type default)
			)
			(layer "F.SilkS")
		)
		(fp_line
			(start -0.12065 -0.305054)
			(end -0.12065 -0.2794)
			(stroke
				(width 0.1)
				(type default)
			)
			(layer "F.Fab")
		)
		(fp_line
			(start -0.67945 -0.305054)
			(end -0.12065 -0.305054)
			(stroke
				(width 0.1)
				(type default)
			)
			(layer "F.Fab")
		)
		(fp_line
			(start 0.67945 -0.3048)
			(end 0.67945 0.3048)
			(stroke
				(width 0.1)
				(type default)
			)
			(layer "F.Fab")
		)
		(fp_line
			(start 0.12065 -0.3048)
			(end 0.67945 -0.3048)
			(stroke
				(width 0.1)
				(type default)
			)
			(layer "F.Fab")
		)
		(fp_line
			(start 0.12065 -0.2794)
			(end 0.12065 -0.3048)
			(stroke
				(width 0.1)
				(type default)
			)
			(layer "F.Fab")
		)
		(fp_line
			(start -0.12065 -0.2794)
			(end 0.12065 -0.2794)
			(stroke
				(width 0.1)
				(type default)
			)
			(layer "F.Fab")
		)
		(fp_line
			(start 0.120396 0.2794)
			(end -0.12065 0.2794)
			(stroke
				(width 0.1)
				(type default)
			)
			(layer "F.Fab")
		)
		(fp_line
			(start -0.12065 0.2794)
			(end -0.12065 0.3048)
			(stroke
				(width 0.1)
				(type default)
			)
			(layer "F.Fab")
		)
		(fp_line
			(start 0.67945 0.3048)
			(end 0.120396 0.3048)
			(stroke
				(width 0.1)
				(type default)
			)
			(layer "F.Fab")
		)
		(fp_line
			(start 0.120396 0.3048)
			(end 0.120396 0.2794)
			(stroke
				(width 0.1)
				(type default)
			)
			(layer "F.Fab")
		)
		(fp_line
			(start -0.12065 0.3048)
			(end -0.67945 0.3048)
			(stroke
				(width 0.1)
				(type default)
			)
			(layer "F.Fab")
		)
		(fp_line
			(start -0.67945 0.3048)
			(end -0.67945 -0.305054)
			(stroke
				(width 0.1)
				(type default)
			)
			(layer "F.Fab")
		)
		(pad "1" smd circle
			(at -0.40005 0 90)
			(size 0 0)
			(layers "F.Cu" "F.Mask" "F.Paste")
			(net "P12V_OCP_SFF_BUF_EN_R")
		)
		(pad "2" smd circle
			(at 0.40005 0 90)
			(size 0 0)
			(layers "F.Cu" "F.Mask" "F.Paste")
			(net "P3V3_OCP_EN_1_R")
		)
	)
	(footprint ""
		(layer "F.Cu")
		(at 60.527438 -31.887922 -90)
		(property "Reference" "R3867"
			(at 0 0 270)
			(layer "F.SilkS")
			(hide yes)
			(effects
				(font
					(size 1.27 1.27)
				)
			)
		)
		(property "Value" ""
			(at 0 0 270)
			(layer "F.Fab")
			(effects
				(font
					(size 1.27 1.27)
				)
			)
		)
		(duplicate_pad_numbers_are_jumpers no)
		(fp_line
			(start -0.7874 0.4064)
			(end -0.7874 -0.4064)
			(stroke
				(width 0.1524)
				(type default)
			)
			(layer "F.SilkS")
		)
		(fp_line
			(start 0.7874 0.4064)
			(end -0.7874 0.4064)
			(stroke
				(width 0.1524)
				(type default)
			)
			(layer "F.SilkS")
		)
		(fp_line
			(start -0.7874 -0.4064)
			(end 0.7874 -0.4064)
			(stroke
				(width 0.1524)
				(type default)
			)
			(layer "F.SilkS")
		)
		(fp_line
			(start 0.7874 -0.4064)
			(end 0.7874 0.4064)
			(stroke
				(width 0.1524)
				(type default)
			)
			(layer "F.SilkS")
		)
		(fp_line
			(start -0.67945 0.3048)
			(end -0.67945 -0.305054)
			(stroke
				(width 0.1)
				(type default)
			)
			(layer "F.Fab")
		)
		(fp_line
			(start -0.12065 0.3048)
			(end -0.67945 0.3048)
			(stroke
				(width 0.1)
				(type default)
			)
			(layer "F.Fab")
		)
		(fp_line
			(start 0.120396 0.3048)
			(end 0.120396 0.2794)
			(stroke
				(width 0.1)
				(type default)
			)
			(layer "F.Fab")
		)
		(fp_line
			(start 0.67945 0.3048)
			(end 0.120396 0.3048)
			(stroke
				(width 0.1)
				(type default)
			)
			(layer "F.Fab")
		)
		(fp_line
			(start -0.12065 0.2794)
			(end -0.12065 0.3048)
			(stroke
				(width 0.1)
				(type default)
			)
			(layer "F.Fab")
		)
		(fp_line
			(start 0.120396 0.2794)
			(end -0.12065 0.2794)
			(stroke
				(width 0.1)
				(type default)
			)
			(layer "F.Fab")
		)
		(fp_line
			(start -0.12065 -0.2794)
			(end 0.12065 -0.2794)
			(stroke
				(width 0.1)
				(type default)
			)
			(layer "F.Fab")
		)
		(fp_line
			(start 0.12065 -0.2794)
			(end 0.12065 -0.3048)
			(stroke
				(width 0.1)
				(type default)
			)
			(layer "F.Fab")
		)
		(fp_line
			(start 0.12065 -0.3048)
			(end 0.67945 -0.3048)
			(stroke
				(width 0.1)
				(type default)
			)
			(layer "F.Fab")
		)
		(fp_line
			(start 0.67945 -0.3048)
			(end 0.67945 0.3048)
			(stroke
				(width 0.1)
				(type default)
			)
			(layer "F.Fab")
		)
		(fp_line
			(start -0.67945 -0.305054)
			(end -0.12065 -0.305054)
			(stroke
				(width 0.1)
				(type default)
			)
			(layer "F.Fab")
		)
		(fp_line
			(start -0.12065 -0.305054)
			(end -0.12065 -0.2794)
			(stroke
				(width 0.1)
				(type default)
			)
			(layer "F.Fab")
		)
		(pad "1" smd rect
			(at -0.40005 0 90)
			(size 0.4572 0.508)
			(layers "F.Cu" "F.Mask" "F.Paste")
			(net "P12V_OCP_SENSE_2")
		)
		(pad "2" smd rect
			(at 0.40005 0 90)
			(size 0.4572 0.508)
			(layers "F.Cu" "F.Mask" "F.Paste")
			(net "P12V_OCP_V3_2_ISENSE_MAM_MAM")
		)
	)
	(footprint ""
		(layer "F.Cu")
		(at 59.33313 -39.007034 90)
		(property "Reference" "R4060"
			(at 0 0 90)
			(layer "F.SilkS")
			(hide yes)
			(effects
				(font
					(size 1.27 1.27)
				)
			)
		)
		(property "Value" ""
			(at 0 0 90)
			(layer "F.Fab")
			(effects
				(font
					(size 1.27 1.27)
				)
			)
		)
		(duplicate_pad_numbers_are_jumpers no)
		(fp_line
			(start 0.7874 -0.4064)
			(end 0.7874 0.4064)
			(stroke
				(width 0.1524)
				(type default)
			)
			(layer "F.SilkS")
		)
		(fp_line
			(start -0.7874 -0.4064)
			(end 0.7874 -0.4064)
			(stroke
				(width 0.1524)
				(type default)
			)
			(layer "F.SilkS")
		)
		(fp_line
			(start 0.7874 0.4064)
			(end -0.7874 0.4064)
			(stroke
				(width 0.1524)
				(type default)
			)
			(layer "F.SilkS")
		)
		(fp_line
			(start -0.7874 0.4064)
			(end -0.7874 -0.4064)
			(stroke
				(width 0.1524)
				(type default)
			)
			(layer "F.SilkS")
		)
		(fp_line
			(start -0.12065 -0.305054)
			(end -0.12065 -0.2794)
			(stroke
				(width 0.1)
				(type default)
			)
			(layer "F.Fab")
		)
		(fp_line
			(start -0.67945 -0.305054)
			(end -0.12065 -0.305054)
			(stroke
				(width 0.1)
				(type default)
			)
			(layer "F.Fab")
		)
		(fp_line
			(start 0.67945 -0.3048)
			(end 0.67945 0.3048)
			(stroke
				(width 0.1)
				(type default)
			)
			(layer "F.Fab")
		)
		(fp_line
			(start 0.12065 -0.3048)
			(end 0.67945 -0.3048)
			(stroke
				(width 0.1)
				(type default)
			)
			(layer "F.Fab")
		)
		(fp_line
			(start 0.12065 -0.2794)
			(end 0.12065 -0.3048)
			(stroke
				(width 0.1)
				(type default)
			)
			(layer "F.Fab")
		)
		(fp_line
			(start -0.12065 -0.2794)
			(end 0.12065 -0.2794)
			(stroke
				(width 0.1)
				(type default)
			)
			(layer "F.Fab")
		)
		(fp_line
			(start 0.120396 0.2794)
			(end -0.12065 0.2794)
			(stroke
				(width 0.1)
				(type default)
			)
			(layer "F.Fab")
		)
		(fp_line
			(start -0.12065 0.2794)
			(end -0.12065 0.3048)
			(stroke
				(width 0.1)
				(type default)
			)
			(layer "F.Fab")
		)
		(fp_line
			(start 0.67945 0.3048)
			(end 0.120396 0.3048)
			(stroke
				(width 0.1)
				(type default)
			)
			(layer "F.Fab")
		)
		(fp_line
			(start 0.120396 0.3048)
			(end 0.120396 0.2794)
			(stroke
				(width 0.1)
				(type default)
			)
			(layer "F.Fab")
		)
		(fp_line
			(start -0.12065 0.3048)
			(end -0.67945 0.3048)
			(stroke
				(width 0.1)
				(type default)
			)
			(layer "F.Fab")
		)
		(fp_line
			(start -0.67945 0.3048)
			(end -0.67945 -0.305054)
			(stroke
				(width 0.1)
				(type default)
			)
			(layer "F.Fab")
		)
		(pad "1" smd circle
			(at -0.40005 0 90)
			(size 0 0)
			(layers "F.Cu" "F.Mask" "F.Paste")
			(net "P3V3_OCP_V3_2_EN_R")
		)
		(pad "2" smd circle
			(at 0.40005 0 90)
			(size 0 0)
			(layers "F.Cu" "F.Mask" "F.Paste")
			(net "P3V3_OCP_EN_2_R")
		)
	)
	(footprint ""
		(layer "F.Cu")
		(at 302.256698 -118.179088 180)
		(property "Reference" "R718"
			(at 0 0 180)
			(layer "F.SilkS")
			(hide yes)
			(effects
				(font
					(size 1.27 1.27)
				)
			)
		)
		(property "Value" ""
			(at 0 0 180)
			(layer "F.Fab")
			(effects
				(font
					(size 1.27 1.27)
				)
			)
		)
		(duplicate_pad_numbers_are_jumpers no)
		(fp_line
			(start 0.7874 0.4064)
			(end -0.7874 0.4064)
			(stroke
				(width 0.1524)
				(type default)
			)
			(layer "F.SilkS")
		)
		(fp_line
			(start 0.7874 -0.4064)
			(end 0.7874 0.4064)
			(stroke
				(width 0.1524)
				(type default)
			)
			(layer "F.SilkS")
		)
		(fp_line
			(start -0.7874 0.4064)
			(end -0.7874 -0.4064)
			(stroke
				(width 0.1524)
				(type default)
			)
			(layer "F.SilkS")
		)
		(fp_line
			(start -0.7874 -0.4064)
			(end 0.7874 -0.4064)
			(stroke
				(width 0.1524)
				(type default)
			)
			(layer "F.SilkS")
		)
		(fp_line
			(start 0.67945 0.3048)
			(end 0.120396 0.3048)
			(stroke
				(width 0.1)
				(type default)
			)
			(layer "F.Fab")
		)
		(fp_line
			(start 0.67945 -0.3048)
			(end 0.67945 0.3048)
			(stroke
				(width 0.1)
				(type default)
			)
			(layer "F.Fab")
		)
		(fp_line
			(start 0.12065 -0.2794)
			(end 0.12065 -0.3048)
			(stroke
				(width 0.1)
				(type default)
			)
			(layer "F.Fab")
		)
		(fp_line
			(start 0.12065 -0.3048)
			(end 0.67945 -0.3048)
			(stroke
				(width 0.1)
				(type default)
			)
			(layer "F.Fab")
		)
		(fp_line
			(start 0.120396 0.3048)
			(end 0.120396 0.2794)
			(stroke
				(width 0.1)
				(type default)
			)
			(layer "F.Fab")
		)
		(fp_line
			(start 0.120396 0.2794)
			(end -0.12065 0.2794)
			(stroke
				(width 0.1)
				(type default)
			)
			(layer "F.Fab")
		)
		(fp_line
			(start -0.12065 0.3048)
			(end -0.67945 0.3048)
			(stroke
				(width 0.1)
				(type default)
			)
			(layer "F.Fab")
		)
		(fp_line
			(start -0.12065 0.2794)
			(end -0.12065 0.3048)
			(stroke
				(width 0.1)
				(type default)
			)
			(layer "F.Fab")
		)
		(fp_line
			(start -0.12065 -0.2794)
			(end 0.12065 -0.2794)
			(stroke
				(width 0.1)
				(type default)
			)
			(layer "F.Fab")
		)
		(fp_line
			(start -0.12065 -0.305054)
			(end -0.12065 -0.2794)
			(stroke
				(width 0.1)
				(type default)
			)
			(layer "F.Fab")
		)
		(fp_line
			(start -0.67945 0.3048)
			(end -0.67945 -0.305054)
			(stroke
				(width 0.1)
				(type default)
			)
			(layer "F.Fab")
		)
		(fp_line
			(start -0.67945 -0.305054)
			(end -0.12065 -0.305054)
			(stroke
				(width 0.1)
				(type default)
			)
			(layer "F.Fab")
		)
		(pad "1" smd circle
			(at -0.40005 0 180)
			(size 0 0)
			(layers "F.Cu" "F.Mask" "F.Paste")
			(net "MB_FRU_ADDR1")
		)
		(pad "2" smd circle
			(at 0.40005 0 180)
			(size 0 0)
			(layers "F.Cu" "F.Mask" "F.Paste")
			(net "GND")
		)
	)
	(footprint ""
		(layer "F.Cu")
		(at 323.637148 -44.716954 180)
		(property "Reference" "R3862"
			(at 0 0 180)
			(layer "F.SilkS")
			(hide yes)
			(effects
				(font
					(size 1.27 1.27)
				)
			)
		)
		(property "Value" ""
			(at 0 0 180)
			(layer "F.Fab")
			(effects
				(font
					(size 1.27 1.27)
				)
			)
		)
		(duplicate_pad_numbers_are_jumpers no)
		(fp_line
			(start 0.7874 0.4064)
			(end -0.7874 0.4064)
			(stroke
				(width 0.1524)
				(type default)
			)
			(layer "F.SilkS")
		)
		(fp_line
			(start 0.7874 -0.4064)
			(end 0.7874 0.4064)
			(stroke
				(width 0.1524)
				(type default)
			)
			(layer "F.SilkS")
		)
		(fp_line
			(start -0.7874 0.4064)
			(end -0.7874 -0.4064)
			(stroke
				(width 0.1524)
				(type default)
			)
			(layer "F.SilkS")
		)
		(fp_line
			(start -0.7874 -0.4064)
			(end 0.7874 -0.4064)
			(stroke
				(width 0.1524)
				(type default)
			)
			(layer "F.SilkS")
		)
		(fp_line
			(start 0.67945 0.3048)
			(end 0.120396 0.3048)
			(stroke
				(width 0.1)
				(type default)
			)
			(layer "F.Fab")
		)
		(fp_line
			(start 0.67945 -0.3048)
			(end 0.67945 0.3048)
			(stroke
				(width 0.1)
				(type default)
			)
			(layer "F.Fab")
		)
		(fp_line
			(start 0.12065 -0.2794)
			(end 0.12065 -0.3048)
			(stroke
				(width 0.1)
				(type default)
			)
			(layer "F.Fab")
		)
		(fp_line
			(start 0.12065 -0.3048)
			(end 0.67945 -0.3048)
			(stroke
				(width 0.1)
				(type default)
			)
			(layer "F.Fab")
		)
		(fp_line
			(start 0.120396 0.3048)
			(end 0.120396 0.2794)
			(stroke
				(width 0.1)
				(type default)
			)
			(layer "F.Fab")
		)
		(fp_line
			(start 0.120396 0.2794)
			(end -0.12065 0.2794)
			(stroke
				(width 0.1)
				(type default)
			)
			(layer "F.Fab")
		)
		(fp_line
			(start -0.12065 0.3048)
			(end -0.67945 0.3048)
			(stroke
				(width 0.1)
				(type default)
			)
			(layer "F.Fab")
		)
		(fp_line
			(start -0.12065 0.2794)
			(end -0.12065 0.3048)
			(stroke
				(width 0.1)
				(type default)
			)
			(layer "F.Fab")
		)
		(fp_line
			(start -0.12065 -0.2794)
			(end 0.12065 -0.2794)
			(stroke
				(width 0.1)
				(type default)
			)
			(layer "F.Fab")
		)
		(fp_line
			(start -0.12065 -0.305054)
			(end -0.12065 -0.2794)
			(stroke
				(width 0.1)
				(type default)
			)
			(layer "F.Fab")
		)
		(fp_line
			(start -0.67945 0.3048)
			(end -0.67945 -0.305054)
			(stroke
				(width 0.1)
				(type default)
			)
			(layer "F.Fab")
		)
		(fp_line
			(start -0.67945 -0.305054)
			(end -0.12065 -0.305054)
			(stroke
				(width 0.1)
				(type default)
			)
			(layer "F.Fab")
		)
		(pad "1" smd rect
			(at -0.40005 0)
			(size 0.4572 0.508)
			(layers "F.Cu" "F.Mask" "F.Paste")
			(net "P12V_OCP_V3_2_ISENSE_MPS_TIC")
		)
		(pad "2" smd rect
			(at 0.40005 0)
			(size 0.4572 0.508)
			(layers "F.Cu" "F.Mask" "F.Paste")
			(net "P12V_OCP_V3_2_ISENSE_TIC")
		)
	)
	(footprint ""
		(layer "F.Cu")
		(at 322.027296 -378.95403 -90)
		(property "Reference" "C908"
			(at 0 0 270)
			(layer "F.SilkS")
			(hide yes)
			(effects
				(font
					(size 1.27 1.27)
				)
			)
		)
		(property "Value" ""
			(at 0 0 270)
			(layer "F.Fab")
			(effects
				(font
					(size 1.27 1.27)
				)
			)
		)
		(duplicate_pad_numbers_are_jumpers no)
		(fp_line
			(start -0.299974 0.150114)
			(end -0.299974 -0.150114)
			(stroke
				(width 0.1)
				(type default)
			)
			(layer "F.Fab")
		)
		(fp_line
			(start 0.299974 0.150114)
			(end -0.299974 0.150114)
			(stroke
				(width 0.1)
				(type default)
			)
			(layer "F.Fab")
		)
		(fp_line
			(start -0.299974 -0.150114)
			(end 0.299974 -0.150114)
			(stroke
				(width 0.1)
				(type default)
			)
			(layer "F.Fab")
		)
		(fp_line
			(start 0.299974 -0.150114)
			(end 0.299974 0.150114)
			(stroke
				(width 0.1)
				(type default)
			)
			(layer "F.Fab")
		)
		(pad "1" smd rect
			(at -0.2667 0 270)
			(size 0.3048 0.381)
			(layers "F.Cu" "F.Mask" "F.Paste")
			(net "P5E_CPU0_P0_TX_C_DN<12>")
		)
		(pad "2" smd rect
			(at 0.2667 0 270)
			(size 0.3048 0.381)
			(layers "F.Cu" "F.Mask" "F.Paste")
			(net "P5E_CPU0_P0_TX_DN<12>")
		)
	)
	(footprint ""
		(layer "F.Cu")
		(at 70.052438 -31.887922 -90)
		(property "Reference" "R3630"
			(at 0 0 270)
			(layer "F.SilkS")
			(hide yes)
			(effects
				(font
					(size 1.27 1.27)
				)
			)
		)
		(property "Value" ""
			(at 0 0 270)
			(layer "F.Fab")
			(effects
				(font
					(size 1.27 1.27)
				)
			)
		)
		(duplicate_pad_numbers_are_jumpers no)
		(fp_line
			(start -0.7874 0.4064)
			(end -0.7874 -0.4064)
			(stroke
				(width 0.1524)
				(type default)
			)
			(layer "F.SilkS")
		)
		(fp_line
			(start 0.7874 0.4064)
			(end -0.7874 0.4064)
			(stroke
				(width 0.1524)
				(type default)
			)
			(layer "F.SilkS")
		)
		(fp_line
			(start -0.7874 -0.4064)
			(end 0.7874 -0.4064)
			(stroke
				(width 0.1524)
				(type default)
			)
			(layer "F.SilkS")
		)
		(fp_line
			(start 0.7874 -0.4064)
			(end 0.7874 0.4064)
			(stroke
				(width 0.1524)
				(type default)
			)
			(layer "F.SilkS")
		)
		(fp_line
			(start -0.67945 0.3048)
			(end -0.67945 -0.305054)
			(stroke
				(width 0.1)
				(type default)
			)
			(layer "F.Fab")
		)
		(fp_line
			(start -0.12065 0.3048)
			(end -0.67945 0.3048)
			(stroke
				(width 0.1)
				(type default)
			)
			(layer "F.Fab")
		)
		(fp_line
			(start 0.120396 0.3048)
			(end 0.120396 0.2794)
			(stroke
				(width 0.1)
				(type default)
			)
			(layer "F.Fab")
		)
		(fp_line
			(start 0.67945 0.3048)
			(end 0.120396 0.3048)
			(stroke
				(width 0.1)
				(type default)
			)
			(layer "F.Fab")
		)
		(fp_line
			(start -0.12065 0.2794)
			(end -0.12065 0.3048)
			(stroke
				(width 0.1)
				(type default)
			)
			(layer "F.Fab")
		)
		(fp_line
			(start 0.120396 0.2794)
			(end -0.12065 0.2794)
			(stroke
				(width 0.1)
				(type default)
			)
			(layer "F.Fab")
		)
		(fp_line
			(start -0.12065 -0.2794)
			(end 0.12065 -0.2794)
			(stroke
				(width 0.1)
				(type default)
			)
			(layer "F.Fab")
		)
		(fp_line
			(start 0.12065 -0.2794)
			(end 0.12065 -0.3048)
			(stroke
				(width 0.1)
				(type default)
			)
			(layer "F.Fab")
		)
		(fp_line
			(start 0.12065 -0.3048)
			(end 0.67945 -0.3048)
			(stroke
				(width 0.1)
				(type default)
			)
			(layer "F.Fab")
		)
		(fp_line
			(start 0.67945 -0.3048)
			(end 0.67945 0.3048)
			(stroke
				(width 0.1)
				(type default)
			)
			(layer "F.Fab")
		)
		(fp_line
			(start -0.67945 -0.305054)
			(end -0.12065 -0.305054)
			(stroke
				(width 0.1)
				(type default)
			)
			(layer "F.Fab")
		)
		(fp_line
			(start -0.12065 -0.305054)
			(end -0.12065 -0.2794)
			(stroke
				(width 0.1)
				(type default)
			)
			(layer "F.Fab")
		)
		(pad "1" smd circle
			(at -0.40005 0 270)
			(size 0 0)
			(layers "F.Cu" "F.Mask" "F.Paste")
			(net "P12V_OCP_V3_2_EN_R")
		)
		(pad "2" smd circle
			(at 0.40005 0 270)
			(size 0 0)
			(layers "F.Cu" "F.Mask" "F.Paste")
			(net "P12V_OCP_V3_2_EN_2_R3")
		)
	)
	(footprint ""
		(layer "F.Cu")
		(at 229.603554 -151.752046 180)
		(property "Reference" "C1521"
			(at 0 0 180)
			(layer "F.SilkS")
			(hide yes)
			(effects
				(font
					(size 1.27 1.27)
				)
			)
		)
		(property "Value" ""
			(at 0 0 180)
			(layer "F.Fab")
			(effects
				(font
					(size 1.27 1.27)
				)
			)
		)
		(duplicate_pad_numbers_are_jumpers no)
		(fp_line
			(start 0.7874 0.4064)
			(end -0.7874 0.4064)
			(stroke
				(width 0.1524)
				(type default)
			)
			(layer "F.SilkS")
		)
		(fp_line
			(start 0.7874 -0.4064)
			(end 0.7874 0.4064)
			(stroke
				(width 0.1524)
				(type default)
			)
			(layer "F.SilkS")
		)
		(fp_line
			(start -0.7874 0.4064)
			(end -0.7874 -0.4064)
			(stroke
				(width 0.1524)
				(type default)
			)
			(layer "F.SilkS")
		)
		(fp_line
			(start -0.7874 -0.4064)
			(end 0.7874 -0.4064)
			(stroke
				(width 0.1524)
				(type default)
			)
			(layer "F.SilkS")
		)
		(fp_line
			(start 0.67945 0.3048)
			(end 0.120396 0.3048)
			(stroke
				(width 0.1)
				(type default)
			)
			(layer "F.Fab")
		)
		(fp_line
			(start 0.67945 -0.3048)
			(end 0.67945 0.3048)
			(stroke
				(width 0.1)
				(type default)
			)
			(layer "F.Fab")
		)
		(fp_line
			(start 0.12065 -0.2794)
			(end 0.12065 -0.3048)
			(stroke
				(width 0.1)
				(type default)
			)
			(layer "F.Fab")
		)
		(fp_line
			(start 0.12065 -0.3048)
			(end 0.67945 -0.3048)
			(stroke
				(width 0.1)
				(type default)
			)
			(layer "F.Fab")
		)
		(fp_line
			(start 0.120396 0.3048)
			(end 0.120396 0.2794)
			(stroke
				(width 0.1)
				(type default)
			)
			(layer "F.Fab")
		)
		(fp_line
			(start 0.120396 0.2794)
			(end -0.12065 0.2794)
			(stroke
				(width 0.1)
				(type default)
			)
			(layer "F.Fab")
		)
		(fp_line
			(start -0.12065 0.3048)
			(end -0.67945 0.3048)
			(stroke
				(width 0.1)
				(type default)
			)
			(layer "F.Fab")
		)
		(fp_line
			(start -0.12065 0.2794)
			(end -0.12065 0.3048)
			(stroke
				(width 0.1)
				(type default)
			)
			(layer "F.Fab")
		)
		(fp_line
			(start -0.12065 -0.2794)
			(end 0.12065 -0.2794)
			(stroke
				(width 0.1)
				(type default)
			)
			(layer "F.Fab")
		)
		(fp_line
			(start -0.12065 -0.305054)
			(end -0.12065 -0.2794)
			(stroke
				(width 0.1)
				(type default)
			)
			(layer "F.Fab")
		)
		(fp_line
			(start -0.67945 0.3048)
			(end -0.67945 -0.305054)
			(stroke
				(width 0.1)
				(type default)
			)
			(layer "F.Fab")
		)
		(fp_line
			(start -0.67945 -0.305054)
			(end -0.12065 -0.305054)
			(stroke
				(width 0.1)
				(type default)
			)
			(layer "F.Fab")
		)
		(pad "1" smd circle
			(at -0.40005 0 180)
			(size 0 0)
			(layers "F.Cu" "F.Mask" "F.Paste")
			(net "PVDD18_S5_P0")
		)
		(pad "2" smd circle
			(at 0.40005 0 180)
			(size 0 0)
			(layers "F.Cu" "F.Mask" "F.Paste")
			(net "GND")
		)
	)
	(footprint ""
		(layer "F.Cu")
		(at 83.878166 -143.785844)
		(property "Reference" "C224"
			(at 0 0 0)
			(layer "F.SilkS")
			(hide yes)
			(effects
				(font
					(size 1.27 1.27)
				)
			)
		)
		(property "Value" ""
			(at 0 0 0)
			(layer "F.Fab")
			(effects
				(font
					(size 1.27 1.27)
				)
			)
		)
		(duplicate_pad_numbers_are_jumpers no)
		(fp_line
			(start -0.7874 -0.4064)
			(end 0.7874 -0.4064)
			(stroke
				(width 0.1524)
				(type default)
			)
			(layer "F.SilkS")
		)
		(fp_line
			(start -0.7874 0.4064)
			(end -0.7874 -0.4064)
			(stroke
				(width 0.1524)
				(type default)
			)
			(layer "F.SilkS")
		)
		(fp_line
			(start 0.7874 -0.4064)
			(end 0.7874 0.4064)
			(stroke
				(width 0.1524)
				(type default)
			)
			(layer "F.SilkS")
		)
		(fp_line
			(start 0.7874 0.4064)
			(end -0.7874 0.4064)
			(stroke
				(width 0.1524)
				(type default)
			)
			(layer "F.SilkS")
		)
		(fp_line
			(start -0.67945 -0.305054)
			(end -0.12065 -0.305054)
			(stroke
				(width 0.1)
				(type default)
			)
			(layer "F.Fab")
		)
		(fp_line
			(start -0.67945 0.3048)
			(end -0.67945 -0.305054)
			(stroke
				(width 0.1)
				(type default)
			)
			(layer "F.Fab")
		)
		(fp_line
			(start -0.12065 -0.305054)
			(end -0.12065 -0.2794)
			(stroke
				(width 0.1)
				(type default)
			)
			(layer "F.Fab")
		)
		(fp_line
			(start -0.12065 -0.2794)
			(end 0.12065 -0.2794)
			(stroke
				(width 0.1)
				(type default)
			)
			(layer "F.Fab")
		)
		(fp_line
			(start -0.12065 0.2794)
			(end -0.12065 0.3048)
			(stroke
				(width 0.1)
				(type default)
			)
			(layer "F.Fab")
		)
		(fp_line
			(start -0.12065 0.3048)
			(end -0.67945 0.3048)
			(stroke
				(width 0.1)
				(type default)
			)
			(layer "F.Fab")
		)
		(fp_line
			(start 0.120396 0.2794)
			(end -0.12065 0.2794)
			(stroke
				(width 0.1)
				(type default)
			)
			(layer "F.Fab")
		)
		(fp_line
			(start 0.120396 0.3048)
			(end 0.120396 0.2794)
			(stroke
				(width 0.1)
				(type default)
			)
			(layer "F.Fab")
		)
		(fp_line
			(start 0.12065 -0.3048)
			(end 0.67945 -0.3048)
			(stroke
				(width 0.1)
				(type default)
			)
			(layer "F.Fab")
		)
		(fp_line
			(start 0.12065 -0.2794)
			(end 0.12065 -0.3048)
			(stroke
				(width 0.1)
				(type default)
			)
			(layer "F.Fab")
		)
		(fp_line
			(start 0.67945 -0.3048)
			(end 0.67945 0.3048)
			(stroke
				(width 0.1)
				(type default)
			)
			(layer "F.Fab")
		)
		(fp_line
			(start 0.67945 0.3048)
			(end 0.120396 0.3048)
			(stroke
				(width 0.1)
				(type default)
			)
			(layer "F.Fab")
		)
		(pad "1" smd circle
			(at -0.40005 0)
			(size 0 0)
			(layers "F.Cu" "F.Mask" "F.Paste")
			(net "P1V8_AUX")
		)
		(pad "2" smd circle
			(at 0.40005 0)
			(size 0 0)
			(layers "F.Cu" "F.Mask" "F.Paste")
			(net "GND")
		)
	)
	(footprint ""
		(layer "F.Cu")
		(at 332.250288 -403.285452 90)
		(property "Reference" "R1012"
			(at 0 0 90)
			(layer "F.SilkS")
			(hide yes)
			(effects
				(font
					(size 1.27 1.27)
				)
			)
		)
		(property "Value" ""
			(at 0 0 90)
			(layer "F.Fab")
			(effects
				(font
					(size 1.27 1.27)
				)
			)
		)
		(duplicate_pad_numbers_are_jumpers no)
		(fp_line
			(start 0.32512 -0.175006)
			(end 0.32512 0.175006)
			(stroke
				(width 0.1)
				(type default)
			)
			(layer "F.Fab")
		)
		(fp_line
			(start -0.32512 -0.175006)
			(end 0.32512 -0.175006)
			(stroke
				(width 0.1)
				(type default)
			)
			(layer "F.Fab")
		)
		(fp_line
			(start 0.32512 0.175006)
			(end -0.32512 0.175006)
			(stroke
				(width 0.1)
				(type default)
			)
			(layer "F.Fab")
		)
		(fp_line
			(start -0.32512 0.175006)
			(end -0.32512 -0.175006)
			(stroke
				(width 0.1)
				(type default)
			)
			(layer "F.Fab")
		)
		(pad "1" smd rect
			(at -0.2667 0 90)
			(size 0.3048 0.381)
			(layers "F.Cu" "F.Mask" "F.Paste")
			(net "RST_RT_CPU0_P1_RESET_N")
		)
		(pad "2" smd rect
			(at 0.2667 0 270)
			(size 0.3048 0.381)
			(layers "F.Cu" "F.Mask" "F.Paste")
			(net "RST_RT_CPU0_P1_RESET_R_N")
		)
	)
	(footprint ""
		(layer "F.Cu")
		(at 5.985002 -403.945852 180)
		(property "Reference" ""
			(at 0 0 180)
			(layer "F.SilkS")
			(hide yes)
			(effects
				(font
					(size 1.27 1.27)
				)
			)
		)
		(property "Value" ""
			(at 0 0 180)
			(layer "F.Fab")
			(effects
				(font
					(size 1.27 1.27)
				)
			)
		)
		(duplicate_pad_numbers_are_jumpers no)
		(pad "1" smd circle
			(at 0 0 180)
			(size 0.9906 0.9906)
			(layers "F.Cu" "F.Mask" "F.Paste")
			(net "Net_2240")
		)
		(zone
			(layer "F.Cu")
			(hatch none 0.5)
			(connect_pads
				(clearance 0)
			)
			(min_thickness 0.25)
			(keepout
				(tracks not_allowed)
				(vias allowed)
				(pads allowed)
				(copperpour not_allowed)
				(footprints allowed)
			)
			(placement
				(enabled no)
				(sheetname "")
			)
			(fill
				(thermal_gap 0.5)
				(thermal_bridge_width 0.5)
				(island_removal_mode 0)
			)
			(polygon
				(pts
					(arc
						(start 7.610602 -403.945852)
						(mid 4.359402 -403.945852)
						(end 7.610602 -403.945852)
					)
				)
			)
		)
	)
	(footprint ""
		(layer "F.Cu")
		(at 449.443602 -428.10811)
		(property "Reference" "PC6604"
			(at 0 0 0)
			(layer "F.SilkS")
			(hide yes)
			(effects
				(font
					(size 1.27 1.27)
				)
			)
		)
		(property "Value" ""
			(at 0 0 0)
			(layer "F.Fab")
			(effects
				(font
					(size 1.27 1.27)
				)
			)
		)
		(duplicate_pad_numbers_are_jumpers no)
		(fp_line
			(start -0.7874 -0.4064)
			(end 0.7874 -0.4064)
			(stroke
				(width 0.1524)
				(type default)
			)
			(layer "F.SilkS")
		)
		(fp_line
			(start -0.7874 0.4064)
			(end -0.7874 -0.4064)
			(stroke
				(width 0.1524)
				(type default)
			)
			(layer "F.SilkS")
		)
		(fp_line
			(start 0.7874 -0.4064)
			(end 0.7874 0.4064)
			(stroke
				(width 0.1524)
				(type default)
			)
			(layer "F.SilkS")
		)
		(fp_line
			(start 0.7874 0.4064)
			(end -0.7874 0.4064)
			(stroke
				(width 0.1524)
				(type default)
			)
			(layer "F.SilkS")
		)
		(fp_line
			(start -0.67945 -0.305054)
			(end -0.12065 -0.305054)
			(stroke
				(width 0.1)
				(type default)
			)
			(layer "F.Fab")
		)
		(fp_line
			(start -0.67945 0.3048)
			(end -0.67945 -0.305054)
			(stroke
				(width 0.1)
				(type default)
			)
			(layer "F.Fab")
		)
		(fp_line
			(start -0.12065 -0.305054)
			(end -0.12065 -0.2794)
			(stroke
				(width 0.1)
				(type default)
			)
			(layer "F.Fab")
		)
		(fp_line
			(start -0.12065 -0.2794)
			(end 0.12065 -0.2794)
			(stroke
				(width 0.1)
				(type default)
			)
			(layer "F.Fab")
		)
		(fp_line
			(start -0.12065 0.2794)
			(end -0.12065 0.3048)
			(stroke
				(width 0.1)
				(type default)
			)
			(layer "F.Fab")
		)
		(fp_line
			(start -0.12065 0.3048)
			(end -0.67945 0.3048)
			(stroke
				(width 0.1)
				(type default)
			)
			(layer "F.Fab")
		)
		(fp_line
			(start 0.120396 0.2794)
			(end -0.12065 0.2794)
			(stroke
				(width 0.1)
				(type default)
			)
			(layer "F.Fab")
		)
		(fp_line
			(start 0.120396 0.3048)
			(end 0.120396 0.2794)
			(stroke
				(width 0.1)
				(type default)
			)
			(layer "F.Fab")
		)
		(fp_line
			(start 0.12065 -0.3048)
			(end 0.67945 -0.3048)
			(stroke
				(width 0.1)
				(type default)
			)
			(layer "F.Fab")
		)
		(fp_line
			(start 0.12065 -0.2794)
			(end 0.12065 -0.3048)
			(stroke
				(width 0.1)
				(type default)
			)
			(layer "F.Fab")
		)
		(fp_line
			(start 0.67945 -0.3048)
			(end 0.67945 0.3048)
			(stroke
				(width 0.1)
				(type default)
			)
			(layer "F.Fab")
		)
		(fp_line
			(start 0.67945 0.3048)
			(end 0.120396 0.3048)
			(stroke
				(width 0.1)
				(type default)
			)
			(layer "F.Fab")
		)
		(pad "1" smd circle
			(at -0.40005 0)
			(size 0 0)
			(layers "F.Cu" "F.Mask" "F.Paste")
			(net "P0V9_RETIMER_CPU0_VCC")
		)
		(pad "2" smd circle
			(at 0.40005 0)
			(size 0 0)
			(layers "F.Cu" "F.Mask" "F.Paste")
			(net "GND")
		)
	)
	(footprint ""
		(layer "F.Cu")
		(at 225.171762 -71.192898 90)
		(property "Reference" "R3977"
			(at 0 0 90)
			(layer "F.SilkS")
			(hide yes)
			(effects
				(font
					(size 1.27 1.27)
				)
			)
		)
		(property "Value" ""
			(at 0 0 90)
			(layer "F.Fab")
			(effects
				(font
					(size 1.27 1.27)
				)
			)
		)
		(duplicate_pad_numbers_are_jumpers no)
		(fp_line
			(start 0.7874 -0.4064)
			(end 0.7874 0.4064)
			(stroke
				(width 0.1524)
				(type default)
			)
			(layer "F.SilkS")
		)
		(fp_line
			(start -0.7874 -0.4064)
			(end 0.7874 -0.4064)
			(stroke
				(width 0.1524)
				(type default)
			)
			(layer "F.SilkS")
		)
		(fp_line
			(start 0.7874 0.4064)
			(end -0.7874 0.4064)
			(stroke
				(width 0.1524)
				(type default)
			)
			(layer "F.SilkS")
		)
		(fp_line
			(start -0.7874 0.4064)
			(end -0.7874 -0.4064)
			(stroke
				(width 0.1524)
				(type default)
			)
			(layer "F.SilkS")
		)
		(fp_line
			(start -0.12065 -0.305054)
			(end -0.12065 -0.2794)
			(stroke
				(width 0.1)
				(type default)
			)
			(layer "F.Fab")
		)
		(fp_line
			(start -0.67945 -0.305054)
			(end -0.12065 -0.305054)
			(stroke
				(width 0.1)
				(type default)
			)
			(layer "F.Fab")
		)
		(fp_line
			(start 0.67945 -0.3048)
			(end 0.67945 0.3048)
			(stroke
				(width 0.1)
				(type default)
			)
			(layer "F.Fab")
		)
		(fp_line
			(start 0.12065 -0.3048)
			(end 0.67945 -0.3048)
			(stroke
				(width 0.1)
				(type default)
			)
			(layer "F.Fab")
		)
		(fp_line
			(start 0.12065 -0.2794)
			(end 0.12065 -0.3048)
			(stroke
				(width 0.1)
				(type default)
			)
			(layer "F.Fab")
		)
		(fp_line
			(start -0.12065 -0.2794)
			(end 0.12065 -0.2794)
			(stroke
				(width 0.1)
				(type default)
			)
			(layer "F.Fab")
		)
		(fp_line
			(start 0.120396 0.2794)
			(end -0.12065 0.2794)
			(stroke
				(width 0.1)
				(type default)
			)
			(layer "F.Fab")
		)
		(fp_line
			(start -0.12065 0.2794)
			(end -0.12065 0.3048)
			(stroke
				(width 0.1)
				(type default)
			)
			(layer "F.Fab")
		)
		(fp_line
			(start 0.67945 0.3048)
			(end 0.120396 0.3048)
			(stroke
				(width 0.1)
				(type default)
			)
			(layer "F.Fab")
		)
		(fp_line
			(start 0.120396 0.3048)
			(end 0.120396 0.2794)
			(stroke
				(width 0.1)
				(type default)
			)
			(layer "F.Fab")
		)
		(fp_line
			(start -0.12065 0.3048)
			(end -0.67945 0.3048)
			(stroke
				(width 0.1)
				(type default)
			)
			(layer "F.Fab")
		)
		(fp_line
			(start -0.67945 0.3048)
			(end -0.67945 -0.305054)
			(stroke
				(width 0.1)
				(type default)
			)
			(layer "F.Fab")
		)
		(pad "1" smd circle
			(at -0.40005 0 90)
			(size 0 0)
			(layers "F.Cu" "F.Mask" "F.Paste")
			(net "P3V3_AUX")
		)
		(pad "2" smd circle
			(at 0.40005 0 90)
			(size 0 0)
			(layers "F.Cu" "F.Mask" "F.Paste")
			(net "P3V3_E1S_FAULT_0")
		)
	)
	(footprint ""
		(layer "F.Cu")
		(at 149.649434 -320.717672 180)
		(property "Reference" "R374"
			(at 0 0 180)
			(layer "F.SilkS")
			(hide yes)
			(effects
				(font
					(size 1.27 1.27)
				)
			)
		)
		(property "Value" ""
			(at 0 0 180)
			(layer "F.Fab")
			(effects
				(font
					(size 1.27 1.27)
				)
			)
		)
		(duplicate_pad_numbers_are_jumpers no)
		(fp_line
			(start 0.7874 0.4064)
			(end -0.7874 0.4064)
			(stroke
				(width 0.1524)
				(type default)
			)
			(layer "F.SilkS")
		)
		(fp_line
			(start 0.7874 -0.4064)
			(end 0.7874 0.4064)
			(stroke
				(width 0.1524)
				(type default)
			)
			(layer "F.SilkS")
		)
		(fp_line
			(start -0.7874 0.4064)
			(end -0.7874 -0.4064)
			(stroke
				(width 0.1524)
				(type default)
			)
			(layer "F.SilkS")
		)
		(fp_line
			(start -0.7874 -0.4064)
			(end 0.7874 -0.4064)
			(stroke
				(width 0.1524)
				(type default)
			)
			(layer "F.SilkS")
		)
		(fp_line
			(start 0.67945 0.3048)
			(end 0.120396 0.3048)
			(stroke
				(width 0.1)
				(type default)
			)
			(layer "F.Fab")
		)
		(fp_line
			(start 0.67945 -0.3048)
			(end 0.67945 0.3048)
			(stroke
				(width 0.1)
				(type default)
			)
			(layer "F.Fab")
		)
		(fp_line
			(start 0.12065 -0.2794)
			(end 0.12065 -0.3048)
			(stroke
				(width 0.1)
				(type default)
			)
			(layer "F.Fab")
		)
		(fp_line
			(start 0.12065 -0.3048)
			(end 0.67945 -0.3048)
			(stroke
				(width 0.1)
				(type default)
			)
			(layer "F.Fab")
		)
		(fp_line
			(start 0.120396 0.3048)
			(end 0.120396 0.2794)
			(stroke
				(width 0.1)
				(type default)
			)
			(layer "F.Fab")
		)
		(fp_line
			(start 0.120396 0.2794)
			(end -0.12065 0.2794)
			(stroke
				(width 0.1)
				(type default)
			)
			(layer "F.Fab")
		)
		(fp_line
			(start -0.12065 0.3048)
			(end -0.67945 0.3048)
			(stroke
				(width 0.1)
				(type default)
			)
			(layer "F.Fab")
		)
		(fp_line
			(start -0.12065 0.2794)
			(end -0.12065 0.3048)
			(stroke
				(width 0.1)
				(type default)
			)
			(layer "F.Fab")
		)
		(fp_line
			(start -0.12065 -0.2794)
			(end 0.12065 -0.2794)
			(stroke
				(width 0.1)
				(type default)
			)
			(layer "F.Fab")
		)
		(fp_line
			(start -0.12065 -0.305054)
			(end -0.12065 -0.2794)
			(stroke
				(width 0.1)
				(type default)
			)
			(layer "F.Fab")
		)
		(fp_line
			(start -0.67945 0.3048)
			(end -0.67945 -0.305054)
			(stroke
				(width 0.1)
				(type default)
			)
			(layer "F.Fab")
		)
		(fp_line
			(start -0.67945 -0.305054)
			(end -0.12065 -0.305054)
			(stroke
				(width 0.1)
				(type default)
			)
			(layer "F.Fab")
		)
		(pad "1" smd circle
			(at -0.40005 0 180)
			(size 0 0)
			(layers "F.Cu" "F.Mask" "F.Paste")
			(net "PVDD18_S5_P1")
		)
		(pad "2" smd circle
			(at 0.40005 0 180)
			(size 0 0)
			(layers "F.Cu" "F.Mask" "F.Paste")
			(net "CPU1_VDDBT_RTC_G")
		)
	)
	(footprint ""
		(layer "F.Cu")
		(at 305.796696 -381.41783 -90)
		(property "Reference" "C923"
			(at 0 0 270)
			(layer "F.SilkS")
			(hide yes)
			(effects
				(font
					(size 1.27 1.27)
				)
			)
		)
		(property "Value" ""
			(at 0 0 270)
			(layer "F.Fab")
			(effects
				(font
					(size 1.27 1.27)
				)
			)
		)
		(duplicate_pad_numbers_are_jumpers no)
		(fp_line
			(start -0.299974 0.150114)
			(end -0.299974 -0.150114)
			(stroke
				(width 0.1)
				(type default)
			)
			(layer "F.Fab")
		)
		(fp_line
			(start 0.299974 0.150114)
			(end -0.299974 0.150114)
			(stroke
				(width 0.1)
				(type default)
			)
			(layer "F.Fab")
		)
		(fp_line
			(start -0.299974 -0.150114)
			(end 0.299974 -0.150114)
			(stroke
				(width 0.1)
				(type default)
			)
			(layer "F.Fab")
		)
		(fp_line
			(start 0.299974 -0.150114)
			(end 0.299974 0.150114)
			(stroke
				(width 0.1)
				(type default)
			)
			(layer "F.Fab")
		)
		(pad "1" smd rect
			(at -0.2667 0 270)
			(size 0.3048 0.381)
			(layers "F.Cu" "F.Mask" "F.Paste")
			(net "P5E_CPU0_P0_TX_C_DP<5>")
		)
		(pad "2" smd rect
			(at 0.2667 0 270)
			(size 0.3048 0.381)
			(layers "F.Cu" "F.Mask" "F.Paste")
			(net "P5E_CPU0_P0_TX_DP<5>")
		)
	)
	(footprint ""
		(layer "F.Cu")
		(at 125.38837 -34.021268)
		(property "Reference" "C6020"
			(at 0 0 0)
			(layer "F.SilkS")
			(hide yes)
			(effects
				(font
					(size 1.27 1.27)
				)
			)
		)
		(property "Value" ""
			(at 0 0 0)
			(layer "F.Fab")
			(effects
				(font
					(size 1.27 1.27)
				)
			)
		)
		(duplicate_pad_numbers_are_jumpers no)
		(fp_line
			(start -0.40005 -0.4064)
			(end 0.40005 -0.4064)
			(stroke
				(width 0.1524)
				(type default)
			)
			(layer "F.SilkS")
		)
		(fp_line
			(start 0.40005 0.4064)
			(end -0.40005 0.4064)
			(stroke
				(width 0.1524)
				(type default)
			)
			(layer "F.SilkS")
		)
		(fp_line
			(start -0.6858 -0.3048)
			(end -0.1016 -0.3048)
			(stroke
				(width 0.1)
				(type default)
			)
			(layer "F.Fab")
		)
		(fp_line
			(start -0.6858 0.3048)
			(end -0.6858 -0.3048)
			(stroke
				(width 0.1)
				(type default)
			)
			(layer "F.Fab")
		)
		(fp_line
			(start -0.1016 -0.3048)
			(end -0.1016 -0.2794)
			(stroke
				(width 0.1)
				(type default)
			)
			(layer "F.Fab")
		)
		(fp_line
			(start -0.1016 -0.2794)
			(end 0.1016 -0.2794)
			(stroke
				(width 0.1)
				(type default)
			)
			(layer "F.Fab")
		)
		(fp_line
			(start -0.1016 0.2794)
			(end -0.1016 0.3048)
			(stroke
				(width 0.1)
				(type default)
			)
			(layer "F.Fab")
		)
		(fp_line
			(start -0.1016 0.3048)
			(end -0.6858 0.3048)
			(stroke
				(width 0.1)
				(type default)
			)
			(layer "F.Fab")
		)
		(fp_line
			(start 0.1016 -0.3048)
			(end 0.6858 -0.3048)
			(stroke
				(width 0.1)
				(type default)
			)
			(layer "F.Fab")
		)
		(fp_line
			(start 0.1016 -0.2794)
			(end 0.1016 -0.3048)
			(stroke
				(width 0.1)
				(type default)
			)
			(layer "F.Fab")
		)
		(fp_line
			(start 0.1016 0.2794)
			(end -0.1016 0.2794)
			(stroke
				(width 0.1)
				(type default)
			)
			(layer "F.Fab")
		)
		(fp_line
			(start 0.1016 0.3048)
			(end 0.1016 0.2794)
			(stroke
				(width 0.1)
				(type default)
			)
			(layer "F.Fab")
		)
		(fp_line
			(start 0.6858 -0.3048)
			(end 0.6858 0.3048)
			(stroke
				(width 0.1)
				(type default)
			)
			(layer "F.Fab")
		)
		(fp_line
			(start 0.6858 0.3048)
			(end 0.1016 0.3048)
			(stroke
				(width 0.1)
				(type default)
			)
			(layer "F.Fab")
		)
		(pad "1" smd rect
			(at -0.40005 0 180)
			(size 0.4572 0.508)
			(layers "F.Cu" "F.Mask" "F.Paste")
			(net "USB3_CPU0_BMC_RX_DN")
		)
		(pad "2" smd rect
			(at 0.40005 0 180)
			(size 0.4572 0.508)
			(layers "F.Cu" "F.Mask" "F.Paste")
			(net "USB3_CPU0_BMC_RX_C1_DN")
		)
	)
	(footprint ""
		(layer "F.Cu")
		(at 36.73094 -108.09732 90)
		(property "Reference" "R1049"
			(at 0 0 90)
			(layer "F.SilkS")
			(hide yes)
			(effects
				(font
					(size 1.27 1.27)
				)
			)
		)
		(property "Value" ""
			(at 0 0 90)
			(layer "F.Fab")
			(effects
				(font
					(size 1.27 1.27)
				)
			)
		)
		(duplicate_pad_numbers_are_jumpers no)
		(fp_line
			(start 0.7874 -0.4064)
			(end 0.7874 0.4064)
			(stroke
				(width 0.1524)
				(type default)
			)
			(layer "F.SilkS")
		)
		(fp_line
			(start -0.7874 -0.4064)
			(end 0.7874 -0.4064)
			(stroke
				(width 0.1524)
				(type default)
			)
			(layer "F.SilkS")
		)
		(fp_line
			(start 0.7874 0.4064)
			(end -0.7874 0.4064)
			(stroke
				(width 0.1524)
				(type default)
			)
			(layer "F.SilkS")
		)
		(fp_line
			(start -0.7874 0.4064)
			(end -0.7874 -0.4064)
			(stroke
				(width 0.1524)
				(type default)
			)
			(layer "F.SilkS")
		)
		(fp_line
			(start -0.12065 -0.305054)
			(end -0.12065 -0.2794)
			(stroke
				(width 0.1)
				(type default)
			)
			(layer "F.Fab")
		)
		(fp_line
			(start -0.67945 -0.305054)
			(end -0.12065 -0.305054)
			(stroke
				(width 0.1)
				(type default)
			)
			(layer "F.Fab")
		)
		(fp_line
			(start 0.67945 -0.3048)
			(end 0.67945 0.3048)
			(stroke
				(width 0.1)
				(type default)
			)
			(layer "F.Fab")
		)
		(fp_line
			(start 0.12065 -0.3048)
			(end 0.67945 -0.3048)
			(stroke
				(width 0.1)
				(type default)
			)
			(layer "F.Fab")
		)
		(fp_line
			(start 0.12065 -0.2794)
			(end 0.12065 -0.3048)
			(stroke
				(width 0.1)
				(type default)
			)
			(layer "F.Fab")
		)
		(fp_line
			(start -0.12065 -0.2794)
			(end 0.12065 -0.2794)
			(stroke
				(width 0.1)
				(type default)
			)
			(layer "F.Fab")
		)
		(fp_line
			(start 0.120396 0.2794)
			(end -0.12065 0.2794)
			(stroke
				(width 0.1)
				(type default)
			)
			(layer "F.Fab")
		)
		(fp_line
			(start -0.12065 0.2794)
			(end -0.12065 0.3048)
			(stroke
				(width 0.1)
				(type default)
			)
			(layer "F.Fab")
		)
		(fp_line
			(start 0.67945 0.3048)
			(end 0.120396 0.3048)
			(stroke
				(width 0.1)
				(type default)
			)
			(layer "F.Fab")
		)
		(fp_line
			(start 0.120396 0.3048)
			(end 0.120396 0.2794)
			(stroke
				(width 0.1)
				(type default)
			)
			(layer "F.Fab")
		)
		(fp_line
			(start -0.12065 0.3048)
			(end -0.67945 0.3048)
			(stroke
				(width 0.1)
				(type default)
			)
			(layer "F.Fab")
		)
		(fp_line
			(start -0.67945 0.3048)
			(end -0.67945 -0.305054)
			(stroke
				(width 0.1)
				(type default)
			)
			(layer "F.Fab")
		)
		(pad "1" smd circle
			(at -0.40005 0 90)
			(size 0 0)
			(layers "F.Cu" "F.Mask" "F.Paste")
			(net "P12V_AUX_DSC_G1")
		)
		(pad "2" smd circle
			(at 0.40005 0 90)
			(size 0 0)
			(layers "F.Cu" "F.Mask" "F.Paste")
			(net "GND")
		)
	)
	(footprint ""
		(layer "F.Cu")
		(at 389.248142 -416.899344 -90)
		(property "Reference" "C6578"
			(at 0 0 270)
			(layer "F.SilkS")
			(hide yes)
			(effects
				(font
					(size 1.27 1.27)
				)
			)
		)
		(property "Value" ""
			(at 0 0 270)
			(layer "F.Fab")
			(effects
				(font
					(size 1.27 1.27)
				)
			)
		)
		(duplicate_pad_numbers_are_jumpers no)
		(fp_line
			(start -0.299974 0.150114)
			(end -0.299974 -0.150114)
			(stroke
				(width 0.1)
				(type default)
			)
			(layer "F.Fab")
		)
		(fp_line
			(start 0.299974 0.150114)
			(end -0.299974 0.150114)
			(stroke
				(width 0.1)
				(type default)
			)
			(layer "F.Fab")
		)
		(fp_line
			(start -0.299974 -0.150114)
			(end 0.299974 -0.150114)
			(stroke
				(width 0.1)
				(type default)
			)
			(layer "F.Fab")
		)
		(fp_line
			(start 0.299974 -0.150114)
			(end 0.299974 0.150114)
			(stroke
				(width 0.1)
				(type default)
			)
			(layer "F.Fab")
		)
		(pad "1" smd rect
			(at -0.2667 0 270)
			(size 0.3048 0.381)
			(layers "F.Cu" "F.Mask" "F.Paste")
			(net "P5E_CPU0_P2_TX_BUF_C_DN<6>")
		)
		(pad "2" smd rect
			(at 0.2667 0 270)
			(size 0.3048 0.381)
			(layers "F.Cu" "F.Mask" "F.Paste")
			(net "P5E_CPU0_P2_TX_BUF_DN<6>")
		)
	)
	(footprint ""
		(layer "F.Cu")
		(at 325.740776 -385.364228)
		(property "Reference" "C904"
			(at 0 0 0)
			(layer "F.SilkS")
			(hide yes)
			(effects
				(font
					(size 1.27 1.27)
				)
			)
		)
		(property "Value" ""
			(at 0 0 0)
			(layer "F.Fab")
			(effects
				(font
					(size 1.27 1.27)
				)
			)
		)
		(duplicate_pad_numbers_are_jumpers no)
		(fp_line
			(start -0.299974 -0.150114)
			(end 0.299974 -0.150114)
			(stroke
				(width 0.1)
				(type default)
			)
			(layer "F.Fab")
		)
		(fp_line
			(start -0.299974 0.150114)
			(end -0.299974 -0.150114)
			(stroke
				(width 0.1)
				(type default)
			)
			(layer "F.Fab")
		)
		(fp_line
			(start 0.299974 -0.150114)
			(end 0.299974 0.150114)
			(stroke
				(width 0.1)
				(type default)
			)
			(layer "F.Fab")
		)
		(fp_line
			(start 0.299974 0.150114)
			(end -0.299974 0.150114)
			(stroke
				(width 0.1)
				(type default)
			)
			(layer "F.Fab")
		)
		(pad "1" smd rect
			(at -0.2667 0)
			(size 0.3048 0.381)
			(layers "F.Cu" "F.Mask" "F.Paste")
			(net "P5E_CPU0_P0_TX_C_DN<14>")
		)
		(pad "2" smd rect
			(at 0.2667 0)
			(size 0.3048 0.381)
			(layers "F.Cu" "F.Mask" "F.Paste")
			(net "P5E_CPU0_P0_TX_DN<14>")
		)
	)
	(footprint ""
		(layer "F.Cu")
		(at 350.361504 -345.146122)
		(property "Reference" "PR7"
			(at 0 0 0)
			(layer "F.SilkS")
			(hide yes)
			(effects
				(font
					(size 1.27 1.27)
				)
			)
		)
		(property "Value" ""
			(at 0 0 0)
			(layer "F.Fab")
			(effects
				(font
					(size 1.27 1.27)
				)
			)
		)
		(duplicate_pad_numbers_are_jumpers no)
		(fp_line
			(start -0.7874 -0.4064)
			(end 0.7874 -0.4064)
			(stroke
				(width 0.1524)
				(type default)
			)
			(layer "F.SilkS")
		)
		(fp_line
			(start -0.7874 0.4064)
			(end -0.7874 -0.4064)
			(stroke
				(width 0.1524)
				(type default)
			)
			(layer "F.SilkS")
		)
		(fp_line
			(start 0.7874 -0.4064)
			(end 0.7874 0.4064)
			(stroke
				(width 0.1524)
				(type default)
			)
			(layer "F.SilkS")
		)
		(fp_line
			(start 0.7874 0.4064)
			(end -0.7874 0.4064)
			(stroke
				(width 0.1524)
				(type default)
			)
			(layer "F.SilkS")
		)
		(fp_line
			(start -0.67945 -0.305054)
			(end -0.12065 -0.305054)
			(stroke
				(width 0.1)
				(type default)
			)
			(layer "F.Fab")
		)
		(fp_line
			(start -0.67945 0.3048)
			(end -0.67945 -0.305054)
			(stroke
				(width 0.1)
				(type default)
			)
			(layer "F.Fab")
		)
		(fp_line
			(start -0.12065 -0.305054)
			(end -0.12065 -0.2794)
			(stroke
				(width 0.1)
				(type default)
			)
			(layer "F.Fab")
		)
		(fp_line
			(start -0.12065 -0.2794)
			(end 0.12065 -0.2794)
			(stroke
				(width 0.1)
				(type default)
			)
			(layer "F.Fab")
		)
		(fp_line
			(start -0.12065 0.2794)
			(end -0.12065 0.3048)
			(stroke
				(width 0.1)
				(type default)
			)
			(layer "F.Fab")
		)
		(fp_line
			(start -0.12065 0.3048)
			(end -0.67945 0.3048)
			(stroke
				(width 0.1)
				(type default)
			)
			(layer "F.Fab")
		)
		(fp_line
			(start 0.120396 0.2794)
			(end -0.12065 0.2794)
			(stroke
				(width 0.1)
				(type default)
			)
			(layer "F.Fab")
		)
		(fp_line
			(start 0.120396 0.3048)
			(end 0.120396 0.2794)
			(stroke
				(width 0.1)
				(type default)
			)
			(layer "F.Fab")
		)
		(fp_line
			(start 0.12065 -0.3048)
			(end 0.67945 -0.3048)
			(stroke
				(width 0.1)
				(type default)
			)
			(layer "F.Fab")
		)
		(fp_line
			(start 0.12065 -0.2794)
			(end 0.12065 -0.3048)
			(stroke
				(width 0.1)
				(type default)
			)
			(layer "F.Fab")
		)
		(fp_line
			(start 0.67945 -0.3048)
			(end 0.67945 0.3048)
			(stroke
				(width 0.1)
				(type default)
			)
			(layer "F.Fab")
		)
		(fp_line
			(start 0.67945 0.3048)
			(end 0.120396 0.3048)
			(stroke
				(width 0.1)
				(type default)
			)
			(layer "F.Fab")
		)
		(pad "1" smd circle
			(at -0.40005 0)
			(size 0 0)
			(layers "F.Cu" "F.Mask" "F.Paste")
			(net "PVDDCR_CPU1_P0_LSET6")
		)
		(pad "2" smd circle
			(at 0.40005 0)
			(size 0 0)
			(layers "F.Cu" "F.Mask" "F.Paste")
			(net "GND")
		)
	)
	(footprint ""
		(layer "F.Cu")
		(at 175.300894 -391.34288 180)
		(property "Reference" "R864"
			(at 0 0 180)
			(layer "F.SilkS")
			(hide yes)
			(effects
				(font
					(size 1.27 1.27)
				)
			)
		)
		(property "Value" ""
			(at 0 0 180)
			(layer "F.Fab")
			(effects
				(font
					(size 1.27 1.27)
				)
			)
		)
		(duplicate_pad_numbers_are_jumpers no)
		(fp_line
			(start 0.32512 0.175006)
			(end -0.32512 0.175006)
			(stroke
				(width 0.1)
				(type default)
			)
			(layer "F.Fab")
		)
		(fp_line
			(start 0.32512 -0.175006)
			(end 0.32512 0.175006)
			(stroke
				(width 0.1)
				(type default)
			)
			(layer "F.Fab")
		)
		(fp_line
			(start -0.32512 0.175006)
			(end -0.32512 -0.175006)
			(stroke
				(width 0.1)
				(type default)
			)
			(layer "F.Fab")
		)
		(fp_line
			(start -0.32512 -0.175006)
			(end 0.32512 -0.175006)
			(stroke
				(width 0.1)
				(type default)
			)
			(layer "F.Fab")
		)
		(pad "1" smd rect
			(at -0.2667 0 180)
			(size 0.3048 0.381)
			(layers "F.Cu" "F.Mask" "F.Paste")
			(net "P1V8_CPU1_RT_1D")
		)
		(pad "2" smd rect
			(at 0.2667 0)
			(size 0.3048 0.381)
			(layers "F.Cu" "F.Mask" "F.Paste")
			(net "RT_CPU1_P2_ADDR2")
		)
	)
	(footprint ""
		(layer "F.Cu")
		(at 256.889504 -44.520612 180)
		(property "Reference" "PC2207"
			(at 0 0 180)
			(layer "F.SilkS")
			(hide yes)
			(effects
				(font
					(size 1.27 1.27)
				)
			)
		)
		(property "Value" ""
			(at 0 0 180)
			(layer "F.Fab")
			(effects
				(font
					(size 1.27 1.27)
				)
			)
		)
		(duplicate_pad_numbers_are_jumpers no)
		(fp_line
			(start 0.7874 0.4064)
			(end -0.7874 0.4064)
			(stroke
				(width 0.1524)
				(type default)
			)
			(layer "F.SilkS")
		)
		(fp_line
			(start 0.7874 -0.4064)
			(end 0.7874 0.4064)
			(stroke
				(width 0.1524)
				(type default)
			)
			(layer "F.SilkS")
		)
		(fp_line
			(start -0.7874 0.4064)
			(end -0.7874 -0.4064)
			(stroke
				(width 0.1524)
				(type default)
			)
			(layer "F.SilkS")
		)
		(fp_line
			(start -0.7874 -0.4064)
			(end 0.7874 -0.4064)
			(stroke
				(width 0.1524)
				(type default)
			)
			(layer "F.SilkS")
		)
		(fp_line
			(start 0.67945 0.3048)
			(end 0.120396 0.3048)
			(stroke
				(width 0.1)
				(type default)
			)
			(layer "F.Fab")
		)
		(fp_line
			(start 0.67945 -0.3048)
			(end 0.67945 0.3048)
			(stroke
				(width 0.1)
				(type default)
			)
			(layer "F.Fab")
		)
		(fp_line
			(start 0.12065 -0.2794)
			(end 0.12065 -0.3048)
			(stroke
				(width 0.1)
				(type default)
			)
			(layer "F.Fab")
		)
		(fp_line
			(start 0.12065 -0.3048)
			(end 0.67945 -0.3048)
			(stroke
				(width 0.1)
				(type default)
			)
			(layer "F.Fab")
		)
		(fp_line
			(start 0.120396 0.3048)
			(end 0.120396 0.2794)
			(stroke
				(width 0.1)
				(type default)
			)
			(layer "F.Fab")
		)
		(fp_line
			(start 0.120396 0.2794)
			(end -0.12065 0.2794)
			(stroke
				(width 0.1)
				(type default)
			)
			(layer "F.Fab")
		)
		(fp_line
			(start -0.12065 0.3048)
			(end -0.67945 0.3048)
			(stroke
				(width 0.1)
				(type default)
			)
			(layer "F.Fab")
		)
		(fp_line
			(start -0.12065 0.2794)
			(end -0.12065 0.3048)
			(stroke
				(width 0.1)
				(type default)
			)
			(layer "F.Fab")
		)
		(fp_line
			(start -0.12065 -0.2794)
			(end 0.12065 -0.2794)
			(stroke
				(width 0.1)
				(type default)
			)
			(layer "F.Fab")
		)
		(fp_line
			(start -0.12065 -0.305054)
			(end -0.12065 -0.2794)
			(stroke
				(width 0.1)
				(type default)
			)
			(layer "F.Fab")
		)
		(fp_line
			(start -0.67945 0.3048)
			(end -0.67945 -0.305054)
			(stroke
				(width 0.1)
				(type default)
			)
			(layer "F.Fab")
		)
		(fp_line
			(start -0.67945 -0.305054)
			(end -0.12065 -0.305054)
			(stroke
				(width 0.1)
				(type default)
			)
			(layer "F.Fab")
		)
		(pad "1" smd circle
			(at -0.40005 0 180)
			(size 0 0)
			(layers "F.Cu" "F.Mask" "F.Paste")
			(net "P12V_AUX")
		)
		(pad "2" smd circle
			(at 0.40005 0 180)
			(size 0 0)
			(layers "F.Cu" "F.Mask" "F.Paste")
			(net "GND")
		)
	)
	(footprint ""
		(layer "F.Cu")
		(at 319.940178 -42.684954)
		(property "Reference" "C2048"
			(at 0 0 0)
			(layer "F.SilkS")
			(hide yes)
			(effects
				(font
					(size 1.27 1.27)
				)
			)
		)
		(property "Value" ""
			(at 0 0 0)
			(layer "F.Fab")
			(effects
				(font
					(size 1.27 1.27)
				)
			)
		)
		(duplicate_pad_numbers_are_jumpers no)
		(fp_line
			(start -0.7874 -0.4064)
			(end 0.7874 -0.4064)
			(stroke
				(width 0.1524)
				(type default)
			)
			(layer "F.SilkS")
		)
		(fp_line
			(start -0.7874 0.4064)
			(end -0.7874 -0.4064)
			(stroke
				(width 0.1524)
				(type default)
			)
			(layer "F.SilkS")
		)
		(fp_line
			(start 0.7874 -0.4064)
			(end 0.7874 0.4064)
			(stroke
				(width 0.1524)
				(type default)
			)
			(layer "F.SilkS")
		)
		(fp_line
			(start 0.7874 0.4064)
			(end -0.7874 0.4064)
			(stroke
				(width 0.1524)
				(type default)
			)
			(layer "F.SilkS")
		)
		(fp_line
			(start -0.67945 -0.305054)
			(end -0.12065 -0.305054)
			(stroke
				(width 0.1)
				(type default)
			)
			(layer "F.Fab")
		)
		(fp_line
			(start -0.67945 0.3048)
			(end -0.67945 -0.305054)
			(stroke
				(width 0.1)
				(type default)
			)
			(layer "F.Fab")
		)
		(fp_line
			(start -0.12065 -0.305054)
			(end -0.12065 -0.2794)
			(stroke
				(width 0.1)
				(type default)
			)
			(layer "F.Fab")
		)
		(fp_line
			(start -0.12065 -0.2794)
			(end 0.12065 -0.2794)
			(stroke
				(width 0.1)
				(type default)
			)
			(layer "F.Fab")
		)
		(fp_line
			(start -0.12065 0.2794)
			(end -0.12065 0.3048)
			(stroke
				(width 0.1)
				(type default)
			)
			(layer "F.Fab")
		)
		(fp_line
			(start -0.12065 0.3048)
			(end -0.67945 0.3048)
			(stroke
				(width 0.1)
				(type default)
			)
			(layer "F.Fab")
		)
		(fp_line
			(start 0.120396 0.2794)
			(end -0.12065 0.2794)
			(stroke
				(width 0.1)
				(type default)
			)
			(layer "F.Fab")
		)
		(fp_line
			(start 0.120396 0.3048)
			(end 0.120396 0.2794)
			(stroke
				(width 0.1)
				(type default)
			)
			(layer "F.Fab")
		)
		(fp_line
			(start 0.12065 -0.3048)
			(end 0.67945 -0.3048)
			(stroke
				(width 0.1)
				(type default)
			)
			(layer "F.Fab")
		)
		(fp_line
			(start 0.12065 -0.2794)
			(end 0.12065 -0.3048)
			(stroke
				(width 0.1)
				(type default)
			)
			(layer "F.Fab")
		)
		(fp_line
			(start 0.67945 -0.3048)
			(end 0.67945 0.3048)
			(stroke
				(width 0.1)
				(type default)
			)
			(layer "F.Fab")
		)
		(fp_line
			(start 0.67945 0.3048)
			(end 0.120396 0.3048)
			(stroke
				(width 0.1)
				(type default)
			)
			(layer "F.Fab")
		)
		(pad "1" smd circle
			(at -0.40005 0)
			(size 0 0)
			(layers "F.Cu" "F.Mask" "F.Paste")
			(net "P3V3_ADC_TIC")
		)
		(pad "2" smd circle
			(at 0.40005 0)
			(size 0 0)
			(layers "F.Cu" "F.Mask" "F.Paste")
			(net "GND")
		)
	)
	(footprint ""
		(layer "F.Cu")
		(at 434.796692 -16.199866 -90)
		(property "Reference" "R1671"
			(at 0 0 270)
			(layer "F.SilkS")
			(hide yes)
			(effects
				(font
					(size 1.27 1.27)
				)
			)
		)
		(property "Value" ""
			(at 0 0 270)
			(layer "F.Fab")
			(effects
				(font
					(size 1.27 1.27)
				)
			)
		)
		(duplicate_pad_numbers_are_jumpers no)
		(fp_line
			(start -0.7874 0.4064)
			(end -0.7874 -0.4064)
			(stroke
				(width 0.1524)
				(type default)
			)
			(layer "F.SilkS")
		)
		(fp_line
			(start 0.7874 0.4064)
			(end -0.7874 0.4064)
			(stroke
				(width 0.1524)
				(type default)
			)
			(layer "F.SilkS")
		)
		(fp_line
			(start -0.7874 -0.4064)
			(end 0.7874 -0.4064)
			(stroke
				(width 0.1524)
				(type default)
			)
			(layer "F.SilkS")
		)
		(fp_line
			(start 0.7874 -0.4064)
			(end 0.7874 0.4064)
			(stroke
				(width 0.1524)
				(type default)
			)
			(layer "F.SilkS")
		)
		(fp_line
			(start -0.67945 0.3048)
			(end -0.67945 -0.305054)
			(stroke
				(width 0.1)
				(type default)
			)
			(layer "F.Fab")
		)
		(fp_line
			(start -0.12065 0.3048)
			(end -0.67945 0.3048)
			(stroke
				(width 0.1)
				(type default)
			)
			(layer "F.Fab")
		)
		(fp_line
			(start 0.120396 0.3048)
			(end 0.120396 0.2794)
			(stroke
				(width 0.1)
				(type default)
			)
			(layer "F.Fab")
		)
		(fp_line
			(start 0.67945 0.3048)
			(end 0.120396 0.3048)
			(stroke
				(width 0.1)
				(type default)
			)
			(layer "F.Fab")
		)
		(fp_line
			(start -0.12065 0.2794)
			(end -0.12065 0.3048)
			(stroke
				(width 0.1)
				(type default)
			)
			(layer "F.Fab")
		)
		(fp_line
			(start 0.120396 0.2794)
			(end -0.12065 0.2794)
			(stroke
				(width 0.1)
				(type default)
			)
			(layer "F.Fab")
		)
		(fp_line
			(start -0.12065 -0.2794)
			(end 0.12065 -0.2794)
			(stroke
				(width 0.1)
				(type default)
			)
			(layer "F.Fab")
		)
		(fp_line
			(start 0.12065 -0.2794)
			(end 0.12065 -0.3048)
			(stroke
				(width 0.1)
				(type default)
			)
			(layer "F.Fab")
		)
		(fp_line
			(start 0.12065 -0.3048)
			(end 0.67945 -0.3048)
			(stroke
				(width 0.1)
				(type default)
			)
			(layer "F.Fab")
		)
		(fp_line
			(start 0.67945 -0.3048)
			(end 0.67945 0.3048)
			(stroke
				(width 0.1)
				(type default)
			)
			(layer "F.Fab")
		)
		(fp_line
			(start -0.67945 -0.305054)
			(end -0.12065 -0.305054)
			(stroke
				(width 0.1)
				(type default)
			)
			(layer "F.Fab")
		)
		(fp_line
			(start -0.12065 -0.305054)
			(end -0.12065 -0.2794)
			(stroke
				(width 0.1)
				(type default)
			)
			(layer "F.Fab")
		)
		(pad "1" smd circle
			(at -0.40005 0 270)
			(size 0 0)
			(layers "F.Cu" "F.Mask" "F.Paste")
			(net "OCP_SFF_AUX_PWR_EN")
		)
		(pad "2" smd circle
			(at 0.40005 0 270)
			(size 0 0)
			(layers "F.Cu" "F.Mask" "F.Paste")
			(net "OCP_SFF_AUX_PWR_EN_R")
		)
	)
	(footprint ""
		(layer "F.Cu")
		(at 391.268458 -402.7424 -90)
		(property "Reference" "R1103"
			(at 0 0 270)
			(layer "F.SilkS")
			(hide yes)
			(effects
				(font
					(size 1.27 1.27)
				)
			)
		)
		(property "Value" ""
			(at 0 0 270)
			(layer "F.Fab")
			(effects
				(font
					(size 1.27 1.27)
				)
			)
		)
		(duplicate_pad_numbers_are_jumpers no)
		(fp_line
			(start -0.32512 0.175006)
			(end -0.32512 -0.175006)
			(stroke
				(width 0.1)
				(type default)
			)
			(layer "F.Fab")
		)
		(fp_line
			(start 0.32512 0.175006)
			(end -0.32512 0.175006)
			(stroke
				(width 0.1)
				(type default)
			)
			(layer "F.Fab")
		)
		(fp_line
			(start -0.32512 -0.175006)
			(end 0.32512 -0.175006)
			(stroke
				(width 0.1)
				(type default)
			)
			(layer "F.Fab")
		)
		(fp_line
			(start 0.32512 -0.175006)
			(end 0.32512 0.175006)
			(stroke
				(width 0.1)
				(type default)
			)
			(layer "F.Fab")
		)
		(pad "1" smd rect
			(at -0.2667 0 270)
			(size 0.3048 0.381)
			(layers "F.Cu" "F.Mask" "F.Paste")
			(net "RST_RT_CPU0_P3_PERST_R_N")
		)
		(pad "2" smd rect
			(at 0.2667 0 90)
			(size 0.3048 0.381)
			(layers "F.Cu" "F.Mask" "F.Paste")
			(net "GND")
		)
	)
	(footprint ""
		(layer "F.Cu")
		(at 325.740776 -387.853428)
		(property "Reference" "C903"
			(at 0 0 0)
			(layer "F.SilkS")
			(hide yes)
			(effects
				(font
					(size 1.27 1.27)
				)
			)
		)
		(property "Value" ""
			(at 0 0 0)
			(layer "F.Fab")
			(effects
				(font
					(size 1.27 1.27)
				)
			)
		)
		(duplicate_pad_numbers_are_jumpers no)
		(fp_line
			(start -0.299974 -0.150114)
			(end 0.299974 -0.150114)
			(stroke
				(width 0.1)
				(type default)
			)
			(layer "F.Fab")
		)
		(fp_line
			(start -0.299974 0.150114)
			(end -0.299974 -0.150114)
			(stroke
				(width 0.1)
				(type default)
			)
			(layer "F.Fab")
		)
		(fp_line
			(start 0.299974 -0.150114)
			(end 0.299974 0.150114)
			(stroke
				(width 0.1)
				(type default)
			)
			(layer "F.Fab")
		)
		(fp_line
			(start 0.299974 0.150114)
			(end -0.299974 0.150114)
			(stroke
				(width 0.1)
				(type default)
			)
			(layer "F.Fab")
		)
		(pad "1" smd rect
			(at -0.2667 0)
			(size 0.3048 0.381)
			(layers "F.Cu" "F.Mask" "F.Paste")
			(net "P5E_CPU0_P0_TX_C_DP<15>")
		)
		(pad "2" smd rect
			(at 0.2667 0)
			(size 0.3048 0.381)
			(layers "F.Cu" "F.Mask" "F.Paste")
			(net "P5E_CPU0_P0_TX_DP<15>")
		)
	)
	(footprint ""
		(layer "F.Cu")
		(at 323.637148 -46.986698)
		(property "Reference" "R3679"
			(at 0 0 0)
			(layer "F.SilkS")
			(hide yes)
			(effects
				(font
					(size 1.27 1.27)
				)
			)
		)
		(property "Value" ""
			(at 0 0 0)
			(layer "F.Fab")
			(effects
				(font
					(size 1.27 1.27)
				)
			)
		)
		(duplicate_pad_numbers_are_jumpers no)
		(fp_line
			(start -0.7874 -0.4064)
			(end 0.7874 -0.4064)
			(stroke
				(width 0.1524)
				(type default)
			)
			(layer "F.SilkS")
		)
		(fp_line
			(start -0.7874 0.4064)
			(end -0.7874 -0.4064)
			(stroke
				(width 0.1524)
				(type default)
			)
			(layer "F.SilkS")
		)
		(fp_line
			(start 0.7874 -0.4064)
			(end 0.7874 0.4064)
			(stroke
				(width 0.1524)
				(type default)
			)
			(layer "F.SilkS")
		)
		(fp_line
			(start 0.7874 0.4064)
			(end -0.7874 0.4064)
			(stroke
				(width 0.1524)
				(type default)
			)
			(layer "F.SilkS")
		)
		(fp_line
			(start -0.67945 -0.305054)
			(end -0.12065 -0.305054)
			(stroke
				(width 0.1)
				(type default)
			)
			(layer "F.Fab")
		)
		(fp_line
			(start -0.67945 0.3048)
			(end -0.67945 -0.305054)
			(stroke
				(width 0.1)
				(type default)
			)
			(layer "F.Fab")
		)
		(fp_line
			(start -0.12065 -0.305054)
			(end -0.12065 -0.2794)
			(stroke
				(width 0.1)
				(type default)
			)
			(layer "F.Fab")
		)
		(fp_line
			(start -0.12065 -0.2794)
			(end 0.12065 -0.2794)
			(stroke
				(width 0.1)
				(type default)
			)
			(layer "F.Fab")
		)
		(fp_line
			(start -0.12065 0.2794)
			(end -0.12065 0.3048)
			(stroke
				(width 0.1)
				(type default)
			)
			(layer "F.Fab")
		)
		(fp_line
			(start -0.12065 0.3048)
			(end -0.67945 0.3048)
			(stroke
				(width 0.1)
				(type default)
			)
			(layer "F.Fab")
		)
		(fp_line
			(start 0.120396 0.2794)
			(end -0.12065 0.2794)
			(stroke
				(width 0.1)
				(type default)
			)
			(layer "F.Fab")
		)
		(fp_line
			(start 0.120396 0.3048)
			(end 0.120396 0.2794)
			(stroke
				(width 0.1)
				(type default)
			)
			(layer "F.Fab")
		)
		(fp_line
			(start 0.12065 -0.3048)
			(end 0.67945 -0.3048)
			(stroke
				(width 0.1)
				(type default)
			)
			(layer "F.Fab")
		)
		(fp_line
			(start 0.12065 -0.2794)
			(end 0.12065 -0.3048)
			(stroke
				(width 0.1)
				(type default)
			)
			(layer "F.Fab")
		)
		(fp_line
			(start 0.67945 -0.3048)
			(end 0.67945 0.3048)
			(stroke
				(width 0.1)
				(type default)
			)
			(layer "F.Fab")
		)
		(fp_line
			(start 0.67945 0.3048)
			(end 0.120396 0.3048)
			(stroke
				(width 0.1)
				(type default)
			)
			(layer "F.Fab")
		)
		(pad "1" smd rect
			(at -0.40005 0 180)
			(size 0.4572 0.508)
			(layers "F.Cu" "F.Mask" "F.Paste")
			(net "P12V_AUX_ADC")
		)
		(pad "2" smd rect
			(at 0.40005 0 180)
			(size 0.4572 0.508)
			(layers "F.Cu" "F.Mask" "F.Paste")
			(net "P12V_AUX_ADC_MAM")
		)
	)
	(footprint ""
		(layer "F.Cu")
		(at 49.849532 -343.716864 180)
		(property "Reference" "PC174"
			(at 0 0 180)
			(layer "F.SilkS")
			(hide yes)
			(effects
				(font
					(size 1.27 1.27)
				)
			)
		)
		(property "Value" ""
			(at 0 0 180)
			(layer "F.Fab")
			(effects
				(font
					(size 1.27 1.27)
				)
			)
		)
		(duplicate_pad_numbers_are_jumpers no)
		(fp_line
			(start 0.7874 0.4064)
			(end -0.7874 0.4064)
			(stroke
				(width 0.1524)
				(type default)
			)
			(layer "F.SilkS")
		)
		(fp_line
			(start 0.7874 -0.4064)
			(end 0.7874 0.4064)
			(stroke
				(width 0.1524)
				(type default)
			)
			(layer "F.SilkS")
		)
		(fp_line
			(start -0.7874 0.4064)
			(end -0.7874 -0.4064)
			(stroke
				(width 0.1524)
				(type default)
			)
			(layer "F.SilkS")
		)
		(fp_line
			(start -0.7874 -0.4064)
			(end 0.7874 -0.4064)
			(stroke
				(width 0.1524)
				(type default)
			)
			(layer "F.SilkS")
		)
		(fp_line
			(start 0.67945 0.3048)
			(end 0.120396 0.3048)
			(stroke
				(width 0.1)
				(type default)
			)
			(layer "F.Fab")
		)
		(fp_line
			(start 0.67945 -0.3048)
			(end 0.67945 0.3048)
			(stroke
				(width 0.1)
				(type default)
			)
			(layer "F.Fab")
		)
		(fp_line
			(start 0.12065 -0.2794)
			(end 0.12065 -0.3048)
			(stroke
				(width 0.1)
				(type default)
			)
			(layer "F.Fab")
		)
		(fp_line
			(start 0.12065 -0.3048)
			(end 0.67945 -0.3048)
			(stroke
				(width 0.1)
				(type default)
			)
			(layer "F.Fab")
		)
		(fp_line
			(start 0.120396 0.3048)
			(end 0.120396 0.2794)
			(stroke
				(width 0.1)
				(type default)
			)
			(layer "F.Fab")
		)
		(fp_line
			(start 0.120396 0.2794)
			(end -0.12065 0.2794)
			(stroke
				(width 0.1)
				(type default)
			)
			(layer "F.Fab")
		)
		(fp_line
			(start -0.12065 0.3048)
			(end -0.67945 0.3048)
			(stroke
				(width 0.1)
				(type default)
			)
			(layer "F.Fab")
		)
		(fp_line
			(start -0.12065 0.2794)
			(end -0.12065 0.3048)
			(stroke
				(width 0.1)
				(type default)
			)
			(layer "F.Fab")
		)
		(fp_line
			(start -0.12065 -0.2794)
			(end 0.12065 -0.2794)
			(stroke
				(width 0.1)
				(type default)
			)
			(layer "F.Fab")
		)
		(fp_line
			(start -0.12065 -0.305054)
			(end -0.12065 -0.2794)
			(stroke
				(width 0.1)
				(type default)
			)
			(layer "F.Fab")
		)
		(fp_line
			(start -0.67945 0.3048)
			(end -0.67945 -0.305054)
			(stroke
				(width 0.1)
				(type default)
			)
			(layer "F.Fab")
		)
		(fp_line
			(start -0.67945 -0.305054)
			(end -0.12065 -0.305054)
			(stroke
				(width 0.1)
				(type default)
			)
			(layer "F.Fab")
		)
		(pad "1" smd circle
			(at -0.40005 0 180)
			(size 0 0)
			(layers "F.Cu" "F.Mask" "F.Paste")
			(net "SW_PVDDIO_P1_SW1")
		)
		(pad "2" smd circle
			(at 0.40005 0 180)
			(size 0 0)
			(layers "F.Cu" "F.Mask" "F.Paste")
			(net "SW_PVDDIO_P1_SW1_RC")
		)
	)
	(footprint ""
		(layer "F.Cu")
		(at 120.396 -434.467 180)
		(property "Reference" "R3494"
			(at 0 0 180)
			(layer "F.SilkS")
			(hide yes)
			(effects
				(font
					(size 1.27 1.27)
				)
			)
		)
		(property "Value" ""
			(at 0 0 180)
			(layer "F.Fab")
			(effects
				(font
					(size 1.27 1.27)
				)
			)
		)
		(duplicate_pad_numbers_are_jumpers no)
		(fp_line
			(start 0.7874 0.4064)
			(end -0.7874 0.4064)
			(stroke
				(width 0.1524)
				(type default)
			)
			(layer "F.SilkS")
		)
		(fp_line
			(start 0.7874 -0.4064)
			(end 0.7874 0.4064)
			(stroke
				(width 0.1524)
				(type default)
			)
			(layer "F.SilkS")
		)
		(fp_line
			(start -0.7874 0.4064)
			(end -0.7874 -0.4064)
			(stroke
				(width 0.1524)
				(type default)
			)
			(layer "F.SilkS")
		)
		(fp_line
			(start -0.7874 -0.4064)
			(end 0.7874 -0.4064)
			(stroke
				(width 0.1524)
				(type default)
			)
			(layer "F.SilkS")
		)
		(fp_line
			(start 0.67945 0.3048)
			(end 0.120396 0.3048)
			(stroke
				(width 0.1)
				(type default)
			)
			(layer "F.Fab")
		)
		(fp_line
			(start 0.67945 -0.3048)
			(end 0.67945 0.3048)
			(stroke
				(width 0.1)
				(type default)
			)
			(layer "F.Fab")
		)
		(fp_line
			(start 0.12065 -0.2794)
			(end 0.12065 -0.3048)
			(stroke
				(width 0.1)
				(type default)
			)
			(layer "F.Fab")
		)
		(fp_line
			(start 0.12065 -0.3048)
			(end 0.67945 -0.3048)
			(stroke
				(width 0.1)
				(type default)
			)
			(layer "F.Fab")
		)
		(fp_line
			(start 0.120396 0.3048)
			(end 0.120396 0.2794)
			(stroke
				(width 0.1)
				(type default)
			)
			(layer "F.Fab")
		)
		(fp_line
			(start 0.120396 0.2794)
			(end -0.12065 0.2794)
			(stroke
				(width 0.1)
				(type default)
			)
			(layer "F.Fab")
		)
		(fp_line
			(start -0.12065 0.3048)
			(end -0.67945 0.3048)
			(stroke
				(width 0.1)
				(type default)
			)
			(layer "F.Fab")
		)
		(fp_line
			(start -0.12065 0.2794)
			(end -0.12065 0.3048)
			(stroke
				(width 0.1)
				(type default)
			)
			(layer "F.Fab")
		)
		(fp_line
			(start -0.12065 -0.2794)
			(end 0.12065 -0.2794)
			(stroke
				(width 0.1)
				(type default)
			)
			(layer "F.Fab")
		)
		(fp_line
			(start -0.12065 -0.305054)
			(end -0.12065 -0.2794)
			(stroke
				(width 0.1)
				(type default)
			)
			(layer "F.Fab")
		)
		(fp_line
			(start -0.67945 0.3048)
			(end -0.67945 -0.305054)
			(stroke
				(width 0.1)
				(type default)
			)
			(layer "F.Fab")
		)
		(fp_line
			(start -0.67945 -0.305054)
			(end -0.12065 -0.305054)
			(stroke
				(width 0.1)
				(type default)
			)
			(layer "F.Fab")
		)
		(pad "1" smd circle
			(at -0.40005 0 180)
			(size 0 0)
			(layers "F.Cu" "F.Mask" "F.Paste")
			(net "P3V3_AUX")
		)
		(pad "2" smd circle
			(at 0.40005 0 180)
			(size 0 0)
			(layers "F.Cu" "F.Mask" "F.Paste")
			(net "GPU_FPGA_EROT_RECOV_BUF_R_N")
		)
	)
	(footprint ""
		(layer "F.Cu")
		(at 452.13905 -48.462946)
		(property "Reference" "R1571"
			(at 0 0 0)
			(layer "F.SilkS")
			(hide yes)
			(effects
				(font
					(size 1.27 1.27)
				)
			)
		)
		(property "Value" ""
			(at 0 0 0)
			(layer "F.Fab")
			(effects
				(font
					(size 1.27 1.27)
				)
			)
		)
		(duplicate_pad_numbers_are_jumpers no)
		(fp_line
			(start -0.7874 -0.4064)
			(end 0.7874 -0.4064)
			(stroke
				(width 0.1524)
				(type default)
			)
			(layer "F.SilkS")
		)
		(fp_line
			(start -0.7874 0.4064)
			(end -0.7874 -0.4064)
			(stroke
				(width 0.1524)
				(type default)
			)
			(layer "F.SilkS")
		)
		(fp_line
			(start 0.7874 -0.4064)
			(end 0.7874 0.4064)
			(stroke
				(width 0.1524)
				(type default)
			)
			(layer "F.SilkS")
		)
		(fp_line
			(start 0.7874 0.4064)
			(end -0.7874 0.4064)
			(stroke
				(width 0.1524)
				(type default)
			)
			(layer "F.SilkS")
		)
		(fp_line
			(start -0.67945 -0.305054)
			(end -0.12065 -0.305054)
			(stroke
				(width 0.1)
				(type default)
			)
			(layer "F.Fab")
		)
		(fp_line
			(start -0.67945 0.3048)
			(end -0.67945 -0.305054)
			(stroke
				(width 0.1)
				(type default)
			)
			(layer "F.Fab")
		)
		(fp_line
			(start -0.12065 -0.305054)
			(end -0.12065 -0.2794)
			(stroke
				(width 0.1)
				(type default)
			)
			(layer "F.Fab")
		)
		(fp_line
			(start -0.12065 -0.2794)
			(end 0.12065 -0.2794)
			(stroke
				(width 0.1)
				(type default)
			)
			(layer "F.Fab")
		)
		(fp_line
			(start -0.12065 0.2794)
			(end -0.12065 0.3048)
			(stroke
				(width 0.1)
				(type default)
			)
			(layer "F.Fab")
		)
		(fp_line
			(start -0.12065 0.3048)
			(end -0.67945 0.3048)
			(stroke
				(width 0.1)
				(type default)
			)
			(layer "F.Fab")
		)
		(fp_line
			(start 0.120396 0.2794)
			(end -0.12065 0.2794)
			(stroke
				(width 0.1)
				(type default)
			)
			(layer "F.Fab")
		)
		(fp_line
			(start 0.120396 0.3048)
			(end 0.120396 0.2794)
			(stroke
				(width 0.1)
				(type default)
			)
			(layer "F.Fab")
		)
		(fp_line
			(start 0.12065 -0.3048)
			(end 0.67945 -0.3048)
			(stroke
				(width 0.1)
				(type default)
			)
			(layer "F.Fab")
		)
		(fp_line
			(start 0.12065 -0.2794)
			(end 0.12065 -0.3048)
			(stroke
				(width 0.1)
				(type default)
			)
			(layer "F.Fab")
		)
		(fp_line
			(start 0.67945 -0.3048)
			(end 0.67945 0.3048)
			(stroke
				(width 0.1)
				(type default)
			)
			(layer "F.Fab")
		)
		(fp_line
			(start 0.67945 0.3048)
			(end 0.120396 0.3048)
			(stroke
				(width 0.1)
				(type default)
			)
			(layer "F.Fab")
		)
		(pad "1" smd circle
			(at -0.40005 0)
			(size 0 0)
			(layers "F.Cu" "F.Mask" "F.Paste")
			(net "PWRGD_P5V_AUX")
		)
		(pad "2" smd circle
			(at 0.40005 0)
			(size 0 0)
			(layers "F.Cu" "F.Mask" "F.Paste")
			(net "P3V3_AUX_EN")
		)
	)
	(footprint ""
		(layer "F.Cu")
		(at 277.650956 -429.572166 180)
		(property "Reference" "R4265"
			(at 0 0 180)
			(layer "F.SilkS")
			(hide yes)
			(effects
				(font
					(size 1.27 1.27)
				)
			)
		)
		(property "Value" ""
			(at 0 0 180)
			(layer "F.Fab")
			(effects
				(font
					(size 1.27 1.27)
				)
			)
		)
		(duplicate_pad_numbers_are_jumpers no)
		(fp_line
			(start 0.7874 0.4064)
			(end -0.7874 0.4064)
			(stroke
				(width 0.1524)
				(type default)
			)
			(layer "F.SilkS")
		)
		(fp_line
			(start 0.7874 -0.4064)
			(end 0.7874 0.4064)
			(stroke
				(width 0.1524)
				(type default)
			)
			(layer "F.SilkS")
		)
		(fp_line
			(start -0.7874 0.4064)
			(end -0.7874 -0.4064)
			(stroke
				(width 0.1524)
				(type default)
			)
			(layer "F.SilkS")
		)
		(fp_line
			(start -0.7874 -0.4064)
			(end 0.7874 -0.4064)
			(stroke
				(width 0.1524)
				(type default)
			)
			(layer "F.SilkS")
		)
		(fp_line
			(start 0.67945 0.3048)
			(end 0.120396 0.3048)
			(stroke
				(width 0.1)
				(type default)
			)
			(layer "F.Fab")
		)
		(fp_line
			(start 0.67945 -0.3048)
			(end 0.67945 0.3048)
			(stroke
				(width 0.1)
				(type default)
			)
			(layer "F.Fab")
		)
		(fp_line
			(start 0.12065 -0.2794)
			(end 0.12065 -0.3048)
			(stroke
				(width 0.1)
				(type default)
			)
			(layer "F.Fab")
		)
		(fp_line
			(start 0.12065 -0.3048)
			(end 0.67945 -0.3048)
			(stroke
				(width 0.1)
				(type default)
			)
			(layer "F.Fab")
		)
		(fp_line
			(start 0.120396 0.3048)
			(end 0.120396 0.2794)
			(stroke
				(width 0.1)
				(type default)
			)
			(layer "F.Fab")
		)
		(fp_line
			(start 0.120396 0.2794)
			(end -0.12065 0.2794)
			(stroke
				(width 0.1)
				(type default)
			)
			(layer "F.Fab")
		)
		(fp_line
			(start -0.12065 0.3048)
			(end -0.67945 0.3048)
			(stroke
				(width 0.1)
				(type default)
			)
			(layer "F.Fab")
		)
		(fp_line
			(start -0.12065 0.2794)
			(end -0.12065 0.3048)
			(stroke
				(width 0.1)
				(type default)
			)
			(layer "F.Fab")
		)
		(fp_line
			(start -0.12065 -0.2794)
			(end 0.12065 -0.2794)
			(stroke
				(width 0.1)
				(type default)
			)
			(layer "F.Fab")
		)
		(fp_line
			(start -0.12065 -0.305054)
			(end -0.12065 -0.2794)
			(stroke
				(width 0.1)
				(type default)
			)
			(layer "F.Fab")
		)
		(fp_line
			(start -0.67945 0.3048)
			(end -0.67945 -0.305054)
			(stroke
				(width 0.1)
				(type default)
			)
			(layer "F.Fab")
		)
		(fp_line
			(start -0.67945 -0.305054)
			(end -0.12065 -0.305054)
			(stroke
				(width 0.1)
				(type default)
			)
			(layer "F.Fab")
		)
		(pad "1" smd circle
			(at -0.40005 0 180)
			(size 0 0)
			(layers "F.Cu" "F.Mask" "F.Paste")
			(net "PWRGD_P3V3_AUX_PDB_BUF_R")
		)
		(pad "2" smd circle
			(at 0.40005 0 180)
			(size 0 0)
			(layers "F.Cu" "F.Mask" "F.Paste")
			(net "GND")
		)
	)
	(footprint ""
		(layer "F.Cu")
		(at 418.896038 -353.763072 90)
		(property "Reference" "PR411"
			(at 0 0 90)
			(layer "F.SilkS")
			(hide yes)
			(effects
				(font
					(size 1.27 1.27)
				)
			)
		)
		(property "Value" ""
			(at 0 0 90)
			(layer "F.Fab")
			(effects
				(font
					(size 1.27 1.27)
				)
			)
		)
		(duplicate_pad_numbers_are_jumpers no)
		(fp_line
			(start 0.7874 -0.4064)
			(end 0.7874 0.4064)
			(stroke
				(width 0.1524)
				(type default)
			)
			(layer "F.SilkS")
		)
		(fp_line
			(start -0.7874 -0.4064)
			(end 0.7874 -0.4064)
			(stroke
				(width 0.1524)
				(type default)
			)
			(layer "F.SilkS")
		)
		(fp_line
			(start 0.7874 0.4064)
			(end -0.7874 0.4064)
			(stroke
				(width 0.1524)
				(type default)
			)
			(layer "F.SilkS")
		)
		(fp_line
			(start -0.7874 0.4064)
			(end -0.7874 -0.4064)
			(stroke
				(width 0.1524)
				(type default)
			)
			(layer "F.SilkS")
		)
		(fp_line
			(start -0.12065 -0.305054)
			(end -0.12065 -0.2794)
			(stroke
				(width 0.1)
				(type default)
			)
			(layer "F.Fab")
		)
		(fp_line
			(start -0.67945 -0.305054)
			(end -0.12065 -0.305054)
			(stroke
				(width 0.1)
				(type default)
			)
			(layer "F.Fab")
		)
		(fp_line
			(start 0.67945 -0.3048)
			(end 0.67945 0.3048)
			(stroke
				(width 0.1)
				(type default)
			)
			(layer "F.Fab")
		)
		(fp_line
			(start 0.12065 -0.3048)
			(end 0.67945 -0.3048)
			(stroke
				(width 0.1)
				(type default)
			)
			(layer "F.Fab")
		)
		(fp_line
			(start 0.12065 -0.2794)
			(end 0.12065 -0.3048)
			(stroke
				(width 0.1)
				(type default)
			)
			(layer "F.Fab")
		)
		(fp_line
			(start -0.12065 -0.2794)
			(end 0.12065 -0.2794)
			(stroke
				(width 0.1)
				(type default)
			)
			(layer "F.Fab")
		)
		(fp_line
			(start 0.120396 0.2794)
			(end -0.12065 0.2794)
			(stroke
				(width 0.1)
				(type default)
			)
			(layer "F.Fab")
		)
		(fp_line
			(start -0.12065 0.2794)
			(end -0.12065 0.3048)
			(stroke
				(width 0.1)
				(type default)
			)
			(layer "F.Fab")
		)
		(fp_line
			(start 0.67945 0.3048)
			(end 0.120396 0.3048)
			(stroke
				(width 0.1)
				(type default)
			)
			(layer "F.Fab")
		)
		(fp_line
			(start 0.120396 0.3048)
			(end 0.120396 0.2794)
			(stroke
				(width 0.1)
				(type default)
			)
			(layer "F.Fab")
		)
		(fp_line
			(start -0.12065 0.3048)
			(end -0.67945 0.3048)
			(stroke
				(width 0.1)
				(type default)
			)
			(layer "F.Fab")
		)
		(fp_line
			(start -0.67945 0.3048)
			(end -0.67945 -0.305054)
			(stroke
				(width 0.1)
				(type default)
			)
			(layer "F.Fab")
		)
		(pad "1" smd circle
			(at -0.40005 0 90)
			(size 0 0)
			(layers "F.Cu" "F.Mask" "F.Paste")
			(net "PVDD11_S3_P0_PVCC")
		)
		(pad "2" smd circle
			(at 0.40005 0 90)
			(size 0 0)
			(layers "F.Cu" "F.Mask" "F.Paste")
			(net "P5V_AUX")
		)
	)
	(footprint ""
		(layer "F.Cu")
		(at 240.792 -287.0708 180)
		(property "Reference" "PC6902"
			(at 0 0 180)
			(layer "F.SilkS")
			(hide yes)
			(effects
				(font
					(size 1.27 1.27)
				)
			)
		)
		(property "Value" ""
			(at 0 0 180)
			(layer "F.Fab")
			(effects
				(font
					(size 1.27 1.27)
				)
			)
		)
		(duplicate_pad_numbers_are_jumpers no)
		(fp_line
			(start 1.524 0.762)
			(end -1.524 0.762)
			(stroke
				(width 0.1524)
				(type default)
			)
			(layer "F.SilkS")
		)
		(fp_line
			(start 1.524 -0.762)
			(end 1.524 0.762)
			(stroke
				(width 0.1524)
				(type default)
			)
			(layer "F.SilkS")
		)
		(fp_line
			(start -1.524 0.762)
			(end -1.524 -0.762)
			(stroke
				(width 0.1524)
				(type default)
			)
			(layer "F.SilkS")
		)
		(fp_line
			(start -1.524 -0.762)
			(end 1.524 -0.762)
			(stroke
				(width 0.1524)
				(type default)
			)
			(layer "F.SilkS")
		)
		(fp_line
			(start 1.1049 0.724916)
			(end 1.1049 -0.724916)
			(stroke
				(width 0.1)
				(type default)
			)
			(layer "F.Fab")
		)
		(fp_line
			(start 1.1049 -0.724916)
			(end -1.1049 -0.724916)
			(stroke
				(width 0.1)
				(type default)
			)
			(layer "F.Fab")
		)
		(fp_line
			(start -1.1049 0.724916)
			(end 1.1049 0.724916)
			(stroke
				(width 0.1)
				(type default)
			)
			(layer "F.Fab")
		)
		(fp_line
			(start -1.1049 -0.724916)
			(end -1.1049 0.724916)
			(stroke
				(width 0.1)
				(type default)
			)
			(layer "F.Fab")
		)
		(pad "1" smd rect
			(at -0.889 0)
			(size 1.016 1.27)
			(layers "F.Cu" "F.Mask" "F.Paste")
			(net "SW_P12V_AUX_P1V8_RETIMER_CPU0_FLT")
		)
		(pad "2" smd rect
			(at 0.889 0)
			(size 1.016 1.27)
			(layers "F.Cu" "F.Mask" "F.Paste")
			(net "GND")
		)
	)
	(footprint ""
		(layer "F.Cu")
		(at 392.311382 -416.899344 -90)
		(property "Reference" "C6580"
			(at 0 0 270)
			(layer "F.SilkS")
			(hide yes)
			(effects
				(font
					(size 1.27 1.27)
				)
			)
		)
		(property "Value" ""
			(at 0 0 270)
			(layer "F.Fab")
			(effects
				(font
					(size 1.27 1.27)
				)
			)
		)
		(duplicate_pad_numbers_are_jumpers no)
		(fp_line
			(start -0.299974 0.150114)
			(end -0.299974 -0.150114)
			(stroke
				(width 0.1)
				(type default)
			)
			(layer "F.Fab")
		)
		(fp_line
			(start 0.299974 0.150114)
			(end -0.299974 0.150114)
			(stroke
				(width 0.1)
				(type default)
			)
			(layer "F.Fab")
		)
		(fp_line
			(start -0.299974 -0.150114)
			(end 0.299974 -0.150114)
			(stroke
				(width 0.1)
				(type default)
			)
			(layer "F.Fab")
		)
		(fp_line
			(start 0.299974 -0.150114)
			(end 0.299974 0.150114)
			(stroke
				(width 0.1)
				(type default)
			)
			(layer "F.Fab")
		)
		(pad "1" smd rect
			(at -0.2667 0 270)
			(size 0.3048 0.381)
			(layers "F.Cu" "F.Mask" "F.Paste")
			(net "P5E_CPU0_P2_TX_BUF_C_DN<7>")
		)
		(pad "2" smd rect
			(at 0.2667 0 270)
			(size 0.3048 0.381)
			(layers "F.Cu" "F.Mask" "F.Paste")
			(net "P5E_CPU0_P2_TX_BUF_DN<7>")
		)
	)
	(footprint ""
		(layer "F.Cu")
		(at 58.297064 -39.003986 90)
		(property "Reference" "R1182"
			(at 0 0 90)
			(layer "F.SilkS")
			(hide yes)
			(effects
				(font
					(size 1.27 1.27)
				)
			)
		)
		(property "Value" ""
			(at 0 0 90)
			(layer "F.Fab")
			(effects
				(font
					(size 1.27 1.27)
				)
			)
		)
		(duplicate_pad_numbers_are_jumpers no)
		(fp_line
			(start 0.7874 -0.4064)
			(end 0.7874 0.4064)
			(stroke
				(width 0.1524)
				(type default)
			)
			(layer "F.SilkS")
		)
		(fp_line
			(start -0.7874 -0.4064)
			(end 0.7874 -0.4064)
			(stroke
				(width 0.1524)
				(type default)
			)
			(layer "F.SilkS")
		)
		(fp_line
			(start 0.7874 0.4064)
			(end -0.7874 0.4064)
			(stroke
				(width 0.1524)
				(type default)
			)
			(layer "F.SilkS")
		)
		(fp_line
			(start -0.7874 0.4064)
			(end -0.7874 -0.4064)
			(stroke
				(width 0.1524)
				(type default)
			)
			(layer "F.SilkS")
		)
		(fp_line
			(start -0.12065 -0.305054)
			(end -0.12065 -0.2794)
			(stroke
				(width 0.1)
				(type default)
			)
			(layer "F.Fab")
		)
		(fp_line
			(start -0.67945 -0.305054)
			(end -0.12065 -0.305054)
			(stroke
				(width 0.1)
				(type default)
			)
			(layer "F.Fab")
		)
		(fp_line
			(start 0.67945 -0.3048)
			(end 0.67945 0.3048)
			(stroke
				(width 0.1)
				(type default)
			)
			(layer "F.Fab")
		)
		(fp_line
			(start 0.12065 -0.3048)
			(end 0.67945 -0.3048)
			(stroke
				(width 0.1)
				(type default)
			)
			(layer "F.Fab")
		)
		(fp_line
			(start 0.12065 -0.2794)
			(end 0.12065 -0.3048)
			(stroke
				(width 0.1)
				(type default)
			)
			(layer "F.Fab")
		)
		(fp_line
			(start -0.12065 -0.2794)
			(end 0.12065 -0.2794)
			(stroke
				(width 0.1)
				(type default)
			)
			(layer "F.Fab")
		)
		(fp_line
			(start 0.120396 0.2794)
			(end -0.12065 0.2794)
			(stroke
				(width 0.1)
				(type default)
			)
			(layer "F.Fab")
		)
		(fp_line
			(start -0.12065 0.2794)
			(end -0.12065 0.3048)
			(stroke
				(width 0.1)
				(type default)
			)
			(layer "F.Fab")
		)
		(fp_line
			(start 0.67945 0.3048)
			(end 0.120396 0.3048)
			(stroke
				(width 0.1)
				(type default)
			)
			(layer "F.Fab")
		)
		(fp_line
			(start 0.120396 0.3048)
			(end 0.120396 0.2794)
			(stroke
				(width 0.1)
				(type default)
			)
			(layer "F.Fab")
		)
		(fp_line
			(start -0.12065 0.3048)
			(end -0.67945 0.3048)
			(stroke
				(width 0.1)
				(type default)
			)
			(layer "F.Fab")
		)
		(fp_line
			(start -0.67945 0.3048)
			(end -0.67945 -0.305054)
			(stroke
				(width 0.1)
				(type default)
			)
			(layer "F.Fab")
		)
		(pad "1" smd circle
			(at -0.40005 0 90)
			(size 0 0)
			(layers "F.Cu" "F.Mask" "F.Paste")
			(net "HP_LVC3_OCP_V3_2_P12V_PWRGD")
		)
		(pad "2" smd circle
			(at 0.40005 0 90)
			(size 0 0)
			(layers "F.Cu" "F.Mask" "F.Paste")
			(net "P3V3_OCP_EN_2_R")
		)
	)
	(footprint ""
		(layer "F.Cu")
		(at 282.575 -423.418 -90)
		(property "Reference" "R4491"
			(at 0 0 270)
			(layer "F.SilkS")
			(hide yes)
			(effects
				(font
					(size 1.27 1.27)
				)
			)
		)
		(property "Value" ""
			(at 0 0 270)
			(layer "F.Fab")
			(effects
				(font
					(size 1.27 1.27)
				)
			)
		)
		(duplicate_pad_numbers_are_jumpers no)
		(fp_line
			(start -0.7874 0.4064)
			(end -0.7874 -0.4064)
			(stroke
				(width 0.1524)
				(type default)
			)
			(layer "F.SilkS")
		)
		(fp_line
			(start 0.7874 0.4064)
			(end -0.7874 0.4064)
			(stroke
				(width 0.1524)
				(type default)
			)
			(layer "F.SilkS")
		)
		(fp_line
			(start -0.7874 -0.4064)
			(end 0.7874 -0.4064)
			(stroke
				(width 0.1524)
				(type default)
			)
			(layer "F.SilkS")
		)
		(fp_line
			(start 0.7874 -0.4064)
			(end 0.7874 0.4064)
			(stroke
				(width 0.1524)
				(type default)
			)
			(layer "F.SilkS")
		)
		(fp_line
			(start -0.67945 0.3048)
			(end -0.67945 -0.305054)
			(stroke
				(width 0.1)
				(type default)
			)
			(layer "F.Fab")
		)
		(fp_line
			(start -0.12065 0.3048)
			(end -0.67945 0.3048)
			(stroke
				(width 0.1)
				(type default)
			)
			(layer "F.Fab")
		)
		(fp_line
			(start 0.120396 0.3048)
			(end 0.120396 0.2794)
			(stroke
				(width 0.1)
				(type default)
			)
			(layer "F.Fab")
		)
		(fp_line
			(start 0.67945 0.3048)
			(end 0.120396 0.3048)
			(stroke
				(width 0.1)
				(type default)
			)
			(layer "F.Fab")
		)
		(fp_line
			(start -0.12065 0.2794)
			(end -0.12065 0.3048)
			(stroke
				(width 0.1)
				(type default)
			)
			(layer "F.Fab")
		)
		(fp_line
			(start 0.120396 0.2794)
			(end -0.12065 0.2794)
			(stroke
				(width 0.1)
				(type default)
			)
			(layer "F.Fab")
		)
		(fp_line
			(start -0.12065 -0.2794)
			(end 0.12065 -0.2794)
			(stroke
				(width 0.1)
				(type default)
			)
			(layer "F.Fab")
		)
		(fp_line
			(start 0.12065 -0.2794)
			(end 0.12065 -0.3048)
			(stroke
				(width 0.1)
				(type default)
			)
			(layer "F.Fab")
		)
		(fp_line
			(start 0.12065 -0.3048)
			(end 0.67945 -0.3048)
			(stroke
				(width 0.1)
				(type default)
			)
			(layer "F.Fab")
		)
		(fp_line
			(start 0.67945 -0.3048)
			(end 0.67945 0.3048)
			(stroke
				(width 0.1)
				(type default)
			)
			(layer "F.Fab")
		)
		(fp_line
			(start -0.67945 -0.305054)
			(end -0.12065 -0.305054)
			(stroke
				(width 0.1)
				(type default)
			)
			(layer "F.Fab")
		)
		(fp_line
			(start -0.12065 -0.305054)
			(end -0.12065 -0.2794)
			(stroke
				(width 0.1)
				(type default)
			)
			(layer "F.Fab")
		)
		(pad "1" smd circle
			(at -0.40005 0 270)
			(size 0 0)
			(layers "F.Cu" "F.Mask" "F.Paste")
			(net "P3V3_AUX")
		)
		(pad "2" smd circle
			(at 0.40005 0 270)
			(size 0 0)
			(layers "F.Cu" "F.Mask" "F.Paste")
			(net "CLK_9ZXL045_P0_HIBW")
		)
	)
	(footprint ""
		(layer "F.Cu")
		(at 59.508644 -180.746908)
		(property "Reference" "PR162"
			(at 0 0 0)
			(layer "F.SilkS")
			(hide yes)
			(effects
				(font
					(size 1.27 1.27)
				)
			)
		)
		(property "Value" ""
			(at 0 0 0)
			(layer "F.Fab")
			(effects
				(font
					(size 1.27 1.27)
				)
			)
		)
		(duplicate_pad_numbers_are_jumpers no)
		(fp_line
			(start -0.7874 -0.4064)
			(end 0.7874 -0.4064)
			(stroke
				(width 0.1524)
				(type default)
			)
			(layer "F.SilkS")
		)
		(fp_line
			(start -0.7874 0.4064)
			(end -0.7874 -0.4064)
			(stroke
				(width 0.1524)
				(type default)
			)
			(layer "F.SilkS")
		)
		(fp_line
			(start 0.7874 -0.4064)
			(end 0.7874 0.4064)
			(stroke
				(width 0.1524)
				(type default)
			)
			(layer "F.SilkS")
		)
		(fp_line
			(start 0.7874 0.4064)
			(end -0.7874 0.4064)
			(stroke
				(width 0.1524)
				(type default)
			)
			(layer "F.SilkS")
		)
		(fp_line
			(start -0.67945 -0.305054)
			(end -0.12065 -0.305054)
			(stroke
				(width 0.1)
				(type default)
			)
			(layer "F.Fab")
		)
		(fp_line
			(start -0.67945 0.3048)
			(end -0.67945 -0.305054)
			(stroke
				(width 0.1)
				(type default)
			)
			(layer "F.Fab")
		)
		(fp_line
			(start -0.12065 -0.305054)
			(end -0.12065 -0.2794)
			(stroke
				(width 0.1)
				(type default)
			)
			(layer "F.Fab")
		)
		(fp_line
			(start -0.12065 -0.2794)
			(end 0.12065 -0.2794)
			(stroke
				(width 0.1)
				(type default)
			)
			(layer "F.Fab")
		)
		(fp_line
			(start -0.12065 0.2794)
			(end -0.12065 0.3048)
			(stroke
				(width 0.1)
				(type default)
			)
			(layer "F.Fab")
		)
		(fp_line
			(start -0.12065 0.3048)
			(end -0.67945 0.3048)
			(stroke
				(width 0.1)
				(type default)
			)
			(layer "F.Fab")
		)
		(fp_line
			(start 0.120396 0.2794)
			(end -0.12065 0.2794)
			(stroke
				(width 0.1)
				(type default)
			)
			(layer "F.Fab")
		)
		(fp_line
			(start 0.120396 0.3048)
			(end 0.120396 0.2794)
			(stroke
				(width 0.1)
				(type default)
			)
			(layer "F.Fab")
		)
		(fp_line
			(start 0.12065 -0.3048)
			(end 0.67945 -0.3048)
			(stroke
				(width 0.1)
				(type default)
			)
			(layer "F.Fab")
		)
		(fp_line
			(start 0.12065 -0.2794)
			(end 0.12065 -0.3048)
			(stroke
				(width 0.1)
				(type default)
			)
			(layer "F.Fab")
		)
		(fp_line
			(start 0.67945 -0.3048)
			(end 0.67945 0.3048)
			(stroke
				(width 0.1)
				(type default)
			)
			(layer "F.Fab")
		)
		(fp_line
			(start 0.67945 0.3048)
			(end 0.120396 0.3048)
			(stroke
				(width 0.1)
				(type default)
			)
			(layer "F.Fab")
		)
		(pad "1" smd circle
			(at -0.40005 0)
			(size 0 0)
			(layers "F.Cu" "F.Mask" "F.Paste")
			(net "VSENSE_VSS_SENSE_A_P1")
		)
		(pad "2" smd circle
			(at 0.40005 0)
			(size 0 0)
			(layers "F.Cu" "F.Mask" "F.Paste")
			(net "GND")
		)
	)
	(footprint ""
		(layer "F.Cu")
		(at 360.583988 -409.388818 -90)
		(property "Reference" "R4515"
			(at 0 0 270)
			(layer "F.SilkS")
			(hide yes)
			(effects
				(font
					(size 1.27 1.27)
				)
			)
		)
		(property "Value" ""
			(at 0 0 270)
			(layer "F.Fab")
			(effects
				(font
					(size 1.27 1.27)
				)
			)
		)
		(duplicate_pad_numbers_are_jumpers no)
		(fp_line
			(start -0.7874 0.4064)
			(end -0.7874 -0.4064)
			(stroke
				(width 0.1524)
				(type default)
			)
			(layer "F.SilkS")
		)
		(fp_line
			(start 0.7874 0.4064)
			(end -0.7874 0.4064)
			(stroke
				(width 0.1524)
				(type default)
			)
			(layer "F.SilkS")
		)
		(fp_line
			(start -0.7874 -0.4064)
			(end 0.7874 -0.4064)
			(stroke
				(width 0.1524)
				(type default)
			)
			(layer "F.SilkS")
		)
		(fp_line
			(start 0.7874 -0.4064)
			(end 0.7874 0.4064)
			(stroke
				(width 0.1524)
				(type default)
			)
			(layer "F.SilkS")
		)
		(fp_line
			(start -0.67945 0.3048)
			(end -0.67945 -0.305054)
			(stroke
				(width 0.1)
				(type default)
			)
			(layer "F.Fab")
		)
		(fp_line
			(start -0.12065 0.3048)
			(end -0.67945 0.3048)
			(stroke
				(width 0.1)
				(type default)
			)
			(layer "F.Fab")
		)
		(fp_line
			(start 0.120396 0.3048)
			(end 0.120396 0.2794)
			(stroke
				(width 0.1)
				(type default)
			)
			(layer "F.Fab")
		)
		(fp_line
			(start 0.67945 0.3048)
			(end 0.120396 0.3048)
			(stroke
				(width 0.1)
				(type default)
			)
			(layer "F.Fab")
		)
		(fp_line
			(start -0.12065 0.2794)
			(end -0.12065 0.3048)
			(stroke
				(width 0.1)
				(type default)
			)
			(layer "F.Fab")
		)
		(fp_line
			(start 0.120396 0.2794)
			(end -0.12065 0.2794)
			(stroke
				(width 0.1)
				(type default)
			)
			(layer "F.Fab")
		)
		(fp_line
			(start -0.12065 -0.2794)
			(end 0.12065 -0.2794)
			(stroke
				(width 0.1)
				(type default)
			)
			(layer "F.Fab")
		)
		(fp_line
			(start 0.12065 -0.2794)
			(end 0.12065 -0.3048)
			(stroke
				(width 0.1)
				(type default)
			)
			(layer "F.Fab")
		)
		(fp_line
			(start 0.12065 -0.3048)
			(end 0.67945 -0.3048)
			(stroke
				(width 0.1)
				(type default)
			)
			(layer "F.Fab")
		)
		(fp_line
			(start 0.67945 -0.3048)
			(end 0.67945 0.3048)
			(stroke
				(width 0.1)
				(type default)
			)
			(layer "F.Fab")
		)
		(fp_line
			(start -0.67945 -0.305054)
			(end -0.12065 -0.305054)
			(stroke
				(width 0.1)
				(type default)
			)
			(layer "F.Fab")
		)
		(fp_line
			(start -0.12065 -0.305054)
			(end -0.12065 -0.2794)
			(stroke
				(width 0.1)
				(type default)
			)
			(layer "F.Fab")
		)
		(pad "1" smd circle
			(at -0.40005 0 270)
			(size 0 0)
			(layers "F.Cu" "F.Mask" "F.Paste")
			(net "P3V3_AUX")
		)
		(pad "2" smd circle
			(at 0.40005 0 270)
			(size 0 0)
			(layers "F.Cu" "F.Mask" "F.Paste")
			(net "UART_BMC_BIC_RX")
		)
	)
	(footprint ""
		(layer "F.Cu")
		(at 82.306668 -17.745202)
		(property "Reference" "R3831"
			(at 0 0 0)
			(layer "F.SilkS")
			(hide yes)
			(effects
				(font
					(size 1.27 1.27)
				)
			)
		)
		(property "Value" ""
			(at 0 0 0)
			(layer "F.Fab")
			(effects
				(font
					(size 1.27 1.27)
				)
			)
		)
		(duplicate_pad_numbers_are_jumpers no)
		(fp_line
			(start -0.7874 -0.4064)
			(end 0.7874 -0.4064)
			(stroke
				(width 0.1524)
				(type default)
			)
			(layer "F.SilkS")
		)
		(fp_line
			(start -0.7874 0.4064)
			(end -0.7874 -0.4064)
			(stroke
				(width 0.1524)
				(type default)
			)
			(layer "F.SilkS")
		)
		(fp_line
			(start 0.7874 -0.4064)
			(end 0.7874 0.4064)
			(stroke
				(width 0.1524)
				(type default)
			)
			(layer "F.SilkS")
		)
		(fp_line
			(start 0.7874 0.4064)
			(end -0.7874 0.4064)
			(stroke
				(width 0.1524)
				(type default)
			)
			(layer "F.SilkS")
		)
		(fp_line
			(start -0.67945 -0.305054)
			(end -0.12065 -0.305054)
			(stroke
				(width 0.1)
				(type default)
			)
			(layer "F.Fab")
		)
		(fp_line
			(start -0.67945 0.3048)
			(end -0.67945 -0.305054)
			(stroke
				(width 0.1)
				(type default)
			)
			(layer "F.Fab")
		)
		(fp_line
			(start -0.12065 -0.305054)
			(end -0.12065 -0.2794)
			(stroke
				(width 0.1)
				(type default)
			)
			(layer "F.Fab")
		)
		(fp_line
			(start -0.12065 -0.2794)
			(end 0.12065 -0.2794)
			(stroke
				(width 0.1)
				(type default)
			)
			(layer "F.Fab")
		)
		(fp_line
			(start -0.12065 0.2794)
			(end -0.12065 0.3048)
			(stroke
				(width 0.1)
				(type default)
			)
			(layer "F.Fab")
		)
		(fp_line
			(start -0.12065 0.3048)
			(end -0.67945 0.3048)
			(stroke
				(width 0.1)
				(type default)
			)
			(layer "F.Fab")
		)
		(fp_line
			(start 0.120396 0.2794)
			(end -0.12065 0.2794)
			(stroke
				(width 0.1)
				(type default)
			)
			(layer "F.Fab")
		)
		(fp_line
			(start 0.120396 0.3048)
			(end 0.120396 0.2794)
			(stroke
				(width 0.1)
				(type default)
			)
			(layer "F.Fab")
		)
		(fp_line
			(start 0.12065 -0.3048)
			(end 0.67945 -0.3048)
			(stroke
				(width 0.1)
				(type default)
			)
			(layer "F.Fab")
		)
		(fp_line
			(start 0.12065 -0.2794)
			(end 0.12065 -0.3048)
			(stroke
				(width 0.1)
				(type default)
			)
			(layer "F.Fab")
		)
		(fp_line
			(start 0.67945 -0.3048)
			(end 0.67945 0.3048)
			(stroke
				(width 0.1)
				(type default)
			)
			(layer "F.Fab")
		)
		(fp_line
			(start 0.67945 0.3048)
			(end 0.120396 0.3048)
			(stroke
				(width 0.1)
				(type default)
			)
			(layer "F.Fab")
		)
		(pad "1" smd circle
			(at -0.40005 0)
			(size 0 0)
			(layers "F.Cu" "F.Mask" "F.Paste")
			(net "P12V_OCP_PWRGD_2")
		)
		(pad "2" smd circle
			(at 0.40005 0)
			(size 0 0)
			(layers "F.Cu" "F.Mask" "F.Paste")
			(net "HP_LVC3_OCP_V3_2_P12V_PWRGD")
		)
	)
	(footprint ""
		(layer "F.Cu")
		(at 185.26252 -19.435572 90)
		(property "Reference" "R6065"
			(at 0 0 90)
			(layer "F.SilkS")
			(hide yes)
			(effects
				(font
					(size 1.27 1.27)
				)
			)
		)
		(property "Value" ""
			(at 0 0 90)
			(layer "F.Fab")
			(effects
				(font
					(size 1.27 1.27)
				)
			)
		)
		(duplicate_pad_numbers_are_jumpers no)
		(fp_line
			(start 0.7874 -0.4064)
			(end 0.7874 0.4064)
			(stroke
				(width 0.1524)
				(type default)
			)
			(layer "F.SilkS")
		)
		(fp_line
			(start -0.7874 -0.4064)
			(end 0.7874 -0.4064)
			(stroke
				(width 0.1524)
				(type default)
			)
			(layer "F.SilkS")
		)
		(fp_line
			(start 0.7874 0.4064)
			(end -0.7874 0.4064)
			(stroke
				(width 0.1524)
				(type default)
			)
			(layer "F.SilkS")
		)
		(fp_line
			(start -0.7874 0.4064)
			(end -0.7874 -0.4064)
			(stroke
				(width 0.1524)
				(type default)
			)
			(layer "F.SilkS")
		)
		(fp_line
			(start -0.12065 -0.305054)
			(end -0.12065 -0.2794)
			(stroke
				(width 0.1)
				(type default)
			)
			(layer "F.Fab")
		)
		(fp_line
			(start -0.67945 -0.305054)
			(end -0.12065 -0.305054)
			(stroke
				(width 0.1)
				(type default)
			)
			(layer "F.Fab")
		)
		(fp_line
			(start 0.67945 -0.3048)
			(end 0.67945 0.3048)
			(stroke
				(width 0.1)
				(type default)
			)
			(layer "F.Fab")
		)
		(fp_line
			(start 0.12065 -0.3048)
			(end 0.67945 -0.3048)
			(stroke
				(width 0.1)
				(type default)
			)
			(layer "F.Fab")
		)
		(fp_line
			(start 0.12065 -0.2794)
			(end 0.12065 -0.3048)
			(stroke
				(width 0.1)
				(type default)
			)
			(layer "F.Fab")
		)
		(fp_line
			(start -0.12065 -0.2794)
			(end 0.12065 -0.2794)
			(stroke
				(width 0.1)
				(type default)
			)
			(layer "F.Fab")
		)
		(fp_line
			(start 0.120396 0.2794)
			(end -0.12065 0.2794)
			(stroke
				(width 0.1)
				(type default)
			)
			(layer "F.Fab")
		)
		(fp_line
			(start -0.12065 0.2794)
			(end -0.12065 0.3048)
			(stroke
				(width 0.1)
				(type default)
			)
			(layer "F.Fab")
		)
		(fp_line
			(start 0.67945 0.3048)
			(end 0.120396 0.3048)
			(stroke
				(width 0.1)
				(type default)
			)
			(layer "F.Fab")
		)
		(fp_line
			(start 0.120396 0.3048)
			(end 0.120396 0.2794)
			(stroke
				(width 0.1)
				(type default)
			)
			(layer "F.Fab")
		)
		(fp_line
			(start -0.12065 0.3048)
			(end -0.67945 0.3048)
			(stroke
				(width 0.1)
				(type default)
			)
			(layer "F.Fab")
		)
		(fp_line
			(start -0.67945 0.3048)
			(end -0.67945 -0.305054)
			(stroke
				(width 0.1)
				(type default)
			)
			(layer "F.Fab")
		)
		(pad "1" smd circle
			(at -0.40005 0 90)
			(size 0 0)
			(layers "F.Cu" "F.Mask" "F.Paste")
			(net "UART_CPU0_SCM_LVC3_UART1_R1_TX")
		)
		(pad "2" smd circle
			(at 0.40005 0 90)
			(size 0 0)
			(layers "F.Cu" "F.Mask" "F.Paste")
			(net "UART_CPU0_SCM_LVC3_UART1_TX")
		)
	)
	(footprint ""
		(layer "F.Cu")
		(at 54.96433 -16.099536 90)
		(property "Reference" "C706"
			(at 0 0 90)
			(layer "F.SilkS")
			(hide yes)
			(effects
				(font
					(size 1.27 1.27)
				)
			)
		)
		(property "Value" ""
			(at 0 0 90)
			(layer "F.Fab")
			(effects
				(font
					(size 1.27 1.27)
				)
			)
		)
		(duplicate_pad_numbers_are_jumpers no)
		(fp_line
			(start 0.299974 -0.150114)
			(end 0.299974 0.150114)
			(stroke
				(width 0.1)
				(type default)
			)
			(layer "F.Fab")
		)
		(fp_line
			(start -0.299974 -0.150114)
			(end 0.299974 -0.150114)
			(stroke
				(width 0.1)
				(type default)
			)
			(layer "F.Fab")
		)
		(fp_line
			(start 0.299974 0.150114)
			(end -0.299974 0.150114)
			(stroke
				(width 0.1)
				(type default)
			)
			(layer "F.Fab")
		)
		(fp_line
			(start -0.299974 0.150114)
			(end -0.299974 -0.150114)
			(stroke
				(width 0.1)
				(type default)
			)
			(layer "F.Fab")
		)
		(pad "1" smd rect
			(at -0.2667 0 90)
			(size 0.3048 0.381)
			(layers "F.Cu" "F.Mask" "F.Paste")
			(net "P5E_CPU1_G1_TX_C_DN<1>")
		)
		(pad "2" smd rect
			(at 0.2667 0 90)
			(size 0.3048 0.381)
			(layers "F.Cu" "F.Mask" "F.Paste")
			(net "P5E_CPU1_G1_TX_DN<1>")
		)
	)
	(footprint ""
		(layer "F.Cu")
		(at 235.89996 -81.700116 180)
		(property "Reference" "H115"
			(at -4.5466 -7.559548 180)
			(unlocked yes)
			(layer "B.SilkS")
			(effects
				(font
					(size 0.7874 0.5842)
					(thickness 0.1524)
				)
				(justify left mirror)
			)
		)
		(property "Value" ""
			(at 0 0 180)
			(layer "F.Fab")
			(effects
				(font
					(size 1.27 1.27)
				)
			)
		)
		(duplicate_pad_numbers_are_jumpers no)
		(fp_circle
			(center 0 0)
			(end -7.999984 0)
			(stroke
				(width 0.1524)
				(type default)
			)
			(fill no)
			(layer "F.SilkS")
		)
		(fp_circle
			(center 0 0)
			(end -7.999984 0)
			(stroke
				(width 0.1524)
				(type default)
			)
			(fill no)
			(layer "B.SilkS")
		)
		(fp_circle
			(center 0 0)
			(end -7.999984 0)
			(stroke
				(width 0.1)
				(type default)
			)
			(fill no)
			(layer "B.Fab")
		)
		(fp_circle
			(center 0 0)
			(end -7.999984 0)
			(stroke
				(width 0.1)
				(type default)
			)
			(fill no)
			(layer "F.Fab")
		)
		(pad "" np_thru_hole oval
			(at 0 0 90)
			(size 5.08 6.477)
			(drill oval 5.08 6.477)
			(layers "*.Cu" "*.Mask")
			(clearance 0.381)
			(thermal_gap 0.381)
		)
		(pad "2" thru_hole circle
			(at 4.38023 0 180)
			(size 0.9144 0.9144)
			(drill 0.5588)
			(layers "*.Cu" "*.Mask")
			(remove_unused_layers no)
			(net "GND")
			(clearance 0.0762)
			(thermal_gap 0.0762)
		)
		(pad "3" thru_hole circle
			(at 3.097276 -3.097276 180)
			(size 0.9144 0.9144)
			(drill 0.5588)
			(layers "*.Cu" "*.Mask")
			(remove_unused_layers no)
			(net "GND")
			(clearance 0.0762)
			(thermal_gap 0.0762)
		)
		(pad "4" thru_hole circle
			(at 0 -4.38023 180)
			(size 0.9144 0.9144)
			(drill 0.5588)
			(layers "*.Cu" "*.Mask")
			(remove_unused_layers no)
			(net "GND")
			(clearance 0.0762)
			(thermal_gap 0.0762)
		)
		(pad "5" thru_hole circle
			(at -3.097276 -3.097276 180)
			(size 0.9144 0.9144)
			(drill 0.5588)
			(layers "*.Cu" "*.Mask")
			(remove_unused_layers no)
			(net "GND")
			(clearance 0.0762)
			(thermal_gap 0.0762)
		)
		(pad "6" thru_hole circle
			(at -4.38023 0 180)
			(size 0.9144 0.9144)
			(drill 0.5588)
			(layers "*.Cu" "*.Mask")
			(remove_unused_layers no)
			(net "GND")
			(clearance 0.0762)
			(thermal_gap 0.0762)
		)
		(pad "7" thru_hole circle
			(at -3.097276 3.097276 180)
			(size 0.9144 0.9144)
			(drill 0.5588)
			(layers "*.Cu" "*.Mask")
			(remove_unused_layers no)
			(net "GND")
			(clearance 0.0762)
			(thermal_gap 0.0762)
		)
		(pad "8" thru_hole circle
			(at 0 4.38023 180)
			(size 0.9144 0.9144)
			(drill 0.5588)
			(layers "*.Cu" "*.Mask")
			(remove_unused_layers no)
			(net "GND")
			(clearance 0.0762)
			(thermal_gap 0.0762)
		)
		(pad "9" thru_hole circle
			(at 3.097276 3.097276 180)
			(size 0.9144 0.9144)
			(drill 0.5588)
			(layers "*.Cu" "*.Mask")
			(remove_unused_layers no)
			(net "GND")
			(clearance 0.0762)
			(thermal_gap 0.0762)
		)
		(zone
			(layer "F.Cu")
			(hatch none 0.5)
			(connect_pads
				(clearance 0)
			)
			(min_thickness 0.25)
			(keepout
				(tracks not_allowed)
				(vias allowed)
				(pads allowed)
				(copperpour not_allowed)
				(footprints allowed)
			)
			(placement
				(enabled no)
				(sheetname "")
			)
			(fill
				(thermal_gap 0.5)
				(thermal_bridge_width 0.5)
				(island_removal_mode 0)
			)
			(polygon
				(pts
					(arc
						(start 230.39197 -81.700116)
						(mid 232.005223 -85.594853)
						(end 235.89996 -87.208106)
					)
					(arc
						(start 235.89996 -86.725506)
						(mid 230.87457 -81.700116)
						(end 235.89996 -76.674726)
					)
					(arc
						(start 235.89996 -76.192126)
						(mid 232.005223 -77.805379)
						(end 230.39197 -81.700116)
					)
				)
			)
		)
		(zone
			(layer "F.Cu")
			(hatch none 0.5)
			(connect_pads
				(clearance 0)
			)
			(min_thickness 0.25)
			(keepout
				(tracks not_allowed)
				(vias allowed)
				(pads allowed)
				(copperpour not_allowed)
				(footprints allowed)
			)
			(placement
				(enabled no)
				(sheetname "")
			)
			(fill
				(thermal_gap 0.5)
				(thermal_bridge_width 0.5)
				(island_removal_mode 0)
			)
			(polygon
				(pts
					(arc
						(start 241.40795 -81.700116)
						(mid 239.794697 -85.594853)
						(end 235.89996 -87.208106)
					)
					(arc
						(start 235.89996 -86.725506)
						(mid 240.92535 -81.700116)
						(end 235.89996 -76.674726)
					)
					(arc
						(start 235.89996 -76.192126)
						(mid 239.794697 -77.805379)
						(end 241.40795 -81.700116)
					)
				)
			)
		)
		(zone
			(layers "F.Cu" "B.Cu" "In1.Cu" "In2.Cu" "In3.Cu" "In4.Cu" "In5.Cu" "In6.Cu"
				"In7.Cu" "In8.Cu" "In9.Cu" "In10.Cu" "In11.Cu" "In12.Cu" "In13.Cu" "In14.Cu"
				"In15.Cu" "In16.Cu"
			)
			(hatch none 0.5)
			(connect_pads
				(clearance 0)
			)
			(min_thickness 0.25)
			(keepout
				(tracks not_allowed)
				(vias allowed)
				(pads allowed)
				(copperpour not_allowed)
				(footprints allowed)
			)
			(placement
				(enabled no)
				(sheetname "")
			)
			(fill
				(thermal_gap 0.5)
				(thermal_bridge_width 0.5)
				(island_removal_mode 0)
			)
			(polygon
				(pts
					(arc
						(start 233.71556 -78.64221)
						(mid 235.89996 -85.458093)
						(end 238.08436 -78.64221)
					)
				)
			)
		)
		(zone
			(layer "B.Cu")
			(hatch none 0.5)
			(connect_pads
				(clearance 0)
			)
			(min_thickness 0.25)
			(keepout
				(tracks not_allowed)
				(vias allowed)
				(pads allowed)
				(copperpour not_allowed)
				(footprints allowed)
			)
			(placement
				(enabled no)
				(sheetname "")
			)
			(fill
				(thermal_gap 0.5)
				(thermal_bridge_width 0.5)
				(island_removal_mode 0)
			)
			(polygon
				(pts
					(arc
						(start 235.89996 -89.7001)
						(mid 227.899976 -81.700116)
						(end 235.89996 -73.700132)
					)
					(arc
						(start 235.89996 -76.446126)
						(mid 232.184828 -77.984984)
						(end 230.64597 -81.700116)
					)
					(arc
						(start 230.64597 -81.700116)
						(mid 232.184828 -85.415248)
						(end 235.89996 -86.954106)
					)
				)
			)
		)
		(zone
			(layer "B.Cu")
			(hatch none 0.5)
			(connect_pads
				(clearance 0)
			)
			(min_thickness 0.25)
			(keepout
				(tracks not_allowed)
				(vias allowed)
				(pads allowed)
				(copperpour not_allowed)
				(footprints allowed)
			)
			(placement
				(enabled no)
				(sheetname "")
			)
			(fill
				(thermal_gap 0.5)
				(thermal_bridge_width 0.5)
				(island_removal_mode 0)
			)
			(polygon
				(pts
					(arc
						(start 235.89996 -89.7001)
						(mid 243.899944 -81.700116)
						(end 235.89996 -73.700132)
					)
					(arc
						(start 235.89996 -76.446126)
						(mid 239.615092 -77.984984)
						(end 241.15395 -81.700116)
					)
					(arc
						(start 241.15395 -81.700116)
						(mid 239.615092 -85.415248)
						(end 235.89996 -86.954106)
					)
				)
			)
		)
	)
	(footprint ""
		(layer "F.Cu")
		(at 360.710226 -62.0903 180)
		(property "Reference" "D8000"
			(at 4.256532 1.652524 0)
			(unlocked yes)
			(layer "F.SilkS")
			(effects
				(font
					(size 0.7874 0.5842)
					(thickness 0.1524)
				)
				(justify left)
			)
		)
		(property "Value" ""
			(at 0 0 180)
			(layer "F.Fab")
			(effects
				(font
					(size 1.27 1.27)
				)
			)
		)
		(duplicate_pad_numbers_are_jumpers no)
		(fp_line
			(start 1.16078 0.4826)
			(end -0.64008 0.4826)
			(stroke
				(width 0.1524)
				(type default)
			)
			(layer "F.SilkS")
		)
		(fp_line
			(start 1.16078 -0.4826)
			(end 1.16078 0.4826)
			(stroke
				(width 0.1524)
				(type default)
			)
			(layer "F.SilkS")
		)
		(fp_line
			(start 1.03378 0.4826)
			(end -0.79248 0.4826)
			(stroke
				(width 0.1524)
				(type default)
			)
			(layer "F.SilkS")
		)
		(fp_line
			(start 1.03378 -0.4826)
			(end 1.03378 0.4826)
			(stroke
				(width 0.1524)
				(type default)
			)
			(layer "F.SilkS")
		)
		(fp_line
			(start 0.90678 0.4826)
			(end -0.90678 0.4826)
			(stroke
				(width 0.1524)
				(type default)
			)
			(layer "F.SilkS")
		)
		(fp_line
			(start 0.90678 -0.4826)
			(end 0.90678 0.4826)
			(stroke
				(width 0.1524)
				(type default)
			)
			(layer "F.SilkS")
		)
		(fp_line
			(start -0.64008 -0.4826)
			(end 1.16078 -0.4826)
			(stroke
				(width 0.1524)
				(type default)
			)
			(layer "F.SilkS")
		)
		(fp_line
			(start -0.79248 -0.4826)
			(end 1.03378 -0.4826)
			(stroke
				(width 0.1524)
				(type default)
			)
			(layer "F.SilkS")
		)
		(fp_line
			(start -0.89408 -0.4826)
			(end 0.90678 -0.4826)
			(stroke
				(width 0.1524)
				(type default)
			)
			(layer "F.SilkS")
		)
		(fp_line
			(start -0.90678 0.4826)
			(end -0.90678 -0.4699)
			(stroke
				(width 0.1524)
				(type default)
			)
			(layer "F.SilkS")
		)
		(fp_line
			(start 0.499872 0.249936)
			(end -0.499872 0.249936)
			(stroke
				(width 0.1)
				(type default)
			)
			(layer "F.Fab")
		)
		(fp_line
			(start 0.499872 -0.249936)
			(end 0.499872 0.249936)
			(stroke
				(width 0.1)
				(type default)
			)
			(layer "F.Fab")
		)
		(fp_line
			(start -0.499872 0.249936)
			(end -0.499872 -0.249936)
			(stroke
				(width 0.1)
				(type default)
			)
			(layer "F.Fab")
		)
		(fp_line
			(start -0.499872 -0.249936)
			(end 0.499872 -0.249936)
			(stroke
				(width 0.1)
				(type default)
			)
			(layer "F.Fab")
		)
		(pad "A" smd rect
			(at -0.47498 0 180)
			(size 0.6096 0.7112)
			(layers "F.Cu" "F.Mask" "F.Paste")
			(net "LED_P12V_AUX_R1")
		)
		(pad "C" smd rect
			(at 0.47498 0 180)
			(size 0.6096 0.7112)
			(layers "F.Cu" "F.Mask" "F.Paste")
			(net "GND")
		)
	)
	(footprint ""
		(layer "F.Cu")
		(at 432.12639 -50.447448 180)
		(property "Reference" "PC3"
			(at -2.5908 -1.793748 0)
			(unlocked yes)
			(layer "F.SilkS")
			(effects
				(font
					(size 0.7874 0.5842)
					(thickness 0.1524)
				)
				(justify left)
			)
		)
		(property "Value" ""
			(at 0 0 180)
			(layer "F.Fab")
			(effects
				(font
					(size 1.27 1.27)
				)
			)
		)
		(duplicate_pad_numbers_are_jumpers no)
		(fp_line
			(start -3.400044 1.249934)
			(end 3.400044 1.249934)
			(stroke
				(width 0.1524)
				(type default)
			)
			(layer "F.SilkS")
		)
		(fp_circle
			(center 0 1.249934)
			(end -3.39979 1.249934)
			(stroke
				(width 0.1524)
				(type default)
			)
			(fill no)
			(layer "F.SilkS")
		)
		(fp_poly
			(pts
				(arc
					(start 3.400044 1.249934)
					(mid 0 4.649978)
					(end -3.400044 1.249934)
				)
			)
			(stroke
				(width 0)
				(type default)
			)
			(fill yes)
			(layer "F.SilkS")
		)
		(fp_circle
			(center 0 1.249934)
			(end -3.39979 1.249934)
			(stroke
				(width 0.1)
				(type default)
			)
			(fill no)
			(layer "F.Fab")
		)
		(pad "1" thru_hole rect
			(at 0 0 180)
			(size 1.524 1.524)
			(drill 1.016)
			(layers "*.Cu" "*.Mask")
			(remove_unused_layers no)
			(net "SW_P3V3_AUX_FLT")
			(clearance 0)
			(padstack
				(mode front_inner_back)
				(layer "Inner"
					(shape circle)
					(size 1.524 1.524)
					(clearance 0)
				)
				(layer "B.Cu"
					(shape rect)
					(size 1.524 1.524)
					(clearance 0)
				)
			)
		)
		(pad "2" thru_hole circle
			(at 0 2.500122 180)
			(size 1.524 1.524)
			(drill 1.016)
			(layers "*.Cu" "*.Mask")
			(remove_unused_layers no)
			(net "GND")
			(clearance 0)
		)
	)
	(footprint ""
		(layer "F.Cu")
		(at 440.807602 -429.37811 -90)
		(property "Reference" "R649"
			(at 0 0 270)
			(layer "F.SilkS")
			(hide yes)
			(effects
				(font
					(size 1.27 1.27)
				)
			)
		)
		(property "Value" ""
			(at 0 0 270)
			(layer "F.Fab")
			(effects
				(font
					(size 1.27 1.27)
				)
			)
		)
		(duplicate_pad_numbers_are_jumpers no)
		(fp_line
			(start -0.7874 0.4064)
			(end -0.7874 -0.4064)
			(stroke
				(width 0.1524)
				(type default)
			)
			(layer "F.SilkS")
		)
		(fp_line
			(start 0.7874 0.4064)
			(end -0.7874 0.4064)
			(stroke
				(width 0.1524)
				(type default)
			)
			(layer "F.SilkS")
		)
		(fp_line
			(start -0.7874 -0.4064)
			(end 0.7874 -0.4064)
			(stroke
				(width 0.1524)
				(type default)
			)
			(layer "F.SilkS")
		)
		(fp_line
			(start 0.7874 -0.4064)
			(end 0.7874 0.4064)
			(stroke
				(width 0.1524)
				(type default)
			)
			(layer "F.SilkS")
		)
		(fp_line
			(start -0.67945 0.3048)
			(end -0.67945 -0.305054)
			(stroke
				(width 0.1)
				(type default)
			)
			(layer "F.Fab")
		)
		(fp_line
			(start -0.12065 0.3048)
			(end -0.67945 0.3048)
			(stroke
				(width 0.1)
				(type default)
			)
			(layer "F.Fab")
		)
		(fp_line
			(start 0.120396 0.3048)
			(end 0.120396 0.2794)
			(stroke
				(width 0.1)
				(type default)
			)
			(layer "F.Fab")
		)
		(fp_line
			(start 0.67945 0.3048)
			(end 0.120396 0.3048)
			(stroke
				(width 0.1)
				(type default)
			)
			(layer "F.Fab")
		)
		(fp_line
			(start -0.12065 0.2794)
			(end -0.12065 0.3048)
			(stroke
				(width 0.1)
				(type default)
			)
			(layer "F.Fab")
		)
		(fp_line
			(start 0.120396 0.2794)
			(end -0.12065 0.2794)
			(stroke
				(width 0.1)
				(type default)
			)
			(layer "F.Fab")
		)
		(fp_line
			(start -0.12065 -0.2794)
			(end 0.12065 -0.2794)
			(stroke
				(width 0.1)
				(type default)
			)
			(layer "F.Fab")
		)
		(fp_line
			(start 0.12065 -0.2794)
			(end 0.12065 -0.3048)
			(stroke
				(width 0.1)
				(type default)
			)
			(layer "F.Fab")
		)
		(fp_line
			(start 0.12065 -0.3048)
			(end 0.67945 -0.3048)
			(stroke
				(width 0.1)
				(type default)
			)
			(layer "F.Fab")
		)
		(fp_line
			(start 0.67945 -0.3048)
			(end 0.67945 0.3048)
			(stroke
				(width 0.1)
				(type default)
			)
			(layer "F.Fab")
		)
		(fp_line
			(start -0.67945 -0.305054)
			(end -0.12065 -0.305054)
			(stroke
				(width 0.1)
				(type default)
			)
			(layer "F.Fab")
		)
		(fp_line
			(start -0.12065 -0.305054)
			(end -0.12065 -0.2794)
			(stroke
				(width 0.1)
				(type default)
			)
			(layer "F.Fab")
		)
		(pad "1" smd circle
			(at -0.40005 0 270)
			(size 0 0)
			(layers "F.Cu" "F.Mask" "F.Paste")
			(net "P3V3_AUX")
		)
		(pad "2" smd circle
			(at 0.40005 0 270)
			(size 0 0)
			(layers "F.Cu" "F.Mask" "F.Paste")
			(net "TP_P0V9_RETIMER_CPU0_PMALERT")
		)
	)
	(footprint ""
		(layer "F.Cu")
		(at 78.867 -66.802 180)
		(property "Reference" "R8096"
			(at 0 0 180)
			(layer "F.SilkS")
			(hide yes)
			(effects
				(font
					(size 1.27 1.27)
				)
			)
		)
		(property "Value" ""
			(at 0 0 180)
			(layer "F.Fab")
			(effects
				(font
					(size 1.27 1.27)
				)
			)
		)
		(duplicate_pad_numbers_are_jumpers no)
		(fp_line
			(start 0.7874 0.4064)
			(end -0.7874 0.4064)
			(stroke
				(width 0.1524)
				(type default)
			)
			(layer "F.SilkS")
		)
		(fp_line
			(start 0.7874 -0.4064)
			(end 0.7874 0.4064)
			(stroke
				(width 0.1524)
				(type default)
			)
			(layer "F.SilkS")
		)
		(fp_line
			(start -0.7874 0.4064)
			(end -0.7874 -0.4064)
			(stroke
				(width 0.1524)
				(type default)
			)
			(layer "F.SilkS")
		)
		(fp_line
			(start -0.7874 -0.4064)
			(end 0.7874 -0.4064)
			(stroke
				(width 0.1524)
				(type default)
			)
			(layer "F.SilkS")
		)
		(fp_line
			(start 0.67945 0.3048)
			(end 0.120396 0.3048)
			(stroke
				(width 0.1)
				(type default)
			)
			(layer "F.Fab")
		)
		(fp_line
			(start 0.67945 -0.3048)
			(end 0.67945 0.3048)
			(stroke
				(width 0.1)
				(type default)
			)
			(layer "F.Fab")
		)
		(fp_line
			(start 0.12065 -0.2794)
			(end 0.12065 -0.3048)
			(stroke
				(width 0.1)
				(type default)
			)
			(layer "F.Fab")
		)
		(fp_line
			(start 0.12065 -0.3048)
			(end 0.67945 -0.3048)
			(stroke
				(width 0.1)
				(type default)
			)
			(layer "F.Fab")
		)
		(fp_line
			(start 0.120396 0.3048)
			(end 0.120396 0.2794)
			(stroke
				(width 0.1)
				(type default)
			)
			(layer "F.Fab")
		)
		(fp_line
			(start 0.120396 0.2794)
			(end -0.12065 0.2794)
			(stroke
				(width 0.1)
				(type default)
			)
			(layer "F.Fab")
		)
		(fp_line
			(start -0.12065 0.3048)
			(end -0.67945 0.3048)
			(stroke
				(width 0.1)
				(type default)
			)
			(layer "F.Fab")
		)
		(fp_line
			(start -0.12065 0.2794)
			(end -0.12065 0.3048)
			(stroke
				(width 0.1)
				(type default)
			)
			(layer "F.Fab")
		)
		(fp_line
			(start -0.12065 -0.2794)
			(end 0.12065 -0.2794)
			(stroke
				(width 0.1)
				(type default)
			)
			(layer "F.Fab")
		)
		(fp_line
			(start -0.12065 -0.305054)
			(end -0.12065 -0.2794)
			(stroke
				(width 0.1)
				(type default)
			)
			(layer "F.Fab")
		)
		(fp_line
			(start -0.67945 0.3048)
			(end -0.67945 -0.305054)
			(stroke
				(width 0.1)
				(type default)
			)
			(layer "F.Fab")
		)
		(fp_line
			(start -0.67945 -0.305054)
			(end -0.12065 -0.305054)
			(stroke
				(width 0.1)
				(type default)
			)
			(layer "F.Fab")
		)
		(pad "1" smd circle
			(at -0.40005 0 180)
			(size 0 0)
			(layers "F.Cu" "F.Mask" "F.Paste")
			(net "OCP_V3_2_P3V3_R1_PWRGD")
		)
		(pad "2" smd circle
			(at 0.40005 0 180)
			(size 0 0)
			(layers "F.Cu" "F.Mask" "F.Paste")
			(net "GND")
		)
	)
	(footprint ""
		(layer "F.Cu")
		(at 102.154736 -119.499126 90)
		(property "Reference" "R1450"
			(at 0 0 90)
			(layer "F.SilkS")
			(hide yes)
			(effects
				(font
					(size 1.27 1.27)
				)
			)
		)
		(property "Value" ""
			(at 0 0 90)
			(layer "F.Fab")
			(effects
				(font
					(size 1.27 1.27)
				)
			)
		)
		(duplicate_pad_numbers_are_jumpers no)
		(fp_line
			(start 0.7874 -0.4064)
			(end 0.7874 0.4064)
			(stroke
				(width 0.1524)
				(type default)
			)
			(layer "F.SilkS")
		)
		(fp_line
			(start -0.7874 -0.4064)
			(end 0.7874 -0.4064)
			(stroke
				(width 0.1524)
				(type default)
			)
			(layer "F.SilkS")
		)
		(fp_line
			(start 0.7874 0.4064)
			(end -0.7874 0.4064)
			(stroke
				(width 0.1524)
				(type default)
			)
			(layer "F.SilkS")
		)
		(fp_line
			(start -0.7874 0.4064)
			(end -0.7874 -0.4064)
			(stroke
				(width 0.1524)
				(type default)
			)
			(layer "F.SilkS")
		)
		(fp_line
			(start -0.12065 -0.305054)
			(end -0.12065 -0.2794)
			(stroke
				(width 0.1)
				(type default)
			)
			(layer "F.Fab")
		)
		(fp_line
			(start -0.67945 -0.305054)
			(end -0.12065 -0.305054)
			(stroke
				(width 0.1)
				(type default)
			)
			(layer "F.Fab")
		)
		(fp_line
			(start 0.67945 -0.3048)
			(end 0.67945 0.3048)
			(stroke
				(width 0.1)
				(type default)
			)
			(layer "F.Fab")
		)
		(fp_line
			(start 0.12065 -0.3048)
			(end 0.67945 -0.3048)
			(stroke
				(width 0.1)
				(type default)
			)
			(layer "F.Fab")
		)
		(fp_line
			(start 0.12065 -0.2794)
			(end 0.12065 -0.3048)
			(stroke
				(width 0.1)
				(type default)
			)
			(layer "F.Fab")
		)
		(fp_line
			(start -0.12065 -0.2794)
			(end 0.12065 -0.2794)
			(stroke
				(width 0.1)
				(type default)
			)
			(layer "F.Fab")
		)
		(fp_line
			(start 0.120396 0.2794)
			(end -0.12065 0.2794)
			(stroke
				(width 0.1)
				(type default)
			)
			(layer "F.Fab")
		)
		(fp_line
			(start -0.12065 0.2794)
			(end -0.12065 0.3048)
			(stroke
				(width 0.1)
				(type default)
			)
			(layer "F.Fab")
		)
		(fp_line
			(start 0.67945 0.3048)
			(end 0.120396 0.3048)
			(stroke
				(width 0.1)
				(type default)
			)
			(layer "F.Fab")
		)
		(fp_line
			(start 0.120396 0.3048)
			(end 0.120396 0.2794)
			(stroke
				(width 0.1)
				(type default)
			)
			(layer "F.Fab")
		)
		(fp_line
			(start -0.12065 0.3048)
			(end -0.67945 0.3048)
			(stroke
				(width 0.1)
				(type default)
			)
			(layer "F.Fab")
		)
		(fp_line
			(start -0.67945 0.3048)
			(end -0.67945 -0.305054)
			(stroke
				(width 0.1)
				(type default)
			)
			(layer "F.Fab")
		)
		(pad "1" smd circle
			(at -0.40005 0 90)
			(size 0 0)
			(layers "F.Cu" "F.Mask" "F.Paste")
			(net "P3V3_AUX")
		)
		(pad "2" smd circle
			(at 0.40005 0 90)
			(size 0 0)
			(layers "F.Cu" "F.Mask" "F.Paste")
			(net "PWRGD_P12V_MEM_CPU0_EN_N")
		)
	)
	(footprint ""
		(layer "F.Cu")
		(at 196.457824 -65.225168 -90)
		(property "Reference" "PC2204"
			(at 0 0 270)
			(layer "F.SilkS")
			(hide yes)
			(effects
				(font
					(size 1.27 1.27)
				)
			)
		)
		(property "Value" ""
			(at 0 0 270)
			(layer "F.Fab")
			(effects
				(font
					(size 1.27 1.27)
				)
			)
		)
		(duplicate_pad_numbers_are_jumpers no)
		(fp_line
			(start -1.524 0.762)
			(end -1.524 -0.762)
			(stroke
				(width 0.1524)
				(type default)
			)
			(layer "F.SilkS")
		)
		(fp_line
			(start 1.524 0.762)
			(end -1.524 0.762)
			(stroke
				(width 0.1524)
				(type default)
			)
			(layer "F.SilkS")
		)
		(fp_line
			(start -1.524 -0.762)
			(end 1.524 -0.762)
			(stroke
				(width 0.1524)
				(type default)
			)
			(layer "F.SilkS")
		)
		(fp_line
			(start 1.524 -0.762)
			(end 1.524 0.762)
			(stroke
				(width 0.1524)
				(type default)
			)
			(layer "F.SilkS")
		)
		(fp_line
			(start -1.1049 0.724916)
			(end 1.1049 0.724916)
			(stroke
				(width 0.1)
				(type default)
			)
			(layer "F.Fab")
		)
		(fp_line
			(start 1.1049 0.724916)
			(end 1.1049 -0.724916)
			(stroke
				(width 0.1)
				(type default)
			)
			(layer "F.Fab")
		)
		(fp_line
			(start -1.1049 -0.724916)
			(end -1.1049 0.724916)
			(stroke
				(width 0.1)
				(type default)
			)
			(layer "F.Fab")
		)
		(fp_line
			(start 1.1049 -0.724916)
			(end -1.1049 -0.724916)
			(stroke
				(width 0.1)
				(type default)
			)
			(layer "F.Fab")
		)
		(pad "1" smd rect
			(at -0.889 0 90)
			(size 1.016 1.27)
			(layers "F.Cu" "F.Mask" "F.Paste")
			(net "P3V3_E1S_0_R")
		)
		(pad "2" smd rect
			(at 0.889 0 90)
			(size 1.016 1.27)
			(layers "F.Cu" "F.Mask" "F.Paste")
			(net "GND")
		)
	)
	(footprint ""
		(layer "F.Cu")
		(at 21.43887 -387.30809 90)
		(property "Reference" "PR6630"
			(at 0 0 90)
			(layer "F.SilkS")
			(hide yes)
			(effects
				(font
					(size 1.27 1.27)
				)
			)
		)
		(property "Value" ""
			(at 0 0 90)
			(layer "F.Fab")
			(effects
				(font
					(size 1.27 1.27)
				)
			)
		)
		(duplicate_pad_numbers_are_jumpers no)
		(fp_line
			(start 0.7874 -0.4064)
			(end 0.7874 0.4064)
			(stroke
				(width 0.1524)
				(type default)
			)
			(layer "F.SilkS")
		)
		(fp_line
			(start -0.7874 -0.4064)
			(end 0.7874 -0.4064)
			(stroke
				(width 0.1524)
				(type default)
			)
			(layer "F.SilkS")
		)
		(fp_line
			(start 0.7874 0.4064)
			(end -0.7874 0.4064)
			(stroke
				(width 0.1524)
				(type default)
			)
			(layer "F.SilkS")
		)
		(fp_line
			(start -0.7874 0.4064)
			(end -0.7874 -0.4064)
			(stroke
				(width 0.1524)
				(type default)
			)
			(layer "F.SilkS")
		)
		(fp_line
			(start -0.12065 -0.305054)
			(end -0.12065 -0.2794)
			(stroke
				(width 0.1)
				(type default)
			)
			(layer "F.Fab")
		)
		(fp_line
			(start -0.67945 -0.305054)
			(end -0.12065 -0.305054)
			(stroke
				(width 0.1)
				(type default)
			)
			(layer "F.Fab")
		)
		(fp_line
			(start 0.67945 -0.3048)
			(end 0.67945 0.3048)
			(stroke
				(width 0.1)
				(type default)
			)
			(layer "F.Fab")
		)
		(fp_line
			(start 0.12065 -0.3048)
			(end 0.67945 -0.3048)
			(stroke
				(width 0.1)
				(type default)
			)
			(layer "F.Fab")
		)
		(fp_line
			(start 0.12065 -0.2794)
			(end 0.12065 -0.3048)
			(stroke
				(width 0.1)
				(type default)
			)
			(layer "F.Fab")
		)
		(fp_line
			(start -0.12065 -0.2794)
			(end 0.12065 -0.2794)
			(stroke
				(width 0.1)
				(type default)
			)
			(layer "F.Fab")
		)
		(fp_line
			(start 0.120396 0.2794)
			(end -0.12065 0.2794)
			(stroke
				(width 0.1)
				(type default)
			)
			(layer "F.Fab")
		)
		(fp_line
			(start -0.12065 0.2794)
			(end -0.12065 0.3048)
			(stroke
				(width 0.1)
				(type default)
			)
			(layer "F.Fab")
		)
		(fp_line
			(start 0.67945 0.3048)
			(end 0.120396 0.3048)
			(stroke
				(width 0.1)
				(type default)
			)
			(layer "F.Fab")
		)
		(fp_line
			(start 0.120396 0.3048)
			(end 0.120396 0.2794)
			(stroke
				(width 0.1)
				(type default)
			)
			(layer "F.Fab")
		)
		(fp_line
			(start -0.12065 0.3048)
			(end -0.67945 0.3048)
			(stroke
				(width 0.1)
				(type default)
			)
			(layer "F.Fab")
		)
		(fp_line
			(start -0.67945 0.3048)
			(end -0.67945 -0.305054)
			(stroke
				(width 0.1)
				(type default)
			)
			(layer "F.Fab")
		)
		(pad "1" smd circle
			(at -0.40005 0 90)
			(size 0 0)
			(layers "F.Cu" "F.Mask" "F.Paste")
			(net "SW_P0V9_RETIMER_CPU1_SW2_RC")
		)
		(pad "2" smd circle
			(at 0.40005 0 90)
			(size 0 0)
			(layers "F.Cu" "F.Mask" "F.Paste")
			(net "GND")
		)
	)
	(footprint ""
		(layer "F.Cu")
		(at 284.461712 -351.368106 90)
		(property "Reference" "PR110"
			(at 0 0 90)
			(layer "F.SilkS")
			(hide yes)
			(effects
				(font
					(size 1.27 1.27)
				)
			)
		)
		(property "Value" ""
			(at 0 0 90)
			(layer "F.Fab")
			(effects
				(font
					(size 1.27 1.27)
				)
			)
		)
		(duplicate_pad_numbers_are_jumpers no)
		(fp_line
			(start 0.7874 -0.4064)
			(end 0.7874 0.4064)
			(stroke
				(width 0.1524)
				(type default)
			)
			(layer "F.SilkS")
		)
		(fp_line
			(start -0.7874 -0.4064)
			(end 0.7874 -0.4064)
			(stroke
				(width 0.1524)
				(type default)
			)
			(layer "F.SilkS")
		)
		(fp_line
			(start 0.7874 0.4064)
			(end -0.7874 0.4064)
			(stroke
				(width 0.1524)
				(type default)
			)
			(layer "F.SilkS")
		)
		(fp_line
			(start -0.7874 0.4064)
			(end -0.7874 -0.4064)
			(stroke
				(width 0.1524)
				(type default)
			)
			(layer "F.SilkS")
		)
		(fp_line
			(start -0.12065 -0.305054)
			(end -0.12065 -0.2794)
			(stroke
				(width 0.1)
				(type default)
			)
			(layer "F.Fab")
		)
		(fp_line
			(start -0.67945 -0.305054)
			(end -0.12065 -0.305054)
			(stroke
				(width 0.1)
				(type default)
			)
			(layer "F.Fab")
		)
		(fp_line
			(start 0.67945 -0.3048)
			(end 0.67945 0.3048)
			(stroke
				(width 0.1)
				(type default)
			)
			(layer "F.Fab")
		)
		(fp_line
			(start 0.12065 -0.3048)
			(end 0.67945 -0.3048)
			(stroke
				(width 0.1)
				(type default)
			)
			(layer "F.Fab")
		)
		(fp_line
			(start 0.12065 -0.2794)
			(end 0.12065 -0.3048)
			(stroke
				(width 0.1)
				(type default)
			)
			(layer "F.Fab")
		)
		(fp_line
			(start -0.12065 -0.2794)
			(end 0.12065 -0.2794)
			(stroke
				(width 0.1)
				(type default)
			)
			(layer "F.Fab")
		)
		(fp_line
			(start 0.120396 0.2794)
			(end -0.12065 0.2794)
			(stroke
				(width 0.1)
				(type default)
			)
			(layer "F.Fab")
		)
		(fp_line
			(start -0.12065 0.2794)
			(end -0.12065 0.3048)
			(stroke
				(width 0.1)
				(type default)
			)
			(layer "F.Fab")
		)
		(fp_line
			(start 0.67945 0.3048)
			(end 0.120396 0.3048)
			(stroke
				(width 0.1)
				(type default)
			)
			(layer "F.Fab")
		)
		(fp_line
			(start 0.120396 0.3048)
			(end 0.120396 0.2794)
			(stroke
				(width 0.1)
				(type default)
			)
			(layer "F.Fab")
		)
		(fp_line
			(start -0.12065 0.3048)
			(end -0.67945 0.3048)
			(stroke
				(width 0.1)
				(type default)
			)
			(layer "F.Fab")
		)
		(fp_line
			(start -0.67945 0.3048)
			(end -0.67945 -0.305054)
			(stroke
				(width 0.1)
				(type default)
			)
			(layer "F.Fab")
		)
		(pad "1" smd circle
			(at -0.40005 0 90)
			(size 0 0)
			(layers "F.Cu" "F.Mask" "F.Paste")
			(net "SW_PVDDIO_P0_BOOT3")
		)
		(pad "2" smd circle
			(at 0.40005 0 90)
			(size 0 0)
			(layers "F.Cu" "F.Mask" "F.Paste")
			(net "SW_PVDDIO_P0_BOOT3_R")
		)
	)
	(footprint ""
		(layer "F.Cu")
		(at 277.20798 -351.368106 -90)
		(property "Reference" "PC183"
			(at 0 0 270)
			(layer "F.SilkS")
			(hide yes)
			(effects
				(font
					(size 1.27 1.27)
				)
			)
		)
		(property "Value" ""
			(at 0 0 270)
			(layer "F.Fab")
			(effects
				(font
					(size 1.27 1.27)
				)
			)
		)
		(duplicate_pad_numbers_are_jumpers no)
		(fp_line
			(start -0.7874 0.4064)
			(end -0.7874 -0.4064)
			(stroke
				(width 0.1524)
				(type default)
			)
			(layer "F.SilkS")
		)
		(fp_line
			(start 0.7874 0.4064)
			(end -0.7874 0.4064)
			(stroke
				(width 0.1524)
				(type default)
			)
			(layer "F.SilkS")
		)
		(fp_line
			(start -0.7874 -0.4064)
			(end 0.7874 -0.4064)
			(stroke
				(width 0.1524)
				(type default)
			)
			(layer "F.SilkS")
		)
		(fp_line
			(start 0.7874 -0.4064)
			(end 0.7874 0.4064)
			(stroke
				(width 0.1524)
				(type default)
			)
			(layer "F.SilkS")
		)
		(fp_line
			(start -0.67945 0.3048)
			(end -0.67945 -0.305054)
			(stroke
				(width 0.1)
				(type default)
			)
			(layer "F.Fab")
		)
		(fp_line
			(start -0.12065 0.3048)
			(end -0.67945 0.3048)
			(stroke
				(width 0.1)
				(type default)
			)
			(layer "F.Fab")
		)
		(fp_line
			(start 0.120396 0.3048)
			(end 0.120396 0.2794)
			(stroke
				(width 0.1)
				(type default)
			)
			(layer "F.Fab")
		)
		(fp_line
			(start 0.67945 0.3048)
			(end 0.120396 0.3048)
			(stroke
				(width 0.1)
				(type default)
			)
			(layer "F.Fab")
		)
		(fp_line
			(start -0.12065 0.2794)
			(end -0.12065 0.3048)
			(stroke
				(width 0.1)
				(type default)
			)
			(layer "F.Fab")
		)
		(fp_line
			(start 0.120396 0.2794)
			(end -0.12065 0.2794)
			(stroke
				(width 0.1)
				(type default)
			)
			(layer "F.Fab")
		)
		(fp_line
			(start -0.12065 -0.2794)
			(end 0.12065 -0.2794)
			(stroke
				(width 0.1)
				(type default)
			)
			(layer "F.Fab")
		)
		(fp_line
			(start 0.12065 -0.2794)
			(end 0.12065 -0.3048)
			(stroke
				(width 0.1)
				(type default)
			)
			(layer "F.Fab")
		)
		(fp_line
			(start 0.12065 -0.3048)
			(end 0.67945 -0.3048)
			(stroke
				(width 0.1)
				(type default)
			)
			(layer "F.Fab")
		)
		(fp_line
			(start 0.67945 -0.3048)
			(end 0.67945 0.3048)
			(stroke
				(width 0.1)
				(type default)
			)
			(layer "F.Fab")
		)
		(fp_line
			(start -0.67945 -0.305054)
			(end -0.12065 -0.305054)
			(stroke
				(width 0.1)
				(type default)
			)
			(layer "F.Fab")
		)
		(fp_line
			(start -0.12065 -0.305054)
			(end -0.12065 -0.2794)
			(stroke
				(width 0.1)
				(type default)
			)
			(layer "F.Fab")
		)
		(pad "1" smd circle
			(at -0.40005 0 270)
			(size 0 0)
			(layers "F.Cu" "F.Mask" "F.Paste")
			(net "SW_PVDDIO_P0_BOOT4_R")
		)
		(pad "2" smd circle
			(at 0.40005 0 270)
			(size 0 0)
			(layers "F.Cu" "F.Mask" "F.Paste")
			(net "SW_PVDDIO_P0_BOOTR4")
		)
	)
	(footprint ""
		(layer "F.Cu")
		(at 289.314382 -351.573846 90)
		(property "Reference" "PC146_8"
			(at 0 0 90)
			(layer "F.SilkS")
			(hide yes)
			(effects
				(font
					(size 1.27 1.27)
				)
			)
		)
		(property "Value" ""
			(at 0 0 90)
			(layer "F.Fab")
			(effects
				(font
					(size 1.27 1.27)
				)
			)
		)
		(duplicate_pad_numbers_are_jumpers no)
		(fp_line
			(start 0.7874 -0.4064)
			(end 0.7874 0.4064)
			(stroke
				(width 0.1524)
				(type default)
			)
			(layer "F.SilkS")
		)
		(fp_line
			(start -0.7874 -0.4064)
			(end 0.7874 -0.4064)
			(stroke
				(width 0.1524)
				(type default)
			)
			(layer "F.SilkS")
		)
		(fp_line
			(start 0.7874 0.4064)
			(end -0.7874 0.4064)
			(stroke
				(width 0.1524)
				(type default)
			)
			(layer "F.SilkS")
		)
		(fp_line
			(start -0.7874 0.4064)
			(end -0.7874 -0.4064)
			(stroke
				(width 0.1524)
				(type default)
			)
			(layer "F.SilkS")
		)
		(fp_line
			(start -0.12065 -0.305054)
			(end -0.12065 -0.2794)
			(stroke
				(width 0.1)
				(type default)
			)
			(layer "F.Fab")
		)
		(fp_line
			(start -0.67945 -0.305054)
			(end -0.12065 -0.305054)
			(stroke
				(width 0.1)
				(type default)
			)
			(layer "F.Fab")
		)
		(fp_line
			(start 0.67945 -0.3048)
			(end 0.67945 0.3048)
			(stroke
				(width 0.1)
				(type default)
			)
			(layer "F.Fab")
		)
		(fp_line
			(start 0.12065 -0.3048)
			(end 0.67945 -0.3048)
			(stroke
				(width 0.1)
				(type default)
			)
			(layer "F.Fab")
		)
		(fp_line
			(start 0.12065 -0.2794)
			(end 0.12065 -0.3048)
			(stroke
				(width 0.1)
				(type default)
			)
			(layer "F.Fab")
		)
		(fp_line
			(start -0.12065 -0.2794)
			(end 0.12065 -0.2794)
			(stroke
				(width 0.1)
				(type default)
			)
			(layer "F.Fab")
		)
		(fp_line
			(start 0.120396 0.2794)
			(end -0.12065 0.2794)
			(stroke
				(width 0.1)
				(type default)
			)
			(layer "F.Fab")
		)
		(fp_line
			(start -0.12065 0.2794)
			(end -0.12065 0.3048)
			(stroke
				(width 0.1)
				(type default)
			)
			(layer "F.Fab")
		)
		(fp_line
			(start 0.67945 0.3048)
			(end 0.120396 0.3048)
			(stroke
				(width 0.1)
				(type default)
			)
			(layer "F.Fab")
		)
		(fp_line
			(start 0.120396 0.3048)
			(end 0.120396 0.2794)
			(stroke
				(width 0.1)
				(type default)
			)
			(layer "F.Fab")
		)
		(fp_line
			(start -0.12065 0.3048)
			(end -0.67945 0.3048)
			(stroke
				(width 0.1)
				(type default)
			)
			(layer "F.Fab")
		)
		(fp_line
			(start -0.67945 0.3048)
			(end -0.67945 -0.305054)
			(stroke
				(width 0.1)
				(type default)
			)
			(layer "F.Fab")
		)
		(pad "1" smd circle
			(at -0.40005 0 90)
			(size 0 0)
			(layers "F.Cu" "F.Mask" "F.Paste")
			(net "PVDDCR_CPU1_P0_VCCS")
		)
		(pad "2" smd circle
			(at 0.40005 0 90)
			(size 0 0)
			(layers "F.Cu" "F.Mask" "F.Paste")
			(net "GND")
		)
	)
	(footprint ""
		(layer "F.Cu")
		(at 304.293778 -434.264308 180)
		(property "Reference" "Q104"
			(at 4.643374 -1.833372 0)
			(unlocked yes)
			(layer "F.SilkS")
			(effects
				(font
					(size 0.7874 0.5842)
					(thickness 0.1524)
				)
				(justify left)
			)
		)
		(property "Value" ""
			(at 0 0 180)
			(layer "F.Fab")
			(effects
				(font
					(size 1.27 1.27)
				)
			)
		)
		(duplicate_pad_numbers_are_jumpers no)
		(fp_line
			(start 1.332738 1.100074)
			(end -1.332738 1.100074)
			(stroke
				(width 0.1524)
				(type default)
			)
			(layer "F.SilkS")
		)
		(fp_line
			(start 1.332738 -1.100074)
			(end 1.332738 1.100074)
			(stroke
				(width 0.1524)
				(type default)
			)
			(layer "F.SilkS")
		)
		(fp_line
			(start 0.4826 -1.100074)
			(end 1.332738 -1.100074)
			(stroke
				(width 0.1524)
				(type default)
			)
			(layer "F.SilkS")
		)
		(fp_line
			(start 0 -0.541274)
			(end 0.4826 -1.100074)
			(stroke
				(width 0.1524)
				(type default)
			)
			(layer "F.SilkS")
		)
		(fp_line
			(start -0.4826 -1.100074)
			(end 0 -0.541274)
			(stroke
				(width 0.1524)
				(type default)
			)
			(layer "F.SilkS")
		)
		(fp_line
			(start -1.332738 1.100074)
			(end -1.332738 -1.100074)
			(stroke
				(width 0.1524)
				(type default)
			)
			(layer "F.SilkS")
		)
		(fp_line
			(start -1.332738 -1.100074)
			(end -0.4826 -1.100074)
			(stroke
				(width 0.1524)
				(type default)
			)
			(layer "F.SilkS")
		)
		(fp_poly
			(pts
				(xy -1.489456 -1.189482) (xy -2.23393 -1.43764) (xy -1.737614 -1.933956)
			)
			(stroke
				(width 0)
				(type default)
			)
			(fill yes)
			(layer "F.SilkS")
		)
		(fp_line
			(start 0.674878 1.100074)
			(end -0.674878 1.100074)
			(stroke
				(width 0.1)
				(type default)
			)
			(layer "F.Fab")
		)
		(fp_line
			(start 0.674878 -1.100074)
			(end 0.674878 1.100074)
			(stroke
				(width 0.1)
				(type default)
			)
			(layer "F.Fab")
		)
		(fp_line
			(start -0.674878 1.100074)
			(end -0.674878 -1.100074)
			(stroke
				(width 0.1)
				(type default)
			)
			(layer "F.Fab")
		)
		(fp_line
			(start -0.674878 -1.100074)
			(end 0.674878 -1.100074)
			(stroke
				(width 0.1)
				(type default)
			)
			(layer "F.Fab")
		)
		(fp_poly
			(pts
				(xy -2.2352 -0.298958) (xy -2.2352 -1.001014) (xy -1.533144 -0.649986)
			)
			(stroke
				(width 0)
				(type default)
			)
			(fill yes)
			(layer "F.Fab")
		)
		(pad "1" smd rect
			(at -0.94996 -0.649986 270)
			(size 0.4318 0.508)
			(layers "F.Cu" "F.Mask" "F.Paste")
			(net "GND")
		)
		(pad "2" smd rect
			(at -0.94996 0 270)
			(size 0.4318 0.508)
			(layers "F.Cu" "F.Mask" "F.Paste")
			(net "GPU_FPGA_OVERT_N")
		)
		(pad "3" smd rect
			(at -0.94996 0.649986 270)
			(size 0.4318 0.508)
			(layers "F.Cu" "F.Mask" "F.Paste")
			(net "GPU_FPGA_OVERT_ISO_N")
		)
		(pad "4" smd rect
			(at 0.94996 0.649986 270)
			(size 0.4318 0.508)
			(layers "F.Cu" "F.Mask" "F.Paste")
			(net "GND")
		)
		(pad "5" smd rect
			(at 0.94996 0 270)
			(size 0.4318 0.508)
			(layers "F.Cu" "F.Mask" "F.Paste")
			(net "GPU_FPGA_OVERT")
		)
		(pad "6" smd rect
			(at 0.94996 -0.649986 270)
			(size 0.4318 0.508)
			(layers "F.Cu" "F.Mask" "F.Paste")
			(net "GPU_FPGA_OVERT")
		)
	)
	(footprint ""
		(layer "F.Cu")
		(at 102.154736 -123.64339 -90)
		(property "Reference" "Q18"
			(at -0.190754 1.882394 90)
			(unlocked yes)
			(layer "F.SilkS")
			(effects
				(font
					(size 0.7874 0.5842)
					(thickness 0.1524)
				)
			)
		)
		(property "Value" ""
			(at 0 0 270)
			(layer "F.Fab")
			(effects
				(font
					(size 1.27 1.27)
				)
			)
		)
		(duplicate_pad_numbers_are_jumpers no)
		(fp_line
			(start -1.7018 1.100074)
			(end -1.7018 -1.100074)
			(stroke
				(width 0.1524)
				(type default)
			)
			(layer "F.SilkS")
		)
		(fp_line
			(start 1.7018 1.100074)
			(end -1.7018 1.100074)
			(stroke
				(width 0.1524)
				(type default)
			)
			(layer "F.SilkS")
		)
		(fp_line
			(start -1.7018 -1.100074)
			(end 1.7018 -1.100074)
			(stroke
				(width 0.1524)
				(type default)
			)
			(layer "F.SilkS")
		)
		(fp_line
			(start 1.7018 -1.100074)
			(end 1.7018 1.100074)
			(stroke
				(width 0.1524)
				(type default)
			)
			(layer "F.SilkS")
		)
		(fp_poly
			(pts
				(xy -2.339594 -0.650748) (xy -2.893314 -0.354076) (xy -2.893314 -0.978916)
			)
			(stroke
				(width 0)
				(type default)
			)
			(fill yes)
			(layer "F.SilkS")
		)
		(fp_line
			(start -0.670052 1.100074)
			(end -0.670052 0.8001)
			(stroke
				(width 0.1)
				(type default)
			)
			(layer "F.Fab")
		)
		(fp_line
			(start 0.670052 1.100074)
			(end -0.670052 1.100074)
			(stroke
				(width 0.1)
				(type default)
			)
			(layer "F.Fab")
		)
		(fp_line
			(start -1.100074 0.8001)
			(end -1.100074 -0.8001)
			(stroke
				(width 0.1)
				(type default)
			)
			(layer "F.Fab")
		)
		(fp_line
			(start -0.670052 0.8001)
			(end -1.100074 0.8001)
			(stroke
				(width 0.1)
				(type default)
			)
			(layer "F.Fab")
		)
		(fp_line
			(start -0.670052 0.8001)
			(end -0.670052 -0.8001)
			(stroke
				(width 0.1)
				(type default)
			)
			(layer "F.Fab")
		)
		(fp_line
			(start 0.670052 0.8001)
			(end 0.670052 1.100074)
			(stroke
				(width 0.1)
				(type default)
			)
			(layer "F.Fab")
		)
		(fp_line
			(start 1.100074 0.8001)
			(end 0.670052 0.8001)
			(stroke
				(width 0.1)
				(type default)
			)
			(layer "F.Fab")
		)
		(fp_line
			(start -1.100074 -0.8001)
			(end -0.670052 -0.8001)
			(stroke
				(width 0.1)
				(type default)
			)
			(layer "F.Fab")
		)
		(fp_line
			(start -0.670052 -0.8001)
			(end -0.670052 -1.100074)
			(stroke
				(width 0.1)
				(type default)
			)
			(layer "F.Fab")
		)
		(fp_line
			(start 0.670052 -0.8001)
			(end 0.670052 0.8001)
			(stroke
				(width 0.1)
				(type default)
			)
			(layer "F.Fab")
		)
		(fp_line
			(start 0.670052 -0.8001)
			(end 1.100074 -0.8001)
			(stroke
				(width 0.1)
				(type default)
			)
			(layer "F.Fab")
		)
		(fp_line
			(start 1.100074 -0.8001)
			(end 1.100074 0.8001)
			(stroke
				(width 0.1)
				(type default)
			)
			(layer "F.Fab")
		)
		(fp_line
			(start -0.670052 -1.100074)
			(end 0.670052 -1.100074)
			(stroke
				(width 0.1)
				(type default)
			)
			(layer "F.Fab")
		)
		(fp_line
			(start 0.670052 -1.100074)
			(end 0.670052 -0.8001)
			(stroke
				(width 0.1)
				(type default)
			)
			(layer "F.Fab")
		)
		(fp_poly
			(pts
				(xy -2.33172 -0.338328) (xy -2.33172 -0.963168) (xy -1.778 -0.635)
			)
			(stroke
				(width 0)
				(type default)
			)
			(fill yes)
			(layer "F.Fab")
		)
		(pad "1" smd rect
			(at -0.937514 -0.649986)
			(size 0.3048 1.2446)
			(layers "F.Cu" "F.Mask" "F.Paste")
			(net "GND")
		)
		(pad "2" smd rect
			(at -0.937514 0)
			(size 0.3048 1.2446)
			(layers "F.Cu" "F.Mask" "F.Paste")
			(net "PWRGD_P12V_MEM_CPU0_EN")
		)
		(pad "3" smd rect
			(at -0.937514 0.649986)
			(size 0.3048 1.2446)
			(layers "F.Cu" "F.Mask" "F.Paste")
			(net "PWRGD_P12V_MEM_CPU0")
		)
		(pad "4" smd rect
			(at 0.937514 0.649986)
			(size 0.3048 1.2446)
			(layers "F.Cu" "F.Mask" "F.Paste")
			(net "GND")
		)
		(pad "5" smd rect
			(at 0.937514 0)
			(size 0.3048 1.2446)
			(layers "F.Cu" "F.Mask" "F.Paste")
			(net "PWRGD_P12V_MEM_CPU0_EN_N")
		)
		(pad "6" smd rect
			(at 0.937514 -0.649986)
			(size 0.3048 1.2446)
			(layers "F.Cu" "F.Mask" "F.Paste")
			(net "PWRGD_P12V_MEM_CPU0_EN_N")
		)
	)
	(footprint ""
		(layer "F.Cu")
		(at 19.241516 -40.942514)
		(property "Reference" "R1307"
			(at 0 0 0)
			(layer "F.SilkS")
			(hide yes)
			(effects
				(font
					(size 1.27 1.27)
				)
			)
		)
		(property "Value" ""
			(at 0 0 0)
			(layer "F.Fab")
			(effects
				(font
					(size 1.27 1.27)
				)
			)
		)
		(duplicate_pad_numbers_are_jumpers no)
		(fp_line
			(start -0.7874 -0.4064)
			(end 0.7874 -0.4064)
			(stroke
				(width 0.1524)
				(type default)
			)
			(layer "F.SilkS")
		)
		(fp_line
			(start -0.7874 0.4064)
			(end -0.7874 -0.4064)
			(stroke
				(width 0.1524)
				(type default)
			)
			(layer "F.SilkS")
		)
		(fp_line
			(start 0.7874 -0.4064)
			(end 0.7874 0.4064)
			(stroke
				(width 0.1524)
				(type default)
			)
			(layer "F.SilkS")
		)
		(fp_line
			(start 0.7874 0.4064)
			(end -0.7874 0.4064)
			(stroke
				(width 0.1524)
				(type default)
			)
			(layer "F.SilkS")
		)
		(fp_line
			(start -0.67945 -0.305054)
			(end -0.12065 -0.305054)
			(stroke
				(width 0.1)
				(type default)
			)
			(layer "F.Fab")
		)
		(fp_line
			(start -0.67945 0.3048)
			(end -0.67945 -0.305054)
			(stroke
				(width 0.1)
				(type default)
			)
			(layer "F.Fab")
		)
		(fp_line
			(start -0.12065 -0.305054)
			(end -0.12065 -0.2794)
			(stroke
				(width 0.1)
				(type default)
			)
			(layer "F.Fab")
		)
		(fp_line
			(start -0.12065 -0.2794)
			(end 0.12065 -0.2794)
			(stroke
				(width 0.1)
				(type default)
			)
			(layer "F.Fab")
		)
		(fp_line
			(start -0.12065 0.2794)
			(end -0.12065 0.3048)
			(stroke
				(width 0.1)
				(type default)
			)
			(layer "F.Fab")
		)
		(fp_line
			(start -0.12065 0.3048)
			(end -0.67945 0.3048)
			(stroke
				(width 0.1)
				(type default)
			)
			(layer "F.Fab")
		)
		(fp_line
			(start 0.120396 0.2794)
			(end -0.12065 0.2794)
			(stroke
				(width 0.1)
				(type default)
			)
			(layer "F.Fab")
		)
		(fp_line
			(start 0.120396 0.3048)
			(end 0.120396 0.2794)
			(stroke
				(width 0.1)
				(type default)
			)
			(layer "F.Fab")
		)
		(fp_line
			(start 0.12065 -0.3048)
			(end 0.67945 -0.3048)
			(stroke
				(width 0.1)
				(type default)
			)
			(layer "F.Fab")
		)
		(fp_line
			(start 0.12065 -0.2794)
			(end 0.12065 -0.3048)
			(stroke
				(width 0.1)
				(type default)
			)
			(layer "F.Fab")
		)
		(fp_line
			(start 0.67945 -0.3048)
			(end 0.67945 0.3048)
			(stroke
				(width 0.1)
				(type default)
			)
			(layer "F.Fab")
		)
		(fp_line
			(start 0.67945 0.3048)
			(end 0.120396 0.3048)
			(stroke
				(width 0.1)
				(type default)
			)
			(layer "F.Fab")
		)
		(pad "1" smd circle
			(at -0.40005 0)
			(size 0 0)
			(layers "F.Cu" "F.Mask" "F.Paste")
			(net "GND")
		)
		(pad "2" smd circle
			(at 0.40005 0)
			(size 0 0)
			(layers "F.Cu" "F.Mask" "F.Paste")
			(net "INA230_7_A1")
		)
	)
	(footprint ""
		(layer "F.Cu")
		(at 312.725308 -43.46321)
		(property "Reference" "U269"
			(at -3.27914 -4.806188 0)
			(unlocked yes)
			(layer "F.SilkS")
			(effects
				(font
					(size 0.7874 0.5842)
					(thickness 0.1524)
				)
				(justify left)
			)
		)
		(property "Value" ""
			(at 0 0 0)
			(layer "F.Fab")
			(effects
				(font
					(size 1.27 1.27)
				)
			)
		)
		(duplicate_pad_numbers_are_jumpers no)
		(fp_line
			(start -1.868932 -2.549906)
			(end -1.868932 2.549906)
			(stroke
				(width 0.1524)
				(type default)
			)
			(layer "F.SilkS")
		)
		(fp_line
			(start -1.868932 2.549906)
			(end 1.868932 2.549906)
			(stroke
				(width 0.1524)
				(type default)
			)
			(layer "F.SilkS")
		)
		(fp_line
			(start -1.025906 -2.549906)
			(end -1.868932 -2.549906)
			(stroke
				(width 0.1524)
				(type default)
			)
			(layer "F.SilkS")
		)
		(fp_line
			(start 0 -1.524)
			(end -1.025906 -2.549906)
			(stroke
				(width 0.1524)
				(type default)
			)
			(layer "F.SilkS")
		)
		(fp_line
			(start 1.025906 -2.549906)
			(end 0 -1.524)
			(stroke
				(width 0.1524)
				(type default)
			)
			(layer "F.SilkS")
		)
		(fp_line
			(start 1.868932 -2.549906)
			(end 1.025906 -2.549906)
			(stroke
				(width 0.1524)
				(type default)
			)
			(layer "F.SilkS")
		)
		(fp_line
			(start 1.868932 2.549906)
			(end 1.868932 -2.549906)
			(stroke
				(width 0.1524)
				(type default)
			)
			(layer "F.SilkS")
		)
		(fp_poly
			(pts
				(xy -3.243326 -3.828796) (xy -2.227326 -3.828796) (xy -2.735326 -2.812796)
			)
			(stroke
				(width 0)
				(type default)
			)
			(fill yes)
			(layer "F.SilkS")
		)
		(fp_line
			(start -2.249932 -2.549906)
			(end -2.249932 2.549906)
			(stroke
				(width 0.1)
				(type default)
			)
			(layer "F.Fab")
		)
		(fp_line
			(start -2.249932 2.549906)
			(end 2.249932 2.549906)
			(stroke
				(width 0.1)
				(type default)
			)
			(layer "F.Fab")
		)
		(fp_line
			(start 2.249932 -2.549906)
			(end -2.249932 -2.549906)
			(stroke
				(width 0.1)
				(type default)
			)
			(layer "F.Fab")
		)
		(fp_line
			(start 2.249932 2.549906)
			(end 2.249932 -2.549906)
			(stroke
				(width 0.1)
				(type default)
			)
			(layer "F.Fab")
		)
		(fp_poly
			(pts
				(xy -4.7752 -1.787398) (xy -4.7752 -2.803398) (xy -3.7592 -2.295398)
			)
			(stroke
				(width 0)
				(type default)
			)
			(fill yes)
			(layer "F.Fab")
		)
		(pad "1" smd rect
			(at -2.800096 -2.275078 270)
			(size 0.3556 1.6002)
			(layers "F.Cu" "F.Mask" "F.Paste")
			(net "ADC128_VREF")
		)
		(pad "2" smd rect
			(at -2.800096 -1.625092 270)
			(size 0.3556 1.6002)
			(layers "F.Cu" "F.Mask" "F.Paste")
			(net "SMB_SEN_TIC_3V3AUX_SDA")
		)
		(pad "3" smd rect
			(at -2.800096 -0.975106 270)
			(size 0.3556 1.6002)
			(layers "F.Cu" "F.Mask" "F.Paste")
			(net "SMB_SEN_TIC_3V3AUX_SCL")
		)
		(pad "4" smd rect
			(at -2.800096 -0.32512 270)
			(size 0.3556 1.6002)
			(layers "F.Cu" "F.Mask" "F.Paste")
			(net "GND")
		)
		(pad "5" smd rect
			(at -2.800096 0.32512 270)
			(size 0.3556 1.6002)
			(layers "F.Cu" "F.Mask" "F.Paste")
			(net "P3V3_ADC128_VCC")
		)
		(pad "6" smd rect
			(at -2.800096 0.975106 270)
			(size 0.3556 1.6002)
			(layers "F.Cu" "F.Mask" "F.Paste")
			(net "TP_ADC128_INT")
		)
		(pad "7" smd rect
			(at -2.800096 1.625092 270)
			(size 0.3556 1.6002)
			(layers "F.Cu" "F.Mask" "F.Paste")
			(net "ADC128_A0")
		)
		(pad "8" smd rect
			(at -2.800096 2.275078 270)
			(size 0.3556 1.6002)
			(layers "F.Cu" "F.Mask" "F.Paste")
			(net "ADC128_A1")
		)
		(pad "9" smd rect
			(at 2.800096 2.275078 270)
			(size 0.3556 1.6002)
			(layers "F.Cu" "F.Mask" "F.Paste")
			(net "P12V_E1S_0_ISENSE_TIC")
		)
		(pad "10" smd rect
			(at 2.800096 1.625092 270)
			(size 0.3556 1.6002)
			(layers "F.Cu" "F.Mask" "F.Paste")
			(net "P3V3_PDB_AUX_ADC_TIC")
		)
		(pad "11" smd rect
			(at 2.800096 0.975106 270)
			(size 0.3556 1.6002)
			(layers "F.Cu" "F.Mask" "F.Paste")
			(net "P3V3_AUX_ADC_TIC")
		)
		(pad "12" smd rect
			(at 2.800096 0.32512 270)
			(size 0.3556 1.6002)
			(layers "F.Cu" "F.Mask" "F.Paste")
			(net "P3V3_ADC_TIC")
		)
		(pad "13" smd rect
			(at 2.800096 -0.32512 270)
			(size 0.3556 1.6002)
			(layers "F.Cu" "F.Mask" "F.Paste")
			(net "P5V_ADC_TIC")
		)
		(pad "14" smd rect
			(at 2.800096 -0.975106 270)
			(size 0.3556 1.6002)
			(layers "F.Cu" "F.Mask" "F.Paste")
			(net "P12V_OCP_V3_2_ISENSE_TIC")
		)
		(pad "15" smd rect
			(at 2.800096 -1.625092 270)
			(size 0.3556 1.6002)
			(layers "F.Cu" "F.Mask" "F.Paste")
			(net "P12V_OCP_SFF_ISENSE_TIC")
		)
		(pad "16" smd rect
			(at 2.800096 -2.275078 270)
			(size 0.3556 1.6002)
			(layers "F.Cu" "F.Mask" "F.Paste")
			(net "P12V_AUX_ADC_TIC")
		)
	)
	(footprint ""
		(layer "F.Cu")
		(at 103.5304 -396.6972 90)
		(property "Reference" "R672"
			(at 0 0 90)
			(layer "F.SilkS")
			(hide yes)
			(effects
				(font
					(size 1.27 1.27)
				)
			)
		)
		(property "Value" ""
			(at 0 0 90)
			(layer "F.Fab")
			(effects
				(font
					(size 1.27 1.27)
				)
			)
		)
		(duplicate_pad_numbers_are_jumpers no)
		(fp_line
			(start 0.32512 -0.175006)
			(end 0.32512 0.175006)
			(stroke
				(width 0.1)
				(type default)
			)
			(layer "F.Fab")
		)
		(fp_line
			(start -0.32512 -0.175006)
			(end 0.32512 -0.175006)
			(stroke
				(width 0.1)
				(type default)
			)
			(layer "F.Fab")
		)
		(fp_line
			(start 0.32512 0.175006)
			(end -0.32512 0.175006)
			(stroke
				(width 0.1)
				(type default)
			)
			(layer "F.Fab")
		)
		(fp_line
			(start -0.32512 0.175006)
			(end -0.32512 -0.175006)
			(stroke
				(width 0.1)
				(type default)
			)
			(layer "F.Fab")
		)
		(pad "1" smd rect
			(at -0.2667 0 90)
			(size 0.3048 0.381)
			(layers "F.Cu" "F.Mask" "F.Paste")
			(net "SMB_RT_CPU1_P0_ROM_R_SCL")
		)
		(pad "2" smd rect
			(at 0.2667 0 270)
			(size 0.3048 0.381)
			(layers "F.Cu" "F.Mask" "F.Paste")
			(net "SMB_RT_CPU1_P0_ROM_SCL")
		)
	)
	(footprint ""
		(layer "F.Cu")
		(at 244.2972 -287.376362)
		(property "Reference" "PC6901"
			(at 0 0 0)
			(layer "F.SilkS")
			(hide yes)
			(effects
				(font
					(size 1.27 1.27)
				)
			)
		)
		(property "Value" ""
			(at 0 0 0)
			(layer "F.Fab")
			(effects
				(font
					(size 1.27 1.27)
				)
			)
		)
		(duplicate_pad_numbers_are_jumpers no)
		(fp_line
			(start -1.524 -0.762)
			(end 1.524 -0.762)
			(stroke
				(width 0.1524)
				(type default)
			)
			(layer "F.SilkS")
		)
		(fp_line
			(start -1.524 0.762)
			(end -1.524 -0.762)
			(stroke
				(width 0.1524)
				(type default)
			)
			(layer "F.SilkS")
		)
		(fp_line
			(start 1.524 -0.762)
			(end 1.524 0.762)
			(stroke
				(width 0.1524)
				(type default)
			)
			(layer "F.SilkS")
		)
		(fp_line
			(start 1.524 0.762)
			(end -1.524 0.762)
			(stroke
				(width 0.1524)
				(type default)
			)
			(layer "F.SilkS")
		)
		(fp_line
			(start -1.1049 -0.724916)
			(end -1.1049 0.724916)
			(stroke
				(width 0.1)
				(type default)
			)
			(layer "F.Fab")
		)
		(fp_line
			(start -1.1049 0.724916)
			(end 1.1049 0.724916)
			(stroke
				(width 0.1)
				(type default)
			)
			(layer "F.Fab")
		)
		(fp_line
			(start 1.1049 -0.724916)
			(end -1.1049 -0.724916)
			(stroke
				(width 0.1)
				(type default)
			)
			(layer "F.Fab")
		)
		(fp_line
			(start 1.1049 0.724916)
			(end 1.1049 -0.724916)
			(stroke
				(width 0.1)
				(type default)
			)
			(layer "F.Fab")
		)
		(pad "1" smd rect
			(at -0.889 0 180)
			(size 1.016 1.27)
			(layers "F.Cu" "F.Mask" "F.Paste")
			(net "SW_P12V_AUX_P1V8_RETIMER_CPU0_FLT")
		)
		(pad "2" smd rect
			(at 0.889 0 180)
			(size 1.016 1.27)
			(layers "F.Cu" "F.Mask" "F.Paste")
			(net "GND")
		)
	)
	(footprint ""
		(layer "F.Cu")
		(at 94.605602 -41.445942 180)
		(property "Reference" "R3185"
			(at 0 0 180)
			(layer "F.SilkS")
			(hide yes)
			(effects
				(font
					(size 1.27 1.27)
				)
			)
		)
		(property "Value" ""
			(at 0 0 180)
			(layer "F.Fab")
			(effects
				(font
					(size 1.27 1.27)
				)
			)
		)
		(duplicate_pad_numbers_are_jumpers no)
		(fp_line
			(start 0.7874 0.4064)
			(end -0.7874 0.4064)
			(stroke
				(width 0.1524)
				(type default)
			)
			(layer "F.SilkS")
		)
		(fp_line
			(start 0.7874 -0.4064)
			(end 0.7874 0.4064)
			(stroke
				(width 0.1524)
				(type default)
			)
			(layer "F.SilkS")
		)
		(fp_line
			(start -0.7874 0.4064)
			(end -0.7874 -0.4064)
			(stroke
				(width 0.1524)
				(type default)
			)
			(layer "F.SilkS")
		)
		(fp_line
			(start -0.7874 -0.4064)
			(end 0.7874 -0.4064)
			(stroke
				(width 0.1524)
				(type default)
			)
			(layer "F.SilkS")
		)
		(fp_line
			(start 0.67945 0.3048)
			(end 0.120396 0.3048)
			(stroke
				(width 0.1)
				(type default)
			)
			(layer "F.Fab")
		)
		(fp_line
			(start 0.67945 -0.3048)
			(end 0.67945 0.3048)
			(stroke
				(width 0.1)
				(type default)
			)
			(layer "F.Fab")
		)
		(fp_line
			(start 0.12065 -0.2794)
			(end 0.12065 -0.3048)
			(stroke
				(width 0.1)
				(type default)
			)
			(layer "F.Fab")
		)
		(fp_line
			(start 0.12065 -0.3048)
			(end 0.67945 -0.3048)
			(stroke
				(width 0.1)
				(type default)
			)
			(layer "F.Fab")
		)
		(fp_line
			(start 0.120396 0.3048)
			(end 0.120396 0.2794)
			(stroke
				(width 0.1)
				(type default)
			)
			(layer "F.Fab")
		)
		(fp_line
			(start 0.120396 0.2794)
			(end -0.12065 0.2794)
			(stroke
				(width 0.1)
				(type default)
			)
			(layer "F.Fab")
		)
		(fp_line
			(start -0.12065 0.3048)
			(end -0.67945 0.3048)
			(stroke
				(width 0.1)
				(type default)
			)
			(layer "F.Fab")
		)
		(fp_line
			(start -0.12065 0.2794)
			(end -0.12065 0.3048)
			(stroke
				(width 0.1)
				(type default)
			)
			(layer "F.Fab")
		)
		(fp_line
			(start -0.12065 -0.2794)
			(end 0.12065 -0.2794)
			(stroke
				(width 0.1)
				(type default)
			)
			(layer "F.Fab")
		)
		(fp_line
			(start -0.12065 -0.305054)
			(end -0.12065 -0.2794)
			(stroke
				(width 0.1)
				(type default)
			)
			(layer "F.Fab")
		)
		(fp_line
			(start -0.67945 0.3048)
			(end -0.67945 -0.305054)
			(stroke
				(width 0.1)
				(type default)
			)
			(layer "F.Fab")
		)
		(fp_line
			(start -0.67945 -0.305054)
			(end -0.12065 -0.305054)
			(stroke
				(width 0.1)
				(type default)
			)
			(layer "F.Fab")
		)
		(pad "1" smd circle
			(at -0.40005 0 180)
			(size 0 0)
			(layers "F.Cu" "F.Mask" "F.Paste")
			(net "OCP_V3_2_WAKE_BUFF_N")
		)
		(pad "2" smd circle
			(at 0.40005 0 180)
			(size 0 0)
			(layers "F.Cu" "F.Mask" "F.Paste")
			(net "OCP_V3_2_WAKE_BUFF_R_N")
		)
	)
	(footprint ""
		(layer "F.Cu")
		(at 108.092748 -187.492894 180)
		(property "Reference" "PL32"
			(at -0.856488 6.245098 0)
			(unlocked yes)
			(layer "F.SilkS")
			(effects
				(font
					(size 0.7874 0.5842)
					(thickness 0.1524)
				)
				(justify left)
			)
		)
		(property "Value" ""
			(at 0 0 180)
			(layer "F.Fab")
			(effects
				(font
					(size 1.27 1.27)
				)
			)
		)
		(duplicate_pad_numbers_are_jumpers no)
		(fp_line
			(start 3.750056 5.500116)
			(end 3.750056 -5.500116)
			(stroke
				(width 0.1524)
				(type default)
			)
			(layer "F.SilkS")
		)
		(fp_line
			(start 3.750056 -5.500116)
			(end 2.393442 -5.500116)
			(stroke
				(width 0.1524)
				(type default)
			)
			(layer "F.SilkS")
		)
		(fp_line
			(start 2.393442 5.500116)
			(end 3.750056 5.500116)
			(stroke
				(width 0.1524)
				(type default)
			)
			(layer "F.SilkS")
		)
		(fp_line
			(start -2.393442 5.500116)
			(end -3.750056 5.500116)
			(stroke
				(width 0.1524)
				(type default)
			)
			(layer "F.SilkS")
		)
		(fp_line
			(start -3.750056 5.500116)
			(end -3.750056 -5.500116)
			(stroke
				(width 0.1524)
				(type default)
			)
			(layer "F.SilkS")
		)
		(fp_line
			(start -3.750056 -5.500116)
			(end -2.393442 -5.500116)
			(stroke
				(width 0.1524)
				(type default)
			)
			(layer "F.SilkS")
		)
		(fp_poly
			(pts
				(xy 3.963416 -4.623562) (xy 4.741418 -5.01269) (xy 4.741418 -4.234434)
			)
			(stroke
				(width 0)
				(type default)
			)
			(fill yes)
			(layer "F.SilkS")
		)
		(fp_line
			(start 3.750056 5.500116)
			(end 3.750056 -5.500116)
			(stroke
				(width 0.1)
				(type default)
			)
			(layer "F.Fab")
		)
		(fp_line
			(start 3.750056 -5.500116)
			(end -3.750056 -5.500116)
			(stroke
				(width 0.1)
				(type default)
			)
			(layer "F.Fab")
		)
		(fp_line
			(start -3.750056 5.500116)
			(end 3.750056 5.500116)
			(stroke
				(width 0.1)
				(type default)
			)
			(layer "F.Fab")
		)
		(fp_line
			(start -3.750056 -5.500116)
			(end -3.750056 5.500116)
			(stroke
				(width 0.1)
				(type default)
			)
			(layer "F.Fab")
		)
		(fp_poly
			(pts
				(xy -4.9276 -4.757928) (xy -4.9276 -3.741928) (xy -3.9116 -4.249928)
			)
			(stroke
				(width 0)
				(type default)
			)
			(fill yes)
			(layer "F.Fab")
		)
		(pad "1" smd rect
			(at 0 -4.249928 90)
			(size 2.413 4.5212)
			(layers "F.Cu" "F.Mask" "F.Paste")
			(net "SW_PVDDCR_CPU0_P1_SW4")
		)
		(pad "2" smd rect
			(at 0 -1.175004 90)
			(size 1.3716 4.5212)
			(layers "F.Cu" "F.Mask" "F.Paste")
			(net "IND_CPU0_P1_CPL3")
		)
		(pad "3" smd rect
			(at 0 1.175004 90)
			(size 1.3716 4.5212)
			(layers "F.Cu" "F.Mask" "F.Paste")
			(net "GND")
		)
		(pad "4" smd rect
			(at 0 4.249928 90)
			(size 2.413 4.5212)
			(layers "F.Cu" "F.Mask" "F.Paste")
			(net "PVDDCR_CPU0_P1")
		)
	)
	(footprint ""
		(layer "F.Cu")
		(at 321.112896 -378.95403 -90)
		(property "Reference" "C909"
			(at 0 0 270)
			(layer "F.SilkS")
			(hide yes)
			(effects
				(font
					(size 1.27 1.27)
				)
			)
		)
		(property "Value" ""
			(at 0 0 270)
			(layer "F.Fab")
			(effects
				(font
					(size 1.27 1.27)
				)
			)
		)
		(duplicate_pad_numbers_are_jumpers no)
		(fp_line
			(start -0.299974 0.150114)
			(end -0.299974 -0.150114)
			(stroke
				(width 0.1)
				(type default)
			)
			(layer "F.Fab")
		)
		(fp_line
			(start 0.299974 0.150114)
			(end -0.299974 0.150114)
			(stroke
				(width 0.1)
				(type default)
			)
			(layer "F.Fab")
		)
		(fp_line
			(start -0.299974 -0.150114)
			(end 0.299974 -0.150114)
			(stroke
				(width 0.1)
				(type default)
			)
			(layer "F.Fab")
		)
		(fp_line
			(start 0.299974 -0.150114)
			(end 0.299974 0.150114)
			(stroke
				(width 0.1)
				(type default)
			)
			(layer "F.Fab")
		)
		(pad "1" smd rect
			(at -0.2667 0 270)
			(size 0.3048 0.381)
			(layers "F.Cu" "F.Mask" "F.Paste")
			(net "P5E_CPU0_P0_TX_C_DP<12>")
		)
		(pad "2" smd rect
			(at 0.2667 0 270)
			(size 0.3048 0.381)
			(layers "F.Cu" "F.Mask" "F.Paste")
			(net "P5E_CPU0_P0_TX_DP<12>")
		)
	)
	(footprint ""
		(layer "F.Cu")
		(at 66.726054 -334.998314 -90)
		(property "Reference" "PC402_C1P1_3"
			(at 0 0 270)
			(layer "F.SilkS")
			(hide yes)
			(effects
				(font
					(size 1.27 1.27)
				)
			)
		)
		(property "Value" ""
			(at 0 0 270)
			(layer "F.Fab")
			(effects
				(font
					(size 1.27 1.27)
				)
			)
		)
		(duplicate_pad_numbers_are_jumpers no)
		(fp_line
			(start -0.7874 0.4064)
			(end -0.7874 -0.4064)
			(stroke
				(width 0.1524)
				(type default)
			)
			(layer "F.SilkS")
		)
		(fp_line
			(start 0.7874 0.4064)
			(end -0.7874 0.4064)
			(stroke
				(width 0.1524)
				(type default)
			)
			(layer "F.SilkS")
		)
		(fp_line
			(start -0.7874 -0.4064)
			(end 0.7874 -0.4064)
			(stroke
				(width 0.1524)
				(type default)
			)
			(layer "F.SilkS")
		)
		(fp_line
			(start 0.7874 -0.4064)
			(end 0.7874 0.4064)
			(stroke
				(width 0.1524)
				(type default)
			)
			(layer "F.SilkS")
		)
		(fp_line
			(start -0.67945 0.3048)
			(end -0.67945 -0.305054)
			(stroke
				(width 0.1)
				(type default)
			)
			(layer "F.Fab")
		)
		(fp_line
			(start -0.12065 0.3048)
			(end -0.67945 0.3048)
			(stroke
				(width 0.1)
				(type default)
			)
			(layer "F.Fab")
		)
		(fp_line
			(start 0.120396 0.3048)
			(end 0.120396 0.2794)
			(stroke
				(width 0.1)
				(type default)
			)
			(layer "F.Fab")
		)
		(fp_line
			(start 0.67945 0.3048)
			(end 0.120396 0.3048)
			(stroke
				(width 0.1)
				(type default)
			)
			(layer "F.Fab")
		)
		(fp_line
			(start -0.12065 0.2794)
			(end -0.12065 0.3048)
			(stroke
				(width 0.1)
				(type default)
			)
			(layer "F.Fab")
		)
		(fp_line
			(start 0.120396 0.2794)
			(end -0.12065 0.2794)
			(stroke
				(width 0.1)
				(type default)
			)
			(layer "F.Fab")
		)
		(fp_line
			(start -0.12065 -0.2794)
			(end 0.12065 -0.2794)
			(stroke
				(width 0.1)
				(type default)
			)
			(layer "F.Fab")
		)
		(fp_line
			(start 0.12065 -0.2794)
			(end 0.12065 -0.3048)
			(stroke
				(width 0.1)
				(type default)
			)
			(layer "F.Fab")
		)
		(fp_line
			(start 0.12065 -0.3048)
			(end 0.67945 -0.3048)
			(stroke
				(width 0.1)
				(type default)
			)
			(layer "F.Fab")
		)
		(fp_line
			(start 0.67945 -0.3048)
			(end 0.67945 0.3048)
			(stroke
				(width 0.1)
				(type default)
			)
			(layer "F.Fab")
		)
		(fp_line
			(start -0.67945 -0.305054)
			(end -0.12065 -0.305054)
			(stroke
				(width 0.1)
				(type default)
			)
			(layer "F.Fab")
		)
		(fp_line
			(start -0.12065 -0.305054)
			(end -0.12065 -0.2794)
			(stroke
				(width 0.1)
				(type default)
			)
			(layer "F.Fab")
		)
		(pad "1" smd circle
			(at -0.40005 0 270)
			(size 0 0)
			(layers "F.Cu" "F.Mask" "F.Paste")
			(net "PVDDCR_CPU1_P1_PVCC")
		)
		(pad "2" smd circle
			(at 0.40005 0 270)
			(size 0 0)
			(layers "F.Cu" "F.Mask" "F.Paste")
			(net "GND")
		)
	)
	(footprint ""
		(layer "F.Cu")
		(at 32.347662 -429.790098 -90)
		(property "Reference" "R3269"
			(at 0 0 270)
			(layer "F.SilkS")
			(hide yes)
			(effects
				(font
					(size 1.27 1.27)
				)
			)
		)
		(property "Value" ""
			(at 0 0 270)
			(layer "F.Fab")
			(effects
				(font
					(size 1.27 1.27)
				)
			)
		)
		(duplicate_pad_numbers_are_jumpers no)
		(fp_line
			(start -0.7874 0.4064)
			(end -0.7874 -0.4064)
			(stroke
				(width 0.1524)
				(type default)
			)
			(layer "F.SilkS")
		)
		(fp_line
			(start 0.7874 0.4064)
			(end -0.7874 0.4064)
			(stroke
				(width 0.1524)
				(type default)
			)
			(layer "F.SilkS")
		)
		(fp_line
			(start -0.7874 -0.4064)
			(end 0.7874 -0.4064)
			(stroke
				(width 0.1524)
				(type default)
			)
			(layer "F.SilkS")
		)
		(fp_line
			(start 0.7874 -0.4064)
			(end 0.7874 0.4064)
			(stroke
				(width 0.1524)
				(type default)
			)
			(layer "F.SilkS")
		)
		(fp_line
			(start -0.67945 0.3048)
			(end -0.67945 -0.305054)
			(stroke
				(width 0.1)
				(type default)
			)
			(layer "F.Fab")
		)
		(fp_line
			(start -0.12065 0.3048)
			(end -0.67945 0.3048)
			(stroke
				(width 0.1)
				(type default)
			)
			(layer "F.Fab")
		)
		(fp_line
			(start 0.120396 0.3048)
			(end 0.120396 0.2794)
			(stroke
				(width 0.1)
				(type default)
			)
			(layer "F.Fab")
		)
		(fp_line
			(start 0.67945 0.3048)
			(end 0.120396 0.3048)
			(stroke
				(width 0.1)
				(type default)
			)
			(layer "F.Fab")
		)
		(fp_line
			(start -0.12065 0.2794)
			(end -0.12065 0.3048)
			(stroke
				(width 0.1)
				(type default)
			)
			(layer "F.Fab")
		)
		(fp_line
			(start 0.120396 0.2794)
			(end -0.12065 0.2794)
			(stroke
				(width 0.1)
				(type default)
			)
			(layer "F.Fab")
		)
		(fp_line
			(start -0.12065 -0.2794)
			(end 0.12065 -0.2794)
			(stroke
				(width 0.1)
				(type default)
			)
			(layer "F.Fab")
		)
		(fp_line
			(start 0.12065 -0.2794)
			(end 0.12065 -0.3048)
			(stroke
				(width 0.1)
				(type default)
			)
			(layer "F.Fab")
		)
		(fp_line
			(start 0.12065 -0.3048)
			(end 0.67945 -0.3048)
			(stroke
				(width 0.1)
				(type default)
			)
			(layer "F.Fab")
		)
		(fp_line
			(start 0.67945 -0.3048)
			(end 0.67945 0.3048)
			(stroke
				(width 0.1)
				(type default)
			)
			(layer "F.Fab")
		)
		(fp_line
			(start -0.67945 -0.305054)
			(end -0.12065 -0.305054)
			(stroke
				(width 0.1)
				(type default)
			)
			(layer "F.Fab")
		)
		(fp_line
			(start -0.12065 -0.305054)
			(end -0.12065 -0.2794)
			(stroke
				(width 0.1)
				(type default)
			)
			(layer "F.Fab")
		)
		(pad "1" smd circle
			(at -0.40005 0 270)
			(size 0 0)
			(layers "F.Cu" "F.Mask" "F.Paste")
			(net "P3V3_AUX")
		)
		(pad "2" smd circle
			(at 0.40005 0 270)
			(size 0 0)
			(layers "F.Cu" "F.Mask" "F.Paste")
			(net "FM_P2E_FGB")
		)
	)
	(footprint ""
		(layer "F.Cu")
		(at 77.128878 -23.308818 180)
		(property "Reference" "PC2098"
			(at 0 0 180)
			(layer "F.SilkS")
			(hide yes)
			(effects
				(font
					(size 1.27 1.27)
				)
			)
		)
		(property "Value" ""
			(at 0 0 180)
			(layer "F.Fab")
			(effects
				(font
					(size 1.27 1.27)
				)
			)
		)
		(duplicate_pad_numbers_are_jumpers no)
		(fp_line
			(start 0.7874 0.4064)
			(end -0.7874 0.4064)
			(stroke
				(width 0.1524)
				(type default)
			)
			(layer "F.SilkS")
		)
		(fp_line
			(start 0.7874 -0.4064)
			(end 0.7874 0.4064)
			(stroke
				(width 0.1524)
				(type default)
			)
			(layer "F.SilkS")
		)
		(fp_line
			(start -0.7874 0.4064)
			(end -0.7874 -0.4064)
			(stroke
				(width 0.1524)
				(type default)
			)
			(layer "F.SilkS")
		)
		(fp_line
			(start -0.7874 -0.4064)
			(end 0.7874 -0.4064)
			(stroke
				(width 0.1524)
				(type default)
			)
			(layer "F.SilkS")
		)
		(fp_line
			(start 0.67945 0.3048)
			(end 0.120396 0.3048)
			(stroke
				(width 0.1)
				(type default)
			)
			(layer "F.Fab")
		)
		(fp_line
			(start 0.67945 -0.3048)
			(end 0.67945 0.3048)
			(stroke
				(width 0.1)
				(type default)
			)
			(layer "F.Fab")
		)
		(fp_line
			(start 0.12065 -0.2794)
			(end 0.12065 -0.3048)
			(stroke
				(width 0.1)
				(type default)
			)
			(layer "F.Fab")
		)
		(fp_line
			(start 0.12065 -0.3048)
			(end 0.67945 -0.3048)
			(stroke
				(width 0.1)
				(type default)
			)
			(layer "F.Fab")
		)
		(fp_line
			(start 0.120396 0.3048)
			(end 0.120396 0.2794)
			(stroke
				(width 0.1)
				(type default)
			)
			(layer "F.Fab")
		)
		(fp_line
			(start 0.120396 0.2794)
			(end -0.12065 0.2794)
			(stroke
				(width 0.1)
				(type default)
			)
			(layer "F.Fab")
		)
		(fp_line
			(start -0.12065 0.3048)
			(end -0.67945 0.3048)
			(stroke
				(width 0.1)
				(type default)
			)
			(layer "F.Fab")
		)
		(fp_line
			(start -0.12065 0.2794)
			(end -0.12065 0.3048)
			(stroke
				(width 0.1)
				(type default)
			)
			(layer "F.Fab")
		)
		(fp_line
			(start -0.12065 -0.2794)
			(end 0.12065 -0.2794)
			(stroke
				(width 0.1)
				(type default)
			)
			(layer "F.Fab")
		)
		(fp_line
			(start -0.12065 -0.305054)
			(end -0.12065 -0.2794)
			(stroke
				(width 0.1)
				(type default)
			)
			(layer "F.Fab")
		)
		(fp_line
			(start -0.67945 0.3048)
			(end -0.67945 -0.305054)
			(stroke
				(width 0.1)
				(type default)
			)
			(layer "F.Fab")
		)
		(fp_line
			(start -0.67945 -0.305054)
			(end -0.12065 -0.305054)
			(stroke
				(width 0.1)
				(type default)
			)
			(layer "F.Fab")
		)
		(pad "1" smd circle
			(at -0.40005 0 180)
			(size 0 0)
			(layers "F.Cu" "F.Mask" "F.Paste")
			(net "P12V_OCP_VCC_2")
		)
		(pad "2" smd circle
			(at 0.40005 0 180)
			(size 0 0)
			(layers "F.Cu" "F.Mask" "F.Paste")
			(net "GND")
		)
	)
	(footprint ""
		(layer "F.Cu")
		(at 442.18352 -434.549296)
		(property "Reference" "Q106"
			(at -1.499616 -2.115566 0)
			(unlocked yes)
			(layer "F.SilkS")
			(effects
				(font
					(size 0.7874 0.5842)
					(thickness 0.1524)
				)
				(justify left)
			)
		)
		(property "Value" ""
			(at 0 0 0)
			(layer "F.Fab")
			(effects
				(font
					(size 1.27 1.27)
				)
			)
		)
		(duplicate_pad_numbers_are_jumpers no)
		(fp_line
			(start -1.332738 -1.100074)
			(end -0.4826 -1.100074)
			(stroke
				(width 0.1524)
				(type default)
			)
			(layer "F.SilkS")
		)
		(fp_line
			(start -1.332738 1.100074)
			(end -1.332738 -1.100074)
			(stroke
				(width 0.1524)
				(type default)
			)
			(layer "F.SilkS")
		)
		(fp_line
			(start -0.4826 -1.100074)
			(end 0 -0.541274)
			(stroke
				(width 0.1524)
				(type default)
			)
			(layer "F.SilkS")
		)
		(fp_line
			(start 0 -0.541274)
			(end 0.4826 -1.100074)
			(stroke
				(width 0.1524)
				(type default)
			)
			(layer "F.SilkS")
		)
		(fp_line
			(start 0.4826 -1.100074)
			(end 1.332738 -1.100074)
			(stroke
				(width 0.1524)
				(type default)
			)
			(layer "F.SilkS")
		)
		(fp_line
			(start 1.332738 -1.100074)
			(end 1.332738 1.100074)
			(stroke
				(width 0.1524)
				(type default)
			)
			(layer "F.SilkS")
		)
		(fp_line
			(start 1.332738 1.100074)
			(end -1.332738 1.100074)
			(stroke
				(width 0.1524)
				(type default)
			)
			(layer "F.SilkS")
		)
		(fp_poly
			(pts
				(xy -1.533144 -0.649986) (xy -2.2352 -0.298958) (xy -2.2352 -1.001014)
			)
			(stroke
				(width 0)
				(type default)
			)
			(fill yes)
			(layer "F.SilkS")
		)
		(fp_line
			(start -0.674878 -1.100074)
			(end 0.674878 -1.100074)
			(stroke
				(width 0.1)
				(type default)
			)
			(layer "F.Fab")
		)
		(fp_line
			(start -0.674878 1.100074)
			(end -0.674878 -1.100074)
			(stroke
				(width 0.1)
				(type default)
			)
			(layer "F.Fab")
		)
		(fp_line
			(start 0.674878 -1.100074)
			(end 0.674878 1.100074)
			(stroke
				(width 0.1)
				(type default)
			)
			(layer "F.Fab")
		)
		(fp_line
			(start 0.674878 1.100074)
			(end -0.674878 1.100074)
			(stroke
				(width 0.1)
				(type default)
			)
			(layer "F.Fab")
		)
		(fp_poly
			(pts
				(xy -2.2352 -0.298958) (xy -2.2352 -1.001014) (xy -1.533144 -0.649986)
			)
			(stroke
				(width 0)
				(type default)
			)
			(fill yes)
			(layer "F.Fab")
		)
		(pad "1" smd rect
			(at -0.94996 -0.649986 90)
			(size 0.4318 0.508)
			(layers "F.Cu" "F.Mask" "F.Paste")
			(net "GND")
		)
		(pad "2" smd rect
			(at -0.94996 0 90)
			(size 0.4318 0.508)
			(layers "F.Cu" "F.Mask" "F.Paste")
			(net "GPU_WP_HW_CTRL_N")
		)
		(pad "3" smd rect
			(at -0.94996 0.649986 90)
			(size 0.4318 0.508)
			(layers "F.Cu" "F.Mask" "F.Paste")
			(net "GPU_WP_HW_CTRL_ISO_N")
		)
		(pad "4" smd rect
			(at 0.94996 0.649986 90)
			(size 0.4318 0.508)
			(layers "F.Cu" "F.Mask" "F.Paste")
			(net "GND")
		)
		(pad "5" smd rect
			(at 0.94996 0 90)
			(size 0.4318 0.508)
			(layers "F.Cu" "F.Mask" "F.Paste")
			(net "GPU_WP_HW_CTRL_ISO")
		)
		(pad "6" smd rect
			(at 0.94996 -0.649986 90)
			(size 0.4318 0.508)
			(layers "F.Cu" "F.Mask" "F.Paste")
			(net "GPU_WP_HW_CTRL_ISO")
		)
	)
	(footprint ""
		(layer "F.Cu")
		(at 93.717364 -408.517344 -90)
		(property "Reference" "C6660"
			(at 0 0 270)
			(layer "F.SilkS")
			(hide yes)
			(effects
				(font
					(size 1.27 1.27)
				)
			)
		)
		(property "Value" ""
			(at 0 0 270)
			(layer "F.Fab")
			(effects
				(font
					(size 1.27 1.27)
				)
			)
		)
		(duplicate_pad_numbers_are_jumpers no)
		(fp_line
			(start -0.299974 0.150114)
			(end -0.299974 -0.150114)
			(stroke
				(width 0.1)
				(type default)
			)
			(layer "F.Fab")
		)
		(fp_line
			(start 0.299974 0.150114)
			(end -0.299974 0.150114)
			(stroke
				(width 0.1)
				(type default)
			)
			(layer "F.Fab")
		)
		(fp_line
			(start -0.299974 -0.150114)
			(end 0.299974 -0.150114)
			(stroke
				(width 0.1)
				(type default)
			)
			(layer "F.Fab")
		)
		(fp_line
			(start 0.299974 -0.150114)
			(end 0.299974 0.150114)
			(stroke
				(width 0.1)
				(type default)
			)
			(layer "F.Fab")
		)
		(pad "1" smd rect
			(at -0.2667 0 270)
			(size 0.3048 0.381)
			(layers "F.Cu" "F.Mask" "F.Paste")
			(net "P5E_CPU1_P0_TX_BUF_C_DN<15>")
		)
		(pad "2" smd rect
			(at 0.2667 0 270)
			(size 0.3048 0.381)
			(layers "F.Cu" "F.Mask" "F.Paste")
			(net "P5E_CPU1_P0_TX_BUF_DN<15>")
		)
	)
	(footprint ""
		(layer "F.Cu")
		(at 79.523844 -339.644736 90)
		(property "Reference" "PR259"
			(at 0 0 90)
			(layer "F.SilkS")
			(hide yes)
			(effects
				(font
					(size 1.27 1.27)
				)
			)
		)
		(property "Value" ""
			(at 0 0 90)
			(layer "F.Fab")
			(effects
				(font
					(size 1.27 1.27)
				)
			)
		)
		(duplicate_pad_numbers_are_jumpers no)
		(fp_line
			(start 0.7874 -0.4064)
			(end 0.7874 0.4064)
			(stroke
				(width 0.1524)
				(type default)
			)
			(layer "F.SilkS")
		)
		(fp_line
			(start -0.7874 -0.4064)
			(end 0.7874 -0.4064)
			(stroke
				(width 0.1524)
				(type default)
			)
			(layer "F.SilkS")
		)
		(fp_line
			(start 0.7874 0.4064)
			(end -0.7874 0.4064)
			(stroke
				(width 0.1524)
				(type default)
			)
			(layer "F.SilkS")
		)
		(fp_line
			(start -0.7874 0.4064)
			(end -0.7874 -0.4064)
			(stroke
				(width 0.1524)
				(type default)
			)
			(layer "F.SilkS")
		)
		(fp_line
			(start -0.12065 -0.305054)
			(end -0.12065 -0.2794)
			(stroke
				(width 0.1)
				(type default)
			)
			(layer "F.Fab")
		)
		(fp_line
			(start -0.67945 -0.305054)
			(end -0.12065 -0.305054)
			(stroke
				(width 0.1)
				(type default)
			)
			(layer "F.Fab")
		)
		(fp_line
			(start 0.67945 -0.3048)
			(end 0.67945 0.3048)
			(stroke
				(width 0.1)
				(type default)
			)
			(layer "F.Fab")
		)
		(fp_line
			(start 0.12065 -0.3048)
			(end 0.67945 -0.3048)
			(stroke
				(width 0.1)
				(type default)
			)
			(layer "F.Fab")
		)
		(fp_line
			(start 0.12065 -0.2794)
			(end 0.12065 -0.3048)
			(stroke
				(width 0.1)
				(type default)
			)
			(layer "F.Fab")
		)
		(fp_line
			(start -0.12065 -0.2794)
			(end 0.12065 -0.2794)
			(stroke
				(width 0.1)
				(type default)
			)
			(layer "F.Fab")
		)
		(fp_line
			(start 0.120396 0.2794)
			(end -0.12065 0.2794)
			(stroke
				(width 0.1)
				(type default)
			)
			(layer "F.Fab")
		)
		(fp_line
			(start -0.12065 0.2794)
			(end -0.12065 0.3048)
			(stroke
				(width 0.1)
				(type default)
			)
			(layer "F.Fab")
		)
		(fp_line
			(start 0.67945 0.3048)
			(end 0.120396 0.3048)
			(stroke
				(width 0.1)
				(type default)
			)
			(layer "F.Fab")
		)
		(fp_line
			(start 0.120396 0.3048)
			(end 0.120396 0.2794)
			(stroke
				(width 0.1)
				(type default)
			)
			(layer "F.Fab")
		)
		(fp_line
			(start -0.12065 0.3048)
			(end -0.67945 0.3048)
			(stroke
				(width 0.1)
				(type default)
			)
			(layer "F.Fab")
		)
		(fp_line
			(start -0.67945 0.3048)
			(end -0.67945 -0.305054)
			(stroke
				(width 0.1)
				(type default)
			)
			(layer "F.Fab")
		)
		(pad "1" smd circle
			(at -0.40005 0 90)
			(size 0 0)
			(layers "F.Cu" "F.Mask" "F.Paste")
			(net "SW_PVDDCR_CPU1_P1_BOOT2")
		)
		(pad "2" smd circle
			(at 0.40005 0 90)
			(size 0 0)
			(layers "F.Cu" "F.Mask" "F.Paste")
			(net "SW_PVDDCR_CPU1_P1_BOOT2_R")
		)
	)
	(footprint ""
		(layer "F.Cu")
		(at 384.760978 -182.745634 90)
		(property "Reference" "PC548_C0P0_3"
			(at 0 0 90)
			(layer "F.SilkS")
			(hide yes)
			(effects
				(font
					(size 1.27 1.27)
				)
			)
		)
		(property "Value" ""
			(at 0 0 90)
			(layer "F.Fab")
			(effects
				(font
					(size 1.27 1.27)
				)
			)
		)
		(duplicate_pad_numbers_are_jumpers no)
		(fp_line
			(start 0.7874 -0.4064)
			(end 0.7874 0.4064)
			(stroke
				(width 0.1524)
				(type default)
			)
			(layer "F.SilkS")
		)
		(fp_line
			(start -0.7874 -0.4064)
			(end 0.7874 -0.4064)
			(stroke
				(width 0.1524)
				(type default)
			)
			(layer "F.SilkS")
		)
		(fp_line
			(start 0.7874 0.4064)
			(end -0.7874 0.4064)
			(stroke
				(width 0.1524)
				(type default)
			)
			(layer "F.SilkS")
		)
		(fp_line
			(start -0.7874 0.4064)
			(end -0.7874 -0.4064)
			(stroke
				(width 0.1524)
				(type default)
			)
			(layer "F.SilkS")
		)
		(fp_line
			(start -0.12065 -0.305054)
			(end -0.12065 -0.2794)
			(stroke
				(width 0.1)
				(type default)
			)
			(layer "F.Fab")
		)
		(fp_line
			(start -0.67945 -0.305054)
			(end -0.12065 -0.305054)
			(stroke
				(width 0.1)
				(type default)
			)
			(layer "F.Fab")
		)
		(fp_line
			(start 0.67945 -0.3048)
			(end 0.67945 0.3048)
			(stroke
				(width 0.1)
				(type default)
			)
			(layer "F.Fab")
		)
		(fp_line
			(start 0.12065 -0.3048)
			(end 0.67945 -0.3048)
			(stroke
				(width 0.1)
				(type default)
			)
			(layer "F.Fab")
		)
		(fp_line
			(start 0.12065 -0.2794)
			(end 0.12065 -0.3048)
			(stroke
				(width 0.1)
				(type default)
			)
			(layer "F.Fab")
		)
		(fp_line
			(start -0.12065 -0.2794)
			(end 0.12065 -0.2794)
			(stroke
				(width 0.1)
				(type default)
			)
			(layer "F.Fab")
		)
		(fp_line
			(start 0.120396 0.2794)
			(end -0.12065 0.2794)
			(stroke
				(width 0.1)
				(type default)
			)
			(layer "F.Fab")
		)
		(fp_line
			(start -0.12065 0.2794)
			(end -0.12065 0.3048)
			(stroke
				(width 0.1)
				(type default)
			)
			(layer "F.Fab")
		)
		(fp_line
			(start 0.67945 0.3048)
			(end 0.120396 0.3048)
			(stroke
				(width 0.1)
				(type default)
			)
			(layer "F.Fab")
		)
		(fp_line
			(start 0.120396 0.3048)
			(end 0.120396 0.2794)
			(stroke
				(width 0.1)
				(type default)
			)
			(layer "F.Fab")
		)
		(fp_line
			(start -0.12065 0.3048)
			(end -0.67945 0.3048)
			(stroke
				(width 0.1)
				(type default)
			)
			(layer "F.Fab")
		)
		(fp_line
			(start -0.67945 0.3048)
			(end -0.67945 -0.305054)
			(stroke
				(width 0.1)
				(type default)
			)
			(layer "F.Fab")
		)
		(pad "1" smd circle
			(at -0.40005 0 90)
			(size 0 0)
			(layers "F.Cu" "F.Mask" "F.Paste")
			(net "PVDDCR_CPU0_P0_PVCC")
		)
		(pad "2" smd circle
			(at 0.40005 0 90)
			(size 0 0)
			(layers "F.Cu" "F.Mask" "F.Paste")
			(net "GND")
		)
	)
	(footprint ""
		(layer "F.Cu")
		(at 443.859666 -380.13767 -90)
		(property "Reference" "PC6571"
			(at 4.75234 2.153666 0)
			(unlocked yes)
			(layer "F.SilkS")
			(effects
				(font
					(size 0.7874 0.5842)
					(thickness 0.1524)
				)
				(justify left)
			)
		)
		(property "Value" ""
			(at 0 0 270)
			(layer "F.Fab")
			(effects
				(font
					(size 1.27 1.27)
				)
			)
		)
		(duplicate_pad_numbers_are_jumpers no)
		(fp_line
			(start -1.988058 2.750058)
			(end 2.750058 2.750058)
			(stroke
				(width 0.1524)
				(type default)
			)
			(layer "F.SilkS")
		)
		(fp_line
			(start 2.750058 2.750058)
			(end 2.750058 0.9398)
			(stroke
				(width 0.1524)
				(type default)
			)
			(layer "F.SilkS")
		)
		(fp_line
			(start -2.750058 1.988058)
			(end -1.988058 2.750058)
			(stroke
				(width 0.1524)
				(type default)
			)
			(layer "F.SilkS")
		)
		(fp_line
			(start -2.750058 0.9398)
			(end -2.750058 1.988058)
			(stroke
				(width 0.1524)
				(type default)
			)
			(layer "F.SilkS")
		)
		(fp_line
			(start 2.750058 -0.9398)
			(end 2.750058 -2.750058)
			(stroke
				(width 0.1524)
				(type default)
			)
			(layer "F.SilkS")
		)
		(fp_line
			(start -2.750058 -1.988058)
			(end -2.750058 -0.9398)
			(stroke
				(width 0.1524)
				(type default)
			)
			(layer "F.SilkS")
		)
		(fp_line
			(start -1.988058 -2.750058)
			(end -2.750058 -1.988058)
			(stroke
				(width 0.1524)
				(type default)
			)
			(layer "F.SilkS")
		)
		(fp_line
			(start 2.750058 -2.750058)
			(end -1.988058 -2.750058)
			(stroke
				(width 0.1524)
				(type default)
			)
			(layer "F.SilkS")
		)
		(fp_line
			(start -2.750058 2.750058)
			(end 2.750058 2.750058)
			(stroke
				(width 0.1)
				(type default)
			)
			(layer "F.Fab")
		)
		(fp_line
			(start 2.750058 2.750058)
			(end 2.750058 -2.750058)
			(stroke
				(width 0.1)
				(type default)
			)
			(layer "F.Fab")
		)
		(fp_line
			(start -2.750058 -2.750058)
			(end -2.750058 2.750058)
			(stroke
				(width 0.1)
				(type default)
			)
			(layer "F.Fab")
		)
		(fp_line
			(start 2.750058 -2.750058)
			(end -2.750058 -2.750058)
			(stroke
				(width 0.1)
				(type default)
			)
			(layer "F.Fab")
		)
		(pad "1" smd rect
			(at -2.199894 0)
			(size 1.6002 3.0226)
			(layers "F.Cu" "F.Mask" "F.Paste")
			(net "P0V9_CPU0_RT_2D")
		)
		(pad "2" smd rect
			(at 2.199894 0)
			(size 1.6002 3.0226)
			(layers "F.Cu" "F.Mask" "F.Paste")
			(net "GND")
		)
	)
	(footprint ""
		(layer "F.Cu")
		(at 24.759158 -402.599906 90)
		(property "Reference" "PL6510"
			(at -3.592576 -2.153158 0)
			(unlocked yes)
			(layer "F.SilkS")
			(effects
				(font
					(size 0.7874 0.5842)
					(thickness 0.1524)
				)
				(justify left)
			)
		)
		(property "Value" ""
			(at 0 0 90)
			(layer "F.Fab")
			(effects
				(font
					(size 1.27 1.27)
				)
			)
		)
		(duplicate_pad_numbers_are_jumpers no)
		(fp_line
			(start 2.249932 -2.249932)
			(end 2.249932 -1.3843)
			(stroke
				(width 0.1524)
				(type default)
			)
			(layer "F.SilkS")
		)
		(fp_line
			(start -2.249932 -2.249932)
			(end 2.249932 -2.249932)
			(stroke
				(width 0.1524)
				(type default)
			)
			(layer "F.SilkS")
		)
		(fp_line
			(start -2.249932 -1.3843)
			(end -2.249932 -2.249932)
			(stroke
				(width 0.1524)
				(type default)
			)
			(layer "F.SilkS")
		)
		(fp_line
			(start 2.249932 1.3843)
			(end 2.249932 2.249932)
			(stroke
				(width 0.1524)
				(type default)
			)
			(layer "F.SilkS")
		)
		(fp_line
			(start 2.249932 2.249932)
			(end -2.249932 2.249932)
			(stroke
				(width 0.1524)
				(type default)
			)
			(layer "F.SilkS")
		)
		(fp_line
			(start -2.249932 2.249932)
			(end -2.249932 1.3843)
			(stroke
				(width 0.1524)
				(type default)
			)
			(layer "F.SilkS")
		)
		(fp_line
			(start 2.249932 -2.249932)
			(end 2.249932 2.249932)
			(stroke
				(width 0.1)
				(type default)
			)
			(layer "F.Fab")
		)
		(fp_line
			(start -2.249932 -2.249932)
			(end 2.249932 -2.249932)
			(stroke
				(width 0.1)
				(type default)
			)
			(layer "F.Fab")
		)
		(fp_line
			(start 2.249932 2.249932)
			(end -2.249932 2.249932)
			(stroke
				(width 0.1)
				(type default)
			)
			(layer "F.Fab")
		)
		(fp_line
			(start -2.249932 2.249932)
			(end -2.249932 -2.249932)
			(stroke
				(width 0.1)
				(type default)
			)
			(layer "F.Fab")
		)
		(pad "1" smd rect
			(at -1.82499 0 90)
			(size 1.0668 2.5146)
			(layers "F.Cu" "F.Mask" "F.Paste")
			(net "SW_P12V_AUX_P0V9_RETIMER_CPU1_FLT")
		)
		(pad "2" smd rect
			(at 1.82499 0 90)
			(size 1.0668 2.5146)
			(layers "F.Cu" "F.Mask" "F.Paste")
			(net "P12V_AUX")
		)
	)
	(footprint ""
		(layer "F.Cu")
		(at 52.22748 -29.657548 90)
		(property "Reference" "U225"
			(at -2.483612 3.139948 90)
			(unlocked yes)
			(layer "F.SilkS")
			(effects
				(font
					(size 0.7874 0.5842)
					(thickness 0.1524)
				)
				(justify left)
			)
		)
		(property "Value" ""
			(at 0 0 90)
			(layer "F.Fab")
			(effects
				(font
					(size 1.27 1.27)
				)
			)
		)
		(duplicate_pad_numbers_are_jumpers no)
		(fp_line
			(start 1.400048 -1.100074)
			(end -1.400048 -1.100074)
			(stroke
				(width 0.1524)
				(type default)
			)
			(layer "F.SilkS")
		)
		(fp_line
			(start 1.400048 -1.100074)
			(end 1.400048 1.100074)
			(stroke
				(width 0.1524)
				(type default)
			)
			(layer "F.SilkS")
		)
		(fp_line
			(start 1.400048 1.100074)
			(end -1.400048 1.100074)
			(stroke
				(width 0.1524)
				(type default)
			)
			(layer "F.SilkS")
		)
		(fp_line
			(start -1.400048 1.100074)
			(end -1.400048 -1.100074)
			(stroke
				(width 0.1524)
				(type default)
			)
			(layer "F.SilkS")
		)
		(fp_poly
			(pts
				(xy -2.606548 -0.141986) (xy -2.606548 -1.157986) (xy -1.590548 -0.649986)
			)
			(stroke
				(width 0)
				(type default)
			)
			(fill yes)
			(layer "F.SilkS")
		)
		(fp_line
			(start 0.674878 -1.100074)
			(end 0.674878 1.100074)
			(stroke
				(width 0.1)
				(type default)
			)
			(layer "F.Fab")
		)
		(fp_line
			(start -0.674878 -1.100074)
			(end 0.674878 -1.100074)
			(stroke
				(width 0.1)
				(type default)
			)
			(layer "F.Fab")
		)
		(fp_line
			(start 0.674878 1.100074)
			(end -0.674878 1.100074)
			(stroke
				(width 0.1)
				(type default)
			)
			(layer "F.Fab")
		)
		(fp_line
			(start -0.674878 1.100074)
			(end -0.674878 -1.100074)
			(stroke
				(width 0.1)
				(type default)
			)
			(layer "F.Fab")
		)
		(fp_poly
			(pts
				(xy -1.590548 -0.649986) (xy -2.606548 -1.157986) (xy -2.606548 -0.141986)
			)
			(stroke
				(width 0)
				(type default)
			)
			(fill yes)
			(layer "F.Fab")
		)
		(pad "1" smd rect
			(at -0.94996 -0.649986)
			(size 0.4318 0.6096)
			(layers "F.Cu" "F.Mask" "F.Paste")
			(net "OCP_V3_2_AUX_PWR_EN_R3")
		)
		(pad "2" smd rect
			(at -0.94996 0)
			(size 0.4318 0.6096)
			(layers "F.Cu" "F.Mask" "F.Paste")
			(net "RST_SMB_SWITCH_N")
		)
		(pad "3" smd rect
			(at -0.94996 0.649986)
			(size 0.4318 0.6096)
			(layers "F.Cu" "F.Mask" "F.Paste")
			(net "GND")
		)
		(pad "4" smd rect
			(at 0.94996 0.649986)
			(size 0.4318 0.6096)
			(layers "F.Cu" "F.Mask" "F.Paste")
			(net "RST_HP_OCP_V3_2_R_N")
		)
		(pad "5" smd rect
			(at 0.94996 -0.649986)
			(size 0.4318 0.6096)
			(layers "F.Cu" "F.Mask" "F.Paste")
			(net "P3V3_AUX")
		)
	)
	(footprint ""
		(layer "F.Cu")
		(at 70.409054 -335.000092)
		(property "Reference" "PU37"
			(at 2.996946 -8.508238 0)
			(unlocked yes)
			(layer "F.SilkS")
			(effects
				(font
					(size 0.7874 0.5842)
					(thickness 0.1524)
				)
				(justify left)
			)
		)
		(property "Value" ""
			(at 0 0 0)
			(layer "F.Fab")
			(effects
				(font
					(size 1.27 1.27)
				)
			)
		)
		(duplicate_pad_numbers_are_jumpers no)
		(fp_line
			(start -2.500122 -2.999994)
			(end -2.24409 -2.999994)
			(stroke
				(width 0.1524)
				(type default)
			)
			(layer "F.SilkS")
		)
		(fp_line
			(start -2.500122 -2.529078)
			(end -2.500122 -2.999994)
			(stroke
				(width 0.1524)
				(type default)
			)
			(layer "F.SilkS")
		)
		(fp_line
			(start -2.500122 0.6604)
			(end -2.500122 0.229108)
			(stroke
				(width 0.1524)
				(type default)
			)
			(layer "F.SilkS")
		)
		(fp_line
			(start -2.500122 2.999994)
			(end -2.500122 2.339594)
			(stroke
				(width 0.1524)
				(type default)
			)
			(layer "F.SilkS")
		)
		(fp_line
			(start -2.2987 2.999994)
			(end -2.500122 2.999994)
			(stroke
				(width 0.1524)
				(type default)
			)
			(layer "F.SilkS")
		)
		(fp_line
			(start 2.31394 -2.999994)
			(end 2.500122 -2.999994)
			(stroke
				(width 0.1524)
				(type default)
			)
			(layer "F.SilkS")
		)
		(fp_line
			(start 2.500122 -2.999994)
			(end 2.500122 -2.44348)
			(stroke
				(width 0.1524)
				(type default)
			)
			(layer "F.SilkS")
		)
		(fp_line
			(start 2.500122 2.339594)
			(end 2.500122 2.999994)
			(stroke
				(width 0.1524)
				(type default)
			)
			(layer "F.SilkS")
		)
		(fp_line
			(start 2.500122 2.999994)
			(end 2.2987 2.999994)
			(stroke
				(width 0.1524)
				(type default)
			)
			(layer "F.SilkS")
		)
		(fp_poly
			(pts
				(xy -2.749296 -2.412238) (xy -3.422904 -2.636774) (xy -2.973832 -3.085846)
			)
			(stroke
				(width 0)
				(type default)
			)
			(fill yes)
			(layer "F.SilkS")
		)
		(fp_line
			(start -2.500122 -2.999994)
			(end 2.500122 -2.999994)
			(stroke
				(width 0.1)
				(type default)
			)
			(layer "F.Fab")
		)
		(fp_line
			(start -2.500122 2.999994)
			(end -2.500122 -2.999994)
			(stroke
				(width 0.1)
				(type default)
			)
			(layer "F.Fab")
		)
		(fp_line
			(start 2.500122 -2.999994)
			(end 2.500122 2.999994)
			(stroke
				(width 0.1)
				(type default)
			)
			(layer "F.Fab")
		)
		(fp_line
			(start 2.500122 2.999994)
			(end -2.500122 2.999994)
			(stroke
				(width 0.1)
				(type default)
			)
			(layer "F.Fab")
		)
		(fp_poly
			(pts
				(xy -4.218432 -2.783078) (xy -4.218432 -1.767078) (xy -3.202432 -2.275078)
			)
			(stroke
				(width 0)
				(type default)
			)
			(fill yes)
			(layer "F.Fab")
		)
		(pad "1" smd rect
			(at -2.400046 -2.275078 90)
			(size 0.2286 0.6096)
			(layers "F.Cu" "F.Mask" "F.Paste")
			(net "PVDDCR_CPU1_P1_VOS3")
		)
		(pad "2" smd rect
			(at -2.400046 -1.82499 90)
			(size 0.2286 0.6096)
			(layers "F.Cu" "F.Mask" "F.Paste")
			(net "GND")
		)
		(pad "3" smd rect
			(at -2.400046 -1.374902 90)
			(size 0.2286 0.6096)
			(layers "F.Cu" "F.Mask" "F.Paste")
			(net "PVDDCR_CPU1_P1_VCC3")
		)
		(pad "4" smd rect
			(at -2.400046 -0.925068 90)
			(size 0.2286 0.6096)
			(layers "F.Cu" "F.Mask" "F.Paste")
			(net "PVDDCR_CPU1_P1_PVCC")
		)
		(pad "5" smd rect
			(at -2.400046 -0.47498 90)
			(size 0.2286 0.6096)
			(layers "F.Cu" "F.Mask" "F.Paste")
			(net "GND")
		)
		(pad "6" smd rect
			(at -2.400046 -0.024892 90)
			(size 0.2286 0.6096)
			(layers "F.Cu" "F.Mask" "F.Paste")
			(net "NC_PVDDCR_CPU1_P1_GL1_3")
		)
		(pad "7_9-20_24" smd circle
			(at 0 1.150112 90)
			(size 0 0)
			(layers "F.Cu" "F.Mask" "F.Paste")
			(net "GND")
		)
		(pad "10_19" smd rect
			(at 0 2.899918 90)
			(size 0.6096 4.318)
			(layers "F.Cu" "F.Mask" "F.Paste")
			(net "SW_PVDDCR_CPU1_P1_SW3")
		)
		(pad "25_29" smd rect
			(at 1.549908 -1.279906 270)
			(size 2.0574 2.3114)
			(layers "F.Cu" "F.Mask" "F.Paste")
			(net "SW_P12V_AUX_PVDDCR_CPU1_P1_FLT")
		)
		(pad "30" smd rect
			(at 2.05994 -2.899918)
			(size 0.2286 0.6096)
			(layers "F.Cu" "F.Mask" "F.Paste")
			(net "SW_P12V_AUX_PVDDCR_CPU1_P1_FLT")
		)
		(pad "31" smd rect
			(at 1.610106 -2.899918)
			(size 0.2286 0.6096)
			(layers "F.Cu" "F.Mask" "F.Paste")
			(net "NC_PVDDCR_CPU1_P1_DNC3")
		)
		(pad "32" smd rect
			(at 1.160018 -2.899918)
			(size 0.2286 0.6096)
			(layers "F.Cu" "F.Mask" "F.Paste")
			(net "SW_PVDDCR_CPU1_P1_BOOTR3")
		)
		(pad "33" smd rect
			(at 0.70993 -2.899918)
			(size 0.2286 0.6096)
			(layers "F.Cu" "F.Mask" "F.Paste")
			(net "SW_PVDDCR_CPU1_P1_BOOT3")
		)
		(pad "34" smd rect
			(at 0.260096 -2.899918)
			(size 0.2286 0.6096)
			(layers "F.Cu" "F.Mask" "F.Paste")
			(net "PVDDCR_CPU1_P1_PWM3")
		)
		(pad "35" smd rect
			(at -0.189992 -2.899918)
			(size 0.2286 0.6096)
			(layers "F.Cu" "F.Mask" "F.Paste")
			(net "PVDDCR_CPU1_P1_VCC3")
		)
		(pad "36" smd rect
			(at -0.64008 -2.899918)
			(size 0.2286 0.6096)
			(layers "F.Cu" "F.Mask" "F.Paste")
			(net "PVDDCR_CPU1_P1_TEMP0")
		)
		(pad "37" smd rect
			(at -1.089914 -2.899918)
			(size 0.2286 0.6096)
			(layers "F.Cu" "F.Mask" "F.Paste")
			(net "PVDDCR_CPU1_P1_LSET3")
		)
		(pad "38" smd rect
			(at -1.540002 -2.899918)
			(size 0.2286 0.6096)
			(layers "F.Cu" "F.Mask" "F.Paste")
			(net "PVDDCR_CPU1_P1_IMON3")
		)
		(pad "39" smd rect
			(at -1.99009 -2.899918)
			(size 0.2286 0.6096)
			(layers "F.Cu" "F.Mask" "F.Paste")
			(net "PVDDCR_CPU1_P1_VCCS")
		)
		(pad "40" smd rect
			(at -0.87503 -1.27508)
			(size 1.7526 1.9558)
			(layers "F.Cu" "F.Mask" "F.Paste")
			(net "GND")
		)
		(pad "41" smd rect
			(at -1.525016 0.249936 270)
			(size 0.3048 0.4572)
			(layers "F.Cu" "F.Mask" "F.Paste")
			(net "NC_PVDDCR_CPU1_P1_GL2_3")
		)
		(zone
			(layer "F.Cu")
			(hatch none 0.5)
			(connect_pads
				(clearance 0)
			)
			(min_thickness 0.25)
			(keepout
				(tracks not_allowed)
				(vias allowed)
				(pads allowed)
				(copperpour not_allowed)
				(footprints allowed)
			)
			(placement
				(enabled no)
				(sheetname "")
			)
			(fill
				(thermal_gap 0.5)
				(thermal_bridge_width 0.5)
				(island_removal_mode 0)
			)
			(polygon
				(pts
					(xy 67.908932 -332.417674) (xy 67.908932 -332.749398) (xy 72.909176 -332.749398) (xy 72.909176 -332.411578)
					(xy 72.618854 -332.411578) (xy 72.618854 -332.455774) (xy 68.199254 -332.455774) (xy 68.199254 -332.417674)
				)
			)
		)
		(zone
			(layer "F.Cu")
			(hatch none 0.5)
			(connect_pads
				(clearance 0)
			)
			(min_thickness 0.25)
			(keepout
				(tracks not_allowed)
				(vias allowed)
				(pads allowed)
				(copperpour not_allowed)
				(footprints allowed)
			)
			(placement
				(enabled no)
				(sheetname "")
			)
			(fill
				(thermal_gap 0.5)
				(thermal_bridge_width 0.5)
				(island_removal_mode 0)
			)
			(polygon
				(pts
					(xy 70.461124 -335.246472) (xy 70.461124 -337.303872) (xy 68.606924 -337.303872) (xy 68.606924 -337.062826)
					(xy 68.364608 -337.062826) (xy 68.364608 -337.54441) (xy 72.286368 -337.54441) (xy 72.286368 -337.359498)
					(xy 70.752462 -337.359498) (xy 70.752462 -335.200498) (xy 72.909176 -335.200498) (xy 72.909176 -334.950816)
					(xy 70.75678 -334.950816)
				)
			)
		)
	)
	(footprint ""
		(layer "F.Cu")
		(at 43.1419 -100.34016 180)
		(property "Reference" "R700"
			(at 0 0 180)
			(layer "F.SilkS")
			(hide yes)
			(effects
				(font
					(size 1.27 1.27)
				)
			)
		)
		(property "Value" ""
			(at 0 0 180)
			(layer "F.Fab")
			(effects
				(font
					(size 1.27 1.27)
				)
			)
		)
		(duplicate_pad_numbers_are_jumpers no)
		(fp_line
			(start 0.7874 0.4064)
			(end -0.7874 0.4064)
			(stroke
				(width 0.1524)
				(type default)
			)
			(layer "F.SilkS")
		)
		(fp_line
			(start 0.7874 -0.4064)
			(end 0.7874 0.4064)
			(stroke
				(width 0.1524)
				(type default)
			)
			(layer "F.SilkS")
		)
		(fp_line
			(start -0.7874 0.4064)
			(end -0.7874 -0.4064)
			(stroke
				(width 0.1524)
				(type default)
			)
			(layer "F.SilkS")
		)
		(fp_line
			(start -0.7874 -0.4064)
			(end 0.7874 -0.4064)
			(stroke
				(width 0.1524)
				(type default)
			)
			(layer "F.SilkS")
		)
		(fp_line
			(start 0.67945 0.3048)
			(end 0.120396 0.3048)
			(stroke
				(width 0.1)
				(type default)
			)
			(layer "F.Fab")
		)
		(fp_line
			(start 0.67945 -0.3048)
			(end 0.67945 0.3048)
			(stroke
				(width 0.1)
				(type default)
			)
			(layer "F.Fab")
		)
		(fp_line
			(start 0.12065 -0.2794)
			(end 0.12065 -0.3048)
			(stroke
				(width 0.1)
				(type default)
			)
			(layer "F.Fab")
		)
		(fp_line
			(start 0.12065 -0.3048)
			(end 0.67945 -0.3048)
			(stroke
				(width 0.1)
				(type default)
			)
			(layer "F.Fab")
		)
		(fp_line
			(start 0.120396 0.3048)
			(end 0.120396 0.2794)
			(stroke
				(width 0.1)
				(type default)
			)
			(layer "F.Fab")
		)
		(fp_line
			(start 0.120396 0.2794)
			(end -0.12065 0.2794)
			(stroke
				(width 0.1)
				(type default)
			)
			(layer "F.Fab")
		)
		(fp_line
			(start -0.12065 0.3048)
			(end -0.67945 0.3048)
			(stroke
				(width 0.1)
				(type default)
			)
			(layer "F.Fab")
		)
		(fp_line
			(start -0.12065 0.2794)
			(end -0.12065 0.3048)
			(stroke
				(width 0.1)
				(type default)
			)
			(layer "F.Fab")
		)
		(fp_line
			(start -0.12065 -0.2794)
			(end 0.12065 -0.2794)
			(stroke
				(width 0.1)
				(type default)
			)
			(layer "F.Fab")
		)
		(fp_line
			(start -0.12065 -0.305054)
			(end -0.12065 -0.2794)
			(stroke
				(width 0.1)
				(type default)
			)
			(layer "F.Fab")
		)
		(fp_line
			(start -0.67945 0.3048)
			(end -0.67945 -0.305054)
			(stroke
				(width 0.1)
				(type default)
			)
			(layer "F.Fab")
		)
		(fp_line
			(start -0.67945 -0.305054)
			(end -0.12065 -0.305054)
			(stroke
				(width 0.1)
				(type default)
			)
			(layer "F.Fab")
		)
		(pad "1" smd circle
			(at -0.40005 0 180)
			(size 0 0)
			(layers "F.Cu" "F.Mask" "F.Paste")
			(net "P12V_AUX")
		)
		(pad "2" smd circle
			(at 0.40005 0 180)
			(size 0 0)
			(layers "F.Cu" "F.Mask" "F.Paste")
			(net "P12V_AUX_DSC_VOL")
		)
	)
	(footprint ""
		(layer "F.Cu")
		(at 160.40227 -73.24217 -90)
		(property "Reference" "R1311"
			(at 0 0 270)
			(layer "F.SilkS")
			(hide yes)
			(effects
				(font
					(size 1.27 1.27)
				)
			)
		)
		(property "Value" ""
			(at 0 0 270)
			(layer "F.Fab")
			(effects
				(font
					(size 1.27 1.27)
				)
			)
		)
		(duplicate_pad_numbers_are_jumpers no)
		(fp_line
			(start -0.7874 0.4064)
			(end -0.7874 -0.4064)
			(stroke
				(width 0.1524)
				(type default)
			)
			(layer "F.SilkS")
		)
		(fp_line
			(start 0.7874 0.4064)
			(end -0.7874 0.4064)
			(stroke
				(width 0.1524)
				(type default)
			)
			(layer "F.SilkS")
		)
		(fp_line
			(start -0.7874 -0.4064)
			(end 0.7874 -0.4064)
			(stroke
				(width 0.1524)
				(type default)
			)
			(layer "F.SilkS")
		)
		(fp_line
			(start 0.7874 -0.4064)
			(end 0.7874 0.4064)
			(stroke
				(width 0.1524)
				(type default)
			)
			(layer "F.SilkS")
		)
		(fp_line
			(start -0.67945 0.3048)
			(end -0.67945 -0.305054)
			(stroke
				(width 0.1)
				(type default)
			)
			(layer "F.Fab")
		)
		(fp_line
			(start -0.12065 0.3048)
			(end -0.67945 0.3048)
			(stroke
				(width 0.1)
				(type default)
			)
			(layer "F.Fab")
		)
		(fp_line
			(start 0.120396 0.3048)
			(end 0.120396 0.2794)
			(stroke
				(width 0.1)
				(type default)
			)
			(layer "F.Fab")
		)
		(fp_line
			(start 0.67945 0.3048)
			(end 0.120396 0.3048)
			(stroke
				(width 0.1)
				(type default)
			)
			(layer "F.Fab")
		)
		(fp_line
			(start -0.12065 0.2794)
			(end -0.12065 0.3048)
			(stroke
				(width 0.1)
				(type default)
			)
			(layer "F.Fab")
		)
		(fp_line
			(start 0.120396 0.2794)
			(end -0.12065 0.2794)
			(stroke
				(width 0.1)
				(type default)
			)
			(layer "F.Fab")
		)
		(fp_line
			(start -0.12065 -0.2794)
			(end 0.12065 -0.2794)
			(stroke
				(width 0.1)
				(type default)
			)
			(layer "F.Fab")
		)
		(fp_line
			(start 0.12065 -0.2794)
			(end 0.12065 -0.3048)
			(stroke
				(width 0.1)
				(type default)
			)
			(layer "F.Fab")
		)
		(fp_line
			(start 0.12065 -0.3048)
			(end 0.67945 -0.3048)
			(stroke
				(width 0.1)
				(type default)
			)
			(layer "F.Fab")
		)
		(fp_line
			(start 0.67945 -0.3048)
			(end 0.67945 0.3048)
			(stroke
				(width 0.1)
				(type default)
			)
			(layer "F.Fab")
		)
		(fp_line
			(start -0.67945 -0.305054)
			(end -0.12065 -0.305054)
			(stroke
				(width 0.1)
				(type default)
			)
			(layer "F.Fab")
		)
		(fp_line
			(start -0.12065 -0.305054)
			(end -0.12065 -0.2794)
			(stroke
				(width 0.1)
				(type default)
			)
			(layer "F.Fab")
		)
		(pad "1" smd circle
			(at -0.40005 0 270)
			(size 0 0)
			(layers "F.Cu" "F.Mask" "F.Paste")
			(net "IRQ_WAKE_R_N")
		)
		(pad "2" smd circle
			(at 0.40005 0 270)
			(size 0 0)
			(layers "F.Cu" "F.Mask" "F.Paste")
			(net "IRQ_WAKE_N")
		)
	)
	(footprint ""
		(layer "F.Cu")
		(at 183.679084 -355.898958 90)
		(property "Reference" "PR330"
			(at 0 0 90)
			(layer "F.SilkS")
			(hide yes)
			(effects
				(font
					(size 1.27 1.27)
				)
			)
		)
		(property "Value" ""
			(at 0 0 90)
			(layer "F.Fab")
			(effects
				(font
					(size 1.27 1.27)
				)
			)
		)
		(duplicate_pad_numbers_are_jumpers no)
		(fp_line
			(start 0.7874 -0.4064)
			(end 0.7874 0.4064)
			(stroke
				(width 0.1524)
				(type default)
			)
			(layer "F.SilkS")
		)
		(fp_line
			(start -0.7874 -0.4064)
			(end 0.7874 -0.4064)
			(stroke
				(width 0.1524)
				(type default)
			)
			(layer "F.SilkS")
		)
		(fp_line
			(start 0.7874 0.4064)
			(end -0.7874 0.4064)
			(stroke
				(width 0.1524)
				(type default)
			)
			(layer "F.SilkS")
		)
		(fp_line
			(start -0.7874 0.4064)
			(end -0.7874 -0.4064)
			(stroke
				(width 0.1524)
				(type default)
			)
			(layer "F.SilkS")
		)
		(fp_line
			(start -0.12065 -0.305054)
			(end -0.12065 -0.2794)
			(stroke
				(width 0.1)
				(type default)
			)
			(layer "F.Fab")
		)
		(fp_line
			(start -0.67945 -0.305054)
			(end -0.12065 -0.305054)
			(stroke
				(width 0.1)
				(type default)
			)
			(layer "F.Fab")
		)
		(fp_line
			(start 0.67945 -0.3048)
			(end 0.67945 0.3048)
			(stroke
				(width 0.1)
				(type default)
			)
			(layer "F.Fab")
		)
		(fp_line
			(start 0.12065 -0.3048)
			(end 0.67945 -0.3048)
			(stroke
				(width 0.1)
				(type default)
			)
			(layer "F.Fab")
		)
		(fp_line
			(start 0.12065 -0.2794)
			(end 0.12065 -0.3048)
			(stroke
				(width 0.1)
				(type default)
			)
			(layer "F.Fab")
		)
		(fp_line
			(start -0.12065 -0.2794)
			(end 0.12065 -0.2794)
			(stroke
				(width 0.1)
				(type default)
			)
			(layer "F.Fab")
		)
		(fp_line
			(start 0.120396 0.2794)
			(end -0.12065 0.2794)
			(stroke
				(width 0.1)
				(type default)
			)
			(layer "F.Fab")
		)
		(fp_line
			(start -0.12065 0.2794)
			(end -0.12065 0.3048)
			(stroke
				(width 0.1)
				(type default)
			)
			(layer "F.Fab")
		)
		(fp_line
			(start 0.67945 0.3048)
			(end 0.120396 0.3048)
			(stroke
				(width 0.1)
				(type default)
			)
			(layer "F.Fab")
		)
		(fp_line
			(start 0.120396 0.3048)
			(end 0.120396 0.2794)
			(stroke
				(width 0.1)
				(type default)
			)
			(layer "F.Fab")
		)
		(fp_line
			(start -0.12065 0.3048)
			(end -0.67945 0.3048)
			(stroke
				(width 0.1)
				(type default)
			)
			(layer "F.Fab")
		)
		(fp_line
			(start -0.67945 0.3048)
			(end -0.67945 -0.305054)
			(stroke
				(width 0.1)
				(type default)
			)
			(layer "F.Fab")
		)
		(pad "1" smd circle
			(at -0.40005 0 90)
			(size 0 0)
			(layers "F.Cu" "F.Mask" "F.Paste")
			(net "SW_PVDD11_S3_P1_BOOT1")
		)
		(pad "2" smd circle
			(at 0.40005 0 90)
			(size 0 0)
			(layers "F.Cu" "F.Mask" "F.Paste")
			(net "SW_PVDD11_S3_P1_BOOT1_RC")
		)
	)
	(footprint ""
		(layer "F.Cu")
		(at 18.865088 -373.44985 -90)
		(property "Reference" "PC6630"
			(at 4.41452 2.228088 0)
			(unlocked yes)
			(layer "F.SilkS")
			(effects
				(font
					(size 0.7874 0.5842)
					(thickness 0.1524)
				)
				(justify left)
			)
		)
		(property "Value" ""
			(at 0 0 270)
			(layer "F.Fab")
			(effects
				(font
					(size 1.27 1.27)
				)
			)
		)
		(duplicate_pad_numbers_are_jumpers no)
		(fp_line
			(start -1.988058 2.750058)
			(end 2.750058 2.750058)
			(stroke
				(width 0.1524)
				(type default)
			)
			(layer "F.SilkS")
		)
		(fp_line
			(start 2.750058 2.750058)
			(end 2.750058 0.9398)
			(stroke
				(width 0.1524)
				(type default)
			)
			(layer "F.SilkS")
		)
		(fp_line
			(start -2.750058 1.988058)
			(end -1.988058 2.750058)
			(stroke
				(width 0.1524)
				(type default)
			)
			(layer "F.SilkS")
		)
		(fp_line
			(start -2.750058 0.9398)
			(end -2.750058 1.988058)
			(stroke
				(width 0.1524)
				(type default)
			)
			(layer "F.SilkS")
		)
		(fp_line
			(start 2.750058 -0.9398)
			(end 2.750058 -2.750058)
			(stroke
				(width 0.1524)
				(type default)
			)
			(layer "F.SilkS")
		)
		(fp_line
			(start -2.750058 -1.988058)
			(end -2.750058 -0.9398)
			(stroke
				(width 0.1524)
				(type default)
			)
			(layer "F.SilkS")
		)
		(fp_line
			(start -1.988058 -2.750058)
			(end -2.750058 -1.988058)
			(stroke
				(width 0.1524)
				(type default)
			)
			(layer "F.SilkS")
		)
		(fp_line
			(start 2.750058 -2.750058)
			(end -1.988058 -2.750058)
			(stroke
				(width 0.1524)
				(type default)
			)
			(layer "F.SilkS")
		)
		(fp_line
			(start -2.750058 2.750058)
			(end 2.750058 2.750058)
			(stroke
				(width 0.1)
				(type default)
			)
			(layer "F.Fab")
		)
		(fp_line
			(start 2.750058 2.750058)
			(end 2.750058 -2.750058)
			(stroke
				(width 0.1)
				(type default)
			)
			(layer "F.Fab")
		)
		(fp_line
			(start -2.750058 -2.750058)
			(end -2.750058 2.750058)
			(stroke
				(width 0.1)
				(type default)
			)
			(layer "F.Fab")
		)
		(fp_line
			(start 2.750058 -2.750058)
			(end -2.750058 -2.750058)
			(stroke
				(width 0.1)
				(type default)
			)
			(layer "F.Fab")
		)
		(pad "1" smd rect
			(at -2.199894 0)
			(size 1.6002 3.0226)
			(layers "F.Cu" "F.Mask" "F.Paste")
			(net "P0V9_CPU1_RT_2D")
		)
		(pad "2" smd rect
			(at 2.199894 0)
			(size 1.6002 3.0226)
			(layers "F.Cu" "F.Mask" "F.Paste")
			(net "GND")
		)
	)
	(footprint ""
		(layer "F.Cu")
		(at 256.87274 -39.082472)
		(property "Reference" "PR4528"
			(at 0 0 0)
			(layer "F.SilkS")
			(hide yes)
			(effects
				(font
					(size 1.27 1.27)
				)
			)
		)
		(property "Value" ""
			(at 0 0 0)
			(layer "F.Fab")
			(effects
				(font
					(size 1.27 1.27)
				)
			)
		)
		(duplicate_pad_numbers_are_jumpers no)
		(fp_line
			(start -0.7874 -0.4064)
			(end 0.7874 -0.4064)
			(stroke
				(width 0.1524)
				(type default)
			)
			(layer "F.SilkS")
		)
		(fp_line
			(start -0.7874 0.4064)
			(end -0.7874 -0.4064)
			(stroke
				(width 0.1524)
				(type default)
			)
			(layer "F.SilkS")
		)
		(fp_line
			(start 0.7874 -0.4064)
			(end 0.7874 0.4064)
			(stroke
				(width 0.1524)
				(type default)
			)
			(layer "F.SilkS")
		)
		(fp_line
			(start 0.7874 0.4064)
			(end -0.7874 0.4064)
			(stroke
				(width 0.1524)
				(type default)
			)
			(layer "F.SilkS")
		)
		(fp_line
			(start -0.67945 -0.305054)
			(end -0.12065 -0.305054)
			(stroke
				(width 0.1)
				(type default)
			)
			(layer "F.Fab")
		)
		(fp_line
			(start -0.67945 0.3048)
			(end -0.67945 -0.305054)
			(stroke
				(width 0.1)
				(type default)
			)
			(layer "F.Fab")
		)
		(fp_line
			(start -0.12065 -0.305054)
			(end -0.12065 -0.2794)
			(stroke
				(width 0.1)
				(type default)
			)
			(layer "F.Fab")
		)
		(fp_line
			(start -0.12065 -0.2794)
			(end 0.12065 -0.2794)
			(stroke
				(width 0.1)
				(type default)
			)
			(layer "F.Fab")
		)
		(fp_line
			(start -0.12065 0.2794)
			(end -0.12065 0.3048)
			(stroke
				(width 0.1)
				(type default)
			)
			(layer "F.Fab")
		)
		(fp_line
			(start -0.12065 0.3048)
			(end -0.67945 0.3048)
			(stroke
				(width 0.1)
				(type default)
			)
			(layer "F.Fab")
		)
		(fp_line
			(start 0.120396 0.2794)
			(end -0.12065 0.2794)
			(stroke
				(width 0.1)
				(type default)
			)
			(layer "F.Fab")
		)
		(fp_line
			(start 0.120396 0.3048)
			(end 0.120396 0.2794)
			(stroke
				(width 0.1)
				(type default)
			)
			(layer "F.Fab")
		)
		(fp_line
			(start 0.12065 -0.3048)
			(end 0.67945 -0.3048)
			(stroke
				(width 0.1)
				(type default)
			)
			(layer "F.Fab")
		)
		(fp_line
			(start 0.12065 -0.2794)
			(end 0.12065 -0.3048)
			(stroke
				(width 0.1)
				(type default)
			)
			(layer "F.Fab")
		)
		(fp_line
			(start 0.67945 -0.3048)
			(end 0.67945 0.3048)
			(stroke
				(width 0.1)
				(type default)
			)
			(layer "F.Fab")
		)
		(fp_line
			(start 0.67945 0.3048)
			(end 0.120396 0.3048)
			(stroke
				(width 0.1)
				(type default)
			)
			(layer "F.Fab")
		)
		(pad "1" smd circle
			(at -0.40005 0)
			(size 0 0)
			(layers "F.Cu" "F.Mask" "F.Paste")
			(net "P12V_E1S_0")
		)
		(pad "2" smd circle
			(at 0.40005 0)
			(size 0 0)
			(layers "F.Cu" "F.Mask" "F.Paste")
			(net "P12V_E1S_GATE_0")
		)
	)
	(footprint ""
		(layer "F.Cu")
		(at 48.683164 -408.517344 -90)
		(property "Reference" "C6629"
			(at 0 0 270)
			(layer "F.SilkS")
			(hide yes)
			(effects
				(font
					(size 1.27 1.27)
				)
			)
		)
		(property "Value" ""
			(at 0 0 270)
			(layer "F.Fab")
			(effects
				(font
					(size 1.27 1.27)
				)
			)
		)
		(duplicate_pad_numbers_are_jumpers no)
		(fp_line
			(start -0.299974 0.150114)
			(end -0.299974 -0.150114)
			(stroke
				(width 0.1)
				(type default)
			)
			(layer "F.Fab")
		)
		(fp_line
			(start 0.299974 0.150114)
			(end -0.299974 0.150114)
			(stroke
				(width 0.1)
				(type default)
			)
			(layer "F.Fab")
		)
		(fp_line
			(start -0.299974 -0.150114)
			(end 0.299974 -0.150114)
			(stroke
				(width 0.1)
				(type default)
			)
			(layer "F.Fab")
		)
		(fp_line
			(start 0.299974 -0.150114)
			(end 0.299974 0.150114)
			(stroke
				(width 0.1)
				(type default)
			)
			(layer "F.Fab")
		)
		(pad "1" smd rect
			(at -0.2667 0 270)
			(size 0.3048 0.381)
			(layers "F.Cu" "F.Mask" "F.Paste")
			(net "P5E_CPU1_P0_TX_BUF_C_DP<0>")
		)
		(pad "2" smd rect
			(at 0.2667 0 270)
			(size 0.3048 0.381)
			(layers "F.Cu" "F.Mask" "F.Paste")
			(net "P5E_CPU1_P0_TX_BUF_DP<0>")
		)
	)
	(footprint ""
		(layer "F.Cu")
		(at 298.050966 -23.763224)
		(property "Reference" "C45"
			(at 0 0 0)
			(layer "F.SilkS")
			(hide yes)
			(effects
				(font
					(size 1.27 1.27)
				)
			)
		)
		(property "Value" ""
			(at 0 0 0)
			(layer "F.Fab")
			(effects
				(font
					(size 1.27 1.27)
				)
			)
		)
		(duplicate_pad_numbers_are_jumpers no)
		(fp_line
			(start -0.7874 -0.4064)
			(end 0.7874 -0.4064)
			(stroke
				(width 0.1524)
				(type default)
			)
			(layer "F.SilkS")
		)
		(fp_line
			(start -0.7874 0.4064)
			(end -0.7874 -0.4064)
			(stroke
				(width 0.1524)
				(type default)
			)
			(layer "F.SilkS")
		)
		(fp_line
			(start 0.7874 -0.4064)
			(end 0.7874 0.4064)
			(stroke
				(width 0.1524)
				(type default)
			)
			(layer "F.SilkS")
		)
		(fp_line
			(start 0.7874 0.4064)
			(end -0.7874 0.4064)
			(stroke
				(width 0.1524)
				(type default)
			)
			(layer "F.SilkS")
		)
		(fp_line
			(start -0.67945 -0.305054)
			(end -0.12065 -0.305054)
			(stroke
				(width 0.1)
				(type default)
			)
			(layer "F.Fab")
		)
		(fp_line
			(start -0.67945 0.3048)
			(end -0.67945 -0.305054)
			(stroke
				(width 0.1)
				(type default)
			)
			(layer "F.Fab")
		)
		(fp_line
			(start -0.12065 -0.305054)
			(end -0.12065 -0.2794)
			(stroke
				(width 0.1)
				(type default)
			)
			(layer "F.Fab")
		)
		(fp_line
			(start -0.12065 -0.2794)
			(end 0.12065 -0.2794)
			(stroke
				(width 0.1)
				(type default)
			)
			(layer "F.Fab")
		)
		(fp_line
			(start -0.12065 0.2794)
			(end -0.12065 0.3048)
			(stroke
				(width 0.1)
				(type default)
			)
			(layer "F.Fab")
		)
		(fp_line
			(start -0.12065 0.3048)
			(end -0.67945 0.3048)
			(stroke
				(width 0.1)
				(type default)
			)
			(layer "F.Fab")
		)
		(fp_line
			(start 0.120396 0.2794)
			(end -0.12065 0.2794)
			(stroke
				(width 0.1)
				(type default)
			)
			(layer "F.Fab")
		)
		(fp_line
			(start 0.120396 0.3048)
			(end 0.120396 0.2794)
			(stroke
				(width 0.1)
				(type default)
			)
			(layer "F.Fab")
		)
		(fp_line
			(start 0.12065 -0.3048)
			(end 0.67945 -0.3048)
			(stroke
				(width 0.1)
				(type default)
			)
			(layer "F.Fab")
		)
		(fp_line
			(start 0.12065 -0.2794)
			(end 0.12065 -0.3048)
			(stroke
				(width 0.1)
				(type default)
			)
			(layer "F.Fab")
		)
		(fp_line
			(start 0.67945 -0.3048)
			(end 0.67945 0.3048)
			(stroke
				(width 0.1)
				(type default)
			)
			(layer "F.Fab")
		)
		(fp_line
			(start 0.67945 0.3048)
			(end 0.120396 0.3048)
			(stroke
				(width 0.1)
				(type default)
			)
			(layer "F.Fab")
		)
		(pad "1" smd circle
			(at -0.40005 0)
			(size 0 0)
			(layers "F.Cu" "F.Mask" "F.Paste")
			(net "P1V5_BAT_IN")
		)
		(pad "2" smd circle
			(at 0.40005 0)
			(size 0 0)
			(layers "F.Cu" "F.Mask" "F.Paste")
			(net "GND")
		)
	)
	(footprint ""
		(layer "F.Cu")
		(at 204.7621 -407.068782 180)
		(property "Reference" "PR1134"
			(at 0 0 180)
			(layer "F.SilkS")
			(hide yes)
			(effects
				(font
					(size 1.27 1.27)
				)
			)
		)
		(property "Value" ""
			(at 0 0 180)
			(layer "F.Fab")
			(effects
				(font
					(size 1.27 1.27)
				)
			)
		)
		(duplicate_pad_numbers_are_jumpers no)
		(fp_line
			(start 0.7874 0.4064)
			(end -0.7874 0.4064)
			(stroke
				(width 0.1524)
				(type default)
			)
			(layer "F.SilkS")
		)
		(fp_line
			(start 0.7874 -0.4064)
			(end 0.7874 0.4064)
			(stroke
				(width 0.1524)
				(type default)
			)
			(layer "F.SilkS")
		)
		(fp_line
			(start -0.7874 0.4064)
			(end -0.7874 -0.4064)
			(stroke
				(width 0.1524)
				(type default)
			)
			(layer "F.SilkS")
		)
		(fp_line
			(start -0.7874 -0.4064)
			(end 0.7874 -0.4064)
			(stroke
				(width 0.1524)
				(type default)
			)
			(layer "F.SilkS")
		)
		(fp_line
			(start 0.67945 0.3048)
			(end 0.120396 0.3048)
			(stroke
				(width 0.1)
				(type default)
			)
			(layer "F.Fab")
		)
		(fp_line
			(start 0.67945 -0.3048)
			(end 0.67945 0.3048)
			(stroke
				(width 0.1)
				(type default)
			)
			(layer "F.Fab")
		)
		(fp_line
			(start 0.12065 -0.2794)
			(end 0.12065 -0.3048)
			(stroke
				(width 0.1)
				(type default)
			)
			(layer "F.Fab")
		)
		(fp_line
			(start 0.12065 -0.3048)
			(end 0.67945 -0.3048)
			(stroke
				(width 0.1)
				(type default)
			)
			(layer "F.Fab")
		)
		(fp_line
			(start 0.120396 0.3048)
			(end 0.120396 0.2794)
			(stroke
				(width 0.1)
				(type default)
			)
			(layer "F.Fab")
		)
		(fp_line
			(start 0.120396 0.2794)
			(end -0.12065 0.2794)
			(stroke
				(width 0.1)
				(type default)
			)
			(layer "F.Fab")
		)
		(fp_line
			(start -0.12065 0.3048)
			(end -0.67945 0.3048)
			(stroke
				(width 0.1)
				(type default)
			)
			(layer "F.Fab")
		)
		(fp_line
			(start -0.12065 0.2794)
			(end -0.12065 0.3048)
			(stroke
				(width 0.1)
				(type default)
			)
			(layer "F.Fab")
		)
		(fp_line
			(start -0.12065 -0.2794)
			(end 0.12065 -0.2794)
			(stroke
				(width 0.1)
				(type default)
			)
			(layer "F.Fab")
		)
		(fp_line
			(start -0.12065 -0.305054)
			(end -0.12065 -0.2794)
			(stroke
				(width 0.1)
				(type default)
			)
			(layer "F.Fab")
		)
		(fp_line
			(start -0.67945 0.3048)
			(end -0.67945 -0.305054)
			(stroke
				(width 0.1)
				(type default)
			)
			(layer "F.Fab")
		)
		(fp_line
			(start -0.67945 -0.305054)
			(end -0.12065 -0.305054)
			(stroke
				(width 0.1)
				(type default)
			)
			(layer "F.Fab")
		)
		(pad "1" smd circle
			(at -0.40005 0 180)
			(size 0 0)
			(layers "F.Cu" "F.Mask" "F.Paste")
			(net "AGND_HSC")
		)
		(pad "2" smd circle
			(at 0.40005 0 180)
			(size 0 0)
			(layers "F.Cu" "F.Mask" "F.Paste")
			(net "HSC_MODE_1")
		)
	)
	(footprint ""
		(layer "F.Cu")
		(at 393.092178 -180.078634 -90)
		(property "Reference" "PC547"
			(at 0 0 270)
			(layer "F.SilkS")
			(hide yes)
			(effects
				(font
					(size 1.27 1.27)
				)
			)
		)
		(property "Value" ""
			(at 0 0 270)
			(layer "F.Fab")
			(effects
				(font
					(size 1.27 1.27)
				)
			)
		)
		(duplicate_pad_numbers_are_jumpers no)
		(fp_line
			(start -0.7874 0.4064)
			(end -0.7874 -0.4064)
			(stroke
				(width 0.1524)
				(type default)
			)
			(layer "F.SilkS")
		)
		(fp_line
			(start -0.134366 0.4064)
			(end -0.7874 0.4064)
			(stroke
				(width 0.1524)
				(type default)
			)
			(layer "F.SilkS")
		)
		(fp_line
			(start 0.7874 0.4064)
			(end 0.449834 0.4064)
			(stroke
				(width 0.1524)
				(type default)
			)
			(layer "F.SilkS")
		)
		(fp_line
			(start -0.7874 -0.4064)
			(end 0.7874 -0.4064)
			(stroke
				(width 0.1524)
				(type default)
			)
			(layer "F.SilkS")
		)
		(fp_line
			(start 0.7874 -0.4064)
			(end 0.7874 0.4064)
			(stroke
				(width 0.1524)
				(type default)
			)
			(layer "F.SilkS")
		)
		(fp_line
			(start -0.67945 0.3048)
			(end -0.67945 -0.305054)
			(stroke
				(width 0.1)
				(type default)
			)
			(layer "F.Fab")
		)
		(fp_line
			(start -0.12065 0.3048)
			(end -0.67945 0.3048)
			(stroke
				(width 0.1)
				(type default)
			)
			(layer "F.Fab")
		)
		(fp_line
			(start 0.120396 0.3048)
			(end 0.120396 0.2794)
			(stroke
				(width 0.1)
				(type default)
			)
			(layer "F.Fab")
		)
		(fp_line
			(start 0.67945 0.3048)
			(end 0.120396 0.3048)
			(stroke
				(width 0.1)
				(type default)
			)
			(layer "F.Fab")
		)
		(fp_line
			(start -0.12065 0.2794)
			(end -0.12065 0.3048)
			(stroke
				(width 0.1)
				(type default)
			)
			(layer "F.Fab")
		)
		(fp_line
			(start 0.120396 0.2794)
			(end -0.12065 0.2794)
			(stroke
				(width 0.1)
				(type default)
			)
			(layer "F.Fab")
		)
		(fp_line
			(start -0.12065 -0.2794)
			(end 0.12065 -0.2794)
			(stroke
				(width 0.1)
				(type default)
			)
			(layer "F.Fab")
		)
		(fp_line
			(start 0.12065 -0.2794)
			(end 0.12065 -0.3048)
			(stroke
				(width 0.1)
				(type default)
			)
			(layer "F.Fab")
		)
		(fp_line
			(start 0.12065 -0.3048)
			(end 0.67945 -0.3048)
			(stroke
				(width 0.1)
				(type default)
			)
			(layer "F.Fab")
		)
		(fp_line
			(start 0.67945 -0.3048)
			(end 0.67945 0.3048)
			(stroke
				(width 0.1)
				(type default)
			)
			(layer "F.Fab")
		)
		(fp_line
			(start -0.67945 -0.305054)
			(end -0.12065 -0.305054)
			(stroke
				(width 0.1)
				(type default)
			)
			(layer "F.Fab")
		)
		(fp_line
			(start -0.12065 -0.305054)
			(end -0.12065 -0.2794)
			(stroke
				(width 0.1)
				(type default)
			)
			(layer "F.Fab")
		)
		(pad "1" smd circle
			(at -0.40005 0 270)
			(size 0 0)
			(layers "F.Cu" "F.Mask" "F.Paste")
			(net "PVDDCR_CPU0_P0_VCC4")
		)
		(pad "2" smd circle
			(at 0.40005 0 270)
			(size 0 0)
			(layers "F.Cu" "F.Mask" "F.Paste")
			(net "GND")
		)
	)
	(footprint ""
		(layer "F.Cu")
		(at 45.94606 -351.372932 90)
		(property "Reference" "PR278"
			(at 0 0 90)
			(layer "F.SilkS")
			(hide yes)
			(effects
				(font
					(size 1.27 1.27)
				)
			)
		)
		(property "Value" ""
			(at 0 0 90)
			(layer "F.Fab")
			(effects
				(font
					(size 1.27 1.27)
				)
			)
		)
		(duplicate_pad_numbers_are_jumpers no)
		(fp_line
			(start 0.7874 -0.4064)
			(end 0.7874 0.4064)
			(stroke
				(width 0.1524)
				(type default)
			)
			(layer "F.SilkS")
		)
		(fp_line
			(start -0.7874 -0.4064)
			(end 0.7874 -0.4064)
			(stroke
				(width 0.1524)
				(type default)
			)
			(layer "F.SilkS")
		)
		(fp_line
			(start 0.7874 0.4064)
			(end -0.7874 0.4064)
			(stroke
				(width 0.1524)
				(type default)
			)
			(layer "F.SilkS")
		)
		(fp_line
			(start -0.7874 0.4064)
			(end -0.7874 -0.4064)
			(stroke
				(width 0.1524)
				(type default)
			)
			(layer "F.SilkS")
		)
		(fp_line
			(start -0.12065 -0.305054)
			(end -0.12065 -0.2794)
			(stroke
				(width 0.1)
				(type default)
			)
			(layer "F.Fab")
		)
		(fp_line
			(start -0.67945 -0.305054)
			(end -0.12065 -0.305054)
			(stroke
				(width 0.1)
				(type default)
			)
			(layer "F.Fab")
		)
		(fp_line
			(start 0.67945 -0.3048)
			(end 0.67945 0.3048)
			(stroke
				(width 0.1)
				(type default)
			)
			(layer "F.Fab")
		)
		(fp_line
			(start 0.12065 -0.3048)
			(end 0.67945 -0.3048)
			(stroke
				(width 0.1)
				(type default)
			)
			(layer "F.Fab")
		)
		(fp_line
			(start 0.12065 -0.2794)
			(end 0.12065 -0.3048)
			(stroke
				(width 0.1)
				(type default)
			)
			(layer "F.Fab")
		)
		(fp_line
			(start -0.12065 -0.2794)
			(end 0.12065 -0.2794)
			(stroke
				(width 0.1)
				(type default)
			)
			(layer "F.Fab")
		)
		(fp_line
			(start 0.120396 0.2794)
			(end -0.12065 0.2794)
			(stroke
				(width 0.1)
				(type default)
			)
			(layer "F.Fab")
		)
		(fp_line
			(start -0.12065 0.2794)
			(end -0.12065 0.3048)
			(stroke
				(width 0.1)
				(type default)
			)
			(layer "F.Fab")
		)
		(fp_line
			(start 0.67945 0.3048)
			(end 0.120396 0.3048)
			(stroke
				(width 0.1)
				(type default)
			)
			(layer "F.Fab")
		)
		(fp_line
			(start 0.120396 0.3048)
			(end 0.120396 0.2794)
			(stroke
				(width 0.1)
				(type default)
			)
			(layer "F.Fab")
		)
		(fp_line
			(start -0.12065 0.3048)
			(end -0.67945 0.3048)
			(stroke
				(width 0.1)
				(type default)
			)
			(layer "F.Fab")
		)
		(fp_line
			(start -0.67945 0.3048)
			(end -0.67945 -0.305054)
			(stroke
				(width 0.1)
				(type default)
			)
			(layer "F.Fab")
		)
		(pad "1" smd circle
			(at -0.40005 0 90)
			(size 0 0)
			(layers "F.Cu" "F.Mask" "F.Paste")
			(net "SW_PVDDIO_P1_BOOT2")
		)
		(pad "2" smd circle
			(at 0.40005 0 90)
			(size 0 0)
			(layers "F.Cu" "F.Mask" "F.Paste")
			(net "SW_PVDDIO_P1_BOOT2_R")
		)
	)
	(footprint ""
		(layer "F.Cu")
		(at 165.509448 -51.81346 -90)
		(property "Reference" "C1920"
			(at 0 0 270)
			(layer "F.SilkS")
			(hide yes)
			(effects
				(font
					(size 1.27 1.27)
				)
			)
		)
		(property "Value" ""
			(at 0 0 270)
			(layer "F.Fab")
			(effects
				(font
					(size 1.27 1.27)
				)
			)
		)
		(duplicate_pad_numbers_are_jumpers no)
		(fp_line
			(start -1.2954 0.5842)
			(end -1.2954 -0.5842)
			(stroke
				(width 0.1524)
				(type default)
			)
			(layer "F.SilkS")
		)
		(fp_line
			(start 1.2954 0.5842)
			(end -1.2954 0.5842)
			(stroke
				(width 0.1524)
				(type default)
			)
			(layer "F.SilkS")
		)
		(fp_line
			(start -1.2954 -0.5842)
			(end 1.2954 -0.5842)
			(stroke
				(width 0.1524)
				(type default)
			)
			(layer "F.SilkS")
		)
		(fp_line
			(start 1.2954 -0.5842)
			(end 1.2954 0.5842)
			(stroke
				(width 0.1524)
				(type default)
			)
			(layer "F.SilkS")
		)
		(fp_line
			(start -0.8636 0.4572)
			(end -0.8636 0.4064)
			(stroke
				(width 0.1)
				(type default)
			)
			(layer "F.Fab")
		)
		(fp_line
			(start 0.8636 0.4572)
			(end -0.8636 0.4572)
			(stroke
				(width 0.1)
				(type default)
			)
			(layer "F.Fab")
		)
		(fp_line
			(start -1.1938 0.4064)
			(end -1.1938 -0.4064)
			(stroke
				(width 0.1)
				(type default)
			)
			(layer "F.Fab")
		)
		(fp_line
			(start -0.8636 0.4064)
			(end -1.1938 0.4064)
			(stroke
				(width 0.1)
				(type default)
			)
			(layer "F.Fab")
		)
		(fp_line
			(start 0.8636 0.4064)
			(end 0.8636 0.4572)
			(stroke
				(width 0.1)
				(type default)
			)
			(layer "F.Fab")
		)
		(fp_line
			(start 1.1938 0.4064)
			(end 0.8636 0.4064)
			(stroke
				(width 0.1)
				(type default)
			)
			(layer "F.Fab")
		)
		(fp_line
			(start -1.1938 -0.4064)
			(end -0.8636 -0.4064)
			(stroke
				(width 0.1)
				(type default)
			)
			(layer "F.Fab")
		)
		(fp_line
			(start -0.8636 -0.4064)
			(end -0.8636 -0.4572)
			(stroke
				(width 0.1)
				(type default)
			)
			(layer "F.Fab")
		)
		(fp_line
			(start 0.8636 -0.4064)
			(end 1.1938 -0.4064)
			(stroke
				(width 0.1)
				(type default)
			)
			(layer "F.Fab")
		)
		(fp_line
			(start 1.1938 -0.4064)
			(end 1.1938 0.4064)
			(stroke
				(width 0.1)
				(type default)
			)
			(layer "F.Fab")
		)
		(fp_line
			(start -0.8636 -0.4572)
			(end 0.8636 -0.4572)
			(stroke
				(width 0.1)
				(type default)
			)
			(layer "F.Fab")
		)
		(fp_line
			(start 0.8636 -0.4572)
			(end 0.8636 -0.4064)
			(stroke
				(width 0.1)
				(type default)
			)
			(layer "F.Fab")
		)
		(pad "1" smd rect
			(at -0.7366 0 180)
			(size 0.7112 0.8128)
			(layers "F.Cu" "F.Mask" "F.Paste")
			(net "P3V3_M2_0")
		)
		(pad "2" smd rect
			(at 0.7366 0 180)
			(size 0.7112 0.8128)
			(layers "F.Cu" "F.Mask" "F.Paste")
			(net "GND")
		)
	)
	(footprint ""
		(layer "F.Cu")
		(at 97.719642 -400.417792)
		(property "Reference" "R1215"
			(at 0 0 0)
			(layer "F.SilkS")
			(hide yes)
			(effects
				(font
					(size 1.27 1.27)
				)
			)
		)
		(property "Value" ""
			(at 0 0 0)
			(layer "F.Fab")
			(effects
				(font
					(size 1.27 1.27)
				)
			)
		)
		(duplicate_pad_numbers_are_jumpers no)
		(fp_line
			(start -0.32512 -0.175006)
			(end 0.32512 -0.175006)
			(stroke
				(width 0.1)
				(type default)
			)
			(layer "F.Fab")
		)
		(fp_line
			(start -0.32512 0.175006)
			(end -0.32512 -0.175006)
			(stroke
				(width 0.1)
				(type default)
			)
			(layer "F.Fab")
		)
		(fp_line
			(start 0.32512 -0.175006)
			(end 0.32512 0.175006)
			(stroke
				(width 0.1)
				(type default)
			)
			(layer "F.Fab")
		)
		(fp_line
			(start 0.32512 0.175006)
			(end -0.32512 0.175006)
			(stroke
				(width 0.1)
				(type default)
			)
			(layer "F.Fab")
		)
		(pad "1" smd rect
			(at -0.2667 0)
			(size 0.3048 0.381)
			(layers "F.Cu" "F.Mask" "F.Paste")
			(net "GND")
		)
		(pad "2" smd rect
			(at 0.2667 0 180)
			(size 0.3048 0.381)
			(layers "F.Cu" "F.Mask" "F.Paste")
			(net "RT_ROM_MUX1_OE_N")
		)
	)
	(footprint ""
		(layer "F.Cu")
		(at 461.593946 -108.567728)
		(property "Reference" "R1148"
			(at 0 0 0)
			(layer "F.SilkS")
			(hide yes)
			(effects
				(font
					(size 1.27 1.27)
				)
			)
		)
		(property "Value" ""
			(at 0 0 0)
			(layer "F.Fab")
			(effects
				(font
					(size 1.27 1.27)
				)
			)
		)
		(duplicate_pad_numbers_are_jumpers no)
		(fp_line
			(start -0.7874 -0.4064)
			(end 0.7874 -0.4064)
			(stroke
				(width 0.1524)
				(type default)
			)
			(layer "F.SilkS")
		)
		(fp_line
			(start -0.7874 0.4064)
			(end -0.7874 -0.4064)
			(stroke
				(width 0.1524)
				(type default)
			)
			(layer "F.SilkS")
		)
		(fp_line
			(start 0.7874 -0.4064)
			(end 0.7874 0.4064)
			(stroke
				(width 0.1524)
				(type default)
			)
			(layer "F.SilkS")
		)
		(fp_line
			(start 0.7874 0.4064)
			(end -0.7874 0.4064)
			(stroke
				(width 0.1524)
				(type default)
			)
			(layer "F.SilkS")
		)
		(fp_line
			(start -0.67945 -0.305054)
			(end -0.12065 -0.305054)
			(stroke
				(width 0.1)
				(type default)
			)
			(layer "F.Fab")
		)
		(fp_line
			(start -0.67945 0.3048)
			(end -0.67945 -0.305054)
			(stroke
				(width 0.1)
				(type default)
			)
			(layer "F.Fab")
		)
		(fp_line
			(start -0.12065 -0.305054)
			(end -0.12065 -0.2794)
			(stroke
				(width 0.1)
				(type default)
			)
			(layer "F.Fab")
		)
		(fp_line
			(start -0.12065 -0.2794)
			(end 0.12065 -0.2794)
			(stroke
				(width 0.1)
				(type default)
			)
			(layer "F.Fab")
		)
		(fp_line
			(start -0.12065 0.2794)
			(end -0.12065 0.3048)
			(stroke
				(width 0.1)
				(type default)
			)
			(layer "F.Fab")
		)
		(fp_line
			(start -0.12065 0.3048)
			(end -0.67945 0.3048)
			(stroke
				(width 0.1)
				(type default)
			)
			(layer "F.Fab")
		)
		(fp_line
			(start 0.120396 0.2794)
			(end -0.12065 0.2794)
			(stroke
				(width 0.1)
				(type default)
			)
			(layer "F.Fab")
		)
		(fp_line
			(start 0.120396 0.3048)
			(end 0.120396 0.2794)
			(stroke
				(width 0.1)
				(type default)
			)
			(layer "F.Fab")
		)
		(fp_line
			(start 0.12065 -0.3048)
			(end 0.67945 -0.3048)
			(stroke
				(width 0.1)
				(type default)
			)
			(layer "F.Fab")
		)
		(fp_line
			(start 0.12065 -0.2794)
			(end 0.12065 -0.3048)
			(stroke
				(width 0.1)
				(type default)
			)
			(layer "F.Fab")
		)
		(fp_line
			(start 0.67945 -0.3048)
			(end 0.67945 0.3048)
			(stroke
				(width 0.1)
				(type default)
			)
			(layer "F.Fab")
		)
		(fp_line
			(start 0.67945 0.3048)
			(end 0.120396 0.3048)
			(stroke
				(width 0.1)
				(type default)
			)
			(layer "F.Fab")
		)
		(pad "1" smd circle
			(at -0.40005 0)
			(size 0 0)
			(layers "F.Cu" "F.Mask" "F.Paste")
			(net "HP_LVC3_OCP_V3_1_PRSNT2_N_R")
		)
		(pad "2" smd circle
			(at 0.40005 0)
			(size 0 0)
			(layers "F.Cu" "F.Mask" "F.Paste")
			(net "HP_LVC3_OCP_SFF_PRSNT2_PLD_N")
		)
	)
	(footprint ""
		(layer "F.Cu")
		(at 131.664964 -151.8793 -90)
		(property "Reference" "PR215"
			(at 0 0 270)
			(layer "F.SilkS")
			(hide yes)
			(effects
				(font
					(size 1.27 1.27)
				)
			)
		)
		(property "Value" ""
			(at 0 0 270)
			(layer "F.Fab")
			(effects
				(font
					(size 1.27 1.27)
				)
			)
		)
		(duplicate_pad_numbers_are_jumpers no)
		(fp_line
			(start -0.7874 0.4064)
			(end -0.7874 -0.4064)
			(stroke
				(width 0.1524)
				(type default)
			)
			(layer "F.SilkS")
		)
		(fp_line
			(start 0.7874 0.4064)
			(end -0.7874 0.4064)
			(stroke
				(width 0.1524)
				(type default)
			)
			(layer "F.SilkS")
		)
		(fp_line
			(start -0.7874 -0.4064)
			(end 0.7874 -0.4064)
			(stroke
				(width 0.1524)
				(type default)
			)
			(layer "F.SilkS")
		)
		(fp_line
			(start 0.7874 -0.4064)
			(end 0.7874 0.4064)
			(stroke
				(width 0.1524)
				(type default)
			)
			(layer "F.SilkS")
		)
		(fp_line
			(start -0.67945 0.3048)
			(end -0.67945 -0.305054)
			(stroke
				(width 0.1)
				(type default)
			)
			(layer "F.Fab")
		)
		(fp_line
			(start -0.12065 0.3048)
			(end -0.67945 0.3048)
			(stroke
				(width 0.1)
				(type default)
			)
			(layer "F.Fab")
		)
		(fp_line
			(start 0.120396 0.3048)
			(end 0.120396 0.2794)
			(stroke
				(width 0.1)
				(type default)
			)
			(layer "F.Fab")
		)
		(fp_line
			(start 0.67945 0.3048)
			(end 0.120396 0.3048)
			(stroke
				(width 0.1)
				(type default)
			)
			(layer "F.Fab")
		)
		(fp_line
			(start -0.12065 0.2794)
			(end -0.12065 0.3048)
			(stroke
				(width 0.1)
				(type default)
			)
			(layer "F.Fab")
		)
		(fp_line
			(start 0.120396 0.2794)
			(end -0.12065 0.2794)
			(stroke
				(width 0.1)
				(type default)
			)
			(layer "F.Fab")
		)
		(fp_line
			(start -0.12065 -0.2794)
			(end 0.12065 -0.2794)
			(stroke
				(width 0.1)
				(type default)
			)
			(layer "F.Fab")
		)
		(fp_line
			(start 0.12065 -0.2794)
			(end 0.12065 -0.3048)
			(stroke
				(width 0.1)
				(type default)
			)
			(layer "F.Fab")
		)
		(fp_line
			(start 0.12065 -0.3048)
			(end 0.67945 -0.3048)
			(stroke
				(width 0.1)
				(type default)
			)
			(layer "F.Fab")
		)
		(fp_line
			(start 0.67945 -0.3048)
			(end 0.67945 0.3048)
			(stroke
				(width 0.1)
				(type default)
			)
			(layer "F.Fab")
		)
		(fp_line
			(start -0.67945 -0.305054)
			(end -0.12065 -0.305054)
			(stroke
				(width 0.1)
				(type default)
			)
			(layer "F.Fab")
		)
		(fp_line
			(start -0.12065 -0.305054)
			(end -0.12065 -0.2794)
			(stroke
				(width 0.1)
				(type default)
			)
			(layer "F.Fab")
		)
		(pad "1" smd circle
			(at -0.40005 0 270)
			(size 0 0)
			(layers "F.Cu" "F.Mask" "F.Paste")
			(net "SW_PVDDCR_SOC_P1_BOOT3")
		)
		(pad "2" smd circle
			(at 0.40005 0 270)
			(size 0 0)
			(layers "F.Cu" "F.Mask" "F.Paste")
			(net "SW_PVDDCR_SOC_P1_BOOT3_RC")
		)
	)
	(footprint ""
		(layer "F.Cu")
		(at 71.882 -386.7912 90)
		(property "Reference" "R6713"
			(at 0 0 90)
			(layer "F.SilkS")
			(hide yes)
			(effects
				(font
					(size 1.27 1.27)
				)
			)
		)
		(property "Value" ""
			(at 0 0 90)
			(layer "F.Fab")
			(effects
				(font
					(size 1.27 1.27)
				)
			)
		)
		(duplicate_pad_numbers_are_jumpers no)
		(fp_line
			(start 0.32512 -0.175006)
			(end 0.32512 0.175006)
			(stroke
				(width 0.1)
				(type default)
			)
			(layer "F.Fab")
		)
		(fp_line
			(start -0.32512 -0.175006)
			(end 0.32512 -0.175006)
			(stroke
				(width 0.1)
				(type default)
			)
			(layer "F.Fab")
		)
		(fp_line
			(start 0.32512 0.175006)
			(end -0.32512 0.175006)
			(stroke
				(width 0.1)
				(type default)
			)
			(layer "F.Fab")
		)
		(fp_line
			(start -0.32512 0.175006)
			(end -0.32512 -0.175006)
			(stroke
				(width 0.1)
				(type default)
			)
			(layer "F.Fab")
		)
		(pad "1" smd rect
			(at -0.2667 0 90)
			(size 0.3048 0.381)
			(layers "F.Cu" "F.Mask" "F.Paste")
			(net "RT_CPU1_P0_ADDR3")
		)
		(pad "2" smd rect
			(at 0.2667 0 270)
			(size 0.3048 0.381)
			(layers "F.Cu" "F.Mask" "F.Paste")
			(net "GND")
		)
	)
	(footprint ""
		(layer "F.Cu")
		(at 445.552068 -23.64105)
		(property "Reference" "PC2082"
			(at 0 0 0)
			(layer "F.SilkS")
			(hide yes)
			(effects
				(font
					(size 1.27 1.27)
				)
			)
		)
		(property "Value" ""
			(at 0 0 0)
			(layer "F.Fab")
			(effects
				(font
					(size 1.27 1.27)
				)
			)
		)
		(duplicate_pad_numbers_are_jumpers no)
		(fp_line
			(start -1.524 -0.762)
			(end 1.524 -0.762)
			(stroke
				(width 0.1524)
				(type default)
			)
			(layer "F.SilkS")
		)
		(fp_line
			(start -1.524 0.762)
			(end -1.524 -0.762)
			(stroke
				(width 0.1524)
				(type default)
			)
			(layer "F.SilkS")
		)
		(fp_line
			(start 1.524 -0.762)
			(end 1.524 0.762)
			(stroke
				(width 0.1524)
				(type default)
			)
			(layer "F.SilkS")
		)
		(fp_line
			(start 1.524 0.762)
			(end -1.524 0.762)
			(stroke
				(width 0.1524)
				(type default)
			)
			(layer "F.SilkS")
		)
		(fp_line
			(start -1.1049 -0.724916)
			(end -1.1049 0.724916)
			(stroke
				(width 0.1)
				(type default)
			)
			(layer "F.Fab")
		)
		(fp_line
			(start -1.1049 0.724916)
			(end 1.1049 0.724916)
			(stroke
				(width 0.1)
				(type default)
			)
			(layer "F.Fab")
		)
		(fp_line
			(start 1.1049 -0.724916)
			(end -1.1049 -0.724916)
			(stroke
				(width 0.1)
				(type default)
			)
			(layer "F.Fab")
		)
		(fp_line
			(start 1.1049 0.724916)
			(end 1.1049 -0.724916)
			(stroke
				(width 0.1)
				(type default)
			)
			(layer "F.Fab")
		)
		(pad "1" smd rect
			(at -0.889 0 180)
			(size 1.016 1.27)
			(layers "F.Cu" "F.Mask" "F.Paste")
			(net "P12V_OCP_SFF")
		)
		(pad "2" smd rect
			(at 0.889 0 180)
			(size 1.016 1.27)
			(layers "F.Cu" "F.Mask" "F.Paste")
			(net "GND")
		)
	)
	(footprint ""
		(layer "F.Cu")
		(at 108.521754 -327.074276 90)
		(property "Reference" "PC392"
			(at 0 0 90)
			(layer "F.SilkS")
			(hide yes)
			(effects
				(font
					(size 1.27 1.27)
				)
			)
		)
		(property "Value" ""
			(at 0 0 90)
			(layer "F.Fab")
			(effects
				(font
					(size 1.27 1.27)
				)
			)
		)
		(duplicate_pad_numbers_are_jumpers no)
		(fp_line
			(start 0.7874 -0.4064)
			(end 0.7874 0.4064)
			(stroke
				(width 0.1524)
				(type default)
			)
			(layer "F.SilkS")
		)
		(fp_line
			(start -0.7874 -0.4064)
			(end 0.7874 -0.4064)
			(stroke
				(width 0.1524)
				(type default)
			)
			(layer "F.SilkS")
		)
		(fp_line
			(start 0.7874 0.4064)
			(end -0.7874 0.4064)
			(stroke
				(width 0.1524)
				(type default)
			)
			(layer "F.SilkS")
		)
		(fp_line
			(start -0.7874 0.4064)
			(end -0.7874 -0.4064)
			(stroke
				(width 0.1524)
				(type default)
			)
			(layer "F.SilkS")
		)
		(fp_line
			(start -0.12065 -0.305054)
			(end -0.12065 -0.2794)
			(stroke
				(width 0.1)
				(type default)
			)
			(layer "F.Fab")
		)
		(fp_line
			(start -0.67945 -0.305054)
			(end -0.12065 -0.305054)
			(stroke
				(width 0.1)
				(type default)
			)
			(layer "F.Fab")
		)
		(fp_line
			(start 0.67945 -0.3048)
			(end 0.67945 0.3048)
			(stroke
				(width 0.1)
				(type default)
			)
			(layer "F.Fab")
		)
		(fp_line
			(start 0.12065 -0.3048)
			(end 0.67945 -0.3048)
			(stroke
				(width 0.1)
				(type default)
			)
			(layer "F.Fab")
		)
		(fp_line
			(start 0.12065 -0.2794)
			(end 0.12065 -0.3048)
			(stroke
				(width 0.1)
				(type default)
			)
			(layer "F.Fab")
		)
		(fp_line
			(start -0.12065 -0.2794)
			(end 0.12065 -0.2794)
			(stroke
				(width 0.1)
				(type default)
			)
			(layer "F.Fab")
		)
		(fp_line
			(start 0.120396 0.2794)
			(end -0.12065 0.2794)
			(stroke
				(width 0.1)
				(type default)
			)
			(layer "F.Fab")
		)
		(fp_line
			(start -0.12065 0.2794)
			(end -0.12065 0.3048)
			(stroke
				(width 0.1)
				(type default)
			)
			(layer "F.Fab")
		)
		(fp_line
			(start 0.67945 0.3048)
			(end 0.120396 0.3048)
			(stroke
				(width 0.1)
				(type default)
			)
			(layer "F.Fab")
		)
		(fp_line
			(start 0.120396 0.3048)
			(end 0.120396 0.2794)
			(stroke
				(width 0.1)
				(type default)
			)
			(layer "F.Fab")
		)
		(fp_line
			(start -0.12065 0.3048)
			(end -0.67945 0.3048)
			(stroke
				(width 0.1)
				(type default)
			)
			(layer "F.Fab")
		)
		(fp_line
			(start -0.67945 0.3048)
			(end -0.67945 -0.305054)
			(stroke
				(width 0.1)
				(type default)
			)
			(layer "F.Fab")
		)
		(pad "1" smd circle
			(at -0.40005 0 90)
			(size 0 0)
			(layers "F.Cu" "F.Mask" "F.Paste")
			(net "PVDDCR_CPU1_P1")
		)
		(pad "2" smd circle
			(at 0.40005 0 90)
			(size 0 0)
			(layers "F.Cu" "F.Mask" "F.Paste")
			(net "GND")
		)
	)
	(footprint ""
		(layer "F.Cu")
		(at 352.135186 -428.406052 90)
		(property "Reference" "Q146"
			(at -1.2954 1.787652 90)
			(unlocked yes)
			(layer "F.SilkS")
			(effects
				(font
					(size 0.7874 0.5842)
					(thickness 0.1524)
				)
				(justify left)
			)
		)
		(property "Value" ""
			(at 0 0 90)
			(layer "F.Fab")
			(effects
				(font
					(size 1.27 1.27)
				)
			)
		)
		(duplicate_pad_numbers_are_jumpers no)
		(fp_line
			(start 1.332738 -1.100074)
			(end 1.332738 1.100074)
			(stroke
				(width 0.1524)
				(type default)
			)
			(layer "F.SilkS")
		)
		(fp_line
			(start 0.4826 -1.100074)
			(end 1.332738 -1.100074)
			(stroke
				(width 0.1524)
				(type default)
			)
			(layer "F.SilkS")
		)
		(fp_line
			(start -0.4826 -1.100074)
			(end 0 -0.541274)
			(stroke
				(width 0.1524)
				(type default)
			)
			(layer "F.SilkS")
		)
		(fp_line
			(start -1.332738 -1.100074)
			(end -0.4826 -1.100074)
			(stroke
				(width 0.1524)
				(type default)
			)
			(layer "F.SilkS")
		)
		(fp_line
			(start 0 -0.541274)
			(end 0.4826 -1.100074)
			(stroke
				(width 0.1524)
				(type default)
			)
			(layer "F.SilkS")
		)
		(fp_line
			(start 1.332738 1.100074)
			(end -1.332738 1.100074)
			(stroke
				(width 0.1524)
				(type default)
			)
			(layer "F.SilkS")
		)
		(fp_line
			(start -1.332738 1.100074)
			(end -1.332738 -1.100074)
			(stroke
				(width 0.1524)
				(type default)
			)
			(layer "F.SilkS")
		)
		(fp_poly
			(pts
				(xy -1.533144 -0.649986) (xy -2.2352 -0.298958) (xy -2.2352 -1.001014)
			)
			(stroke
				(width 0)
				(type default)
			)
			(fill yes)
			(layer "F.SilkS")
		)
		(fp_line
			(start 0.674878 -1.100074)
			(end 0.674878 1.100074)
			(stroke
				(width 0.1)
				(type default)
			)
			(layer "F.Fab")
		)
		(fp_line
			(start -0.674878 -1.100074)
			(end 0.674878 -1.100074)
			(stroke
				(width 0.1)
				(type default)
			)
			(layer "F.Fab")
		)
		(fp_line
			(start 0.674878 1.100074)
			(end -0.674878 1.100074)
			(stroke
				(width 0.1)
				(type default)
			)
			(layer "F.Fab")
		)
		(fp_line
			(start -0.674878 1.100074)
			(end -0.674878 -1.100074)
			(stroke
				(width 0.1)
				(type default)
			)
			(layer "F.Fab")
		)
		(fp_poly
			(pts
				(xy -2.2352 -0.298958) (xy -2.2352 -1.001014) (xy -1.533144 -0.649986)
			)
			(stroke
				(width 0)
				(type default)
			)
			(fill yes)
			(layer "F.Fab")
		)
		(pad "1" smd rect
			(at -0.94996 -0.649986 180)
			(size 0.4318 0.508)
			(layers "F.Cu" "F.Mask" "F.Paste")
			(net "GND")
		)
		(pad "2" smd rect
			(at -0.94996 0 180)
			(size 0.4318 0.508)
			(layers "F.Cu" "F.Mask" "F.Paste")
			(net "SWB_HSC_PWRGD")
		)
		(pad "3" smd rect
			(at -0.94996 0.649986 180)
			(size 0.4318 0.508)
			(layers "F.Cu" "F.Mask" "F.Paste")
			(net "SWB_HSC_PWRGD_ISO")
		)
		(pad "4" smd rect
			(at 0.94996 0.649986 180)
			(size 0.4318 0.508)
			(layers "F.Cu" "F.Mask" "F.Paste")
			(net "GND")
		)
		(pad "5" smd rect
			(at 0.94996 0 180)
			(size 0.4318 0.508)
			(layers "F.Cu" "F.Mask" "F.Paste")
			(net "SWB_HSC_PWRGD_N")
		)
		(pad "6" smd rect
			(at 0.94996 -0.649986 180)
			(size 0.4318 0.508)
			(layers "F.Cu" "F.Mask" "F.Paste")
			(net "SWB_HSC_PWRGD_N")
		)
	)
	(footprint ""
		(layer "F.Cu")
		(at 146.214846 -395.221206 -90)
		(property "Reference" "R884"
			(at 0 0 270)
			(layer "F.SilkS")
			(hide yes)
			(effects
				(font
					(size 1.27 1.27)
				)
			)
		)
		(property "Value" ""
			(at 0 0 270)
			(layer "F.Fab")
			(effects
				(font
					(size 1.27 1.27)
				)
			)
		)
		(duplicate_pad_numbers_are_jumpers no)
		(fp_line
			(start -0.32512 0.175006)
			(end -0.32512 -0.175006)
			(stroke
				(width 0.1)
				(type default)
			)
			(layer "F.Fab")
		)
		(fp_line
			(start 0.32512 0.175006)
			(end -0.32512 0.175006)
			(stroke
				(width 0.1)
				(type default)
			)
			(layer "F.Fab")
		)
		(fp_line
			(start -0.32512 -0.175006)
			(end 0.32512 -0.175006)
			(stroke
				(width 0.1)
				(type default)
			)
			(layer "F.Fab")
		)
		(fp_line
			(start 0.32512 -0.175006)
			(end 0.32512 0.175006)
			(stroke
				(width 0.1)
				(type default)
			)
			(layer "F.Fab")
		)
		(pad "1" smd rect
			(at -0.2667 0 270)
			(size 0.3048 0.381)
			(layers "F.Cu" "F.Mask" "F.Paste")
			(net "JTAG_TEST_MODE_RT_CPU1_P2")
		)
		(pad "2" smd rect
			(at 0.2667 0 90)
			(size 0.3048 0.381)
			(layers "F.Cu" "F.Mask" "F.Paste")
			(net "GND")
		)
	)
	(footprint ""
		(layer "F.Cu")
		(at 200.952608 -116.673376)
		(property "Reference" "R800"
			(at 0 0 0)
			(layer "F.SilkS")
			(hide yes)
			(effects
				(font
					(size 1.27 1.27)
				)
			)
		)
		(property "Value" ""
			(at 0 0 0)
			(layer "F.Fab")
			(effects
				(font
					(size 1.27 1.27)
				)
			)
		)
		(duplicate_pad_numbers_are_jumpers no)
		(fp_line
			(start -0.7874 -0.4064)
			(end 0.7874 -0.4064)
			(stroke
				(width 0.1524)
				(type default)
			)
			(layer "F.SilkS")
		)
		(fp_line
			(start -0.7874 0.4064)
			(end -0.7874 -0.4064)
			(stroke
				(width 0.1524)
				(type default)
			)
			(layer "F.SilkS")
		)
		(fp_line
			(start 0.7874 -0.4064)
			(end 0.7874 0.4064)
			(stroke
				(width 0.1524)
				(type default)
			)
			(layer "F.SilkS")
		)
		(fp_line
			(start 0.7874 0.4064)
			(end -0.7874 0.4064)
			(stroke
				(width 0.1524)
				(type default)
			)
			(layer "F.SilkS")
		)
		(fp_line
			(start -0.67945 -0.305054)
			(end -0.12065 -0.305054)
			(stroke
				(width 0.1)
				(type default)
			)
			(layer "F.Fab")
		)
		(fp_line
			(start -0.67945 0.3048)
			(end -0.67945 -0.305054)
			(stroke
				(width 0.1)
				(type default)
			)
			(layer "F.Fab")
		)
		(fp_line
			(start -0.12065 -0.305054)
			(end -0.12065 -0.2794)
			(stroke
				(width 0.1)
				(type default)
			)
			(layer "F.Fab")
		)
		(fp_line
			(start -0.12065 -0.2794)
			(end 0.12065 -0.2794)
			(stroke
				(width 0.1)
				(type default)
			)
			(layer "F.Fab")
		)
		(fp_line
			(start -0.12065 0.2794)
			(end -0.12065 0.3048)
			(stroke
				(width 0.1)
				(type default)
			)
			(layer "F.Fab")
		)
		(fp_line
			(start -0.12065 0.3048)
			(end -0.67945 0.3048)
			(stroke
				(width 0.1)
				(type default)
			)
			(layer "F.Fab")
		)
		(fp_line
			(start 0.120396 0.2794)
			(end -0.12065 0.2794)
			(stroke
				(width 0.1)
				(type default)
			)
			(layer "F.Fab")
		)
		(fp_line
			(start 0.120396 0.3048)
			(end 0.120396 0.2794)
			(stroke
				(width 0.1)
				(type default)
			)
			(layer "F.Fab")
		)
		(fp_line
			(start 0.12065 -0.3048)
			(end 0.67945 -0.3048)
			(stroke
				(width 0.1)
				(type default)
			)
			(layer "F.Fab")
		)
		(fp_line
			(start 0.12065 -0.2794)
			(end 0.12065 -0.3048)
			(stroke
				(width 0.1)
				(type default)
			)
			(layer "F.Fab")
		)
		(fp_line
			(start 0.67945 -0.3048)
			(end 0.67945 0.3048)
			(stroke
				(width 0.1)
				(type default)
			)
			(layer "F.Fab")
		)
		(fp_line
			(start 0.67945 0.3048)
			(end 0.120396 0.3048)
			(stroke
				(width 0.1)
				(type default)
			)
			(layer "F.Fab")
		)
		(pad "1" smd circle
			(at -0.40005 0)
			(size 0 0)
			(layers "F.Cu" "F.Mask" "F.Paste")
			(net "RST_PERST_E1S_0_N")
		)
		(pad "2" smd circle
			(at 0.40005 0)
			(size 0 0)
			(layers "F.Cu" "F.Mask" "F.Paste")
			(net "GND")
		)
	)
	(footprint ""
		(layer "F.Cu")
		(at 125.992636 -59.182 180)
		(property "Reference" "R1739"
			(at 0 0 180)
			(layer "F.SilkS")
			(hide yes)
			(effects
				(font
					(size 1.27 1.27)
				)
			)
		)
		(property "Value" ""
			(at 0 0 180)
			(layer "F.Fab")
			(effects
				(font
					(size 1.27 1.27)
				)
			)
		)
		(duplicate_pad_numbers_are_jumpers no)
		(fp_line
			(start 0.7874 0.4064)
			(end -0.7874 0.4064)
			(stroke
				(width 0.1524)
				(type default)
			)
			(layer "F.SilkS")
		)
		(fp_line
			(start 0.7874 -0.4064)
			(end 0.7874 0.4064)
			(stroke
				(width 0.1524)
				(type default)
			)
			(layer "F.SilkS")
		)
		(fp_line
			(start -0.7874 0.4064)
			(end -0.7874 -0.4064)
			(stroke
				(width 0.1524)
				(type default)
			)
			(layer "F.SilkS")
		)
		(fp_line
			(start -0.7874 -0.4064)
			(end 0.7874 -0.4064)
			(stroke
				(width 0.1524)
				(type default)
			)
			(layer "F.SilkS")
		)
		(fp_line
			(start 0.67945 0.3048)
			(end 0.120396 0.3048)
			(stroke
				(width 0.1)
				(type default)
			)
			(layer "F.Fab")
		)
		(fp_line
			(start 0.67945 -0.3048)
			(end 0.67945 0.3048)
			(stroke
				(width 0.1)
				(type default)
			)
			(layer "F.Fab")
		)
		(fp_line
			(start 0.12065 -0.2794)
			(end 0.12065 -0.3048)
			(stroke
				(width 0.1)
				(type default)
			)
			(layer "F.Fab")
		)
		(fp_line
			(start 0.12065 -0.3048)
			(end 0.67945 -0.3048)
			(stroke
				(width 0.1)
				(type default)
			)
			(layer "F.Fab")
		)
		(fp_line
			(start 0.120396 0.3048)
			(end 0.120396 0.2794)
			(stroke
				(width 0.1)
				(type default)
			)
			(layer "F.Fab")
		)
		(fp_line
			(start 0.120396 0.2794)
			(end -0.12065 0.2794)
			(stroke
				(width 0.1)
				(type default)
			)
			(layer "F.Fab")
		)
		(fp_line
			(start -0.12065 0.3048)
			(end -0.67945 0.3048)
			(stroke
				(width 0.1)
				(type default)
			)
			(layer "F.Fab")
		)
		(fp_line
			(start -0.12065 0.2794)
			(end -0.12065 0.3048)
			(stroke
				(width 0.1)
				(type default)
			)
			(layer "F.Fab")
		)
		(fp_line
			(start -0.12065 -0.2794)
			(end 0.12065 -0.2794)
			(stroke
				(width 0.1)
				(type default)
			)
			(layer "F.Fab")
		)
		(fp_line
			(start -0.12065 -0.305054)
			(end -0.12065 -0.2794)
			(stroke
				(width 0.1)
				(type default)
			)
			(layer "F.Fab")
		)
		(fp_line
			(start -0.67945 0.3048)
			(end -0.67945 -0.305054)
			(stroke
				(width 0.1)
				(type default)
			)
			(layer "F.Fab")
		)
		(fp_line
			(start -0.67945 -0.305054)
			(end -0.12065 -0.305054)
			(stroke
				(width 0.1)
				(type default)
			)
			(layer "F.Fab")
		)
		(pad "1" smd circle
			(at -0.40005 0 180)
			(size 0 0)
			(layers "F.Cu" "F.Mask" "F.Paste")
			(net "JTAG_SCM_MUX_R_TDO")
		)
		(pad "2" smd circle
			(at 0.40005 0 180)
			(size 0 0)
			(layers "F.Cu" "F.Mask" "F.Paste")
			(net "JTAG_SCM_MUX_TDO")
		)
	)
	(footprint ""
		(layer "F.Cu")
		(at 310.056022 -37.017706 180)
		(property "Reference" "C1767"
			(at 0 0 180)
			(layer "F.SilkS")
			(hide yes)
			(effects
				(font
					(size 1.27 1.27)
				)
			)
		)
		(property "Value" ""
			(at 0 0 180)
			(layer "F.Fab")
			(effects
				(font
					(size 1.27 1.27)
				)
			)
		)
		(duplicate_pad_numbers_are_jumpers no)
		(fp_line
			(start 1.524 0.762)
			(end -1.524 0.762)
			(stroke
				(width 0.1524)
				(type default)
			)
			(layer "F.SilkS")
		)
		(fp_line
			(start 1.524 -0.762)
			(end 1.524 0.762)
			(stroke
				(width 0.1524)
				(type default)
			)
			(layer "F.SilkS")
		)
		(fp_line
			(start -1.524 0.762)
			(end -1.524 -0.762)
			(stroke
				(width 0.1524)
				(type default)
			)
			(layer "F.SilkS")
		)
		(fp_line
			(start -1.524 -0.762)
			(end 1.524 -0.762)
			(stroke
				(width 0.1524)
				(type default)
			)
			(layer "F.SilkS")
		)
		(fp_line
			(start 1.1049 0.724916)
			(end 1.1049 -0.724916)
			(stroke
				(width 0.1)
				(type default)
			)
			(layer "F.Fab")
		)
		(fp_line
			(start 1.1049 -0.724916)
			(end -1.1049 -0.724916)
			(stroke
				(width 0.1)
				(type default)
			)
			(layer "F.Fab")
		)
		(fp_line
			(start -1.1049 0.724916)
			(end 1.1049 0.724916)
			(stroke
				(width 0.1)
				(type default)
			)
			(layer "F.Fab")
		)
		(fp_line
			(start -1.1049 -0.724916)
			(end -1.1049 0.724916)
			(stroke
				(width 0.1)
				(type default)
			)
			(layer "F.Fab")
		)
		(pad "1" smd rect
			(at -0.889 0)
			(size 1.016 1.27)
			(layers "F.Cu" "F.Mask" "F.Paste")
			(net "MAX11617_VREF")
		)
		(pad "2" smd rect
			(at 0.889 0)
			(size 1.016 1.27)
			(layers "F.Cu" "F.Mask" "F.Paste")
			(net "GND")
		)
	)
	(footprint ""
		(layer "F.Cu")
		(at 405.478742 -416.899344 -90)
		(property "Reference" "C6587"
			(at 0 0 270)
			(layer "F.SilkS")
			(hide yes)
			(effects
				(font
					(size 1.27 1.27)
				)
			)
		)
		(property "Value" ""
			(at 0 0 270)
			(layer "F.Fab")
			(effects
				(font
					(size 1.27 1.27)
				)
			)
		)
		(duplicate_pad_numbers_are_jumpers no)
		(fp_line
			(start -0.299974 0.150114)
			(end -0.299974 -0.150114)
			(stroke
				(width 0.1)
				(type default)
			)
			(layer "F.Fab")
		)
		(fp_line
			(start 0.299974 0.150114)
			(end -0.299974 0.150114)
			(stroke
				(width 0.1)
				(type default)
			)
			(layer "F.Fab")
		)
		(fp_line
			(start -0.299974 -0.150114)
			(end 0.299974 -0.150114)
			(stroke
				(width 0.1)
				(type default)
			)
			(layer "F.Fab")
		)
		(fp_line
			(start 0.299974 -0.150114)
			(end 0.299974 0.150114)
			(stroke
				(width 0.1)
				(type default)
			)
			(layer "F.Fab")
		)
		(pad "1" smd rect
			(at -0.2667 0 270)
			(size 0.3048 0.381)
			(layers "F.Cu" "F.Mask" "F.Paste")
			(net "P5E_CPU0_P2_TX_BUF_C_DP<11>")
		)
		(pad "2" smd rect
			(at 0.2667 0 270)
			(size 0.3048 0.381)
			(layers "F.Cu" "F.Mask" "F.Paste")
			(net "P5E_CPU0_P2_TX_BUF_DP<11>")
		)
	)
	(footprint ""
		(layer "F.Cu")
		(at 183.007 -140.172948 90)
		(property "Reference" "R1287"
			(at 0 0 90)
			(layer "F.SilkS")
			(hide yes)
			(effects
				(font
					(size 1.27 1.27)
				)
			)
		)
		(property "Value" ""
			(at 0 0 90)
			(layer "F.Fab")
			(effects
				(font
					(size 1.27 1.27)
				)
			)
		)
		(duplicate_pad_numbers_are_jumpers no)
		(fp_line
			(start 0.7874 -0.4064)
			(end 0.7874 0.4064)
			(stroke
				(width 0.1524)
				(type default)
			)
			(layer "F.SilkS")
		)
		(fp_line
			(start -0.7874 -0.4064)
			(end 0.7874 -0.4064)
			(stroke
				(width 0.1524)
				(type default)
			)
			(layer "F.SilkS")
		)
		(fp_line
			(start 0.7874 0.4064)
			(end -0.7874 0.4064)
			(stroke
				(width 0.1524)
				(type default)
			)
			(layer "F.SilkS")
		)
		(fp_line
			(start -0.7874 0.4064)
			(end -0.7874 -0.4064)
			(stroke
				(width 0.1524)
				(type default)
			)
			(layer "F.SilkS")
		)
		(fp_line
			(start -0.12065 -0.305054)
			(end -0.12065 -0.2794)
			(stroke
				(width 0.1)
				(type default)
			)
			(layer "F.Fab")
		)
		(fp_line
			(start -0.67945 -0.305054)
			(end -0.12065 -0.305054)
			(stroke
				(width 0.1)
				(type default)
			)
			(layer "F.Fab")
		)
		(fp_line
			(start 0.67945 -0.3048)
			(end 0.67945 0.3048)
			(stroke
				(width 0.1)
				(type default)
			)
			(layer "F.Fab")
		)
		(fp_line
			(start 0.12065 -0.3048)
			(end 0.67945 -0.3048)
			(stroke
				(width 0.1)
				(type default)
			)
			(layer "F.Fab")
		)
		(fp_line
			(start 0.12065 -0.2794)
			(end 0.12065 -0.3048)
			(stroke
				(width 0.1)
				(type default)
			)
			(layer "F.Fab")
		)
		(fp_line
			(start -0.12065 -0.2794)
			(end 0.12065 -0.2794)
			(stroke
				(width 0.1)
				(type default)
			)
			(layer "F.Fab")
		)
		(fp_line
			(start 0.120396 0.2794)
			(end -0.12065 0.2794)
			(stroke
				(width 0.1)
				(type default)
			)
			(layer "F.Fab")
		)
		(fp_line
			(start -0.12065 0.2794)
			(end -0.12065 0.3048)
			(stroke
				(width 0.1)
				(type default)
			)
			(layer "F.Fab")
		)
		(fp_line
			(start 0.67945 0.3048)
			(end 0.120396 0.3048)
			(stroke
				(width 0.1)
				(type default)
			)
			(layer "F.Fab")
		)
		(fp_line
			(start 0.120396 0.3048)
			(end 0.120396 0.2794)
			(stroke
				(width 0.1)
				(type default)
			)
			(layer "F.Fab")
		)
		(fp_line
			(start -0.12065 0.3048)
			(end -0.67945 0.3048)
			(stroke
				(width 0.1)
				(type default)
			)
			(layer "F.Fab")
		)
		(fp_line
			(start -0.67945 0.3048)
			(end -0.67945 -0.305054)
			(stroke
				(width 0.1)
				(type default)
			)
			(layer "F.Fab")
		)
		(pad "1" smd circle
			(at -0.40005 0 90)
			(size 0 0)
			(layers "F.Cu" "F.Mask" "F.Paste")
			(net "FM_P0_PCC0_N")
		)
		(pad "2" smd circle
			(at 0.40005 0 90)
			(size 0 0)
			(layers "F.Cu" "F.Mask" "F.Paste")
			(net "PVDD18_S5_P0")
		)
	)
	(footprint ""
		(layer "F.Cu")
		(at 237.843822 -290.341812 90)
		(property "Reference" "PC6515"
			(at 0 0 90)
			(layer "F.SilkS")
			(hide yes)
			(effects
				(font
					(size 1.27 1.27)
				)
			)
		)
		(property "Value" ""
			(at 0 0 90)
			(layer "F.Fab")
			(effects
				(font
					(size 1.27 1.27)
				)
			)
		)
		(duplicate_pad_numbers_are_jumpers no)
		(fp_line
			(start 0.7874 -0.4064)
			(end 0.7874 0.4064)
			(stroke
				(width 0.1524)
				(type default)
			)
			(layer "F.SilkS")
		)
		(fp_line
			(start -0.7874 -0.4064)
			(end 0.7874 -0.4064)
			(stroke
				(width 0.1524)
				(type default)
			)
			(layer "F.SilkS")
		)
		(fp_line
			(start 0.7874 0.4064)
			(end -0.7874 0.4064)
			(stroke
				(width 0.1524)
				(type default)
			)
			(layer "F.SilkS")
		)
		(fp_line
			(start -0.7874 0.4064)
			(end -0.7874 -0.4064)
			(stroke
				(width 0.1524)
				(type default)
			)
			(layer "F.SilkS")
		)
		(fp_line
			(start -0.12065 -0.305054)
			(end -0.12065 -0.2794)
			(stroke
				(width 0.1)
				(type default)
			)
			(layer "F.Fab")
		)
		(fp_line
			(start -0.67945 -0.305054)
			(end -0.12065 -0.305054)
			(stroke
				(width 0.1)
				(type default)
			)
			(layer "F.Fab")
		)
		(fp_line
			(start 0.67945 -0.3048)
			(end 0.67945 0.3048)
			(stroke
				(width 0.1)
				(type default)
			)
			(layer "F.Fab")
		)
		(fp_line
			(start 0.12065 -0.3048)
			(end 0.67945 -0.3048)
			(stroke
				(width 0.1)
				(type default)
			)
			(layer "F.Fab")
		)
		(fp_line
			(start 0.12065 -0.2794)
			(end 0.12065 -0.3048)
			(stroke
				(width 0.1)
				(type default)
			)
			(layer "F.Fab")
		)
		(fp_line
			(start -0.12065 -0.2794)
			(end 0.12065 -0.2794)
			(stroke
				(width 0.1)
				(type default)
			)
			(layer "F.Fab")
		)
		(fp_line
			(start 0.120396 0.2794)
			(end -0.12065 0.2794)
			(stroke
				(width 0.1)
				(type default)
			)
			(layer "F.Fab")
		)
		(fp_line
			(start -0.12065 0.2794)
			(end -0.12065 0.3048)
			(stroke
				(width 0.1)
				(type default)
			)
			(layer "F.Fab")
		)
		(fp_line
			(start 0.67945 0.3048)
			(end 0.120396 0.3048)
			(stroke
				(width 0.1)
				(type default)
			)
			(layer "F.Fab")
		)
		(fp_line
			(start 0.120396 0.3048)
			(end 0.120396 0.2794)
			(stroke
				(width 0.1)
				(type default)
			)
			(layer "F.Fab")
		)
		(fp_line
			(start -0.12065 0.3048)
			(end -0.67945 0.3048)
			(stroke
				(width 0.1)
				(type default)
			)
			(layer "F.Fab")
		)
		(fp_line
			(start -0.67945 0.3048)
			(end -0.67945 -0.305054)
			(stroke
				(width 0.1)
				(type default)
			)
			(layer "F.Fab")
		)
		(pad "1" smd circle
			(at -0.40005 0 90)
			(size 0 0)
			(layers "F.Cu" "F.Mask" "F.Paste")
			(net "P1V8_RETIMER_CPU0_FB")
		)
		(pad "2" smd circle
			(at 0.40005 0 90)
			(size 0 0)
			(layers "F.Cu" "F.Mask" "F.Paste")
			(net "P1V8_CPU0_RT_1D")
		)
	)
	(footprint ""
		(layer "F.Cu")
		(at 15.55115 -68.128642)
		(property "Reference" "R1191"
			(at 0 0 0)
			(layer "F.SilkS")
			(hide yes)
			(effects
				(font
					(size 1.27 1.27)
				)
			)
		)
		(property "Value" ""
			(at 0 0 0)
			(layer "F.Fab")
			(effects
				(font
					(size 1.27 1.27)
				)
			)
		)
		(duplicate_pad_numbers_are_jumpers no)
		(fp_line
			(start -0.7874 -0.4064)
			(end 0.7874 -0.4064)
			(stroke
				(width 0.1524)
				(type default)
			)
			(layer "F.SilkS")
		)
		(fp_line
			(start -0.7874 0.4064)
			(end -0.7874 -0.4064)
			(stroke
				(width 0.1524)
				(type default)
			)
			(layer "F.SilkS")
		)
		(fp_line
			(start 0.7874 -0.4064)
			(end 0.7874 0.4064)
			(stroke
				(width 0.1524)
				(type default)
			)
			(layer "F.SilkS")
		)
		(fp_line
			(start 0.7874 0.4064)
			(end -0.7874 0.4064)
			(stroke
				(width 0.1524)
				(type default)
			)
			(layer "F.SilkS")
		)
		(fp_line
			(start -0.67945 -0.305054)
			(end -0.12065 -0.305054)
			(stroke
				(width 0.1)
				(type default)
			)
			(layer "F.Fab")
		)
		(fp_line
			(start -0.67945 0.3048)
			(end -0.67945 -0.305054)
			(stroke
				(width 0.1)
				(type default)
			)
			(layer "F.Fab")
		)
		(fp_line
			(start -0.12065 -0.305054)
			(end -0.12065 -0.2794)
			(stroke
				(width 0.1)
				(type default)
			)
			(layer "F.Fab")
		)
		(fp_line
			(start -0.12065 -0.2794)
			(end 0.12065 -0.2794)
			(stroke
				(width 0.1)
				(type default)
			)
			(layer "F.Fab")
		)
		(fp_line
			(start -0.12065 0.2794)
			(end -0.12065 0.3048)
			(stroke
				(width 0.1)
				(type default)
			)
			(layer "F.Fab")
		)
		(fp_line
			(start -0.12065 0.3048)
			(end -0.67945 0.3048)
			(stroke
				(width 0.1)
				(type default)
			)
			(layer "F.Fab")
		)
		(fp_line
			(start 0.120396 0.2794)
			(end -0.12065 0.2794)
			(stroke
				(width 0.1)
				(type default)
			)
			(layer "F.Fab")
		)
		(fp_line
			(start 0.120396 0.3048)
			(end 0.120396 0.2794)
			(stroke
				(width 0.1)
				(type default)
			)
			(layer "F.Fab")
		)
		(fp_line
			(start 0.12065 -0.3048)
			(end 0.67945 -0.3048)
			(stroke
				(width 0.1)
				(type default)
			)
			(layer "F.Fab")
		)
		(fp_line
			(start 0.12065 -0.2794)
			(end 0.12065 -0.3048)
			(stroke
				(width 0.1)
				(type default)
			)
			(layer "F.Fab")
		)
		(fp_line
			(start 0.67945 -0.3048)
			(end 0.67945 0.3048)
			(stroke
				(width 0.1)
				(type default)
			)
			(layer "F.Fab")
		)
		(fp_line
			(start 0.67945 0.3048)
			(end 0.120396 0.3048)
			(stroke
				(width 0.1)
				(type default)
			)
			(layer "F.Fab")
		)
		(pad "1" smd circle
			(at -0.40005 0)
			(size 0 0)
			(layers "F.Cu" "F.Mask" "F.Paste")
			(net "HP_LVC3_OCP_V3_2_PRSNT2_N_R")
		)
		(pad "2" smd circle
			(at 0.40005 0)
			(size 0 0)
			(layers "F.Cu" "F.Mask" "F.Paste")
			(net "HP_LVC3_OCP_V3_2_PRSNT2_N")
		)
	)
	(footprint ""
		(layer "F.Cu")
		(at 187.833 -96.103948 -90)
		(property "Reference" "R1036"
			(at 0 0 270)
			(layer "F.SilkS")
			(hide yes)
			(effects
				(font
					(size 1.27 1.27)
				)
			)
		)
		(property "Value" ""
			(at 0 0 270)
			(layer "F.Fab")
			(effects
				(font
					(size 1.27 1.27)
				)
			)
		)
		(duplicate_pad_numbers_are_jumpers no)
		(fp_line
			(start -0.7874 0.4064)
			(end -0.7874 -0.4064)
			(stroke
				(width 0.1524)
				(type default)
			)
			(layer "F.SilkS")
		)
		(fp_line
			(start 0.7874 0.4064)
			(end -0.7874 0.4064)
			(stroke
				(width 0.1524)
				(type default)
			)
			(layer "F.SilkS")
		)
		(fp_line
			(start -0.7874 -0.4064)
			(end 0.7874 -0.4064)
			(stroke
				(width 0.1524)
				(type default)
			)
			(layer "F.SilkS")
		)
		(fp_line
			(start 0.7874 -0.4064)
			(end 0.7874 0.4064)
			(stroke
				(width 0.1524)
				(type default)
			)
			(layer "F.SilkS")
		)
		(fp_line
			(start -0.67945 0.3048)
			(end -0.67945 -0.305054)
			(stroke
				(width 0.1)
				(type default)
			)
			(layer "F.Fab")
		)
		(fp_line
			(start -0.12065 0.3048)
			(end -0.67945 0.3048)
			(stroke
				(width 0.1)
				(type default)
			)
			(layer "F.Fab")
		)
		(fp_line
			(start 0.120396 0.3048)
			(end 0.120396 0.2794)
			(stroke
				(width 0.1)
				(type default)
			)
			(layer "F.Fab")
		)
		(fp_line
			(start 0.67945 0.3048)
			(end 0.120396 0.3048)
			(stroke
				(width 0.1)
				(type default)
			)
			(layer "F.Fab")
		)
		(fp_line
			(start -0.12065 0.2794)
			(end -0.12065 0.3048)
			(stroke
				(width 0.1)
				(type default)
			)
			(layer "F.Fab")
		)
		(fp_line
			(start 0.120396 0.2794)
			(end -0.12065 0.2794)
			(stroke
				(width 0.1)
				(type default)
			)
			(layer "F.Fab")
		)
		(fp_line
			(start -0.12065 -0.2794)
			(end 0.12065 -0.2794)
			(stroke
				(width 0.1)
				(type default)
			)
			(layer "F.Fab")
		)
		(fp_line
			(start 0.12065 -0.2794)
			(end 0.12065 -0.3048)
			(stroke
				(width 0.1)
				(type default)
			)
			(layer "F.Fab")
		)
		(fp_line
			(start 0.12065 -0.3048)
			(end 0.67945 -0.3048)
			(stroke
				(width 0.1)
				(type default)
			)
			(layer "F.Fab")
		)
		(fp_line
			(start 0.67945 -0.3048)
			(end 0.67945 0.3048)
			(stroke
				(width 0.1)
				(type default)
			)
			(layer "F.Fab")
		)
		(fp_line
			(start -0.67945 -0.305054)
			(end -0.12065 -0.305054)
			(stroke
				(width 0.1)
				(type default)
			)
			(layer "F.Fab")
		)
		(fp_line
			(start -0.12065 -0.305054)
			(end -0.12065 -0.2794)
			(stroke
				(width 0.1)
				(type default)
			)
			(layer "F.Fab")
		)
		(pad "1" smd circle
			(at -0.40005 0 270)
			(size 0 0)
			(layers "F.Cu" "F.Mask" "F.Paste")
			(net "FM_SMB_RST_E1S_0_N")
		)
		(pad "2" smd circle
			(at 0.40005 0 270)
			(size 0 0)
			(layers "F.Cu" "F.Mask" "F.Paste")
			(net "FM_SMB_RST_E1S_0_R_N")
		)
	)
	(footprint ""
		(layer "F.Cu")
		(at 495.90833 -147.933918 -90)
		(property "Reference" "X4"
			(at -1.809496 3.220974 0)
			(unlocked yes)
			(layer "F.SilkS")
			(effects
				(font
					(size 0.7874 0.5842)
					(thickness 0.1524)
				)
				(justify left)
			)
		)
		(property "Value" ""
			(at 0 0 270)
			(layer "F.Fab")
			(effects
				(font
					(size 1.27 1.27)
				)
			)
		)
		(property "Device Type" "TP_TDR_4P_FTS_TH-TP_TDR_4P_DIP,EMPTY,TP15"
			(at 1.30175 1.27 0)
			(unlocked yes)
			(layer "F.Fab")
			(hide yes)
			(effects
				(font
					(size 0.635 0.4064)
					(thickness 0.1524)
				)
			)
		)
		(property "User Part Number" "N_A"
			(at 1.30175 1.27 0)
			(unlocked yes)
			(layer "Cmts.User")
			(hide yes)
			(effects
				(font
					(size 0.635 0.4064)
					(thickness 0.1524)
				)
			)
		)
		(duplicate_pad_numbers_are_jumpers no)
		(fp_line
			(start 0 3.81)
			(end 2.54 3.81)
			(stroke
				(width 0.1524)
				(type default)
			)
			(layer "F.SilkS")
		)
		(fp_line
			(start 2.54 3.81)
			(end 2.54 3.6703)
			(stroke
				(width 0.1524)
				(type default)
			)
			(layer "F.SilkS")
		)
		(fp_line
			(start 0 3.175)
			(end 0 3.81)
			(stroke
				(width 0.1524)
				(type default)
			)
			(layer "F.SilkS")
		)
		(fp_line
			(start 2.54 1.4097)
			(end 2.54 1.1303)
			(stroke
				(width 0.1524)
				(type default)
			)
			(layer "F.SilkS")
		)
		(fp_line
			(start 0 0.635)
			(end 0 1.905)
			(stroke
				(width 0.1524)
				(type default)
			)
			(layer "F.SilkS")
		)
		(fp_line
			(start 2.54 -1.1303)
			(end 2.54 -1.27)
			(stroke
				(width 0.1524)
				(type default)
			)
			(layer "F.SilkS")
		)
		(fp_line
			(start 0 -1.27)
			(end 0 -0.635)
			(stroke
				(width 0.1524)
				(type default)
			)
			(layer "F.SilkS")
		)
		(fp_line
			(start 2.54 -1.27)
			(end 0 -1.27)
			(stroke
				(width 0.1524)
				(type default)
			)
			(layer "F.SilkS")
		)
		(fp_poly
			(pts
				(xy -0.761746 0) (xy -2.285746 0.762) (xy -2.285746 -0.762)
			)
			(stroke
				(width 0)
				(type default)
			)
			(fill yes)
			(layer "F.SilkS")
		)
		(fp_line
			(start 0 3.81)
			(end 2.54 3.81)
			(stroke
				(width 0.1)
				(type default)
			)
			(layer "F.Fab")
		)
		(fp_line
			(start 2.54 3.81)
			(end 2.54 -1.27)
			(stroke
				(width 0.1)
				(type default)
			)
			(layer "F.Fab")
		)
		(fp_line
			(start 0 -1.27)
			(end 0 3.81)
			(stroke
				(width 0.1)
				(type default)
			)
			(layer "F.Fab")
		)
		(fp_line
			(start 2.54 -1.27)
			(end 0 -1.27)
			(stroke
				(width 0.1)
				(type default)
			)
			(layer "F.Fab")
		)
		(fp_poly
			(pts
				(xy -0.761746 0) (xy -2.285746 -0.762) (xy -2.285746 0.762)
			)
			(stroke
				(width 0)
				(type default)
			)
			(fill yes)
			(layer "F.Fab")
		)
		(pad "1" thru_hole circle
			(at 0 0 270)
			(size 1.0033 1.0033)
			(drill 0.249936)
			(layers "*.Cu" "*.Mask")
			(remove_unused_layers no)
			(net "TDR_DIFF_80_IN3_DP")
			(clearance 0.10795)
			(thermal_gap 0.10795)
			(padstack
				(mode front_inner_back)
				(layer "Inner"
					(shape circle)
					(size 0.8001 0.8001)
					(clearance 0.1524)
				)
				(layer "B.Cu"
					(shape circle)
					(size 1.0033 1.0033)
					(clearance 0.10795)
				)
			)
		)
		(pad "2" thru_hole circle
			(at 2.54 0 270)
			(size 1.9939 1.9939)
			(drill 0.249936)
			(layers "*.Cu" "*.Mask")
			(remove_unused_layers no)
			(net "T1_GND")
			(clearance 0.10795)
			(thermal_gap 0.10795)
			(padstack
				(mode front_inner_back)
				(layer "Inner"
					(shape circle)
					(size 0.8001 0.8001)
					(clearance 0.1524)
				)
				(layer "B.Cu"
					(shape circle)
					(size 1.9939 1.9939)
					(clearance 0.10795)
				)
			)
		)
		(pad "3" thru_hole circle
			(at 2.54 2.54 270)
			(size 1.9939 1.9939)
			(drill 0.249936)
			(layers "*.Cu" "*.Mask")
			(remove_unused_layers no)
			(net "T1_GND")
			(clearance 0.10795)
			(thermal_gap 0.10795)
			(padstack
				(mode front_inner_back)
				(layer "Inner"
					(shape circle)
					(size 0.8001 0.8001)
					(clearance 0.1524)
				)
				(layer "B.Cu"
					(shape circle)
					(size 1.9939 1.9939)
					(clearance 0.10795)
				)
			)
		)
		(pad "4" thru_hole circle
			(at 0 2.54 270)
			(size 1.0033 1.0033)
			(drill 0.249936)
			(layers "*.Cu" "*.Mask")
			(remove_unused_layers no)
			(net "TDR_DIFF_80_IN3_DN")
			(clearance 0.10795)
			(thermal_gap 0.10795)
			(padstack
				(mode front_inner_back)
				(layer "Inner"
					(shape circle)
					(size 0.8001 0.8001)
					(clearance 0.1524)
				)
				(layer "B.Cu"
					(shape circle)
					(size 1.0033 1.0033)
					(clearance 0.10795)
				)
			)
		)
	)
	(footprint ""
		(layer "F.Cu")
		(at 94.36481 -180.010562 -90)
		(property "Reference" "PC257"
			(at 0 0 270)
			(layer "F.SilkS")
			(hide yes)
			(effects
				(font
					(size 1.27 1.27)
				)
			)
		)
		(property "Value" ""
			(at 0 0 270)
			(layer "F.Fab")
			(effects
				(font
					(size 1.27 1.27)
				)
			)
		)
		(duplicate_pad_numbers_are_jumpers no)
		(fp_line
			(start -0.7874 0.4064)
			(end -0.7874 -0.4064)
			(stroke
				(width 0.1524)
				(type default)
			)
			(layer "F.SilkS")
		)
		(fp_line
			(start -0.278638 0.4064)
			(end -0.7874 0.4064)
			(stroke
				(width 0.1524)
				(type default)
			)
			(layer "F.SilkS")
		)
		(fp_line
			(start 0.7874 0.4064)
			(end 0.305562 0.4064)
			(stroke
				(width 0.1524)
				(type default)
			)
			(layer "F.SilkS")
		)
		(fp_line
			(start -0.7874 -0.4064)
			(end 0.7874 -0.4064)
			(stroke
				(width 0.1524)
				(type default)
			)
			(layer "F.SilkS")
		)
		(fp_line
			(start 0.7874 -0.4064)
			(end 0.7874 0.4064)
			(stroke
				(width 0.1524)
				(type default)
			)
			(layer "F.SilkS")
		)
		(fp_line
			(start -0.67945 0.3048)
			(end -0.67945 -0.305054)
			(stroke
				(width 0.1)
				(type default)
			)
			(layer "F.Fab")
		)
		(fp_line
			(start -0.12065 0.3048)
			(end -0.67945 0.3048)
			(stroke
				(width 0.1)
				(type default)
			)
			(layer "F.Fab")
		)
		(fp_line
			(start 0.120396 0.3048)
			(end 0.120396 0.2794)
			(stroke
				(width 0.1)
				(type default)
			)
			(layer "F.Fab")
		)
		(fp_line
			(start 0.67945 0.3048)
			(end 0.120396 0.3048)
			(stroke
				(width 0.1)
				(type default)
			)
			(layer "F.Fab")
		)
		(fp_line
			(start -0.12065 0.2794)
			(end -0.12065 0.3048)
			(stroke
				(width 0.1)
				(type default)
			)
			(layer "F.Fab")
		)
		(fp_line
			(start 0.120396 0.2794)
			(end -0.12065 0.2794)
			(stroke
				(width 0.1)
				(type default)
			)
			(layer "F.Fab")
		)
		(fp_line
			(start -0.12065 -0.2794)
			(end 0.12065 -0.2794)
			(stroke
				(width 0.1)
				(type default)
			)
			(layer "F.Fab")
		)
		(fp_line
			(start 0.12065 -0.2794)
			(end 0.12065 -0.3048)
			(stroke
				(width 0.1)
				(type default)
			)
			(layer "F.Fab")
		)
		(fp_line
			(start 0.12065 -0.3048)
			(end 0.67945 -0.3048)
			(stroke
				(width 0.1)
				(type default)
			)
			(layer "F.Fab")
		)
		(fp_line
			(start 0.67945 -0.3048)
			(end 0.67945 0.3048)
			(stroke
				(width 0.1)
				(type default)
			)
			(layer "F.Fab")
		)
		(fp_line
			(start -0.67945 -0.305054)
			(end -0.12065 -0.305054)
			(stroke
				(width 0.1)
				(type default)
			)
			(layer "F.Fab")
		)
		(fp_line
			(start -0.12065 -0.305054)
			(end -0.12065 -0.2794)
			(stroke
				(width 0.1)
				(type default)
			)
			(layer "F.Fab")
		)
		(pad "1" smd circle
			(at -0.40005 0 270)
			(size 0 0)
			(layers "F.Cu" "F.Mask" "F.Paste")
			(net "PVDDCR_CPU0_P1_VCC2")
		)
		(pad "2" smd circle
			(at 0.40005 0 270)
			(size 0 0)
			(layers "F.Cu" "F.Mask" "F.Paste")
			(net "GND")
		)
	)
	(footprint ""
		(layer "F.Cu")
		(at 213.9188 -122.460512)
		(property "Reference" "R956"
			(at 0 0 0)
			(layer "F.SilkS")
			(hide yes)
			(effects
				(font
					(size 1.27 1.27)
				)
			)
		)
		(property "Value" ""
			(at 0 0 0)
			(layer "F.Fab")
			(effects
				(font
					(size 1.27 1.27)
				)
			)
		)
		(duplicate_pad_numbers_are_jumpers no)
		(fp_line
			(start -0.7874 -0.4064)
			(end 0.7874 -0.4064)
			(stroke
				(width 0.1524)
				(type default)
			)
			(layer "F.SilkS")
		)
		(fp_line
			(start -0.7874 0.4064)
			(end -0.7874 -0.4064)
			(stroke
				(width 0.1524)
				(type default)
			)
			(layer "F.SilkS")
		)
		(fp_line
			(start 0.7874 -0.4064)
			(end 0.7874 0.4064)
			(stroke
				(width 0.1524)
				(type default)
			)
			(layer "F.SilkS")
		)
		(fp_line
			(start 0.7874 0.4064)
			(end -0.7874 0.4064)
			(stroke
				(width 0.1524)
				(type default)
			)
			(layer "F.SilkS")
		)
		(fp_line
			(start -0.67945 -0.305054)
			(end -0.12065 -0.305054)
			(stroke
				(width 0.1)
				(type default)
			)
			(layer "F.Fab")
		)
		(fp_line
			(start -0.67945 0.3048)
			(end -0.67945 -0.305054)
			(stroke
				(width 0.1)
				(type default)
			)
			(layer "F.Fab")
		)
		(fp_line
			(start -0.12065 -0.305054)
			(end -0.12065 -0.2794)
			(stroke
				(width 0.1)
				(type default)
			)
			(layer "F.Fab")
		)
		(fp_line
			(start -0.12065 -0.2794)
			(end 0.12065 -0.2794)
			(stroke
				(width 0.1)
				(type default)
			)
			(layer "F.Fab")
		)
		(fp_line
			(start -0.12065 0.2794)
			(end -0.12065 0.3048)
			(stroke
				(width 0.1)
				(type default)
			)
			(layer "F.Fab")
		)
		(fp_line
			(start -0.12065 0.3048)
			(end -0.67945 0.3048)
			(stroke
				(width 0.1)
				(type default)
			)
			(layer "F.Fab")
		)
		(fp_line
			(start 0.120396 0.2794)
			(end -0.12065 0.2794)
			(stroke
				(width 0.1)
				(type default)
			)
			(layer "F.Fab")
		)
		(fp_line
			(start 0.120396 0.3048)
			(end 0.120396 0.2794)
			(stroke
				(width 0.1)
				(type default)
			)
			(layer "F.Fab")
		)
		(fp_line
			(start 0.12065 -0.3048)
			(end 0.67945 -0.3048)
			(stroke
				(width 0.1)
				(type default)
			)
			(layer "F.Fab")
		)
		(fp_line
			(start 0.12065 -0.2794)
			(end 0.12065 -0.3048)
			(stroke
				(width 0.1)
				(type default)
			)
			(layer "F.Fab")
		)
		(fp_line
			(start 0.67945 -0.3048)
			(end 0.67945 0.3048)
			(stroke
				(width 0.1)
				(type default)
			)
			(layer "F.Fab")
		)
		(fp_line
			(start 0.67945 0.3048)
			(end 0.120396 0.3048)
			(stroke
				(width 0.1)
				(type default)
			)
			(layer "F.Fab")
		)
		(pad "1" smd circle
			(at -0.40005 0)
			(size 0 0)
			(layers "F.Cu" "F.Mask" "F.Paste")
			(net "RST_PERST_OCP_SFF_BUF2_N")
		)
		(pad "2" smd circle
			(at 0.40005 0)
			(size 0 0)
			(layers "F.Cu" "F.Mask" "F.Paste")
			(net "RST_PERST3_OCP_SFF_N")
		)
	)
	(footprint ""
		(layer "F.Cu")
		(at 301.800768 -147.909788 180)
		(property "Reference" "U105"
			(at -1.93294 -3.065272 90)
			(unlocked yes)
			(layer "F.SilkS")
			(effects
				(font
					(size 0.7874 0.5842)
					(thickness 0.1524)
				)
			)
		)
		(property "Value" ""
			(at 0 0 180)
			(layer "F.Fab")
			(effects
				(font
					(size 1.27 1.27)
				)
			)
		)
		(duplicate_pad_numbers_are_jumpers no)
		(fp_line
			(start 1.03378 1.284478)
			(end -1.03378 1.284478)
			(stroke
				(width 0.1524)
				(type default)
			)
			(layer "F.SilkS")
		)
		(fp_line
			(start 1.03378 -1.284478)
			(end 1.03378 1.284478)
			(stroke
				(width 0.1524)
				(type default)
			)
			(layer "F.SilkS")
		)
		(fp_line
			(start -1.03378 1.284478)
			(end -1.03378 -1.284478)
			(stroke
				(width 0.1524)
				(type default)
			)
			(layer "F.SilkS")
		)
		(fp_line
			(start -1.03378 -1.284478)
			(end 1.03378 -1.284478)
			(stroke
				(width 0.1524)
				(type default)
			)
			(layer "F.SilkS")
		)
		(fp_poly
			(pts
				(xy -1.806702 -1.052576) (xy -1.201674 -0.750062) (xy -1.806702 -0.447548)
			)
			(stroke
				(width 0)
				(type default)
			)
			(fill yes)
			(layer "F.SilkS")
		)
		(fp_line
			(start 0.774954 1.02489)
			(end -0.774954 1.02489)
			(stroke
				(width 0.1)
				(type default)
			)
			(layer "F.Fab")
		)
		(fp_line
			(start 0.774954 -1.02489)
			(end 0.774954 1.02489)
			(stroke
				(width 0.1)
				(type default)
			)
			(layer "F.Fab")
		)
		(fp_line
			(start -0.774954 1.02489)
			(end -0.774954 -1.02489)
			(stroke
				(width 0.1)
				(type default)
			)
			(layer "F.Fab")
		)
		(fp_line
			(start -0.774954 -1.02489)
			(end 0.774954 -1.02489)
			(stroke
				(width 0.1)
				(type default)
			)
			(layer "F.Fab")
		)
		(fp_poly
			(pts
				(xy -1.201674 -0.750062) (xy -1.806702 -0.447548) (xy -1.806702 -1.052576)
			)
			(stroke
				(width 0)
				(type default)
			)
			(fill yes)
			(layer "F.Fab")
		)
		(pad "1" smd rect
			(at -0.64008 -0.750062 270)
			(size 0.3048 0.5334)
			(layers "F.Cu" "F.Mask" "F.Paste")
			(net "I3C_0_SPD_DDRAF_CPU0_SCL")
		)
		(pad "2" smd rect
			(at -0.64008 -0.249936 270)
			(size 0.254 0.5334)
			(layers "F.Cu" "F.Mask" "F.Paste")
			(net "I3C_0_SPD_DDRAF_CPU0_SDA")
		)
		(pad "3" smd rect
			(at -0.64008 0.249936 270)
			(size 0.254 0.5334)
			(layers "F.Cu" "F.Mask" "F.Paste")
			(net "I3C_SCM_0_R_SCL")
		)
		(pad "4" smd rect
			(at -0.64008 0.750062 270)
			(size 0.3048 0.5334)
			(layers "F.Cu" "F.Mask" "F.Paste")
			(net "I3C_SCM_0_R_SDA")
		)
		(pad "5" smd rect
			(at 0 0.839978 180)
			(size 0.3302 0.635)
			(layers "F.Cu" "F.Mask" "F.Paste")
			(net "GND")
		)
		(pad "6" smd rect
			(at 0.64008 0.750062 270)
			(size 0.3048 0.5334)
			(layers "F.Cu" "F.Mask" "F.Paste")
			(net "FM_I3C_CPU0_MUX0_OE_N")
		)
		(pad "7" smd rect
			(at 0.64008 0.249936 270)
			(size 0.254 0.5334)
			(layers "F.Cu" "F.Mask" "F.Paste")
			(net "I3C_SPD_DDRAF_CPU0_LVC1_SDA")
		)
		(pad "8" smd rect
			(at 0.64008 -0.249936 270)
			(size 0.254 0.5334)
			(layers "F.Cu" "F.Mask" "F.Paste")
			(net "I3C_SPD_DDRAF_CPU0_LVC1_SCL")
		)
		(pad "9" smd rect
			(at 0.64008 -0.750062 270)
			(size 0.3048 0.5334)
			(layers "F.Cu" "F.Mask" "F.Paste")
			(net "FM_I3C_CPU0_MUX0_SEL")
		)
		(pad "10" smd rect
			(at 0 -0.839978 180)
			(size 0.3302 0.635)
			(layers "F.Cu" "F.Mask" "F.Paste")
			(net "P3V3_AUX")
		)
	)
	(footprint ""
		(layer "F.Cu")
		(at 504.058428 -298.345606 90)
		(property "Reference" "X3"
			(at -1.94437 1.232916 0)
			(unlocked yes)
			(layer "F.SilkS")
			(effects
				(font
					(size 0.7874 0.5842)
					(thickness 0.1524)
				)
				(justify left)
			)
		)
		(property "Value" ""
			(at 0 0 90)
			(layer "F.Fab")
			(effects
				(font
					(size 1.27 1.27)
				)
			)
		)
		(property "User Part Number" "N_A"
			(at 1.30175 1.27 180)
			(unlocked yes)
			(layer "Cmts.User")
			(hide yes)
			(effects
				(font
					(size 0.635 0.4064)
					(thickness 0.1524)
				)
			)
		)
		(property "Device Type" "TP_TDR_4P_FTS_TH-TP_TDR_4P_DIP,EMPTY,TP15"
			(at 1.30175 1.27 180)
			(unlocked yes)
			(layer "F.Fab")
			(hide yes)
			(effects
				(font
					(size 0.635 0.4064)
					(thickness 0.1524)
				)
			)
		)
		(duplicate_pad_numbers_are_jumpers no)
		(fp_line
			(start 2.54 -1.27)
			(end 0 -1.27)
			(stroke
				(width 0.1524)
				(type default)
			)
			(layer "F.SilkS")
		)
		(fp_line
			(start 0 -1.27)
			(end 0 -0.635)
			(stroke
				(width 0.1524)
				(type default)
			)
			(layer "F.SilkS")
		)
		(fp_line
			(start 2.54 -1.1303)
			(end 2.54 -1.27)
			(stroke
				(width 0.1524)
				(type default)
			)
			(layer "F.SilkS")
		)
		(fp_line
			(start 0 0.635)
			(end 0 1.905)
			(stroke
				(width 0.1524)
				(type default)
			)
			(layer "F.SilkS")
		)
		(fp_line
			(start 2.54 1.4097)
			(end 2.54 1.1303)
			(stroke
				(width 0.1524)
				(type default)
			)
			(layer "F.SilkS")
		)
		(fp_line
			(start 0 3.175)
			(end 0 3.81)
			(stroke
				(width 0.1524)
				(type default)
			)
			(layer "F.SilkS")
		)
		(fp_line
			(start 2.54 3.81)
			(end 2.54 3.6703)
			(stroke
				(width 0.1524)
				(type default)
			)
			(layer "F.SilkS")
		)
		(fp_line
			(start 0 3.81)
			(end 2.54 3.81)
			(stroke
				(width 0.1524)
				(type default)
			)
			(layer "F.SilkS")
		)
		(fp_poly
			(pts
				(xy -0.761746 0) (xy -2.285746 0.762) (xy -2.285746 -0.762)
			)
			(stroke
				(width 0)
				(type default)
			)
			(fill yes)
			(layer "F.SilkS")
		)
		(fp_line
			(start 2.54 -1.27)
			(end 0 -1.27)
			(stroke
				(width 0.1)
				(type default)
			)
			(layer "F.Fab")
		)
		(fp_line
			(start 0 -1.27)
			(end 0 3.81)
			(stroke
				(width 0.1)
				(type default)
			)
			(layer "F.Fab")
		)
		(fp_line
			(start 2.54 3.81)
			(end 2.54 -1.27)
			(stroke
				(width 0.1)
				(type default)
			)
			(layer "F.Fab")
		)
		(fp_line
			(start 0 3.81)
			(end 2.54 3.81)
			(stroke
				(width 0.1)
				(type default)
			)
			(layer "F.Fab")
		)
		(fp_poly
			(pts
				(xy -0.761746 0) (xy -2.285746 -0.762) (xy -2.285746 0.762)
			)
			(stroke
				(width 0)
				(type default)
			)
			(fill yes)
			(layer "F.Fab")
		)
		(pad "1" thru_hole circle
			(at 0 0 90)
			(size 1.0033 1.0033)
			(drill 0.249936)
			(layers "*.Cu" "*.Mask")
			(remove_unused_layers no)
			(net "TDR_DIFF_80_IN2_DP")
			(clearance 0.10795)
			(thermal_gap 0.10795)
			(padstack
				(mode front_inner_back)
				(layer "Inner"
					(shape circle)
					(size 0.8001 0.8001)
					(clearance 0.1524)
				)
				(layer "B.Cu"
					(shape circle)
					(size 1.0033 1.0033)
					(clearance 0.10795)
				)
			)
		)
		(pad "2" thru_hole circle
			(at 2.54 0 90)
			(size 1.9939 1.9939)
			(drill 0.249936)
			(layers "*.Cu" "*.Mask")
			(remove_unused_layers no)
			(net "T1_GND")
			(clearance 0.10795)
			(thermal_gap 0.10795)
			(padstack
				(mode front_inner_back)
				(layer "Inner"
					(shape circle)
					(size 0.8001 0.8001)
					(clearance 0.1524)
				)
				(layer "B.Cu"
					(shape circle)
					(size 1.9939 1.9939)
					(clearance 0.10795)
				)
			)
		)
		(pad "3" thru_hole circle
			(at 2.54 2.54 90)
			(size 1.9939 1.9939)
			(drill 0.249936)
			(layers "*.Cu" "*.Mask")
			(remove_unused_layers no)
			(net "T1_GND")
			(clearance 0.10795)
			(thermal_gap 0.10795)
			(padstack
				(mode front_inner_back)
				(layer "Inner"
					(shape circle)
					(size 0.8001 0.8001)
					(clearance 0.1524)
				)
				(layer "B.Cu"
					(shape circle)
					(size 1.9939 1.9939)
					(clearance 0.10795)
				)
			)
		)
		(pad "4" thru_hole circle
			(at 0 2.54 90)
			(size 1.0033 1.0033)
			(drill 0.249936)
			(layers "*.Cu" "*.Mask")
			(remove_unused_layers no)
			(net "TDR_DIFF_80_IN2_DN")
			(clearance 0.10795)
			(thermal_gap 0.10795)
			(padstack
				(mode front_inner_back)
				(layer "Inner"
					(shape circle)
					(size 0.8001 0.8001)
					(clearance 0.1524)
				)
				(layer "B.Cu"
					(shape circle)
					(size 1.0033 1.0033)
					(clearance 0.10795)
				)
			)
		)
	)
	(footprint ""
		(layer "F.Cu")
		(at 364.314486 -409.931616 180)
		(property "Reference" "C9002"
			(at 0 0 180)
			(layer "F.SilkS")
			(hide yes)
			(effects
				(font
					(size 1.27 1.27)
				)
			)
		)
		(property "Value" ""
			(at 0 0 180)
			(layer "F.Fab")
			(effects
				(font
					(size 1.27 1.27)
				)
			)
		)
		(duplicate_pad_numbers_are_jumpers no)
		(fp_line
			(start 0.7874 0.4064)
			(end -0.7874 0.4064)
			(stroke
				(width 0.1524)
				(type default)
			)
			(layer "F.SilkS")
		)
		(fp_line
			(start 0.7874 -0.4064)
			(end 0.7874 0.4064)
			(stroke
				(width 0.1524)
				(type default)
			)
			(layer "F.SilkS")
		)
		(fp_line
			(start -0.7874 0.4064)
			(end -0.7874 -0.4064)
			(stroke
				(width 0.1524)
				(type default)
			)
			(layer "F.SilkS")
		)
		(fp_line
			(start -0.7874 -0.4064)
			(end 0.7874 -0.4064)
			(stroke
				(width 0.1524)
				(type default)
			)
			(layer "F.SilkS")
		)
		(fp_line
			(start 0.67945 0.3048)
			(end 0.120396 0.3048)
			(stroke
				(width 0.1)
				(type default)
			)
			(layer "F.Fab")
		)
		(fp_line
			(start 0.67945 -0.3048)
			(end 0.67945 0.3048)
			(stroke
				(width 0.1)
				(type default)
			)
			(layer "F.Fab")
		)
		(fp_line
			(start 0.12065 -0.2794)
			(end 0.12065 -0.3048)
			(stroke
				(width 0.1)
				(type default)
			)
			(layer "F.Fab")
		)
		(fp_line
			(start 0.12065 -0.3048)
			(end 0.67945 -0.3048)
			(stroke
				(width 0.1)
				(type default)
			)
			(layer "F.Fab")
		)
		(fp_line
			(start 0.120396 0.3048)
			(end 0.120396 0.2794)
			(stroke
				(width 0.1)
				(type default)
			)
			(layer "F.Fab")
		)
		(fp_line
			(start 0.120396 0.2794)
			(end -0.12065 0.2794)
			(stroke
				(width 0.1)
				(type default)
			)
			(layer "F.Fab")
		)
		(fp_line
			(start -0.12065 0.3048)
			(end -0.67945 0.3048)
			(stroke
				(width 0.1)
				(type default)
			)
			(layer "F.Fab")
		)
		(fp_line
			(start -0.12065 0.2794)
			(end -0.12065 0.3048)
			(stroke
				(width 0.1)
				(type default)
			)
			(layer "F.Fab")
		)
		(fp_line
			(start -0.12065 -0.2794)
			(end 0.12065 -0.2794)
			(stroke
				(width 0.1)
				(type default)
			)
			(layer "F.Fab")
		)
		(fp_line
			(start -0.12065 -0.305054)
			(end -0.12065 -0.2794)
			(stroke
				(width 0.1)
				(type default)
			)
			(layer "F.Fab")
		)
		(fp_line
			(start -0.67945 0.3048)
			(end -0.67945 -0.305054)
			(stroke
				(width 0.1)
				(type default)
			)
			(layer "F.Fab")
		)
		(fp_line
			(start -0.67945 -0.305054)
			(end -0.12065 -0.305054)
			(stroke
				(width 0.1)
				(type default)
			)
			(layer "F.Fab")
		)
		(pad "1" smd circle
			(at -0.40005 0 180)
			(size 0 0)
			(layers "F.Cu" "F.Mask" "F.Paste")
			(net "PRSNT_CABLE_GPU_A3_ISO_N")
		)
		(pad "2" smd circle
			(at 0.40005 0 180)
			(size 0 0)
			(layers "F.Cu" "F.Mask" "F.Paste")
			(net "GND")
		)
	)
	(footprint ""
		(layer "F.Cu")
		(at 161.06013 -352.668078 -90)
		(property "Reference" "R8382"
			(at 0 0 270)
			(layer "F.SilkS")
			(hide yes)
			(effects
				(font
					(size 1.27 1.27)
				)
			)
		)
		(property "Value" ""
			(at 0 0 270)
			(layer "F.Fab")
			(effects
				(font
					(size 1.27 1.27)
				)
			)
		)
		(duplicate_pad_numbers_are_jumpers no)
		(fp_line
			(start -0.7874 0.4064)
			(end -0.7874 -0.4064)
			(stroke
				(width 0.1524)
				(type default)
			)
			(layer "F.SilkS")
		)
		(fp_line
			(start 0.7874 0.4064)
			(end -0.7874 0.4064)
			(stroke
				(width 0.1524)
				(type default)
			)
			(layer "F.SilkS")
		)
		(fp_line
			(start -0.7874 -0.4064)
			(end 0.7874 -0.4064)
			(stroke
				(width 0.1524)
				(type default)
			)
			(layer "F.SilkS")
		)
		(fp_line
			(start 0.7874 -0.4064)
			(end 0.7874 0.4064)
			(stroke
				(width 0.1524)
				(type default)
			)
			(layer "F.SilkS")
		)
		(fp_line
			(start -0.67945 0.3048)
			(end -0.67945 -0.305054)
			(stroke
				(width 0.1)
				(type default)
			)
			(layer "F.Fab")
		)
		(fp_line
			(start -0.12065 0.3048)
			(end -0.67945 0.3048)
			(stroke
				(width 0.1)
				(type default)
			)
			(layer "F.Fab")
		)
		(fp_line
			(start 0.120396 0.3048)
			(end 0.120396 0.2794)
			(stroke
				(width 0.1)
				(type default)
			)
			(layer "F.Fab")
		)
		(fp_line
			(start 0.67945 0.3048)
			(end 0.120396 0.3048)
			(stroke
				(width 0.1)
				(type default)
			)
			(layer "F.Fab")
		)
		(fp_line
			(start -0.12065 0.2794)
			(end -0.12065 0.3048)
			(stroke
				(width 0.1)
				(type default)
			)
			(layer "F.Fab")
		)
		(fp_line
			(start 0.120396 0.2794)
			(end -0.12065 0.2794)
			(stroke
				(width 0.1)
				(type default)
			)
			(layer "F.Fab")
		)
		(fp_line
			(start -0.12065 -0.2794)
			(end 0.12065 -0.2794)
			(stroke
				(width 0.1)
				(type default)
			)
			(layer "F.Fab")
		)
		(fp_line
			(start 0.12065 -0.2794)
			(end 0.12065 -0.3048)
			(stroke
				(width 0.1)
				(type default)
			)
			(layer "F.Fab")
		)
		(fp_line
			(start 0.12065 -0.3048)
			(end 0.67945 -0.3048)
			(stroke
				(width 0.1)
				(type default)
			)
			(layer "F.Fab")
		)
		(fp_line
			(start 0.67945 -0.3048)
			(end 0.67945 0.3048)
			(stroke
				(width 0.1)
				(type default)
			)
			(layer "F.Fab")
		)
		(fp_line
			(start -0.67945 -0.305054)
			(end -0.12065 -0.305054)
			(stroke
				(width 0.1)
				(type default)
			)
			(layer "F.Fab")
		)
		(fp_line
			(start -0.12065 -0.305054)
			(end -0.12065 -0.2794)
			(stroke
				(width 0.1)
				(type default)
			)
			(layer "F.Fab")
		)
		(pad "1" smd circle
			(at -0.40005 0 270)
			(size 0 0)
			(layers "F.Cu" "F.Mask" "F.Paste")
			(net "SMB_SCM_2_R2_SDA")
		)
		(pad "2" smd circle
			(at 0.40005 0 270)
			(size 0 0)
			(layers "F.Cu" "F.Mask" "F.Paste")
			(net "PVDD11_S3_P1_PMSDA_R")
		)
	)
	(footprint ""
		(layer "F.Cu")
		(at 27.7368 -421.069008)
		(property "Reference" "C6005"
			(at 0 0 0)
			(layer "F.SilkS")
			(hide yes)
			(effects
				(font
					(size 1.27 1.27)
				)
			)
		)
		(property "Value" ""
			(at 0 0 0)
			(layer "F.Fab")
			(effects
				(font
					(size 1.27 1.27)
				)
			)
		)
		(duplicate_pad_numbers_are_jumpers no)
		(fp_line
			(start -0.7874 -0.4064)
			(end -0.3556 -0.4064)
			(stroke
				(width 0.1524)
				(type default)
			)
			(layer "F.SilkS")
		)
		(fp_line
			(start 0.7874 -0.215392)
			(end 0.7874 0.4064)
			(stroke
				(width 0.1524)
				(type default)
			)
			(layer "F.SilkS")
		)
		(fp_line
			(start 0.7874 0.4064)
			(end -0.7874 0.4064)
			(stroke
				(width 0.1524)
				(type default)
			)
			(layer "F.SilkS")
		)
		(fp_line
			(start -0.6858 -0.3048)
			(end -0.1016 -0.3048)
			(stroke
				(width 0.1)
				(type default)
			)
			(layer "F.Fab")
		)
		(fp_line
			(start -0.6858 0.3048)
			(end -0.6858 -0.3048)
			(stroke
				(width 0.1)
				(type default)
			)
			(layer "F.Fab")
		)
		(fp_line
			(start -0.1016 -0.3048)
			(end -0.1016 -0.2794)
			(stroke
				(width 0.1)
				(type default)
			)
			(layer "F.Fab")
		)
		(fp_line
			(start -0.1016 -0.2794)
			(end 0.1016 -0.2794)
			(stroke
				(width 0.1)
				(type default)
			)
			(layer "F.Fab")
		)
		(fp_line
			(start -0.1016 0.2794)
			(end -0.1016 0.3048)
			(stroke
				(width 0.1)
				(type default)
			)
			(layer "F.Fab")
		)
		(fp_line
			(start -0.1016 0.3048)
			(end -0.6858 0.3048)
			(stroke
				(width 0.1)
				(type default)
			)
			(layer "F.Fab")
		)
		(fp_line
			(start 0.1016 -0.3048)
			(end 0.6858 -0.3048)
			(stroke
				(width 0.1)
				(type default)
			)
			(layer "F.Fab")
		)
		(fp_line
			(start 0.1016 -0.2794)
			(end 0.1016 -0.3048)
			(stroke
				(width 0.1)
				(type default)
			)
			(layer "F.Fab")
		)
		(fp_line
			(start 0.1016 0.2794)
			(end -0.1016 0.2794)
			(stroke
				(width 0.1)
				(type default)
			)
			(layer "F.Fab")
		)
		(fp_line
			(start 0.1016 0.3048)
			(end 0.1016 0.2794)
			(stroke
				(width 0.1)
				(type default)
			)
			(layer "F.Fab")
		)
		(fp_line
			(start 0.6858 -0.3048)
			(end 0.6858 0.3048)
			(stroke
				(width 0.1)
				(type default)
			)
			(layer "F.Fab")
		)
		(fp_line
			(start 0.6858 0.3048)
			(end 0.1016 0.3048)
			(stroke
				(width 0.1)
				(type default)
			)
			(layer "F.Fab")
		)
		(pad "1" smd rect
			(at -0.40005 0 180)
			(size 0.4572 0.508)
			(layers "F.Cu" "F.Mask" "F.Paste")
			(net "P2E_MB_BMC_TX_BUF2_DP<0>")
		)
		(pad "2" smd rect
			(at 0.40005 0 180)
			(size 0.4572 0.508)
			(layers "F.Cu" "F.Mask" "F.Paste")
			(net "P2E_MB_BMC_TX_BUF_C_DP<0>")
		)
	)
	(footprint ""
		(layer "F.Cu")
		(at 153.543 -104.648)
		(property "Reference" "C9007"
			(at 0 0 0)
			(layer "F.SilkS")
			(hide yes)
			(effects
				(font
					(size 1.27 1.27)
				)
			)
		)
		(property "Value" ""
			(at 0 0 0)
			(layer "F.Fab")
			(effects
				(font
					(size 1.27 1.27)
				)
			)
		)
		(duplicate_pad_numbers_are_jumpers no)
		(fp_line
			(start -0.7874 -0.4064)
			(end 0.7874 -0.4064)
			(stroke
				(width 0.1524)
				(type default)
			)
			(layer "F.SilkS")
		)
		(fp_line
			(start -0.7874 0.4064)
			(end -0.7874 -0.4064)
			(stroke
				(width 0.1524)
				(type default)
			)
			(layer "F.SilkS")
		)
		(fp_line
			(start 0.7874 -0.4064)
			(end 0.7874 0.4064)
			(stroke
				(width 0.1524)
				(type default)
			)
			(layer "F.SilkS")
		)
		(fp_line
			(start 0.7874 0.4064)
			(end -0.7874 0.4064)
			(stroke
				(width 0.1524)
				(type default)
			)
			(layer "F.SilkS")
		)
		(fp_line
			(start -0.67945 -0.305054)
			(end -0.12065 -0.305054)
			(stroke
				(width 0.1)
				(type default)
			)
			(layer "F.Fab")
		)
		(fp_line
			(start -0.67945 0.3048)
			(end -0.67945 -0.305054)
			(stroke
				(width 0.1)
				(type default)
			)
			(layer "F.Fab")
		)
		(fp_line
			(start -0.12065 -0.305054)
			(end -0.12065 -0.2794)
			(stroke
				(width 0.1)
				(type default)
			)
			(layer "F.Fab")
		)
		(fp_line
			(start -0.12065 -0.2794)
			(end 0.12065 -0.2794)
			(stroke
				(width 0.1)
				(type default)
			)
			(layer "F.Fab")
		)
		(fp_line
			(start -0.12065 0.2794)
			(end -0.12065 0.3048)
			(stroke
				(width 0.1)
				(type default)
			)
			(layer "F.Fab")
		)
		(fp_line
			(start -0.12065 0.3048)
			(end -0.67945 0.3048)
			(stroke
				(width 0.1)
				(type default)
			)
			(layer "F.Fab")
		)
		(fp_line
			(start 0.120396 0.2794)
			(end -0.12065 0.2794)
			(stroke
				(width 0.1)
				(type default)
			)
			(layer "F.Fab")
		)
		(fp_line
			(start 0.120396 0.3048)
			(end 0.120396 0.2794)
			(stroke
				(width 0.1)
				(type default)
			)
			(layer "F.Fab")
		)
		(fp_line
			(start 0.12065 -0.3048)
			(end 0.67945 -0.3048)
			(stroke
				(width 0.1)
				(type default)
			)
			(layer "F.Fab")
		)
		(fp_line
			(start 0.12065 -0.2794)
			(end 0.12065 -0.3048)
			(stroke
				(width 0.1)
				(type default)
			)
			(layer "F.Fab")
		)
		(fp_line
			(start 0.67945 -0.3048)
			(end 0.67945 0.3048)
			(stroke
				(width 0.1)
				(type default)
			)
			(layer "F.Fab")
		)
		(fp_line
			(start 0.67945 0.3048)
			(end 0.120396 0.3048)
			(stroke
				(width 0.1)
				(type default)
			)
			(layer "F.Fab")
		)
		(pad "1" smd circle
			(at -0.40005 0)
			(size 0 0)
			(layers "F.Cu" "F.Mask" "F.Paste")
			(net "P3V3_AUX")
		)
		(pad "2" smd circle
			(at 0.40005 0)
			(size 0 0)
			(layers "F.Cu" "F.Mask" "F.Paste")
			(net "GND")
		)
	)
	(footprint ""
		(layer "F.Cu")
		(at 423.841164 -16.100298 90)
		(property "Reference" "C1572"
			(at 0 0 90)
			(layer "F.SilkS")
			(hide yes)
			(effects
				(font
					(size 1.27 1.27)
				)
			)
		)
		(property "Value" ""
			(at 0 0 90)
			(layer "F.Fab")
			(effects
				(font
					(size 1.27 1.27)
				)
			)
		)
		(duplicate_pad_numbers_are_jumpers no)
		(fp_line
			(start 0.299974 -0.150114)
			(end 0.299974 0.150114)
			(stroke
				(width 0.1)
				(type default)
			)
			(layer "F.Fab")
		)
		(fp_line
			(start -0.299974 -0.150114)
			(end 0.299974 -0.150114)
			(stroke
				(width 0.1)
				(type default)
			)
			(layer "F.Fab")
		)
		(fp_line
			(start 0.299974 0.150114)
			(end -0.299974 0.150114)
			(stroke
				(width 0.1)
				(type default)
			)
			(layer "F.Fab")
		)
		(fp_line
			(start -0.299974 0.150114)
			(end -0.299974 -0.150114)
			(stroke
				(width 0.1)
				(type default)
			)
			(layer "F.Fab")
		)
		(pad "1" smd rect
			(at -0.2667 0 90)
			(size 0.3048 0.381)
			(layers "F.Cu" "F.Mask" "F.Paste")
			(net "P5E_CPU0_G3_TX_C_DN<3>")
		)
		(pad "2" smd rect
			(at 0.2667 0 90)
			(size 0.3048 0.381)
			(layers "F.Cu" "F.Mask" "F.Paste")
			(net "P5E_CPU0_G3_TX_DN<3>")
		)
	)
	(footprint ""
		(layer "F.Cu")
		(at 91.45143 -58.33237 180)
		(property "Reference" "PU200"
			(at 2.957068 2.756662 0)
			(unlocked yes)
			(layer "F.SilkS")
			(effects
				(font
					(size 0.7874 0.5842)
					(thickness 0.1524)
				)
				(justify left)
			)
		)
		(property "Value" ""
			(at 0 0 180)
			(layer "F.Fab")
			(effects
				(font
					(size 1.27 1.27)
				)
			)
		)
		(duplicate_pad_numbers_are_jumpers no)
		(fp_line
			(start 1.774952 1.039876)
			(end 1.774952 -1.039876)
			(stroke
				(width 0.1524)
				(type default)
			)
			(layer "F.SilkS")
		)
		(fp_line
			(start 1.774952 -1.039876)
			(end -1.774952 -1.039876)
			(stroke
				(width 0.1524)
				(type default)
			)
			(layer "F.SilkS")
		)
		(fp_line
			(start -1.774952 1.039876)
			(end 1.774952 1.039876)
			(stroke
				(width 0.1524)
				(type default)
			)
			(layer "F.SilkS")
		)
		(fp_line
			(start -1.774952 -1.039876)
			(end -1.774952 1.039876)
			(stroke
				(width 0.1524)
				(type default)
			)
			(layer "F.SilkS")
		)
		(fp_poly
			(pts
				(xy -0.999998 -1.801876) (xy -0.999998 -1.039876) (xy -1.769872 -1.039876) (xy -1.769872 -0.249936)
				(xy -2.531872 -0.249936) (xy -2.531872 -1.801876)
			)
			(stroke
				(width 0)
				(type default)
			)
			(fill yes)
			(layer "F.SilkS")
		)
		(fp_line
			(start 1.769872 1.039876)
			(end 1.769872 -1.039876)
			(stroke
				(width 0.1)
				(type default)
			)
			(layer "F.Fab")
		)
		(fp_line
			(start 1.769872 -1.039876)
			(end -1.769872 -1.039876)
			(stroke
				(width 0.1)
				(type default)
			)
			(layer "F.Fab")
		)
		(fp_line
			(start -1.769872 1.039876)
			(end 1.769872 1.039876)
			(stroke
				(width 0.1)
				(type default)
			)
			(layer "F.Fab")
		)
		(fp_line
			(start -1.769872 -1.039876)
			(end -1.769872 1.039876)
			(stroke
				(width 0.1)
				(type default)
			)
			(layer "F.Fab")
		)
		(fp_poly
			(pts
				(xy -1.769872 -1.039876) (xy -0.999998 -1.039876) (xy -0.999998 -1.801876) (xy -2.531872 -1.801876)
				(xy -2.531872 -0.249936) (xy -1.769872 -0.249936)
			)
			(stroke
				(width 0)
				(type default)
			)
			(fill yes)
			(layer "F.Fab")
		)
		(pad "A1" smd circle
			(at -1.500124 -0.750062 180)
			(size 0.2286 0.2286)
			(layers "F.Cu" "F.Mask" "F.Paste")
			(net "P3V3_OCP_SENSE_2")
		)
		(pad "A2" smd circle
			(at -0.999998 -0.750062 180)
			(size 0.2286 0.2286)
			(layers "F.Cu" "F.Mask" "F.Paste")
			(net "P3V3_OCP_VCC_2")
		)
		(pad "A3" smd circle
			(at -0.499872 -0.750062 180)
			(size 0.2286 0.2286)
			(layers "F.Cu" "F.Mask" "F.Paste")
			(net "P3V3_AUX")
		)
		(pad "A4" smd circle
			(at 0 -0.750062 180)
			(size 0.2286 0.2286)
			(layers "F.Cu" "F.Mask" "F.Paste")
			(net "P3V3_OCP_V3_2_R")
		)
		(pad "A5" smd circle
			(at 0.499872 -0.750062 180)
			(size 0.2286 0.2286)
			(layers "F.Cu" "F.Mask" "F.Paste")
			(net "P3V3_AUX")
		)
		(pad "A6" smd circle
			(at 0.999998 -0.750062 180)
			(size 0.2286 0.2286)
			(layers "F.Cu" "F.Mask" "F.Paste")
			(net "P3V3_OCP_GATE_2")
		)
		(pad "A7" smd circle
			(at 1.500124 -0.750062 180)
			(size 0.2286 0.2286)
			(layers "F.Cu" "F.Mask" "F.Paste")
			(net "GND")
		)
		(pad "B1" smd circle
			(at -1.500124 -0.249936 180)
			(size 0.2286 0.2286)
			(layers "F.Cu" "F.Mask" "F.Paste")
			(net "P3V3_OCP_CB_2")
		)
		(pad "B2" smd circle
			(at -0.999998 -0.249936 180)
			(size 0.2286 0.2286)
			(layers "F.Cu" "F.Mask" "F.Paste")
			(net "GND")
		)
		(pad "B3" smd circle
			(at -0.499872 -0.249936 180)
			(size 0.2286 0.2286)
			(layers "F.Cu" "F.Mask" "F.Paste")
			(net "P3V3_AUX")
		)
		(pad "B4" smd circle
			(at 0 -0.249936 180)
			(size 0.2286 0.2286)
			(layers "F.Cu" "F.Mask" "F.Paste")
			(net "P3V3_OCP_V3_2_R")
		)
		(pad "B5" smd circle
			(at 0.499872 -0.249936 180)
			(size 0.2286 0.2286)
			(layers "F.Cu" "F.Mask" "F.Paste")
			(net "P3V3_AUX")
		)
		(pad "B6" smd circle
			(at 0.999998 -0.249936 180)
			(size 0.2286 0.2286)
			(layers "F.Cu" "F.Mask" "F.Paste")
			(net "P3V3_OCP_V3_2_R")
		)
		(pad "B7" smd circle
			(at 1.500124 -0.249936 180)
			(size 0.2286 0.2286)
			(layers "F.Cu" "F.Mask" "F.Paste")
			(net "GND")
		)
		(pad "C1" smd circle
			(at -1.500124 0.249936 180)
			(size 0.2286 0.2286)
			(layers "F.Cu" "F.Mask" "F.Paste")
			(net "GND")
		)
		(pad "C2" smd circle
			(at -0.999998 0.249936 180)
			(size 0.2286 0.2286)
			(layers "F.Cu" "F.Mask" "F.Paste")
			(net "GND")
		)
		(pad "C3" smd circle
			(at -0.499872 0.249936 180)
			(size 0.2286 0.2286)
			(layers "F.Cu" "F.Mask" "F.Paste")
			(net "P3V3_AUX")
		)
		(pad "C4" smd circle
			(at 0 0.249936 180)
			(size 0.2286 0.2286)
			(layers "F.Cu" "F.Mask" "F.Paste")
			(net "P3V3_OCP_V3_2_R")
		)
		(pad "C5" smd circle
			(at 0.499872 0.249936 180)
			(size 0.2286 0.2286)
			(layers "F.Cu" "F.Mask" "F.Paste")
			(net "P3V3_AUX")
		)
		(pad "C6" smd circle
			(at 0.999998 0.249936 180)
			(size 0.2286 0.2286)
			(layers "F.Cu" "F.Mask" "F.Paste")
			(net "P3V3_OCP_V3_2_R")
		)
		(pad "C7" smd circle
			(at 1.500124 0.249936 180)
			(size 0.2286 0.2286)
			(layers "F.Cu" "F.Mask" "F.Paste")
			(net "P3V3_OCP_FAULT_2")
		)
		(pad "D1" smd circle
			(at -1.500124 0.750062 180)
			(size 0.2286 0.2286)
			(layers "F.Cu" "F.Mask" "F.Paste")
			(net "P3V3_OCP_REG_2")
		)
		(pad "D2" smd circle
			(at -0.999998 0.750062 180)
			(size 0.2286 0.2286)
			(layers "F.Cu" "F.Mask" "F.Paste")
			(net "P3V3_OCP_UV_2")
		)
		(pad "D3" smd circle
			(at -0.499872 0.750062 180)
			(size 0.2286 0.2286)
			(layers "F.Cu" "F.Mask" "F.Paste")
			(net "P3V3_OCP_OV_2")
		)
		(pad "D4" smd circle
			(at 0 0.750062 180)
			(size 0.2286 0.2286)
			(layers "F.Cu" "F.Mask" "F.Paste")
			(net "P3V3_OCP_V3_2_R")
		)
		(pad "D5" smd circle
			(at 0.499872 0.750062 180)
			(size 0.2286 0.2286)
			(layers "F.Cu" "F.Mask" "F.Paste")
			(net "P3V3_AUX")
		)
		(pad "D6" smd circle
			(at 0.999998 0.750062 180)
			(size 0.2286 0.2286)
			(layers "F.Cu" "F.Mask" "F.Paste")
			(net "P3V3_OCP_V3_2_R")
		)
		(pad "D7" smd circle
			(at 1.500124 0.750062 180)
			(size 0.2286 0.2286)
			(layers "F.Cu" "F.Mask" "F.Paste")
			(net "P3V3_OCP_PWRGD_2")
		)
	)
	(footprint ""
		(layer "F.Cu")
		(at 236.7661 -401.887182)
		(property "Reference" "PC2225"
			(at 0 0 0)
			(layer "F.SilkS")
			(hide yes)
			(effects
				(font
					(size 1.27 1.27)
				)
			)
		)
		(property "Value" ""
			(at 0 0 0)
			(layer "F.Fab")
			(effects
				(font
					(size 1.27 1.27)
				)
			)
		)
		(duplicate_pad_numbers_are_jumpers no)
		(fp_line
			(start -0.7874 -0.4064)
			(end 0.7874 -0.4064)
			(stroke
				(width 0.1524)
				(type default)
			)
			(layer "F.SilkS")
		)
		(fp_line
			(start -0.7874 0.4064)
			(end -0.7874 -0.4064)
			(stroke
				(width 0.1524)
				(type default)
			)
			(layer "F.SilkS")
		)
		(fp_line
			(start 0.7874 -0.4064)
			(end 0.7874 0.4064)
			(stroke
				(width 0.1524)
				(type default)
			)
			(layer "F.SilkS")
		)
		(fp_line
			(start 0.7874 0.4064)
			(end -0.7874 0.4064)
			(stroke
				(width 0.1524)
				(type default)
			)
			(layer "F.SilkS")
		)
		(fp_line
			(start -0.67945 -0.305054)
			(end -0.12065 -0.305054)
			(stroke
				(width 0.1)
				(type default)
			)
			(layer "F.Fab")
		)
		(fp_line
			(start -0.67945 0.3048)
			(end -0.67945 -0.305054)
			(stroke
				(width 0.1)
				(type default)
			)
			(layer "F.Fab")
		)
		(fp_line
			(start -0.12065 -0.305054)
			(end -0.12065 -0.2794)
			(stroke
				(width 0.1)
				(type default)
			)
			(layer "F.Fab")
		)
		(fp_line
			(start -0.12065 -0.2794)
			(end 0.12065 -0.2794)
			(stroke
				(width 0.1)
				(type default)
			)
			(layer "F.Fab")
		)
		(fp_line
			(start -0.12065 0.2794)
			(end -0.12065 0.3048)
			(stroke
				(width 0.1)
				(type default)
			)
			(layer "F.Fab")
		)
		(fp_line
			(start -0.12065 0.3048)
			(end -0.67945 0.3048)
			(stroke
				(width 0.1)
				(type default)
			)
			(layer "F.Fab")
		)
		(fp_line
			(start 0.120396 0.2794)
			(end -0.12065 0.2794)
			(stroke
				(width 0.1)
				(type default)
			)
			(layer "F.Fab")
		)
		(fp_line
			(start 0.120396 0.3048)
			(end 0.120396 0.2794)
			(stroke
				(width 0.1)
				(type default)
			)
			(layer "F.Fab")
		)
		(fp_line
			(start 0.12065 -0.3048)
			(end 0.67945 -0.3048)
			(stroke
				(width 0.1)
				(type default)
			)
			(layer "F.Fab")
		)
		(fp_line
			(start 0.12065 -0.2794)
			(end 0.12065 -0.3048)
			(stroke
				(width 0.1)
				(type default)
			)
			(layer "F.Fab")
		)
		(fp_line
			(start 0.67945 -0.3048)
			(end 0.67945 0.3048)
			(stroke
				(width 0.1)
				(type default)
			)
			(layer "F.Fab")
		)
		(fp_line
			(start 0.67945 0.3048)
			(end 0.120396 0.3048)
			(stroke
				(width 0.1)
				(type default)
			)
			(layer "F.Fab")
		)
		(pad "1" smd circle
			(at -0.40005 0)
			(size 0 0)
			(layers "F.Cu" "F.Mask" "F.Paste")
			(net "HSC_ON")
		)
		(pad "2" smd circle
			(at 0.40005 0)
			(size 0 0)
			(layers "F.Cu" "F.Mask" "F.Paste")
			(net "AGND_HSC")
		)
	)
	(footprint ""
		(layer "F.Cu")
		(at 136.101328 -158.265368 -90)
		(property "Reference" "PR511"
			(at 0 0 270)
			(layer "F.SilkS")
			(hide yes)
			(effects
				(font
					(size 1.27 1.27)
				)
			)
		)
		(property "Value" ""
			(at 0 0 270)
			(layer "F.Fab")
			(effects
				(font
					(size 1.27 1.27)
				)
			)
		)
		(duplicate_pad_numbers_are_jumpers no)
		(fp_line
			(start -0.7874 0.4064)
			(end -0.7874 -0.4064)
			(stroke
				(width 0.1524)
				(type default)
			)
			(layer "F.SilkS")
		)
		(fp_line
			(start 0.7874 0.4064)
			(end -0.7874 0.4064)
			(stroke
				(width 0.1524)
				(type default)
			)
			(layer "F.SilkS")
		)
		(fp_line
			(start -0.7874 -0.4064)
			(end 0.7874 -0.4064)
			(stroke
				(width 0.1524)
				(type default)
			)
			(layer "F.SilkS")
		)
		(fp_line
			(start 0.7874 -0.4064)
			(end 0.7874 0.4064)
			(stroke
				(width 0.1524)
				(type default)
			)
			(layer "F.SilkS")
		)
		(fp_line
			(start -0.67945 0.3048)
			(end -0.67945 -0.305054)
			(stroke
				(width 0.1)
				(type default)
			)
			(layer "F.Fab")
		)
		(fp_line
			(start -0.12065 0.3048)
			(end -0.67945 0.3048)
			(stroke
				(width 0.1)
				(type default)
			)
			(layer "F.Fab")
		)
		(fp_line
			(start 0.120396 0.3048)
			(end 0.120396 0.2794)
			(stroke
				(width 0.1)
				(type default)
			)
			(layer "F.Fab")
		)
		(fp_line
			(start 0.67945 0.3048)
			(end 0.120396 0.3048)
			(stroke
				(width 0.1)
				(type default)
			)
			(layer "F.Fab")
		)
		(fp_line
			(start -0.12065 0.2794)
			(end -0.12065 0.3048)
			(stroke
				(width 0.1)
				(type default)
			)
			(layer "F.Fab")
		)
		(fp_line
			(start 0.120396 0.2794)
			(end -0.12065 0.2794)
			(stroke
				(width 0.1)
				(type default)
			)
			(layer "F.Fab")
		)
		(fp_line
			(start -0.12065 -0.2794)
			(end 0.12065 -0.2794)
			(stroke
				(width 0.1)
				(type default)
			)
			(layer "F.Fab")
		)
		(fp_line
			(start 0.12065 -0.2794)
			(end 0.12065 -0.3048)
			(stroke
				(width 0.1)
				(type default)
			)
			(layer "F.Fab")
		)
		(fp_line
			(start 0.12065 -0.3048)
			(end 0.67945 -0.3048)
			(stroke
				(width 0.1)
				(type default)
			)
			(layer "F.Fab")
		)
		(fp_line
			(start 0.67945 -0.3048)
			(end 0.67945 0.3048)
			(stroke
				(width 0.1)
				(type default)
			)
			(layer "F.Fab")
		)
		(fp_line
			(start -0.67945 -0.305054)
			(end -0.12065 -0.305054)
			(stroke
				(width 0.1)
				(type default)
			)
			(layer "F.Fab")
		)
		(fp_line
			(start -0.12065 -0.305054)
			(end -0.12065 -0.2794)
			(stroke
				(width 0.1)
				(type default)
			)
			(layer "F.Fab")
		)
		(pad "1" smd circle
			(at -0.40005 0 270)
			(size 0 0)
			(layers "F.Cu" "F.Mask" "F.Paste")
			(net "SW_PVDDCR_SOC_P1_SW3_RC")
		)
		(pad "2" smd circle
			(at 0.40005 0 270)
			(size 0 0)
			(layers "F.Cu" "F.Mask" "F.Paste")
			(net "GND")
		)
	)
	(footprint ""
		(layer "F.Cu")
		(at 434.43144 -434.467508 90)
		(property "Reference" "R2836"
			(at 0 0 90)
			(layer "F.SilkS")
			(hide yes)
			(effects
				(font
					(size 1.27 1.27)
				)
			)
		)
		(property "Value" ""
			(at 0 0 90)
			(layer "F.Fab")
			(effects
				(font
					(size 1.27 1.27)
				)
			)
		)
		(duplicate_pad_numbers_are_jumpers no)
		(fp_line
			(start 0.7874 -0.4064)
			(end 0.7874 0.4064)
			(stroke
				(width 0.1524)
				(type default)
			)
			(layer "F.SilkS")
		)
		(fp_line
			(start -0.7874 -0.4064)
			(end 0.7874 -0.4064)
			(stroke
				(width 0.1524)
				(type default)
			)
			(layer "F.SilkS")
		)
		(fp_line
			(start 0.7874 0.4064)
			(end -0.7874 0.4064)
			(stroke
				(width 0.1524)
				(type default)
			)
			(layer "F.SilkS")
		)
		(fp_line
			(start -0.7874 0.4064)
			(end -0.7874 -0.4064)
			(stroke
				(width 0.1524)
				(type default)
			)
			(layer "F.SilkS")
		)
		(fp_line
			(start -0.12065 -0.305054)
			(end -0.12065 -0.2794)
			(stroke
				(width 0.1)
				(type default)
			)
			(layer "F.Fab")
		)
		(fp_line
			(start -0.67945 -0.305054)
			(end -0.12065 -0.305054)
			(stroke
				(width 0.1)
				(type default)
			)
			(layer "F.Fab")
		)
		(fp_line
			(start 0.67945 -0.3048)
			(end 0.67945 0.3048)
			(stroke
				(width 0.1)
				(type default)
			)
			(layer "F.Fab")
		)
		(fp_line
			(start 0.12065 -0.3048)
			(end 0.67945 -0.3048)
			(stroke
				(width 0.1)
				(type default)
			)
			(layer "F.Fab")
		)
		(fp_line
			(start 0.12065 -0.2794)
			(end 0.12065 -0.3048)
			(stroke
				(width 0.1)
				(type default)
			)
			(layer "F.Fab")
		)
		(fp_line
			(start -0.12065 -0.2794)
			(end 0.12065 -0.2794)
			(stroke
				(width 0.1)
				(type default)
			)
			(layer "F.Fab")
		)
		(fp_line
			(start 0.120396 0.2794)
			(end -0.12065 0.2794)
			(stroke
				(width 0.1)
				(type default)
			)
			(layer "F.Fab")
		)
		(fp_line
			(start -0.12065 0.2794)
			(end -0.12065 0.3048)
			(stroke
				(width 0.1)
				(type default)
			)
			(layer "F.Fab")
		)
		(fp_line
			(start 0.67945 0.3048)
			(end 0.120396 0.3048)
			(stroke
				(width 0.1)
				(type default)
			)
			(layer "F.Fab")
		)
		(fp_line
			(start 0.120396 0.3048)
			(end 0.120396 0.2794)
			(stroke
				(width 0.1)
				(type default)
			)
			(layer "F.Fab")
		)
		(fp_line
			(start -0.12065 0.3048)
			(end -0.67945 0.3048)
			(stroke
				(width 0.1)
				(type default)
			)
			(layer "F.Fab")
		)
		(fp_line
			(start -0.67945 0.3048)
			(end -0.67945 -0.305054)
			(stroke
				(width 0.1)
				(type default)
			)
			(layer "F.Fab")
		)
		(pad "1" smd circle
			(at -0.40005 0 90)
			(size 0 0)
			(layers "F.Cu" "F.Mask" "F.Paste")
			(net "P3V3_AUX")
		)
		(pad "2" smd circle
			(at 0.40005 0 90)
			(size 0 0)
			(layers "F.Cu" "F.Mask" "F.Paste")
			(net "FM_SWB_BIC_READY")
		)
	)
	(footprint ""
		(layer "F.Cu")
		(at 408.04084 -378.95403 -90)
		(property "Reference" "C856"
			(at 0 0 270)
			(layer "F.SilkS")
			(hide yes)
			(effects
				(font
					(size 1.27 1.27)
				)
			)
		)
		(property "Value" ""
			(at 0 0 270)
			(layer "F.Fab")
			(effects
				(font
					(size 1.27 1.27)
				)
			)
		)
		(duplicate_pad_numbers_are_jumpers no)
		(fp_line
			(start -0.299974 0.150114)
			(end -0.299974 -0.150114)
			(stroke
				(width 0.1)
				(type default)
			)
			(layer "F.Fab")
		)
		(fp_line
			(start 0.299974 0.150114)
			(end -0.299974 0.150114)
			(stroke
				(width 0.1)
				(type default)
			)
			(layer "F.Fab")
		)
		(fp_line
			(start -0.299974 -0.150114)
			(end 0.299974 -0.150114)
			(stroke
				(width 0.1)
				(type default)
			)
			(layer "F.Fab")
		)
		(fp_line
			(start 0.299974 -0.150114)
			(end 0.299974 0.150114)
			(stroke
				(width 0.1)
				(type default)
			)
			(layer "F.Fab")
		)
		(pad "1" smd rect
			(at -0.2667 0 270)
			(size 0.3048 0.381)
			(layers "F.Cu" "F.Mask" "F.Paste")
			(net "P5E_CPU0_P2_TX_C_DN<6>")
		)
		(pad "2" smd rect
			(at 0.2667 0 270)
			(size 0.3048 0.381)
			(layers "F.Cu" "F.Mask" "F.Paste")
			(net "P5E_CPU0_P2_TX_DN<6>")
		)
	)
	(footprint ""
		(layer "F.Cu")
		(at 215.4301 -401.988782 180)
		(property "Reference" "PR3990"
			(at 0 0 180)
			(layer "F.SilkS")
			(hide yes)
			(effects
				(font
					(size 1.27 1.27)
				)
			)
		)
		(property "Value" ""
			(at 0 0 180)
			(layer "F.Fab")
			(effects
				(font
					(size 1.27 1.27)
				)
			)
		)
		(duplicate_pad_numbers_are_jumpers no)
		(fp_line
			(start 0.7874 0.4064)
			(end -0.7874 0.4064)
			(stroke
				(width 0.1524)
				(type default)
			)
			(layer "F.SilkS")
		)
		(fp_line
			(start 0.7874 -0.4064)
			(end 0.7874 0.4064)
			(stroke
				(width 0.1524)
				(type default)
			)
			(layer "F.SilkS")
		)
		(fp_line
			(start -0.7874 0.4064)
			(end -0.7874 -0.4064)
			(stroke
				(width 0.1524)
				(type default)
			)
			(layer "F.SilkS")
		)
		(fp_line
			(start -0.7874 -0.4064)
			(end 0.7874 -0.4064)
			(stroke
				(width 0.1524)
				(type default)
			)
			(layer "F.SilkS")
		)
		(fp_line
			(start 0.67945 0.3048)
			(end 0.120396 0.3048)
			(stroke
				(width 0.1)
				(type default)
			)
			(layer "F.Fab")
		)
		(fp_line
			(start 0.67945 -0.3048)
			(end 0.67945 0.3048)
			(stroke
				(width 0.1)
				(type default)
			)
			(layer "F.Fab")
		)
		(fp_line
			(start 0.12065 -0.2794)
			(end 0.12065 -0.3048)
			(stroke
				(width 0.1)
				(type default)
			)
			(layer "F.Fab")
		)
		(fp_line
			(start 0.12065 -0.3048)
			(end 0.67945 -0.3048)
			(stroke
				(width 0.1)
				(type default)
			)
			(layer "F.Fab")
		)
		(fp_line
			(start 0.120396 0.3048)
			(end 0.120396 0.2794)
			(stroke
				(width 0.1)
				(type default)
			)
			(layer "F.Fab")
		)
		(fp_line
			(start 0.120396 0.2794)
			(end -0.12065 0.2794)
			(stroke
				(width 0.1)
				(type default)
			)
			(layer "F.Fab")
		)
		(fp_line
			(start -0.12065 0.3048)
			(end -0.67945 0.3048)
			(stroke
				(width 0.1)
				(type default)
			)
			(layer "F.Fab")
		)
		(fp_line
			(start -0.12065 0.2794)
			(end -0.12065 0.3048)
			(stroke
				(width 0.1)
				(type default)
			)
			(layer "F.Fab")
		)
		(fp_line
			(start -0.12065 -0.2794)
			(end 0.12065 -0.2794)
			(stroke
				(width 0.1)
				(type default)
			)
			(layer "F.Fab")
		)
		(fp_line
			(start -0.12065 -0.305054)
			(end -0.12065 -0.2794)
			(stroke
				(width 0.1)
				(type default)
			)
			(layer "F.Fab")
		)
		(fp_line
			(start -0.67945 0.3048)
			(end -0.67945 -0.305054)
			(stroke
				(width 0.1)
				(type default)
			)
			(layer "F.Fab")
		)
		(fp_line
			(start -0.67945 -0.305054)
			(end -0.12065 -0.305054)
			(stroke
				(width 0.1)
				(type default)
			)
			(layer "F.Fab")
		)
		(pad "1" smd circle
			(at -0.40005 0 180)
			(size 0 0)
			(layers "F.Cu" "F.Mask" "F.Paste")
			(net "HSC_IMON")
		)
		(pad "2" smd circle
			(at 0.40005 0 180)
			(size 0 0)
			(layers "F.Cu" "F.Mask" "F.Paste")
			(net "AGND_HSC")
		)
	)
	(footprint ""
		(layer "F.Cu")
		(at 329.592178 -42.176954 180)
		(property "Reference" "R2908"
			(at 0 0 180)
			(layer "F.SilkS")
			(hide yes)
			(effects
				(font
					(size 1.27 1.27)
				)
			)
		)
		(property "Value" ""
			(at 0 0 180)
			(layer "F.Fab")
			(effects
				(font
					(size 1.27 1.27)
				)
			)
		)
		(duplicate_pad_numbers_are_jumpers no)
		(fp_line
			(start 0.7874 0.4064)
			(end -0.7874 0.4064)
			(stroke
				(width 0.1524)
				(type default)
			)
			(layer "F.SilkS")
		)
		(fp_line
			(start 0.7874 -0.4064)
			(end 0.7874 0.4064)
			(stroke
				(width 0.1524)
				(type default)
			)
			(layer "F.SilkS")
		)
		(fp_line
			(start -0.7874 0.4064)
			(end -0.7874 -0.4064)
			(stroke
				(width 0.1524)
				(type default)
			)
			(layer "F.SilkS")
		)
		(fp_line
			(start -0.7874 -0.4064)
			(end 0.7874 -0.4064)
			(stroke
				(width 0.1524)
				(type default)
			)
			(layer "F.SilkS")
		)
		(fp_line
			(start 0.67945 0.3048)
			(end 0.120396 0.3048)
			(stroke
				(width 0.1)
				(type default)
			)
			(layer "F.Fab")
		)
		(fp_line
			(start 0.67945 -0.3048)
			(end 0.67945 0.3048)
			(stroke
				(width 0.1)
				(type default)
			)
			(layer "F.Fab")
		)
		(fp_line
			(start 0.12065 -0.2794)
			(end 0.12065 -0.3048)
			(stroke
				(width 0.1)
				(type default)
			)
			(layer "F.Fab")
		)
		(fp_line
			(start 0.12065 -0.3048)
			(end 0.67945 -0.3048)
			(stroke
				(width 0.1)
				(type default)
			)
			(layer "F.Fab")
		)
		(fp_line
			(start 0.120396 0.3048)
			(end 0.120396 0.2794)
			(stroke
				(width 0.1)
				(type default)
			)
			(layer "F.Fab")
		)
		(fp_line
			(start 0.120396 0.2794)
			(end -0.12065 0.2794)
			(stroke
				(width 0.1)
				(type default)
			)
			(layer "F.Fab")
		)
		(fp_line
			(start -0.12065 0.3048)
			(end -0.67945 0.3048)
			(stroke
				(width 0.1)
				(type default)
			)
			(layer "F.Fab")
		)
		(fp_line
			(start -0.12065 0.2794)
			(end -0.12065 0.3048)
			(stroke
				(width 0.1)
				(type default)
			)
			(layer "F.Fab")
		)
		(fp_line
			(start -0.12065 -0.2794)
			(end 0.12065 -0.2794)
			(stroke
				(width 0.1)
				(type default)
			)
			(layer "F.Fab")
		)
		(fp_line
			(start -0.12065 -0.305054)
			(end -0.12065 -0.2794)
			(stroke
				(width 0.1)
				(type default)
			)
			(layer "F.Fab")
		)
		(fp_line
			(start -0.67945 0.3048)
			(end -0.67945 -0.305054)
			(stroke
				(width 0.1)
				(type default)
			)
			(layer "F.Fab")
		)
		(fp_line
			(start -0.67945 -0.305054)
			(end -0.12065 -0.305054)
			(stroke
				(width 0.1)
				(type default)
			)
			(layer "F.Fab")
		)
		(pad "1" smd circle
			(at -0.40005 0 180)
			(size 0 0)
			(layers "F.Cu" "F.Mask" "F.Paste")
			(net "P3V3")
		)
		(pad "2" smd circle
			(at 0.40005 0 180)
			(size 0 0)
			(layers "F.Cu" "F.Mask" "F.Paste")
			(net "P3V3_ADC")
		)
	)
	(footprint ""
		(layer "F.Cu")
		(at 385.214114 -178.359562 180)
		(property "Reference" "PC551_4"
			(at 0 0 180)
			(layer "F.SilkS")
			(hide yes)
			(effects
				(font
					(size 1.27 1.27)
				)
			)
		)
		(property "Value" ""
			(at 0 0 180)
			(layer "F.Fab")
			(effects
				(font
					(size 1.27 1.27)
				)
			)
		)
		(duplicate_pad_numbers_are_jumpers no)
		(fp_line
			(start 0.7874 0.4064)
			(end -0.7874 0.4064)
			(stroke
				(width 0.1524)
				(type default)
			)
			(layer "F.SilkS")
		)
		(fp_line
			(start 0.7874 -0.4064)
			(end 0.7874 0.4064)
			(stroke
				(width 0.1524)
				(type default)
			)
			(layer "F.SilkS")
		)
		(fp_line
			(start -0.7874 0.4064)
			(end -0.7874 -0.4064)
			(stroke
				(width 0.1524)
				(type default)
			)
			(layer "F.SilkS")
		)
		(fp_line
			(start -0.7874 -0.4064)
			(end 0.7874 -0.4064)
			(stroke
				(width 0.1524)
				(type default)
			)
			(layer "F.SilkS")
		)
		(fp_line
			(start 0.67945 0.3048)
			(end 0.120396 0.3048)
			(stroke
				(width 0.1)
				(type default)
			)
			(layer "F.Fab")
		)
		(fp_line
			(start 0.67945 -0.3048)
			(end 0.67945 0.3048)
			(stroke
				(width 0.1)
				(type default)
			)
			(layer "F.Fab")
		)
		(fp_line
			(start 0.12065 -0.2794)
			(end 0.12065 -0.3048)
			(stroke
				(width 0.1)
				(type default)
			)
			(layer "F.Fab")
		)
		(fp_line
			(start 0.12065 -0.3048)
			(end 0.67945 -0.3048)
			(stroke
				(width 0.1)
				(type default)
			)
			(layer "F.Fab")
		)
		(fp_line
			(start 0.120396 0.3048)
			(end 0.120396 0.2794)
			(stroke
				(width 0.1)
				(type default)
			)
			(layer "F.Fab")
		)
		(fp_line
			(start 0.120396 0.2794)
			(end -0.12065 0.2794)
			(stroke
				(width 0.1)
				(type default)
			)
			(layer "F.Fab")
		)
		(fp_line
			(start -0.12065 0.3048)
			(end -0.67945 0.3048)
			(stroke
				(width 0.1)
				(type default)
			)
			(layer "F.Fab")
		)
		(fp_line
			(start -0.12065 0.2794)
			(end -0.12065 0.3048)
			(stroke
				(width 0.1)
				(type default)
			)
			(layer "F.Fab")
		)
		(fp_line
			(start -0.12065 -0.2794)
			(end 0.12065 -0.2794)
			(stroke
				(width 0.1)
				(type default)
			)
			(layer "F.Fab")
		)
		(fp_line
			(start -0.12065 -0.305054)
			(end -0.12065 -0.2794)
			(stroke
				(width 0.1)
				(type default)
			)
			(layer "F.Fab")
		)
		(fp_line
			(start -0.67945 0.3048)
			(end -0.67945 -0.305054)
			(stroke
				(width 0.1)
				(type default)
			)
			(layer "F.Fab")
		)
		(fp_line
			(start -0.67945 -0.305054)
			(end -0.12065 -0.305054)
			(stroke
				(width 0.1)
				(type default)
			)
			(layer "F.Fab")
		)
		(pad "1" smd circle
			(at -0.40005 0 180)
			(size 0 0)
			(layers "F.Cu" "F.Mask" "F.Paste")
			(net "SW_P12V_AUX_PVDDCR_CPU0_P0_FLT")
		)
		(pad "2" smd circle
			(at 0.40005 0 180)
			(size 0 0)
			(layers "F.Cu" "F.Mask" "F.Paste")
			(net "GND")
		)
	)
	(footprint ""
		(layer "F.Cu")
		(at 360.172 -401.4216)
		(property "Reference" "R1392"
			(at 0 0 0)
			(layer "F.SilkS")
			(hide yes)
			(effects
				(font
					(size 1.27 1.27)
				)
			)
		)
		(property "Value" ""
			(at 0 0 0)
			(layer "F.Fab")
			(effects
				(font
					(size 1.27 1.27)
				)
			)
		)
		(duplicate_pad_numbers_are_jumpers no)
		(fp_line
			(start -0.32512 -0.175006)
			(end 0.32512 -0.175006)
			(stroke
				(width 0.1)
				(type default)
			)
			(layer "F.Fab")
		)
		(fp_line
			(start -0.32512 0.175006)
			(end -0.32512 -0.175006)
			(stroke
				(width 0.1)
				(type default)
			)
			(layer "F.Fab")
		)
		(fp_line
			(start 0.32512 -0.175006)
			(end 0.32512 0.175006)
			(stroke
				(width 0.1)
				(type default)
			)
			(layer "F.Fab")
		)
		(fp_line
			(start 0.32512 0.175006)
			(end -0.32512 0.175006)
			(stroke
				(width 0.1)
				(type default)
			)
			(layer "F.Fab")
		)
		(pad "1" smd rect
			(at -0.2667 0)
			(size 0.3048 0.381)
			(layers "F.Cu" "F.Mask" "F.Paste")
			(net "JTAG_TCK_RT_CPU0_P1")
		)
		(pad "2" smd rect
			(at 0.2667 0 180)
			(size 0.3048 0.381)
			(layers "F.Cu" "F.Mask" "F.Paste")
			(net "GND")
		)
	)
	(footprint ""
		(layer "F.Cu")
		(at 257.242056 -117.89537 180)
		(property "Reference" "R3718"
			(at 0 0 180)
			(layer "F.SilkS")
			(hide yes)
			(effects
				(font
					(size 1.27 1.27)
				)
			)
		)
		(property "Value" ""
			(at 0 0 180)
			(layer "F.Fab")
			(effects
				(font
					(size 1.27 1.27)
				)
			)
		)
		(duplicate_pad_numbers_are_jumpers no)
		(fp_line
			(start 0.7874 0.4064)
			(end -0.7874 0.4064)
			(stroke
				(width 0.1524)
				(type default)
			)
			(layer "F.SilkS")
		)
		(fp_line
			(start 0.7874 -0.4064)
			(end 0.7874 0.4064)
			(stroke
				(width 0.1524)
				(type default)
			)
			(layer "F.SilkS")
		)
		(fp_line
			(start -0.7874 0.4064)
			(end -0.7874 -0.4064)
			(stroke
				(width 0.1524)
				(type default)
			)
			(layer "F.SilkS")
		)
		(fp_line
			(start -0.7874 -0.4064)
			(end 0.7874 -0.4064)
			(stroke
				(width 0.1524)
				(type default)
			)
			(layer "F.SilkS")
		)
		(fp_line
			(start 0.67945 0.3048)
			(end 0.120396 0.3048)
			(stroke
				(width 0.1)
				(type default)
			)
			(layer "F.Fab")
		)
		(fp_line
			(start 0.67945 -0.3048)
			(end 0.67945 0.3048)
			(stroke
				(width 0.1)
				(type default)
			)
			(layer "F.Fab")
		)
		(fp_line
			(start 0.12065 -0.2794)
			(end 0.12065 -0.3048)
			(stroke
				(width 0.1)
				(type default)
			)
			(layer "F.Fab")
		)
		(fp_line
			(start 0.12065 -0.3048)
			(end 0.67945 -0.3048)
			(stroke
				(width 0.1)
				(type default)
			)
			(layer "F.Fab")
		)
		(fp_line
			(start 0.120396 0.3048)
			(end 0.120396 0.2794)
			(stroke
				(width 0.1)
				(type default)
			)
			(layer "F.Fab")
		)
		(fp_line
			(start 0.120396 0.2794)
			(end -0.12065 0.2794)
			(stroke
				(width 0.1)
				(type default)
			)
			(layer "F.Fab")
		)
		(fp_line
			(start -0.12065 0.3048)
			(end -0.67945 0.3048)
			(stroke
				(width 0.1)
				(type default)
			)
			(layer "F.Fab")
		)
		(fp_line
			(start -0.12065 0.2794)
			(end -0.12065 0.3048)
			(stroke
				(width 0.1)
				(type default)
			)
			(layer "F.Fab")
		)
		(fp_line
			(start -0.12065 -0.2794)
			(end 0.12065 -0.2794)
			(stroke
				(width 0.1)
				(type default)
			)
			(layer "F.Fab")
		)
		(fp_line
			(start -0.12065 -0.305054)
			(end -0.12065 -0.2794)
			(stroke
				(width 0.1)
				(type default)
			)
			(layer "F.Fab")
		)
		(fp_line
			(start -0.67945 0.3048)
			(end -0.67945 -0.305054)
			(stroke
				(width 0.1)
				(type default)
			)
			(layer "F.Fab")
		)
		(fp_line
			(start -0.67945 -0.305054)
			(end -0.12065 -0.305054)
			(stroke
				(width 0.1)
				(type default)
			)
			(layer "F.Fab")
		)
		(pad "1" smd circle
			(at -0.40005 0 180)
			(size 0 0)
			(layers "F.Cu" "F.Mask" "F.Paste")
			(net "SMB_LM75_1_3V3AUX_SDA_R")
		)
		(pad "2" smd circle
			(at 0.40005 0 180)
			(size 0 0)
			(layers "F.Cu" "F.Mask" "F.Paste")
			(net "SMB_LM75_1_3V3AUX_SDA")
		)
	)
	(footprint ""
		(layer "F.Cu")
		(at 47.91456 -105.08234)
		(property "Reference" "C1114"
			(at 0 0 0)
			(layer "F.SilkS")
			(hide yes)
			(effects
				(font
					(size 1.27 1.27)
				)
			)
		)
		(property "Value" ""
			(at 0 0 0)
			(layer "F.Fab")
			(effects
				(font
					(size 1.27 1.27)
				)
			)
		)
		(duplicate_pad_numbers_are_jumpers no)
		(fp_line
			(start -1.524 -0.762)
			(end 1.524 -0.762)
			(stroke
				(width 0.1524)
				(type default)
			)
			(layer "F.SilkS")
		)
		(fp_line
			(start -1.524 0.762)
			(end -1.524 -0.762)
			(stroke
				(width 0.1524)
				(type default)
			)
			(layer "F.SilkS")
		)
		(fp_line
			(start 1.524 -0.762)
			(end 1.524 0.762)
			(stroke
				(width 0.1524)
				(type default)
			)
			(layer "F.SilkS")
		)
		(fp_line
			(start 1.524 0.762)
			(end -1.524 0.762)
			(stroke
				(width 0.1524)
				(type default)
			)
			(layer "F.SilkS")
		)
		(fp_line
			(start -1.1049 -0.724916)
			(end -1.1049 0.724916)
			(stroke
				(width 0.1)
				(type default)
			)
			(layer "F.Fab")
		)
		(fp_line
			(start -1.1049 0.724916)
			(end 1.1049 0.724916)
			(stroke
				(width 0.1)
				(type default)
			)
			(layer "F.Fab")
		)
		(fp_line
			(start 1.1049 -0.724916)
			(end -1.1049 -0.724916)
			(stroke
				(width 0.1)
				(type default)
			)
			(layer "F.Fab")
		)
		(fp_line
			(start 1.1049 0.724916)
			(end 1.1049 -0.724916)
			(stroke
				(width 0.1)
				(type default)
			)
			(layer "F.Fab")
		)
		(pad "1" smd rect
			(at -0.889 0 180)
			(size 1.016 1.27)
			(layers "F.Cu" "F.Mask" "F.Paste")
			(net "P3V3_AUX_DSC_S1")
		)
		(pad "2" smd rect
			(at 0.889 0 180)
			(size 1.016 1.27)
			(layers "F.Cu" "F.Mask" "F.Paste")
			(net "GND")
		)
	)
	(footprint ""
		(layer "F.Cu")
		(at 126.804928 -50.169064 180)
		(property "Reference" "R6214"
			(at 0 0 180)
			(layer "F.SilkS")
			(hide yes)
			(effects
				(font
					(size 1.27 1.27)
				)
			)
		)
		(property "Value" ""
			(at 0 0 180)
			(layer "F.Fab")
			(effects
				(font
					(size 1.27 1.27)
				)
			)
		)
		(duplicate_pad_numbers_are_jumpers no)
		(fp_line
			(start 0.7874 0.4064)
			(end -0.7874 0.4064)
			(stroke
				(width 0.1524)
				(type default)
			)
			(layer "F.SilkS")
		)
		(fp_line
			(start 0.7874 -0.4064)
			(end 0.7874 0.4064)
			(stroke
				(width 0.1524)
				(type default)
			)
			(layer "F.SilkS")
		)
		(fp_line
			(start -0.7874 0.4064)
			(end -0.7874 -0.4064)
			(stroke
				(width 0.1524)
				(type default)
			)
			(layer "F.SilkS")
		)
		(fp_line
			(start -0.7874 -0.4064)
			(end 0.7874 -0.4064)
			(stroke
				(width 0.1524)
				(type default)
			)
			(layer "F.SilkS")
		)
		(fp_line
			(start 0.67945 0.3048)
			(end 0.120396 0.3048)
			(stroke
				(width 0.1)
				(type default)
			)
			(layer "F.Fab")
		)
		(fp_line
			(start 0.67945 -0.3048)
			(end 0.67945 0.3048)
			(stroke
				(width 0.1)
				(type default)
			)
			(layer "F.Fab")
		)
		(fp_line
			(start 0.12065 -0.2794)
			(end 0.12065 -0.3048)
			(stroke
				(width 0.1)
				(type default)
			)
			(layer "F.Fab")
		)
		(fp_line
			(start 0.12065 -0.3048)
			(end 0.67945 -0.3048)
			(stroke
				(width 0.1)
				(type default)
			)
			(layer "F.Fab")
		)
		(fp_line
			(start 0.120396 0.3048)
			(end 0.120396 0.2794)
			(stroke
				(width 0.1)
				(type default)
			)
			(layer "F.Fab")
		)
		(fp_line
			(start 0.120396 0.2794)
			(end -0.12065 0.2794)
			(stroke
				(width 0.1)
				(type default)
			)
			(layer "F.Fab")
		)
		(fp_line
			(start -0.12065 0.3048)
			(end -0.67945 0.3048)
			(stroke
				(width 0.1)
				(type default)
			)
			(layer "F.Fab")
		)
		(fp_line
			(start -0.12065 0.2794)
			(end -0.12065 0.3048)
			(stroke
				(width 0.1)
				(type default)
			)
			(layer "F.Fab")
		)
		(fp_line
			(start -0.12065 -0.2794)
			(end 0.12065 -0.2794)
			(stroke
				(width 0.1)
				(type default)
			)
			(layer "F.Fab")
		)
		(fp_line
			(start -0.12065 -0.305054)
			(end -0.12065 -0.2794)
			(stroke
				(width 0.1)
				(type default)
			)
			(layer "F.Fab")
		)
		(fp_line
			(start -0.67945 0.3048)
			(end -0.67945 -0.305054)
			(stroke
				(width 0.1)
				(type default)
			)
			(layer "F.Fab")
		)
		(fp_line
			(start -0.67945 -0.305054)
			(end -0.12065 -0.305054)
			(stroke
				(width 0.1)
				(type default)
			)
			(layer "F.Fab")
		)
		(pad "1" smd circle
			(at -0.40005 0 180)
			(size 0 0)
			(layers "F.Cu" "F.Mask" "F.Paste")
			(net "USB_CPU0_HUB1_MODE_SEL1")
		)
		(pad "2" smd circle
			(at 0.40005 0 180)
			(size 0 0)
			(layers "F.Cu" "F.Mask" "F.Paste")
			(net "GND")
		)
	)
	(footprint ""
		(layer "F.Cu")
		(at 452.138034 -255.560068 180)
		(property "Reference" "J67"
			(at 2.380488 -81.709768 0)
			(unlocked yes)
			(layer "F.SilkS")
			(effects
				(font
					(size 0.7874 0.5842)
					(thickness 0.1524)
				)
			)
		)
		(property "Value" ""
			(at 0 0 180)
			(layer "F.Fab")
			(effects
				(font
					(size 1.27 1.27)
				)
			)
		)
		(duplicate_pad_numbers_are_jumpers no)
		(fp_line
			(start 3.24993 81.000092)
			(end -3.24993 81.000092)
			(stroke
				(width 0.1524)
				(type default)
			)
			(layer "F.SilkS")
		)
		(fp_line
			(start 3.24993 -81.000092)
			(end 3.24993 81.000092)
			(stroke
				(width 0.1524)
				(type default)
			)
			(layer "F.SilkS")
		)
		(fp_line
			(start -3.24993 81.000092)
			(end -3.24993 -81.000092)
			(stroke
				(width 0.1524)
				(type default)
			)
			(layer "F.SilkS")
		)
		(fp_line
			(start -3.24993 72.499982)
			(end 3.24993 72.499982)
			(stroke
				(width 0.1524)
				(type default)
			)
			(layer "F.SilkS")
		)
		(fp_line
			(start -3.24993 -72.499982)
			(end 3.24993 -72.499982)
			(stroke
				(width 0.1524)
				(type default)
			)
			(layer "F.SilkS")
		)
		(fp_line
			(start -3.24993 -81.000092)
			(end 3.24993 -81.000092)
			(stroke
				(width 0.1524)
				(type default)
			)
			(layer "F.SilkS")
		)
		(fp_poly
			(pts
				(xy -4.601972 -64.083184) (xy -3.592322 -63.562484) (xy -4.614672 -63.067184)
			)
			(stroke
				(width 0)
				(type default)
			)
			(fill yes)
			(layer "F.SilkS")
		)
		(fp_line
			(start 3.24993 81.000092)
			(end -3.24993 81.000092)
			(stroke
				(width 0.1)
				(type default)
			)
			(layer "F.Fab")
		)
		(fp_line
			(start 3.24993 -81.000092)
			(end 3.24993 81.000092)
			(stroke
				(width 0.1)
				(type default)
			)
			(layer "F.Fab")
		)
		(fp_line
			(start -3.24993 81.000092)
			(end -3.24993 -81.000092)
			(stroke
				(width 0.1)
				(type default)
			)
			(layer "F.Fab")
		)
		(fp_line
			(start -3.24993 72.499982)
			(end 3.24993 72.499982)
			(stroke
				(width 0.1)
				(type default)
			)
			(layer "F.Fab")
		)
		(fp_line
			(start -3.24993 71.000112)
			(end 3.24993 71.000112)
			(stroke
				(width 0.1)
				(type default)
			)
			(layer "F.Fab")
		)
		(fp_line
			(start -3.24993 -71.000112)
			(end 3.24993 -71.000112)
			(stroke
				(width 0.1)
				(type default)
			)
			(layer "F.Fab")
		)
		(fp_line
			(start -3.24993 -72.499982)
			(end 3.24993 -72.499982)
			(stroke
				(width 0.1)
				(type default)
			)
			(layer "F.Fab")
		)
		(fp_line
			(start -3.24993 -81.000092)
			(end 3.24993 -81.000092)
			(stroke
				(width 0.1)
				(type default)
			)
			(layer "F.Fab")
		)
		(fp_poly
			(pts
				(xy -3.41503 -63.324994) (xy -4.43103 -62.816994) (xy -4.43103 -63.832994)
			)
			(stroke
				(width 0)
				(type default)
			)
			(fill yes)
			(layer "F.Fab")
		)
		(pad "1" smd rect
			(at -2.050034 -63.324994 90)
			(size 0.519938 1.4986)
			(layers "F.Cu" "F.Mask" "F.Paste")
			(net "P12V_MEM_CPU0")
		)
		(pad "2" smd rect
			(at -2.050034 -62.47511 90)
			(size 0.519938 1.4986)
			(layers "F.Cu" "F.Mask" "F.Paste")
			(net "Net_2403")
		)
		(pad "3" smd rect
			(at -2.050034 -61.624972 90)
			(size 0.519938 1.4986)
			(layers "F.Cu" "F.Mask" "F.Paste")
			(net "P3V3_AUX")
		)
		(pad "4" smd rect
			(at -2.050034 -60.775088 90)
			(size 0.519938 1.4986)
			(layers "F.Cu" "F.Mask" "F.Paste")
			(net "I3C_SPD_DDRL_CPU0_SCL")
		)
		(pad "5" smd rect
			(at -2.050034 -59.92495 90)
			(size 0.519938 1.4986)
			(layers "F.Cu" "F.Mask" "F.Paste")
			(net "I3C_SPD_DDRL_CPU0_SDA")
		)
		(pad "6" smd rect
			(at -2.050034 -59.075066 90)
			(size 0.519938 1.4986)
			(layers "F.Cu" "F.Mask" "F.Paste")
			(net "GND")
		)
		(pad "7" smd rect
			(at -2.050034 -58.224928 90)
			(size 0.519938 1.4986)
			(layers "F.Cu" "F.Mask" "F.Paste")
			(net "M_L_CPU0_SA_DQ<0>")
		)
		(pad "8" smd rect
			(at -2.050034 -57.375044 90)
			(size 0.519938 1.4986)
			(layers "F.Cu" "F.Mask" "F.Paste")
			(net "GND")
		)
		(pad "9" smd rect
			(at -2.050034 -56.524906 90)
			(size 0.519938 1.4986)
			(layers "F.Cu" "F.Mask" "F.Paste")
			(net "M_L_CPU0_SA_DQ<1>")
		)
		(pad "10" smd rect
			(at -2.050034 -55.675022 90)
			(size 0.519938 1.4986)
			(layers "F.Cu" "F.Mask" "F.Paste")
			(net "GND")
		)
		(pad "11" smd rect
			(at -2.050034 -54.824884 90)
			(size 0.519938 1.4986)
			(layers "F.Cu" "F.Mask" "F.Paste")
			(net "M_L_CPU0_SA_DQS_DP<0>")
		)
		(pad "12" smd rect
			(at -2.050034 -53.975 90)
			(size 0.519938 1.4986)
			(layers "F.Cu" "F.Mask" "F.Paste")
			(net "M_L_CPU0_SA_DQS_DN<0>")
		)
		(pad "13" smd rect
			(at -2.050034 -53.125116 90)
			(size 0.519938 1.4986)
			(layers "F.Cu" "F.Mask" "F.Paste")
			(net "GND")
		)
		(pad "14" smd rect
			(at -2.050034 -52.274978 90)
			(size 0.519938 1.4986)
			(layers "F.Cu" "F.Mask" "F.Paste")
			(net "M_L_CPU0_SA_DQ<4>")
		)
		(pad "15" smd rect
			(at -2.050034 -51.425094 90)
			(size 0.519938 1.4986)
			(layers "F.Cu" "F.Mask" "F.Paste")
			(net "GND")
		)
		(pad "16" smd rect
			(at -2.050034 -50.574956 90)
			(size 0.519938 1.4986)
			(layers "F.Cu" "F.Mask" "F.Paste")
			(net "M_L_CPU0_SA_DQ<5>")
		)
		(pad "17" smd rect
			(at -2.050034 -49.725072 90)
			(size 0.519938 1.4986)
			(layers "F.Cu" "F.Mask" "F.Paste")
			(net "GND")
		)
		(pad "18" smd rect
			(at -2.050034 -48.874934 90)
			(size 0.519938 1.4986)
			(layers "F.Cu" "F.Mask" "F.Paste")
			(net "M_L_CPU0_SA_DQ<8>")
		)
		(pad "19" smd rect
			(at -2.050034 -48.02505 90)
			(size 0.519938 1.4986)
			(layers "F.Cu" "F.Mask" "F.Paste")
			(net "GND")
		)
		(pad "20" smd rect
			(at -2.050034 -47.174912 90)
			(size 0.519938 1.4986)
			(layers "F.Cu" "F.Mask" "F.Paste")
			(net "M_L_CPU0_SA_DQ<9>")
		)
		(pad "21" smd rect
			(at -2.050034 -46.325028 90)
			(size 0.519938 1.4986)
			(layers "F.Cu" "F.Mask" "F.Paste")
			(net "GND")
		)
		(pad "22" smd rect
			(at -2.050034 -45.47489 90)
			(size 0.519938 1.4986)
			(layers "F.Cu" "F.Mask" "F.Paste")
			(net "M_L_CPU0_SA_DQS_DP<1>")
		)
		(pad "23" smd rect
			(at -2.050034 -44.625006 90)
			(size 0.519938 1.4986)
			(layers "F.Cu" "F.Mask" "F.Paste")
			(net "M_L_CPU0_SA_DQS_DN<1>")
		)
		(pad "24" smd rect
			(at -2.050034 -43.775122 90)
			(size 0.519938 1.4986)
			(layers "F.Cu" "F.Mask" "F.Paste")
			(net "GND")
		)
		(pad "25" smd rect
			(at -2.050034 -42.924984 90)
			(size 0.519938 1.4986)
			(layers "F.Cu" "F.Mask" "F.Paste")
			(net "M_L_CPU0_SA_DQ<12>")
		)
		(pad "26" smd rect
			(at -2.050034 -42.0751 90)
			(size 0.519938 1.4986)
			(layers "F.Cu" "F.Mask" "F.Paste")
			(net "GND")
		)
		(pad "27" smd rect
			(at -2.050034 -41.224962 90)
			(size 0.519938 1.4986)
			(layers "F.Cu" "F.Mask" "F.Paste")
			(net "M_L_CPU0_SA_DQ<13>")
		)
		(pad "28" smd rect
			(at -2.050034 -40.375078 90)
			(size 0.519938 1.4986)
			(layers "F.Cu" "F.Mask" "F.Paste")
			(net "GND")
		)
		(pad "29" smd rect
			(at -2.050034 -39.52494 90)
			(size 0.519938 1.4986)
			(layers "F.Cu" "F.Mask" "F.Paste")
			(net "M_L_CPU0_SA_DQ<16>")
		)
		(pad "30" smd rect
			(at -2.050034 -38.675056 90)
			(size 0.519938 1.4986)
			(layers "F.Cu" "F.Mask" "F.Paste")
			(net "GND")
		)
		(pad "31" smd rect
			(at -2.050034 -37.824918 90)
			(size 0.519938 1.4986)
			(layers "F.Cu" "F.Mask" "F.Paste")
			(net "M_L_CPU0_SA_DQ<17>")
		)
		(pad "32" smd rect
			(at -2.050034 -36.975034 90)
			(size 0.519938 1.4986)
			(layers "F.Cu" "F.Mask" "F.Paste")
			(net "GND")
		)
		(pad "33" smd rect
			(at -2.050034 -36.124896 90)
			(size 0.519938 1.4986)
			(layers "F.Cu" "F.Mask" "F.Paste")
			(net "M_L_CPU0_SA_DQS_DP<2>")
		)
		(pad "34" smd rect
			(at -2.050034 -35.275012 90)
			(size 0.519938 1.4986)
			(layers "F.Cu" "F.Mask" "F.Paste")
			(net "M_L_CPU0_SA_DQS_DN<2>")
		)
		(pad "35" smd rect
			(at -2.050034 -34.425128 90)
			(size 0.519938 1.4986)
			(layers "F.Cu" "F.Mask" "F.Paste")
			(net "GND")
		)
		(pad "36" smd rect
			(at -2.050034 -33.57499 90)
			(size 0.519938 1.4986)
			(layers "F.Cu" "F.Mask" "F.Paste")
			(net "M_L_CPU0_SA_DQ<20>")
		)
		(pad "37" smd rect
			(at -2.050034 -32.725106 90)
			(size 0.519938 1.4986)
			(layers "F.Cu" "F.Mask" "F.Paste")
			(net "GND")
		)
		(pad "38" smd rect
			(at -2.050034 -31.874968 90)
			(size 0.519938 1.4986)
			(layers "F.Cu" "F.Mask" "F.Paste")
			(net "M_L_CPU0_SA_DQ<21>")
		)
		(pad "39" smd rect
			(at -2.050034 -31.025084 90)
			(size 0.519938 1.4986)
			(layers "F.Cu" "F.Mask" "F.Paste")
			(net "GND")
		)
		(pad "40" smd rect
			(at -2.050034 -30.174946 90)
			(size 0.519938 1.4986)
			(layers "F.Cu" "F.Mask" "F.Paste")
			(net "M_L_CPU0_SA_DQ<24>")
		)
		(pad "41" smd rect
			(at -2.050034 -29.325062 90)
			(size 0.519938 1.4986)
			(layers "F.Cu" "F.Mask" "F.Paste")
			(net "GND")
		)
		(pad "42" smd rect
			(at -2.050034 -28.474924 90)
			(size 0.519938 1.4986)
			(layers "F.Cu" "F.Mask" "F.Paste")
			(net "M_L_CPU0_SA_DQ<25>")
		)
		(pad "43" smd rect
			(at -2.050034 -27.62504 90)
			(size 0.519938 1.4986)
			(layers "F.Cu" "F.Mask" "F.Paste")
			(net "GND")
		)
		(pad "44" smd rect
			(at -2.050034 -26.774902 90)
			(size 0.519938 1.4986)
			(layers "F.Cu" "F.Mask" "F.Paste")
			(net "M_L_CPU0_SA_DQS_DP<3>")
		)
		(pad "45" smd rect
			(at -2.050034 -25.925018 90)
			(size 0.519938 1.4986)
			(layers "F.Cu" "F.Mask" "F.Paste")
			(net "M_L_CPU0_SA_DQS_DN<3>")
		)
		(pad "46" smd rect
			(at -2.050034 -25.07488 90)
			(size 0.519938 1.4986)
			(layers "F.Cu" "F.Mask" "F.Paste")
			(net "GND")
		)
		(pad "47" smd rect
			(at -2.050034 -24.224996 90)
			(size 0.519938 1.4986)
			(layers "F.Cu" "F.Mask" "F.Paste")
			(net "M_L_CPU0_SA_DQ<28>")
		)
		(pad "48" smd rect
			(at -2.050034 -23.375112 90)
			(size 0.519938 1.4986)
			(layers "F.Cu" "F.Mask" "F.Paste")
			(net "GND")
		)
		(pad "49" smd rect
			(at -2.050034 -22.524974 90)
			(size 0.519938 1.4986)
			(layers "F.Cu" "F.Mask" "F.Paste")
			(net "M_L_CPU0_SA_DQ<29>")
		)
		(pad "50" smd rect
			(at -2.050034 -21.67509 90)
			(size 0.519938 1.4986)
			(layers "F.Cu" "F.Mask" "F.Paste")
			(net "GND")
		)
		(pad "51" smd rect
			(at -2.050034 -20.824952 90)
			(size 0.519938 1.4986)
			(layers "F.Cu" "F.Mask" "F.Paste")
			(net "M_L_CPU0_SA_CB<0>")
		)
		(pad "52" smd rect
			(at -2.050034 -19.975068 90)
			(size 0.519938 1.4986)
			(layers "F.Cu" "F.Mask" "F.Paste")
			(net "GND")
		)
		(pad "53" smd rect
			(at -2.050034 -19.12493 90)
			(size 0.519938 1.4986)
			(layers "F.Cu" "F.Mask" "F.Paste")
			(net "M_L_CPU0_SA_CB<1>")
		)
		(pad "54" smd rect
			(at -2.050034 -18.275046 90)
			(size 0.519938 1.4986)
			(layers "F.Cu" "F.Mask" "F.Paste")
			(net "GND")
		)
		(pad "55" smd rect
			(at -2.050034 -17.424908 90)
			(size 0.519938 1.4986)
			(layers "F.Cu" "F.Mask" "F.Paste")
			(net "M_L_CPU0_SA_DQS_DP<4>")
		)
		(pad "56" smd rect
			(at -2.050034 -16.575024 90)
			(size 0.519938 1.4986)
			(layers "F.Cu" "F.Mask" "F.Paste")
			(net "M_L_CPU0_SA_DQS_DN<4>")
		)
		(pad "57" smd rect
			(at -2.050034 -15.724886 90)
			(size 0.519938 1.4986)
			(layers "F.Cu" "F.Mask" "F.Paste")
			(net "GND")
		)
		(pad "58" smd rect
			(at -2.050034 -14.875002 90)
			(size 0.519938 1.4986)
			(layers "F.Cu" "F.Mask" "F.Paste")
			(net "M_L_CPU0_SA_CB<4>")
		)
		(pad "59" smd rect
			(at -2.050034 -14.025118 90)
			(size 0.519938 1.4986)
			(layers "F.Cu" "F.Mask" "F.Paste")
			(net "GND")
		)
		(pad "60" smd rect
			(at -2.050034 -13.17498 90)
			(size 0.519938 1.4986)
			(layers "F.Cu" "F.Mask" "F.Paste")
			(net "M_L_CPU0_SA_CB<5>")
		)
		(pad "61" smd rect
			(at -2.050034 -12.325096 90)
			(size 0.519938 1.4986)
			(layers "F.Cu" "F.Mask" "F.Paste")
			(net "GND")
		)
		(pad "62" smd rect
			(at -2.050034 -11.474958 90)
			(size 0.519938 1.4986)
			(layers "F.Cu" "F.Mask" "F.Paste")
			(net "M_L_CPU0_ALERT_N")
		)
		(pad "63" smd rect
			(at -2.050034 -10.625074 90)
			(size 0.519938 1.4986)
			(layers "F.Cu" "F.Mask" "F.Paste")
			(net "GND")
		)
		(pad "64" smd rect
			(at -2.050034 -9.774936 90)
			(size 0.519938 1.4986)
			(layers "F.Cu" "F.Mask" "F.Paste")
			(net "M_L_CPU0_SA_CS_N<0>")
		)
		(pad "65" smd rect
			(at -2.050034 -8.925052 90)
			(size 0.519938 1.4986)
			(layers "F.Cu" "F.Mask" "F.Paste")
			(net "GND")
		)
		(pad "66" smd rect
			(at -2.050034 -8.074914 90)
			(size 0.519938 1.4986)
			(layers "F.Cu" "F.Mask" "F.Paste")
			(net "M_L_CPU0_SA_CA<0>")
		)
		(pad "67" smd rect
			(at -2.050034 -7.22503 90)
			(size 0.519938 1.4986)
			(layers "F.Cu" "F.Mask" "F.Paste")
			(net "GND")
		)
		(pad "68" smd rect
			(at -2.050034 -6.374892 90)
			(size 0.519938 1.4986)
			(layers "F.Cu" "F.Mask" "F.Paste")
			(net "M_L_CPU0_SA_CA<2>")
		)
		(pad "69" smd rect
			(at -2.050034 -5.525008 90)
			(size 0.519938 1.4986)
			(layers "F.Cu" "F.Mask" "F.Paste")
			(net "GND")
		)
		(pad "70" smd rect
			(at -2.050034 -4.675124 90)
			(size 0.519938 1.4986)
			(layers "F.Cu" "F.Mask" "F.Paste")
			(net "M_L_CPU0_SA_CA<4>")
		)
		(pad "71" smd rect
			(at -2.050034 -3.824986 90)
			(size 0.519938 1.4986)
			(layers "F.Cu" "F.Mask" "F.Paste")
			(net "GND")
		)
		(pad "72" smd rect
			(at -2.050034 -2.975102 90)
			(size 0.519938 1.4986)
			(layers "F.Cu" "F.Mask" "F.Paste")
			(net "M_L_CPU0_SA_CA<6>")
		)
		(pad "73" smd rect
			(at -2.050034 -2.124964 90)
			(size 0.519938 1.4986)
			(layers "F.Cu" "F.Mask" "F.Paste")
			(net "GND")
		)
		(pad "74" smd rect
			(at -2.050034 -1.27508 90)
			(size 0.519938 1.4986)
			(layers "F.Cu" "F.Mask" "F.Paste")
			(net "M_L_CPU0_SA_PAR")
		)
		(pad "75" smd rect
			(at -2.050034 -0.424942 90)
			(size 0.519938 1.4986)
			(layers "F.Cu" "F.Mask" "F.Paste")
			(net "GND")
		)
		(pad "76" smd rect
			(at -2.050034 5.525008 90)
			(size 0.519938 1.4986)
			(layers "F.Cu" "F.Mask" "F.Paste")
			(net "M_L_CPU0_SB_CA<0>")
		)
		(pad "77" smd rect
			(at -2.050034 6.374892 90)
			(size 0.519938 1.4986)
			(layers "F.Cu" "F.Mask" "F.Paste")
			(net "GND")
		)
		(pad "78" smd rect
			(at -2.050034 7.22503 90)
			(size 0.519938 1.4986)
			(layers "F.Cu" "F.Mask" "F.Paste")
			(net "M_L_CPU0_SB_CA<2>")
		)
		(pad "79" smd rect
			(at -2.050034 8.074914 90)
			(size 0.519938 1.4986)
			(layers "F.Cu" "F.Mask" "F.Paste")
			(net "GND")
		)
		(pad "80" smd rect
			(at -2.050034 8.925052 90)
			(size 0.519938 1.4986)
			(layers "F.Cu" "F.Mask" "F.Paste")
			(net "M_L_CPU0_SB_CA<4>")
		)
		(pad "81" smd rect
			(at -2.050034 9.774936 90)
			(size 0.519938 1.4986)
			(layers "F.Cu" "F.Mask" "F.Paste")
			(net "GND")
		)
		(pad "82" smd rect
			(at -2.050034 10.625074 90)
			(size 0.519938 1.4986)
			(layers "F.Cu" "F.Mask" "F.Paste")
			(net "M_L_CPU0_SB_CA<6>")
		)
		(pad "83" smd rect
			(at -2.050034 11.474958 90)
			(size 0.519938 1.4986)
			(layers "F.Cu" "F.Mask" "F.Paste")
			(net "GND")
		)
		(pad "84" smd rect
			(at -2.050034 12.325096 90)
			(size 0.519938 1.4986)
			(layers "F.Cu" "F.Mask" "F.Paste")
			(net "M_L_CPU0_SB_CS_N<0>")
		)
		(pad "85" smd rect
			(at -2.050034 13.17498 90)
			(size 0.519938 1.4986)
			(layers "F.Cu" "F.Mask" "F.Paste")
			(net "GND")
		)
		(pad "86" smd rect
			(at -2.050034 14.025118 90)
			(size 0.519938 1.4986)
			(layers "F.Cu" "F.Mask" "F.Paste")
			(net "M_L_CPU0_SA_RSP<0>")
		)
		(pad "87" smd rect
			(at -2.050034 14.875002 90)
			(size 0.519938 1.4986)
			(layers "F.Cu" "F.Mask" "F.Paste")
			(net "M_L_CPU0_SB_RSP<0>")
		)
		(pad "88" smd rect
			(at -2.050034 15.724886 90)
			(size 0.519938 1.4986)
			(layers "F.Cu" "F.Mask" "F.Paste")
			(net "GND")
		)
		(pad "89" smd rect
			(at -2.050034 16.575024 90)
			(size 0.519938 1.4986)
			(layers "F.Cu" "F.Mask" "F.Paste")
			(net "M_L_CPU0_SB_CB<4>")
		)
		(pad "90" smd rect
			(at -2.050034 17.424908 90)
			(size 0.519938 1.4986)
			(layers "F.Cu" "F.Mask" "F.Paste")
			(net "GND")
		)
		(pad "91" smd rect
			(at -2.050034 18.275046 90)
			(size 0.519938 1.4986)
			(layers "F.Cu" "F.Mask" "F.Paste")
			(net "M_L_CPU0_SB_CB<5>")
		)
		(pad "92" smd rect
			(at -2.050034 19.12493 90)
			(size 0.519938 1.4986)
			(layers "F.Cu" "F.Mask" "F.Paste")
			(net "GND")
		)
		(pad "93" smd rect
			(at -2.050034 19.975068 90)
			(size 0.519938 1.4986)
			(layers "F.Cu" "F.Mask" "F.Paste")
			(net "M_L_CPU0_SB_DQS_DP<9>")
		)
		(pad "94" smd rect
			(at -2.050034 20.824952 90)
			(size 0.519938 1.4986)
			(layers "F.Cu" "F.Mask" "F.Paste")
			(net "M_L_CPU0_SB_DQS_DN<9>")
		)
		(pad "95" smd rect
			(at -2.050034 21.67509 90)
			(size 0.519938 1.4986)
			(layers "F.Cu" "F.Mask" "F.Paste")
			(net "GND")
		)
		(pad "96" smd rect
			(at -2.050034 22.524974 90)
			(size 0.519938 1.4986)
			(layers "F.Cu" "F.Mask" "F.Paste")
			(net "M_L_CPU0_SB_CB<0>")
		)
		(pad "97" smd rect
			(at -2.050034 23.375112 90)
			(size 0.519938 1.4986)
			(layers "F.Cu" "F.Mask" "F.Paste")
			(net "GND")
		)
		(pad "98" smd rect
			(at -2.050034 24.224996 90)
			(size 0.519938 1.4986)
			(layers "F.Cu" "F.Mask" "F.Paste")
			(net "M_L_CPU0_SB_CB<1>")
		)
		(pad "99" smd rect
			(at -2.050034 25.07488 90)
			(size 0.519938 1.4986)
			(layers "F.Cu" "F.Mask" "F.Paste")
			(net "GND")
		)
		(pad "100" smd rect
			(at -2.050034 25.925018 90)
			(size 0.519938 1.4986)
			(layers "F.Cu" "F.Mask" "F.Paste")
			(net "M_L_CPU0_SB_DQ<0>")
		)
		(pad "101" smd rect
			(at -2.050034 26.774902 90)
			(size 0.519938 1.4986)
			(layers "F.Cu" "F.Mask" "F.Paste")
			(net "GND")
		)
		(pad "102" smd rect
			(at -2.050034 27.62504 90)
			(size 0.519938 1.4986)
			(layers "F.Cu" "F.Mask" "F.Paste")
			(net "M_L_CPU0_SB_DQ<1>")
		)
		(pad "103" smd rect
			(at -2.050034 28.474924 90)
			(size 0.519938 1.4986)
			(layers "F.Cu" "F.Mask" "F.Paste")
			(net "GND")
		)
		(pad "104" smd rect
			(at -2.050034 29.325062 90)
			(size 0.519938 1.4986)
			(layers "F.Cu" "F.Mask" "F.Paste")
			(net "M_L_CPU0_SB_DQS_DP<0>")
		)
		(pad "105" smd rect
			(at -2.050034 30.174946 90)
			(size 0.519938 1.4986)
			(layers "F.Cu" "F.Mask" "F.Paste")
			(net "M_L_CPU0_SB_DQS_DN<0>")
		)
		(pad "106" smd rect
			(at -2.050034 31.025084 90)
			(size 0.519938 1.4986)
			(layers "F.Cu" "F.Mask" "F.Paste")
			(net "GND")
		)
		(pad "107" smd rect
			(at -2.050034 31.874968 90)
			(size 0.519938 1.4986)
			(layers "F.Cu" "F.Mask" "F.Paste")
			(net "M_L_CPU0_SB_DQ<4>")
		)
		(pad "108" smd rect
			(at -2.050034 32.725106 90)
			(size 0.519938 1.4986)
			(layers "F.Cu" "F.Mask" "F.Paste")
			(net "GND")
		)
		(pad "109" smd rect
			(at -2.050034 33.57499 90)
			(size 0.519938 1.4986)
			(layers "F.Cu" "F.Mask" "F.Paste")
			(net "M_L_CPU0_SB_DQ<5>")
		)
		(pad "110" smd rect
			(at -2.050034 34.425128 90)
			(size 0.519938 1.4986)
			(layers "F.Cu" "F.Mask" "F.Paste")
			(net "GND")
		)
		(pad "111" smd rect
			(at -2.050034 35.275012 90)
			(size 0.519938 1.4986)
			(layers "F.Cu" "F.Mask" "F.Paste")
			(net "M_L_CPU0_SB_DQ<8>")
		)
		(pad "112" smd rect
			(at -2.050034 36.124896 90)
			(size 0.519938 1.4986)
			(layers "F.Cu" "F.Mask" "F.Paste")
			(net "GND")
		)
		(pad "113" smd rect
			(at -2.050034 36.975034 90)
			(size 0.519938 1.4986)
			(layers "F.Cu" "F.Mask" "F.Paste")
			(net "M_L_CPU0_SB_DQ<9>")
		)
		(pad "114" smd rect
			(at -2.050034 37.824918 90)
			(size 0.519938 1.4986)
			(layers "F.Cu" "F.Mask" "F.Paste")
			(net "GND")
		)
		(pad "115" smd rect
			(at -2.050034 38.675056 90)
			(size 0.519938 1.4986)
			(layers "F.Cu" "F.Mask" "F.Paste")
			(net "M_L_CPU0_SB_DQS_DP<1>")
		)
		(pad "116" smd rect
			(at -2.050034 39.52494 90)
			(size 0.519938 1.4986)
			(layers "F.Cu" "F.Mask" "F.Paste")
			(net "M_L_CPU0_SB_DQS_DN<1>")
		)
		(pad "117" smd rect
			(at -2.050034 40.375078 90)
			(size 0.519938 1.4986)
			(layers "F.Cu" "F.Mask" "F.Paste")
			(net "GND")
		)
		(pad "118" smd rect
			(at -2.050034 41.224962 90)
			(size 0.519938 1.4986)
			(layers "F.Cu" "F.Mask" "F.Paste")
			(net "M_L_CPU0_SB_DQ<12>")
		)
		(pad "119" smd rect
			(at -2.050034 42.0751 90)
			(size 0.519938 1.4986)
			(layers "F.Cu" "F.Mask" "F.Paste")
			(net "GND")
		)
		(pad "120" smd rect
			(at -2.050034 42.924984 90)
			(size 0.519938 1.4986)
			(layers "F.Cu" "F.Mask" "F.Paste")
			(net "M_L_CPU0_SB_DQ<13>")
		)
		(pad "121" smd rect
			(at -2.050034 43.775122 90)
			(size 0.519938 1.4986)
			(layers "F.Cu" "F.Mask" "F.Paste")
			(net "GND")
		)
		(pad "122" smd rect
			(at -2.050034 44.625006 90)
			(size 0.519938 1.4986)
			(layers "F.Cu" "F.Mask" "F.Paste")
			(net "M_L_CPU0_SB_DQ<16>")
		)
		(pad "123" smd rect
			(at -2.050034 45.47489 90)
			(size 0.519938 1.4986)
			(layers "F.Cu" "F.Mask" "F.Paste")
			(net "GND")
		)
		(pad "124" smd rect
			(at -2.050034 46.325028 90)
			(size 0.519938 1.4986)
			(layers "F.Cu" "F.Mask" "F.Paste")
			(net "M_L_CPU0_SB_DQ<17>")
		)
		(pad "125" smd rect
			(at -2.050034 47.174912 90)
			(size 0.519938 1.4986)
			(layers "F.Cu" "F.Mask" "F.Paste")
			(net "GND")
		)
		(pad "126" smd rect
			(at -2.050034 48.02505 90)
			(size 0.519938 1.4986)
			(layers "F.Cu" "F.Mask" "F.Paste")
			(net "M_L_CPU0_SB_DQS_DP<2>")
		)
		(pad "127" smd rect
			(at -2.050034 48.874934 90)
			(size 0.519938 1.4986)
			(layers "F.Cu" "F.Mask" "F.Paste")
			(net "M_L_CPU0_SB_DQS_DN<2>")
		)
		(pad "128" smd rect
			(at -2.050034 49.725072 90)
			(size 0.519938 1.4986)
			(layers "F.Cu" "F.Mask" "F.Paste")
			(net "GND")
		)
		(pad "129" smd rect
			(at -2.050034 50.574956 90)
			(size 0.519938 1.4986)
			(layers "F.Cu" "F.Mask" "F.Paste")
			(net "M_L_CPU0_SB_DQ<20>")
		)
		(pad "130" smd rect
			(at -2.050034 51.425094 90)
			(size 0.519938 1.4986)
			(layers "F.Cu" "F.Mask" "F.Paste")
			(net "GND")
		)
		(pad "131" smd rect
			(at -2.050034 52.274978 90)
			(size 0.519938 1.4986)
			(layers "F.Cu" "F.Mask" "F.Paste")
			(net "M_L_CPU0_SB_DQ<21>")
		)
		(pad "132" smd rect
			(at -2.050034 53.125116 90)
			(size 0.519938 1.4986)
			(layers "F.Cu" "F.Mask" "F.Paste")
			(net "GND")
		)
		(pad "133" smd rect
			(at -2.050034 53.975 90)
			(size 0.519938 1.4986)
			(layers "F.Cu" "F.Mask" "F.Paste")
			(net "M_L_CPU0_SB_DQ<24>")
		)
		(pad "134" smd rect
			(at -2.050034 54.824884 90)
			(size 0.519938 1.4986)
			(layers "F.Cu" "F.Mask" "F.Paste")
			(net "GND")
		)
		(pad "135" smd rect
			(at -2.050034 55.675022 90)
			(size 0.519938 1.4986)
			(layers "F.Cu" "F.Mask" "F.Paste")
			(net "M_L_CPU0_SB_DQ<25>")
		)
		(pad "136" smd rect
			(at -2.050034 56.524906 90)
			(size 0.519938 1.4986)
			(layers "F.Cu" "F.Mask" "F.Paste")
			(net "GND")
		)
		(pad "137" smd rect
			(at -2.050034 57.375044 90)
			(size 0.519938 1.4986)
			(layers "F.Cu" "F.Mask" "F.Paste")
			(net "M_L_CPU0_SB_DQS_DP<3>")
		)
		(pad "138" smd rect
			(at -2.050034 58.224928 90)
			(size 0.519938 1.4986)
			(layers "F.Cu" "F.Mask" "F.Paste")
			(net "M_L_CPU0_SB_DQS_DN<3>")
		)
		(pad "139" smd rect
			(at -2.050034 59.075066 90)
			(size 0.519938 1.4986)
			(layers "F.Cu" "F.Mask" "F.Paste")
			(net "GND")
		)
		(pad "140" smd rect
			(at -2.050034 59.92495 90)
			(size 0.519938 1.4986)
			(layers "F.Cu" "F.Mask" "F.Paste")
			(net "M_L_CPU0_SB_DQ<28>")
		)
		(pad "141" smd rect
			(at -2.050034 60.775088 90)
			(size 0.519938 1.4986)
			(layers "F.Cu" "F.Mask" "F.Paste")
			(net "GND")
		)
		(pad "142" smd rect
			(at -2.050034 61.624972 90)
			(size 0.519938 1.4986)
			(layers "F.Cu" "F.Mask" "F.Paste")
			(net "M_L_CPU0_SB_DQ<29>")
		)
		(pad "143" smd rect
			(at -2.050034 62.47511 90)
			(size 0.519938 1.4986)
			(layers "F.Cu" "F.Mask" "F.Paste")
			(net "GND")
		)
		(pad "144" smd rect
			(at -2.050034 63.324994 90)
			(size 0.519938 1.4986)
			(layers "F.Cu" "F.Mask" "F.Paste")
			(net "Net_2404")
		)
		(pad "145" smd rect
			(at 2.050034 -63.324994 90)
			(size 0.519938 1.4986)
			(layers "F.Cu" "F.Mask" "F.Paste")
			(net "P12V_MEM_CPU0")
		)
		(pad "146" smd rect
			(at 2.050034 -62.47511 90)
			(size 0.519938 1.4986)
			(layers "F.Cu" "F.Mask" "F.Paste")
			(net "P12V_MEM_CPU0")
		)
		(pad "147" smd rect
			(at 2.050034 -61.624972 90)
			(size 0.519938 1.4986)
			(layers "F.Cu" "F.Mask" "F.Paste")
			(net "PWRGD_CHL_CPU0_DIMM")
		)
		(pad "148" smd rect
			(at 2.050034 -60.775088 90)
			(size 0.519938 1.4986)
			(layers "F.Cu" "F.Mask" "F.Paste")
			(net "PD_CHL_CPU0_DIMM_SAA")
		)
		(pad "149" smd rect
			(at 2.050034 -59.92495 90)
			(size 0.519938 1.4986)
			(layers "F.Cu" "F.Mask" "F.Paste")
			(net "Net_2405")
		)
		(pad "150" smd rect
			(at 2.050034 -59.075066 90)
			(size 0.519938 1.4986)
			(layers "F.Cu" "F.Mask" "F.Paste")
			(net "Net_2406")
		)
		(pad "151" smd rect
			(at 2.050034 -58.224928 90)
			(size 0.519938 1.4986)
			(layers "F.Cu" "F.Mask" "F.Paste")
			(net "GND")
		)
		(pad "152" smd rect
			(at 2.050034 -57.375044 90)
			(size 0.519938 1.4986)
			(layers "F.Cu" "F.Mask" "F.Paste")
			(net "M_L_CPU0_SA_DQ<2>")
		)
		(pad "153" smd rect
			(at 2.050034 -56.524906 90)
			(size 0.519938 1.4986)
			(layers "F.Cu" "F.Mask" "F.Paste")
			(net "GND")
		)
		(pad "154" smd rect
			(at 2.050034 -55.675022 90)
			(size 0.519938 1.4986)
			(layers "F.Cu" "F.Mask" "F.Paste")
			(net "M_L_CPU0_SA_DQ<3>")
		)
		(pad "155" smd rect
			(at 2.050034 -54.824884 90)
			(size 0.519938 1.4986)
			(layers "F.Cu" "F.Mask" "F.Paste")
			(net "GND")
		)
		(pad "156" smd rect
			(at 2.050034 -53.975 90)
			(size 0.519938 1.4986)
			(layers "F.Cu" "F.Mask" "F.Paste")
			(net "M_L_CPU0_SA_DQS_DN<5>")
		)
		(pad "157" smd rect
			(at 2.050034 -53.125116 90)
			(size 0.519938 1.4986)
			(layers "F.Cu" "F.Mask" "F.Paste")
			(net "M_L_CPU0_SA_DQS_DP<5>")
		)
		(pad "158" smd rect
			(at 2.050034 -52.274978 90)
			(size 0.519938 1.4986)
			(layers "F.Cu" "F.Mask" "F.Paste")
			(net "GND")
		)
		(pad "159" smd rect
			(at 2.050034 -51.425094 90)
			(size 0.519938 1.4986)
			(layers "F.Cu" "F.Mask" "F.Paste")
			(net "M_L_CPU0_SA_DQ<6>")
		)
		(pad "160" smd rect
			(at 2.050034 -50.574956 90)
			(size 0.519938 1.4986)
			(layers "F.Cu" "F.Mask" "F.Paste")
			(net "GND")
		)
		(pad "161" smd rect
			(at 2.050034 -49.725072 90)
			(size 0.519938 1.4986)
			(layers "F.Cu" "F.Mask" "F.Paste")
			(net "M_L_CPU0_SA_DQ<7>")
		)
		(pad "162" smd rect
			(at 2.050034 -48.874934 90)
			(size 0.519938 1.4986)
			(layers "F.Cu" "F.Mask" "F.Paste")
			(net "GND")
		)
		(pad "163" smd rect
			(at 2.050034 -48.02505 90)
			(size 0.519938 1.4986)
			(layers "F.Cu" "F.Mask" "F.Paste")
			(net "M_L_CPU0_SA_DQ<10>")
		)
		(pad "164" smd rect
			(at 2.050034 -47.174912 90)
			(size 0.519938 1.4986)
			(layers "F.Cu" "F.Mask" "F.Paste")
			(net "GND")
		)
		(pad "165" smd rect
			(at 2.050034 -46.325028 90)
			(size 0.519938 1.4986)
			(layers "F.Cu" "F.Mask" "F.Paste")
			(net "M_L_CPU0_SA_DQ<11>")
		)
		(pad "166" smd rect
			(at 2.050034 -45.47489 90)
			(size 0.519938 1.4986)
			(layers "F.Cu" "F.Mask" "F.Paste")
			(net "GND")
		)
		(pad "167" smd rect
			(at 2.050034 -44.625006 90)
			(size 0.519938 1.4986)
			(layers "F.Cu" "F.Mask" "F.Paste")
			(net "M_L_CPU0_SA_DQS_DN<6>")
		)
		(pad "168" smd rect
			(at 2.050034 -43.775122 90)
			(size 0.519938 1.4986)
			(layers "F.Cu" "F.Mask" "F.Paste")
			(net "M_L_CPU0_SA_DQS_DP<6>")
		)
		(pad "169" smd rect
			(at 2.050034 -42.924984 90)
			(size 0.519938 1.4986)
			(layers "F.Cu" "F.Mask" "F.Paste")
			(net "GND")
		)
		(pad "170" smd rect
			(at 2.050034 -42.0751 90)
			(size 0.519938 1.4986)
			(layers "F.Cu" "F.Mask" "F.Paste")
			(net "M_L_CPU0_SA_DQ<14>")
		)
		(pad "171" smd rect
			(at 2.050034 -41.224962 90)
			(size 0.519938 1.4986)
			(layers "F.Cu" "F.Mask" "F.Paste")
			(net "GND")
		)
		(pad "172" smd rect
			(at 2.050034 -40.375078 90)
			(size 0.519938 1.4986)
			(layers "F.Cu" "F.Mask" "F.Paste")
			(net "M_L_CPU0_SA_DQ<15>")
		)
		(pad "173" smd rect
			(at 2.050034 -39.52494 90)
			(size 0.519938 1.4986)
			(layers "F.Cu" "F.Mask" "F.Paste")
			(net "GND")
		)
		(pad "174" smd rect
			(at 2.050034 -38.675056 90)
			(size 0.519938 1.4986)
			(layers "F.Cu" "F.Mask" "F.Paste")
			(net "M_L_CPU0_SA_DQ<18>")
		)
		(pad "175" smd rect
			(at 2.050034 -37.824918 90)
			(size 0.519938 1.4986)
			(layers "F.Cu" "F.Mask" "F.Paste")
			(net "GND")
		)
		(pad "176" smd rect
			(at 2.050034 -36.975034 90)
			(size 0.519938 1.4986)
			(layers "F.Cu" "F.Mask" "F.Paste")
			(net "M_L_CPU0_SA_DQ<19>")
		)
		(pad "177" smd rect
			(at 2.050034 -36.124896 90)
			(size 0.519938 1.4986)
			(layers "F.Cu" "F.Mask" "F.Paste")
			(net "GND")
		)
		(pad "178" smd rect
			(at 2.050034 -35.275012 90)
			(size 0.519938 1.4986)
			(layers "F.Cu" "F.Mask" "F.Paste")
			(net "M_L_CPU0_SA_DQS_DN<7>")
		)
		(pad "179" smd rect
			(at 2.050034 -34.425128 90)
			(size 0.519938 1.4986)
			(layers "F.Cu" "F.Mask" "F.Paste")
			(net "M_L_CPU0_SA_DQS_DP<7>")
		)
		(pad "180" smd rect
			(at 2.050034 -33.57499 90)
			(size 0.519938 1.4986)
			(layers "F.Cu" "F.Mask" "F.Paste")
			(net "GND")
		)
		(pad "181" smd rect
			(at 2.050034 -32.725106 90)
			(size 0.519938 1.4986)
			(layers "F.Cu" "F.Mask" "F.Paste")
			(net "M_L_CPU0_SA_DQ<22>")
		)
		(pad "182" smd rect
			(at 2.050034 -31.874968 90)
			(size 0.519938 1.4986)
			(layers "F.Cu" "F.Mask" "F.Paste")
			(net "GND")
		)
		(pad "183" smd rect
			(at 2.050034 -31.025084 90)
			(size 0.519938 1.4986)
			(layers "F.Cu" "F.Mask" "F.Paste")
			(net "M_L_CPU0_SA_DQ<23>")
		)
		(pad "184" smd rect
			(at 2.050034 -30.174946 90)
			(size 0.519938 1.4986)
			(layers "F.Cu" "F.Mask" "F.Paste")
			(net "GND")
		)
		(pad "185" smd rect
			(at 2.050034 -29.325062 90)
			(size 0.519938 1.4986)
			(layers "F.Cu" "F.Mask" "F.Paste")
			(net "M_L_CPU0_SA_DQ<26>")
		)
		(pad "186" smd rect
			(at 2.050034 -28.474924 90)
			(size 0.519938 1.4986)
			(layers "F.Cu" "F.Mask" "F.Paste")
			(net "GND")
		)
		(pad "187" smd rect
			(at 2.050034 -27.62504 90)
			(size 0.519938 1.4986)
			(layers "F.Cu" "F.Mask" "F.Paste")
			(net "M_L_CPU0_SA_DQ<27>")
		)
		(pad "188" smd rect
			(at 2.050034 -26.774902 90)
			(size 0.519938 1.4986)
			(layers "F.Cu" "F.Mask" "F.Paste")
			(net "GND")
		)
		(pad "189" smd rect
			(at 2.050034 -25.925018 90)
			(size 0.519938 1.4986)
			(layers "F.Cu" "F.Mask" "F.Paste")
			(net "M_L_CPU0_SA_DQS_DN<8>")
		)
		(pad "190" smd rect
			(at 2.050034 -25.07488 90)
			(size 0.519938 1.4986)
			(layers "F.Cu" "F.Mask" "F.Paste")
			(net "M_L_CPU0_SA_DQS_DP<8>")
		)
		(pad "191" smd rect
			(at 2.050034 -24.224996 90)
			(size 0.519938 1.4986)
			(layers "F.Cu" "F.Mask" "F.Paste")
			(net "GND")
		)
		(pad "192" smd rect
			(at 2.050034 -23.375112 90)
			(size 0.519938 1.4986)
			(layers "F.Cu" "F.Mask" "F.Paste")
			(net "M_L_CPU0_SA_DQ<30>")
		)
		(pad "193" smd rect
			(at 2.050034 -22.524974 90)
			(size 0.519938 1.4986)
			(layers "F.Cu" "F.Mask" "F.Paste")
			(net "GND")
		)
		(pad "194" smd rect
			(at 2.050034 -21.67509 90)
			(size 0.519938 1.4986)
			(layers "F.Cu" "F.Mask" "F.Paste")
			(net "M_L_CPU0_SA_DQ<31>")
		)
		(pad "195" smd rect
			(at 2.050034 -20.824952 90)
			(size 0.519938 1.4986)
			(layers "F.Cu" "F.Mask" "F.Paste")
			(net "GND")
		)
		(pad "196" smd rect
			(at 2.050034 -19.975068 90)
			(size 0.519938 1.4986)
			(layers "F.Cu" "F.Mask" "F.Paste")
			(net "M_L_CPU0_SA_CB<2>")
		)
		(pad "197" smd rect
			(at 2.050034 -19.12493 90)
			(size 0.519938 1.4986)
			(layers "F.Cu" "F.Mask" "F.Paste")
			(net "GND")
		)
		(pad "198" smd rect
			(at 2.050034 -18.275046 90)
			(size 0.519938 1.4986)
			(layers "F.Cu" "F.Mask" "F.Paste")
			(net "M_L_CPU0_SA_CB<3>")
		)
		(pad "199" smd rect
			(at 2.050034 -17.424908 90)
			(size 0.519938 1.4986)
			(layers "F.Cu" "F.Mask" "F.Paste")
			(net "GND")
		)
		(pad "200" smd rect
			(at 2.050034 -16.575024 90)
			(size 0.519938 1.4986)
			(layers "F.Cu" "F.Mask" "F.Paste")
			(net "M_L_CPU0_SA_DQS_DN<9>")
		)
		(pad "201" smd rect
			(at 2.050034 -15.724886 90)
			(size 0.519938 1.4986)
			(layers "F.Cu" "F.Mask" "F.Paste")
			(net "M_L_CPU0_SA_DQS_DP<9>")
		)
		(pad "202" smd rect
			(at 2.050034 -14.875002 90)
			(size 0.519938 1.4986)
			(layers "F.Cu" "F.Mask" "F.Paste")
			(net "GND")
		)
		(pad "203" smd rect
			(at 2.050034 -14.025118 90)
			(size 0.519938 1.4986)
			(layers "F.Cu" "F.Mask" "F.Paste")
			(net "M_L_CPU0_SA_CB<6>")
		)
		(pad "204" smd rect
			(at 2.050034 -13.17498 90)
			(size 0.519938 1.4986)
			(layers "F.Cu" "F.Mask" "F.Paste")
			(net "GND")
		)
		(pad "205" smd rect
			(at 2.050034 -12.325096 90)
			(size 0.519938 1.4986)
			(layers "F.Cu" "F.Mask" "F.Paste")
			(net "M_L_CPU0_SA_CB<7>")
		)
		(pad "206" smd rect
			(at 2.050034 -11.474958 90)
			(size 0.519938 1.4986)
			(layers "F.Cu" "F.Mask" "F.Paste")
			(net "GND")
		)
		(pad "207" smd rect
			(at 2.050034 -10.625074 90)
			(size 0.519938 1.4986)
			(layers "F.Cu" "F.Mask" "F.Paste")
			(net "M_L_CPU0_RESET_N")
		)
		(pad "208" smd rect
			(at 2.050034 -9.774936 90)
			(size 0.519938 1.4986)
			(layers "F.Cu" "F.Mask" "F.Paste")
			(net "GND")
		)
		(pad "209" smd rect
			(at 2.050034 -8.925052 90)
			(size 0.519938 1.4986)
			(layers "F.Cu" "F.Mask" "F.Paste")
			(net "M_L_CPU0_SA_CS_N<1>")
		)
		(pad "210" smd rect
			(at 2.050034 -8.074914 90)
			(size 0.519938 1.4986)
			(layers "F.Cu" "F.Mask" "F.Paste")
			(net "GND")
		)
		(pad "211" smd rect
			(at 2.050034 -7.22503 90)
			(size 0.519938 1.4986)
			(layers "F.Cu" "F.Mask" "F.Paste")
			(net "M_L_CPU0_SA_CA<1>")
		)
		(pad "212" smd rect
			(at 2.050034 -6.374892 90)
			(size 0.519938 1.4986)
			(layers "F.Cu" "F.Mask" "F.Paste")
			(net "GND")
		)
		(pad "213" smd rect
			(at 2.050034 -5.525008 90)
			(size 0.519938 1.4986)
			(layers "F.Cu" "F.Mask" "F.Paste")
			(net "M_L_CPU0_SA_CA<3>")
		)
		(pad "214" smd rect
			(at 2.050034 -4.675124 90)
			(size 0.519938 1.4986)
			(layers "F.Cu" "F.Mask" "F.Paste")
			(net "GND")
		)
		(pad "215" smd rect
			(at 2.050034 -3.824986 90)
			(size 0.519938 1.4986)
			(layers "F.Cu" "F.Mask" "F.Paste")
			(net "M_L_CPU0_SA_CA<5>")
		)
		(pad "216" smd rect
			(at 2.050034 -2.975102 90)
			(size 0.519938 1.4986)
			(layers "F.Cu" "F.Mask" "F.Paste")
			(net "GND")
		)
		(pad "217" smd rect
			(at 2.050034 -2.124964 90)
			(size 0.519938 1.4986)
			(layers "F.Cu" "F.Mask" "F.Paste")
			(net "M_L_CPU0_CLK_DP<0>")
		)
		(pad "218" smd rect
			(at 2.050034 -1.27508 90)
			(size 0.519938 1.4986)
			(layers "F.Cu" "F.Mask" "F.Paste")
			(net "M_L_CPU0_CLK_DN<0>")
		)
		(pad "219" smd rect
			(at 2.050034 -0.424942 90)
			(size 0.519938 1.4986)
			(layers "F.Cu" "F.Mask" "F.Paste")
			(net "GND")
		)
		(pad "220" smd rect
			(at 2.050034 5.525008 90)
			(size 0.519938 1.4986)
			(layers "F.Cu" "F.Mask" "F.Paste")
			(net "Net_2407")
		)
		(pad "221" smd rect
			(at 2.050034 6.374892 90)
			(size 0.519938 1.4986)
			(layers "F.Cu" "F.Mask" "F.Paste")
			(net "M_L_CPU0_SB_CA<1>")
		)
		(pad "222" smd rect
			(at 2.050034 7.22503 90)
			(size 0.519938 1.4986)
			(layers "F.Cu" "F.Mask" "F.Paste")
			(net "GND")
		)
		(pad "223" smd rect
			(at 2.050034 8.074914 90)
			(size 0.519938 1.4986)
			(layers "F.Cu" "F.Mask" "F.Paste")
			(net "M_L_CPU0_SB_CA<3>")
		)
		(pad "224" smd rect
			(at 2.050034 8.925052 90)
			(size 0.519938 1.4986)
			(layers "F.Cu" "F.Mask" "F.Paste")
			(net "GND")
		)
		(pad "225" smd rect
			(at 2.050034 9.774936 90)
			(size 0.519938 1.4986)
			(layers "F.Cu" "F.Mask" "F.Paste")
			(net "M_L_CPU0_SB_CA<5>")
		)
		(pad "226" smd rect
			(at 2.050034 10.625074 90)
			(size 0.519938 1.4986)
			(layers "F.Cu" "F.Mask" "F.Paste")
			(net "GND")
		)
		(pad "227" smd rect
			(at 2.050034 11.474958 90)
			(size 0.519938 1.4986)
			(layers "F.Cu" "F.Mask" "F.Paste")
			(net "M_L_CPU0_SB_PAR")
		)
		(pad "228" smd rect
			(at 2.050034 12.325096 90)
			(size 0.519938 1.4986)
			(layers "F.Cu" "F.Mask" "F.Paste")
			(net "GND")
		)
		(pad "229" smd rect
			(at 2.050034 13.17498 90)
			(size 0.519938 1.4986)
			(layers "F.Cu" "F.Mask" "F.Paste")
			(net "M_L_CPU0_SB_CS_N<1>")
		)
		(pad "230" smd rect
			(at 2.050034 14.025118 90)
			(size 0.519938 1.4986)
			(layers "F.Cu" "F.Mask" "F.Paste")
			(net "GND")
		)
		(pad "231" smd rect
			(at 2.050034 14.875002 90)
			(size 0.519938 1.4986)
			(layers "F.Cu" "F.Mask" "F.Paste")
			(net "Net_2408")
		)
		(pad "232" smd rect
			(at 2.050034 15.724886 90)
			(size 0.519938 1.4986)
			(layers "F.Cu" "F.Mask" "F.Paste")
			(net "Net_2409")
		)
		(pad "233" smd rect
			(at 2.050034 16.575024 90)
			(size 0.519938 1.4986)
			(layers "F.Cu" "F.Mask" "F.Paste")
			(net "GND")
		)
		(pad "234" smd rect
			(at 2.050034 17.424908 90)
			(size 0.519938 1.4986)
			(layers "F.Cu" "F.Mask" "F.Paste")
			(net "M_L_CPU0_SB_CB<6>")
		)
		(pad "235" smd rect
			(at 2.050034 18.275046 90)
			(size 0.519938 1.4986)
			(layers "F.Cu" "F.Mask" "F.Paste")
			(net "GND")
		)
		(pad "236" smd rect
			(at 2.050034 19.12493 90)
			(size 0.519938 1.4986)
			(layers "F.Cu" "F.Mask" "F.Paste")
			(net "M_L_CPU0_SB_CB<7>")
		)
		(pad "237" smd rect
			(at 2.050034 19.975068 90)
			(size 0.519938 1.4986)
			(layers "F.Cu" "F.Mask" "F.Paste")
			(net "GND")
		)
		(pad "238" smd rect
			(at 2.050034 20.824952 90)
			(size 0.519938 1.4986)
			(layers "F.Cu" "F.Mask" "F.Paste")
			(net "M_L_CPU0_SB_DQS_DN<4>")
		)
		(pad "239" smd rect
			(at 2.050034 21.67509 90)
			(size 0.519938 1.4986)
			(layers "F.Cu" "F.Mask" "F.Paste")
			(net "M_L_CPU0_SB_DQS_DP<4>")
		)
		(pad "240" smd rect
			(at 2.050034 22.524974 90)
			(size 0.519938 1.4986)
			(layers "F.Cu" "F.Mask" "F.Paste")
			(net "GND")
		)
		(pad "241" smd rect
			(at 2.050034 23.375112 90)
			(size 0.519938 1.4986)
			(layers "F.Cu" "F.Mask" "F.Paste")
			(net "M_L_CPU0_SB_CB<2>")
		)
		(pad "242" smd rect
			(at 2.050034 24.224996 90)
			(size 0.519938 1.4986)
			(layers "F.Cu" "F.Mask" "F.Paste")
			(net "GND")
		)
		(pad "243" smd rect
			(at 2.050034 25.07488 90)
			(size 0.519938 1.4986)
			(layers "F.Cu" "F.Mask" "F.Paste")
			(net "M_L_CPU0_SB_CB<3>")
		)
		(pad "244" smd rect
			(at 2.050034 25.925018 90)
			(size 0.519938 1.4986)
			(layers "F.Cu" "F.Mask" "F.Paste")
			(net "GND")
		)
		(pad "245" smd rect
			(at 2.050034 26.774902 90)
			(size 0.519938 1.4986)
			(layers "F.Cu" "F.Mask" "F.Paste")
			(net "M_L_CPU0_SB_DQ<2>")
		)
		(pad "246" smd rect
			(at 2.050034 27.62504 90)
			(size 0.519938 1.4986)
			(layers "F.Cu" "F.Mask" "F.Paste")
			(net "GND")
		)
		(pad "247" smd rect
			(at 2.050034 28.474924 90)
			(size 0.519938 1.4986)
			(layers "F.Cu" "F.Mask" "F.Paste")
			(net "M_L_CPU0_SB_DQ<3>")
		)
		(pad "248" smd rect
			(at 2.050034 29.325062 90)
			(size 0.519938 1.4986)
			(layers "F.Cu" "F.Mask" "F.Paste")
			(net "GND")
		)
		(pad "249" smd rect
			(at 2.050034 30.174946 90)
			(size 0.519938 1.4986)
			(layers "F.Cu" "F.Mask" "F.Paste")
			(net "M_L_CPU0_SB_DQS_DN<5>")
		)
		(pad "250" smd rect
			(at 2.050034 31.025084 90)
			(size 0.519938 1.4986)
			(layers "F.Cu" "F.Mask" "F.Paste")
			(net "M_L_CPU0_SB_DQS_DP<5>")
		)
		(pad "251" smd rect
			(at 2.050034 31.874968 90)
			(size 0.519938 1.4986)
			(layers "F.Cu" "F.Mask" "F.Paste")
			(net "GND")
		)
		(pad "252" smd rect
			(at 2.050034 32.725106 90)
			(size 0.519938 1.4986)
			(layers "F.Cu" "F.Mask" "F.Paste")
			(net "M_L_CPU0_SB_DQ<6>")
		)
		(pad "253" smd rect
			(at 2.050034 33.57499 90)
			(size 0.519938 1.4986)
			(layers "F.Cu" "F.Mask" "F.Paste")
			(net "GND")
		)
		(pad "254" smd rect
			(at 2.050034 34.425128 90)
			(size 0.519938 1.4986)
			(layers "F.Cu" "F.Mask" "F.Paste")
			(net "M_L_CPU0_SB_DQ<7>")
		)
		(pad "255" smd rect
			(at 2.050034 35.275012 90)
			(size 0.519938 1.4986)
			(layers "F.Cu" "F.Mask" "F.Paste")
			(net "GND")
		)
		(pad "256" smd rect
			(at 2.050034 36.124896 90)
			(size 0.519938 1.4986)
			(layers "F.Cu" "F.Mask" "F.Paste")
			(net "M_L_CPU0_SB_DQ<10>")
		)
		(pad "257" smd rect
			(at 2.050034 36.975034 90)
			(size 0.519938 1.4986)
			(layers "F.Cu" "F.Mask" "F.Paste")
			(net "GND")
		)
		(pad "258" smd rect
			(at 2.050034 37.824918 90)
			(size 0.519938 1.4986)
			(layers "F.Cu" "F.Mask" "F.Paste")
			(net "M_L_CPU0_SB_DQ<11>")
		)
		(pad "259" smd rect
			(at 2.050034 38.675056 90)
			(size 0.519938 1.4986)
			(layers "F.Cu" "F.Mask" "F.Paste")
			(net "GND")
		)
		(pad "260" smd rect
			(at 2.050034 39.52494 90)
			(size 0.519938 1.4986)
			(layers "F.Cu" "F.Mask" "F.Paste")
			(net "M_L_CPU0_SB_DQS_DN<6>")
		)
		(pad "261" smd rect
			(at 2.050034 40.375078 90)
			(size 0.519938 1.4986)
			(layers "F.Cu" "F.Mask" "F.Paste")
			(net "M_L_CPU0_SB_DQS_DP<6>")
		)
		(pad "262" smd rect
			(at 2.050034 41.224962 90)
			(size 0.519938 1.4986)
			(layers "F.Cu" "F.Mask" "F.Paste")
			(net "GND")
		)
		(pad "263" smd rect
			(at 2.050034 42.0751 90)
			(size 0.519938 1.4986)
			(layers "F.Cu" "F.Mask" "F.Paste")
			(net "M_L_CPU0_SB_DQ<14>")
		)
		(pad "264" smd rect
			(at 2.050034 42.924984 90)
			(size 0.519938 1.4986)
			(layers "F.Cu" "F.Mask" "F.Paste")
			(net "GND")
		)
		(pad "265" smd rect
			(at 2.050034 43.775122 90)
			(size 0.519938 1.4986)
			(layers "F.Cu" "F.Mask" "F.Paste")
			(net "M_L_CPU0_SB_DQ<15>")
		)
		(pad "266" smd rect
			(at 2.050034 44.625006 90)
			(size 0.519938 1.4986)
			(layers "F.Cu" "F.Mask" "F.Paste")
			(net "GND")
		)
		(pad "267" smd rect
			(at 2.050034 45.47489 90)
			(size 0.519938 1.4986)
			(layers "F.Cu" "F.Mask" "F.Paste")
			(net "M_L_CPU0_SB_DQ<18>")
		)
		(pad "268" smd rect
			(at 2.050034 46.325028 90)
			(size 0.519938 1.4986)
			(layers "F.Cu" "F.Mask" "F.Paste")
			(net "GND")
		)
		(pad "269" smd rect
			(at 2.050034 47.174912 90)
			(size 0.519938 1.4986)
			(layers "F.Cu" "F.Mask" "F.Paste")
			(net "M_L_CPU0_SB_DQ<19>")
		)
		(pad "270" smd rect
			(at 2.050034 48.02505 90)
			(size 0.519938 1.4986)
			(layers "F.Cu" "F.Mask" "F.Paste")
			(net "GND")
		)
		(pad "271" smd rect
			(at 2.050034 48.874934 90)
			(size 0.519938 1.4986)
			(layers "F.Cu" "F.Mask" "F.Paste")
			(net "M_L_CPU0_SB_DQS_DN<7>")
		)
		(pad "272" smd rect
			(at 2.050034 49.725072 90)
			(size 0.519938 1.4986)
			(layers "F.Cu" "F.Mask" "F.Paste")
			(net "M_L_CPU0_SB_DQS_DP<7>")
		)
		(pad "273" smd rect
			(at 2.050034 50.574956 90)
			(size 0.519938 1.4986)
			(layers "F.Cu" "F.Mask" "F.Paste")
			(net "GND")
		)
		(pad "274" smd rect
			(at 2.050034 51.425094 90)
			(size 0.519938 1.4986)
			(layers "F.Cu" "F.Mask" "F.Paste")
			(net "M_L_CPU0_SB_DQ<22>")
		)
		(pad "275" smd rect
			(at 2.050034 52.274978 90)
			(size 0.519938 1.4986)
			(layers "F.Cu" "F.Mask" "F.Paste")
			(net "GND")
		)
		(pad "276" smd rect
			(at 2.050034 53.125116 90)
			(size 0.519938 1.4986)
			(layers "F.Cu" "F.Mask" "F.Paste")
			(net "M_L_CPU0_SB_DQ<23>")
		)
		(pad "277" smd rect
			(at 2.050034 53.975 90)
			(size 0.519938 1.4986)
			(layers "F.Cu" "F.Mask" "F.Paste")
			(net "GND")
		)
		(pad "278" smd rect
			(at 2.050034 54.824884 90)
			(size 0.519938 1.4986)
			(layers "F.Cu" "F.Mask" "F.Paste")
			(net "M_L_CPU0_SB_DQ<26>")
		)
		(pad "279" smd rect
			(at 2.050034 55.675022 90)
			(size 0.519938 1.4986)
			(layers "F.Cu" "F.Mask" "F.Paste")
			(net "GND")
		)
		(pad "280" smd rect
			(at 2.050034 56.524906 90)
			(size 0.519938 1.4986)
			(layers "F.Cu" "F.Mask" "F.Paste")
			(net "M_L_CPU0_SB_DQ<27>")
		)
		(pad "281" smd rect
			(at 2.050034 57.375044 90)
			(size 0.519938 1.4986)
			(layers "F.Cu" "F.Mask" "F.Paste")
			(net "GND")
		)
		(pad "282" smd rect
			(at 2.050034 58.224928 90)
			(size 0.519938 1.4986)
			(layers "F.Cu" "F.Mask" "F.Paste")
			(net "M_L_CPU0_SB_DQS_DN<8>")
		)
		(pad "283" smd rect
			(at 2.050034 59.075066 90)
			(size 0.519938 1.4986)
			(layers "F.Cu" "F.Mask" "F.Paste")
			(net "M_L_CPU0_SB_DQS_DP<8>")
		)
		(pad "284" smd rect
			(at 2.050034 59.92495 90)
			(size 0.519938 1.4986)
			(layers "F.Cu" "F.Mask" "F.Paste")
			(net "GND")
		)
		(pad "285" smd rect
			(at 2.050034 60.775088 90)
			(size 0.519938 1.4986)
			(layers "F.Cu" "F.Mask" "F.Paste")
			(net "M_L_CPU0_SB_DQ<30>")
		)
		(pad "286" smd rect
			(at 2.050034 61.624972 90)
			(size 0.519938 1.4986)
			(layers "F.Cu" "F.Mask" "F.Paste")
			(net "GND")
		)
		(pad "287" smd rect
			(at 2.050034 62.47511 90)
			(size 0.519938 1.4986)
			(layers "F.Cu" "F.Mask" "F.Paste")
			(net "M_L_CPU0_SB_DQ<31>")
		)
		(pad "288" smd rect
			(at 2.050034 63.324994 90)
			(size 0.519938 1.4986)
			(layers "F.Cu" "F.Mask" "F.Paste")
			(net "GND")
		)
		(pad "G1" thru_hole oval
			(at 0 -68.97497 90)
			(size 1.7272 3.4798)
			(drill oval 1.2192 2.4638)
			(layers "*.Cu" "*.Mask")
			(remove_unused_layers no)
			(net "GND")
			(clearance 0.127)
			(thermal_gap 0.127)
		)
		(pad "G2" thru_hole oval
			(at 0 3.875024 90)
			(size 1.7272 3.4798)
			(drill oval 1.2192 2.4638)
			(layers "*.Cu" "*.Mask")
			(remove_unused_layers no)
			(net "GND")
			(clearance 0.127)
			(thermal_gap 0.127)
		)
		(pad "G3" thru_hole oval
			(at 0 68.97497 90)
			(size 1.7272 3.4798)
			(drill oval 1.2192 2.4638)
			(layers "*.Cu" "*.Mask")
			(remove_unused_layers no)
			(net "GND")
			(clearance 0.127)
			(thermal_gap 0.127)
		)
	)
	(footprint ""
		(layer "F.Cu")
		(at 265.395964 -385.27736 90)
		(property "Reference" "PPQ7"
			(at -7.603236 -2.160524 0)
			(unlocked yes)
			(layer "F.SilkS")
			(effects
				(font
					(size 0.7874 0.5842)
					(thickness 0.1524)
				)
				(justify left)
			)
		)
		(property "Value" ""
			(at 0 0 90)
			(layer "F.Fab")
			(effects
				(font
					(size 1.27 1.27)
				)
			)
		)
		(duplicate_pad_numbers_are_jumpers no)
		(fp_line
			(start 2.350008 -2.649982)
			(end 2.350008 -2.4892)
			(stroke
				(width 0.1524)
				(type default)
			)
			(layer "F.SilkS")
		)
		(fp_line
			(start -2.350008 -2.649982)
			(end 2.350008 -2.649982)
			(stroke
				(width 0.1524)
				(type default)
			)
			(layer "F.SilkS")
		)
		(fp_line
			(start -2.350008 -2.4384)
			(end -2.350008 -2.649982)
			(stroke
				(width 0.1524)
				(type default)
			)
			(layer "F.SilkS")
		)
		(fp_line
			(start 2.350008 2.4892)
			(end 2.350008 2.649982)
			(stroke
				(width 0.1524)
				(type default)
			)
			(layer "F.SilkS")
		)
		(fp_line
			(start 2.350008 2.649982)
			(end -2.350008 2.649982)
			(stroke
				(width 0.1524)
				(type default)
			)
			(layer "F.SilkS")
		)
		(fp_line
			(start -2.350008 2.649982)
			(end -2.350008 2.413)
			(stroke
				(width 0.1524)
				(type default)
			)
			(layer "F.SilkS")
		)
		(fp_poly
			(pts
				(xy -3.447796 -3.466338) (xy -2.648712 -3.428238) (xy -3.116834 -2.40792)
			)
			(stroke
				(width 0)
				(type default)
			)
			(fill yes)
			(layer "F.SilkS")
		)
		(fp_line
			(start 2.350008 -2.649982)
			(end 2.350008 2.649982)
			(stroke
				(width 0.1)
				(type default)
			)
			(layer "F.Fab")
		)
		(fp_line
			(start -2.350008 -2.649982)
			(end 2.350008 -2.649982)
			(stroke
				(width 0.1)
				(type default)
			)
			(layer "F.Fab")
		)
		(fp_line
			(start 2.350008 2.649982)
			(end -2.350008 2.649982)
			(stroke
				(width 0.1)
				(type default)
			)
			(layer "F.Fab")
		)
		(fp_line
			(start -2.350008 2.649982)
			(end -2.350008 -2.649982)
			(stroke
				(width 0.1)
				(type default)
			)
			(layer "F.Fab")
		)
		(fp_poly
			(pts
				(xy -3.717544 -1.905) (xy -4.758944 -2.3241) (xy -4.758944 -1.524)
			)
			(stroke
				(width 0)
				(type default)
			)
			(fill yes)
			(layer "F.Fab")
		)
		(pad "1" smd rect
			(at -2.999994 -1.905)
			(size 0.7112 1.1684)
			(layers "F.Cu" "F.Mask" "F.Paste")
			(net "P12V_AUX")
		)
		(pad "2" smd rect
			(at -2.999994 -0.635)
			(size 0.7112 1.1684)
			(layers "F.Cu" "F.Mask" "F.Paste")
			(net "P12V_AUX")
		)
		(pad "3" smd rect
			(at -2.999994 0.635)
			(size 0.7112 1.1684)
			(layers "F.Cu" "F.Mask" "F.Paste")
			(net "P12V_AUX")
		)
		(pad "4" smd rect
			(at -2.999994 1.905)
			(size 0.7112 1.1684)
			(layers "F.Cu" "F.Mask" "F.Paste")
			(net "P12V_HSC_GATE_G3")
		)
		(pad "5" smd circle
			(at 0.925068 0)
			(size 0 0)
			(layers "F.Cu" "F.Mask" "F.Paste")
			(net "P12V_MAIN_R")
		)
		(zone
			(layer "F.Cu")
			(hatch none 0.5)
			(connect_pads
				(clearance 0)
			)
			(min_thickness 0.25)
			(keepout
				(tracks not_allowed)
				(vias allowed)
				(pads allowed)
				(copperpour not_allowed)
				(footprints allowed)
			)
			(placement
				(enabled no)
				(sheetname "")
			)
			(fill
				(thermal_gap 0.5)
				(thermal_bridge_width 0.5)
				(island_removal_mode 0)
			)
			(polygon
				(pts
					(xy 262.754364 -383.7178) (xy 268.037564 -383.7178) (xy 268.037564 -382.92786) (xy 262.754364 -382.92786)
				)
			)
		)
	)
	(footprint ""
		(layer "F.Cu")
		(at 112.267238 -41.17975 90)
		(property "Reference" "R6288"
			(at 0 0 90)
			(layer "F.SilkS")
			(hide yes)
			(effects
				(font
					(size 1.27 1.27)
				)
			)
		)
		(property "Value" ""
			(at 0 0 90)
			(layer "F.Fab")
			(effects
				(font
					(size 1.27 1.27)
				)
			)
		)
		(duplicate_pad_numbers_are_jumpers no)
		(fp_line
			(start 0.7874 -0.4064)
			(end 0.7874 0.4064)
			(stroke
				(width 0.1524)
				(type default)
			)
			(layer "F.SilkS")
		)
		(fp_line
			(start -0.7874 -0.4064)
			(end 0.7874 -0.4064)
			(stroke
				(width 0.1524)
				(type default)
			)
			(layer "F.SilkS")
		)
		(fp_line
			(start 0.7874 0.4064)
			(end -0.7874 0.4064)
			(stroke
				(width 0.1524)
				(type default)
			)
			(layer "F.SilkS")
		)
		(fp_line
			(start -0.7874 0.4064)
			(end -0.7874 -0.4064)
			(stroke
				(width 0.1524)
				(type default)
			)
			(layer "F.SilkS")
		)
		(fp_line
			(start -0.12065 -0.305054)
			(end -0.12065 -0.2794)
			(stroke
				(width 0.1)
				(type default)
			)
			(layer "F.Fab")
		)
		(fp_line
			(start -0.67945 -0.305054)
			(end -0.12065 -0.305054)
			(stroke
				(width 0.1)
				(type default)
			)
			(layer "F.Fab")
		)
		(fp_line
			(start 0.67945 -0.3048)
			(end 0.67945 0.3048)
			(stroke
				(width 0.1)
				(type default)
			)
			(layer "F.Fab")
		)
		(fp_line
			(start 0.12065 -0.3048)
			(end 0.67945 -0.3048)
			(stroke
				(width 0.1)
				(type default)
			)
			(layer "F.Fab")
		)
		(fp_line
			(start 0.12065 -0.2794)
			(end 0.12065 -0.3048)
			(stroke
				(width 0.1)
				(type default)
			)
			(layer "F.Fab")
		)
		(fp_line
			(start -0.12065 -0.2794)
			(end 0.12065 -0.2794)
			(stroke
				(width 0.1)
				(type default)
			)
			(layer "F.Fab")
		)
		(fp_line
			(start 0.120396 0.2794)
			(end -0.12065 0.2794)
			(stroke
				(width 0.1)
				(type default)
			)
			(layer "F.Fab")
		)
		(fp_line
			(start -0.12065 0.2794)
			(end -0.12065 0.3048)
			(stroke
				(width 0.1)
				(type default)
			)
			(layer "F.Fab")
		)
		(fp_line
			(start 0.67945 0.3048)
			(end 0.120396 0.3048)
			(stroke
				(width 0.1)
				(type default)
			)
			(layer "F.Fab")
		)
		(fp_line
			(start 0.120396 0.3048)
			(end 0.120396 0.2794)
			(stroke
				(width 0.1)
				(type default)
			)
			(layer "F.Fab")
		)
		(fp_line
			(start -0.12065 0.3048)
			(end -0.67945 0.3048)
			(stroke
				(width 0.1)
				(type default)
			)
			(layer "F.Fab")
		)
		(fp_line
			(start -0.67945 0.3048)
			(end -0.67945 -0.305054)
			(stroke
				(width 0.1)
				(type default)
			)
			(layer "F.Fab")
		)
		(pad "1" smd circle
			(at -0.40005 0 90)
			(size 0 0)
			(layers "F.Cu" "F.Mask" "F.Paste")
			(net "USB_HUB2_TI_PWRCTL_POL")
		)
		(pad "2" smd circle
			(at 0.40005 0 90)
			(size 0 0)
			(layers "F.Cu" "F.Mask" "F.Paste")
			(net "GND")
		)
	)
	(footprint ""
		(layer "F.Cu")
		(at 16.110966 -92.687648 90)
		(property "Reference" "R3658"
			(at 0 0 90)
			(layer "F.SilkS")
			(hide yes)
			(effects
				(font
					(size 1.27 1.27)
				)
			)
		)
		(property "Value" ""
			(at 0 0 90)
			(layer "F.Fab")
			(effects
				(font
					(size 1.27 1.27)
				)
			)
		)
		(duplicate_pad_numbers_are_jumpers no)
		(fp_line
			(start 0.7874 -0.4064)
			(end 0.7874 0.4064)
			(stroke
				(width 0.1524)
				(type default)
			)
			(layer "F.SilkS")
		)
		(fp_line
			(start -0.7874 -0.4064)
			(end 0.7874 -0.4064)
			(stroke
				(width 0.1524)
				(type default)
			)
			(layer "F.SilkS")
		)
		(fp_line
			(start 0.7874 0.4064)
			(end -0.7874 0.4064)
			(stroke
				(width 0.1524)
				(type default)
			)
			(layer "F.SilkS")
		)
		(fp_line
			(start -0.7874 0.4064)
			(end -0.7874 -0.4064)
			(stroke
				(width 0.1524)
				(type default)
			)
			(layer "F.SilkS")
		)
		(fp_line
			(start -0.12065 -0.305054)
			(end -0.12065 -0.2794)
			(stroke
				(width 0.1)
				(type default)
			)
			(layer "F.Fab")
		)
		(fp_line
			(start -0.67945 -0.305054)
			(end -0.12065 -0.305054)
			(stroke
				(width 0.1)
				(type default)
			)
			(layer "F.Fab")
		)
		(fp_line
			(start 0.67945 -0.3048)
			(end 0.67945 0.3048)
			(stroke
				(width 0.1)
				(type default)
			)
			(layer "F.Fab")
		)
		(fp_line
			(start 0.12065 -0.3048)
			(end 0.67945 -0.3048)
			(stroke
				(width 0.1)
				(type default)
			)
			(layer "F.Fab")
		)
		(fp_line
			(start 0.12065 -0.2794)
			(end 0.12065 -0.3048)
			(stroke
				(width 0.1)
				(type default)
			)
			(layer "F.Fab")
		)
		(fp_line
			(start -0.12065 -0.2794)
			(end 0.12065 -0.2794)
			(stroke
				(width 0.1)
				(type default)
			)
			(layer "F.Fab")
		)
		(fp_line
			(start 0.120396 0.2794)
			(end -0.12065 0.2794)
			(stroke
				(width 0.1)
				(type default)
			)
			(layer "F.Fab")
		)
		(fp_line
			(start -0.12065 0.2794)
			(end -0.12065 0.3048)
			(stroke
				(width 0.1)
				(type default)
			)
			(layer "F.Fab")
		)
		(fp_line
			(start 0.67945 0.3048)
			(end 0.120396 0.3048)
			(stroke
				(width 0.1)
				(type default)
			)
			(layer "F.Fab")
		)
		(fp_line
			(start 0.120396 0.3048)
			(end 0.120396 0.2794)
			(stroke
				(width 0.1)
				(type default)
			)
			(layer "F.Fab")
		)
		(fp_line
			(start -0.12065 0.3048)
			(end -0.67945 0.3048)
			(stroke
				(width 0.1)
				(type default)
			)
			(layer "F.Fab")
		)
		(fp_line
			(start -0.67945 0.3048)
			(end -0.67945 -0.305054)
			(stroke
				(width 0.1)
				(type default)
			)
			(layer "F.Fab")
		)
		(pad "1" smd circle
			(at -0.40005 0 90)
			(size 0 0)
			(layers "F.Cu" "F.Mask" "F.Paste")
			(net "P3V3_AUX")
		)
		(pad "2" smd circle
			(at 0.40005 0 90)
			(size 0 0)
			(layers "F.Cu" "F.Mask" "F.Paste")
			(net "USB_HUB_OVCUR3")
		)
	)
	(footprint ""
		(layer "F.Cu")
		(at 360.762042 -397.87576)
		(property "Reference" "R1398"
			(at 0 0 0)
			(layer "F.SilkS")
			(hide yes)
			(effects
				(font
					(size 1.27 1.27)
				)
			)
		)
		(property "Value" ""
			(at 0 0 0)
			(layer "F.Fab")
			(effects
				(font
					(size 1.27 1.27)
				)
			)
		)
		(duplicate_pad_numbers_are_jumpers no)
		(fp_line
			(start -0.32512 -0.175006)
			(end 0.32512 -0.175006)
			(stroke
				(width 0.1)
				(type default)
			)
			(layer "F.Fab")
		)
		(fp_line
			(start -0.32512 0.175006)
			(end -0.32512 -0.175006)
			(stroke
				(width 0.1)
				(type default)
			)
			(layer "F.Fab")
		)
		(fp_line
			(start 0.32512 -0.175006)
			(end 0.32512 0.175006)
			(stroke
				(width 0.1)
				(type default)
			)
			(layer "F.Fab")
		)
		(fp_line
			(start 0.32512 0.175006)
			(end -0.32512 0.175006)
			(stroke
				(width 0.1)
				(type default)
			)
			(layer "F.Fab")
		)
		(pad "1" smd rect
			(at -0.2667 0)
			(size 0.3048 0.381)
			(layers "F.Cu" "F.Mask" "F.Paste")
			(net "RXDET_BYP_RT_CPU0_P1")
		)
		(pad "2" smd rect
			(at 0.2667 0 180)
			(size 0.3048 0.381)
			(layers "F.Cu" "F.Mask" "F.Paste")
			(net "GND")
		)
	)
	(footprint ""
		(layer "F.Cu")
		(at 19.240754 -36.878514 180)
		(property "Reference" "R1328"
			(at 0 0 180)
			(layer "F.SilkS")
			(hide yes)
			(effects
				(font
					(size 1.27 1.27)
				)
			)
		)
		(property "Value" ""
			(at 0 0 180)
			(layer "F.Fab")
			(effects
				(font
					(size 1.27 1.27)
				)
			)
		)
		(duplicate_pad_numbers_are_jumpers no)
		(fp_line
			(start 0.7874 0.4064)
			(end -0.7874 0.4064)
			(stroke
				(width 0.1524)
				(type default)
			)
			(layer "F.SilkS")
		)
		(fp_line
			(start 0.7874 -0.4064)
			(end 0.7874 0.4064)
			(stroke
				(width 0.1524)
				(type default)
			)
			(layer "F.SilkS")
		)
		(fp_line
			(start -0.7874 0.4064)
			(end -0.7874 -0.4064)
			(stroke
				(width 0.1524)
				(type default)
			)
			(layer "F.SilkS")
		)
		(fp_line
			(start -0.7874 -0.4064)
			(end 0.7874 -0.4064)
			(stroke
				(width 0.1524)
				(type default)
			)
			(layer "F.SilkS")
		)
		(fp_line
			(start 0.67945 0.3048)
			(end 0.120396 0.3048)
			(stroke
				(width 0.1)
				(type default)
			)
			(layer "F.Fab")
		)
		(fp_line
			(start 0.67945 -0.3048)
			(end 0.67945 0.3048)
			(stroke
				(width 0.1)
				(type default)
			)
			(layer "F.Fab")
		)
		(fp_line
			(start 0.12065 -0.2794)
			(end 0.12065 -0.3048)
			(stroke
				(width 0.1)
				(type default)
			)
			(layer "F.Fab")
		)
		(fp_line
			(start 0.12065 -0.3048)
			(end 0.67945 -0.3048)
			(stroke
				(width 0.1)
				(type default)
			)
			(layer "F.Fab")
		)
		(fp_line
			(start 0.120396 0.3048)
			(end 0.120396 0.2794)
			(stroke
				(width 0.1)
				(type default)
			)
			(layer "F.Fab")
		)
		(fp_line
			(start 0.120396 0.2794)
			(end -0.12065 0.2794)
			(stroke
				(width 0.1)
				(type default)
			)
			(layer "F.Fab")
		)
		(fp_line
			(start -0.12065 0.3048)
			(end -0.67945 0.3048)
			(stroke
				(width 0.1)
				(type default)
			)
			(layer "F.Fab")
		)
		(fp_line
			(start -0.12065 0.2794)
			(end -0.12065 0.3048)
			(stroke
				(width 0.1)
				(type default)
			)
			(layer "F.Fab")
		)
		(fp_line
			(start -0.12065 -0.2794)
			(end 0.12065 -0.2794)
			(stroke
				(width 0.1)
				(type default)
			)
			(layer "F.Fab")
		)
		(fp_line
			(start -0.12065 -0.305054)
			(end -0.12065 -0.2794)
			(stroke
				(width 0.1)
				(type default)
			)
			(layer "F.Fab")
		)
		(fp_line
			(start -0.67945 0.3048)
			(end -0.67945 -0.305054)
			(stroke
				(width 0.1)
				(type default)
			)
			(layer "F.Fab")
		)
		(fp_line
			(start -0.67945 -0.305054)
			(end -0.12065 -0.305054)
			(stroke
				(width 0.1)
				(type default)
			)
			(layer "F.Fab")
		)
		(pad "1" smd circle
			(at -0.40005 0 180)
			(size 0 0)
			(layers "F.Cu" "F.Mask" "F.Paste")
			(net "P3V3_AUX")
		)
		(pad "2" smd circle
			(at 0.40005 0 180)
			(size 0 0)
			(layers "F.Cu" "F.Mask" "F.Paste")
			(net "OCP_V3_2_P3V3_P12V_ADC_R_ALERT")
		)
	)
	(footprint ""
		(layer "F.Cu")
		(at 148.494242 -108.699046 180)
		(property "Reference" "R333"
			(at 0 0 180)
			(layer "F.SilkS")
			(hide yes)
			(effects
				(font
					(size 1.27 1.27)
				)
			)
		)
		(property "Value" ""
			(at 0 0 180)
			(layer "F.Fab")
			(effects
				(font
					(size 1.27 1.27)
				)
			)
		)
		(duplicate_pad_numbers_are_jumpers no)
		(fp_line
			(start 0.7874 0.4064)
			(end -0.7874 0.4064)
			(stroke
				(width 0.1524)
				(type default)
			)
			(layer "F.SilkS")
		)
		(fp_line
			(start 0.7874 -0.4064)
			(end 0.7874 0.4064)
			(stroke
				(width 0.1524)
				(type default)
			)
			(layer "F.SilkS")
		)
		(fp_line
			(start -0.7874 0.4064)
			(end -0.7874 -0.4064)
			(stroke
				(width 0.1524)
				(type default)
			)
			(layer "F.SilkS")
		)
		(fp_line
			(start -0.7874 -0.4064)
			(end 0.7874 -0.4064)
			(stroke
				(width 0.1524)
				(type default)
			)
			(layer "F.SilkS")
		)
		(fp_line
			(start 0.67945 0.3048)
			(end 0.120396 0.3048)
			(stroke
				(width 0.1)
				(type default)
			)
			(layer "F.Fab")
		)
		(fp_line
			(start 0.67945 -0.3048)
			(end 0.67945 0.3048)
			(stroke
				(width 0.1)
				(type default)
			)
			(layer "F.Fab")
		)
		(fp_line
			(start 0.12065 -0.2794)
			(end 0.12065 -0.3048)
			(stroke
				(width 0.1)
				(type default)
			)
			(layer "F.Fab")
		)
		(fp_line
			(start 0.12065 -0.3048)
			(end 0.67945 -0.3048)
			(stroke
				(width 0.1)
				(type default)
			)
			(layer "F.Fab")
		)
		(fp_line
			(start 0.120396 0.3048)
			(end 0.120396 0.2794)
			(stroke
				(width 0.1)
				(type default)
			)
			(layer "F.Fab")
		)
		(fp_line
			(start 0.120396 0.2794)
			(end -0.12065 0.2794)
			(stroke
				(width 0.1)
				(type default)
			)
			(layer "F.Fab")
		)
		(fp_line
			(start -0.12065 0.3048)
			(end -0.67945 0.3048)
			(stroke
				(width 0.1)
				(type default)
			)
			(layer "F.Fab")
		)
		(fp_line
			(start -0.12065 0.2794)
			(end -0.12065 0.3048)
			(stroke
				(width 0.1)
				(type default)
			)
			(layer "F.Fab")
		)
		(fp_line
			(start -0.12065 -0.2794)
			(end 0.12065 -0.2794)
			(stroke
				(width 0.1)
				(type default)
			)
			(layer "F.Fab")
		)
		(fp_line
			(start -0.12065 -0.305054)
			(end -0.12065 -0.2794)
			(stroke
				(width 0.1)
				(type default)
			)
			(layer "F.Fab")
		)
		(fp_line
			(start -0.67945 0.3048)
			(end -0.67945 -0.305054)
			(stroke
				(width 0.1)
				(type default)
			)
			(layer "F.Fab")
		)
		(fp_line
			(start -0.67945 -0.305054)
			(end -0.12065 -0.305054)
			(stroke
				(width 0.1)
				(type default)
			)
			(layer "F.Fab")
		)
		(pad "1" smd circle
			(at -0.40005 0 180)
			(size 0 0)
			(layers "F.Cu" "F.Mask" "F.Paste")
			(net "FM_P5V_EN")
		)
		(pad "2" smd circle
			(at 0.40005 0 180)
			(size 0 0)
			(layers "F.Cu" "F.Mask" "F.Paste")
			(net "VR_P5V_EN")
		)
	)
	(footprint ""
		(layer "F.Cu")
		(at 217.861134 -97.54362)
		(property "Reference" "R9029"
			(at 0 0 0)
			(layer "F.SilkS")
			(hide yes)
			(effects
				(font
					(size 1.27 1.27)
				)
			)
		)
		(property "Value" ""
			(at 0 0 0)
			(layer "F.Fab")
			(effects
				(font
					(size 1.27 1.27)
				)
			)
		)
		(duplicate_pad_numbers_are_jumpers no)
		(fp_line
			(start -0.7874 -0.4064)
			(end 0.7874 -0.4064)
			(stroke
				(width 0.1524)
				(type default)
			)
			(layer "F.SilkS")
		)
		(fp_line
			(start -0.7874 0.4064)
			(end -0.7874 -0.4064)
			(stroke
				(width 0.1524)
				(type default)
			)
			(layer "F.SilkS")
		)
		(fp_line
			(start 0.7874 -0.4064)
			(end 0.7874 0.4064)
			(stroke
				(width 0.1524)
				(type default)
			)
			(layer "F.SilkS")
		)
		(fp_line
			(start 0.7874 0.4064)
			(end -0.7874 0.4064)
			(stroke
				(width 0.1524)
				(type default)
			)
			(layer "F.SilkS")
		)
		(fp_line
			(start -0.67945 -0.305054)
			(end -0.12065 -0.305054)
			(stroke
				(width 0.1)
				(type default)
			)
			(layer "F.Fab")
		)
		(fp_line
			(start -0.67945 0.3048)
			(end -0.67945 -0.305054)
			(stroke
				(width 0.1)
				(type default)
			)
			(layer "F.Fab")
		)
		(fp_line
			(start -0.12065 -0.305054)
			(end -0.12065 -0.2794)
			(stroke
				(width 0.1)
				(type default)
			)
			(layer "F.Fab")
		)
		(fp_line
			(start -0.12065 -0.2794)
			(end 0.12065 -0.2794)
			(stroke
				(width 0.1)
				(type default)
			)
			(layer "F.Fab")
		)
		(fp_line
			(start -0.12065 0.2794)
			(end -0.12065 0.3048)
			(stroke
				(width 0.1)
				(type default)
			)
			(layer "F.Fab")
		)
		(fp_line
			(start -0.12065 0.3048)
			(end -0.67945 0.3048)
			(stroke
				(width 0.1)
				(type default)
			)
			(layer "F.Fab")
		)
		(fp_line
			(start 0.120396 0.2794)
			(end -0.12065 0.2794)
			(stroke
				(width 0.1)
				(type default)
			)
			(layer "F.Fab")
		)
		(fp_line
			(start 0.120396 0.3048)
			(end 0.120396 0.2794)
			(stroke
				(width 0.1)
				(type default)
			)
			(layer "F.Fab")
		)
		(fp_line
			(start 0.12065 -0.3048)
			(end 0.67945 -0.3048)
			(stroke
				(width 0.1)
				(type default)
			)
			(layer "F.Fab")
		)
		(fp_line
			(start 0.12065 -0.2794)
			(end 0.12065 -0.3048)
			(stroke
				(width 0.1)
				(type default)
			)
			(layer "F.Fab")
		)
		(fp_line
			(start 0.67945 -0.3048)
			(end 0.67945 0.3048)
			(stroke
				(width 0.1)
				(type default)
			)
			(layer "F.Fab")
		)
		(fp_line
			(start 0.67945 0.3048)
			(end 0.120396 0.3048)
			(stroke
				(width 0.1)
				(type default)
			)
			(layer "F.Fab")
		)
		(pad "1" smd circle
			(at -0.40005 0)
			(size 0 0)
			(layers "F.Cu" "F.Mask" "F.Paste")
			(net "OCP_SFF_AUX_PWR_EN_R3")
		)
		(pad "2" smd circle
			(at 0.40005 0)
			(size 0 0)
			(layers "F.Cu" "F.Mask" "F.Paste")
			(net "HP_LVC3_OCP_V3_1_PWRGD_R1")
		)
	)
	(footprint ""
		(layer "F.Cu")
		(at 285.24454 -401.395692 180)
		(property "Reference" "C1786"
			(at 0 0 180)
			(layer "F.SilkS")
			(hide yes)
			(effects
				(font
					(size 1.27 1.27)
				)
			)
		)
		(property "Value" ""
			(at 0 0 180)
			(layer "F.Fab")
			(effects
				(font
					(size 1.27 1.27)
				)
			)
		)
		(duplicate_pad_numbers_are_jumpers no)
		(fp_line
			(start 1.2954 0.5842)
			(end -1.2954 0.5842)
			(stroke
				(width 0.1524)
				(type default)
			)
			(layer "F.SilkS")
		)
		(fp_line
			(start 1.2954 -0.5842)
			(end 1.2954 0.5842)
			(stroke
				(width 0.1524)
				(type default)
			)
			(layer "F.SilkS")
		)
		(fp_line
			(start -1.2954 0.5842)
			(end -1.2954 -0.5842)
			(stroke
				(width 0.1524)
				(type default)
			)
			(layer "F.SilkS")
		)
		(fp_line
			(start -1.2954 -0.5842)
			(end 1.2954 -0.5842)
			(stroke
				(width 0.1524)
				(type default)
			)
			(layer "F.SilkS")
		)
		(fp_line
			(start 1.1938 0.4064)
			(end 0.8636 0.4064)
			(stroke
				(width 0.1)
				(type default)
			)
			(layer "F.Fab")
		)
		(fp_line
			(start 1.1938 -0.4064)
			(end 1.1938 0.4064)
			(stroke
				(width 0.1)
				(type default)
			)
			(layer "F.Fab")
		)
		(fp_line
			(start 0.8636 0.4572)
			(end -0.8636 0.4572)
			(stroke
				(width 0.1)
				(type default)
			)
			(layer "F.Fab")
		)
		(fp_line
			(start 0.8636 0.4064)
			(end 0.8636 0.4572)
			(stroke
				(width 0.1)
				(type default)
			)
			(layer "F.Fab")
		)
		(fp_line
			(start 0.8636 -0.4064)
			(end 1.1938 -0.4064)
			(stroke
				(width 0.1)
				(type default)
			)
			(layer "F.Fab")
		)
		(fp_line
			(start 0.8636 -0.4572)
			(end 0.8636 -0.4064)
			(stroke
				(width 0.1)
				(type default)
			)
			(layer "F.Fab")
		)
		(fp_line
			(start -0.8636 0.4572)
			(end -0.8636 0.4064)
			(stroke
				(width 0.1)
				(type default)
			)
			(layer "F.Fab")
		)
		(fp_line
			(start -0.8636 0.4064)
			(end -1.1938 0.4064)
			(stroke
				(width 0.1)
				(type default)
			)
			(layer "F.Fab")
		)
		(fp_line
			(start -0.8636 -0.4064)
			(end -0.8636 -0.4572)
			(stroke
				(width 0.1)
				(type default)
			)
			(layer "F.Fab")
		)
		(fp_line
			(start -0.8636 -0.4572)
			(end 0.8636 -0.4572)
			(stroke
				(width 0.1)
				(type default)
			)
			(layer "F.Fab")
		)
		(fp_line
			(start -1.1938 0.4064)
			(end -1.1938 -0.4064)
			(stroke
				(width 0.1)
				(type default)
			)
			(layer "F.Fab")
		)
		(fp_line
			(start -1.1938 -0.4064)
			(end -0.8636 -0.4064)
			(stroke
				(width 0.1)
				(type default)
			)
			(layer "F.Fab")
		)
		(pad "1" smd rect
			(at -0.7366 0 90)
			(size 0.7112 0.8128)
			(layers "F.Cu" "F.Mask" "F.Paste")
			(net "P12V_HSC_TEMP_D+")
		)
		(pad "2" smd rect
			(at 0.7366 0 90)
			(size 0.7112 0.8128)
			(layers "F.Cu" "F.Mask" "F.Paste")
			(net "P12V_HSC_TEMP_D-")
		)
	)
	(footprint ""
		(layer "F.Cu")
		(at 148.944076 -23.284942 -90)
		(property "Reference" "R364"
			(at 0 0 270)
			(layer "F.SilkS")
			(hide yes)
			(effects
				(font
					(size 1.27 1.27)
				)
			)
		)
		(property "Value" ""
			(at 0 0 270)
			(layer "F.Fab")
			(effects
				(font
					(size 1.27 1.27)
				)
			)
		)
		(duplicate_pad_numbers_are_jumpers no)
		(fp_line
			(start -0.7874 0.4064)
			(end -0.7874 -0.4064)
			(stroke
				(width 0.1524)
				(type default)
			)
			(layer "F.SilkS")
		)
		(fp_line
			(start 0.7874 0.4064)
			(end -0.7874 0.4064)
			(stroke
				(width 0.1524)
				(type default)
			)
			(layer "F.SilkS")
		)
		(fp_line
			(start -0.7874 -0.4064)
			(end 0.7874 -0.4064)
			(stroke
				(width 0.1524)
				(type default)
			)
			(layer "F.SilkS")
		)
		(fp_line
			(start 0.7874 -0.4064)
			(end 0.7874 0.4064)
			(stroke
				(width 0.1524)
				(type default)
			)
			(layer "F.SilkS")
		)
		(fp_line
			(start -0.67945 0.3048)
			(end -0.67945 -0.305054)
			(stroke
				(width 0.1)
				(type default)
			)
			(layer "F.Fab")
		)
		(fp_line
			(start -0.12065 0.3048)
			(end -0.67945 0.3048)
			(stroke
				(width 0.1)
				(type default)
			)
			(layer "F.Fab")
		)
		(fp_line
			(start 0.120396 0.3048)
			(end 0.120396 0.2794)
			(stroke
				(width 0.1)
				(type default)
			)
			(layer "F.Fab")
		)
		(fp_line
			(start 0.67945 0.3048)
			(end 0.120396 0.3048)
			(stroke
				(width 0.1)
				(type default)
			)
			(layer "F.Fab")
		)
		(fp_line
			(start -0.12065 0.2794)
			(end -0.12065 0.3048)
			(stroke
				(width 0.1)
				(type default)
			)
			(layer "F.Fab")
		)
		(fp_line
			(start 0.120396 0.2794)
			(end -0.12065 0.2794)
			(stroke
				(width 0.1)
				(type default)
			)
			(layer "F.Fab")
		)
		(fp_line
			(start -0.12065 -0.2794)
			(end 0.12065 -0.2794)
			(stroke
				(width 0.1)
				(type default)
			)
			(layer "F.Fab")
		)
		(fp_line
			(start 0.12065 -0.2794)
			(end 0.12065 -0.3048)
			(stroke
				(width 0.1)
				(type default)
			)
			(layer "F.Fab")
		)
		(fp_line
			(start 0.12065 -0.3048)
			(end 0.67945 -0.3048)
			(stroke
				(width 0.1)
				(type default)
			)
			(layer "F.Fab")
		)
		(fp_line
			(start 0.67945 -0.3048)
			(end 0.67945 0.3048)
			(stroke
				(width 0.1)
				(type default)
			)
			(layer "F.Fab")
		)
		(fp_line
			(start -0.67945 -0.305054)
			(end -0.12065 -0.305054)
			(stroke
				(width 0.1)
				(type default)
			)
			(layer "F.Fab")
		)
		(fp_line
			(start -0.12065 -0.305054)
			(end -0.12065 -0.2794)
			(stroke
				(width 0.1)
				(type default)
			)
			(layer "F.Fab")
		)
		(pad "1" smd circle
			(at -0.40005 0 270)
			(size 0 0)
			(layers "F.Cu" "F.Mask" "F.Paste")
			(net "P3V_BAT_R")
		)
		(pad "2" smd circle
			(at 0.40005 0 270)
			(size 0 0)
			(layers "F.Cu" "F.Mask" "F.Paste")
			(net "SCM_VDD_RTC")
		)
	)
	(footprint ""
		(layer "F.Cu")
		(at 403.977348 -17.624298 90)
		(property "Reference" "C1558"
			(at 0 0 90)
			(layer "F.SilkS")
			(hide yes)
			(effects
				(font
					(size 1.27 1.27)
				)
			)
		)
		(property "Value" ""
			(at 0 0 90)
			(layer "F.Fab")
			(effects
				(font
					(size 1.27 1.27)
				)
			)
		)
		(duplicate_pad_numbers_are_jumpers no)
		(fp_line
			(start 0.299974 -0.150114)
			(end 0.299974 0.150114)
			(stroke
				(width 0.1)
				(type default)
			)
			(layer "F.Fab")
		)
		(fp_line
			(start -0.299974 -0.150114)
			(end 0.299974 -0.150114)
			(stroke
				(width 0.1)
				(type default)
			)
			(layer "F.Fab")
		)
		(fp_line
			(start 0.299974 0.150114)
			(end -0.299974 0.150114)
			(stroke
				(width 0.1)
				(type default)
			)
			(layer "F.Fab")
		)
		(fp_line
			(start -0.299974 0.150114)
			(end -0.299974 -0.150114)
			(stroke
				(width 0.1)
				(type default)
			)
			(layer "F.Fab")
		)
		(pad "1" smd rect
			(at -0.2667 0 90)
			(size 0.3048 0.381)
			(layers "F.Cu" "F.Mask" "F.Paste")
			(net "P5E_CPU0_G3_TX_C_DN<10>")
		)
		(pad "2" smd rect
			(at 0.2667 0 90)
			(size 0.3048 0.381)
			(layers "F.Cu" "F.Mask" "F.Paste")
			(net "P5E_CPU0_G3_TX_DN<10>")
		)
	)
	(footprint ""
		(layer "F.Cu")
		(at 281.905456 -434.655976 180)
		(property "Reference" "R4268"
			(at 0 0 180)
			(layer "F.SilkS")
			(hide yes)
			(effects
				(font
					(size 1.27 1.27)
				)
			)
		)
		(property "Value" ""
			(at 0 0 180)
			(layer "F.Fab")
			(effects
				(font
					(size 1.27 1.27)
				)
			)
		)
		(duplicate_pad_numbers_are_jumpers no)
		(fp_line
			(start 0.7874 0.4064)
			(end -0.7874 0.4064)
			(stroke
				(width 0.1524)
				(type default)
			)
			(layer "F.SilkS")
		)
		(fp_line
			(start 0.7874 -0.4064)
			(end 0.7874 0.4064)
			(stroke
				(width 0.1524)
				(type default)
			)
			(layer "F.SilkS")
		)
		(fp_line
			(start -0.7874 0.4064)
			(end -0.7874 -0.4064)
			(stroke
				(width 0.1524)
				(type default)
			)
			(layer "F.SilkS")
		)
		(fp_line
			(start -0.7874 -0.4064)
			(end 0.7874 -0.4064)
			(stroke
				(width 0.1524)
				(type default)
			)
			(layer "F.SilkS")
		)
		(fp_line
			(start 0.67945 0.3048)
			(end 0.120396 0.3048)
			(stroke
				(width 0.1)
				(type default)
			)
			(layer "F.Fab")
		)
		(fp_line
			(start 0.67945 -0.3048)
			(end 0.67945 0.3048)
			(stroke
				(width 0.1)
				(type default)
			)
			(layer "F.Fab")
		)
		(fp_line
			(start 0.12065 -0.2794)
			(end 0.12065 -0.3048)
			(stroke
				(width 0.1)
				(type default)
			)
			(layer "F.Fab")
		)
		(fp_line
			(start 0.12065 -0.3048)
			(end 0.67945 -0.3048)
			(stroke
				(width 0.1)
				(type default)
			)
			(layer "F.Fab")
		)
		(fp_line
			(start 0.120396 0.3048)
			(end 0.120396 0.2794)
			(stroke
				(width 0.1)
				(type default)
			)
			(layer "F.Fab")
		)
		(fp_line
			(start 0.120396 0.2794)
			(end -0.12065 0.2794)
			(stroke
				(width 0.1)
				(type default)
			)
			(layer "F.Fab")
		)
		(fp_line
			(start -0.12065 0.3048)
			(end -0.67945 0.3048)
			(stroke
				(width 0.1)
				(type default)
			)
			(layer "F.Fab")
		)
		(fp_line
			(start -0.12065 0.2794)
			(end -0.12065 0.3048)
			(stroke
				(width 0.1)
				(type default)
			)
			(layer "F.Fab")
		)
		(fp_line
			(start -0.12065 -0.2794)
			(end 0.12065 -0.2794)
			(stroke
				(width 0.1)
				(type default)
			)
			(layer "F.Fab")
		)
		(fp_line
			(start -0.12065 -0.305054)
			(end -0.12065 -0.2794)
			(stroke
				(width 0.1)
				(type default)
			)
			(layer "F.Fab")
		)
		(fp_line
			(start -0.67945 0.3048)
			(end -0.67945 -0.305054)
			(stroke
				(width 0.1)
				(type default)
			)
			(layer "F.Fab")
		)
		(fp_line
			(start -0.67945 -0.305054)
			(end -0.12065 -0.305054)
			(stroke
				(width 0.1)
				(type default)
			)
			(layer "F.Fab")
		)
		(pad "1" smd circle
			(at -0.40005 0 180)
			(size 0 0)
			(layers "F.Cu" "F.Mask" "F.Paste")
			(net "PWRGD_P3V3_AUX_PDB")
		)
		(pad "2" smd circle
			(at 0.40005 0 180)
			(size 0 0)
			(layers "F.Cu" "F.Mask" "F.Paste")
			(net "PWRGD_P3V3_AUX_PDB_R")
		)
	)
	(footprint ""
		(layer "F.Cu")
		(at 180.528468 -53.980334)
		(property "Reference" "C1099"
			(at 0 0 0)
			(layer "F.SilkS")
			(hide yes)
			(effects
				(font
					(size 1.27 1.27)
				)
			)
		)
		(property "Value" ""
			(at 0 0 0)
			(layer "F.Fab")
			(effects
				(font
					(size 1.27 1.27)
				)
			)
		)
		(duplicate_pad_numbers_are_jumpers no)
		(fp_line
			(start -0.299974 -0.150114)
			(end 0.299974 -0.150114)
			(stroke
				(width 0.1)
				(type default)
			)
			(layer "F.Fab")
		)
		(fp_line
			(start -0.299974 0.150114)
			(end -0.299974 -0.150114)
			(stroke
				(width 0.1)
				(type default)
			)
			(layer "F.Fab")
		)
		(fp_line
			(start 0.299974 -0.150114)
			(end 0.299974 0.150114)
			(stroke
				(width 0.1)
				(type default)
			)
			(layer "F.Fab")
		)
		(fp_line
			(start 0.299974 0.150114)
			(end -0.299974 0.150114)
			(stroke
				(width 0.1)
				(type default)
			)
			(layer "F.Fab")
		)
		(pad "1" smd rect
			(at -0.2667 0)
			(size 0.3048 0.381)
			(layers "F.Cu" "F.Mask" "F.Paste")
			(net "P3E_CPU1_P4_TX_C_DN<3>")
		)
		(pad "2" smd rect
			(at 0.2667 0)
			(size 0.3048 0.381)
			(layers "F.Cu" "F.Mask" "F.Paste")
			(net "P3E_CPU1_P4_TX_DN<3>")
		)
	)
	(footprint ""
		(layer "F.Cu")
		(at 109.136942 -19.9898 -90)
		(property "Reference" "R6272"
			(at 0 0 270)
			(layer "F.SilkS")
			(hide yes)
			(effects
				(font
					(size 1.27 1.27)
				)
			)
		)
		(property "Value" ""
			(at 0 0 270)
			(layer "F.Fab")
			(effects
				(font
					(size 1.27 1.27)
				)
			)
		)
		(duplicate_pad_numbers_are_jumpers no)
		(fp_line
			(start -0.7874 0.4064)
			(end -0.7874 -0.4064)
			(stroke
				(width 0.1524)
				(type default)
			)
			(layer "F.SilkS")
		)
		(fp_line
			(start 0.7874 0.4064)
			(end -0.7874 0.4064)
			(stroke
				(width 0.1524)
				(type default)
			)
			(layer "F.SilkS")
		)
		(fp_line
			(start -0.7874 -0.4064)
			(end 0.7874 -0.4064)
			(stroke
				(width 0.1524)
				(type default)
			)
			(layer "F.SilkS")
		)
		(fp_line
			(start 0.7874 -0.4064)
			(end 0.7874 0.4064)
			(stroke
				(width 0.1524)
				(type default)
			)
			(layer "F.SilkS")
		)
		(fp_line
			(start -0.67945 0.3048)
			(end -0.67945 -0.305054)
			(stroke
				(width 0.1)
				(type default)
			)
			(layer "F.Fab")
		)
		(fp_line
			(start -0.12065 0.3048)
			(end -0.67945 0.3048)
			(stroke
				(width 0.1)
				(type default)
			)
			(layer "F.Fab")
		)
		(fp_line
			(start 0.120396 0.3048)
			(end 0.120396 0.2794)
			(stroke
				(width 0.1)
				(type default)
			)
			(layer "F.Fab")
		)
		(fp_line
			(start 0.67945 0.3048)
			(end 0.120396 0.3048)
			(stroke
				(width 0.1)
				(type default)
			)
			(layer "F.Fab")
		)
		(fp_line
			(start -0.12065 0.2794)
			(end -0.12065 0.3048)
			(stroke
				(width 0.1)
				(type default)
			)
			(layer "F.Fab")
		)
		(fp_line
			(start 0.120396 0.2794)
			(end -0.12065 0.2794)
			(stroke
				(width 0.1)
				(type default)
			)
			(layer "F.Fab")
		)
		(fp_line
			(start -0.12065 -0.2794)
			(end 0.12065 -0.2794)
			(stroke
				(width 0.1)
				(type default)
			)
			(layer "F.Fab")
		)
		(fp_line
			(start 0.12065 -0.2794)
			(end 0.12065 -0.3048)
			(stroke
				(width 0.1)
				(type default)
			)
			(layer "F.Fab")
		)
		(fp_line
			(start 0.12065 -0.3048)
			(end 0.67945 -0.3048)
			(stroke
				(width 0.1)
				(type default)
			)
			(layer "F.Fab")
		)
		(fp_line
			(start 0.67945 -0.3048)
			(end 0.67945 0.3048)
			(stroke
				(width 0.1)
				(type default)
			)
			(layer "F.Fab")
		)
		(fp_line
			(start -0.67945 -0.305054)
			(end -0.12065 -0.305054)
			(stroke
				(width 0.1)
				(type default)
			)
			(layer "F.Fab")
		)
		(fp_line
			(start -0.12065 -0.305054)
			(end -0.12065 -0.2794)
			(stroke
				(width 0.1)
				(type default)
			)
			(layer "F.Fab")
		)
		(pad "1" smd circle
			(at -0.40005 0 270)
			(size 0 0)
			(layers "F.Cu" "F.Mask" "F.Paste")
			(net "USB_HUB2_MRP_CFG_STRAP")
		)
		(pad "2" smd circle
			(at 0.40005 0 270)
			(size 0 0)
			(layers "F.Cu" "F.Mask" "F.Paste")
			(net "GND")
		)
	)
	(footprint ""
		(layer "F.Cu")
		(at 179.058062 -32.935672 90)
		(property "Reference" "PC2229"
			(at 0 0 90)
			(layer "F.SilkS")
			(hide yes)
			(effects
				(font
					(size 1.27 1.27)
				)
			)
		)
		(property "Value" ""
			(at 0 0 90)
			(layer "F.Fab")
			(effects
				(font
					(size 1.27 1.27)
				)
			)
		)
		(duplicate_pad_numbers_are_jumpers no)
		(fp_line
			(start 0.7874 -0.4064)
			(end 0.7874 0.4064)
			(stroke
				(width 0.1524)
				(type default)
			)
			(layer "F.SilkS")
		)
		(fp_line
			(start -0.7874 -0.4064)
			(end 0.7874 -0.4064)
			(stroke
				(width 0.1524)
				(type default)
			)
			(layer "F.SilkS")
		)
		(fp_line
			(start 0.7874 0.4064)
			(end -0.7874 0.4064)
			(stroke
				(width 0.1524)
				(type default)
			)
			(layer "F.SilkS")
		)
		(fp_line
			(start -0.7874 0.4064)
			(end -0.7874 -0.4064)
			(stroke
				(width 0.1524)
				(type default)
			)
			(layer "F.SilkS")
		)
		(fp_line
			(start -0.12065 -0.305054)
			(end -0.12065 -0.2794)
			(stroke
				(width 0.1)
				(type default)
			)
			(layer "F.Fab")
		)
		(fp_line
			(start -0.67945 -0.305054)
			(end -0.12065 -0.305054)
			(stroke
				(width 0.1)
				(type default)
			)
			(layer "F.Fab")
		)
		(fp_line
			(start 0.67945 -0.3048)
			(end 0.67945 0.3048)
			(stroke
				(width 0.1)
				(type default)
			)
			(layer "F.Fab")
		)
		(fp_line
			(start 0.12065 -0.3048)
			(end 0.67945 -0.3048)
			(stroke
				(width 0.1)
				(type default)
			)
			(layer "F.Fab")
		)
		(fp_line
			(start 0.12065 -0.2794)
			(end 0.12065 -0.3048)
			(stroke
				(width 0.1)
				(type default)
			)
			(layer "F.Fab")
		)
		(fp_line
			(start -0.12065 -0.2794)
			(end 0.12065 -0.2794)
			(stroke
				(width 0.1)
				(type default)
			)
			(layer "F.Fab")
		)
		(fp_line
			(start 0.120396 0.2794)
			(end -0.12065 0.2794)
			(stroke
				(width 0.1)
				(type default)
			)
			(layer "F.Fab")
		)
		(fp_line
			(start -0.12065 0.2794)
			(end -0.12065 0.3048)
			(stroke
				(width 0.1)
				(type default)
			)
			(layer "F.Fab")
		)
		(fp_line
			(start 0.67945 0.3048)
			(end 0.120396 0.3048)
			(stroke
				(width 0.1)
				(type default)
			)
			(layer "F.Fab")
		)
		(fp_line
			(start 0.120396 0.3048)
			(end 0.120396 0.2794)
			(stroke
				(width 0.1)
				(type default)
			)
			(layer "F.Fab")
		)
		(fp_line
			(start -0.12065 0.3048)
			(end -0.67945 0.3048)
			(stroke
				(width 0.1)
				(type default)
			)
			(layer "F.Fab")
		)
		(fp_line
			(start -0.67945 0.3048)
			(end -0.67945 -0.305054)
			(stroke
				(width 0.1)
				(type default)
			)
			(layer "F.Fab")
		)
		(pad "1" smd circle
			(at -0.40005 0 90)
			(size 0 0)
			(layers "F.Cu" "F.Mask" "F.Paste")
			(net "P12V_SCM_TIMER")
		)
		(pad "2" smd circle
			(at 0.40005 0 90)
			(size 0 0)
			(layers "F.Cu" "F.Mask" "F.Paste")
			(net "GND")
		)
	)
	(footprint ""
		(layer "F.Cu")
		(at 277.352252 -111.91367)
		(property "Reference" "R3535"
			(at 0 0 0)
			(layer "F.SilkS")
			(hide yes)
			(effects
				(font
					(size 1.27 1.27)
				)
			)
		)
		(property "Value" ""
			(at 0 0 0)
			(layer "F.Fab")
			(effects
				(font
					(size 1.27 1.27)
				)
			)
		)
		(duplicate_pad_numbers_are_jumpers no)
		(fp_line
			(start -0.7874 -0.4064)
			(end 0.7874 -0.4064)
			(stroke
				(width 0.1524)
				(type default)
			)
			(layer "F.SilkS")
		)
		(fp_line
			(start -0.7874 0.4064)
			(end -0.7874 -0.4064)
			(stroke
				(width 0.1524)
				(type default)
			)
			(layer "F.SilkS")
		)
		(fp_line
			(start 0.7874 -0.4064)
			(end 0.7874 0.4064)
			(stroke
				(width 0.1524)
				(type default)
			)
			(layer "F.SilkS")
		)
		(fp_line
			(start 0.7874 0.4064)
			(end -0.7874 0.4064)
			(stroke
				(width 0.1524)
				(type default)
			)
			(layer "F.SilkS")
		)
		(fp_line
			(start -0.67945 -0.305054)
			(end -0.12065 -0.305054)
			(stroke
				(width 0.1)
				(type default)
			)
			(layer "F.Fab")
		)
		(fp_line
			(start -0.67945 0.3048)
			(end -0.67945 -0.305054)
			(stroke
				(width 0.1)
				(type default)
			)
			(layer "F.Fab")
		)
		(fp_line
			(start -0.12065 -0.305054)
			(end -0.12065 -0.2794)
			(stroke
				(width 0.1)
				(type default)
			)
			(layer "F.Fab")
		)
		(fp_line
			(start -0.12065 -0.2794)
			(end 0.12065 -0.2794)
			(stroke
				(width 0.1)
				(type default)
			)
			(layer "F.Fab")
		)
		(fp_line
			(start -0.12065 0.2794)
			(end -0.12065 0.3048)
			(stroke
				(width 0.1)
				(type default)
			)
			(layer "F.Fab")
		)
		(fp_line
			(start -0.12065 0.3048)
			(end -0.67945 0.3048)
			(stroke
				(width 0.1)
				(type default)
			)
			(layer "F.Fab")
		)
		(fp_line
			(start 0.120396 0.2794)
			(end -0.12065 0.2794)
			(stroke
				(width 0.1)
				(type default)
			)
			(layer "F.Fab")
		)
		(fp_line
			(start 0.120396 0.3048)
			(end 0.120396 0.2794)
			(stroke
				(width 0.1)
				(type default)
			)
			(layer "F.Fab")
		)
		(fp_line
			(start 0.12065 -0.3048)
			(end 0.67945 -0.3048)
			(stroke
				(width 0.1)
				(type default)
			)
			(layer "F.Fab")
		)
		(fp_line
			(start 0.12065 -0.2794)
			(end 0.12065 -0.3048)
			(stroke
				(width 0.1)
				(type default)
			)
			(layer "F.Fab")
		)
		(fp_line
			(start 0.67945 -0.3048)
			(end 0.67945 0.3048)
			(stroke
				(width 0.1)
				(type default)
			)
			(layer "F.Fab")
		)
		(fp_line
			(start 0.67945 0.3048)
			(end 0.120396 0.3048)
			(stroke
				(width 0.1)
				(type default)
			)
			(layer "F.Fab")
		)
		(pad "1" smd circle
			(at -0.40005 0)
			(size 0 0)
			(layers "F.Cu" "F.Mask" "F.Paste")
			(net "P3V3_AUX")
		)
		(pad "2" smd circle
			(at 0.40005 0)
			(size 0 0)
			(layers "F.Cu" "F.Mask" "F.Paste")
			(net "SMB_SENSOR_E1S_3V3AUX_SCL")
		)
	)
	(footprint ""
		(layer "F.Cu")
		(at 270.192754 -418.971476 90)
		(property "Reference" "C2179"
			(at 0 0 90)
			(layer "F.SilkS")
			(hide yes)
			(effects
				(font
					(size 1.27 1.27)
				)
			)
		)
		(property "Value" ""
			(at 0 0 90)
			(layer "F.Fab")
			(effects
				(font
					(size 1.27 1.27)
				)
			)
		)
		(duplicate_pad_numbers_are_jumpers no)
		(fp_line
			(start 0.7874 -0.4064)
			(end 0.7874 0.4064)
			(stroke
				(width 0.1524)
				(type default)
			)
			(layer "F.SilkS")
		)
		(fp_line
			(start -0.7874 -0.4064)
			(end 0.7874 -0.4064)
			(stroke
				(width 0.1524)
				(type default)
			)
			(layer "F.SilkS")
		)
		(fp_line
			(start 0.7874 0.4064)
			(end -0.7874 0.4064)
			(stroke
				(width 0.1524)
				(type default)
			)
			(layer "F.SilkS")
		)
		(fp_line
			(start -0.7874 0.4064)
			(end -0.7874 -0.4064)
			(stroke
				(width 0.1524)
				(type default)
			)
			(layer "F.SilkS")
		)
		(fp_line
			(start -0.12065 -0.305054)
			(end -0.12065 -0.2794)
			(stroke
				(width 0.1)
				(type default)
			)
			(layer "F.Fab")
		)
		(fp_line
			(start -0.67945 -0.305054)
			(end -0.12065 -0.305054)
			(stroke
				(width 0.1)
				(type default)
			)
			(layer "F.Fab")
		)
		(fp_line
			(start 0.67945 -0.3048)
			(end 0.67945 0.3048)
			(stroke
				(width 0.1)
				(type default)
			)
			(layer "F.Fab")
		)
		(fp_line
			(start 0.12065 -0.3048)
			(end 0.67945 -0.3048)
			(stroke
				(width 0.1)
				(type default)
			)
			(layer "F.Fab")
		)
		(fp_line
			(start 0.12065 -0.2794)
			(end 0.12065 -0.3048)
			(stroke
				(width 0.1)
				(type default)
			)
			(layer "F.Fab")
		)
		(fp_line
			(start -0.12065 -0.2794)
			(end 0.12065 -0.2794)
			(stroke
				(width 0.1)
				(type default)
			)
			(layer "F.Fab")
		)
		(fp_line
			(start 0.120396 0.2794)
			(end -0.12065 0.2794)
			(stroke
				(width 0.1)
				(type default)
			)
			(layer "F.Fab")
		)
		(fp_line
			(start -0.12065 0.2794)
			(end -0.12065 0.3048)
			(stroke
				(width 0.1)
				(type default)
			)
			(layer "F.Fab")
		)
		(fp_line
			(start 0.67945 0.3048)
			(end 0.120396 0.3048)
			(stroke
				(width 0.1)
				(type default)
			)
			(layer "F.Fab")
		)
		(fp_line
			(start 0.120396 0.3048)
			(end 0.120396 0.2794)
			(stroke
				(width 0.1)
				(type default)
			)
			(layer "F.Fab")
		)
		(fp_line
			(start -0.12065 0.3048)
			(end -0.67945 0.3048)
			(stroke
				(width 0.1)
				(type default)
			)
			(layer "F.Fab")
		)
		(fp_line
			(start -0.67945 0.3048)
			(end -0.67945 -0.305054)
			(stroke
				(width 0.1)
				(type default)
			)
			(layer "F.Fab")
		)
		(pad "1" smd circle
			(at -0.40005 0 90)
			(size 0 0)
			(layers "F.Cu" "F.Mask" "F.Paste")
			(net "HSC_EN")
		)
		(pad "2" smd circle
			(at 0.40005 0 90)
			(size 0 0)
			(layers "F.Cu" "F.Mask" "F.Paste")
			(net "GND")
		)
	)
	(footprint ""
		(layer "F.Cu")
		(at 427.975268 -58.397648 90)
		(property "Reference" "C693"
			(at 0 0 90)
			(layer "F.SilkS")
			(hide yes)
			(effects
				(font
					(size 1.27 1.27)
				)
			)
		)
		(property "Value" ""
			(at 0 0 90)
			(layer "F.Fab")
			(effects
				(font
					(size 1.27 1.27)
				)
			)
		)
		(duplicate_pad_numbers_are_jumpers no)
		(fp_line
			(start 0.7874 -0.4064)
			(end 0.7874 0.4064)
			(stroke
				(width 0.1524)
				(type default)
			)
			(layer "F.SilkS")
		)
		(fp_line
			(start -0.7874 -0.4064)
			(end 0.7874 -0.4064)
			(stroke
				(width 0.1524)
				(type default)
			)
			(layer "F.SilkS")
		)
		(fp_line
			(start 0.7874 0.4064)
			(end -0.7874 0.4064)
			(stroke
				(width 0.1524)
				(type default)
			)
			(layer "F.SilkS")
		)
		(fp_line
			(start -0.7874 0.4064)
			(end -0.7874 -0.4064)
			(stroke
				(width 0.1524)
				(type default)
			)
			(layer "F.SilkS")
		)
		(fp_line
			(start -0.12065 -0.305054)
			(end -0.12065 -0.2794)
			(stroke
				(width 0.1)
				(type default)
			)
			(layer "F.Fab")
		)
		(fp_line
			(start -0.67945 -0.305054)
			(end -0.12065 -0.305054)
			(stroke
				(width 0.1)
				(type default)
			)
			(layer "F.Fab")
		)
		(fp_line
			(start 0.67945 -0.3048)
			(end 0.67945 0.3048)
			(stroke
				(width 0.1)
				(type default)
			)
			(layer "F.Fab")
		)
		(fp_line
			(start 0.12065 -0.3048)
			(end 0.67945 -0.3048)
			(stroke
				(width 0.1)
				(type default)
			)
			(layer "F.Fab")
		)
		(fp_line
			(start 0.12065 -0.2794)
			(end 0.12065 -0.3048)
			(stroke
				(width 0.1)
				(type default)
			)
			(layer "F.Fab")
		)
		(fp_line
			(start -0.12065 -0.2794)
			(end 0.12065 -0.2794)
			(stroke
				(width 0.1)
				(type default)
			)
			(layer "F.Fab")
		)
		(fp_line
			(start 0.120396 0.2794)
			(end -0.12065 0.2794)
			(stroke
				(width 0.1)
				(type default)
			)
			(layer "F.Fab")
		)
		(fp_line
			(start -0.12065 0.2794)
			(end -0.12065 0.3048)
			(stroke
				(width 0.1)
				(type default)
			)
			(layer "F.Fab")
		)
		(fp_line
			(start 0.67945 0.3048)
			(end 0.120396 0.3048)
			(stroke
				(width 0.1)
				(type default)
			)
			(layer "F.Fab")
		)
		(fp_line
			(start 0.120396 0.3048)
			(end 0.120396 0.2794)
			(stroke
				(width 0.1)
				(type default)
			)
			(layer "F.Fab")
		)
		(fp_line
			(start -0.12065 0.3048)
			(end -0.67945 0.3048)
			(stroke
				(width 0.1)
				(type default)
			)
			(layer "F.Fab")
		)
		(fp_line
			(start -0.67945 0.3048)
			(end -0.67945 -0.305054)
			(stroke
				(width 0.1)
				(type default)
			)
			(layer "F.Fab")
		)
		(pad "1" smd circle
			(at -0.40005 0 90)
			(size 0 0)
			(layers "F.Cu" "F.Mask" "F.Paste")
			(net "U124_VCC")
		)
		(pad "2" smd circle
			(at 0.40005 0 90)
			(size 0 0)
			(layers "F.Cu" "F.Mask" "F.Paste")
			(net "GND")
		)
	)
	(footprint ""
		(layer "F.Cu")
		(at 5.35432 -74.719688)
		(property "Reference" "U241"
			(at -2.3876 -2.250948 0)
			(unlocked yes)
			(layer "F.SilkS")
			(effects
				(font
					(size 0.7874 0.5842)
					(thickness 0.1524)
				)
				(justify left)
			)
		)
		(property "Value" ""
			(at 0 0 0)
			(layer "F.Fab")
			(effects
				(font
					(size 1.27 1.27)
				)
			)
		)
		(duplicate_pad_numbers_are_jumpers no)
		(fp_line
			(start -1.207008 -1.549908)
			(end -1.207008 1.549908)
			(stroke
				(width 0.1524)
				(type default)
			)
			(layer "F.SilkS")
		)
		(fp_line
			(start -1.207008 1.549908)
			(end 1.207008 1.549908)
			(stroke
				(width 0.1524)
				(type default)
			)
			(layer "F.SilkS")
		)
		(fp_line
			(start -0.762508 -1.549908)
			(end -1.207008 -1.549908)
			(stroke
				(width 0.1524)
				(type default)
			)
			(layer "F.SilkS")
		)
		(fp_line
			(start 0 -0.635)
			(end -0.762508 -1.549908)
			(stroke
				(width 0.1524)
				(type default)
			)
			(layer "F.SilkS")
		)
		(fp_line
			(start 0.762508 -1.549908)
			(end 0 -0.635)
			(stroke
				(width 0.1524)
				(type default)
			)
			(layer "F.SilkS")
		)
		(fp_line
			(start 1.207008 -1.549908)
			(end 0.762508 -1.549908)
			(stroke
				(width 0.1524)
				(type default)
			)
			(layer "F.SilkS")
		)
		(fp_line
			(start 1.207008 1.549908)
			(end 1.207008 -1.549908)
			(stroke
				(width 0.1524)
				(type default)
			)
			(layer "F.SilkS")
		)
		(fp_poly
			(pts
				(xy -2.3876 -1.02489) (xy -3.4036 -0.51689) (xy -3.4036 -1.53289)
			)
			(stroke
				(width 0)
				(type default)
			)
			(fill yes)
			(layer "F.SilkS")
		)
		(fp_line
			(start -1.549908 -1.549908)
			(end -1.549908 1.549908)
			(stroke
				(width 0.1)
				(type default)
			)
			(layer "F.Fab")
		)
		(fp_line
			(start -1.549908 1.549908)
			(end 1.549908 1.549908)
			(stroke
				(width 0.1)
				(type default)
			)
			(layer "F.Fab")
		)
		(fp_line
			(start 1.549908 -1.549908)
			(end -1.549908 -1.549908)
			(stroke
				(width 0.1)
				(type default)
			)
			(layer "F.Fab")
		)
		(fp_line
			(start 1.549908 1.549908)
			(end 1.549908 -1.549908)
			(stroke
				(width 0.1)
				(type default)
			)
			(layer "F.Fab")
		)
		(fp_poly
			(pts
				(xy -3.4036 -1.53289) (xy -3.4036 -0.51689) (xy -2.3876 -1.02489)
			)
			(stroke
				(width 0)
				(type default)
			)
			(fill yes)
			(layer "F.Fab")
		)
		(pad "1" smd rect
			(at -1.774952 -1.02489 270)
			(size 0.508 0.8636)
			(layers "F.Cu" "F.Mask" "F.Paste")
			(net "OCP_V3_2_PRSNT0_R_N")
		)
		(pad "2" smd rect
			(at -1.774952 -0.32512 270)
			(size 0.4064 0.8636)
			(layers "F.Cu" "F.Mask" "F.Paste")
			(net "OCP_V3_2_PRSNT1_R_N")
		)
		(pad "3" smd rect
			(at -1.774952 0.32512 270)
			(size 0.4064 0.8636)
			(layers "F.Cu" "F.Mask" "F.Paste")
			(net "OCP_V3_2_PRSNT23_R_N")
		)
		(pad "4" smd rect
			(at -1.774952 1.02489 270)
			(size 0.508 0.8636)
			(layers "F.Cu" "F.Mask" "F.Paste")
			(net "GND")
		)
		(pad "5" smd rect
			(at 1.774952 1.02489 270)
			(size 0.508 0.8636)
			(layers "F.Cu" "F.Mask" "F.Paste")
			(net "OCP_V3_2_PRSNT2_R_N")
		)
		(pad "6" smd rect
			(at 1.774952 0.32512 270)
			(size 0.4064 0.8636)
			(layers "F.Cu" "F.Mask" "F.Paste")
			(net "OCP_V3_2_PRSNT3_R_N")
		)
		(pad "7" smd rect
			(at 1.774952 -0.32512 270)
			(size 0.4064 0.8636)
			(layers "F.Cu" "F.Mask" "F.Paste")
			(net "OCP_V3_2_PRSNT01_R_N")
		)
		(pad "8" smd rect
			(at 1.774952 -1.02489 270)
			(size 0.508 0.8636)
			(layers "F.Cu" "F.Mask" "F.Paste")
			(net "P3V3_AUX")
		)
	)
	(footprint ""
		(layer "F.Cu")
		(at 12.96416 -71.210678)
		(property "Reference" "U59"
			(at -1.2065 1.973072 0)
			(unlocked yes)
			(layer "F.SilkS")
			(effects
				(font
					(size 0.7874 0.5842)
					(thickness 0.1524)
				)
				(justify left)
			)
		)
		(property "Value" ""
			(at 0 0 0)
			(layer "F.Fab")
			(effects
				(font
					(size 1.27 1.27)
				)
			)
		)
		(duplicate_pad_numbers_are_jumpers no)
		(fp_line
			(start -1.38176 -1.100074)
			(end -1.38176 1.100074)
			(stroke
				(width 0.1524)
				(type default)
			)
			(layer "F.SilkS")
		)
		(fp_line
			(start -1.38176 1.100074)
			(end 1.38176 1.100074)
			(stroke
				(width 0.1524)
				(type default)
			)
			(layer "F.SilkS")
		)
		(fp_line
			(start -0.592074 -1.100074)
			(end -1.38176 -1.100074)
			(stroke
				(width 0.1524)
				(type default)
			)
			(layer "F.SilkS")
		)
		(fp_line
			(start 0 -0.508)
			(end -0.592074 -1.100074)
			(stroke
				(width 0.1524)
				(type default)
			)
			(layer "F.SilkS")
		)
		(fp_line
			(start 0.592074 -1.100074)
			(end 0 -0.508)
			(stroke
				(width 0.1524)
				(type default)
			)
			(layer "F.SilkS")
		)
		(fp_line
			(start 1.38176 -1.100074)
			(end 0.592074 -1.100074)
			(stroke
				(width 0.1524)
				(type default)
			)
			(layer "F.SilkS")
		)
		(fp_line
			(start 1.38176 1.100074)
			(end 1.38176 -1.100074)
			(stroke
				(width 0.1524)
				(type default)
			)
			(layer "F.SilkS")
		)
		(fp_poly
			(pts
				(xy -1.9431 -0.429768) (xy -1.9431 -0.870204) (xy -1.50241 -0.649986)
			)
			(stroke
				(width 0)
				(type default)
			)
			(fill yes)
			(layer "F.SilkS")
		)
		(fp_line
			(start -0.674878 -1.100074)
			(end -0.674878 1.100074)
			(stroke
				(width 0.1)
				(type default)
			)
			(layer "F.Fab")
		)
		(fp_line
			(start -0.674878 1.100074)
			(end 0.674878 1.100074)
			(stroke
				(width 0.1)
				(type default)
			)
			(layer "F.Fab")
		)
		(fp_line
			(start 0.674878 -1.100074)
			(end -0.674878 -1.100074)
			(stroke
				(width 0.1)
				(type default)
			)
			(layer "F.Fab")
		)
		(fp_line
			(start 0.674878 1.100074)
			(end 0.674878 -1.100074)
			(stroke
				(width 0.1)
				(type default)
			)
			(layer "F.Fab")
		)
		(fp_poly
			(pts
				(xy -1.9431 -0.870204) (xy -1.50241 -0.649986) (xy -1.9431 -0.429768)
			)
			(stroke
				(width 0)
				(type default)
			)
			(fill yes)
			(layer "F.Fab")
		)
		(pad "1" smd rect
			(at -0.94996 -0.649986 270)
			(size 0.4318 0.6096)
			(layers "F.Cu" "F.Mask" "F.Paste")
			(net "OCP_V3_2_PRSNT2_R_N")
		)
		(pad "2" smd rect
			(at -0.94996 0 270)
			(size 0.4318 0.6096)
			(layers "F.Cu" "F.Mask" "F.Paste")
			(net "GND")
		)
		(pad "3" smd rect
			(at -0.94996 0.649986 270)
			(size 0.4318 0.6096)
			(layers "F.Cu" "F.Mask" "F.Paste")
			(net "OCP_V3_2_PRSNT3_R_N")
		)
		(pad "4" smd rect
			(at 0.94996 0.649986 270)
			(size 0.4318 0.6096)
			(layers "F.Cu" "F.Mask" "F.Paste")
			(net "HP_LVC3_OCP_V3_2_PRSNT2_N_R")
		)
		(pad "5" smd rect
			(at 0.94996 0 270)
			(size 0.4318 0.6096)
			(layers "F.Cu" "F.Mask" "F.Paste")
			(net "P3V3_AUX")
		)
		(pad "6" smd rect
			(at 0.94996 -0.649986 270)
			(size 0.4318 0.6096)
			(layers "F.Cu" "F.Mask" "F.Paste")
			(net "HP_LVC3_OCP_V3_2_PRSNT2_N_R")
		)
	)
	(footprint ""
		(layer "F.Cu")
		(at 332.365096 -339.831172 90)
		(property "Reference" "PC84_1"
			(at 0 0 90)
			(layer "F.SilkS")
			(hide yes)
			(effects
				(font
					(size 1.27 1.27)
				)
			)
		)
		(property "Value" ""
			(at 0 0 90)
			(layer "F.Fab")
			(effects
				(font
					(size 1.27 1.27)
				)
			)
		)
		(duplicate_pad_numbers_are_jumpers no)
		(fp_line
			(start 0.7874 -0.4064)
			(end 0.7874 0.4064)
			(stroke
				(width 0.1524)
				(type default)
			)
			(layer "F.SilkS")
		)
		(fp_line
			(start -0.7874 -0.4064)
			(end 0.7874 -0.4064)
			(stroke
				(width 0.1524)
				(type default)
			)
			(layer "F.SilkS")
		)
		(fp_line
			(start 0.7874 0.4064)
			(end -0.7874 0.4064)
			(stroke
				(width 0.1524)
				(type default)
			)
			(layer "F.SilkS")
		)
		(fp_line
			(start -0.7874 0.4064)
			(end -0.7874 -0.4064)
			(stroke
				(width 0.1524)
				(type default)
			)
			(layer "F.SilkS")
		)
		(fp_line
			(start -0.12065 -0.305054)
			(end -0.12065 -0.2794)
			(stroke
				(width 0.1)
				(type default)
			)
			(layer "F.Fab")
		)
		(fp_line
			(start -0.67945 -0.305054)
			(end -0.12065 -0.305054)
			(stroke
				(width 0.1)
				(type default)
			)
			(layer "F.Fab")
		)
		(fp_line
			(start 0.67945 -0.3048)
			(end 0.67945 0.3048)
			(stroke
				(width 0.1)
				(type default)
			)
			(layer "F.Fab")
		)
		(fp_line
			(start 0.12065 -0.3048)
			(end 0.67945 -0.3048)
			(stroke
				(width 0.1)
				(type default)
			)
			(layer "F.Fab")
		)
		(fp_line
			(start 0.12065 -0.2794)
			(end 0.12065 -0.3048)
			(stroke
				(width 0.1)
				(type default)
			)
			(layer "F.Fab")
		)
		(fp_line
			(start -0.12065 -0.2794)
			(end 0.12065 -0.2794)
			(stroke
				(width 0.1)
				(type default)
			)
			(layer "F.Fab")
		)
		(fp_line
			(start 0.120396 0.2794)
			(end -0.12065 0.2794)
			(stroke
				(width 0.1)
				(type default)
			)
			(layer "F.Fab")
		)
		(fp_line
			(start -0.12065 0.2794)
			(end -0.12065 0.3048)
			(stroke
				(width 0.1)
				(type default)
			)
			(layer "F.Fab")
		)
		(fp_line
			(start 0.67945 0.3048)
			(end 0.120396 0.3048)
			(stroke
				(width 0.1)
				(type default)
			)
			(layer "F.Fab")
		)
		(fp_line
			(start 0.120396 0.3048)
			(end 0.120396 0.2794)
			(stroke
				(width 0.1)
				(type default)
			)
			(layer "F.Fab")
		)
		(fp_line
			(start -0.12065 0.3048)
			(end -0.67945 0.3048)
			(stroke
				(width 0.1)
				(type default)
			)
			(layer "F.Fab")
		)
		(fp_line
			(start -0.67945 0.3048)
			(end -0.67945 -0.305054)
			(stroke
				(width 0.1)
				(type default)
			)
			(layer "F.Fab")
		)
		(pad "1" smd circle
			(at -0.40005 0 90)
			(size 0 0)
			(layers "F.Cu" "F.Mask" "F.Paste")
			(net "PVDDCR_CPU1_P0_VCCS")
		)
		(pad "2" smd circle
			(at 0.40005 0 90)
			(size 0 0)
			(layers "F.Cu" "F.Mask" "F.Paste")
			(net "GND")
		)
	)
	(footprint ""
		(layer "F.Cu")
		(at 41.5544 -391.795)
		(property "Reference" "R726"
			(at 0 0 0)
			(layer "F.SilkS")
			(hide yes)
			(effects
				(font
					(size 1.27 1.27)
				)
			)
		)
		(property "Value" ""
			(at 0 0 0)
			(layer "F.Fab")
			(effects
				(font
					(size 1.27 1.27)
				)
			)
		)
		(duplicate_pad_numbers_are_jumpers no)
		(fp_line
			(start -0.32512 -0.175006)
			(end 0.32512 -0.175006)
			(stroke
				(width 0.1)
				(type default)
			)
			(layer "F.Fab")
		)
		(fp_line
			(start -0.32512 0.175006)
			(end -0.32512 -0.175006)
			(stroke
				(width 0.1)
				(type default)
			)
			(layer "F.Fab")
		)
		(fp_line
			(start 0.32512 -0.175006)
			(end 0.32512 0.175006)
			(stroke
				(width 0.1)
				(type default)
			)
			(layer "F.Fab")
		)
		(fp_line
			(start 0.32512 0.175006)
			(end -0.32512 0.175006)
			(stroke
				(width 0.1)
				(type default)
			)
			(layer "F.Fab")
		)
		(pad "1" smd rect
			(at -0.2667 0)
			(size 0.3048 0.381)
			(layers "F.Cu" "F.Mask" "F.Paste")
			(net "JTAG_TEST_MODE_RT_CPU1_P0")
		)
		(pad "2" smd rect
			(at 0.2667 0 180)
			(size 0.3048 0.381)
			(layers "F.Cu" "F.Mask" "F.Paste")
			(net "GND")
		)
	)
	(footprint ""
		(layer "F.Cu")
		(at 16.368268 -128.51511 -90)
		(property "Reference" "R4521"
			(at 0 0 270)
			(layer "F.SilkS")
			(hide yes)
			(effects
				(font
					(size 1.27 1.27)
				)
			)
		)
		(property "Value" ""
			(at 0 0 270)
			(layer "F.Fab")
			(effects
				(font
					(size 1.27 1.27)
				)
			)
		)
		(duplicate_pad_numbers_are_jumpers no)
		(fp_line
			(start -0.7874 0.4064)
			(end -0.7874 -0.4064)
			(stroke
				(width 0.1524)
				(type default)
			)
			(layer "F.SilkS")
		)
		(fp_line
			(start 0.7874 0.4064)
			(end -0.7874 0.4064)
			(stroke
				(width 0.1524)
				(type default)
			)
			(layer "F.SilkS")
		)
		(fp_line
			(start -0.7874 -0.4064)
			(end 0.7874 -0.4064)
			(stroke
				(width 0.1524)
				(type default)
			)
			(layer "F.SilkS")
		)
		(fp_line
			(start 0.7874 -0.4064)
			(end 0.7874 0.4064)
			(stroke
				(width 0.1524)
				(type default)
			)
			(layer "F.SilkS")
		)
		(fp_line
			(start -0.67945 0.3048)
			(end -0.67945 -0.305054)
			(stroke
				(width 0.1)
				(type default)
			)
			(layer "F.Fab")
		)
		(fp_line
			(start -0.12065 0.3048)
			(end -0.67945 0.3048)
			(stroke
				(width 0.1)
				(type default)
			)
			(layer "F.Fab")
		)
		(fp_line
			(start 0.120396 0.3048)
			(end 0.120396 0.2794)
			(stroke
				(width 0.1)
				(type default)
			)
			(layer "F.Fab")
		)
		(fp_line
			(start 0.67945 0.3048)
			(end 0.120396 0.3048)
			(stroke
				(width 0.1)
				(type default)
			)
			(layer "F.Fab")
		)
		(fp_line
			(start -0.12065 0.2794)
			(end -0.12065 0.3048)
			(stroke
				(width 0.1)
				(type default)
			)
			(layer "F.Fab")
		)
		(fp_line
			(start 0.120396 0.2794)
			(end -0.12065 0.2794)
			(stroke
				(width 0.1)
				(type default)
			)
			(layer "F.Fab")
		)
		(fp_line
			(start -0.12065 -0.2794)
			(end 0.12065 -0.2794)
			(stroke
				(width 0.1)
				(type default)
			)
			(layer "F.Fab")
		)
		(fp_line
			(start 0.12065 -0.2794)
			(end 0.12065 -0.3048)
			(stroke
				(width 0.1)
				(type default)
			)
			(layer "F.Fab")
		)
		(fp_line
			(start 0.12065 -0.3048)
			(end 0.67945 -0.3048)
			(stroke
				(width 0.1)
				(type default)
			)
			(layer "F.Fab")
		)
		(fp_line
			(start 0.67945 -0.3048)
			(end 0.67945 0.3048)
			(stroke
				(width 0.1)
				(type default)
			)
			(layer "F.Fab")
		)
		(fp_line
			(start -0.67945 -0.305054)
			(end -0.12065 -0.305054)
			(stroke
				(width 0.1)
				(type default)
			)
			(layer "F.Fab")
		)
		(fp_line
			(start -0.12065 -0.305054)
			(end -0.12065 -0.2794)
			(stroke
				(width 0.1)
				(type default)
			)
			(layer "F.Fab")
		)
		(pad "1" smd circle
			(at -0.40005 0 270)
			(size 0 0)
			(layers "F.Cu" "F.Mask" "F.Paste")
			(net "P3V3_AUX")
		)
		(pad "2" smd circle
			(at 0.40005 0 270)
			(size 0 0)
			(layers "F.Cu" "F.Mask" "F.Paste")
			(net "CLK_GEN2_BMC_RC_OE_N")
		)
	)
	(footprint ""
		(layer "F.Cu")
		(at 266.862306 -332.015846)
		(property "Reference" "TP5"
			(at -5.423916 0.05207 0)
			(unlocked yes)
			(layer "F.SilkS")
			(effects
				(font
					(size 0.7874 0.5842)
					(thickness 0.1524)
				)
				(justify left)
			)
		)
		(property "Value" ""
			(at 0 0 0)
			(layer "F.Fab")
			(effects
				(font
					(size 1.27 1.27)
				)
			)
		)
		(duplicate_pad_numbers_are_jumpers no)
		(pad "1" smd circle
			(at 0 0)
			(size 0.762 0.762)
			(layers "F.Cu" "F.Mask" "F.Paste")
			(net "VSENSE_PVDDIO_P0_DP")
		)
	)
	(footprint ""
		(layer "F.Cu")
		(at 430.277016 -101.97719 180)
		(property "Reference" "R3783"
			(at 0 0 180)
			(layer "F.SilkS")
			(hide yes)
			(effects
				(font
					(size 1.27 1.27)
				)
			)
		)
		(property "Value" ""
			(at 0 0 180)
			(layer "F.Fab")
			(effects
				(font
					(size 1.27 1.27)
				)
			)
		)
		(duplicate_pad_numbers_are_jumpers no)
		(fp_line
			(start 0.7874 0.4064)
			(end -0.7874 0.4064)
			(stroke
				(width 0.1524)
				(type default)
			)
			(layer "F.SilkS")
		)
		(fp_line
			(start 0.7874 -0.4064)
			(end 0.7874 0.4064)
			(stroke
				(width 0.1524)
				(type default)
			)
			(layer "F.SilkS")
		)
		(fp_line
			(start -0.7874 0.4064)
			(end -0.7874 -0.4064)
			(stroke
				(width 0.1524)
				(type default)
			)
			(layer "F.SilkS")
		)
		(fp_line
			(start -0.7874 -0.4064)
			(end 0.7874 -0.4064)
			(stroke
				(width 0.1524)
				(type default)
			)
			(layer "F.SilkS")
		)
		(fp_line
			(start 0.67945 0.3048)
			(end 0.120396 0.3048)
			(stroke
				(width 0.1)
				(type default)
			)
			(layer "F.Fab")
		)
		(fp_line
			(start 0.67945 -0.3048)
			(end 0.67945 0.3048)
			(stroke
				(width 0.1)
				(type default)
			)
			(layer "F.Fab")
		)
		(fp_line
			(start 0.12065 -0.2794)
			(end 0.12065 -0.3048)
			(stroke
				(width 0.1)
				(type default)
			)
			(layer "F.Fab")
		)
		(fp_line
			(start 0.12065 -0.3048)
			(end 0.67945 -0.3048)
			(stroke
				(width 0.1)
				(type default)
			)
			(layer "F.Fab")
		)
		(fp_line
			(start 0.120396 0.3048)
			(end 0.120396 0.2794)
			(stroke
				(width 0.1)
				(type default)
			)
			(layer "F.Fab")
		)
		(fp_line
			(start 0.120396 0.2794)
			(end -0.12065 0.2794)
			(stroke
				(width 0.1)
				(type default)
			)
			(layer "F.Fab")
		)
		(fp_line
			(start -0.12065 0.3048)
			(end -0.67945 0.3048)
			(stroke
				(width 0.1)
				(type default)
			)
			(layer "F.Fab")
		)
		(fp_line
			(start -0.12065 0.2794)
			(end -0.12065 0.3048)
			(stroke
				(width 0.1)
				(type default)
			)
			(layer "F.Fab")
		)
		(fp_line
			(start -0.12065 -0.2794)
			(end 0.12065 -0.2794)
			(stroke
				(width 0.1)
				(type default)
			)
			(layer "F.Fab")
		)
		(fp_line
			(start -0.12065 -0.305054)
			(end -0.12065 -0.2794)
			(stroke
				(width 0.1)
				(type default)
			)
			(layer "F.Fab")
		)
		(fp_line
			(start -0.67945 0.3048)
			(end -0.67945 -0.305054)
			(stroke
				(width 0.1)
				(type default)
			)
			(layer "F.Fab")
		)
		(fp_line
			(start -0.67945 -0.305054)
			(end -0.12065 -0.305054)
			(stroke
				(width 0.1)
				(type default)
			)
			(layer "F.Fab")
		)
		(pad "1" smd circle
			(at -0.40005 0 180)
			(size 0 0)
			(layers "F.Cu" "F.Mask" "F.Paste")
			(net "P3V3_AUX")
		)
		(pad "2" smd circle
			(at 0.40005 0 180)
			(size 0 0)
			(layers "F.Cu" "F.Mask" "F.Paste")
			(net "OCP_V3_1_P3V3_PWRGD")
		)
	)
	(footprint ""
		(layer "F.Cu")
		(at 331.494892 -390.77646 180)
		(property "Reference" "C965"
			(at 0 0 180)
			(layer "F.SilkS")
			(hide yes)
			(effects
				(font
					(size 1.27 1.27)
				)
			)
		)
		(property "Value" ""
			(at 0 0 180)
			(layer "F.Fab")
			(effects
				(font
					(size 1.27 1.27)
				)
			)
		)
		(duplicate_pad_numbers_are_jumpers no)
		(fp_line
			(start 0.299974 0.150114)
			(end -0.299974 0.150114)
			(stroke
				(width 0.1)
				(type default)
			)
			(layer "F.Fab")
		)
		(fp_line
			(start 0.299974 -0.150114)
			(end 0.299974 0.150114)
			(stroke
				(width 0.1)
				(type default)
			)
			(layer "F.Fab")
		)
		(fp_line
			(start -0.299974 0.150114)
			(end -0.299974 -0.150114)
			(stroke
				(width 0.1)
				(type default)
			)
			(layer "F.Fab")
		)
		(fp_line
			(start -0.299974 -0.150114)
			(end 0.299974 -0.150114)
			(stroke
				(width 0.1)
				(type default)
			)
			(layer "F.Fab")
		)
		(pad "1" smd rect
			(at -0.2667 0 180)
			(size 0.3048 0.381)
			(layers "F.Cu" "F.Mask" "F.Paste")
			(net "P5E_CPU0_P1_TX_C_DP<0>")
		)
		(pad "2" smd rect
			(at 0.2667 0 180)
			(size 0.3048 0.381)
			(layers "F.Cu" "F.Mask" "F.Paste")
			(net "P5E_CPU0_P1_TX_DP<0>")
		)
	)
	(footprint ""
		(layer "F.Cu")
		(at 205.693518 -143.112998 90)
		(property "Reference" "R2529"
			(at 0 0 90)
			(layer "F.SilkS")
			(hide yes)
			(effects
				(font
					(size 1.27 1.27)
				)
			)
		)
		(property "Value" ""
			(at 0 0 90)
			(layer "F.Fab")
			(effects
				(font
					(size 1.27 1.27)
				)
			)
		)
		(duplicate_pad_numbers_are_jumpers no)
		(fp_line
			(start 0.7874 -0.4064)
			(end 0.7874 0.4064)
			(stroke
				(width 0.1524)
				(type default)
			)
			(layer "F.SilkS")
		)
		(fp_line
			(start -0.7874 -0.4064)
			(end 0.7874 -0.4064)
			(stroke
				(width 0.1524)
				(type default)
			)
			(layer "F.SilkS")
		)
		(fp_line
			(start 0.7874 0.4064)
			(end -0.7874 0.4064)
			(stroke
				(width 0.1524)
				(type default)
			)
			(layer "F.SilkS")
		)
		(fp_line
			(start -0.7874 0.4064)
			(end -0.7874 -0.4064)
			(stroke
				(width 0.1524)
				(type default)
			)
			(layer "F.SilkS")
		)
		(fp_line
			(start -0.12065 -0.305054)
			(end -0.12065 -0.2794)
			(stroke
				(width 0.1)
				(type default)
			)
			(layer "F.Fab")
		)
		(fp_line
			(start -0.67945 -0.305054)
			(end -0.12065 -0.305054)
			(stroke
				(width 0.1)
				(type default)
			)
			(layer "F.Fab")
		)
		(fp_line
			(start 0.67945 -0.3048)
			(end 0.67945 0.3048)
			(stroke
				(width 0.1)
				(type default)
			)
			(layer "F.Fab")
		)
		(fp_line
			(start 0.12065 -0.3048)
			(end 0.67945 -0.3048)
			(stroke
				(width 0.1)
				(type default)
			)
			(layer "F.Fab")
		)
		(fp_line
			(start 0.12065 -0.2794)
			(end 0.12065 -0.3048)
			(stroke
				(width 0.1)
				(type default)
			)
			(layer "F.Fab")
		)
		(fp_line
			(start -0.12065 -0.2794)
			(end 0.12065 -0.2794)
			(stroke
				(width 0.1)
				(type default)
			)
			(layer "F.Fab")
		)
		(fp_line
			(start 0.120396 0.2794)
			(end -0.12065 0.2794)
			(stroke
				(width 0.1)
				(type default)
			)
			(layer "F.Fab")
		)
		(fp_line
			(start -0.12065 0.2794)
			(end -0.12065 0.3048)
			(stroke
				(width 0.1)
				(type default)
			)
			(layer "F.Fab")
		)
		(fp_line
			(start 0.67945 0.3048)
			(end 0.120396 0.3048)
			(stroke
				(width 0.1)
				(type default)
			)
			(layer "F.Fab")
		)
		(fp_line
			(start 0.120396 0.3048)
			(end 0.120396 0.2794)
			(stroke
				(width 0.1)
				(type default)
			)
			(layer "F.Fab")
		)
		(fp_line
			(start -0.12065 0.3048)
			(end -0.67945 0.3048)
			(stroke
				(width 0.1)
				(type default)
			)
			(layer "F.Fab")
		)
		(fp_line
			(start -0.67945 0.3048)
			(end -0.67945 -0.305054)
			(stroke
				(width 0.1)
				(type default)
			)
			(layer "F.Fab")
		)
		(pad "1" smd circle
			(at -0.40005 0 90)
			(size 0 0)
			(layers "F.Cu" "F.Mask" "F.Paste")
			(net "FM_P12V_HSC_EN_N")
		)
		(pad "2" smd circle
			(at 0.40005 0 90)
			(size 0 0)
			(layers "F.Cu" "F.Mask" "F.Paste")
			(net "FM_P12V_HSC_EN_R_N")
		)
	)
	(footprint ""
		(layer "F.Cu")
		(at 188.143642 -413.64408 90)
		(property "Reference" "R9012"
			(at 0 0 90)
			(layer "F.SilkS")
			(hide yes)
			(effects
				(font
					(size 1.27 1.27)
				)
			)
		)
		(property "Value" ""
			(at 0 0 90)
			(layer "F.Fab")
			(effects
				(font
					(size 1.27 1.27)
				)
			)
		)
		(duplicate_pad_numbers_are_jumpers no)
		(fp_line
			(start 0.7874 -0.4064)
			(end 0.7874 0.4064)
			(stroke
				(width 0.1524)
				(type default)
			)
			(layer "F.SilkS")
		)
		(fp_line
			(start -0.7874 -0.4064)
			(end 0.7874 -0.4064)
			(stroke
				(width 0.1524)
				(type default)
			)
			(layer "F.SilkS")
		)
		(fp_line
			(start 0.7874 0.4064)
			(end -0.7874 0.4064)
			(stroke
				(width 0.1524)
				(type default)
			)
			(layer "F.SilkS")
		)
		(fp_line
			(start -0.7874 0.4064)
			(end -0.7874 -0.4064)
			(stroke
				(width 0.1524)
				(type default)
			)
			(layer "F.SilkS")
		)
		(fp_line
			(start -0.12065 -0.305054)
			(end -0.12065 -0.2794)
			(stroke
				(width 0.1)
				(type default)
			)
			(layer "F.Fab")
		)
		(fp_line
			(start -0.67945 -0.305054)
			(end -0.12065 -0.305054)
			(stroke
				(width 0.1)
				(type default)
			)
			(layer "F.Fab")
		)
		(fp_line
			(start 0.67945 -0.3048)
			(end 0.67945 0.3048)
			(stroke
				(width 0.1)
				(type default)
			)
			(layer "F.Fab")
		)
		(fp_line
			(start 0.12065 -0.3048)
			(end 0.67945 -0.3048)
			(stroke
				(width 0.1)
				(type default)
			)
			(layer "F.Fab")
		)
		(fp_line
			(start 0.12065 -0.2794)
			(end 0.12065 -0.3048)
			(stroke
				(width 0.1)
				(type default)
			)
			(layer "F.Fab")
		)
		(fp_line
			(start -0.12065 -0.2794)
			(end 0.12065 -0.2794)
			(stroke
				(width 0.1)
				(type default)
			)
			(layer "F.Fab")
		)
		(fp_line
			(start 0.120396 0.2794)
			(end -0.12065 0.2794)
			(stroke
				(width 0.1)
				(type default)
			)
			(layer "F.Fab")
		)
		(fp_line
			(start -0.12065 0.2794)
			(end -0.12065 0.3048)
			(stroke
				(width 0.1)
				(type default)
			)
			(layer "F.Fab")
		)
		(fp_line
			(start 0.67945 0.3048)
			(end 0.120396 0.3048)
			(stroke
				(width 0.1)
				(type default)
			)
			(layer "F.Fab")
		)
		(fp_line
			(start 0.120396 0.3048)
			(end 0.120396 0.2794)
			(stroke
				(width 0.1)
				(type default)
			)
			(layer "F.Fab")
		)
		(fp_line
			(start -0.12065 0.3048)
			(end -0.67945 0.3048)
			(stroke
				(width 0.1)
				(type default)
			)
			(layer "F.Fab")
		)
		(fp_line
			(start -0.67945 0.3048)
			(end -0.67945 -0.305054)
			(stroke
				(width 0.1)
				(type default)
			)
			(layer "F.Fab")
		)
		(pad "1" smd circle
			(at -0.40005 0 90)
			(size 0 0)
			(layers "F.Cu" "F.Mask" "F.Paste")
			(net "PRSNT_CABLE_SWB_B2_ISO_N")
		)
		(pad "2" smd circle
			(at 0.40005 0 90)
			(size 0 0)
			(layers "F.Cu" "F.Mask" "F.Paste")
			(net "PRSNT_CABLE_SWB_B2_ISO_R_N")
		)
	)
	(footprint ""
		(layer "F.Cu")
		(at 105.191814 -36.6522)
		(property "Reference" "R6323"
			(at 0 0 0)
			(layer "F.SilkS")
			(hide yes)
			(effects
				(font
					(size 1.27 1.27)
				)
			)
		)
		(property "Value" ""
			(at 0 0 0)
			(layer "F.Fab")
			(effects
				(font
					(size 1.27 1.27)
				)
			)
		)
		(duplicate_pad_numbers_are_jumpers no)
		(fp_line
			(start -0.7874 -0.4064)
			(end 0.7874 -0.4064)
			(stroke
				(width 0.1524)
				(type default)
			)
			(layer "F.SilkS")
		)
		(fp_line
			(start -0.7874 0.4064)
			(end -0.7874 -0.4064)
			(stroke
				(width 0.1524)
				(type default)
			)
			(layer "F.SilkS")
		)
		(fp_line
			(start 0.7874 -0.4064)
			(end 0.7874 0.4064)
			(stroke
				(width 0.1524)
				(type default)
			)
			(layer "F.SilkS")
		)
		(fp_line
			(start 0.7874 0.4064)
			(end -0.7874 0.4064)
			(stroke
				(width 0.1524)
				(type default)
			)
			(layer "F.SilkS")
		)
		(fp_line
			(start -0.67945 -0.305054)
			(end -0.12065 -0.305054)
			(stroke
				(width 0.1)
				(type default)
			)
			(layer "F.Fab")
		)
		(fp_line
			(start -0.67945 0.3048)
			(end -0.67945 -0.305054)
			(stroke
				(width 0.1)
				(type default)
			)
			(layer "F.Fab")
		)
		(fp_line
			(start -0.12065 -0.305054)
			(end -0.12065 -0.2794)
			(stroke
				(width 0.1)
				(type default)
			)
			(layer "F.Fab")
		)
		(fp_line
			(start -0.12065 -0.2794)
			(end 0.12065 -0.2794)
			(stroke
				(width 0.1)
				(type default)
			)
			(layer "F.Fab")
		)
		(fp_line
			(start -0.12065 0.2794)
			(end -0.12065 0.3048)
			(stroke
				(width 0.1)
				(type default)
			)
			(layer "F.Fab")
		)
		(fp_line
			(start -0.12065 0.3048)
			(end -0.67945 0.3048)
			(stroke
				(width 0.1)
				(type default)
			)
			(layer "F.Fab")
		)
		(fp_line
			(start 0.120396 0.2794)
			(end -0.12065 0.2794)
			(stroke
				(width 0.1)
				(type default)
			)
			(layer "F.Fab")
		)
		(fp_line
			(start 0.120396 0.3048)
			(end 0.120396 0.2794)
			(stroke
				(width 0.1)
				(type default)
			)
			(layer "F.Fab")
		)
		(fp_line
			(start 0.12065 -0.3048)
			(end 0.67945 -0.3048)
			(stroke
				(width 0.1)
				(type default)
			)
			(layer "F.Fab")
		)
		(fp_line
			(start 0.12065 -0.2794)
			(end 0.12065 -0.3048)
			(stroke
				(width 0.1)
				(type default)
			)
			(layer "F.Fab")
		)
		(fp_line
			(start 0.67945 -0.3048)
			(end 0.67945 0.3048)
			(stroke
				(width 0.1)
				(type default)
			)
			(layer "F.Fab")
		)
		(fp_line
			(start 0.67945 0.3048)
			(end 0.120396 0.3048)
			(stroke
				(width 0.1)
				(type default)
			)
			(layer "F.Fab")
		)
		(pad "1" smd circle
			(at -0.40005 0)
			(size 0 0)
			(layers "F.Cu" "F.Mask" "F.Paste")
			(net "USB_HUB2_TI_TEST")
		)
		(pad "2" smd circle
			(at 0.40005 0)
			(size 0 0)
			(layers "F.Cu" "F.Mask" "F.Paste")
			(net "USB_HUB2_TI_TEST_MRP_PROG_FUNC6")
		)
	)
	(footprint ""
		(layer "F.Cu")
		(at 14.265402 -105.537762 90)
		(property "Reference" "R4419"
			(at 0 0 90)
			(layer "F.SilkS")
			(hide yes)
			(effects
				(font
					(size 1.27 1.27)
				)
			)
		)
		(property "Value" ""
			(at 0 0 90)
			(layer "F.Fab")
			(effects
				(font
					(size 1.27 1.27)
				)
			)
		)
		(duplicate_pad_numbers_are_jumpers no)
		(fp_line
			(start 0.7874 -0.4064)
			(end 0.7874 0.4064)
			(stroke
				(width 0.1524)
				(type default)
			)
			(layer "F.SilkS")
		)
		(fp_line
			(start -0.7874 -0.4064)
			(end 0.7874 -0.4064)
			(stroke
				(width 0.1524)
				(type default)
			)
			(layer "F.SilkS")
		)
		(fp_line
			(start 0.7874 0.4064)
			(end -0.7874 0.4064)
			(stroke
				(width 0.1524)
				(type default)
			)
			(layer "F.SilkS")
		)
		(fp_line
			(start -0.7874 0.4064)
			(end -0.7874 -0.4064)
			(stroke
				(width 0.1524)
				(type default)
			)
			(layer "F.SilkS")
		)
		(fp_line
			(start -0.12065 -0.305054)
			(end -0.12065 -0.2794)
			(stroke
				(width 0.1)
				(type default)
			)
			(layer "F.Fab")
		)
		(fp_line
			(start -0.67945 -0.305054)
			(end -0.12065 -0.305054)
			(stroke
				(width 0.1)
				(type default)
			)
			(layer "F.Fab")
		)
		(fp_line
			(start 0.67945 -0.3048)
			(end 0.67945 0.3048)
			(stroke
				(width 0.1)
				(type default)
			)
			(layer "F.Fab")
		)
		(fp_line
			(start 0.12065 -0.3048)
			(end 0.67945 -0.3048)
			(stroke
				(width 0.1)
				(type default)
			)
			(layer "F.Fab")
		)
		(fp_line
			(start 0.12065 -0.2794)
			(end 0.12065 -0.3048)
			(stroke
				(width 0.1)
				(type default)
			)
			(layer "F.Fab")
		)
		(fp_line
			(start -0.12065 -0.2794)
			(end 0.12065 -0.2794)
			(stroke
				(width 0.1)
				(type default)
			)
			(layer "F.Fab")
		)
		(fp_line
			(start 0.120396 0.2794)
			(end -0.12065 0.2794)
			(stroke
				(width 0.1)
				(type default)
			)
			(layer "F.Fab")
		)
		(fp_line
			(start -0.12065 0.2794)
			(end -0.12065 0.3048)
			(stroke
				(width 0.1)
				(type default)
			)
			(layer "F.Fab")
		)
		(fp_line
			(start 0.67945 0.3048)
			(end 0.120396 0.3048)
			(stroke
				(width 0.1)
				(type default)
			)
			(layer "F.Fab")
		)
		(fp_line
			(start 0.120396 0.3048)
			(end 0.120396 0.2794)
			(stroke
				(width 0.1)
				(type default)
			)
			(layer "F.Fab")
		)
		(fp_line
			(start -0.12065 0.3048)
			(end -0.67945 0.3048)
			(stroke
				(width 0.1)
				(type default)
			)
			(layer "F.Fab")
		)
		(fp_line
			(start -0.67945 0.3048)
			(end -0.67945 -0.305054)
			(stroke
				(width 0.1)
				(type default)
			)
			(layer "F.Fab")
		)
		(pad "1" smd circle
			(at -0.40005 0 90)
			(size 0 0)
			(layers "F.Cu" "F.Mask" "F.Paste")
			(net "USB2_HOST_BMC_B_DP")
		)
		(pad "2" smd circle
			(at 0.40005 0 90)
			(size 0 0)
			(layers "F.Cu" "F.Mask" "F.Paste")
			(net "GND")
		)
	)
	(footprint ""
		(layer "F.Cu")
		(at 452.13905 -47.475394 180)
		(property "Reference" "PC1870"
			(at 0 0 180)
			(layer "F.SilkS")
			(hide yes)
			(effects
				(font
					(size 1.27 1.27)
				)
			)
		)
		(property "Value" ""
			(at 0 0 180)
			(layer "F.Fab")
			(effects
				(font
					(size 1.27 1.27)
				)
			)
		)
		(duplicate_pad_numbers_are_jumpers no)
		(fp_line
			(start 0.7874 0.4064)
			(end -0.7874 0.4064)
			(stroke
				(width 0.1524)
				(type default)
			)
			(layer "F.SilkS")
		)
		(fp_line
			(start 0.7874 -0.4064)
			(end 0.7874 0.4064)
			(stroke
				(width 0.1524)
				(type default)
			)
			(layer "F.SilkS")
		)
		(fp_line
			(start -0.7874 0.4064)
			(end -0.7874 -0.4064)
			(stroke
				(width 0.1524)
				(type default)
			)
			(layer "F.SilkS")
		)
		(fp_line
			(start -0.7874 -0.4064)
			(end 0.7874 -0.4064)
			(stroke
				(width 0.1524)
				(type default)
			)
			(layer "F.SilkS")
		)
		(fp_line
			(start 0.67945 0.3048)
			(end 0.120396 0.3048)
			(stroke
				(width 0.1)
				(type default)
			)
			(layer "F.Fab")
		)
		(fp_line
			(start 0.67945 -0.3048)
			(end 0.67945 0.3048)
			(stroke
				(width 0.1)
				(type default)
			)
			(layer "F.Fab")
		)
		(fp_line
			(start 0.12065 -0.2794)
			(end 0.12065 -0.3048)
			(stroke
				(width 0.1)
				(type default)
			)
			(layer "F.Fab")
		)
		(fp_line
			(start 0.12065 -0.3048)
			(end 0.67945 -0.3048)
			(stroke
				(width 0.1)
				(type default)
			)
			(layer "F.Fab")
		)
		(fp_line
			(start 0.120396 0.3048)
			(end 0.120396 0.2794)
			(stroke
				(width 0.1)
				(type default)
			)
			(layer "F.Fab")
		)
		(fp_line
			(start 0.120396 0.2794)
			(end -0.12065 0.2794)
			(stroke
				(width 0.1)
				(type default)
			)
			(layer "F.Fab")
		)
		(fp_line
			(start -0.12065 0.3048)
			(end -0.67945 0.3048)
			(stroke
				(width 0.1)
				(type default)
			)
			(layer "F.Fab")
		)
		(fp_line
			(start -0.12065 0.2794)
			(end -0.12065 0.3048)
			(stroke
				(width 0.1)
				(type default)
			)
			(layer "F.Fab")
		)
		(fp_line
			(start -0.12065 -0.2794)
			(end 0.12065 -0.2794)
			(stroke
				(width 0.1)
				(type default)
			)
			(layer "F.Fab")
		)
		(fp_line
			(start -0.12065 -0.305054)
			(end -0.12065 -0.2794)
			(stroke
				(width 0.1)
				(type default)
			)
			(layer "F.Fab")
		)
		(fp_line
			(start -0.67945 0.3048)
			(end -0.67945 -0.305054)
			(stroke
				(width 0.1)
				(type default)
			)
			(layer "F.Fab")
		)
		(fp_line
			(start -0.67945 -0.305054)
			(end -0.12065 -0.305054)
			(stroke
				(width 0.1)
				(type default)
			)
			(layer "F.Fab")
		)
		(pad "1" smd circle
			(at -0.40005 0 180)
			(size 0 0)
			(layers "F.Cu" "F.Mask" "F.Paste")
			(net "P3V3_AUX_EN")
		)
		(pad "2" smd circle
			(at 0.40005 0 180)
			(size 0 0)
			(layers "F.Cu" "F.Mask" "F.Paste")
			(net "GND")
		)
	)
	(footprint ""
		(layer "F.Cu")
		(at 425.36872 -384.449828)
		(property "Reference" "C841"
			(at 0 0 0)
			(layer "F.SilkS")
			(hide yes)
			(effects
				(font
					(size 1.27 1.27)
				)
			)
		)
		(property "Value" ""
			(at 0 0 0)
			(layer "F.Fab")
			(effects
				(font
					(size 1.27 1.27)
				)
			)
		)
		(duplicate_pad_numbers_are_jumpers no)
		(fp_line
			(start -0.299974 -0.150114)
			(end 0.299974 -0.150114)
			(stroke
				(width 0.1)
				(type default)
			)
			(layer "F.Fab")
		)
		(fp_line
			(start -0.299974 0.150114)
			(end -0.299974 -0.150114)
			(stroke
				(width 0.1)
				(type default)
			)
			(layer "F.Fab")
		)
		(fp_line
			(start 0.299974 -0.150114)
			(end 0.299974 0.150114)
			(stroke
				(width 0.1)
				(type default)
			)
			(layer "F.Fab")
		)
		(fp_line
			(start 0.299974 0.150114)
			(end -0.299974 0.150114)
			(stroke
				(width 0.1)
				(type default)
			)
			(layer "F.Fab")
		)
		(pad "1" smd rect
			(at -0.2667 0)
			(size 0.3048 0.381)
			(layers "F.Cu" "F.Mask" "F.Paste")
			(net "P5E_CPU0_P2_TX_C_DP<14>")
		)
		(pad "2" smd rect
			(at 0.2667 0)
			(size 0.3048 0.381)
			(layers "F.Cu" "F.Mask" "F.Paste")
			(net "P5E_CPU0_P2_TX_DP<14>")
		)
	)
	(footprint ""
		(layer "F.Cu")
		(at 254.592836 -113.32845)
		(property "Reference" "R3729"
			(at 0 0 0)
			(layer "F.SilkS")
			(hide yes)
			(effects
				(font
					(size 1.27 1.27)
				)
			)
		)
		(property "Value" ""
			(at 0 0 0)
			(layer "F.Fab")
			(effects
				(font
					(size 1.27 1.27)
				)
			)
		)
		(duplicate_pad_numbers_are_jumpers no)
		(fp_line
			(start -0.7874 -0.4064)
			(end 0.7874 -0.4064)
			(stroke
				(width 0.1524)
				(type default)
			)
			(layer "F.SilkS")
		)
		(fp_line
			(start -0.7874 0.4064)
			(end -0.7874 -0.4064)
			(stroke
				(width 0.1524)
				(type default)
			)
			(layer "F.SilkS")
		)
		(fp_line
			(start 0.7874 -0.4064)
			(end 0.7874 0.4064)
			(stroke
				(width 0.1524)
				(type default)
			)
			(layer "F.SilkS")
		)
		(fp_line
			(start 0.7874 0.4064)
			(end -0.7874 0.4064)
			(stroke
				(width 0.1524)
				(type default)
			)
			(layer "F.SilkS")
		)
		(fp_line
			(start -0.67945 -0.305054)
			(end -0.12065 -0.305054)
			(stroke
				(width 0.1)
				(type default)
			)
			(layer "F.Fab")
		)
		(fp_line
			(start -0.67945 0.3048)
			(end -0.67945 -0.305054)
			(stroke
				(width 0.1)
				(type default)
			)
			(layer "F.Fab")
		)
		(fp_line
			(start -0.12065 -0.305054)
			(end -0.12065 -0.2794)
			(stroke
				(width 0.1)
				(type default)
			)
			(layer "F.Fab")
		)
		(fp_line
			(start -0.12065 -0.2794)
			(end 0.12065 -0.2794)
			(stroke
				(width 0.1)
				(type default)
			)
			(layer "F.Fab")
		)
		(fp_line
			(start -0.12065 0.2794)
			(end -0.12065 0.3048)
			(stroke
				(width 0.1)
				(type default)
			)
			(layer "F.Fab")
		)
		(fp_line
			(start -0.12065 0.3048)
			(end -0.67945 0.3048)
			(stroke
				(width 0.1)
				(type default)
			)
			(layer "F.Fab")
		)
		(fp_line
			(start 0.120396 0.2794)
			(end -0.12065 0.2794)
			(stroke
				(width 0.1)
				(type default)
			)
			(layer "F.Fab")
		)
		(fp_line
			(start 0.120396 0.3048)
			(end 0.120396 0.2794)
			(stroke
				(width 0.1)
				(type default)
			)
			(layer "F.Fab")
		)
		(fp_line
			(start 0.12065 -0.3048)
			(end 0.67945 -0.3048)
			(stroke
				(width 0.1)
				(type default)
			)
			(layer "F.Fab")
		)
		(fp_line
			(start 0.12065 -0.2794)
			(end 0.12065 -0.3048)
			(stroke
				(width 0.1)
				(type default)
			)
			(layer "F.Fab")
		)
		(fp_line
			(start 0.67945 -0.3048)
			(end 0.67945 0.3048)
			(stroke
				(width 0.1)
				(type default)
			)
			(layer "F.Fab")
		)
		(fp_line
			(start 0.67945 0.3048)
			(end 0.120396 0.3048)
			(stroke
				(width 0.1)
				(type default)
			)
			(layer "F.Fab")
		)
		(pad "1" smd circle
			(at -0.40005 0)
			(size 0 0)
			(layers "F.Cu" "F.Mask" "F.Paste")
			(net "P3V3_AUX")
		)
		(pad "2" smd circle
			(at 0.40005 0)
			(size 0 0)
			(layers "F.Cu" "F.Mask" "F.Paste")
			(net "SMB_LM75_2_3V3AUX_SCL")
		)
	)
	(footprint ""
		(layer "F.Cu")
		(at 18.302478 -17.623536 90)
		(property "Reference" "C680"
			(at 0 0 90)
			(layer "F.SilkS")
			(hide yes)
			(effects
				(font
					(size 1.27 1.27)
				)
			)
		)
		(property "Value" ""
			(at 0 0 90)
			(layer "F.Fab")
			(effects
				(font
					(size 1.27 1.27)
				)
			)
		)
		(duplicate_pad_numbers_are_jumpers no)
		(fp_line
			(start 0.299974 -0.150114)
			(end 0.299974 0.150114)
			(stroke
				(width 0.1)
				(type default)
			)
			(layer "F.Fab")
		)
		(fp_line
			(start -0.299974 -0.150114)
			(end 0.299974 -0.150114)
			(stroke
				(width 0.1)
				(type default)
			)
			(layer "F.Fab")
		)
		(fp_line
			(start 0.299974 0.150114)
			(end -0.299974 0.150114)
			(stroke
				(width 0.1)
				(type default)
			)
			(layer "F.Fab")
		)
		(fp_line
			(start -0.299974 0.150114)
			(end -0.299974 -0.150114)
			(stroke
				(width 0.1)
				(type default)
			)
			(layer "F.Fab")
		)
		(pad "1" smd rect
			(at -0.2667 0 90)
			(size 0.3048 0.381)
			(layers "F.Cu" "F.Mask" "F.Paste")
			(net "P5E_CPU1_G1_TX_C_DN<14>")
		)
		(pad "2" smd rect
			(at 0.2667 0 90)
			(size 0.3048 0.381)
			(layers "F.Cu" "F.Mask" "F.Paste")
			(net "P5E_CPU1_G1_TX_DN<14>")
		)
	)
	(footprint ""
		(layer "F.Cu")
		(at 76.53401 -24.713946 -90)
		(property "Reference" "PC2139"
			(at 0 0 270)
			(layer "F.SilkS")
			(hide yes)
			(effects
				(font
					(size 1.27 1.27)
				)
			)
		)
		(property "Value" ""
			(at 0 0 270)
			(layer "F.Fab")
			(effects
				(font
					(size 1.27 1.27)
				)
			)
		)
		(duplicate_pad_numbers_are_jumpers no)
		(fp_line
			(start -0.7874 0.4064)
			(end -0.7874 -0.4064)
			(stroke
				(width 0.1524)
				(type default)
			)
			(layer "F.SilkS")
		)
		(fp_line
			(start 0.7874 0.4064)
			(end -0.7874 0.4064)
			(stroke
				(width 0.1524)
				(type default)
			)
			(layer "F.SilkS")
		)
		(fp_line
			(start -0.7874 -0.4064)
			(end 0.7874 -0.4064)
			(stroke
				(width 0.1524)
				(type default)
			)
			(layer "F.SilkS")
		)
		(fp_line
			(start 0.7874 -0.4064)
			(end 0.7874 0.4064)
			(stroke
				(width 0.1524)
				(type default)
			)
			(layer "F.SilkS")
		)
		(fp_line
			(start -0.67945 0.3048)
			(end -0.67945 -0.305054)
			(stroke
				(width 0.1)
				(type default)
			)
			(layer "F.Fab")
		)
		(fp_line
			(start -0.12065 0.3048)
			(end -0.67945 0.3048)
			(stroke
				(width 0.1)
				(type default)
			)
			(layer "F.Fab")
		)
		(fp_line
			(start 0.120396 0.3048)
			(end 0.120396 0.2794)
			(stroke
				(width 0.1)
				(type default)
			)
			(layer "F.Fab")
		)
		(fp_line
			(start 0.67945 0.3048)
			(end 0.120396 0.3048)
			(stroke
				(width 0.1)
				(type default)
			)
			(layer "F.Fab")
		)
		(fp_line
			(start -0.12065 0.2794)
			(end -0.12065 0.3048)
			(stroke
				(width 0.1)
				(type default)
			)
			(layer "F.Fab")
		)
		(fp_line
			(start 0.120396 0.2794)
			(end -0.12065 0.2794)
			(stroke
				(width 0.1)
				(type default)
			)
			(layer "F.Fab")
		)
		(fp_line
			(start -0.12065 -0.2794)
			(end 0.12065 -0.2794)
			(stroke
				(width 0.1)
				(type default)
			)
			(layer "F.Fab")
		)
		(fp_line
			(start 0.12065 -0.2794)
			(end 0.12065 -0.3048)
			(stroke
				(width 0.1)
				(type default)
			)
			(layer "F.Fab")
		)
		(fp_line
			(start 0.12065 -0.3048)
			(end 0.67945 -0.3048)
			(stroke
				(width 0.1)
				(type default)
			)
			(layer "F.Fab")
		)
		(fp_line
			(start 0.67945 -0.3048)
			(end 0.67945 0.3048)
			(stroke
				(width 0.1)
				(type default)
			)
			(layer "F.Fab")
		)
		(fp_line
			(start -0.67945 -0.305054)
			(end -0.12065 -0.305054)
			(stroke
				(width 0.1)
				(type default)
			)
			(layer "F.Fab")
		)
		(fp_line
			(start -0.12065 -0.305054)
			(end -0.12065 -0.2794)
			(stroke
				(width 0.1)
				(type default)
			)
			(layer "F.Fab")
		)
		(pad "1" smd circle
			(at -0.40005 0 270)
			(size 0 0)
			(layers "F.Cu" "F.Mask" "F.Paste")
			(net "P12V_AUX")
		)
		(pad "2" smd circle
			(at 0.40005 0 270)
			(size 0 0)
			(layers "F.Cu" "F.Mask" "F.Paste")
			(net "GND")
		)
	)
	(footprint ""
		(layer "F.Cu")
		(at 178.689 -406.527)
		(property "Reference" "PR2106"
			(at 0 0 0)
			(layer "F.SilkS")
			(hide yes)
			(effects
				(font
					(size 1.27 1.27)
				)
			)
		)
		(property "Value" ""
			(at 0 0 0)
			(layer "F.Fab")
			(effects
				(font
					(size 1.27 1.27)
				)
			)
		)
		(duplicate_pad_numbers_are_jumpers no)
		(fp_line
			(start -0.7874 -0.4064)
			(end 0.7874 -0.4064)
			(stroke
				(width 0.1524)
				(type default)
			)
			(layer "F.SilkS")
		)
		(fp_line
			(start -0.7874 0.4064)
			(end -0.7874 -0.4064)
			(stroke
				(width 0.1524)
				(type default)
			)
			(layer "F.SilkS")
		)
		(fp_line
			(start 0.7874 -0.4064)
			(end 0.7874 0.4064)
			(stroke
				(width 0.1524)
				(type default)
			)
			(layer "F.SilkS")
		)
		(fp_line
			(start 0.7874 0.4064)
			(end -0.7874 0.4064)
			(stroke
				(width 0.1524)
				(type default)
			)
			(layer "F.SilkS")
		)
		(fp_line
			(start -0.67945 -0.305054)
			(end -0.12065 -0.305054)
			(stroke
				(width 0.1)
				(type default)
			)
			(layer "F.Fab")
		)
		(fp_line
			(start -0.67945 0.3048)
			(end -0.67945 -0.305054)
			(stroke
				(width 0.1)
				(type default)
			)
			(layer "F.Fab")
		)
		(fp_line
			(start -0.12065 -0.305054)
			(end -0.12065 -0.2794)
			(stroke
				(width 0.1)
				(type default)
			)
			(layer "F.Fab")
		)
		(fp_line
			(start -0.12065 -0.2794)
			(end 0.12065 -0.2794)
			(stroke
				(width 0.1)
				(type default)
			)
			(layer "F.Fab")
		)
		(fp_line
			(start -0.12065 0.2794)
			(end -0.12065 0.3048)
			(stroke
				(width 0.1)
				(type default)
			)
			(layer "F.Fab")
		)
		(fp_line
			(start -0.12065 0.3048)
			(end -0.67945 0.3048)
			(stroke
				(width 0.1)
				(type default)
			)
			(layer "F.Fab")
		)
		(fp_line
			(start 0.120396 0.2794)
			(end -0.12065 0.2794)
			(stroke
				(width 0.1)
				(type default)
			)
			(layer "F.Fab")
		)
		(fp_line
			(start 0.120396 0.3048)
			(end 0.120396 0.2794)
			(stroke
				(width 0.1)
				(type default)
			)
			(layer "F.Fab")
		)
		(fp_line
			(start 0.12065 -0.3048)
			(end 0.67945 -0.3048)
			(stroke
				(width 0.1)
				(type default)
			)
			(layer "F.Fab")
		)
		(fp_line
			(start 0.12065 -0.2794)
			(end 0.12065 -0.3048)
			(stroke
				(width 0.1)
				(type default)
			)
			(layer "F.Fab")
		)
		(fp_line
			(start 0.67945 -0.3048)
			(end 0.67945 0.3048)
			(stroke
				(width 0.1)
				(type default)
			)
			(layer "F.Fab")
		)
		(fp_line
			(start 0.67945 0.3048)
			(end 0.120396 0.3048)
			(stroke
				(width 0.1)
				(type default)
			)
			(layer "F.Fab")
		)
		(pad "1" smd circle
			(at -0.40005 0)
			(size 0 0)
			(layers "F.Cu" "F.Mask" "F.Paste")
			(net "HSC_VDD")
		)
		(pad "2" smd circle
			(at 0.40005 0)
			(size 0 0)
			(layers "F.Cu" "F.Mask" "F.Paste")
			(net "HSC_VIN_UVW_N")
		)
	)
	(footprint ""
		(layer "F.Cu")
		(at 37.211 -363.093)
		(property "Reference" "PC367"
			(at 0 0 0)
			(layer "F.SilkS")
			(hide yes)
			(effects
				(font
					(size 1.27 1.27)
				)
			)
		)
		(property "Value" ""
			(at 0 0 0)
			(layer "F.Fab")
			(effects
				(font
					(size 1.27 1.27)
				)
			)
		)
		(duplicate_pad_numbers_are_jumpers no)
		(fp_line
			(start -0.7874 -0.4064)
			(end 0.7874 -0.4064)
			(stroke
				(width 0.1524)
				(type default)
			)
			(layer "F.SilkS")
		)
		(fp_line
			(start -0.7874 0.4064)
			(end -0.7874 -0.4064)
			(stroke
				(width 0.1524)
				(type default)
			)
			(layer "F.SilkS")
		)
		(fp_line
			(start 0.7874 -0.4064)
			(end 0.7874 0.4064)
			(stroke
				(width 0.1524)
				(type default)
			)
			(layer "F.SilkS")
		)
		(fp_line
			(start 0.7874 0.4064)
			(end -0.7874 0.4064)
			(stroke
				(width 0.1524)
				(type default)
			)
			(layer "F.SilkS")
		)
		(fp_line
			(start -0.67945 -0.305054)
			(end -0.12065 -0.305054)
			(stroke
				(width 0.1)
				(type default)
			)
			(layer "F.Fab")
		)
		(fp_line
			(start -0.67945 0.3048)
			(end -0.67945 -0.305054)
			(stroke
				(width 0.1)
				(type default)
			)
			(layer "F.Fab")
		)
		(fp_line
			(start -0.12065 -0.305054)
			(end -0.12065 -0.2794)
			(stroke
				(width 0.1)
				(type default)
			)
			(layer "F.Fab")
		)
		(fp_line
			(start -0.12065 -0.2794)
			(end 0.12065 -0.2794)
			(stroke
				(width 0.1)
				(type default)
			)
			(layer "F.Fab")
		)
		(fp_line
			(start -0.12065 0.2794)
			(end -0.12065 0.3048)
			(stroke
				(width 0.1)
				(type default)
			)
			(layer "F.Fab")
		)
		(fp_line
			(start -0.12065 0.3048)
			(end -0.67945 0.3048)
			(stroke
				(width 0.1)
				(type default)
			)
			(layer "F.Fab")
		)
		(fp_line
			(start 0.120396 0.2794)
			(end -0.12065 0.2794)
			(stroke
				(width 0.1)
				(type default)
			)
			(layer "F.Fab")
		)
		(fp_line
			(start 0.120396 0.3048)
			(end 0.120396 0.2794)
			(stroke
				(width 0.1)
				(type default)
			)
			(layer "F.Fab")
		)
		(fp_line
			(start 0.12065 -0.3048)
			(end 0.67945 -0.3048)
			(stroke
				(width 0.1)
				(type default)
			)
			(layer "F.Fab")
		)
		(fp_line
			(start 0.12065 -0.2794)
			(end 0.12065 -0.3048)
			(stroke
				(width 0.1)
				(type default)
			)
			(layer "F.Fab")
		)
		(fp_line
			(start 0.67945 -0.3048)
			(end 0.67945 0.3048)
			(stroke
				(width 0.1)
				(type default)
			)
			(layer "F.Fab")
		)
		(fp_line
			(start 0.67945 0.3048)
			(end 0.120396 0.3048)
			(stroke
				(width 0.1)
				(type default)
			)
			(layer "F.Fab")
		)
		(pad "1" smd circle
			(at -0.40005 0)
			(size 0 0)
			(layers "F.Cu" "F.Mask" "F.Paste")
			(net "PVDDIO_P1_TEMP1")
		)
		(pad "2" smd circle
			(at 0.40005 0)
			(size 0 0)
			(layers "F.Cu" "F.Mask" "F.Paste")
			(net "GND")
		)
	)
	(footprint ""
		(layer "F.Cu")
		(at 155.419552 -121.819924 180)
		(property "Reference" "U325"
			(at -0.155956 2.20472 0)
			(unlocked yes)
			(layer "F.SilkS")
			(effects
				(font
					(size 0.7874 0.5842)
					(thickness 0.1524)
				)
			)
		)
		(property "Value" ""
			(at 0 0 180)
			(layer "F.Fab")
			(effects
				(font
					(size 1.27 1.27)
				)
			)
		)
		(duplicate_pad_numbers_are_jumpers no)
		(fp_line
			(start 1.949958 1.610106)
			(end -1.949958 1.610106)
			(stroke
				(width 0.1524)
				(type default)
			)
			(layer "F.SilkS")
		)
		(fp_line
			(start 1.949958 -1.560068)
			(end 1.949958 1.610106)
			(stroke
				(width 0.1524)
				(type default)
			)
			(layer "F.SilkS")
		)
		(fp_line
			(start -1.949958 1.610106)
			(end -1.949958 -1.610106)
			(stroke
				(width 0.1524)
				(type default)
			)
			(layer "F.SilkS")
		)
		(fp_line
			(start -1.949958 -1.610106)
			(end 1.949958 -1.610106)
			(stroke
				(width 0.1524)
				(type default)
			)
			(layer "F.SilkS")
		)
		(fp_line
			(start 0.750062 1.560068)
			(end -0.750062 1.560068)
			(stroke
				(width 0.1)
				(type default)
			)
			(layer "F.Fab")
		)
		(fp_line
			(start 0.750062 -1.560068)
			(end 0.750062 1.560068)
			(stroke
				(width 0.1)
				(type default)
			)
			(layer "F.Fab")
		)
		(fp_line
			(start -0.750062 1.560068)
			(end -0.750062 -1.560068)
			(stroke
				(width 0.1)
				(type default)
			)
			(layer "F.Fab")
		)
		(fp_line
			(start -0.750062 -1.560068)
			(end 0.750062 -1.560068)
			(stroke
				(width 0.1)
				(type default)
			)
			(layer "F.Fab")
		)
		(pad "D" smd rect
			(at 1.100074 0 90)
			(size 1.016 1.4224)
			(layers "F.Cu" "F.Mask" "F.Paste")
			(net "IRQ_UV_DETECT_N")
		)
		(pad "G" smd rect
			(at -1.100074 -0.94996 90)
			(size 1.016 1.4224)
			(layers "F.Cu" "F.Mask" "F.Paste")
			(net "A_P12V_STBY_FPH_GATE")
		)
		(pad "S" smd rect
			(at -1.100074 0.94996 90)
			(size 1.016 1.4224)
			(layers "F.Cu" "F.Mask" "F.Paste")
			(net "GND")
		)
	)
	(footprint ""
		(layer "F.Cu")
		(at 329.592178 -46.748954 180)
		(property "Reference" "R1799"
			(at 0 0 180)
			(layer "F.SilkS")
			(hide yes)
			(effects
				(font
					(size 1.27 1.27)
				)
			)
		)
		(property "Value" ""
			(at 0 0 180)
			(layer "F.Fab")
			(effects
				(font
					(size 1.27 1.27)
				)
			)
		)
		(duplicate_pad_numbers_are_jumpers no)
		(fp_line
			(start 0.7874 0.4064)
			(end -0.7874 0.4064)
			(stroke
				(width 0.1524)
				(type default)
			)
			(layer "F.SilkS")
		)
		(fp_line
			(start 0.7874 -0.4064)
			(end 0.7874 0.4064)
			(stroke
				(width 0.1524)
				(type default)
			)
			(layer "F.SilkS")
		)
		(fp_line
			(start -0.7874 0.4064)
			(end -0.7874 -0.4064)
			(stroke
				(width 0.1524)
				(type default)
			)
			(layer "F.SilkS")
		)
		(fp_line
			(start -0.7874 -0.4064)
			(end 0.7874 -0.4064)
			(stroke
				(width 0.1524)
				(type default)
			)
			(layer "F.SilkS")
		)
		(fp_line
			(start 0.67945 0.3048)
			(end 0.120396 0.3048)
			(stroke
				(width 0.1)
				(type default)
			)
			(layer "F.Fab")
		)
		(fp_line
			(start 0.67945 -0.3048)
			(end 0.67945 0.3048)
			(stroke
				(width 0.1)
				(type default)
			)
			(layer "F.Fab")
		)
		(fp_line
			(start 0.12065 -0.2794)
			(end 0.12065 -0.3048)
			(stroke
				(width 0.1)
				(type default)
			)
			(layer "F.Fab")
		)
		(fp_line
			(start 0.12065 -0.3048)
			(end 0.67945 -0.3048)
			(stroke
				(width 0.1)
				(type default)
			)
			(layer "F.Fab")
		)
		(fp_line
			(start 0.120396 0.3048)
			(end 0.120396 0.2794)
			(stroke
				(width 0.1)
				(type default)
			)
			(layer "F.Fab")
		)
		(fp_line
			(start 0.120396 0.2794)
			(end -0.12065 0.2794)
			(stroke
				(width 0.1)
				(type default)
			)
			(layer "F.Fab")
		)
		(fp_line
			(start -0.12065 0.3048)
			(end -0.67945 0.3048)
			(stroke
				(width 0.1)
				(type default)
			)
			(layer "F.Fab")
		)
		(fp_line
			(start -0.12065 0.2794)
			(end -0.12065 0.3048)
			(stroke
				(width 0.1)
				(type default)
			)
			(layer "F.Fab")
		)
		(fp_line
			(start -0.12065 -0.2794)
			(end 0.12065 -0.2794)
			(stroke
				(width 0.1)
				(type default)
			)
			(layer "F.Fab")
		)
		(fp_line
			(start -0.12065 -0.305054)
			(end -0.12065 -0.2794)
			(stroke
				(width 0.1)
				(type default)
			)
			(layer "F.Fab")
		)
		(fp_line
			(start -0.67945 0.3048)
			(end -0.67945 -0.305054)
			(stroke
				(width 0.1)
				(type default)
			)
			(layer "F.Fab")
		)
		(fp_line
			(start -0.67945 -0.305054)
			(end -0.12065 -0.305054)
			(stroke
				(width 0.1)
				(type default)
			)
			(layer "F.Fab")
		)
		(pad "1" smd circle
			(at -0.40005 0 180)
			(size 0 0)
			(layers "F.Cu" "F.Mask" "F.Paste")
			(net "P12V_AUX")
		)
		(pad "2" smd circle
			(at 0.40005 0 180)
			(size 0 0)
			(layers "F.Cu" "F.Mask" "F.Paste")
			(net "P12V_AUX_ADC")
		)
	)
	(footprint ""
		(layer "F.Cu")
		(at 199.536558 -401.920202 180)
		(property "Reference" "PU287"
			(at 3.001772 -4.951222 90)
			(unlocked yes)
			(layer "F.SilkS")
			(effects
				(font
					(size 0.7874 0.5842)
					(thickness 0.1524)
				)
			)
		)
		(property "Value" ""
			(at 0 0 180)
			(layer "F.Fab")
			(effects
				(font
					(size 1.27 1.27)
				)
			)
		)
		(duplicate_pad_numbers_are_jumpers no)
		(fp_line
			(start 2.567686 2.567686)
			(end 2.567686 -2.567686)
			(stroke
				(width 0.1524)
				(type default)
			)
			(layer "F.SilkS")
		)
		(fp_line
			(start 2.567686 -2.567686)
			(end -2.567686 -2.567686)
			(stroke
				(width 0.1524)
				(type default)
			)
			(layer "F.SilkS")
		)
		(fp_line
			(start -2.567686 2.567686)
			(end 2.567686 2.567686)
			(stroke
				(width 0.1524)
				(type default)
			)
			(layer "F.SilkS")
		)
		(fp_line
			(start -2.567686 -2.567686)
			(end -2.567686 2.567686)
			(stroke
				(width 0.1524)
				(type default)
			)
			(layer "F.SilkS")
		)
		(fp_poly
			(pts
				(xy -2.632456 -2.13233) (xy -3.709924 -2.491486) (xy -2.991612 -3.209798)
			)
			(stroke
				(width 0)
				(type default)
			)
			(fill yes)
			(layer "F.SilkS")
		)
		(fp_line
			(start 2.549906 2.549906)
			(end 2.549906 -2.549906)
			(stroke
				(width 0.1)
				(type default)
			)
			(layer "F.Fab")
		)
		(fp_line
			(start 2.549906 -2.549906)
			(end -2.549906 -2.549906)
			(stroke
				(width 0.1)
				(type default)
			)
			(layer "F.Fab")
		)
		(fp_line
			(start -2.549906 2.549906)
			(end 2.549906 2.549906)
			(stroke
				(width 0.1)
				(type default)
			)
			(layer "F.Fab")
		)
		(fp_line
			(start -2.549906 -2.549906)
			(end -2.549906 2.549906)
			(stroke
				(width 0.1)
				(type default)
			)
			(layer "F.Fab")
		)
		(fp_poly
			(pts
				(xy -3.806698 -2.25806) (xy -3.806698 -1.24206) (xy -2.790698 -1.75006)
			)
			(stroke
				(width 0)
				(type default)
			)
			(fill yes)
			(layer "F.Fab")
		)
		(pad "1" smd rect
			(at -2.250186 -1.75006 270)
			(size 0.254 0.3556)
			(layers "F.Cu" "F.Mask" "F.Paste")
			(net "P12V_AUX")
		)
		(pad "2" smd rect
			(at -2.237486 -1.249934 270)
			(size 0.254 0.381)
			(layers "F.Cu" "F.Mask" "F.Paste")
			(net "P12V_AUX")
		)
		(pad "3" smd rect
			(at -2.237486 -0.750062 270)
			(size 0.254 0.381)
			(layers "F.Cu" "F.Mask" "F.Paste")
			(net "HSC_D_OC_1")
		)
		(pad "4" smd rect
			(at -2.237486 -0.249936 270)
			(size 0.254 0.381)
			(layers "F.Cu" "F.Mask" "F.Paste")
			(net "HSC_ON")
		)
		(pad "5" smd rect
			(at -2.237486 0.249936 270)
			(size 0.254 0.381)
			(layers "F.Cu" "F.Mask" "F.Paste")
			(net "HSC_FAULT")
		)
		(pad "6" smd rect
			(at -2.237486 0.750062 270)
			(size 0.254 0.381)
			(layers "F.Cu" "F.Mask" "F.Paste")
			(net "HSC_FLT_TYPE_1")
		)
		(pad "7" smd rect
			(at -2.237486 1.249934 270)
			(size 0.254 0.381)
			(layers "F.Cu" "F.Mask" "F.Paste")
			(net "HSC_NC1_1")
		)
		(pad "8" smd rect
			(at -2.250186 1.75006 270)
			(size 0.254 0.3556)
			(layers "F.Cu" "F.Mask" "F.Paste")
			(net "HSC_MODE_1")
		)
		(pad "9" smd rect
			(at -1.75006 2.250186 180)
			(size 0.254 0.3556)
			(layers "F.Cu" "F.Mask" "F.Paste")
			(net "P12V_PSU")
		)
		(pad "10" smd rect
			(at -1.249934 2.237486 180)
			(size 0.254 0.381)
			(layers "F.Cu" "F.Mask" "F.Paste")
			(net "P12V_PSU")
		)
		(pad "11" smd rect
			(at -0.750062 2.237486 180)
			(size 0.254 0.381)
			(layers "F.Cu" "F.Mask" "F.Paste")
			(net "P12V_PSU")
		)
		(pad "12" smd rect
			(at -0.249936 2.237486 180)
			(size 0.254 0.381)
			(layers "F.Cu" "F.Mask" "F.Paste")
			(net "P12V_PSU")
		)
		(pad "13" smd rect
			(at 0.249936 2.237486 180)
			(size 0.254 0.381)
			(layers "F.Cu" "F.Mask" "F.Paste")
			(net "P12V_PSU")
		)
		(pad "14" smd rect
			(at 0.750062 2.237486 180)
			(size 0.254 0.381)
			(layers "F.Cu" "F.Mask" "F.Paste")
			(net "P12V_PSU")
		)
		(pad "15" smd rect
			(at 1.249934 2.237486 180)
			(size 0.254 0.381)
			(layers "F.Cu" "F.Mask" "F.Paste")
			(net "P12V_PSU")
		)
		(pad "16" smd rect
			(at 1.75006 2.250186 180)
			(size 0.254 0.3556)
			(layers "F.Cu" "F.Mask" "F.Paste")
			(net "P12V_PSU")
		)
		(pad "17" smd rect
			(at 2.250186 1.75006 270)
			(size 0.254 0.3556)
			(layers "F.Cu" "F.Mask" "F.Paste")
			(net "HSC_SCREF_1")
		)
		(pad "18" smd rect
			(at 2.237486 1.249934 270)
			(size 0.254 0.381)
			(layers "F.Cu" "F.Mask" "F.Paste")
			(net "HSC_VTEMP")
		)
		(pad "19" smd rect
			(at 2.237486 0.750062 270)
			(size 0.254 0.381)
			(layers "F.Cu" "F.Mask" "F.Paste")
			(net "HSC_SS")
		)
		(pad "20" smd rect
			(at 2.237486 0.249936 270)
			(size 0.254 0.381)
			(layers "F.Cu" "F.Mask" "F.Paste")
			(net "AGND_HSC")
		)
		(pad "21" smd rect
			(at 2.237486 -0.249936 270)
			(size 0.254 0.381)
			(layers "F.Cu" "F.Mask" "F.Paste")
			(net "HSC_VDD_R_1")
		)
		(pad "22" smd rect
			(at 2.237486 -0.750062 270)
			(size 0.254 0.381)
			(layers "F.Cu" "F.Mask" "F.Paste")
			(net "HSC_IMON")
		)
		(pad "23" smd rect
			(at 2.237486 -1.249934 270)
			(size 0.254 0.381)
			(layers "F.Cu" "F.Mask" "F.Paste")
			(net "HSC_CS_1")
		)
		(pad "24" smd rect
			(at 2.250186 -1.75006 270)
			(size 0.254 0.3556)
			(layers "F.Cu" "F.Mask" "F.Paste")
			(net "HSC_OCREF")
		)
		(pad "25" smd rect
			(at 1.75006 -2.250186 180)
			(size 0.254 0.3556)
			(layers "F.Cu" "F.Mask" "F.Paste")
			(net "P12V_AUX")
		)
		(pad "26" smd rect
			(at 1.249934 -2.237486 180)
			(size 0.254 0.381)
			(layers "F.Cu" "F.Mask" "F.Paste")
			(net "P12V_AUX")
		)
		(pad "27" smd rect
			(at 0.750062 -2.237486 180)
			(size 0.254 0.381)
			(layers "F.Cu" "F.Mask" "F.Paste")
			(net "P12V_AUX")
		)
		(pad "28" smd rect
			(at 0.249936 -2.237486 180)
			(size 0.254 0.381)
			(layers "F.Cu" "F.Mask" "F.Paste")
			(net "P12V_AUX")
		)
		(pad "29" smd rect
			(at -0.249936 -2.237486 180)
			(size 0.254 0.381)
			(layers "F.Cu" "F.Mask" "F.Paste")
			(net "P12V_AUX")
		)
		(pad "30" smd rect
			(at -0.750062 -2.237486 180)
			(size 0.254 0.381)
			(layers "F.Cu" "F.Mask" "F.Paste")
			(net "P12V_AUX")
		)
		(pad "31" smd rect
			(at -1.249934 -2.237486 180)
			(size 0.254 0.381)
			(layers "F.Cu" "F.Mask" "F.Paste")
			(net "P12V_AUX")
		)
		(pad "32" smd rect
			(at -1.75006 -2.250186 180)
			(size 0.254 0.3556)
			(layers "F.Cu" "F.Mask" "F.Paste")
			(net "P12V_AUX")
		)
		(pad "33" smd rect
			(at 0 0 180)
			(size 3.4036 3.4036)
			(layers "F.Cu" "F.Mask" "F.Paste")
			(net "P12V_PSU")
		)
		(zone
			(layer "F.Cu")
			(hatch none 0.5)
			(connect_pads
				(clearance 0)
			)
			(min_thickness 0.25)
			(keepout
				(tracks not_allowed)
				(vias allowed)
				(pads allowed)
				(copperpour not_allowed)
				(footprints allowed)
			)
			(placement
				(enabled no)
				(sheetname "")
			)
			(fill
				(thermal_gap 0.5)
				(thermal_bridge_width 0.5)
				(island_removal_mode 0)
			)
			(polygon
				(pts
					(xy 197.514972 -403.61108) (xy 197.783958 -403.61108) (xy 197.783958 -400.167602) (xy 201.289158 -400.167602)
					(xy 201.289158 -402.428202) (xy 201.532744 -402.428202) (xy 201.532744 -400.472402) (xy 201.558144 -400.472402)
					(xy 201.558144 -399.898616) (xy 200.984358 -399.898616) (xy 200.984358 -399.924016) (xy 198.088758 -399.924016)
					(xy 198.088758 -399.898616) (xy 197.514972 -399.898616) (xy 197.514972 -400.472402) (xy 197.540372 -400.472402)
					(xy 197.540372 -403.368002) (xy 197.514972 -403.368002)
				)
			)
		)
	)
	(footprint ""
		(layer "F.Cu")
		(at 435.80812 -45.025056 90)
		(property "Reference" "PL8045"
			(at -1.629156 -3.891026 90)
			(unlocked yes)
			(layer "F.SilkS")
			(effects
				(font
					(size 0.7874 0.5842)
					(thickness 0.1524)
				)
				(justify left)
			)
		)
		(property "Value" ""
			(at 0 0 90)
			(layer "F.Fab")
			(effects
				(font
					(size 1.27 1.27)
				)
			)
		)
		(duplicate_pad_numbers_are_jumpers no)
		(fp_line
			(start 2.249932 -2.249932)
			(end 2.249932 -1.3843)
			(stroke
				(width 0.1524)
				(type default)
			)
			(layer "F.SilkS")
		)
		(fp_line
			(start -2.249932 -2.249932)
			(end 2.249932 -2.249932)
			(stroke
				(width 0.1524)
				(type default)
			)
			(layer "F.SilkS")
		)
		(fp_line
			(start -2.249932 -1.3843)
			(end -2.249932 -2.249932)
			(stroke
				(width 0.1524)
				(type default)
			)
			(layer "F.SilkS")
		)
		(fp_line
			(start 2.249932 1.3843)
			(end 2.249932 2.249932)
			(stroke
				(width 0.1524)
				(type default)
			)
			(layer "F.SilkS")
		)
		(fp_line
			(start 2.249932 2.249932)
			(end -2.249932 2.249932)
			(stroke
				(width 0.1524)
				(type default)
			)
			(layer "F.SilkS")
		)
		(fp_line
			(start -2.249932 2.249932)
			(end -2.249932 1.3843)
			(stroke
				(width 0.1524)
				(type default)
			)
			(layer "F.SilkS")
		)
		(fp_line
			(start 2.249932 -2.249932)
			(end 2.249932 2.249932)
			(stroke
				(width 0.1)
				(type default)
			)
			(layer "F.Fab")
		)
		(fp_line
			(start -2.249932 -2.249932)
			(end 2.249932 -2.249932)
			(stroke
				(width 0.1)
				(type default)
			)
			(layer "F.Fab")
		)
		(fp_line
			(start 2.249932 2.249932)
			(end -2.249932 2.249932)
			(stroke
				(width 0.1)
				(type default)
			)
			(layer "F.Fab")
		)
		(fp_line
			(start -2.249932 2.249932)
			(end -2.249932 -2.249932)
			(stroke
				(width 0.1)
				(type default)
			)
			(layer "F.Fab")
		)
		(pad "1" smd rect
			(at -1.82499 0 90)
			(size 1.0668 2.5146)
			(layers "F.Cu" "F.Mask" "F.Paste")
			(net "P12V_AUX")
		)
		(pad "2" smd rect
			(at 1.82499 0 90)
			(size 1.0668 2.5146)
			(layers "F.Cu" "F.Mask" "F.Paste")
			(net "SW_P3V3_AUX_FLT")
		)
	)
	(footprint ""
		(layer "F.Cu")
		(at 142.074392 -401.884896 90)
		(property "Reference" "C7040"
			(at 0 0 90)
			(layer "F.SilkS")
			(hide yes)
			(effects
				(font
					(size 1.27 1.27)
				)
			)
		)
		(property "Value" ""
			(at 0 0 90)
			(layer "F.Fab")
			(effects
				(font
					(size 1.27 1.27)
				)
			)
		)
		(duplicate_pad_numbers_are_jumpers no)
		(fp_line
			(start 1.524 -0.762)
			(end 1.524 0.762)
			(stroke
				(width 0.1524)
				(type default)
			)
			(layer "F.SilkS")
		)
		(fp_line
			(start -1.524 -0.762)
			(end 1.524 -0.762)
			(stroke
				(width 0.1524)
				(type default)
			)
			(layer "F.SilkS")
		)
		(fp_line
			(start 1.524 0.762)
			(end -1.524 0.762)
			(stroke
				(width 0.1524)
				(type default)
			)
			(layer "F.SilkS")
		)
		(fp_line
			(start -1.524 0.762)
			(end -1.524 -0.762)
			(stroke
				(width 0.1524)
				(type default)
			)
			(layer "F.SilkS")
		)
		(fp_line
			(start 1.1049 -0.724916)
			(end -1.1049 -0.724916)
			(stroke
				(width 0.1)
				(type default)
			)
			(layer "F.Fab")
		)
		(fp_line
			(start -1.1049 -0.724916)
			(end -1.1049 0.724916)
			(stroke
				(width 0.1)
				(type default)
			)
			(layer "F.Fab")
		)
		(fp_line
			(start 1.1049 0.724916)
			(end 1.1049 -0.724916)
			(stroke
				(width 0.1)
				(type default)
			)
			(layer "F.Fab")
		)
		(fp_line
			(start -1.1049 0.724916)
			(end 1.1049 0.724916)
			(stroke
				(width 0.1)
				(type default)
			)
			(layer "F.Fab")
		)
		(pad "1" smd rect
			(at -0.889 0 270)
			(size 1.016 1.27)
			(layers "F.Cu" "F.Mask" "F.Paste")
			(net "P0V9_CPU1_RT_2D")
		)
		(pad "2" smd rect
			(at 0.889 0 270)
			(size 1.016 1.27)
			(layers "F.Cu" "F.Mask" "F.Paste")
			(net "GND")
		)
	)
	(footprint ""
		(layer "F.Cu")
		(at 46.355 -38.354)
		(property "Reference" "U32"
			(at -2.017776 -2.360422 0)
			(unlocked yes)
			(layer "F.SilkS")
			(effects
				(font
					(size 0.7874 0.5842)
					(thickness 0.1524)
				)
			)
		)
		(property "Value" ""
			(at 0 0 0)
			(layer "F.Fab")
			(effects
				(font
					(size 1.27 1.27)
				)
			)
		)
		(duplicate_pad_numbers_are_jumpers no)
		(fp_line
			(start -1.949958 -1.610106)
			(end 1.949958 -1.610106)
			(stroke
				(width 0.1524)
				(type default)
			)
			(layer "F.SilkS")
		)
		(fp_line
			(start -1.949958 1.610106)
			(end -1.949958 -1.610106)
			(stroke
				(width 0.1524)
				(type default)
			)
			(layer "F.SilkS")
		)
		(fp_line
			(start 1.949958 -1.560068)
			(end 1.949958 1.610106)
			(stroke
				(width 0.1524)
				(type default)
			)
			(layer "F.SilkS")
		)
		(fp_line
			(start 1.949958 1.610106)
			(end -1.949958 1.610106)
			(stroke
				(width 0.1524)
				(type default)
			)
			(layer "F.SilkS")
		)
		(fp_line
			(start -0.750062 -1.560068)
			(end 0.750062 -1.560068)
			(stroke
				(width 0.1)
				(type default)
			)
			(layer "F.Fab")
		)
		(fp_line
			(start -0.750062 1.560068)
			(end -0.750062 -1.560068)
			(stroke
				(width 0.1)
				(type default)
			)
			(layer "F.Fab")
		)
		(fp_line
			(start 0.750062 -1.560068)
			(end 0.750062 1.560068)
			(stroke
				(width 0.1)
				(type default)
			)
			(layer "F.Fab")
		)
		(fp_line
			(start 0.750062 1.560068)
			(end -0.750062 1.560068)
			(stroke
				(width 0.1)
				(type default)
			)
			(layer "F.Fab")
		)
		(pad "D" smd rect
			(at 1.100074 0 270)
			(size 1.016 1.4224)
			(layers "F.Cu" "F.Mask" "F.Paste")
			(net "HP_LVC3_OCP_V3_2_PRSNT2")
		)
		(pad "G" smd rect
			(at -1.100074 -0.94996 270)
			(size 1.016 1.4224)
			(layers "F.Cu" "F.Mask" "F.Paste")
			(net "HP_LVC3_OCP_V3_2_PRSNT2_N")
		)
		(pad "S" smd rect
			(at -1.100074 0.94996 270)
			(size 1.016 1.4224)
			(layers "F.Cu" "F.Mask" "F.Paste")
			(net "GND")
		)
	)
	(footprint ""
		(layer "F.Cu")
		(at 361.046014 -258.795012)
		(property "Reference" "C2527"
			(at 0 0 0)
			(layer "F.SilkS")
			(hide yes)
			(effects
				(font
					(size 1.27 1.27)
				)
			)
		)
		(property "Value" ""
			(at 0 0 0)
			(layer "F.Fab")
			(effects
				(font
					(size 1.27 1.27)
				)
			)
		)
		(duplicate_pad_numbers_are_jumpers no)
		(fp_line
			(start -0.7874 -0.4064)
			(end 0.7874 -0.4064)
			(stroke
				(width 0.1524)
				(type default)
			)
			(layer "F.SilkS")
		)
		(fp_line
			(start -0.7874 0.4064)
			(end -0.7874 -0.4064)
			(stroke
				(width 0.1524)
				(type default)
			)
			(layer "F.SilkS")
		)
		(fp_line
			(start 0.7874 -0.4064)
			(end 0.7874 0.4064)
			(stroke
				(width 0.1524)
				(type default)
			)
			(layer "F.SilkS")
		)
		(fp_line
			(start 0.7874 0.4064)
			(end -0.7874 0.4064)
			(stroke
				(width 0.1524)
				(type default)
			)
			(layer "F.SilkS")
		)
		(fp_line
			(start -0.67945 -0.305054)
			(end -0.12065 -0.305054)
			(stroke
				(width 0.1)
				(type default)
			)
			(layer "F.Fab")
		)
		(fp_line
			(start -0.67945 0.3048)
			(end -0.67945 -0.305054)
			(stroke
				(width 0.1)
				(type default)
			)
			(layer "F.Fab")
		)
		(fp_line
			(start -0.12065 -0.305054)
			(end -0.12065 -0.2794)
			(stroke
				(width 0.1)
				(type default)
			)
			(layer "F.Fab")
		)
		(fp_line
			(start -0.12065 -0.2794)
			(end 0.12065 -0.2794)
			(stroke
				(width 0.1)
				(type default)
			)
			(layer "F.Fab")
		)
		(fp_line
			(start -0.12065 0.2794)
			(end -0.12065 0.3048)
			(stroke
				(width 0.1)
				(type default)
			)
			(layer "F.Fab")
		)
		(fp_line
			(start -0.12065 0.3048)
			(end -0.67945 0.3048)
			(stroke
				(width 0.1)
				(type default)
			)
			(layer "F.Fab")
		)
		(fp_line
			(start 0.120396 0.2794)
			(end -0.12065 0.2794)
			(stroke
				(width 0.1)
				(type default)
			)
			(layer "F.Fab")
		)
		(fp_line
			(start 0.120396 0.3048)
			(end 0.120396 0.2794)
			(stroke
				(width 0.1)
				(type default)
			)
			(layer "F.Fab")
		)
		(fp_line
			(start 0.12065 -0.3048)
			(end 0.67945 -0.3048)
			(stroke
				(width 0.1)
				(type default)
			)
			(layer "F.Fab")
		)
		(fp_line
			(start 0.12065 -0.2794)
			(end 0.12065 -0.3048)
			(stroke
				(width 0.1)
				(type default)
			)
			(layer "F.Fab")
		)
		(fp_line
			(start 0.67945 -0.3048)
			(end 0.67945 0.3048)
			(stroke
				(width 0.1)
				(type default)
			)
			(layer "F.Fab")
		)
		(fp_line
			(start 0.67945 0.3048)
			(end 0.120396 0.3048)
			(stroke
				(width 0.1)
				(type default)
			)
			(layer "F.Fab")
		)
		(pad "1" smd circle
			(at -0.40005 0)
			(size 0 0)
			(layers "F.Cu" "F.Mask" "F.Paste")
			(net "PVDDCR_SOC_P0")
		)
		(pad "2" smd circle
			(at 0.40005 0)
			(size 0 0)
			(layers "F.Cu" "F.Mask" "F.Paste")
			(net "GND")
		)
	)
	(footprint ""
		(layer "F.Cu")
		(at 156.83484 -93.174058 180)
		(property "Reference" "R3305"
			(at 0 0 180)
			(layer "F.SilkS")
			(hide yes)
			(effects
				(font
					(size 1.27 1.27)
				)
			)
		)
		(property "Value" ""
			(at 0 0 180)
			(layer "F.Fab")
			(effects
				(font
					(size 1.27 1.27)
				)
			)
		)
		(duplicate_pad_numbers_are_jumpers no)
		(fp_line
			(start 0.7874 0.4064)
			(end -0.7874 0.4064)
			(stroke
				(width 0.1524)
				(type default)
			)
			(layer "F.SilkS")
		)
		(fp_line
			(start 0.7874 -0.4064)
			(end 0.7874 0.4064)
			(stroke
				(width 0.1524)
				(type default)
			)
			(layer "F.SilkS")
		)
		(fp_line
			(start -0.7874 0.4064)
			(end -0.7874 -0.4064)
			(stroke
				(width 0.1524)
				(type default)
			)
			(layer "F.SilkS")
		)
		(fp_line
			(start -0.7874 -0.4064)
			(end 0.7874 -0.4064)
			(stroke
				(width 0.1524)
				(type default)
			)
			(layer "F.SilkS")
		)
		(fp_line
			(start 0.67945 0.3048)
			(end 0.120396 0.3048)
			(stroke
				(width 0.1)
				(type default)
			)
			(layer "F.Fab")
		)
		(fp_line
			(start 0.67945 -0.3048)
			(end 0.67945 0.3048)
			(stroke
				(width 0.1)
				(type default)
			)
			(layer "F.Fab")
		)
		(fp_line
			(start 0.12065 -0.2794)
			(end 0.12065 -0.3048)
			(stroke
				(width 0.1)
				(type default)
			)
			(layer "F.Fab")
		)
		(fp_line
			(start 0.12065 -0.3048)
			(end 0.67945 -0.3048)
			(stroke
				(width 0.1)
				(type default)
			)
			(layer "F.Fab")
		)
		(fp_line
			(start 0.120396 0.3048)
			(end 0.120396 0.2794)
			(stroke
				(width 0.1)
				(type default)
			)
			(layer "F.Fab")
		)
		(fp_line
			(start 0.120396 0.2794)
			(end -0.12065 0.2794)
			(stroke
				(width 0.1)
				(type default)
			)
			(layer "F.Fab")
		)
		(fp_line
			(start -0.12065 0.3048)
			(end -0.67945 0.3048)
			(stroke
				(width 0.1)
				(type default)
			)
			(layer "F.Fab")
		)
		(fp_line
			(start -0.12065 0.2794)
			(end -0.12065 0.3048)
			(stroke
				(width 0.1)
				(type default)
			)
			(layer "F.Fab")
		)
		(fp_line
			(start -0.12065 -0.2794)
			(end 0.12065 -0.2794)
			(stroke
				(width 0.1)
				(type default)
			)
			(layer "F.Fab")
		)
		(fp_line
			(start -0.12065 -0.305054)
			(end -0.12065 -0.2794)
			(stroke
				(width 0.1)
				(type default)
			)
			(layer "F.Fab")
		)
		(fp_line
			(start -0.67945 0.3048)
			(end -0.67945 -0.305054)
			(stroke
				(width 0.1)
				(type default)
			)
			(layer "F.Fab")
		)
		(fp_line
			(start -0.67945 -0.305054)
			(end -0.12065 -0.305054)
			(stroke
				(width 0.1)
				(type default)
			)
			(layer "F.Fab")
		)
		(pad "1" smd circle
			(at -0.40005 0 180)
			(size 0 0)
			(layers "F.Cu" "F.Mask" "F.Paste")
			(net "OCP_SFF_RBT_ARB_IN_MUX1")
		)
		(pad "2" smd circle
			(at 0.40005 0 180)
			(size 0 0)
			(layers "F.Cu" "F.Mask" "F.Paste")
			(net "OCP_SFF_RBT_ARB_IN_MUX1_R")
		)
	)
	(footprint ""
		(layer "F.Cu")
		(at 259.842 -102.108 180)
		(property "Reference" "C8006"
			(at 0 0 180)
			(layer "F.SilkS")
			(hide yes)
			(effects
				(font
					(size 1.27 1.27)
				)
			)
		)
		(property "Value" ""
			(at 0 0 180)
			(layer "F.Fab")
			(effects
				(font
					(size 1.27 1.27)
				)
			)
		)
		(duplicate_pad_numbers_are_jumpers no)
		(fp_line
			(start 0.7874 0.4064)
			(end -0.7874 0.4064)
			(stroke
				(width 0.1524)
				(type default)
			)
			(layer "F.SilkS")
		)
		(fp_line
			(start 0.7874 -0.4064)
			(end 0.7874 0.4064)
			(stroke
				(width 0.1524)
				(type default)
			)
			(layer "F.SilkS")
		)
		(fp_line
			(start -0.7874 0.4064)
			(end -0.7874 -0.4064)
			(stroke
				(width 0.1524)
				(type default)
			)
			(layer "F.SilkS")
		)
		(fp_line
			(start -0.7874 -0.4064)
			(end 0.7874 -0.4064)
			(stroke
				(width 0.1524)
				(type default)
			)
			(layer "F.SilkS")
		)
		(fp_line
			(start 0.67945 0.3048)
			(end 0.120396 0.3048)
			(stroke
				(width 0.1)
				(type default)
			)
			(layer "F.Fab")
		)
		(fp_line
			(start 0.67945 -0.3048)
			(end 0.67945 0.3048)
			(stroke
				(width 0.1)
				(type default)
			)
			(layer "F.Fab")
		)
		(fp_line
			(start 0.12065 -0.2794)
			(end 0.12065 -0.3048)
			(stroke
				(width 0.1)
				(type default)
			)
			(layer "F.Fab")
		)
		(fp_line
			(start 0.12065 -0.3048)
			(end 0.67945 -0.3048)
			(stroke
				(width 0.1)
				(type default)
			)
			(layer "F.Fab")
		)
		(fp_line
			(start 0.120396 0.3048)
			(end 0.120396 0.2794)
			(stroke
				(width 0.1)
				(type default)
			)
			(layer "F.Fab")
		)
		(fp_line
			(start 0.120396 0.2794)
			(end -0.12065 0.2794)
			(stroke
				(width 0.1)
				(type default)
			)
			(layer "F.Fab")
		)
		(fp_line
			(start -0.12065 0.3048)
			(end -0.67945 0.3048)
			(stroke
				(width 0.1)
				(type default)
			)
			(layer "F.Fab")
		)
		(fp_line
			(start -0.12065 0.2794)
			(end -0.12065 0.3048)
			(stroke
				(width 0.1)
				(type default)
			)
			(layer "F.Fab")
		)
		(fp_line
			(start -0.12065 -0.2794)
			(end 0.12065 -0.2794)
			(stroke
				(width 0.1)
				(type default)
			)
			(layer "F.Fab")
		)
		(fp_line
			(start -0.12065 -0.305054)
			(end -0.12065 -0.2794)
			(stroke
				(width 0.1)
				(type default)
			)
			(layer "F.Fab")
		)
		(fp_line
			(start -0.67945 0.3048)
			(end -0.67945 -0.305054)
			(stroke
				(width 0.1)
				(type default)
			)
			(layer "F.Fab")
		)
		(fp_line
			(start -0.67945 -0.305054)
			(end -0.12065 -0.305054)
			(stroke
				(width 0.1)
				(type default)
			)
			(layer "F.Fab")
		)
		(pad "1" smd circle
			(at -0.40005 0 180)
			(size 0 0)
			(layers "F.Cu" "F.Mask" "F.Paste")
			(net "JTAG_BMC_R_D_OE")
		)
		(pad "2" smd circle
			(at 0.40005 0 180)
			(size 0 0)
			(layers "F.Cu" "F.Mask" "F.Paste")
			(net "GND")
		)
	)
	(footprint ""
		(layer "F.Cu")
		(at 213.416134 -47.335948 90)
		(property "Reference" "R3589"
			(at 0 0 90)
			(layer "F.SilkS")
			(hide yes)
			(effects
				(font
					(size 1.27 1.27)
				)
			)
		)
		(property "Value" ""
			(at 0 0 90)
			(layer "F.Fab")
			(effects
				(font
					(size 1.27 1.27)
				)
			)
		)
		(duplicate_pad_numbers_are_jumpers no)
		(fp_line
			(start 0.7874 -0.4064)
			(end 0.7874 0.4064)
			(stroke
				(width 0.1524)
				(type default)
			)
			(layer "F.SilkS")
		)
		(fp_line
			(start -0.7874 -0.4064)
			(end 0.7874 -0.4064)
			(stroke
				(width 0.1524)
				(type default)
			)
			(layer "F.SilkS")
		)
		(fp_line
			(start 0.7874 0.4064)
			(end -0.7874 0.4064)
			(stroke
				(width 0.1524)
				(type default)
			)
			(layer "F.SilkS")
		)
		(fp_line
			(start -0.7874 0.4064)
			(end -0.7874 -0.4064)
			(stroke
				(width 0.1524)
				(type default)
			)
			(layer "F.SilkS")
		)
		(fp_line
			(start -0.12065 -0.305054)
			(end -0.12065 -0.2794)
			(stroke
				(width 0.1)
				(type default)
			)
			(layer "F.Fab")
		)
		(fp_line
			(start -0.67945 -0.305054)
			(end -0.12065 -0.305054)
			(stroke
				(width 0.1)
				(type default)
			)
			(layer "F.Fab")
		)
		(fp_line
			(start 0.67945 -0.3048)
			(end 0.67945 0.3048)
			(stroke
				(width 0.1)
				(type default)
			)
			(layer "F.Fab")
		)
		(fp_line
			(start 0.12065 -0.3048)
			(end 0.67945 -0.3048)
			(stroke
				(width 0.1)
				(type default)
			)
			(layer "F.Fab")
		)
		(fp_line
			(start 0.12065 -0.2794)
			(end 0.12065 -0.3048)
			(stroke
				(width 0.1)
				(type default)
			)
			(layer "F.Fab")
		)
		(fp_line
			(start -0.12065 -0.2794)
			(end 0.12065 -0.2794)
			(stroke
				(width 0.1)
				(type default)
			)
			(layer "F.Fab")
		)
		(fp_line
			(start 0.120396 0.2794)
			(end -0.12065 0.2794)
			(stroke
				(width 0.1)
				(type default)
			)
			(layer "F.Fab")
		)
		(fp_line
			(start -0.12065 0.2794)
			(end -0.12065 0.3048)
			(stroke
				(width 0.1)
				(type default)
			)
			(layer "F.Fab")
		)
		(fp_line
			(start 0.67945 0.3048)
			(end 0.120396 0.3048)
			(stroke
				(width 0.1)
				(type default)
			)
			(layer "F.Fab")
		)
		(fp_line
			(start 0.120396 0.3048)
			(end 0.120396 0.2794)
			(stroke
				(width 0.1)
				(type default)
			)
			(layer "F.Fab")
		)
		(fp_line
			(start -0.12065 0.3048)
			(end -0.67945 0.3048)
			(stroke
				(width 0.1)
				(type default)
			)
			(layer "F.Fab")
		)
		(fp_line
			(start -0.67945 0.3048)
			(end -0.67945 -0.305054)
			(stroke
				(width 0.1)
				(type default)
			)
			(layer "F.Fab")
		)
		(pad "1" smd circle
			(at -0.40005 0 90)
			(size 0 0)
			(layers "F.Cu" "F.Mask" "F.Paste")
			(net "SMB_INA230_3V3AUX_SDA")
		)
		(pad "2" smd circle
			(at 0.40005 0 90)
			(size 0 0)
			(layers "F.Cu" "F.Mask" "F.Paste")
			(net "SMB_INA230_2_3V3AUX_SDA_R")
		)
	)
	(footprint ""
		(layer "F.Cu")
		(at 343.39022 -335.024476)
		(property "Reference" "PU16"
			(at -3.03022 -7.848854 0)
			(unlocked yes)
			(layer "F.SilkS")
			(effects
				(font
					(size 0.7874 0.5842)
					(thickness 0.1524)
				)
				(justify left)
			)
		)
		(property "Value" ""
			(at 0 0 0)
			(layer "F.Fab")
			(effects
				(font
					(size 1.27 1.27)
				)
			)
		)
		(duplicate_pad_numbers_are_jumpers no)
		(fp_line
			(start -2.500122 -2.999994)
			(end -2.24409 -2.999994)
			(stroke
				(width 0.1524)
				(type default)
			)
			(layer "F.SilkS")
		)
		(fp_line
			(start -2.500122 -2.529078)
			(end -2.500122 -2.999994)
			(stroke
				(width 0.1524)
				(type default)
			)
			(layer "F.SilkS")
		)
		(fp_line
			(start -2.500122 0.6604)
			(end -2.500122 0.229108)
			(stroke
				(width 0.1524)
				(type default)
			)
			(layer "F.SilkS")
		)
		(fp_line
			(start -2.500122 2.999994)
			(end -2.500122 2.339594)
			(stroke
				(width 0.1524)
				(type default)
			)
			(layer "F.SilkS")
		)
		(fp_line
			(start -2.2987 2.999994)
			(end -2.500122 2.999994)
			(stroke
				(width 0.1524)
				(type default)
			)
			(layer "F.SilkS")
		)
		(fp_line
			(start 2.31394 -2.999994)
			(end 2.500122 -2.999994)
			(stroke
				(width 0.1524)
				(type default)
			)
			(layer "F.SilkS")
		)
		(fp_line
			(start 2.500122 -2.999994)
			(end 2.500122 -2.44348)
			(stroke
				(width 0.1524)
				(type default)
			)
			(layer "F.SilkS")
		)
		(fp_line
			(start 2.500122 2.339594)
			(end 2.500122 2.999994)
			(stroke
				(width 0.1524)
				(type default)
			)
			(layer "F.SilkS")
		)
		(fp_line
			(start 2.500122 2.999994)
			(end 2.2987 2.999994)
			(stroke
				(width 0.1524)
				(type default)
			)
			(layer "F.SilkS")
		)
		(fp_poly
			(pts
				(xy -2.742692 -2.464308) (xy -3.4163 -2.68859) (xy -2.967228 -3.137662)
			)
			(stroke
				(width 0)
				(type default)
			)
			(fill yes)
			(layer "F.SilkS")
		)
		(fp_line
			(start -2.500122 -2.999994)
			(end 2.500122 -2.999994)
			(stroke
				(width 0.1)
				(type default)
			)
			(layer "F.Fab")
		)
		(fp_line
			(start -2.500122 2.999994)
			(end -2.500122 -2.999994)
			(stroke
				(width 0.1)
				(type default)
			)
			(layer "F.Fab")
		)
		(fp_line
			(start 2.500122 -2.999994)
			(end 2.500122 2.999994)
			(stroke
				(width 0.1)
				(type default)
			)
			(layer "F.Fab")
		)
		(fp_line
			(start 2.500122 2.999994)
			(end -2.500122 2.999994)
			(stroke
				(width 0.1)
				(type default)
			)
			(layer "F.Fab")
		)
		(fp_poly
			(pts
				(xy -4.218432 -2.783078) (xy -4.218432 -1.767078) (xy -3.202432 -2.275078)
			)
			(stroke
				(width 0)
				(type default)
			)
			(fill yes)
			(layer "F.Fab")
		)
		(pad "1" smd rect
			(at -2.400046 -2.275078 90)
			(size 0.2286 0.6096)
			(layers "F.Cu" "F.Mask" "F.Paste")
			(net "PVDDCR_CPU1_P0_VOS5")
		)
		(pad "2" smd rect
			(at -2.400046 -1.82499 90)
			(size 0.2286 0.6096)
			(layers "F.Cu" "F.Mask" "F.Paste")
			(net "GND")
		)
		(pad "3" smd rect
			(at -2.400046 -1.374902 90)
			(size 0.2286 0.6096)
			(layers "F.Cu" "F.Mask" "F.Paste")
			(net "PVDDCR_CPU1_P0_VCC5")
		)
		(pad "4" smd rect
			(at -2.400046 -0.925068 90)
			(size 0.2286 0.6096)
			(layers "F.Cu" "F.Mask" "F.Paste")
			(net "PVDDCR_CPU1_P0_PVCC")
		)
		(pad "5" smd rect
			(at -2.400046 -0.47498 90)
			(size 0.2286 0.6096)
			(layers "F.Cu" "F.Mask" "F.Paste")
			(net "GND")
		)
		(pad "6" smd rect
			(at -2.400046 -0.024892 90)
			(size 0.2286 0.6096)
			(layers "F.Cu" "F.Mask" "F.Paste")
			(net "NC_PVDDCR_CPU1_P0_GL1_5")
		)
		(pad "7_9-20_24" smd circle
			(at 0 1.150112 90)
			(size 0 0)
			(layers "F.Cu" "F.Mask" "F.Paste")
			(net "GND")
		)
		(pad "10_19" smd rect
			(at 0 2.899918 90)
			(size 0.6096 4.318)
			(layers "F.Cu" "F.Mask" "F.Paste")
			(net "SW_PVDDCR_CPU1_P0_SW5")
		)
		(pad "25_29" smd rect
			(at 1.549908 -1.279906 270)
			(size 2.0574 2.3114)
			(layers "F.Cu" "F.Mask" "F.Paste")
			(net "SW_P12V_AUX_PVDDCR_CPU1_P0_FLT")
		)
		(pad "30" smd rect
			(at 2.05994 -2.899918)
			(size 0.2286 0.6096)
			(layers "F.Cu" "F.Mask" "F.Paste")
			(net "SW_P12V_AUX_PVDDCR_CPU1_P0_FLT")
		)
		(pad "31" smd rect
			(at 1.610106 -2.899918)
			(size 0.2286 0.6096)
			(layers "F.Cu" "F.Mask" "F.Paste")
			(net "NC_PVDDCR_CPU1_P0_DNC5")
		)
		(pad "32" smd rect
			(at 1.160018 -2.899918)
			(size 0.2286 0.6096)
			(layers "F.Cu" "F.Mask" "F.Paste")
			(net "SW_PVDDCR_CPU1_P0_BOOTR5")
		)
		(pad "33" smd rect
			(at 0.70993 -2.899918)
			(size 0.2286 0.6096)
			(layers "F.Cu" "F.Mask" "F.Paste")
			(net "SW_PVDDCR_CPU1_P0_BOOT5")
		)
		(pad "34" smd rect
			(at 0.260096 -2.899918)
			(size 0.2286 0.6096)
			(layers "F.Cu" "F.Mask" "F.Paste")
			(net "PVDDCR_CPU1_P0_PWM5")
		)
		(pad "35" smd rect
			(at -0.189992 -2.899918)
			(size 0.2286 0.6096)
			(layers "F.Cu" "F.Mask" "F.Paste")
			(net "PVDDCR_CPU1_P0_VCC5")
		)
		(pad "36" smd rect
			(at -0.64008 -2.899918)
			(size 0.2286 0.6096)
			(layers "F.Cu" "F.Mask" "F.Paste")
			(net "PVDDCR_CPU1_P0_TEMP0")
		)
		(pad "37" smd rect
			(at -1.089914 -2.899918)
			(size 0.2286 0.6096)
			(layers "F.Cu" "F.Mask" "F.Paste")
			(net "PVDDCR_CPU1_P0_LSET5")
		)
		(pad "38" smd rect
			(at -1.540002 -2.899918)
			(size 0.2286 0.6096)
			(layers "F.Cu" "F.Mask" "F.Paste")
			(net "PVDDCR_CPU1_P0_IMON5")
		)
		(pad "39" smd rect
			(at -1.99009 -2.899918)
			(size 0.2286 0.6096)
			(layers "F.Cu" "F.Mask" "F.Paste")
			(net "PVDDCR_CPU1_P0_VCCS")
		)
		(pad "40" smd rect
			(at -0.87503 -1.27508)
			(size 1.7526 1.9558)
			(layers "F.Cu" "F.Mask" "F.Paste")
			(net "GND")
		)
		(pad "41" smd rect
			(at -1.525016 0.249936 270)
			(size 0.3048 0.4572)
			(layers "F.Cu" "F.Mask" "F.Paste")
			(net "NC_PVDDCR_CPU1_P0_GL2_5")
		)
		(zone
			(layer "F.Cu")
			(hatch none 0.5)
			(connect_pads
				(clearance 0)
			)
			(min_thickness 0.25)
			(keepout
				(tracks not_allowed)
				(vias allowed)
				(pads allowed)
				(copperpour not_allowed)
				(footprints allowed)
			)
			(placement
				(enabled no)
				(sheetname "")
			)
			(fill
				(thermal_gap 0.5)
				(thermal_bridge_width 0.5)
				(island_removal_mode 0)
			)
			(polygon
				(pts
					(xy 340.890098 -332.444598) (xy 340.890098 -332.773782) (xy 345.890342 -332.773782) (xy 345.890342 -332.456282)
					(xy 345.60002 -332.456282) (xy 345.60002 -332.480158) (xy 341.18042 -332.480158) (xy 341.18042 -332.444598)
				)
			)
		)
		(zone
			(layer "F.Cu")
			(hatch none 0.5)
			(connect_pads
				(clearance 0)
			)
			(min_thickness 0.25)
			(keepout
				(tracks not_allowed)
				(vias allowed)
				(pads allowed)
				(copperpour not_allowed)
				(footprints allowed)
			)
			(placement
				(enabled no)
				(sheetname "")
			)
			(fill
				(thermal_gap 0.5)
				(thermal_bridge_width 0.5)
				(island_removal_mode 0)
			)
			(polygon
				(pts
					(xy 343.44229 -335.270856) (xy 343.44229 -337.328256) (xy 341.58809 -337.328256) (xy 341.58809 -337.08721)
					(xy 341.345774 -337.08721) (xy 341.345774 -337.568794) (xy 345.109038 -337.568794) (xy 345.109038 -337.383882)
					(xy 343.733628 -337.383882) (xy 343.733628 -335.224882) (xy 345.890342 -335.224882) (xy 345.890342 -334.9752)
					(xy 343.737946 -334.9752)
				)
			)
		)
	)
	(footprint ""
		(layer "F.Cu")
		(at 320.612262 -403.1615 -90)
		(property "Reference" "R6809"
			(at 0 0 270)
			(layer "F.SilkS")
			(hide yes)
			(effects
				(font
					(size 1.27 1.27)
				)
			)
		)
		(property "Value" ""
			(at 0 0 270)
			(layer "F.Fab")
			(effects
				(font
					(size 1.27 1.27)
				)
			)
		)
		(duplicate_pad_numbers_are_jumpers no)
		(fp_line
			(start -0.32512 0.175006)
			(end -0.32512 -0.175006)
			(stroke
				(width 0.1)
				(type default)
			)
			(layer "F.Fab")
		)
		(fp_line
			(start 0.32512 0.175006)
			(end -0.32512 0.175006)
			(stroke
				(width 0.1)
				(type default)
			)
			(layer "F.Fab")
		)
		(fp_line
			(start -0.32512 -0.175006)
			(end 0.32512 -0.175006)
			(stroke
				(width 0.1)
				(type default)
			)
			(layer "F.Fab")
		)
		(fp_line
			(start 0.32512 -0.175006)
			(end 0.32512 0.175006)
			(stroke
				(width 0.1)
				(type default)
			)
			(layer "F.Fab")
		)
		(pad "1" smd rect
			(at -0.2667 0 270)
			(size 0.3048 0.381)
			(layers "F.Cu" "F.Mask" "F.Paste")
			(net "RT_CPU0_P0_VQPS")
		)
		(pad "2" smd rect
			(at 0.2667 0 90)
			(size 0.3048 0.381)
			(layers "F.Cu" "F.Mask" "F.Paste")
			(net "GND")
		)
	)
	(footprint ""
		(layer "F.Cu")
		(at 367.441226 -62.0903)
		(property "Reference" "R8023"
			(at 0 0 0)
			(layer "F.SilkS")
			(hide yes)
			(effects
				(font
					(size 1.27 1.27)
				)
			)
		)
		(property "Value" ""
			(at 0 0 0)
			(layer "F.Fab")
			(effects
				(font
					(size 1.27 1.27)
				)
			)
		)
		(duplicate_pad_numbers_are_jumpers no)
		(fp_line
			(start -0.7874 -0.4064)
			(end 0.7874 -0.4064)
			(stroke
				(width 0.1524)
				(type default)
			)
			(layer "F.SilkS")
		)
		(fp_line
			(start -0.7874 0.4064)
			(end -0.7874 -0.4064)
			(stroke
				(width 0.1524)
				(type default)
			)
			(layer "F.SilkS")
		)
		(fp_line
			(start 0.7874 -0.4064)
			(end 0.7874 0.4064)
			(stroke
				(width 0.1524)
				(type default)
			)
			(layer "F.SilkS")
		)
		(fp_line
			(start 0.7874 0.4064)
			(end -0.7874 0.4064)
			(stroke
				(width 0.1524)
				(type default)
			)
			(layer "F.SilkS")
		)
		(fp_line
			(start -0.67945 -0.305054)
			(end -0.12065 -0.305054)
			(stroke
				(width 0.1)
				(type default)
			)
			(layer "F.Fab")
		)
		(fp_line
			(start -0.67945 0.3048)
			(end -0.67945 -0.305054)
			(stroke
				(width 0.1)
				(type default)
			)
			(layer "F.Fab")
		)
		(fp_line
			(start -0.12065 -0.305054)
			(end -0.12065 -0.2794)
			(stroke
				(width 0.1)
				(type default)
			)
			(layer "F.Fab")
		)
		(fp_line
			(start -0.12065 -0.2794)
			(end 0.12065 -0.2794)
			(stroke
				(width 0.1)
				(type default)
			)
			(layer "F.Fab")
		)
		(fp_line
			(start -0.12065 0.2794)
			(end -0.12065 0.3048)
			(stroke
				(width 0.1)
				(type default)
			)
			(layer "F.Fab")
		)
		(fp_line
			(start -0.12065 0.3048)
			(end -0.67945 0.3048)
			(stroke
				(width 0.1)
				(type default)
			)
			(layer "F.Fab")
		)
		(fp_line
			(start 0.120396 0.2794)
			(end -0.12065 0.2794)
			(stroke
				(width 0.1)
				(type default)
			)
			(layer "F.Fab")
		)
		(fp_line
			(start 0.120396 0.3048)
			(end 0.120396 0.2794)
			(stroke
				(width 0.1)
				(type default)
			)
			(layer "F.Fab")
		)
		(fp_line
			(start 0.12065 -0.3048)
			(end 0.67945 -0.3048)
			(stroke
				(width 0.1)
				(type default)
			)
			(layer "F.Fab")
		)
		(fp_line
			(start 0.12065 -0.2794)
			(end 0.12065 -0.3048)
			(stroke
				(width 0.1)
				(type default)
			)
			(layer "F.Fab")
		)
		(fp_line
			(start 0.67945 -0.3048)
			(end 0.67945 0.3048)
			(stroke
				(width 0.1)
				(type default)
			)
			(layer "F.Fab")
		)
		(fp_line
			(start 0.67945 0.3048)
			(end 0.120396 0.3048)
			(stroke
				(width 0.1)
				(type default)
			)
			(layer "F.Fab")
		)
		(pad "1" smd circle
			(at -0.40005 0)
			(size 0 0)
			(layers "F.Cu" "F.Mask" "F.Paste")
			(net "LED_P12V_AUX_R2")
		)
		(pad "2" smd circle
			(at 0.40005 0)
			(size 0 0)
			(layers "F.Cu" "F.Mask" "F.Paste")
			(net "LED_P12V_AUX_R3")
		)
	)
	(footprint ""
		(layer "F.Cu")
		(at 288.198052 -14.354048)
		(property "Reference" "R4179"
			(at 0 0 0)
			(layer "F.SilkS")
			(hide yes)
			(effects
				(font
					(size 1.27 1.27)
				)
			)
		)
		(property "Value" ""
			(at 0 0 0)
			(layer "F.Fab")
			(effects
				(font
					(size 1.27 1.27)
				)
			)
		)
		(duplicate_pad_numbers_are_jumpers no)
		(fp_line
			(start -0.7874 -0.4064)
			(end 0.7874 -0.4064)
			(stroke
				(width 0.1524)
				(type default)
			)
			(layer "F.SilkS")
		)
		(fp_line
			(start -0.7874 0.4064)
			(end -0.7874 -0.4064)
			(stroke
				(width 0.1524)
				(type default)
			)
			(layer "F.SilkS")
		)
		(fp_line
			(start 0.7874 -0.4064)
			(end 0.7874 0.4064)
			(stroke
				(width 0.1524)
				(type default)
			)
			(layer "F.SilkS")
		)
		(fp_line
			(start 0.7874 0.4064)
			(end -0.7874 0.4064)
			(stroke
				(width 0.1524)
				(type default)
			)
			(layer "F.SilkS")
		)
		(fp_line
			(start -0.67945 -0.305054)
			(end -0.12065 -0.305054)
			(stroke
				(width 0.1)
				(type default)
			)
			(layer "F.Fab")
		)
		(fp_line
			(start -0.67945 0.3048)
			(end -0.67945 -0.305054)
			(stroke
				(width 0.1)
				(type default)
			)
			(layer "F.Fab")
		)
		(fp_line
			(start -0.12065 -0.305054)
			(end -0.12065 -0.2794)
			(stroke
				(width 0.1)
				(type default)
			)
			(layer "F.Fab")
		)
		(fp_line
			(start -0.12065 -0.2794)
			(end 0.12065 -0.2794)
			(stroke
				(width 0.1)
				(type default)
			)
			(layer "F.Fab")
		)
		(fp_line
			(start -0.12065 0.2794)
			(end -0.12065 0.3048)
			(stroke
				(width 0.1)
				(type default)
			)
			(layer "F.Fab")
		)
		(fp_line
			(start -0.12065 0.3048)
			(end -0.67945 0.3048)
			(stroke
				(width 0.1)
				(type default)
			)
			(layer "F.Fab")
		)
		(fp_line
			(start 0.120396 0.2794)
			(end -0.12065 0.2794)
			(stroke
				(width 0.1)
				(type default)
			)
			(layer "F.Fab")
		)
		(fp_line
			(start 0.120396 0.3048)
			(end 0.120396 0.2794)
			(stroke
				(width 0.1)
				(type default)
			)
			(layer "F.Fab")
		)
		(fp_line
			(start 0.12065 -0.3048)
			(end 0.67945 -0.3048)
			(stroke
				(width 0.1)
				(type default)
			)
			(layer "F.Fab")
		)
		(fp_line
			(start 0.12065 -0.2794)
			(end 0.12065 -0.3048)
			(stroke
				(width 0.1)
				(type default)
			)
			(layer "F.Fab")
		)
		(fp_line
			(start 0.67945 -0.3048)
			(end 0.67945 0.3048)
			(stroke
				(width 0.1)
				(type default)
			)
			(layer "F.Fab")
		)
		(fp_line
			(start 0.67945 0.3048)
			(end 0.120396 0.3048)
			(stroke
				(width 0.1)
				(type default)
			)
			(layer "F.Fab")
		)
		(pad "1" smd circle
			(at -0.40005 0)
			(size 0 0)
			(layers "F.Cu" "F.Mask" "F.Paste")
			(net "SMB_LM75_1_3V3AUX_SCL")
		)
		(pad "2" smd circle
			(at 0.40005 0)
			(size 0 0)
			(layers "F.Cu" "F.Mask" "F.Paste")
			(net "SMB_LM75_1_3V3AUX_SCL_R1")
		)
	)
	(footprint ""
		(layer "F.Cu")
		(at 97.177352 -71.21398)
		(property "Reference" "PC1322"
			(at 0 0 0)
			(layer "F.SilkS")
			(hide yes)
			(effects
				(font
					(size 1.27 1.27)
				)
			)
		)
		(property "Value" ""
			(at 0 0 0)
			(layer "F.Fab")
			(effects
				(font
					(size 1.27 1.27)
				)
			)
		)
		(duplicate_pad_numbers_are_jumpers no)
		(fp_line
			(start -0.7874 -0.4064)
			(end 0.7874 -0.4064)
			(stroke
				(width 0.1524)
				(type default)
			)
			(layer "F.SilkS")
		)
		(fp_line
			(start -0.7874 0.4064)
			(end -0.7874 -0.4064)
			(stroke
				(width 0.1524)
				(type default)
			)
			(layer "F.SilkS")
		)
		(fp_line
			(start 0.7874 -0.4064)
			(end 0.7874 0.4064)
			(stroke
				(width 0.1524)
				(type default)
			)
			(layer "F.SilkS")
		)
		(fp_line
			(start 0.7874 0.4064)
			(end -0.7874 0.4064)
			(stroke
				(width 0.1524)
				(type default)
			)
			(layer "F.SilkS")
		)
		(fp_line
			(start -0.67945 -0.305054)
			(end -0.12065 -0.305054)
			(stroke
				(width 0.1)
				(type default)
			)
			(layer "F.Fab")
		)
		(fp_line
			(start -0.67945 0.3048)
			(end -0.67945 -0.305054)
			(stroke
				(width 0.1)
				(type default)
			)
			(layer "F.Fab")
		)
		(fp_line
			(start -0.12065 -0.305054)
			(end -0.12065 -0.2794)
			(stroke
				(width 0.1)
				(type default)
			)
			(layer "F.Fab")
		)
		(fp_line
			(start -0.12065 -0.2794)
			(end 0.12065 -0.2794)
			(stroke
				(width 0.1)
				(type default)
			)
			(layer "F.Fab")
		)
		(fp_line
			(start -0.12065 0.2794)
			(end -0.12065 0.3048)
			(stroke
				(width 0.1)
				(type default)
			)
			(layer "F.Fab")
		)
		(fp_line
			(start -0.12065 0.3048)
			(end -0.67945 0.3048)
			(stroke
				(width 0.1)
				(type default)
			)
			(layer "F.Fab")
		)
		(fp_line
			(start 0.120396 0.2794)
			(end -0.12065 0.2794)
			(stroke
				(width 0.1)
				(type default)
			)
			(layer "F.Fab")
		)
		(fp_line
			(start 0.120396 0.3048)
			(end 0.120396 0.2794)
			(stroke
				(width 0.1)
				(type default)
			)
			(layer "F.Fab")
		)
		(fp_line
			(start 0.12065 -0.3048)
			(end 0.67945 -0.3048)
			(stroke
				(width 0.1)
				(type default)
			)
			(layer "F.Fab")
		)
		(fp_line
			(start 0.12065 -0.2794)
			(end 0.12065 -0.3048)
			(stroke
				(width 0.1)
				(type default)
			)
			(layer "F.Fab")
		)
		(fp_line
			(start 0.67945 -0.3048)
			(end 0.67945 0.3048)
			(stroke
				(width 0.1)
				(type default)
			)
			(layer "F.Fab")
		)
		(fp_line
			(start 0.67945 0.3048)
			(end 0.120396 0.3048)
			(stroke
				(width 0.1)
				(type default)
			)
			(layer "F.Fab")
		)
		(pad "1" smd circle
			(at -0.40005 0)
			(size 0 0)
			(layers "F.Cu" "F.Mask" "F.Paste")
			(net "P3V3_OCP_GATE_PU207_2")
		)
		(pad "2" smd circle
			(at 0.40005 0)
			(size 0 0)
			(layers "F.Cu" "F.Mask" "F.Paste")
			(net "GND")
		)
	)
	(footprint ""
		(layer "F.Cu")
		(at 77.654912 -180.630068)
		(property "Reference" "PC318"
			(at 0 0 0)
			(layer "F.SilkS")
			(hide yes)
			(effects
				(font
					(size 1.27 1.27)
				)
			)
		)
		(property "Value" ""
			(at 0 0 0)
			(layer "F.Fab")
			(effects
				(font
					(size 1.27 1.27)
				)
			)
		)
		(duplicate_pad_numbers_are_jumpers no)
		(fp_line
			(start -0.7874 -0.4064)
			(end 0.7874 -0.4064)
			(stroke
				(width 0.1524)
				(type default)
			)
			(layer "F.SilkS")
		)
		(fp_line
			(start -0.7874 0.4064)
			(end -0.7874 -0.4064)
			(stroke
				(width 0.1524)
				(type default)
			)
			(layer "F.SilkS")
		)
		(fp_line
			(start 0.7874 -0.4064)
			(end 0.7874 0.4064)
			(stroke
				(width 0.1524)
				(type default)
			)
			(layer "F.SilkS")
		)
		(fp_line
			(start 0.7874 0.4064)
			(end -0.7874 0.4064)
			(stroke
				(width 0.1524)
				(type default)
			)
			(layer "F.SilkS")
		)
		(fp_line
			(start -0.67945 -0.305054)
			(end -0.12065 -0.305054)
			(stroke
				(width 0.1)
				(type default)
			)
			(layer "F.Fab")
		)
		(fp_line
			(start -0.67945 0.3048)
			(end -0.67945 -0.305054)
			(stroke
				(width 0.1)
				(type default)
			)
			(layer "F.Fab")
		)
		(fp_line
			(start -0.12065 -0.305054)
			(end -0.12065 -0.2794)
			(stroke
				(width 0.1)
				(type default)
			)
			(layer "F.Fab")
		)
		(fp_line
			(start -0.12065 -0.2794)
			(end 0.12065 -0.2794)
			(stroke
				(width 0.1)
				(type default)
			)
			(layer "F.Fab")
		)
		(fp_line
			(start -0.12065 0.2794)
			(end -0.12065 0.3048)
			(stroke
				(width 0.1)
				(type default)
			)
			(layer "F.Fab")
		)
		(fp_line
			(start -0.12065 0.3048)
			(end -0.67945 0.3048)
			(stroke
				(width 0.1)
				(type default)
			)
			(layer "F.Fab")
		)
		(fp_line
			(start 0.120396 0.2794)
			(end -0.12065 0.2794)
			(stroke
				(width 0.1)
				(type default)
			)
			(layer "F.Fab")
		)
		(fp_line
			(start 0.120396 0.3048)
			(end 0.120396 0.2794)
			(stroke
				(width 0.1)
				(type default)
			)
			(layer "F.Fab")
		)
		(fp_line
			(start 0.12065 -0.3048)
			(end 0.67945 -0.3048)
			(stroke
				(width 0.1)
				(type default)
			)
			(layer "F.Fab")
		)
		(fp_line
			(start 0.12065 -0.2794)
			(end 0.12065 -0.3048)
			(stroke
				(width 0.1)
				(type default)
			)
			(layer "F.Fab")
		)
		(fp_line
			(start 0.67945 -0.3048)
			(end 0.67945 0.3048)
			(stroke
				(width 0.1)
				(type default)
			)
			(layer "F.Fab")
		)
		(fp_line
			(start 0.67945 0.3048)
			(end 0.120396 0.3048)
			(stroke
				(width 0.1)
				(type default)
			)
			(layer "F.Fab")
		)
		(pad "1" smd circle
			(at -0.40005 0)
			(size 0 0)
			(layers "F.Cu" "F.Mask" "F.Paste")
			(net "SW_PVDDCR_CPU0_P1_SW5")
		)
		(pad "2" smd circle
			(at 0.40005 0)
			(size 0 0)
			(layers "F.Cu" "F.Mask" "F.Paste")
			(net "SW_PVDDCR_CPU0_P1_SW5_RC")
		)
	)
	(footprint ""
		(layer "F.Cu")
		(at 213.8426 -138.124438 -90)
		(property "Reference" "R2531"
			(at 0 0 270)
			(layer "F.SilkS")
			(hide yes)
			(effects
				(font
					(size 1.27 1.27)
				)
			)
		)
		(property "Value" ""
			(at 0 0 270)
			(layer "F.Fab")
			(effects
				(font
					(size 1.27 1.27)
				)
			)
		)
		(duplicate_pad_numbers_are_jumpers no)
		(fp_line
			(start -0.7874 0.4064)
			(end -0.7874 -0.4064)
			(stroke
				(width 0.1524)
				(type default)
			)
			(layer "F.SilkS")
		)
		(fp_line
			(start 0.7874 0.4064)
			(end -0.7874 0.4064)
			(stroke
				(width 0.1524)
				(type default)
			)
			(layer "F.SilkS")
		)
		(fp_line
			(start -0.7874 -0.4064)
			(end 0.7874 -0.4064)
			(stroke
				(width 0.1524)
				(type default)
			)
			(layer "F.SilkS")
		)
		(fp_line
			(start 0.7874 -0.4064)
			(end 0.7874 0.4064)
			(stroke
				(width 0.1524)
				(type default)
			)
			(layer "F.SilkS")
		)
		(fp_line
			(start -0.67945 0.3048)
			(end -0.67945 -0.305054)
			(stroke
				(width 0.1)
				(type default)
			)
			(layer "F.Fab")
		)
		(fp_line
			(start -0.12065 0.3048)
			(end -0.67945 0.3048)
			(stroke
				(width 0.1)
				(type default)
			)
			(layer "F.Fab")
		)
		(fp_line
			(start 0.120396 0.3048)
			(end 0.120396 0.2794)
			(stroke
				(width 0.1)
				(type default)
			)
			(layer "F.Fab")
		)
		(fp_line
			(start 0.67945 0.3048)
			(end 0.120396 0.3048)
			(stroke
				(width 0.1)
				(type default)
			)
			(layer "F.Fab")
		)
		(fp_line
			(start -0.12065 0.2794)
			(end -0.12065 0.3048)
			(stroke
				(width 0.1)
				(type default)
			)
			(layer "F.Fab")
		)
		(fp_line
			(start 0.120396 0.2794)
			(end -0.12065 0.2794)
			(stroke
				(width 0.1)
				(type default)
			)
			(layer "F.Fab")
		)
		(fp_line
			(start -0.12065 -0.2794)
			(end 0.12065 -0.2794)
			(stroke
				(width 0.1)
				(type default)
			)
			(layer "F.Fab")
		)
		(fp_line
			(start 0.12065 -0.2794)
			(end 0.12065 -0.3048)
			(stroke
				(width 0.1)
				(type default)
			)
			(layer "F.Fab")
		)
		(fp_line
			(start 0.12065 -0.3048)
			(end 0.67945 -0.3048)
			(stroke
				(width 0.1)
				(type default)
			)
			(layer "F.Fab")
		)
		(fp_line
			(start 0.67945 -0.3048)
			(end 0.67945 0.3048)
			(stroke
				(width 0.1)
				(type default)
			)
			(layer "F.Fab")
		)
		(fp_line
			(start -0.67945 -0.305054)
			(end -0.12065 -0.305054)
			(stroke
				(width 0.1)
				(type default)
			)
			(layer "F.Fab")
		)
		(fp_line
			(start -0.12065 -0.305054)
			(end -0.12065 -0.2794)
			(stroke
				(width 0.1)
				(type default)
			)
			(layer "F.Fab")
		)
		(pad "1" smd circle
			(at -0.40005 0 270)
			(size 0 0)
			(layers "F.Cu" "F.Mask" "F.Paste")
			(net "MB0_P12V_STBY_PWRGD")
		)
		(pad "2" smd circle
			(at 0.40005 0 270)
			(size 0 0)
			(layers "F.Cu" "F.Mask" "F.Paste")
			(net "FM_P12V_HSC_EN_R")
		)
	)
	(footprint ""
		(layer "F.Cu")
		(at 101.958902 -370.57203 -90)
		(property "Reference" "C714"
			(at 0 0 270)
			(layer "F.SilkS")
			(hide yes)
			(effects
				(font
					(size 1.27 1.27)
				)
			)
		)
		(property "Value" ""
			(at 0 0 270)
			(layer "F.Fab")
			(effects
				(font
					(size 1.27 1.27)
				)
			)
		)
		(duplicate_pad_numbers_are_jumpers no)
		(fp_line
			(start -0.299974 0.150114)
			(end -0.299974 -0.150114)
			(stroke
				(width 0.1)
				(type default)
			)
			(layer "F.Fab")
		)
		(fp_line
			(start 0.299974 0.150114)
			(end -0.299974 0.150114)
			(stroke
				(width 0.1)
				(type default)
			)
			(layer "F.Fab")
		)
		(fp_line
			(start -0.299974 -0.150114)
			(end 0.299974 -0.150114)
			(stroke
				(width 0.1)
				(type default)
			)
			(layer "F.Fab")
		)
		(fp_line
			(start 0.299974 -0.150114)
			(end 0.299974 0.150114)
			(stroke
				(width 0.1)
				(type default)
			)
			(layer "F.Fab")
		)
		(pad "1" smd rect
			(at -0.2667 0 270)
			(size 0.3048 0.381)
			(layers "F.Cu" "F.Mask" "F.Paste")
			(net "P5E_CPU1_P1_TX_C_DN<13>")
		)
		(pad "2" smd rect
			(at 0.2667 0 270)
			(size 0.3048 0.381)
			(layers "F.Cu" "F.Mask" "F.Paste")
			(net "P5E_CPU1_P1_TX_DN<13>")
		)
	)
	(footprint ""
		(layer "F.Cu")
		(at 148.642324 -115.377468)
		(property "Reference" "R8118"
			(at 0 0 0)
			(layer "F.SilkS")
			(hide yes)
			(effects
				(font
					(size 1.27 1.27)
				)
			)
		)
		(property "Value" ""
			(at 0 0 0)
			(layer "F.Fab")
			(effects
				(font
					(size 1.27 1.27)
				)
			)
		)
		(duplicate_pad_numbers_are_jumpers no)
		(fp_line
			(start -0.7874 -0.4064)
			(end 0.7874 -0.4064)
			(stroke
				(width 0.1524)
				(type default)
			)
			(layer "F.SilkS")
		)
		(fp_line
			(start -0.7874 0.4064)
			(end -0.7874 -0.4064)
			(stroke
				(width 0.1524)
				(type default)
			)
			(layer "F.SilkS")
		)
		(fp_line
			(start 0.7874 -0.4064)
			(end 0.7874 0.4064)
			(stroke
				(width 0.1524)
				(type default)
			)
			(layer "F.SilkS")
		)
		(fp_line
			(start 0.7874 0.4064)
			(end -0.7874 0.4064)
			(stroke
				(width 0.1524)
				(type default)
			)
			(layer "F.SilkS")
		)
		(fp_line
			(start -0.67945 -0.305054)
			(end -0.12065 -0.305054)
			(stroke
				(width 0.1)
				(type default)
			)
			(layer "F.Fab")
		)
		(fp_line
			(start -0.67945 0.3048)
			(end -0.67945 -0.305054)
			(stroke
				(width 0.1)
				(type default)
			)
			(layer "F.Fab")
		)
		(fp_line
			(start -0.12065 -0.305054)
			(end -0.12065 -0.2794)
			(stroke
				(width 0.1)
				(type default)
			)
			(layer "F.Fab")
		)
		(fp_line
			(start -0.12065 -0.2794)
			(end 0.12065 -0.2794)
			(stroke
				(width 0.1)
				(type default)
			)
			(layer "F.Fab")
		)
		(fp_line
			(start -0.12065 0.2794)
			(end -0.12065 0.3048)
			(stroke
				(width 0.1)
				(type default)
			)
			(layer "F.Fab")
		)
		(fp_line
			(start -0.12065 0.3048)
			(end -0.67945 0.3048)
			(stroke
				(width 0.1)
				(type default)
			)
			(layer "F.Fab")
		)
		(fp_line
			(start 0.120396 0.2794)
			(end -0.12065 0.2794)
			(stroke
				(width 0.1)
				(type default)
			)
			(layer "F.Fab")
		)
		(fp_line
			(start 0.120396 0.3048)
			(end 0.120396 0.2794)
			(stroke
				(width 0.1)
				(type default)
			)
			(layer "F.Fab")
		)
		(fp_line
			(start 0.12065 -0.3048)
			(end 0.67945 -0.3048)
			(stroke
				(width 0.1)
				(type default)
			)
			(layer "F.Fab")
		)
		(fp_line
			(start 0.12065 -0.2794)
			(end 0.12065 -0.3048)
			(stroke
				(width 0.1)
				(type default)
			)
			(layer "F.Fab")
		)
		(fp_line
			(start 0.67945 -0.3048)
			(end 0.67945 0.3048)
			(stroke
				(width 0.1)
				(type default)
			)
			(layer "F.Fab")
		)
		(fp_line
			(start 0.67945 0.3048)
			(end 0.120396 0.3048)
			(stroke
				(width 0.1)
				(type default)
			)
			(layer "F.Fab")
		)
		(pad "1" smd circle
			(at -0.40005 0)
			(size 0 0)
			(layers "F.Cu" "F.Mask" "F.Paste")
			(net "FM_UV_ADR_TRIGGER_N_R2")
		)
		(pad "2" smd circle
			(at 0.40005 0)
			(size 0 0)
			(layers "F.Cu" "F.Mask" "F.Paste")
			(net "FM_UV_ADR_TRIGGER_N")
		)
	)
	(footprint ""
		(layer "F.Cu")
		(at 37.64026 -351.372932 90)
		(property "Reference" "PR373"
			(at 0 0 90)
			(layer "F.SilkS")
			(hide yes)
			(effects
				(font
					(size 1.27 1.27)
				)
			)
		)
		(property "Value" ""
			(at 0 0 90)
			(layer "F.Fab")
			(effects
				(font
					(size 1.27 1.27)
				)
			)
		)
		(duplicate_pad_numbers_are_jumpers no)
		(fp_line
			(start 0.7874 -0.4064)
			(end 0.7874 0.4064)
			(stroke
				(width 0.1524)
				(type default)
			)
			(layer "F.SilkS")
		)
		(fp_line
			(start -0.7874 -0.4064)
			(end 0.7874 -0.4064)
			(stroke
				(width 0.1524)
				(type default)
			)
			(layer "F.SilkS")
		)
		(fp_line
			(start 0.7874 0.4064)
			(end -0.7874 0.4064)
			(stroke
				(width 0.1524)
				(type default)
			)
			(layer "F.SilkS")
		)
		(fp_line
			(start -0.7874 0.4064)
			(end -0.7874 -0.4064)
			(stroke
				(width 0.1524)
				(type default)
			)
			(layer "F.SilkS")
		)
		(fp_line
			(start -0.12065 -0.305054)
			(end -0.12065 -0.2794)
			(stroke
				(width 0.1)
				(type default)
			)
			(layer "F.Fab")
		)
		(fp_line
			(start -0.67945 -0.305054)
			(end -0.12065 -0.305054)
			(stroke
				(width 0.1)
				(type default)
			)
			(layer "F.Fab")
		)
		(fp_line
			(start 0.67945 -0.3048)
			(end 0.67945 0.3048)
			(stroke
				(width 0.1)
				(type default)
			)
			(layer "F.Fab")
		)
		(fp_line
			(start 0.12065 -0.3048)
			(end 0.67945 -0.3048)
			(stroke
				(width 0.1)
				(type default)
			)
			(layer "F.Fab")
		)
		(fp_line
			(start 0.12065 -0.2794)
			(end 0.12065 -0.3048)
			(stroke
				(width 0.1)
				(type default)
			)
			(layer "F.Fab")
		)
		(fp_line
			(start -0.12065 -0.2794)
			(end 0.12065 -0.2794)
			(stroke
				(width 0.1)
				(type default)
			)
			(layer "F.Fab")
		)
		(fp_line
			(start 0.120396 0.2794)
			(end -0.12065 0.2794)
			(stroke
				(width 0.1)
				(type default)
			)
			(layer "F.Fab")
		)
		(fp_line
			(start -0.12065 0.2794)
			(end -0.12065 0.3048)
			(stroke
				(width 0.1)
				(type default)
			)
			(layer "F.Fab")
		)
		(fp_line
			(start 0.67945 0.3048)
			(end 0.120396 0.3048)
			(stroke
				(width 0.1)
				(type default)
			)
			(layer "F.Fab")
		)
		(fp_line
			(start 0.120396 0.3048)
			(end 0.120396 0.2794)
			(stroke
				(width 0.1)
				(type default)
			)
			(layer "F.Fab")
		)
		(fp_line
			(start -0.12065 0.3048)
			(end -0.67945 0.3048)
			(stroke
				(width 0.1)
				(type default)
			)
			(layer "F.Fab")
		)
		(fp_line
			(start -0.67945 0.3048)
			(end -0.67945 -0.305054)
			(stroke
				(width 0.1)
				(type default)
			)
			(layer "F.Fab")
		)
		(pad "1" smd circle
			(at -0.40005 0 90)
			(size 0 0)
			(layers "F.Cu" "F.Mask" "F.Paste")
			(net "SW_PVDDIO_P1_BOOT3")
		)
		(pad "2" smd circle
			(at 0.40005 0 90)
			(size 0 0)
			(layers "F.Cu" "F.Mask" "F.Paste")
			(net "SW_PVDDIO_P1_BOOT3_R")
		)
	)
	(footprint ""
		(layer "F.Cu")
		(at 177.223674 -353.958652 90)
		(property "Reference" "PR387"
			(at 0 0 90)
			(layer "F.SilkS")
			(hide yes)
			(effects
				(font
					(size 1.27 1.27)
				)
			)
		)
		(property "Value" ""
			(at 0 0 90)
			(layer "F.Fab")
			(effects
				(font
					(size 1.27 1.27)
				)
			)
		)
		(duplicate_pad_numbers_are_jumpers no)
		(fp_line
			(start 0.7874 -0.4064)
			(end 0.7874 0.4064)
			(stroke
				(width 0.1524)
				(type default)
			)
			(layer "F.SilkS")
		)
		(fp_line
			(start -0.7874 -0.4064)
			(end 0.7874 -0.4064)
			(stroke
				(width 0.1524)
				(type default)
			)
			(layer "F.SilkS")
		)
		(fp_line
			(start 0.7874 0.4064)
			(end -0.7874 0.4064)
			(stroke
				(width 0.1524)
				(type default)
			)
			(layer "F.SilkS")
		)
		(fp_line
			(start -0.7874 0.4064)
			(end -0.7874 -0.4064)
			(stroke
				(width 0.1524)
				(type default)
			)
			(layer "F.SilkS")
		)
		(fp_line
			(start -0.12065 -0.305054)
			(end -0.12065 -0.2794)
			(stroke
				(width 0.1)
				(type default)
			)
			(layer "F.Fab")
		)
		(fp_line
			(start -0.67945 -0.305054)
			(end -0.12065 -0.305054)
			(stroke
				(width 0.1)
				(type default)
			)
			(layer "F.Fab")
		)
		(fp_line
			(start 0.67945 -0.3048)
			(end 0.67945 0.3048)
			(stroke
				(width 0.1)
				(type default)
			)
			(layer "F.Fab")
		)
		(fp_line
			(start 0.12065 -0.3048)
			(end 0.67945 -0.3048)
			(stroke
				(width 0.1)
				(type default)
			)
			(layer "F.Fab")
		)
		(fp_line
			(start 0.12065 -0.2794)
			(end 0.12065 -0.3048)
			(stroke
				(width 0.1)
				(type default)
			)
			(layer "F.Fab")
		)
		(fp_line
			(start -0.12065 -0.2794)
			(end 0.12065 -0.2794)
			(stroke
				(width 0.1)
				(type default)
			)
			(layer "F.Fab")
		)
		(fp_line
			(start 0.120396 0.2794)
			(end -0.12065 0.2794)
			(stroke
				(width 0.1)
				(type default)
			)
			(layer "F.Fab")
		)
		(fp_line
			(start -0.12065 0.2794)
			(end -0.12065 0.3048)
			(stroke
				(width 0.1)
				(type default)
			)
			(layer "F.Fab")
		)
		(fp_line
			(start 0.67945 0.3048)
			(end 0.120396 0.3048)
			(stroke
				(width 0.1)
				(type default)
			)
			(layer "F.Fab")
		)
		(fp_line
			(start 0.120396 0.3048)
			(end 0.120396 0.2794)
			(stroke
				(width 0.1)
				(type default)
			)
			(layer "F.Fab")
		)
		(fp_line
			(start -0.12065 0.3048)
			(end -0.67945 0.3048)
			(stroke
				(width 0.1)
				(type default)
			)
			(layer "F.Fab")
		)
		(fp_line
			(start -0.67945 0.3048)
			(end -0.67945 -0.305054)
			(stroke
				(width 0.1)
				(type default)
			)
			(layer "F.Fab")
		)
		(pad "1" smd circle
			(at -0.40005 0 90)
			(size 0 0)
			(layers "F.Cu" "F.Mask" "F.Paste")
			(net "PVDD11_S3_P1_PVCC")
		)
		(pad "2" smd circle
			(at 0.40005 0 90)
			(size 0 0)
			(layers "F.Cu" "F.Mask" "F.Paste")
			(net "P5V_AUX")
		)
	)
	(footprint ""
		(layer "F.Cu")
		(at 75.08748 -333.258668 90)
		(property "Reference" "PR513"
			(at 0 0 90)
			(layer "F.SilkS")
			(hide yes)
			(effects
				(font
					(size 1.27 1.27)
				)
			)
		)
		(property "Value" ""
			(at 0 0 90)
			(layer "F.Fab")
			(effects
				(font
					(size 1.27 1.27)
				)
			)
		)
		(duplicate_pad_numbers_are_jumpers no)
		(fp_line
			(start 0.7874 -0.4064)
			(end 0.7874 0.4064)
			(stroke
				(width 0.1524)
				(type default)
			)
			(layer "F.SilkS")
		)
		(fp_line
			(start -0.7874 -0.4064)
			(end 0.7874 -0.4064)
			(stroke
				(width 0.1524)
				(type default)
			)
			(layer "F.SilkS")
		)
		(fp_line
			(start 0.7874 0.4064)
			(end -0.7874 0.4064)
			(stroke
				(width 0.1524)
				(type default)
			)
			(layer "F.SilkS")
		)
		(fp_line
			(start -0.7874 0.4064)
			(end -0.7874 -0.4064)
			(stroke
				(width 0.1524)
				(type default)
			)
			(layer "F.SilkS")
		)
		(fp_line
			(start -0.12065 -0.305054)
			(end -0.12065 -0.2794)
			(stroke
				(width 0.1)
				(type default)
			)
			(layer "F.Fab")
		)
		(fp_line
			(start -0.67945 -0.305054)
			(end -0.12065 -0.305054)
			(stroke
				(width 0.1)
				(type default)
			)
			(layer "F.Fab")
		)
		(fp_line
			(start 0.67945 -0.3048)
			(end 0.67945 0.3048)
			(stroke
				(width 0.1)
				(type default)
			)
			(layer "F.Fab")
		)
		(fp_line
			(start 0.12065 -0.3048)
			(end 0.67945 -0.3048)
			(stroke
				(width 0.1)
				(type default)
			)
			(layer "F.Fab")
		)
		(fp_line
			(start 0.12065 -0.2794)
			(end 0.12065 -0.3048)
			(stroke
				(width 0.1)
				(type default)
			)
			(layer "F.Fab")
		)
		(fp_line
			(start -0.12065 -0.2794)
			(end 0.12065 -0.2794)
			(stroke
				(width 0.1)
				(type default)
			)
			(layer "F.Fab")
		)
		(fp_line
			(start 0.120396 0.2794)
			(end -0.12065 0.2794)
			(stroke
				(width 0.1)
				(type default)
			)
			(layer "F.Fab")
		)
		(fp_line
			(start -0.12065 0.2794)
			(end -0.12065 0.3048)
			(stroke
				(width 0.1)
				(type default)
			)
			(layer "F.Fab")
		)
		(fp_line
			(start 0.67945 0.3048)
			(end 0.120396 0.3048)
			(stroke
				(width 0.1)
				(type default)
			)
			(layer "F.Fab")
		)
		(fp_line
			(start 0.120396 0.3048)
			(end 0.120396 0.2794)
			(stroke
				(width 0.1)
				(type default)
			)
			(layer "F.Fab")
		)
		(fp_line
			(start -0.12065 0.3048)
			(end -0.67945 0.3048)
			(stroke
				(width 0.1)
				(type default)
			)
			(layer "F.Fab")
		)
		(fp_line
			(start -0.67945 0.3048)
			(end -0.67945 -0.305054)
			(stroke
				(width 0.1)
				(type default)
			)
			(layer "F.Fab")
		)
		(pad "1" smd circle
			(at -0.40005 0 90)
			(size 0 0)
			(layers "F.Cu" "F.Mask" "F.Paste")
			(net "SW_PVDDCR_CPU1_P1_SW2_RC")
		)
		(pad "2" smd circle
			(at 0.40005 0 90)
			(size 0 0)
			(layers "F.Cu" "F.Mask" "F.Paste")
			(net "GND")
		)
	)
	(footprint ""
		(layer "F.Cu")
		(at 106.892598 -18.20291)
		(property "Reference" "R3554"
			(at 0 0 0)
			(layer "F.SilkS")
			(hide yes)
			(effects
				(font
					(size 1.27 1.27)
				)
			)
		)
		(property "Value" ""
			(at 0 0 0)
			(layer "F.Fab")
			(effects
				(font
					(size 1.27 1.27)
				)
			)
		)
		(duplicate_pad_numbers_are_jumpers no)
		(fp_line
			(start -0.7874 -0.4064)
			(end 0.7874 -0.4064)
			(stroke
				(width 0.1524)
				(type default)
			)
			(layer "F.SilkS")
		)
		(fp_line
			(start -0.7874 0.4064)
			(end -0.7874 -0.4064)
			(stroke
				(width 0.1524)
				(type default)
			)
			(layer "F.SilkS")
		)
		(fp_line
			(start 0.7874 -0.4064)
			(end 0.7874 0.4064)
			(stroke
				(width 0.1524)
				(type default)
			)
			(layer "F.SilkS")
		)
		(fp_line
			(start 0.7874 0.4064)
			(end -0.7874 0.4064)
			(stroke
				(width 0.1524)
				(type default)
			)
			(layer "F.SilkS")
		)
		(fp_line
			(start -0.67945 -0.305054)
			(end -0.12065 -0.305054)
			(stroke
				(width 0.1)
				(type default)
			)
			(layer "F.Fab")
		)
		(fp_line
			(start -0.67945 0.3048)
			(end -0.67945 -0.305054)
			(stroke
				(width 0.1)
				(type default)
			)
			(layer "F.Fab")
		)
		(fp_line
			(start -0.12065 -0.305054)
			(end -0.12065 -0.2794)
			(stroke
				(width 0.1)
				(type default)
			)
			(layer "F.Fab")
		)
		(fp_line
			(start -0.12065 -0.2794)
			(end 0.12065 -0.2794)
			(stroke
				(width 0.1)
				(type default)
			)
			(layer "F.Fab")
		)
		(fp_line
			(start -0.12065 0.2794)
			(end -0.12065 0.3048)
			(stroke
				(width 0.1)
				(type default)
			)
			(layer "F.Fab")
		)
		(fp_line
			(start -0.12065 0.3048)
			(end -0.67945 0.3048)
			(stroke
				(width 0.1)
				(type default)
			)
			(layer "F.Fab")
		)
		(fp_line
			(start 0.120396 0.2794)
			(end -0.12065 0.2794)
			(stroke
				(width 0.1)
				(type default)
			)
			(layer "F.Fab")
		)
		(fp_line
			(start 0.120396 0.3048)
			(end 0.120396 0.2794)
			(stroke
				(width 0.1)
				(type default)
			)
			(layer "F.Fab")
		)
		(fp_line
			(start 0.12065 -0.3048)
			(end 0.67945 -0.3048)
			(stroke
				(width 0.1)
				(type default)
			)
			(layer "F.Fab")
		)
		(fp_line
			(start 0.12065 -0.2794)
			(end 0.12065 -0.3048)
			(stroke
				(width 0.1)
				(type default)
			)
			(layer "F.Fab")
		)
		(fp_line
			(start 0.67945 -0.3048)
			(end 0.67945 0.3048)
			(stroke
				(width 0.1)
				(type default)
			)
			(layer "F.Fab")
		)
		(fp_line
			(start 0.67945 0.3048)
			(end 0.120396 0.3048)
			(stroke
				(width 0.1)
				(type default)
			)
			(layer "F.Fab")
		)
		(pad "1" smd circle
			(at -0.40005 0)
			(size 0 0)
			(layers "F.Cu" "F.Mask" "F.Paste")
			(net "SMB_LM75_3_3V3AUX_SDA")
		)
		(pad "2" smd circle
			(at 0.40005 0)
			(size 0 0)
			(layers "F.Cu" "F.Mask" "F.Paste")
			(net "SMB_LM75_3_3V3AUX_SDA_R1")
		)
	)
	(footprint ""
		(layer "F.Cu")
		(at 182.14594 -406.659842 90)
		(property "Reference" "R3925"
			(at 0 0 90)
			(layer "F.SilkS")
			(hide yes)
			(effects
				(font
					(size 1.27 1.27)
				)
			)
		)
		(property "Value" ""
			(at 0 0 90)
			(layer "F.Fab")
			(effects
				(font
					(size 1.27 1.27)
				)
			)
		)
		(duplicate_pad_numbers_are_jumpers no)
		(fp_line
			(start 0.7874 -0.4064)
			(end 0.7874 0.4064)
			(stroke
				(width 0.1524)
				(type default)
			)
			(layer "F.SilkS")
		)
		(fp_line
			(start -0.7874 -0.4064)
			(end 0.7874 -0.4064)
			(stroke
				(width 0.1524)
				(type default)
			)
			(layer "F.SilkS")
		)
		(fp_line
			(start 0.7874 0.4064)
			(end -0.7874 0.4064)
			(stroke
				(width 0.1524)
				(type default)
			)
			(layer "F.SilkS")
		)
		(fp_line
			(start -0.7874 0.4064)
			(end -0.7874 -0.4064)
			(stroke
				(width 0.1524)
				(type default)
			)
			(layer "F.SilkS")
		)
		(fp_line
			(start -0.12065 -0.305054)
			(end -0.12065 -0.2794)
			(stroke
				(width 0.1)
				(type default)
			)
			(layer "F.Fab")
		)
		(fp_line
			(start -0.67945 -0.305054)
			(end -0.12065 -0.305054)
			(stroke
				(width 0.1)
				(type default)
			)
			(layer "F.Fab")
		)
		(fp_line
			(start 0.67945 -0.3048)
			(end 0.67945 0.3048)
			(stroke
				(width 0.1)
				(type default)
			)
			(layer "F.Fab")
		)
		(fp_line
			(start 0.12065 -0.3048)
			(end 0.67945 -0.3048)
			(stroke
				(width 0.1)
				(type default)
			)
			(layer "F.Fab")
		)
		(fp_line
			(start 0.12065 -0.2794)
			(end 0.12065 -0.3048)
			(stroke
				(width 0.1)
				(type default)
			)
			(layer "F.Fab")
		)
		(fp_line
			(start -0.12065 -0.2794)
			(end 0.12065 -0.2794)
			(stroke
				(width 0.1)
				(type default)
			)
			(layer "F.Fab")
		)
		(fp_line
			(start 0.120396 0.2794)
			(end -0.12065 0.2794)
			(stroke
				(width 0.1)
				(type default)
			)
			(layer "F.Fab")
		)
		(fp_line
			(start -0.12065 0.2794)
			(end -0.12065 0.3048)
			(stroke
				(width 0.1)
				(type default)
			)
			(layer "F.Fab")
		)
		(fp_line
			(start 0.67945 0.3048)
			(end 0.120396 0.3048)
			(stroke
				(width 0.1)
				(type default)
			)
			(layer "F.Fab")
		)
		(fp_line
			(start 0.120396 0.3048)
			(end 0.120396 0.2794)
			(stroke
				(width 0.1)
				(type default)
			)
			(layer "F.Fab")
		)
		(fp_line
			(start -0.12065 0.3048)
			(end -0.67945 0.3048)
			(stroke
				(width 0.1)
				(type default)
			)
			(layer "F.Fab")
		)
		(fp_line
			(start -0.67945 0.3048)
			(end -0.67945 -0.305054)
			(stroke
				(width 0.1)
				(type default)
			)
			(layer "F.Fab")
		)
		(pad "1" smd circle
			(at -0.40005 0 90)
			(size 0 0)
			(layers "F.Cu" "F.Mask" "F.Paste")
			(net "IRQ_SML1_PMBUS_ALERT")
		)
		(pad "2" smd circle
			(at 0.40005 0 90)
			(size 0 0)
			(layers "F.Cu" "F.Mask" "F.Paste")
			(net "P3V3_AUX")
		)
	)
	(footprint ""
		(layer "F.Cu")
		(at 75.219306 -152.990804 90)
		(property "Reference" "PC150"
			(at 0 0 90)
			(layer "F.SilkS")
			(hide yes)
			(effects
				(font
					(size 1.27 1.27)
				)
			)
		)
		(property "Value" ""
			(at 0 0 90)
			(layer "F.Fab")
			(effects
				(font
					(size 1.27 1.27)
				)
			)
		)
		(duplicate_pad_numbers_are_jumpers no)
		(fp_line
			(start 1.524 -0.762)
			(end 1.524 0.762)
			(stroke
				(width 0.1524)
				(type default)
			)
			(layer "F.SilkS")
		)
		(fp_line
			(start -1.524 -0.762)
			(end 1.524 -0.762)
			(stroke
				(width 0.1524)
				(type default)
			)
			(layer "F.SilkS")
		)
		(fp_line
			(start 1.524 0.762)
			(end -1.524 0.762)
			(stroke
				(width 0.1524)
				(type default)
			)
			(layer "F.SilkS")
		)
		(fp_line
			(start -1.524 0.762)
			(end -1.524 -0.762)
			(stroke
				(width 0.1524)
				(type default)
			)
			(layer "F.SilkS")
		)
		(fp_line
			(start 1.1049 -0.724916)
			(end -1.1049 -0.724916)
			(stroke
				(width 0.1)
				(type default)
			)
			(layer "F.Fab")
		)
		(fp_line
			(start -1.1049 -0.724916)
			(end -1.1049 0.724916)
			(stroke
				(width 0.1)
				(type default)
			)
			(layer "F.Fab")
		)
		(fp_line
			(start 1.1049 0.724916)
			(end 1.1049 -0.724916)
			(stroke
				(width 0.1)
				(type default)
			)
			(layer "F.Fab")
		)
		(fp_line
			(start -1.1049 0.724916)
			(end 1.1049 0.724916)
			(stroke
				(width 0.1)
				(type default)
			)
			(layer "F.Fab")
		)
		(pad "1" smd rect
			(at -0.889 0 270)
			(size 1.016 1.27)
			(layers "F.Cu" "F.Mask" "F.Paste")
			(net "SW_P12V_AUX_PVDD18_S5_P1_FLT")
		)
		(pad "2" smd rect
			(at 0.889 0 270)
			(size 1.016 1.27)
			(layers "F.Cu" "F.Mask" "F.Paste")
			(net "GND")
		)
	)
	(footprint ""
		(layer "F.Cu")
		(at 32.601662 -419.249098 -90)
		(property "Reference" "R3273"
			(at 0 0 270)
			(layer "F.SilkS")
			(hide yes)
			(effects
				(font
					(size 1.27 1.27)
				)
			)
		)
		(property "Value" ""
			(at 0 0 270)
			(layer "F.Fab")
			(effects
				(font
					(size 1.27 1.27)
				)
			)
		)
		(duplicate_pad_numbers_are_jumpers no)
		(fp_line
			(start -0.7874 0.4064)
			(end -0.7874 -0.4064)
			(stroke
				(width 0.1524)
				(type default)
			)
			(layer "F.SilkS")
		)
		(fp_line
			(start 0.7874 0.4064)
			(end -0.7874 0.4064)
			(stroke
				(width 0.1524)
				(type default)
			)
			(layer "F.SilkS")
		)
		(fp_line
			(start -0.7874 -0.4064)
			(end 0.7874 -0.4064)
			(stroke
				(width 0.1524)
				(type default)
			)
			(layer "F.SilkS")
		)
		(fp_line
			(start 0.7874 -0.4064)
			(end 0.7874 0.4064)
			(stroke
				(width 0.1524)
				(type default)
			)
			(layer "F.SilkS")
		)
		(fp_line
			(start -0.67945 0.3048)
			(end -0.67945 -0.305054)
			(stroke
				(width 0.1)
				(type default)
			)
			(layer "F.Fab")
		)
		(fp_line
			(start -0.12065 0.3048)
			(end -0.67945 0.3048)
			(stroke
				(width 0.1)
				(type default)
			)
			(layer "F.Fab")
		)
		(fp_line
			(start 0.120396 0.3048)
			(end 0.120396 0.2794)
			(stroke
				(width 0.1)
				(type default)
			)
			(layer "F.Fab")
		)
		(fp_line
			(start 0.67945 0.3048)
			(end 0.120396 0.3048)
			(stroke
				(width 0.1)
				(type default)
			)
			(layer "F.Fab")
		)
		(fp_line
			(start -0.12065 0.2794)
			(end -0.12065 0.3048)
			(stroke
				(width 0.1)
				(type default)
			)
			(layer "F.Fab")
		)
		(fp_line
			(start 0.120396 0.2794)
			(end -0.12065 0.2794)
			(stroke
				(width 0.1)
				(type default)
			)
			(layer "F.Fab")
		)
		(fp_line
			(start -0.12065 -0.2794)
			(end 0.12065 -0.2794)
			(stroke
				(width 0.1)
				(type default)
			)
			(layer "F.Fab")
		)
		(fp_line
			(start 0.12065 -0.2794)
			(end 0.12065 -0.3048)
			(stroke
				(width 0.1)
				(type default)
			)
			(layer "F.Fab")
		)
		(fp_line
			(start 0.12065 -0.3048)
			(end 0.67945 -0.3048)
			(stroke
				(width 0.1)
				(type default)
			)
			(layer "F.Fab")
		)
		(fp_line
			(start 0.67945 -0.3048)
			(end 0.67945 0.3048)
			(stroke
				(width 0.1)
				(type default)
			)
			(layer "F.Fab")
		)
		(fp_line
			(start -0.67945 -0.305054)
			(end -0.12065 -0.305054)
			(stroke
				(width 0.1)
				(type default)
			)
			(layer "F.Fab")
		)
		(fp_line
			(start -0.12065 -0.305054)
			(end -0.12065 -0.2794)
			(stroke
				(width 0.1)
				(type default)
			)
			(layer "F.Fab")
		)
		(pad "1" smd circle
			(at -0.40005 0 270)
			(size 0 0)
			(layers "F.Cu" "F.Mask" "F.Paste")
			(net "FM_P2E_FGA")
		)
		(pad "2" smd circle
			(at 0.40005 0 270)
			(size 0 0)
			(layers "F.Cu" "F.Mask" "F.Paste")
			(net "GND")
		)
	)
	(footprint ""
		(layer "F.Cu")
		(at 252.88875 -99.065842 -90)
		(property "Reference" "U150"
			(at 1.886204 -3.446272 90)
			(unlocked yes)
			(layer "F.SilkS")
			(effects
				(font
					(size 0.7874 0.5842)
					(thickness 0.1524)
				)
				(justify left)
			)
		)
		(property "Value" ""
			(at 0 0 270)
			(layer "F.Fab")
			(effects
				(font
					(size 1.27 1.27)
				)
			)
		)
		(duplicate_pad_numbers_are_jumpers no)
		(fp_line
			(start -1.868932 2.549906)
			(end 1.868932 2.549906)
			(stroke
				(width 0.1524)
				(type default)
			)
			(layer "F.SilkS")
		)
		(fp_line
			(start 1.868932 2.549906)
			(end 1.868932 -2.549906)
			(stroke
				(width 0.1524)
				(type default)
			)
			(layer "F.SilkS")
		)
		(fp_line
			(start 0 -1.524)
			(end -1.025906 -2.549906)
			(stroke
				(width 0.1524)
				(type default)
			)
			(layer "F.SilkS")
		)
		(fp_line
			(start -1.868932 -2.549906)
			(end -1.868932 2.549906)
			(stroke
				(width 0.1524)
				(type default)
			)
			(layer "F.SilkS")
		)
		(fp_line
			(start -1.025906 -2.549906)
			(end -1.868932 -2.549906)
			(stroke
				(width 0.1524)
				(type default)
			)
			(layer "F.SilkS")
		)
		(fp_line
			(start 1.025906 -2.549906)
			(end 0 -1.524)
			(stroke
				(width 0.1524)
				(type default)
			)
			(layer "F.SilkS")
		)
		(fp_line
			(start 1.868932 -2.549906)
			(end 1.025906 -2.549906)
			(stroke
				(width 0.1524)
				(type default)
			)
			(layer "F.SilkS")
		)
		(fp_poly
			(pts
				(xy -3.7592 -2.295398) (xy -4.7752 -1.787398) (xy -4.7752 -2.803398)
			)
			(stroke
				(width 0)
				(type default)
			)
			(fill yes)
			(layer "F.SilkS")
		)
		(fp_line
			(start -2.249932 2.549906)
			(end 2.249932 2.549906)
			(stroke
				(width 0.1)
				(type default)
			)
			(layer "F.Fab")
		)
		(fp_line
			(start 2.249932 2.549906)
			(end 2.249932 -2.549906)
			(stroke
				(width 0.1)
				(type default)
			)
			(layer "F.Fab")
		)
		(fp_line
			(start -2.249932 -2.549906)
			(end -2.249932 2.549906)
			(stroke
				(width 0.1)
				(type default)
			)
			(layer "F.Fab")
		)
		(fp_line
			(start 2.249932 -2.549906)
			(end -2.249932 -2.549906)
			(stroke
				(width 0.1)
				(type default)
			)
			(layer "F.Fab")
		)
		(fp_poly
			(pts
				(xy -4.7752 -1.787398) (xy -4.7752 -2.803398) (xy -3.7592 -2.295398)
			)
			(stroke
				(width 0)
				(type default)
			)
			(fill yes)
			(layer "F.Fab")
		)
		(pad "1" smd rect
			(at -2.800096 -2.275078 180)
			(size 0.3556 1.6002)
			(layers "F.Cu" "F.Mask" "F.Paste")
			(net "PVDD18_S5_P0")
		)
		(pad "2" smd rect
			(at -2.800096 -1.625092 180)
			(size 0.3556 1.6002)
			(layers "F.Cu" "F.Mask" "F.Paste")
			(net "PVDD18_S5_P0")
		)
		(pad "3" smd rect
			(at -2.800096 -0.975106 180)
			(size 0.3556 1.6002)
			(layers "F.Cu" "F.Mask" "F.Paste")
			(net "JTAG_TCK")
		)
		(pad "4" smd rect
			(at -2.800096 -0.32512 180)
			(size 0.3556 1.6002)
			(layers "F.Cu" "F.Mask" "F.Paste")
			(net "JTAG_TMS")
		)
		(pad "5" smd rect
			(at -2.800096 0.32512 180)
			(size 0.3556 1.6002)
			(layers "F.Cu" "F.Mask" "F.Paste")
			(net "JTAG_TRST_N")
		)
		(pad "6" smd rect
			(at -2.800096 0.975106 180)
			(size 0.3556 1.6002)
			(layers "F.Cu" "F.Mask" "F.Paste")
			(net "JTAG_DBREQ_N")
		)
		(pad "7" smd rect
			(at -2.800096 1.625092 180)
			(size 0.3556 1.6002)
			(layers "F.Cu" "F.Mask" "F.Paste")
			(net "PVDD18_S5_P0")
		)
		(pad "8" smd rect
			(at -2.800096 2.275078 180)
			(size 0.3556 1.6002)
			(layers "F.Cu" "F.Mask" "F.Paste")
			(net "PVDD18_S5_P0")
		)
		(pad "9" smd rect
			(at 2.800096 2.275078 180)
			(size 0.3556 1.6002)
			(layers "F.Cu" "F.Mask" "F.Paste")
			(net "CPU0_JTAG_BUF_OE")
		)
		(pad "10" smd rect
			(at 2.800096 1.625092 180)
			(size 0.3556 1.6002)
			(layers "F.Cu" "F.Mask" "F.Paste")
			(net "GND")
		)
		(pad "11" smd rect
			(at 2.800096 0.975106 180)
			(size 0.3556 1.6002)
			(layers "F.Cu" "F.Mask" "F.Paste")
			(net "JTAG_P0_R_DBREQ_N")
		)
		(pad "12" smd rect
			(at 2.800096 0.32512 180)
			(size 0.3556 1.6002)
			(layers "F.Cu" "F.Mask" "F.Paste")
			(net "JTAG_P0_R_TRST_N")
		)
		(pad "13" smd rect
			(at 2.800096 -0.32512 180)
			(size 0.3556 1.6002)
			(layers "F.Cu" "F.Mask" "F.Paste")
			(net "JTAG_P0_R_TMS")
		)
		(pad "14" smd rect
			(at 2.800096 -0.975106 180)
			(size 0.3556 1.6002)
			(layers "F.Cu" "F.Mask" "F.Paste")
			(net "JTAG_P0_R_TCK")
		)
		(pad "15" smd rect
			(at 2.800096 -1.625092 180)
			(size 0.3556 1.6002)
			(layers "F.Cu" "F.Mask" "F.Paste")
			(net "PVDD18_S5_P0")
		)
		(pad "16" smd rect
			(at 2.800096 -2.275078 180)
			(size 0.3556 1.6002)
			(layers "F.Cu" "F.Mask" "F.Paste")
			(net "PVDD18_S5_P0")
		)
	)
	(footprint ""
		(layer "F.Cu")
		(at 92.759784 -33.06191)
		(property "Reference" "C38"
			(at 0 0 0)
			(layer "F.SilkS")
			(hide yes)
			(effects
				(font
					(size 1.27 1.27)
				)
			)
		)
		(property "Value" ""
			(at 0 0 0)
			(layer "F.Fab")
			(effects
				(font
					(size 1.27 1.27)
				)
			)
		)
		(duplicate_pad_numbers_are_jumpers no)
		(fp_line
			(start -0.7874 -0.4064)
			(end 0.7874 -0.4064)
			(stroke
				(width 0.1524)
				(type default)
			)
			(layer "F.SilkS")
		)
		(fp_line
			(start -0.7874 0.4064)
			(end -0.7874 -0.4064)
			(stroke
				(width 0.1524)
				(type default)
			)
			(layer "F.SilkS")
		)
		(fp_line
			(start 0.7874 -0.4064)
			(end 0.7874 0.4064)
			(stroke
				(width 0.1524)
				(type default)
			)
			(layer "F.SilkS")
		)
		(fp_line
			(start 0.7874 0.4064)
			(end -0.7874 0.4064)
			(stroke
				(width 0.1524)
				(type default)
			)
			(layer "F.SilkS")
		)
		(fp_line
			(start -0.67945 -0.305054)
			(end -0.12065 -0.305054)
			(stroke
				(width 0.1)
				(type default)
			)
			(layer "F.Fab")
		)
		(fp_line
			(start -0.67945 0.3048)
			(end -0.67945 -0.305054)
			(stroke
				(width 0.1)
				(type default)
			)
			(layer "F.Fab")
		)
		(fp_line
			(start -0.12065 -0.305054)
			(end -0.12065 -0.2794)
			(stroke
				(width 0.1)
				(type default)
			)
			(layer "F.Fab")
		)
		(fp_line
			(start -0.12065 -0.2794)
			(end 0.12065 -0.2794)
			(stroke
				(width 0.1)
				(type default)
			)
			(layer "F.Fab")
		)
		(fp_line
			(start -0.12065 0.2794)
			(end -0.12065 0.3048)
			(stroke
				(width 0.1)
				(type default)
			)
			(layer "F.Fab")
		)
		(fp_line
			(start -0.12065 0.3048)
			(end -0.67945 0.3048)
			(stroke
				(width 0.1)
				(type default)
			)
			(layer "F.Fab")
		)
		(fp_line
			(start 0.120396 0.2794)
			(end -0.12065 0.2794)
			(stroke
				(width 0.1)
				(type default)
			)
			(layer "F.Fab")
		)
		(fp_line
			(start 0.120396 0.3048)
			(end 0.120396 0.2794)
			(stroke
				(width 0.1)
				(type default)
			)
			(layer "F.Fab")
		)
		(fp_line
			(start 0.12065 -0.3048)
			(end 0.67945 -0.3048)
			(stroke
				(width 0.1)
				(type default)
			)
			(layer "F.Fab")
		)
		(fp_line
			(start 0.12065 -0.2794)
			(end 0.12065 -0.3048)
			(stroke
				(width 0.1)
				(type default)
			)
			(layer "F.Fab")
		)
		(fp_line
			(start 0.67945 -0.3048)
			(end 0.67945 0.3048)
			(stroke
				(width 0.1)
				(type default)
			)
			(layer "F.Fab")
		)
		(fp_line
			(start 0.67945 0.3048)
			(end 0.120396 0.3048)
			(stroke
				(width 0.1)
				(type default)
			)
			(layer "F.Fab")
		)
		(pad "1" smd circle
			(at -0.40005 0)
			(size 0 0)
			(layers "F.Cu" "F.Mask" "F.Paste")
			(net "P3V3_AUX")
		)
		(pad "2" smd circle
			(at 0.40005 0)
			(size 0 0)
			(layers "F.Cu" "F.Mask" "F.Paste")
			(net "GND")
		)
	)
	(footprint ""
		(layer "F.Cu")
		(at 305.197002 -119.475504)
		(property "Reference" "R721"
			(at 0 0 0)
			(layer "F.SilkS")
			(hide yes)
			(effects
				(font
					(size 1.27 1.27)
				)
			)
		)
		(property "Value" ""
			(at 0 0 0)
			(layer "F.Fab")
			(effects
				(font
					(size 1.27 1.27)
				)
			)
		)
		(duplicate_pad_numbers_are_jumpers no)
		(fp_line
			(start -0.7874 -0.4064)
			(end 0.7874 -0.4064)
			(stroke
				(width 0.1524)
				(type default)
			)
			(layer "F.SilkS")
		)
		(fp_line
			(start -0.7874 0.4064)
			(end -0.7874 -0.4064)
			(stroke
				(width 0.1524)
				(type default)
			)
			(layer "F.SilkS")
		)
		(fp_line
			(start 0.7874 -0.4064)
			(end 0.7874 0.4064)
			(stroke
				(width 0.1524)
				(type default)
			)
			(layer "F.SilkS")
		)
		(fp_line
			(start 0.7874 0.4064)
			(end -0.7874 0.4064)
			(stroke
				(width 0.1524)
				(type default)
			)
			(layer "F.SilkS")
		)
		(fp_line
			(start -0.67945 -0.305054)
			(end -0.12065 -0.305054)
			(stroke
				(width 0.1)
				(type default)
			)
			(layer "F.Fab")
		)
		(fp_line
			(start -0.67945 0.3048)
			(end -0.67945 -0.305054)
			(stroke
				(width 0.1)
				(type default)
			)
			(layer "F.Fab")
		)
		(fp_line
			(start -0.12065 -0.305054)
			(end -0.12065 -0.2794)
			(stroke
				(width 0.1)
				(type default)
			)
			(layer "F.Fab")
		)
		(fp_line
			(start -0.12065 -0.2794)
			(end 0.12065 -0.2794)
			(stroke
				(width 0.1)
				(type default)
			)
			(layer "F.Fab")
		)
		(fp_line
			(start -0.12065 0.2794)
			(end -0.12065 0.3048)
			(stroke
				(width 0.1)
				(type default)
			)
			(layer "F.Fab")
		)
		(fp_line
			(start -0.12065 0.3048)
			(end -0.67945 0.3048)
			(stroke
				(width 0.1)
				(type default)
			)
			(layer "F.Fab")
		)
		(fp_line
			(start 0.120396 0.2794)
			(end -0.12065 0.2794)
			(stroke
				(width 0.1)
				(type default)
			)
			(layer "F.Fab")
		)
		(fp_line
			(start 0.120396 0.3048)
			(end 0.120396 0.2794)
			(stroke
				(width 0.1)
				(type default)
			)
			(layer "F.Fab")
		)
		(fp_line
			(start 0.12065 -0.3048)
			(end 0.67945 -0.3048)
			(stroke
				(width 0.1)
				(type default)
			)
			(layer "F.Fab")
		)
		(fp_line
			(start 0.12065 -0.2794)
			(end 0.12065 -0.3048)
			(stroke
				(width 0.1)
				(type default)
			)
			(layer "F.Fab")
		)
		(fp_line
			(start 0.67945 -0.3048)
			(end 0.67945 0.3048)
			(stroke
				(width 0.1)
				(type default)
			)
			(layer "F.Fab")
		)
		(fp_line
			(start 0.67945 0.3048)
			(end 0.120396 0.3048)
			(stroke
				(width 0.1)
				(type default)
			)
			(layer "F.Fab")
		)
		(pad "1" smd circle
			(at -0.40005 0)
			(size 0 0)
			(layers "F.Cu" "F.Mask" "F.Paste")
			(net "P3V3_AUX")
		)
		(pad "2" smd circle
			(at 0.40005 0)
			(size 0 0)
			(layers "F.Cu" "F.Mask" "F.Paste")
			(net "MB_FRU_ADDR0")
		)
	)
	(footprint ""
		(layer "F.Cu")
		(at 197.269608 -108.545376 180)
		(property "Reference" "R279"
			(at 0 0 180)
			(layer "F.SilkS")
			(hide yes)
			(effects
				(font
					(size 1.27 1.27)
				)
			)
		)
		(property "Value" ""
			(at 0 0 180)
			(layer "F.Fab")
			(effects
				(font
					(size 1.27 1.27)
				)
			)
		)
		(duplicate_pad_numbers_are_jumpers no)
		(fp_line
			(start 0.7874 0.4064)
			(end -0.7874 0.4064)
			(stroke
				(width 0.1524)
				(type default)
			)
			(layer "F.SilkS")
		)
		(fp_line
			(start 0.7874 -0.4064)
			(end 0.7874 0.4064)
			(stroke
				(width 0.1524)
				(type default)
			)
			(layer "F.SilkS")
		)
		(fp_line
			(start -0.7874 0.4064)
			(end -0.7874 -0.4064)
			(stroke
				(width 0.1524)
				(type default)
			)
			(layer "F.SilkS")
		)
		(fp_line
			(start -0.7874 -0.4064)
			(end 0.7874 -0.4064)
			(stroke
				(width 0.1524)
				(type default)
			)
			(layer "F.SilkS")
		)
		(fp_line
			(start 0.67945 0.3048)
			(end 0.120396 0.3048)
			(stroke
				(width 0.1)
				(type default)
			)
			(layer "F.Fab")
		)
		(fp_line
			(start 0.67945 -0.3048)
			(end 0.67945 0.3048)
			(stroke
				(width 0.1)
				(type default)
			)
			(layer "F.Fab")
		)
		(fp_line
			(start 0.12065 -0.2794)
			(end 0.12065 -0.3048)
			(stroke
				(width 0.1)
				(type default)
			)
			(layer "F.Fab")
		)
		(fp_line
			(start 0.12065 -0.3048)
			(end 0.67945 -0.3048)
			(stroke
				(width 0.1)
				(type default)
			)
			(layer "F.Fab")
		)
		(fp_line
			(start 0.120396 0.3048)
			(end 0.120396 0.2794)
			(stroke
				(width 0.1)
				(type default)
			)
			(layer "F.Fab")
		)
		(fp_line
			(start 0.120396 0.2794)
			(end -0.12065 0.2794)
			(stroke
				(width 0.1)
				(type default)
			)
			(layer "F.Fab")
		)
		(fp_line
			(start -0.12065 0.3048)
			(end -0.67945 0.3048)
			(stroke
				(width 0.1)
				(type default)
			)
			(layer "F.Fab")
		)
		(fp_line
			(start -0.12065 0.2794)
			(end -0.12065 0.3048)
			(stroke
				(width 0.1)
				(type default)
			)
			(layer "F.Fab")
		)
		(fp_line
			(start -0.12065 -0.2794)
			(end 0.12065 -0.2794)
			(stroke
				(width 0.1)
				(type default)
			)
			(layer "F.Fab")
		)
		(fp_line
			(start -0.12065 -0.305054)
			(end -0.12065 -0.2794)
			(stroke
				(width 0.1)
				(type default)
			)
			(layer "F.Fab")
		)
		(fp_line
			(start -0.67945 0.3048)
			(end -0.67945 -0.305054)
			(stroke
				(width 0.1)
				(type default)
			)
			(layer "F.Fab")
		)
		(fp_line
			(start -0.67945 -0.305054)
			(end -0.12065 -0.305054)
			(stroke
				(width 0.1)
				(type default)
			)
			(layer "F.Fab")
		)
		(pad "1" smd circle
			(at -0.40005 0 180)
			(size 0 0)
			(layers "F.Cu" "F.Mask" "F.Paste")
			(net "PVDD11_S3_P1_EN")
		)
		(pad "2" smd circle
			(at 0.40005 0 180)
			(size 0 0)
			(layers "F.Cu" "F.Mask" "F.Paste")
			(net "FM_PVDD11_S3_P1_EN")
		)
	)
	(footprint ""
		(layer "F.Cu")
		(at 432.974496 -109.13745 90)
		(property "Reference" "PR5481"
			(at 0 0 90)
			(layer "F.SilkS")
			(hide yes)
			(effects
				(font
					(size 1.27 1.27)
				)
			)
		)
		(property "Value" ""
			(at 0 0 90)
			(layer "F.Fab")
			(effects
				(font
					(size 1.27 1.27)
				)
			)
		)
		(duplicate_pad_numbers_are_jumpers no)
		(fp_line
			(start 0.7874 -0.4064)
			(end 0.7874 0.4064)
			(stroke
				(width 0.1524)
				(type default)
			)
			(layer "F.SilkS")
		)
		(fp_line
			(start -0.7874 -0.4064)
			(end 0.7874 -0.4064)
			(stroke
				(width 0.1524)
				(type default)
			)
			(layer "F.SilkS")
		)
		(fp_line
			(start 0.7874 0.4064)
			(end -0.7874 0.4064)
			(stroke
				(width 0.1524)
				(type default)
			)
			(layer "F.SilkS")
		)
		(fp_line
			(start -0.7874 0.4064)
			(end -0.7874 -0.4064)
			(stroke
				(width 0.1524)
				(type default)
			)
			(layer "F.SilkS")
		)
		(fp_line
			(start -0.12065 -0.305054)
			(end -0.12065 -0.2794)
			(stroke
				(width 0.1)
				(type default)
			)
			(layer "F.Fab")
		)
		(fp_line
			(start -0.67945 -0.305054)
			(end -0.12065 -0.305054)
			(stroke
				(width 0.1)
				(type default)
			)
			(layer "F.Fab")
		)
		(fp_line
			(start 0.67945 -0.3048)
			(end 0.67945 0.3048)
			(stroke
				(width 0.1)
				(type default)
			)
			(layer "F.Fab")
		)
		(fp_line
			(start 0.12065 -0.3048)
			(end 0.67945 -0.3048)
			(stroke
				(width 0.1)
				(type default)
			)
			(layer "F.Fab")
		)
		(fp_line
			(start 0.12065 -0.2794)
			(end 0.12065 -0.3048)
			(stroke
				(width 0.1)
				(type default)
			)
			(layer "F.Fab")
		)
		(fp_line
			(start -0.12065 -0.2794)
			(end 0.12065 -0.2794)
			(stroke
				(width 0.1)
				(type default)
			)
			(layer "F.Fab")
		)
		(fp_line
			(start 0.120396 0.2794)
			(end -0.12065 0.2794)
			(stroke
				(width 0.1)
				(type default)
			)
			(layer "F.Fab")
		)
		(fp_line
			(start -0.12065 0.2794)
			(end -0.12065 0.3048)
			(stroke
				(width 0.1)
				(type default)
			)
			(layer "F.Fab")
		)
		(fp_line
			(start 0.67945 0.3048)
			(end 0.120396 0.3048)
			(stroke
				(width 0.1)
				(type default)
			)
			(layer "F.Fab")
		)
		(fp_line
			(start 0.120396 0.3048)
			(end 0.120396 0.2794)
			(stroke
				(width 0.1)
				(type default)
			)
			(layer "F.Fab")
		)
		(fp_line
			(start -0.12065 0.3048)
			(end -0.67945 0.3048)
			(stroke
				(width 0.1)
				(type default)
			)
			(layer "F.Fab")
		)
		(fp_line
			(start -0.67945 0.3048)
			(end -0.67945 -0.305054)
			(stroke
				(width 0.1)
				(type default)
			)
			(layer "F.Fab")
		)
		(pad "1" smd circle
			(at -0.40005 0 90)
			(size 0 0)
			(layers "F.Cu" "F.Mask" "F.Paste")
			(net "P3V3_OCP_SENSE_1")
		)
		(pad "2" smd circle
			(at 0.40005 0 90)
			(size 0 0)
			(layers "F.Cu" "F.Mask" "F.Paste")
			(net "GND")
		)
	)
	(footprint ""
		(layer "F.Cu")
		(at 325.9074 -364.236)
		(property "Reference" "R351"
			(at 0 0 0)
			(layer "F.SilkS")
			(hide yes)
			(effects
				(font
					(size 1.27 1.27)
				)
			)
		)
		(property "Value" ""
			(at 0 0 0)
			(layer "F.Fab")
			(effects
				(font
					(size 1.27 1.27)
				)
			)
		)
		(duplicate_pad_numbers_are_jumpers no)
		(fp_line
			(start -0.7874 -0.4064)
			(end 0.7874 -0.4064)
			(stroke
				(width 0.1524)
				(type default)
			)
			(layer "F.SilkS")
		)
		(fp_line
			(start -0.7874 0.4064)
			(end -0.7874 -0.4064)
			(stroke
				(width 0.1524)
				(type default)
			)
			(layer "F.SilkS")
		)
		(fp_line
			(start 0.7874 -0.4064)
			(end 0.7874 0.4064)
			(stroke
				(width 0.1524)
				(type default)
			)
			(layer "F.SilkS")
		)
		(fp_line
			(start 0.7874 0.4064)
			(end -0.7874 0.4064)
			(stroke
				(width 0.1524)
				(type default)
			)
			(layer "F.SilkS")
		)
		(fp_line
			(start -0.67945 -0.305054)
			(end -0.12065 -0.305054)
			(stroke
				(width 0.1)
				(type default)
			)
			(layer "F.Fab")
		)
		(fp_line
			(start -0.67945 0.3048)
			(end -0.67945 -0.305054)
			(stroke
				(width 0.1)
				(type default)
			)
			(layer "F.Fab")
		)
		(fp_line
			(start -0.12065 -0.305054)
			(end -0.12065 -0.2794)
			(stroke
				(width 0.1)
				(type default)
			)
			(layer "F.Fab")
		)
		(fp_line
			(start -0.12065 -0.2794)
			(end 0.12065 -0.2794)
			(stroke
				(width 0.1)
				(type default)
			)
			(layer "F.Fab")
		)
		(fp_line
			(start -0.12065 0.2794)
			(end -0.12065 0.3048)
			(stroke
				(width 0.1)
				(type default)
			)
			(layer "F.Fab")
		)
		(fp_line
			(start -0.12065 0.3048)
			(end -0.67945 0.3048)
			(stroke
				(width 0.1)
				(type default)
			)
			(layer "F.Fab")
		)
		(fp_line
			(start 0.120396 0.2794)
			(end -0.12065 0.2794)
			(stroke
				(width 0.1)
				(type default)
			)
			(layer "F.Fab")
		)
		(fp_line
			(start 0.120396 0.3048)
			(end 0.120396 0.2794)
			(stroke
				(width 0.1)
				(type default)
			)
			(layer "F.Fab")
		)
		(fp_line
			(start 0.12065 -0.3048)
			(end 0.67945 -0.3048)
			(stroke
				(width 0.1)
				(type default)
			)
			(layer "F.Fab")
		)
		(fp_line
			(start 0.12065 -0.2794)
			(end 0.12065 -0.3048)
			(stroke
				(width 0.1)
				(type default)
			)
			(layer "F.Fab")
		)
		(fp_line
			(start 0.67945 -0.3048)
			(end 0.67945 0.3048)
			(stroke
				(width 0.1)
				(type default)
			)
			(layer "F.Fab")
		)
		(fp_line
			(start 0.67945 0.3048)
			(end 0.120396 0.3048)
			(stroke
				(width 0.1)
				(type default)
			)
			(layer "F.Fab")
		)
		(pad "1" smd circle
			(at -0.40005 0)
			(size 0 0)
			(layers "F.Cu" "F.Mask" "F.Paste")
			(net "SMB_SCM_2_R5_SCL")
		)
		(pad "2" smd circle
			(at 0.40005 0)
			(size 0 0)
			(layers "F.Cu" "F.Mask" "F.Paste")
			(net "SMB_SCM_2_R6_SCL")
		)
	)
	(footprint ""
		(layer "F.Cu")
		(at 300.538388 0.002794 180)
		(property "Reference" "J81"
			(at -4.350766 -1.264158 90)
			(unlocked yes)
			(layer "F.SilkS")
			(effects
				(font
					(size 0.7874 0.5842)
					(thickness 0.1524)
				)
				(justify left)
			)
		)
		(property "Value" ""
			(at 0 0 180)
			(layer "F.Fab")
			(effects
				(font
					(size 1.27 1.27)
				)
			)
		)
		(duplicate_pad_numbers_are_jumpers no)
		(fp_line
			(start 1.2192 2.06756)
			(end -1.2192 2.06756)
			(stroke
				(width 0.1524)
				(type default)
			)
			(layer "F.SilkS")
		)
		(fp_line
			(start 1.2192 -2.06756)
			(end 1.2192 2.06756)
			(stroke
				(width 0.1524)
				(type default)
			)
			(layer "F.SilkS")
		)
		(fp_line
			(start -1.2192 2.06756)
			(end -1.2192 -2.06756)
			(stroke
				(width 0.1524)
				(type default)
			)
			(layer "F.SilkS")
		)
		(fp_line
			(start -1.2192 -2.06756)
			(end 1.2192 -2.06756)
			(stroke
				(width 0.1524)
				(type default)
			)
			(layer "F.SilkS")
		)
		(pad "" np_thru_hole circle
			(at -2.8829 -1.27 90)
			(size 1.0414 1.0414)
			(drill 1.0414)
			(layers "*.Cu" "*.Mask")
			(clearance 0.381)
			(thermal_gap 0.381)
		)
		(pad "" np_thru_hole circle
			(at -2.8829 1.27 90)
			(size 1.0414 1.0414)
			(drill 1.0414)
			(layers "*.Cu" "*.Mask")
			(clearance 0.381)
			(thermal_gap 0.381)
		)
		(pad "" np_thru_hole circle
			(at 3.4671 -1.27 90)
			(size 1.0414 1.0414)
			(drill 1.0414)
			(layers "*.Cu" "*.Mask")
			(clearance 0.381)
			(thermal_gap 0.381)
		)
		(pad "" np_thru_hole circle
			(at 3.4671 1.27 90)
			(size 1.0414 1.0414)
			(drill 1.0414)
			(layers "*.Cu" "*.Mask")
			(clearance 0.381)
			(thermal_gap 0.381)
		)
		(pad "1" smd rect
			(at 0.8255 -0.249936 90)
			(size 0.3048 0.508)
			(layers "F.Cu" "F.Mask" "F.Paste")
			(net "DELTA_L_85_10INCH_TOP_DN")
		)
		(pad "2" smd rect
			(at 0.8255 0.249936 90)
			(size 0.3048 0.508)
			(layers "F.Cu" "F.Mask" "F.Paste")
			(net "DELTA_L_85_10INCH_TOP_DP")
		)
		(pad "3" smd circle
			(at 0 0 180)
			(size 0 0)
			(layers "F.Cu" "F.Mask" "F.Paste")
			(net "DELTA_L_GND_1")
		)
		(zone
			(layer "F.Cu")
			(hatch none 0.5)
			(connect_pads
				(clearance 0)
			)
			(min_thickness 0.25)
			(keepout
				(tracks not_allowed)
				(vias allowed)
				(pads allowed)
				(copperpour not_allowed)
				(footprints allowed)
			)
			(placement
				(enabled no)
				(sheetname "")
			)
			(fill
				(thermal_gap 0.5)
				(thermal_bridge_width 0.5)
				(island_removal_mode 0)
			)
			(polygon
				(pts
					(xy 299.420788 0.551434) (xy 299.420788 0.45593) (xy 300.017688 0.45593) (xy 300.017688 0.04953)
					(xy 299.420788 0.04953) (xy 299.420788 -0.043942) (xy 300.017688 -0.043942) (xy 300.017688 -0.450342)
					(xy 299.420788 -0.450342) (xy 299.420788 -0.545846) (xy 300.119288 -0.545846) (xy 300.119288 0.551434)
				)
			)
		)
		(zone
			(layers "F.Cu" "B.Cu" "In1.Cu" "In2.Cu" "In3.Cu" "In4.Cu" "In5.Cu" "In6.Cu"
				"In7.Cu" "In8.Cu" "In9.Cu" "In10.Cu" "In11.Cu" "In12.Cu" "In13.Cu" "In14.Cu"
				"In15.Cu" "In16.Cu"
			)
			(hatch none 0.5)
			(connect_pads
				(clearance 0)
			)
			(min_thickness 0.25)
			(keepout
				(tracks not_allowed)
				(vias allowed)
				(pads allowed)
				(copperpour not_allowed)
				(footprints allowed)
			)
			(placement
				(enabled no)
				(sheetname "")
			)
			(fill
				(thermal_gap 0.5)
				(thermal_bridge_width 0.5)
				(island_removal_mode 0)
			)
			(polygon
				(pts
					(arc
						(start 297.998388 -1.267206)
						(mid 296.144188 -1.267206)
						(end 297.998388 -1.267206)
					)
				)
			)
		)
		(zone
			(layers "F.Cu" "B.Cu" "In1.Cu" "In2.Cu" "In3.Cu" "In4.Cu" "In5.Cu" "In6.Cu"
				"In7.Cu" "In8.Cu" "In9.Cu" "In10.Cu" "In11.Cu" "In12.Cu" "In13.Cu" "In14.Cu"
				"In15.Cu" "In16.Cu"
			)
			(hatch none 0.5)
			(connect_pads
				(clearance 0)
			)
			(min_thickness 0.25)
			(keepout
				(tracks not_allowed)
				(vias allowed)
				(pads allowed)
				(copperpour not_allowed)
				(footprints allowed)
			)
			(placement
				(enabled no)
				(sheetname "")
			)
			(fill
				(thermal_gap 0.5)
				(thermal_bridge_width 0.5)
				(island_removal_mode 0)
			)
			(polygon
				(pts
					(arc
						(start 297.998388 1.272794)
						(mid 296.144188 1.272794)
						(end 297.998388 1.272794)
					)
				)
			)
		)
		(zone
			(layers "F.Cu" "B.Cu" "In1.Cu" "In2.Cu" "In3.Cu" "In4.Cu" "In5.Cu" "In6.Cu"
				"In7.Cu" "In8.Cu" "In9.Cu" "In10.Cu" "In11.Cu" "In12.Cu" "In13.Cu" "In14.Cu"
				"In15.Cu" "In16.Cu"
			)
			(hatch none 0.5)
			(connect_pads
				(clearance 0)
			)
			(min_thickness 0.25)
			(keepout
				(tracks not_allowed)
				(vias allowed)
				(pads allowed)
				(copperpour not_allowed)
				(footprints allowed)
			)
			(placement
				(enabled no)
				(sheetname "")
			)
			(fill
				(thermal_gap 0.5)
				(thermal_bridge_width 0.5)
				(island_removal_mode 0)
			)
			(polygon
				(pts
					(arc
						(start 304.348388 -1.267206)
						(mid 302.494188 -1.267206)
						(end 304.348388 -1.267206)
					)
				)
			)
		)
		(zone
			(layers "F.Cu" "B.Cu" "In1.Cu" "In2.Cu" "In3.Cu" "In4.Cu" "In5.Cu" "In6.Cu"
				"In7.Cu" "In8.Cu" "In9.Cu" "In10.Cu" "In11.Cu" "In12.Cu" "In13.Cu" "In14.Cu"
				"In15.Cu" "In16.Cu"
			)
			(hatch none 0.5)
			(connect_pads
				(clearance 0)
			)
			(min_thickness 0.25)
			(keepout
				(tracks not_allowed)
				(vias allowed)
				(pads allowed)
				(copperpour not_allowed)
				(footprints allowed)
			)
			(placement
				(enabled no)
				(sheetname "")
			)
			(fill
				(thermal_gap 0.5)
				(thermal_bridge_width 0.5)
				(island_removal_mode 0)
			)
			(polygon
				(pts
					(arc
						(start 304.348388 1.272794)
						(mid 302.494188 1.272794)
						(end 304.348388 1.272794)
					)
				)
			)
		)
	)
	(footprint ""
		(layer "F.Cu")
		(at 58.197496 -344.986864 90)
		(property "Reference" "PR515"
			(at 0 0 90)
			(layer "F.SilkS")
			(hide yes)
			(effects
				(font
					(size 1.27 1.27)
				)
			)
		)
		(property "Value" ""
			(at 0 0 90)
			(layer "F.Fab")
			(effects
				(font
					(size 1.27 1.27)
				)
			)
		)
		(duplicate_pad_numbers_are_jumpers no)
		(fp_line
			(start 0.7874 -0.4064)
			(end 0.7874 0.4064)
			(stroke
				(width 0.1524)
				(type default)
			)
			(layer "F.SilkS")
		)
		(fp_line
			(start -0.7874 -0.4064)
			(end 0.7874 -0.4064)
			(stroke
				(width 0.1524)
				(type default)
			)
			(layer "F.SilkS")
		)
		(fp_line
			(start 0.7874 0.4064)
			(end -0.7874 0.4064)
			(stroke
				(width 0.1524)
				(type default)
			)
			(layer "F.SilkS")
		)
		(fp_line
			(start -0.7874 0.4064)
			(end -0.7874 -0.4064)
			(stroke
				(width 0.1524)
				(type default)
			)
			(layer "F.SilkS")
		)
		(fp_line
			(start -0.12065 -0.305054)
			(end -0.12065 -0.2794)
			(stroke
				(width 0.1)
				(type default)
			)
			(layer "F.Fab")
		)
		(fp_line
			(start -0.67945 -0.305054)
			(end -0.12065 -0.305054)
			(stroke
				(width 0.1)
				(type default)
			)
			(layer "F.Fab")
		)
		(fp_line
			(start 0.67945 -0.3048)
			(end 0.67945 0.3048)
			(stroke
				(width 0.1)
				(type default)
			)
			(layer "F.Fab")
		)
		(fp_line
			(start 0.12065 -0.3048)
			(end 0.67945 -0.3048)
			(stroke
				(width 0.1)
				(type default)
			)
			(layer "F.Fab")
		)
		(fp_line
			(start 0.12065 -0.2794)
			(end 0.12065 -0.3048)
			(stroke
				(width 0.1)
				(type default)
			)
			(layer "F.Fab")
		)
		(fp_line
			(start -0.12065 -0.2794)
			(end 0.12065 -0.2794)
			(stroke
				(width 0.1)
				(type default)
			)
			(layer "F.Fab")
		)
		(fp_line
			(start 0.120396 0.2794)
			(end -0.12065 0.2794)
			(stroke
				(width 0.1)
				(type default)
			)
			(layer "F.Fab")
		)
		(fp_line
			(start -0.12065 0.2794)
			(end -0.12065 0.3048)
			(stroke
				(width 0.1)
				(type default)
			)
			(layer "F.Fab")
		)
		(fp_line
			(start 0.67945 0.3048)
			(end 0.120396 0.3048)
			(stroke
				(width 0.1)
				(type default)
			)
			(layer "F.Fab")
		)
		(fp_line
			(start 0.120396 0.3048)
			(end 0.120396 0.2794)
			(stroke
				(width 0.1)
				(type default)
			)
			(layer "F.Fab")
		)
		(fp_line
			(start -0.12065 0.3048)
			(end -0.67945 0.3048)
			(stroke
				(width 0.1)
				(type default)
			)
			(layer "F.Fab")
		)
		(fp_line
			(start -0.67945 0.3048)
			(end -0.67945 -0.305054)
			(stroke
				(width 0.1)
				(type default)
			)
			(layer "F.Fab")
		)
		(pad "1" smd circle
			(at -0.40005 0 90)
			(size 0 0)
			(layers "F.Cu" "F.Mask" "F.Paste")
			(net "SW_PVDDCR_CPU1_P1_SW4_RC")
		)
		(pad "2" smd circle
			(at 0.40005 0 90)
			(size 0 0)
			(layers "F.Cu" "F.Mask" "F.Paste")
			(net "GND")
		)
	)
	(footprint ""
		(layer "F.Cu")
		(at 409.830778 -168.595548 90)
		(property "Reference" "PC582_SOP0_2"
			(at 0 0 90)
			(layer "F.SilkS")
			(hide yes)
			(effects
				(font
					(size 1.27 1.27)
				)
			)
		)
		(property "Value" ""
			(at 0 0 90)
			(layer "F.Fab")
			(effects
				(font
					(size 1.27 1.27)
				)
			)
		)
		(duplicate_pad_numbers_are_jumpers no)
		(fp_line
			(start 0.7874 -0.4064)
			(end 0.7874 0.4064)
			(stroke
				(width 0.1524)
				(type default)
			)
			(layer "F.SilkS")
		)
		(fp_line
			(start -0.7874 -0.4064)
			(end 0.7874 -0.4064)
			(stroke
				(width 0.1524)
				(type default)
			)
			(layer "F.SilkS")
		)
		(fp_line
			(start 0.7874 0.4064)
			(end -0.7874 0.4064)
			(stroke
				(width 0.1524)
				(type default)
			)
			(layer "F.SilkS")
		)
		(fp_line
			(start -0.7874 0.4064)
			(end -0.7874 -0.4064)
			(stroke
				(width 0.1524)
				(type default)
			)
			(layer "F.SilkS")
		)
		(fp_line
			(start -0.12065 -0.305054)
			(end -0.12065 -0.2794)
			(stroke
				(width 0.1)
				(type default)
			)
			(layer "F.Fab")
		)
		(fp_line
			(start -0.67945 -0.305054)
			(end -0.12065 -0.305054)
			(stroke
				(width 0.1)
				(type default)
			)
			(layer "F.Fab")
		)
		(fp_line
			(start 0.67945 -0.3048)
			(end 0.67945 0.3048)
			(stroke
				(width 0.1)
				(type default)
			)
			(layer "F.Fab")
		)
		(fp_line
			(start 0.12065 -0.3048)
			(end 0.67945 -0.3048)
			(stroke
				(width 0.1)
				(type default)
			)
			(layer "F.Fab")
		)
		(fp_line
			(start 0.12065 -0.2794)
			(end 0.12065 -0.3048)
			(stroke
				(width 0.1)
				(type default)
			)
			(layer "F.Fab")
		)
		(fp_line
			(start -0.12065 -0.2794)
			(end 0.12065 -0.2794)
			(stroke
				(width 0.1)
				(type default)
			)
			(layer "F.Fab")
		)
		(fp_line
			(start 0.120396 0.2794)
			(end -0.12065 0.2794)
			(stroke
				(width 0.1)
				(type default)
			)
			(layer "F.Fab")
		)
		(fp_line
			(start -0.12065 0.2794)
			(end -0.12065 0.3048)
			(stroke
				(width 0.1)
				(type default)
			)
			(layer "F.Fab")
		)
		(fp_line
			(start 0.67945 0.3048)
			(end 0.120396 0.3048)
			(stroke
				(width 0.1)
				(type default)
			)
			(layer "F.Fab")
		)
		(fp_line
			(start 0.120396 0.3048)
			(end 0.120396 0.2794)
			(stroke
				(width 0.1)
				(type default)
			)
			(layer "F.Fab")
		)
		(fp_line
			(start -0.12065 0.3048)
			(end -0.67945 0.3048)
			(stroke
				(width 0.1)
				(type default)
			)
			(layer "F.Fab")
		)
		(fp_line
			(start -0.67945 0.3048)
			(end -0.67945 -0.305054)
			(stroke
				(width 0.1)
				(type default)
			)
			(layer "F.Fab")
		)
		(pad "1" smd circle
			(at -0.40005 0 90)
			(size 0 0)
			(layers "F.Cu" "F.Mask" "F.Paste")
			(net "PVDDCR_CPU0_P0_PVCC")
		)
		(pad "2" smd circle
			(at 0.40005 0 90)
			(size 0 0)
			(layers "F.Cu" "F.Mask" "F.Paste")
			(net "GND")
		)
	)
	(footprint ""
		(layer "F.Cu")
		(at 219.974922 -73.484994 180)
		(property "Reference" "PC2210"
			(at 0 0 180)
			(layer "F.SilkS")
			(hide yes)
			(effects
				(font
					(size 1.27 1.27)
				)
			)
		)
		(property "Value" ""
			(at 0 0 180)
			(layer "F.Fab")
			(effects
				(font
					(size 1.27 1.27)
				)
			)
		)
		(duplicate_pad_numbers_are_jumpers no)
		(fp_line
			(start 0.7874 0.4064)
			(end -0.7874 0.4064)
			(stroke
				(width 0.1524)
				(type default)
			)
			(layer "F.SilkS")
		)
		(fp_line
			(start 0.7874 -0.4064)
			(end 0.7874 0.4064)
			(stroke
				(width 0.1524)
				(type default)
			)
			(layer "F.SilkS")
		)
		(fp_line
			(start -0.7874 0.4064)
			(end -0.7874 -0.4064)
			(stroke
				(width 0.1524)
				(type default)
			)
			(layer "F.SilkS")
		)
		(fp_line
			(start -0.7874 -0.4064)
			(end 0.7874 -0.4064)
			(stroke
				(width 0.1524)
				(type default)
			)
			(layer "F.SilkS")
		)
		(fp_line
			(start 0.67945 0.3048)
			(end 0.120396 0.3048)
			(stroke
				(width 0.1)
				(type default)
			)
			(layer "F.Fab")
		)
		(fp_line
			(start 0.67945 -0.3048)
			(end 0.67945 0.3048)
			(stroke
				(width 0.1)
				(type default)
			)
			(layer "F.Fab")
		)
		(fp_line
			(start 0.12065 -0.2794)
			(end 0.12065 -0.3048)
			(stroke
				(width 0.1)
				(type default)
			)
			(layer "F.Fab")
		)
		(fp_line
			(start 0.12065 -0.3048)
			(end 0.67945 -0.3048)
			(stroke
				(width 0.1)
				(type default)
			)
			(layer "F.Fab")
		)
		(fp_line
			(start 0.120396 0.3048)
			(end 0.120396 0.2794)
			(stroke
				(width 0.1)
				(type default)
			)
			(layer "F.Fab")
		)
		(fp_line
			(start 0.120396 0.2794)
			(end -0.12065 0.2794)
			(stroke
				(width 0.1)
				(type default)
			)
			(layer "F.Fab")
		)
		(fp_line
			(start -0.12065 0.3048)
			(end -0.67945 0.3048)
			(stroke
				(width 0.1)
				(type default)
			)
			(layer "F.Fab")
		)
		(fp_line
			(start -0.12065 0.2794)
			(end -0.12065 0.3048)
			(stroke
				(width 0.1)
				(type default)
			)
			(layer "F.Fab")
		)
		(fp_line
			(start -0.12065 -0.2794)
			(end 0.12065 -0.2794)
			(stroke
				(width 0.1)
				(type default)
			)
			(layer "F.Fab")
		)
		(fp_line
			(start -0.12065 -0.305054)
			(end -0.12065 -0.2794)
			(stroke
				(width 0.1)
				(type default)
			)
			(layer "F.Fab")
		)
		(fp_line
			(start -0.67945 0.3048)
			(end -0.67945 -0.305054)
			(stroke
				(width 0.1)
				(type default)
			)
			(layer "F.Fab")
		)
		(fp_line
			(start -0.67945 -0.305054)
			(end -0.12065 -0.305054)
			(stroke
				(width 0.1)
				(type default)
			)
			(layer "F.Fab")
		)
		(pad "1" smd circle
			(at -0.40005 0 180)
			(size 0 0)
			(layers "F.Cu" "F.Mask" "F.Paste")
			(net "P3V3_E1S_VCC_0")
		)
		(pad "2" smd circle
			(at 0.40005 0 180)
			(size 0 0)
			(layers "F.Cu" "F.Mask" "F.Paste")
			(net "GND")
		)
	)
	(footprint ""
		(layer "F.Cu")
		(at 319.22339 -192.89776 -90)
		(property "Reference" "R427"
			(at 0 0 270)
			(layer "F.SilkS")
			(hide yes)
			(effects
				(font
					(size 1.27 1.27)
				)
			)
		)
		(property "Value" ""
			(at 0 0 270)
			(layer "F.Fab")
			(effects
				(font
					(size 1.27 1.27)
				)
			)
		)
		(duplicate_pad_numbers_are_jumpers no)
		(fp_line
			(start -0.7874 0.4064)
			(end -0.7874 -0.4064)
			(stroke
				(width 0.1524)
				(type default)
			)
			(layer "F.SilkS")
		)
		(fp_line
			(start 0.7874 0.4064)
			(end -0.7874 0.4064)
			(stroke
				(width 0.1524)
				(type default)
			)
			(layer "F.SilkS")
		)
		(fp_line
			(start -0.7874 -0.4064)
			(end 0.7874 -0.4064)
			(stroke
				(width 0.1524)
				(type default)
			)
			(layer "F.SilkS")
		)
		(fp_line
			(start 0.7874 -0.4064)
			(end 0.7874 0.4064)
			(stroke
				(width 0.1524)
				(type default)
			)
			(layer "F.SilkS")
		)
		(fp_line
			(start -0.67945 0.3048)
			(end -0.67945 -0.305054)
			(stroke
				(width 0.1)
				(type default)
			)
			(layer "F.Fab")
		)
		(fp_line
			(start -0.12065 0.3048)
			(end -0.67945 0.3048)
			(stroke
				(width 0.1)
				(type default)
			)
			(layer "F.Fab")
		)
		(fp_line
			(start 0.120396 0.3048)
			(end 0.120396 0.2794)
			(stroke
				(width 0.1)
				(type default)
			)
			(layer "F.Fab")
		)
		(fp_line
			(start 0.67945 0.3048)
			(end 0.120396 0.3048)
			(stroke
				(width 0.1)
				(type default)
			)
			(layer "F.Fab")
		)
		(fp_line
			(start -0.12065 0.2794)
			(end -0.12065 0.3048)
			(stroke
				(width 0.1)
				(type default)
			)
			(layer "F.Fab")
		)
		(fp_line
			(start 0.120396 0.2794)
			(end -0.12065 0.2794)
			(stroke
				(width 0.1)
				(type default)
			)
			(layer "F.Fab")
		)
		(fp_line
			(start -0.12065 -0.2794)
			(end 0.12065 -0.2794)
			(stroke
				(width 0.1)
				(type default)
			)
			(layer "F.Fab")
		)
		(fp_line
			(start 0.12065 -0.2794)
			(end 0.12065 -0.3048)
			(stroke
				(width 0.1)
				(type default)
			)
			(layer "F.Fab")
		)
		(fp_line
			(start 0.12065 -0.3048)
			(end 0.67945 -0.3048)
			(stroke
				(width 0.1)
				(type default)
			)
			(layer "F.Fab")
		)
		(fp_line
			(start 0.67945 -0.3048)
			(end 0.67945 0.3048)
			(stroke
				(width 0.1)
				(type default)
			)
			(layer "F.Fab")
		)
		(fp_line
			(start -0.67945 -0.305054)
			(end -0.12065 -0.305054)
			(stroke
				(width 0.1)
				(type default)
			)
			(layer "F.Fab")
		)
		(fp_line
			(start -0.12065 -0.305054)
			(end -0.12065 -0.2794)
			(stroke
				(width 0.1)
				(type default)
			)
			(layer "F.Fab")
		)
		(pad "1" smd rect
			(at -0.40005 0 90)
			(size 0.4572 0.508)
			(layers "F.Cu" "F.Mask" "F.Paste")
			(net "I3C_0_SPD_DDRAF_CPU0_SDA")
		)
		(pad "2" smd rect
			(at 0.40005 0 90)
			(size 0.4572 0.508)
			(layers "F.Cu" "F.Mask" "F.Paste")
			(net "I3C_0_SPD_DDRAF_CPU0_R_SDA")
		)
	)
	(footprint ""
		(layer "F.Cu")
		(at 197.269608 -124.801376)
		(property "Reference" "R1527"
			(at 0 0 0)
			(layer "F.SilkS")
			(hide yes)
			(effects
				(font
					(size 1.27 1.27)
				)
			)
		)
		(property "Value" ""
			(at 0 0 0)
			(layer "F.Fab")
			(effects
				(font
					(size 1.27 1.27)
				)
			)
		)
		(duplicate_pad_numbers_are_jumpers no)
		(fp_line
			(start -0.7874 -0.4064)
			(end 0.7874 -0.4064)
			(stroke
				(width 0.1524)
				(type default)
			)
			(layer "F.SilkS")
		)
		(fp_line
			(start -0.7874 0.4064)
			(end -0.7874 -0.4064)
			(stroke
				(width 0.1524)
				(type default)
			)
			(layer "F.SilkS")
		)
		(fp_line
			(start 0.7874 -0.4064)
			(end 0.7874 0.4064)
			(stroke
				(width 0.1524)
				(type default)
			)
			(layer "F.SilkS")
		)
		(fp_line
			(start 0.7874 0.4064)
			(end -0.7874 0.4064)
			(stroke
				(width 0.1524)
				(type default)
			)
			(layer "F.SilkS")
		)
		(fp_line
			(start -0.67945 -0.305054)
			(end -0.12065 -0.305054)
			(stroke
				(width 0.1)
				(type default)
			)
			(layer "F.Fab")
		)
		(fp_line
			(start -0.67945 0.3048)
			(end -0.67945 -0.305054)
			(stroke
				(width 0.1)
				(type default)
			)
			(layer "F.Fab")
		)
		(fp_line
			(start -0.12065 -0.305054)
			(end -0.12065 -0.2794)
			(stroke
				(width 0.1)
				(type default)
			)
			(layer "F.Fab")
		)
		(fp_line
			(start -0.12065 -0.2794)
			(end 0.12065 -0.2794)
			(stroke
				(width 0.1)
				(type default)
			)
			(layer "F.Fab")
		)
		(fp_line
			(start -0.12065 0.2794)
			(end -0.12065 0.3048)
			(stroke
				(width 0.1)
				(type default)
			)
			(layer "F.Fab")
		)
		(fp_line
			(start -0.12065 0.3048)
			(end -0.67945 0.3048)
			(stroke
				(width 0.1)
				(type default)
			)
			(layer "F.Fab")
		)
		(fp_line
			(start 0.120396 0.2794)
			(end -0.12065 0.2794)
			(stroke
				(width 0.1)
				(type default)
			)
			(layer "F.Fab")
		)
		(fp_line
			(start 0.120396 0.3048)
			(end 0.120396 0.2794)
			(stroke
				(width 0.1)
				(type default)
			)
			(layer "F.Fab")
		)
		(fp_line
			(start 0.12065 -0.3048)
			(end 0.67945 -0.3048)
			(stroke
				(width 0.1)
				(type default)
			)
			(layer "F.Fab")
		)
		(fp_line
			(start 0.12065 -0.2794)
			(end 0.12065 -0.3048)
			(stroke
				(width 0.1)
				(type default)
			)
			(layer "F.Fab")
		)
		(fp_line
			(start 0.67945 -0.3048)
			(end 0.67945 0.3048)
			(stroke
				(width 0.1)
				(type default)
			)
			(layer "F.Fab")
		)
		(fp_line
			(start 0.67945 0.3048)
			(end 0.120396 0.3048)
			(stroke
				(width 0.1)
				(type default)
			)
			(layer "F.Fab")
		)
		(pad "1" smd circle
			(at -0.40005 0)
			(size 0 0)
			(layers "F.Cu" "F.Mask" "F.Paste")
			(net "PRSNT_HDT_N")
		)
		(pad "2" smd circle
			(at 0.40005 0)
			(size 0 0)
			(layers "F.Cu" "F.Mask" "F.Paste")
			(net "P3V3_AUX")
		)
	)
	(footprint ""
		(layer "F.Cu")
		(at 293.038022 -53.29809)
		(property "Reference" "R424"
			(at 0 0 0)
			(layer "F.SilkS")
			(hide yes)
			(effects
				(font
					(size 1.27 1.27)
				)
			)
		)
		(property "Value" ""
			(at 0 0 0)
			(layer "F.Fab")
			(effects
				(font
					(size 1.27 1.27)
				)
			)
		)
		(duplicate_pad_numbers_are_jumpers no)
		(fp_line
			(start -0.7874 -0.4064)
			(end 0.7874 -0.4064)
			(stroke
				(width 0.1524)
				(type default)
			)
			(layer "F.SilkS")
		)
		(fp_line
			(start -0.7874 0.4064)
			(end -0.7874 -0.4064)
			(stroke
				(width 0.1524)
				(type default)
			)
			(layer "F.SilkS")
		)
		(fp_line
			(start 0.7874 -0.4064)
			(end 0.7874 0.4064)
			(stroke
				(width 0.1524)
				(type default)
			)
			(layer "F.SilkS")
		)
		(fp_line
			(start 0.7874 0.4064)
			(end -0.7874 0.4064)
			(stroke
				(width 0.1524)
				(type default)
			)
			(layer "F.SilkS")
		)
		(fp_line
			(start -0.67945 -0.305054)
			(end -0.12065 -0.305054)
			(stroke
				(width 0.1)
				(type default)
			)
			(layer "F.Fab")
		)
		(fp_line
			(start -0.67945 0.3048)
			(end -0.67945 -0.305054)
			(stroke
				(width 0.1)
				(type default)
			)
			(layer "F.Fab")
		)
		(fp_line
			(start -0.12065 -0.305054)
			(end -0.12065 -0.2794)
			(stroke
				(width 0.1)
				(type default)
			)
			(layer "F.Fab")
		)
		(fp_line
			(start -0.12065 -0.2794)
			(end 0.12065 -0.2794)
			(stroke
				(width 0.1)
				(type default)
			)
			(layer "F.Fab")
		)
		(fp_line
			(start -0.12065 0.2794)
			(end -0.12065 0.3048)
			(stroke
				(width 0.1)
				(type default)
			)
			(layer "F.Fab")
		)
		(fp_line
			(start -0.12065 0.3048)
			(end -0.67945 0.3048)
			(stroke
				(width 0.1)
				(type default)
			)
			(layer "F.Fab")
		)
		(fp_line
			(start 0.120396 0.2794)
			(end -0.12065 0.2794)
			(stroke
				(width 0.1)
				(type default)
			)
			(layer "F.Fab")
		)
		(fp_line
			(start 0.120396 0.3048)
			(end 0.120396 0.2794)
			(stroke
				(width 0.1)
				(type default)
			)
			(layer "F.Fab")
		)
		(fp_line
			(start 0.12065 -0.3048)
			(end 0.67945 -0.3048)
			(stroke
				(width 0.1)
				(type default)
			)
			(layer "F.Fab")
		)
		(fp_line
			(start 0.12065 -0.2794)
			(end 0.12065 -0.3048)
			(stroke
				(width 0.1)
				(type default)
			)
			(layer "F.Fab")
		)
		(fp_line
			(start 0.67945 -0.3048)
			(end 0.67945 0.3048)
			(stroke
				(width 0.1)
				(type default)
			)
			(layer "F.Fab")
		)
		(fp_line
			(start 0.67945 0.3048)
			(end 0.120396 0.3048)
			(stroke
				(width 0.1)
				(type default)
			)
			(layer "F.Fab")
		)
		(pad "1" smd circle
			(at -0.40005 0)
			(size 0 0)
			(layers "F.Cu" "F.Mask" "F.Paste")
			(net "PVDD18_S5_P0")
		)
		(pad "2" smd circle
			(at 0.40005 0)
			(size 0 0)
			(layers "F.Cu" "F.Mask" "F.Paste")
			(net "CPU0_PWR_BTN_N")
		)
	)
	(footprint ""
		(layer "F.Cu")
		(at 363.008926 -28.273502 90)
		(property "Reference" "R1419"
			(at 0 0 90)
			(layer "F.SilkS")
			(hide yes)
			(effects
				(font
					(size 1.27 1.27)
				)
			)
		)
		(property "Value" ""
			(at 0 0 90)
			(layer "F.Fab")
			(effects
				(font
					(size 1.27 1.27)
				)
			)
		)
		(duplicate_pad_numbers_are_jumpers no)
		(fp_line
			(start 0.7874 -0.4064)
			(end 0.7874 0.4064)
			(stroke
				(width 0.1524)
				(type default)
			)
			(layer "F.SilkS")
		)
		(fp_line
			(start -0.7874 -0.4064)
			(end 0.7874 -0.4064)
			(stroke
				(width 0.1524)
				(type default)
			)
			(layer "F.SilkS")
		)
		(fp_line
			(start 0.7874 0.4064)
			(end -0.7874 0.4064)
			(stroke
				(width 0.1524)
				(type default)
			)
			(layer "F.SilkS")
		)
		(fp_line
			(start -0.7874 0.4064)
			(end -0.7874 -0.4064)
			(stroke
				(width 0.1524)
				(type default)
			)
			(layer "F.SilkS")
		)
		(fp_line
			(start -0.12065 -0.305054)
			(end -0.12065 -0.2794)
			(stroke
				(width 0.1)
				(type default)
			)
			(layer "F.Fab")
		)
		(fp_line
			(start -0.67945 -0.305054)
			(end -0.12065 -0.305054)
			(stroke
				(width 0.1)
				(type default)
			)
			(layer "F.Fab")
		)
		(fp_line
			(start 0.67945 -0.3048)
			(end 0.67945 0.3048)
			(stroke
				(width 0.1)
				(type default)
			)
			(layer "F.Fab")
		)
		(fp_line
			(start 0.12065 -0.3048)
			(end 0.67945 -0.3048)
			(stroke
				(width 0.1)
				(type default)
			)
			(layer "F.Fab")
		)
		(fp_line
			(start 0.12065 -0.2794)
			(end 0.12065 -0.3048)
			(stroke
				(width 0.1)
				(type default)
			)
			(layer "F.Fab")
		)
		(fp_line
			(start -0.12065 -0.2794)
			(end 0.12065 -0.2794)
			(stroke
				(width 0.1)
				(type default)
			)
			(layer "F.Fab")
		)
		(fp_line
			(start 0.120396 0.2794)
			(end -0.12065 0.2794)
			(stroke
				(width 0.1)
				(type default)
			)
			(layer "F.Fab")
		)
		(fp_line
			(start -0.12065 0.2794)
			(end -0.12065 0.3048)
			(stroke
				(width 0.1)
				(type default)
			)
			(layer "F.Fab")
		)
		(fp_line
			(start 0.67945 0.3048)
			(end 0.120396 0.3048)
			(stroke
				(width 0.1)
				(type default)
			)
			(layer "F.Fab")
		)
		(fp_line
			(start 0.120396 0.3048)
			(end 0.120396 0.2794)
			(stroke
				(width 0.1)
				(type default)
			)
			(layer "F.Fab")
		)
		(fp_line
			(start -0.12065 0.3048)
			(end -0.67945 0.3048)
			(stroke
				(width 0.1)
				(type default)
			)
			(layer "F.Fab")
		)
		(fp_line
			(start -0.67945 0.3048)
			(end -0.67945 -0.305054)
			(stroke
				(width 0.1)
				(type default)
			)
			(layer "F.Fab")
		)
		(pad "1" smd circle
			(at -0.40005 0 90)
			(size 0 0)
			(layers "F.Cu" "F.Mask" "F.Paste")
			(net "PVDD18_S5_P0")
		)
		(pad "2" smd circle
			(at 0.40005 0 90)
			(size 0 0)
			(layers "F.Cu" "F.Mask" "F.Paste")
			(net "UART_LS_EN_R_N")
		)
	)
	(footprint ""
		(layer "F.Cu")
		(at 177.81016 -391.6172)
		(property "Reference" "R1490"
			(at 0 0 0)
			(layer "F.SilkS")
			(hide yes)
			(effects
				(font
					(size 1.27 1.27)
				)
			)
		)
		(property "Value" ""
			(at 0 0 0)
			(layer "F.Fab")
			(effects
				(font
					(size 1.27 1.27)
				)
			)
		)
		(duplicate_pad_numbers_are_jumpers no)
		(fp_line
			(start -0.32512 -0.175006)
			(end 0.32512 -0.175006)
			(stroke
				(width 0.1)
				(type default)
			)
			(layer "F.Fab")
		)
		(fp_line
			(start -0.32512 0.175006)
			(end -0.32512 -0.175006)
			(stroke
				(width 0.1)
				(type default)
			)
			(layer "F.Fab")
		)
		(fp_line
			(start 0.32512 -0.175006)
			(end 0.32512 0.175006)
			(stroke
				(width 0.1)
				(type default)
			)
			(layer "F.Fab")
		)
		(fp_line
			(start 0.32512 0.175006)
			(end -0.32512 0.175006)
			(stroke
				(width 0.1)
				(type default)
			)
			(layer "F.Fab")
		)
		(pad "1" smd rect
			(at -0.2667 0)
			(size 0.3048 0.381)
			(layers "F.Cu" "F.Mask" "F.Paste")
			(net "P1V8_CPU1_RT_1D")
		)
		(pad "2" smd rect
			(at 0.2667 0 180)
			(size 0.3048 0.381)
			(layers "F.Cu" "F.Mask" "F.Paste")
			(net "JTAG_TDO_RT_CPU1_P2")
		)
	)
	(footprint ""
		(layer "F.Cu")
		(at 28.967684 -52.004214)
		(property "Reference" "J49"
			(at -1.016 -3.495548 0)
			(unlocked yes)
			(layer "F.SilkS")
			(effects
				(font
					(size 0.7874 0.5842)
					(thickness 0.1524)
				)
			)
		)
		(property "Value" ""
			(at 0 0 0)
			(layer "F.Fab")
			(effects
				(font
					(size 1.27 1.27)
				)
			)
		)
		(duplicate_pad_numbers_are_jumpers no)
		(fp_line
			(start -1.700022 -2.739898)
			(end 1.700022 -2.739898)
			(stroke
				(width 0.1524)
				(type default)
			)
			(layer "F.SilkS")
		)
		(fp_line
			(start -1.700022 -2.4257)
			(end -1.700022 -2.739898)
			(stroke
				(width 0.1524)
				(type default)
			)
			(layer "F.SilkS")
		)
		(fp_line
			(start -1.700022 -1.1557)
			(end -1.700022 -1.3843)
			(stroke
				(width 0.1524)
				(type default)
			)
			(layer "F.SilkS")
		)
		(fp_line
			(start -1.700022 0.1143)
			(end -1.700022 -0.1143)
			(stroke
				(width 0.1524)
				(type default)
			)
			(layer "F.SilkS")
		)
		(fp_line
			(start -1.700022 1.3843)
			(end -1.700022 1.1557)
			(stroke
				(width 0.1524)
				(type default)
			)
			(layer "F.SilkS")
		)
		(fp_line
			(start -1.700022 2.739898)
			(end -1.700022 2.4257)
			(stroke
				(width 0.1524)
				(type default)
			)
			(layer "F.SilkS")
		)
		(fp_line
			(start 1.700022 -2.739898)
			(end 1.700022 -2.4257)
			(stroke
				(width 0.1524)
				(type default)
			)
			(layer "F.SilkS")
		)
		(fp_line
			(start 1.700022 -1.3843)
			(end 1.700022 -1.1557)
			(stroke
				(width 0.1524)
				(type default)
			)
			(layer "F.SilkS")
		)
		(fp_line
			(start 1.700022 -0.1143)
			(end 1.700022 0.1143)
			(stroke
				(width 0.1524)
				(type default)
			)
			(layer "F.SilkS")
		)
		(fp_line
			(start 1.700022 1.1557)
			(end 1.700022 1.3843)
			(stroke
				(width 0.1524)
				(type default)
			)
			(layer "F.SilkS")
		)
		(fp_line
			(start 1.700022 2.4257)
			(end 1.700022 2.739898)
			(stroke
				(width 0.1524)
				(type default)
			)
			(layer "F.SilkS")
		)
		(fp_line
			(start 1.700022 2.739898)
			(end -1.700022 2.739898)
			(stroke
				(width 0.1524)
				(type default)
			)
			(layer "F.SilkS")
		)
		(fp_poly
			(pts
				(xy -3.383534 -1.905) (xy -4.399534 -1.397) (xy -4.399534 -2.413)
			)
			(stroke
				(width 0)
				(type default)
			)
			(fill yes)
			(layer "F.SilkS")
		)
		(fp_line
			(start -1.700022 -2.739898)
			(end 1.700022 -2.739898)
			(stroke
				(width 0.1)
				(type default)
			)
			(layer "F.Fab")
		)
		(fp_line
			(start -1.700022 2.739898)
			(end -1.700022 -2.739898)
			(stroke
				(width 0.1)
				(type default)
			)
			(layer "F.Fab")
		)
		(fp_line
			(start 1.700022 -2.739898)
			(end 1.700022 2.739898)
			(stroke
				(width 0.1)
				(type default)
			)
			(layer "F.Fab")
		)
		(fp_line
			(start 1.700022 2.739898)
			(end -1.700022 2.739898)
			(stroke
				(width 0.1)
				(type default)
			)
			(layer "F.Fab")
		)
		(fp_poly
			(pts
				(xy -4.399534 -2.413) (xy -4.399534 -1.397) (xy -3.383534 -1.905)
			)
			(stroke
				(width 0)
				(type default)
			)
			(fill yes)
			(layer "F.Fab")
		)
		(pad "1" smd rect
			(at -2.050034 -1.905 270)
			(size 0.762 2.413)
			(layers "F.Cu" "F.Mask" "F.Paste")
			(net "CPU1_BP0")
		)
		(pad "2" smd rect
			(at 2.050034 -1.905 270)
			(size 0.762 2.413)
			(layers "F.Cu" "F.Mask" "F.Paste")
			(net "GND")
		)
		(pad "3" smd rect
			(at -2.050034 -0.635 270)
			(size 0.762 2.413)
			(layers "F.Cu" "F.Mask" "F.Paste")
			(net "CPU1_BP1")
		)
		(pad "4" smd rect
			(at 2.050034 -0.635 270)
			(size 0.762 2.413)
			(layers "F.Cu" "F.Mask" "F.Paste")
			(net "GND")
		)
		(pad "5" smd rect
			(at -2.050034 0.635 270)
			(size 0.762 2.413)
			(layers "F.Cu" "F.Mask" "F.Paste")
			(net "CPU1_BP2")
		)
		(pad "6" smd rect
			(at 2.050034 0.635 270)
			(size 0.762 2.413)
			(layers "F.Cu" "F.Mask" "F.Paste")
			(net "GND")
		)
		(pad "7" smd rect
			(at -2.050034 1.905 270)
			(size 0.762 2.413)
			(layers "F.Cu" "F.Mask" "F.Paste")
			(net "CPU1_BP3")
		)
		(pad "8" smd rect
			(at 2.050034 1.905 270)
			(size 0.762 2.413)
			(layers "F.Cu" "F.Mask" "F.Paste")
			(net "GND")
		)
	)
	(footprint ""
		(layer "F.Cu")
		(at 334.028288 -402.548852 -90)
		(property "Reference" "R1006"
			(at 0 0 270)
			(layer "F.SilkS")
			(hide yes)
			(effects
				(font
					(size 1.27 1.27)
				)
			)
		)
		(property "Value" ""
			(at 0 0 270)
			(layer "F.Fab")
			(effects
				(font
					(size 1.27 1.27)
				)
			)
		)
		(duplicate_pad_numbers_are_jumpers no)
		(fp_line
			(start -0.32512 0.175006)
			(end -0.32512 -0.175006)
			(stroke
				(width 0.1)
				(type default)
			)
			(layer "F.Fab")
		)
		(fp_line
			(start 0.32512 0.175006)
			(end -0.32512 0.175006)
			(stroke
				(width 0.1)
				(type default)
			)
			(layer "F.Fab")
		)
		(fp_line
			(start -0.32512 -0.175006)
			(end 0.32512 -0.175006)
			(stroke
				(width 0.1)
				(type default)
			)
			(layer "F.Fab")
		)
		(fp_line
			(start 0.32512 -0.175006)
			(end 0.32512 0.175006)
			(stroke
				(width 0.1)
				(type default)
			)
			(layer "F.Fab")
		)
		(pad "1" smd rect
			(at -0.2667 0 270)
			(size 0.3048 0.381)
			(layers "F.Cu" "F.Mask" "F.Paste")
			(net "MODE_RT_CPU0_P1")
		)
		(pad "2" smd rect
			(at 0.2667 0 90)
			(size 0.3048 0.381)
			(layers "F.Cu" "F.Mask" "F.Paste")
			(net "GND")
		)
	)
	(footprint ""
		(layer "F.Cu")
		(at 336.172556 -133.75005)
		(property "Reference" "PC81"
			(at 0 0 0)
			(layer "F.SilkS")
			(hide yes)
			(effects
				(font
					(size 1.27 1.27)
				)
			)
		)
		(property "Value" ""
			(at 0 0 0)
			(layer "F.Fab")
			(effects
				(font
					(size 1.27 1.27)
				)
			)
		)
		(duplicate_pad_numbers_are_jumpers no)
		(fp_line
			(start -1.524 -0.762)
			(end 1.524 -0.762)
			(stroke
				(width 0.1524)
				(type default)
			)
			(layer "F.SilkS")
		)
		(fp_line
			(start -1.524 0.762)
			(end -1.524 -0.762)
			(stroke
				(width 0.1524)
				(type default)
			)
			(layer "F.SilkS")
		)
		(fp_line
			(start 1.524 -0.762)
			(end 1.524 0.762)
			(stroke
				(width 0.1524)
				(type default)
			)
			(layer "F.SilkS")
		)
		(fp_line
			(start 1.524 0.762)
			(end -1.524 0.762)
			(stroke
				(width 0.1524)
				(type default)
			)
			(layer "F.SilkS")
		)
		(fp_line
			(start -1.1049 -0.724916)
			(end -1.1049 0.724916)
			(stroke
				(width 0.1)
				(type default)
			)
			(layer "F.Fab")
		)
		(fp_line
			(start -1.1049 0.724916)
			(end 1.1049 0.724916)
			(stroke
				(width 0.1)
				(type default)
			)
			(layer "F.Fab")
		)
		(fp_line
			(start 1.1049 -0.724916)
			(end -1.1049 -0.724916)
			(stroke
				(width 0.1)
				(type default)
			)
			(layer "F.Fab")
		)
		(fp_line
			(start 1.1049 0.724916)
			(end 1.1049 -0.724916)
			(stroke
				(width 0.1)
				(type default)
			)
			(layer "F.Fab")
		)
		(pad "1" smd rect
			(at -0.889 0 180)
			(size 1.016 1.27)
			(layers "F.Cu" "F.Mask" "F.Paste")
			(net "SW_P12V_AUX_PVDD18_S5_P0_FLT")
		)
		(pad "2" smd rect
			(at 0.889 0 180)
			(size 1.016 1.27)
			(layers "F.Cu" "F.Mask" "F.Paste")
			(net "GND")
		)
	)
	(footprint ""
		(layer "F.Cu")
		(at 426.230796 -394.7668)
		(property "Reference" "C666"
			(at 0 0 0)
			(layer "F.SilkS")
			(hide yes)
			(effects
				(font
					(size 1.27 1.27)
				)
			)
		)
		(property "Value" ""
			(at 0 0 0)
			(layer "F.Fab")
			(effects
				(font
					(size 1.27 1.27)
				)
			)
		)
		(duplicate_pad_numbers_are_jumpers no)
		(fp_line
			(start -1.524 -0.762)
			(end 1.524 -0.762)
			(stroke
				(width 0.1524)
				(type default)
			)
			(layer "F.SilkS")
		)
		(fp_line
			(start -1.524 0.762)
			(end -1.524 -0.762)
			(stroke
				(width 0.1524)
				(type default)
			)
			(layer "F.SilkS")
		)
		(fp_line
			(start 1.524 -0.762)
			(end 1.524 0.762)
			(stroke
				(width 0.1524)
				(type default)
			)
			(layer "F.SilkS")
		)
		(fp_line
			(start 1.524 0.762)
			(end -1.524 0.762)
			(stroke
				(width 0.1524)
				(type default)
			)
			(layer "F.SilkS")
		)
		(fp_line
			(start -1.1049 -0.724916)
			(end -1.1049 0.724916)
			(stroke
				(width 0.1)
				(type default)
			)
			(layer "F.Fab")
		)
		(fp_line
			(start -1.1049 0.724916)
			(end 1.1049 0.724916)
			(stroke
				(width 0.1)
				(type default)
			)
			(layer "F.Fab")
		)
		(fp_line
			(start 1.1049 -0.724916)
			(end -1.1049 -0.724916)
			(stroke
				(width 0.1)
				(type default)
			)
			(layer "F.Fab")
		)
		(fp_line
			(start 1.1049 0.724916)
			(end 1.1049 -0.724916)
			(stroke
				(width 0.1)
				(type default)
			)
			(layer "F.Fab")
		)
		(pad "1" smd rect
			(at -0.889 0 180)
			(size 1.016 1.27)
			(layers "F.Cu" "F.Mask" "F.Paste")
			(net "P1V8_CPU0_RT2_1A")
		)
		(pad "2" smd rect
			(at 0.889 0 180)
			(size 1.016 1.27)
			(layers "F.Cu" "F.Mask" "F.Paste")
			(net "GND")
		)
	)
	(footprint ""
		(layer "F.Cu")
		(at 198.247 -92.456)
		(property "Reference" "R8089"
			(at 0 0 0)
			(layer "F.SilkS")
			(hide yes)
			(effects
				(font
					(size 1.27 1.27)
				)
			)
		)
		(property "Value" ""
			(at 0 0 0)
			(layer "F.Fab")
			(effects
				(font
					(size 1.27 1.27)
				)
			)
		)
		(duplicate_pad_numbers_are_jumpers no)
		(fp_line
			(start -0.7874 -0.4064)
			(end 0.7874 -0.4064)
			(stroke
				(width 0.1524)
				(type default)
			)
			(layer "F.SilkS")
		)
		(fp_line
			(start -0.7874 0.4064)
			(end -0.7874 -0.4064)
			(stroke
				(width 0.1524)
				(type default)
			)
			(layer "F.SilkS")
		)
		(fp_line
			(start 0.7874 -0.4064)
			(end 0.7874 0.4064)
			(stroke
				(width 0.1524)
				(type default)
			)
			(layer "F.SilkS")
		)
		(fp_line
			(start 0.7874 0.4064)
			(end -0.7874 0.4064)
			(stroke
				(width 0.1524)
				(type default)
			)
			(layer "F.SilkS")
		)
		(fp_line
			(start -0.67945 -0.305054)
			(end -0.12065 -0.305054)
			(stroke
				(width 0.1)
				(type default)
			)
			(layer "F.Fab")
		)
		(fp_line
			(start -0.67945 0.3048)
			(end -0.67945 -0.305054)
			(stroke
				(width 0.1)
				(type default)
			)
			(layer "F.Fab")
		)
		(fp_line
			(start -0.12065 -0.305054)
			(end -0.12065 -0.2794)
			(stroke
				(width 0.1)
				(type default)
			)
			(layer "F.Fab")
		)
		(fp_line
			(start -0.12065 -0.2794)
			(end 0.12065 -0.2794)
			(stroke
				(width 0.1)
				(type default)
			)
			(layer "F.Fab")
		)
		(fp_line
			(start -0.12065 0.2794)
			(end -0.12065 0.3048)
			(stroke
				(width 0.1)
				(type default)
			)
			(layer "F.Fab")
		)
		(fp_line
			(start -0.12065 0.3048)
			(end -0.67945 0.3048)
			(stroke
				(width 0.1)
				(type default)
			)
			(layer "F.Fab")
		)
		(fp_line
			(start 0.120396 0.2794)
			(end -0.12065 0.2794)
			(stroke
				(width 0.1)
				(type default)
			)
			(layer "F.Fab")
		)
		(fp_line
			(start 0.120396 0.3048)
			(end 0.120396 0.2794)
			(stroke
				(width 0.1)
				(type default)
			)
			(layer "F.Fab")
		)
		(fp_line
			(start 0.12065 -0.3048)
			(end 0.67945 -0.3048)
			(stroke
				(width 0.1)
				(type default)
			)
			(layer "F.Fab")
		)
		(fp_line
			(start 0.12065 -0.2794)
			(end 0.12065 -0.3048)
			(stroke
				(width 0.1)
				(type default)
			)
			(layer "F.Fab")
		)
		(fp_line
			(start 0.67945 -0.3048)
			(end 0.67945 0.3048)
			(stroke
				(width 0.1)
				(type default)
			)
			(layer "F.Fab")
		)
		(fp_line
			(start 0.67945 0.3048)
			(end 0.120396 0.3048)
			(stroke
				(width 0.1)
				(type default)
			)
			(layer "F.Fab")
		)
		(pad "1" smd circle
			(at -0.40005 0)
			(size 0 0)
			(layers "F.Cu" "F.Mask" "F.Paste")
			(net "PWRGD_CHGL_CPU1")
		)
		(pad "2" smd circle
			(at 0.40005 0)
			(size 0 0)
			(layers "F.Cu" "F.Mask" "F.Paste")
			(net "PWRGD_CHGL_CPU1_R1")
		)
	)
	(footprint ""
		(layer "F.Cu")
		(at 196.729858 -77.06614 180)
		(property "Reference" "R79"
			(at 0 0 180)
			(layer "F.SilkS")
			(hide yes)
			(effects
				(font
					(size 1.27 1.27)
				)
			)
		)
		(property "Value" ""
			(at 0 0 180)
			(layer "F.Fab")
			(effects
				(font
					(size 1.27 1.27)
				)
			)
		)
		(duplicate_pad_numbers_are_jumpers no)
		(fp_line
			(start 0.7874 0.4064)
			(end -0.7874 0.4064)
			(stroke
				(width 0.1524)
				(type default)
			)
			(layer "F.SilkS")
		)
		(fp_line
			(start 0.7874 -0.4064)
			(end 0.7874 0.4064)
			(stroke
				(width 0.1524)
				(type default)
			)
			(layer "F.SilkS")
		)
		(fp_line
			(start -0.7874 0.4064)
			(end -0.7874 -0.4064)
			(stroke
				(width 0.1524)
				(type default)
			)
			(layer "F.SilkS")
		)
		(fp_line
			(start -0.7874 -0.4064)
			(end 0.7874 -0.4064)
			(stroke
				(width 0.1524)
				(type default)
			)
			(layer "F.SilkS")
		)
		(fp_line
			(start 0.67945 0.3048)
			(end 0.120396 0.3048)
			(stroke
				(width 0.1)
				(type default)
			)
			(layer "F.Fab")
		)
		(fp_line
			(start 0.67945 -0.3048)
			(end 0.67945 0.3048)
			(stroke
				(width 0.1)
				(type default)
			)
			(layer "F.Fab")
		)
		(fp_line
			(start 0.12065 -0.2794)
			(end 0.12065 -0.3048)
			(stroke
				(width 0.1)
				(type default)
			)
			(layer "F.Fab")
		)
		(fp_line
			(start 0.12065 -0.3048)
			(end 0.67945 -0.3048)
			(stroke
				(width 0.1)
				(type default)
			)
			(layer "F.Fab")
		)
		(fp_line
			(start 0.120396 0.3048)
			(end 0.120396 0.2794)
			(stroke
				(width 0.1)
				(type default)
			)
			(layer "F.Fab")
		)
		(fp_line
			(start 0.120396 0.2794)
			(end -0.12065 0.2794)
			(stroke
				(width 0.1)
				(type default)
			)
			(layer "F.Fab")
		)
		(fp_line
			(start -0.12065 0.3048)
			(end -0.67945 0.3048)
			(stroke
				(width 0.1)
				(type default)
			)
			(layer "F.Fab")
		)
		(fp_line
			(start -0.12065 0.2794)
			(end -0.12065 0.3048)
			(stroke
				(width 0.1)
				(type default)
			)
			(layer "F.Fab")
		)
		(fp_line
			(start -0.12065 -0.2794)
			(end 0.12065 -0.2794)
			(stroke
				(width 0.1)
				(type default)
			)
			(layer "F.Fab")
		)
		(fp_line
			(start -0.12065 -0.305054)
			(end -0.12065 -0.2794)
			(stroke
				(width 0.1)
				(type default)
			)
			(layer "F.Fab")
		)
		(fp_line
			(start -0.67945 0.3048)
			(end -0.67945 -0.305054)
			(stroke
				(width 0.1)
				(type default)
			)
			(layer "F.Fab")
		)
		(fp_line
			(start -0.67945 -0.305054)
			(end -0.12065 -0.305054)
			(stroke
				(width 0.1)
				(type default)
			)
			(layer "F.Fab")
		)
		(pad "1" smd circle
			(at -0.40005 0 180)
			(size 0 0)
			(layers "F.Cu" "F.Mask" "F.Paste")
			(net "RMII_OCP_BMC_RXD_0")
		)
		(pad "2" smd circle
			(at 0.40005 0 180)
			(size 0 0)
			(layers "F.Cu" "F.Mask" "F.Paste")
			(net "GND")
		)
	)
	(footprint ""
		(layer "F.Cu")
		(at 420.153338 -157.606492 -90)
		(property "Reference" "PR445"
			(at 0 0 270)
			(layer "F.SilkS")
			(hide yes)
			(effects
				(font
					(size 1.27 1.27)
				)
			)
		)
		(property "Value" ""
			(at 0 0 270)
			(layer "F.Fab")
			(effects
				(font
					(size 1.27 1.27)
				)
			)
		)
		(duplicate_pad_numbers_are_jumpers no)
		(fp_line
			(start -0.7874 0.4064)
			(end -0.7874 -0.4064)
			(stroke
				(width 0.1524)
				(type default)
			)
			(layer "F.SilkS")
		)
		(fp_line
			(start 0.7874 0.4064)
			(end -0.7874 0.4064)
			(stroke
				(width 0.1524)
				(type default)
			)
			(layer "F.SilkS")
		)
		(fp_line
			(start -0.7874 -0.4064)
			(end 0.7874 -0.4064)
			(stroke
				(width 0.1524)
				(type default)
			)
			(layer "F.SilkS")
		)
		(fp_line
			(start 0.7874 -0.4064)
			(end 0.7874 0.4064)
			(stroke
				(width 0.1524)
				(type default)
			)
			(layer "F.SilkS")
		)
		(fp_line
			(start -0.67945 0.3048)
			(end -0.67945 -0.305054)
			(stroke
				(width 0.1)
				(type default)
			)
			(layer "F.Fab")
		)
		(fp_line
			(start -0.12065 0.3048)
			(end -0.67945 0.3048)
			(stroke
				(width 0.1)
				(type default)
			)
			(layer "F.Fab")
		)
		(fp_line
			(start 0.120396 0.3048)
			(end 0.120396 0.2794)
			(stroke
				(width 0.1)
				(type default)
			)
			(layer "F.Fab")
		)
		(fp_line
			(start 0.67945 0.3048)
			(end 0.120396 0.3048)
			(stroke
				(width 0.1)
				(type default)
			)
			(layer "F.Fab")
		)
		(fp_line
			(start -0.12065 0.2794)
			(end -0.12065 0.3048)
			(stroke
				(width 0.1)
				(type default)
			)
			(layer "F.Fab")
		)
		(fp_line
			(start 0.120396 0.2794)
			(end -0.12065 0.2794)
			(stroke
				(width 0.1)
				(type default)
			)
			(layer "F.Fab")
		)
		(fp_line
			(start -0.12065 -0.2794)
			(end 0.12065 -0.2794)
			(stroke
				(width 0.1)
				(type default)
			)
			(layer "F.Fab")
		)
		(fp_line
			(start 0.12065 -0.2794)
			(end 0.12065 -0.3048)
			(stroke
				(width 0.1)
				(type default)
			)
			(layer "F.Fab")
		)
		(fp_line
			(start 0.12065 -0.3048)
			(end 0.67945 -0.3048)
			(stroke
				(width 0.1)
				(type default)
			)
			(layer "F.Fab")
		)
		(fp_line
			(start 0.67945 -0.3048)
			(end 0.67945 0.3048)
			(stroke
				(width 0.1)
				(type default)
			)
			(layer "F.Fab")
		)
		(fp_line
			(start -0.67945 -0.305054)
			(end -0.12065 -0.305054)
			(stroke
				(width 0.1)
				(type default)
			)
			(layer "F.Fab")
		)
		(fp_line
			(start -0.12065 -0.305054)
			(end -0.12065 -0.2794)
			(stroke
				(width 0.1)
				(type default)
			)
			(layer "F.Fab")
		)
		(pad "1" smd circle
			(at -0.40005 0 270)
			(size 0 0)
			(layers "F.Cu" "F.Mask" "F.Paste")
			(net "PVDDCR_CPU0_P0_PVCC")
		)
		(pad "2" smd circle
			(at 0.40005 0 270)
			(size 0 0)
			(layers "F.Cu" "F.Mask" "F.Paste")
			(net "P5V_AUX")
		)
	)
	(footprint ""
		(layer "F.Cu")
		(at 394.981938 -393.9032 90)
		(property "Reference" "R1097"
			(at 0 0 90)
			(layer "F.SilkS")
			(hide yes)
			(effects
				(font
					(size 1.27 1.27)
				)
			)
		)
		(property "Value" ""
			(at 0 0 90)
			(layer "F.Fab")
			(effects
				(font
					(size 1.27 1.27)
				)
			)
		)
		(duplicate_pad_numbers_are_jumpers no)
		(fp_line
			(start 0.32512 -0.175006)
			(end 0.32512 0.175006)
			(stroke
				(width 0.1)
				(type default)
			)
			(layer "F.Fab")
		)
		(fp_line
			(start -0.32512 -0.175006)
			(end 0.32512 -0.175006)
			(stroke
				(width 0.1)
				(type default)
			)
			(layer "F.Fab")
		)
		(fp_line
			(start 0.32512 0.175006)
			(end -0.32512 0.175006)
			(stroke
				(width 0.1)
				(type default)
			)
			(layer "F.Fab")
		)
		(fp_line
			(start -0.32512 0.175006)
			(end -0.32512 -0.175006)
			(stroke
				(width 0.1)
				(type default)
			)
			(layer "F.Fab")
		)
		(pad "1" smd rect
			(at -0.2667 0 90)
			(size 0.3048 0.381)
			(layers "F.Cu" "F.Mask" "F.Paste")
			(net "P1V8_CPU0_RT_1D")
		)
		(pad "2" smd rect
			(at 0.2667 0 270)
			(size 0.3048 0.381)
			(layers "F.Cu" "F.Mask" "F.Paste")
			(net "RT_CPU0_P3_ADDR3")
		)
	)
	(footprint ""
		(layer "F.Cu")
		(at 245.222268 -44.03979 90)
		(property "Reference" "C1278"
			(at 0 0 90)
			(layer "F.SilkS")
			(hide yes)
			(effects
				(font
					(size 1.27 1.27)
				)
			)
		)
		(property "Value" ""
			(at 0 0 90)
			(layer "F.Fab")
			(effects
				(font
					(size 1.27 1.27)
				)
			)
		)
		(duplicate_pad_numbers_are_jumpers no)
		(fp_line
			(start 0.7874 -0.4064)
			(end 0.7874 0.4064)
			(stroke
				(width 0.1524)
				(type default)
			)
			(layer "F.SilkS")
		)
		(fp_line
			(start -0.7874 -0.4064)
			(end 0.7874 -0.4064)
			(stroke
				(width 0.1524)
				(type default)
			)
			(layer "F.SilkS")
		)
		(fp_line
			(start 0.7874 0.4064)
			(end -0.7874 0.4064)
			(stroke
				(width 0.1524)
				(type default)
			)
			(layer "F.SilkS")
		)
		(fp_line
			(start -0.7874 0.4064)
			(end -0.7874 -0.4064)
			(stroke
				(width 0.1524)
				(type default)
			)
			(layer "F.SilkS")
		)
		(fp_line
			(start -0.12065 -0.305054)
			(end -0.12065 -0.2794)
			(stroke
				(width 0.1)
				(type default)
			)
			(layer "F.Fab")
		)
		(fp_line
			(start -0.67945 -0.305054)
			(end -0.12065 -0.305054)
			(stroke
				(width 0.1)
				(type default)
			)
			(layer "F.Fab")
		)
		(fp_line
			(start 0.67945 -0.3048)
			(end 0.67945 0.3048)
			(stroke
				(width 0.1)
				(type default)
			)
			(layer "F.Fab")
		)
		(fp_line
			(start 0.12065 -0.3048)
			(end 0.67945 -0.3048)
			(stroke
				(width 0.1)
				(type default)
			)
			(layer "F.Fab")
		)
		(fp_line
			(start 0.12065 -0.2794)
			(end 0.12065 -0.3048)
			(stroke
				(width 0.1)
				(type default)
			)
			(layer "F.Fab")
		)
		(fp_line
			(start -0.12065 -0.2794)
			(end 0.12065 -0.2794)
			(stroke
				(width 0.1)
				(type default)
			)
			(layer "F.Fab")
		)
		(fp_line
			(start 0.120396 0.2794)
			(end -0.12065 0.2794)
			(stroke
				(width 0.1)
				(type default)
			)
			(layer "F.Fab")
		)
		(fp_line
			(start -0.12065 0.2794)
			(end -0.12065 0.3048)
			(stroke
				(width 0.1)
				(type default)
			)
			(layer "F.Fab")
		)
		(fp_line
			(start 0.67945 0.3048)
			(end 0.120396 0.3048)
			(stroke
				(width 0.1)
				(type default)
			)
			(layer "F.Fab")
		)
		(fp_line
			(start 0.120396 0.3048)
			(end 0.120396 0.2794)
			(stroke
				(width 0.1)
				(type default)
			)
			(layer "F.Fab")
		)
		(fp_line
			(start -0.12065 0.3048)
			(end -0.67945 0.3048)
			(stroke
				(width 0.1)
				(type default)
			)
			(layer "F.Fab")
		)
		(fp_line
			(start -0.67945 0.3048)
			(end -0.67945 -0.305054)
			(stroke
				(width 0.1)
				(type default)
			)
			(layer "F.Fab")
		)
		(pad "1" smd circle
			(at -0.40005 0 90)
			(size 0 0)
			(layers "F.Cu" "F.Mask" "F.Paste")
			(net "P12V_E1S_0_R")
		)
		(pad "2" smd circle
			(at 0.40005 0 90)
			(size 0 0)
			(layers "F.Cu" "F.Mask" "F.Paste")
			(net "GND")
		)
	)
	(footprint ""
		(layer "F.Cu")
		(at 186.53252 -19.435572 90)
		(property "Reference" "R6064"
			(at 0 0 90)
			(layer "F.SilkS")
			(hide yes)
			(effects
				(font
					(size 1.27 1.27)
				)
			)
		)
		(property "Value" ""
			(at 0 0 90)
			(layer "F.Fab")
			(effects
				(font
					(size 1.27 1.27)
				)
			)
		)
		(duplicate_pad_numbers_are_jumpers no)
		(fp_line
			(start 0.7874 -0.4064)
			(end 0.7874 0.4064)
			(stroke
				(width 0.1524)
				(type default)
			)
			(layer "F.SilkS")
		)
		(fp_line
			(start -0.7874 -0.4064)
			(end 0.7874 -0.4064)
			(stroke
				(width 0.1524)
				(type default)
			)
			(layer "F.SilkS")
		)
		(fp_line
			(start 0.7874 0.4064)
			(end -0.7874 0.4064)
			(stroke
				(width 0.1524)
				(type default)
			)
			(layer "F.SilkS")
		)
		(fp_line
			(start -0.7874 0.4064)
			(end -0.7874 -0.4064)
			(stroke
				(width 0.1524)
				(type default)
			)
			(layer "F.SilkS")
		)
		(fp_line
			(start -0.12065 -0.305054)
			(end -0.12065 -0.2794)
			(stroke
				(width 0.1)
				(type default)
			)
			(layer "F.Fab")
		)
		(fp_line
			(start -0.67945 -0.305054)
			(end -0.12065 -0.305054)
			(stroke
				(width 0.1)
				(type default)
			)
			(layer "F.Fab")
		)
		(fp_line
			(start 0.67945 -0.3048)
			(end 0.67945 0.3048)
			(stroke
				(width 0.1)
				(type default)
			)
			(layer "F.Fab")
		)
		(fp_line
			(start 0.12065 -0.3048)
			(end 0.67945 -0.3048)
			(stroke
				(width 0.1)
				(type default)
			)
			(layer "F.Fab")
		)
		(fp_line
			(start 0.12065 -0.2794)
			(end 0.12065 -0.3048)
			(stroke
				(width 0.1)
				(type default)
			)
			(layer "F.Fab")
		)
		(fp_line
			(start -0.12065 -0.2794)
			(end 0.12065 -0.2794)
			(stroke
				(width 0.1)
				(type default)
			)
			(layer "F.Fab")
		)
		(fp_line
			(start 0.120396 0.2794)
			(end -0.12065 0.2794)
			(stroke
				(width 0.1)
				(type default)
			)
			(layer "F.Fab")
		)
		(fp_line
			(start -0.12065 0.2794)
			(end -0.12065 0.3048)
			(stroke
				(width 0.1)
				(type default)
			)
			(layer "F.Fab")
		)
		(fp_line
			(start 0.67945 0.3048)
			(end 0.120396 0.3048)
			(stroke
				(width 0.1)
				(type default)
			)
			(layer "F.Fab")
		)
		(fp_line
			(start 0.120396 0.3048)
			(end 0.120396 0.2794)
			(stroke
				(width 0.1)
				(type default)
			)
			(layer "F.Fab")
		)
		(fp_line
			(start -0.12065 0.3048)
			(end -0.67945 0.3048)
			(stroke
				(width 0.1)
				(type default)
			)
			(layer "F.Fab")
		)
		(fp_line
			(start -0.67945 0.3048)
			(end -0.67945 -0.305054)
			(stroke
				(width 0.1)
				(type default)
			)
			(layer "F.Fab")
		)
		(pad "1" smd circle
			(at -0.40005 0 90)
			(size 0 0)
			(layers "F.Cu" "F.Mask" "F.Paste")
			(net "UART_CPU0_SCM_LVC3_UART1_RX")
		)
		(pad "2" smd circle
			(at 0.40005 0 90)
			(size 0 0)
			(layers "F.Cu" "F.Mask" "F.Paste")
			(net "UART_CPU0_SCM_LVC3_UART1_R_RX")
		)
	)
	(footprint ""
		(layer "F.Cu")
		(at 101.346 -412.931102 -90)
		(property "Reference" "R4210"
			(at 0 0 270)
			(layer "F.SilkS")
			(hide yes)
			(effects
				(font
					(size 1.27 1.27)
				)
			)
		)
		(property "Value" ""
			(at 0 0 270)
			(layer "F.Fab")
			(effects
				(font
					(size 1.27 1.27)
				)
			)
		)
		(duplicate_pad_numbers_are_jumpers no)
		(fp_line
			(start -0.7874 0.4064)
			(end -0.7874 -0.4064)
			(stroke
				(width 0.1524)
				(type default)
			)
			(layer "F.SilkS")
		)
		(fp_line
			(start 0.7874 0.4064)
			(end -0.7874 0.4064)
			(stroke
				(width 0.1524)
				(type default)
			)
			(layer "F.SilkS")
		)
		(fp_line
			(start -0.7874 -0.4064)
			(end 0.7874 -0.4064)
			(stroke
				(width 0.1524)
				(type default)
			)
			(layer "F.SilkS")
		)
		(fp_line
			(start 0.7874 -0.4064)
			(end 0.7874 0.4064)
			(stroke
				(width 0.1524)
				(type default)
			)
			(layer "F.SilkS")
		)
		(fp_line
			(start -0.67945 0.3048)
			(end -0.67945 -0.305054)
			(stroke
				(width 0.1)
				(type default)
			)
			(layer "F.Fab")
		)
		(fp_line
			(start -0.12065 0.3048)
			(end -0.67945 0.3048)
			(stroke
				(width 0.1)
				(type default)
			)
			(layer "F.Fab")
		)
		(fp_line
			(start 0.120396 0.3048)
			(end 0.120396 0.2794)
			(stroke
				(width 0.1)
				(type default)
			)
			(layer "F.Fab")
		)
		(fp_line
			(start 0.67945 0.3048)
			(end 0.120396 0.3048)
			(stroke
				(width 0.1)
				(type default)
			)
			(layer "F.Fab")
		)
		(fp_line
			(start -0.12065 0.2794)
			(end -0.12065 0.3048)
			(stroke
				(width 0.1)
				(type default)
			)
			(layer "F.Fab")
		)
		(fp_line
			(start 0.120396 0.2794)
			(end -0.12065 0.2794)
			(stroke
				(width 0.1)
				(type default)
			)
			(layer "F.Fab")
		)
		(fp_line
			(start -0.12065 -0.2794)
			(end 0.12065 -0.2794)
			(stroke
				(width 0.1)
				(type default)
			)
			(layer "F.Fab")
		)
		(fp_line
			(start 0.12065 -0.2794)
			(end 0.12065 -0.3048)
			(stroke
				(width 0.1)
				(type default)
			)
			(layer "F.Fab")
		)
		(fp_line
			(start 0.12065 -0.3048)
			(end 0.67945 -0.3048)
			(stroke
				(width 0.1)
				(type default)
			)
			(layer "F.Fab")
		)
		(fp_line
			(start 0.67945 -0.3048)
			(end 0.67945 0.3048)
			(stroke
				(width 0.1)
				(type default)
			)
			(layer "F.Fab")
		)
		(fp_line
			(start -0.67945 -0.305054)
			(end -0.12065 -0.305054)
			(stroke
				(width 0.1)
				(type default)
			)
			(layer "F.Fab")
		)
		(fp_line
			(start -0.12065 -0.305054)
			(end -0.12065 -0.2794)
			(stroke
				(width 0.1)
				(type default)
			)
			(layer "F.Fab")
		)
		(pad "1" smd circle
			(at -0.40005 0 270)
			(size 0 0)
			(layers "F.Cu" "F.Mask" "F.Paste")
			(net "P3V3_AUX")
		)
		(pad "2" smd circle
			(at 0.40005 0 270)
			(size 0 0)
			(layers "F.Cu" "F.Mask" "F.Paste")
			(net "FM_THERMAL_ALERT_N")
		)
	)
	(footprint ""
		(layer "F.Cu")
		(at 94.1832 -401.1676 180)
		(property "Reference" "R1436"
			(at 0 0 180)
			(layer "F.SilkS")
			(hide yes)
			(effects
				(font
					(size 1.27 1.27)
				)
			)
		)
		(property "Value" ""
			(at 0 0 180)
			(layer "F.Fab")
			(effects
				(font
					(size 1.27 1.27)
				)
			)
		)
		(duplicate_pad_numbers_are_jumpers no)
		(fp_line
			(start 0.32512 0.175006)
			(end -0.32512 0.175006)
			(stroke
				(width 0.1)
				(type default)
			)
			(layer "F.Fab")
		)
		(fp_line
			(start 0.32512 -0.175006)
			(end 0.32512 0.175006)
			(stroke
				(width 0.1)
				(type default)
			)
			(layer "F.Fab")
		)
		(fp_line
			(start -0.32512 0.175006)
			(end -0.32512 -0.175006)
			(stroke
				(width 0.1)
				(type default)
			)
			(layer "F.Fab")
		)
		(fp_line
			(start -0.32512 -0.175006)
			(end 0.32512 -0.175006)
			(stroke
				(width 0.1)
				(type default)
			)
			(layer "F.Fab")
		)
		(pad "1" smd rect
			(at -0.2667 0 180)
			(size 0.3048 0.381)
			(layers "F.Cu" "F.Mask" "F.Paste")
			(net "P1V8_CPU1_RT_1D")
		)
		(pad "2" smd rect
			(at 0.2667 0)
			(size 0.3048 0.381)
			(layers "F.Cu" "F.Mask" "F.Paste")
			(net "SMB_RT_CPU1_P0_ROM_MUX_1D_SDA")
		)
	)
	(footprint ""
		(layer "F.Cu")
		(at 63.411354 -373.03583 -90)
		(property "Reference" "C815"
			(at 0 0 270)
			(layer "F.SilkS")
			(hide yes)
			(effects
				(font
					(size 1.27 1.27)
				)
			)
		)
		(property "Value" ""
			(at 0 0 270)
			(layer "F.Fab")
			(effects
				(font
					(size 1.27 1.27)
				)
			)
		)
		(duplicate_pad_numbers_are_jumpers no)
		(fp_line
			(start -0.299974 0.150114)
			(end -0.299974 -0.150114)
			(stroke
				(width 0.1)
				(type default)
			)
			(layer "F.Fab")
		)
		(fp_line
			(start 0.299974 0.150114)
			(end -0.299974 0.150114)
			(stroke
				(width 0.1)
				(type default)
			)
			(layer "F.Fab")
		)
		(fp_line
			(start -0.299974 -0.150114)
			(end 0.299974 -0.150114)
			(stroke
				(width 0.1)
				(type default)
			)
			(layer "F.Fab")
		)
		(fp_line
			(start 0.299974 -0.150114)
			(end 0.299974 0.150114)
			(stroke
				(width 0.1)
				(type default)
			)
			(layer "F.Fab")
		)
		(pad "1" smd rect
			(at -0.2667 0 270)
			(size 0.3048 0.381)
			(layers "F.Cu" "F.Mask" "F.Paste")
			(net "P5E_CPU1_P0_TX_C_DP<11>")
		)
		(pad "2" smd rect
			(at 0.2667 0 270)
			(size 0.3048 0.381)
			(layers "F.Cu" "F.Mask" "F.Paste")
			(net "P5E_CPU1_P0_TX_DP<11>")
		)
	)
	(footprint ""
		(layer "F.Cu")
		(at 365.794798 -427.39691 180)
		(property "Reference" "R686"
			(at 0 0 180)
			(layer "F.SilkS")
			(hide yes)
			(effects
				(font
					(size 1.27 1.27)
				)
			)
		)
		(property "Value" ""
			(at 0 0 180)
			(layer "F.Fab")
			(effects
				(font
					(size 1.27 1.27)
				)
			)
		)
		(duplicate_pad_numbers_are_jumpers no)
		(fp_line
			(start 0.32512 0.175006)
			(end -0.32512 0.175006)
			(stroke
				(width 0.1)
				(type default)
			)
			(layer "F.Fab")
		)
		(fp_line
			(start 0.32512 -0.175006)
			(end 0.32512 0.175006)
			(stroke
				(width 0.1)
				(type default)
			)
			(layer "F.Fab")
		)
		(fp_line
			(start -0.32512 0.175006)
			(end -0.32512 -0.175006)
			(stroke
				(width 0.1)
				(type default)
			)
			(layer "F.Fab")
		)
		(fp_line
			(start -0.32512 -0.175006)
			(end 0.32512 -0.175006)
			(stroke
				(width 0.1)
				(type default)
			)
			(layer "F.Fab")
		)
		(pad "1" smd rect
			(at -0.2667 0 180)
			(size 0.3048 0.381)
			(layers "F.Cu" "F.Mask" "F.Paste")
			(net "SMB_RT_CPU0_P3_ROM_MUX_1D_SDA")
		)
		(pad "2" smd rect
			(at 0.2667 0)
			(size 0.3048 0.381)
			(layers "F.Cu" "F.Mask" "F.Paste")
			(net "SMB_RT_CPU0_P3_ROM_MUX_1D_R_SDA")
		)
	)
	(footprint ""
		(layer "F.Cu")
		(at 334.795876 -70.098412 90)
		(property "Reference" "D79"
			(at -3.934714 -0.691642 90)
			(unlocked yes)
			(layer "F.SilkS")
			(effects
				(font
					(size 0.7874 0.5842)
					(thickness 0.1524)
				)
				(justify left)
			)
		)
		(property "Value" ""
			(at 0 0 90)
			(layer "F.Fab")
			(effects
				(font
					(size 1.27 1.27)
				)
			)
		)
		(duplicate_pad_numbers_are_jumpers no)
		(fp_line
			(start 1.16078 -0.4826)
			(end 1.16078 0.4826)
			(stroke
				(width 0.1524)
				(type default)
			)
			(layer "F.SilkS")
		)
		(fp_line
			(start 1.03378 -0.4826)
			(end 1.03378 0.4826)
			(stroke
				(width 0.1524)
				(type default)
			)
			(layer "F.SilkS")
		)
		(fp_line
			(start 0.90678 -0.4826)
			(end 0.90678 0.4826)
			(stroke
				(width 0.1524)
				(type default)
			)
			(layer "F.SilkS")
		)
		(fp_line
			(start -0.64008 -0.4826)
			(end 1.16078 -0.4826)
			(stroke
				(width 0.1524)
				(type default)
			)
			(layer "F.SilkS")
		)
		(fp_line
			(start -0.79248 -0.4826)
			(end 1.03378 -0.4826)
			(stroke
				(width 0.1524)
				(type default)
			)
			(layer "F.SilkS")
		)
		(fp_line
			(start -0.89408 -0.4826)
			(end 0.90678 -0.4826)
			(stroke
				(width 0.1524)
				(type default)
			)
			(layer "F.SilkS")
		)
		(fp_line
			(start 1.16078 0.4826)
			(end -0.64008 0.4826)
			(stroke
				(width 0.1524)
				(type default)
			)
			(layer "F.SilkS")
		)
		(fp_line
			(start 1.03378 0.4826)
			(end -0.79248 0.4826)
			(stroke
				(width 0.1524)
				(type default)
			)
			(layer "F.SilkS")
		)
		(fp_line
			(start 0.90678 0.4826)
			(end -0.90678 0.4826)
			(stroke
				(width 0.1524)
				(type default)
			)
			(layer "F.SilkS")
		)
		(fp_line
			(start -0.90678 0.4826)
			(end -0.90678 -0.4699)
			(stroke
				(width 0.1524)
				(type default)
			)
			(layer "F.SilkS")
		)
		(fp_line
			(start 0.499872 -0.249936)
			(end 0.499872 0.249936)
			(stroke
				(width 0.1)
				(type default)
			)
			(layer "F.Fab")
		)
		(fp_line
			(start -0.499872 -0.249936)
			(end 0.499872 -0.249936)
			(stroke
				(width 0.1)
				(type default)
			)
			(layer "F.Fab")
		)
		(fp_line
			(start 0.499872 0.249936)
			(end -0.499872 0.249936)
			(stroke
				(width 0.1)
				(type default)
			)
			(layer "F.Fab")
		)
		(fp_line
			(start -0.499872 0.249936)
			(end -0.499872 -0.249936)
			(stroke
				(width 0.1)
				(type default)
			)
			(layer "F.Fab")
		)
		(pad "A" smd rect
			(at -0.47498 0 90)
			(size 0.6096 0.7112)
			(layers "F.Cu" "F.Mask" "F.Paste")
			(net "LED_PWRGD_PVDD18_S5_P0_R")
		)
		(pad "C" smd rect
			(at 0.47498 0 90)
			(size 0.6096 0.7112)
			(layers "F.Cu" "F.Mask" "F.Paste")
			(net "LED_PWRGD_PVDD18_S5_P0_D")
		)
	)
	(footprint ""
		(layer "F.Cu")
		(at 68.432426 -155.237688)
		(property "Reference" "PC20"
			(at 0 0 0)
			(layer "F.SilkS")
			(hide yes)
			(effects
				(font
					(size 1.27 1.27)
				)
			)
		)
		(property "Value" ""
			(at 0 0 0)
			(layer "F.Fab")
			(effects
				(font
					(size 1.27 1.27)
				)
			)
		)
		(duplicate_pad_numbers_are_jumpers no)
		(fp_line
			(start -0.7874 -0.4064)
			(end 0.7874 -0.4064)
			(stroke
				(width 0.1524)
				(type default)
			)
			(layer "F.SilkS")
		)
		(fp_line
			(start -0.7874 0.4064)
			(end -0.7874 -0.4064)
			(stroke
				(width 0.1524)
				(type default)
			)
			(layer "F.SilkS")
		)
		(fp_line
			(start 0.7874 -0.4064)
			(end 0.7874 0.4064)
			(stroke
				(width 0.1524)
				(type default)
			)
			(layer "F.SilkS")
		)
		(fp_line
			(start 0.7874 0.4064)
			(end -0.7874 0.4064)
			(stroke
				(width 0.1524)
				(type default)
			)
			(layer "F.SilkS")
		)
		(fp_line
			(start -0.67945 -0.305054)
			(end -0.12065 -0.305054)
			(stroke
				(width 0.1)
				(type default)
			)
			(layer "F.Fab")
		)
		(fp_line
			(start -0.67945 0.3048)
			(end -0.67945 -0.305054)
			(stroke
				(width 0.1)
				(type default)
			)
			(layer "F.Fab")
		)
		(fp_line
			(start -0.12065 -0.305054)
			(end -0.12065 -0.2794)
			(stroke
				(width 0.1)
				(type default)
			)
			(layer "F.Fab")
		)
		(fp_line
			(start -0.12065 -0.2794)
			(end 0.12065 -0.2794)
			(stroke
				(width 0.1)
				(type default)
			)
			(layer "F.Fab")
		)
		(fp_line
			(start -0.12065 0.2794)
			(end -0.12065 0.3048)
			(stroke
				(width 0.1)
				(type default)
			)
			(layer "F.Fab")
		)
		(fp_line
			(start -0.12065 0.3048)
			(end -0.67945 0.3048)
			(stroke
				(width 0.1)
				(type default)
			)
			(layer "F.Fab")
		)
		(fp_line
			(start 0.120396 0.2794)
			(end -0.12065 0.2794)
			(stroke
				(width 0.1)
				(type default)
			)
			(layer "F.Fab")
		)
		(fp_line
			(start 0.120396 0.3048)
			(end 0.120396 0.2794)
			(stroke
				(width 0.1)
				(type default)
			)
			(layer "F.Fab")
		)
		(fp_line
			(start 0.12065 -0.3048)
			(end 0.67945 -0.3048)
			(stroke
				(width 0.1)
				(type default)
			)
			(layer "F.Fab")
		)
		(fp_line
			(start 0.12065 -0.2794)
			(end 0.12065 -0.3048)
			(stroke
				(width 0.1)
				(type default)
			)
			(layer "F.Fab")
		)
		(fp_line
			(start 0.67945 -0.3048)
			(end 0.67945 0.3048)
			(stroke
				(width 0.1)
				(type default)
			)
			(layer "F.Fab")
		)
		(fp_line
			(start 0.67945 0.3048)
			(end 0.120396 0.3048)
			(stroke
				(width 0.1)
				(type default)
			)
			(layer "F.Fab")
		)
		(pad "1" smd circle
			(at -0.40005 0)
			(size 0 0)
			(layers "F.Cu" "F.Mask" "F.Paste")
			(net "PVDD18_S5_P1_VCC")
		)
		(pad "2" smd circle
			(at 0.40005 0)
			(size 0 0)
			(layers "F.Cu" "F.Mask" "F.Paste")
			(net "GND")
		)
	)
	(footprint ""
		(layer "F.Cu")
		(at 112.649 -411.1498)
		(property "Reference" "C68"
			(at 0 0 0)
			(layer "F.SilkS")
			(hide yes)
			(effects
				(font
					(size 1.27 1.27)
				)
			)
		)
		(property "Value" ""
			(at 0 0 0)
			(layer "F.Fab")
			(effects
				(font
					(size 1.27 1.27)
				)
			)
		)
		(duplicate_pad_numbers_are_jumpers no)
		(fp_line
			(start -0.7874 -0.4064)
			(end 0.7874 -0.4064)
			(stroke
				(width 0.1524)
				(type default)
			)
			(layer "F.SilkS")
		)
		(fp_line
			(start -0.7874 0.4064)
			(end -0.7874 -0.4064)
			(stroke
				(width 0.1524)
				(type default)
			)
			(layer "F.SilkS")
		)
		(fp_line
			(start 0.7874 -0.4064)
			(end 0.7874 0.4064)
			(stroke
				(width 0.1524)
				(type default)
			)
			(layer "F.SilkS")
		)
		(fp_line
			(start 0.7874 0.4064)
			(end -0.7874 0.4064)
			(stroke
				(width 0.1524)
				(type default)
			)
			(layer "F.SilkS")
		)
		(fp_line
			(start -0.67945 -0.305054)
			(end -0.12065 -0.305054)
			(stroke
				(width 0.1)
				(type default)
			)
			(layer "F.Fab")
		)
		(fp_line
			(start -0.67945 0.3048)
			(end -0.67945 -0.305054)
			(stroke
				(width 0.1)
				(type default)
			)
			(layer "F.Fab")
		)
		(fp_line
			(start -0.12065 -0.305054)
			(end -0.12065 -0.2794)
			(stroke
				(width 0.1)
				(type default)
			)
			(layer "F.Fab")
		)
		(fp_line
			(start -0.12065 -0.2794)
			(end 0.12065 -0.2794)
			(stroke
				(width 0.1)
				(type default)
			)
			(layer "F.Fab")
		)
		(fp_line
			(start -0.12065 0.2794)
			(end -0.12065 0.3048)
			(stroke
				(width 0.1)
				(type default)
			)
			(layer "F.Fab")
		)
		(fp_line
			(start -0.12065 0.3048)
			(end -0.67945 0.3048)
			(stroke
				(width 0.1)
				(type default)
			)
			(layer "F.Fab")
		)
		(fp_line
			(start 0.120396 0.2794)
			(end -0.12065 0.2794)
			(stroke
				(width 0.1)
				(type default)
			)
			(layer "F.Fab")
		)
		(fp_line
			(start 0.120396 0.3048)
			(end 0.120396 0.2794)
			(stroke
				(width 0.1)
				(type default)
			)
			(layer "F.Fab")
		)
		(fp_line
			(start 0.12065 -0.3048)
			(end 0.67945 -0.3048)
			(stroke
				(width 0.1)
				(type default)
			)
			(layer "F.Fab")
		)
		(fp_line
			(start 0.12065 -0.2794)
			(end 0.12065 -0.3048)
			(stroke
				(width 0.1)
				(type default)
			)
			(layer "F.Fab")
		)
		(fp_line
			(start 0.67945 -0.3048)
			(end 0.67945 0.3048)
			(stroke
				(width 0.1)
				(type default)
			)
			(layer "F.Fab")
		)
		(fp_line
			(start 0.67945 0.3048)
			(end 0.120396 0.3048)
			(stroke
				(width 0.1)
				(type default)
			)
			(layer "F.Fab")
		)
		(pad "1" smd circle
			(at -0.40005 0)
			(size 0 0)
			(layers "F.Cu" "F.Mask" "F.Paste")
			(net "P3V3_9ZXL045_P1_VDDA")
		)
		(pad "2" smd circle
			(at 0.40005 0)
			(size 0 0)
			(layers "F.Cu" "F.Mask" "F.Paste")
			(net "GND")
		)
	)
	(footprint ""
		(layer "F.Cu")
		(at 277.581106 -414.966404)
		(property "Reference" "R6783"
			(at 0 0 0)
			(layer "F.SilkS")
			(hide yes)
			(effects
				(font
					(size 1.27 1.27)
				)
			)
		)
		(property "Value" ""
			(at 0 0 0)
			(layer "F.Fab")
			(effects
				(font
					(size 1.27 1.27)
				)
			)
		)
		(duplicate_pad_numbers_are_jumpers no)
		(fp_line
			(start -0.7874 -0.4064)
			(end 0.7874 -0.4064)
			(stroke
				(width 0.1524)
				(type default)
			)
			(layer "F.SilkS")
		)
		(fp_line
			(start -0.7874 0.4064)
			(end -0.7874 -0.4064)
			(stroke
				(width 0.1524)
				(type default)
			)
			(layer "F.SilkS")
		)
		(fp_line
			(start 0.7874 -0.4064)
			(end 0.7874 0.4064)
			(stroke
				(width 0.1524)
				(type default)
			)
			(layer "F.SilkS")
		)
		(fp_line
			(start 0.7874 0.4064)
			(end -0.7874 0.4064)
			(stroke
				(width 0.1524)
				(type default)
			)
			(layer "F.SilkS")
		)
		(fp_line
			(start -0.67945 -0.305054)
			(end -0.12065 -0.305054)
			(stroke
				(width 0.1)
				(type default)
			)
			(layer "F.Fab")
		)
		(fp_line
			(start -0.67945 0.3048)
			(end -0.67945 -0.305054)
			(stroke
				(width 0.1)
				(type default)
			)
			(layer "F.Fab")
		)
		(fp_line
			(start -0.12065 -0.305054)
			(end -0.12065 -0.2794)
			(stroke
				(width 0.1)
				(type default)
			)
			(layer "F.Fab")
		)
		(fp_line
			(start -0.12065 -0.2794)
			(end 0.12065 -0.2794)
			(stroke
				(width 0.1)
				(type default)
			)
			(layer "F.Fab")
		)
		(fp_line
			(start -0.12065 0.2794)
			(end -0.12065 0.3048)
			(stroke
				(width 0.1)
				(type default)
			)
			(layer "F.Fab")
		)
		(fp_line
			(start -0.12065 0.3048)
			(end -0.67945 0.3048)
			(stroke
				(width 0.1)
				(type default)
			)
			(layer "F.Fab")
		)
		(fp_line
			(start 0.120396 0.2794)
			(end -0.12065 0.2794)
			(stroke
				(width 0.1)
				(type default)
			)
			(layer "F.Fab")
		)
		(fp_line
			(start 0.120396 0.3048)
			(end 0.120396 0.2794)
			(stroke
				(width 0.1)
				(type default)
			)
			(layer "F.Fab")
		)
		(fp_line
			(start 0.12065 -0.3048)
			(end 0.67945 -0.3048)
			(stroke
				(width 0.1)
				(type default)
			)
			(layer "F.Fab")
		)
		(fp_line
			(start 0.12065 -0.2794)
			(end 0.12065 -0.3048)
			(stroke
				(width 0.1)
				(type default)
			)
			(layer "F.Fab")
		)
		(fp_line
			(start 0.67945 -0.3048)
			(end 0.67945 0.3048)
			(stroke
				(width 0.1)
				(type default)
			)
			(layer "F.Fab")
		)
		(fp_line
			(start 0.67945 0.3048)
			(end 0.120396 0.3048)
			(stroke
				(width 0.1)
				(type default)
			)
			(layer "F.Fab")
		)
		(pad "1" smd circle
			(at -0.40005 0)
			(size 0 0)
			(layers "F.Cu" "F.Mask" "F.Paste")
			(net "SMB_MUX_RT_ROM_R1_SDA")
		)
		(pad "2" smd circle
			(at 0.40005 0)
			(size 0 0)
			(layers "F.Cu" "F.Mask" "F.Paste")
			(net "SMB_HOST_CLK_3V3AUX_SDA_R1")
		)
	)
	(footprint ""
		(layer "F.Cu")
		(at 419.96106 -353.78009 90)
		(property "Reference" "PC203"
			(at 0 0 90)
			(layer "F.SilkS")
			(hide yes)
			(effects
				(font
					(size 1.27 1.27)
				)
			)
		)
		(property "Value" ""
			(at 0 0 90)
			(layer "F.Fab")
			(effects
				(font
					(size 1.27 1.27)
				)
			)
		)
		(duplicate_pad_numbers_are_jumpers no)
		(fp_line
			(start 0.7874 -0.4064)
			(end 0.7874 0.4064)
			(stroke
				(width 0.1524)
				(type default)
			)
			(layer "F.SilkS")
		)
		(fp_line
			(start -0.7874 -0.4064)
			(end 0.7874 -0.4064)
			(stroke
				(width 0.1524)
				(type default)
			)
			(layer "F.SilkS")
		)
		(fp_line
			(start 0.7874 0.4064)
			(end 0.37211 0.4064)
			(stroke
				(width 0.1524)
				(type default)
			)
			(layer "F.SilkS")
		)
		(fp_line
			(start -0.18669 0.4064)
			(end -0.7874 0.4064)
			(stroke
				(width 0.1524)
				(type default)
			)
			(layer "F.SilkS")
		)
		(fp_line
			(start -0.7874 0.4064)
			(end -0.7874 -0.4064)
			(stroke
				(width 0.1524)
				(type default)
			)
			(layer "F.SilkS")
		)
		(fp_line
			(start -0.12065 -0.305054)
			(end -0.12065 -0.2794)
			(stroke
				(width 0.1)
				(type default)
			)
			(layer "F.Fab")
		)
		(fp_line
			(start -0.67945 -0.305054)
			(end -0.12065 -0.305054)
			(stroke
				(width 0.1)
				(type default)
			)
			(layer "F.Fab")
		)
		(fp_line
			(start 0.67945 -0.3048)
			(end 0.67945 0.3048)
			(stroke
				(width 0.1)
				(type default)
			)
			(layer "F.Fab")
		)
		(fp_line
			(start 0.12065 -0.3048)
			(end 0.67945 -0.3048)
			(stroke
				(width 0.1)
				(type default)
			)
			(layer "F.Fab")
		)
		(fp_line
			(start 0.12065 -0.2794)
			(end 0.12065 -0.3048)
			(stroke
				(width 0.1)
				(type default)
			)
			(layer "F.Fab")
		)
		(fp_line
			(start -0.12065 -0.2794)
			(end 0.12065 -0.2794)
			(stroke
				(width 0.1)
				(type default)
			)
			(layer "F.Fab")
		)
		(fp_line
			(start 0.120396 0.2794)
			(end -0.12065 0.2794)
			(stroke
				(width 0.1)
				(type default)
			)
			(layer "F.Fab")
		)
		(fp_line
			(start -0.12065 0.2794)
			(end -0.12065 0.3048)
			(stroke
				(width 0.1)
				(type default)
			)
			(layer "F.Fab")
		)
		(fp_line
			(start 0.67945 0.3048)
			(end 0.120396 0.3048)
			(stroke
				(width 0.1)
				(type default)
			)
			(layer "F.Fab")
		)
		(fp_line
			(start 0.120396 0.3048)
			(end 0.120396 0.2794)
			(stroke
				(width 0.1)
				(type default)
			)
			(layer "F.Fab")
		)
		(fp_line
			(start -0.12065 0.3048)
			(end -0.67945 0.3048)
			(stroke
				(width 0.1)
				(type default)
			)
			(layer "F.Fab")
		)
		(fp_line
			(start -0.67945 0.3048)
			(end -0.67945 -0.305054)
			(stroke
				(width 0.1)
				(type default)
			)
			(layer "F.Fab")
		)
		(pad "1" smd circle
			(at -0.40005 0 90)
			(size 0 0)
			(layers "F.Cu" "F.Mask" "F.Paste")
			(net "PVDD11_S3_P0_VCC1")
		)
		(pad "2" smd circle
			(at 0.40005 0 90)
			(size 0 0)
			(layers "F.Cu" "F.Mask" "F.Paste")
			(net "GND")
		)
	)
	(footprint ""
		(layer "F.Cu")
		(at 42.967402 -376.85726 180)
		(property "Reference" "C834"
			(at 0 0 180)
			(layer "F.SilkS")
			(hide yes)
			(effects
				(font
					(size 1.27 1.27)
				)
			)
		)
		(property "Value" ""
			(at 0 0 180)
			(layer "F.Fab")
			(effects
				(font
					(size 1.27 1.27)
				)
			)
		)
		(duplicate_pad_numbers_are_jumpers no)
		(fp_line
			(start 0.299974 0.150114)
			(end -0.299974 0.150114)
			(stroke
				(width 0.1)
				(type default)
			)
			(layer "F.Fab")
		)
		(fp_line
			(start 0.299974 -0.150114)
			(end 0.299974 0.150114)
			(stroke
				(width 0.1)
				(type default)
			)
			(layer "F.Fab")
		)
		(fp_line
			(start -0.299974 0.150114)
			(end -0.299974 -0.150114)
			(stroke
				(width 0.1)
				(type default)
			)
			(layer "F.Fab")
		)
		(fp_line
			(start -0.299974 -0.150114)
			(end 0.299974 -0.150114)
			(stroke
				(width 0.1)
				(type default)
			)
			(layer "F.Fab")
		)
		(pad "1" smd rect
			(at -0.2667 0 180)
			(size 0.3048 0.381)
			(layers "F.Cu" "F.Mask" "F.Paste")
			(net "P5E_CPU1_P0_TX_C_DN<1>")
		)
		(pad "2" smd rect
			(at 0.2667 0 180)
			(size 0.3048 0.381)
			(layers "F.Cu" "F.Mask" "F.Paste")
			(net "P5E_CPU1_P0_TX_DN<1>")
		)
	)
	(footprint ""
		(layer "F.Cu")
		(at 410.479748 -17.624298 90)
		(property "Reference" "C44"
			(at 0 0 90)
			(layer "F.SilkS")
			(hide yes)
			(effects
				(font
					(size 1.27 1.27)
				)
			)
		)
		(property "Value" ""
			(at 0 0 90)
			(layer "F.Fab")
			(effects
				(font
					(size 1.27 1.27)
				)
			)
		)
		(duplicate_pad_numbers_are_jumpers no)
		(fp_line
			(start 0.299974 -0.150114)
			(end 0.299974 0.150114)
			(stroke
				(width 0.1)
				(type default)
			)
			(layer "F.Fab")
		)
		(fp_line
			(start -0.299974 -0.150114)
			(end 0.299974 -0.150114)
			(stroke
				(width 0.1)
				(type default)
			)
			(layer "F.Fab")
		)
		(fp_line
			(start 0.299974 0.150114)
			(end -0.299974 0.150114)
			(stroke
				(width 0.1)
				(type default)
			)
			(layer "F.Fab")
		)
		(fp_line
			(start -0.299974 0.150114)
			(end -0.299974 -0.150114)
			(stroke
				(width 0.1)
				(type default)
			)
			(layer "F.Fab")
		)
		(pad "1" smd rect
			(at -0.2667 0 90)
			(size 0.3048 0.381)
			(layers "F.Cu" "F.Mask" "F.Paste")
			(net "P5E_CPU0_G3_TX_C_DP<8>")
		)
		(pad "2" smd rect
			(at 0.2667 0 90)
			(size 0.3048 0.381)
			(layers "F.Cu" "F.Mask" "F.Paste")
			(net "P5E_CPU0_G3_TX_DP<8>")
		)
	)
	(footprint ""
		(layer "F.Cu")
		(at 452.995792 -53.075078 90)
		(property "Reference" "PC577"
			(at 0 0 90)
			(layer "F.SilkS")
			(hide yes)
			(effects
				(font
					(size 1.27 1.27)
				)
			)
		)
		(property "Value" ""
			(at 0 0 90)
			(layer "F.Fab")
			(effects
				(font
					(size 1.27 1.27)
				)
			)
		)
		(duplicate_pad_numbers_are_jumpers no)
		(fp_line
			(start 0.7874 -0.4064)
			(end 0.7874 0.4064)
			(stroke
				(width 0.1524)
				(type default)
			)
			(layer "F.SilkS")
		)
		(fp_line
			(start -0.7874 -0.4064)
			(end 0.7874 -0.4064)
			(stroke
				(width 0.1524)
				(type default)
			)
			(layer "F.SilkS")
		)
		(fp_line
			(start 0.7874 0.4064)
			(end -0.7874 0.4064)
			(stroke
				(width 0.1524)
				(type default)
			)
			(layer "F.SilkS")
		)
		(fp_line
			(start -0.7874 0.4064)
			(end -0.7874 -0.4064)
			(stroke
				(width 0.1524)
				(type default)
			)
			(layer "F.SilkS")
		)
		(fp_line
			(start -0.12065 -0.305054)
			(end -0.12065 -0.2794)
			(stroke
				(width 0.1)
				(type default)
			)
			(layer "F.Fab")
		)
		(fp_line
			(start -0.67945 -0.305054)
			(end -0.12065 -0.305054)
			(stroke
				(width 0.1)
				(type default)
			)
			(layer "F.Fab")
		)
		(fp_line
			(start 0.67945 -0.3048)
			(end 0.67945 0.3048)
			(stroke
				(width 0.1)
				(type default)
			)
			(layer "F.Fab")
		)
		(fp_line
			(start 0.12065 -0.3048)
			(end 0.67945 -0.3048)
			(stroke
				(width 0.1)
				(type default)
			)
			(layer "F.Fab")
		)
		(fp_line
			(start 0.12065 -0.2794)
			(end 0.12065 -0.3048)
			(stroke
				(width 0.1)
				(type default)
			)
			(layer "F.Fab")
		)
		(fp_line
			(start -0.12065 -0.2794)
			(end 0.12065 -0.2794)
			(stroke
				(width 0.1)
				(type default)
			)
			(layer "F.Fab")
		)
		(fp_line
			(start 0.120396 0.2794)
			(end -0.12065 0.2794)
			(stroke
				(width 0.1)
				(type default)
			)
			(layer "F.Fab")
		)
		(fp_line
			(start -0.12065 0.2794)
			(end -0.12065 0.3048)
			(stroke
				(width 0.1)
				(type default)
			)
			(layer "F.Fab")
		)
		(fp_line
			(start 0.67945 0.3048)
			(end 0.120396 0.3048)
			(stroke
				(width 0.1)
				(type default)
			)
			(layer "F.Fab")
		)
		(fp_line
			(start 0.120396 0.3048)
			(end 0.120396 0.2794)
			(stroke
				(width 0.1)
				(type default)
			)
			(layer "F.Fab")
		)
		(fp_line
			(start -0.12065 0.3048)
			(end -0.67945 0.3048)
			(stroke
				(width 0.1)
				(type default)
			)
			(layer "F.Fab")
		)
		(fp_line
			(start -0.67945 0.3048)
			(end -0.67945 -0.305054)
			(stroke
				(width 0.1)
				(type default)
			)
			(layer "F.Fab")
		)
		(pad "1" smd circle
			(at -0.40005 0 90)
			(size 0 0)
			(layers "F.Cu" "F.Mask" "F.Paste")
			(net "SW_P3V3_AUX_FLT")
		)
		(pad "2" smd circle
			(at 0.40005 0 90)
			(size 0 0)
			(layers "F.Cu" "F.Mask" "F.Paste")
			(net "GND")
		)
	)
	(footprint ""
		(layer "F.Cu")
		(at 179.705 -100.294948 90)
		(property "Reference" "R190"
			(at 0 0 90)
			(layer "F.SilkS")
			(hide yes)
			(effects
				(font
					(size 1.27 1.27)
				)
			)
		)
		(property "Value" ""
			(at 0 0 90)
			(layer "F.Fab")
			(effects
				(font
					(size 1.27 1.27)
				)
			)
		)
		(duplicate_pad_numbers_are_jumpers no)
		(fp_line
			(start 0.7874 -0.4064)
			(end 0.7874 0.4064)
			(stroke
				(width 0.1524)
				(type default)
			)
			(layer "F.SilkS")
		)
		(fp_line
			(start -0.7874 -0.4064)
			(end 0.7874 -0.4064)
			(stroke
				(width 0.1524)
				(type default)
			)
			(layer "F.SilkS")
		)
		(fp_line
			(start 0.7874 0.4064)
			(end -0.7874 0.4064)
			(stroke
				(width 0.1524)
				(type default)
			)
			(layer "F.SilkS")
		)
		(fp_line
			(start -0.7874 0.4064)
			(end -0.7874 -0.4064)
			(stroke
				(width 0.1524)
				(type default)
			)
			(layer "F.SilkS")
		)
		(fp_line
			(start -0.12065 -0.305054)
			(end -0.12065 -0.2794)
			(stroke
				(width 0.1)
				(type default)
			)
			(layer "F.Fab")
		)
		(fp_line
			(start -0.67945 -0.305054)
			(end -0.12065 -0.305054)
			(stroke
				(width 0.1)
				(type default)
			)
			(layer "F.Fab")
		)
		(fp_line
			(start 0.67945 -0.3048)
			(end 0.67945 0.3048)
			(stroke
				(width 0.1)
				(type default)
			)
			(layer "F.Fab")
		)
		(fp_line
			(start 0.12065 -0.3048)
			(end 0.67945 -0.3048)
			(stroke
				(width 0.1)
				(type default)
			)
			(layer "F.Fab")
		)
		(fp_line
			(start 0.12065 -0.2794)
			(end 0.12065 -0.3048)
			(stroke
				(width 0.1)
				(type default)
			)
			(layer "F.Fab")
		)
		(fp_line
			(start -0.12065 -0.2794)
			(end 0.12065 -0.2794)
			(stroke
				(width 0.1)
				(type default)
			)
			(layer "F.Fab")
		)
		(fp_line
			(start 0.120396 0.2794)
			(end -0.12065 0.2794)
			(stroke
				(width 0.1)
				(type default)
			)
			(layer "F.Fab")
		)
		(fp_line
			(start -0.12065 0.2794)
			(end -0.12065 0.3048)
			(stroke
				(width 0.1)
				(type default)
			)
			(layer "F.Fab")
		)
		(fp_line
			(start 0.67945 0.3048)
			(end 0.120396 0.3048)
			(stroke
				(width 0.1)
				(type default)
			)
			(layer "F.Fab")
		)
		(fp_line
			(start 0.120396 0.3048)
			(end 0.120396 0.2794)
			(stroke
				(width 0.1)
				(type default)
			)
			(layer "F.Fab")
		)
		(fp_line
			(start -0.12065 0.3048)
			(end -0.67945 0.3048)
			(stroke
				(width 0.1)
				(type default)
			)
			(layer "F.Fab")
		)
		(fp_line
			(start -0.67945 0.3048)
			(end -0.67945 -0.305054)
			(stroke
				(width 0.1)
				(type default)
			)
			(layer "F.Fab")
		)
		(pad "1" smd circle
			(at -0.40005 0 90)
			(size 0 0)
			(layers "F.Cu" "F.Mask" "F.Paste")
			(net "FM_CPU1_BMC_RST_N")
		)
		(pad "2" smd circle
			(at 0.40005 0 90)
			(size 0 0)
			(layers "F.Cu" "F.Mask" "F.Paste")
			(net "FM_CPU1_BMC_RST_R_N")
		)
	)
	(footprint ""
		(layer "F.Cu")
		(at 365.887 -411.226 -90)
		(property "Reference" "R6253"
			(at 0 0 270)
			(layer "F.SilkS")
			(hide yes)
			(effects
				(font
					(size 1.27 1.27)
				)
			)
		)
		(property "Value" ""
			(at 0 0 270)
			(layer "F.Fab")
			(effects
				(font
					(size 1.27 1.27)
				)
			)
		)
		(duplicate_pad_numbers_are_jumpers no)
		(fp_line
			(start -0.7874 0.4064)
			(end -0.7874 -0.4064)
			(stroke
				(width 0.1524)
				(type default)
			)
			(layer "F.SilkS")
		)
		(fp_line
			(start 0.7874 0.4064)
			(end -0.7874 0.4064)
			(stroke
				(width 0.1524)
				(type default)
			)
			(layer "F.SilkS")
		)
		(fp_line
			(start -0.7874 -0.4064)
			(end 0.7874 -0.4064)
			(stroke
				(width 0.1524)
				(type default)
			)
			(layer "F.SilkS")
		)
		(fp_line
			(start 0.7874 -0.4064)
			(end 0.7874 0.4064)
			(stroke
				(width 0.1524)
				(type default)
			)
			(layer "F.SilkS")
		)
		(fp_line
			(start -0.67945 0.3048)
			(end -0.67945 -0.305054)
			(stroke
				(width 0.1)
				(type default)
			)
			(layer "F.Fab")
		)
		(fp_line
			(start -0.12065 0.3048)
			(end -0.67945 0.3048)
			(stroke
				(width 0.1)
				(type default)
			)
			(layer "F.Fab")
		)
		(fp_line
			(start 0.120396 0.3048)
			(end 0.120396 0.2794)
			(stroke
				(width 0.1)
				(type default)
			)
			(layer "F.Fab")
		)
		(fp_line
			(start 0.67945 0.3048)
			(end 0.120396 0.3048)
			(stroke
				(width 0.1)
				(type default)
			)
			(layer "F.Fab")
		)
		(fp_line
			(start -0.12065 0.2794)
			(end -0.12065 0.3048)
			(stroke
				(width 0.1)
				(type default)
			)
			(layer "F.Fab")
		)
		(fp_line
			(start 0.120396 0.2794)
			(end -0.12065 0.2794)
			(stroke
				(width 0.1)
				(type default)
			)
			(layer "F.Fab")
		)
		(fp_line
			(start -0.12065 -0.2794)
			(end 0.12065 -0.2794)
			(stroke
				(width 0.1)
				(type default)
			)
			(layer "F.Fab")
		)
		(fp_line
			(start 0.12065 -0.2794)
			(end 0.12065 -0.3048)
			(stroke
				(width 0.1)
				(type default)
			)
			(layer "F.Fab")
		)
		(fp_line
			(start 0.12065 -0.3048)
			(end 0.67945 -0.3048)
			(stroke
				(width 0.1)
				(type default)
			)
			(layer "F.Fab")
		)
		(fp_line
			(start 0.67945 -0.3048)
			(end 0.67945 0.3048)
			(stroke
				(width 0.1)
				(type default)
			)
			(layer "F.Fab")
		)
		(fp_line
			(start -0.67945 -0.305054)
			(end -0.12065 -0.305054)
			(stroke
				(width 0.1)
				(type default)
			)
			(layer "F.Fab")
		)
		(fp_line
			(start -0.12065 -0.305054)
			(end -0.12065 -0.2794)
			(stroke
				(width 0.1)
				(type default)
			)
			(layer "F.Fab")
		)
		(pad "1" smd circle
			(at -0.40005 0 270)
			(size 0 0)
			(layers "F.Cu" "F.Mask" "F.Paste")
			(net "SMB_LM75_0_3V3AUX_SDA")
		)
		(pad "2" smd circle
			(at 0.40005 0 270)
			(size 0 0)
			(layers "F.Cu" "F.Mask" "F.Paste")
			(net "SMB_HSC_TYPE_ADC_SDA")
		)
	)
	(footprint ""
		(layer "F.Cu")
		(at 121.411238 -41.17975 -90)
		(property "Reference" "R6258"
			(at 0 0 270)
			(layer "F.SilkS")
			(hide yes)
			(effects
				(font
					(size 1.27 1.27)
				)
			)
		)
		(property "Value" ""
			(at 0 0 270)
			(layer "F.Fab")
			(effects
				(font
					(size 1.27 1.27)
				)
			)
		)
		(duplicate_pad_numbers_are_jumpers no)
		(fp_line
			(start -0.7874 0.4064)
			(end -0.7874 -0.4064)
			(stroke
				(width 0.1524)
				(type default)
			)
			(layer "F.SilkS")
		)
		(fp_line
			(start 0.7874 0.4064)
			(end -0.7874 0.4064)
			(stroke
				(width 0.1524)
				(type default)
			)
			(layer "F.SilkS")
		)
		(fp_line
			(start -0.7874 -0.4064)
			(end 0.7874 -0.4064)
			(stroke
				(width 0.1524)
				(type default)
			)
			(layer "F.SilkS")
		)
		(fp_line
			(start 0.7874 -0.4064)
			(end 0.7874 0.4064)
			(stroke
				(width 0.1524)
				(type default)
			)
			(layer "F.SilkS")
		)
		(fp_line
			(start -0.67945 0.3048)
			(end -0.67945 -0.305054)
			(stroke
				(width 0.1)
				(type default)
			)
			(layer "F.Fab")
		)
		(fp_line
			(start -0.12065 0.3048)
			(end -0.67945 0.3048)
			(stroke
				(width 0.1)
				(type default)
			)
			(layer "F.Fab")
		)
		(fp_line
			(start 0.120396 0.3048)
			(end 0.120396 0.2794)
			(stroke
				(width 0.1)
				(type default)
			)
			(layer "F.Fab")
		)
		(fp_line
			(start 0.67945 0.3048)
			(end 0.120396 0.3048)
			(stroke
				(width 0.1)
				(type default)
			)
			(layer "F.Fab")
		)
		(fp_line
			(start -0.12065 0.2794)
			(end -0.12065 0.3048)
			(stroke
				(width 0.1)
				(type default)
			)
			(layer "F.Fab")
		)
		(fp_line
			(start 0.120396 0.2794)
			(end -0.12065 0.2794)
			(stroke
				(width 0.1)
				(type default)
			)
			(layer "F.Fab")
		)
		(fp_line
			(start -0.12065 -0.2794)
			(end 0.12065 -0.2794)
			(stroke
				(width 0.1)
				(type default)
			)
			(layer "F.Fab")
		)
		(fp_line
			(start 0.12065 -0.2794)
			(end 0.12065 -0.3048)
			(stroke
				(width 0.1)
				(type default)
			)
			(layer "F.Fab")
		)
		(fp_line
			(start 0.12065 -0.3048)
			(end 0.67945 -0.3048)
			(stroke
				(width 0.1)
				(type default)
			)
			(layer "F.Fab")
		)
		(fp_line
			(start 0.67945 -0.3048)
			(end 0.67945 0.3048)
			(stroke
				(width 0.1)
				(type default)
			)
			(layer "F.Fab")
		)
		(fp_line
			(start -0.67945 -0.305054)
			(end -0.12065 -0.305054)
			(stroke
				(width 0.1)
				(type default)
			)
			(layer "F.Fab")
		)
		(fp_line
			(start -0.12065 -0.305054)
			(end -0.12065 -0.2794)
			(stroke
				(width 0.1)
				(type default)
			)
			(layer "F.Fab")
		)
		(pad "1" smd circle
			(at -0.40005 0 270)
			(size 0 0)
			(layers "F.Cu" "F.Mask" "F.Paste")
			(net "P3V3_AUX")
		)
		(pad "2" smd circle
			(at 0.40005 0 270)
			(size 0 0)
			(layers "F.Cu" "F.Mask" "F.Paste")
			(net "USB_HUB2_TI_PWRCTL2_MRP_VDD12")
		)
	)
	(footprint ""
		(layer "F.Cu")
		(at 302.271938 -119.479568 180)
		(property "Reference" "R722"
			(at 0 0 180)
			(layer "F.SilkS")
			(hide yes)
			(effects
				(font
					(size 1.27 1.27)
				)
			)
		)
		(property "Value" ""
			(at 0 0 180)
			(layer "F.Fab")
			(effects
				(font
					(size 1.27 1.27)
				)
			)
		)
		(duplicate_pad_numbers_are_jumpers no)
		(fp_line
			(start 0.7874 0.4064)
			(end -0.7874 0.4064)
			(stroke
				(width 0.1524)
				(type default)
			)
			(layer "F.SilkS")
		)
		(fp_line
			(start 0.7874 -0.4064)
			(end 0.7874 0.4064)
			(stroke
				(width 0.1524)
				(type default)
			)
			(layer "F.SilkS")
		)
		(fp_line
			(start -0.7874 0.4064)
			(end -0.7874 -0.4064)
			(stroke
				(width 0.1524)
				(type default)
			)
			(layer "F.SilkS")
		)
		(fp_line
			(start -0.7874 -0.4064)
			(end 0.7874 -0.4064)
			(stroke
				(width 0.1524)
				(type default)
			)
			(layer "F.SilkS")
		)
		(fp_line
			(start 0.67945 0.3048)
			(end 0.120396 0.3048)
			(stroke
				(width 0.1)
				(type default)
			)
			(layer "F.Fab")
		)
		(fp_line
			(start 0.67945 -0.3048)
			(end 0.67945 0.3048)
			(stroke
				(width 0.1)
				(type default)
			)
			(layer "F.Fab")
		)
		(fp_line
			(start 0.12065 -0.2794)
			(end 0.12065 -0.3048)
			(stroke
				(width 0.1)
				(type default)
			)
			(layer "F.Fab")
		)
		(fp_line
			(start 0.12065 -0.3048)
			(end 0.67945 -0.3048)
			(stroke
				(width 0.1)
				(type default)
			)
			(layer "F.Fab")
		)
		(fp_line
			(start 0.120396 0.3048)
			(end 0.120396 0.2794)
			(stroke
				(width 0.1)
				(type default)
			)
			(layer "F.Fab")
		)
		(fp_line
			(start 0.120396 0.2794)
			(end -0.12065 0.2794)
			(stroke
				(width 0.1)
				(type default)
			)
			(layer "F.Fab")
		)
		(fp_line
			(start -0.12065 0.3048)
			(end -0.67945 0.3048)
			(stroke
				(width 0.1)
				(type default)
			)
			(layer "F.Fab")
		)
		(fp_line
			(start -0.12065 0.2794)
			(end -0.12065 0.3048)
			(stroke
				(width 0.1)
				(type default)
			)
			(layer "F.Fab")
		)
		(fp_line
			(start -0.12065 -0.2794)
			(end 0.12065 -0.2794)
			(stroke
				(width 0.1)
				(type default)
			)
			(layer "F.Fab")
		)
		(fp_line
			(start -0.12065 -0.305054)
			(end -0.12065 -0.2794)
			(stroke
				(width 0.1)
				(type default)
			)
			(layer "F.Fab")
		)
		(fp_line
			(start -0.67945 0.3048)
			(end -0.67945 -0.305054)
			(stroke
				(width 0.1)
				(type default)
			)
			(layer "F.Fab")
		)
		(fp_line
			(start -0.67945 -0.305054)
			(end -0.12065 -0.305054)
			(stroke
				(width 0.1)
				(type default)
			)
			(layer "F.Fab")
		)
		(pad "1" smd circle
			(at -0.40005 0 180)
			(size 0 0)
			(layers "F.Cu" "F.Mask" "F.Paste")
			(net "MB_FRU_ADDR0")
		)
		(pad "2" smd circle
			(at 0.40005 0 180)
			(size 0 0)
			(layers "F.Cu" "F.Mask" "F.Paste")
			(net "GND")
		)
	)
	(footprint ""
		(layer "F.Cu")
		(at 40.960294 -17.623536 90)
		(property "Reference" "C696"
			(at 0 0 90)
			(layer "F.SilkS")
			(hide yes)
			(effects
				(font
					(size 1.27 1.27)
				)
			)
		)
		(property "Value" ""
			(at 0 0 90)
			(layer "F.Fab")
			(effects
				(font
					(size 1.27 1.27)
				)
			)
		)
		(duplicate_pad_numbers_are_jumpers no)
		(fp_line
			(start 0.299974 -0.150114)
			(end 0.299974 0.150114)
			(stroke
				(width 0.1)
				(type default)
			)
			(layer "F.Fab")
		)
		(fp_line
			(start -0.299974 -0.150114)
			(end 0.299974 -0.150114)
			(stroke
				(width 0.1)
				(type default)
			)
			(layer "F.Fab")
		)
		(fp_line
			(start 0.299974 0.150114)
			(end -0.299974 0.150114)
			(stroke
				(width 0.1)
				(type default)
			)
			(layer "F.Fab")
		)
		(fp_line
			(start -0.299974 0.150114)
			(end -0.299974 -0.150114)
			(stroke
				(width 0.1)
				(type default)
			)
			(layer "F.Fab")
		)
		(pad "1" smd rect
			(at -0.2667 0 90)
			(size 0.3048 0.381)
			(layers "F.Cu" "F.Mask" "F.Paste")
			(net "P5E_CPU1_G1_TX_C_DN<6>")
		)
		(pad "2" smd rect
			(at 0.2667 0 90)
			(size 0.3048 0.381)
			(layers "F.Cu" "F.Mask" "F.Paste")
			(net "P5E_CPU1_G1_TX_DN<6>")
		)
	)
	(footprint ""
		(layer "F.Cu")
		(at 325.39686 -340.199726)
		(property "Reference" "PR77"
			(at 0 0 0)
			(layer "F.SilkS")
			(hide yes)
			(effects
				(font
					(size 1.27 1.27)
				)
			)
		)
		(property "Value" ""
			(at 0 0 0)
			(layer "F.Fab")
			(effects
				(font
					(size 1.27 1.27)
				)
			)
		)
		(duplicate_pad_numbers_are_jumpers no)
		(fp_line
			(start -0.7874 -0.4064)
			(end 0.7874 -0.4064)
			(stroke
				(width 0.1524)
				(type default)
			)
			(layer "F.SilkS")
		)
		(fp_line
			(start -0.7874 0.4064)
			(end -0.7874 -0.4064)
			(stroke
				(width 0.1524)
				(type default)
			)
			(layer "F.SilkS")
		)
		(fp_line
			(start 0.7874 -0.4064)
			(end 0.7874 0.4064)
			(stroke
				(width 0.1524)
				(type default)
			)
			(layer "F.SilkS")
		)
		(fp_line
			(start 0.7874 0.4064)
			(end -0.7874 0.4064)
			(stroke
				(width 0.1524)
				(type default)
			)
			(layer "F.SilkS")
		)
		(fp_line
			(start -0.67945 -0.305054)
			(end -0.12065 -0.305054)
			(stroke
				(width 0.1)
				(type default)
			)
			(layer "F.Fab")
		)
		(fp_line
			(start -0.67945 0.3048)
			(end -0.67945 -0.305054)
			(stroke
				(width 0.1)
				(type default)
			)
			(layer "F.Fab")
		)
		(fp_line
			(start -0.12065 -0.305054)
			(end -0.12065 -0.2794)
			(stroke
				(width 0.1)
				(type default)
			)
			(layer "F.Fab")
		)
		(fp_line
			(start -0.12065 -0.2794)
			(end 0.12065 -0.2794)
			(stroke
				(width 0.1)
				(type default)
			)
			(layer "F.Fab")
		)
		(fp_line
			(start -0.12065 0.2794)
			(end -0.12065 0.3048)
			(stroke
				(width 0.1)
				(type default)
			)
			(layer "F.Fab")
		)
		(fp_line
			(start -0.12065 0.3048)
			(end -0.67945 0.3048)
			(stroke
				(width 0.1)
				(type default)
			)
			(layer "F.Fab")
		)
		(fp_line
			(start 0.120396 0.2794)
			(end -0.12065 0.2794)
			(stroke
				(width 0.1)
				(type default)
			)
			(layer "F.Fab")
		)
		(fp_line
			(start 0.120396 0.3048)
			(end 0.120396 0.2794)
			(stroke
				(width 0.1)
				(type default)
			)
			(layer "F.Fab")
		)
		(fp_line
			(start 0.12065 -0.3048)
			(end 0.67945 -0.3048)
			(stroke
				(width 0.1)
				(type default)
			)
			(layer "F.Fab")
		)
		(fp_line
			(start 0.12065 -0.2794)
			(end 0.12065 -0.3048)
			(stroke
				(width 0.1)
				(type default)
			)
			(layer "F.Fab")
		)
		(fp_line
			(start 0.67945 -0.3048)
			(end 0.67945 0.3048)
			(stroke
				(width 0.1)
				(type default)
			)
			(layer "F.Fab")
		)
		(fp_line
			(start 0.67945 0.3048)
			(end 0.120396 0.3048)
			(stroke
				(width 0.1)
				(type default)
			)
			(layer "F.Fab")
		)
		(pad "1" smd circle
			(at -0.40005 0)
			(size 0 0)
			(layers "F.Cu" "F.Mask" "F.Paste")
			(net "PVDDCR_CPU1_P0_LSET2")
		)
		(pad "2" smd circle
			(at 0.40005 0)
			(size 0 0)
			(layers "F.Cu" "F.Mask" "F.Paste")
			(net "GND")
		)
	)
	(footprint ""
		(layer "F.Cu")
		(at 356.69601 -402.7424 -90)
		(property "Reference" "R1019"
			(at 0 0 270)
			(layer "F.SilkS")
			(hide yes)
			(effects
				(font
					(size 1.27 1.27)
				)
			)
		)
		(property "Value" ""
			(at 0 0 270)
			(layer "F.Fab")
			(effects
				(font
					(size 1.27 1.27)
				)
			)
		)
		(duplicate_pad_numbers_are_jumpers no)
		(fp_line
			(start -0.32512 0.175006)
			(end -0.32512 -0.175006)
			(stroke
				(width 0.1)
				(type default)
			)
			(layer "F.Fab")
		)
		(fp_line
			(start 0.32512 0.175006)
			(end -0.32512 0.175006)
			(stroke
				(width 0.1)
				(type default)
			)
			(layer "F.Fab")
		)
		(fp_line
			(start -0.32512 -0.175006)
			(end 0.32512 -0.175006)
			(stroke
				(width 0.1)
				(type default)
			)
			(layer "F.Fab")
		)
		(fp_line
			(start 0.32512 -0.175006)
			(end 0.32512 0.175006)
			(stroke
				(width 0.1)
				(type default)
			)
			(layer "F.Fab")
		)
		(pad "1" smd rect
			(at -0.2667 0 270)
			(size 0.3048 0.381)
			(layers "F.Cu" "F.Mask" "F.Paste")
			(net "RST_RT_CPU0_P1_PERST_R_N")
		)
		(pad "2" smd rect
			(at 0.2667 0 90)
			(size 0.3048 0.381)
			(layers "F.Cu" "F.Mask" "F.Paste")
			(net "GND")
		)
	)
	(footprint ""
		(layer "F.Cu")
		(at 58.017918 -83.554062)
		(property "Reference" "ME1"
			(at 0.1016 -5.9055 0)
			(unlocked yes)
			(layer "F.SilkS")
			(effects
				(font
					(size 0.254 0.127)
					(thickness 0.000001)
				)
				(justify left)
			)
		)
		(property "Value" ""
			(at 0 0 0)
			(layer "F.Fab")
			(effects
				(font
					(size 1.27 1.27)
				)
			)
		)
		(duplicate_pad_numbers_are_jumpers no)
		(fp_line
			(start 0.089408 -2.660396)
			(end 1.561846 -4.072636)
			(stroke
				(width 0.1)
				(type default)
			)
			(layer "F.SilkS")
		)
		(fp_line
			(start 0.089408 -2.660396)
			(end 1.561846 -4.072636)
			(stroke
				(width 0.1)
				(type default)
			)
			(layer "F.SilkS")
		)
		(fp_line
			(start 0.098806 -2.611628)
			(end 1.482344 -3.938778)
			(stroke
				(width 0.1)
				(type default)
			)
			(layer "F.SilkS")
		)
		(fp_line
			(start 0.098806 -2.611628)
			(end 1.482344 -3.938778)
			(stroke
				(width 0.1)
				(type default)
			)
			(layer "F.SilkS")
		)
		(fp_line
			(start 0.108204 -2.563114)
			(end 1.4224 -3.823716)
			(stroke
				(width 0.1)
				(type default)
			)
			(layer "F.SilkS")
		)
		(fp_line
			(start 0.108204 -2.563114)
			(end 1.4224 -3.823716)
			(stroke
				(width 0.1)
				(type default)
			)
			(layer "F.SilkS")
		)
		(fp_line
			(start 0.117602 -2.514346)
			(end 1.38557 -3.730498)
			(stroke
				(width 0.1)
				(type default)
			)
			(layer "F.SilkS")
		)
		(fp_line
			(start 0.117602 -2.514346)
			(end 1.38557 -3.730498)
			(stroke
				(width 0.1)
				(type default)
			)
			(layer "F.SilkS")
		)
		(fp_line
			(start 0.127254 -2.465832)
			(end 1.360932 -3.649218)
			(stroke
				(width 0.1)
				(type default)
			)
			(layer "F.SilkS")
		)
		(fp_line
			(start 0.127254 -2.465832)
			(end 1.360932 -3.649218)
			(stroke
				(width 0.1)
				(type default)
			)
			(layer "F.SilkS")
		)
		(fp_line
			(start 0.139954 -2.420366)
			(end 1.336548 -3.568192)
			(stroke
				(width 0.1)
				(type default)
			)
			(layer "F.SilkS")
		)
		(fp_line
			(start 0.139954 -2.420366)
			(end 1.336548 -3.568192)
			(stroke
				(width 0.1)
				(type default)
			)
			(layer "F.SilkS")
		)
		(fp_line
			(start 0.152908 -2.3749)
			(end 1.31445 -3.489198)
			(stroke
				(width 0.1)
				(type default)
			)
			(layer "F.SilkS")
		)
		(fp_line
			(start 0.152908 -2.3749)
			(end 1.31445 -3.489198)
			(stroke
				(width 0.1)
				(type default)
			)
			(layer "F.SilkS")
		)
		(fp_line
			(start 0.165608 -2.329434)
			(end 1.307592 -3.424936)
			(stroke
				(width 0.1)
				(type default)
			)
			(layer "F.SilkS")
		)
		(fp_line
			(start 0.165608 -2.329434)
			(end 1.307592 -3.424936)
			(stroke
				(width 0.1)
				(type default)
			)
			(layer "F.SilkS")
		)
		(fp_line
			(start 0.178562 -2.284222)
			(end 1.300988 -3.360674)
			(stroke
				(width 0.1)
				(type default)
			)
			(layer "F.SilkS")
		)
		(fp_line
			(start 0.178562 -2.284222)
			(end 1.300988 -3.360674)
			(stroke
				(width 0.1)
				(type default)
			)
			(layer "F.SilkS")
		)
		(fp_line
			(start 0.191516 -2.238756)
			(end 1.29413 -3.296412)
			(stroke
				(width 0.1)
				(type default)
			)
			(layer "F.SilkS")
		)
		(fp_line
			(start 0.191516 -2.238756)
			(end 1.29413 -3.296412)
			(stroke
				(width 0.1)
				(type default)
			)
			(layer "F.SilkS")
		)
		(fp_line
			(start 0.205994 -2.195068)
			(end 1.287526 -3.232404)
			(stroke
				(width 0.1)
				(type default)
			)
			(layer "F.SilkS")
		)
		(fp_line
			(start 0.205994 -2.195068)
			(end 1.287526 -3.232404)
			(stroke
				(width 0.1)
				(type default)
			)
			(layer "F.SilkS")
		)
		(fp_line
			(start 0.222504 -2.153158)
			(end 1.2827 -3.170174)
			(stroke
				(width 0.1)
				(type default)
			)
			(layer "F.SilkS")
		)
		(fp_line
			(start 0.222504 -2.153158)
			(end 1.2827 -3.170174)
			(stroke
				(width 0.1)
				(type default)
			)
			(layer "F.SilkS")
		)
		(fp_line
			(start 0.239268 -2.111502)
			(end 1.287018 -3.11658)
			(stroke
				(width 0.1)
				(type default)
			)
			(layer "F.SilkS")
		)
		(fp_line
			(start 0.239268 -2.111502)
			(end 1.287018 -3.11658)
			(stroke
				(width 0.1)
				(type default)
			)
			(layer "F.SilkS")
		)
		(fp_line
			(start 0.256032 -2.069846)
			(end 1.291082 -3.062732)
			(stroke
				(width 0.1)
				(type default)
			)
			(layer "F.SilkS")
		)
		(fp_line
			(start 0.256032 -2.069846)
			(end 1.291082 -3.062732)
			(stroke
				(width 0.1)
				(type default)
			)
			(layer "F.SilkS")
		)
		(fp_line
			(start 0.272796 -2.02819)
			(end 1.295146 -3.009138)
			(stroke
				(width 0.1)
				(type default)
			)
			(layer "F.SilkS")
		)
		(fp_line
			(start 0.272796 -2.02819)
			(end 1.295146 -3.009138)
			(stroke
				(width 0.1)
				(type default)
			)
			(layer "F.SilkS")
		)
		(fp_line
			(start 0.289306 -1.986534)
			(end 1.299464 -2.955544)
			(stroke
				(width 0.1)
				(type default)
			)
			(layer "F.SilkS")
		)
		(fp_line
			(start 0.289306 -1.986534)
			(end 1.299464 -2.955544)
			(stroke
				(width 0.1)
				(type default)
			)
			(layer "F.SilkS")
		)
		(fp_line
			(start 0.307086 -1.94564)
			(end 1.303528 -2.901696)
			(stroke
				(width 0.1)
				(type default)
			)
			(layer "F.SilkS")
		)
		(fp_line
			(start 0.307086 -1.94564)
			(end 1.303528 -2.901696)
			(stroke
				(width 0.1)
				(type default)
			)
			(layer "F.SilkS")
		)
		(fp_line
			(start 0.327914 -1.908048)
			(end 1.31318 -2.853182)
			(stroke
				(width 0.1)
				(type default)
			)
			(layer "F.SilkS")
		)
		(fp_line
			(start 0.327914 -1.908048)
			(end 1.31318 -2.853182)
			(stroke
				(width 0.1)
				(type default)
			)
			(layer "F.SilkS")
		)
		(fp_line
			(start 0.348996 -1.870456)
			(end 1.325118 -2.8067)
			(stroke
				(width 0.1)
				(type default)
			)
			(layer "F.SilkS")
		)
		(fp_line
			(start 0.348996 -1.870456)
			(end 1.325118 -2.8067)
			(stroke
				(width 0.1)
				(type default)
			)
			(layer "F.SilkS")
		)
		(fp_line
			(start 0.369824 -1.832864)
			(end 1.336802 -2.760472)
			(stroke
				(width 0.1)
				(type default)
			)
			(layer "F.SilkS")
		)
		(fp_line
			(start 0.369824 -1.832864)
			(end 1.336802 -2.760472)
			(stroke
				(width 0.1)
				(type default)
			)
			(layer "F.SilkS")
		)
		(fp_line
			(start 0.390906 -1.795272)
			(end 1.348486 -2.714244)
			(stroke
				(width 0.1)
				(type default)
			)
			(layer "F.SilkS")
		)
		(fp_line
			(start 0.390906 -1.795272)
			(end 1.348486 -2.714244)
			(stroke
				(width 0.1)
				(type default)
			)
			(layer "F.SilkS")
		)
		(fp_line
			(start 0.411988 -1.75768)
			(end 1.360424 -2.667508)
			(stroke
				(width 0.1)
				(type default)
			)
			(layer "F.SilkS")
		)
		(fp_line
			(start 0.411988 -1.75768)
			(end 1.360424 -2.667508)
			(stroke
				(width 0.1)
				(type default)
			)
			(layer "F.SilkS")
		)
		(fp_line
			(start 0.432816 -1.720088)
			(end 1.372362 -2.62128)
			(stroke
				(width 0.1)
				(type default)
			)
			(layer "F.SilkS")
		)
		(fp_line
			(start 0.432816 -1.720088)
			(end 1.372362 -2.62128)
			(stroke
				(width 0.1)
				(type default)
			)
			(layer "F.SilkS")
		)
		(fp_line
			(start 0.456184 -1.684782)
			(end 1.387856 -2.578608)
			(stroke
				(width 0.1)
				(type default)
			)
			(layer "F.SilkS")
		)
		(fp_line
			(start 0.456184 -1.684782)
			(end 1.387856 -2.578608)
			(stroke
				(width 0.1)
				(type default)
			)
			(layer "F.SilkS")
		)
		(fp_line
			(start 0.481838 -1.651762)
			(end 1.40589 -2.538222)
			(stroke
				(width 0.1)
				(type default)
			)
			(layer "F.SilkS")
		)
		(fp_line
			(start 0.481838 -1.651762)
			(end 1.40589 -2.538222)
			(stroke
				(width 0.1)
				(type default)
			)
			(layer "F.SilkS")
		)
		(fp_line
			(start 0.507746 -1.618742)
			(end 1.423924 -2.497836)
			(stroke
				(width 0.1)
				(type default)
			)
			(layer "F.SilkS")
		)
		(fp_line
			(start 0.507746 -1.618742)
			(end 1.423924 -2.497836)
			(stroke
				(width 0.1)
				(type default)
			)
			(layer "F.SilkS")
		)
		(fp_line
			(start 0.5334 -1.585722)
			(end 1.441958 -2.457196)
			(stroke
				(width 0.1)
				(type default)
			)
			(layer "F.SilkS")
		)
		(fp_line
			(start 0.5334 -1.585722)
			(end 1.441958 -2.457196)
			(stroke
				(width 0.1)
				(type default)
			)
			(layer "F.SilkS")
		)
		(fp_line
			(start 0.559054 -1.552702)
			(end 1.459992 -2.41681)
			(stroke
				(width 0.1)
				(type default)
			)
			(layer "F.SilkS")
		)
		(fp_line
			(start 0.559054 -1.552702)
			(end 1.459992 -2.41681)
			(stroke
				(width 0.1)
				(type default)
			)
			(layer "F.SilkS")
		)
		(fp_line
			(start 0.584962 -1.519682)
			(end 1.477772 -2.376424)
			(stroke
				(width 0.1)
				(type default)
			)
			(layer "F.SilkS")
		)
		(fp_line
			(start 0.584962 -1.519682)
			(end 1.477772 -2.376424)
			(stroke
				(width 0.1)
				(type default)
			)
			(layer "F.SilkS")
		)
		(fp_line
			(start 0.610616 -1.486916)
			(end 1.496568 -2.336546)
			(stroke
				(width 0.1)
				(type default)
			)
			(layer "F.SilkS")
		)
		(fp_line
			(start 0.610616 -1.486916)
			(end 1.496568 -2.336546)
			(stroke
				(width 0.1)
				(type default)
			)
			(layer "F.SilkS")
		)
		(fp_line
			(start 0.637794 -1.455166)
			(end 1.52019 -2.301494)
			(stroke
				(width 0.1)
				(type default)
			)
			(layer "F.SilkS")
		)
		(fp_line
			(start 0.637794 -1.455166)
			(end 1.52019 -2.301494)
			(stroke
				(width 0.1)
				(type default)
			)
			(layer "F.SilkS")
		)
		(fp_line
			(start 0.668274 -1.426464)
			(end 1.543558 -2.266188)
			(stroke
				(width 0.1)
				(type default)
			)
			(layer "F.SilkS")
		)
		(fp_line
			(start 0.668274 -1.426464)
			(end 1.543558 -2.266188)
			(stroke
				(width 0.1)
				(type default)
			)
			(layer "F.SilkS")
		)
		(fp_line
			(start 0.6985 -1.397762)
			(end 1.56718 -2.231136)
			(stroke
				(width 0.1)
				(type default)
			)
			(layer "F.SilkS")
		)
		(fp_line
			(start 0.6985 -1.397762)
			(end 1.56718 -2.231136)
			(stroke
				(width 0.1)
				(type default)
			)
			(layer "F.SilkS")
		)
		(fp_line
			(start 0.728726 -1.36906)
			(end 1.590802 -2.196084)
			(stroke
				(width 0.1)
				(type default)
			)
			(layer "F.SilkS")
		)
		(fp_line
			(start 0.728726 -1.36906)
			(end 1.590802 -2.196084)
			(stroke
				(width 0.1)
				(type default)
			)
			(layer "F.SilkS")
		)
		(fp_line
			(start 0.758952 -1.340358)
			(end 1.61417 -2.160778)
			(stroke
				(width 0.1)
				(type default)
			)
			(layer "F.SilkS")
		)
		(fp_line
			(start 0.758952 -1.340358)
			(end 1.61417 -2.160778)
			(stroke
				(width 0.1)
				(type default)
			)
			(layer "F.SilkS")
		)
		(fp_line
			(start 0.789178 -1.31191)
			(end 1.637792 -2.125726)
			(stroke
				(width 0.1)
				(type default)
			)
			(layer "F.SilkS")
		)
		(fp_line
			(start 0.789178 -1.31191)
			(end 1.637792 -2.125726)
			(stroke
				(width 0.1)
				(type default)
			)
			(layer "F.SilkS")
		)
		(fp_line
			(start 0.819404 -1.282954)
			(end 1.663954 -2.09296)
			(stroke
				(width 0.1)
				(type default)
			)
			(layer "F.SilkS")
		)
		(fp_line
			(start 0.819404 -1.282954)
			(end 1.663954 -2.09296)
			(stroke
				(width 0.1)
				(type default)
			)
			(layer "F.SilkS")
		)
		(fp_line
			(start 0.851408 -1.25603)
			(end 1.69291 -2.063242)
			(stroke
				(width 0.1)
				(type default)
			)
			(layer "F.SilkS")
		)
		(fp_line
			(start 0.851408 -1.25603)
			(end 1.69291 -2.063242)
			(stroke
				(width 0.1)
				(type default)
			)
			(layer "F.SilkS")
		)
		(fp_line
			(start 0.885698 -1.230884)
			(end 1.72212 -2.03327)
			(stroke
				(width 0.1)
				(type default)
			)
			(layer "F.SilkS")
		)
		(fp_line
			(start 0.885698 -1.230884)
			(end 1.72212 -2.03327)
			(stroke
				(width 0.1)
				(type default)
			)
			(layer "F.SilkS")
		)
		(fp_line
			(start 0.919734 -1.206246)
			(end 1.751076 -2.003552)
			(stroke
				(width 0.1)
				(type default)
			)
			(layer "F.SilkS")
		)
		(fp_line
			(start 0.919734 -1.206246)
			(end 1.751076 -2.003552)
			(stroke
				(width 0.1)
				(type default)
			)
			(layer "F.SilkS")
		)
		(fp_line
			(start 0.954024 -1.1811)
			(end 1.780032 -1.973834)
			(stroke
				(width 0.1)
				(type default)
			)
			(layer "F.SilkS")
		)
		(fp_line
			(start 0.954024 -1.1811)
			(end 1.780032 -1.973834)
			(stroke
				(width 0.1)
				(type default)
			)
			(layer "F.SilkS")
		)
		(fp_line
			(start 0.988314 -1.156462)
			(end 1.809242 -1.943862)
			(stroke
				(width 0.1)
				(type default)
			)
			(layer "F.SilkS")
		)
		(fp_line
			(start 0.988314 -1.156462)
			(end 1.809242 -1.943862)
			(stroke
				(width 0.1)
				(type default)
			)
			(layer "F.SilkS")
		)
		(fp_line
			(start 1.02235 -1.13157)
			(end 1.838452 -1.914144)
			(stroke
				(width 0.1)
				(type default)
			)
			(layer "F.SilkS")
		)
		(fp_line
			(start 1.02235 -1.13157)
			(end 1.838452 -1.914144)
			(stroke
				(width 0.1)
				(type default)
			)
			(layer "F.SilkS")
		)
		(fp_line
			(start 1.05664 -1.106678)
			(end 1.872488 -1.889252)
			(stroke
				(width 0.1)
				(type default)
			)
			(layer "F.SilkS")
		)
		(fp_line
			(start 1.05664 -1.106678)
			(end 1.872488 -1.889252)
			(stroke
				(width 0.1)
				(type default)
			)
			(layer "F.SilkS")
		)
		(fp_line
			(start 1.09347 -1.084326)
			(end 1.907794 -1.865376)
			(stroke
				(width 0.1)
				(type default)
			)
			(layer "F.SilkS")
		)
		(fp_line
			(start 1.09347 -1.084326)
			(end 1.907794 -1.865376)
			(stroke
				(width 0.1)
				(type default)
			)
			(layer "F.SilkS")
		)
		(fp_line
			(start 1.131824 -1.063498)
			(end 1.9431 -1.8415)
			(stroke
				(width 0.1)
				(type default)
			)
			(layer "F.SilkS")
		)
		(fp_line
			(start 1.131824 -1.063498)
			(end 1.9431 -1.8415)
			(stroke
				(width 0.1)
				(type default)
			)
			(layer "F.SilkS")
		)
		(fp_line
			(start 1.133856 -5.220462)
			(end 0.47117 -4.5847)
			(stroke
				(width 0.1)
				(type default)
			)
			(layer "F.SilkS")
		)
		(fp_line
			(start 1.133856 -5.220462)
			(end 0.47117 -4.5847)
			(stroke
				(width 0.1)
				(type default)
			)
			(layer "F.SilkS")
		)
		(fp_line
			(start 1.170178 -1.042416)
			(end 1.978406 -1.817624)
			(stroke
				(width 0.1)
				(type default)
			)
			(layer "F.SilkS")
		)
		(fp_line
			(start 1.170178 -1.042416)
			(end 1.978406 -1.817624)
			(stroke
				(width 0.1)
				(type default)
			)
			(layer "F.SilkS")
		)
		(fp_line
			(start 1.208532 -1.021334)
			(end 2.013458 -1.793748)
			(stroke
				(width 0.1)
				(type default)
			)
			(layer "F.SilkS")
		)
		(fp_line
			(start 1.208532 -1.021334)
			(end 2.013458 -1.793748)
			(stroke
				(width 0.1)
				(type default)
			)
			(layer "F.SilkS")
		)
		(fp_line
			(start 1.246886 -1.000506)
			(end 2.048764 -1.769872)
			(stroke
				(width 0.1)
				(type default)
			)
			(layer "F.SilkS")
		)
		(fp_line
			(start 1.246886 -1.000506)
			(end 2.048764 -1.769872)
			(stroke
				(width 0.1)
				(type default)
			)
			(layer "F.SilkS")
		)
		(fp_line
			(start 1.28524 -0.979424)
			(end 2.087626 -1.749298)
			(stroke
				(width 0.1)
				(type default)
			)
			(layer "F.SilkS")
		)
		(fp_line
			(start 1.28524 -0.979424)
			(end 2.087626 -1.749298)
			(stroke
				(width 0.1)
				(type default)
			)
			(layer "F.SilkS")
		)
		(fp_line
			(start 1.293368 -5.315966)
			(end 0.37465 -4.434332)
			(stroke
				(width 0.1)
				(type default)
			)
			(layer "F.SilkS")
		)
		(fp_line
			(start 1.293368 -5.315966)
			(end 0.37465 -4.434332)
			(stroke
				(width 0.1)
				(type default)
			)
			(layer "F.SilkS")
		)
		(fp_line
			(start 1.323594 -0.958596)
			(end 2.130552 -1.732788)
			(stroke
				(width 0.1)
				(type default)
			)
			(layer "F.SilkS")
		)
		(fp_line
			(start 1.323594 -0.958596)
			(end 2.130552 -1.732788)
			(stroke
				(width 0.1)
				(type default)
			)
			(layer "F.SilkS")
		)
		(fp_line
			(start 1.366266 -0.941832)
			(end 2.173478 -1.716024)
			(stroke
				(width 0.1)
				(type default)
			)
			(layer "F.SilkS")
		)
		(fp_line
			(start 1.366266 -0.941832)
			(end 2.173478 -1.716024)
			(stroke
				(width 0.1)
				(type default)
			)
			(layer "F.SilkS")
		)
		(fp_line
			(start 1.408684 -0.924814)
			(end 2.21615 -1.699514)
			(stroke
				(width 0.1)
				(type default)
			)
			(layer "F.SilkS")
		)
		(fp_line
			(start 1.408684 -0.924814)
			(end 2.21615 -1.699514)
			(stroke
				(width 0.1)
				(type default)
			)
			(layer "F.SilkS")
		)
		(fp_line
			(start 1.41224 -5.3721)
			(end 0.302768 -4.307586)
			(stroke
				(width 0.1)
				(type default)
			)
			(layer "F.SilkS")
		)
		(fp_line
			(start 1.41224 -5.3721)
			(end 0.302768 -4.307586)
			(stroke
				(width 0.1)
				(type default)
			)
			(layer "F.SilkS")
		)
		(fp_line
			(start 1.451356 -0.90805)
			(end 2.259076 -1.68275)
			(stroke
				(width 0.1)
				(type default)
			)
			(layer "F.SilkS")
		)
		(fp_line
			(start 1.451356 -0.90805)
			(end 2.259076 -1.68275)
			(stroke
				(width 0.1)
				(type default)
			)
			(layer "F.SilkS")
		)
		(fp_line
			(start 1.493774 -0.891032)
			(end 2.301748 -1.66624)
			(stroke
				(width 0.1)
				(type default)
			)
			(layer "F.SilkS")
		)
		(fp_line
			(start 1.493774 -0.891032)
			(end 2.301748 -1.66624)
			(stroke
				(width 0.1)
				(type default)
			)
			(layer "F.SilkS")
		)
		(fp_line
			(start 1.52781 -5.425186)
			(end 0.256794 -4.205732)
			(stroke
				(width 0.1)
				(type default)
			)
			(layer "F.SilkS")
		)
		(fp_line
			(start 1.52781 -5.425186)
			(end 0.256794 -4.205732)
			(stroke
				(width 0.1)
				(type default)
			)
			(layer "F.SilkS")
		)
		(fp_line
			(start 1.536446 -0.874268)
			(end 2.351024 -1.655826)
			(stroke
				(width 0.1)
				(type default)
			)
			(layer "F.SilkS")
		)
		(fp_line
			(start 1.536446 -0.874268)
			(end 2.351024 -1.655826)
			(stroke
				(width 0.1)
				(type default)
			)
			(layer "F.SilkS")
		)
		(fp_line
			(start 1.578864 -0.857504)
			(end 2.404364 -1.649222)
			(stroke
				(width 0.1)
				(type default)
			)
			(layer "F.SilkS")
		)
		(fp_line
			(start 1.578864 -0.857504)
			(end 2.404364 -1.649222)
			(stroke
				(width 0.1)
				(type default)
			)
			(layer "F.SilkS")
		)
		(fp_line
			(start 1.62306 -5.458714)
			(end 0.211328 -4.10464)
			(stroke
				(width 0.1)
				(type default)
			)
			(layer "F.SilkS")
		)
		(fp_line
			(start 1.62306 -5.458714)
			(end 0.211328 -4.10464)
			(stroke
				(width 0.1)
				(type default)
			)
			(layer "F.SilkS")
		)
		(fp_line
			(start 1.623314 -0.842264)
			(end 2.457704 -1.642618)
			(stroke
				(width 0.1)
				(type default)
			)
			(layer "F.SilkS")
		)
		(fp_line
			(start 1.623314 -0.842264)
			(end 2.457704 -1.642618)
			(stroke
				(width 0.1)
				(type default)
			)
			(layer "F.SilkS")
		)
		(fp_line
			(start 1.67005 -0.829564)
			(end 2.511044 -1.636014)
			(stroke
				(width 0.1)
				(type default)
			)
			(layer "F.SilkS")
		)
		(fp_line
			(start 1.67005 -0.829564)
			(end 2.511044 -1.636014)
			(stroke
				(width 0.1)
				(type default)
			)
			(layer "F.SilkS")
		)
		(fp_line
			(start 1.716786 -0.816356)
			(end 2.56413 -1.62941)
			(stroke
				(width 0.1)
				(type default)
			)
			(layer "F.SilkS")
		)
		(fp_line
			(start 1.716786 -0.816356)
			(end 2.56413 -1.62941)
			(stroke
				(width 0.1)
				(type default)
			)
			(layer "F.SilkS")
		)
		(fp_line
			(start 1.717802 -5.492242)
			(end 0.181356 -4.018026)
			(stroke
				(width 0.1)
				(type default)
			)
			(layer "F.SilkS")
		)
		(fp_line
			(start 1.717802 -5.492242)
			(end 0.181356 -4.018026)
			(stroke
				(width 0.1)
				(type default)
			)
			(layer "F.SilkS")
		)
		(fp_line
			(start 1.763522 -0.803656)
			(end 2.624582 -1.629664)
			(stroke
				(width 0.1)
				(type default)
			)
			(layer "F.SilkS")
		)
		(fp_line
			(start 1.763522 -0.803656)
			(end 2.624582 -1.629664)
			(stroke
				(width 0.1)
				(type default)
			)
			(layer "F.SilkS")
		)
		(fp_line
			(start 1.805686 -5.518658)
			(end 0.1524 -3.932682)
			(stroke
				(width 0.1)
				(type default)
			)
			(layer "F.SilkS")
		)
		(fp_line
			(start 1.805686 -5.518658)
			(end 0.1524 -3.932682)
			(stroke
				(width 0.1)
				(type default)
			)
			(layer "F.SilkS")
		)
		(fp_line
			(start 1.810512 -0.790956)
			(end 2.692654 -1.637284)
			(stroke
				(width 0.1)
				(type default)
			)
			(layer "F.SilkS")
		)
		(fp_line
			(start 1.810512 -0.790956)
			(end 2.692654 -1.637284)
			(stroke
				(width 0.1)
				(type default)
			)
			(layer "F.SilkS")
		)
		(fp_line
			(start 1.856994 -0.777748)
			(end 2.760726 -1.64465)
			(stroke
				(width 0.1)
				(type default)
			)
			(layer "F.SilkS")
		)
		(fp_line
			(start 1.856994 -0.777748)
			(end 2.760726 -1.64465)
			(stroke
				(width 0.1)
				(type default)
			)
			(layer "F.SilkS")
		)
		(fp_line
			(start 1.886458 -5.538216)
			(end 0.128016 -3.851402)
			(stroke
				(width 0.1)
				(type default)
			)
			(layer "F.SilkS")
		)
		(fp_line
			(start 1.886458 -5.538216)
			(end 0.128016 -3.851402)
			(stroke
				(width 0.1)
				(type default)
			)
			(layer "F.SilkS")
		)
		(fp_line
			(start 1.90373 -0.765048)
			(end 2.828544 -1.65227)
			(stroke
				(width 0.1)
				(type default)
			)
			(layer "F.SilkS")
		)
		(fp_line
			(start 1.90373 -0.765048)
			(end 2.828544 -1.65227)
			(stroke
				(width 0.1)
				(type default)
			)
			(layer "F.SilkS")
		)
		(fp_line
			(start 1.954276 -0.75565)
			(end 2.906014 -1.66878)
			(stroke
				(width 0.1)
				(type default)
			)
			(layer "F.SilkS")
		)
		(fp_line
			(start 1.954276 -0.75565)
			(end 2.906014 -1.66878)
			(stroke
				(width 0.1)
				(type default)
			)
			(layer "F.SilkS")
		)
		(fp_line
			(start 1.966722 -5.557774)
			(end 0.110236 -3.776726)
			(stroke
				(width 0.1)
				(type default)
			)
			(layer "F.SilkS")
		)
		(fp_line
			(start 1.966722 -5.557774)
			(end 0.110236 -3.776726)
			(stroke
				(width 0.1)
				(type default)
			)
			(layer "F.SilkS")
		)
		(fp_line
			(start 2.00533 -0.74676)
			(end 3.000248 -1.701546)
			(stroke
				(width 0.1)
				(type default)
			)
			(layer "F.SilkS")
		)
		(fp_line
			(start 2.00533 -0.74676)
			(end 3.000248 -1.701546)
			(stroke
				(width 0.1)
				(type default)
			)
			(layer "F.SilkS")
		)
		(fp_line
			(start 2.04597 -5.576062)
			(end 0.092456 -3.70205)
			(stroke
				(width 0.1)
				(type default)
			)
			(layer "F.SilkS")
		)
		(fp_line
			(start 2.04597 -5.576062)
			(end 0.092456 -3.70205)
			(stroke
				(width 0.1)
				(type default)
			)
			(layer "F.SilkS")
		)
		(fp_line
			(start 2.05613 -0.73787)
			(end 3.094228 -1.733804)
			(stroke
				(width 0.1)
				(type default)
			)
			(layer "F.SilkS")
		)
		(fp_line
			(start 2.05613 -0.73787)
			(end 3.094228 -1.733804)
			(stroke
				(width 0.1)
				(type default)
			)
			(layer "F.SilkS")
		)
		(fp_line
			(start 2.10693 -0.72898)
			(end 3.238246 -1.814322)
			(stroke
				(width 0.1)
				(type default)
			)
			(layer "F.SilkS")
		)
		(fp_line
			(start 2.10693 -0.72898)
			(end 3.238246 -1.814322)
			(stroke
				(width 0.1)
				(type default)
			)
			(layer "F.SilkS")
		)
		(fp_line
			(start 2.116328 -5.585968)
			(end 0.07874 -3.631184)
			(stroke
				(width 0.1)
				(type default)
			)
			(layer "F.SilkS")
		)
		(fp_line
			(start 2.116328 -5.585968)
			(end 0.07874 -3.631184)
			(stroke
				(width 0.1)
				(type default)
			)
			(layer "F.SilkS")
		)
		(fp_line
			(start 2.18694 -5.595874)
			(end 0.069342 -3.564382)
			(stroke
				(width 0.1)
				(type default)
			)
			(layer "F.SilkS")
		)
		(fp_line
			(start 2.18694 -5.595874)
			(end 0.069342 -3.564382)
			(stroke
				(width 0.1)
				(type default)
			)
			(layer "F.SilkS")
		)
		(fp_line
			(start 2.208784 -0.710946)
			(end 5.142484 -3.52552)
			(stroke
				(width 0.1)
				(type default)
			)
			(layer "F.SilkS")
		)
		(fp_line
			(start 2.208784 -0.710946)
			(end 5.142484 -3.52552)
			(stroke
				(width 0.1)
				(type default)
			)
			(layer "F.SilkS")
		)
		(fp_line
			(start 2.257552 -5.60578)
			(end 0.059944 -3.49758)
			(stroke
				(width 0.1)
				(type default)
			)
			(layer "F.SilkS")
		)
		(fp_line
			(start 2.257552 -5.60578)
			(end 0.059944 -3.49758)
			(stroke
				(width 0.1)
				(type default)
			)
			(layer "F.SilkS")
		)
		(fp_line
			(start 2.2606 -0.703326)
			(end 5.147564 -3.472942)
			(stroke
				(width 0.1)
				(type default)
			)
			(layer "F.SilkS")
		)
		(fp_line
			(start 2.2606 -0.703326)
			(end 5.147564 -3.472942)
			(stroke
				(width 0.1)
				(type default)
			)
			(layer "F.SilkS")
		)
		(fp_line
			(start 2.315464 -0.698246)
			(end 5.152898 -3.42011)
			(stroke
				(width 0.1)
				(type default)
			)
			(layer "F.SilkS")
		)
		(fp_line
			(start 2.315464 -0.698246)
			(end 5.152898 -3.42011)
			(stroke
				(width 0.1)
				(type default)
			)
			(layer "F.SilkS")
		)
		(fp_line
			(start 2.32791 -5.615686)
			(end 0.051308 -3.431794)
			(stroke
				(width 0.1)
				(type default)
			)
			(layer "F.SilkS")
		)
		(fp_line
			(start 2.32791 -5.615686)
			(end 0.051308 -3.431794)
			(stroke
				(width 0.1)
				(type default)
			)
			(layer "F.SilkS")
		)
		(fp_line
			(start 2.370328 -0.693166)
			(end 5.156708 -3.366262)
			(stroke
				(width 0.1)
				(type default)
			)
			(layer "F.SilkS")
		)
		(fp_line
			(start 2.370328 -0.693166)
			(end 5.156708 -3.366262)
			(stroke
				(width 0.1)
				(type default)
			)
			(layer "F.SilkS")
		)
		(fp_line
			(start 2.390902 -5.61848)
			(end 0.048514 -3.371342)
			(stroke
				(width 0.1)
				(type default)
			)
			(layer "F.SilkS")
		)
		(fp_line
			(start 2.390902 -5.61848)
			(end 0.048514 -3.371342)
			(stroke
				(width 0.1)
				(type default)
			)
			(layer "F.SilkS")
		)
		(fp_line
			(start 2.424938 -0.687832)
			(end 5.158994 -3.310382)
			(stroke
				(width 0.1)
				(type default)
			)
			(layer "F.SilkS")
		)
		(fp_line
			(start 2.424938 -0.687832)
			(end 5.158994 -3.310382)
			(stroke
				(width 0.1)
				(type default)
			)
			(layer "F.SilkS")
		)
		(fp_line
			(start 2.454148 -5.621274)
			(end 0.04572 -3.31089)
			(stroke
				(width 0.1)
				(type default)
			)
			(layer "F.SilkS")
		)
		(fp_line
			(start 2.454148 -5.621274)
			(end 0.04572 -3.31089)
			(stroke
				(width 0.1)
				(type default)
			)
			(layer "F.SilkS")
		)
		(fp_line
			(start 2.479802 -0.682752)
			(end 5.16001 -3.25374)
			(stroke
				(width 0.1)
				(type default)
			)
			(layer "F.SilkS")
		)
		(fp_line
			(start 2.479802 -0.682752)
			(end 5.16001 -3.25374)
			(stroke
				(width 0.1)
				(type default)
			)
			(layer "F.SilkS")
		)
		(fp_line
			(start 2.517394 -5.624322)
			(end 0.042926 -3.250438)
			(stroke
				(width 0.1)
				(type default)
			)
			(layer "F.SilkS")
		)
		(fp_line
			(start 2.517394 -5.624322)
			(end 0.042926 -3.250438)
			(stroke
				(width 0.1)
				(type default)
			)
			(layer "F.SilkS")
		)
		(fp_line
			(start 2.534666 -0.677672)
			(end 5.15747 -3.193796)
			(stroke
				(width 0.1)
				(type default)
			)
			(layer "F.SilkS")
		)
		(fp_line
			(start 2.534666 -0.677672)
			(end 5.15747 -3.193796)
			(stroke
				(width 0.1)
				(type default)
			)
			(layer "F.SilkS")
		)
		(fp_line
			(start 2.580386 -5.626862)
			(end 0.041656 -3.19151)
			(stroke
				(width 0.1)
				(type default)
			)
			(layer "F.SilkS")
		)
		(fp_line
			(start 2.580386 -5.626862)
			(end 0.041656 -3.19151)
			(stroke
				(width 0.1)
				(type default)
			)
			(layer "F.SilkS")
		)
		(fp_line
			(start 2.589276 -0.672338)
			(end 5.15493 -3.133598)
			(stroke
				(width 0.1)
				(type default)
			)
			(layer "F.SilkS")
		)
		(fp_line
			(start 2.589276 -0.672338)
			(end 5.15493 -3.133598)
			(stroke
				(width 0.1)
				(type default)
			)
			(layer "F.SilkS")
		)
		(fp_line
			(start 2.64287 -5.629148)
			(end 0.042672 -3.135122)
			(stroke
				(width 0.1)
				(type default)
			)
			(layer "F.SilkS")
		)
		(fp_line
			(start 2.64287 -5.629148)
			(end 0.042672 -3.135122)
			(stroke
				(width 0.1)
				(type default)
			)
			(layer "F.SilkS")
		)
		(fp_line
			(start 2.646426 -0.669544)
			(end 5.15239 -3.073146)
			(stroke
				(width 0.1)
				(type default)
			)
			(layer "F.SilkS")
		)
		(fp_line
			(start 2.646426 -0.669544)
			(end 5.15239 -3.073146)
			(stroke
				(width 0.1)
				(type default)
			)
			(layer "F.SilkS")
		)
		(fp_line
			(start 2.700528 -5.626862)
			(end 0.04445 -3.078734)
			(stroke
				(width 0.1)
				(type default)
			)
			(layer "F.SilkS")
		)
		(fp_line
			(start 2.700528 -5.626862)
			(end 0.04445 -3.078734)
			(stroke
				(width 0.1)
				(type default)
			)
			(layer "F.SilkS")
		)
		(fp_line
			(start 2.704846 -0.66802)
			(end 5.14985 -3.013202)
			(stroke
				(width 0.1)
				(type default)
			)
			(layer "F.SilkS")
		)
		(fp_line
			(start 2.704846 -0.66802)
			(end 5.14985 -3.013202)
			(stroke
				(width 0.1)
				(type default)
			)
			(layer "F.SilkS")
		)
		(fp_line
			(start 2.75844 -5.62483)
			(end 0.048006 -3.024632)
			(stroke
				(width 0.1)
				(type default)
			)
			(layer "F.SilkS")
		)
		(fp_line
			(start 2.75844 -5.62483)
			(end 0.048006 -3.024632)
			(stroke
				(width 0.1)
				(type default)
			)
			(layer "F.SilkS")
		)
		(fp_line
			(start 2.76352 -0.666242)
			(end 5.14731 -2.953258)
			(stroke
				(width 0.1)
				(type default)
			)
			(layer "F.SilkS")
		)
		(fp_line
			(start 2.76352 -0.666242)
			(end 5.14731 -2.953258)
			(stroke
				(width 0.1)
				(type default)
			)
			(layer "F.SilkS")
		)
		(fp_line
			(start 2.816098 -5.622544)
			(end 0.051562 -2.970276)
			(stroke
				(width 0.1)
				(type default)
			)
			(layer "F.SilkS")
		)
		(fp_line
			(start 2.816098 -5.622544)
			(end 0.051562 -2.970276)
			(stroke
				(width 0.1)
				(type default)
			)
			(layer "F.SilkS")
		)
		(fp_line
			(start 2.82194 -0.664718)
			(end 5.145024 -2.89306)
			(stroke
				(width 0.1)
				(type default)
			)
			(layer "F.SilkS")
		)
		(fp_line
			(start 2.82194 -0.664718)
			(end 5.145024 -2.89306)
			(stroke
				(width 0.1)
				(type default)
			)
			(layer "F.SilkS")
		)
		(fp_line
			(start 2.87401 -5.620258)
			(end 0.054864 -2.91592)
			(stroke
				(width 0.1)
				(type default)
			)
			(layer "F.SilkS")
		)
		(fp_line
			(start 2.87401 -5.620258)
			(end 0.054864 -2.91592)
			(stroke
				(width 0.1)
				(type default)
			)
			(layer "F.SilkS")
		)
		(fp_line
			(start 2.88036 -0.662686)
			(end 5.13588 -2.826512)
			(stroke
				(width 0.1)
				(type default)
			)
			(layer "F.SilkS")
		)
		(fp_line
			(start 2.88036 -0.662686)
			(end 5.13588 -2.826512)
			(stroke
				(width 0.1)
				(type default)
			)
			(layer "F.SilkS")
		)
		(fp_line
			(start 2.92989 -5.616194)
			(end 0.061468 -2.864358)
			(stroke
				(width 0.1)
				(type default)
			)
			(layer "F.SilkS")
		)
		(fp_line
			(start 2.92989 -5.616194)
			(end 0.061468 -2.864358)
			(stroke
				(width 0.1)
				(type default)
			)
			(layer "F.SilkS")
		)
		(fp_line
			(start 2.93878 -0.661416)
			(end 5.126736 -2.760218)
			(stroke
				(width 0.1)
				(type default)
			)
			(layer "F.SilkS")
		)
		(fp_line
			(start 2.93878 -0.661416)
			(end 5.126736 -2.760218)
			(stroke
				(width 0.1)
				(type default)
			)
			(layer "F.SilkS")
		)
		(fp_line
			(start 2.98323 -5.609336)
			(end 0.067818 -2.812542)
			(stroke
				(width 0.1)
				(type default)
			)
			(layer "F.SilkS")
		)
		(fp_line
			(start 2.98323 -5.609336)
			(end 0.067818 -2.812542)
			(stroke
				(width 0.1)
				(type default)
			)
			(layer "F.SilkS")
		)
		(fp_line
			(start 2.9972 -0.659638)
			(end 5.117592 -2.69367)
			(stroke
				(width 0.1)
				(type default)
			)
			(layer "F.SilkS")
		)
		(fp_line
			(start 2.9972 -0.659638)
			(end 5.117592 -2.69367)
			(stroke
				(width 0.1)
				(type default)
			)
			(layer "F.SilkS")
		)
		(fp_line
			(start 3.03657 -5.602732)
			(end 0.073914 -2.76098)
			(stroke
				(width 0.1)
				(type default)
			)
			(layer "F.SilkS")
		)
		(fp_line
			(start 3.03657 -5.602732)
			(end 0.073914 -2.76098)
			(stroke
				(width 0.1)
				(type default)
			)
			(layer "F.SilkS")
		)
		(fp_line
			(start 3.048 -0.651002)
			(end 5.108194 -2.627122)
			(stroke
				(width 0.1)
				(type default)
			)
			(layer "F.SilkS")
		)
		(fp_line
			(start 3.048 -0.651002)
			(end 5.108194 -2.627122)
			(stroke
				(width 0.1)
				(type default)
			)
			(layer "F.SilkS")
		)
		(fp_line
			(start 3.089656 -5.596382)
			(end 0.080264 -2.709418)
			(stroke
				(width 0.1)
				(type default)
			)
			(layer "F.SilkS")
		)
		(fp_line
			(start 3.089656 -5.596382)
			(end 0.080264 -2.709418)
			(stroke
				(width 0.1)
				(type default)
			)
			(layer "F.SilkS")
		)
		(fp_line
			(start 3.094482 -0.637286)
			(end 5.09905 -2.560574)
			(stroke
				(width 0.1)
				(type default)
			)
			(layer "F.SilkS")
		)
		(fp_line
			(start 3.094482 -0.637286)
			(end 5.09905 -2.560574)
			(stroke
				(width 0.1)
				(type default)
			)
			(layer "F.SilkS")
		)
		(fp_line
			(start 3.13944 -0.622808)
			(end 5.081524 -2.485898)
			(stroke
				(width 0.1)
				(type default)
			)
			(layer "F.SilkS")
		)
		(fp_line
			(start 3.13944 -0.622808)
			(end 5.081524 -2.485898)
			(stroke
				(width 0.1)
				(type default)
			)
			(layer "F.SilkS")
		)
		(fp_line
			(start 3.14325 -5.589778)
			(end 1.972818 -4.467098)
			(stroke
				(width 0.1)
				(type default)
			)
			(layer "F.SilkS")
		)
		(fp_line
			(start 3.14325 -5.589778)
			(end 1.972818 -4.467098)
			(stroke
				(width 0.1)
				(type default)
			)
			(layer "F.SilkS")
		)
		(fp_line
			(start 3.184144 -0.60833)
			(end 5.061966 -2.409698)
			(stroke
				(width 0.1)
				(type default)
			)
			(layer "F.SilkS")
		)
		(fp_line
			(start 3.184144 -0.60833)
			(end 5.061966 -2.409698)
			(stroke
				(width 0.1)
				(type default)
			)
			(layer "F.SilkS")
		)
		(fp_line
			(start 3.19405 -5.580888)
			(end 2.123694 -4.553966)
			(stroke
				(width 0.1)
				(type default)
			)
			(layer "F.SilkS")
		)
		(fp_line
			(start 3.19405 -5.580888)
			(end 2.123694 -4.553966)
			(stroke
				(width 0.1)
				(type default)
			)
			(layer "F.SilkS")
		)
		(fp_line
			(start 3.22834 -0.592836)
			(end 5.042408 -2.33299)
			(stroke
				(width 0.1)
				(type default)
			)
			(layer "F.SilkS")
		)
		(fp_line
			(start 3.22834 -0.592836)
			(end 5.042408 -2.33299)
			(stroke
				(width 0.1)
				(type default)
			)
			(layer "F.SilkS")
		)
		(fp_line
			(start 3.243072 -5.57022)
			(end 2.217166 -4.586224)
			(stroke
				(width 0.1)
				(type default)
			)
			(layer "F.SilkS")
		)
		(fp_line
			(start 3.243072 -5.57022)
			(end 2.217166 -4.586224)
			(stroke
				(width 0.1)
				(type default)
			)
			(layer "F.SilkS")
		)
		(fp_line
			(start 3.272536 -0.577342)
			(end 5.02285 -2.256536)
			(stroke
				(width 0.1)
				(type default)
			)
			(layer "F.SilkS")
		)
		(fp_line
			(start 3.272536 -0.577342)
			(end 5.02285 -2.256536)
			(stroke
				(width 0.1)
				(type default)
			)
			(layer "F.SilkS")
		)
		(fp_line
			(start 3.292094 -5.559552)
			(end 2.310892 -4.618228)
			(stroke
				(width 0.1)
				(type default)
			)
			(layer "F.SilkS")
		)
		(fp_line
			(start 3.292094 -5.559552)
			(end 2.310892 -4.618228)
			(stroke
				(width 0.1)
				(type default)
			)
			(layer "F.SilkS")
		)
		(fp_line
			(start 3.316224 -0.561848)
			(end 4.990338 -2.167636)
			(stroke
				(width 0.1)
				(type default)
			)
			(layer "F.SilkS")
		)
		(fp_line
			(start 3.316224 -0.561848)
			(end 4.990338 -2.167636)
			(stroke
				(width 0.1)
				(type default)
			)
			(layer "F.SilkS")
		)
		(fp_line
			(start 3.34137 -5.549138)
			(end 2.389632 -4.636262)
			(stroke
				(width 0.1)
				(type default)
			)
			(layer "F.SilkS")
		)
		(fp_line
			(start 3.34137 -5.549138)
			(end 2.389632 -4.636262)
			(stroke
				(width 0.1)
				(type default)
			)
			(layer "F.SilkS")
		)
		(fp_line
			(start 3.359912 -0.545846)
			(end 4.953254 -2.074418)
			(stroke
				(width 0.1)
				(type default)
			)
			(layer "F.SilkS")
		)
		(fp_line
			(start 3.359912 -0.545846)
			(end 4.953254 -2.074418)
			(stroke
				(width 0.1)
				(type default)
			)
			(layer "F.SilkS")
		)
		(fp_line
			(start 3.390392 -5.53847)
			(end 2.458212 -4.644136)
			(stroke
				(width 0.1)
				(type default)
			)
			(layer "F.SilkS")
		)
		(fp_line
			(start 3.390392 -5.53847)
			(end 2.458212 -4.644136)
			(stroke
				(width 0.1)
				(type default)
			)
			(layer "F.SilkS")
		)
		(fp_line
			(start 3.4036 -0.530098)
			(end 4.915916 -1.980946)
			(stroke
				(width 0.1)
				(type default)
			)
			(layer "F.SilkS")
		)
		(fp_line
			(start 3.4036 -0.530098)
			(end 4.915916 -1.980946)
			(stroke
				(width 0.1)
				(type default)
			)
			(layer "F.SilkS")
		)
		(fp_line
			(start 3.437382 -5.52577)
			(end 2.526538 -4.65201)
			(stroke
				(width 0.1)
				(type default)
			)
			(layer "F.SilkS")
		)
		(fp_line
			(start 3.437382 -5.52577)
			(end 2.526538 -4.65201)
			(stroke
				(width 0.1)
				(type default)
			)
			(layer "F.SilkS")
		)
		(fp_line
			(start 3.447034 -0.513842)
			(end 4.85267 -1.862582)
			(stroke
				(width 0.1)
				(type default)
			)
			(layer "F.SilkS")
		)
		(fp_line
			(start 3.447034 -0.513842)
			(end 4.85267 -1.862582)
			(stroke
				(width 0.1)
				(type default)
			)
			(layer "F.SilkS")
		)
		(fp_line
			(start 3.482594 -5.511292)
			(end 2.593086 -4.658106)
			(stroke
				(width 0.1)
				(type default)
			)
			(layer "F.SilkS")
		)
		(fp_line
			(start 3.482594 -5.511292)
			(end 2.593086 -4.658106)
			(stroke
				(width 0.1)
				(type default)
			)
			(layer "F.SilkS")
		)
		(fp_line
			(start 3.490468 -0.498094)
			(end 4.77901 -1.734058)
			(stroke
				(width 0.1)
				(type default)
			)
			(layer "F.SilkS")
		)
		(fp_line
			(start 3.490468 -0.498094)
			(end 4.77901 -1.734058)
			(stroke
				(width 0.1)
				(type default)
			)
			(layer "F.SilkS")
		)
		(fp_line
			(start 3.527806 -5.497068)
			(end 2.647188 -4.652264)
			(stroke
				(width 0.1)
				(type default)
			)
			(layer "F.SilkS")
		)
		(fp_line
			(start 3.527806 -5.497068)
			(end 2.647188 -4.652264)
			(stroke
				(width 0.1)
				(type default)
			)
			(layer "F.SilkS")
		)
		(fp_line
			(start 3.533648 -0.481838)
			(end 4.147312 -1.070356)
			(stroke
				(width 0.1)
				(type default)
			)
			(layer "F.SilkS")
		)
		(fp_line
			(start 3.533648 -0.481838)
			(end 4.147312 -1.070356)
			(stroke
				(width 0.1)
				(type default)
			)
			(layer "F.SilkS")
		)
		(fp_line
			(start 3.573018 -5.482844)
			(end 2.700782 -4.645914)
			(stroke
				(width 0.1)
				(type default)
			)
			(layer "F.SilkS")
		)
		(fp_line
			(start 3.573018 -5.482844)
			(end 2.700782 -4.645914)
			(stroke
				(width 0.1)
				(type default)
			)
			(layer "F.SilkS")
		)
		(fp_line
			(start 3.61823 -5.468366)
			(end 2.75463 -4.639818)
			(stroke
				(width 0.1)
				(type default)
			)
			(layer "F.SilkS")
		)
		(fp_line
			(start 3.61823 -5.468366)
			(end 2.75463 -4.639818)
			(stroke
				(width 0.1)
				(type default)
			)
			(layer "F.SilkS")
		)
		(fp_line
			(start 3.620008 -0.449072)
			(end 4.2164 -1.02108)
			(stroke
				(width 0.1)
				(type default)
			)
			(layer "F.SilkS")
		)
		(fp_line
			(start 3.620008 -0.449072)
			(end 4.2164 -1.02108)
			(stroke
				(width 0.1)
				(type default)
			)
			(layer "F.SilkS")
		)
		(fp_line
			(start 3.662426 -5.452872)
			(end 2.808478 -4.633976)
			(stroke
				(width 0.1)
				(type default)
			)
			(layer "F.SilkS")
		)
		(fp_line
			(start 3.662426 -5.452872)
			(end 2.808478 -4.633976)
			(stroke
				(width 0.1)
				(type default)
			)
			(layer "F.SilkS")
		)
		(fp_line
			(start 3.663442 -0.43307)
			(end 4.250944 -0.996696)
			(stroke
				(width 0.1)
				(type default)
			)
			(layer "F.SilkS")
		)
		(fp_line
			(start 3.663442 -0.43307)
			(end 4.250944 -0.996696)
			(stroke
				(width 0.1)
				(type default)
			)
			(layer "F.SilkS")
		)
		(fp_line
			(start 3.703828 -5.435092)
			(end 2.860548 -4.626102)
			(stroke
				(width 0.1)
				(type default)
			)
			(layer "F.SilkS")
		)
		(fp_line
			(start 3.703828 -5.435092)
			(end 2.860548 -4.626102)
			(stroke
				(width 0.1)
				(type default)
			)
			(layer "F.SilkS")
		)
		(fp_line
			(start 3.706368 -0.416814)
			(end 4.285488 -0.972058)
			(stroke
				(width 0.1)
				(type default)
			)
			(layer "F.SilkS")
		)
		(fp_line
			(start 3.706368 -0.416814)
			(end 4.285488 -0.972058)
			(stroke
				(width 0.1)
				(type default)
			)
			(layer "F.SilkS")
		)
		(fp_line
			(start 3.745484 -5.417058)
			(end 2.90449 -4.610354)
			(stroke
				(width 0.1)
				(type default)
			)
			(layer "F.SilkS")
		)
		(fp_line
			(start 3.745484 -5.417058)
			(end 2.90449 -4.610354)
			(stroke
				(width 0.1)
				(type default)
			)
			(layer "F.SilkS")
		)
		(fp_line
			(start 3.749548 -0.400304)
			(end 4.320286 -0.947674)
			(stroke
				(width 0.1)
				(type default)
			)
			(layer "F.SilkS")
		)
		(fp_line
			(start 3.749548 -0.400304)
			(end 4.320286 -0.947674)
			(stroke
				(width 0.1)
				(type default)
			)
			(layer "F.SilkS")
		)
		(fp_line
			(start 3.786886 -5.399278)
			(end 2.948432 -4.595114)
			(stroke
				(width 0.1)
				(type default)
			)
			(layer "F.SilkS")
		)
		(fp_line
			(start 3.786886 -5.399278)
			(end 2.948432 -4.595114)
			(stroke
				(width 0.1)
				(type default)
			)
			(layer "F.SilkS")
		)
		(fp_line
			(start 3.792474 -0.383794)
			(end 4.35483 -0.923036)
			(stroke
				(width 0.1)
				(type default)
			)
			(layer "F.SilkS")
		)
		(fp_line
			(start 3.792474 -0.383794)
			(end 4.35483 -0.923036)
			(stroke
				(width 0.1)
				(type default)
			)
			(layer "F.SilkS")
		)
		(fp_line
			(start 3.828288 -5.381498)
			(end 2.992628 -4.57962)
			(stroke
				(width 0.1)
				(type default)
			)
			(layer "F.SilkS")
		)
		(fp_line
			(start 3.828288 -5.381498)
			(end 2.992628 -4.57962)
			(stroke
				(width 0.1)
				(type default)
			)
			(layer "F.SilkS")
		)
		(fp_line
			(start 3.8354 -0.36703)
			(end 4.389374 -0.898398)
			(stroke
				(width 0.1)
				(type default)
			)
			(layer "F.SilkS")
		)
		(fp_line
			(start 3.8354 -0.36703)
			(end 4.389374 -0.898398)
			(stroke
				(width 0.1)
				(type default)
			)
			(layer "F.SilkS")
		)
		(fp_line
			(start 3.870198 -5.363464)
			(end 3.036824 -4.56438)
			(stroke
				(width 0.1)
				(type default)
			)
			(layer "F.SilkS")
		)
		(fp_line
			(start 3.870198 -5.363464)
			(end 3.036824 -4.56438)
			(stroke
				(width 0.1)
				(type default)
			)
			(layer "F.SilkS")
		)
		(fp_line
			(start 3.878326 -0.35052)
			(end 4.423918 -0.874014)
			(stroke
				(width 0.1)
				(type default)
			)
			(layer "F.SilkS")
		)
		(fp_line
			(start 3.878326 -0.35052)
			(end 4.423918 -0.874014)
			(stroke
				(width 0.1)
				(type default)
			)
			(layer "F.SilkS")
		)
		(fp_line
			(start 3.908552 -5.34289)
			(end 3.080766 -4.548886)
			(stroke
				(width 0.1)
				(type default)
			)
			(layer "F.SilkS")
		)
		(fp_line
			(start 3.908552 -5.34289)
			(end 3.080766 -4.548886)
			(stroke
				(width 0.1)
				(type default)
			)
			(layer "F.SilkS")
		)
		(fp_line
			(start 3.921252 -0.33401)
			(end 4.458462 -0.849376)
			(stroke
				(width 0.1)
				(type default)
			)
			(layer "F.SilkS")
		)
		(fp_line
			(start 3.921252 -0.33401)
			(end 4.458462 -0.849376)
			(stroke
				(width 0.1)
				(type default)
			)
			(layer "F.SilkS")
		)
		(fp_line
			(start 3.946652 -5.321808)
			(end 3.12039 -4.529074)
			(stroke
				(width 0.1)
				(type default)
			)
			(layer "F.SilkS")
		)
		(fp_line
			(start 3.946652 -5.321808)
			(end 3.12039 -4.529074)
			(stroke
				(width 0.1)
				(type default)
			)
			(layer "F.SilkS")
		)
		(fp_line
			(start 3.964178 -0.3175)
			(end 4.493006 -0.824738)
			(stroke
				(width 0.1)
				(type default)
			)
			(layer "F.SilkS")
		)
		(fp_line
			(start 3.964178 -0.3175)
			(end 4.493006 -0.824738)
			(stroke
				(width 0.1)
				(type default)
			)
			(layer "F.SilkS")
		)
		(fp_line
			(start 3.984752 -5.300472)
			(end 3.15722 -4.506722)
			(stroke
				(width 0.1)
				(type default)
			)
			(layer "F.SilkS")
		)
		(fp_line
			(start 3.984752 -5.300472)
			(end 3.15722 -4.506722)
			(stroke
				(width 0.1)
				(type default)
			)
			(layer "F.SilkS")
		)
		(fp_line
			(start 4.00685 -0.30099)
			(end 4.52755 -0.800608)
			(stroke
				(width 0.1)
				(type default)
			)
			(layer "F.SilkS")
		)
		(fp_line
			(start 4.00685 -0.30099)
			(end 4.52755 -0.800608)
			(stroke
				(width 0.1)
				(type default)
			)
			(layer "F.SilkS")
		)
		(fp_line
			(start 4.022852 -5.27939)
			(end 3.193796 -4.484116)
			(stroke
				(width 0.1)
				(type default)
			)
			(layer "F.SilkS")
		)
		(fp_line
			(start 4.022852 -5.27939)
			(end 3.193796 -4.484116)
			(stroke
				(width 0.1)
				(type default)
			)
			(layer "F.SilkS")
		)
		(fp_line
			(start 4.049776 -0.284226)
			(end 4.562094 -0.775716)
			(stroke
				(width 0.1)
				(type default)
			)
			(layer "F.SilkS")
		)
		(fp_line
			(start 4.049776 -0.284226)
			(end 4.562094 -0.775716)
			(stroke
				(width 0.1)
				(type default)
			)
			(layer "F.SilkS")
		)
		(fp_line
			(start 4.060952 -5.258054)
			(end 3.230372 -4.461256)
			(stroke
				(width 0.1)
				(type default)
			)
			(layer "F.SilkS")
		)
		(fp_line
			(start 4.060952 -5.258054)
			(end 3.230372 -4.461256)
			(stroke
				(width 0.1)
				(type default)
			)
			(layer "F.SilkS")
		)
		(fp_line
			(start 4.092448 -0.267462)
			(end 4.596892 -0.751332)
			(stroke
				(width 0.1)
				(type default)
			)
			(layer "F.SilkS")
		)
		(fp_line
			(start 4.092448 -0.267462)
			(end 4.596892 -0.751332)
			(stroke
				(width 0.1)
				(type default)
			)
			(layer "F.SilkS")
		)
		(fp_line
			(start 4.09829 -5.23621)
			(end 3.266948 -4.438904)
			(stroke
				(width 0.1)
				(type default)
			)
			(layer "F.SilkS")
		)
		(fp_line
			(start 4.09829 -5.23621)
			(end 3.266948 -4.438904)
			(stroke
				(width 0.1)
				(type default)
			)
			(layer "F.SilkS")
		)
		(fp_line
			(start 4.133088 -5.21208)
			(end 3.303524 -4.416044)
			(stroke
				(width 0.1)
				(type default)
			)
			(layer "F.SilkS")
		)
		(fp_line
			(start 4.133088 -5.21208)
			(end 3.303524 -4.416044)
			(stroke
				(width 0.1)
				(type default)
			)
			(layer "F.SilkS")
		)
		(fp_line
			(start 4.135374 -0.250698)
			(end 4.631436 -0.726694)
			(stroke
				(width 0.1)
				(type default)
			)
			(layer "F.SilkS")
		)
		(fp_line
			(start 4.135374 -0.250698)
			(end 4.631436 -0.726694)
			(stroke
				(width 0.1)
				(type default)
			)
			(layer "F.SilkS")
		)
		(fp_line
			(start 4.16814 -5.187696)
			(end 3.337052 -4.390644)
			(stroke
				(width 0.1)
				(type default)
			)
			(layer "F.SilkS")
		)
		(fp_line
			(start 4.16814 -5.187696)
			(end 3.337052 -4.390644)
			(stroke
				(width 0.1)
				(type default)
			)
			(layer "F.SilkS")
		)
		(fp_line
			(start 4.178046 -0.234188)
			(end 4.66598 -0.702056)
			(stroke
				(width 0.1)
				(type default)
			)
			(layer "F.SilkS")
		)
		(fp_line
			(start 4.178046 -0.234188)
			(end 4.66598 -0.702056)
			(stroke
				(width 0.1)
				(type default)
			)
			(layer "F.SilkS")
		)
		(fp_line
			(start 4.181856 -1.045718)
			(end 3.576828 -0.465582)
			(stroke
				(width 0.1)
				(type default)
			)
			(layer "F.SilkS")
		)
		(fp_line
			(start 4.181856 -1.045718)
			(end 3.576828 -0.465582)
			(stroke
				(width 0.1)
				(type default)
			)
			(layer "F.SilkS")
		)
		(fp_line
			(start 4.202938 -5.163312)
			(end 3.367532 -4.362196)
			(stroke
				(width 0.1)
				(type default)
			)
			(layer "F.SilkS")
		)
		(fp_line
			(start 4.202938 -5.163312)
			(end 3.367532 -4.362196)
			(stroke
				(width 0.1)
				(type default)
			)
			(layer "F.SilkS")
		)
		(fp_line
			(start 4.220718 -0.217678)
			(end 4.700524 -0.677926)
			(stroke
				(width 0.1)
				(type default)
			)
			(layer "F.SilkS")
		)
		(fp_line
			(start 4.220718 -0.217678)
			(end 4.700524 -0.677926)
			(stroke
				(width 0.1)
				(type default)
			)
			(layer "F.SilkS")
		)
		(fp_line
			(start 4.237736 -5.139182)
			(end 3.397504 -4.33324)
			(stroke
				(width 0.1)
				(type default)
			)
			(layer "F.SilkS")
		)
		(fp_line
			(start 4.237736 -5.139182)
			(end 3.397504 -4.33324)
			(stroke
				(width 0.1)
				(type default)
			)
			(layer "F.SilkS")
		)
		(fp_line
			(start 4.26339 -0.200406)
			(end 4.735068 -0.653034)
			(stroke
				(width 0.1)
				(type default)
			)
			(layer "F.SilkS")
		)
		(fp_line
			(start 4.26339 -0.200406)
			(end 4.735068 -0.653034)
			(stroke
				(width 0.1)
				(type default)
			)
			(layer "F.SilkS")
		)
		(fp_line
			(start 4.272534 -5.115052)
			(end 3.427984 -4.304792)
			(stroke
				(width 0.1)
				(type default)
			)
			(layer "F.SilkS")
		)
		(fp_line
			(start 4.272534 -5.115052)
			(end 3.427984 -4.304792)
			(stroke
				(width 0.1)
				(type default)
			)
			(layer "F.SilkS")
		)
		(fp_line
			(start 4.306062 -0.183896)
			(end 4.769866 -0.62865)
			(stroke
				(width 0.1)
				(type default)
			)
			(layer "F.SilkS")
		)
		(fp_line
			(start 4.306062 -0.183896)
			(end 4.769866 -0.62865)
			(stroke
				(width 0.1)
				(type default)
			)
			(layer "F.SilkS")
		)
		(fp_line
			(start 4.306316 -5.089398)
			(end 3.45821 -4.275836)
			(stroke
				(width 0.1)
				(type default)
			)
			(layer "F.SilkS")
		)
		(fp_line
			(start 4.306316 -5.089398)
			(end 3.45821 -4.275836)
			(stroke
				(width 0.1)
				(type default)
			)
			(layer "F.SilkS")
		)
		(fp_line
			(start 4.338066 -5.06222)
			(end 3.488436 -4.247388)
			(stroke
				(width 0.1)
				(type default)
			)
			(layer "F.SilkS")
		)
		(fp_line
			(start 4.338066 -5.06222)
			(end 3.488436 -4.247388)
			(stroke
				(width 0.1)
				(type default)
			)
			(layer "F.SilkS")
		)
		(fp_line
			(start 4.348734 -0.166878)
			(end 4.80441 -0.604266)
			(stroke
				(width 0.1)
				(type default)
			)
			(layer "F.SilkS")
		)
		(fp_line
			(start 4.348734 -0.166878)
			(end 4.80441 -0.604266)
			(stroke
				(width 0.1)
				(type default)
			)
			(layer "F.SilkS")
		)
		(fp_line
			(start 4.37007 -5.035296)
			(end 3.518408 -4.218432)
			(stroke
				(width 0.1)
				(type default)
			)
			(layer "F.SilkS")
		)
		(fp_line
			(start 4.37007 -5.035296)
			(end 3.518408 -4.218432)
			(stroke
				(width 0.1)
				(type default)
			)
			(layer "F.SilkS")
		)
		(fp_line
			(start 4.391406 -0.150114)
			(end 4.838954 -0.579628)
			(stroke
				(width 0.1)
				(type default)
			)
			(layer "F.SilkS")
		)
		(fp_line
			(start 4.391406 -0.150114)
			(end 4.838954 -0.579628)
			(stroke
				(width 0.1)
				(type default)
			)
			(layer "F.SilkS")
		)
		(fp_line
			(start 4.401566 -5.008118)
			(end 3.542792 -4.183888)
			(stroke
				(width 0.1)
				(type default)
			)
			(layer "F.SilkS")
		)
		(fp_line
			(start 4.401566 -5.008118)
			(end 3.542792 -4.183888)
			(stroke
				(width 0.1)
				(type default)
			)
			(layer "F.SilkS")
		)
		(fp_line
			(start 4.43357 -4.98094)
			(end 3.567176 -4.149598)
			(stroke
				(width 0.1)
				(type default)
			)
			(layer "F.SilkS")
		)
		(fp_line
			(start 4.43357 -4.98094)
			(end 3.567176 -4.149598)
			(stroke
				(width 0.1)
				(type default)
			)
			(layer "F.SilkS")
		)
		(fp_line
			(start 4.433824 -0.133604)
			(end 4.873752 -0.555244)
			(stroke
				(width 0.1)
				(type default)
			)
			(layer "F.SilkS")
		)
		(fp_line
			(start 4.433824 -0.133604)
			(end 4.873752 -0.555244)
			(stroke
				(width 0.1)
				(type default)
			)
			(layer "F.SilkS")
		)
		(fp_line
			(start 4.46532 -4.953508)
			(end 3.59156 -4.115308)
			(stroke
				(width 0.1)
				(type default)
			)
			(layer "F.SilkS")
		)
		(fp_line
			(start 4.46532 -4.953508)
			(end 3.59156 -4.115308)
			(stroke
				(width 0.1)
				(type default)
			)
			(layer "F.SilkS")
		)
		(fp_line
			(start 4.476496 -0.116332)
			(end 4.908296 -0.530352)
			(stroke
				(width 0.1)
				(type default)
			)
			(layer "F.SilkS")
		)
		(fp_line
			(start 4.476496 -0.116332)
			(end 4.908296 -0.530352)
			(stroke
				(width 0.1)
				(type default)
			)
			(layer "F.SilkS")
		)
		(fp_line
			(start 4.4958 -4.92506)
			(end 3.615944 -4.081018)
			(stroke
				(width 0.1)
				(type default)
			)
			(layer "F.SilkS")
		)
		(fp_line
			(start 4.4958 -4.92506)
			(end 3.615944 -4.081018)
			(stroke
				(width 0.1)
				(type default)
			)
			(layer "F.SilkS")
		)
		(fp_line
			(start 4.519168 -0.099822)
			(end 4.94284 -0.506222)
			(stroke
				(width 0.1)
				(type default)
			)
			(layer "F.SilkS")
		)
		(fp_line
			(start 4.519168 -0.099822)
			(end 4.94284 -0.506222)
			(stroke
				(width 0.1)
				(type default)
			)
			(layer "F.SilkS")
		)
		(fp_line
			(start 4.52374 -4.894072)
			(end 3.640328 -4.046728)
			(stroke
				(width 0.1)
				(type default)
			)
			(layer "F.SilkS")
		)
		(fp_line
			(start 4.52374 -4.894072)
			(end 3.640328 -4.046728)
			(stroke
				(width 0.1)
				(type default)
			)
			(layer "F.SilkS")
		)
		(fp_line
			(start 4.55168 -4.863338)
			(end 3.664712 -4.012438)
			(stroke
				(width 0.1)
				(type default)
			)
			(layer "F.SilkS")
		)
		(fp_line
			(start 4.55168 -4.863338)
			(end 3.664712 -4.012438)
			(stroke
				(width 0.1)
				(type default)
			)
			(layer "F.SilkS")
		)
		(fp_line
			(start 4.561586 -0.08255)
			(end 4.977384 -0.481584)
			(stroke
				(width 0.1)
				(type default)
			)
			(layer "F.SilkS")
		)
		(fp_line
			(start 4.561586 -0.08255)
			(end 4.977384 -0.481584)
			(stroke
				(width 0.1)
				(type default)
			)
			(layer "F.SilkS")
		)
		(fp_line
			(start 4.57962 -4.83235)
			(end 3.686556 -3.975608)
			(stroke
				(width 0.1)
				(type default)
			)
			(layer "F.SilkS")
		)
		(fp_line
			(start 4.57962 -4.83235)
			(end 3.686556 -3.975608)
			(stroke
				(width 0.1)
				(type default)
			)
			(layer "F.SilkS")
		)
		(fp_line
			(start 4.60756 -4.801362)
			(end 3.704844 -3.935476)
			(stroke
				(width 0.1)
				(type default)
			)
			(layer "F.SilkS")
		)
		(fp_line
			(start 4.60756 -4.801362)
			(end 3.704844 -3.935476)
			(stroke
				(width 0.1)
				(type default)
			)
			(layer "F.SilkS")
		)
		(fp_line
			(start 4.631182 -0.091948)
			(end 4.713478 -0.112776)
			(stroke
				(width 0.1)
				(type default)
			)
			(layer "F.SilkS")
		)
		(fp_line
			(start 4.631182 -0.091948)
			(end 4.713478 -0.112776)
			(stroke
				(width 0.1)
				(type default)
			)
			(layer "F.SilkS")
		)
		(fp_line
			(start 4.631182 -0.091948)
			(end 5.012182 -0.456946)
			(stroke
				(width 0.1)
				(type default)
			)
			(layer "F.SilkS")
		)
		(fp_line
			(start 4.631182 -0.091948)
			(end 5.012182 -0.456946)
			(stroke
				(width 0.1)
				(type default)
			)
			(layer "F.SilkS")
		)
		(fp_line
			(start 4.635246 -4.770374)
			(end 3.723386 -3.895598)
			(stroke
				(width 0.1)
				(type default)
			)
			(layer "F.SilkS")
		)
		(fp_line
			(start 4.635246 -4.770374)
			(end 3.723386 -3.895598)
			(stroke
				(width 0.1)
				(type default)
			)
			(layer "F.SilkS")
		)
		(fp_line
			(start 4.663186 -4.739386)
			(end 3.741928 -3.85572)
			(stroke
				(width 0.1)
				(type default)
			)
			(layer "F.SilkS")
		)
		(fp_line
			(start 4.663186 -4.739386)
			(end 3.741928 -3.85572)
			(stroke
				(width 0.1)
				(type default)
			)
			(layer "F.SilkS")
		)
		(fp_line
			(start 4.690618 -4.70789)
			(end 3.76047 -3.815588)
			(stroke
				(width 0.1)
				(type default)
			)
			(layer "F.SilkS")
		)
		(fp_line
			(start 4.690618 -4.70789)
			(end 3.76047 -3.815588)
			(stroke
				(width 0.1)
				(type default)
			)
			(layer "F.SilkS")
		)
		(fp_line
			(start 4.713478 -0.112776)
			(end 4.795266 -0.133604)
			(stroke
				(width 0.1)
				(type default)
			)
			(layer "F.SilkS")
		)
		(fp_line
			(start 4.713478 -0.112776)
			(end 4.795266 -0.133604)
			(stroke
				(width 0.1)
				(type default)
			)
			(layer "F.SilkS")
		)
		(fp_line
			(start 4.713478 -0.112776)
			(end 5.046726 -0.432562)
			(stroke
				(width 0.1)
				(type default)
			)
			(layer "F.SilkS")
		)
		(fp_line
			(start 4.713478 -0.112776)
			(end 5.046726 -0.432562)
			(stroke
				(width 0.1)
				(type default)
			)
			(layer "F.SilkS")
		)
		(fp_line
			(start 4.713732 -4.672584)
			(end 3.778758 -3.775456)
			(stroke
				(width 0.1)
				(type default)
			)
			(layer "F.SilkS")
		)
		(fp_line
			(start 4.713732 -4.672584)
			(end 3.778758 -3.775456)
			(stroke
				(width 0.1)
				(type default)
			)
			(layer "F.SilkS")
		)
		(fp_line
			(start 4.7371 -4.637278)
			(end 3.7973 -3.735578)
			(stroke
				(width 0.1)
				(type default)
			)
			(layer "F.SilkS")
		)
		(fp_line
			(start 4.7371 -4.637278)
			(end 3.7973 -3.735578)
			(stroke
				(width 0.1)
				(type default)
			)
			(layer "F.SilkS")
		)
		(fp_line
			(start 4.760214 -4.601718)
			(end 3.81 -3.689858)
			(stroke
				(width 0.1)
				(type default)
			)
			(layer "F.SilkS")
		)
		(fp_line
			(start 4.760214 -4.601718)
			(end 3.81 -3.689858)
			(stroke
				(width 0.1)
				(type default)
			)
			(layer "F.SilkS")
		)
		(fp_line
			(start 4.783582 -4.566158)
			(end 3.821938 -3.643884)
			(stroke
				(width 0.1)
				(type default)
			)
			(layer "F.SilkS")
		)
		(fp_line
			(start 4.783582 -4.566158)
			(end 3.821938 -3.643884)
			(stroke
				(width 0.1)
				(type default)
			)
			(layer "F.SilkS")
		)
		(fp_line
			(start 4.795266 -0.133604)
			(end 4.877308 -0.15494)
			(stroke
				(width 0.1)
				(type default)
			)
			(layer "F.SilkS")
		)
		(fp_line
			(start 4.795266 -0.133604)
			(end 4.877308 -0.15494)
			(stroke
				(width 0.1)
				(type default)
			)
			(layer "F.SilkS")
		)
		(fp_line
			(start 4.795266 -0.133604)
			(end 5.08127 -0.408178)
			(stroke
				(width 0.1)
				(type default)
			)
			(layer "F.SilkS")
		)
		(fp_line
			(start 4.795266 -0.133604)
			(end 5.08127 -0.408178)
			(stroke
				(width 0.1)
				(type default)
			)
			(layer "F.SilkS")
		)
		(fp_line
			(start 4.806696 -4.530852)
			(end 3.83413 -3.59791)
			(stroke
				(width 0.1)
				(type default)
			)
			(layer "F.SilkS")
		)
		(fp_line
			(start 4.806696 -4.530852)
			(end 3.83413 -3.59791)
			(stroke
				(width 0.1)
				(type default)
			)
			(layer "F.SilkS")
		)
		(fp_line
			(start 4.82981 -4.495292)
			(end 3.846068 -3.551682)
			(stroke
				(width 0.1)
				(type default)
			)
			(layer "F.SilkS")
		)
		(fp_line
			(start 4.82981 -4.495292)
			(end 3.846068 -3.551682)
			(stroke
				(width 0.1)
				(type default)
			)
			(layer "F.SilkS")
		)
		(fp_line
			(start 4.851654 -4.458462)
			(end 3.858006 -3.505454)
			(stroke
				(width 0.1)
				(type default)
			)
			(layer "F.SilkS")
		)
		(fp_line
			(start 4.851654 -4.458462)
			(end 3.858006 -3.505454)
			(stroke
				(width 0.1)
				(type default)
			)
			(layer "F.SilkS")
		)
		(fp_line
			(start 4.870958 -4.419092)
			(end 3.870198 -3.459226)
			(stroke
				(width 0.1)
				(type default)
			)
			(layer "F.SilkS")
		)
		(fp_line
			(start 4.870958 -4.419092)
			(end 3.870198 -3.459226)
			(stroke
				(width 0.1)
				(type default)
			)
			(layer "F.SilkS")
		)
		(fp_line
			(start 4.877308 -0.15494)
			(end 4.95935 -0.175514)
			(stroke
				(width 0.1)
				(type default)
			)
			(layer "F.SilkS")
		)
		(fp_line
			(start 4.877308 -0.15494)
			(end 4.95935 -0.175514)
			(stroke
				(width 0.1)
				(type default)
			)
			(layer "F.SilkS")
		)
		(fp_line
			(start 4.877308 -0.15494)
			(end 5.115814 -0.383794)
			(stroke
				(width 0.1)
				(type default)
			)
			(layer "F.SilkS")
		)
		(fp_line
			(start 4.877308 -0.15494)
			(end 5.115814 -0.383794)
			(stroke
				(width 0.1)
				(type default)
			)
			(layer "F.SilkS")
		)
		(fp_line
			(start 4.889754 -4.379722)
			(end 3.878072 -3.409188)
			(stroke
				(width 0.1)
				(type default)
			)
			(layer "F.SilkS")
		)
		(fp_line
			(start 4.889754 -4.379722)
			(end 3.878072 -3.409188)
			(stroke
				(width 0.1)
				(type default)
			)
			(layer "F.SilkS")
		)
		(fp_line
			(start 4.908804 -4.340098)
			(end 3.88239 -3.355848)
			(stroke
				(width 0.1)
				(type default)
			)
			(layer "F.SilkS")
		)
		(fp_line
			(start 4.908804 -4.340098)
			(end 3.88239 -3.355848)
			(stroke
				(width 0.1)
				(type default)
			)
			(layer "F.SilkS")
		)
		(fp_line
			(start 4.927854 -4.300728)
			(end 3.886962 -3.302254)
			(stroke
				(width 0.1)
				(type default)
			)
			(layer "F.SilkS")
		)
		(fp_line
			(start 4.927854 -4.300728)
			(end 3.886962 -3.302254)
			(stroke
				(width 0.1)
				(type default)
			)
			(layer "F.SilkS")
		)
		(fp_line
			(start 4.946904 -4.261358)
			(end 3.891534 -3.248914)
			(stroke
				(width 0.1)
				(type default)
			)
			(layer "F.SilkS")
		)
		(fp_line
			(start 4.946904 -4.261358)
			(end 3.891534 -3.248914)
			(stroke
				(width 0.1)
				(type default)
			)
			(layer "F.SilkS")
		)
		(fp_line
			(start 4.95935 -0.175514)
			(end 5.041392 -0.196596)
			(stroke
				(width 0.1)
				(type default)
			)
			(layer "F.SilkS")
		)
		(fp_line
			(start 4.95935 -0.175514)
			(end 5.041392 -0.196596)
			(stroke
				(width 0.1)
				(type default)
			)
			(layer "F.SilkS")
		)
		(fp_line
			(start 4.95935 -0.175514)
			(end 5.150612 -0.359156)
			(stroke
				(width 0.1)
				(type default)
			)
			(layer "F.SilkS")
		)
		(fp_line
			(start 4.95935 -0.175514)
			(end 5.150612 -0.359156)
			(stroke
				(width 0.1)
				(type default)
			)
			(layer "F.SilkS")
		)
		(fp_line
			(start 4.965446 -4.221226)
			(end 3.895852 -3.19532)
			(stroke
				(width 0.1)
				(type default)
			)
			(layer "F.SilkS")
		)
		(fp_line
			(start 4.965446 -4.221226)
			(end 3.895852 -3.19532)
			(stroke
				(width 0.1)
				(type default)
			)
			(layer "F.SilkS")
		)
		(fp_line
			(start 4.980686 -4.1783)
			(end 3.900424 -3.14198)
			(stroke
				(width 0.1)
				(type default)
			)
			(layer "F.SilkS")
		)
		(fp_line
			(start 4.980686 -4.1783)
			(end 3.900424 -3.14198)
			(stroke
				(width 0.1)
				(type default)
			)
			(layer "F.SilkS")
		)
		(fp_line
			(start 4.995672 -4.13512)
			(end 3.899408 -3.083306)
			(stroke
				(width 0.1)
				(type default)
			)
			(layer "F.SilkS")
		)
		(fp_line
			(start 4.995672 -4.13512)
			(end 3.899408 -3.083306)
			(stroke
				(width 0.1)
				(type default)
			)
			(layer "F.SilkS")
		)
		(fp_line
			(start 5.011166 -4.09194)
			(end 3.894328 -3.020822)
			(stroke
				(width 0.1)
				(type default)
			)
			(layer "F.SilkS")
		)
		(fp_line
			(start 5.011166 -4.09194)
			(end 3.894328 -3.020822)
			(stroke
				(width 0.1)
				(type default)
			)
			(layer "F.SilkS")
		)
		(fp_line
			(start 5.026152 -4.04876)
			(end 3.889248 -2.958084)
			(stroke
				(width 0.1)
				(type default)
			)
			(layer "F.SilkS")
		)
		(fp_line
			(start 5.026152 -4.04876)
			(end 3.889248 -2.958084)
			(stroke
				(width 0.1)
				(type default)
			)
			(layer "F.SilkS")
		)
		(fp_line
			(start 5.041392 -4.00558)
			(end 3.884168 -2.8956)
			(stroke
				(width 0.1)
				(type default)
			)
			(layer "F.SilkS")
		)
		(fp_line
			(start 5.041392 -4.00558)
			(end 3.884168 -2.8956)
			(stroke
				(width 0.1)
				(type default)
			)
			(layer "F.SilkS")
		)
		(fp_line
			(start 5.041392 -0.196596)
			(end 5.12318 -0.217678)
			(stroke
				(width 0.1)
				(type default)
			)
			(layer "F.SilkS")
		)
		(fp_line
			(start 5.041392 -0.196596)
			(end 5.12318 -0.217678)
			(stroke
				(width 0.1)
				(type default)
			)
			(layer "F.SilkS")
		)
		(fp_line
			(start 5.041392 -0.196596)
			(end 5.185156 -0.334772)
			(stroke
				(width 0.1)
				(type default)
			)
			(layer "F.SilkS")
		)
		(fp_line
			(start 5.041392 -0.196596)
			(end 5.185156 -0.334772)
			(stroke
				(width 0.1)
				(type default)
			)
			(layer "F.SilkS")
		)
		(fp_line
			(start 5.0546 -3.960622)
			(end 3.879088 -2.832862)
			(stroke
				(width 0.1)
				(type default)
			)
			(layer "F.SilkS")
		)
		(fp_line
			(start 5.0546 -3.960622)
			(end 3.879088 -2.832862)
			(stroke
				(width 0.1)
				(type default)
			)
			(layer "F.SilkS")
		)
		(fp_line
			(start 5.066284 -3.91414)
			(end 3.863086 -2.75971)
			(stroke
				(width 0.1)
				(type default)
			)
			(layer "F.SilkS")
		)
		(fp_line
			(start 5.066284 -3.91414)
			(end 3.863086 -2.75971)
			(stroke
				(width 0.1)
				(type default)
			)
			(layer "F.SilkS")
		)
		(fp_line
			(start 5.078222 -3.867658)
			(end 3.843782 -2.68351)
			(stroke
				(width 0.1)
				(type default)
			)
			(layer "F.SilkS")
		)
		(fp_line
			(start 5.078222 -3.867658)
			(end 3.843782 -2.68351)
			(stroke
				(width 0.1)
				(type default)
			)
			(layer "F.SilkS")
		)
		(fp_line
			(start 5.089652 -3.821176)
			(end 3.824478 -2.607564)
			(stroke
				(width 0.1)
				(type default)
			)
			(layer "F.SilkS")
		)
		(fp_line
			(start 5.089652 -3.821176)
			(end 3.824478 -2.607564)
			(stroke
				(width 0.1)
				(type default)
			)
			(layer "F.SilkS")
		)
		(fp_line
			(start 5.101336 -3.774694)
			(end 3.802126 -2.528316)
			(stroke
				(width 0.1)
				(type default)
			)
			(layer "F.SilkS")
		)
		(fp_line
			(start 5.101336 -3.774694)
			(end 3.802126 -2.528316)
			(stroke
				(width 0.1)
				(type default)
			)
			(layer "F.SilkS")
		)
		(fp_line
			(start 5.110734 -3.72618)
			(end 3.756406 -2.426716)
			(stroke
				(width 0.1)
				(type default)
			)
			(layer "F.SilkS")
		)
		(fp_line
			(start 5.110734 -3.72618)
			(end 3.756406 -2.426716)
			(stroke
				(width 0.1)
				(type default)
			)
			(layer "F.SilkS")
		)
		(fp_line
			(start 5.11937 -3.676396)
			(end 3.710686 -2.32537)
			(stroke
				(width 0.1)
				(type default)
			)
			(layer "F.SilkS")
		)
		(fp_line
			(start 5.11937 -3.676396)
			(end 3.710686 -2.32537)
			(stroke
				(width 0.1)
				(type default)
			)
			(layer "F.SilkS")
		)
		(fp_line
			(start 5.12318 -0.217678)
			(end 5.205222 -0.238252)
			(stroke
				(width 0.1)
				(type default)
			)
			(layer "F.SilkS")
		)
		(fp_line
			(start 5.12318 -0.217678)
			(end 5.205222 -0.238252)
			(stroke
				(width 0.1)
				(type default)
			)
			(layer "F.SilkS")
		)
		(fp_line
			(start 5.12318 -0.217678)
			(end 5.219954 -0.310388)
			(stroke
				(width 0.1)
				(type default)
			)
			(layer "F.SilkS")
		)
		(fp_line
			(start 5.12318 -0.217678)
			(end 5.219954 -0.310388)
			(stroke
				(width 0.1)
				(type default)
			)
			(layer "F.SilkS")
		)
		(fp_line
			(start 5.127498 -3.626612)
			(end 3.618992 -2.17932)
			(stroke
				(width 0.1)
				(type default)
			)
			(layer "F.SilkS")
		)
		(fp_line
			(start 5.127498 -3.626612)
			(end 3.618992 -2.17932)
			(stroke
				(width 0.1)
				(type default)
			)
			(layer "F.SilkS")
		)
		(fp_line
			(start 5.13588 -3.576828)
			(end 2.15773 -0.719836)
			(stroke
				(width 0.1)
				(type default)
			)
			(layer "F.SilkS")
		)
		(fp_line
			(start 5.13588 -3.576828)
			(end 2.15773 -0.719836)
			(stroke
				(width 0.1)
				(type default)
			)
			(layer "F.SilkS")
		)
		(fp_line
			(start 5.205222 -0.238252)
			(end 5.254752 -0.28575)
			(stroke
				(width 0.1)
				(type default)
			)
			(layer "F.SilkS")
		)
		(fp_line
			(start 5.205222 -0.238252)
			(end 5.254752 -0.28575)
			(stroke
				(width 0.1)
				(type default)
			)
			(layer "F.SilkS")
		)
		(fp_line
			(start 5.287264 -0.259588)
			(end 5.205222 -0.238252)
			(stroke
				(width 0.1)
				(type default)
			)
			(layer "F.SilkS")
		)
		(fp_line
			(start 5.287264 -0.259588)
			(end 5.205222 -0.238252)
			(stroke
				(width 0.1)
				(type default)
			)
			(layer "F.SilkS")
		)
		(fp_line
			(start 5.287264 -0.259588)
			(end 5.289296 -0.261366)
			(stroke
				(width 0.1)
				(type default)
			)
			(layer "F.SilkS")
		)
		(fp_line
			(start 5.287264 -0.259588)
			(end 5.289296 -0.261366)
			(stroke
				(width 0.1)
				(type default)
			)
			(layer "F.SilkS")
		)
		(fp_line
			(start 5.507482 -2.281682)
			(end 6.825488 -3.54584)
			(stroke
				(width 0.1)
				(type default)
			)
			(layer "F.SilkS")
		)
		(fp_line
			(start 5.507482 -2.281682)
			(end 6.825488 -3.54584)
			(stroke
				(width 0.1)
				(type default)
			)
			(layer "F.SilkS")
		)
		(fp_line
			(start 5.50799 -2.224278)
			(end 6.81355 -3.476498)
			(stroke
				(width 0.1)
				(type default)
			)
			(layer "F.SilkS")
		)
		(fp_line
			(start 5.50799 -2.224278)
			(end 6.81355 -3.476498)
			(stroke
				(width 0.1)
				(type default)
			)
			(layer "F.SilkS")
		)
		(fp_line
			(start 5.508498 -2.167128)
			(end 6.801104 -3.407156)
			(stroke
				(width 0.1)
				(type default)
			)
			(layer "F.SilkS")
		)
		(fp_line
			(start 5.508498 -2.167128)
			(end 6.801104 -3.407156)
			(stroke
				(width 0.1)
				(type default)
			)
			(layer "F.SilkS")
		)
		(fp_line
			(start 5.508752 -2.109724)
			(end 6.788912 -3.337814)
			(stroke
				(width 0.1)
				(type default)
			)
			(layer "F.SilkS")
		)
		(fp_line
			(start 5.508752 -2.109724)
			(end 6.788912 -3.337814)
			(stroke
				(width 0.1)
				(type default)
			)
			(layer "F.SilkS")
		)
		(fp_line
			(start 5.50926 -2.052574)
			(end 6.776974 -3.268472)
			(stroke
				(width 0.1)
				(type default)
			)
			(layer "F.SilkS")
		)
		(fp_line
			(start 5.50926 -2.052574)
			(end 6.776974 -3.268472)
			(stroke
				(width 0.1)
				(type default)
			)
			(layer "F.SilkS")
		)
		(fp_line
			(start 5.509768 -1.99517)
			(end 6.764782 -3.19913)
			(stroke
				(width 0.1)
				(type default)
			)
			(layer "F.SilkS")
		)
		(fp_line
			(start 5.509768 -1.99517)
			(end 6.764782 -3.19913)
			(stroke
				(width 0.1)
				(type default)
			)
			(layer "F.SilkS")
		)
		(fp_line
			(start 5.510276 -1.937766)
			(end 6.75259 -3.129534)
			(stroke
				(width 0.1)
				(type default)
			)
			(layer "F.SilkS")
		)
		(fp_line
			(start 5.510276 -1.937766)
			(end 6.75259 -3.129534)
			(stroke
				(width 0.1)
				(type default)
			)
			(layer "F.SilkS")
		)
		(fp_line
			(start 5.518912 -1.88849)
			(end 6.740144 -3.060192)
			(stroke
				(width 0.1)
				(type default)
			)
			(layer "F.SilkS")
		)
		(fp_line
			(start 5.518912 -1.88849)
			(end 6.740144 -3.060192)
			(stroke
				(width 0.1)
				(type default)
			)
			(layer "F.SilkS")
		)
		(fp_line
			(start 5.527802 -1.839214)
			(end 6.728206 -2.99085)
			(stroke
				(width 0.1)
				(type default)
			)
			(layer "F.SilkS")
		)
		(fp_line
			(start 5.527802 -1.839214)
			(end 6.728206 -2.99085)
			(stroke
				(width 0.1)
				(type default)
			)
			(layer "F.SilkS")
		)
		(fp_line
			(start 5.536438 -1.789938)
			(end 6.716014 -2.921254)
			(stroke
				(width 0.1)
				(type default)
			)
			(layer "F.SilkS")
		)
		(fp_line
			(start 5.536438 -1.789938)
			(end 6.716014 -2.921254)
			(stroke
				(width 0.1)
				(type default)
			)
			(layer "F.SilkS")
		)
		(fp_line
			(start 5.545582 -1.740916)
			(end 6.703822 -2.852166)
			(stroke
				(width 0.1)
				(type default)
			)
			(layer "F.SilkS")
		)
		(fp_line
			(start 5.545582 -1.740916)
			(end 6.703822 -2.852166)
			(stroke
				(width 0.1)
				(type default)
			)
			(layer "F.SilkS")
		)
		(fp_line
			(start 5.554218 -1.69164)
			(end 6.695186 -2.786126)
			(stroke
				(width 0.1)
				(type default)
			)
			(layer "F.SilkS")
		)
		(fp_line
			(start 5.554218 -1.69164)
			(end 6.695186 -2.786126)
			(stroke
				(width 0.1)
				(type default)
			)
			(layer "F.SilkS")
		)
		(fp_line
			(start 5.563108 -1.642364)
			(end 6.68655 -2.720086)
			(stroke
				(width 0.1)
				(type default)
			)
			(layer "F.SilkS")
		)
		(fp_line
			(start 5.563108 -1.642364)
			(end 6.68655 -2.720086)
			(stroke
				(width 0.1)
				(type default)
			)
			(layer "F.SilkS")
		)
		(fp_line
			(start 5.573522 -1.594612)
			(end 6.678168 -2.6543)
			(stroke
				(width 0.1)
				(type default)
			)
			(layer "F.SilkS")
		)
		(fp_line
			(start 5.573522 -1.594612)
			(end 6.678168 -2.6543)
			(stroke
				(width 0.1)
				(type default)
			)
			(layer "F.SilkS")
		)
		(fp_line
			(start 5.58038 -2.870962)
			(end 5.568188 -2.801366)
			(stroke
				(width 0.1)
				(type default)
			)
			(layer "F.SilkS")
		)
		(fp_line
			(start 5.58038 -2.870962)
			(end 5.568188 -2.801366)
			(stroke
				(width 0.1)
				(type default)
			)
			(layer "F.SilkS")
		)
		(fp_line
			(start 5.591048 -1.553718)
			(end 6.669532 -2.58826)
			(stroke
				(width 0.1)
				(type default)
			)
			(layer "F.SilkS")
		)
		(fp_line
			(start 5.591048 -1.553718)
			(end 6.669532 -2.58826)
			(stroke
				(width 0.1)
				(type default)
			)
			(layer "F.SilkS")
		)
		(fp_line
			(start 5.592572 -2.940304)
			(end 5.58038 -2.870962)
			(stroke
				(width 0.1)
				(type default)
			)
			(layer "F.SilkS")
		)
		(fp_line
			(start 5.592572 -2.940304)
			(end 5.58038 -2.870962)
			(stroke
				(width 0.1)
				(type default)
			)
			(layer "F.SilkS")
		)
		(fp_line
			(start 5.604764 -3.009646)
			(end 5.592572 -2.940304)
			(stroke
				(width 0.1)
				(type default)
			)
			(layer "F.SilkS")
		)
		(fp_line
			(start 5.604764 -3.009646)
			(end 5.592572 -2.940304)
			(stroke
				(width 0.1)
				(type default)
			)
			(layer "F.SilkS")
		)
		(fp_line
			(start 5.60832 -1.51257)
			(end 6.669024 -2.530094)
			(stroke
				(width 0.1)
				(type default)
			)
			(layer "F.SilkS")
		)
		(fp_line
			(start 5.60832 -1.51257)
			(end 6.669024 -2.530094)
			(stroke
				(width 0.1)
				(type default)
			)
			(layer "F.SilkS")
		)
		(fp_line
			(start 5.616956 -3.079242)
			(end 5.604764 -3.009646)
			(stroke
				(width 0.1)
				(type default)
			)
			(layer "F.SilkS")
		)
		(fp_line
			(start 5.616956 -3.079242)
			(end 5.604764 -3.009646)
			(stroke
				(width 0.1)
				(type default)
			)
			(layer "F.SilkS")
		)
		(fp_line
			(start 5.625846 -1.471676)
			(end 6.668516 -2.471928)
			(stroke
				(width 0.1)
				(type default)
			)
			(layer "F.SilkS")
		)
		(fp_line
			(start 5.625846 -1.471676)
			(end 6.668516 -2.471928)
			(stroke
				(width 0.1)
				(type default)
			)
			(layer "F.SilkS")
		)
		(fp_line
			(start 5.629148 -3.148584)
			(end 5.616956 -3.079242)
			(stroke
				(width 0.1)
				(type default)
			)
			(layer "F.SilkS")
		)
		(fp_line
			(start 5.629148 -3.148584)
			(end 5.616956 -3.079242)
			(stroke
				(width 0.1)
				(type default)
			)
			(layer "F.SilkS")
		)
		(fp_line
			(start 5.64134 -3.217926)
			(end 5.629148 -3.148584)
			(stroke
				(width 0.1)
				(type default)
			)
			(layer "F.SilkS")
		)
		(fp_line
			(start 5.64134 -3.217926)
			(end 5.629148 -3.148584)
			(stroke
				(width 0.1)
				(type default)
			)
			(layer "F.SilkS")
		)
		(fp_line
			(start 5.643118 -1.430528)
			(end 6.668008 -2.413762)
			(stroke
				(width 0.1)
				(type default)
			)
			(layer "F.SilkS")
		)
		(fp_line
			(start 5.643118 -1.430528)
			(end 6.668008 -2.413762)
			(stroke
				(width 0.1)
				(type default)
			)
			(layer "F.SilkS")
		)
		(fp_line
			(start 5.653532 -3.287268)
			(end 5.64134 -3.217926)
			(stroke
				(width 0.1)
				(type default)
			)
			(layer "F.SilkS")
		)
		(fp_line
			(start 5.653532 -3.287268)
			(end 5.64134 -3.217926)
			(stroke
				(width 0.1)
				(type default)
			)
			(layer "F.SilkS")
		)
		(fp_line
			(start 5.660644 -1.389634)
			(end 6.67004 -2.357882)
			(stroke
				(width 0.1)
				(type default)
			)
			(layer "F.SilkS")
		)
		(fp_line
			(start 5.660644 -1.389634)
			(end 6.67004 -2.357882)
			(stroke
				(width 0.1)
				(type default)
			)
			(layer "F.SilkS")
		)
		(fp_line
			(start 5.665724 -3.35661)
			(end 5.653532 -3.287268)
			(stroke
				(width 0.1)
				(type default)
			)
			(layer "F.SilkS")
		)
		(fp_line
			(start 5.665724 -3.35661)
			(end 5.653532 -3.287268)
			(stroke
				(width 0.1)
				(type default)
			)
			(layer "F.SilkS")
		)
		(fp_line
			(start 5.677662 -3.425952)
			(end 5.665724 -3.35661)
			(stroke
				(width 0.1)
				(type default)
			)
			(layer "F.SilkS")
		)
		(fp_line
			(start 5.677662 -3.425952)
			(end 5.665724 -3.35661)
			(stroke
				(width 0.1)
				(type default)
			)
			(layer "F.SilkS")
		)
		(fp_line
			(start 5.677916 -1.34874)
			(end 6.678168 -2.308352)
			(stroke
				(width 0.1)
				(type default)
			)
			(layer "F.SilkS")
		)
		(fp_line
			(start 5.677916 -1.34874)
			(end 6.678168 -2.308352)
			(stroke
				(width 0.1)
				(type default)
			)
			(layer "F.SilkS")
		)
		(fp_line
			(start 5.690108 -3.495548)
			(end 5.677662 -3.425952)
			(stroke
				(width 0.1)
				(type default)
			)
			(layer "F.SilkS")
		)
		(fp_line
			(start 5.690108 -3.495548)
			(end 5.677662 -3.425952)
			(stroke
				(width 0.1)
				(type default)
			)
			(layer "F.SilkS")
		)
		(fp_line
			(start 5.697982 -1.310132)
			(end 6.68655 -2.258568)
			(stroke
				(width 0.1)
				(type default)
			)
			(layer "F.SilkS")
		)
		(fp_line
			(start 5.697982 -1.310132)
			(end 6.68655 -2.258568)
			(stroke
				(width 0.1)
				(type default)
			)
			(layer "F.SilkS")
		)
		(fp_line
			(start 5.7023 -3.56489)
			(end 5.690108 -3.495548)
			(stroke
				(width 0.1)
				(type default)
			)
			(layer "F.SilkS")
		)
		(fp_line
			(start 5.7023 -3.56489)
			(end 5.690108 -3.495548)
			(stroke
				(width 0.1)
				(type default)
			)
			(layer "F.SilkS")
		)
		(fp_line
			(start 5.714238 -3.634232)
			(end 5.7023 -3.56489)
			(stroke
				(width 0.1)
				(type default)
			)
			(layer "F.SilkS")
		)
		(fp_line
			(start 5.714238 -3.634232)
			(end 5.7023 -3.56489)
			(stroke
				(width 0.1)
				(type default)
			)
			(layer "F.SilkS")
		)
		(fp_line
			(start 5.724398 -1.27762)
			(end 6.694932 -2.20853)
			(stroke
				(width 0.1)
				(type default)
			)
			(layer "F.SilkS")
		)
		(fp_line
			(start 5.724398 -1.27762)
			(end 6.694932 -2.20853)
			(stroke
				(width 0.1)
				(type default)
			)
			(layer "F.SilkS")
		)
		(fp_line
			(start 5.72643 -3.703828)
			(end 5.714238 -3.634232)
			(stroke
				(width 0.1)
				(type default)
			)
			(layer "F.SilkS")
		)
		(fp_line
			(start 5.72643 -3.703828)
			(end 5.714238 -3.634232)
			(stroke
				(width 0.1)
				(type default)
			)
			(layer "F.SilkS")
		)
		(fp_line
			(start 5.738876 -3.772916)
			(end 5.72643 -3.703828)
			(stroke
				(width 0.1)
				(type default)
			)
			(layer "F.SilkS")
		)
		(fp_line
			(start 5.738876 -3.772916)
			(end 5.72643 -3.703828)
			(stroke
				(width 0.1)
				(type default)
			)
			(layer "F.SilkS")
		)
		(fp_line
			(start 5.750306 -1.244854)
			(end 6.710934 -2.166366)
			(stroke
				(width 0.1)
				(type default)
			)
			(layer "F.SilkS")
		)
		(fp_line
			(start 5.750306 -1.244854)
			(end 6.710934 -2.166366)
			(stroke
				(width 0.1)
				(type default)
			)
			(layer "F.SilkS")
		)
		(fp_line
			(start 5.751068 -3.842512)
			(end 5.738876 -3.772916)
			(stroke
				(width 0.1)
				(type default)
			)
			(layer "F.SilkS")
		)
		(fp_line
			(start 5.751068 -3.842512)
			(end 5.738876 -3.772916)
			(stroke
				(width 0.1)
				(type default)
			)
			(layer "F.SilkS")
		)
		(fp_line
			(start 5.763006 -3.911854)
			(end 5.751068 -3.842512)
			(stroke
				(width 0.1)
				(type default)
			)
			(layer "F.SilkS")
		)
		(fp_line
			(start 5.763006 -3.911854)
			(end 5.751068 -3.842512)
			(stroke
				(width 0.1)
				(type default)
			)
			(layer "F.SilkS")
		)
		(fp_line
			(start 5.775198 -3.98145)
			(end 5.763006 -3.911854)
			(stroke
				(width 0.1)
				(type default)
			)
			(layer "F.SilkS")
		)
		(fp_line
			(start 5.775198 -3.98145)
			(end 5.763006 -3.911854)
			(stroke
				(width 0.1)
				(type default)
			)
			(layer "F.SilkS")
		)
		(fp_line
			(start 5.776468 -1.212342)
			(end 6.728714 -2.125726)
			(stroke
				(width 0.1)
				(type default)
			)
			(layer "F.SilkS")
		)
		(fp_line
			(start 5.776468 -1.212342)
			(end 6.728714 -2.125726)
			(stroke
				(width 0.1)
				(type default)
			)
			(layer "F.SilkS")
		)
		(fp_line
			(start 5.78739 -4.050538)
			(end 5.775198 -3.98145)
			(stroke
				(width 0.1)
				(type default)
			)
			(layer "F.SilkS")
		)
		(fp_line
			(start 5.78739 -4.050538)
			(end 5.775198 -3.98145)
			(stroke
				(width 0.1)
				(type default)
			)
			(layer "F.SilkS")
		)
		(fp_line
			(start 5.799582 -4.11988)
			(end 5.78739 -4.050538)
			(stroke
				(width 0.1)
				(type default)
			)
			(layer "F.SilkS")
		)
		(fp_line
			(start 5.799582 -4.11988)
			(end 5.78739 -4.050538)
			(stroke
				(width 0.1)
				(type default)
			)
			(layer "F.SilkS")
		)
		(fp_line
			(start 5.80263 -1.179576)
			(end 6.746494 -2.084832)
			(stroke
				(width 0.1)
				(type default)
			)
			(layer "F.SilkS")
		)
		(fp_line
			(start 5.80263 -1.179576)
			(end 6.746494 -2.084832)
			(stroke
				(width 0.1)
				(type default)
			)
			(layer "F.SilkS")
		)
		(fp_line
			(start 5.811774 -4.189476)
			(end 5.799582 -4.11988)
			(stroke
				(width 0.1)
				(type default)
			)
			(layer "F.SilkS")
		)
		(fp_line
			(start 5.811774 -4.189476)
			(end 5.799582 -4.11988)
			(stroke
				(width 0.1)
				(type default)
			)
			(layer "F.SilkS")
		)
		(fp_line
			(start 5.823966 -4.258818)
			(end 5.811774 -4.189476)
			(stroke
				(width 0.1)
				(type default)
			)
			(layer "F.SilkS")
		)
		(fp_line
			(start 5.823966 -4.258818)
			(end 5.811774 -4.189476)
			(stroke
				(width 0.1)
				(type default)
			)
			(layer "F.SilkS")
		)
		(fp_line
			(start 5.828792 -1.147064)
			(end 6.769608 -2.049272)
			(stroke
				(width 0.1)
				(type default)
			)
			(layer "F.SilkS")
		)
		(fp_line
			(start 5.828792 -1.147064)
			(end 6.769608 -2.049272)
			(stroke
				(width 0.1)
				(type default)
			)
			(layer "F.SilkS")
		)
		(fp_line
			(start 5.836158 -4.328414)
			(end 5.823966 -4.258818)
			(stroke
				(width 0.1)
				(type default)
			)
			(layer "F.SilkS")
		)
		(fp_line
			(start 5.836158 -4.328414)
			(end 5.823966 -4.258818)
			(stroke
				(width 0.1)
				(type default)
			)
			(layer "F.SilkS")
		)
		(fp_line
			(start 5.84835 -4.397502)
			(end 5.836158 -4.328414)
			(stroke
				(width 0.1)
				(type default)
			)
			(layer "F.SilkS")
		)
		(fp_line
			(start 5.84835 -4.397502)
			(end 5.836158 -4.328414)
			(stroke
				(width 0.1)
				(type default)
			)
			(layer "F.SilkS")
		)
		(fp_line
			(start 5.854954 -1.114298)
			(end 6.79704 -2.018284)
			(stroke
				(width 0.1)
				(type default)
			)
			(layer "F.SilkS")
		)
		(fp_line
			(start 5.854954 -1.114298)
			(end 6.79704 -2.018284)
			(stroke
				(width 0.1)
				(type default)
			)
			(layer "F.SilkS")
		)
		(fp_line
			(start 5.860542 -4.467098)
			(end 5.84835 -4.397502)
			(stroke
				(width 0.1)
				(type default)
			)
			(layer "F.SilkS")
		)
		(fp_line
			(start 5.860542 -4.467098)
			(end 5.84835 -4.397502)
			(stroke
				(width 0.1)
				(type default)
			)
			(layer "F.SilkS")
		)
		(fp_line
			(start 5.872734 -4.53644)
			(end 5.860542 -4.467098)
			(stroke
				(width 0.1)
				(type default)
			)
			(layer "F.SilkS")
		)
		(fp_line
			(start 5.872734 -4.53644)
			(end 5.860542 -4.467098)
			(stroke
				(width 0.1)
				(type default)
			)
			(layer "F.SilkS")
		)
		(fp_line
			(start 5.872734 -4.53644)
			(end 5.884926 -4.605782)
			(stroke
				(width 0.1)
				(type default)
			)
			(layer "F.SilkS")
		)
		(fp_line
			(start 5.872734 -4.53644)
			(end 5.884926 -4.605782)
			(stroke
				(width 0.1)
				(type default)
			)
			(layer "F.SilkS")
		)
		(fp_line
			(start 5.884926 -4.605782)
			(end 5.897118 -4.675124)
			(stroke
				(width 0.1)
				(type default)
			)
			(layer "F.SilkS")
		)
		(fp_line
			(start 5.884926 -4.605782)
			(end 5.897118 -4.675124)
			(stroke
				(width 0.1)
				(type default)
			)
			(layer "F.SilkS")
		)
		(fp_line
			(start 5.884926 -1.085342)
			(end 6.824726 -1.987042)
			(stroke
				(width 0.1)
				(type default)
			)
			(layer "F.SilkS")
		)
		(fp_line
			(start 5.884926 -1.085342)
			(end 6.824726 -1.987042)
			(stroke
				(width 0.1)
				(type default)
			)
			(layer "F.SilkS")
		)
		(fp_line
			(start 5.897118 -4.675124)
			(end 5.90931 -4.74472)
			(stroke
				(width 0.1)
				(type default)
			)
			(layer "F.SilkS")
		)
		(fp_line
			(start 5.897118 -4.675124)
			(end 5.90931 -4.74472)
			(stroke
				(width 0.1)
				(type default)
			)
			(layer "F.SilkS")
		)
		(fp_line
			(start 5.90931 -4.74472)
			(end 5.921502 -4.814062)
			(stroke
				(width 0.1)
				(type default)
			)
			(layer "F.SilkS")
		)
		(fp_line
			(start 5.90931 -4.74472)
			(end 5.921502 -4.814062)
			(stroke
				(width 0.1)
				(type default)
			)
			(layer "F.SilkS")
		)
		(fp_line
			(start 5.919978 -1.061212)
			(end 6.856222 -1.95961)
			(stroke
				(width 0.1)
				(type default)
			)
			(layer "F.SilkS")
		)
		(fp_line
			(start 5.919978 -1.061212)
			(end 6.856222 -1.95961)
			(stroke
				(width 0.1)
				(type default)
			)
			(layer "F.SilkS")
		)
		(fp_line
			(start 5.921502 -4.814062)
			(end 5.933694 -4.883404)
			(stroke
				(width 0.1)
				(type default)
			)
			(layer "F.SilkS")
		)
		(fp_line
			(start 5.921502 -4.814062)
			(end 5.933694 -4.883404)
			(stroke
				(width 0.1)
				(type default)
			)
			(layer "F.SilkS")
		)
		(fp_line
			(start 5.933694 -4.883404)
			(end 5.945886 -4.952746)
			(stroke
				(width 0.1)
				(type default)
			)
			(layer "F.SilkS")
		)
		(fp_line
			(start 5.933694 -4.883404)
			(end 5.945886 -4.952746)
			(stroke
				(width 0.1)
				(type default)
			)
			(layer "F.SilkS")
		)
		(fp_line
			(start 5.945886 -4.952746)
			(end 5.958078 -5.022088)
			(stroke
				(width 0.1)
				(type default)
			)
			(layer "F.SilkS")
		)
		(fp_line
			(start 5.945886 -4.952746)
			(end 5.958078 -5.022088)
			(stroke
				(width 0.1)
				(type default)
			)
			(layer "F.SilkS")
		)
		(fp_line
			(start 5.955284 -1.03759)
			(end 6.894068 -1.93802)
			(stroke
				(width 0.1)
				(type default)
			)
			(layer "F.SilkS")
		)
		(fp_line
			(start 5.955284 -1.03759)
			(end 6.894068 -1.93802)
			(stroke
				(width 0.1)
				(type default)
			)
			(layer "F.SilkS")
		)
		(fp_line
			(start 5.958078 -5.022088)
			(end 5.97027 -5.091684)
			(stroke
				(width 0.1)
				(type default)
			)
			(layer "F.SilkS")
		)
		(fp_line
			(start 5.958078 -5.022088)
			(end 5.97027 -5.091684)
			(stroke
				(width 0.1)
				(type default)
			)
			(layer "F.SilkS")
		)
		(fp_line
			(start 5.97027 -5.091684)
			(end 5.982208 -5.161026)
			(stroke
				(width 0.1)
				(type default)
			)
			(layer "F.SilkS")
		)
		(fp_line
			(start 5.97027 -5.091684)
			(end 5.982208 -5.161026)
			(stroke
				(width 0.1)
				(type default)
			)
			(layer "F.SilkS")
		)
		(fp_line
			(start 5.98424 -5.171694)
			(end 5.982208 -5.161026)
			(stroke
				(width 0.1)
				(type default)
			)
			(layer "F.SilkS")
		)
		(fp_line
			(start 5.98424 -5.171694)
			(end 5.982208 -5.161026)
			(stroke
				(width 0.1)
				(type default)
			)
			(layer "F.SilkS")
		)
		(fp_line
			(start 5.99059 -1.013714)
			(end 6.93166 -1.91643)
			(stroke
				(width 0.1)
				(type default)
			)
			(layer "F.SilkS")
		)
		(fp_line
			(start 5.99059 -1.013714)
			(end 6.93166 -1.91643)
			(stroke
				(width 0.1)
				(type default)
			)
			(layer "F.SilkS")
		)
		(fp_line
			(start 5.993638 -5.171694)
			(end 5.982208 -5.161026)
			(stroke
				(width 0.1)
				(type default)
			)
			(layer "F.SilkS")
		)
		(fp_line
			(start 5.993638 -5.171694)
			(end 5.982208 -5.161026)
			(stroke
				(width 0.1)
				(type default)
			)
			(layer "F.SilkS")
		)
		(fp_line
			(start 5.993638 -5.171694)
			(end 5.98424 -5.171694)
			(stroke
				(width 0.1)
				(type default)
			)
			(layer "F.SilkS")
		)
		(fp_line
			(start 5.993638 -5.171694)
			(end 5.98424 -5.171694)
			(stroke
				(width 0.1)
				(type default)
			)
			(layer "F.SilkS")
		)
		(fp_line
			(start 6.025642 -0.989584)
			(end 6.973062 -1.898396)
			(stroke
				(width 0.1)
				(type default)
			)
			(layer "F.SilkS")
		)
		(fp_line
			(start 6.025642 -0.989584)
			(end 6.973062 -1.898396)
			(stroke
				(width 0.1)
				(type default)
			)
			(layer "F.SilkS")
		)
		(fp_line
			(start 6.053582 -5.171694)
			(end 5.97027 -5.091684)
			(stroke
				(width 0.1)
				(type default)
			)
			(layer "F.SilkS")
		)
		(fp_line
			(start 6.053582 -5.171694)
			(end 5.97027 -5.091684)
			(stroke
				(width 0.1)
				(type default)
			)
			(layer "F.SilkS")
		)
		(fp_line
			(start 6.053582 -5.171694)
			(end 5.993638 -5.171694)
			(stroke
				(width 0.1)
				(type default)
			)
			(layer "F.SilkS")
		)
		(fp_line
			(start 6.053582 -5.171694)
			(end 5.993638 -5.171694)
			(stroke
				(width 0.1)
				(type default)
			)
			(layer "F.SilkS")
		)
		(fp_line
			(start 6.060948 -0.965962)
			(end 7.020306 -1.88595)
			(stroke
				(width 0.1)
				(type default)
			)
			(layer "F.SilkS")
		)
		(fp_line
			(start 6.060948 -0.965962)
			(end 7.020306 -1.88595)
			(stroke
				(width 0.1)
				(type default)
			)
			(layer "F.SilkS")
		)
		(fp_line
			(start 6.096254 -0.942086)
			(end 7.06755 -1.873504)
			(stroke
				(width 0.1)
				(type default)
			)
			(layer "F.SilkS")
		)
		(fp_line
			(start 6.096254 -0.942086)
			(end 7.06755 -1.873504)
			(stroke
				(width 0.1)
				(type default)
			)
			(layer "F.SilkS")
		)
		(fp_line
			(start 6.11378 -5.171694)
			(end 5.958078 -5.022088)
			(stroke
				(width 0.1)
				(type default)
			)
			(layer "F.SilkS")
		)
		(fp_line
			(start 6.11378 -5.171694)
			(end 5.958078 -5.022088)
			(stroke
				(width 0.1)
				(type default)
			)
			(layer "F.SilkS")
		)
		(fp_line
			(start 6.11378 -5.171694)
			(end 6.053582 -5.171694)
			(stroke
				(width 0.1)
				(type default)
			)
			(layer "F.SilkS")
		)
		(fp_line
			(start 6.11378 -5.171694)
			(end 6.053582 -5.171694)
			(stroke
				(width 0.1)
				(type default)
			)
			(layer "F.SilkS")
		)
		(fp_line
			(start 6.136132 -0.922528)
			(end 7.118604 -1.865122)
			(stroke
				(width 0.1)
				(type default)
			)
			(layer "F.SilkS")
		)
		(fp_line
			(start 6.136132 -0.922528)
			(end 7.118604 -1.865122)
			(stroke
				(width 0.1)
				(type default)
			)
			(layer "F.SilkS")
		)
		(fp_line
			(start 6.173978 -5.171694)
			(end 5.945886 -4.952746)
			(stroke
				(width 0.1)
				(type default)
			)
			(layer "F.SilkS")
		)
		(fp_line
			(start 6.173978 -5.171694)
			(end 5.945886 -4.952746)
			(stroke
				(width 0.1)
				(type default)
			)
			(layer "F.SilkS")
		)
		(fp_line
			(start 6.173978 -5.171694)
			(end 6.11378 -5.171694)
			(stroke
				(width 0.1)
				(type default)
			)
			(layer "F.SilkS")
		)
		(fp_line
			(start 6.173978 -5.171694)
			(end 6.11378 -5.171694)
			(stroke
				(width 0.1)
				(type default)
			)
			(layer "F.SilkS")
		)
		(fp_line
			(start 6.180836 -0.907796)
			(end 7.174738 -1.861058)
			(stroke
				(width 0.1)
				(type default)
			)
			(layer "F.SilkS")
		)
		(fp_line
			(start 6.180836 -0.907796)
			(end 7.174738 -1.861058)
			(stroke
				(width 0.1)
				(type default)
			)
			(layer "F.SilkS")
		)
		(fp_line
			(start 6.225794 -0.89281)
			(end 7.231126 -1.857248)
			(stroke
				(width 0.1)
				(type default)
			)
			(layer "F.SilkS")
		)
		(fp_line
			(start 6.225794 -0.89281)
			(end 7.231126 -1.857248)
			(stroke
				(width 0.1)
				(type default)
			)
			(layer "F.SilkS")
		)
		(fp_line
			(start 6.234176 -5.171694)
			(end 5.933694 -4.883404)
			(stroke
				(width 0.1)
				(type default)
			)
			(layer "F.SilkS")
		)
		(fp_line
			(start 6.234176 -5.171694)
			(end 5.933694 -4.883404)
			(stroke
				(width 0.1)
				(type default)
			)
			(layer "F.SilkS")
		)
		(fp_line
			(start 6.234176 -5.171694)
			(end 6.173978 -5.171694)
			(stroke
				(width 0.1)
				(type default)
			)
			(layer "F.SilkS")
		)
		(fp_line
			(start 6.234176 -5.171694)
			(end 6.173978 -5.171694)
			(stroke
				(width 0.1)
				(type default)
			)
			(layer "F.SilkS")
		)
		(fp_line
			(start 6.270752 -0.878332)
			(end 7.291832 -1.857756)
			(stroke
				(width 0.1)
				(type default)
			)
			(layer "F.SilkS")
		)
		(fp_line
			(start 6.270752 -0.878332)
			(end 7.291832 -1.857756)
			(stroke
				(width 0.1)
				(type default)
			)
			(layer "F.SilkS")
		)
		(fp_line
			(start 6.294374 -5.171694)
			(end 5.921502 -4.814062)
			(stroke
				(width 0.1)
				(type default)
			)
			(layer "F.SilkS")
		)
		(fp_line
			(start 6.294374 -5.171694)
			(end 5.921502 -4.814062)
			(stroke
				(width 0.1)
				(type default)
			)
			(layer "F.SilkS")
		)
		(fp_line
			(start 6.294374 -5.171694)
			(end 6.234176 -5.171694)
			(stroke
				(width 0.1)
				(type default)
			)
			(layer "F.SilkS")
		)
		(fp_line
			(start 6.294374 -5.171694)
			(end 6.234176 -5.171694)
			(stroke
				(width 0.1)
				(type default)
			)
			(layer "F.SilkS")
		)
		(fp_line
			(start 6.315456 -0.8636)
			(end 7.356348 -1.862074)
			(stroke
				(width 0.1)
				(type default)
			)
			(layer "F.SilkS")
		)
		(fp_line
			(start 6.315456 -0.8636)
			(end 7.356348 -1.862074)
			(stroke
				(width 0.1)
				(type default)
			)
			(layer "F.SilkS")
		)
		(fp_line
			(start 6.354318 -5.171694)
			(end 5.90931 -4.74472)
			(stroke
				(width 0.1)
				(type default)
			)
			(layer "F.SilkS")
		)
		(fp_line
			(start 6.354318 -5.171694)
			(end 5.90931 -4.74472)
			(stroke
				(width 0.1)
				(type default)
			)
			(layer "F.SilkS")
		)
		(fp_line
			(start 6.354318 -5.171694)
			(end 6.294374 -5.171694)
			(stroke
				(width 0.1)
				(type default)
			)
			(layer "F.SilkS")
		)
		(fp_line
			(start 6.354318 -5.171694)
			(end 6.294374 -5.171694)
			(stroke
				(width 0.1)
				(type default)
			)
			(layer "F.SilkS")
		)
		(fp_line
			(start 6.36016 -0.848868)
			(end 7.421118 -1.866392)
			(stroke
				(width 0.1)
				(type default)
			)
			(layer "F.SilkS")
		)
		(fp_line
			(start 6.36016 -0.848868)
			(end 7.421118 -1.866392)
			(stroke
				(width 0.1)
				(type default)
			)
			(layer "F.SilkS")
		)
		(fp_line
			(start 6.405118 -0.833882)
			(end 7.500366 -1.884934)
			(stroke
				(width 0.1)
				(type default)
			)
			(layer "F.SilkS")
		)
		(fp_line
			(start 6.405118 -0.833882)
			(end 7.500366 -1.884934)
			(stroke
				(width 0.1)
				(type default)
			)
			(layer "F.SilkS")
		)
		(fp_line
			(start 6.41477 -5.171694)
			(end 5.897118 -4.675124)
			(stroke
				(width 0.1)
				(type default)
			)
			(layer "F.SilkS")
		)
		(fp_line
			(start 6.41477 -5.171694)
			(end 5.897118 -4.675124)
			(stroke
				(width 0.1)
				(type default)
			)
			(layer "F.SilkS")
		)
		(fp_line
			(start 6.41477 -5.171694)
			(end 6.354318 -5.171694)
			(stroke
				(width 0.1)
				(type default)
			)
			(layer "F.SilkS")
		)
		(fp_line
			(start 6.41477 -5.171694)
			(end 6.354318 -5.171694)
			(stroke
				(width 0.1)
				(type default)
			)
			(layer "F.SilkS")
		)
		(fp_line
			(start 6.455664 -0.824738)
			(end 7.582662 -1.906016)
			(stroke
				(width 0.1)
				(type default)
			)
			(layer "F.SilkS")
		)
		(fp_line
			(start 6.455664 -0.824738)
			(end 7.582662 -1.906016)
			(stroke
				(width 0.1)
				(type default)
			)
			(layer "F.SilkS")
		)
		(fp_line
			(start 6.474714 -5.171694)
			(end 5.884926 -4.605782)
			(stroke
				(width 0.1)
				(type default)
			)
			(layer "F.SilkS")
		)
		(fp_line
			(start 6.474714 -5.171694)
			(end 5.884926 -4.605782)
			(stroke
				(width 0.1)
				(type default)
			)
			(layer "F.SilkS")
		)
		(fp_line
			(start 6.474714 -5.171694)
			(end 6.41477 -5.171694)
			(stroke
				(width 0.1)
				(type default)
			)
			(layer "F.SilkS")
		)
		(fp_line
			(start 6.474714 -5.171694)
			(end 6.41477 -5.171694)
			(stroke
				(width 0.1)
				(type default)
			)
			(layer "F.SilkS")
		)
		(fp_line
			(start 6.510528 -0.819912)
			(end 7.699756 -1.96088)
			(stroke
				(width 0.1)
				(type default)
			)
			(layer "F.SilkS")
		)
		(fp_line
			(start 6.510528 -0.819912)
			(end 7.699756 -1.96088)
			(stroke
				(width 0.1)
				(type default)
			)
			(layer "F.SilkS")
		)
		(fp_line
			(start 6.534912 -5.171694)
			(end 5.872734 -4.53644)
			(stroke
				(width 0.1)
				(type default)
			)
			(layer "F.SilkS")
		)
		(fp_line
			(start 6.534912 -5.171694)
			(end 5.872734 -4.53644)
			(stroke
				(width 0.1)
				(type default)
			)
			(layer "F.SilkS")
		)
		(fp_line
			(start 6.534912 -5.171694)
			(end 6.474714 -5.171694)
			(stroke
				(width 0.1)
				(type default)
			)
			(layer "F.SilkS")
		)
		(fp_line
			(start 6.534912 -5.171694)
			(end 6.474714 -5.171694)
			(stroke
				(width 0.1)
				(type default)
			)
			(layer "F.SilkS")
		)
		(fp_line
			(start 6.59511 -5.171694)
			(end 5.860542 -4.467098)
			(stroke
				(width 0.1)
				(type default)
			)
			(layer "F.SilkS")
		)
		(fp_line
			(start 6.59511 -5.171694)
			(end 5.860542 -4.467098)
			(stroke
				(width 0.1)
				(type default)
			)
			(layer "F.SilkS")
		)
		(fp_line
			(start 6.59511 -5.171694)
			(end 6.534912 -5.171694)
			(stroke
				(width 0.1)
				(type default)
			)
			(layer "F.SilkS")
		)
		(fp_line
			(start 6.59511 -5.171694)
			(end 6.534912 -5.171694)
			(stroke
				(width 0.1)
				(type default)
			)
			(layer "F.SilkS")
		)
		(fp_line
			(start 6.620256 -0.809498)
			(end 9.404096 -3.480054)
			(stroke
				(width 0.1)
				(type default)
			)
			(layer "F.SilkS")
		)
		(fp_line
			(start 6.620256 -0.809498)
			(end 9.404096 -3.480054)
			(stroke
				(width 0.1)
				(type default)
			)
			(layer "F.SilkS")
		)
		(fp_line
			(start 6.655308 -5.171694)
			(end 5.84835 -4.397502)
			(stroke
				(width 0.1)
				(type default)
			)
			(layer "F.SilkS")
		)
		(fp_line
			(start 6.655308 -5.171694)
			(end 5.84835 -4.397502)
			(stroke
				(width 0.1)
				(type default)
			)
			(layer "F.SilkS")
		)
		(fp_line
			(start 6.655308 -5.171694)
			(end 6.59511 -5.171694)
			(stroke
				(width 0.1)
				(type default)
			)
			(layer "F.SilkS")
		)
		(fp_line
			(start 6.655308 -5.171694)
			(end 6.59511 -5.171694)
			(stroke
				(width 0.1)
				(type default)
			)
			(layer "F.SilkS")
		)
		(fp_line
			(start 6.67512 -0.804672)
			(end 9.391904 -3.410712)
			(stroke
				(width 0.1)
				(type default)
			)
			(layer "F.SilkS")
		)
		(fp_line
			(start 6.67512 -0.804672)
			(end 9.391904 -3.410712)
			(stroke
				(width 0.1)
				(type default)
			)
			(layer "F.SilkS")
		)
		(fp_line
			(start 6.703822 -2.852166)
			(end 6.716014 -2.921254)
			(stroke
				(width 0.1)
				(type default)
			)
			(layer "F.SilkS")
		)
		(fp_line
			(start 6.703822 -2.852166)
			(end 6.716014 -2.921254)
			(stroke
				(width 0.1)
				(type default)
			)
			(layer "F.SilkS")
		)
		(fp_line
			(start 6.715506 -5.171694)
			(end 5.836158 -4.328414)
			(stroke
				(width 0.1)
				(type default)
			)
			(layer "F.SilkS")
		)
		(fp_line
			(start 6.715506 -5.171694)
			(end 5.836158 -4.328414)
			(stroke
				(width 0.1)
				(type default)
			)
			(layer "F.SilkS")
		)
		(fp_line
			(start 6.715506 -5.171694)
			(end 6.655308 -5.171694)
			(stroke
				(width 0.1)
				(type default)
			)
			(layer "F.SilkS")
		)
		(fp_line
			(start 6.715506 -5.171694)
			(end 6.655308 -5.171694)
			(stroke
				(width 0.1)
				(type default)
			)
			(layer "F.SilkS")
		)
		(fp_line
			(start 6.716014 -2.921254)
			(end 6.728206 -2.99085)
			(stroke
				(width 0.1)
				(type default)
			)
			(layer "F.SilkS")
		)
		(fp_line
			(start 6.716014 -2.921254)
			(end 6.728206 -2.99085)
			(stroke
				(width 0.1)
				(type default)
			)
			(layer "F.SilkS")
		)
		(fp_line
			(start 6.728206 -2.99085)
			(end 6.740144 -3.060192)
			(stroke
				(width 0.1)
				(type default)
			)
			(layer "F.SilkS")
		)
		(fp_line
			(start 6.728206 -2.99085)
			(end 6.740144 -3.060192)
			(stroke
				(width 0.1)
				(type default)
			)
			(layer "F.SilkS")
		)
		(fp_line
			(start 6.729984 -0.799592)
			(end 9.379712 -3.34137)
			(stroke
				(width 0.1)
				(type default)
			)
			(layer "F.SilkS")
		)
		(fp_line
			(start 6.729984 -0.799592)
			(end 9.379712 -3.34137)
			(stroke
				(width 0.1)
				(type default)
			)
			(layer "F.SilkS")
		)
		(fp_line
			(start 6.740144 -3.060192)
			(end 6.75259 -3.129534)
			(stroke
				(width 0.1)
				(type default)
			)
			(layer "F.SilkS")
		)
		(fp_line
			(start 6.740144 -3.060192)
			(end 6.75259 -3.129534)
			(stroke
				(width 0.1)
				(type default)
			)
			(layer "F.SilkS")
		)
		(fp_line
			(start 6.75259 -3.129534)
			(end 6.764782 -3.19913)
			(stroke
				(width 0.1)
				(type default)
			)
			(layer "F.SilkS")
		)
		(fp_line
			(start 6.75259 -3.129534)
			(end 6.764782 -3.19913)
			(stroke
				(width 0.1)
				(type default)
			)
			(layer "F.SilkS")
		)
		(fp_line
			(start 6.764782 -3.19913)
			(end 6.776974 -3.268472)
			(stroke
				(width 0.1)
				(type default)
			)
			(layer "F.SilkS")
		)
		(fp_line
			(start 6.764782 -3.19913)
			(end 6.776974 -3.268472)
			(stroke
				(width 0.1)
				(type default)
			)
			(layer "F.SilkS")
		)
		(fp_line
			(start 6.77545 -5.171694)
			(end 5.823966 -4.258818)
			(stroke
				(width 0.1)
				(type default)
			)
			(layer "F.SilkS")
		)
		(fp_line
			(start 6.77545 -5.171694)
			(end 5.823966 -4.258818)
			(stroke
				(width 0.1)
				(type default)
			)
			(layer "F.SilkS")
		)
		(fp_line
			(start 6.77545 -5.171694)
			(end 6.715506 -5.171694)
			(stroke
				(width 0.1)
				(type default)
			)
			(layer "F.SilkS")
		)
		(fp_line
			(start 6.77545 -5.171694)
			(end 6.715506 -5.171694)
			(stroke
				(width 0.1)
				(type default)
			)
			(layer "F.SilkS")
		)
		(fp_line
			(start 6.776974 -3.268472)
			(end 6.788912 -3.337814)
			(stroke
				(width 0.1)
				(type default)
			)
			(layer "F.SilkS")
		)
		(fp_line
			(start 6.776974 -3.268472)
			(end 6.788912 -3.337814)
			(stroke
				(width 0.1)
				(type default)
			)
			(layer "F.SilkS")
		)
		(fp_line
			(start 6.784848 -0.794258)
			(end 9.36752 -3.272028)
			(stroke
				(width 0.1)
				(type default)
			)
			(layer "F.SilkS")
		)
		(fp_line
			(start 6.784848 -0.794258)
			(end 9.36752 -3.272028)
			(stroke
				(width 0.1)
				(type default)
			)
			(layer "F.SilkS")
		)
		(fp_line
			(start 6.788912 -3.337814)
			(end 6.801104 -3.407156)
			(stroke
				(width 0.1)
				(type default)
			)
			(layer "F.SilkS")
		)
		(fp_line
			(start 6.788912 -3.337814)
			(end 6.801104 -3.407156)
			(stroke
				(width 0.1)
				(type default)
			)
			(layer "F.SilkS")
		)
		(fp_line
			(start 6.801104 -3.407156)
			(end 6.81355 -3.476498)
			(stroke
				(width 0.1)
				(type default)
			)
			(layer "F.SilkS")
		)
		(fp_line
			(start 6.801104 -3.407156)
			(end 6.81355 -3.476498)
			(stroke
				(width 0.1)
				(type default)
			)
			(layer "F.SilkS")
		)
		(fp_line
			(start 6.825488 -3.54584)
			(end 6.81355 -3.476498)
			(stroke
				(width 0.1)
				(type default)
			)
			(layer "F.SilkS")
		)
		(fp_line
			(start 6.825488 -3.54584)
			(end 6.81355 -3.476498)
			(stroke
				(width 0.1)
				(type default)
			)
			(layer "F.SilkS")
		)
		(fp_line
			(start 6.825488 -3.54584)
			(end 6.83768 -3.615436)
			(stroke
				(width 0.1)
				(type default)
			)
			(layer "F.SilkS")
		)
		(fp_line
			(start 6.825488 -3.54584)
			(end 6.83768 -3.615436)
			(stroke
				(width 0.1)
				(type default)
			)
			(layer "F.SilkS")
		)
		(fp_line
			(start 6.835648 -5.171694)
			(end 5.811774 -4.189476)
			(stroke
				(width 0.1)
				(type default)
			)
			(layer "F.SilkS")
		)
		(fp_line
			(start 6.835648 -5.171694)
			(end 5.811774 -4.189476)
			(stroke
				(width 0.1)
				(type default)
			)
			(layer "F.SilkS")
		)
		(fp_line
			(start 6.835648 -5.171694)
			(end 6.77545 -5.171694)
			(stroke
				(width 0.1)
				(type default)
			)
			(layer "F.SilkS")
		)
		(fp_line
			(start 6.835648 -5.171694)
			(end 6.77545 -5.171694)
			(stroke
				(width 0.1)
				(type default)
			)
			(layer "F.SilkS")
		)
		(fp_line
			(start 6.83768 -3.615436)
			(end 5.509514 -2.341372)
			(stroke
				(width 0.1)
				(type default)
			)
			(layer "F.SilkS")
		)
		(fp_line
			(start 6.83768 -3.615436)
			(end 5.509514 -2.341372)
			(stroke
				(width 0.1)
				(type default)
			)
			(layer "F.SilkS")
		)
		(fp_line
			(start 6.83768 -3.615436)
			(end 6.849872 -3.684778)
			(stroke
				(width 0.1)
				(type default)
			)
			(layer "F.SilkS")
		)
		(fp_line
			(start 6.83768 -3.615436)
			(end 6.849872 -3.684778)
			(stroke
				(width 0.1)
				(type default)
			)
			(layer "F.SilkS")
		)
		(fp_line
			(start 6.848348 -0.797814)
			(end 9.355328 -3.202432)
			(stroke
				(width 0.1)
				(type default)
			)
			(layer "F.SilkS")
		)
		(fp_line
			(start 6.848348 -0.797814)
			(end 9.355328 -3.202432)
			(stroke
				(width 0.1)
				(type default)
			)
			(layer "F.SilkS")
		)
		(fp_line
			(start 6.849872 -3.684778)
			(end 5.517642 -2.40665)
			(stroke
				(width 0.1)
				(type default)
			)
			(layer "F.SilkS")
		)
		(fp_line
			(start 6.849872 -3.684778)
			(end 5.517642 -2.40665)
			(stroke
				(width 0.1)
				(type default)
			)
			(layer "F.SilkS")
		)
		(fp_line
			(start 6.849872 -3.684778)
			(end 6.862318 -3.75412)
			(stroke
				(width 0.1)
				(type default)
			)
			(layer "F.SilkS")
		)
		(fp_line
			(start 6.849872 -3.684778)
			(end 6.862318 -3.75412)
			(stroke
				(width 0.1)
				(type default)
			)
			(layer "F.SilkS")
		)
		(fp_line
			(start 6.862318 -3.75412)
			(end 5.525516 -2.471928)
			(stroke
				(width 0.1)
				(type default)
			)
			(layer "F.SilkS")
		)
		(fp_line
			(start 6.862318 -3.75412)
			(end 5.525516 -2.471928)
			(stroke
				(width 0.1)
				(type default)
			)
			(layer "F.SilkS")
		)
		(fp_line
			(start 6.862318 -3.75412)
			(end 6.874256 -3.823716)
			(stroke
				(width 0.1)
				(type default)
			)
			(layer "F.SilkS")
		)
		(fp_line
			(start 6.862318 -3.75412)
			(end 6.874256 -3.823716)
			(stroke
				(width 0.1)
				(type default)
			)
			(layer "F.SilkS")
		)
		(fp_line
			(start 6.874256 -3.823716)
			(end 5.53339 -2.537206)
			(stroke
				(width 0.1)
				(type default)
			)
			(layer "F.SilkS")
		)
		(fp_line
			(start 6.874256 -3.823716)
			(end 5.53339 -2.537206)
			(stroke
				(width 0.1)
				(type default)
			)
			(layer "F.SilkS")
		)
		(fp_line
			(start 6.874256 -3.823716)
			(end 6.886448 -3.893058)
			(stroke
				(width 0.1)
				(type default)
			)
			(layer "F.SilkS")
		)
		(fp_line
			(start 6.874256 -3.823716)
			(end 6.886448 -3.893058)
			(stroke
				(width 0.1)
				(type default)
			)
			(layer "F.SilkS")
		)
		(fp_line
			(start 6.886448 -3.893058)
			(end 5.541264 -2.602738)
			(stroke
				(width 0.1)
				(type default)
			)
			(layer "F.SilkS")
		)
		(fp_line
			(start 6.886448 -3.893058)
			(end 5.541264 -2.602738)
			(stroke
				(width 0.1)
				(type default)
			)
			(layer "F.SilkS")
		)
		(fp_line
			(start 6.886448 -3.893058)
			(end 6.89864 -3.9624)
			(stroke
				(width 0.1)
				(type default)
			)
			(layer "F.SilkS")
		)
		(fp_line
			(start 6.886448 -3.893058)
			(end 6.89864 -3.9624)
			(stroke
				(width 0.1)
				(type default)
			)
			(layer "F.SilkS")
		)
		(fp_line
			(start 6.895846 -5.171694)
			(end 5.799582 -4.11988)
			(stroke
				(width 0.1)
				(type default)
			)
			(layer "F.SilkS")
		)
		(fp_line
			(start 6.895846 -5.171694)
			(end 5.799582 -4.11988)
			(stroke
				(width 0.1)
				(type default)
			)
			(layer "F.SilkS")
		)
		(fp_line
			(start 6.895846 -5.171694)
			(end 6.835648 -5.171694)
			(stroke
				(width 0.1)
				(type default)
			)
			(layer "F.SilkS")
		)
		(fp_line
			(start 6.895846 -5.171694)
			(end 6.835648 -5.171694)
			(stroke
				(width 0.1)
				(type default)
			)
			(layer "F.SilkS")
		)
		(fp_line
			(start 6.89864 -3.9624)
			(end 5.549392 -2.668016)
			(stroke
				(width 0.1)
				(type default)
			)
			(layer "F.SilkS")
		)
		(fp_line
			(start 6.89864 -3.9624)
			(end 5.549392 -2.668016)
			(stroke
				(width 0.1)
				(type default)
			)
			(layer "F.SilkS")
		)
		(fp_line
			(start 6.89864 -3.9624)
			(end 6.910832 -4.031742)
			(stroke
				(width 0.1)
				(type default)
			)
			(layer "F.SilkS")
		)
		(fp_line
			(start 6.89864 -3.9624)
			(end 6.910832 -4.031742)
			(stroke
				(width 0.1)
				(type default)
			)
			(layer "F.SilkS")
		)
		(fp_line
			(start 6.910832 -4.031742)
			(end 5.557266 -2.733294)
			(stroke
				(width 0.1)
				(type default)
			)
			(layer "F.SilkS")
		)
		(fp_line
			(start 6.910832 -4.031742)
			(end 5.557266 -2.733294)
			(stroke
				(width 0.1)
				(type default)
			)
			(layer "F.SilkS")
		)
		(fp_line
			(start 6.910832 -4.031742)
			(end 6.923024 -4.101084)
			(stroke
				(width 0.1)
				(type default)
			)
			(layer "F.SilkS")
		)
		(fp_line
			(start 6.910832 -4.031742)
			(end 6.923024 -4.101084)
			(stroke
				(width 0.1)
				(type default)
			)
			(layer "F.SilkS")
		)
		(fp_line
			(start 6.914896 -0.80391)
			(end 9.343136 -3.13309)
			(stroke
				(width 0.1)
				(type default)
			)
			(layer "F.SilkS")
		)
		(fp_line
			(start 6.914896 -0.80391)
			(end 9.343136 -3.13309)
			(stroke
				(width 0.1)
				(type default)
			)
			(layer "F.SilkS")
		)
		(fp_line
			(start 6.923024 -4.101084)
			(end 5.568188 -2.801366)
			(stroke
				(width 0.1)
				(type default)
			)
			(layer "F.SilkS")
		)
		(fp_line
			(start 6.923024 -4.101084)
			(end 5.568188 -2.801366)
			(stroke
				(width 0.1)
				(type default)
			)
			(layer "F.SilkS")
		)
		(fp_line
			(start 6.923024 -4.101084)
			(end 6.935216 -4.170426)
			(stroke
				(width 0.1)
				(type default)
			)
			(layer "F.SilkS")
		)
		(fp_line
			(start 6.923024 -4.101084)
			(end 6.935216 -4.170426)
			(stroke
				(width 0.1)
				(type default)
			)
			(layer "F.SilkS")
		)
		(fp_line
			(start 6.935216 -4.170426)
			(end 5.58038 -2.870962)
			(stroke
				(width 0.1)
				(type default)
			)
			(layer "F.SilkS")
		)
		(fp_line
			(start 6.935216 -4.170426)
			(end 5.58038 -2.870962)
			(stroke
				(width 0.1)
				(type default)
			)
			(layer "F.SilkS")
		)
		(fp_line
			(start 6.935216 -4.170426)
			(end 6.947408 -4.240022)
			(stroke
				(width 0.1)
				(type default)
			)
			(layer "F.SilkS")
		)
		(fp_line
			(start 6.935216 -4.170426)
			(end 6.947408 -4.240022)
			(stroke
				(width 0.1)
				(type default)
			)
			(layer "F.SilkS")
		)
		(fp_line
			(start 6.947408 -4.240022)
			(end 5.592572 -2.940304)
			(stroke
				(width 0.1)
				(type default)
			)
			(layer "F.SilkS")
		)
		(fp_line
			(start 6.947408 -4.240022)
			(end 5.592572 -2.940304)
			(stroke
				(width 0.1)
				(type default)
			)
			(layer "F.SilkS")
		)
		(fp_line
			(start 6.947408 -4.240022)
			(end 6.9596 -4.309364)
			(stroke
				(width 0.1)
				(type default)
			)
			(layer "F.SilkS")
		)
		(fp_line
			(start 6.947408 -4.240022)
			(end 6.9596 -4.309364)
			(stroke
				(width 0.1)
				(type default)
			)
			(layer "F.SilkS")
		)
		(fp_line
			(start 6.956044 -5.171694)
			(end 5.78739 -4.050538)
			(stroke
				(width 0.1)
				(type default)
			)
			(layer "F.SilkS")
		)
		(fp_line
			(start 6.956044 -5.171694)
			(end 5.78739 -4.050538)
			(stroke
				(width 0.1)
				(type default)
			)
			(layer "F.SilkS")
		)
		(fp_line
			(start 6.956044 -5.171694)
			(end 6.895846 -5.171694)
			(stroke
				(width 0.1)
				(type default)
			)
			(layer "F.SilkS")
		)
		(fp_line
			(start 6.956044 -5.171694)
			(end 6.895846 -5.171694)
			(stroke
				(width 0.1)
				(type default)
			)
			(layer "F.SilkS")
		)
		(fp_line
			(start 6.9596 -4.309364)
			(end 5.604764 -3.009646)
			(stroke
				(width 0.1)
				(type default)
			)
			(layer "F.SilkS")
		)
		(fp_line
			(start 6.9596 -4.309364)
			(end 5.604764 -3.009646)
			(stroke
				(width 0.1)
				(type default)
			)
			(layer "F.SilkS")
		)
		(fp_line
			(start 6.9596 -4.309364)
			(end 6.971792 -4.378706)
			(stroke
				(width 0.1)
				(type default)
			)
			(layer "F.SilkS")
		)
		(fp_line
			(start 6.9596 -4.309364)
			(end 6.971792 -4.378706)
			(stroke
				(width 0.1)
				(type default)
			)
			(layer "F.SilkS")
		)
		(fp_line
			(start 6.971792 -4.378706)
			(end 5.616956 -3.079242)
			(stroke
				(width 0.1)
				(type default)
			)
			(layer "F.SilkS")
		)
		(fp_line
			(start 6.971792 -4.378706)
			(end 5.616956 -3.079242)
			(stroke
				(width 0.1)
				(type default)
			)
			(layer "F.SilkS")
		)
		(fp_line
			(start 6.971792 -4.378706)
			(end 6.983984 -4.448302)
			(stroke
				(width 0.1)
				(type default)
			)
			(layer "F.SilkS")
		)
		(fp_line
			(start 6.971792 -4.378706)
			(end 6.983984 -4.448302)
			(stroke
				(width 0.1)
				(type default)
			)
			(layer "F.SilkS")
		)
		(fp_line
			(start 6.981444 -0.809752)
			(end 9.330944 -3.063748)
			(stroke
				(width 0.1)
				(type default)
			)
			(layer "F.SilkS")
		)
		(fp_line
			(start 6.981444 -0.809752)
			(end 9.330944 -3.063748)
			(stroke
				(width 0.1)
				(type default)
			)
			(layer "F.SilkS")
		)
		(fp_line
			(start 6.983984 -4.448302)
			(end 5.629148 -3.148584)
			(stroke
				(width 0.1)
				(type default)
			)
			(layer "F.SilkS")
		)
		(fp_line
			(start 6.983984 -4.448302)
			(end 5.629148 -3.148584)
			(stroke
				(width 0.1)
				(type default)
			)
			(layer "F.SilkS")
		)
		(fp_line
			(start 6.983984 -4.448302)
			(end 6.996176 -4.51739)
			(stroke
				(width 0.1)
				(type default)
			)
			(layer "F.SilkS")
		)
		(fp_line
			(start 6.983984 -4.448302)
			(end 6.996176 -4.51739)
			(stroke
				(width 0.1)
				(type default)
			)
			(layer "F.SilkS")
		)
		(fp_line
			(start 6.996176 -4.51739)
			(end 5.64134 -3.217926)
			(stroke
				(width 0.1)
				(type default)
			)
			(layer "F.SilkS")
		)
		(fp_line
			(start 6.996176 -4.51739)
			(end 5.64134 -3.217926)
			(stroke
				(width 0.1)
				(type default)
			)
			(layer "F.SilkS")
		)
		(fp_line
			(start 6.996176 -4.51739)
			(end 7.008368 -4.586986)
			(stroke
				(width 0.1)
				(type default)
			)
			(layer "F.SilkS")
		)
		(fp_line
			(start 6.996176 -4.51739)
			(end 7.008368 -4.586986)
			(stroke
				(width 0.1)
				(type default)
			)
			(layer "F.SilkS")
		)
		(fp_line
			(start 7.008368 -4.586986)
			(end 5.653532 -3.287268)
			(stroke
				(width 0.1)
				(type default)
			)
			(layer "F.SilkS")
		)
		(fp_line
			(start 7.008368 -4.586986)
			(end 5.653532 -3.287268)
			(stroke
				(width 0.1)
				(type default)
			)
			(layer "F.SilkS")
		)
		(fp_line
			(start 7.008368 -4.586986)
			(end 7.02056 -4.656328)
			(stroke
				(width 0.1)
				(type default)
			)
			(layer "F.SilkS")
		)
		(fp_line
			(start 7.008368 -4.586986)
			(end 7.02056 -4.656328)
			(stroke
				(width 0.1)
				(type default)
			)
			(layer "F.SilkS")
		)
		(fp_line
			(start 7.016242 -5.171694)
			(end 5.775198 -3.98145)
			(stroke
				(width 0.1)
				(type default)
			)
			(layer "F.SilkS")
		)
		(fp_line
			(start 7.016242 -5.171694)
			(end 5.775198 -3.98145)
			(stroke
				(width 0.1)
				(type default)
			)
			(layer "F.SilkS")
		)
		(fp_line
			(start 7.016242 -5.171694)
			(end 6.956044 -5.171694)
			(stroke
				(width 0.1)
				(type default)
			)
			(layer "F.SilkS")
		)
		(fp_line
			(start 7.016242 -5.171694)
			(end 6.956044 -5.171694)
			(stroke
				(width 0.1)
				(type default)
			)
			(layer "F.SilkS")
		)
		(fp_line
			(start 7.02056 -4.656328)
			(end 5.665724 -3.35661)
			(stroke
				(width 0.1)
				(type default)
			)
			(layer "F.SilkS")
		)
		(fp_line
			(start 7.02056 -4.656328)
			(end 5.665724 -3.35661)
			(stroke
				(width 0.1)
				(type default)
			)
			(layer "F.SilkS")
		)
		(fp_line
			(start 7.02056 -4.656328)
			(end 7.032752 -4.725924)
			(stroke
				(width 0.1)
				(type default)
			)
			(layer "F.SilkS")
		)
		(fp_line
			(start 7.02056 -4.656328)
			(end 7.032752 -4.725924)
			(stroke
				(width 0.1)
				(type default)
			)
			(layer "F.SilkS")
		)
		(fp_line
			(start 7.032752 -4.725924)
			(end 5.677662 -3.425952)
			(stroke
				(width 0.1)
				(type default)
			)
			(layer "F.SilkS")
		)
		(fp_line
			(start 7.032752 -4.725924)
			(end 5.677662 -3.425952)
			(stroke
				(width 0.1)
				(type default)
			)
			(layer "F.SilkS")
		)
		(fp_line
			(start 7.032752 -4.725924)
			(end 7.04469 -4.795012)
			(stroke
				(width 0.1)
				(type default)
			)
			(layer "F.SilkS")
		)
		(fp_line
			(start 7.032752 -4.725924)
			(end 7.04469 -4.795012)
			(stroke
				(width 0.1)
				(type default)
			)
			(layer "F.SilkS")
		)
		(fp_line
			(start 7.04469 -4.795012)
			(end 5.690108 -3.495548)
			(stroke
				(width 0.1)
				(type default)
			)
			(layer "F.SilkS")
		)
		(fp_line
			(start 7.04469 -4.795012)
			(end 5.690108 -3.495548)
			(stroke
				(width 0.1)
				(type default)
			)
			(layer "F.SilkS")
		)
		(fp_line
			(start 7.04469 -4.795012)
			(end 7.057136 -4.864354)
			(stroke
				(width 0.1)
				(type default)
			)
			(layer "F.SilkS")
		)
		(fp_line
			(start 7.04469 -4.795012)
			(end 7.057136 -4.864354)
			(stroke
				(width 0.1)
				(type default)
			)
			(layer "F.SilkS")
		)
		(fp_line
			(start 7.047992 -0.816102)
			(end 9.318752 -2.994406)
			(stroke
				(width 0.1)
				(type default)
			)
			(layer "F.SilkS")
		)
		(fp_line
			(start 7.047992 -0.816102)
			(end 9.318752 -2.994406)
			(stroke
				(width 0.1)
				(type default)
			)
			(layer "F.SilkS")
		)
		(fp_line
			(start 7.057136 -4.864354)
			(end 5.7023 -3.56489)
			(stroke
				(width 0.1)
				(type default)
			)
			(layer "F.SilkS")
		)
		(fp_line
			(start 7.057136 -4.864354)
			(end 5.7023 -3.56489)
			(stroke
				(width 0.1)
				(type default)
			)
			(layer "F.SilkS")
		)
		(fp_line
			(start 7.057136 -4.864354)
			(end 7.069328 -4.93395)
			(stroke
				(width 0.1)
				(type default)
			)
			(layer "F.SilkS")
		)
		(fp_line
			(start 7.057136 -4.864354)
			(end 7.069328 -4.93395)
			(stroke
				(width 0.1)
				(type default)
			)
			(layer "F.SilkS")
		)
		(fp_line
			(start 7.069328 -4.93395)
			(end 5.714238 -3.634232)
			(stroke
				(width 0.1)
				(type default)
			)
			(layer "F.SilkS")
		)
		(fp_line
			(start 7.069328 -4.93395)
			(end 5.714238 -3.634232)
			(stroke
				(width 0.1)
				(type default)
			)
			(layer "F.SilkS")
		)
		(fp_line
			(start 7.069328 -4.93395)
			(end 7.081266 -5.003292)
			(stroke
				(width 0.1)
				(type default)
			)
			(layer "F.SilkS")
		)
		(fp_line
			(start 7.069328 -4.93395)
			(end 7.081266 -5.003292)
			(stroke
				(width 0.1)
				(type default)
			)
			(layer "F.SilkS")
		)
		(fp_line
			(start 7.07644 -5.171694)
			(end 5.763006 -3.911854)
			(stroke
				(width 0.1)
				(type default)
			)
			(layer "F.SilkS")
		)
		(fp_line
			(start 7.07644 -5.171694)
			(end 5.763006 -3.911854)
			(stroke
				(width 0.1)
				(type default)
			)
			(layer "F.SilkS")
		)
		(fp_line
			(start 7.07644 -5.171694)
			(end 7.016242 -5.171694)
			(stroke
				(width 0.1)
				(type default)
			)
			(layer "F.SilkS")
		)
		(fp_line
			(start 7.07644 -5.171694)
			(end 7.016242 -5.171694)
			(stroke
				(width 0.1)
				(type default)
			)
			(layer "F.SilkS")
		)
		(fp_line
			(start 7.081266 -5.003292)
			(end 5.72643 -3.703828)
			(stroke
				(width 0.1)
				(type default)
			)
			(layer "F.SilkS")
		)
		(fp_line
			(start 7.081266 -5.003292)
			(end 5.72643 -3.703828)
			(stroke
				(width 0.1)
				(type default)
			)
			(layer "F.SilkS")
		)
		(fp_line
			(start 7.081266 -5.003292)
			(end 7.093458 -5.072888)
			(stroke
				(width 0.1)
				(type default)
			)
			(layer "F.SilkS")
		)
		(fp_line
			(start 7.081266 -5.003292)
			(end 7.093458 -5.072888)
			(stroke
				(width 0.1)
				(type default)
			)
			(layer "F.SilkS")
		)
		(fp_line
			(start 7.093458 -5.072888)
			(end 5.738876 -3.772916)
			(stroke
				(width 0.1)
				(type default)
			)
			(layer "F.SilkS")
		)
		(fp_line
			(start 7.093458 -5.072888)
			(end 5.738876 -3.772916)
			(stroke
				(width 0.1)
				(type default)
			)
			(layer "F.SilkS")
		)
		(fp_line
			(start 7.093458 -5.072888)
			(end 7.10565 -5.141976)
			(stroke
				(width 0.1)
				(type default)
			)
			(layer "F.SilkS")
		)
		(fp_line
			(start 7.093458 -5.072888)
			(end 7.10565 -5.141976)
			(stroke
				(width 0.1)
				(type default)
			)
			(layer "F.SilkS")
		)
		(fp_line
			(start 7.10565 -5.141976)
			(end 5.751068 -3.842512)
			(stroke
				(width 0.1)
				(type default)
			)
			(layer "F.SilkS")
		)
		(fp_line
			(start 7.10565 -5.141976)
			(end 5.751068 -3.842512)
			(stroke
				(width 0.1)
				(type default)
			)
			(layer "F.SilkS")
		)
		(fp_line
			(start 7.10565 -5.141976)
			(end 7.110984 -5.171694)
			(stroke
				(width 0.1)
				(type default)
			)
			(layer "F.SilkS")
		)
		(fp_line
			(start 7.10565 -5.141976)
			(end 7.110984 -5.171694)
			(stroke
				(width 0.1)
				(type default)
			)
			(layer "F.SilkS")
		)
		(fp_line
			(start 7.110984 -5.171694)
			(end 7.07644 -5.171694)
			(stroke
				(width 0.1)
				(type default)
			)
			(layer "F.SilkS")
		)
		(fp_line
			(start 7.110984 -5.171694)
			(end 7.07644 -5.171694)
			(stroke
				(width 0.1)
				(type default)
			)
			(layer "F.SilkS")
		)
		(fp_line
			(start 7.11454 -0.822198)
			(end 9.30656 -2.925064)
			(stroke
				(width 0.1)
				(type default)
			)
			(layer "F.SilkS")
		)
		(fp_line
			(start 7.11454 -0.822198)
			(end 9.30656 -2.925064)
			(stroke
				(width 0.1)
				(type default)
			)
			(layer "F.SilkS")
		)
		(fp_line
			(start 7.196582 -0.84328)
			(end 9.294368 -2.855468)
			(stroke
				(width 0.1)
				(type default)
			)
			(layer "F.SilkS")
		)
		(fp_line
			(start 7.196582 -0.84328)
			(end 9.294368 -2.855468)
			(stroke
				(width 0.1)
				(type default)
			)
			(layer "F.SilkS")
		)
		(fp_line
			(start 7.281418 -0.866648)
			(end 9.281922 -2.786126)
			(stroke
				(width 0.1)
				(type default)
			)
			(layer "F.SilkS")
		)
		(fp_line
			(start 7.281418 -0.866648)
			(end 9.281922 -2.786126)
			(stroke
				(width 0.1)
				(type default)
			)
			(layer "F.SilkS")
		)
		(fp_line
			(start 7.366 -0.890016)
			(end 9.269984 -2.716784)
			(stroke
				(width 0.1)
				(type default)
			)
			(layer "F.SilkS")
		)
		(fp_line
			(start 7.366 -0.890016)
			(end 9.269984 -2.716784)
			(stroke
				(width 0.1)
				(type default)
			)
			(layer "F.SilkS")
		)
		(fp_line
			(start 7.464298 -0.926846)
			(end 9.257792 -2.647188)
			(stroke
				(width 0.1)
				(type default)
			)
			(layer "F.SilkS")
		)
		(fp_line
			(start 7.464298 -0.926846)
			(end 9.257792 -2.647188)
			(stroke
				(width 0.1)
				(type default)
			)
			(layer "F.SilkS")
		)
		(fp_line
			(start 7.583678 -0.983488)
			(end 9.2456 -2.577592)
			(stroke
				(width 0.1)
				(type default)
			)
			(layer "F.SilkS")
		)
		(fp_line
			(start 7.583678 -0.983488)
			(end 9.2456 -2.577592)
			(stroke
				(width 0.1)
				(type default)
			)
			(layer "F.SilkS")
		)
		(fp_line
			(start 7.737348 -1.07315)
			(end 9.233408 -2.508504)
			(stroke
				(width 0.1)
				(type default)
			)
			(layer "F.SilkS")
		)
		(fp_line
			(start 7.737348 -1.07315)
			(end 9.233408 -2.508504)
			(stroke
				(width 0.1)
				(type default)
			)
			(layer "F.SilkS")
		)
		(fp_line
			(start 7.82066 -0.882904)
			(end 7.839456 -0.882904)
			(stroke
				(width 0.1)
				(type default)
			)
			(layer "F.SilkS")
		)
		(fp_line
			(start 7.82066 -0.882904)
			(end 7.839456 -0.882904)
			(stroke
				(width 0.1)
				(type default)
			)
			(layer "F.SilkS")
		)
		(fp_line
			(start 7.828788 -0.930148)
			(end 7.82066 -0.882904)
			(stroke
				(width 0.1)
				(type default)
			)
			(layer "F.SilkS")
		)
		(fp_line
			(start 7.828788 -0.930148)
			(end 7.82066 -0.882904)
			(stroke
				(width 0.1)
				(type default)
			)
			(layer "F.SilkS")
		)
		(fp_line
			(start 7.828788 -0.930148)
			(end 9.18464 -2.230882)
			(stroke
				(width 0.1)
				(type default)
			)
			(layer "F.SilkS")
		)
		(fp_line
			(start 7.828788 -0.930148)
			(end 9.18464 -2.230882)
			(stroke
				(width 0.1)
				(type default)
			)
			(layer "F.SilkS")
		)
		(fp_line
			(start 7.839456 -0.882904)
			(end 7.899908 -0.882904)
			(stroke
				(width 0.1)
				(type default)
			)
			(layer "F.SilkS")
		)
		(fp_line
			(start 7.839456 -0.882904)
			(end 7.899908 -0.882904)
			(stroke
				(width 0.1)
				(type default)
			)
			(layer "F.SilkS")
		)
		(fp_line
			(start 7.839456 -0.882904)
			(end 9.172194 -2.161286)
			(stroke
				(width 0.1)
				(type default)
			)
			(layer "F.SilkS")
		)
		(fp_line
			(start 7.839456 -0.882904)
			(end 9.172194 -2.161286)
			(stroke
				(width 0.1)
				(type default)
			)
			(layer "F.SilkS")
		)
		(fp_line
			(start 7.84098 -0.999744)
			(end 7.828788 -0.930148)
			(stroke
				(width 0.1)
				(type default)
			)
			(layer "F.SilkS")
		)
		(fp_line
			(start 7.84098 -0.999744)
			(end 7.828788 -0.930148)
			(stroke
				(width 0.1)
				(type default)
			)
			(layer "F.SilkS")
		)
		(fp_line
			(start 7.84098 -0.999744)
			(end 9.196832 -2.300224)
			(stroke
				(width 0.1)
				(type default)
			)
			(layer "F.SilkS")
		)
		(fp_line
			(start 7.84098 -0.999744)
			(end 9.196832 -2.300224)
			(stroke
				(width 0.1)
				(type default)
			)
			(layer "F.SilkS")
		)
		(fp_line
			(start 7.852918 -1.068832)
			(end 7.84098 -0.999744)
			(stroke
				(width 0.1)
				(type default)
			)
			(layer "F.SilkS")
		)
		(fp_line
			(start 7.852918 -1.068832)
			(end 7.84098 -0.999744)
			(stroke
				(width 0.1)
				(type default)
			)
			(layer "F.SilkS")
		)
		(fp_line
			(start 7.852918 -1.068832)
			(end 9.209024 -2.369566)
			(stroke
				(width 0.1)
				(type default)
			)
			(layer "F.SilkS")
		)
		(fp_line
			(start 7.852918 -1.068832)
			(end 9.209024 -2.369566)
			(stroke
				(width 0.1)
				(type default)
			)
			(layer "F.SilkS")
		)
		(fp_line
			(start 7.865364 -1.138428)
			(end 7.852918 -1.068832)
			(stroke
				(width 0.1)
				(type default)
			)
			(layer "F.SilkS")
		)
		(fp_line
			(start 7.865364 -1.138428)
			(end 7.852918 -1.068832)
			(stroke
				(width 0.1)
				(type default)
			)
			(layer "F.SilkS")
		)
		(fp_line
			(start 7.865364 -1.138428)
			(end 9.220962 -2.438908)
			(stroke
				(width 0.1)
				(type default)
			)
			(layer "F.SilkS")
		)
		(fp_line
			(start 7.865364 -1.138428)
			(end 9.220962 -2.438908)
			(stroke
				(width 0.1)
				(type default)
			)
			(layer "F.SilkS")
		)
		(fp_line
			(start 7.899908 -0.882904)
			(end 7.960106 -0.882904)
			(stroke
				(width 0.1)
				(type default)
			)
			(layer "F.SilkS")
		)
		(fp_line
			(start 7.899908 -0.882904)
			(end 7.960106 -0.882904)
			(stroke
				(width 0.1)
				(type default)
			)
			(layer "F.SilkS")
		)
		(fp_line
			(start 7.899908 -0.882904)
			(end 9.160002 -2.091944)
			(stroke
				(width 0.1)
				(type default)
			)
			(layer "F.SilkS")
		)
		(fp_line
			(start 7.899908 -0.882904)
			(end 9.160002 -2.091944)
			(stroke
				(width 0.1)
				(type default)
			)
			(layer "F.SilkS")
		)
		(fp_line
			(start 7.936484 -2.187702)
			(end 9.42848 -3.618992)
			(stroke
				(width 0.1)
				(type default)
			)
			(layer "F.SilkS")
		)
		(fp_line
			(start 7.936484 -2.187702)
			(end 9.42848 -3.618992)
			(stroke
				(width 0.1)
				(type default)
			)
			(layer "F.SilkS")
		)
		(fp_line
			(start 7.960106 -0.882904)
			(end 8.02005 -0.882904)
			(stroke
				(width 0.1)
				(type default)
			)
			(layer "F.SilkS")
		)
		(fp_line
			(start 7.960106 -0.882904)
			(end 8.02005 -0.882904)
			(stroke
				(width 0.1)
				(type default)
			)
			(layer "F.SilkS")
		)
		(fp_line
			(start 7.960106 -0.882904)
			(end 9.148064 -2.022602)
			(stroke
				(width 0.1)
				(type default)
			)
			(layer "F.SilkS")
		)
		(fp_line
			(start 7.960106 -0.882904)
			(end 9.148064 -2.022602)
			(stroke
				(width 0.1)
				(type default)
			)
			(layer "F.SilkS")
		)
		(fp_line
			(start 8.002778 -2.30886)
			(end 9.440672 -3.688334)
			(stroke
				(width 0.1)
				(type default)
			)
			(layer "F.SilkS")
		)
		(fp_line
			(start 8.002778 -2.30886)
			(end 9.440672 -3.688334)
			(stroke
				(width 0.1)
				(type default)
			)
			(layer "F.SilkS")
		)
		(fp_line
			(start 8.02005 -0.882904)
			(end 8.080248 -0.882904)
			(stroke
				(width 0.1)
				(type default)
			)
			(layer "F.SilkS")
		)
		(fp_line
			(start 8.02005 -0.882904)
			(end 8.080248 -0.882904)
			(stroke
				(width 0.1)
				(type default)
			)
			(layer "F.SilkS")
		)
		(fp_line
			(start 8.02005 -0.882904)
			(end 9.135872 -1.953006)
			(stroke
				(width 0.1)
				(type default)
			)
			(layer "F.SilkS")
		)
		(fp_line
			(start 8.02005 -0.882904)
			(end 9.135872 -1.953006)
			(stroke
				(width 0.1)
				(type default)
			)
			(layer "F.SilkS")
		)
		(fp_line
			(start 8.04799 -2.410206)
			(end 9.452864 -3.75793)
			(stroke
				(width 0.1)
				(type default)
			)
			(layer "F.SilkS")
		)
		(fp_line
			(start 8.04799 -2.410206)
			(end 9.452864 -3.75793)
			(stroke
				(width 0.1)
				(type default)
			)
			(layer "F.SilkS")
		)
		(fp_line
			(start 8.078724 -2.497328)
			(end 9.465056 -3.827526)
			(stroke
				(width 0.1)
				(type default)
			)
			(layer "F.SilkS")
		)
		(fp_line
			(start 8.078724 -2.497328)
			(end 9.465056 -3.827526)
			(stroke
				(width 0.1)
				(type default)
			)
			(layer "F.SilkS")
		)
		(fp_line
			(start 8.080248 -0.882904)
			(end 8.140446 -0.882904)
			(stroke
				(width 0.1)
				(type default)
			)
			(layer "F.SilkS")
		)
		(fp_line
			(start 8.080248 -0.882904)
			(end 8.140446 -0.882904)
			(stroke
				(width 0.1)
				(type default)
			)
			(layer "F.SilkS")
		)
		(fp_line
			(start 8.080248 -0.882904)
			(end 9.12368 -1.883664)
			(stroke
				(width 0.1)
				(type default)
			)
			(layer "F.SilkS")
		)
		(fp_line
			(start 8.080248 -0.882904)
			(end 9.12368 -1.883664)
			(stroke
				(width 0.1)
				(type default)
			)
			(layer "F.SilkS")
		)
		(fp_line
			(start 8.140446 -0.882904)
			(end 8.200644 -0.882904)
			(stroke
				(width 0.1)
				(type default)
			)
			(layer "F.SilkS")
		)
		(fp_line
			(start 8.140446 -0.882904)
			(end 8.200644 -0.882904)
			(stroke
				(width 0.1)
				(type default)
			)
			(layer "F.SilkS")
		)
		(fp_line
			(start 8.140446 -0.882904)
			(end 9.111234 -1.814322)
			(stroke
				(width 0.1)
				(type default)
			)
			(layer "F.SilkS")
		)
		(fp_line
			(start 8.140446 -0.882904)
			(end 9.111234 -1.814322)
			(stroke
				(width 0.1)
				(type default)
			)
			(layer "F.SilkS")
		)
		(fp_line
			(start 8.18261 -2.943352)
			(end 8.170418 -2.87401)
			(stroke
				(width 0.1)
				(type default)
			)
			(layer "F.SilkS")
		)
		(fp_line
			(start 8.18261 -2.943352)
			(end 8.170418 -2.87401)
			(stroke
				(width 0.1)
				(type default)
			)
			(layer "F.SilkS")
		)
		(fp_line
			(start 8.194802 -3.012694)
			(end 8.18261 -2.943352)
			(stroke
				(width 0.1)
				(type default)
			)
			(layer "F.SilkS")
		)
		(fp_line
			(start 8.194802 -3.012694)
			(end 8.18261 -2.943352)
			(stroke
				(width 0.1)
				(type default)
			)
			(layer "F.SilkS")
		)
		(fp_line
			(start 8.200644 -0.882904)
			(end 8.260842 -0.882904)
			(stroke
				(width 0.1)
				(type default)
			)
			(layer "F.SilkS")
		)
		(fp_line
			(start 8.200644 -0.882904)
			(end 8.260842 -0.882904)
			(stroke
				(width 0.1)
				(type default)
			)
			(layer "F.SilkS")
		)
		(fp_line
			(start 8.200644 -0.882904)
			(end 9.099042 -1.744726)
			(stroke
				(width 0.1)
				(type default)
			)
			(layer "F.SilkS")
		)
		(fp_line
			(start 8.200644 -0.882904)
			(end 9.099042 -1.744726)
			(stroke
				(width 0.1)
				(type default)
			)
			(layer "F.SilkS")
		)
		(fp_line
			(start 8.206994 -3.08229)
			(end 8.194802 -3.012694)
			(stroke
				(width 0.1)
				(type default)
			)
			(layer "F.SilkS")
		)
		(fp_line
			(start 8.206994 -3.08229)
			(end 8.194802 -3.012694)
			(stroke
				(width 0.1)
				(type default)
			)
			(layer "F.SilkS")
		)
		(fp_line
			(start 8.219186 -3.151378)
			(end 8.206994 -3.08229)
			(stroke
				(width 0.1)
				(type default)
			)
			(layer "F.SilkS")
		)
		(fp_line
			(start 8.219186 -3.151378)
			(end 8.206994 -3.08229)
			(stroke
				(width 0.1)
				(type default)
			)
			(layer "F.SilkS")
		)
		(fp_line
			(start 8.231378 -3.22072)
			(end 8.219186 -3.151378)
			(stroke
				(width 0.1)
				(type default)
			)
			(layer "F.SilkS")
		)
		(fp_line
			(start 8.231378 -3.22072)
			(end 8.219186 -3.151378)
			(stroke
				(width 0.1)
				(type default)
			)
			(layer "F.SilkS")
		)
		(fp_line
			(start 8.24357 -3.290316)
			(end 8.231378 -3.22072)
			(stroke
				(width 0.1)
				(type default)
			)
			(layer "F.SilkS")
		)
		(fp_line
			(start 8.24357 -3.290316)
			(end 8.231378 -3.22072)
			(stroke
				(width 0.1)
				(type default)
			)
			(layer "F.SilkS")
		)
		(fp_line
			(start 8.255762 -3.359658)
			(end 8.24357 -3.290316)
			(stroke
				(width 0.1)
				(type default)
			)
			(layer "F.SilkS")
		)
		(fp_line
			(start 8.255762 -3.359658)
			(end 8.24357 -3.290316)
			(stroke
				(width 0.1)
				(type default)
			)
			(layer "F.SilkS")
		)
		(fp_line
			(start 8.260842 -0.882904)
			(end 8.320786 -0.882904)
			(stroke
				(width 0.1)
				(type default)
			)
			(layer "F.SilkS")
		)
		(fp_line
			(start 8.260842 -0.882904)
			(end 8.320786 -0.882904)
			(stroke
				(width 0.1)
				(type default)
			)
			(layer "F.SilkS")
		)
		(fp_line
			(start 8.260842 -0.882904)
			(end 9.087104 -1.675384)
			(stroke
				(width 0.1)
				(type default)
			)
			(layer "F.SilkS")
		)
		(fp_line
			(start 8.260842 -0.882904)
			(end 9.087104 -1.675384)
			(stroke
				(width 0.1)
				(type default)
			)
			(layer "F.SilkS")
		)
		(fp_line
			(start 8.2677 -3.429)
			(end 8.255762 -3.359658)
			(stroke
				(width 0.1)
				(type default)
			)
			(layer "F.SilkS")
		)
		(fp_line
			(start 8.2677 -3.429)
			(end 8.255762 -3.359658)
			(stroke
				(width 0.1)
				(type default)
			)
			(layer "F.SilkS")
		)
		(fp_line
			(start 8.279892 -3.498342)
			(end 8.2677 -3.429)
			(stroke
				(width 0.1)
				(type default)
			)
			(layer "F.SilkS")
		)
		(fp_line
			(start 8.279892 -3.498342)
			(end 8.2677 -3.429)
			(stroke
				(width 0.1)
				(type default)
			)
			(layer "F.SilkS")
		)
		(fp_line
			(start 8.292084 -3.567684)
			(end 8.279892 -3.498342)
			(stroke
				(width 0.1)
				(type default)
			)
			(layer "F.SilkS")
		)
		(fp_line
			(start 8.292084 -3.567684)
			(end 8.279892 -3.498342)
			(stroke
				(width 0.1)
				(type default)
			)
			(layer "F.SilkS")
		)
		(fp_line
			(start 8.304276 -3.63728)
			(end 8.292084 -3.567684)
			(stroke
				(width 0.1)
				(type default)
			)
			(layer "F.SilkS")
		)
		(fp_line
			(start 8.304276 -3.63728)
			(end 8.292084 -3.567684)
			(stroke
				(width 0.1)
				(type default)
			)
			(layer "F.SilkS")
		)
		(fp_line
			(start 8.316468 -3.706368)
			(end 8.304276 -3.63728)
			(stroke
				(width 0.1)
				(type default)
			)
			(layer "F.SilkS")
		)
		(fp_line
			(start 8.316468 -3.706368)
			(end 8.304276 -3.63728)
			(stroke
				(width 0.1)
				(type default)
			)
			(layer "F.SilkS")
		)
		(fp_line
			(start 8.320786 -0.882904)
			(end 8.381238 -0.882904)
			(stroke
				(width 0.1)
				(type default)
			)
			(layer "F.SilkS")
		)
		(fp_line
			(start 8.320786 -0.882904)
			(end 8.381238 -0.882904)
			(stroke
				(width 0.1)
				(type default)
			)
			(layer "F.SilkS")
		)
		(fp_line
			(start 8.320786 -0.882904)
			(end 9.074912 -1.606296)
			(stroke
				(width 0.1)
				(type default)
			)
			(layer "F.SilkS")
		)
		(fp_line
			(start 8.320786 -0.882904)
			(end 9.074912 -1.606296)
			(stroke
				(width 0.1)
				(type default)
			)
			(layer "F.SilkS")
		)
		(fp_line
			(start 8.32866 -3.77571)
			(end 8.316468 -3.706368)
			(stroke
				(width 0.1)
				(type default)
			)
			(layer "F.SilkS")
		)
		(fp_line
			(start 8.32866 -3.77571)
			(end 8.316468 -3.706368)
			(stroke
				(width 0.1)
				(type default)
			)
			(layer "F.SilkS")
		)
		(fp_line
			(start 8.340852 -3.845306)
			(end 8.32866 -3.77571)
			(stroke
				(width 0.1)
				(type default)
			)
			(layer "F.SilkS")
		)
		(fp_line
			(start 8.340852 -3.845306)
			(end 8.32866 -3.77571)
			(stroke
				(width 0.1)
				(type default)
			)
			(layer "F.SilkS")
		)
		(fp_line
			(start 8.35279 -3.914648)
			(end 8.340852 -3.845306)
			(stroke
				(width 0.1)
				(type default)
			)
			(layer "F.SilkS")
		)
		(fp_line
			(start 8.35279 -3.914648)
			(end 8.340852 -3.845306)
			(stroke
				(width 0.1)
				(type default)
			)
			(layer "F.SilkS")
		)
		(fp_line
			(start 8.365236 -3.98399)
			(end 8.35279 -3.914648)
			(stroke
				(width 0.1)
				(type default)
			)
			(layer "F.SilkS")
		)
		(fp_line
			(start 8.365236 -3.98399)
			(end 8.35279 -3.914648)
			(stroke
				(width 0.1)
				(type default)
			)
			(layer "F.SilkS")
		)
		(fp_line
			(start 8.377174 -4.053332)
			(end 8.365236 -3.98399)
			(stroke
				(width 0.1)
				(type default)
			)
			(layer "F.SilkS")
		)
		(fp_line
			(start 8.377174 -4.053332)
			(end 8.365236 -3.98399)
			(stroke
				(width 0.1)
				(type default)
			)
			(layer "F.SilkS")
		)
		(fp_line
			(start 8.381238 -0.882904)
			(end 8.441182 -0.882904)
			(stroke
				(width 0.1)
				(type default)
			)
			(layer "F.SilkS")
		)
		(fp_line
			(start 8.381238 -0.882904)
			(end 8.441182 -0.882904)
			(stroke
				(width 0.1)
				(type default)
			)
			(layer "F.SilkS")
		)
		(fp_line
			(start 8.381238 -0.882904)
			(end 9.062466 -1.5367)
			(stroke
				(width 0.1)
				(type default)
			)
			(layer "F.SilkS")
		)
		(fp_line
			(start 8.381238 -0.882904)
			(end 9.062466 -1.5367)
			(stroke
				(width 0.1)
				(type default)
			)
			(layer "F.SilkS")
		)
		(fp_line
			(start 8.389366 -4.122674)
			(end 8.377174 -4.053332)
			(stroke
				(width 0.1)
				(type default)
			)
			(layer "F.SilkS")
		)
		(fp_line
			(start 8.389366 -4.122674)
			(end 8.377174 -4.053332)
			(stroke
				(width 0.1)
				(type default)
			)
			(layer "F.SilkS")
		)
		(fp_line
			(start 8.401558 -4.19227)
			(end 8.389366 -4.122674)
			(stroke
				(width 0.1)
				(type default)
			)
			(layer "F.SilkS")
		)
		(fp_line
			(start 8.401558 -4.19227)
			(end 8.389366 -4.122674)
			(stroke
				(width 0.1)
				(type default)
			)
			(layer "F.SilkS")
		)
		(fp_line
			(start 8.41375 -4.261612)
			(end 8.401558 -4.19227)
			(stroke
				(width 0.1)
				(type default)
			)
			(layer "F.SilkS")
		)
		(fp_line
			(start 8.41375 -4.261612)
			(end 8.401558 -4.19227)
			(stroke
				(width 0.1)
				(type default)
			)
			(layer "F.SilkS")
		)
		(fp_line
			(start 8.425942 -4.3307)
			(end 8.41375 -4.261612)
			(stroke
				(width 0.1)
				(type default)
			)
			(layer "F.SilkS")
		)
		(fp_line
			(start 8.425942 -4.3307)
			(end 8.41375 -4.261612)
			(stroke
				(width 0.1)
				(type default)
			)
			(layer "F.SilkS")
		)
		(fp_line
			(start 8.43788 -4.400296)
			(end 8.425942 -4.3307)
			(stroke
				(width 0.1)
				(type default)
			)
			(layer "F.SilkS")
		)
		(fp_line
			(start 8.43788 -4.400296)
			(end 8.425942 -4.3307)
			(stroke
				(width 0.1)
				(type default)
			)
			(layer "F.SilkS")
		)
		(fp_line
			(start 8.441182 -0.882904)
			(end 8.50138 -0.882904)
			(stroke
				(width 0.1)
				(type default)
			)
			(layer "F.SilkS")
		)
		(fp_line
			(start 8.441182 -0.882904)
			(end 8.50138 -0.882904)
			(stroke
				(width 0.1)
				(type default)
			)
			(layer "F.SilkS")
		)
		(fp_line
			(start 8.441182 -0.882904)
			(end 9.050274 -1.467104)
			(stroke
				(width 0.1)
				(type default)
			)
			(layer "F.SilkS")
		)
		(fp_line
			(start 8.441182 -0.882904)
			(end 9.050274 -1.467104)
			(stroke
				(width 0.1)
				(type default)
			)
			(layer "F.SilkS")
		)
		(fp_line
			(start 8.450326 -4.469638)
			(end 8.43788 -4.400296)
			(stroke
				(width 0.1)
				(type default)
			)
			(layer "F.SilkS")
		)
		(fp_line
			(start 8.450326 -4.469638)
			(end 8.43788 -4.400296)
			(stroke
				(width 0.1)
				(type default)
			)
			(layer "F.SilkS")
		)
		(fp_line
			(start 8.450326 -4.469638)
			(end 8.462264 -4.53898)
			(stroke
				(width 0.1)
				(type default)
			)
			(layer "F.SilkS")
		)
		(fp_line
			(start 8.450326 -4.469638)
			(end 8.462264 -4.53898)
			(stroke
				(width 0.1)
				(type default)
			)
			(layer "F.SilkS")
		)
		(fp_line
			(start 8.462264 -4.53898)
			(end 8.474456 -4.608322)
			(stroke
				(width 0.1)
				(type default)
			)
			(layer "F.SilkS")
		)
		(fp_line
			(start 8.462264 -4.53898)
			(end 8.474456 -4.608322)
			(stroke
				(width 0.1)
				(type default)
			)
			(layer "F.SilkS")
		)
		(fp_line
			(start 8.474456 -4.608322)
			(end 8.486648 -4.677664)
			(stroke
				(width 0.1)
				(type default)
			)
			(layer "F.SilkS")
		)
		(fp_line
			(start 8.474456 -4.608322)
			(end 8.486648 -4.677664)
			(stroke
				(width 0.1)
				(type default)
			)
			(layer "F.SilkS")
		)
		(fp_line
			(start 8.486648 -4.677664)
			(end 8.49884 -4.74726)
			(stroke
				(width 0.1)
				(type default)
			)
			(layer "F.SilkS")
		)
		(fp_line
			(start 8.486648 -4.677664)
			(end 8.49884 -4.74726)
			(stroke
				(width 0.1)
				(type default)
			)
			(layer "F.SilkS")
		)
		(fp_line
			(start 8.49884 -4.74726)
			(end 8.511032 -4.816602)
			(stroke
				(width 0.1)
				(type default)
			)
			(layer "F.SilkS")
		)
		(fp_line
			(start 8.49884 -4.74726)
			(end 8.511032 -4.816602)
			(stroke
				(width 0.1)
				(type default)
			)
			(layer "F.SilkS")
		)
		(fp_line
			(start 8.50138 -0.882904)
			(end 8.561578 -0.882904)
			(stroke
				(width 0.1)
				(type default)
			)
			(layer "F.SilkS")
		)
		(fp_line
			(start 8.50138 -0.882904)
			(end 8.561578 -0.882904)
			(stroke
				(width 0.1)
				(type default)
			)
			(layer "F.SilkS")
		)
		(fp_line
			(start 8.50138 -0.882904)
			(end 9.038082 -1.397762)
			(stroke
				(width 0.1)
				(type default)
			)
			(layer "F.SilkS")
		)
		(fp_line
			(start 8.50138 -0.882904)
			(end 9.038082 -1.397762)
			(stroke
				(width 0.1)
				(type default)
			)
			(layer "F.SilkS")
		)
		(fp_line
			(start 8.511032 -4.816602)
			(end 8.52297 -4.88569)
			(stroke
				(width 0.1)
				(type default)
			)
			(layer "F.SilkS")
		)
		(fp_line
			(start 8.511032 -4.816602)
			(end 8.52297 -4.88569)
			(stroke
				(width 0.1)
				(type default)
			)
			(layer "F.SilkS")
		)
		(fp_line
			(start 8.52297 -4.88569)
			(end 8.535416 -4.955286)
			(stroke
				(width 0.1)
				(type default)
			)
			(layer "F.SilkS")
		)
		(fp_line
			(start 8.52297 -4.88569)
			(end 8.535416 -4.955286)
			(stroke
				(width 0.1)
				(type default)
			)
			(layer "F.SilkS")
		)
		(fp_line
			(start 8.535416 -4.955286)
			(end 8.547608 -5.024628)
			(stroke
				(width 0.1)
				(type default)
			)
			(layer "F.SilkS")
		)
		(fp_line
			(start 8.535416 -4.955286)
			(end 8.547608 -5.024628)
			(stroke
				(width 0.1)
				(type default)
			)
			(layer "F.SilkS")
		)
		(fp_line
			(start 8.547608 -5.024628)
			(end 8.559546 -5.09397)
			(stroke
				(width 0.1)
				(type default)
			)
			(layer "F.SilkS")
		)
		(fp_line
			(start 8.547608 -5.024628)
			(end 8.559546 -5.09397)
			(stroke
				(width 0.1)
				(type default)
			)
			(layer "F.SilkS")
		)
		(fp_line
			(start 8.559546 -5.09397)
			(end 8.571738 -5.163312)
			(stroke
				(width 0.1)
				(type default)
			)
			(layer "F.SilkS")
		)
		(fp_line
			(start 8.559546 -5.09397)
			(end 8.571738 -5.163312)
			(stroke
				(width 0.1)
				(type default)
			)
			(layer "F.SilkS")
		)
		(fp_line
			(start 8.561578 -0.882904)
			(end 8.621522 -0.882904)
			(stroke
				(width 0.1)
				(type default)
			)
			(layer "F.SilkS")
		)
		(fp_line
			(start 8.561578 -0.882904)
			(end 8.621522 -0.882904)
			(stroke
				(width 0.1)
				(type default)
			)
			(layer "F.SilkS")
		)
		(fp_line
			(start 8.561578 -0.882904)
			(end 9.026144 -1.32842)
			(stroke
				(width 0.1)
				(type default)
			)
			(layer "F.SilkS")
		)
		(fp_line
			(start 8.561578 -0.882904)
			(end 9.026144 -1.32842)
			(stroke
				(width 0.1)
				(type default)
			)
			(layer "F.SilkS")
		)
		(fp_line
			(start 8.573262 -5.171694)
			(end 8.571738 -5.163312)
			(stroke
				(width 0.1)
				(type default)
			)
			(layer "F.SilkS")
		)
		(fp_line
			(start 8.573262 -5.171694)
			(end 8.571738 -5.163312)
			(stroke
				(width 0.1)
				(type default)
			)
			(layer "F.SilkS")
		)
		(fp_line
			(start 8.580374 -5.171694)
			(end 8.571738 -5.163312)
			(stroke
				(width 0.1)
				(type default)
			)
			(layer "F.SilkS")
		)
		(fp_line
			(start 8.580374 -5.171694)
			(end 8.571738 -5.163312)
			(stroke
				(width 0.1)
				(type default)
			)
			(layer "F.SilkS")
		)
		(fp_line
			(start 8.580374 -5.171694)
			(end 8.573262 -5.171694)
			(stroke
				(width 0.1)
				(type default)
			)
			(layer "F.SilkS")
		)
		(fp_line
			(start 8.580374 -5.171694)
			(end 8.573262 -5.171694)
			(stroke
				(width 0.1)
				(type default)
			)
			(layer "F.SilkS")
		)
		(fp_line
			(start 8.621522 -0.882904)
			(end 8.681974 -0.882904)
			(stroke
				(width 0.1)
				(type default)
			)
			(layer "F.SilkS")
		)
		(fp_line
			(start 8.621522 -0.882904)
			(end 8.681974 -0.882904)
			(stroke
				(width 0.1)
				(type default)
			)
			(layer "F.SilkS")
		)
		(fp_line
			(start 8.621522 -0.882904)
			(end 9.013952 -1.259078)
			(stroke
				(width 0.1)
				(type default)
			)
			(layer "F.SilkS")
		)
		(fp_line
			(start 8.621522 -0.882904)
			(end 9.013952 -1.259078)
			(stroke
				(width 0.1)
				(type default)
			)
			(layer "F.SilkS")
		)
		(fp_line
			(start 8.640572 -5.171694)
			(end 8.559546 -5.09397)
			(stroke
				(width 0.1)
				(type default)
			)
			(layer "F.SilkS")
		)
		(fp_line
			(start 8.640572 -5.171694)
			(end 8.559546 -5.09397)
			(stroke
				(width 0.1)
				(type default)
			)
			(layer "F.SilkS")
		)
		(fp_line
			(start 8.640572 -5.171694)
			(end 8.580374 -5.171694)
			(stroke
				(width 0.1)
				(type default)
			)
			(layer "F.SilkS")
		)
		(fp_line
			(start 8.640572 -5.171694)
			(end 8.580374 -5.171694)
			(stroke
				(width 0.1)
				(type default)
			)
			(layer "F.SilkS")
		)
		(fp_line
			(start 8.681974 -0.882904)
			(end 8.741918 -0.882904)
			(stroke
				(width 0.1)
				(type default)
			)
			(layer "F.SilkS")
		)
		(fp_line
			(start 8.681974 -0.882904)
			(end 8.741918 -0.882904)
			(stroke
				(width 0.1)
				(type default)
			)
			(layer "F.SilkS")
		)
		(fp_line
			(start 8.681974 -0.882904)
			(end 9.001506 -1.189482)
			(stroke
				(width 0.1)
				(type default)
			)
			(layer "F.SilkS")
		)
		(fp_line
			(start 8.681974 -0.882904)
			(end 9.001506 -1.189482)
			(stroke
				(width 0.1)
				(type default)
			)
			(layer "F.SilkS")
		)
		(fp_line
			(start 8.70077 -5.171694)
			(end 8.547608 -5.024628)
			(stroke
				(width 0.1)
				(type default)
			)
			(layer "F.SilkS")
		)
		(fp_line
			(start 8.70077 -5.171694)
			(end 8.547608 -5.024628)
			(stroke
				(width 0.1)
				(type default)
			)
			(layer "F.SilkS")
		)
		(fp_line
			(start 8.70077 -5.171694)
			(end 8.640572 -5.171694)
			(stroke
				(width 0.1)
				(type default)
			)
			(layer "F.SilkS")
		)
		(fp_line
			(start 8.70077 -5.171694)
			(end 8.640572 -5.171694)
			(stroke
				(width 0.1)
				(type default)
			)
			(layer "F.SilkS")
		)
		(fp_line
			(start 8.741918 -0.882904)
			(end 8.802116 -0.882904)
			(stroke
				(width 0.1)
				(type default)
			)
			(layer "F.SilkS")
		)
		(fp_line
			(start 8.741918 -0.882904)
			(end 8.802116 -0.882904)
			(stroke
				(width 0.1)
				(type default)
			)
			(layer "F.SilkS")
		)
		(fp_line
			(start 8.741918 -0.882904)
			(end 8.989314 -1.12014)
			(stroke
				(width 0.1)
				(type default)
			)
			(layer "F.SilkS")
		)
		(fp_line
			(start 8.741918 -0.882904)
			(end 8.989314 -1.12014)
			(stroke
				(width 0.1)
				(type default)
			)
			(layer "F.SilkS")
		)
		(fp_line
			(start 8.760968 -5.171694)
			(end 8.535416 -4.955286)
			(stroke
				(width 0.1)
				(type default)
			)
			(layer "F.SilkS")
		)
		(fp_line
			(start 8.760968 -5.171694)
			(end 8.535416 -4.955286)
			(stroke
				(width 0.1)
				(type default)
			)
			(layer "F.SilkS")
		)
		(fp_line
			(start 8.760968 -5.171694)
			(end 8.70077 -5.171694)
			(stroke
				(width 0.1)
				(type default)
			)
			(layer "F.SilkS")
		)
		(fp_line
			(start 8.760968 -5.171694)
			(end 8.70077 -5.171694)
			(stroke
				(width 0.1)
				(type default)
			)
			(layer "F.SilkS")
		)
		(fp_line
			(start 8.802116 -0.882904)
			(end 8.862314 -0.882904)
			(stroke
				(width 0.1)
				(type default)
			)
			(layer "F.SilkS")
		)
		(fp_line
			(start 8.802116 -0.882904)
			(end 8.862314 -0.882904)
			(stroke
				(width 0.1)
				(type default)
			)
			(layer "F.SilkS")
		)
		(fp_line
			(start 8.802116 -0.882904)
			(end 8.977122 -1.050798)
			(stroke
				(width 0.1)
				(type default)
			)
			(layer "F.SilkS")
		)
		(fp_line
			(start 8.802116 -0.882904)
			(end 8.977122 -1.050798)
			(stroke
				(width 0.1)
				(type default)
			)
			(layer "F.SilkS")
		)
		(fp_line
			(start 8.821166 -5.171694)
			(end 8.52297 -4.88569)
			(stroke
				(width 0.1)
				(type default)
			)
			(layer "F.SilkS")
		)
		(fp_line
			(start 8.821166 -5.171694)
			(end 8.52297 -4.88569)
			(stroke
				(width 0.1)
				(type default)
			)
			(layer "F.SilkS")
		)
		(fp_line
			(start 8.821166 -5.171694)
			(end 8.760968 -5.171694)
			(stroke
				(width 0.1)
				(type default)
			)
			(layer "F.SilkS")
		)
		(fp_line
			(start 8.821166 -5.171694)
			(end 8.760968 -5.171694)
			(stroke
				(width 0.1)
				(type default)
			)
			(layer "F.SilkS")
		)
		(fp_line
			(start 8.862314 -0.882904)
			(end 8.922512 -0.882904)
			(stroke
				(width 0.1)
				(type default)
			)
			(layer "F.SilkS")
		)
		(fp_line
			(start 8.862314 -0.882904)
			(end 8.922512 -0.882904)
			(stroke
				(width 0.1)
				(type default)
			)
			(layer "F.SilkS")
		)
		(fp_line
			(start 8.862314 -0.882904)
			(end 8.965184 -0.981456)
			(stroke
				(width 0.1)
				(type default)
			)
			(layer "F.SilkS")
		)
		(fp_line
			(start 8.862314 -0.882904)
			(end 8.965184 -0.981456)
			(stroke
				(width 0.1)
				(type default)
			)
			(layer "F.SilkS")
		)
		(fp_line
			(start 8.88111 -5.171694)
			(end 8.511032 -4.816602)
			(stroke
				(width 0.1)
				(type default)
			)
			(layer "F.SilkS")
		)
		(fp_line
			(start 8.88111 -5.171694)
			(end 8.511032 -4.816602)
			(stroke
				(width 0.1)
				(type default)
			)
			(layer "F.SilkS")
		)
		(fp_line
			(start 8.88111 -5.171694)
			(end 8.821166 -5.171694)
			(stroke
				(width 0.1)
				(type default)
			)
			(layer "F.SilkS")
		)
		(fp_line
			(start 8.88111 -5.171694)
			(end 8.821166 -5.171694)
			(stroke
				(width 0.1)
				(type default)
			)
			(layer "F.SilkS")
		)
		(fp_line
			(start 8.922512 -0.882904)
			(end 8.947658 -0.882904)
			(stroke
				(width 0.1)
				(type default)
			)
			(layer "F.SilkS")
		)
		(fp_line
			(start 8.922512 -0.882904)
			(end 8.947658 -0.882904)
			(stroke
				(width 0.1)
				(type default)
			)
			(layer "F.SilkS")
		)
		(fp_line
			(start 8.922512 -0.882904)
			(end 8.952738 -0.91186)
			(stroke
				(width 0.1)
				(type default)
			)
			(layer "F.SilkS")
		)
		(fp_line
			(start 8.922512 -0.882904)
			(end 8.952738 -0.91186)
			(stroke
				(width 0.1)
				(type default)
			)
			(layer "F.SilkS")
		)
		(fp_line
			(start 8.941308 -5.171694)
			(end 8.49884 -4.74726)
			(stroke
				(width 0.1)
				(type default)
			)
			(layer "F.SilkS")
		)
		(fp_line
			(start 8.941308 -5.171694)
			(end 8.49884 -4.74726)
			(stroke
				(width 0.1)
				(type default)
			)
			(layer "F.SilkS")
		)
		(fp_line
			(start 8.941308 -5.171694)
			(end 8.88111 -5.171694)
			(stroke
				(width 0.1)
				(type default)
			)
			(layer "F.SilkS")
		)
		(fp_line
			(start 8.941308 -5.171694)
			(end 8.88111 -5.171694)
			(stroke
				(width 0.1)
				(type default)
			)
			(layer "F.SilkS")
		)
		(fp_line
			(start 8.947658 -0.882904)
			(end 8.952738 -0.91186)
			(stroke
				(width 0.1)
				(type default)
			)
			(layer "F.SilkS")
		)
		(fp_line
			(start 8.947658 -0.882904)
			(end 8.952738 -0.91186)
			(stroke
				(width 0.1)
				(type default)
			)
			(layer "F.SilkS")
		)
		(fp_line
			(start 8.965184 -0.981456)
			(end 8.952738 -0.91186)
			(stroke
				(width 0.1)
				(type default)
			)
			(layer "F.SilkS")
		)
		(fp_line
			(start 8.965184 -0.981456)
			(end 8.952738 -0.91186)
			(stroke
				(width 0.1)
				(type default)
			)
			(layer "F.SilkS")
		)
		(fp_line
			(start 8.977122 -1.050798)
			(end 8.965184 -0.981456)
			(stroke
				(width 0.1)
				(type default)
			)
			(layer "F.SilkS")
		)
		(fp_line
			(start 8.977122 -1.050798)
			(end 8.965184 -0.981456)
			(stroke
				(width 0.1)
				(type default)
			)
			(layer "F.SilkS")
		)
		(fp_line
			(start 8.989314 -1.12014)
			(end 8.977122 -1.050798)
			(stroke
				(width 0.1)
				(type default)
			)
			(layer "F.SilkS")
		)
		(fp_line
			(start 8.989314 -1.12014)
			(end 8.977122 -1.050798)
			(stroke
				(width 0.1)
				(type default)
			)
			(layer "F.SilkS")
		)
		(fp_line
			(start 9.001506 -5.171694)
			(end 8.486648 -4.677664)
			(stroke
				(width 0.1)
				(type default)
			)
			(layer "F.SilkS")
		)
		(fp_line
			(start 9.001506 -5.171694)
			(end 8.486648 -4.677664)
			(stroke
				(width 0.1)
				(type default)
			)
			(layer "F.SilkS")
		)
		(fp_line
			(start 9.001506 -5.171694)
			(end 8.941308 -5.171694)
			(stroke
				(width 0.1)
				(type default)
			)
			(layer "F.SilkS")
		)
		(fp_line
			(start 9.001506 -5.171694)
			(end 8.941308 -5.171694)
			(stroke
				(width 0.1)
				(type default)
			)
			(layer "F.SilkS")
		)
		(fp_line
			(start 9.001506 -1.189482)
			(end 8.989314 -1.12014)
			(stroke
				(width 0.1)
				(type default)
			)
			(layer "F.SilkS")
		)
		(fp_line
			(start 9.001506 -1.189482)
			(end 8.989314 -1.12014)
			(stroke
				(width 0.1)
				(type default)
			)
			(layer "F.SilkS")
		)
		(fp_line
			(start 9.013952 -1.259078)
			(end 9.001506 -1.189482)
			(stroke
				(width 0.1)
				(type default)
			)
			(layer "F.SilkS")
		)
		(fp_line
			(start 9.013952 -1.259078)
			(end 9.001506 -1.189482)
			(stroke
				(width 0.1)
				(type default)
			)
			(layer "F.SilkS")
		)
		(fp_line
			(start 9.026144 -1.32842)
			(end 9.013952 -1.259078)
			(stroke
				(width 0.1)
				(type default)
			)
			(layer "F.SilkS")
		)
		(fp_line
			(start 9.026144 -1.32842)
			(end 9.013952 -1.259078)
			(stroke
				(width 0.1)
				(type default)
			)
			(layer "F.SilkS")
		)
		(fp_line
			(start 9.038082 -1.397762)
			(end 9.026144 -1.32842)
			(stroke
				(width 0.1)
				(type default)
			)
			(layer "F.SilkS")
		)
		(fp_line
			(start 9.038082 -1.397762)
			(end 9.026144 -1.32842)
			(stroke
				(width 0.1)
				(type default)
			)
			(layer "F.SilkS")
		)
		(fp_line
			(start 9.050274 -1.467104)
			(end 9.038082 -1.397762)
			(stroke
				(width 0.1)
				(type default)
			)
			(layer "F.SilkS")
		)
		(fp_line
			(start 9.050274 -1.467104)
			(end 9.038082 -1.397762)
			(stroke
				(width 0.1)
				(type default)
			)
			(layer "F.SilkS")
		)
		(fp_line
			(start 9.061704 -5.171694)
			(end 8.474456 -4.608322)
			(stroke
				(width 0.1)
				(type default)
			)
			(layer "F.SilkS")
		)
		(fp_line
			(start 9.061704 -5.171694)
			(end 8.474456 -4.608322)
			(stroke
				(width 0.1)
				(type default)
			)
			(layer "F.SilkS")
		)
		(fp_line
			(start 9.061704 -5.171694)
			(end 9.001506 -5.171694)
			(stroke
				(width 0.1)
				(type default)
			)
			(layer "F.SilkS")
		)
		(fp_line
			(start 9.061704 -5.171694)
			(end 9.001506 -5.171694)
			(stroke
				(width 0.1)
				(type default)
			)
			(layer "F.SilkS")
		)
		(fp_line
			(start 9.062466 -1.5367)
			(end 9.050274 -1.467104)
			(stroke
				(width 0.1)
				(type default)
			)
			(layer "F.SilkS")
		)
		(fp_line
			(start 9.062466 -1.5367)
			(end 9.050274 -1.467104)
			(stroke
				(width 0.1)
				(type default)
			)
			(layer "F.SilkS")
		)
		(fp_line
			(start 9.074912 -1.606296)
			(end 9.062466 -1.5367)
			(stroke
				(width 0.1)
				(type default)
			)
			(layer "F.SilkS")
		)
		(fp_line
			(start 9.074912 -1.606296)
			(end 9.062466 -1.5367)
			(stroke
				(width 0.1)
				(type default)
			)
			(layer "F.SilkS")
		)
		(fp_line
			(start 9.087104 -1.675384)
			(end 9.074912 -1.606296)
			(stroke
				(width 0.1)
				(type default)
			)
			(layer "F.SilkS")
		)
		(fp_line
			(start 9.087104 -1.675384)
			(end 9.074912 -1.606296)
			(stroke
				(width 0.1)
				(type default)
			)
			(layer "F.SilkS")
		)
		(fp_line
			(start 9.099042 -1.744726)
			(end 9.087104 -1.675384)
			(stroke
				(width 0.1)
				(type default)
			)
			(layer "F.SilkS")
		)
		(fp_line
			(start 9.099042 -1.744726)
			(end 9.087104 -1.675384)
			(stroke
				(width 0.1)
				(type default)
			)
			(layer "F.SilkS")
		)
		(fp_line
			(start 9.111234 -1.814322)
			(end 9.099042 -1.744726)
			(stroke
				(width 0.1)
				(type default)
			)
			(layer "F.SilkS")
		)
		(fp_line
			(start 9.111234 -1.814322)
			(end 9.099042 -1.744726)
			(stroke
				(width 0.1)
				(type default)
			)
			(layer "F.SilkS")
		)
		(fp_line
			(start 9.121902 -5.171694)
			(end 8.462264 -4.53898)
			(stroke
				(width 0.1)
				(type default)
			)
			(layer "F.SilkS")
		)
		(fp_line
			(start 9.121902 -5.171694)
			(end 8.462264 -4.53898)
			(stroke
				(width 0.1)
				(type default)
			)
			(layer "F.SilkS")
		)
		(fp_line
			(start 9.121902 -5.171694)
			(end 9.061704 -5.171694)
			(stroke
				(width 0.1)
				(type default)
			)
			(layer "F.SilkS")
		)
		(fp_line
			(start 9.121902 -5.171694)
			(end 9.061704 -5.171694)
			(stroke
				(width 0.1)
				(type default)
			)
			(layer "F.SilkS")
		)
		(fp_line
			(start 9.12368 -1.883664)
			(end 9.111234 -1.814322)
			(stroke
				(width 0.1)
				(type default)
			)
			(layer "F.SilkS")
		)
		(fp_line
			(start 9.12368 -1.883664)
			(end 9.111234 -1.814322)
			(stroke
				(width 0.1)
				(type default)
			)
			(layer "F.SilkS")
		)
		(fp_line
			(start 9.135872 -1.953006)
			(end 9.12368 -1.883664)
			(stroke
				(width 0.1)
				(type default)
			)
			(layer "F.SilkS")
		)
		(fp_line
			(start 9.135872 -1.953006)
			(end 9.12368 -1.883664)
			(stroke
				(width 0.1)
				(type default)
			)
			(layer "F.SilkS")
		)
		(fp_line
			(start 9.148064 -2.022602)
			(end 9.135872 -1.953006)
			(stroke
				(width 0.1)
				(type default)
			)
			(layer "F.SilkS")
		)
		(fp_line
			(start 9.148064 -2.022602)
			(end 9.135872 -1.953006)
			(stroke
				(width 0.1)
				(type default)
			)
			(layer "F.SilkS")
		)
		(fp_line
			(start 9.160002 -2.091944)
			(end 9.148064 -2.022602)
			(stroke
				(width 0.1)
				(type default)
			)
			(layer "F.SilkS")
		)
		(fp_line
			(start 9.160002 -2.091944)
			(end 9.148064 -2.022602)
			(stroke
				(width 0.1)
				(type default)
			)
			(layer "F.SilkS")
		)
		(fp_line
			(start 9.172194 -2.161286)
			(end 9.160002 -2.091944)
			(stroke
				(width 0.1)
				(type default)
			)
			(layer "F.SilkS")
		)
		(fp_line
			(start 9.172194 -2.161286)
			(end 9.160002 -2.091944)
			(stroke
				(width 0.1)
				(type default)
			)
			(layer "F.SilkS")
		)
		(fp_line
			(start 9.172194 -2.161286)
			(end 9.18464 -2.230882)
			(stroke
				(width 0.1)
				(type default)
			)
			(layer "F.SilkS")
		)
		(fp_line
			(start 9.172194 -2.161286)
			(end 9.18464 -2.230882)
			(stroke
				(width 0.1)
				(type default)
			)
			(layer "F.SilkS")
		)
		(fp_line
			(start 9.181846 -5.171694)
			(end 8.450326 -4.469638)
			(stroke
				(width 0.1)
				(type default)
			)
			(layer "F.SilkS")
		)
		(fp_line
			(start 9.181846 -5.171694)
			(end 8.450326 -4.469638)
			(stroke
				(width 0.1)
				(type default)
			)
			(layer "F.SilkS")
		)
		(fp_line
			(start 9.181846 -5.171694)
			(end 9.121902 -5.171694)
			(stroke
				(width 0.1)
				(type default)
			)
			(layer "F.SilkS")
		)
		(fp_line
			(start 9.181846 -5.171694)
			(end 9.121902 -5.171694)
			(stroke
				(width 0.1)
				(type default)
			)
			(layer "F.SilkS")
		)
		(fp_line
			(start 9.18464 -2.230882)
			(end 9.196832 -2.300224)
			(stroke
				(width 0.1)
				(type default)
			)
			(layer "F.SilkS")
		)
		(fp_line
			(start 9.18464 -2.230882)
			(end 9.196832 -2.300224)
			(stroke
				(width 0.1)
				(type default)
			)
			(layer "F.SilkS")
		)
		(fp_line
			(start 9.196832 -2.300224)
			(end 9.209024 -2.369566)
			(stroke
				(width 0.1)
				(type default)
			)
			(layer "F.SilkS")
		)
		(fp_line
			(start 9.196832 -2.300224)
			(end 9.209024 -2.369566)
			(stroke
				(width 0.1)
				(type default)
			)
			(layer "F.SilkS")
		)
		(fp_line
			(start 9.209024 -2.369566)
			(end 9.220962 -2.438908)
			(stroke
				(width 0.1)
				(type default)
			)
			(layer "F.SilkS")
		)
		(fp_line
			(start 9.209024 -2.369566)
			(end 9.220962 -2.438908)
			(stroke
				(width 0.1)
				(type default)
			)
			(layer "F.SilkS")
		)
		(fp_line
			(start 9.220962 -2.438908)
			(end 9.233408 -2.508504)
			(stroke
				(width 0.1)
				(type default)
			)
			(layer "F.SilkS")
		)
		(fp_line
			(start 9.220962 -2.438908)
			(end 9.233408 -2.508504)
			(stroke
				(width 0.1)
				(type default)
			)
			(layer "F.SilkS")
		)
		(fp_line
			(start 9.233408 -2.508504)
			(end 9.2456 -2.577592)
			(stroke
				(width 0.1)
				(type default)
			)
			(layer "F.SilkS")
		)
		(fp_line
			(start 9.233408 -2.508504)
			(end 9.2456 -2.577592)
			(stroke
				(width 0.1)
				(type default)
			)
			(layer "F.SilkS")
		)
		(fp_line
			(start 9.242298 -5.171694)
			(end 8.43788 -4.400296)
			(stroke
				(width 0.1)
				(type default)
			)
			(layer "F.SilkS")
		)
		(fp_line
			(start 9.242298 -5.171694)
			(end 8.43788 -4.400296)
			(stroke
				(width 0.1)
				(type default)
			)
			(layer "F.SilkS")
		)
		(fp_line
			(start 9.242298 -5.171694)
			(end 9.181846 -5.171694)
			(stroke
				(width 0.1)
				(type default)
			)
			(layer "F.SilkS")
		)
		(fp_line
			(start 9.242298 -5.171694)
			(end 9.181846 -5.171694)
			(stroke
				(width 0.1)
				(type default)
			)
			(layer "F.SilkS")
		)
		(fp_line
			(start 9.2456 -2.577592)
			(end 9.257792 -2.647188)
			(stroke
				(width 0.1)
				(type default)
			)
			(layer "F.SilkS")
		)
		(fp_line
			(start 9.2456 -2.577592)
			(end 9.257792 -2.647188)
			(stroke
				(width 0.1)
				(type default)
			)
			(layer "F.SilkS")
		)
		(fp_line
			(start 9.257792 -2.647188)
			(end 9.269984 -2.716784)
			(stroke
				(width 0.1)
				(type default)
			)
			(layer "F.SilkS")
		)
		(fp_line
			(start 9.257792 -2.647188)
			(end 9.269984 -2.716784)
			(stroke
				(width 0.1)
				(type default)
			)
			(layer "F.SilkS")
		)
		(fp_line
			(start 9.269984 -2.716784)
			(end 9.281922 -2.786126)
			(stroke
				(width 0.1)
				(type default)
			)
			(layer "F.SilkS")
		)
		(fp_line
			(start 9.269984 -2.716784)
			(end 9.281922 -2.786126)
			(stroke
				(width 0.1)
				(type default)
			)
			(layer "F.SilkS")
		)
		(fp_line
			(start 9.281922 -2.786126)
			(end 9.294368 -2.855468)
			(stroke
				(width 0.1)
				(type default)
			)
			(layer "F.SilkS")
		)
		(fp_line
			(start 9.281922 -2.786126)
			(end 9.294368 -2.855468)
			(stroke
				(width 0.1)
				(type default)
			)
			(layer "F.SilkS")
		)
		(fp_line
			(start 9.294368 -2.855468)
			(end 9.30656 -2.925064)
			(stroke
				(width 0.1)
				(type default)
			)
			(layer "F.SilkS")
		)
		(fp_line
			(start 9.294368 -2.855468)
			(end 9.30656 -2.925064)
			(stroke
				(width 0.1)
				(type default)
			)
			(layer "F.SilkS")
		)
		(fp_line
			(start 9.302242 -5.171694)
			(end 8.425942 -4.3307)
			(stroke
				(width 0.1)
				(type default)
			)
			(layer "F.SilkS")
		)
		(fp_line
			(start 9.302242 -5.171694)
			(end 8.425942 -4.3307)
			(stroke
				(width 0.1)
				(type default)
			)
			(layer "F.SilkS")
		)
		(fp_line
			(start 9.302242 -5.171694)
			(end 9.242298 -5.171694)
			(stroke
				(width 0.1)
				(type default)
			)
			(layer "F.SilkS")
		)
		(fp_line
			(start 9.302242 -5.171694)
			(end 9.242298 -5.171694)
			(stroke
				(width 0.1)
				(type default)
			)
			(layer "F.SilkS")
		)
		(fp_line
			(start 9.30656 -2.925064)
			(end 9.318752 -2.994406)
			(stroke
				(width 0.1)
				(type default)
			)
			(layer "F.SilkS")
		)
		(fp_line
			(start 9.30656 -2.925064)
			(end 9.318752 -2.994406)
			(stroke
				(width 0.1)
				(type default)
			)
			(layer "F.SilkS")
		)
		(fp_line
			(start 9.318752 -2.994406)
			(end 9.330944 -3.063748)
			(stroke
				(width 0.1)
				(type default)
			)
			(layer "F.SilkS")
		)
		(fp_line
			(start 9.318752 -2.994406)
			(end 9.330944 -3.063748)
			(stroke
				(width 0.1)
				(type default)
			)
			(layer "F.SilkS")
		)
		(fp_line
			(start 9.330944 -3.063748)
			(end 9.343136 -3.13309)
			(stroke
				(width 0.1)
				(type default)
			)
			(layer "F.SilkS")
		)
		(fp_line
			(start 9.330944 -3.063748)
			(end 9.343136 -3.13309)
			(stroke
				(width 0.1)
				(type default)
			)
			(layer "F.SilkS")
		)
		(fp_line
			(start 9.343136 -3.13309)
			(end 9.355328 -3.202432)
			(stroke
				(width 0.1)
				(type default)
			)
			(layer "F.SilkS")
		)
		(fp_line
			(start 9.343136 -3.13309)
			(end 9.355328 -3.202432)
			(stroke
				(width 0.1)
				(type default)
			)
			(layer "F.SilkS")
		)
		(fp_line
			(start 9.355328 -3.202432)
			(end 9.36752 -3.272028)
			(stroke
				(width 0.1)
				(type default)
			)
			(layer "F.SilkS")
		)
		(fp_line
			(start 9.355328 -3.202432)
			(end 9.36752 -3.272028)
			(stroke
				(width 0.1)
				(type default)
			)
			(layer "F.SilkS")
		)
		(fp_line
			(start 9.36244 -5.171694)
			(end 8.41375 -4.261612)
			(stroke
				(width 0.1)
				(type default)
			)
			(layer "F.SilkS")
		)
		(fp_line
			(start 9.36244 -5.171694)
			(end 8.41375 -4.261612)
			(stroke
				(width 0.1)
				(type default)
			)
			(layer "F.SilkS")
		)
		(fp_line
			(start 9.36244 -5.171694)
			(end 9.302242 -5.171694)
			(stroke
				(width 0.1)
				(type default)
			)
			(layer "F.SilkS")
		)
		(fp_line
			(start 9.36244 -5.171694)
			(end 9.302242 -5.171694)
			(stroke
				(width 0.1)
				(type default)
			)
			(layer "F.SilkS")
		)
		(fp_line
			(start 9.36752 -3.272028)
			(end 9.379712 -3.34137)
			(stroke
				(width 0.1)
				(type default)
			)
			(layer "F.SilkS")
		)
		(fp_line
			(start 9.36752 -3.272028)
			(end 9.379712 -3.34137)
			(stroke
				(width 0.1)
				(type default)
			)
			(layer "F.SilkS")
		)
		(fp_line
			(start 9.379712 -3.34137)
			(end 9.391904 -3.410712)
			(stroke
				(width 0.1)
				(type default)
			)
			(layer "F.SilkS")
		)
		(fp_line
			(start 9.379712 -3.34137)
			(end 9.391904 -3.410712)
			(stroke
				(width 0.1)
				(type default)
			)
			(layer "F.SilkS")
		)
		(fp_line
			(start 9.404096 -3.480054)
			(end 9.391904 -3.410712)
			(stroke
				(width 0.1)
				(type default)
			)
			(layer "F.SilkS")
		)
		(fp_line
			(start 9.404096 -3.480054)
			(end 9.391904 -3.410712)
			(stroke
				(width 0.1)
				(type default)
			)
			(layer "F.SilkS")
		)
		(fp_line
			(start 9.416288 -3.54965)
			(end 6.565392 -0.815086)
			(stroke
				(width 0.1)
				(type default)
			)
			(layer "F.SilkS")
		)
		(fp_line
			(start 9.416288 -3.54965)
			(end 6.565392 -0.815086)
			(stroke
				(width 0.1)
				(type default)
			)
			(layer "F.SilkS")
		)
		(fp_line
			(start 9.416288 -3.54965)
			(end 9.404096 -3.480054)
			(stroke
				(width 0.1)
				(type default)
			)
			(layer "F.SilkS")
		)
		(fp_line
			(start 9.416288 -3.54965)
			(end 9.404096 -3.480054)
			(stroke
				(width 0.1)
				(type default)
			)
			(layer "F.SilkS")
		)
		(fp_line
			(start 9.416288 -3.54965)
			(end 9.42848 -3.618992)
			(stroke
				(width 0.1)
				(type default)
			)
			(layer "F.SilkS")
		)
		(fp_line
			(start 9.416288 -3.54965)
			(end 9.42848 -3.618992)
			(stroke
				(width 0.1)
				(type default)
			)
			(layer "F.SilkS")
		)
		(fp_line
			(start 9.422638 -5.171694)
			(end 8.401558 -4.19227)
			(stroke
				(width 0.1)
				(type default)
			)
			(layer "F.SilkS")
		)
		(fp_line
			(start 9.422638 -5.171694)
			(end 8.401558 -4.19227)
			(stroke
				(width 0.1)
				(type default)
			)
			(layer "F.SilkS")
		)
		(fp_line
			(start 9.422638 -5.171694)
			(end 9.36244 -5.171694)
			(stroke
				(width 0.1)
				(type default)
			)
			(layer "F.SilkS")
		)
		(fp_line
			(start 9.422638 -5.171694)
			(end 9.36244 -5.171694)
			(stroke
				(width 0.1)
				(type default)
			)
			(layer "F.SilkS")
		)
		(fp_line
			(start 9.42848 -3.618992)
			(end 9.440672 -3.688334)
			(stroke
				(width 0.1)
				(type default)
			)
			(layer "F.SilkS")
		)
		(fp_line
			(start 9.42848 -3.618992)
			(end 9.440672 -3.688334)
			(stroke
				(width 0.1)
				(type default)
			)
			(layer "F.SilkS")
		)
		(fp_line
			(start 9.440672 -3.688334)
			(end 9.452864 -3.75793)
			(stroke
				(width 0.1)
				(type default)
			)
			(layer "F.SilkS")
		)
		(fp_line
			(start 9.440672 -3.688334)
			(end 9.452864 -3.75793)
			(stroke
				(width 0.1)
				(type default)
			)
			(layer "F.SilkS")
		)
		(fp_line
			(start 9.465056 -3.827526)
			(end 9.452864 -3.75793)
			(stroke
				(width 0.1)
				(type default)
			)
			(layer "F.SilkS")
		)
		(fp_line
			(start 9.465056 -3.827526)
			(end 9.452864 -3.75793)
			(stroke
				(width 0.1)
				(type default)
			)
			(layer "F.SilkS")
		)
		(fp_line
			(start 9.465056 -3.827526)
			(end 9.477248 -3.896614)
			(stroke
				(width 0.1)
				(type default)
			)
			(layer "F.SilkS")
		)
		(fp_line
			(start 9.465056 -3.827526)
			(end 9.477248 -3.896614)
			(stroke
				(width 0.1)
				(type default)
			)
			(layer "F.SilkS")
		)
		(fp_line
			(start 9.477248 -3.896614)
			(end 8.107172 -2.582418)
			(stroke
				(width 0.1)
				(type default)
			)
			(layer "F.SilkS")
		)
		(fp_line
			(start 9.477248 -3.896614)
			(end 8.107172 -2.582418)
			(stroke
				(width 0.1)
				(type default)
			)
			(layer "F.SilkS")
		)
		(fp_line
			(start 9.477248 -3.896614)
			(end 9.48944 -3.965956)
			(stroke
				(width 0.1)
				(type default)
			)
			(layer "F.SilkS")
		)
		(fp_line
			(start 9.477248 -3.896614)
			(end 9.48944 -3.965956)
			(stroke
				(width 0.1)
				(type default)
			)
			(layer "F.SilkS")
		)
		(fp_line
			(start 9.482836 -5.171694)
			(end 8.389366 -4.122674)
			(stroke
				(width 0.1)
				(type default)
			)
			(layer "F.SilkS")
		)
		(fp_line
			(start 9.482836 -5.171694)
			(end 8.389366 -4.122674)
			(stroke
				(width 0.1)
				(type default)
			)
			(layer "F.SilkS")
		)
		(fp_line
			(start 9.482836 -5.171694)
			(end 9.422638 -5.171694)
			(stroke
				(width 0.1)
				(type default)
			)
			(layer "F.SilkS")
		)
		(fp_line
			(start 9.482836 -5.171694)
			(end 9.422638 -5.171694)
			(stroke
				(width 0.1)
				(type default)
			)
			(layer "F.SilkS")
		)
		(fp_line
			(start 9.48944 -3.965956)
			(end 8.123682 -2.655824)
			(stroke
				(width 0.1)
				(type default)
			)
			(layer "F.SilkS")
		)
		(fp_line
			(start 9.48944 -3.965956)
			(end 8.123682 -2.655824)
			(stroke
				(width 0.1)
				(type default)
			)
			(layer "F.SilkS")
		)
		(fp_line
			(start 9.48944 -3.965956)
			(end 9.501632 -4.035552)
			(stroke
				(width 0.1)
				(type default)
			)
			(layer "F.SilkS")
		)
		(fp_line
			(start 9.48944 -3.965956)
			(end 9.501632 -4.035552)
			(stroke
				(width 0.1)
				(type default)
			)
			(layer "F.SilkS")
		)
		(fp_line
			(start 9.501632 -4.035552)
			(end 8.140446 -2.729738)
			(stroke
				(width 0.1)
				(type default)
			)
			(layer "F.SilkS")
		)
		(fp_line
			(start 9.501632 -4.035552)
			(end 8.140446 -2.729738)
			(stroke
				(width 0.1)
				(type default)
			)
			(layer "F.SilkS")
		)
		(fp_line
			(start 9.501632 -4.035552)
			(end 9.513824 -4.104894)
			(stroke
				(width 0.1)
				(type default)
			)
			(layer "F.SilkS")
		)
		(fp_line
			(start 9.501632 -4.035552)
			(end 9.513824 -4.104894)
			(stroke
				(width 0.1)
				(type default)
			)
			(layer "F.SilkS")
		)
		(fp_line
			(start 9.513824 -4.104894)
			(end 8.156956 -2.803398)
			(stroke
				(width 0.1)
				(type default)
			)
			(layer "F.SilkS")
		)
		(fp_line
			(start 9.513824 -4.104894)
			(end 8.156956 -2.803398)
			(stroke
				(width 0.1)
				(type default)
			)
			(layer "F.SilkS")
		)
		(fp_line
			(start 9.513824 -4.104894)
			(end 9.526016 -4.174236)
			(stroke
				(width 0.1)
				(type default)
			)
			(layer "F.SilkS")
		)
		(fp_line
			(start 9.513824 -4.104894)
			(end 9.526016 -4.174236)
			(stroke
				(width 0.1)
				(type default)
			)
			(layer "F.SilkS")
		)
		(fp_line
			(start 9.526016 -4.174236)
			(end 8.170418 -2.87401)
			(stroke
				(width 0.1)
				(type default)
			)
			(layer "F.SilkS")
		)
		(fp_line
			(start 9.526016 -4.174236)
			(end 8.170418 -2.87401)
			(stroke
				(width 0.1)
				(type default)
			)
			(layer "F.SilkS")
		)
		(fp_line
			(start 9.526016 -4.174236)
			(end 9.538208 -4.243578)
			(stroke
				(width 0.1)
				(type default)
			)
			(layer "F.SilkS")
		)
		(fp_line
			(start 9.526016 -4.174236)
			(end 9.538208 -4.243578)
			(stroke
				(width 0.1)
				(type default)
			)
			(layer "F.SilkS")
		)
		(fp_line
			(start 9.538208 -4.243578)
			(end 8.18261 -2.943352)
			(stroke
				(width 0.1)
				(type default)
			)
			(layer "F.SilkS")
		)
		(fp_line
			(start 9.538208 -4.243578)
			(end 8.18261 -2.943352)
			(stroke
				(width 0.1)
				(type default)
			)
			(layer "F.SilkS")
		)
		(fp_line
			(start 9.538208 -4.243578)
			(end 9.5504 -4.313174)
			(stroke
				(width 0.1)
				(type default)
			)
			(layer "F.SilkS")
		)
		(fp_line
			(start 9.538208 -4.243578)
			(end 9.5504 -4.313174)
			(stroke
				(width 0.1)
				(type default)
			)
			(layer "F.SilkS")
		)
		(fp_line
			(start 9.543034 -5.171694)
			(end 8.377174 -4.053332)
			(stroke
				(width 0.1)
				(type default)
			)
			(layer "F.SilkS")
		)
		(fp_line
			(start 9.543034 -5.171694)
			(end 8.377174 -4.053332)
			(stroke
				(width 0.1)
				(type default)
			)
			(layer "F.SilkS")
		)
		(fp_line
			(start 9.543034 -5.171694)
			(end 9.482836 -5.171694)
			(stroke
				(width 0.1)
				(type default)
			)
			(layer "F.SilkS")
		)
		(fp_line
			(start 9.543034 -5.171694)
			(end 9.482836 -5.171694)
			(stroke
				(width 0.1)
				(type default)
			)
			(layer "F.SilkS")
		)
		(fp_line
			(start 9.5504 -4.313174)
			(end 8.194802 -3.012694)
			(stroke
				(width 0.1)
				(type default)
			)
			(layer "F.SilkS")
		)
		(fp_line
			(start 9.5504 -4.313174)
			(end 8.194802 -3.012694)
			(stroke
				(width 0.1)
				(type default)
			)
			(layer "F.SilkS")
		)
		(fp_line
			(start 9.5504 -4.313174)
			(end 9.562592 -4.382516)
			(stroke
				(width 0.1)
				(type default)
			)
			(layer "F.SilkS")
		)
		(fp_line
			(start 9.5504 -4.313174)
			(end 9.562592 -4.382516)
			(stroke
				(width 0.1)
				(type default)
			)
			(layer "F.SilkS")
		)
		(fp_line
			(start 9.562592 -4.382516)
			(end 8.206994 -3.08229)
			(stroke
				(width 0.1)
				(type default)
			)
			(layer "F.SilkS")
		)
		(fp_line
			(start 9.562592 -4.382516)
			(end 8.206994 -3.08229)
			(stroke
				(width 0.1)
				(type default)
			)
			(layer "F.SilkS")
		)
		(fp_line
			(start 9.562592 -4.382516)
			(end 9.574784 -4.452112)
			(stroke
				(width 0.1)
				(type default)
			)
			(layer "F.SilkS")
		)
		(fp_line
			(start 9.562592 -4.382516)
			(end 9.574784 -4.452112)
			(stroke
				(width 0.1)
				(type default)
			)
			(layer "F.SilkS")
		)
		(fp_line
			(start 9.574784 -4.452112)
			(end 8.219186 -3.151378)
			(stroke
				(width 0.1)
				(type default)
			)
			(layer "F.SilkS")
		)
		(fp_line
			(start 9.574784 -4.452112)
			(end 8.219186 -3.151378)
			(stroke
				(width 0.1)
				(type default)
			)
			(layer "F.SilkS")
		)
		(fp_line
			(start 9.574784 -4.452112)
			(end 9.586976 -4.5212)
			(stroke
				(width 0.1)
				(type default)
			)
			(layer "F.SilkS")
		)
		(fp_line
			(start 9.574784 -4.452112)
			(end 9.586976 -4.5212)
			(stroke
				(width 0.1)
				(type default)
			)
			(layer "F.SilkS")
		)
		(fp_line
			(start 9.586976 -4.5212)
			(end 8.231378 -3.22072)
			(stroke
				(width 0.1)
				(type default)
			)
			(layer "F.SilkS")
		)
		(fp_line
			(start 9.586976 -4.5212)
			(end 8.231378 -3.22072)
			(stroke
				(width 0.1)
				(type default)
			)
			(layer "F.SilkS")
		)
		(fp_line
			(start 9.586976 -4.5212)
			(end 9.599168 -4.590796)
			(stroke
				(width 0.1)
				(type default)
			)
			(layer "F.SilkS")
		)
		(fp_line
			(start 9.586976 -4.5212)
			(end 9.599168 -4.590796)
			(stroke
				(width 0.1)
				(type default)
			)
			(layer "F.SilkS")
		)
		(fp_line
			(start 9.599168 -4.590796)
			(end 8.24357 -3.290316)
			(stroke
				(width 0.1)
				(type default)
			)
			(layer "F.SilkS")
		)
		(fp_line
			(start 9.599168 -4.590796)
			(end 8.24357 -3.290316)
			(stroke
				(width 0.1)
				(type default)
			)
			(layer "F.SilkS")
		)
		(fp_line
			(start 9.599168 -4.590796)
			(end 9.61136 -4.660138)
			(stroke
				(width 0.1)
				(type default)
			)
			(layer "F.SilkS")
		)
		(fp_line
			(start 9.599168 -4.590796)
			(end 9.61136 -4.660138)
			(stroke
				(width 0.1)
				(type default)
			)
			(layer "F.SilkS")
		)
		(fp_line
			(start 9.603232 -5.171694)
			(end 8.365236 -3.98399)
			(stroke
				(width 0.1)
				(type default)
			)
			(layer "F.SilkS")
		)
		(fp_line
			(start 9.603232 -5.171694)
			(end 8.365236 -3.98399)
			(stroke
				(width 0.1)
				(type default)
			)
			(layer "F.SilkS")
		)
		(fp_line
			(start 9.603232 -5.171694)
			(end 9.543034 -5.171694)
			(stroke
				(width 0.1)
				(type default)
			)
			(layer "F.SilkS")
		)
		(fp_line
			(start 9.603232 -5.171694)
			(end 9.543034 -5.171694)
			(stroke
				(width 0.1)
				(type default)
			)
			(layer "F.SilkS")
		)
		(fp_line
			(start 9.61136 -4.660138)
			(end 8.255762 -3.359658)
			(stroke
				(width 0.1)
				(type default)
			)
			(layer "F.SilkS")
		)
		(fp_line
			(start 9.61136 -4.660138)
			(end 8.255762 -3.359658)
			(stroke
				(width 0.1)
				(type default)
			)
			(layer "F.SilkS")
		)
		(fp_line
			(start 9.61136 -4.660138)
			(end 9.623552 -4.729734)
			(stroke
				(width 0.1)
				(type default)
			)
			(layer "F.SilkS")
		)
		(fp_line
			(start 9.61136 -4.660138)
			(end 9.623552 -4.729734)
			(stroke
				(width 0.1)
				(type default)
			)
			(layer "F.SilkS")
		)
		(fp_line
			(start 9.623552 -4.729734)
			(end 8.2677 -3.429)
			(stroke
				(width 0.1)
				(type default)
			)
			(layer "F.SilkS")
		)
		(fp_line
			(start 9.623552 -4.729734)
			(end 8.2677 -3.429)
			(stroke
				(width 0.1)
				(type default)
			)
			(layer "F.SilkS")
		)
		(fp_line
			(start 9.623552 -4.729734)
			(end 9.635744 -4.798822)
			(stroke
				(width 0.1)
				(type default)
			)
			(layer "F.SilkS")
		)
		(fp_line
			(start 9.623552 -4.729734)
			(end 9.635744 -4.798822)
			(stroke
				(width 0.1)
				(type default)
			)
			(layer "F.SilkS")
		)
		(fp_line
			(start 9.635744 -4.798822)
			(end 8.279892 -3.498342)
			(stroke
				(width 0.1)
				(type default)
			)
			(layer "F.SilkS")
		)
		(fp_line
			(start 9.635744 -4.798822)
			(end 8.279892 -3.498342)
			(stroke
				(width 0.1)
				(type default)
			)
			(layer "F.SilkS")
		)
		(fp_line
			(start 9.635744 -4.798822)
			(end 9.64819 -4.868418)
			(stroke
				(width 0.1)
				(type default)
			)
			(layer "F.SilkS")
		)
		(fp_line
			(start 9.635744 -4.798822)
			(end 9.64819 -4.868418)
			(stroke
				(width 0.1)
				(type default)
			)
			(layer "F.SilkS")
		)
		(fp_line
			(start 9.64819 -4.868418)
			(end 8.292084 -3.567684)
			(stroke
				(width 0.1)
				(type default)
			)
			(layer "F.SilkS")
		)
		(fp_line
			(start 9.64819 -4.868418)
			(end 8.292084 -3.567684)
			(stroke
				(width 0.1)
				(type default)
			)
			(layer "F.SilkS")
		)
		(fp_line
			(start 9.64819 -4.868418)
			(end 9.660382 -4.938014)
			(stroke
				(width 0.1)
				(type default)
			)
			(layer "F.SilkS")
		)
		(fp_line
			(start 9.64819 -4.868418)
			(end 9.660382 -4.938014)
			(stroke
				(width 0.1)
				(type default)
			)
			(layer "F.SilkS")
		)
		(fp_line
			(start 9.660382 -4.938014)
			(end 8.304276 -3.63728)
			(stroke
				(width 0.1)
				(type default)
			)
			(layer "F.SilkS")
		)
		(fp_line
			(start 9.660382 -4.938014)
			(end 8.304276 -3.63728)
			(stroke
				(width 0.1)
				(type default)
			)
			(layer "F.SilkS")
		)
		(fp_line
			(start 9.660382 -4.938014)
			(end 9.67232 -5.007356)
			(stroke
				(width 0.1)
				(type default)
			)
			(layer "F.SilkS")
		)
		(fp_line
			(start 9.660382 -4.938014)
			(end 9.67232 -5.007356)
			(stroke
				(width 0.1)
				(type default)
			)
			(layer "F.SilkS")
		)
		(fp_line
			(start 9.663176 -5.171694)
			(end 8.35279 -3.914648)
			(stroke
				(width 0.1)
				(type default)
			)
			(layer "F.SilkS")
		)
		(fp_line
			(start 9.663176 -5.171694)
			(end 8.35279 -3.914648)
			(stroke
				(width 0.1)
				(type default)
			)
			(layer "F.SilkS")
		)
		(fp_line
			(start 9.663176 -5.171694)
			(end 9.603232 -5.171694)
			(stroke
				(width 0.1)
				(type default)
			)
			(layer "F.SilkS")
		)
		(fp_line
			(start 9.663176 -5.171694)
			(end 9.603232 -5.171694)
			(stroke
				(width 0.1)
				(type default)
			)
			(layer "F.SilkS")
		)
		(fp_line
			(start 9.67232 -5.007356)
			(end 8.316468 -3.706368)
			(stroke
				(width 0.1)
				(type default)
			)
			(layer "F.SilkS")
		)
		(fp_line
			(start 9.67232 -5.007356)
			(end 8.316468 -3.706368)
			(stroke
				(width 0.1)
				(type default)
			)
			(layer "F.SilkS")
		)
		(fp_line
			(start 9.67232 -5.007356)
			(end 9.684512 -5.076698)
			(stroke
				(width 0.1)
				(type default)
			)
			(layer "F.SilkS")
		)
		(fp_line
			(start 9.67232 -5.007356)
			(end 9.684512 -5.076698)
			(stroke
				(width 0.1)
				(type default)
			)
			(layer "F.SilkS")
		)
		(fp_line
			(start 9.684512 -5.076698)
			(end 8.32866 -3.77571)
			(stroke
				(width 0.1)
				(type default)
			)
			(layer "F.SilkS")
		)
		(fp_line
			(start 9.684512 -5.076698)
			(end 8.32866 -3.77571)
			(stroke
				(width 0.1)
				(type default)
			)
			(layer "F.SilkS")
		)
		(fp_line
			(start 9.684512 -5.076698)
			(end 9.696704 -5.14604)
			(stroke
				(width 0.1)
				(type default)
			)
			(layer "F.SilkS")
		)
		(fp_line
			(start 9.684512 -5.076698)
			(end 9.696704 -5.14604)
			(stroke
				(width 0.1)
				(type default)
			)
			(layer "F.SilkS")
		)
		(fp_line
			(start 9.696704 -5.14604)
			(end 8.340852 -3.845306)
			(stroke
				(width 0.1)
				(type default)
			)
			(layer "F.SilkS")
		)
		(fp_line
			(start 9.696704 -5.14604)
			(end 8.340852 -3.845306)
			(stroke
				(width 0.1)
				(type default)
			)
			(layer "F.SilkS")
		)
		(fp_line
			(start 9.696704 -5.14604)
			(end 9.701276 -5.171694)
			(stroke
				(width 0.1)
				(type default)
			)
			(layer "F.SilkS")
		)
		(fp_line
			(start 9.696704 -5.14604)
			(end 9.701276 -5.171694)
			(stroke
				(width 0.1)
				(type default)
			)
			(layer "F.SilkS")
		)
		(fp_line
			(start 9.701276 -5.171694)
			(end 9.663176 -5.171694)
			(stroke
				(width 0.1)
				(type default)
			)
			(layer "F.SilkS")
		)
		(fp_line
			(start 9.701276 -5.171694)
			(end 9.663176 -5.171694)
			(stroke
				(width 0.1)
				(type default)
			)
			(layer "F.SilkS")
		)
		(fp_line
			(start 9.754616 -1.96977)
			(end 11.590528 -3.730752)
			(stroke
				(width 0.1)
				(type default)
			)
			(layer "F.SilkS")
		)
		(fp_line
			(start 9.754616 -1.96977)
			(end 11.590528 -3.730752)
			(stroke
				(width 0.1)
				(type default)
			)
			(layer "F.SilkS")
		)
		(fp_line
			(start 9.75614 -2.028698)
			(end 11.526012 -3.726688)
			(stroke
				(width 0.1)
				(type default)
			)
			(layer "F.SilkS")
		)
		(fp_line
			(start 9.75614 -2.028698)
			(end 11.526012 -3.726688)
			(stroke
				(width 0.1)
				(type default)
			)
			(layer "F.SilkS")
		)
		(fp_line
			(start 9.75741 -2.08788)
			(end 11.46175 -3.722878)
			(stroke
				(width 0.1)
				(type default)
			)
			(layer "F.SilkS")
		)
		(fp_line
			(start 9.75741 -2.08788)
			(end 11.46175 -3.722878)
			(stroke
				(width 0.1)
				(type default)
			)
			(layer "F.SilkS")
		)
		(fp_line
			(start 9.758172 -1.915414)
			(end 11.65479 -3.734816)
			(stroke
				(width 0.1)
				(type default)
			)
			(layer "F.SilkS")
		)
		(fp_line
			(start 9.758172 -1.915414)
			(end 11.65479 -3.734816)
			(stroke
				(width 0.1)
				(type default)
			)
			(layer "F.SilkS")
		)
		(fp_line
			(start 9.760458 -2.148332)
			(end 11.394694 -3.71602)
			(stroke
				(width 0.1)
				(type default)
			)
			(layer "F.SilkS")
		)
		(fp_line
			(start 9.760458 -2.148332)
			(end 11.394694 -3.71602)
			(stroke
				(width 0.1)
				(type default)
			)
			(layer "F.SilkS")
		)
		(fp_line
			(start 9.762998 -1.862074)
			(end 11.719052 -3.738626)
			(stroke
				(width 0.1)
				(type default)
			)
			(layer "F.SilkS")
		)
		(fp_line
			(start 9.762998 -1.862074)
			(end 11.719052 -3.738626)
			(stroke
				(width 0.1)
				(type default)
			)
			(layer "F.SilkS")
		)
		(fp_line
			(start 9.76757 -1.808988)
			(end 11.782044 -3.74142)
			(stroke
				(width 0.1)
				(type default)
			)
			(layer "F.SilkS")
		)
		(fp_line
			(start 9.76757 -1.808988)
			(end 11.782044 -3.74142)
			(stroke
				(width 0.1)
				(type default)
			)
			(layer "F.SilkS")
		)
		(fp_line
			(start 9.768586 -2.214118)
			(end 11.319002 -3.701288)
			(stroke
				(width 0.1)
				(type default)
			)
			(layer "F.SilkS")
		)
		(fp_line
			(start 9.768586 -2.214118)
			(end 11.319002 -3.701288)
			(stroke
				(width 0.1)
				(type default)
			)
			(layer "F.SilkS")
		)
		(fp_line
			(start 9.77646 -1.759712)
			(end 11.83894 -3.738372)
			(stroke
				(width 0.1)
				(type default)
			)
			(layer "F.SilkS")
		)
		(fp_line
			(start 9.77646 -1.759712)
			(end 11.83894 -3.738372)
			(stroke
				(width 0.1)
				(type default)
			)
			(layer "F.SilkS")
		)
		(fp_line
			(start 9.777222 -2.279904)
			(end 11.24331 -3.686556)
			(stroke
				(width 0.1)
				(type default)
			)
			(layer "F.SilkS")
		)
		(fp_line
			(start 9.777222 -2.279904)
			(end 11.24331 -3.686556)
			(stroke
				(width 0.1)
				(type default)
			)
			(layer "F.SilkS")
		)
		(fp_line
			(start 9.78662 -1.711706)
			(end 11.89609 -3.735324)
			(stroke
				(width 0.1)
				(type default)
			)
			(layer "F.SilkS")
		)
		(fp_line
			(start 9.78662 -1.711706)
			(end 11.89609 -3.735324)
			(stroke
				(width 0.1)
				(type default)
			)
			(layer "F.SilkS")
		)
		(fp_line
			(start 9.79043 -2.350262)
			(end 11.167872 -3.67157)
			(stroke
				(width 0.1)
				(type default)
			)
			(layer "F.SilkS")
		)
		(fp_line
			(start 9.79043 -2.350262)
			(end 11.167872 -3.67157)
			(stroke
				(width 0.1)
				(type default)
			)
			(layer "F.SilkS")
		)
		(fp_line
			(start 9.797034 -1.663954)
			(end 11.952986 -3.732276)
			(stroke
				(width 0.1)
				(type default)
			)
			(layer "F.SilkS")
		)
		(fp_line
			(start 9.797034 -1.663954)
			(end 11.952986 -3.732276)
			(stroke
				(width 0.1)
				(type default)
			)
			(layer "F.SilkS")
		)
		(fp_line
			(start 9.809988 -1.618742)
			(end 12.010136 -3.729482)
			(stroke
				(width 0.1)
				(type default)
			)
			(layer "F.SilkS")
		)
		(fp_line
			(start 9.809988 -1.618742)
			(end 12.010136 -3.729482)
			(stroke
				(width 0.1)
				(type default)
			)
			(layer "F.SilkS")
		)
		(fp_line
			(start 9.812528 -2.429256)
			(end 11.09218 -3.656838)
			(stroke
				(width 0.1)
				(type default)
			)
			(layer "F.SilkS")
		)
		(fp_line
			(start 9.812528 -2.429256)
			(end 11.09218 -3.656838)
			(stroke
				(width 0.1)
				(type default)
			)
			(layer "F.SilkS")
		)
		(fp_line
			(start 9.825228 -1.575562)
			(end 12.063984 -3.723132)
			(stroke
				(width 0.1)
				(type default)
			)
			(layer "F.SilkS")
		)
		(fp_line
			(start 9.825228 -1.575562)
			(end 12.063984 -3.723132)
			(stroke
				(width 0.1)
				(type default)
			)
			(layer "F.SilkS")
		)
		(fp_line
			(start 9.834626 -2.507996)
			(end 11.00201 -3.627882)
			(stroke
				(width 0.1)
				(type default)
			)
			(layer "F.SilkS")
		)
		(fp_line
			(start 9.834626 -2.507996)
			(end 11.00201 -3.627882)
			(stroke
				(width 0.1)
				(type default)
			)
			(layer "F.SilkS")
		)
		(fp_line
			(start 9.840214 -1.532382)
			(end 12.115038 -3.714496)
			(stroke
				(width 0.1)
				(type default)
			)
			(layer "F.SilkS")
		)
		(fp_line
			(start 9.840214 -1.532382)
			(end 12.115038 -3.714496)
			(stroke
				(width 0.1)
				(type default)
			)
			(layer "F.SilkS")
		)
		(fp_line
			(start 9.856978 -2.587244)
			(end 10.90676 -3.594354)
			(stroke
				(width 0.1)
				(type default)
			)
			(layer "F.SilkS")
		)
		(fp_line
			(start 9.856978 -2.587244)
			(end 10.90676 -3.594354)
			(stroke
				(width 0.1)
				(type default)
			)
			(layer "F.SilkS")
		)
		(fp_line
			(start 9.857232 -1.49098)
			(end 12.165838 -3.705352)
			(stroke
				(width 0.1)
				(type default)
			)
			(layer "F.SilkS")
		)
		(fp_line
			(start 9.857232 -1.49098)
			(end 12.165838 -3.705352)
			(stroke
				(width 0.1)
				(type default)
			)
			(layer "F.SilkS")
		)
		(fp_line
			(start 9.87679 -1.452118)
			(end 10.97661 -2.50698)
			(stroke
				(width 0.1)
				(type default)
			)
			(layer "F.SilkS")
		)
		(fp_line
			(start 9.87679 -1.452118)
			(end 10.97661 -2.50698)
			(stroke
				(width 0.1)
				(type default)
			)
			(layer "F.SilkS")
		)
		(fp_line
			(start 9.884664 -2.671572)
			(end 10.811764 -3.560826)
			(stroke
				(width 0.1)
				(type default)
			)
			(layer "F.SilkS")
		)
		(fp_line
			(start 9.884664 -2.671572)
			(end 10.811764 -3.560826)
			(stroke
				(width 0.1)
				(type default)
			)
			(layer "F.SilkS")
		)
		(fp_line
			(start 9.896602 -1.413256)
			(end 10.944606 -2.418588)
			(stroke
				(width 0.1)
				(type default)
			)
			(layer "F.SilkS")
		)
		(fp_line
			(start 9.896602 -1.413256)
			(end 10.944606 -2.418588)
			(stroke
				(width 0.1)
				(type default)
			)
			(layer "F.SilkS")
		)
		(fp_line
			(start 9.916922 -1.375156)
			(end 10.912856 -2.33045)
			(stroke
				(width 0.1)
				(type default)
			)
			(layer "F.SilkS")
		)
		(fp_line
			(start 9.916922 -1.375156)
			(end 10.912856 -2.33045)
			(stroke
				(width 0.1)
				(type default)
			)
			(layer "F.SilkS")
		)
		(fp_line
			(start 9.940798 -1.340358)
			(end 10.903712 -2.263902)
			(stroke
				(width 0.1)
				(type default)
			)
			(layer "F.SilkS")
		)
		(fp_line
			(start 9.940798 -1.340358)
			(end 10.903712 -2.263902)
			(stroke
				(width 0.1)
				(type default)
			)
			(layer "F.SilkS")
		)
		(fp_line
			(start 9.945116 -2.787142)
			(end 10.69721 -3.508502)
			(stroke
				(width 0.1)
				(type default)
			)
			(layer "F.SilkS")
		)
		(fp_line
			(start 9.945116 -2.787142)
			(end 10.69721 -3.508502)
			(stroke
				(width 0.1)
				(type default)
			)
			(layer "F.SilkS")
		)
		(fp_line
			(start 9.964674 -1.30556)
			(end 10.898632 -2.201418)
			(stroke
				(width 0.1)
				(type default)
			)
			(layer "F.SilkS")
		)
		(fp_line
			(start 9.964674 -1.30556)
			(end 10.898632 -2.201418)
			(stroke
				(width 0.1)
				(type default)
			)
			(layer "F.SilkS")
		)
		(fp_line
			(start 9.98855 -1.270508)
			(end 10.902442 -2.147316)
			(stroke
				(width 0.1)
				(type default)
			)
			(layer "F.SilkS")
		)
		(fp_line
			(start 9.98855 -1.270508)
			(end 10.902442 -2.147316)
			(stroke
				(width 0.1)
				(type default)
			)
			(layer "F.SilkS")
		)
		(fp_line
			(start 10.005568 -2.902966)
			(end 10.557002 -3.431794)
			(stroke
				(width 0.1)
				(type default)
			)
			(layer "F.SilkS")
		)
		(fp_line
			(start 10.005568 -2.902966)
			(end 10.557002 -3.431794)
			(stroke
				(width 0.1)
				(type default)
			)
			(layer "F.SilkS")
		)
		(fp_line
			(start 10.015982 -1.239266)
			(end 10.90803 -2.094992)
			(stroke
				(width 0.1)
				(type default)
			)
			(layer "F.SilkS")
		)
		(fp_line
			(start 10.015982 -1.239266)
			(end 10.90803 -2.094992)
			(stroke
				(width 0.1)
				(type default)
			)
			(layer "F.SilkS")
		)
		(fp_line
			(start 10.043668 -1.208278)
			(end 10.921238 -2.04978)
			(stroke
				(width 0.1)
				(type default)
			)
			(layer "F.SilkS")
		)
		(fp_line
			(start 10.043668 -1.208278)
			(end 10.921238 -2.04978)
			(stroke
				(width 0.1)
				(type default)
			)
			(layer "F.SilkS")
		)
		(fp_line
			(start 10.071608 -1.17729)
			(end 10.9347 -2.00533)
			(stroke
				(width 0.1)
				(type default)
			)
			(layer "F.SilkS")
		)
		(fp_line
			(start 10.071608 -1.17729)
			(end 10.9347 -2.00533)
			(stroke
				(width 0.1)
				(type default)
			)
			(layer "F.SilkS")
		)
		(fp_line
			(start 10.102088 -1.148588)
			(end 10.956798 -1.9685)
			(stroke
				(width 0.1)
				(type default)
			)
			(layer "F.SilkS")
		)
		(fp_line
			(start 10.102088 -1.148588)
			(end 10.956798 -1.9685)
			(stroke
				(width 0.1)
				(type default)
			)
			(layer "F.SilkS")
		)
		(fp_line
			(start 10.133584 -1.121156)
			(end 10.978642 -1.931924)
			(stroke
				(width 0.1)
				(type default)
			)
			(layer "F.SilkS")
		)
		(fp_line
			(start 10.133584 -1.121156)
			(end 10.978642 -1.931924)
			(stroke
				(width 0.1)
				(type default)
			)
			(layer "F.SilkS")
		)
		(fp_line
			(start 10.16508 -1.093724)
			(end 11.006582 -1.90119)
			(stroke
				(width 0.1)
				(type default)
			)
			(layer "F.SilkS")
		)
		(fp_line
			(start 10.16508 -1.093724)
			(end 11.006582 -1.90119)
			(stroke
				(width 0.1)
				(type default)
			)
			(layer "F.SilkS")
		)
		(fp_line
			(start 10.198354 -1.067816)
			(end 11.037062 -1.872742)
			(stroke
				(width 0.1)
				(type default)
			)
			(layer "F.SilkS")
		)
		(fp_line
			(start 10.198354 -1.067816)
			(end 11.037062 -1.872742)
			(stroke
				(width 0.1)
				(type default)
			)
			(layer "F.SilkS")
		)
		(fp_line
			(start 10.233406 -1.043686)
			(end 11.06932 -1.845818)
			(stroke
				(width 0.1)
				(type default)
			)
			(layer "F.SilkS")
		)
		(fp_line
			(start 10.233406 -1.043686)
			(end 11.06932 -1.845818)
			(stroke
				(width 0.1)
				(type default)
			)
			(layer "F.SilkS")
		)
		(fp_line
			(start 10.268458 -1.01981)
			(end 11.108182 -1.825244)
			(stroke
				(width 0.1)
				(type default)
			)
			(layer "F.SilkS")
		)
		(fp_line
			(start 10.268458 -1.01981)
			(end 11.108182 -1.825244)
			(stroke
				(width 0.1)
				(type default)
			)
			(layer "F.SilkS")
		)
		(fp_line
			(start 10.30478 -0.99695)
			(end 11.147044 -1.804924)
			(stroke
				(width 0.1)
				(type default)
			)
			(layer "F.SilkS")
		)
		(fp_line
			(start 10.30478 -0.99695)
			(end 11.147044 -1.804924)
			(stroke
				(width 0.1)
				(type default)
			)
			(layer "F.SilkS")
		)
		(fp_line
			(start 10.343388 -0.976122)
			(end 11.190478 -1.788922)
			(stroke
				(width 0.1)
				(type default)
			)
			(layer "F.SilkS")
		)
		(fp_line
			(start 10.343388 -0.976122)
			(end 11.190478 -1.788922)
			(stroke
				(width 0.1)
				(type default)
			)
			(layer "F.SilkS")
		)
		(fp_line
			(start 10.381996 -0.955548)
			(end 11.237722 -1.776476)
			(stroke
				(width 0.1)
				(type default)
			)
			(layer "F.SilkS")
		)
		(fp_line
			(start 10.381996 -0.955548)
			(end 11.237722 -1.776476)
			(stroke
				(width 0.1)
				(type default)
			)
			(layer "F.SilkS")
		)
		(fp_line
			(start 10.421366 -0.935482)
			(end 11.28522 -1.76403)
			(stroke
				(width 0.1)
				(type default)
			)
			(layer "F.SilkS")
		)
		(fp_line
			(start 10.421366 -0.935482)
			(end 11.28522 -1.76403)
			(stroke
				(width 0.1)
				(type default)
			)
			(layer "F.SilkS")
		)
		(fp_line
			(start 10.46353 -0.918464)
			(end 11.33856 -1.75768)
			(stroke
				(width 0.1)
				(type default)
			)
			(layer "F.SilkS")
		)
		(fp_line
			(start 10.46353 -0.918464)
			(end 11.33856 -1.75768)
			(stroke
				(width 0.1)
				(type default)
			)
			(layer "F.SilkS")
		)
		(fp_line
			(start 10.505694 -0.901192)
			(end 11.39444 -1.753616)
			(stroke
				(width 0.1)
				(type default)
			)
			(layer "F.SilkS")
		)
		(fp_line
			(start 10.505694 -0.901192)
			(end 11.39444 -1.753616)
			(stroke
				(width 0.1)
				(type default)
			)
			(layer "F.SilkS")
		)
		(fp_line
			(start 10.548366 -0.884682)
			(end 11.45032 -1.749552)
			(stroke
				(width 0.1)
				(type default)
			)
			(layer "F.SilkS")
		)
		(fp_line
			(start 10.548366 -0.884682)
			(end 11.45032 -1.749552)
			(stroke
				(width 0.1)
				(type default)
			)
			(layer "F.SilkS")
		)
		(fp_line
			(start 10.572496 -4.831842)
			(end 10.566146 -4.825746)
			(stroke
				(width 0.1)
				(type default)
			)
			(layer "F.SilkS")
		)
		(fp_line
			(start 10.572496 -4.831842)
			(end 10.566146 -4.825746)
			(stroke
				(width 0.1)
				(type default)
			)
			(layer "F.SilkS")
		)
		(fp_line
			(start 10.582148 -4.783328)
			(end 10.566146 -4.825746)
			(stroke
				(width 0.1)
				(type default)
			)
			(layer "F.SilkS")
		)
		(fp_line
			(start 10.582148 -4.783328)
			(end 10.566146 -4.825746)
			(stroke
				(width 0.1)
				(type default)
			)
			(layer "F.SilkS")
		)
		(fp_line
			(start 10.59434 -0.870712)
			(end 11.516614 -1.75514)
			(stroke
				(width 0.1)
				(type default)
			)
			(layer "F.SilkS")
		)
		(fp_line
			(start 10.59434 -0.870712)
			(end 11.516614 -1.75514)
			(stroke
				(width 0.1)
				(type default)
			)
			(layer "F.SilkS")
		)
		(fp_line
			(start 10.59815 -4.74091)
			(end 10.582148 -4.783328)
			(stroke
				(width 0.1)
				(type default)
			)
			(layer "F.SilkS")
		)
		(fp_line
			(start 10.59815 -4.74091)
			(end 10.582148 -4.783328)
			(stroke
				(width 0.1)
				(type default)
			)
			(layer "F.SilkS")
		)
		(fp_line
			(start 10.613898 -4.698746)
			(end 10.59815 -4.74091)
			(stroke
				(width 0.1)
				(type default)
			)
			(layer "F.SilkS")
		)
		(fp_line
			(start 10.613898 -4.698746)
			(end 10.59815 -4.74091)
			(stroke
				(width 0.1)
				(type default)
			)
			(layer "F.SilkS")
		)
		(fp_line
			(start 10.613898 -4.698746)
			(end 10.6299 -4.656074)
			(stroke
				(width 0.1)
				(type default)
			)
			(layer "F.SilkS")
		)
		(fp_line
			(start 10.613898 -4.698746)
			(end 10.6299 -4.656074)
			(stroke
				(width 0.1)
				(type default)
			)
			(layer "F.SilkS")
		)
		(fp_line
			(start 10.6299 -4.656074)
			(end 10.645902 -4.613656)
			(stroke
				(width 0.1)
				(type default)
			)
			(layer "F.SilkS")
		)
		(fp_line
			(start 10.6299 -4.656074)
			(end 10.645902 -4.613656)
			(stroke
				(width 0.1)
				(type default)
			)
			(layer "F.SilkS")
		)
		(fp_line
			(start 10.64006 -0.856996)
			(end 11.585448 -1.763522)
			(stroke
				(width 0.1)
				(type default)
			)
			(layer "F.SilkS")
		)
		(fp_line
			(start 10.64006 -0.856996)
			(end 11.585448 -1.763522)
			(stroke
				(width 0.1)
				(type default)
			)
			(layer "F.SilkS")
		)
		(fp_line
			(start 10.645902 -4.613656)
			(end 10.661904 -4.571492)
			(stroke
				(width 0.1)
				(type default)
			)
			(layer "F.SilkS")
		)
		(fp_line
			(start 10.645902 -4.613656)
			(end 10.661904 -4.571492)
			(stroke
				(width 0.1)
				(type default)
			)
			(layer "F.SilkS")
		)
		(fp_line
			(start 10.661904 -4.571492)
			(end 10.677906 -4.529074)
			(stroke
				(width 0.1)
				(type default)
			)
			(layer "F.SilkS")
		)
		(fp_line
			(start 10.661904 -4.571492)
			(end 10.677906 -4.529074)
			(stroke
				(width 0.1)
				(type default)
			)
			(layer "F.SilkS")
		)
		(fp_line
			(start 10.677906 -4.529074)
			(end 10.693908 -4.486402)
			(stroke
				(width 0.1)
				(type default)
			)
			(layer "F.SilkS")
		)
		(fp_line
			(start 10.677906 -4.529074)
			(end 10.693908 -4.486402)
			(stroke
				(width 0.1)
				(type default)
			)
			(layer "F.SilkS")
		)
		(fp_line
			(start 10.686542 -0.843534)
			(end 11.654282 -1.772158)
			(stroke
				(width 0.1)
				(type default)
			)
			(layer "F.SilkS")
		)
		(fp_line
			(start 10.686542 -0.843534)
			(end 11.654282 -1.772158)
			(stroke
				(width 0.1)
				(type default)
			)
			(layer "F.SilkS")
		)
		(fp_line
			(start 10.693908 -4.486402)
			(end 10.709656 -4.443984)
			(stroke
				(width 0.1)
				(type default)
			)
			(layer "F.SilkS")
		)
		(fp_line
			(start 10.693908 -4.486402)
			(end 10.709656 -4.443984)
			(stroke
				(width 0.1)
				(type default)
			)
			(layer "F.SilkS")
		)
		(fp_line
			(start 10.698734 -4.895088)
			(end 10.582148 -4.783328)
			(stroke
				(width 0.1)
				(type default)
			)
			(layer "F.SilkS")
		)
		(fp_line
			(start 10.698734 -4.895088)
			(end 10.582148 -4.783328)
			(stroke
				(width 0.1)
				(type default)
			)
			(layer "F.SilkS")
		)
		(fp_line
			(start 10.709656 -4.443984)
			(end 10.725658 -4.40182)
			(stroke
				(width 0.1)
				(type default)
			)
			(layer "F.SilkS")
		)
		(fp_line
			(start 10.709656 -4.443984)
			(end 10.725658 -4.40182)
			(stroke
				(width 0.1)
				(type default)
			)
			(layer "F.SilkS")
		)
		(fp_line
			(start 10.725658 -4.40182)
			(end 10.74166 -4.359402)
			(stroke
				(width 0.1)
				(type default)
			)
			(layer "F.SilkS")
		)
		(fp_line
			(start 10.725658 -4.40182)
			(end 10.74166 -4.359402)
			(stroke
				(width 0.1)
				(type default)
			)
			(layer "F.SilkS")
		)
		(fp_line
			(start 10.736072 -0.833628)
			(end 11.723116 -1.78054)
			(stroke
				(width 0.1)
				(type default)
			)
			(layer "F.SilkS")
		)
		(fp_line
			(start 10.736072 -0.833628)
			(end 11.723116 -1.78054)
			(stroke
				(width 0.1)
				(type default)
			)
			(layer "F.SilkS")
		)
		(fp_line
			(start 10.74166 -4.359402)
			(end 10.757662 -4.316984)
			(stroke
				(width 0.1)
				(type default)
			)
			(layer "F.SilkS")
		)
		(fp_line
			(start 10.74166 -4.359402)
			(end 10.757662 -4.316984)
			(stroke
				(width 0.1)
				(type default)
			)
			(layer "F.SilkS")
		)
		(fp_line
			(start 10.757662 -4.316984)
			(end 10.773664 -4.274566)
			(stroke
				(width 0.1)
				(type default)
			)
			(layer "F.SilkS")
		)
		(fp_line
			(start 10.757662 -4.316984)
			(end 10.773664 -4.274566)
			(stroke
				(width 0.1)
				(type default)
			)
			(layer "F.SilkS")
		)
		(fp_line
			(start 10.773664 -4.274566)
			(end 10.789666 -4.232148)
			(stroke
				(width 0.1)
				(type default)
			)
			(layer "F.SilkS")
		)
		(fp_line
			(start 10.773664 -4.274566)
			(end 10.789666 -4.232148)
			(stroke
				(width 0.1)
				(type default)
			)
			(layer "F.SilkS")
		)
		(fp_line
			(start 10.785602 -0.823214)
			(end 11.818112 -1.813814)
			(stroke
				(width 0.1)
				(type default)
			)
			(layer "F.SilkS")
		)
		(fp_line
			(start 10.785602 -0.823214)
			(end 11.818112 -1.813814)
			(stroke
				(width 0.1)
				(type default)
			)
			(layer "F.SilkS")
		)
		(fp_line
			(start 10.789666 -4.232148)
			(end 10.805414 -4.18973)
			(stroke
				(width 0.1)
				(type default)
			)
			(layer "F.SilkS")
		)
		(fp_line
			(start 10.789666 -4.232148)
			(end 10.805414 -4.18973)
			(stroke
				(width 0.1)
				(type default)
			)
			(layer "F.SilkS")
		)
		(fp_line
			(start 10.805414 -4.18973)
			(end 10.821416 -4.147312)
			(stroke
				(width 0.1)
				(type default)
			)
			(layer "F.SilkS")
		)
		(fp_line
			(start 10.805414 -4.18973)
			(end 10.821416 -4.147312)
			(stroke
				(width 0.1)
				(type default)
			)
			(layer "F.SilkS")
		)
		(fp_line
			(start 10.818368 -4.952492)
			(end 10.59815 -4.74091)
			(stroke
				(width 0.1)
				(type default)
			)
			(layer "F.SilkS")
		)
		(fp_line
			(start 10.818368 -4.952492)
			(end 10.59815 -4.74091)
			(stroke
				(width 0.1)
				(type default)
			)
			(layer "F.SilkS")
		)
		(fp_line
			(start 10.821416 -4.147312)
			(end 10.837418 -4.104894)
			(stroke
				(width 0.1)
				(type default)
			)
			(layer "F.SilkS")
		)
		(fp_line
			(start 10.821416 -4.147312)
			(end 10.837418 -4.104894)
			(stroke
				(width 0.1)
				(type default)
			)
			(layer "F.SilkS")
		)
		(fp_line
			(start 10.836402 -0.814324)
			(end 11.91514 -1.84912)
			(stroke
				(width 0.1)
				(type default)
			)
			(layer "F.SilkS")
		)
		(fp_line
			(start 10.836402 -0.814324)
			(end 11.91514 -1.84912)
			(stroke
				(width 0.1)
				(type default)
			)
			(layer "F.SilkS")
		)
		(fp_line
			(start 10.837418 -4.104894)
			(end 10.85342 -4.062476)
			(stroke
				(width 0.1)
				(type default)
			)
			(layer "F.SilkS")
		)
		(fp_line
			(start 10.837418 -4.104894)
			(end 10.85342 -4.062476)
			(stroke
				(width 0.1)
				(type default)
			)
			(layer "F.SilkS")
		)
		(fp_line
			(start 10.889742 -0.808228)
			(end 12.047474 -1.918462)
			(stroke
				(width 0.1)
				(type default)
			)
			(layer "F.SilkS")
		)
		(fp_line
			(start 10.889742 -0.808228)
			(end 12.047474 -1.918462)
			(stroke
				(width 0.1)
				(type default)
			)
			(layer "F.SilkS")
		)
		(fp_line
			(start 10.931144 -5.002784)
			(end 10.613898 -4.698746)
			(stroke
				(width 0.1)
				(type default)
			)
			(layer "F.SilkS")
		)
		(fp_line
			(start 10.931144 -5.002784)
			(end 10.613898 -4.698746)
			(stroke
				(width 0.1)
				(type default)
			)
			(layer "F.SilkS")
		)
		(fp_line
			(start 10.99947 -0.797814)
			(end 13.653516 -3.343402)
			(stroke
				(width 0.1)
				(type default)
			)
			(layer "F.SilkS")
		)
		(fp_line
			(start 10.99947 -0.797814)
			(end 13.653516 -3.343402)
			(stroke
				(width 0.1)
				(type default)
			)
			(layer "F.SilkS")
		)
		(fp_line
			(start 11.03503 -5.044694)
			(end 10.6299 -4.656074)
			(stroke
				(width 0.1)
				(type default)
			)
			(layer "F.SilkS")
		)
		(fp_line
			(start 11.03503 -5.044694)
			(end 10.6299 -4.656074)
			(stroke
				(width 0.1)
				(type default)
			)
			(layer "F.SilkS")
		)
		(fp_line
			(start 11.057382 -0.795274)
			(end 13.64107 -3.27406)
			(stroke
				(width 0.1)
				(type default)
			)
			(layer "F.SilkS")
		)
		(fp_line
			(start 11.057382 -0.795274)
			(end 13.64107 -3.27406)
			(stroke
				(width 0.1)
				(type default)
			)
			(layer "F.SilkS")
		)
		(fp_line
			(start 11.11504 -0.792988)
			(end 13.629132 -3.204972)
			(stroke
				(width 0.1)
				(type default)
			)
			(layer "F.SilkS")
		)
		(fp_line
			(start 11.11504 -0.792988)
			(end 13.629132 -3.204972)
			(stroke
				(width 0.1)
				(type default)
			)
			(layer "F.SilkS")
		)
		(fp_line
			(start 11.13536 -5.083048)
			(end 10.645902 -4.613656)
			(stroke
				(width 0.1)
				(type default)
			)
			(layer "F.SilkS")
		)
		(fp_line
			(start 11.13536 -5.083048)
			(end 10.645902 -4.613656)
			(stroke
				(width 0.1)
				(type default)
			)
			(layer "F.SilkS")
		)
		(fp_line
			(start 11.182096 -0.799846)
			(end 13.61694 -3.135376)
			(stroke
				(width 0.1)
				(type default)
			)
			(layer "F.SilkS")
		)
		(fp_line
			(start 11.182096 -0.799846)
			(end 13.61694 -3.135376)
			(stroke
				(width 0.1)
				(type default)
			)
			(layer "F.SilkS")
		)
		(fp_line
			(start 11.226546 -5.11302)
			(end 10.661904 -4.571492)
			(stroke
				(width 0.1)
				(type default)
			)
			(layer "F.SilkS")
		)
		(fp_line
			(start 11.226546 -5.11302)
			(end 10.661904 -4.571492)
			(stroke
				(width 0.1)
				(type default)
			)
			(layer "F.SilkS")
		)
		(fp_line
			(start 11.246612 -2.76606)
			(end 12.216638 -3.696716)
			(stroke
				(width 0.1)
				(type default)
			)
			(layer "F.SilkS")
		)
		(fp_line
			(start 11.246612 -2.76606)
			(end 12.216638 -3.696716)
			(stroke
				(width 0.1)
				(type default)
			)
			(layer "F.SilkS")
		)
		(fp_line
			(start 11.248898 -0.805942)
			(end 13.604494 -3.06578)
			(stroke
				(width 0.1)
				(type default)
			)
			(layer "F.SilkS")
		)
		(fp_line
			(start 11.248898 -0.805942)
			(end 13.604494 -3.06578)
			(stroke
				(width 0.1)
				(type default)
			)
			(layer "F.SilkS")
		)
		(fp_line
			(start 11.315446 -5.140706)
			(end 10.677906 -4.529074)
			(stroke
				(width 0.1)
				(type default)
			)
			(layer "F.SilkS")
		)
		(fp_line
			(start 11.315446 -5.140706)
			(end 10.677906 -4.529074)
			(stroke
				(width 0.1)
				(type default)
			)
			(layer "F.SilkS")
		)
		(fp_line
			(start 11.315954 -0.813054)
			(end 13.592556 -2.996692)
			(stroke
				(width 0.1)
				(type default)
			)
			(layer "F.SilkS")
		)
		(fp_line
			(start 11.315954 -0.813054)
			(end 13.592556 -2.996692)
			(stroke
				(width 0.1)
				(type default)
			)
			(layer "F.SilkS")
		)
		(fp_line
			(start 11.364722 -2.821686)
			(end 12.265914 -3.686302)
			(stroke
				(width 0.1)
				(type default)
			)
			(layer "F.SilkS")
		)
		(fp_line
			(start 11.364722 -2.821686)
			(end 12.265914 -3.686302)
			(stroke
				(width 0.1)
				(type default)
			)
			(layer "F.SilkS")
		)
		(fp_line
			(start 11.382756 -0.81915)
			(end 13.580364 -2.927096)
			(stroke
				(width 0.1)
				(type default)
			)
			(layer "F.SilkS")
		)
		(fp_line
			(start 11.382756 -0.81915)
			(end 13.580364 -2.927096)
			(stroke
				(width 0.1)
				(type default)
			)
			(layer "F.SilkS")
		)
		(fp_line
			(start 11.398758 -5.163058)
			(end 10.693908 -4.486402)
			(stroke
				(width 0.1)
				(type default)
			)
			(layer "F.SilkS")
		)
		(fp_line
			(start 11.398758 -5.163058)
			(end 10.693908 -4.486402)
			(stroke
				(width 0.1)
				(type default)
			)
			(layer "F.SilkS")
		)
		(fp_line
			(start 11.436096 -2.832354)
			(end 12.31138 -3.672078)
			(stroke
				(width 0.1)
				(type default)
			)
			(layer "F.SilkS")
		)
		(fp_line
			(start 11.436096 -2.832354)
			(end 12.31138 -3.672078)
			(stroke
				(width 0.1)
				(type default)
			)
			(layer "F.SilkS")
		)
		(fp_line
			(start 11.460734 -0.836422)
			(end 13.568172 -2.857754)
			(stroke
				(width 0.1)
				(type default)
			)
			(layer "F.SilkS")
		)
		(fp_line
			(start 11.460734 -0.836422)
			(end 13.568172 -2.857754)
			(stroke
				(width 0.1)
				(type default)
			)
			(layer "F.SilkS")
		)
		(fp_line
			(start 11.478514 -5.1816)
			(end 10.709656 -4.443984)
			(stroke
				(width 0.1)
				(type default)
			)
			(layer "F.SilkS")
		)
		(fp_line
			(start 11.478514 -5.1816)
			(end 10.709656 -4.443984)
			(stroke
				(width 0.1)
				(type default)
			)
			(layer "F.SilkS")
		)
		(fp_line
			(start 11.505184 -2.84099)
			(end 12.356592 -3.657854)
			(stroke
				(width 0.1)
				(type default)
			)
			(layer "F.SilkS")
		)
		(fp_line
			(start 11.505184 -2.84099)
			(end 12.356592 -3.657854)
			(stroke
				(width 0.1)
				(type default)
			)
			(layer "F.SilkS")
		)
		(fp_line
			(start 11.546332 -0.860552)
			(end 13.55598 -2.788412)
			(stroke
				(width 0.1)
				(type default)
			)
			(layer "F.SilkS")
		)
		(fp_line
			(start 11.546332 -0.860552)
			(end 13.55598 -2.788412)
			(stroke
				(width 0.1)
				(type default)
			)
			(layer "F.SilkS")
		)
		(fp_line
			(start 11.557762 -5.199888)
			(end 10.725658 -4.40182)
			(stroke
				(width 0.1)
				(type default)
			)
			(layer "F.SilkS")
		)
		(fp_line
			(start 11.557762 -5.199888)
			(end 10.725658 -4.40182)
			(stroke
				(width 0.1)
				(type default)
			)
			(layer "F.SilkS")
		)
		(fp_line
			(start 11.629898 -5.211572)
			(end 10.74166 -4.359402)
			(stroke
				(width 0.1)
				(type default)
			)
			(layer "F.SilkS")
		)
		(fp_line
			(start 11.629898 -5.211572)
			(end 10.74166 -4.359402)
			(stroke
				(width 0.1)
				(type default)
			)
			(layer "F.SilkS")
		)
		(fp_line
			(start 11.63193 -0.884936)
			(end 13.544042 -2.71907)
			(stroke
				(width 0.1)
				(type default)
			)
			(layer "F.SilkS")
		)
		(fp_line
			(start 11.63193 -0.884936)
			(end 13.544042 -2.71907)
			(stroke
				(width 0.1)
				(type default)
			)
			(layer "F.SilkS")
		)
		(fp_line
			(start 11.702034 -5.223002)
			(end 10.757662 -4.316984)
			(stroke
				(width 0.1)
				(type default)
			)
			(layer "F.SilkS")
		)
		(fp_line
			(start 11.702034 -5.223002)
			(end 10.757662 -4.316984)
			(stroke
				(width 0.1)
				(type default)
			)
			(layer "F.SilkS")
		)
		(fp_line
			(start 11.728704 -0.919988)
			(end 13.531596 -2.649728)
			(stroke
				(width 0.1)
				(type default)
			)
			(layer "F.SilkS")
		)
		(fp_line
			(start 11.728704 -0.919988)
			(end 13.531596 -2.649728)
			(stroke
				(width 0.1)
				(type default)
			)
			(layer "F.SilkS")
		)
		(fp_line
			(start 11.77417 -5.234178)
			(end 10.773664 -4.274566)
			(stroke
				(width 0.1)
				(type default)
			)
			(layer "F.SilkS")
		)
		(fp_line
			(start 11.77417 -5.234178)
			(end 10.773664 -4.274566)
			(stroke
				(width 0.1)
				(type default)
			)
			(layer "F.SilkS")
		)
		(fp_line
			(start 11.84021 -5.24002)
			(end 10.789666 -4.232148)
			(stroke
				(width 0.1)
				(type default)
			)
			(layer "F.SilkS")
		)
		(fp_line
			(start 11.84021 -5.24002)
			(end 10.789666 -4.232148)
			(stroke
				(width 0.1)
				(type default)
			)
			(layer "F.SilkS")
		)
		(fp_line
			(start 11.8491 -0.9779)
			(end 13.519404 -2.580386)
			(stroke
				(width 0.1)
				(type default)
			)
			(layer "F.SilkS")
		)
		(fp_line
			(start 11.8491 -0.9779)
			(end 13.519404 -2.580386)
			(stroke
				(width 0.1)
				(type default)
			)
			(layer "F.SilkS")
		)
		(fp_line
			(start 11.906504 -5.245862)
			(end 10.805414 -4.18973)
			(stroke
				(width 0.1)
				(type default)
			)
			(layer "F.SilkS")
		)
		(fp_line
			(start 11.906504 -5.245862)
			(end 10.805414 -4.18973)
			(stroke
				(width 0.1)
				(type default)
			)
			(layer "F.SilkS")
		)
		(fp_line
			(start 11.972798 -5.251958)
			(end 10.821416 -4.147312)
			(stroke
				(width 0.1)
				(type default)
			)
			(layer "F.SilkS")
		)
		(fp_line
			(start 11.972798 -5.251958)
			(end 10.821416 -4.147312)
			(stroke
				(width 0.1)
				(type default)
			)
			(layer "F.SilkS")
		)
		(fp_line
			(start 12.000738 -1.06553)
			(end 13.507466 -2.51079)
			(stroke
				(width 0.1)
				(type default)
			)
			(layer "F.SilkS")
		)
		(fp_line
			(start 12.000738 -1.06553)
			(end 13.507466 -2.51079)
			(stroke
				(width 0.1)
				(type default)
			)
			(layer "F.SilkS")
		)
		(fp_line
			(start 12.036806 -5.255514)
			(end 10.837418 -4.104894)
			(stroke
				(width 0.1)
				(type default)
			)
			(layer "F.SilkS")
		)
		(fp_line
			(start 12.036806 -5.255514)
			(end 10.837418 -4.104894)
			(stroke
				(width 0.1)
				(type default)
			)
			(layer "F.SilkS")
		)
		(fp_line
			(start 12.093956 -0.882904)
			(end 12.111228 -0.882904)
			(stroke
				(width 0.1)
				(type default)
			)
			(layer "F.SilkS")
		)
		(fp_line
			(start 12.093956 -0.882904)
			(end 12.111228 -0.882904)
			(stroke
				(width 0.1)
				(type default)
			)
			(layer "F.SilkS")
		)
		(fp_line
			(start 12.098528 -5.257038)
			(end 10.85342 -4.062476)
			(stroke
				(width 0.1)
				(type default)
			)
			(layer "F.SilkS")
		)
		(fp_line
			(start 12.098528 -5.257038)
			(end 10.85342 -4.062476)
			(stroke
				(width 0.1)
				(type default)
			)
			(layer "F.SilkS")
		)
		(fp_line
			(start 12.102592 -0.932434)
			(end 12.093956 -0.882904)
			(stroke
				(width 0.1)
				(type default)
			)
			(layer "F.SilkS")
		)
		(fp_line
			(start 12.102592 -0.932434)
			(end 12.093956 -0.882904)
			(stroke
				(width 0.1)
				(type default)
			)
			(layer "F.SilkS")
		)
		(fp_line
			(start 12.102592 -0.932434)
			(end 13.458444 -2.233422)
			(stroke
				(width 0.1)
				(type default)
			)
			(layer "F.SilkS")
		)
		(fp_line
			(start 12.102592 -0.932434)
			(end 13.458444 -2.233422)
			(stroke
				(width 0.1)
				(type default)
			)
			(layer "F.SilkS")
		)
		(fp_line
			(start 12.111228 -0.882904)
			(end 12.171172 -0.882904)
			(stroke
				(width 0.1)
				(type default)
			)
			(layer "F.SilkS")
		)
		(fp_line
			(start 12.111228 -0.882904)
			(end 12.171172 -0.882904)
			(stroke
				(width 0.1)
				(type default)
			)
			(layer "F.SilkS")
		)
		(fp_line
			(start 12.111228 -0.882904)
			(end 13.446506 -2.163826)
			(stroke
				(width 0.1)
				(type default)
			)
			(layer "F.SilkS")
		)
		(fp_line
			(start 12.111228 -0.882904)
			(end 13.446506 -2.163826)
			(stroke
				(width 0.1)
				(type default)
			)
			(layer "F.SilkS")
		)
		(fp_line
			(start 12.115038 -1.00203)
			(end 12.102592 -0.932434)
			(stroke
				(width 0.1)
				(type default)
			)
			(layer "F.SilkS")
		)
		(fp_line
			(start 12.115038 -1.00203)
			(end 12.102592 -0.932434)
			(stroke
				(width 0.1)
				(type default)
			)
			(layer "F.SilkS")
		)
		(fp_line
			(start 12.115038 -1.00203)
			(end 13.47089 -2.302764)
			(stroke
				(width 0.1)
				(type default)
			)
			(layer "F.SilkS")
		)
		(fp_line
			(start 12.115038 -1.00203)
			(end 13.47089 -2.302764)
			(stroke
				(width 0.1)
				(type default)
			)
			(layer "F.SilkS")
		)
		(fp_line
			(start 12.12723 -1.071626)
			(end 12.115038 -1.00203)
			(stroke
				(width 0.1)
				(type default)
			)
			(layer "F.SilkS")
		)
		(fp_line
			(start 12.12723 -1.071626)
			(end 12.115038 -1.00203)
			(stroke
				(width 0.1)
				(type default)
			)
			(layer "F.SilkS")
		)
		(fp_line
			(start 12.12723 -1.071626)
			(end 13.483082 -2.372106)
			(stroke
				(width 0.1)
				(type default)
			)
			(layer "F.SilkS")
		)
		(fp_line
			(start 12.12723 -1.071626)
			(end 13.483082 -2.372106)
			(stroke
				(width 0.1)
				(type default)
			)
			(layer "F.SilkS")
		)
		(fp_line
			(start 12.139676 -1.140968)
			(end 12.12723 -1.071626)
			(stroke
				(width 0.1)
				(type default)
			)
			(layer "F.SilkS")
		)
		(fp_line
			(start 12.139676 -1.140968)
			(end 12.12723 -1.071626)
			(stroke
				(width 0.1)
				(type default)
			)
			(layer "F.SilkS")
		)
		(fp_line
			(start 12.139676 -1.140968)
			(end 13.49502 -2.441448)
			(stroke
				(width 0.1)
				(type default)
			)
			(layer "F.SilkS")
		)
		(fp_line
			(start 12.139676 -1.140968)
			(end 13.49502 -2.441448)
			(stroke
				(width 0.1)
				(type default)
			)
			(layer "F.SilkS")
		)
		(fp_line
			(start 12.160504 -5.258816)
			(end 10.92708 -4.07543)
			(stroke
				(width 0.1)
				(type default)
			)
			(layer "F.SilkS")
		)
		(fp_line
			(start 12.160504 -5.258816)
			(end 10.92708 -4.07543)
			(stroke
				(width 0.1)
				(type default)
			)
			(layer "F.SilkS")
		)
		(fp_line
			(start 12.171172 -0.882904)
			(end 12.23137 -0.882904)
			(stroke
				(width 0.1)
				(type default)
			)
			(layer "F.SilkS")
		)
		(fp_line
			(start 12.171172 -0.882904)
			(end 12.23137 -0.882904)
			(stroke
				(width 0.1)
				(type default)
			)
			(layer "F.SilkS")
		)
		(fp_line
			(start 12.171172 -0.882904)
			(end 13.434314 -2.094738)
			(stroke
				(width 0.1)
				(type default)
			)
			(layer "F.SilkS")
		)
		(fp_line
			(start 12.171172 -0.882904)
			(end 13.434314 -2.094738)
			(stroke
				(width 0.1)
				(type default)
			)
			(layer "F.SilkS")
		)
		(fp_line
			(start 12.22248 -5.260594)
			(end 11.042904 -4.12877)
			(stroke
				(width 0.1)
				(type default)
			)
			(layer "F.SilkS")
		)
		(fp_line
			(start 12.22248 -5.260594)
			(end 11.042904 -4.12877)
			(stroke
				(width 0.1)
				(type default)
			)
			(layer "F.SilkS")
		)
		(fp_line
			(start 12.23137 -0.882904)
			(end 12.291568 -0.882904)
			(stroke
				(width 0.1)
				(type default)
			)
			(layer "F.SilkS")
		)
		(fp_line
			(start 12.23137 -0.882904)
			(end 12.291568 -0.882904)
			(stroke
				(width 0.1)
				(type default)
			)
			(layer "F.SilkS")
		)
		(fp_line
			(start 12.23137 -0.882904)
			(end 13.422122 -2.025396)
			(stroke
				(width 0.1)
				(type default)
			)
			(layer "F.SilkS")
		)
		(fp_line
			(start 12.23137 -0.882904)
			(end 13.422122 -2.025396)
			(stroke
				(width 0.1)
				(type default)
			)
			(layer "F.SilkS")
		)
		(fp_line
			(start 12.281408 -5.25907)
			(end 11.150092 -4.173728)
			(stroke
				(width 0.1)
				(type default)
			)
			(layer "F.SilkS")
		)
		(fp_line
			(start 12.281408 -5.25907)
			(end 11.150092 -4.173728)
			(stroke
				(width 0.1)
				(type default)
			)
			(layer "F.SilkS")
		)
		(fp_line
			(start 12.291568 -0.882904)
			(end 12.351512 -0.882904)
			(stroke
				(width 0.1)
				(type default)
			)
			(layer "F.SilkS")
		)
		(fp_line
			(start 12.291568 -0.882904)
			(end 12.351512 -0.882904)
			(stroke
				(width 0.1)
				(type default)
			)
			(layer "F.SilkS")
		)
		(fp_line
			(start 12.291568 -0.882904)
			(end 13.40993 -1.9558)
			(stroke
				(width 0.1)
				(type default)
			)
			(layer "F.SilkS")
		)
		(fp_line
			(start 12.291568 -0.882904)
			(end 13.40993 -1.9558)
			(stroke
				(width 0.1)
				(type default)
			)
			(layer "F.SilkS")
		)
		(fp_line
			(start 12.335002 -2.251964)
			(end 12.323064 -2.182622)
			(stroke
				(width 0.1)
				(type default)
			)
			(layer "F.SilkS")
		)
		(fp_line
			(start 12.335002 -2.251964)
			(end 12.323064 -2.182622)
			(stroke
				(width 0.1)
				(type default)
			)
			(layer "F.SilkS")
		)
		(fp_line
			(start 12.337542 -5.255514)
			(end 11.246358 -4.208526)
			(stroke
				(width 0.1)
				(type default)
			)
			(layer "F.SilkS")
		)
		(fp_line
			(start 12.337542 -5.255514)
			(end 11.246358 -4.208526)
			(stroke
				(width 0.1)
				(type default)
			)
			(layer "F.SilkS")
		)
		(fp_line
			(start 12.347194 -2.321306)
			(end 12.335002 -2.251964)
			(stroke
				(width 0.1)
				(type default)
			)
			(layer "F.SilkS")
		)
		(fp_line
			(start 12.347194 -2.321306)
			(end 12.335002 -2.251964)
			(stroke
				(width 0.1)
				(type default)
			)
			(layer "F.SilkS")
		)
		(fp_line
			(start 12.351512 -0.882904)
			(end 12.41171 -0.882904)
			(stroke
				(width 0.1)
				(type default)
			)
			(layer "F.SilkS")
		)
		(fp_line
			(start 12.351512 -0.882904)
			(end 12.41171 -0.882904)
			(stroke
				(width 0.1)
				(type default)
			)
			(layer "F.SilkS")
		)
		(fp_line
			(start 12.351512 -0.882904)
			(end 13.397992 -1.886458)
			(stroke
				(width 0.1)
				(type default)
			)
			(layer "F.SilkS")
		)
		(fp_line
			(start 12.351512 -0.882904)
			(end 13.397992 -1.886458)
			(stroke
				(width 0.1)
				(type default)
			)
			(layer "F.SilkS")
		)
		(fp_line
			(start 12.359386 -2.390902)
			(end 12.347194 -2.321306)
			(stroke
				(width 0.1)
				(type default)
			)
			(layer "F.SilkS")
		)
		(fp_line
			(start 12.359386 -2.390902)
			(end 12.347194 -2.321306)
			(stroke
				(width 0.1)
				(type default)
			)
			(layer "F.SilkS")
		)
		(fp_line
			(start 12.371578 -2.460244)
			(end 12.359386 -2.390902)
			(stroke
				(width 0.1)
				(type default)
			)
			(layer "F.SilkS")
		)
		(fp_line
			(start 12.371578 -2.460244)
			(end 12.359386 -2.390902)
			(stroke
				(width 0.1)
				(type default)
			)
			(layer "F.SilkS")
		)
		(fp_line
			(start 12.38377 -2.529586)
			(end 12.371578 -2.460244)
			(stroke
				(width 0.1)
				(type default)
			)
			(layer "F.SilkS")
		)
		(fp_line
			(start 12.38377 -2.529586)
			(end 12.371578 -2.460244)
			(stroke
				(width 0.1)
				(type default)
			)
			(layer "F.SilkS")
		)
		(fp_line
			(start 12.393676 -5.251704)
			(end 11.336782 -4.237736)
			(stroke
				(width 0.1)
				(type default)
			)
			(layer "F.SilkS")
		)
		(fp_line
			(start 12.393676 -5.251704)
			(end 11.336782 -4.237736)
			(stroke
				(width 0.1)
				(type default)
			)
			(layer "F.SilkS")
		)
		(fp_line
			(start 12.395962 -2.598928)
			(end 12.38377 -2.529586)
			(stroke
				(width 0.1)
				(type default)
			)
			(layer "F.SilkS")
		)
		(fp_line
			(start 12.395962 -2.598928)
			(end 12.38377 -2.529586)
			(stroke
				(width 0.1)
				(type default)
			)
			(layer "F.SilkS")
		)
		(fp_line
			(start 12.401804 -3.64363)
			(end 11.574526 -2.849626)
			(stroke
				(width 0.1)
				(type default)
			)
			(layer "F.SilkS")
		)
		(fp_line
			(start 12.401804 -3.64363)
			(end 11.574526 -2.849626)
			(stroke
				(width 0.1)
				(type default)
			)
			(layer "F.SilkS")
		)
		(fp_line
			(start 12.408154 -2.668524)
			(end 12.395962 -2.598928)
			(stroke
				(width 0.1)
				(type default)
			)
			(layer "F.SilkS")
		)
		(fp_line
			(start 12.408154 -2.668524)
			(end 12.395962 -2.598928)
			(stroke
				(width 0.1)
				(type default)
			)
			(layer "F.SilkS")
		)
		(fp_line
			(start 12.41171 -0.882904)
			(end 12.471908 -0.882904)
			(stroke
				(width 0.1)
				(type default)
			)
			(layer "F.SilkS")
		)
		(fp_line
			(start 12.41171 -0.882904)
			(end 12.471908 -0.882904)
			(stroke
				(width 0.1)
				(type default)
			)
			(layer "F.SilkS")
		)
		(fp_line
			(start 12.41171 -0.882904)
			(end 13.385546 -1.817116)
			(stroke
				(width 0.1)
				(type default)
			)
			(layer "F.SilkS")
		)
		(fp_line
			(start 12.41171 -0.882904)
			(end 13.385546 -1.817116)
			(stroke
				(width 0.1)
				(type default)
			)
			(layer "F.SilkS")
		)
		(fp_line
			(start 12.445238 -3.62712)
			(end 11.643614 -2.858262)
			(stroke
				(width 0.1)
				(type default)
			)
			(layer "F.SilkS")
		)
		(fp_line
			(start 12.445238 -3.62712)
			(end 11.643614 -2.858262)
			(stroke
				(width 0.1)
				(type default)
			)
			(layer "F.SilkS")
		)
		(fp_line
			(start 12.44981 -5.24764)
			(end 11.421364 -4.261104)
			(stroke
				(width 0.1)
				(type default)
			)
			(layer "F.SilkS")
		)
		(fp_line
			(start 12.44981 -5.24764)
			(end 11.421364 -4.261104)
			(stroke
				(width 0.1)
				(type default)
			)
			(layer "F.SilkS")
		)
		(fp_line
			(start 12.471908 -0.882904)
			(end 12.53236 -0.882904)
			(stroke
				(width 0.1)
				(type default)
			)
			(layer "F.SilkS")
		)
		(fp_line
			(start 12.471908 -0.882904)
			(end 12.53236 -0.882904)
			(stroke
				(width 0.1)
				(type default)
			)
			(layer "F.SilkS")
		)
		(fp_line
			(start 12.471908 -0.882904)
			(end 13.373354 -1.74752)
			(stroke
				(width 0.1)
				(type default)
			)
			(layer "F.SilkS")
		)
		(fp_line
			(start 12.471908 -0.882904)
			(end 13.373354 -1.74752)
			(stroke
				(width 0.1)
				(type default)
			)
			(layer "F.SilkS")
		)
		(fp_line
			(start 12.485624 -3.608324)
			(end 11.704574 -2.859278)
			(stroke
				(width 0.1)
				(type default)
			)
			(layer "F.SilkS")
		)
		(fp_line
			(start 12.485624 -3.608324)
			(end 11.704574 -2.859278)
			(stroke
				(width 0.1)
				(type default)
			)
			(layer "F.SilkS")
		)
		(fp_line
			(start 12.506198 -5.24383)
			(end 11.499596 -4.278376)
			(stroke
				(width 0.1)
				(type default)
			)
			(layer "F.SilkS")
		)
		(fp_line
			(start 12.506198 -5.24383)
			(end 11.499596 -4.278376)
			(stroke
				(width 0.1)
				(type default)
			)
			(layer "F.SilkS")
		)
		(fp_line
			(start 12.52601 -3.589274)
			(end 11.763502 -2.858008)
			(stroke
				(width 0.1)
				(type default)
			)
			(layer "F.SilkS")
		)
		(fp_line
			(start 12.52601 -3.589274)
			(end 11.763502 -2.858008)
			(stroke
				(width 0.1)
				(type default)
			)
			(layer "F.SilkS")
		)
		(fp_line
			(start 12.53236 -0.882904)
			(end 12.592558 -0.882904)
			(stroke
				(width 0.1)
				(type default)
			)
			(layer "F.SilkS")
		)
		(fp_line
			(start 12.53236 -0.882904)
			(end 12.592558 -0.882904)
			(stroke
				(width 0.1)
				(type default)
			)
			(layer "F.SilkS")
		)
		(fp_line
			(start 12.53236 -0.882904)
			(end 13.361416 -1.678178)
			(stroke
				(width 0.1)
				(type default)
			)
			(layer "F.SilkS")
		)
		(fp_line
			(start 12.53236 -0.882904)
			(end 13.361416 -1.678178)
			(stroke
				(width 0.1)
				(type default)
			)
			(layer "F.SilkS")
		)
		(fp_line
			(start 12.562078 -5.24002)
			(end 11.575542 -4.293616)
			(stroke
				(width 0.1)
				(type default)
			)
			(layer "F.SilkS")
		)
		(fp_line
			(start 12.562078 -5.24002)
			(end 11.575542 -4.293616)
			(stroke
				(width 0.1)
				(type default)
			)
			(layer "F.SilkS")
		)
		(fp_line
			(start 12.590018 -3.708654)
			(end 12.57808 -3.639312)
			(stroke
				(width 0.1)
				(type default)
			)
			(layer "F.SilkS")
		)
		(fp_line
			(start 12.590018 -3.708654)
			(end 12.57808 -3.639312)
			(stroke
				(width 0.1)
				(type default)
			)
			(layer "F.SilkS")
		)
		(fp_line
			(start 12.592558 -0.882904)
			(end 12.652502 -0.882904)
			(stroke
				(width 0.1)
				(type default)
			)
			(layer "F.SilkS")
		)
		(fp_line
			(start 12.592558 -0.882904)
			(end 12.652502 -0.882904)
			(stroke
				(width 0.1)
				(type default)
			)
			(layer "F.SilkS")
		)
		(fp_line
			(start 12.592558 -0.882904)
			(end 13.34897 -1.608836)
			(stroke
				(width 0.1)
				(type default)
			)
			(layer "F.SilkS")
		)
		(fp_line
			(start 12.592558 -0.882904)
			(end 13.34897 -1.608836)
			(stroke
				(width 0.1)
				(type default)
			)
			(layer "F.SilkS")
		)
		(fp_line
			(start 12.601956 -3.777996)
			(end 12.590018 -3.708654)
			(stroke
				(width 0.1)
				(type default)
			)
			(layer "F.SilkS")
		)
		(fp_line
			(start 12.601956 -3.777996)
			(end 12.590018 -3.708654)
			(stroke
				(width 0.1)
				(type default)
			)
			(layer "F.SilkS")
		)
		(fp_line
			(start 12.618212 -5.23621)
			(end 11.6459 -4.303268)
			(stroke
				(width 0.1)
				(type default)
			)
			(layer "F.SilkS")
		)
		(fp_line
			(start 12.618212 -5.23621)
			(end 11.6459 -4.303268)
			(stroke
				(width 0.1)
				(type default)
			)
			(layer "F.SilkS")
		)
		(fp_line
			(start 12.652502 -0.882904)
			(end 12.7127 -0.882904)
			(stroke
				(width 0.1)
				(type default)
			)
			(layer "F.SilkS")
		)
		(fp_line
			(start 12.652502 -0.882904)
			(end 12.7127 -0.882904)
			(stroke
				(width 0.1)
				(type default)
			)
			(layer "F.SilkS")
		)
		(fp_line
			(start 12.652502 -0.882904)
			(end 13.337286 -1.539494)
			(stroke
				(width 0.1)
				(type default)
			)
			(layer "F.SilkS")
		)
		(fp_line
			(start 12.652502 -0.882904)
			(end 13.337286 -1.539494)
			(stroke
				(width 0.1)
				(type default)
			)
			(layer "F.SilkS")
		)
		(fp_line
			(start 12.666726 -5.225034)
			(end 11.715242 -4.312412)
			(stroke
				(width 0.1)
				(type default)
			)
			(layer "F.SilkS")
		)
		(fp_line
			(start 12.666726 -5.225034)
			(end 11.715242 -4.312412)
			(stroke
				(width 0.1)
				(type default)
			)
			(layer "F.SilkS")
		)
		(fp_line
			(start 12.7127 -0.882904)
			(end 12.772898 -0.882904)
			(stroke
				(width 0.1)
				(type default)
			)
			(layer "F.SilkS")
		)
		(fp_line
			(start 12.7127 -0.882904)
			(end 12.772898 -0.882904)
			(stroke
				(width 0.1)
				(type default)
			)
			(layer "F.SilkS")
		)
		(fp_line
			(start 12.7127 -0.882904)
			(end 13.32484 -1.470152)
			(stroke
				(width 0.1)
				(type default)
			)
			(layer "F.SilkS")
		)
		(fp_line
			(start 12.7127 -0.882904)
			(end 13.32484 -1.470152)
			(stroke
				(width 0.1)
				(type default)
			)
			(layer "F.SilkS")
		)
		(fp_line
			(start 12.715494 -5.214112)
			(end 11.78179 -4.318254)
			(stroke
				(width 0.1)
				(type default)
			)
			(layer "F.SilkS")
		)
		(fp_line
			(start 12.715494 -5.214112)
			(end 11.78179 -4.318254)
			(stroke
				(width 0.1)
				(type default)
			)
			(layer "F.SilkS")
		)
		(fp_line
			(start 12.764008 -5.202936)
			(end 11.846306 -4.322572)
			(stroke
				(width 0.1)
				(type default)
			)
			(layer "F.SilkS")
		)
		(fp_line
			(start 12.764008 -5.202936)
			(end 11.846306 -4.322572)
			(stroke
				(width 0.1)
				(type default)
			)
			(layer "F.SilkS")
		)
		(fp_line
			(start 12.772898 -0.882904)
			(end 12.832842 -0.882904)
			(stroke
				(width 0.1)
				(type default)
			)
			(layer "F.SilkS")
		)
		(fp_line
			(start 12.772898 -0.882904)
			(end 12.832842 -0.882904)
			(stroke
				(width 0.1)
				(type default)
			)
			(layer "F.SilkS")
		)
		(fp_line
			(start 12.772898 -0.882904)
			(end 13.312394 -1.400556)
			(stroke
				(width 0.1)
				(type default)
			)
			(layer "F.SilkS")
		)
		(fp_line
			(start 12.772898 -0.882904)
			(end 13.312394 -1.400556)
			(stroke
				(width 0.1)
				(type default)
			)
			(layer "F.SilkS")
		)
		(fp_line
			(start 12.812522 -5.19176)
			(end 11.910568 -4.326636)
			(stroke
				(width 0.1)
				(type default)
			)
			(layer "F.SilkS")
		)
		(fp_line
			(start 12.812522 -5.19176)
			(end 11.910568 -4.326636)
			(stroke
				(width 0.1)
				(type default)
			)
			(layer "F.SilkS")
		)
		(fp_line
			(start 12.832842 -0.882904)
			(end 12.89304 -0.882904)
			(stroke
				(width 0.1)
				(type default)
			)
			(layer "F.SilkS")
		)
		(fp_line
			(start 12.832842 -0.882904)
			(end 12.89304 -0.882904)
			(stroke
				(width 0.1)
				(type default)
			)
			(layer "F.SilkS")
		)
		(fp_line
			(start 12.832842 -0.882904)
			(end 13.30071 -1.331468)
			(stroke
				(width 0.1)
				(type default)
			)
			(layer "F.SilkS")
		)
		(fp_line
			(start 12.832842 -0.882904)
			(end 13.30071 -1.331468)
			(stroke
				(width 0.1)
				(type default)
			)
			(layer "F.SilkS")
		)
		(fp_line
			(start 12.861036 -5.180584)
			(end 11.972036 -4.327906)
			(stroke
				(width 0.1)
				(type default)
			)
			(layer "F.SilkS")
		)
		(fp_line
			(start 12.861036 -5.180584)
			(end 11.972036 -4.327906)
			(stroke
				(width 0.1)
				(type default)
			)
			(layer "F.SilkS")
		)
		(fp_line
			(start 12.89304 -0.882904)
			(end 12.953238 -0.882904)
			(stroke
				(width 0.1)
				(type default)
			)
			(layer "F.SilkS")
		)
		(fp_line
			(start 12.89304 -0.882904)
			(end 12.953238 -0.882904)
			(stroke
				(width 0.1)
				(type default)
			)
			(layer "F.SilkS")
		)
		(fp_line
			(start 12.89304 -0.882904)
			(end 13.288264 -1.262126)
			(stroke
				(width 0.1)
				(type default)
			)
			(layer "F.SilkS")
		)
		(fp_line
			(start 12.89304 -0.882904)
			(end 13.288264 -1.262126)
			(stroke
				(width 0.1)
				(type default)
			)
			(layer "F.SilkS")
		)
		(fp_line
			(start 12.909804 -5.169408)
			(end 12.033758 -4.328922)
			(stroke
				(width 0.1)
				(type default)
			)
			(layer "F.SilkS")
		)
		(fp_line
			(start 12.909804 -5.169408)
			(end 12.033758 -4.328922)
			(stroke
				(width 0.1)
				(type default)
			)
			(layer "F.SilkS")
		)
		(fp_line
			(start 12.953238 -0.882904)
			(end 13.01369 -0.882904)
			(stroke
				(width 0.1)
				(type default)
			)
			(layer "F.SilkS")
		)
		(fp_line
			(start 12.953238 -0.882904)
			(end 13.01369 -0.882904)
			(stroke
				(width 0.1)
				(type default)
			)
			(layer "F.SilkS")
		)
		(fp_line
			(start 12.953238 -0.882904)
			(end 13.275818 -1.19253)
			(stroke
				(width 0.1)
				(type default)
			)
			(layer "F.SilkS")
		)
		(fp_line
			(start 12.953238 -0.882904)
			(end 13.275818 -1.19253)
			(stroke
				(width 0.1)
				(type default)
			)
			(layer "F.SilkS")
		)
		(fp_line
			(start 12.955778 -5.155946)
			(end 12.09421 -4.32943)
			(stroke
				(width 0.1)
				(type default)
			)
			(layer "F.SilkS")
		)
		(fp_line
			(start 12.955778 -5.155946)
			(end 12.09421 -4.32943)
			(stroke
				(width 0.1)
				(type default)
			)
			(layer "F.SilkS")
		)
		(fp_line
			(start 12.996926 -5.137658)
			(end 12.149836 -4.325112)
			(stroke
				(width 0.1)
				(type default)
			)
			(layer "F.SilkS")
		)
		(fp_line
			(start 12.996926 -5.137658)
			(end 12.149836 -4.325112)
			(stroke
				(width 0.1)
				(type default)
			)
			(layer "F.SilkS")
		)
		(fp_line
			(start 13.01369 -0.882904)
			(end 13.073634 -0.882904)
			(stroke
				(width 0.1)
				(type default)
			)
			(layer "F.SilkS")
		)
		(fp_line
			(start 13.01369 -0.882904)
			(end 13.073634 -0.882904)
			(stroke
				(width 0.1)
				(type default)
			)
			(layer "F.SilkS")
		)
		(fp_line
			(start 13.01369 -0.882904)
			(end 13.264134 -1.123188)
			(stroke
				(width 0.1)
				(type default)
			)
			(layer "F.SilkS")
		)
		(fp_line
			(start 13.01369 -0.882904)
			(end 13.264134 -1.123188)
			(stroke
				(width 0.1)
				(type default)
			)
			(layer "F.SilkS")
		)
		(fp_line
			(start 13.038074 -5.11937)
			(end 12.205462 -4.320794)
			(stroke
				(width 0.1)
				(type default)
			)
			(layer "F.SilkS")
		)
		(fp_line
			(start 13.038074 -5.11937)
			(end 12.205462 -4.320794)
			(stroke
				(width 0.1)
				(type default)
			)
			(layer "F.SilkS")
		)
		(fp_line
			(start 13.073634 -0.882904)
			(end 13.133578 -0.882904)
			(stroke
				(width 0.1)
				(type default)
			)
			(layer "F.SilkS")
		)
		(fp_line
			(start 13.073634 -0.882904)
			(end 13.133578 -0.882904)
			(stroke
				(width 0.1)
				(type default)
			)
			(layer "F.SilkS")
		)
		(fp_line
			(start 13.073634 -0.882904)
			(end 13.251942 -1.053846)
			(stroke
				(width 0.1)
				(type default)
			)
			(layer "F.SilkS")
		)
		(fp_line
			(start 13.073634 -0.882904)
			(end 13.251942 -1.053846)
			(stroke
				(width 0.1)
				(type default)
			)
			(layer "F.SilkS")
		)
		(fp_line
			(start 13.079222 -5.101336)
			(end 12.256008 -4.311396)
			(stroke
				(width 0.1)
				(type default)
			)
			(layer "F.SilkS")
		)
		(fp_line
			(start 13.079222 -5.101336)
			(end 12.256008 -4.311396)
			(stroke
				(width 0.1)
				(type default)
			)
			(layer "F.SilkS")
		)
		(fp_line
			(start 13.120116 -5.083048)
			(end 12.302998 -4.29895)
			(stroke
				(width 0.1)
				(type default)
			)
			(layer "F.SilkS")
		)
		(fp_line
			(start 13.120116 -5.083048)
			(end 12.302998 -4.29895)
			(stroke
				(width 0.1)
				(type default)
			)
			(layer "F.SilkS")
		)
		(fp_line
			(start 13.133578 -0.882904)
			(end 13.19403 -0.882904)
			(stroke
				(width 0.1)
				(type default)
			)
			(layer "F.SilkS")
		)
		(fp_line
			(start 13.133578 -0.882904)
			(end 13.19403 -0.882904)
			(stroke
				(width 0.1)
				(type default)
			)
			(layer "F.SilkS")
		)
		(fp_line
			(start 13.133578 -0.882904)
			(end 13.23975 -0.984504)
			(stroke
				(width 0.1)
				(type default)
			)
			(layer "F.SilkS")
		)
		(fp_line
			(start 13.133578 -0.882904)
			(end 13.23975 -0.984504)
			(stroke
				(width 0.1)
				(type default)
			)
			(layer "F.SilkS")
		)
		(fp_line
			(start 13.161518 -5.06476)
			(end 12.34948 -4.285742)
			(stroke
				(width 0.1)
				(type default)
			)
			(layer "F.SilkS")
		)
		(fp_line
			(start 13.161518 -5.06476)
			(end 12.34948 -4.285742)
			(stroke
				(width 0.1)
				(type default)
			)
			(layer "F.SilkS")
		)
		(fp_line
			(start 13.19403 -0.882904)
			(end 13.22197 -0.882904)
			(stroke
				(width 0.1)
				(type default)
			)
			(layer "F.SilkS")
		)
		(fp_line
			(start 13.19403 -0.882904)
			(end 13.22197 -0.882904)
			(stroke
				(width 0.1)
				(type default)
			)
			(layer "F.SilkS")
		)
		(fp_line
			(start 13.19403 -0.882904)
			(end 13.227812 -0.914908)
			(stroke
				(width 0.1)
				(type default)
			)
			(layer "F.SilkS")
		)
		(fp_line
			(start 13.19403 -0.882904)
			(end 13.227812 -0.914908)
			(stroke
				(width 0.1)
				(type default)
			)
			(layer "F.SilkS")
		)
		(fp_line
			(start 13.20292 -5.046472)
			(end 12.388596 -4.265422)
			(stroke
				(width 0.1)
				(type default)
			)
			(layer "F.SilkS")
		)
		(fp_line
			(start 13.20292 -5.046472)
			(end 12.388596 -4.265422)
			(stroke
				(width 0.1)
				(type default)
			)
			(layer "F.SilkS")
		)
		(fp_line
			(start 13.22197 -0.882904)
			(end 13.227812 -0.914908)
			(stroke
				(width 0.1)
				(type default)
			)
			(layer "F.SilkS")
		)
		(fp_line
			(start 13.22197 -0.882904)
			(end 13.227812 -0.914908)
			(stroke
				(width 0.1)
				(type default)
			)
			(layer "F.SilkS")
		)
		(fp_line
			(start 13.227812 -0.914908)
			(end 13.23975 -0.984504)
			(stroke
				(width 0.1)
				(type default)
			)
			(layer "F.SilkS")
		)
		(fp_line
			(start 13.227812 -0.914908)
			(end 13.23975 -0.984504)
			(stroke
				(width 0.1)
				(type default)
			)
			(layer "F.SilkS")
		)
		(fp_line
			(start 13.238988 -5.023612)
			(end 12.427458 -4.245102)
			(stroke
				(width 0.1)
				(type default)
			)
			(layer "F.SilkS")
		)
		(fp_line
			(start 13.238988 -5.023612)
			(end 12.427458 -4.245102)
			(stroke
				(width 0.1)
				(type default)
			)
			(layer "F.SilkS")
		)
		(fp_line
			(start 13.23975 -0.984504)
			(end 13.251942 -1.053846)
			(stroke
				(width 0.1)
				(type default)
			)
			(layer "F.SilkS")
		)
		(fp_line
			(start 13.23975 -0.984504)
			(end 13.251942 -1.053846)
			(stroke
				(width 0.1)
				(type default)
			)
			(layer "F.SilkS")
		)
		(fp_line
			(start 13.251942 -1.053846)
			(end 13.264134 -1.123188)
			(stroke
				(width 0.1)
				(type default)
			)
			(layer "F.SilkS")
		)
		(fp_line
			(start 13.251942 -1.053846)
			(end 13.264134 -1.123188)
			(stroke
				(width 0.1)
				(type default)
			)
			(layer "F.SilkS")
		)
		(fp_line
			(start 13.264134 -1.123188)
			(end 13.275818 -1.19253)
			(stroke
				(width 0.1)
				(type default)
			)
			(layer "F.SilkS")
		)
		(fp_line
			(start 13.264134 -1.123188)
			(end 13.275818 -1.19253)
			(stroke
				(width 0.1)
				(type default)
			)
			(layer "F.SilkS")
		)
		(fp_line
			(start 13.272516 -4.998212)
			(end 12.461748 -4.22021)
			(stroke
				(width 0.1)
				(type default)
			)
			(layer "F.SilkS")
		)
		(fp_line
			(start 13.272516 -4.998212)
			(end 12.461748 -4.22021)
			(stroke
				(width 0.1)
				(type default)
			)
			(layer "F.SilkS")
		)
		(fp_line
			(start 13.275818 -1.19253)
			(end 13.288264 -1.262126)
			(stroke
				(width 0.1)
				(type default)
			)
			(layer "F.SilkS")
		)
		(fp_line
			(start 13.275818 -1.19253)
			(end 13.288264 -1.262126)
			(stroke
				(width 0.1)
				(type default)
			)
			(layer "F.SilkS")
		)
		(fp_line
			(start 13.288264 -1.262126)
			(end 13.30071 -1.331468)
			(stroke
				(width 0.1)
				(type default)
			)
			(layer "F.SilkS")
		)
		(fp_line
			(start 13.288264 -1.262126)
			(end 13.30071 -1.331468)
			(stroke
				(width 0.1)
				(type default)
			)
			(layer "F.SilkS")
		)
		(fp_line
			(start 13.30071 -1.331468)
			(end 13.312394 -1.400556)
			(stroke
				(width 0.1)
				(type default)
			)
			(layer "F.SilkS")
		)
		(fp_line
			(start 13.30071 -1.331468)
			(end 13.312394 -1.400556)
			(stroke
				(width 0.1)
				(type default)
			)
			(layer "F.SilkS")
		)
		(fp_line
			(start 13.306298 -4.972812)
			(end 12.49299 -4.192524)
			(stroke
				(width 0.1)
				(type default)
			)
			(layer "F.SilkS")
		)
		(fp_line
			(start 13.306298 -4.972812)
			(end 12.49299 -4.192524)
			(stroke
				(width 0.1)
				(type default)
			)
			(layer "F.SilkS")
		)
		(fp_line
			(start 13.312394 -1.400556)
			(end 13.32484 -1.470152)
			(stroke
				(width 0.1)
				(type default)
			)
			(layer "F.SilkS")
		)
		(fp_line
			(start 13.312394 -1.400556)
			(end 13.32484 -1.470152)
			(stroke
				(width 0.1)
				(type default)
			)
			(layer "F.SilkS")
		)
		(fp_line
			(start 13.32484 -1.470152)
			(end 13.337286 -1.539494)
			(stroke
				(width 0.1)
				(type default)
			)
			(layer "F.SilkS")
		)
		(fp_line
			(start 13.32484 -1.470152)
			(end 13.337286 -1.539494)
			(stroke
				(width 0.1)
				(type default)
			)
			(layer "F.SilkS")
		)
		(fp_line
			(start 13.337286 -1.539494)
			(end 13.34897 -1.608836)
			(stroke
				(width 0.1)
				(type default)
			)
			(layer "F.SilkS")
		)
		(fp_line
			(start 13.337286 -1.539494)
			(end 13.34897 -1.608836)
			(stroke
				(width 0.1)
				(type default)
			)
			(layer "F.SilkS")
		)
		(fp_line
			(start 13.34008 -4.947412)
			(end 12.522454 -4.16306)
			(stroke
				(width 0.1)
				(type default)
			)
			(layer "F.SilkS")
		)
		(fp_line
			(start 13.34008 -4.947412)
			(end 12.522454 -4.16306)
			(stroke
				(width 0.1)
				(type default)
			)
			(layer "F.SilkS")
		)
		(fp_line
			(start 13.34897 -1.608836)
			(end 13.361416 -1.678178)
			(stroke
				(width 0.1)
				(type default)
			)
			(layer "F.SilkS")
		)
		(fp_line
			(start 13.34897 -1.608836)
			(end 13.361416 -1.678178)
			(stroke
				(width 0.1)
				(type default)
			)
			(layer "F.SilkS")
		)
		(fp_line
			(start 13.361416 -1.678178)
			(end 13.373354 -1.74752)
			(stroke
				(width 0.1)
				(type default)
			)
			(layer "F.SilkS")
		)
		(fp_line
			(start 13.361416 -1.678178)
			(end 13.373354 -1.74752)
			(stroke
				(width 0.1)
				(type default)
			)
			(layer "F.SilkS")
		)
		(fp_line
			(start 13.373354 -1.74752)
			(end 13.385546 -1.817116)
			(stroke
				(width 0.1)
				(type default)
			)
			(layer "F.SilkS")
		)
		(fp_line
			(start 13.373354 -1.74752)
			(end 13.385546 -1.817116)
			(stroke
				(width 0.1)
				(type default)
			)
			(layer "F.SilkS")
		)
		(fp_line
			(start 13.373862 -4.922012)
			(end 12.545822 -4.127754)
			(stroke
				(width 0.1)
				(type default)
			)
			(layer "F.SilkS")
		)
		(fp_line
			(start 13.373862 -4.922012)
			(end 12.545822 -4.127754)
			(stroke
				(width 0.1)
				(type default)
			)
			(layer "F.SilkS")
		)
		(fp_line
			(start 13.385546 -1.817116)
			(end 13.397992 -1.886458)
			(stroke
				(width 0.1)
				(type default)
			)
			(layer "F.SilkS")
		)
		(fp_line
			(start 13.385546 -1.817116)
			(end 13.397992 -1.886458)
			(stroke
				(width 0.1)
				(type default)
			)
			(layer "F.SilkS")
		)
		(fp_line
			(start 13.397992 -1.886458)
			(end 13.40993 -1.9558)
			(stroke
				(width 0.1)
				(type default)
			)
			(layer "F.SilkS")
		)
		(fp_line
			(start 13.397992 -1.886458)
			(end 13.40993 -1.9558)
			(stroke
				(width 0.1)
				(type default)
			)
			(layer "F.SilkS")
		)
		(fp_line
			(start 13.407136 -4.896358)
			(end 12.568936 -4.092194)
			(stroke
				(width 0.1)
				(type default)
			)
			(layer "F.SilkS")
		)
		(fp_line
			(start 13.407136 -4.896358)
			(end 12.568936 -4.092194)
			(stroke
				(width 0.1)
				(type default)
			)
			(layer "F.SilkS")
		)
		(fp_line
			(start 13.40993 -1.9558)
			(end 13.422122 -2.025396)
			(stroke
				(width 0.1)
				(type default)
			)
			(layer "F.SilkS")
		)
		(fp_line
			(start 13.40993 -1.9558)
			(end 13.422122 -2.025396)
			(stroke
				(width 0.1)
				(type default)
			)
			(layer "F.SilkS")
		)
		(fp_line
			(start 13.422122 -2.025396)
			(end 13.434314 -2.094738)
			(stroke
				(width 0.1)
				(type default)
			)
			(layer "F.SilkS")
		)
		(fp_line
			(start 13.422122 -2.025396)
			(end 13.434314 -2.094738)
			(stroke
				(width 0.1)
				(type default)
			)
			(layer "F.SilkS")
		)
		(fp_line
			(start 13.434314 -2.094738)
			(end 13.446506 -2.163826)
			(stroke
				(width 0.1)
				(type default)
			)
			(layer "F.SilkS")
		)
		(fp_line
			(start 13.434314 -2.094738)
			(end 13.446506 -2.163826)
			(stroke
				(width 0.1)
				(type default)
			)
			(layer "F.SilkS")
		)
		(fp_line
			(start 13.440664 -4.871212)
			(end 12.58443 -4.049522)
			(stroke
				(width 0.1)
				(type default)
			)
			(layer "F.SilkS")
		)
		(fp_line
			(start 13.440664 -4.871212)
			(end 12.58443 -4.049522)
			(stroke
				(width 0.1)
				(type default)
			)
			(layer "F.SilkS")
		)
		(fp_line
			(start 13.446506 -2.163826)
			(end 13.458444 -2.233422)
			(stroke
				(width 0.1)
				(type default)
			)
			(layer "F.SilkS")
		)
		(fp_line
			(start 13.446506 -2.163826)
			(end 13.458444 -2.233422)
			(stroke
				(width 0.1)
				(type default)
			)
			(layer "F.SilkS")
		)
		(fp_line
			(start 13.458444 -2.233422)
			(end 13.47089 -2.302764)
			(stroke
				(width 0.1)
				(type default)
			)
			(layer "F.SilkS")
		)
		(fp_line
			(start 13.458444 -2.233422)
			(end 13.47089 -2.302764)
			(stroke
				(width 0.1)
				(type default)
			)
			(layer "F.SilkS")
		)
		(fp_line
			(start 13.466826 -4.837938)
			(end 12.599162 -4.005834)
			(stroke
				(width 0.1)
				(type default)
			)
			(layer "F.SilkS")
		)
		(fp_line
			(start 13.466826 -4.837938)
			(end 12.599162 -4.005834)
			(stroke
				(width 0.1)
				(type default)
			)
			(layer "F.SilkS")
		)
		(fp_line
			(start 13.47089 -2.302764)
			(end 13.483082 -2.372106)
			(stroke
				(width 0.1)
				(type default)
			)
			(layer "F.SilkS")
		)
		(fp_line
			(start 13.47089 -2.302764)
			(end 13.483082 -2.372106)
			(stroke
				(width 0.1)
				(type default)
			)
			(layer "F.SilkS")
		)
		(fp_line
			(start 13.483082 -2.372106)
			(end 13.49502 -2.441448)
			(stroke
				(width 0.1)
				(type default)
			)
			(layer "F.SilkS")
		)
		(fp_line
			(start 13.483082 -2.372106)
			(end 13.49502 -2.441448)
			(stroke
				(width 0.1)
				(type default)
			)
			(layer "F.SilkS")
		)
		(fp_line
			(start 13.492226 -4.804918)
			(end 12.606782 -3.955288)
			(stroke
				(width 0.1)
				(type default)
			)
			(layer "F.SilkS")
		)
		(fp_line
			(start 13.492226 -4.804918)
			(end 12.606782 -3.955288)
			(stroke
				(width 0.1)
				(type default)
			)
			(layer "F.SilkS")
		)
		(fp_line
			(start 13.49502 -2.441448)
			(end 13.507466 -2.51079)
			(stroke
				(width 0.1)
				(type default)
			)
			(layer "F.SilkS")
		)
		(fp_line
			(start 13.49502 -2.441448)
			(end 13.507466 -2.51079)
			(stroke
				(width 0.1)
				(type default)
			)
			(layer "F.SilkS")
		)
		(fp_line
			(start 13.507466 -2.51079)
			(end 13.519404 -2.580386)
			(stroke
				(width 0.1)
				(type default)
			)
			(layer "F.SilkS")
		)
		(fp_line
			(start 13.507466 -2.51079)
			(end 13.519404 -2.580386)
			(stroke
				(width 0.1)
				(type default)
			)
			(layer "F.SilkS")
		)
		(fp_line
			(start 13.518134 -4.771898)
			(end 12.612116 -3.902964)
			(stroke
				(width 0.1)
				(type default)
			)
			(layer "F.SilkS")
		)
		(fp_line
			(start 13.518134 -4.771898)
			(end 12.612116 -3.902964)
			(stroke
				(width 0.1)
				(type default)
			)
			(layer "F.SilkS")
		)
		(fp_line
			(start 13.519404 -2.580386)
			(end 13.531596 -2.649728)
			(stroke
				(width 0.1)
				(type default)
			)
			(layer "F.SilkS")
		)
		(fp_line
			(start 13.519404 -2.580386)
			(end 13.531596 -2.649728)
			(stroke
				(width 0.1)
				(type default)
			)
			(layer "F.SilkS")
		)
		(fp_line
			(start 13.531596 -2.649728)
			(end 13.544042 -2.71907)
			(stroke
				(width 0.1)
				(type default)
			)
			(layer "F.SilkS")
		)
		(fp_line
			(start 13.531596 -2.649728)
			(end 13.544042 -2.71907)
			(stroke
				(width 0.1)
				(type default)
			)
			(layer "F.SilkS")
		)
		(fp_line
			(start 13.544042 -4.738878)
			(end 12.60856 -3.84175)
			(stroke
				(width 0.1)
				(type default)
			)
			(layer "F.SilkS")
		)
		(fp_line
			(start 13.544042 -4.738878)
			(end 12.60856 -3.84175)
			(stroke
				(width 0.1)
				(type default)
			)
			(layer "F.SilkS")
		)
		(fp_line
			(start 13.544042 -2.71907)
			(end 13.55598 -2.788412)
			(stroke
				(width 0.1)
				(type default)
			)
			(layer "F.SilkS")
		)
		(fp_line
			(start 13.544042 -2.71907)
			(end 13.55598 -2.788412)
			(stroke
				(width 0.1)
				(type default)
			)
			(layer "F.SilkS")
		)
		(fp_line
			(start 13.55598 -2.788412)
			(end 13.568172 -2.857754)
			(stroke
				(width 0.1)
				(type default)
			)
			(layer "F.SilkS")
		)
		(fp_line
			(start 13.55598 -2.788412)
			(end 13.568172 -2.857754)
			(stroke
				(width 0.1)
				(type default)
			)
			(layer "F.SilkS")
		)
		(fp_line
			(start 13.568172 -2.857754)
			(end 13.580364 -2.927096)
			(stroke
				(width 0.1)
				(type default)
			)
			(layer "F.SilkS")
		)
		(fp_line
			(start 13.568172 -2.857754)
			(end 13.580364 -2.927096)
			(stroke
				(width 0.1)
				(type default)
			)
			(layer "F.SilkS")
		)
		(fp_line
			(start 13.569442 -4.705858)
			(end 12.601956 -3.777996)
			(stroke
				(width 0.1)
				(type default)
			)
			(layer "F.SilkS")
		)
		(fp_line
			(start 13.569442 -4.705858)
			(end 12.601956 -3.777996)
			(stroke
				(width 0.1)
				(type default)
			)
			(layer "F.SilkS")
		)
		(fp_line
			(start 13.580364 -2.927096)
			(end 13.592556 -2.996692)
			(stroke
				(width 0.1)
				(type default)
			)
			(layer "F.SilkS")
		)
		(fp_line
			(start 13.580364 -2.927096)
			(end 13.592556 -2.996692)
			(stroke
				(width 0.1)
				(type default)
			)
			(layer "F.SilkS")
		)
		(fp_line
			(start 13.592556 -2.996692)
			(end 13.604494 -3.06578)
			(stroke
				(width 0.1)
				(type default)
			)
			(layer "F.SilkS")
		)
		(fp_line
			(start 13.592556 -2.996692)
			(end 13.604494 -3.06578)
			(stroke
				(width 0.1)
				(type default)
			)
			(layer "F.SilkS")
		)
		(fp_line
			(start 13.59535 -4.672838)
			(end 12.590018 -3.708654)
			(stroke
				(width 0.1)
				(type default)
			)
			(layer "F.SilkS")
		)
		(fp_line
			(start 13.59535 -4.672838)
			(end 12.590018 -3.708654)
			(stroke
				(width 0.1)
				(type default)
			)
			(layer "F.SilkS")
		)
		(fp_line
			(start 13.604494 -3.06578)
			(end 13.61694 -3.135376)
			(stroke
				(width 0.1)
				(type default)
			)
			(layer "F.SilkS")
		)
		(fp_line
			(start 13.604494 -3.06578)
			(end 13.61694 -3.135376)
			(stroke
				(width 0.1)
				(type default)
			)
			(layer "F.SilkS")
		)
		(fp_line
			(start 13.616432 -4.635246)
			(end 12.57808 -3.639312)
			(stroke
				(width 0.1)
				(type default)
			)
			(layer "F.SilkS")
		)
		(fp_line
			(start 13.616432 -4.635246)
			(end 12.57808 -3.639312)
			(stroke
				(width 0.1)
				(type default)
			)
			(layer "F.SilkS")
		)
		(fp_line
			(start 13.61694 -3.135376)
			(end 13.629132 -3.204972)
			(stroke
				(width 0.1)
				(type default)
			)
			(layer "F.SilkS")
		)
		(fp_line
			(start 13.61694 -3.135376)
			(end 13.629132 -3.204972)
			(stroke
				(width 0.1)
				(type default)
			)
			(layer "F.SilkS")
		)
		(fp_line
			(start 13.629132 -3.204972)
			(end 13.64107 -3.27406)
			(stroke
				(width 0.1)
				(type default)
			)
			(layer "F.SilkS")
		)
		(fp_line
			(start 13.629132 -3.204972)
			(end 13.64107 -3.27406)
			(stroke
				(width 0.1)
				(type default)
			)
			(layer "F.SilkS")
		)
		(fp_line
			(start 13.633196 -4.593844)
			(end 11.82116 -2.855722)
			(stroke
				(width 0.1)
				(type default)
			)
			(layer "F.SilkS")
		)
		(fp_line
			(start 13.633196 -4.593844)
			(end 11.82116 -2.855722)
			(stroke
				(width 0.1)
				(type default)
			)
			(layer "F.SilkS")
		)
		(fp_line
			(start 13.64996 -4.552442)
			(end 11.877548 -2.851912)
			(stroke
				(width 0.1)
				(type default)
			)
			(layer "F.SilkS")
		)
		(fp_line
			(start 13.64996 -4.552442)
			(end 11.877548 -2.851912)
			(stroke
				(width 0.1)
				(type default)
			)
			(layer "F.SilkS")
		)
		(fp_line
			(start 13.653516 -3.343402)
			(end 13.64107 -3.27406)
			(stroke
				(width 0.1)
				(type default)
			)
			(layer "F.SilkS")
		)
		(fp_line
			(start 13.653516 -3.343402)
			(end 13.64107 -3.27406)
			(stroke
				(width 0.1)
				(type default)
			)
			(layer "F.SilkS")
		)
		(fp_line
			(start 13.665708 -3.412998)
			(end 10.943336 -0.801624)
			(stroke
				(width 0.1)
				(type default)
			)
			(layer "F.SilkS")
		)
		(fp_line
			(start 13.665708 -3.412998)
			(end 10.943336 -0.801624)
			(stroke
				(width 0.1)
				(type default)
			)
			(layer "F.SilkS")
		)
		(fp_line
			(start 13.665708 -3.412998)
			(end 13.653516 -3.343402)
			(stroke
				(width 0.1)
				(type default)
			)
			(layer "F.SilkS")
		)
		(fp_line
			(start 13.665708 -3.412998)
			(end 13.653516 -3.343402)
			(stroke
				(width 0.1)
				(type default)
			)
			(layer "F.SilkS")
		)
		(fp_line
			(start 13.667232 -4.51104)
			(end 11.93292 -2.84734)
			(stroke
				(width 0.1)
				(type default)
			)
			(layer "F.SilkS")
		)
		(fp_line
			(start 13.667232 -4.51104)
			(end 11.93292 -2.84734)
			(stroke
				(width 0.1)
				(type default)
			)
			(layer "F.SilkS")
		)
		(fp_line
			(start 13.677646 -3.48234)
			(end 12.323064 -2.182622)
			(stroke
				(width 0.1)
				(type default)
			)
			(layer "F.SilkS")
		)
		(fp_line
			(start 13.677646 -3.48234)
			(end 12.323064 -2.182622)
			(stroke
				(width 0.1)
				(type default)
			)
			(layer "F.SilkS")
		)
		(fp_line
			(start 13.677646 -3.48234)
			(end 13.665708 -3.412998)
			(stroke
				(width 0.1)
				(type default)
			)
			(layer "F.SilkS")
		)
		(fp_line
			(start 13.677646 -3.48234)
			(end 13.665708 -3.412998)
			(stroke
				(width 0.1)
				(type default)
			)
			(layer "F.SilkS")
		)
		(fp_line
			(start 13.684504 -4.469638)
			(end 11.986006 -2.840482)
			(stroke
				(width 0.1)
				(type default)
			)
			(layer "F.SilkS")
		)
		(fp_line
			(start 13.684504 -4.469638)
			(end 11.986006 -2.840482)
			(stroke
				(width 0.1)
				(type default)
			)
			(layer "F.SilkS")
		)
		(fp_line
			(start 13.690092 -3.551682)
			(end 12.335002 -2.251964)
			(stroke
				(width 0.1)
				(type default)
			)
			(layer "F.SilkS")
		)
		(fp_line
			(start 13.690092 -3.551682)
			(end 12.335002 -2.251964)
			(stroke
				(width 0.1)
				(type default)
			)
			(layer "F.SilkS")
		)
		(fp_line
			(start 13.690092 -3.551682)
			(end 13.677646 -3.48234)
			(stroke
				(width 0.1)
				(type default)
			)
			(layer "F.SilkS")
		)
		(fp_line
			(start 13.690092 -3.551682)
			(end 13.677646 -3.48234)
			(stroke
				(width 0.1)
				(type default)
			)
			(layer "F.SilkS")
		)
		(fp_line
			(start 13.701014 -4.42849)
			(end 12.037822 -2.832862)
			(stroke
				(width 0.1)
				(type default)
			)
			(layer "F.SilkS")
		)
		(fp_line
			(start 13.701014 -4.42849)
			(end 12.037822 -2.832862)
			(stroke
				(width 0.1)
				(type default)
			)
			(layer "F.SilkS")
		)
		(fp_line
			(start 13.70203 -3.621024)
			(end 12.347194 -2.321306)
			(stroke
				(width 0.1)
				(type default)
			)
			(layer "F.SilkS")
		)
		(fp_line
			(start 13.70203 -3.621024)
			(end 12.347194 -2.321306)
			(stroke
				(width 0.1)
				(type default)
			)
			(layer "F.SilkS")
		)
		(fp_line
			(start 13.70203 -3.621024)
			(end 13.690092 -3.551682)
			(stroke
				(width 0.1)
				(type default)
			)
			(layer "F.SilkS")
		)
		(fp_line
			(start 13.70203 -3.621024)
			(end 13.690092 -3.551682)
			(stroke
				(width 0.1)
				(type default)
			)
			(layer "F.SilkS")
		)
		(fp_line
			(start 13.714222 -3.690366)
			(end 12.359386 -2.390902)
			(stroke
				(width 0.1)
				(type default)
			)
			(layer "F.SilkS")
		)
		(fp_line
			(start 13.714222 -3.690366)
			(end 12.359386 -2.390902)
			(stroke
				(width 0.1)
				(type default)
			)
			(layer "F.SilkS")
		)
		(fp_line
			(start 13.714222 -3.690366)
			(end 13.70203 -3.621024)
			(stroke
				(width 0.1)
				(type default)
			)
			(layer "F.SilkS")
		)
		(fp_line
			(start 13.714222 -3.690366)
			(end 13.70203 -3.621024)
			(stroke
				(width 0.1)
				(type default)
			)
			(layer "F.SilkS")
		)
		(fp_line
			(start 13.715238 -4.383786)
			(end 12.087352 -2.822448)
			(stroke
				(width 0.1)
				(type default)
			)
			(layer "F.SilkS")
		)
		(fp_line
			(start 13.715238 -4.383786)
			(end 12.087352 -2.822448)
			(stroke
				(width 0.1)
				(type default)
			)
			(layer "F.SilkS")
		)
		(fp_line
			(start 13.722096 -4.332732)
			(end 12.135612 -2.810764)
			(stroke
				(width 0.1)
				(type default)
			)
			(layer "F.SilkS")
		)
		(fp_line
			(start 13.722096 -4.332732)
			(end 12.135612 -2.810764)
			(stroke
				(width 0.1)
				(type default)
			)
			(layer "F.SilkS")
		)
		(fp_line
			(start 13.72616 -3.759962)
			(end 12.371578 -2.460244)
			(stroke
				(width 0.1)
				(type default)
			)
			(layer "F.SilkS")
		)
		(fp_line
			(start 13.72616 -3.759962)
			(end 12.371578 -2.460244)
			(stroke
				(width 0.1)
				(type default)
			)
			(layer "F.SilkS")
		)
		(fp_line
			(start 13.729208 -4.281932)
			(end 12.181078 -2.796794)
			(stroke
				(width 0.1)
				(type default)
			)
			(layer "F.SilkS")
		)
		(fp_line
			(start 13.729208 -4.281932)
			(end 12.181078 -2.796794)
			(stroke
				(width 0.1)
				(type default)
			)
			(layer "F.SilkS")
		)
		(fp_line
			(start 13.731494 -3.822446)
			(end 12.38377 -2.529586)
			(stroke
				(width 0.1)
				(type default)
			)
			(layer "F.SilkS")
		)
		(fp_line
			(start 13.731494 -3.822446)
			(end 12.38377 -2.529586)
			(stroke
				(width 0.1)
				(type default)
			)
			(layer "F.SilkS")
		)
		(fp_line
			(start 13.73632 -4.230878)
			(end 12.224766 -2.781046)
			(stroke
				(width 0.1)
				(type default)
			)
			(layer "F.SilkS")
		)
		(fp_line
			(start 13.73632 -4.230878)
			(end 12.224766 -2.781046)
			(stroke
				(width 0.1)
				(type default)
			)
			(layer "F.SilkS")
		)
		(fp_line
			(start 13.736574 -3.88493)
			(end 12.395962 -2.598928)
			(stroke
				(width 0.1)
				(type default)
			)
			(layer "F.SilkS")
		)
		(fp_line
			(start 13.736574 -3.88493)
			(end 12.395962 -2.598928)
			(stroke
				(width 0.1)
				(type default)
			)
			(layer "F.SilkS")
		)
		(fp_line
			(start 13.741654 -3.947668)
			(end 12.408154 -2.668524)
			(stroke
				(width 0.1)
				(type default)
			)
			(layer "F.SilkS")
		)
		(fp_line
			(start 13.741654 -3.947668)
			(end 12.408154 -2.668524)
			(stroke
				(width 0.1)
				(type default)
			)
			(layer "F.SilkS")
		)
		(fp_line
			(start 13.743178 -4.179824)
			(end 12.266422 -2.76352)
			(stroke
				(width 0.1)
				(type default)
			)
			(layer "F.SilkS")
		)
		(fp_line
			(start 13.743178 -4.179824)
			(end 12.266422 -2.76352)
			(stroke
				(width 0.1)
				(type default)
			)
			(layer "F.SilkS")
		)
		(fp_line
			(start 13.74648 -4.010152)
			(end 12.380214 -2.699512)
			(stroke
				(width 0.1)
				(type default)
			)
			(layer "F.SilkS")
		)
		(fp_line
			(start 13.74648 -4.010152)
			(end 12.380214 -2.699512)
			(stroke
				(width 0.1)
				(type default)
			)
			(layer "F.SilkS")
		)
		(fp_line
			(start 13.750036 -4.12877)
			(end 12.306046 -2.743454)
			(stroke
				(width 0.1)
				(type default)
			)
			(layer "F.SilkS")
		)
		(fp_line
			(start 13.750036 -4.12877)
			(end 12.306046 -2.743454)
			(stroke
				(width 0.1)
				(type default)
			)
			(layer "F.SilkS")
		)
		(fp_line
			(start 13.751814 -4.072636)
			(end 12.344654 -2.722626)
			(stroke
				(width 0.1)
				(type default)
			)
			(layer "F.SilkS")
		)
		(fp_line
			(start 13.751814 -4.072636)
			(end 12.344654 -2.722626)
			(stroke
				(width 0.1)
				(type default)
			)
			(layer "F.SilkS")
		)
		(fp_line
			(start 13.944854 -0.882904)
			(end 13.976096 -0.882904)
			(stroke
				(width 0.1)
				(type default)
			)
			(layer "F.SilkS")
		)
		(fp_line
			(start 13.944854 -0.882904)
			(end 13.976096 -0.882904)
			(stroke
				(width 0.1)
				(type default)
			)
			(layer "F.SilkS")
		)
		(fp_line
			(start 13.95095 -0.916178)
			(end 13.944854 -0.882904)
			(stroke
				(width 0.1)
				(type default)
			)
			(layer "F.SilkS")
		)
		(fp_line
			(start 13.95095 -0.916178)
			(end 13.944854 -0.882904)
			(stroke
				(width 0.1)
				(type default)
			)
			(layer "F.SilkS")
		)
		(fp_line
			(start 13.95095 -0.916178)
			(end 15.307056 -2.21742)
			(stroke
				(width 0.1)
				(type default)
			)
			(layer "F.SilkS")
		)
		(fp_line
			(start 13.95095 -0.916178)
			(end 15.307056 -2.21742)
			(stroke
				(width 0.1)
				(type default)
			)
			(layer "F.SilkS")
		)
		(fp_line
			(start 13.962888 -0.985774)
			(end 13.95095 -0.916178)
			(stroke
				(width 0.1)
				(type default)
			)
			(layer "F.SilkS")
		)
		(fp_line
			(start 13.962888 -0.985774)
			(end 13.95095 -0.916178)
			(stroke
				(width 0.1)
				(type default)
			)
			(layer "F.SilkS")
		)
		(fp_line
			(start 13.962888 -0.985774)
			(end 15.319248 -2.286762)
			(stroke
				(width 0.1)
				(type default)
			)
			(layer "F.SilkS")
		)
		(fp_line
			(start 13.962888 -0.985774)
			(end 15.319248 -2.286762)
			(stroke
				(width 0.1)
				(type default)
			)
			(layer "F.SilkS")
		)
		(fp_line
			(start 13.975334 -1.055116)
			(end 13.962888 -0.985774)
			(stroke
				(width 0.1)
				(type default)
			)
			(layer "F.SilkS")
		)
		(fp_line
			(start 13.975334 -1.055116)
			(end 13.962888 -0.985774)
			(stroke
				(width 0.1)
				(type default)
			)
			(layer "F.SilkS")
		)
		(fp_line
			(start 13.975334 -1.055116)
			(end 15.331186 -2.356104)
			(stroke
				(width 0.1)
				(type default)
			)
			(layer "F.SilkS")
		)
		(fp_line
			(start 13.975334 -1.055116)
			(end 15.331186 -2.356104)
			(stroke
				(width 0.1)
				(type default)
			)
			(layer "F.SilkS")
		)
		(fp_line
			(start 13.976096 -0.882904)
			(end 14.036294 -0.882904)
			(stroke
				(width 0.1)
				(type default)
			)
			(layer "F.SilkS")
		)
		(fp_line
			(start 13.976096 -0.882904)
			(end 14.036294 -0.882904)
			(stroke
				(width 0.1)
				(type default)
			)
			(layer "F.SilkS")
		)
		(fp_line
			(start 13.976096 -0.882904)
			(end 15.294864 -2.147824)
			(stroke
				(width 0.1)
				(type default)
			)
			(layer "F.SilkS")
		)
		(fp_line
			(start 13.976096 -0.882904)
			(end 15.294864 -2.147824)
			(stroke
				(width 0.1)
				(type default)
			)
			(layer "F.SilkS")
		)
		(fp_line
			(start 13.987272 -1.124458)
			(end 13.975334 -1.055116)
			(stroke
				(width 0.1)
				(type default)
			)
			(layer "F.SilkS")
		)
		(fp_line
			(start 13.987272 -1.124458)
			(end 13.975334 -1.055116)
			(stroke
				(width 0.1)
				(type default)
			)
			(layer "F.SilkS")
		)
		(fp_line
			(start 13.987272 -1.124458)
			(end 15.343632 -2.425446)
			(stroke
				(width 0.1)
				(type default)
			)
			(layer "F.SilkS")
		)
		(fp_line
			(start 13.987272 -1.124458)
			(end 15.343632 -2.425446)
			(stroke
				(width 0.1)
				(type default)
			)
			(layer "F.SilkS")
		)
		(fp_line
			(start 13.999464 -1.194054)
			(end 13.987272 -1.124458)
			(stroke
				(width 0.1)
				(type default)
			)
			(layer "F.SilkS")
		)
		(fp_line
			(start 13.999464 -1.194054)
			(end 13.987272 -1.124458)
			(stroke
				(width 0.1)
				(type default)
			)
			(layer "F.SilkS")
		)
		(fp_line
			(start 13.999464 -1.194054)
			(end 15.355824 -2.495042)
			(stroke
				(width 0.1)
				(type default)
			)
			(layer "F.SilkS")
		)
		(fp_line
			(start 13.999464 -1.194054)
			(end 15.355824 -2.495042)
			(stroke
				(width 0.1)
				(type default)
			)
			(layer "F.SilkS")
		)
		(fp_line
			(start 14.01191 -1.26365)
			(end 13.999464 -1.194054)
			(stroke
				(width 0.1)
				(type default)
			)
			(layer "F.SilkS")
		)
		(fp_line
			(start 14.01191 -1.26365)
			(end 13.999464 -1.194054)
			(stroke
				(width 0.1)
				(type default)
			)
			(layer "F.SilkS")
		)
		(fp_line
			(start 14.01191 -1.26365)
			(end 15.367762 -2.564384)
			(stroke
				(width 0.1)
				(type default)
			)
			(layer "F.SilkS")
		)
		(fp_line
			(start 14.01191 -1.26365)
			(end 15.367762 -2.564384)
			(stroke
				(width 0.1)
				(type default)
			)
			(layer "F.SilkS")
		)
		(fp_line
			(start 14.023848 -1.332738)
			(end 14.01191 -1.26365)
			(stroke
				(width 0.1)
				(type default)
			)
			(layer "F.SilkS")
		)
		(fp_line
			(start 14.023848 -1.332738)
			(end 14.01191 -1.26365)
			(stroke
				(width 0.1)
				(type default)
			)
			(layer "F.SilkS")
		)
		(fp_line
			(start 14.023848 -1.332738)
			(end 15.380208 -2.633726)
			(stroke
				(width 0.1)
				(type default)
			)
			(layer "F.SilkS")
		)
		(fp_line
			(start 14.023848 -1.332738)
			(end 15.380208 -2.633726)
			(stroke
				(width 0.1)
				(type default)
			)
			(layer "F.SilkS")
		)
		(fp_line
			(start 14.03604 -1.40208)
			(end 14.023848 -1.332738)
			(stroke
				(width 0.1)
				(type default)
			)
			(layer "F.SilkS")
		)
		(fp_line
			(start 14.03604 -1.40208)
			(end 14.023848 -1.332738)
			(stroke
				(width 0.1)
				(type default)
			)
			(layer "F.SilkS")
		)
		(fp_line
			(start 14.03604 -1.40208)
			(end 15.392654 -2.703322)
			(stroke
				(width 0.1)
				(type default)
			)
			(layer "F.SilkS")
		)
		(fp_line
			(start 14.03604 -1.40208)
			(end 15.392654 -2.703322)
			(stroke
				(width 0.1)
				(type default)
			)
			(layer "F.SilkS")
		)
		(fp_line
			(start 14.036294 -0.882904)
			(end 14.096238 -0.882904)
			(stroke
				(width 0.1)
				(type default)
			)
			(layer "F.SilkS")
		)
		(fp_line
			(start 14.036294 -0.882904)
			(end 14.096238 -0.882904)
			(stroke
				(width 0.1)
				(type default)
			)
			(layer "F.SilkS")
		)
		(fp_line
			(start 14.036294 -0.882904)
			(end 15.282418 -2.078482)
			(stroke
				(width 0.1)
				(type default)
			)
			(layer "F.SilkS")
		)
		(fp_line
			(start 14.036294 -0.882904)
			(end 15.282418 -2.078482)
			(stroke
				(width 0.1)
				(type default)
			)
			(layer "F.SilkS")
		)
		(fp_line
			(start 14.048232 -1.471676)
			(end 14.03604 -1.40208)
			(stroke
				(width 0.1)
				(type default)
			)
			(layer "F.SilkS")
		)
		(fp_line
			(start 14.048232 -1.471676)
			(end 14.03604 -1.40208)
			(stroke
				(width 0.1)
				(type default)
			)
			(layer "F.SilkS")
		)
		(fp_line
			(start 14.048232 -1.471676)
			(end 15.404592 -2.772664)
			(stroke
				(width 0.1)
				(type default)
			)
			(layer "F.SilkS")
		)
		(fp_line
			(start 14.048232 -1.471676)
			(end 15.404592 -2.772664)
			(stroke
				(width 0.1)
				(type default)
			)
			(layer "F.SilkS")
		)
		(fp_line
			(start 14.060678 -1.541018)
			(end 14.048232 -1.471676)
			(stroke
				(width 0.1)
				(type default)
			)
			(layer "F.SilkS")
		)
		(fp_line
			(start 14.060678 -1.541018)
			(end 14.048232 -1.471676)
			(stroke
				(width 0.1)
				(type default)
			)
			(layer "F.SilkS")
		)
		(fp_line
			(start 14.060678 -1.541018)
			(end 15.416784 -2.84226)
			(stroke
				(width 0.1)
				(type default)
			)
			(layer "F.SilkS")
		)
		(fp_line
			(start 14.060678 -1.541018)
			(end 15.416784 -2.84226)
			(stroke
				(width 0.1)
				(type default)
			)
			(layer "F.SilkS")
		)
		(fp_line
			(start 14.072362 -1.61036)
			(end 14.060678 -1.541018)
			(stroke
				(width 0.1)
				(type default)
			)
			(layer "F.SilkS")
		)
		(fp_line
			(start 14.072362 -1.61036)
			(end 14.060678 -1.541018)
			(stroke
				(width 0.1)
				(type default)
			)
			(layer "F.SilkS")
		)
		(fp_line
			(start 14.072362 -1.61036)
			(end 15.42923 -2.911602)
			(stroke
				(width 0.1)
				(type default)
			)
			(layer "F.SilkS")
		)
		(fp_line
			(start 14.072362 -1.61036)
			(end 15.42923 -2.911602)
			(stroke
				(width 0.1)
				(type default)
			)
			(layer "F.SilkS")
		)
		(fp_line
			(start 14.084808 -1.679702)
			(end 14.072362 -1.61036)
			(stroke
				(width 0.1)
				(type default)
			)
			(layer "F.SilkS")
		)
		(fp_line
			(start 14.084808 -1.679702)
			(end 14.072362 -1.61036)
			(stroke
				(width 0.1)
				(type default)
			)
			(layer "F.SilkS")
		)
		(fp_line
			(start 14.084808 -1.679702)
			(end 14.097254 -1.749044)
			(stroke
				(width 0.1)
				(type default)
			)
			(layer "F.SilkS")
		)
		(fp_line
			(start 14.084808 -1.679702)
			(end 14.097254 -1.749044)
			(stroke
				(width 0.1)
				(type default)
			)
			(layer "F.SilkS")
		)
		(fp_line
			(start 14.096238 -0.882904)
			(end 14.156436 -0.882904)
			(stroke
				(width 0.1)
				(type default)
			)
			(layer "F.SilkS")
		)
		(fp_line
			(start 14.096238 -0.882904)
			(end 14.156436 -0.882904)
			(stroke
				(width 0.1)
				(type default)
			)
			(layer "F.SilkS")
		)
		(fp_line
			(start 14.096238 -0.882904)
			(end 15.270226 -2.00914)
			(stroke
				(width 0.1)
				(type default)
			)
			(layer "F.SilkS")
		)
		(fp_line
			(start 14.096238 -0.882904)
			(end 15.270226 -2.00914)
			(stroke
				(width 0.1)
				(type default)
			)
			(layer "F.SilkS")
		)
		(fp_line
			(start 14.109192 -1.81864)
			(end 14.097254 -1.749044)
			(stroke
				(width 0.1)
				(type default)
			)
			(layer "F.SilkS")
		)
		(fp_line
			(start 14.109192 -1.81864)
			(end 14.097254 -1.749044)
			(stroke
				(width 0.1)
				(type default)
			)
			(layer "F.SilkS")
		)
		(fp_line
			(start 14.121384 -1.887982)
			(end 14.109192 -1.81864)
			(stroke
				(width 0.1)
				(type default)
			)
			(layer "F.SilkS")
		)
		(fp_line
			(start 14.121384 -1.887982)
			(end 14.109192 -1.81864)
			(stroke
				(width 0.1)
				(type default)
			)
			(layer "F.SilkS")
		)
		(fp_line
			(start 14.13383 -1.957324)
			(end 14.121384 -1.887982)
			(stroke
				(width 0.1)
				(type default)
			)
			(layer "F.SilkS")
		)
		(fp_line
			(start 14.13383 -1.957324)
			(end 14.121384 -1.887982)
			(stroke
				(width 0.1)
				(type default)
			)
			(layer "F.SilkS")
		)
		(fp_line
			(start 14.145768 -2.02692)
			(end 14.13383 -1.957324)
			(stroke
				(width 0.1)
				(type default)
			)
			(layer "F.SilkS")
		)
		(fp_line
			(start 14.145768 -2.02692)
			(end 14.13383 -1.957324)
			(stroke
				(width 0.1)
				(type default)
			)
			(layer "F.SilkS")
		)
		(fp_line
			(start 14.156436 -0.882904)
			(end 14.216888 -0.882904)
			(stroke
				(width 0.1)
				(type default)
			)
			(layer "F.SilkS")
		)
		(fp_line
			(start 14.156436 -0.882904)
			(end 14.216888 -0.882904)
			(stroke
				(width 0.1)
				(type default)
			)
			(layer "F.SilkS")
		)
		(fp_line
			(start 14.156436 -0.882904)
			(end 15.258288 -1.939544)
			(stroke
				(width 0.1)
				(type default)
			)
			(layer "F.SilkS")
		)
		(fp_line
			(start 14.156436 -0.882904)
			(end 15.258288 -1.939544)
			(stroke
				(width 0.1)
				(type default)
			)
			(layer "F.SilkS")
		)
		(fp_line
			(start 14.15796 -2.096262)
			(end 14.145768 -2.02692)
			(stroke
				(width 0.1)
				(type default)
			)
			(layer "F.SilkS")
		)
		(fp_line
			(start 14.15796 -2.096262)
			(end 14.145768 -2.02692)
			(stroke
				(width 0.1)
				(type default)
			)
			(layer "F.SilkS")
		)
		(fp_line
			(start 14.170406 -2.165604)
			(end 14.15796 -2.096262)
			(stroke
				(width 0.1)
				(type default)
			)
			(layer "F.SilkS")
		)
		(fp_line
			(start 14.170406 -2.165604)
			(end 14.15796 -2.096262)
			(stroke
				(width 0.1)
				(type default)
			)
			(layer "F.SilkS")
		)
		(fp_line
			(start 14.182344 -2.234946)
			(end 14.170406 -2.165604)
			(stroke
				(width 0.1)
				(type default)
			)
			(layer "F.SilkS")
		)
		(fp_line
			(start 14.182344 -2.234946)
			(end 14.170406 -2.165604)
			(stroke
				(width 0.1)
				(type default)
			)
			(layer "F.SilkS")
		)
		(fp_line
			(start 14.194282 -2.304288)
			(end 14.182344 -2.234946)
			(stroke
				(width 0.1)
				(type default)
			)
			(layer "F.SilkS")
		)
		(fp_line
			(start 14.194282 -2.304288)
			(end 14.182344 -2.234946)
			(stroke
				(width 0.1)
				(type default)
			)
			(layer "F.SilkS")
		)
		(fp_line
			(start 14.206728 -2.373884)
			(end 14.194282 -2.304288)
			(stroke
				(width 0.1)
				(type default)
			)
			(layer "F.SilkS")
		)
		(fp_line
			(start 14.206728 -2.373884)
			(end 14.194282 -2.304288)
			(stroke
				(width 0.1)
				(type default)
			)
			(layer "F.SilkS")
		)
		(fp_line
			(start 14.216888 -0.882904)
			(end 14.277086 -0.882904)
			(stroke
				(width 0.1)
				(type default)
			)
			(layer "F.SilkS")
		)
		(fp_line
			(start 14.216888 -0.882904)
			(end 14.277086 -0.882904)
			(stroke
				(width 0.1)
				(type default)
			)
			(layer "F.SilkS")
		)
		(fp_line
			(start 14.216888 -0.882904)
			(end 15.245842 -1.869948)
			(stroke
				(width 0.1)
				(type default)
			)
			(layer "F.SilkS")
		)
		(fp_line
			(start 14.216888 -0.882904)
			(end 15.245842 -1.869948)
			(stroke
				(width 0.1)
				(type default)
			)
			(layer "F.SilkS")
		)
		(fp_line
			(start 14.21892 -2.443226)
			(end 14.206728 -2.373884)
			(stroke
				(width 0.1)
				(type default)
			)
			(layer "F.SilkS")
		)
		(fp_line
			(start 14.21892 -2.443226)
			(end 14.206728 -2.373884)
			(stroke
				(width 0.1)
				(type default)
			)
			(layer "F.SilkS")
		)
		(fp_line
			(start 14.230858 -2.512314)
			(end 14.21892 -2.443226)
			(stroke
				(width 0.1)
				(type default)
			)
			(layer "F.SilkS")
		)
		(fp_line
			(start 14.230858 -2.512314)
			(end 14.21892 -2.443226)
			(stroke
				(width 0.1)
				(type default)
			)
			(layer "F.SilkS")
		)
		(fp_line
			(start 14.243304 -2.58191)
			(end 14.230858 -2.512314)
			(stroke
				(width 0.1)
				(type default)
			)
			(layer "F.SilkS")
		)
		(fp_line
			(start 14.243304 -2.58191)
			(end 14.230858 -2.512314)
			(stroke
				(width 0.1)
				(type default)
			)
			(layer "F.SilkS")
		)
		(fp_line
			(start 14.255496 -2.651506)
			(end 14.243304 -2.58191)
			(stroke
				(width 0.1)
				(type default)
			)
			(layer "F.SilkS")
		)
		(fp_line
			(start 14.255496 -2.651506)
			(end 14.243304 -2.58191)
			(stroke
				(width 0.1)
				(type default)
			)
			(layer "F.SilkS")
		)
		(fp_line
			(start 14.267434 -2.720594)
			(end 14.255496 -2.651506)
			(stroke
				(width 0.1)
				(type default)
			)
			(layer "F.SilkS")
		)
		(fp_line
			(start 14.267434 -2.720594)
			(end 14.255496 -2.651506)
			(stroke
				(width 0.1)
				(type default)
			)
			(layer "F.SilkS")
		)
		(fp_line
			(start 14.277086 -0.882904)
			(end 14.33703 -0.882904)
			(stroke
				(width 0.1)
				(type default)
			)
			(layer "F.SilkS")
		)
		(fp_line
			(start 14.277086 -0.882904)
			(end 14.33703 -0.882904)
			(stroke
				(width 0.1)
				(type default)
			)
			(layer "F.SilkS")
		)
		(fp_line
			(start 14.277086 -0.882904)
			(end 15.233396 -1.800606)
			(stroke
				(width 0.1)
				(type default)
			)
			(layer "F.SilkS")
		)
		(fp_line
			(start 14.277086 -0.882904)
			(end 15.233396 -1.800606)
			(stroke
				(width 0.1)
				(type default)
			)
			(layer "F.SilkS")
		)
		(fp_line
			(start 14.27988 -2.79019)
			(end 14.267434 -2.720594)
			(stroke
				(width 0.1)
				(type default)
			)
			(layer "F.SilkS")
		)
		(fp_line
			(start 14.27988 -2.79019)
			(end 14.267434 -2.720594)
			(stroke
				(width 0.1)
				(type default)
			)
			(layer "F.SilkS")
		)
		(fp_line
			(start 14.291818 -2.859532)
			(end 14.27988 -2.79019)
			(stroke
				(width 0.1)
				(type default)
			)
			(layer "F.SilkS")
		)
		(fp_line
			(start 14.291818 -2.859532)
			(end 14.27988 -2.79019)
			(stroke
				(width 0.1)
				(type default)
			)
			(layer "F.SilkS")
		)
		(fp_line
			(start 14.30401 -2.928874)
			(end 14.291818 -2.859532)
			(stroke
				(width 0.1)
				(type default)
			)
			(layer "F.SilkS")
		)
		(fp_line
			(start 14.30401 -2.928874)
			(end 14.291818 -2.859532)
			(stroke
				(width 0.1)
				(type default)
			)
			(layer "F.SilkS")
		)
		(fp_line
			(start 14.316456 -2.998216)
			(end 14.30401 -2.928874)
			(stroke
				(width 0.1)
				(type default)
			)
			(layer "F.SilkS")
		)
		(fp_line
			(start 14.316456 -2.998216)
			(end 14.30401 -2.928874)
			(stroke
				(width 0.1)
				(type default)
			)
			(layer "F.SilkS")
		)
		(fp_line
			(start 14.328394 -3.067558)
			(end 14.316456 -2.998216)
			(stroke
				(width 0.1)
				(type default)
			)
			(layer "F.SilkS")
		)
		(fp_line
			(start 14.328394 -3.067558)
			(end 14.316456 -2.998216)
			(stroke
				(width 0.1)
				(type default)
			)
			(layer "F.SilkS")
		)
		(fp_line
			(start 14.33703 -0.882904)
			(end 14.396974 -0.882904)
			(stroke
				(width 0.1)
				(type default)
			)
			(layer "F.SilkS")
		)
		(fp_line
			(start 14.33703 -0.882904)
			(end 14.396974 -0.882904)
			(stroke
				(width 0.1)
				(type default)
			)
			(layer "F.SilkS")
		)
		(fp_line
			(start 14.33703 -0.882904)
			(end 15.221458 -1.731518)
			(stroke
				(width 0.1)
				(type default)
			)
			(layer "F.SilkS")
		)
		(fp_line
			(start 14.33703 -0.882904)
			(end 15.221458 -1.731518)
			(stroke
				(width 0.1)
				(type default)
			)
			(layer "F.SilkS")
		)
		(fp_line
			(start 14.340586 -3.137154)
			(end 14.328394 -3.067558)
			(stroke
				(width 0.1)
				(type default)
			)
			(layer "F.SilkS")
		)
		(fp_line
			(start 14.340586 -3.137154)
			(end 14.328394 -3.067558)
			(stroke
				(width 0.1)
				(type default)
			)
			(layer "F.SilkS")
		)
		(fp_line
			(start 14.352778 -3.206496)
			(end 14.340586 -3.137154)
			(stroke
				(width 0.1)
				(type default)
			)
			(layer "F.SilkS")
		)
		(fp_line
			(start 14.352778 -3.206496)
			(end 14.340586 -3.137154)
			(stroke
				(width 0.1)
				(type default)
			)
			(layer "F.SilkS")
		)
		(fp_line
			(start 14.36497 -3.275838)
			(end 14.352778 -3.206496)
			(stroke
				(width 0.1)
				(type default)
			)
			(layer "F.SilkS")
		)
		(fp_line
			(start 14.36497 -3.275838)
			(end 14.352778 -3.206496)
			(stroke
				(width 0.1)
				(type default)
			)
			(layer "F.SilkS")
		)
		(fp_line
			(start 14.376908 -3.34518)
			(end 14.36497 -3.275838)
			(stroke
				(width 0.1)
				(type default)
			)
			(layer "F.SilkS")
		)
		(fp_line
			(start 14.376908 -3.34518)
			(end 14.36497 -3.275838)
			(stroke
				(width 0.1)
				(type default)
			)
			(layer "F.SilkS")
		)
		(fp_line
			(start 14.389354 -3.414776)
			(end 14.376908 -3.34518)
			(stroke
				(width 0.1)
				(type default)
			)
			(layer "F.SilkS")
		)
		(fp_line
			(start 14.389354 -3.414776)
			(end 14.376908 -3.34518)
			(stroke
				(width 0.1)
				(type default)
			)
			(layer "F.SilkS")
		)
		(fp_line
			(start 14.396974 -0.882904)
			(end 14.45768 -0.882904)
			(stroke
				(width 0.1)
				(type default)
			)
			(layer "F.SilkS")
		)
		(fp_line
			(start 14.396974 -0.882904)
			(end 14.45768 -0.882904)
			(stroke
				(width 0.1)
				(type default)
			)
			(layer "F.SilkS")
		)
		(fp_line
			(start 14.396974 -0.882904)
			(end 15.209266 -1.661922)
			(stroke
				(width 0.1)
				(type default)
			)
			(layer "F.SilkS")
		)
		(fp_line
			(start 14.396974 -0.882904)
			(end 15.209266 -1.661922)
			(stroke
				(width 0.1)
				(type default)
			)
			(layer "F.SilkS")
		)
		(fp_line
			(start 14.401546 -3.484118)
			(end 14.389354 -3.414776)
			(stroke
				(width 0.1)
				(type default)
			)
			(layer "F.SilkS")
		)
		(fp_line
			(start 14.401546 -3.484118)
			(end 14.389354 -3.414776)
			(stroke
				(width 0.1)
				(type default)
			)
			(layer "F.SilkS")
		)
		(fp_line
			(start 14.413484 -3.55346)
			(end 14.401546 -3.484118)
			(stroke
				(width 0.1)
				(type default)
			)
			(layer "F.SilkS")
		)
		(fp_line
			(start 14.413484 -3.55346)
			(end 14.401546 -3.484118)
			(stroke
				(width 0.1)
				(type default)
			)
			(layer "F.SilkS")
		)
		(fp_line
			(start 14.42593 -3.622802)
			(end 14.413484 -3.55346)
			(stroke
				(width 0.1)
				(type default)
			)
			(layer "F.SilkS")
		)
		(fp_line
			(start 14.42593 -3.622802)
			(end 14.413484 -3.55346)
			(stroke
				(width 0.1)
				(type default)
			)
			(layer "F.SilkS")
		)
		(fp_line
			(start 14.438376 -3.692398)
			(end 14.42593 -3.622802)
			(stroke
				(width 0.1)
				(type default)
			)
			(layer "F.SilkS")
		)
		(fp_line
			(start 14.438376 -3.692398)
			(end 14.42593 -3.622802)
			(stroke
				(width 0.1)
				(type default)
			)
			(layer "F.SilkS")
		)
		(fp_line
			(start 14.45006 -3.76174)
			(end 14.438376 -3.692398)
			(stroke
				(width 0.1)
				(type default)
			)
			(layer "F.SilkS")
		)
		(fp_line
			(start 14.45006 -3.76174)
			(end 14.438376 -3.692398)
			(stroke
				(width 0.1)
				(type default)
			)
			(layer "F.SilkS")
		)
		(fp_line
			(start 14.45768 -0.882904)
			(end 14.517624 -0.882904)
			(stroke
				(width 0.1)
				(type default)
			)
			(layer "F.SilkS")
		)
		(fp_line
			(start 14.45768 -0.882904)
			(end 14.517624 -0.882904)
			(stroke
				(width 0.1)
				(type default)
			)
			(layer "F.SilkS")
		)
		(fp_line
			(start 14.45768 -0.882904)
			(end 15.19682 -1.592326)
			(stroke
				(width 0.1)
				(type default)
			)
			(layer "F.SilkS")
		)
		(fp_line
			(start 14.45768 -0.882904)
			(end 15.19682 -1.592326)
			(stroke
				(width 0.1)
				(type default)
			)
			(layer "F.SilkS")
		)
		(fp_line
			(start 14.462506 -3.831082)
			(end 14.45006 -3.76174)
			(stroke
				(width 0.1)
				(type default)
			)
			(layer "F.SilkS")
		)
		(fp_line
			(start 14.462506 -3.831082)
			(end 14.45006 -3.76174)
			(stroke
				(width 0.1)
				(type default)
			)
			(layer "F.SilkS")
		)
		(fp_line
			(start 14.474952 -3.900424)
			(end 14.462506 -3.831082)
			(stroke
				(width 0.1)
				(type default)
			)
			(layer "F.SilkS")
		)
		(fp_line
			(start 14.474952 -3.900424)
			(end 14.462506 -3.831082)
			(stroke
				(width 0.1)
				(type default)
			)
			(layer "F.SilkS")
		)
		(fp_line
			(start 14.486636 -3.969766)
			(end 14.474952 -3.900424)
			(stroke
				(width 0.1)
				(type default)
			)
			(layer "F.SilkS")
		)
		(fp_line
			(start 14.486636 -3.969766)
			(end 14.474952 -3.900424)
			(stroke
				(width 0.1)
				(type default)
			)
			(layer "F.SilkS")
		)
		(fp_line
			(start 14.498828 -4.039362)
			(end 14.486636 -3.969766)
			(stroke
				(width 0.1)
				(type default)
			)
			(layer "F.SilkS")
		)
		(fp_line
			(start 14.498828 -4.039362)
			(end 14.486636 -3.969766)
			(stroke
				(width 0.1)
				(type default)
			)
			(layer "F.SilkS")
		)
		(fp_line
			(start 14.511274 -4.108704)
			(end 14.498828 -4.039362)
			(stroke
				(width 0.1)
				(type default)
			)
			(layer "F.SilkS")
		)
		(fp_line
			(start 14.511274 -4.108704)
			(end 14.498828 -4.039362)
			(stroke
				(width 0.1)
				(type default)
			)
			(layer "F.SilkS")
		)
		(fp_line
			(start 14.517624 -0.882904)
			(end 14.577568 -0.882904)
			(stroke
				(width 0.1)
				(type default)
			)
			(layer "F.SilkS")
		)
		(fp_line
			(start 14.517624 -0.882904)
			(end 14.577568 -0.882904)
			(stroke
				(width 0.1)
				(type default)
			)
			(layer "F.SilkS")
		)
		(fp_line
			(start 14.517624 -0.882904)
			(end 15.184882 -1.522984)
			(stroke
				(width 0.1)
				(type default)
			)
			(layer "F.SilkS")
		)
		(fp_line
			(start 14.517624 -0.882904)
			(end 15.184882 -1.522984)
			(stroke
				(width 0.1)
				(type default)
			)
			(layer "F.SilkS")
		)
		(fp_line
			(start 14.523466 -4.178046)
			(end 14.511274 -4.108704)
			(stroke
				(width 0.1)
				(type default)
			)
			(layer "F.SilkS")
		)
		(fp_line
			(start 14.523466 -4.178046)
			(end 14.511274 -4.108704)
			(stroke
				(width 0.1)
				(type default)
			)
			(layer "F.SilkS")
		)
		(fp_line
			(start 14.523466 -4.178046)
			(end 14.535404 -4.247388)
			(stroke
				(width 0.1)
				(type default)
			)
			(layer "F.SilkS")
		)
		(fp_line
			(start 14.523466 -4.178046)
			(end 14.535404 -4.247388)
			(stroke
				(width 0.1)
				(type default)
			)
			(layer "F.SilkS")
		)
		(fp_line
			(start 14.535404 -4.247388)
			(end 14.54785 -4.316984)
			(stroke
				(width 0.1)
				(type default)
			)
			(layer "F.SilkS")
		)
		(fp_line
			(start 14.535404 -4.247388)
			(end 14.54785 -4.316984)
			(stroke
				(width 0.1)
				(type default)
			)
			(layer "F.SilkS")
		)
		(fp_line
			(start 14.54785 -4.316984)
			(end 14.560042 -4.386326)
			(stroke
				(width 0.1)
				(type default)
			)
			(layer "F.SilkS")
		)
		(fp_line
			(start 14.54785 -4.316984)
			(end 14.560042 -4.386326)
			(stroke
				(width 0.1)
				(type default)
			)
			(layer "F.SilkS")
		)
		(fp_line
			(start 14.560042 -4.386326)
			(end 14.57198 -4.455668)
			(stroke
				(width 0.1)
				(type default)
			)
			(layer "F.SilkS")
		)
		(fp_line
			(start 14.560042 -4.386326)
			(end 14.57198 -4.455668)
			(stroke
				(width 0.1)
				(type default)
			)
			(layer "F.SilkS")
		)
		(fp_line
			(start 14.57198 -4.455668)
			(end 14.584426 -4.52501)
			(stroke
				(width 0.1)
				(type default)
			)
			(layer "F.SilkS")
		)
		(fp_line
			(start 14.57198 -4.455668)
			(end 14.584426 -4.52501)
			(stroke
				(width 0.1)
				(type default)
			)
			(layer "F.SilkS")
		)
		(fp_line
			(start 14.577568 -0.882904)
			(end 14.637766 -0.882904)
			(stroke
				(width 0.1)
				(type default)
			)
			(layer "F.SilkS")
		)
		(fp_line
			(start 14.577568 -0.882904)
			(end 14.637766 -0.882904)
			(stroke
				(width 0.1)
				(type default)
			)
			(layer "F.SilkS")
		)
		(fp_line
			(start 14.577568 -0.882904)
			(end 15.17269 -1.453642)
			(stroke
				(width 0.1)
				(type default)
			)
			(layer "F.SilkS")
		)
		(fp_line
			(start 14.577568 -0.882904)
			(end 15.17269 -1.453642)
			(stroke
				(width 0.1)
				(type default)
			)
			(layer "F.SilkS")
		)
		(fp_line
			(start 14.584426 -4.52501)
			(end 14.596364 -4.594352)
			(stroke
				(width 0.1)
				(type default)
			)
			(layer "F.SilkS")
		)
		(fp_line
			(start 14.584426 -4.52501)
			(end 14.596364 -4.594352)
			(stroke
				(width 0.1)
				(type default)
			)
			(layer "F.SilkS")
		)
		(fp_line
			(start 14.596364 -4.594352)
			(end 14.608556 -4.663948)
			(stroke
				(width 0.1)
				(type default)
			)
			(layer "F.SilkS")
		)
		(fp_line
			(start 14.596364 -4.594352)
			(end 14.608556 -4.663948)
			(stroke
				(width 0.1)
				(type default)
			)
			(layer "F.SilkS")
		)
		(fp_line
			(start 14.608556 -4.663948)
			(end 14.621002 -4.733036)
			(stroke
				(width 0.1)
				(type default)
			)
			(layer "F.SilkS")
		)
		(fp_line
			(start 14.608556 -4.663948)
			(end 14.621002 -4.733036)
			(stroke
				(width 0.1)
				(type default)
			)
			(layer "F.SilkS")
		)
		(fp_line
			(start 14.621002 -4.733036)
			(end 14.63294 -4.802632)
			(stroke
				(width 0.1)
				(type default)
			)
			(layer "F.SilkS")
		)
		(fp_line
			(start 14.621002 -4.733036)
			(end 14.63294 -4.802632)
			(stroke
				(width 0.1)
				(type default)
			)
			(layer "F.SilkS")
		)
		(fp_line
			(start 14.63294 -4.802632)
			(end 14.645132 -4.872228)
			(stroke
				(width 0.1)
				(type default)
			)
			(layer "F.SilkS")
		)
		(fp_line
			(start 14.63294 -4.802632)
			(end 14.645132 -4.872228)
			(stroke
				(width 0.1)
				(type default)
			)
			(layer "F.SilkS")
		)
		(fp_line
			(start 14.637766 -0.882904)
			(end 14.697964 -0.882904)
			(stroke
				(width 0.1)
				(type default)
			)
			(layer "F.SilkS")
		)
		(fp_line
			(start 14.637766 -0.882904)
			(end 14.697964 -0.882904)
			(stroke
				(width 0.1)
				(type default)
			)
			(layer "F.SilkS")
		)
		(fp_line
			(start 14.637766 -0.882904)
			(end 15.160498 -1.384046)
			(stroke
				(width 0.1)
				(type default)
			)
			(layer "F.SilkS")
		)
		(fp_line
			(start 14.637766 -0.882904)
			(end 15.160498 -1.384046)
			(stroke
				(width 0.1)
				(type default)
			)
			(layer "F.SilkS")
		)
		(fp_line
			(start 14.645132 -4.872228)
			(end 14.657324 -4.941316)
			(stroke
				(width 0.1)
				(type default)
			)
			(layer "F.SilkS")
		)
		(fp_line
			(start 14.645132 -4.872228)
			(end 14.657324 -4.941316)
			(stroke
				(width 0.1)
				(type default)
			)
			(layer "F.SilkS")
		)
		(fp_line
			(start 14.657324 -4.941316)
			(end 14.669516 -5.010912)
			(stroke
				(width 0.1)
				(type default)
			)
			(layer "F.SilkS")
		)
		(fp_line
			(start 14.657324 -4.941316)
			(end 14.669516 -5.010912)
			(stroke
				(width 0.1)
				(type default)
			)
			(layer "F.SilkS")
		)
		(fp_line
			(start 14.669516 -5.010912)
			(end 14.681454 -5.080254)
			(stroke
				(width 0.1)
				(type default)
			)
			(layer "F.SilkS")
		)
		(fp_line
			(start 14.669516 -5.010912)
			(end 14.681454 -5.080254)
			(stroke
				(width 0.1)
				(type default)
			)
			(layer "F.SilkS")
		)
		(fp_line
			(start 14.681454 -5.080254)
			(end 14.6939 -5.149596)
			(stroke
				(width 0.1)
				(type default)
			)
			(layer "F.SilkS")
		)
		(fp_line
			(start 14.681454 -5.080254)
			(end 14.6939 -5.149596)
			(stroke
				(width 0.1)
				(type default)
			)
			(layer "F.SilkS")
		)
		(fp_line
			(start 14.69771 -5.171694)
			(end 14.6939 -5.149596)
			(stroke
				(width 0.1)
				(type default)
			)
			(layer "F.SilkS")
		)
		(fp_line
			(start 14.69771 -5.171694)
			(end 14.6939 -5.149596)
			(stroke
				(width 0.1)
				(type default)
			)
			(layer "F.SilkS")
		)
		(fp_line
			(start 14.697964 -0.882904)
			(end 14.757908 -0.882904)
			(stroke
				(width 0.1)
				(type default)
			)
			(layer "F.SilkS")
		)
		(fp_line
			(start 14.697964 -0.882904)
			(end 14.757908 -0.882904)
			(stroke
				(width 0.1)
				(type default)
			)
			(layer "F.SilkS")
		)
		(fp_line
			(start 14.697964 -0.882904)
			(end 15.148052 -1.314704)
			(stroke
				(width 0.1)
				(type default)
			)
			(layer "F.SilkS")
		)
		(fp_line
			(start 14.697964 -0.882904)
			(end 15.148052 -1.314704)
			(stroke
				(width 0.1)
				(type default)
			)
			(layer "F.SilkS")
		)
		(fp_line
			(start 14.71676 -5.171694)
			(end 14.6939 -5.149596)
			(stroke
				(width 0.1)
				(type default)
			)
			(layer "F.SilkS")
		)
		(fp_line
			(start 14.71676 -5.171694)
			(end 14.6939 -5.149596)
			(stroke
				(width 0.1)
				(type default)
			)
			(layer "F.SilkS")
		)
		(fp_line
			(start 14.71676 -5.171694)
			(end 14.69771 -5.171694)
			(stroke
				(width 0.1)
				(type default)
			)
			(layer "F.SilkS")
		)
		(fp_line
			(start 14.71676 -5.171694)
			(end 14.69771 -5.171694)
			(stroke
				(width 0.1)
				(type default)
			)
			(layer "F.SilkS")
		)
		(fp_line
			(start 14.757908 -0.882904)
			(end 14.81836 -0.882904)
			(stroke
				(width 0.1)
				(type default)
			)
			(layer "F.SilkS")
		)
		(fp_line
			(start 14.757908 -0.882904)
			(end 14.81836 -0.882904)
			(stroke
				(width 0.1)
				(type default)
			)
			(layer "F.SilkS")
		)
		(fp_line
			(start 14.757908 -0.882904)
			(end 15.13586 -1.245362)
			(stroke
				(width 0.1)
				(type default)
			)
			(layer "F.SilkS")
		)
		(fp_line
			(start 14.757908 -0.882904)
			(end 15.13586 -1.245362)
			(stroke
				(width 0.1)
				(type default)
			)
			(layer "F.SilkS")
		)
		(fp_line
			(start 14.776958 -5.171694)
			(end 14.681454 -5.080254)
			(stroke
				(width 0.1)
				(type default)
			)
			(layer "F.SilkS")
		)
		(fp_line
			(start 14.776958 -5.171694)
			(end 14.681454 -5.080254)
			(stroke
				(width 0.1)
				(type default)
			)
			(layer "F.SilkS")
		)
		(fp_line
			(start 14.776958 -5.171694)
			(end 14.71676 -5.171694)
			(stroke
				(width 0.1)
				(type default)
			)
			(layer "F.SilkS")
		)
		(fp_line
			(start 14.776958 -5.171694)
			(end 14.71676 -5.171694)
			(stroke
				(width 0.1)
				(type default)
			)
			(layer "F.SilkS")
		)
		(fp_line
			(start 14.81836 -0.882904)
			(end 14.878558 -0.882904)
			(stroke
				(width 0.1)
				(type default)
			)
			(layer "F.SilkS")
		)
		(fp_line
			(start 14.81836 -0.882904)
			(end 14.878558 -0.882904)
			(stroke
				(width 0.1)
				(type default)
			)
			(layer "F.SilkS")
		)
		(fp_line
			(start 14.81836 -0.882904)
			(end 15.123922 -1.17602)
			(stroke
				(width 0.1)
				(type default)
			)
			(layer "F.SilkS")
		)
		(fp_line
			(start 14.81836 -0.882904)
			(end 15.123922 -1.17602)
			(stroke
				(width 0.1)
				(type default)
			)
			(layer "F.SilkS")
		)
		(fp_line
			(start 14.837156 -5.171694)
			(end 14.669516 -5.010912)
			(stroke
				(width 0.1)
				(type default)
			)
			(layer "F.SilkS")
		)
		(fp_line
			(start 14.837156 -5.171694)
			(end 14.669516 -5.010912)
			(stroke
				(width 0.1)
				(type default)
			)
			(layer "F.SilkS")
		)
		(fp_line
			(start 14.837156 -5.171694)
			(end 14.776958 -5.171694)
			(stroke
				(width 0.1)
				(type default)
			)
			(layer "F.SilkS")
		)
		(fp_line
			(start 14.837156 -5.171694)
			(end 14.776958 -5.171694)
			(stroke
				(width 0.1)
				(type default)
			)
			(layer "F.SilkS")
		)
		(fp_line
			(start 14.878558 -0.882904)
			(end 14.938502 -0.882904)
			(stroke
				(width 0.1)
				(type default)
			)
			(layer "F.SilkS")
		)
		(fp_line
			(start 14.878558 -0.882904)
			(end 14.938502 -0.882904)
			(stroke
				(width 0.1)
				(type default)
			)
			(layer "F.SilkS")
		)
		(fp_line
			(start 14.878558 -0.882904)
			(end 15.111476 -1.106424)
			(stroke
				(width 0.1)
				(type default)
			)
			(layer "F.SilkS")
		)
		(fp_line
			(start 14.878558 -0.882904)
			(end 15.111476 -1.106424)
			(stroke
				(width 0.1)
				(type default)
			)
			(layer "F.SilkS")
		)
		(fp_line
			(start 14.8971 -5.171694)
			(end 14.657324 -4.941316)
			(stroke
				(width 0.1)
				(type default)
			)
			(layer "F.SilkS")
		)
		(fp_line
			(start 14.8971 -5.171694)
			(end 14.657324 -4.941316)
			(stroke
				(width 0.1)
				(type default)
			)
			(layer "F.SilkS")
		)
		(fp_line
			(start 14.8971 -5.171694)
			(end 14.837156 -5.171694)
			(stroke
				(width 0.1)
				(type default)
			)
			(layer "F.SilkS")
		)
		(fp_line
			(start 14.8971 -5.171694)
			(end 14.837156 -5.171694)
			(stroke
				(width 0.1)
				(type default)
			)
			(layer "F.SilkS")
		)
		(fp_line
			(start 14.938502 -0.882904)
			(end 14.998954 -0.882904)
			(stroke
				(width 0.1)
				(type default)
			)
			(layer "F.SilkS")
		)
		(fp_line
			(start 14.938502 -0.882904)
			(end 14.998954 -0.882904)
			(stroke
				(width 0.1)
				(type default)
			)
			(layer "F.SilkS")
		)
		(fp_line
			(start 14.938502 -0.882904)
			(end 15.09903 -1.036828)
			(stroke
				(width 0.1)
				(type default)
			)
			(layer "F.SilkS")
		)
		(fp_line
			(start 14.938502 -0.882904)
			(end 15.09903 -1.036828)
			(stroke
				(width 0.1)
				(type default)
			)
			(layer "F.SilkS")
		)
		(fp_line
			(start 14.957552 -5.171694)
			(end 14.645132 -4.872228)
			(stroke
				(width 0.1)
				(type default)
			)
			(layer "F.SilkS")
		)
		(fp_line
			(start 14.957552 -5.171694)
			(end 14.645132 -4.872228)
			(stroke
				(width 0.1)
				(type default)
			)
			(layer "F.SilkS")
		)
		(fp_line
			(start 14.957552 -5.171694)
			(end 14.8971 -5.171694)
			(stroke
				(width 0.1)
				(type default)
			)
			(layer "F.SilkS")
		)
		(fp_line
			(start 14.957552 -5.171694)
			(end 14.8971 -5.171694)
			(stroke
				(width 0.1)
				(type default)
			)
			(layer "F.SilkS")
		)
		(fp_line
			(start 14.998954 -0.882904)
			(end 15.059152 -0.882904)
			(stroke
				(width 0.1)
				(type default)
			)
			(layer "F.SilkS")
		)
		(fp_line
			(start 14.998954 -0.882904)
			(end 15.059152 -0.882904)
			(stroke
				(width 0.1)
				(type default)
			)
			(layer "F.SilkS")
		)
		(fp_line
			(start 14.998954 -0.882904)
			(end 15.087092 -0.96774)
			(stroke
				(width 0.1)
				(type default)
			)
			(layer "F.SilkS")
		)
		(fp_line
			(start 14.998954 -0.882904)
			(end 15.087092 -0.96774)
			(stroke
				(width 0.1)
				(type default)
			)
			(layer "F.SilkS")
		)
		(fp_line
			(start 15.01775 -5.171694)
			(end 14.63294 -4.802632)
			(stroke
				(width 0.1)
				(type default)
			)
			(layer "F.SilkS")
		)
		(fp_line
			(start 15.01775 -5.171694)
			(end 14.63294 -4.802632)
			(stroke
				(width 0.1)
				(type default)
			)
			(layer "F.SilkS")
		)
		(fp_line
			(start 15.01775 -5.171694)
			(end 14.957552 -5.171694)
			(stroke
				(width 0.1)
				(type default)
			)
			(layer "F.SilkS")
		)
		(fp_line
			(start 15.01775 -5.171694)
			(end 14.957552 -5.171694)
			(stroke
				(width 0.1)
				(type default)
			)
			(layer "F.SilkS")
		)
		(fp_line
			(start 15.059152 -0.882904)
			(end 15.072106 -0.882904)
			(stroke
				(width 0.1)
				(type default)
			)
			(layer "F.SilkS")
		)
		(fp_line
			(start 15.059152 -0.882904)
			(end 15.072106 -0.882904)
			(stroke
				(width 0.1)
				(type default)
			)
			(layer "F.SilkS")
		)
		(fp_line
			(start 15.059152 -0.882904)
			(end 15.0749 -0.898398)
			(stroke
				(width 0.1)
				(type default)
			)
			(layer "F.SilkS")
		)
		(fp_line
			(start 15.059152 -0.882904)
			(end 15.0749 -0.898398)
			(stroke
				(width 0.1)
				(type default)
			)
			(layer "F.SilkS")
		)
		(fp_line
			(start 15.072106 -0.882904)
			(end 15.0749 -0.898398)
			(stroke
				(width 0.1)
				(type default)
			)
			(layer "F.SilkS")
		)
		(fp_line
			(start 15.072106 -0.882904)
			(end 15.0749 -0.898398)
			(stroke
				(width 0.1)
				(type default)
			)
			(layer "F.SilkS")
		)
		(fp_line
			(start 15.077694 -5.171694)
			(end 14.621002 -4.733036)
			(stroke
				(width 0.1)
				(type default)
			)
			(layer "F.SilkS")
		)
		(fp_line
			(start 15.077694 -5.171694)
			(end 14.621002 -4.733036)
			(stroke
				(width 0.1)
				(type default)
			)
			(layer "F.SilkS")
		)
		(fp_line
			(start 15.077694 -5.171694)
			(end 15.01775 -5.171694)
			(stroke
				(width 0.1)
				(type default)
			)
			(layer "F.SilkS")
		)
		(fp_line
			(start 15.077694 -5.171694)
			(end 15.01775 -5.171694)
			(stroke
				(width 0.1)
				(type default)
			)
			(layer "F.SilkS")
		)
		(fp_line
			(start 15.087092 -0.96774)
			(end 15.0749 -0.898398)
			(stroke
				(width 0.1)
				(type default)
			)
			(layer "F.SilkS")
		)
		(fp_line
			(start 15.087092 -0.96774)
			(end 15.0749 -0.898398)
			(stroke
				(width 0.1)
				(type default)
			)
			(layer "F.SilkS")
		)
		(fp_line
			(start 15.09903 -1.036828)
			(end 15.087092 -0.96774)
			(stroke
				(width 0.1)
				(type default)
			)
			(layer "F.SilkS")
		)
		(fp_line
			(start 15.09903 -1.036828)
			(end 15.087092 -0.96774)
			(stroke
				(width 0.1)
				(type default)
			)
			(layer "F.SilkS")
		)
		(fp_line
			(start 15.111476 -1.106424)
			(end 15.09903 -1.036828)
			(stroke
				(width 0.1)
				(type default)
			)
			(layer "F.SilkS")
		)
		(fp_line
			(start 15.111476 -1.106424)
			(end 15.09903 -1.036828)
			(stroke
				(width 0.1)
				(type default)
			)
			(layer "F.SilkS")
		)
		(fp_line
			(start 15.123922 -1.17602)
			(end 15.111476 -1.106424)
			(stroke
				(width 0.1)
				(type default)
			)
			(layer "F.SilkS")
		)
		(fp_line
			(start 15.123922 -1.17602)
			(end 15.111476 -1.106424)
			(stroke
				(width 0.1)
				(type default)
			)
			(layer "F.SilkS")
		)
		(fp_line
			(start 15.13586 -1.245362)
			(end 15.123922 -1.17602)
			(stroke
				(width 0.1)
				(type default)
			)
			(layer "F.SilkS")
		)
		(fp_line
			(start 15.13586 -1.245362)
			(end 15.123922 -1.17602)
			(stroke
				(width 0.1)
				(type default)
			)
			(layer "F.SilkS")
		)
		(fp_line
			(start 15.137892 -5.171694)
			(end 14.608556 -4.663948)
			(stroke
				(width 0.1)
				(type default)
			)
			(layer "F.SilkS")
		)
		(fp_line
			(start 15.137892 -5.171694)
			(end 14.608556 -4.663948)
			(stroke
				(width 0.1)
				(type default)
			)
			(layer "F.SilkS")
		)
		(fp_line
			(start 15.137892 -5.171694)
			(end 15.077694 -5.171694)
			(stroke
				(width 0.1)
				(type default)
			)
			(layer "F.SilkS")
		)
		(fp_line
			(start 15.137892 -5.171694)
			(end 15.077694 -5.171694)
			(stroke
				(width 0.1)
				(type default)
			)
			(layer "F.SilkS")
		)
		(fp_line
			(start 15.148052 -1.314704)
			(end 15.13586 -1.245362)
			(stroke
				(width 0.1)
				(type default)
			)
			(layer "F.SilkS")
		)
		(fp_line
			(start 15.148052 -1.314704)
			(end 15.13586 -1.245362)
			(stroke
				(width 0.1)
				(type default)
			)
			(layer "F.SilkS")
		)
		(fp_line
			(start 15.160498 -1.384046)
			(end 15.148052 -1.314704)
			(stroke
				(width 0.1)
				(type default)
			)
			(layer "F.SilkS")
		)
		(fp_line
			(start 15.160498 -1.384046)
			(end 15.148052 -1.314704)
			(stroke
				(width 0.1)
				(type default)
			)
			(layer "F.SilkS")
		)
		(fp_line
			(start 15.17269 -1.453642)
			(end 15.160498 -1.384046)
			(stroke
				(width 0.1)
				(type default)
			)
			(layer "F.SilkS")
		)
		(fp_line
			(start 15.17269 -1.453642)
			(end 15.160498 -1.384046)
			(stroke
				(width 0.1)
				(type default)
			)
			(layer "F.SilkS")
		)
		(fp_line
			(start 15.184882 -1.522984)
			(end 15.17269 -1.453642)
			(stroke
				(width 0.1)
				(type default)
			)
			(layer "F.SilkS")
		)
		(fp_line
			(start 15.184882 -1.522984)
			(end 15.17269 -1.453642)
			(stroke
				(width 0.1)
				(type default)
			)
			(layer "F.SilkS")
		)
		(fp_line
			(start 15.184882 -1.522984)
			(end 15.19682 -1.592326)
			(stroke
				(width 0.1)
				(type default)
			)
			(layer "F.SilkS")
		)
		(fp_line
			(start 15.184882 -1.522984)
			(end 15.19682 -1.592326)
			(stroke
				(width 0.1)
				(type default)
			)
			(layer "F.SilkS")
		)
		(fp_line
			(start 15.19682 -1.592326)
			(end 15.209266 -1.661922)
			(stroke
				(width 0.1)
				(type default)
			)
			(layer "F.SilkS")
		)
		(fp_line
			(start 15.19682 -1.592326)
			(end 15.209266 -1.661922)
			(stroke
				(width 0.1)
				(type default)
			)
			(layer "F.SilkS")
		)
		(fp_line
			(start 15.198344 -5.171694)
			(end 14.596364 -4.594352)
			(stroke
				(width 0.1)
				(type default)
			)
			(layer "F.SilkS")
		)
		(fp_line
			(start 15.198344 -5.171694)
			(end 14.596364 -4.594352)
			(stroke
				(width 0.1)
				(type default)
			)
			(layer "F.SilkS")
		)
		(fp_line
			(start 15.198344 -5.171694)
			(end 15.137892 -5.171694)
			(stroke
				(width 0.1)
				(type default)
			)
			(layer "F.SilkS")
		)
		(fp_line
			(start 15.198344 -5.171694)
			(end 15.137892 -5.171694)
			(stroke
				(width 0.1)
				(type default)
			)
			(layer "F.SilkS")
		)
		(fp_line
			(start 15.209266 -1.661922)
			(end 15.221458 -1.731518)
			(stroke
				(width 0.1)
				(type default)
			)
			(layer "F.SilkS")
		)
		(fp_line
			(start 15.209266 -1.661922)
			(end 15.221458 -1.731518)
			(stroke
				(width 0.1)
				(type default)
			)
			(layer "F.SilkS")
		)
		(fp_line
			(start 15.221458 -1.731518)
			(end 15.233396 -1.800606)
			(stroke
				(width 0.1)
				(type default)
			)
			(layer "F.SilkS")
		)
		(fp_line
			(start 15.221458 -1.731518)
			(end 15.233396 -1.800606)
			(stroke
				(width 0.1)
				(type default)
			)
			(layer "F.SilkS")
		)
		(fp_line
			(start 15.233396 -1.800606)
			(end 15.245842 -1.869948)
			(stroke
				(width 0.1)
				(type default)
			)
			(layer "F.SilkS")
		)
		(fp_line
			(start 15.233396 -1.800606)
			(end 15.245842 -1.869948)
			(stroke
				(width 0.1)
				(type default)
			)
			(layer "F.SilkS")
		)
		(fp_line
			(start 15.245842 -1.869948)
			(end 15.258288 -1.939544)
			(stroke
				(width 0.1)
				(type default)
			)
			(layer "F.SilkS")
		)
		(fp_line
			(start 15.245842 -1.869948)
			(end 15.258288 -1.939544)
			(stroke
				(width 0.1)
				(type default)
			)
			(layer "F.SilkS")
		)
		(fp_line
			(start 15.258288 -5.171694)
			(end 14.584426 -4.52501)
			(stroke
				(width 0.1)
				(type default)
			)
			(layer "F.SilkS")
		)
		(fp_line
			(start 15.258288 -5.171694)
			(end 14.584426 -4.52501)
			(stroke
				(width 0.1)
				(type default)
			)
			(layer "F.SilkS")
		)
		(fp_line
			(start 15.258288 -5.171694)
			(end 15.198344 -5.171694)
			(stroke
				(width 0.1)
				(type default)
			)
			(layer "F.SilkS")
		)
		(fp_line
			(start 15.258288 -5.171694)
			(end 15.198344 -5.171694)
			(stroke
				(width 0.1)
				(type default)
			)
			(layer "F.SilkS")
		)
		(fp_line
			(start 15.258288 -1.939544)
			(end 15.270226 -2.00914)
			(stroke
				(width 0.1)
				(type default)
			)
			(layer "F.SilkS")
		)
		(fp_line
			(start 15.258288 -1.939544)
			(end 15.270226 -2.00914)
			(stroke
				(width 0.1)
				(type default)
			)
			(layer "F.SilkS")
		)
		(fp_line
			(start 15.270226 -2.00914)
			(end 15.282418 -2.078482)
			(stroke
				(width 0.1)
				(type default)
			)
			(layer "F.SilkS")
		)
		(fp_line
			(start 15.270226 -2.00914)
			(end 15.282418 -2.078482)
			(stroke
				(width 0.1)
				(type default)
			)
			(layer "F.SilkS")
		)
		(fp_line
			(start 15.282418 -2.078482)
			(end 15.294864 -2.147824)
			(stroke
				(width 0.1)
				(type default)
			)
			(layer "F.SilkS")
		)
		(fp_line
			(start 15.282418 -2.078482)
			(end 15.294864 -2.147824)
			(stroke
				(width 0.1)
				(type default)
			)
			(layer "F.SilkS")
		)
		(fp_line
			(start 15.294864 -2.147824)
			(end 15.307056 -2.21742)
			(stroke
				(width 0.1)
				(type default)
			)
			(layer "F.SilkS")
		)
		(fp_line
			(start 15.294864 -2.147824)
			(end 15.307056 -2.21742)
			(stroke
				(width 0.1)
				(type default)
			)
			(layer "F.SilkS")
		)
		(fp_line
			(start 15.307056 -2.21742)
			(end 15.319248 -2.286762)
			(stroke
				(width 0.1)
				(type default)
			)
			(layer "F.SilkS")
		)
		(fp_line
			(start 15.307056 -2.21742)
			(end 15.319248 -2.286762)
			(stroke
				(width 0.1)
				(type default)
			)
			(layer "F.SilkS")
		)
		(fp_line
			(start 15.318486 -5.171694)
			(end 14.57198 -4.455668)
			(stroke
				(width 0.1)
				(type default)
			)
			(layer "F.SilkS")
		)
		(fp_line
			(start 15.318486 -5.171694)
			(end 14.57198 -4.455668)
			(stroke
				(width 0.1)
				(type default)
			)
			(layer "F.SilkS")
		)
		(fp_line
			(start 15.318486 -5.171694)
			(end 15.258288 -5.171694)
			(stroke
				(width 0.1)
				(type default)
			)
			(layer "F.SilkS")
		)
		(fp_line
			(start 15.318486 -5.171694)
			(end 15.258288 -5.171694)
			(stroke
				(width 0.1)
				(type default)
			)
			(layer "F.SilkS")
		)
		(fp_line
			(start 15.319248 -2.286762)
			(end 15.331186 -2.356104)
			(stroke
				(width 0.1)
				(type default)
			)
			(layer "F.SilkS")
		)
		(fp_line
			(start 15.319248 -2.286762)
			(end 15.331186 -2.356104)
			(stroke
				(width 0.1)
				(type default)
			)
			(layer "F.SilkS")
		)
		(fp_line
			(start 15.331186 -2.356104)
			(end 15.343632 -2.425446)
			(stroke
				(width 0.1)
				(type default)
			)
			(layer "F.SilkS")
		)
		(fp_line
			(start 15.331186 -2.356104)
			(end 15.343632 -2.425446)
			(stroke
				(width 0.1)
				(type default)
			)
			(layer "F.SilkS")
		)
		(fp_line
			(start 15.343632 -2.425446)
			(end 15.355824 -2.495042)
			(stroke
				(width 0.1)
				(type default)
			)
			(layer "F.SilkS")
		)
		(fp_line
			(start 15.343632 -2.425446)
			(end 15.355824 -2.495042)
			(stroke
				(width 0.1)
				(type default)
			)
			(layer "F.SilkS")
		)
		(fp_line
			(start 15.355824 -2.495042)
			(end 15.367762 -2.564384)
			(stroke
				(width 0.1)
				(type default)
			)
			(layer "F.SilkS")
		)
		(fp_line
			(start 15.355824 -2.495042)
			(end 15.367762 -2.564384)
			(stroke
				(width 0.1)
				(type default)
			)
			(layer "F.SilkS")
		)
		(fp_line
			(start 15.367762 -2.564384)
			(end 15.380208 -2.633726)
			(stroke
				(width 0.1)
				(type default)
			)
			(layer "F.SilkS")
		)
		(fp_line
			(start 15.367762 -2.564384)
			(end 15.380208 -2.633726)
			(stroke
				(width 0.1)
				(type default)
			)
			(layer "F.SilkS")
		)
		(fp_line
			(start 15.378938 -5.171694)
			(end 14.560042 -4.386326)
			(stroke
				(width 0.1)
				(type default)
			)
			(layer "F.SilkS")
		)
		(fp_line
			(start 15.378938 -5.171694)
			(end 14.560042 -4.386326)
			(stroke
				(width 0.1)
				(type default)
			)
			(layer "F.SilkS")
		)
		(fp_line
			(start 15.378938 -5.171694)
			(end 15.318486 -5.171694)
			(stroke
				(width 0.1)
				(type default)
			)
			(layer "F.SilkS")
		)
		(fp_line
			(start 15.378938 -5.171694)
			(end 15.318486 -5.171694)
			(stroke
				(width 0.1)
				(type default)
			)
			(layer "F.SilkS")
		)
		(fp_line
			(start 15.380208 -2.633726)
			(end 15.392654 -2.703322)
			(stroke
				(width 0.1)
				(type default)
			)
			(layer "F.SilkS")
		)
		(fp_line
			(start 15.380208 -2.633726)
			(end 15.392654 -2.703322)
			(stroke
				(width 0.1)
				(type default)
			)
			(layer "F.SilkS")
		)
		(fp_line
			(start 15.392654 -2.703322)
			(end 15.404592 -2.772664)
			(stroke
				(width 0.1)
				(type default)
			)
			(layer "F.SilkS")
		)
		(fp_line
			(start 15.392654 -2.703322)
			(end 15.404592 -2.772664)
			(stroke
				(width 0.1)
				(type default)
			)
			(layer "F.SilkS")
		)
		(fp_line
			(start 15.404592 -2.772664)
			(end 15.416784 -2.84226)
			(stroke
				(width 0.1)
				(type default)
			)
			(layer "F.SilkS")
		)
		(fp_line
			(start 15.404592 -2.772664)
			(end 15.416784 -2.84226)
			(stroke
				(width 0.1)
				(type default)
			)
			(layer "F.SilkS")
		)
		(fp_line
			(start 15.42923 -2.911602)
			(end 15.416784 -2.84226)
			(stroke
				(width 0.1)
				(type default)
			)
			(layer "F.SilkS")
		)
		(fp_line
			(start 15.42923 -2.911602)
			(end 15.416784 -2.84226)
			(stroke
				(width 0.1)
				(type default)
			)
			(layer "F.SilkS")
		)
		(fp_line
			(start 15.438882 -5.171694)
			(end 14.54785 -4.316984)
			(stroke
				(width 0.1)
				(type default)
			)
			(layer "F.SilkS")
		)
		(fp_line
			(start 15.438882 -5.171694)
			(end 14.54785 -4.316984)
			(stroke
				(width 0.1)
				(type default)
			)
			(layer "F.SilkS")
		)
		(fp_line
			(start 15.438882 -5.171694)
			(end 15.378938 -5.171694)
			(stroke
				(width 0.1)
				(type default)
			)
			(layer "F.SilkS")
		)
		(fp_line
			(start 15.438882 -5.171694)
			(end 15.378938 -5.171694)
			(stroke
				(width 0.1)
				(type default)
			)
			(layer "F.SilkS")
		)
		(fp_line
			(start 15.441168 -2.980944)
			(end 14.084808 -1.679702)
			(stroke
				(width 0.1)
				(type default)
			)
			(layer "F.SilkS")
		)
		(fp_line
			(start 15.441168 -2.980944)
			(end 14.084808 -1.679702)
			(stroke
				(width 0.1)
				(type default)
			)
			(layer "F.SilkS")
		)
		(fp_line
			(start 15.441168 -2.980944)
			(end 15.42923 -2.911602)
			(stroke
				(width 0.1)
				(type default)
			)
			(layer "F.SilkS")
		)
		(fp_line
			(start 15.441168 -2.980944)
			(end 15.42923 -2.911602)
			(stroke
				(width 0.1)
				(type default)
			)
			(layer "F.SilkS")
		)
		(fp_line
			(start 15.45336 -3.050286)
			(end 14.097254 -1.749044)
			(stroke
				(width 0.1)
				(type default)
			)
			(layer "F.SilkS")
		)
		(fp_line
			(start 15.45336 -3.050286)
			(end 14.097254 -1.749044)
			(stroke
				(width 0.1)
				(type default)
			)
			(layer "F.SilkS")
		)
		(fp_line
			(start 15.45336 -3.050286)
			(end 15.441168 -2.980944)
			(stroke
				(width 0.1)
				(type default)
			)
			(layer "F.SilkS")
		)
		(fp_line
			(start 15.45336 -3.050286)
			(end 15.441168 -2.980944)
			(stroke
				(width 0.1)
				(type default)
			)
			(layer "F.SilkS")
		)
		(fp_line
			(start 15.465552 -3.119882)
			(end 14.109192 -1.81864)
			(stroke
				(width 0.1)
				(type default)
			)
			(layer "F.SilkS")
		)
		(fp_line
			(start 15.465552 -3.119882)
			(end 14.109192 -1.81864)
			(stroke
				(width 0.1)
				(type default)
			)
			(layer "F.SilkS")
		)
		(fp_line
			(start 15.465552 -3.119882)
			(end 15.45336 -3.050286)
			(stroke
				(width 0.1)
				(type default)
			)
			(layer "F.SilkS")
		)
		(fp_line
			(start 15.465552 -3.119882)
			(end 15.45336 -3.050286)
			(stroke
				(width 0.1)
				(type default)
			)
			(layer "F.SilkS")
		)
		(fp_line
			(start 15.477998 -3.189224)
			(end 14.121384 -1.887982)
			(stroke
				(width 0.1)
				(type default)
			)
			(layer "F.SilkS")
		)
		(fp_line
			(start 15.477998 -3.189224)
			(end 14.121384 -1.887982)
			(stroke
				(width 0.1)
				(type default)
			)
			(layer "F.SilkS")
		)
		(fp_line
			(start 15.477998 -3.189224)
			(end 15.465552 -3.119882)
			(stroke
				(width 0.1)
				(type default)
			)
			(layer "F.SilkS")
		)
		(fp_line
			(start 15.477998 -3.189224)
			(end 15.465552 -3.119882)
			(stroke
				(width 0.1)
				(type default)
			)
			(layer "F.SilkS")
		)
		(fp_line
			(start 15.491714 -3.260344)
			(end 14.13383 -1.957324)
			(stroke
				(width 0.1)
				(type default)
			)
			(layer "F.SilkS")
		)
		(fp_line
			(start 15.491714 -3.260344)
			(end 14.13383 -1.957324)
			(stroke
				(width 0.1)
				(type default)
			)
			(layer "F.SilkS")
		)
		(fp_line
			(start 15.49908 -5.171694)
			(end 14.535404 -4.247388)
			(stroke
				(width 0.1)
				(type default)
			)
			(layer "F.SilkS")
		)
		(fp_line
			(start 15.49908 -5.171694)
			(end 14.535404 -4.247388)
			(stroke
				(width 0.1)
				(type default)
			)
			(layer "F.SilkS")
		)
		(fp_line
			(start 15.49908 -5.171694)
			(end 15.438882 -5.171694)
			(stroke
				(width 0.1)
				(type default)
			)
			(layer "F.SilkS")
		)
		(fp_line
			(start 15.49908 -5.171694)
			(end 15.438882 -5.171694)
			(stroke
				(width 0.1)
				(type default)
			)
			(layer "F.SilkS")
		)
		(fp_line
			(start 15.508478 -3.334004)
			(end 14.145768 -2.02692)
			(stroke
				(width 0.1)
				(type default)
			)
			(layer "F.SilkS")
		)
		(fp_line
			(start 15.508478 -3.334004)
			(end 14.145768 -2.02692)
			(stroke
				(width 0.1)
				(type default)
			)
			(layer "F.SilkS")
		)
		(fp_line
			(start 15.524988 -3.40741)
			(end 14.15796 -2.096262)
			(stroke
				(width 0.1)
				(type default)
			)
			(layer "F.SilkS")
		)
		(fp_line
			(start 15.524988 -3.40741)
			(end 14.15796 -2.096262)
			(stroke
				(width 0.1)
				(type default)
			)
			(layer "F.SilkS")
		)
		(fp_line
			(start 15.54099 -3.480562)
			(end 14.170406 -2.165604)
			(stroke
				(width 0.1)
				(type default)
			)
			(layer "F.SilkS")
		)
		(fp_line
			(start 15.54099 -3.480562)
			(end 14.170406 -2.165604)
			(stroke
				(width 0.1)
				(type default)
			)
			(layer "F.SilkS")
		)
		(fp_line
			(start 15.559278 -5.171694)
			(end 14.523466 -4.178046)
			(stroke
				(width 0.1)
				(type default)
			)
			(layer "F.SilkS")
		)
		(fp_line
			(start 15.559278 -5.171694)
			(end 14.523466 -4.178046)
			(stroke
				(width 0.1)
				(type default)
			)
			(layer "F.SilkS")
		)
		(fp_line
			(start 15.559278 -5.171694)
			(end 15.49908 -5.171694)
			(stroke
				(width 0.1)
				(type default)
			)
			(layer "F.SilkS")
		)
		(fp_line
			(start 15.559278 -5.171694)
			(end 15.49908 -5.171694)
			(stroke
				(width 0.1)
				(type default)
			)
			(layer "F.SilkS")
		)
		(fp_line
			(start 15.570962 -3.566922)
			(end 14.182344 -2.234946)
			(stroke
				(width 0.1)
				(type default)
			)
			(layer "F.SilkS")
		)
		(fp_line
			(start 15.570962 -3.566922)
			(end 14.182344 -2.234946)
			(stroke
				(width 0.1)
				(type default)
			)
			(layer "F.SilkS")
		)
		(fp_line
			(start 15.601442 -3.654044)
			(end 14.194282 -2.304288)
			(stroke
				(width 0.1)
				(type default)
			)
			(layer "F.SilkS")
		)
		(fp_line
			(start 15.601442 -3.654044)
			(end 14.194282 -2.304288)
			(stroke
				(width 0.1)
				(type default)
			)
			(layer "F.SilkS")
		)
		(fp_line
			(start 15.619222 -5.171694)
			(end 14.511274 -4.108704)
			(stroke
				(width 0.1)
				(type default)
			)
			(layer "F.SilkS")
		)
		(fp_line
			(start 15.619222 -5.171694)
			(end 14.511274 -4.108704)
			(stroke
				(width 0.1)
				(type default)
			)
			(layer "F.SilkS")
		)
		(fp_line
			(start 15.619222 -5.171694)
			(end 15.559278 -5.171694)
			(stroke
				(width 0.1)
				(type default)
			)
			(layer "F.SilkS")
		)
		(fp_line
			(start 15.619222 -5.171694)
			(end 15.559278 -5.171694)
			(stroke
				(width 0.1)
				(type default)
			)
			(layer "F.SilkS")
		)
		(fp_line
			(start 15.649702 -3.75793)
			(end 14.206728 -2.373884)
			(stroke
				(width 0.1)
				(type default)
			)
			(layer "F.SilkS")
		)
		(fp_line
			(start 15.649702 -3.75793)
			(end 14.206728 -2.373884)
			(stroke
				(width 0.1)
				(type default)
			)
			(layer "F.SilkS")
		)
		(fp_line
			(start 15.679166 -5.171694)
			(end 14.498828 -4.039362)
			(stroke
				(width 0.1)
				(type default)
			)
			(layer "F.SilkS")
		)
		(fp_line
			(start 15.679166 -5.171694)
			(end 14.498828 -4.039362)
			(stroke
				(width 0.1)
				(type default)
			)
			(layer "F.SilkS")
		)
		(fp_line
			(start 15.679166 -5.171694)
			(end 15.619222 -5.171694)
			(stroke
				(width 0.1)
				(type default)
			)
			(layer "F.SilkS")
		)
		(fp_line
			(start 15.679166 -5.171694)
			(end 15.619222 -5.171694)
			(stroke
				(width 0.1)
				(type default)
			)
			(layer "F.SilkS")
		)
		(fp_line
			(start 15.729458 -3.892296)
			(end 14.21892 -2.443226)
			(stroke
				(width 0.1)
				(type default)
			)
			(layer "F.SilkS")
		)
		(fp_line
			(start 15.729458 -3.892296)
			(end 14.21892 -2.443226)
			(stroke
				(width 0.1)
				(type default)
			)
			(layer "F.SilkS")
		)
		(fp_line
			(start 15.739618 -5.171694)
			(end 14.486636 -3.969766)
			(stroke
				(width 0.1)
				(type default)
			)
			(layer "F.SilkS")
		)
		(fp_line
			(start 15.739618 -5.171694)
			(end 14.486636 -3.969766)
			(stroke
				(width 0.1)
				(type default)
			)
			(layer "F.SilkS")
		)
		(fp_line
			(start 15.739618 -5.171694)
			(end 15.679166 -5.171694)
			(stroke
				(width 0.1)
				(type default)
			)
			(layer "F.SilkS")
		)
		(fp_line
			(start 15.739618 -5.171694)
			(end 15.679166 -5.171694)
			(stroke
				(width 0.1)
				(type default)
			)
			(layer "F.SilkS")
		)
		(fp_line
			(start 15.781274 -4.923028)
			(end 14.42593 -3.622802)
			(stroke
				(width 0.1)
				(type default)
			)
			(layer "F.SilkS")
		)
		(fp_line
			(start 15.781274 -4.923028)
			(end 14.42593 -3.622802)
			(stroke
				(width 0.1)
				(type default)
			)
			(layer "F.SilkS")
		)
		(fp_line
			(start 15.781274 -4.923028)
			(end 15.79372 -4.992624)
			(stroke
				(width 0.1)
				(type default)
			)
			(layer "F.SilkS")
		)
		(fp_line
			(start 15.781274 -4.923028)
			(end 15.79372 -4.992624)
			(stroke
				(width 0.1)
				(type default)
			)
			(layer "F.SilkS")
		)
		(fp_line
			(start 15.79372 -4.992624)
			(end 14.438376 -3.692398)
			(stroke
				(width 0.1)
				(type default)
			)
			(layer "F.SilkS")
		)
		(fp_line
			(start 15.79372 -4.992624)
			(end 14.438376 -3.692398)
			(stroke
				(width 0.1)
				(type default)
			)
			(layer "F.SilkS")
		)
		(fp_line
			(start 15.79372 -4.992624)
			(end 15.805658 -5.061966)
			(stroke
				(width 0.1)
				(type default)
			)
			(layer "F.SilkS")
		)
		(fp_line
			(start 15.79372 -4.992624)
			(end 15.805658 -5.061966)
			(stroke
				(width 0.1)
				(type default)
			)
			(layer "F.SilkS")
		)
		(fp_line
			(start 15.799816 -5.171694)
			(end 14.474952 -3.900424)
			(stroke
				(width 0.1)
				(type default)
			)
			(layer "F.SilkS")
		)
		(fp_line
			(start 15.799816 -5.171694)
			(end 14.474952 -3.900424)
			(stroke
				(width 0.1)
				(type default)
			)
			(layer "F.SilkS")
		)
		(fp_line
			(start 15.799816 -5.171694)
			(end 15.739618 -5.171694)
			(stroke
				(width 0.1)
				(type default)
			)
			(layer "F.SilkS")
		)
		(fp_line
			(start 15.799816 -5.171694)
			(end 15.739618 -5.171694)
			(stroke
				(width 0.1)
				(type default)
			)
			(layer "F.SilkS")
		)
		(fp_line
			(start 15.805658 -5.061966)
			(end 14.45006 -3.76174)
			(stroke
				(width 0.1)
				(type default)
			)
			(layer "F.SilkS")
		)
		(fp_line
			(start 15.805658 -5.061966)
			(end 14.45006 -3.76174)
			(stroke
				(width 0.1)
				(type default)
			)
			(layer "F.SilkS")
		)
		(fp_line
			(start 15.805658 -5.061966)
			(end 15.81785 -5.131308)
			(stroke
				(width 0.1)
				(type default)
			)
			(layer "F.SilkS")
		)
		(fp_line
			(start 15.805658 -5.061966)
			(end 15.81785 -5.131308)
			(stroke
				(width 0.1)
				(type default)
			)
			(layer "F.SilkS")
		)
		(fp_line
			(start 15.81785 -5.131308)
			(end 14.462506 -3.831082)
			(stroke
				(width 0.1)
				(type default)
			)
			(layer "F.SilkS")
		)
		(fp_line
			(start 15.81785 -5.131308)
			(end 14.462506 -3.831082)
			(stroke
				(width 0.1)
				(type default)
			)
			(layer "F.SilkS")
		)
		(fp_line
			(start 15.81785 -5.131308)
			(end 15.824962 -5.171694)
			(stroke
				(width 0.1)
				(type default)
			)
			(layer "F.SilkS")
		)
		(fp_line
			(start 15.81785 -5.131308)
			(end 15.824962 -5.171694)
			(stroke
				(width 0.1)
				(type default)
			)
			(layer "F.SilkS")
		)
		(fp_line
			(start 15.824962 -5.171694)
			(end 15.799816 -5.171694)
			(stroke
				(width 0.1)
				(type default)
			)
			(layer "F.SilkS")
		)
		(fp_line
			(start 15.824962 -5.171694)
			(end 15.799816 -5.171694)
			(stroke
				(width 0.1)
				(type default)
			)
			(layer "F.SilkS")
		)
		(fp_line
			(start 15.884652 -4.96443)
			(end 14.413484 -3.55346)
			(stroke
				(width 0.1)
				(type default)
			)
			(layer "F.SilkS")
		)
		(fp_line
			(start 15.884652 -4.96443)
			(end 14.413484 -3.55346)
			(stroke
				(width 0.1)
				(type default)
			)
			(layer "F.SilkS")
		)
		(fp_line
			(start 16.049498 -5.065268)
			(end 14.401546 -3.484118)
			(stroke
				(width 0.1)
				(type default)
			)
			(layer "F.SilkS")
		)
		(fp_line
			(start 16.049498 -5.065268)
			(end 14.401546 -3.484118)
			(stroke
				(width 0.1)
				(type default)
			)
			(layer "F.SilkS")
		)
		(fp_line
			(start 16.169132 -5.12191)
			(end 14.389354 -3.414776)
			(stroke
				(width 0.1)
				(type default)
			)
			(layer "F.SilkS")
		)
		(fp_line
			(start 16.169132 -5.12191)
			(end 14.389354 -3.414776)
			(stroke
				(width 0.1)
				(type default)
			)
			(layer "F.SilkS")
		)
		(fp_line
			(start 16.270986 -5.161788)
			(end 14.376908 -3.34518)
			(stroke
				(width 0.1)
				(type default)
			)
			(layer "F.SilkS")
		)
		(fp_line
			(start 16.270986 -5.161788)
			(end 14.376908 -3.34518)
			(stroke
				(width 0.1)
				(type default)
			)
			(layer "F.SilkS")
		)
		(fp_line
			(start 16.355568 -5.18541)
			(end 14.36497 -3.275838)
			(stroke
				(width 0.1)
				(type default)
			)
			(layer "F.SilkS")
		)
		(fp_line
			(start 16.355568 -5.18541)
			(end 14.36497 -3.275838)
			(stroke
				(width 0.1)
				(type default)
			)
			(layer "F.SilkS")
		)
		(fp_line
			(start 16.439896 -5.208778)
			(end 14.352778 -3.206496)
			(stroke
				(width 0.1)
				(type default)
			)
			(layer "F.SilkS")
		)
		(fp_line
			(start 16.439896 -5.208778)
			(end 14.352778 -3.206496)
			(stroke
				(width 0.1)
				(type default)
			)
			(layer "F.SilkS")
		)
		(fp_line
			(start 16.52397 -5.231638)
			(end 14.340586 -3.137154)
			(stroke
				(width 0.1)
				(type default)
			)
			(layer "F.SilkS")
		)
		(fp_line
			(start 16.52397 -5.231638)
			(end 14.340586 -3.137154)
			(stroke
				(width 0.1)
				(type default)
			)
			(layer "F.SilkS")
		)
		(fp_line
			(start 16.533622 -0.882904)
			(end 16.562832 -0.882904)
			(stroke
				(width 0.1)
				(type default)
			)
			(layer "F.SilkS")
		)
		(fp_line
			(start 16.533622 -0.882904)
			(end 16.562832 -0.882904)
			(stroke
				(width 0.1)
				(type default)
			)
			(layer "F.SilkS")
		)
		(fp_line
			(start 16.539718 -0.918464)
			(end 16.533622 -0.882904)
			(stroke
				(width 0.1)
				(type default)
			)
			(layer "F.SilkS")
		)
		(fp_line
			(start 16.539718 -0.918464)
			(end 16.533622 -0.882904)
			(stroke
				(width 0.1)
				(type default)
			)
			(layer "F.SilkS")
		)
		(fp_line
			(start 16.539718 -0.918464)
			(end 17.896586 -2.21996)
			(stroke
				(width 0.1)
				(type default)
			)
			(layer "F.SilkS")
		)
		(fp_line
			(start 16.539718 -0.918464)
			(end 17.896586 -2.21996)
			(stroke
				(width 0.1)
				(type default)
			)
			(layer "F.SilkS")
		)
		(fp_line
			(start 16.552164 -0.987806)
			(end 16.539718 -0.918464)
			(stroke
				(width 0.1)
				(type default)
			)
			(layer "F.SilkS")
		)
		(fp_line
			(start 16.552164 -0.987806)
			(end 16.539718 -0.918464)
			(stroke
				(width 0.1)
				(type default)
			)
			(layer "F.SilkS")
		)
		(fp_line
			(start 16.552164 -0.987806)
			(end 17.908524 -2.289048)
			(stroke
				(width 0.1)
				(type default)
			)
			(layer "F.SilkS")
		)
		(fp_line
			(start 16.552164 -0.987806)
			(end 17.908524 -2.289048)
			(stroke
				(width 0.1)
				(type default)
			)
			(layer "F.SilkS")
		)
		(fp_line
			(start 16.562832 -0.882904)
			(end 16.623284 -0.882904)
			(stroke
				(width 0.1)
				(type default)
			)
			(layer "F.SilkS")
		)
		(fp_line
			(start 16.562832 -0.882904)
			(end 16.623284 -0.882904)
			(stroke
				(width 0.1)
				(type default)
			)
			(layer "F.SilkS")
		)
		(fp_line
			(start 16.562832 -0.882904)
			(end 17.88414 -2.150364)
			(stroke
				(width 0.1)
				(type default)
			)
			(layer "F.SilkS")
		)
		(fp_line
			(start 16.562832 -0.882904)
			(end 17.88414 -2.150364)
			(stroke
				(width 0.1)
				(type default)
			)
			(layer "F.SilkS")
		)
		(fp_line
			(start 16.564356 -1.057148)
			(end 16.552164 -0.987806)
			(stroke
				(width 0.1)
				(type default)
			)
			(layer "F.SilkS")
		)
		(fp_line
			(start 16.564356 -1.057148)
			(end 16.552164 -0.987806)
			(stroke
				(width 0.1)
				(type default)
			)
			(layer "F.SilkS")
		)
		(fp_line
			(start 16.564356 -1.057148)
			(end 17.920716 -2.35839)
			(stroke
				(width 0.1)
				(type default)
			)
			(layer "F.SilkS")
		)
		(fp_line
			(start 16.564356 -1.057148)
			(end 17.920716 -2.35839)
			(stroke
				(width 0.1)
				(type default)
			)
			(layer "F.SilkS")
		)
		(fp_line
			(start 16.576294 -1.126744)
			(end 16.564356 -1.057148)
			(stroke
				(width 0.1)
				(type default)
			)
			(layer "F.SilkS")
		)
		(fp_line
			(start 16.576294 -1.126744)
			(end 16.564356 -1.057148)
			(stroke
				(width 0.1)
				(type default)
			)
			(layer "F.SilkS")
		)
		(fp_line
			(start 16.576294 -1.126744)
			(end 17.932908 -2.427732)
			(stroke
				(width 0.1)
				(type default)
			)
			(layer "F.SilkS")
		)
		(fp_line
			(start 16.576294 -1.126744)
			(end 17.932908 -2.427732)
			(stroke
				(width 0.1)
				(type default)
			)
			(layer "F.SilkS")
		)
		(fp_line
			(start 16.58874 -1.196086)
			(end 16.576294 -1.126744)
			(stroke
				(width 0.1)
				(type default)
			)
			(layer "F.SilkS")
		)
		(fp_line
			(start 16.58874 -1.196086)
			(end 16.576294 -1.126744)
			(stroke
				(width 0.1)
				(type default)
			)
			(layer "F.SilkS")
		)
		(fp_line
			(start 16.58874 -1.196086)
			(end 17.9451 -2.497328)
			(stroke
				(width 0.1)
				(type default)
			)
			(layer "F.SilkS")
		)
		(fp_line
			(start 16.58874 -1.196086)
			(end 17.9451 -2.497328)
			(stroke
				(width 0.1)
				(type default)
			)
			(layer "F.SilkS")
		)
		(fp_line
			(start 16.590772 -5.237734)
			(end 14.328394 -3.067558)
			(stroke
				(width 0.1)
				(type default)
			)
			(layer "F.SilkS")
		)
		(fp_line
			(start 16.590772 -5.237734)
			(end 14.328394 -3.067558)
			(stroke
				(width 0.1)
				(type default)
			)
			(layer "F.SilkS")
		)
		(fp_line
			(start 16.600932 -1.265428)
			(end 16.58874 -1.196086)
			(stroke
				(width 0.1)
				(type default)
			)
			(layer "F.SilkS")
		)
		(fp_line
			(start 16.600932 -1.265428)
			(end 16.58874 -1.196086)
			(stroke
				(width 0.1)
				(type default)
			)
			(layer "F.SilkS")
		)
		(fp_line
			(start 16.600932 -1.265428)
			(end 17.957038 -2.56667)
			(stroke
				(width 0.1)
				(type default)
			)
			(layer "F.SilkS")
		)
		(fp_line
			(start 16.600932 -1.265428)
			(end 17.957038 -2.56667)
			(stroke
				(width 0.1)
				(type default)
			)
			(layer "F.SilkS")
		)
		(fp_line
			(start 16.61287 -1.33477)
			(end 16.600932 -1.265428)
			(stroke
				(width 0.1)
				(type default)
			)
			(layer "F.SilkS")
		)
		(fp_line
			(start 16.61287 -1.33477)
			(end 16.600932 -1.265428)
			(stroke
				(width 0.1)
				(type default)
			)
			(layer "F.SilkS")
		)
		(fp_line
			(start 16.61287 -1.33477)
			(end 17.969484 -2.636012)
			(stroke
				(width 0.1)
				(type default)
			)
			(layer "F.SilkS")
		)
		(fp_line
			(start 16.61287 -1.33477)
			(end 17.969484 -2.636012)
			(stroke
				(width 0.1)
				(type default)
			)
			(layer "F.SilkS")
		)
		(fp_line
			(start 16.623284 -0.882904)
			(end 16.683228 -0.882904)
			(stroke
				(width 0.1)
				(type default)
			)
			(layer "F.SilkS")
		)
		(fp_line
			(start 16.623284 -0.882904)
			(end 16.683228 -0.882904)
			(stroke
				(width 0.1)
				(type default)
			)
			(layer "F.SilkS")
		)
		(fp_line
			(start 16.623284 -0.882904)
			(end 17.871948 -2.081022)
			(stroke
				(width 0.1)
				(type default)
			)
			(layer "F.SilkS")
		)
		(fp_line
			(start 16.623284 -0.882904)
			(end 17.871948 -2.081022)
			(stroke
				(width 0.1)
				(type default)
			)
			(layer "F.SilkS")
		)
		(fp_line
			(start 16.625316 -1.404366)
			(end 16.61287 -1.33477)
			(stroke
				(width 0.1)
				(type default)
			)
			(layer "F.SilkS")
		)
		(fp_line
			(start 16.625316 -1.404366)
			(end 16.61287 -1.33477)
			(stroke
				(width 0.1)
				(type default)
			)
			(layer "F.SilkS")
		)
		(fp_line
			(start 16.625316 -1.404366)
			(end 17.981676 -2.705608)
			(stroke
				(width 0.1)
				(type default)
			)
			(layer "F.SilkS")
		)
		(fp_line
			(start 16.625316 -1.404366)
			(end 17.981676 -2.705608)
			(stroke
				(width 0.1)
				(type default)
			)
			(layer "F.SilkS")
		)
		(fp_line
			(start 16.637762 -1.473962)
			(end 16.625316 -1.404366)
			(stroke
				(width 0.1)
				(type default)
			)
			(layer "F.SilkS")
		)
		(fp_line
			(start 16.637762 -1.473962)
			(end 16.625316 -1.404366)
			(stroke
				(width 0.1)
				(type default)
			)
			(layer "F.SilkS")
		)
		(fp_line
			(start 16.637762 -1.473962)
			(end 17.993614 -2.77495)
			(stroke
				(width 0.1)
				(type default)
			)
			(layer "F.SilkS")
		)
		(fp_line
			(start 16.637762 -1.473962)
			(end 17.993614 -2.77495)
			(stroke
				(width 0.1)
				(type default)
			)
			(layer "F.SilkS")
		)
		(fp_line
			(start 16.6497 -1.54305)
			(end 16.637762 -1.473962)
			(stroke
				(width 0.1)
				(type default)
			)
			(layer "F.SilkS")
		)
		(fp_line
			(start 16.6497 -1.54305)
			(end 16.637762 -1.473962)
			(stroke
				(width 0.1)
				(type default)
			)
			(layer "F.SilkS")
		)
		(fp_line
			(start 16.6497 -1.54305)
			(end 18.00606 -2.844292)
			(stroke
				(width 0.1)
				(type default)
			)
			(layer "F.SilkS")
		)
		(fp_line
			(start 16.6497 -1.54305)
			(end 18.00606 -2.844292)
			(stroke
				(width 0.1)
				(type default)
			)
			(layer "F.SilkS")
		)
		(fp_line
			(start 16.657066 -5.24383)
			(end 14.316456 -2.998216)
			(stroke
				(width 0.1)
				(type default)
			)
			(layer "F.SilkS")
		)
		(fp_line
			(start 16.657066 -5.24383)
			(end 14.316456 -2.998216)
			(stroke
				(width 0.1)
				(type default)
			)
			(layer "F.SilkS")
		)
		(fp_line
			(start 16.661892 -1.612646)
			(end 16.6497 -1.54305)
			(stroke
				(width 0.1)
				(type default)
			)
			(layer "F.SilkS")
		)
		(fp_line
			(start 16.661892 -1.612646)
			(end 16.6497 -1.54305)
			(stroke
				(width 0.1)
				(type default)
			)
			(layer "F.SilkS")
		)
		(fp_line
			(start 16.661892 -1.612646)
			(end 18.017998 -2.913634)
			(stroke
				(width 0.1)
				(type default)
			)
			(layer "F.SilkS")
		)
		(fp_line
			(start 16.661892 -1.612646)
			(end 18.017998 -2.913634)
			(stroke
				(width 0.1)
				(type default)
			)
			(layer "F.SilkS")
		)
		(fp_line
			(start 16.674084 -1.681988)
			(end 16.661892 -1.612646)
			(stroke
				(width 0.1)
				(type default)
			)
			(layer "F.SilkS")
		)
		(fp_line
			(start 16.674084 -1.681988)
			(end 16.661892 -1.612646)
			(stroke
				(width 0.1)
				(type default)
			)
			(layer "F.SilkS")
		)
		(fp_line
			(start 16.674084 -1.681988)
			(end 18.03019 -2.982976)
			(stroke
				(width 0.1)
				(type default)
			)
			(layer "F.SilkS")
		)
		(fp_line
			(start 16.674084 -1.681988)
			(end 18.03019 -2.982976)
			(stroke
				(width 0.1)
				(type default)
			)
			(layer "F.SilkS")
		)
		(fp_line
			(start 16.683228 -0.882904)
			(end 16.743426 -0.882904)
			(stroke
				(width 0.1)
				(type default)
			)
			(layer "F.SilkS")
		)
		(fp_line
			(start 16.683228 -0.882904)
			(end 16.743426 -0.882904)
			(stroke
				(width 0.1)
				(type default)
			)
			(layer "F.SilkS")
		)
		(fp_line
			(start 16.683228 -0.882904)
			(end 17.86001 -2.011426)
			(stroke
				(width 0.1)
				(type default)
			)
			(layer "F.SilkS")
		)
		(fp_line
			(start 16.683228 -0.882904)
			(end 17.86001 -2.011426)
			(stroke
				(width 0.1)
				(type default)
			)
			(layer "F.SilkS")
		)
		(fp_line
			(start 16.686276 -1.751584)
			(end 16.674084 -1.681988)
			(stroke
				(width 0.1)
				(type default)
			)
			(layer "F.SilkS")
		)
		(fp_line
			(start 16.686276 -1.751584)
			(end 16.674084 -1.681988)
			(stroke
				(width 0.1)
				(type default)
			)
			(layer "F.SilkS")
		)
		(fp_line
			(start 16.686276 -1.751584)
			(end 18.042636 -3.052572)
			(stroke
				(width 0.1)
				(type default)
			)
			(layer "F.SilkS")
		)
		(fp_line
			(start 16.686276 -1.751584)
			(end 18.042636 -3.052572)
			(stroke
				(width 0.1)
				(type default)
			)
			(layer "F.SilkS")
		)
		(fp_line
			(start 16.698214 -1.820926)
			(end 16.686276 -1.751584)
			(stroke
				(width 0.1)
				(type default)
			)
			(layer "F.SilkS")
		)
		(fp_line
			(start 16.698214 -1.820926)
			(end 16.686276 -1.751584)
			(stroke
				(width 0.1)
				(type default)
			)
			(layer "F.SilkS")
		)
		(fp_line
			(start 16.698214 -1.820926)
			(end 18.054574 -3.121914)
			(stroke
				(width 0.1)
				(type default)
			)
			(layer "F.SilkS")
		)
		(fp_line
			(start 16.698214 -1.820926)
			(end 18.054574 -3.121914)
			(stroke
				(width 0.1)
				(type default)
			)
			(layer "F.SilkS")
		)
		(fp_line
			(start 16.71066 -1.890268)
			(end 16.698214 -1.820926)
			(stroke
				(width 0.1)
				(type default)
			)
			(layer "F.SilkS")
		)
		(fp_line
			(start 16.71066 -1.890268)
			(end 16.698214 -1.820926)
			(stroke
				(width 0.1)
				(type default)
			)
			(layer "F.SilkS")
		)
		(fp_line
			(start 16.71066 -1.890268)
			(end 18.066766 -3.191002)
			(stroke
				(width 0.1)
				(type default)
			)
			(layer "F.SilkS")
		)
		(fp_line
			(start 16.71066 -1.890268)
			(end 18.066766 -3.191002)
			(stroke
				(width 0.1)
				(type default)
			)
			(layer "F.SilkS")
		)
		(fp_line
			(start 16.723106 -1.95961)
			(end 16.71066 -1.890268)
			(stroke
				(width 0.1)
				(type default)
			)
			(layer "F.SilkS")
		)
		(fp_line
			(start 16.723106 -1.95961)
			(end 16.71066 -1.890268)
			(stroke
				(width 0.1)
				(type default)
			)
			(layer "F.SilkS")
		)
		(fp_line
			(start 16.723106 -1.95961)
			(end 18.079212 -3.260598)
			(stroke
				(width 0.1)
				(type default)
			)
			(layer "F.SilkS")
		)
		(fp_line
			(start 16.723106 -1.95961)
			(end 18.079212 -3.260598)
			(stroke
				(width 0.1)
				(type default)
			)
			(layer "F.SilkS")
		)
		(fp_line
			(start 16.723868 -5.25018)
			(end 14.30401 -2.928874)
			(stroke
				(width 0.1)
				(type default)
			)
			(layer "F.SilkS")
		)
		(fp_line
			(start 16.723868 -5.25018)
			(end 14.30401 -2.928874)
			(stroke
				(width 0.1)
				(type default)
			)
			(layer "F.SilkS")
		)
		(fp_line
			(start 16.735044 -2.028952)
			(end 16.723106 -1.95961)
			(stroke
				(width 0.1)
				(type default)
			)
			(layer "F.SilkS")
		)
		(fp_line
			(start 16.735044 -2.028952)
			(end 16.723106 -1.95961)
			(stroke
				(width 0.1)
				(type default)
			)
			(layer "F.SilkS")
		)
		(fp_line
			(start 16.735044 -2.028952)
			(end 18.089372 -3.328416)
			(stroke
				(width 0.1)
				(type default)
			)
			(layer "F.SilkS")
		)
		(fp_line
			(start 16.735044 -2.028952)
			(end 18.089372 -3.328416)
			(stroke
				(width 0.1)
				(type default)
			)
			(layer "F.SilkS")
		)
		(fp_line
			(start 16.743426 -0.882904)
			(end 16.803624 -0.882904)
			(stroke
				(width 0.1)
				(type default)
			)
			(layer "F.SilkS")
		)
		(fp_line
			(start 16.743426 -0.882904)
			(end 16.803624 -0.882904)
			(stroke
				(width 0.1)
				(type default)
			)
			(layer "F.SilkS")
		)
		(fp_line
			(start 16.743426 -0.882904)
			(end 17.847564 -1.942338)
			(stroke
				(width 0.1)
				(type default)
			)
			(layer "F.SilkS")
		)
		(fp_line
			(start 16.743426 -0.882904)
			(end 17.847564 -1.942338)
			(stroke
				(width 0.1)
				(type default)
			)
			(layer "F.SilkS")
		)
		(fp_line
			(start 16.747236 -2.098548)
			(end 16.735044 -2.028952)
			(stroke
				(width 0.1)
				(type default)
			)
			(layer "F.SilkS")
		)
		(fp_line
			(start 16.747236 -2.098548)
			(end 16.735044 -2.028952)
			(stroke
				(width 0.1)
				(type default)
			)
			(layer "F.SilkS")
		)
		(fp_line
			(start 16.747236 -2.098548)
			(end 18.097246 -3.393694)
			(stroke
				(width 0.1)
				(type default)
			)
			(layer "F.SilkS")
		)
		(fp_line
			(start 16.747236 -2.098548)
			(end 18.097246 -3.393694)
			(stroke
				(width 0.1)
				(type default)
			)
			(layer "F.SilkS")
		)
		(fp_line
			(start 16.759682 -2.16789)
			(end 16.747236 -2.098548)
			(stroke
				(width 0.1)
				(type default)
			)
			(layer "F.SilkS")
		)
		(fp_line
			(start 16.759682 -2.16789)
			(end 16.747236 -2.098548)
			(stroke
				(width 0.1)
				(type default)
			)
			(layer "F.SilkS")
		)
		(fp_line
			(start 16.759682 -2.16789)
			(end 18.105374 -3.458718)
			(stroke
				(width 0.1)
				(type default)
			)
			(layer "F.SilkS")
		)
		(fp_line
			(start 16.759682 -2.16789)
			(end 18.105374 -3.458718)
			(stroke
				(width 0.1)
				(type default)
			)
			(layer "F.SilkS")
		)
		(fp_line
			(start 16.77162 -2.237232)
			(end 16.759682 -2.16789)
			(stroke
				(width 0.1)
				(type default)
			)
			(layer "F.SilkS")
		)
		(fp_line
			(start 16.77162 -2.237232)
			(end 16.759682 -2.16789)
			(stroke
				(width 0.1)
				(type default)
			)
			(layer "F.SilkS")
		)
		(fp_line
			(start 16.77162 -2.237232)
			(end 18.113248 -3.52425)
			(stroke
				(width 0.1)
				(type default)
			)
			(layer "F.SilkS")
		)
		(fp_line
			(start 16.77162 -2.237232)
			(end 18.113248 -3.52425)
			(stroke
				(width 0.1)
				(type default)
			)
			(layer "F.SilkS")
		)
		(fp_line
			(start 16.783812 -2.306828)
			(end 16.77162 -2.237232)
			(stroke
				(width 0.1)
				(type default)
			)
			(layer "F.SilkS")
		)
		(fp_line
			(start 16.783812 -2.306828)
			(end 16.77162 -2.237232)
			(stroke
				(width 0.1)
				(type default)
			)
			(layer "F.SilkS")
		)
		(fp_line
			(start 16.783812 -2.306828)
			(end 18.121122 -3.589782)
			(stroke
				(width 0.1)
				(type default)
			)
			(layer "F.SilkS")
		)
		(fp_line
			(start 16.783812 -2.306828)
			(end 18.121122 -3.589782)
			(stroke
				(width 0.1)
				(type default)
			)
			(layer "F.SilkS")
		)
		(fp_line
			(start 16.790162 -5.256022)
			(end 14.291818 -2.859532)
			(stroke
				(width 0.1)
				(type default)
			)
			(layer "F.SilkS")
		)
		(fp_line
			(start 16.790162 -5.256022)
			(end 14.291818 -2.859532)
			(stroke
				(width 0.1)
				(type default)
			)
			(layer "F.SilkS")
		)
		(fp_line
			(start 16.796258 -2.37617)
			(end 16.783812 -2.306828)
			(stroke
				(width 0.1)
				(type default)
			)
			(layer "F.SilkS")
		)
		(fp_line
			(start 16.796258 -2.37617)
			(end 16.783812 -2.306828)
			(stroke
				(width 0.1)
				(type default)
			)
			(layer "F.SilkS")
		)
		(fp_line
			(start 16.796258 -2.37617)
			(end 18.129504 -3.65506)
			(stroke
				(width 0.1)
				(type default)
			)
			(layer "F.SilkS")
		)
		(fp_line
			(start 16.796258 -2.37617)
			(end 18.129504 -3.65506)
			(stroke
				(width 0.1)
				(type default)
			)
			(layer "F.SilkS")
		)
		(fp_line
			(start 16.803624 -0.882904)
			(end 16.863568 -0.882904)
			(stroke
				(width 0.1)
				(type default)
			)
			(layer "F.SilkS")
		)
		(fp_line
			(start 16.803624 -0.882904)
			(end 16.863568 -0.882904)
			(stroke
				(width 0.1)
				(type default)
			)
			(layer "F.SilkS")
		)
		(fp_line
			(start 16.803624 -0.882904)
			(end 17.835626 -1.872742)
			(stroke
				(width 0.1)
				(type default)
			)
			(layer "F.SilkS")
		)
		(fp_line
			(start 16.803624 -0.882904)
			(end 17.835626 -1.872742)
			(stroke
				(width 0.1)
				(type default)
			)
			(layer "F.SilkS")
		)
		(fp_line
			(start 16.808196 -2.445512)
			(end 16.796258 -2.37617)
			(stroke
				(width 0.1)
				(type default)
			)
			(layer "F.SilkS")
		)
		(fp_line
			(start 16.808196 -2.445512)
			(end 16.796258 -2.37617)
			(stroke
				(width 0.1)
				(type default)
			)
			(layer "F.SilkS")
		)
		(fp_line
			(start 16.808196 -2.445512)
			(end 18.13687 -3.720338)
			(stroke
				(width 0.1)
				(type default)
			)
			(layer "F.SilkS")
		)
		(fp_line
			(start 16.808196 -2.445512)
			(end 18.13687 -3.720338)
			(stroke
				(width 0.1)
				(type default)
			)
			(layer "F.SilkS")
		)
		(fp_line
			(start 16.820134 -2.515108)
			(end 16.808196 -2.445512)
			(stroke
				(width 0.1)
				(type default)
			)
			(layer "F.SilkS")
		)
		(fp_line
			(start 16.820134 -2.515108)
			(end 16.808196 -2.445512)
			(stroke
				(width 0.1)
				(type default)
			)
			(layer "F.SilkS")
		)
		(fp_line
			(start 16.820134 -2.515108)
			(end 16.83258 -2.58445)
			(stroke
				(width 0.1)
				(type default)
			)
			(layer "F.SilkS")
		)
		(fp_line
			(start 16.820134 -2.515108)
			(end 16.83258 -2.58445)
			(stroke
				(width 0.1)
				(type default)
			)
			(layer "F.SilkS")
		)
		(fp_line
			(start 16.820134 -2.515108)
			(end 18.138394 -3.779266)
			(stroke
				(width 0.1)
				(type default)
			)
			(layer "F.SilkS")
		)
		(fp_line
			(start 16.820134 -2.515108)
			(end 18.138394 -3.779266)
			(stroke
				(width 0.1)
				(type default)
			)
			(layer "F.SilkS")
		)
		(fp_line
			(start 16.845026 -2.653792)
			(end 16.83258 -2.58445)
			(stroke
				(width 0.1)
				(type default)
			)
			(layer "F.SilkS")
		)
		(fp_line
			(start 16.845026 -2.653792)
			(end 16.83258 -2.58445)
			(stroke
				(width 0.1)
				(type default)
			)
			(layer "F.SilkS")
		)
		(fp_line
			(start 16.845026 -2.653792)
			(end 18.137378 -3.89382)
			(stroke
				(width 0.1)
				(type default)
			)
			(layer "F.SilkS")
		)
		(fp_line
			(start 16.845026 -2.653792)
			(end 18.137378 -3.89382)
			(stroke
				(width 0.1)
				(type default)
			)
			(layer "F.SilkS")
		)
		(fp_line
			(start 16.854678 -5.26034)
			(end 14.27988 -2.79019)
			(stroke
				(width 0.1)
				(type default)
			)
			(layer "F.SilkS")
		)
		(fp_line
			(start 16.854678 -5.26034)
			(end 14.27988 -2.79019)
			(stroke
				(width 0.1)
				(type default)
			)
			(layer "F.SilkS")
		)
		(fp_line
			(start 16.857218 -2.723134)
			(end 16.845026 -2.653792)
			(stroke
				(width 0.1)
				(type default)
			)
			(layer "F.SilkS")
		)
		(fp_line
			(start 16.857218 -2.723134)
			(end 16.845026 -2.653792)
			(stroke
				(width 0.1)
				(type default)
			)
			(layer "F.SilkS")
		)
		(fp_line
			(start 16.857218 -2.723134)
			(end 18.13687 -3.95097)
			(stroke
				(width 0.1)
				(type default)
			)
			(layer "F.SilkS")
		)
		(fp_line
			(start 16.857218 -2.723134)
			(end 18.13687 -3.95097)
			(stroke
				(width 0.1)
				(type default)
			)
			(layer "F.SilkS")
		)
		(fp_line
			(start 16.863568 -0.882904)
			(end 16.92402 -0.882904)
			(stroke
				(width 0.1)
				(type default)
			)
			(layer "F.SilkS")
		)
		(fp_line
			(start 16.863568 -0.882904)
			(end 16.92402 -0.882904)
			(stroke
				(width 0.1)
				(type default)
			)
			(layer "F.SilkS")
		)
		(fp_line
			(start 16.863568 -0.882904)
			(end 17.823434 -1.8034)
			(stroke
				(width 0.1)
				(type default)
			)
			(layer "F.SilkS")
		)
		(fp_line
			(start 16.863568 -0.882904)
			(end 17.823434 -1.8034)
			(stroke
				(width 0.1)
				(type default)
			)
			(layer "F.SilkS")
		)
		(fp_line
			(start 16.869156 -2.79273)
			(end 16.857218 -2.723134)
			(stroke
				(width 0.1)
				(type default)
			)
			(layer "F.SilkS")
		)
		(fp_line
			(start 16.869156 -2.79273)
			(end 16.857218 -2.723134)
			(stroke
				(width 0.1)
				(type default)
			)
			(layer "F.SilkS")
		)
		(fp_line
			(start 16.869156 -2.79273)
			(end 18.136362 -4.008374)
			(stroke
				(width 0.1)
				(type default)
			)
			(layer "F.SilkS")
		)
		(fp_line
			(start 16.869156 -2.79273)
			(end 18.136362 -4.008374)
			(stroke
				(width 0.1)
				(type default)
			)
			(layer "F.SilkS")
		)
		(fp_line
			(start 16.881602 -2.862072)
			(end 16.869156 -2.79273)
			(stroke
				(width 0.1)
				(type default)
			)
			(layer "F.SilkS")
		)
		(fp_line
			(start 16.881602 -2.862072)
			(end 16.869156 -2.79273)
			(stroke
				(width 0.1)
				(type default)
			)
			(layer "F.SilkS")
		)
		(fp_line
			(start 16.881602 -2.862072)
			(end 18.136362 -4.065524)
			(stroke
				(width 0.1)
				(type default)
			)
			(layer "F.SilkS")
		)
		(fp_line
			(start 16.881602 -2.862072)
			(end 18.136362 -4.065524)
			(stroke
				(width 0.1)
				(type default)
			)
			(layer "F.SilkS")
		)
		(fp_line
			(start 16.89354 -2.931414)
			(end 16.881602 -2.862072)
			(stroke
				(width 0.1)
				(type default)
			)
			(layer "F.SilkS")
		)
		(fp_line
			(start 16.89354 -2.931414)
			(end 16.881602 -2.862072)
			(stroke
				(width 0.1)
				(type default)
			)
			(layer "F.SilkS")
		)
		(fp_line
			(start 16.89354 -2.931414)
			(end 18.134838 -4.121912)
			(stroke
				(width 0.1)
				(type default)
			)
			(layer "F.SilkS")
		)
		(fp_line
			(start 16.89354 -2.931414)
			(end 18.134838 -4.121912)
			(stroke
				(width 0.1)
				(type default)
			)
			(layer "F.SilkS")
		)
		(fp_line
			(start 16.905732 -3.000756)
			(end 16.89354 -2.931414)
			(stroke
				(width 0.1)
				(type default)
			)
			(layer "F.SilkS")
		)
		(fp_line
			(start 16.905732 -3.000756)
			(end 16.89354 -2.931414)
			(stroke
				(width 0.1)
				(type default)
			)
			(layer "F.SilkS")
		)
		(fp_line
			(start 16.905732 -3.000756)
			(end 18.125948 -4.171188)
			(stroke
				(width 0.1)
				(type default)
			)
			(layer "F.SilkS")
		)
		(fp_line
			(start 16.905732 -3.000756)
			(end 18.125948 -4.171188)
			(stroke
				(width 0.1)
				(type default)
			)
			(layer "F.SilkS")
		)
		(fp_line
			(start 16.909796 -5.255514)
			(end 14.267434 -2.720594)
			(stroke
				(width 0.1)
				(type default)
			)
			(layer "F.SilkS")
		)
		(fp_line
			(start 16.909796 -5.255514)
			(end 14.267434 -2.720594)
			(stroke
				(width 0.1)
				(type default)
			)
			(layer "F.SilkS")
		)
		(fp_line
			(start 16.918178 -3.070352)
			(end 16.905732 -3.000756)
			(stroke
				(width 0.1)
				(type default)
			)
			(layer "F.SilkS")
		)
		(fp_line
			(start 16.918178 -3.070352)
			(end 16.905732 -3.000756)
			(stroke
				(width 0.1)
				(type default)
			)
			(layer "F.SilkS")
		)
		(fp_line
			(start 16.918178 -3.070352)
			(end 18.117058 -4.220464)
			(stroke
				(width 0.1)
				(type default)
			)
			(layer "F.SilkS")
		)
		(fp_line
			(start 16.918178 -3.070352)
			(end 18.117058 -4.220464)
			(stroke
				(width 0.1)
				(type default)
			)
			(layer "F.SilkS")
		)
		(fp_line
			(start 16.92402 -0.882904)
			(end 16.984218 -0.882904)
			(stroke
				(width 0.1)
				(type default)
			)
			(layer "F.SilkS")
		)
		(fp_line
			(start 16.92402 -0.882904)
			(end 16.984218 -0.882904)
			(stroke
				(width 0.1)
				(type default)
			)
			(layer "F.SilkS")
		)
		(fp_line
			(start 16.92402 -0.882904)
			(end 17.810988 -1.734058)
			(stroke
				(width 0.1)
				(type default)
			)
			(layer "F.SilkS")
		)
		(fp_line
			(start 16.92402 -0.882904)
			(end 17.810988 -1.734058)
			(stroke
				(width 0.1)
				(type default)
			)
			(layer "F.SilkS")
		)
		(fp_line
			(start 16.930624 -3.139694)
			(end 16.918178 -3.070352)
			(stroke
				(width 0.1)
				(type default)
			)
			(layer "F.SilkS")
		)
		(fp_line
			(start 16.930624 -3.139694)
			(end 16.918178 -3.070352)
			(stroke
				(width 0.1)
				(type default)
			)
			(layer "F.SilkS")
		)
		(fp_line
			(start 16.96466 -5.25018)
			(end 14.255496 -2.651506)
			(stroke
				(width 0.1)
				(type default)
			)
			(layer "F.SilkS")
		)
		(fp_line
			(start 16.96466 -5.25018)
			(end 14.255496 -2.651506)
			(stroke
				(width 0.1)
				(type default)
			)
			(layer "F.SilkS")
		)
		(fp_line
			(start 16.984218 -0.882904)
			(end 17.044162 -0.882904)
			(stroke
				(width 0.1)
				(type default)
			)
			(layer "F.SilkS")
		)
		(fp_line
			(start 16.984218 -0.882904)
			(end 17.044162 -0.882904)
			(stroke
				(width 0.1)
				(type default)
			)
			(layer "F.SilkS")
		)
		(fp_line
			(start 16.984218 -0.882904)
			(end 17.79905 -1.664716)
			(stroke
				(width 0.1)
				(type default)
			)
			(layer "F.SilkS")
		)
		(fp_line
			(start 16.984218 -0.882904)
			(end 17.79905 -1.664716)
			(stroke
				(width 0.1)
				(type default)
			)
			(layer "F.SilkS")
		)
		(fp_line
			(start 17.01927 -5.245354)
			(end 14.243304 -2.58191)
			(stroke
				(width 0.1)
				(type default)
			)
			(layer "F.SilkS")
		)
		(fp_line
			(start 17.01927 -5.245354)
			(end 14.243304 -2.58191)
			(stroke
				(width 0.1)
				(type default)
			)
			(layer "F.SilkS")
		)
		(fp_line
			(start 17.044162 -0.882904)
			(end 17.10436 -0.882904)
			(stroke
				(width 0.1)
				(type default)
			)
			(layer "F.SilkS")
		)
		(fp_line
			(start 17.044162 -0.882904)
			(end 17.10436 -0.882904)
			(stroke
				(width 0.1)
				(type default)
			)
			(layer "F.SilkS")
		)
		(fp_line
			(start 17.044162 -0.882904)
			(end 17.786858 -1.595374)
			(stroke
				(width 0.1)
				(type default)
			)
			(layer "F.SilkS")
		)
		(fp_line
			(start 17.044162 -0.882904)
			(end 17.786858 -1.595374)
			(stroke
				(width 0.1)
				(type default)
			)
			(layer "F.SilkS")
		)
		(fp_line
			(start 17.074388 -5.240274)
			(end 14.230858 -2.512314)
			(stroke
				(width 0.1)
				(type default)
			)
			(layer "F.SilkS")
		)
		(fp_line
			(start 17.074388 -5.240274)
			(end 14.230858 -2.512314)
			(stroke
				(width 0.1)
				(type default)
			)
			(layer "F.SilkS")
		)
		(fp_line
			(start 17.10436 -0.882904)
			(end 17.164812 -0.882904)
			(stroke
				(width 0.1)
				(type default)
			)
			(layer "F.SilkS")
		)
		(fp_line
			(start 17.10436 -0.882904)
			(end 17.164812 -0.882904)
			(stroke
				(width 0.1)
				(type default)
			)
			(layer "F.SilkS")
		)
		(fp_line
			(start 17.10436 -0.882904)
			(end 17.774666 -1.525778)
			(stroke
				(width 0.1)
				(type default)
			)
			(layer "F.SilkS")
		)
		(fp_line
			(start 17.10436 -0.882904)
			(end 17.774666 -1.525778)
			(stroke
				(width 0.1)
				(type default)
			)
			(layer "F.SilkS")
		)
		(fp_line
			(start 17.129252 -5.235194)
			(end 15.934944 -4.0894)
			(stroke
				(width 0.1)
				(type default)
			)
			(layer "F.SilkS")
		)
		(fp_line
			(start 17.129252 -5.235194)
			(end 15.934944 -4.0894)
			(stroke
				(width 0.1)
				(type default)
			)
			(layer "F.SilkS")
		)
		(fp_line
			(start 17.164812 -0.882904)
			(end 17.224756 -0.882904)
			(stroke
				(width 0.1)
				(type default)
			)
			(layer "F.SilkS")
		)
		(fp_line
			(start 17.164812 -0.882904)
			(end 17.224756 -0.882904)
			(stroke
				(width 0.1)
				(type default)
			)
			(layer "F.SilkS")
		)
		(fp_line
			(start 17.164812 -0.882904)
			(end 17.762474 -1.456436)
			(stroke
				(width 0.1)
				(type default)
			)
			(layer "F.SilkS")
		)
		(fp_line
			(start 17.164812 -0.882904)
			(end 17.762474 -1.456436)
			(stroke
				(width 0.1)
				(type default)
			)
			(layer "F.SilkS")
		)
		(fp_line
			(start 17.184116 -5.230114)
			(end 16.052292 -4.144264)
			(stroke
				(width 0.1)
				(type default)
			)
			(layer "F.SilkS")
		)
		(fp_line
			(start 17.184116 -5.230114)
			(end 16.052292 -4.144264)
			(stroke
				(width 0.1)
				(type default)
			)
			(layer "F.SilkS")
		)
		(fp_line
			(start 17.224756 -0.882904)
			(end 17.284954 -0.882904)
			(stroke
				(width 0.1)
				(type default)
			)
			(layer "F.SilkS")
		)
		(fp_line
			(start 17.224756 -0.882904)
			(end 17.284954 -0.882904)
			(stroke
				(width 0.1)
				(type default)
			)
			(layer "F.SilkS")
		)
		(fp_line
			(start 17.224756 -0.882904)
			(end 17.750536 -1.387348)
			(stroke
				(width 0.1)
				(type default)
			)
			(layer "F.SilkS")
		)
		(fp_line
			(start 17.224756 -0.882904)
			(end 17.750536 -1.387348)
			(stroke
				(width 0.1)
				(type default)
			)
			(layer "F.SilkS")
		)
		(fp_line
			(start 17.235678 -5.221986)
			(end 16.13789 -4.168648)
			(stroke
				(width 0.1)
				(type default)
			)
			(layer "F.SilkS")
		)
		(fp_line
			(start 17.235678 -5.221986)
			(end 16.13789 -4.168648)
			(stroke
				(width 0.1)
				(type default)
			)
			(layer "F.SilkS")
		)
		(fp_line
			(start 17.280636 -5.207254)
			(end 16.218154 -4.187698)
			(stroke
				(width 0.1)
				(type default)
			)
			(layer "F.SilkS")
		)
		(fp_line
			(start 17.280636 -5.207254)
			(end 16.218154 -4.187698)
			(stroke
				(width 0.1)
				(type default)
			)
			(layer "F.SilkS")
		)
		(fp_line
			(start 17.284954 -0.882904)
			(end 17.345406 -0.882904)
			(stroke
				(width 0.1)
				(type default)
			)
			(layer "F.SilkS")
		)
		(fp_line
			(start 17.284954 -0.882904)
			(end 17.345406 -0.882904)
			(stroke
				(width 0.1)
				(type default)
			)
			(layer "F.SilkS")
		)
		(fp_line
			(start 17.284954 -0.882904)
			(end 17.73809 -1.317752)
			(stroke
				(width 0.1)
				(type default)
			)
			(layer "F.SilkS")
		)
		(fp_line
			(start 17.284954 -0.882904)
			(end 17.73809 -1.317752)
			(stroke
				(width 0.1)
				(type default)
			)
			(layer "F.SilkS")
		)
		(fp_line
			(start 17.32534 -5.192522)
			(end 16.283178 -4.192524)
			(stroke
				(width 0.1)
				(type default)
			)
			(layer "F.SilkS")
		)
		(fp_line
			(start 17.32534 -5.192522)
			(end 16.283178 -4.192524)
			(stroke
				(width 0.1)
				(type default)
			)
			(layer "F.SilkS")
		)
		(fp_line
			(start 17.345406 -0.882904)
			(end 17.40535 -0.882904)
			(stroke
				(width 0.1)
				(type default)
			)
			(layer "F.SilkS")
		)
		(fp_line
			(start 17.345406 -0.882904)
			(end 17.40535 -0.882904)
			(stroke
				(width 0.1)
				(type default)
			)
			(layer "F.SilkS")
		)
		(fp_line
			(start 17.345406 -0.882904)
			(end 17.725898 -1.248156)
			(stroke
				(width 0.1)
				(type default)
			)
			(layer "F.SilkS")
		)
		(fp_line
			(start 17.345406 -0.882904)
			(end 17.725898 -1.248156)
			(stroke
				(width 0.1)
				(type default)
			)
			(layer "F.SilkS")
		)
		(fp_line
			(start 17.370044 -5.17779)
			(end 16.347948 -4.197096)
			(stroke
				(width 0.1)
				(type default)
			)
			(layer "F.SilkS")
		)
		(fp_line
			(start 17.370044 -5.17779)
			(end 16.347948 -4.197096)
			(stroke
				(width 0.1)
				(type default)
			)
			(layer "F.SilkS")
		)
		(fp_line
			(start 17.40535 -0.882904)
			(end 17.465294 -0.882904)
			(stroke
				(width 0.1)
				(type default)
			)
			(layer "F.SilkS")
		)
		(fp_line
			(start 17.40535 -0.882904)
			(end 17.465294 -0.882904)
			(stroke
				(width 0.1)
				(type default)
			)
			(layer "F.SilkS")
		)
		(fp_line
			(start 17.40535 -0.882904)
			(end 17.71396 -1.178814)
			(stroke
				(width 0.1)
				(type default)
			)
			(layer "F.SilkS")
		)
		(fp_line
			(start 17.40535 -0.882904)
			(end 17.71396 -1.178814)
			(stroke
				(width 0.1)
				(type default)
			)
			(layer "F.SilkS")
		)
		(fp_line
			(start 17.415002 -5.163058)
			(end 16.40967 -4.198366)
			(stroke
				(width 0.1)
				(type default)
			)
			(layer "F.SilkS")
		)
		(fp_line
			(start 17.415002 -5.163058)
			(end 16.40967 -4.198366)
			(stroke
				(width 0.1)
				(type default)
			)
			(layer "F.SilkS")
		)
		(fp_line
			(start 17.45996 -5.148326)
			(end 16.465804 -4.194556)
			(stroke
				(width 0.1)
				(type default)
			)
			(layer "F.SilkS")
		)
		(fp_line
			(start 17.45996 -5.148326)
			(end 16.465804 -4.194556)
			(stroke
				(width 0.1)
				(type default)
			)
			(layer "F.SilkS")
		)
		(fp_line
			(start 17.465294 -0.882904)
			(end 17.525746 -0.882904)
			(stroke
				(width 0.1)
				(type default)
			)
			(layer "F.SilkS")
		)
		(fp_line
			(start 17.465294 -0.882904)
			(end 17.525746 -0.882904)
			(stroke
				(width 0.1)
				(type default)
			)
			(layer "F.SilkS")
		)
		(fp_line
			(start 17.465294 -0.882904)
			(end 17.701514 -1.109472)
			(stroke
				(width 0.1)
				(type default)
			)
			(layer "F.SilkS")
		)
		(fp_line
			(start 17.465294 -0.882904)
			(end 17.701514 -1.109472)
			(stroke
				(width 0.1)
				(type default)
			)
			(layer "F.SilkS")
		)
		(fp_line
			(start 17.50441 -5.13334)
			(end 16.521938 -4.190746)
			(stroke
				(width 0.1)
				(type default)
			)
			(layer "F.SilkS")
		)
		(fp_line
			(start 17.50441 -5.13334)
			(end 16.521938 -4.190746)
			(stroke
				(width 0.1)
				(type default)
			)
			(layer "F.SilkS")
		)
		(fp_line
			(start 17.525746 -0.882904)
			(end 17.58569 -0.882904)
			(stroke
				(width 0.1)
				(type default)
			)
			(layer "F.SilkS")
		)
		(fp_line
			(start 17.525746 -0.882904)
			(end 17.58569 -0.882904)
			(stroke
				(width 0.1)
				(type default)
			)
			(layer "F.SilkS")
		)
		(fp_line
			(start 17.525746 -0.882904)
			(end 17.689576 -1.04013)
			(stroke
				(width 0.1)
				(type default)
			)
			(layer "F.SilkS")
		)
		(fp_line
			(start 17.525746 -0.882904)
			(end 17.689576 -1.04013)
			(stroke
				(width 0.1)
				(type default)
			)
			(layer "F.SilkS")
		)
		(fp_line
			(start 17.545558 -5.115052)
			(end 16.5735 -4.182872)
			(stroke
				(width 0.1)
				(type default)
			)
			(layer "F.SilkS")
		)
		(fp_line
			(start 17.545558 -5.115052)
			(end 16.5735 -4.182872)
			(stroke
				(width 0.1)
				(type default)
			)
			(layer "F.SilkS")
		)
		(fp_line
			(start 17.580864 -5.091176)
			(end 16.621252 -4.170426)
			(stroke
				(width 0.1)
				(type default)
			)
			(layer "F.SilkS")
		)
		(fp_line
			(start 17.580864 -5.091176)
			(end 16.621252 -4.170426)
			(stroke
				(width 0.1)
				(type default)
			)
			(layer "F.SilkS")
		)
		(fp_line
			(start 17.58569 -0.882904)
			(end 17.645634 -0.882904)
			(stroke
				(width 0.1)
				(type default)
			)
			(layer "F.SilkS")
		)
		(fp_line
			(start 17.58569 -0.882904)
			(end 17.645634 -0.882904)
			(stroke
				(width 0.1)
				(type default)
			)
			(layer "F.SilkS")
		)
		(fp_line
			(start 17.58569 -0.882904)
			(end 17.677384 -0.970788)
			(stroke
				(width 0.1)
				(type default)
			)
			(layer "F.SilkS")
		)
		(fp_line
			(start 17.58569 -0.882904)
			(end 17.677384 -0.970788)
			(stroke
				(width 0.1)
				(type default)
			)
			(layer "F.SilkS")
		)
		(fp_line
			(start 17.61617 -5.067046)
			(end 16.668242 -4.15798)
			(stroke
				(width 0.1)
				(type default)
			)
			(layer "F.SilkS")
		)
		(fp_line
			(start 17.61617 -5.067046)
			(end 16.668242 -4.15798)
			(stroke
				(width 0.1)
				(type default)
			)
			(layer "F.SilkS")
		)
		(fp_line
			(start 17.645634 -0.882904)
			(end 17.66189 -0.882904)
			(stroke
				(width 0.1)
				(type default)
			)
			(layer "F.SilkS")
		)
		(fp_line
			(start 17.645634 -0.882904)
			(end 17.66189 -0.882904)
			(stroke
				(width 0.1)
				(type default)
			)
			(layer "F.SilkS")
		)
		(fp_line
			(start 17.645634 -0.882904)
			(end 17.664938 -0.901192)
			(stroke
				(width 0.1)
				(type default)
			)
			(layer "F.SilkS")
		)
		(fp_line
			(start 17.645634 -0.882904)
			(end 17.664938 -0.901192)
			(stroke
				(width 0.1)
				(type default)
			)
			(layer "F.SilkS")
		)
		(fp_line
			(start 17.651222 -5.043424)
			(end 16.71066 -4.140962)
			(stroke
				(width 0.1)
				(type default)
			)
			(layer "F.SilkS")
		)
		(fp_line
			(start 17.651222 -5.043424)
			(end 16.71066 -4.140962)
			(stroke
				(width 0.1)
				(type default)
			)
			(layer "F.SilkS")
		)
		(fp_line
			(start 17.66189 -0.882904)
			(end 17.664938 -0.901192)
			(stroke
				(width 0.1)
				(type default)
			)
			(layer "F.SilkS")
		)
		(fp_line
			(start 17.66189 -0.882904)
			(end 17.664938 -0.901192)
			(stroke
				(width 0.1)
				(type default)
			)
			(layer "F.SilkS")
		)
		(fp_line
			(start 17.677384 -0.970788)
			(end 17.664938 -0.901192)
			(stroke
				(width 0.1)
				(type default)
			)
			(layer "F.SilkS")
		)
		(fp_line
			(start 17.677384 -0.970788)
			(end 17.664938 -0.901192)
			(stroke
				(width 0.1)
				(type default)
			)
			(layer "F.SilkS")
		)
		(fp_line
			(start 17.686274 -5.019294)
			(end 16.747998 -4.119118)
			(stroke
				(width 0.1)
				(type default)
			)
			(layer "F.SilkS")
		)
		(fp_line
			(start 17.686274 -5.019294)
			(end 16.747998 -4.119118)
			(stroke
				(width 0.1)
				(type default)
			)
			(layer "F.SilkS")
		)
		(fp_line
			(start 17.689576 -1.04013)
			(end 17.677384 -0.970788)
			(stroke
				(width 0.1)
				(type default)
			)
			(layer "F.SilkS")
		)
		(fp_line
			(start 17.689576 -1.04013)
			(end 17.677384 -0.970788)
			(stroke
				(width 0.1)
				(type default)
			)
			(layer "F.SilkS")
		)
		(fp_line
			(start 17.701514 -1.109472)
			(end 17.689576 -1.04013)
			(stroke
				(width 0.1)
				(type default)
			)
			(layer "F.SilkS")
		)
		(fp_line
			(start 17.701514 -1.109472)
			(end 17.689576 -1.04013)
			(stroke
				(width 0.1)
				(type default)
			)
			(layer "F.SilkS")
		)
		(fp_line
			(start 17.71396 -1.178814)
			(end 17.701514 -1.109472)
			(stroke
				(width 0.1)
				(type default)
			)
			(layer "F.SilkS")
		)
		(fp_line
			(start 17.71396 -1.178814)
			(end 17.701514 -1.109472)
			(stroke
				(width 0.1)
				(type default)
			)
			(layer "F.SilkS")
		)
		(fp_line
			(start 17.721834 -4.995672)
			(end 16.785844 -4.097782)
			(stroke
				(width 0.1)
				(type default)
			)
			(layer "F.SilkS")
		)
		(fp_line
			(start 17.721834 -4.995672)
			(end 16.785844 -4.097782)
			(stroke
				(width 0.1)
				(type default)
			)
			(layer "F.SilkS")
		)
		(fp_line
			(start 17.725898 -1.248156)
			(end 17.71396 -1.178814)
			(stroke
				(width 0.1)
				(type default)
			)
			(layer "F.SilkS")
		)
		(fp_line
			(start 17.725898 -1.248156)
			(end 17.71396 -1.178814)
			(stroke
				(width 0.1)
				(type default)
			)
			(layer "F.SilkS")
		)
		(fp_line
			(start 17.73809 -1.317752)
			(end 17.725898 -1.248156)
			(stroke
				(width 0.1)
				(type default)
			)
			(layer "F.SilkS")
		)
		(fp_line
			(start 17.73809 -1.317752)
			(end 17.725898 -1.248156)
			(stroke
				(width 0.1)
				(type default)
			)
			(layer "F.SilkS")
		)
		(fp_line
			(start 17.750536 -1.387348)
			(end 17.73809 -1.317752)
			(stroke
				(width 0.1)
				(type default)
			)
			(layer "F.SilkS")
		)
		(fp_line
			(start 17.750536 -1.387348)
			(end 17.73809 -1.317752)
			(stroke
				(width 0.1)
				(type default)
			)
			(layer "F.SilkS")
		)
		(fp_line
			(start 17.757394 -4.971796)
			(end 16.818102 -4.071112)
			(stroke
				(width 0.1)
				(type default)
			)
			(layer "F.SilkS")
		)
		(fp_line
			(start 17.757394 -4.971796)
			(end 16.818102 -4.071112)
			(stroke
				(width 0.1)
				(type default)
			)
			(layer "F.SilkS")
		)
		(fp_line
			(start 17.762474 -1.456436)
			(end 17.750536 -1.387348)
			(stroke
				(width 0.1)
				(type default)
			)
			(layer "F.SilkS")
		)
		(fp_line
			(start 17.762474 -1.456436)
			(end 17.750536 -1.387348)
			(stroke
				(width 0.1)
				(type default)
			)
			(layer "F.SilkS")
		)
		(fp_line
			(start 17.774666 -1.525778)
			(end 17.762474 -1.456436)
			(stroke
				(width 0.1)
				(type default)
			)
			(layer "F.SilkS")
		)
		(fp_line
			(start 17.774666 -1.525778)
			(end 17.762474 -1.456436)
			(stroke
				(width 0.1)
				(type default)
			)
			(layer "F.SilkS")
		)
		(fp_line
			(start 17.786858 -1.595374)
			(end 17.774666 -1.525778)
			(stroke
				(width 0.1)
				(type default)
			)
			(layer "F.SilkS")
		)
		(fp_line
			(start 17.786858 -1.595374)
			(end 17.774666 -1.525778)
			(stroke
				(width 0.1)
				(type default)
			)
			(layer "F.SilkS")
		)
		(fp_line
			(start 17.78762 -4.943348)
			(end 16.845788 -4.03987)
			(stroke
				(width 0.1)
				(type default)
			)
			(layer "F.SilkS")
		)
		(fp_line
			(start 17.78762 -4.943348)
			(end 16.845788 -4.03987)
			(stroke
				(width 0.1)
				(type default)
			)
			(layer "F.SilkS")
		)
		(fp_line
			(start 17.79905 -1.664716)
			(end 17.786858 -1.595374)
			(stroke
				(width 0.1)
				(type default)
			)
			(layer "F.SilkS")
		)
		(fp_line
			(start 17.79905 -1.664716)
			(end 17.786858 -1.595374)
			(stroke
				(width 0.1)
				(type default)
			)
			(layer "F.SilkS")
		)
		(fp_line
			(start 17.810988 -1.734058)
			(end 17.79905 -1.664716)
			(stroke
				(width 0.1)
				(type default)
			)
			(layer "F.SilkS")
		)
		(fp_line
			(start 17.810988 -1.734058)
			(end 17.79905 -1.664716)
			(stroke
				(width 0.1)
				(type default)
			)
			(layer "F.SilkS")
		)
		(fp_line
			(start 17.813782 -4.910836)
			(end 16.87322 -4.008882)
			(stroke
				(width 0.1)
				(type default)
			)
			(layer "F.SilkS")
		)
		(fp_line
			(start 17.813782 -4.910836)
			(end 16.87322 -4.008882)
			(stroke
				(width 0.1)
				(type default)
			)
			(layer "F.SilkS")
		)
		(fp_line
			(start 17.823434 -1.8034)
			(end 17.810988 -1.734058)
			(stroke
				(width 0.1)
				(type default)
			)
			(layer "F.SilkS")
		)
		(fp_line
			(start 17.823434 -1.8034)
			(end 17.810988 -1.734058)
			(stroke
				(width 0.1)
				(type default)
			)
			(layer "F.SilkS")
		)
		(fp_line
			(start 17.835626 -1.872742)
			(end 17.823434 -1.8034)
			(stroke
				(width 0.1)
				(type default)
			)
			(layer "F.SilkS")
		)
		(fp_line
			(start 17.835626 -1.872742)
			(end 17.823434 -1.8034)
			(stroke
				(width 0.1)
				(type default)
			)
			(layer "F.SilkS")
		)
		(fp_line
			(start 17.839944 -4.878324)
			(end 16.89735 -3.97383)
			(stroke
				(width 0.1)
				(type default)
			)
			(layer "F.SilkS")
		)
		(fp_line
			(start 17.839944 -4.878324)
			(end 16.89735 -3.97383)
			(stroke
				(width 0.1)
				(type default)
			)
			(layer "F.SilkS")
		)
		(fp_line
			(start 17.847564 -1.942338)
			(end 17.835626 -1.872742)
			(stroke
				(width 0.1)
				(type default)
			)
			(layer "F.SilkS")
		)
		(fp_line
			(start 17.847564 -1.942338)
			(end 17.835626 -1.872742)
			(stroke
				(width 0.1)
				(type default)
			)
			(layer "F.SilkS")
		)
		(fp_line
			(start 17.86001 -2.011426)
			(end 17.847564 -1.942338)
			(stroke
				(width 0.1)
				(type default)
			)
			(layer "F.SilkS")
		)
		(fp_line
			(start 17.86001 -2.011426)
			(end 17.847564 -1.942338)
			(stroke
				(width 0.1)
				(type default)
			)
			(layer "F.SilkS")
		)
		(fp_line
			(start 17.866106 -4.845558)
			(end 16.915384 -3.93319)
			(stroke
				(width 0.1)
				(type default)
			)
			(layer "F.SilkS")
		)
		(fp_line
			(start 17.866106 -4.845558)
			(end 16.915384 -3.93319)
			(stroke
				(width 0.1)
				(type default)
			)
			(layer "F.SilkS")
		)
		(fp_line
			(start 17.871948 -2.081022)
			(end 17.86001 -2.011426)
			(stroke
				(width 0.1)
				(type default)
			)
			(layer "F.SilkS")
		)
		(fp_line
			(start 17.871948 -2.081022)
			(end 17.86001 -2.011426)
			(stroke
				(width 0.1)
				(type default)
			)
			(layer "F.SilkS")
		)
		(fp_line
			(start 17.88414 -2.150364)
			(end 17.871948 -2.081022)
			(stroke
				(width 0.1)
				(type default)
			)
			(layer "F.SilkS")
		)
		(fp_line
			(start 17.88414 -2.150364)
			(end 17.871948 -2.081022)
			(stroke
				(width 0.1)
				(type default)
			)
			(layer "F.SilkS")
		)
		(fp_line
			(start 17.892268 -4.813046)
			(end 16.93291 -3.89255)
			(stroke
				(width 0.1)
				(type default)
			)
			(layer "F.SilkS")
		)
		(fp_line
			(start 17.892268 -4.813046)
			(end 16.93291 -3.89255)
			(stroke
				(width 0.1)
				(type default)
			)
			(layer "F.SilkS")
		)
		(fp_line
			(start 17.896586 -2.21996)
			(end 17.88414 -2.150364)
			(stroke
				(width 0.1)
				(type default)
			)
			(layer "F.SilkS")
		)
		(fp_line
			(start 17.896586 -2.21996)
			(end 17.88414 -2.150364)
			(stroke
				(width 0.1)
				(type default)
			)
			(layer "F.SilkS")
		)
		(fp_line
			(start 17.908524 -2.289048)
			(end 17.896586 -2.21996)
			(stroke
				(width 0.1)
				(type default)
			)
			(layer "F.SilkS")
		)
		(fp_line
			(start 17.908524 -2.289048)
			(end 17.896586 -2.21996)
			(stroke
				(width 0.1)
				(type default)
			)
			(layer "F.SilkS")
		)
		(fp_line
			(start 17.91843 -4.780534)
			(end 16.949674 -3.850894)
			(stroke
				(width 0.1)
				(type default)
			)
			(layer "F.SilkS")
		)
		(fp_line
			(start 17.91843 -4.780534)
			(end 16.949674 -3.850894)
			(stroke
				(width 0.1)
				(type default)
			)
			(layer "F.SilkS")
		)
		(fp_line
			(start 17.920716 -2.35839)
			(end 17.908524 -2.289048)
			(stroke
				(width 0.1)
				(type default)
			)
			(layer "F.SilkS")
		)
		(fp_line
			(start 17.920716 -2.35839)
			(end 17.908524 -2.289048)
			(stroke
				(width 0.1)
				(type default)
			)
			(layer "F.SilkS")
		)
		(fp_line
			(start 17.932908 -2.427732)
			(end 17.920716 -2.35839)
			(stroke
				(width 0.1)
				(type default)
			)
			(layer "F.SilkS")
		)
		(fp_line
			(start 17.932908 -2.427732)
			(end 17.920716 -2.35839)
			(stroke
				(width 0.1)
				(type default)
			)
			(layer "F.SilkS")
		)
		(fp_line
			(start 17.944846 -4.748022)
			(end 16.958056 -3.80111)
			(stroke
				(width 0.1)
				(type default)
			)
			(layer "F.SilkS")
		)
		(fp_line
			(start 17.944846 -4.748022)
			(end 16.958056 -3.80111)
			(stroke
				(width 0.1)
				(type default)
			)
			(layer "F.SilkS")
		)
		(fp_line
			(start 17.9451 -2.497328)
			(end 17.932908 -2.427732)
			(stroke
				(width 0.1)
				(type default)
			)
			(layer "F.SilkS")
		)
		(fp_line
			(start 17.9451 -2.497328)
			(end 17.932908 -2.427732)
			(stroke
				(width 0.1)
				(type default)
			)
			(layer "F.SilkS")
		)
		(fp_line
			(start 17.957038 -2.56667)
			(end 17.9451 -2.497328)
			(stroke
				(width 0.1)
				(type default)
			)
			(layer "F.SilkS")
		)
		(fp_line
			(start 17.957038 -2.56667)
			(end 17.9451 -2.497328)
			(stroke
				(width 0.1)
				(type default)
			)
			(layer "F.SilkS")
		)
		(fp_line
			(start 17.966182 -4.710176)
			(end 16.966438 -3.751326)
			(stroke
				(width 0.1)
				(type default)
			)
			(layer "F.SilkS")
		)
		(fp_line
			(start 17.966182 -4.710176)
			(end 16.966438 -3.751326)
			(stroke
				(width 0.1)
				(type default)
			)
			(layer "F.SilkS")
		)
		(fp_line
			(start 17.969484 -2.636012)
			(end 17.957038 -2.56667)
			(stroke
				(width 0.1)
				(type default)
			)
			(layer "F.SilkS")
		)
		(fp_line
			(start 17.969484 -2.636012)
			(end 17.957038 -2.56667)
			(stroke
				(width 0.1)
				(type default)
			)
			(layer "F.SilkS")
		)
		(fp_line
			(start 17.981676 -2.705608)
			(end 17.969484 -2.636012)
			(stroke
				(width 0.1)
				(type default)
			)
			(layer "F.SilkS")
		)
		(fp_line
			(start 17.981676 -2.705608)
			(end 17.969484 -2.636012)
			(stroke
				(width 0.1)
				(type default)
			)
			(layer "F.SilkS")
		)
		(fp_line
			(start 17.9832 -4.669282)
			(end 16.974566 -3.701542)
			(stroke
				(width 0.1)
				(type default)
			)
			(layer "F.SilkS")
		)
		(fp_line
			(start 17.9832 -4.669282)
			(end 16.974566 -3.701542)
			(stroke
				(width 0.1)
				(type default)
			)
			(layer "F.SilkS")
		)
		(fp_line
			(start 17.993614 -2.77495)
			(end 17.981676 -2.705608)
			(stroke
				(width 0.1)
				(type default)
			)
			(layer "F.SilkS")
		)
		(fp_line
			(start 17.993614 -2.77495)
			(end 17.981676 -2.705608)
			(stroke
				(width 0.1)
				(type default)
			)
			(layer "F.SilkS")
		)
		(fp_line
			(start 18.000472 -4.628388)
			(end 16.97736 -3.646424)
			(stroke
				(width 0.1)
				(type default)
			)
			(layer "F.SilkS")
		)
		(fp_line
			(start 18.000472 -4.628388)
			(end 16.97736 -3.646424)
			(stroke
				(width 0.1)
				(type default)
			)
			(layer "F.SilkS")
		)
		(fp_line
			(start 18.00606 -2.844292)
			(end 17.993614 -2.77495)
			(stroke
				(width 0.1)
				(type default)
			)
			(layer "F.SilkS")
		)
		(fp_line
			(start 18.00606 -2.844292)
			(end 17.993614 -2.77495)
			(stroke
				(width 0.1)
				(type default)
			)
			(layer "F.SilkS")
		)
		(fp_line
			(start 18.017998 -4.58724)
			(end 16.976598 -3.588258)
			(stroke
				(width 0.1)
				(type default)
			)
			(layer "F.SilkS")
		)
		(fp_line
			(start 18.017998 -4.58724)
			(end 16.976598 -3.588258)
			(stroke
				(width 0.1)
				(type default)
			)
			(layer "F.SilkS")
		)
		(fp_line
			(start 18.017998 -2.913634)
			(end 18.00606 -2.844292)
			(stroke
				(width 0.1)
				(type default)
			)
			(layer "F.SilkS")
		)
		(fp_line
			(start 18.017998 -2.913634)
			(end 18.00606 -2.844292)
			(stroke
				(width 0.1)
				(type default)
			)
			(layer "F.SilkS")
		)
		(fp_line
			(start 18.03019 -2.982976)
			(end 18.017998 -2.913634)
			(stroke
				(width 0.1)
				(type default)
			)
			(layer "F.SilkS")
		)
		(fp_line
			(start 18.03019 -2.982976)
			(end 18.017998 -2.913634)
			(stroke
				(width 0.1)
				(type default)
			)
			(layer "F.SilkS")
		)
		(fp_line
			(start 18.035778 -4.546346)
			(end 16.97609 -3.529838)
			(stroke
				(width 0.1)
				(type default)
			)
			(layer "F.SilkS")
		)
		(fp_line
			(start 18.035778 -4.546346)
			(end 16.97609 -3.529838)
			(stroke
				(width 0.1)
				(type default)
			)
			(layer "F.SilkS")
		)
		(fp_line
			(start 18.042636 -3.052572)
			(end 18.03019 -2.982976)
			(stroke
				(width 0.1)
				(type default)
			)
			(layer "F.SilkS")
		)
		(fp_line
			(start 18.042636 -3.052572)
			(end 18.03019 -2.982976)
			(stroke
				(width 0.1)
				(type default)
			)
			(layer "F.SilkS")
		)
		(fp_line
			(start 18.052796 -4.505198)
			(end 16.975582 -3.471672)
			(stroke
				(width 0.1)
				(type default)
			)
			(layer "F.SilkS")
		)
		(fp_line
			(start 18.052796 -4.505198)
			(end 16.975582 -3.471672)
			(stroke
				(width 0.1)
				(type default)
			)
			(layer "F.SilkS")
		)
		(fp_line
			(start 18.054574 -3.121914)
			(end 18.042636 -3.052572)
			(stroke
				(width 0.1)
				(type default)
			)
			(layer "F.SilkS")
		)
		(fp_line
			(start 18.054574 -3.121914)
			(end 18.042636 -3.052572)
			(stroke
				(width 0.1)
				(type default)
			)
			(layer "F.SilkS")
		)
		(fp_line
			(start 18.066766 -3.191002)
			(end 18.054574 -3.121914)
			(stroke
				(width 0.1)
				(type default)
			)
			(layer "F.SilkS")
		)
		(fp_line
			(start 18.066766 -3.191002)
			(end 18.054574 -3.121914)
			(stroke
				(width 0.1)
				(type default)
			)
			(layer "F.SilkS")
		)
		(fp_line
			(start 18.070068 -4.464304)
			(end 16.967708 -3.406648)
			(stroke
				(width 0.1)
				(type default)
			)
			(layer "F.SilkS")
		)
		(fp_line
			(start 18.070068 -4.464304)
			(end 16.967708 -3.406648)
			(stroke
				(width 0.1)
				(type default)
			)
			(layer "F.SilkS")
		)
		(fp_line
			(start 18.079212 -3.260598)
			(end 18.066766 -3.191002)
			(stroke
				(width 0.1)
				(type default)
			)
			(layer "F.SilkS")
		)
		(fp_line
			(start 18.079212 -3.260598)
			(end 18.066766 -3.191002)
			(stroke
				(width 0.1)
				(type default)
			)
			(layer "F.SilkS")
		)
		(fp_line
			(start 18.081752 -4.417314)
			(end 16.959326 -3.340608)
			(stroke
				(width 0.1)
				(type default)
			)
			(layer "F.SilkS")
		)
		(fp_line
			(start 18.081752 -4.417314)
			(end 16.959326 -3.340608)
			(stroke
				(width 0.1)
				(type default)
			)
			(layer "F.SilkS")
		)
		(fp_line
			(start 18.090388 -4.368038)
			(end 16.950436 -3.274568)
			(stroke
				(width 0.1)
				(type default)
			)
			(layer "F.SilkS")
		)
		(fp_line
			(start 18.090388 -4.368038)
			(end 16.950436 -3.274568)
			(stroke
				(width 0.1)
				(type default)
			)
			(layer "F.SilkS")
		)
		(fp_line
			(start 18.099532 -4.318762)
			(end 16.942308 -3.208782)
			(stroke
				(width 0.1)
				(type default)
			)
			(layer "F.SilkS")
		)
		(fp_line
			(start 18.099532 -4.318762)
			(end 16.942308 -3.208782)
			(stroke
				(width 0.1)
				(type default)
			)
			(layer "F.SilkS")
		)
		(fp_line
			(start 18.107914 -4.26974)
			(end 16.930624 -3.139694)
			(stroke
				(width 0.1)
				(type default)
			)
			(layer "F.SilkS")
		)
		(fp_line
			(start 18.107914 -4.26974)
			(end 16.930624 -3.139694)
			(stroke
				(width 0.1)
				(type default)
			)
			(layer "F.SilkS")
		)
		(fp_line
			(start 18.137632 -3.836416)
			(end 16.83258 -2.58445)
			(stroke
				(width 0.1)
				(type default)
			)
			(layer "F.SilkS")
		)
		(fp_line
			(start 18.137632 -3.836416)
			(end 16.83258 -2.58445)
			(stroke
				(width 0.1)
				(type default)
			)
			(layer "F.SilkS")
		)
		(fp_line
			(start 18.736818 -4.109466)
			(end 18.783554 -4.109466)
			(stroke
				(width 0.1)
				(type default)
			)
			(layer "F.SilkS")
		)
		(fp_line
			(start 18.736818 -4.109466)
			(end 18.783554 -4.109466)
			(stroke
				(width 0.1)
				(type default)
			)
			(layer "F.SilkS")
		)
		(fp_line
			(start 18.739612 -4.12496)
			(end 18.736818 -4.109466)
			(stroke
				(width 0.1)
				(type default)
			)
			(layer "F.SilkS")
		)
		(fp_line
			(start 18.739612 -4.12496)
			(end 18.736818 -4.109466)
			(stroke
				(width 0.1)
				(type default)
			)
			(layer "F.SilkS")
		)
		(fp_line
			(start 18.739612 -4.12496)
			(end 20.959318 -6.254496)
			(stroke
				(width 0.1)
				(type default)
			)
			(layer "F.SilkS")
		)
		(fp_line
			(start 18.739612 -4.12496)
			(end 20.959318 -6.254496)
			(stroke
				(width 0.1)
				(type default)
			)
			(layer "F.SilkS")
		)
		(fp_line
			(start 18.75155 -4.194556)
			(end 18.739612 -4.12496)
			(stroke
				(width 0.1)
				(type default)
			)
			(layer "F.SilkS")
		)
		(fp_line
			(start 18.75155 -4.194556)
			(end 18.739612 -4.12496)
			(stroke
				(width 0.1)
				(type default)
			)
			(layer "F.SilkS")
		)
		(fp_line
			(start 18.763996 -4.263898)
			(end 18.75155 -4.194556)
			(stroke
				(width 0.1)
				(type default)
			)
			(layer "F.SilkS")
		)
		(fp_line
			(start 18.763996 -4.263898)
			(end 18.75155 -4.194556)
			(stroke
				(width 0.1)
				(type default)
			)
			(layer "F.SilkS")
		)
		(fp_line
			(start 18.775934 -4.33324)
			(end 18.763996 -4.263898)
			(stroke
				(width 0.1)
				(type default)
			)
			(layer "F.SilkS")
		)
		(fp_line
			(start 18.775934 -4.33324)
			(end 18.763996 -4.263898)
			(stroke
				(width 0.1)
				(type default)
			)
			(layer "F.SilkS")
		)
		(fp_line
			(start 18.775934 -4.33324)
			(end 18.78838 -4.402836)
			(stroke
				(width 0.1)
				(type default)
			)
			(layer "F.SilkS")
		)
		(fp_line
			(start 18.775934 -4.33324)
			(end 18.78838 -4.402836)
			(stroke
				(width 0.1)
				(type default)
			)
			(layer "F.SilkS")
		)
		(fp_line
			(start 18.783554 -4.109466)
			(end 18.843498 -4.109466)
			(stroke
				(width 0.1)
				(type default)
			)
			(layer "F.SilkS")
		)
		(fp_line
			(start 18.783554 -4.109466)
			(end 18.843498 -4.109466)
			(stroke
				(width 0.1)
				(type default)
			)
			(layer "F.SilkS")
		)
		(fp_line
			(start 18.783554 -4.109466)
			(end 20.947126 -6.1849)
			(stroke
				(width 0.1)
				(type default)
			)
			(layer "F.SilkS")
		)
		(fp_line
			(start 18.783554 -4.109466)
			(end 20.947126 -6.1849)
			(stroke
				(width 0.1)
				(type default)
			)
			(layer "F.SilkS")
		)
		(fp_line
			(start 18.78838 -4.402836)
			(end 18.800572 -4.472178)
			(stroke
				(width 0.1)
				(type default)
			)
			(layer "F.SilkS")
		)
		(fp_line
			(start 18.78838 -4.402836)
			(end 18.800572 -4.472178)
			(stroke
				(width 0.1)
				(type default)
			)
			(layer "F.SilkS")
		)
		(fp_line
			(start 18.78838 -4.402836)
			(end 19.58975 -5.171694)
			(stroke
				(width 0.1)
				(type default)
			)
			(layer "F.SilkS")
		)
		(fp_line
			(start 18.78838 -4.402836)
			(end 19.58975 -5.171694)
			(stroke
				(width 0.1)
				(type default)
			)
			(layer "F.SilkS")
		)
		(fp_line
			(start 18.800572 -4.472178)
			(end 18.81251 -4.54152)
			(stroke
				(width 0.1)
				(type default)
			)
			(layer "F.SilkS")
		)
		(fp_line
			(start 18.800572 -4.472178)
			(end 18.81251 -4.54152)
			(stroke
				(width 0.1)
				(type default)
			)
			(layer "F.SilkS")
		)
		(fp_line
			(start 18.800572 -4.472178)
			(end 19.529806 -5.171694)
			(stroke
				(width 0.1)
				(type default)
			)
			(layer "F.SilkS")
		)
		(fp_line
			(start 18.800572 -4.472178)
			(end 19.529806 -5.171694)
			(stroke
				(width 0.1)
				(type default)
			)
			(layer "F.SilkS")
		)
		(fp_line
			(start 18.81251 -4.54152)
			(end 18.824956 -4.610862)
			(stroke
				(width 0.1)
				(type default)
			)
			(layer "F.SilkS")
		)
		(fp_line
			(start 18.81251 -4.54152)
			(end 18.824956 -4.610862)
			(stroke
				(width 0.1)
				(type default)
			)
			(layer "F.SilkS")
		)
		(fp_line
			(start 18.81251 -4.54152)
			(end 19.469608 -5.171694)
			(stroke
				(width 0.1)
				(type default)
			)
			(layer "F.SilkS")
		)
		(fp_line
			(start 18.81251 -4.54152)
			(end 19.469608 -5.171694)
			(stroke
				(width 0.1)
				(type default)
			)
			(layer "F.SilkS")
		)
		(fp_line
			(start 18.824956 -4.610862)
			(end 18.836894 -4.680458)
			(stroke
				(width 0.1)
				(type default)
			)
			(layer "F.SilkS")
		)
		(fp_line
			(start 18.824956 -4.610862)
			(end 18.836894 -4.680458)
			(stroke
				(width 0.1)
				(type default)
			)
			(layer "F.SilkS")
		)
		(fp_line
			(start 18.824956 -4.610862)
			(end 19.409664 -5.171694)
			(stroke
				(width 0.1)
				(type default)
			)
			(layer "F.SilkS")
		)
		(fp_line
			(start 18.824956 -4.610862)
			(end 19.409664 -5.171694)
			(stroke
				(width 0.1)
				(type default)
			)
			(layer "F.SilkS")
		)
		(fp_line
			(start 18.836894 -4.680458)
			(end 18.84934 -4.7498)
			(stroke
				(width 0.1)
				(type default)
			)
			(layer "F.SilkS")
		)
		(fp_line
			(start 18.836894 -4.680458)
			(end 18.84934 -4.7498)
			(stroke
				(width 0.1)
				(type default)
			)
			(layer "F.SilkS")
		)
		(fp_line
			(start 18.836894 -4.680458)
			(end 19.349212 -5.171694)
			(stroke
				(width 0.1)
				(type default)
			)
			(layer "F.SilkS")
		)
		(fp_line
			(start 18.836894 -4.680458)
			(end 19.349212 -5.171694)
			(stroke
				(width 0.1)
				(type default)
			)
			(layer "F.SilkS")
		)
		(fp_line
			(start 18.843498 -4.109466)
			(end 18.90395 -4.109466)
			(stroke
				(width 0.1)
				(type default)
			)
			(layer "F.SilkS")
		)
		(fp_line
			(start 18.843498 -4.109466)
			(end 18.90395 -4.109466)
			(stroke
				(width 0.1)
				(type default)
			)
			(layer "F.SilkS")
		)
		(fp_line
			(start 18.843498 -4.109466)
			(end 20.93468 -6.115558)
			(stroke
				(width 0.1)
				(type default)
			)
			(layer "F.SilkS")
		)
		(fp_line
			(start 18.843498 -4.109466)
			(end 20.93468 -6.115558)
			(stroke
				(width 0.1)
				(type default)
			)
			(layer "F.SilkS")
		)
		(fp_line
			(start 18.84934 -4.7498)
			(end 18.861532 -4.819142)
			(stroke
				(width 0.1)
				(type default)
			)
			(layer "F.SilkS")
		)
		(fp_line
			(start 18.84934 -4.7498)
			(end 18.861532 -4.819142)
			(stroke
				(width 0.1)
				(type default)
			)
			(layer "F.SilkS")
		)
		(fp_line
			(start 18.84934 -4.7498)
			(end 19.289014 -5.171694)
			(stroke
				(width 0.1)
				(type default)
			)
			(layer "F.SilkS")
		)
		(fp_line
			(start 18.84934 -4.7498)
			(end 19.289014 -5.171694)
			(stroke
				(width 0.1)
				(type default)
			)
			(layer "F.SilkS")
		)
		(fp_line
			(start 18.861532 -4.819142)
			(end 18.873978 -4.888484)
			(stroke
				(width 0.1)
				(type default)
			)
			(layer "F.SilkS")
		)
		(fp_line
			(start 18.861532 -4.819142)
			(end 18.873978 -4.888484)
			(stroke
				(width 0.1)
				(type default)
			)
			(layer "F.SilkS")
		)
		(fp_line
			(start 18.861532 -4.819142)
			(end 19.22907 -5.171694)
			(stroke
				(width 0.1)
				(type default)
			)
			(layer "F.SilkS")
		)
		(fp_line
			(start 18.861532 -4.819142)
			(end 19.22907 -5.171694)
			(stroke
				(width 0.1)
				(type default)
			)
			(layer "F.SilkS")
		)
		(fp_line
			(start 18.873978 -4.888484)
			(end 19.168872 -5.171694)
			(stroke
				(width 0.1)
				(type default)
			)
			(layer "F.SilkS")
		)
		(fp_line
			(start 18.873978 -4.888484)
			(end 19.168872 -5.171694)
			(stroke
				(width 0.1)
				(type default)
			)
			(layer "F.SilkS")
		)
		(fp_line
			(start 18.885916 -4.95808)
			(end 18.873978 -4.888484)
			(stroke
				(width 0.1)
				(type default)
			)
			(layer "F.SilkS")
		)
		(fp_line
			(start 18.885916 -4.95808)
			(end 18.873978 -4.888484)
			(stroke
				(width 0.1)
				(type default)
			)
			(layer "F.SilkS")
		)
		(fp_line
			(start 18.898108 -5.027422)
			(end 18.885916 -4.95808)
			(stroke
				(width 0.1)
				(type default)
			)
			(layer "F.SilkS")
		)
		(fp_line
			(start 18.898108 -5.027422)
			(end 18.885916 -4.95808)
			(stroke
				(width 0.1)
				(type default)
			)
			(layer "F.SilkS")
		)
		(fp_line
			(start 18.898108 -5.027422)
			(end 18.9103 -5.097018)
			(stroke
				(width 0.1)
				(type default)
			)
			(layer "F.SilkS")
		)
		(fp_line
			(start 18.898108 -5.027422)
			(end 18.9103 -5.097018)
			(stroke
				(width 0.1)
				(type default)
			)
			(layer "F.SilkS")
		)
		(fp_line
			(start 18.898108 -5.027422)
			(end 19.048476 -5.171694)
			(stroke
				(width 0.1)
				(type default)
			)
			(layer "F.SilkS")
		)
		(fp_line
			(start 18.898108 -5.027422)
			(end 19.048476 -5.171694)
			(stroke
				(width 0.1)
				(type default)
			)
			(layer "F.SilkS")
		)
		(fp_line
			(start 18.90395 -4.109466)
			(end 18.964148 -4.109466)
			(stroke
				(width 0.1)
				(type default)
			)
			(layer "F.SilkS")
		)
		(fp_line
			(start 18.90395 -4.109466)
			(end 18.964148 -4.109466)
			(stroke
				(width 0.1)
				(type default)
			)
			(layer "F.SilkS")
		)
		(fp_line
			(start 18.90395 -4.109466)
			(end 20.922742 -6.04647)
			(stroke
				(width 0.1)
				(type default)
			)
			(layer "F.SilkS")
		)
		(fp_line
			(start 18.90395 -4.109466)
			(end 20.922742 -6.04647)
			(stroke
				(width 0.1)
				(type default)
			)
			(layer "F.SilkS")
		)
		(fp_line
			(start 18.9103 -5.097018)
			(end 18.922492 -5.166106)
			(stroke
				(width 0.1)
				(type default)
			)
			(layer "F.SilkS")
		)
		(fp_line
			(start 18.9103 -5.097018)
			(end 18.922492 -5.166106)
			(stroke
				(width 0.1)
				(type default)
			)
			(layer "F.SilkS")
		)
		(fp_line
			(start 18.9103 -5.097018)
			(end 18.988278 -5.171694)
			(stroke
				(width 0.1)
				(type default)
			)
			(layer "F.SilkS")
		)
		(fp_line
			(start 18.9103 -5.097018)
			(end 18.988278 -5.171694)
			(stroke
				(width 0.1)
				(type default)
			)
			(layer "F.SilkS")
		)
		(fp_line
			(start 18.922492 -5.166106)
			(end 18.923508 -5.171694)
			(stroke
				(width 0.1)
				(type default)
			)
			(layer "F.SilkS")
		)
		(fp_line
			(start 18.922492 -5.166106)
			(end 18.923508 -5.171694)
			(stroke
				(width 0.1)
				(type default)
			)
			(layer "F.SilkS")
		)
		(fp_line
			(start 18.922492 -5.166106)
			(end 18.928334 -5.171694)
			(stroke
				(width 0.1)
				(type default)
			)
			(layer "F.SilkS")
		)
		(fp_line
			(start 18.922492 -5.166106)
			(end 18.928334 -5.171694)
			(stroke
				(width 0.1)
				(type default)
			)
			(layer "F.SilkS")
		)
		(fp_line
			(start 18.923508 -5.171694)
			(end 18.928334 -5.171694)
			(stroke
				(width 0.1)
				(type default)
			)
			(layer "F.SilkS")
		)
		(fp_line
			(start 18.923508 -5.171694)
			(end 18.928334 -5.171694)
			(stroke
				(width 0.1)
				(type default)
			)
			(layer "F.SilkS")
		)
		(fp_line
			(start 18.964148 -4.109466)
			(end 19.024092 -4.109466)
			(stroke
				(width 0.1)
				(type default)
			)
			(layer "F.SilkS")
		)
		(fp_line
			(start 18.964148 -4.109466)
			(end 19.024092 -4.109466)
			(stroke
				(width 0.1)
				(type default)
			)
			(layer "F.SilkS")
		)
		(fp_line
			(start 18.964148 -4.109466)
			(end 20.91055 -5.976874)
			(stroke
				(width 0.1)
				(type default)
			)
			(layer "F.SilkS")
		)
		(fp_line
			(start 18.964148 -4.109466)
			(end 20.91055 -5.976874)
			(stroke
				(width 0.1)
				(type default)
			)
			(layer "F.SilkS")
		)
		(fp_line
			(start 18.988278 -5.171694)
			(end 18.928334 -5.171694)
			(stroke
				(width 0.1)
				(type default)
			)
			(layer "F.SilkS")
		)
		(fp_line
			(start 18.988278 -5.171694)
			(end 18.928334 -5.171694)
			(stroke
				(width 0.1)
				(type default)
			)
			(layer "F.SilkS")
		)
		(fp_line
			(start 19.024092 -4.109466)
			(end 19.08429 -4.109466)
			(stroke
				(width 0.1)
				(type default)
			)
			(layer "F.SilkS")
		)
		(fp_line
			(start 19.024092 -4.109466)
			(end 19.08429 -4.109466)
			(stroke
				(width 0.1)
				(type default)
			)
			(layer "F.SilkS")
		)
		(fp_line
			(start 19.024092 -4.109466)
			(end 20.898104 -5.907278)
			(stroke
				(width 0.1)
				(type default)
			)
			(layer "F.SilkS")
		)
		(fp_line
			(start 19.024092 -4.109466)
			(end 20.898104 -5.907278)
			(stroke
				(width 0.1)
				(type default)
			)
			(layer "F.SilkS")
		)
		(fp_line
			(start 19.048476 -5.171694)
			(end 18.988278 -5.171694)
			(stroke
				(width 0.1)
				(type default)
			)
			(layer "F.SilkS")
		)
		(fp_line
			(start 19.048476 -5.171694)
			(end 18.988278 -5.171694)
			(stroke
				(width 0.1)
				(type default)
			)
			(layer "F.SilkS")
		)
		(fp_line
			(start 19.048476 -5.171694)
			(end 19.10842 -5.171694)
			(stroke
				(width 0.1)
				(type default)
			)
			(layer "F.SilkS")
		)
		(fp_line
			(start 19.048476 -5.171694)
			(end 19.10842 -5.171694)
			(stroke
				(width 0.1)
				(type default)
			)
			(layer "F.SilkS")
		)
		(fp_line
			(start 19.074638 -1.79197)
			(end 20.399248 -3.062478)
			(stroke
				(width 0.1)
				(type default)
			)
			(layer "F.SilkS")
		)
		(fp_line
			(start 19.074638 -1.79197)
			(end 20.399248 -3.062478)
			(stroke
				(width 0.1)
				(type default)
			)
			(layer "F.SilkS")
		)
		(fp_line
			(start 19.077178 -1.851914)
			(end 20.41144 -3.13182)
			(stroke
				(width 0.1)
				(type default)
			)
			(layer "F.SilkS")
		)
		(fp_line
			(start 19.077178 -1.851914)
			(end 20.41144 -3.13182)
			(stroke
				(width 0.1)
				(type default)
			)
			(layer "F.SilkS")
		)
		(fp_line
			(start 19.078448 -1.737868)
			(end 20.38731 -2.99339)
			(stroke
				(width 0.1)
				(type default)
			)
			(layer "F.SilkS")
		)
		(fp_line
			(start 19.078448 -1.737868)
			(end 20.38731 -2.99339)
			(stroke
				(width 0.1)
				(type default)
			)
			(layer "F.SilkS")
		)
		(fp_line
			(start 19.082258 -1.683512)
			(end 20.374864 -2.923794)
			(stroke
				(width 0.1)
				(type default)
			)
			(layer "F.SilkS")
		)
		(fp_line
			(start 19.082258 -1.683512)
			(end 20.374864 -2.923794)
			(stroke
				(width 0.1)
				(type default)
			)
			(layer "F.SilkS")
		)
		(fp_line
			(start 19.083274 -1.915668)
			(end 20.423886 -3.201416)
			(stroke
				(width 0.1)
				(type default)
			)
			(layer "F.SilkS")
		)
		(fp_line
			(start 19.083274 -1.915668)
			(end 20.423886 -3.201416)
			(stroke
				(width 0.1)
				(type default)
			)
			(layer "F.SilkS")
		)
		(fp_line
			(start 19.08429 -4.109466)
			(end 19.144234 -4.109466)
			(stroke
				(width 0.1)
				(type default)
			)
			(layer "F.SilkS")
		)
		(fp_line
			(start 19.08429 -4.109466)
			(end 19.144234 -4.109466)
			(stroke
				(width 0.1)
				(type default)
			)
			(layer "F.SilkS")
		)
		(fp_line
			(start 19.08429 -4.109466)
			(end 20.886166 -5.837936)
			(stroke
				(width 0.1)
				(type default)
			)
			(layer "F.SilkS")
		)
		(fp_line
			(start 19.08429 -4.109466)
			(end 20.886166 -5.837936)
			(stroke
				(width 0.1)
				(type default)
			)
			(layer "F.SilkS")
		)
		(fp_line
			(start 19.086068 -1.62941)
			(end 20.362926 -2.854198)
			(stroke
				(width 0.1)
				(type default)
			)
			(layer "F.SilkS")
		)
		(fp_line
			(start 19.086068 -1.62941)
			(end 20.362926 -2.854198)
			(stroke
				(width 0.1)
				(type default)
			)
			(layer "F.SilkS")
		)
		(fp_line
			(start 19.089624 -1.575308)
			(end 20.35048 -2.784856)
			(stroke
				(width 0.1)
				(type default)
			)
			(layer "F.SilkS")
		)
		(fp_line
			(start 19.089624 -1.575308)
			(end 20.35048 -2.784856)
			(stroke
				(width 0.1)
				(type default)
			)
			(layer "F.SilkS")
		)
		(fp_line
			(start 19.089878 -1.979676)
			(end 20.435824 -3.270758)
			(stroke
				(width 0.1)
				(type default)
			)
			(layer "F.SilkS")
		)
		(fp_line
			(start 19.089878 -1.979676)
			(end 20.435824 -3.270758)
			(stroke
				(width 0.1)
				(type default)
			)
			(layer "F.SilkS")
		)
		(fp_line
			(start 19.095974 -2.043176)
			(end 20.44827 -3.340354)
			(stroke
				(width 0.1)
				(type default)
			)
			(layer "F.SilkS")
		)
		(fp_line
			(start 19.095974 -2.043176)
			(end 20.44827 -3.340354)
			(stroke
				(width 0.1)
				(type default)
			)
			(layer "F.SilkS")
		)
		(fp_line
			(start 19.100292 -1.528064)
			(end 20.338288 -2.715768)
			(stroke
				(width 0.1)
				(type default)
			)
			(layer "F.SilkS")
		)
		(fp_line
			(start 19.100292 -1.528064)
			(end 20.338288 -2.715768)
			(stroke
				(width 0.1)
				(type default)
			)
			(layer "F.SilkS")
		)
		(fp_line
			(start 19.10461 -2.108962)
			(end 20.460462 -3.409442)
			(stroke
				(width 0.1)
				(type default)
			)
			(layer "F.SilkS")
		)
		(fp_line
			(start 19.10461 -2.108962)
			(end 20.460462 -3.409442)
			(stroke
				(width 0.1)
				(type default)
			)
			(layer "F.SilkS")
		)
		(fp_line
			(start 19.10842 -5.171694)
			(end 18.885916 -4.95808)
			(stroke
				(width 0.1)
				(type default)
			)
			(layer "F.SilkS")
		)
		(fp_line
			(start 19.10842 -5.171694)
			(end 18.885916 -4.95808)
			(stroke
				(width 0.1)
				(type default)
			)
			(layer "F.SilkS")
		)
		(fp_line
			(start 19.10842 -5.171694)
			(end 19.168872 -5.171694)
			(stroke
				(width 0.1)
				(type default)
			)
			(layer "F.SilkS")
		)
		(fp_line
			(start 19.10842 -5.171694)
			(end 19.168872 -5.171694)
			(stroke
				(width 0.1)
				(type default)
			)
			(layer "F.SilkS")
		)
		(fp_line
			(start 19.112738 -1.48209)
			(end 20.32635 -2.646172)
			(stroke
				(width 0.1)
				(type default)
			)
			(layer "F.SilkS")
		)
		(fp_line
			(start 19.112738 -1.48209)
			(end 20.32635 -2.646172)
			(stroke
				(width 0.1)
				(type default)
			)
			(layer "F.SilkS")
		)
		(fp_line
			(start 19.116802 -2.178304)
			(end 19.10461 -2.108962)
			(stroke
				(width 0.1)
				(type default)
			)
			(layer "F.SilkS")
		)
		(fp_line
			(start 19.116802 -2.178304)
			(end 19.10461 -2.108962)
			(stroke
				(width 0.1)
				(type default)
			)
			(layer "F.SilkS")
		)
		(fp_line
			(start 19.116802 -2.178304)
			(end 20.4724 -3.479038)
			(stroke
				(width 0.1)
				(type default)
			)
			(layer "F.SilkS")
		)
		(fp_line
			(start 19.116802 -2.178304)
			(end 20.4724 -3.479038)
			(stroke
				(width 0.1)
				(type default)
			)
			(layer "F.SilkS")
		)
		(fp_line
			(start 19.12493 -1.436116)
			(end 20.313904 -2.576576)
			(stroke
				(width 0.1)
				(type default)
			)
			(layer "F.SilkS")
		)
		(fp_line
			(start 19.12493 -1.436116)
			(end 20.313904 -2.576576)
			(stroke
				(width 0.1)
				(type default)
			)
			(layer "F.SilkS")
		)
		(fp_line
			(start 19.12874 -2.2479)
			(end 19.116802 -2.178304)
			(stroke
				(width 0.1)
				(type default)
			)
			(layer "F.SilkS")
		)
		(fp_line
			(start 19.12874 -2.2479)
			(end 19.116802 -2.178304)
			(stroke
				(width 0.1)
				(type default)
			)
			(layer "F.SilkS")
		)
		(fp_line
			(start 19.12874 -2.2479)
			(end 19.141186 -2.317242)
			(stroke
				(width 0.1)
				(type default)
			)
			(layer "F.SilkS")
		)
		(fp_line
			(start 19.12874 -2.2479)
			(end 19.141186 -2.317242)
			(stroke
				(width 0.1)
				(type default)
			)
			(layer "F.SilkS")
		)
		(fp_line
			(start 19.12874 -2.2479)
			(end 20.484846 -3.548634)
			(stroke
				(width 0.1)
				(type default)
			)
			(layer "F.SilkS")
		)
		(fp_line
			(start 19.12874 -2.2479)
			(end 20.484846 -3.548634)
			(stroke
				(width 0.1)
				(type default)
			)
			(layer "F.SilkS")
		)
		(fp_line
			(start 19.137376 -1.390396)
			(end 20.301966 -2.507234)
			(stroke
				(width 0.1)
				(type default)
			)
			(layer "F.SilkS")
		)
		(fp_line
			(start 19.137376 -1.390396)
			(end 20.301966 -2.507234)
			(stroke
				(width 0.1)
				(type default)
			)
			(layer "F.SilkS")
		)
		(fp_line
			(start 19.144234 -4.109466)
			(end 19.204686 -4.109466)
			(stroke
				(width 0.1)
				(type default)
			)
			(layer "F.SilkS")
		)
		(fp_line
			(start 19.144234 -4.109466)
			(end 19.204686 -4.109466)
			(stroke
				(width 0.1)
				(type default)
			)
			(layer "F.SilkS")
		)
		(fp_line
			(start 19.144234 -4.109466)
			(end 20.874228 -5.768594)
			(stroke
				(width 0.1)
				(type default)
			)
			(layer "F.SilkS")
		)
		(fp_line
			(start 19.144234 -4.109466)
			(end 20.874228 -5.768594)
			(stroke
				(width 0.1)
				(type default)
			)
			(layer "F.SilkS")
		)
		(fp_line
			(start 19.149822 -1.344676)
			(end 20.28952 -2.437892)
			(stroke
				(width 0.1)
				(type default)
			)
			(layer "F.SilkS")
		)
		(fp_line
			(start 19.149822 -1.344676)
			(end 20.28952 -2.437892)
			(stroke
				(width 0.1)
				(type default)
			)
			(layer "F.SilkS")
		)
		(fp_line
			(start 19.153378 -2.386584)
			(end 19.141186 -2.317242)
			(stroke
				(width 0.1)
				(type default)
			)
			(layer "F.SilkS")
		)
		(fp_line
			(start 19.153378 -2.386584)
			(end 19.141186 -2.317242)
			(stroke
				(width 0.1)
				(type default)
			)
			(layer "F.SilkS")
		)
		(fp_line
			(start 19.153378 -2.386584)
			(end 20.50923 -3.687064)
			(stroke
				(width 0.1)
				(type default)
			)
			(layer "F.SilkS")
		)
		(fp_line
			(start 19.153378 -2.386584)
			(end 20.50923 -3.687064)
			(stroke
				(width 0.1)
				(type default)
			)
			(layer "F.SilkS")
		)
		(fp_line
			(start 19.165316 -2.455926)
			(end 19.153378 -2.386584)
			(stroke
				(width 0.1)
				(type default)
			)
			(layer "F.SilkS")
		)
		(fp_line
			(start 19.165316 -2.455926)
			(end 19.153378 -2.386584)
			(stroke
				(width 0.1)
				(type default)
			)
			(layer "F.SilkS")
		)
		(fp_line
			(start 19.165316 -2.455926)
			(end 20.521422 -3.75666)
			(stroke
				(width 0.1)
				(type default)
			)
			(layer "F.SilkS")
		)
		(fp_line
			(start 19.165316 -2.455926)
			(end 20.521422 -3.75666)
			(stroke
				(width 0.1)
				(type default)
			)
			(layer "F.SilkS")
		)
		(fp_line
			(start 19.170142 -1.306322)
			(end 20.278344 -2.369312)
			(stroke
				(width 0.1)
				(type default)
			)
			(layer "F.SilkS")
		)
		(fp_line
			(start 19.170142 -1.306322)
			(end 20.278344 -2.369312)
			(stroke
				(width 0.1)
				(type default)
			)
			(layer "F.SilkS")
		)
		(fp_line
			(start 19.177762 -2.525522)
			(end 19.165316 -2.455926)
			(stroke
				(width 0.1)
				(type default)
			)
			(layer "F.SilkS")
		)
		(fp_line
			(start 19.177762 -2.525522)
			(end 19.165316 -2.455926)
			(stroke
				(width 0.1)
				(type default)
			)
			(layer "F.SilkS")
		)
		(fp_line
			(start 19.177762 -2.525522)
			(end 20.533614 -3.826256)
			(stroke
				(width 0.1)
				(type default)
			)
			(layer "F.SilkS")
		)
		(fp_line
			(start 19.177762 -2.525522)
			(end 20.533614 -3.826256)
			(stroke
				(width 0.1)
				(type default)
			)
			(layer "F.SilkS")
		)
		(fp_line
			(start 19.1897 -2.594864)
			(end 19.177762 -2.525522)
			(stroke
				(width 0.1)
				(type default)
			)
			(layer "F.SilkS")
		)
		(fp_line
			(start 19.1897 -2.594864)
			(end 19.177762 -2.525522)
			(stroke
				(width 0.1)
				(type default)
			)
			(layer "F.SilkS")
		)
		(fp_line
			(start 19.1897 -2.594864)
			(end 20.545806 -3.895344)
			(stroke
				(width 0.1)
				(type default)
			)
			(layer "F.SilkS")
		)
		(fp_line
			(start 19.1897 -2.594864)
			(end 20.545806 -3.895344)
			(stroke
				(width 0.1)
				(type default)
			)
			(layer "F.SilkS")
		)
		(fp_line
			(start 19.190462 -1.267968)
			(end 20.270216 -2.303526)
			(stroke
				(width 0.1)
				(type default)
			)
			(layer "F.SilkS")
		)
		(fp_line
			(start 19.190462 -1.267968)
			(end 20.270216 -2.303526)
			(stroke
				(width 0.1)
				(type default)
			)
			(layer "F.SilkS")
		)
		(fp_line
			(start 19.201892 -2.663952)
			(end 19.1897 -2.594864)
			(stroke
				(width 0.1)
				(type default)
			)
			(layer "F.SilkS")
		)
		(fp_line
			(start 19.201892 -2.663952)
			(end 19.1897 -2.594864)
			(stroke
				(width 0.1)
				(type default)
			)
			(layer "F.SilkS")
		)
		(fp_line
			(start 19.201892 -2.663952)
			(end 20.557744 -3.96494)
			(stroke
				(width 0.1)
				(type default)
			)
			(layer "F.SilkS")
		)
		(fp_line
			(start 19.201892 -2.663952)
			(end 20.557744 -3.96494)
			(stroke
				(width 0.1)
				(type default)
			)
			(layer "F.SilkS")
		)
		(fp_line
			(start 19.204686 -4.109466)
			(end 19.264884 -4.109466)
			(stroke
				(width 0.1)
				(type default)
			)
			(layer "F.SilkS")
		)
		(fp_line
			(start 19.204686 -4.109466)
			(end 19.264884 -4.109466)
			(stroke
				(width 0.1)
				(type default)
			)
			(layer "F.SilkS")
		)
		(fp_line
			(start 19.204686 -4.109466)
			(end 20.861782 -5.699252)
			(stroke
				(width 0.1)
				(type default)
			)
			(layer "F.SilkS")
		)
		(fp_line
			(start 19.204686 -4.109466)
			(end 20.861782 -5.699252)
			(stroke
				(width 0.1)
				(type default)
			)
			(layer "F.SilkS")
		)
		(fp_line
			(start 19.210782 -1.229868)
			(end 20.26285 -2.239264)
			(stroke
				(width 0.1)
				(type default)
			)
			(layer "F.SilkS")
		)
		(fp_line
			(start 19.210782 -1.229868)
			(end 20.26285 -2.239264)
			(stroke
				(width 0.1)
				(type default)
			)
			(layer "F.SilkS")
		)
		(fp_line
			(start 19.21383 -2.733548)
			(end 19.201892 -2.663952)
			(stroke
				(width 0.1)
				(type default)
			)
			(layer "F.SilkS")
		)
		(fp_line
			(start 19.21383 -2.733548)
			(end 19.201892 -2.663952)
			(stroke
				(width 0.1)
				(type default)
			)
			(layer "F.SilkS")
		)
		(fp_line
			(start 19.21383 -2.733548)
			(end 20.57019 -4.034282)
			(stroke
				(width 0.1)
				(type default)
			)
			(layer "F.SilkS")
		)
		(fp_line
			(start 19.21383 -2.733548)
			(end 20.57019 -4.034282)
			(stroke
				(width 0.1)
				(type default)
			)
			(layer "F.SilkS")
		)
		(fp_line
			(start 19.226276 -2.80289)
			(end 19.21383 -2.733548)
			(stroke
				(width 0.1)
				(type default)
			)
			(layer "F.SilkS")
		)
		(fp_line
			(start 19.226276 -2.80289)
			(end 19.21383 -2.733548)
			(stroke
				(width 0.1)
				(type default)
			)
			(layer "F.SilkS")
		)
		(fp_line
			(start 19.226276 -2.80289)
			(end 20.582382 -4.103878)
			(stroke
				(width 0.1)
				(type default)
			)
			(layer "F.SilkS")
		)
		(fp_line
			(start 19.226276 -2.80289)
			(end 20.582382 -4.103878)
			(stroke
				(width 0.1)
				(type default)
			)
			(layer "F.SilkS")
		)
		(fp_line
			(start 19.22907 -5.171694)
			(end 19.168872 -5.171694)
			(stroke
				(width 0.1)
				(type default)
			)
			(layer "F.SilkS")
		)
		(fp_line
			(start 19.22907 -5.171694)
			(end 19.168872 -5.171694)
			(stroke
				(width 0.1)
				(type default)
			)
			(layer "F.SilkS")
		)
		(fp_line
			(start 19.230848 -1.191514)
			(end 20.263358 -2.181606)
			(stroke
				(width 0.1)
				(type default)
			)
			(layer "F.SilkS")
		)
		(fp_line
			(start 19.230848 -1.191514)
			(end 20.263358 -2.181606)
			(stroke
				(width 0.1)
				(type default)
			)
			(layer "F.SilkS")
		)
		(fp_line
			(start 19.238468 -2.872232)
			(end 19.226276 -2.80289)
			(stroke
				(width 0.1)
				(type default)
			)
			(layer "F.SilkS")
		)
		(fp_line
			(start 19.238468 -2.872232)
			(end 19.226276 -2.80289)
			(stroke
				(width 0.1)
				(type default)
			)
			(layer "F.SilkS")
		)
		(fp_line
			(start 19.238468 -2.872232)
			(end 21.635466 -5.171694)
			(stroke
				(width 0.1)
				(type default)
			)
			(layer "F.SilkS")
		)
		(fp_line
			(start 19.238468 -2.872232)
			(end 21.635466 -5.171694)
			(stroke
				(width 0.1)
				(type default)
			)
			(layer "F.SilkS")
		)
		(fp_line
			(start 19.250406 -2.941574)
			(end 19.238468 -2.872232)
			(stroke
				(width 0.1)
				(type default)
			)
			(layer "F.SilkS")
		)
		(fp_line
			(start 19.250406 -2.941574)
			(end 19.238468 -2.872232)
			(stroke
				(width 0.1)
				(type default)
			)
			(layer "F.SilkS")
		)
		(fp_line
			(start 19.25193 -1.153922)
			(end 20.265136 -2.125726)
			(stroke
				(width 0.1)
				(type default)
			)
			(layer "F.SilkS")
		)
		(fp_line
			(start 19.25193 -1.153922)
			(end 20.265136 -2.125726)
			(stroke
				(width 0.1)
				(type default)
			)
			(layer "F.SilkS")
		)
		(fp_line
			(start 19.262852 -3.01117)
			(end 19.250406 -2.941574)
			(stroke
				(width 0.1)
				(type default)
			)
			(layer "F.SilkS")
		)
		(fp_line
			(start 19.262852 -3.01117)
			(end 19.250406 -2.941574)
			(stroke
				(width 0.1)
				(type default)
			)
			(layer "F.SilkS")
		)
		(fp_line
			(start 19.264884 -4.109466)
			(end 19.324828 -4.109466)
			(stroke
				(width 0.1)
				(type default)
			)
			(layer "F.SilkS")
		)
		(fp_line
			(start 19.264884 -4.109466)
			(end 19.324828 -4.109466)
			(stroke
				(width 0.1)
				(type default)
			)
			(layer "F.SilkS")
		)
		(fp_line
			(start 19.264884 -4.109466)
			(end 20.84959 -5.629656)
			(stroke
				(width 0.1)
				(type default)
			)
			(layer "F.SilkS")
		)
		(fp_line
			(start 19.264884 -4.109466)
			(end 20.84959 -5.629656)
			(stroke
				(width 0.1)
				(type default)
			)
			(layer "F.SilkS")
		)
		(fp_line
			(start 19.27479 -3.080512)
			(end 19.262852 -3.01117)
			(stroke
				(width 0.1)
				(type default)
			)
			(layer "F.SilkS")
		)
		(fp_line
			(start 19.27479 -3.080512)
			(end 19.262852 -3.01117)
			(stroke
				(width 0.1)
				(type default)
			)
			(layer "F.SilkS")
		)
		(fp_line
			(start 19.279616 -1.122934)
			(end 20.274534 -2.077212)
			(stroke
				(width 0.1)
				(type default)
			)
			(layer "F.SilkS")
		)
		(fp_line
			(start 19.279616 -1.122934)
			(end 20.274534 -2.077212)
			(stroke
				(width 0.1)
				(type default)
			)
			(layer "F.SilkS")
		)
		(fp_line
			(start 19.286982 -3.149854)
			(end 19.27479 -3.080512)
			(stroke
				(width 0.1)
				(type default)
			)
			(layer "F.SilkS")
		)
		(fp_line
			(start 19.286982 -3.149854)
			(end 19.27479 -3.080512)
			(stroke
				(width 0.1)
				(type default)
			)
			(layer "F.SilkS")
		)
		(fp_line
			(start 19.289014 -5.171694)
			(end 19.22907 -5.171694)
			(stroke
				(width 0.1)
				(type default)
			)
			(layer "F.SilkS")
		)
		(fp_line
			(start 19.289014 -5.171694)
			(end 19.22907 -5.171694)
			(stroke
				(width 0.1)
				(type default)
			)
			(layer "F.SilkS")
		)
		(fp_line
			(start 19.299428 -3.218942)
			(end 19.286982 -3.149854)
			(stroke
				(width 0.1)
				(type default)
			)
			(layer "F.SilkS")
		)
		(fp_line
			(start 19.299428 -3.218942)
			(end 19.286982 -3.149854)
			(stroke
				(width 0.1)
				(type default)
			)
			(layer "F.SilkS")
		)
		(fp_line
			(start 19.307556 -1.091946)
			(end 20.287488 -2.031746)
			(stroke
				(width 0.1)
				(type default)
			)
			(layer "F.SilkS")
		)
		(fp_line
			(start 19.307556 -1.091946)
			(end 20.287488 -2.031746)
			(stroke
				(width 0.1)
				(type default)
			)
			(layer "F.SilkS")
		)
		(fp_line
			(start 19.311366 -3.288538)
			(end 19.299428 -3.218942)
			(stroke
				(width 0.1)
				(type default)
			)
			(layer "F.SilkS")
		)
		(fp_line
			(start 19.311366 -3.288538)
			(end 19.299428 -3.218942)
			(stroke
				(width 0.1)
				(type default)
			)
			(layer "F.SilkS")
		)
		(fp_line
			(start 19.323558 -3.358134)
			(end 19.311366 -3.288538)
			(stroke
				(width 0.1)
				(type default)
			)
			(layer "F.SilkS")
		)
		(fp_line
			(start 19.323558 -3.358134)
			(end 19.311366 -3.288538)
			(stroke
				(width 0.1)
				(type default)
			)
			(layer "F.SilkS")
		)
		(fp_line
			(start 19.324828 -4.109466)
			(end 19.385026 -4.109466)
			(stroke
				(width 0.1)
				(type default)
			)
			(layer "F.SilkS")
		)
		(fp_line
			(start 19.324828 -4.109466)
			(end 19.385026 -4.109466)
			(stroke
				(width 0.1)
				(type default)
			)
			(layer "F.SilkS")
		)
		(fp_line
			(start 19.324828 -4.109466)
			(end 20.837144 -5.560314)
			(stroke
				(width 0.1)
				(type default)
			)
			(layer "F.SilkS")
		)
		(fp_line
			(start 19.324828 -4.109466)
			(end 20.837144 -5.560314)
			(stroke
				(width 0.1)
				(type default)
			)
			(layer "F.SilkS")
		)
		(fp_line
			(start 19.335496 -1.061212)
			(end 20.307046 -1.992884)
			(stroke
				(width 0.1)
				(type default)
			)
			(layer "F.SilkS")
		)
		(fp_line
			(start 19.335496 -1.061212)
			(end 20.307046 -1.992884)
			(stroke
				(width 0.1)
				(type default)
			)
			(layer "F.SilkS")
		)
		(fp_line
			(start 19.33575 -3.427476)
			(end 19.323558 -3.358134)
			(stroke
				(width 0.1)
				(type default)
			)
			(layer "F.SilkS")
		)
		(fp_line
			(start 19.33575 -3.427476)
			(end 19.323558 -3.358134)
			(stroke
				(width 0.1)
				(type default)
			)
			(layer "F.SilkS")
		)
		(fp_line
			(start 19.347942 -3.496564)
			(end 19.33575 -3.427476)
			(stroke
				(width 0.1)
				(type default)
			)
			(layer "F.SilkS")
		)
		(fp_line
			(start 19.347942 -3.496564)
			(end 19.33575 -3.427476)
			(stroke
				(width 0.1)
				(type default)
			)
			(layer "F.SilkS")
		)
		(fp_line
			(start 19.349212 -5.171694)
			(end 19.289014 -5.171694)
			(stroke
				(width 0.1)
				(type default)
			)
			(layer "F.SilkS")
		)
		(fp_line
			(start 19.349212 -5.171694)
			(end 19.289014 -5.171694)
			(stroke
				(width 0.1)
				(type default)
			)
			(layer "F.SilkS")
		)
		(fp_line
			(start 19.35988 -3.56616)
			(end 19.347942 -3.496564)
			(stroke
				(width 0.1)
				(type default)
			)
			(layer "F.SilkS")
		)
		(fp_line
			(start 19.35988 -3.56616)
			(end 19.347942 -3.496564)
			(stroke
				(width 0.1)
				(type default)
			)
			(layer "F.SilkS")
		)
		(fp_line
			(start 19.363436 -1.030224)
			(end 20.332446 -1.959356)
			(stroke
				(width 0.1)
				(type default)
			)
			(layer "F.SilkS")
		)
		(fp_line
			(start 19.363436 -1.030224)
			(end 20.332446 -1.959356)
			(stroke
				(width 0.1)
				(type default)
			)
			(layer "F.SilkS")
		)
		(fp_line
			(start 19.372326 -3.635502)
			(end 19.35988 -3.56616)
			(stroke
				(width 0.1)
				(type default)
			)
			(layer "F.SilkS")
		)
		(fp_line
			(start 19.372326 -3.635502)
			(end 19.35988 -3.56616)
			(stroke
				(width 0.1)
				(type default)
			)
			(layer "F.SilkS")
		)
		(fp_line
			(start 19.384518 -3.704844)
			(end 19.372326 -3.635502)
			(stroke
				(width 0.1)
				(type default)
			)
			(layer "F.SilkS")
		)
		(fp_line
			(start 19.384518 -3.704844)
			(end 19.372326 -3.635502)
			(stroke
				(width 0.1)
				(type default)
			)
			(layer "F.SilkS")
		)
		(fp_line
			(start 19.385026 -4.109466)
			(end 19.445478 -4.109466)
			(stroke
				(width 0.1)
				(type default)
			)
			(layer "F.SilkS")
		)
		(fp_line
			(start 19.385026 -4.109466)
			(end 19.445478 -4.109466)
			(stroke
				(width 0.1)
				(type default)
			)
			(layer "F.SilkS")
		)
		(fp_line
			(start 19.385026 -4.109466)
			(end 20.825206 -5.490972)
			(stroke
				(width 0.1)
				(type default)
			)
			(layer "F.SilkS")
		)
		(fp_line
			(start 19.385026 -4.109466)
			(end 20.825206 -5.490972)
			(stroke
				(width 0.1)
				(type default)
			)
			(layer "F.SilkS")
		)
		(fp_line
			(start 19.392646 -1.000252)
			(end 20.362164 -1.9304)
			(stroke
				(width 0.1)
				(type default)
			)
			(layer "F.SilkS")
		)
		(fp_line
			(start 19.392646 -1.000252)
			(end 20.362164 -1.9304)
			(stroke
				(width 0.1)
				(type default)
			)
			(layer "F.SilkS")
		)
		(fp_line
			(start 19.396456 -3.774186)
			(end 19.384518 -3.704844)
			(stroke
				(width 0.1)
				(type default)
			)
			(layer "F.SilkS")
		)
		(fp_line
			(start 19.396456 -3.774186)
			(end 19.384518 -3.704844)
			(stroke
				(width 0.1)
				(type default)
			)
			(layer "F.SilkS")
		)
		(fp_line
			(start 19.408902 -3.843528)
			(end 19.396456 -3.774186)
			(stroke
				(width 0.1)
				(type default)
			)
			(layer "F.SilkS")
		)
		(fp_line
			(start 19.408902 -3.843528)
			(end 19.396456 -3.774186)
			(stroke
				(width 0.1)
				(type default)
			)
			(layer "F.SilkS")
		)
		(fp_line
			(start 19.409664 -5.171694)
			(end 19.349212 -5.171694)
			(stroke
				(width 0.1)
				(type default)
			)
			(layer "F.SilkS")
		)
		(fp_line
			(start 19.409664 -5.171694)
			(end 19.349212 -5.171694)
			(stroke
				(width 0.1)
				(type default)
			)
			(layer "F.SilkS")
		)
		(fp_line
			(start 19.42084 -3.913124)
			(end 19.408902 -3.843528)
			(stroke
				(width 0.1)
				(type default)
			)
			(layer "F.SilkS")
		)
		(fp_line
			(start 19.42084 -3.913124)
			(end 19.408902 -3.843528)
			(stroke
				(width 0.1)
				(type default)
			)
			(layer "F.SilkS")
		)
		(fp_line
			(start 19.42084 -3.913124)
			(end 20.776184 -5.21335)
			(stroke
				(width 0.1)
				(type default)
			)
			(layer "F.SilkS")
		)
		(fp_line
			(start 19.42084 -3.913124)
			(end 20.776184 -5.21335)
			(stroke
				(width 0.1)
				(type default)
			)
			(layer "F.SilkS")
		)
		(fp_line
			(start 19.42846 -0.976884)
			(end 20.400772 -1.909572)
			(stroke
				(width 0.1)
				(type default)
			)
			(layer "F.SilkS")
		)
		(fp_line
			(start 19.42846 -0.976884)
			(end 20.400772 -1.909572)
			(stroke
				(width 0.1)
				(type default)
			)
			(layer "F.SilkS")
		)
		(fp_line
			(start 19.433032 -3.982466)
			(end 19.42084 -3.913124)
			(stroke
				(width 0.1)
				(type default)
			)
			(layer "F.SilkS")
		)
		(fp_line
			(start 19.433032 -3.982466)
			(end 19.42084 -3.913124)
			(stroke
				(width 0.1)
				(type default)
			)
			(layer "F.SilkS")
		)
		(fp_line
			(start 19.445478 -4.109466)
			(end 19.455384 -4.109466)
			(stroke
				(width 0.1)
				(type default)
			)
			(layer "F.SilkS")
		)
		(fp_line
			(start 19.445478 -4.109466)
			(end 19.455384 -4.109466)
			(stroke
				(width 0.1)
				(type default)
			)
			(layer "F.SilkS")
		)
		(fp_line
			(start 19.445478 -4.109466)
			(end 20.81276 -5.421376)
			(stroke
				(width 0.1)
				(type default)
			)
			(layer "F.SilkS")
		)
		(fp_line
			(start 19.445478 -4.109466)
			(end 20.81276 -5.421376)
			(stroke
				(width 0.1)
				(type default)
			)
			(layer "F.SilkS")
		)
		(fp_line
			(start 19.445478 -4.051554)
			(end 19.433032 -3.982466)
			(stroke
				(width 0.1)
				(type default)
			)
			(layer "F.SilkS")
		)
		(fp_line
			(start 19.445478 -4.051554)
			(end 19.433032 -3.982466)
			(stroke
				(width 0.1)
				(type default)
			)
			(layer "F.SilkS")
		)
		(fp_line
			(start 19.455384 -4.109466)
			(end 19.445478 -4.051554)
			(stroke
				(width 0.1)
				(type default)
			)
			(layer "F.SilkS")
		)
		(fp_line
			(start 19.455384 -4.109466)
			(end 19.445478 -4.051554)
			(stroke
				(width 0.1)
				(type default)
			)
			(layer "F.SilkS")
		)
		(fp_line
			(start 19.46402 -0.953516)
			(end 20.442428 -1.892046)
			(stroke
				(width 0.1)
				(type default)
			)
			(layer "F.SilkS")
		)
		(fp_line
			(start 19.46402 -0.953516)
			(end 20.442428 -1.892046)
			(stroke
				(width 0.1)
				(type default)
			)
			(layer "F.SilkS")
		)
		(fp_line
			(start 19.469608 -5.171694)
			(end 19.409664 -5.171694)
			(stroke
				(width 0.1)
				(type default)
			)
			(layer "F.SilkS")
		)
		(fp_line
			(start 19.469608 -5.171694)
			(end 19.409664 -5.171694)
			(stroke
				(width 0.1)
				(type default)
			)
			(layer "F.SilkS")
		)
		(fp_line
			(start 19.500088 -0.930148)
			(end 20.491704 -1.881378)
			(stroke
				(width 0.1)
				(type default)
			)
			(layer "F.SilkS")
		)
		(fp_line
			(start 19.500088 -0.930148)
			(end 20.491704 -1.881378)
			(stroke
				(width 0.1)
				(type default)
			)
			(layer "F.SilkS")
		)
		(fp_line
			(start 19.529806 -5.171694)
			(end 19.469608 -5.171694)
			(stroke
				(width 0.1)
				(type default)
			)
			(layer "F.SilkS")
		)
		(fp_line
			(start 19.529806 -5.171694)
			(end 19.469608 -5.171694)
			(stroke
				(width 0.1)
				(type default)
			)
			(layer "F.SilkS")
		)
		(fp_line
			(start 19.536156 -0.906526)
			(end 20.545044 -1.874774)
			(stroke
				(width 0.1)
				(type default)
			)
			(layer "F.SilkS")
		)
		(fp_line
			(start 19.536156 -0.906526)
			(end 20.545044 -1.874774)
			(stroke
				(width 0.1)
				(type default)
			)
			(layer "F.SilkS")
		)
		(fp_line
			(start 19.574002 -0.88519)
			(end 20.60194 -1.871726)
			(stroke
				(width 0.1)
				(type default)
			)
			(layer "F.SilkS")
		)
		(fp_line
			(start 19.574002 -0.88519)
			(end 20.60194 -1.871726)
			(stroke
				(width 0.1)
				(type default)
			)
			(layer "F.SilkS")
		)
		(fp_line
			(start 19.58975 -5.171694)
			(end 19.529806 -5.171694)
			(stroke
				(width 0.1)
				(type default)
			)
			(layer "F.SilkS")
		)
		(fp_line
			(start 19.58975 -5.171694)
			(end 19.529806 -5.171694)
			(stroke
				(width 0.1)
				(type default)
			)
			(layer "F.SilkS")
		)
		(fp_line
			(start 19.58975 -5.171694)
			(end 19.641566 -5.171694)
			(stroke
				(width 0.1)
				(type default)
			)
			(layer "F.SilkS")
		)
		(fp_line
			(start 19.58975 -5.171694)
			(end 19.641566 -5.171694)
			(stroke
				(width 0.1)
				(type default)
			)
			(layer "F.SilkS")
		)
		(fp_line
			(start 19.617944 -0.870458)
			(end 20.669504 -1.878838)
			(stroke
				(width 0.1)
				(type default)
			)
			(layer "F.SilkS")
		)
		(fp_line
			(start 19.617944 -0.870458)
			(end 20.669504 -1.878838)
			(stroke
				(width 0.1)
				(type default)
			)
			(layer "F.SilkS")
		)
		(fp_line
			(start 19.641566 -5.171694)
			(end 19.651726 -5.23113)
			(stroke
				(width 0.1)
				(type default)
			)
			(layer "F.SilkS")
		)
		(fp_line
			(start 19.641566 -5.171694)
			(end 19.651726 -5.23113)
			(stroke
				(width 0.1)
				(type default)
			)
			(layer "F.SilkS")
		)
		(fp_line
			(start 19.662902 -0.855218)
			(end 20.738084 -1.886966)
			(stroke
				(width 0.1)
				(type default)
			)
			(layer "F.SilkS")
		)
		(fp_line
			(start 19.662902 -0.855218)
			(end 20.738084 -1.886966)
			(stroke
				(width 0.1)
				(type default)
			)
			(layer "F.SilkS")
		)
		(fp_line
			(start 19.664172 -5.300472)
			(end 19.651726 -5.23113)
			(stroke
				(width 0.1)
				(type default)
			)
			(layer "F.SilkS")
		)
		(fp_line
			(start 19.664172 -5.300472)
			(end 19.651726 -5.23113)
			(stroke
				(width 0.1)
				(type default)
			)
			(layer "F.SilkS")
		)
		(fp_line
			(start 19.676364 -5.370068)
			(end 19.664172 -5.300472)
			(stroke
				(width 0.1)
				(type default)
			)
			(layer "F.SilkS")
		)
		(fp_line
			(start 19.676364 -5.370068)
			(end 19.664172 -5.300472)
			(stroke
				(width 0.1)
				(type default)
			)
			(layer "F.SilkS")
		)
		(fp_line
			(start 19.688302 -5.439156)
			(end 19.676364 -5.370068)
			(stroke
				(width 0.1)
				(type default)
			)
			(layer "F.SilkS")
		)
		(fp_line
			(start 19.688302 -5.439156)
			(end 19.676364 -5.370068)
			(stroke
				(width 0.1)
				(type default)
			)
			(layer "F.SilkS")
		)
		(fp_line
			(start 19.700748 -5.508752)
			(end 19.688302 -5.439156)
			(stroke
				(width 0.1)
				(type default)
			)
			(layer "F.SilkS")
		)
		(fp_line
			(start 19.700748 -5.508752)
			(end 19.688302 -5.439156)
			(stroke
				(width 0.1)
				(type default)
			)
			(layer "F.SilkS")
		)
		(fp_line
			(start 19.707352 -0.840486)
			(end 20.828 -1.915414)
			(stroke
				(width 0.1)
				(type default)
			)
			(layer "F.SilkS")
		)
		(fp_line
			(start 19.707352 -0.840486)
			(end 20.828 -1.915414)
			(stroke
				(width 0.1)
				(type default)
			)
			(layer "F.SilkS")
		)
		(fp_line
			(start 19.712686 -5.578094)
			(end 19.700748 -5.508752)
			(stroke
				(width 0.1)
				(type default)
			)
			(layer "F.SilkS")
		)
		(fp_line
			(start 19.712686 -5.578094)
			(end 19.700748 -5.508752)
			(stroke
				(width 0.1)
				(type default)
			)
			(layer "F.SilkS")
		)
		(fp_line
			(start 19.725132 -5.647436)
			(end 19.712686 -5.578094)
			(stroke
				(width 0.1)
				(type default)
			)
			(layer "F.SilkS")
		)
		(fp_line
			(start 19.725132 -5.647436)
			(end 19.712686 -5.578094)
			(stroke
				(width 0.1)
				(type default)
			)
			(layer "F.SilkS")
		)
		(fp_line
			(start 19.737324 -5.716778)
			(end 19.725132 -5.647436)
			(stroke
				(width 0.1)
				(type default)
			)
			(layer "F.SilkS")
		)
		(fp_line
			(start 19.737324 -5.716778)
			(end 19.725132 -5.647436)
			(stroke
				(width 0.1)
				(type default)
			)
			(layer "F.SilkS")
		)
		(fp_line
			(start 19.749262 -5.786374)
			(end 19.737324 -5.716778)
			(stroke
				(width 0.1)
				(type default)
			)
			(layer "F.SilkS")
		)
		(fp_line
			(start 19.749262 -5.786374)
			(end 19.737324 -5.716778)
			(stroke
				(width 0.1)
				(type default)
			)
			(layer "F.SilkS")
		)
		(fp_line
			(start 19.751802 -0.825246)
			(end 20.932902 -1.95834)
			(stroke
				(width 0.1)
				(type default)
			)
			(layer "F.SilkS")
		)
		(fp_line
			(start 19.751802 -0.825246)
			(end 20.932902 -1.95834)
			(stroke
				(width 0.1)
				(type default)
			)
			(layer "F.SilkS")
		)
		(fp_line
			(start 19.761708 -5.85597)
			(end 19.749262 -5.786374)
			(stroke
				(width 0.1)
				(type default)
			)
			(layer "F.SilkS")
		)
		(fp_line
			(start 19.761708 -5.85597)
			(end 19.749262 -5.786374)
			(stroke
				(width 0.1)
				(type default)
			)
			(layer "F.SilkS")
		)
		(fp_line
			(start 19.773646 -5.925058)
			(end 19.761708 -5.85597)
			(stroke
				(width 0.1)
				(type default)
			)
			(layer "F.SilkS")
		)
		(fp_line
			(start 19.773646 -5.925058)
			(end 19.761708 -5.85597)
			(stroke
				(width 0.1)
				(type default)
			)
			(layer "F.SilkS")
		)
		(fp_line
			(start 19.785838 -5.9944)
			(end 19.773646 -5.925058)
			(stroke
				(width 0.1)
				(type default)
			)
			(layer "F.SilkS")
		)
		(fp_line
			(start 19.785838 -5.9944)
			(end 19.773646 -5.925058)
			(stroke
				(width 0.1)
				(type default)
			)
			(layer "F.SilkS")
		)
		(fp_line
			(start 19.798284 -6.063996)
			(end 19.785838 -5.9944)
			(stroke
				(width 0.1)
				(type default)
			)
			(layer "F.SilkS")
		)
		(fp_line
			(start 19.798284 -6.063996)
			(end 19.785838 -5.9944)
			(stroke
				(width 0.1)
				(type default)
			)
			(layer "F.SilkS")
		)
		(fp_line
			(start 19.798284 -6.063996)
			(end 19.810222 -6.133338)
			(stroke
				(width 0.1)
				(type default)
			)
			(layer "F.SilkS")
		)
		(fp_line
			(start 19.798284 -6.063996)
			(end 19.810222 -6.133338)
			(stroke
				(width 0.1)
				(type default)
			)
			(layer "F.SilkS")
		)
		(fp_line
			(start 19.801078 -0.815086)
			(end 21.08327 -2.044954)
			(stroke
				(width 0.1)
				(type default)
			)
			(layer "F.SilkS")
		)
		(fp_line
			(start 19.801078 -0.815086)
			(end 21.08327 -2.044954)
			(stroke
				(width 0.1)
				(type default)
			)
			(layer "F.SilkS")
		)
		(fp_line
			(start 19.810222 -6.133338)
			(end 19.822668 -6.20268)
			(stroke
				(width 0.1)
				(type default)
			)
			(layer "F.SilkS")
		)
		(fp_line
			(start 19.810222 -6.133338)
			(end 19.822668 -6.20268)
			(stroke
				(width 0.1)
				(type default)
			)
			(layer "F.SilkS")
		)
		(fp_line
			(start 19.822668 -6.20268)
			(end 19.834606 -6.272022)
			(stroke
				(width 0.1)
				(type default)
			)
			(layer "F.SilkS")
		)
		(fp_line
			(start 19.822668 -6.20268)
			(end 19.834606 -6.272022)
			(stroke
				(width 0.1)
				(type default)
			)
			(layer "F.SilkS")
		)
		(fp_line
			(start 19.835114 -6.274308)
			(end 19.834606 -6.272022)
			(stroke
				(width 0.1)
				(type default)
			)
			(layer "F.SilkS")
		)
		(fp_line
			(start 19.835114 -6.274308)
			(end 19.834606 -6.272022)
			(stroke
				(width 0.1)
				(type default)
			)
			(layer "F.SilkS")
		)
		(fp_line
			(start 19.838924 -6.276086)
			(end 19.834606 -6.272022)
			(stroke
				(width 0.1)
				(type default)
			)
			(layer "F.SilkS")
		)
		(fp_line
			(start 19.838924 -6.276086)
			(end 19.834606 -6.272022)
			(stroke
				(width 0.1)
				(type default)
			)
			(layer "F.SilkS")
		)
		(fp_line
			(start 19.838924 -6.276086)
			(end 19.835114 -6.274308)
			(stroke
				(width 0.1)
				(type default)
			)
			(layer "F.SilkS")
		)
		(fp_line
			(start 19.838924 -6.276086)
			(end 19.835114 -6.274308)
			(stroke
				(width 0.1)
				(type default)
			)
			(layer "F.SilkS")
		)
		(fp_line
			(start 19.855434 -0.809498)
			(end 21.299932 -2.195068)
			(stroke
				(width 0.1)
				(type default)
			)
			(layer "F.SilkS")
		)
		(fp_line
			(start 19.855434 -0.809498)
			(end 21.299932 -2.195068)
			(stroke
				(width 0.1)
				(type default)
			)
			(layer "F.SilkS")
		)
		(fp_line
			(start 19.910044 -0.80391)
			(end 21.273516 -2.11201)
			(stroke
				(width 0.1)
				(type default)
			)
			(layer "F.SilkS")
		)
		(fp_line
			(start 19.910044 -0.80391)
			(end 21.273516 -2.11201)
			(stroke
				(width 0.1)
				(type default)
			)
			(layer "F.SilkS")
		)
		(fp_line
			(start 19.95424 -6.329172)
			(end 19.822668 -6.20268)
			(stroke
				(width 0.1)
				(type default)
			)
			(layer "F.SilkS")
		)
		(fp_line
			(start 19.95424 -6.329172)
			(end 19.822668 -6.20268)
			(stroke
				(width 0.1)
				(type default)
			)
			(layer "F.SilkS")
		)
		(fp_line
			(start 19.95424 -6.329172)
			(end 19.838924 -6.276086)
			(stroke
				(width 0.1)
				(type default)
			)
			(layer "F.SilkS")
		)
		(fp_line
			(start 19.95424 -6.329172)
			(end 19.838924 -6.276086)
			(stroke
				(width 0.1)
				(type default)
			)
			(layer "F.SilkS")
		)
		(fp_line
			(start 19.964654 -0.798576)
			(end 21.2471 -2.028952)
			(stroke
				(width 0.1)
				(type default)
			)
			(layer "F.SilkS")
		)
		(fp_line
			(start 19.964654 -0.798576)
			(end 21.2471 -2.028952)
			(stroke
				(width 0.1)
				(type default)
			)
			(layer "F.SilkS")
		)
		(fp_line
			(start 20.01901 -0.792988)
			(end 21.220684 -1.946148)
			(stroke
				(width 0.1)
				(type default)
			)
			(layer "F.SilkS")
		)
		(fp_line
			(start 20.01901 -0.792988)
			(end 21.220684 -1.946148)
			(stroke
				(width 0.1)
				(type default)
			)
			(layer "F.SilkS")
		)
		(fp_line
			(start 20.069302 -6.382004)
			(end 19.810222 -6.133338)
			(stroke
				(width 0.1)
				(type default)
			)
			(layer "F.SilkS")
		)
		(fp_line
			(start 20.069302 -6.382004)
			(end 19.810222 -6.133338)
			(stroke
				(width 0.1)
				(type default)
			)
			(layer "F.SilkS")
		)
		(fp_line
			(start 20.069302 -6.382004)
			(end 19.95424 -6.329172)
			(stroke
				(width 0.1)
				(type default)
			)
			(layer "F.SilkS")
		)
		(fp_line
			(start 20.069302 -6.382004)
			(end 19.95424 -6.329172)
			(stroke
				(width 0.1)
				(type default)
			)
			(layer "F.SilkS")
		)
		(fp_line
			(start 20.084542 -0.798576)
			(end 21.194268 -1.862836)
			(stroke
				(width 0.1)
				(type default)
			)
			(layer "F.SilkS")
		)
		(fp_line
			(start 20.084542 -0.798576)
			(end 21.194268 -1.862836)
			(stroke
				(width 0.1)
				(type default)
			)
			(layer "F.SilkS")
		)
		(fp_line
			(start 20.14982 -0.803402)
			(end 21.167852 -1.779778)
			(stroke
				(width 0.1)
				(type default)
			)
			(layer "F.SilkS")
		)
		(fp_line
			(start 20.14982 -0.803402)
			(end 21.167852 -1.779778)
			(stroke
				(width 0.1)
				(type default)
			)
			(layer "F.SilkS")
		)
		(fp_line
			(start 20.185126 -6.43509)
			(end 19.798284 -6.063996)
			(stroke
				(width 0.1)
				(type default)
			)
			(layer "F.SilkS")
		)
		(fp_line
			(start 20.185126 -6.43509)
			(end 19.798284 -6.063996)
			(stroke
				(width 0.1)
				(type default)
			)
			(layer "F.SilkS")
		)
		(fp_line
			(start 20.185126 -6.43509)
			(end 20.069302 -6.382004)
			(stroke
				(width 0.1)
				(type default)
			)
			(layer "F.SilkS")
		)
		(fp_line
			(start 20.185126 -6.43509)
			(end 20.069302 -6.382004)
			(stroke
				(width 0.1)
				(type default)
			)
			(layer "F.SilkS")
		)
		(fp_line
			(start 20.215352 -0.808228)
			(end 21.141436 -1.69672)
			(stroke
				(width 0.1)
				(type default)
			)
			(layer "F.SilkS")
		)
		(fp_line
			(start 20.215352 -0.808228)
			(end 21.141436 -1.69672)
			(stroke
				(width 0.1)
				(type default)
			)
			(layer "F.SilkS")
		)
		(fp_line
			(start 20.280884 -0.813562)
			(end 21.115274 -1.613916)
			(stroke
				(width 0.1)
				(type default)
			)
			(layer "F.SilkS")
		)
		(fp_line
			(start 20.280884 -0.813562)
			(end 21.115274 -1.613916)
			(stroke
				(width 0.1)
				(type default)
			)
			(layer "F.SilkS")
		)
		(fp_line
			(start 20.30095 -6.488176)
			(end 19.785838 -5.9944)
			(stroke
				(width 0.1)
				(type default)
			)
			(layer "F.SilkS")
		)
		(fp_line
			(start 20.30095 -6.488176)
			(end 19.785838 -5.9944)
			(stroke
				(width 0.1)
				(type default)
			)
			(layer "F.SilkS")
		)
		(fp_line
			(start 20.30095 -6.488176)
			(end 20.185126 -6.43509)
			(stroke
				(width 0.1)
				(type default)
			)
			(layer "F.SilkS")
		)
		(fp_line
			(start 20.30095 -6.488176)
			(end 20.185126 -6.43509)
			(stroke
				(width 0.1)
				(type default)
			)
			(layer "F.SilkS")
		)
		(fp_line
			(start 20.301966 -2.507234)
			(end 20.28952 -2.437892)
			(stroke
				(width 0.1)
				(type default)
			)
			(layer "F.SilkS")
		)
		(fp_line
			(start 20.301966 -2.507234)
			(end 20.28952 -2.437892)
			(stroke
				(width 0.1)
				(type default)
			)
			(layer "F.SilkS")
		)
		(fp_line
			(start 20.313904 -2.576576)
			(end 20.301966 -2.507234)
			(stroke
				(width 0.1)
				(type default)
			)
			(layer "F.SilkS")
		)
		(fp_line
			(start 20.313904 -2.576576)
			(end 20.301966 -2.507234)
			(stroke
				(width 0.1)
				(type default)
			)
			(layer "F.SilkS")
		)
		(fp_line
			(start 20.32635 -2.646172)
			(end 20.313904 -2.576576)
			(stroke
				(width 0.1)
				(type default)
			)
			(layer "F.SilkS")
		)
		(fp_line
			(start 20.32635 -2.646172)
			(end 20.313904 -2.576576)
			(stroke
				(width 0.1)
				(type default)
			)
			(layer "F.SilkS")
		)
		(fp_line
			(start 20.32635 -2.646172)
			(end 20.338288 -2.715768)
			(stroke
				(width 0.1)
				(type default)
			)
			(layer "F.SilkS")
		)
		(fp_line
			(start 20.32635 -2.646172)
			(end 20.338288 -2.715768)
			(stroke
				(width 0.1)
				(type default)
			)
			(layer "F.SilkS")
		)
		(fp_line
			(start 20.338288 -2.715768)
			(end 20.35048 -2.784856)
			(stroke
				(width 0.1)
				(type default)
			)
			(layer "F.SilkS")
		)
		(fp_line
			(start 20.338288 -2.715768)
			(end 20.35048 -2.784856)
			(stroke
				(width 0.1)
				(type default)
			)
			(layer "F.SilkS")
		)
		(fp_line
			(start 20.35048 -2.784856)
			(end 20.362926 -2.854198)
			(stroke
				(width 0.1)
				(type default)
			)
			(layer "F.SilkS")
		)
		(fp_line
			(start 20.35048 -2.784856)
			(end 20.362926 -2.854198)
			(stroke
				(width 0.1)
				(type default)
			)
			(layer "F.SilkS")
		)
		(fp_line
			(start 20.359116 -0.830834)
			(end 21.088858 -1.530604)
			(stroke
				(width 0.1)
				(type default)
			)
			(layer "F.SilkS")
		)
		(fp_line
			(start 20.359116 -0.830834)
			(end 21.088858 -1.530604)
			(stroke
				(width 0.1)
				(type default)
			)
			(layer "F.SilkS")
		)
		(fp_line
			(start 20.362926 -2.854198)
			(end 20.374864 -2.923794)
			(stroke
				(width 0.1)
				(type default)
			)
			(layer "F.SilkS")
		)
		(fp_line
			(start 20.362926 -2.854198)
			(end 20.374864 -2.923794)
			(stroke
				(width 0.1)
				(type default)
			)
			(layer "F.SilkS")
		)
		(fp_line
			(start 20.374864 -2.923794)
			(end 20.38731 -2.99339)
			(stroke
				(width 0.1)
				(type default)
			)
			(layer "F.SilkS")
		)
		(fp_line
			(start 20.374864 -2.923794)
			(end 20.38731 -2.99339)
			(stroke
				(width 0.1)
				(type default)
			)
			(layer "F.SilkS")
		)
		(fp_line
			(start 20.38731 -2.99339)
			(end 20.399248 -3.062478)
			(stroke
				(width 0.1)
				(type default)
			)
			(layer "F.SilkS")
		)
		(fp_line
			(start 20.38731 -2.99339)
			(end 20.399248 -3.062478)
			(stroke
				(width 0.1)
				(type default)
			)
			(layer "F.SilkS")
		)
		(fp_line
			(start 20.399248 -3.062478)
			(end 20.41144 -3.13182)
			(stroke
				(width 0.1)
				(type default)
			)
			(layer "F.SilkS")
		)
		(fp_line
			(start 20.399248 -3.062478)
			(end 20.41144 -3.13182)
			(stroke
				(width 0.1)
				(type default)
			)
			(layer "F.SilkS")
		)
		(fp_line
			(start 20.41144 -3.13182)
			(end 20.423886 -3.201416)
			(stroke
				(width 0.1)
				(type default)
			)
			(layer "F.SilkS")
		)
		(fp_line
			(start 20.41144 -3.13182)
			(end 20.423886 -3.201416)
			(stroke
				(width 0.1)
				(type default)
			)
			(layer "F.SilkS")
		)
		(fp_line
			(start 20.416012 -6.541262)
			(end 19.773646 -5.925058)
			(stroke
				(width 0.1)
				(type default)
			)
			(layer "F.SilkS")
		)
		(fp_line
			(start 20.416012 -6.541262)
			(end 19.773646 -5.925058)
			(stroke
				(width 0.1)
				(type default)
			)
			(layer "F.SilkS")
		)
		(fp_line
			(start 20.416012 -6.541262)
			(end 20.30095 -6.488176)
			(stroke
				(width 0.1)
				(type default)
			)
			(layer "F.SilkS")
		)
		(fp_line
			(start 20.416012 -6.541262)
			(end 20.30095 -6.488176)
			(stroke
				(width 0.1)
				(type default)
			)
			(layer "F.SilkS")
		)
		(fp_line
			(start 20.423886 -3.201416)
			(end 20.435824 -3.270758)
			(stroke
				(width 0.1)
				(type default)
			)
			(layer "F.SilkS")
		)
		(fp_line
			(start 20.423886 -3.201416)
			(end 20.435824 -3.270758)
			(stroke
				(width 0.1)
				(type default)
			)
			(layer "F.SilkS")
		)
		(fp_line
			(start 20.435824 -3.270758)
			(end 20.44827 -3.340354)
			(stroke
				(width 0.1)
				(type default)
			)
			(layer "F.SilkS")
		)
		(fp_line
			(start 20.435824 -3.270758)
			(end 20.44827 -3.340354)
			(stroke
				(width 0.1)
				(type default)
			)
			(layer "F.SilkS")
		)
		(fp_line
			(start 20.437602 -0.848106)
			(end 21.062188 -1.447546)
			(stroke
				(width 0.1)
				(type default)
			)
			(layer "F.SilkS")
		)
		(fp_line
			(start 20.437602 -0.848106)
			(end 21.062188 -1.447546)
			(stroke
				(width 0.1)
				(type default)
			)
			(layer "F.SilkS")
		)
		(fp_line
			(start 20.44827 -3.340354)
			(end 20.460462 -3.409442)
			(stroke
				(width 0.1)
				(type default)
			)
			(layer "F.SilkS")
		)
		(fp_line
			(start 20.44827 -3.340354)
			(end 20.460462 -3.409442)
			(stroke
				(width 0.1)
				(type default)
			)
			(layer "F.SilkS")
		)
		(fp_line
			(start 20.460462 -3.409442)
			(end 20.4724 -3.479038)
			(stroke
				(width 0.1)
				(type default)
			)
			(layer "F.SilkS")
		)
		(fp_line
			(start 20.460462 -3.409442)
			(end 20.4724 -3.479038)
			(stroke
				(width 0.1)
				(type default)
			)
			(layer "F.SilkS")
		)
		(fp_line
			(start 20.484846 -3.548634)
			(end 20.4724 -3.479038)
			(stroke
				(width 0.1)
				(type default)
			)
			(layer "F.SilkS")
		)
		(fp_line
			(start 20.484846 -3.548634)
			(end 20.4724 -3.479038)
			(stroke
				(width 0.1)
				(type default)
			)
			(layer "F.SilkS")
		)
		(fp_line
			(start 20.496784 -3.617976)
			(end 19.141186 -2.317242)
			(stroke
				(width 0.1)
				(type default)
			)
			(layer "F.SilkS")
		)
		(fp_line
			(start 20.496784 -3.617976)
			(end 19.141186 -2.317242)
			(stroke
				(width 0.1)
				(type default)
			)
			(layer "F.SilkS")
		)
		(fp_line
			(start 20.496784 -3.617976)
			(end 20.484846 -3.548634)
			(stroke
				(width 0.1)
				(type default)
			)
			(layer "F.SilkS")
		)
		(fp_line
			(start 20.496784 -3.617976)
			(end 20.484846 -3.548634)
			(stroke
				(width 0.1)
				(type default)
			)
			(layer "F.SilkS")
		)
		(fp_line
			(start 20.496784 -3.617976)
			(end 20.50923 -3.687064)
			(stroke
				(width 0.1)
				(type default)
			)
			(layer "F.SilkS")
		)
		(fp_line
			(start 20.496784 -3.617976)
			(end 20.50923 -3.687064)
			(stroke
				(width 0.1)
				(type default)
			)
			(layer "F.SilkS")
		)
		(fp_line
			(start 20.50923 -3.687064)
			(end 20.521422 -3.75666)
			(stroke
				(width 0.1)
				(type default)
			)
			(layer "F.SilkS")
		)
		(fp_line
			(start 20.50923 -3.687064)
			(end 20.521422 -3.75666)
			(stroke
				(width 0.1)
				(type default)
			)
			(layer "F.SilkS")
		)
		(fp_line
			(start 20.515834 -0.865632)
			(end 21.035772 -1.364742)
			(stroke
				(width 0.1)
				(type default)
			)
			(layer "F.SilkS")
		)
		(fp_line
			(start 20.515834 -0.865632)
			(end 21.035772 -1.364742)
			(stroke
				(width 0.1)
				(type default)
			)
			(layer "F.SilkS")
		)
		(fp_line
			(start 20.521422 -3.75666)
			(end 20.533614 -3.826256)
			(stroke
				(width 0.1)
				(type default)
			)
			(layer "F.SilkS")
		)
		(fp_line
			(start 20.521422 -3.75666)
			(end 20.533614 -3.826256)
			(stroke
				(width 0.1)
				(type default)
			)
			(layer "F.SilkS")
		)
		(fp_line
			(start 20.531328 -6.594348)
			(end 19.761708 -5.85597)
			(stroke
				(width 0.1)
				(type default)
			)
			(layer "F.SilkS")
		)
		(fp_line
			(start 20.531328 -6.594348)
			(end 19.761708 -5.85597)
			(stroke
				(width 0.1)
				(type default)
			)
			(layer "F.SilkS")
		)
		(fp_line
			(start 20.531328 -6.594348)
			(end 20.416012 -6.541262)
			(stroke
				(width 0.1)
				(type default)
			)
			(layer "F.SilkS")
		)
		(fp_line
			(start 20.531328 -6.594348)
			(end 20.416012 -6.541262)
			(stroke
				(width 0.1)
				(type default)
			)
			(layer "F.SilkS")
		)
		(fp_line
			(start 20.533614 -3.826256)
			(end 20.545806 -3.895344)
			(stroke
				(width 0.1)
				(type default)
			)
			(layer "F.SilkS")
		)
		(fp_line
			(start 20.533614 -3.826256)
			(end 20.545806 -3.895344)
			(stroke
				(width 0.1)
				(type default)
			)
			(layer "F.SilkS")
		)
		(fp_line
			(start 20.545806 -3.895344)
			(end 20.557744 -3.96494)
			(stroke
				(width 0.1)
				(type default)
			)
			(layer "F.SilkS")
		)
		(fp_line
			(start 20.545806 -3.895344)
			(end 20.557744 -3.96494)
			(stroke
				(width 0.1)
				(type default)
			)
			(layer "F.SilkS")
		)
		(fp_line
			(start 20.557744 -3.96494)
			(end 20.57019 -4.034282)
			(stroke
				(width 0.1)
				(type default)
			)
			(layer "F.SilkS")
		)
		(fp_line
			(start 20.557744 -3.96494)
			(end 20.57019 -4.034282)
			(stroke
				(width 0.1)
				(type default)
			)
			(layer "F.SilkS")
		)
		(fp_line
			(start 20.57019 -4.034282)
			(end 20.582382 -4.103878)
			(stroke
				(width 0.1)
				(type default)
			)
			(layer "F.SilkS")
		)
		(fp_line
			(start 20.57019 -4.034282)
			(end 20.582382 -4.103878)
			(stroke
				(width 0.1)
				(type default)
			)
			(layer "F.SilkS")
		)
		(fp_line
			(start 20.582382 -4.103878)
			(end 20.583398 -4.109466)
			(stroke
				(width 0.1)
				(type default)
			)
			(layer "F.SilkS")
		)
		(fp_line
			(start 20.582382 -4.103878)
			(end 20.583398 -4.109466)
			(stroke
				(width 0.1)
				(type default)
			)
			(layer "F.SilkS")
		)
		(fp_line
			(start 20.582382 -4.103878)
			(end 20.588224 -4.109466)
			(stroke
				(width 0.1)
				(type default)
			)
			(layer "F.SilkS")
		)
		(fp_line
			(start 20.582382 -4.103878)
			(end 20.588224 -4.109466)
			(stroke
				(width 0.1)
				(type default)
			)
			(layer "F.SilkS")
		)
		(fp_line
			(start 20.583398 -4.109466)
			(end 20.588224 -4.109466)
			(stroke
				(width 0.1)
				(type default)
			)
			(layer "F.SilkS")
		)
		(fp_line
			(start 20.583398 -4.109466)
			(end 20.588224 -4.109466)
			(stroke
				(width 0.1)
				(type default)
			)
			(layer "F.SilkS")
		)
		(fp_line
			(start 20.610322 -0.898652)
			(end 21.00961 -1.281684)
			(stroke
				(width 0.1)
				(type default)
			)
			(layer "F.SilkS")
		)
		(fp_line
			(start 20.610322 -0.898652)
			(end 21.00961 -1.281684)
			(stroke
				(width 0.1)
				(type default)
			)
			(layer "F.SilkS")
		)
		(fp_line
			(start 20.647152 -6.647434)
			(end 19.749262 -5.786374)
			(stroke
				(width 0.1)
				(type default)
			)
			(layer "F.SilkS")
		)
		(fp_line
			(start 20.647152 -6.647434)
			(end 19.749262 -5.786374)
			(stroke
				(width 0.1)
				(type default)
			)
			(layer "F.SilkS")
		)
		(fp_line
			(start 20.647152 -6.647434)
			(end 20.531328 -6.594348)
			(stroke
				(width 0.1)
				(type default)
			)
			(layer "F.SilkS")
		)
		(fp_line
			(start 20.647152 -6.647434)
			(end 20.531328 -6.594348)
			(stroke
				(width 0.1)
				(type default)
			)
			(layer "F.SilkS")
		)
		(fp_line
			(start 20.648422 -4.109466)
			(end 20.588224 -4.109466)
			(stroke
				(width 0.1)
				(type default)
			)
			(layer "F.SilkS")
		)
		(fp_line
			(start 20.648422 -4.109466)
			(end 20.588224 -4.109466)
			(stroke
				(width 0.1)
				(type default)
			)
			(layer "F.SilkS")
		)
		(fp_line
			(start 20.708366 -0.934974)
			(end 20.98294 -1.198626)
			(stroke
				(width 0.1)
				(type default)
			)
			(layer "F.SilkS")
		)
		(fp_line
			(start 20.708366 -0.934974)
			(end 20.98294 -1.198626)
			(stroke
				(width 0.1)
				(type default)
			)
			(layer "F.SilkS")
		)
		(fp_line
			(start 20.70862 -4.109466)
			(end 20.648422 -4.109466)
			(stroke
				(width 0.1)
				(type default)
			)
			(layer "F.SilkS")
		)
		(fp_line
			(start 20.70862 -4.109466)
			(end 20.648422 -4.109466)
			(stroke
				(width 0.1)
				(type default)
			)
			(layer "F.SilkS")
		)
		(fp_line
			(start 20.762722 -6.70052)
			(end 19.737324 -5.716778)
			(stroke
				(width 0.1)
				(type default)
			)
			(layer "F.SilkS")
		)
		(fp_line
			(start 20.762722 -6.70052)
			(end 19.737324 -5.716778)
			(stroke
				(width 0.1)
				(type default)
			)
			(layer "F.SilkS")
		)
		(fp_line
			(start 20.762722 -6.70052)
			(end 20.647152 -6.647434)
			(stroke
				(width 0.1)
				(type default)
			)
			(layer "F.SilkS")
		)
		(fp_line
			(start 20.762722 -6.70052)
			(end 20.647152 -6.647434)
			(stroke
				(width 0.1)
				(type default)
			)
			(layer "F.SilkS")
		)
		(fp_line
			(start 20.768564 -4.109466)
			(end 20.70862 -4.109466)
			(stroke
				(width 0.1)
				(type default)
			)
			(layer "F.SilkS")
		)
		(fp_line
			(start 20.768564 -4.109466)
			(end 20.70862 -4.109466)
			(stroke
				(width 0.1)
				(type default)
			)
			(layer "F.SilkS")
		)
		(fp_line
			(start 20.769072 -5.171694)
			(end 20.793202 -5.171694)
			(stroke
				(width 0.1)
				(type default)
			)
			(layer "F.SilkS")
		)
		(fp_line
			(start 20.769072 -5.171694)
			(end 20.793202 -5.171694)
			(stroke
				(width 0.1)
				(type default)
			)
			(layer "F.SilkS")
		)
		(fp_line
			(start 20.776184 -5.21335)
			(end 20.769072 -5.171694)
			(stroke
				(width 0.1)
				(type default)
			)
			(layer "F.SilkS")
		)
		(fp_line
			(start 20.776184 -5.21335)
			(end 20.769072 -5.171694)
			(stroke
				(width 0.1)
				(type default)
			)
			(layer "F.SilkS")
		)
		(fp_line
			(start 20.776184 -5.21335)
			(end 20.78863 -5.282692)
			(stroke
				(width 0.1)
				(type default)
			)
			(layer "F.SilkS")
		)
		(fp_line
			(start 20.776184 -5.21335)
			(end 20.78863 -5.282692)
			(stroke
				(width 0.1)
				(type default)
			)
			(layer "F.SilkS")
		)
		(fp_line
			(start 20.78863 -5.282692)
			(end 19.433032 -3.982466)
			(stroke
				(width 0.1)
				(type default)
			)
			(layer "F.SilkS")
		)
		(fp_line
			(start 20.78863 -5.282692)
			(end 19.433032 -3.982466)
			(stroke
				(width 0.1)
				(type default)
			)
			(layer "F.SilkS")
		)
		(fp_line
			(start 20.78863 -5.282692)
			(end 20.800822 -5.352034)
			(stroke
				(width 0.1)
				(type default)
			)
			(layer "F.SilkS")
		)
		(fp_line
			(start 20.78863 -5.282692)
			(end 20.800822 -5.352034)
			(stroke
				(width 0.1)
				(type default)
			)
			(layer "F.SilkS")
		)
		(fp_line
			(start 20.793202 -5.171694)
			(end 19.408902 -3.843528)
			(stroke
				(width 0.1)
				(type default)
			)
			(layer "F.SilkS")
		)
		(fp_line
			(start 20.793202 -5.171694)
			(end 19.408902 -3.843528)
			(stroke
				(width 0.1)
				(type default)
			)
			(layer "F.SilkS")
		)
		(fp_line
			(start 20.800822 -5.352034)
			(end 19.445478 -4.051554)
			(stroke
				(width 0.1)
				(type default)
			)
			(layer "F.SilkS")
		)
		(fp_line
			(start 20.800822 -5.352034)
			(end 19.445478 -4.051554)
			(stroke
				(width 0.1)
				(type default)
			)
			(layer "F.SilkS")
		)
		(fp_line
			(start 20.800822 -5.352034)
			(end 20.81276 -5.421376)
			(stroke
				(width 0.1)
				(type default)
			)
			(layer "F.SilkS")
		)
		(fp_line
			(start 20.800822 -5.352034)
			(end 20.81276 -5.421376)
			(stroke
				(width 0.1)
				(type default)
			)
			(layer "F.SilkS")
		)
		(fp_line
			(start 20.81276 -5.421376)
			(end 20.825206 -5.490972)
			(stroke
				(width 0.1)
				(type default)
			)
			(layer "F.SilkS")
		)
		(fp_line
			(start 20.81276 -5.421376)
			(end 20.825206 -5.490972)
			(stroke
				(width 0.1)
				(type default)
			)
			(layer "F.SilkS")
		)
		(fp_line
			(start 20.825206 -5.490972)
			(end 20.837144 -5.560314)
			(stroke
				(width 0.1)
				(type default)
			)
			(layer "F.SilkS")
		)
		(fp_line
			(start 20.825206 -5.490972)
			(end 20.837144 -5.560314)
			(stroke
				(width 0.1)
				(type default)
			)
			(layer "F.SilkS")
		)
		(fp_line
			(start 20.829016 -4.109466)
			(end 20.768564 -4.109466)
			(stroke
				(width 0.1)
				(type default)
			)
			(layer "F.SilkS")
		)
		(fp_line
			(start 20.829016 -4.109466)
			(end 20.768564 -4.109466)
			(stroke
				(width 0.1)
				(type default)
			)
			(layer "F.SilkS")
		)
		(fp_line
			(start 20.831302 -0.995426)
			(end 20.956524 -1.115314)
			(stroke
				(width 0.1)
				(type default)
			)
			(layer "F.SilkS")
		)
		(fp_line
			(start 20.831302 -0.995426)
			(end 20.956524 -1.115314)
			(stroke
				(width 0.1)
				(type default)
			)
			(layer "F.SilkS")
		)
		(fp_line
			(start 20.837144 -5.560314)
			(end 20.84959 -5.629656)
			(stroke
				(width 0.1)
				(type default)
			)
			(layer "F.SilkS")
		)
		(fp_line
			(start 20.837144 -5.560314)
			(end 20.84959 -5.629656)
			(stroke
				(width 0.1)
				(type default)
			)
			(layer "F.SilkS")
		)
		(fp_line
			(start 20.84959 -5.629656)
			(end 20.861782 -5.699252)
			(stroke
				(width 0.1)
				(type default)
			)
			(layer "F.SilkS")
		)
		(fp_line
			(start 20.84959 -5.629656)
			(end 20.861782 -5.699252)
			(stroke
				(width 0.1)
				(type default)
			)
			(layer "F.SilkS")
		)
		(fp_line
			(start 20.8534 -5.171694)
			(end 19.396456 -3.774186)
			(stroke
				(width 0.1)
				(type default)
			)
			(layer "F.SilkS")
		)
		(fp_line
			(start 20.8534 -5.171694)
			(end 19.396456 -3.774186)
			(stroke
				(width 0.1)
				(type default)
			)
			(layer "F.SilkS")
		)
		(fp_line
			(start 20.8534 -5.171694)
			(end 20.793202 -5.171694)
			(stroke
				(width 0.1)
				(type default)
			)
			(layer "F.SilkS")
		)
		(fp_line
			(start 20.8534 -5.171694)
			(end 20.793202 -5.171694)
			(stroke
				(width 0.1)
				(type default)
			)
			(layer "F.SilkS")
		)
		(fp_line
			(start 20.861782 -5.699252)
			(end 20.874228 -5.768594)
			(stroke
				(width 0.1)
				(type default)
			)
			(layer "F.SilkS")
		)
		(fp_line
			(start 20.861782 -5.699252)
			(end 20.874228 -5.768594)
			(stroke
				(width 0.1)
				(type default)
			)
			(layer "F.SilkS")
		)
		(fp_line
			(start 20.874228 -5.768594)
			(end 20.886166 -5.837936)
			(stroke
				(width 0.1)
				(type default)
			)
			(layer "F.SilkS")
		)
		(fp_line
			(start 20.874228 -5.768594)
			(end 20.886166 -5.837936)
			(stroke
				(width 0.1)
				(type default)
			)
			(layer "F.SilkS")
		)
		(fp_line
			(start 20.877784 -6.753606)
			(end 19.725132 -5.647436)
			(stroke
				(width 0.1)
				(type default)
			)
			(layer "F.SilkS")
		)
		(fp_line
			(start 20.877784 -6.753606)
			(end 19.725132 -5.647436)
			(stroke
				(width 0.1)
				(type default)
			)
			(layer "F.SilkS")
		)
		(fp_line
			(start 20.877784 -6.753606)
			(end 20.762722 -6.70052)
			(stroke
				(width 0.1)
				(type default)
			)
			(layer "F.SilkS")
		)
		(fp_line
			(start 20.877784 -6.753606)
			(end 20.762722 -6.70052)
			(stroke
				(width 0.1)
				(type default)
			)
			(layer "F.SilkS")
		)
		(fp_line
			(start 20.886166 -5.837936)
			(end 20.898104 -5.907278)
			(stroke
				(width 0.1)
				(type default)
			)
			(layer "F.SilkS")
		)
		(fp_line
			(start 20.886166 -5.837936)
			(end 20.898104 -5.907278)
			(stroke
				(width 0.1)
				(type default)
			)
			(layer "F.SilkS")
		)
		(fp_line
			(start 20.889214 -4.109466)
			(end 20.829016 -4.109466)
			(stroke
				(width 0.1)
				(type default)
			)
			(layer "F.SilkS")
		)
		(fp_line
			(start 20.889214 -4.109466)
			(end 20.829016 -4.109466)
			(stroke
				(width 0.1)
				(type default)
			)
			(layer "F.SilkS")
		)
		(fp_line
			(start 20.898104 -5.907278)
			(end 20.91055 -5.976874)
			(stroke
				(width 0.1)
				(type default)
			)
			(layer "F.SilkS")
		)
		(fp_line
			(start 20.898104 -5.907278)
			(end 20.91055 -5.976874)
			(stroke
				(width 0.1)
				(type default)
			)
			(layer "F.SilkS")
		)
		(fp_line
			(start 20.91055 -5.976874)
			(end 20.922742 -6.04647)
			(stroke
				(width 0.1)
				(type default)
			)
			(layer "F.SilkS")
		)
		(fp_line
			(start 20.91055 -5.976874)
			(end 20.922742 -6.04647)
			(stroke
				(width 0.1)
				(type default)
			)
			(layer "F.SilkS")
		)
		(fp_line
			(start 20.913344 -5.171694)
			(end 19.384518 -3.704844)
			(stroke
				(width 0.1)
				(type default)
			)
			(layer "F.SilkS")
		)
		(fp_line
			(start 20.913344 -5.171694)
			(end 19.384518 -3.704844)
			(stroke
				(width 0.1)
				(type default)
			)
			(layer "F.SilkS")
		)
		(fp_line
			(start 20.913344 -5.171694)
			(end 20.8534 -5.171694)
			(stroke
				(width 0.1)
				(type default)
			)
			(layer "F.SilkS")
		)
		(fp_line
			(start 20.913344 -5.171694)
			(end 20.8534 -5.171694)
			(stroke
				(width 0.1)
				(type default)
			)
			(layer "F.SilkS")
		)
		(fp_line
			(start 20.922742 -6.04647)
			(end 20.93468 -6.115558)
			(stroke
				(width 0.1)
				(type default)
			)
			(layer "F.SilkS")
		)
		(fp_line
			(start 20.922742 -6.04647)
			(end 20.93468 -6.115558)
			(stroke
				(width 0.1)
				(type default)
			)
			(layer "F.SilkS")
		)
		(fp_line
			(start 20.93468 -6.115558)
			(end 20.947126 -6.1849)
			(stroke
				(width 0.1)
				(type default)
			)
			(layer "F.SilkS")
		)
		(fp_line
			(start 20.93468 -6.115558)
			(end 20.947126 -6.1849)
			(stroke
				(width 0.1)
				(type default)
			)
			(layer "F.SilkS")
		)
		(fp_line
			(start 20.947126 -6.1849)
			(end 20.959318 -6.254496)
			(stroke
				(width 0.1)
				(type default)
			)
			(layer "F.SilkS")
		)
		(fp_line
			(start 20.947126 -6.1849)
			(end 20.959318 -6.254496)
			(stroke
				(width 0.1)
				(type default)
			)
			(layer "F.SilkS")
		)
		(fp_line
			(start 20.949666 -4.109466)
			(end 20.889214 -4.109466)
			(stroke
				(width 0.1)
				(type default)
			)
			(layer "F.SilkS")
		)
		(fp_line
			(start 20.949666 -4.109466)
			(end 20.889214 -4.109466)
			(stroke
				(width 0.1)
				(type default)
			)
			(layer "F.SilkS")
		)
		(fp_line
			(start 20.959318 -6.254496)
			(end 20.97151 -6.324092)
			(stroke
				(width 0.1)
				(type default)
			)
			(layer "F.SilkS")
		)
		(fp_line
			(start 20.959318 -6.254496)
			(end 20.97151 -6.324092)
			(stroke
				(width 0.1)
				(type default)
			)
			(layer "F.SilkS")
		)
		(fp_line
			(start 20.97151 -6.324092)
			(end 18.75155 -4.194556)
			(stroke
				(width 0.1)
				(type default)
			)
			(layer "F.SilkS")
		)
		(fp_line
			(start 20.97151 -6.324092)
			(end 18.75155 -4.194556)
			(stroke
				(width 0.1)
				(type default)
			)
			(layer "F.SilkS")
		)
		(fp_line
			(start 20.97151 -6.324092)
			(end 20.983702 -6.393434)
			(stroke
				(width 0.1)
				(type default)
			)
			(layer "F.SilkS")
		)
		(fp_line
			(start 20.97151 -6.324092)
			(end 20.983702 -6.393434)
			(stroke
				(width 0.1)
				(type default)
			)
			(layer "F.SilkS")
		)
		(fp_line
			(start 20.973542 -5.171694)
			(end 19.372326 -3.635502)
			(stroke
				(width 0.1)
				(type default)
			)
			(layer "F.SilkS")
		)
		(fp_line
			(start 20.973542 -5.171694)
			(end 19.372326 -3.635502)
			(stroke
				(width 0.1)
				(type default)
			)
			(layer "F.SilkS")
		)
		(fp_line
			(start 20.973542 -5.171694)
			(end 20.913344 -5.171694)
			(stroke
				(width 0.1)
				(type default)
			)
			(layer "F.SilkS")
		)
		(fp_line
			(start 20.973542 -5.171694)
			(end 20.913344 -5.171694)
			(stroke
				(width 0.1)
				(type default)
			)
			(layer "F.SilkS")
		)
		(fp_line
			(start 20.98294 -1.198626)
			(end 20.956524 -1.115314)
			(stroke
				(width 0.1)
				(type default)
			)
			(layer "F.SilkS")
		)
		(fp_line
			(start 20.98294 -1.198626)
			(end 20.956524 -1.115314)
			(stroke
				(width 0.1)
				(type default)
			)
			(layer "F.SilkS")
		)
		(fp_line
			(start 20.983702 -6.393434)
			(end 18.763996 -4.263898)
			(stroke
				(width 0.1)
				(type default)
			)
			(layer "F.SilkS")
		)
		(fp_line
			(start 20.983702 -6.393434)
			(end 18.763996 -4.263898)
			(stroke
				(width 0.1)
				(type default)
			)
			(layer "F.SilkS")
		)
		(fp_line
			(start 20.983702 -6.393434)
			(end 20.996148 -6.462522)
			(stroke
				(width 0.1)
				(type default)
			)
			(layer "F.SilkS")
		)
		(fp_line
			(start 20.983702 -6.393434)
			(end 20.996148 -6.462522)
			(stroke
				(width 0.1)
				(type default)
			)
			(layer "F.SilkS")
		)
		(fp_line
			(start 20.993354 -6.806438)
			(end 19.712686 -5.578094)
			(stroke
				(width 0.1)
				(type default)
			)
			(layer "F.SilkS")
		)
		(fp_line
			(start 20.993354 -6.806438)
			(end 19.712686 -5.578094)
			(stroke
				(width 0.1)
				(type default)
			)
			(layer "F.SilkS")
		)
		(fp_line
			(start 20.993354 -6.806438)
			(end 20.877784 -6.753606)
			(stroke
				(width 0.1)
				(type default)
			)
			(layer "F.SilkS")
		)
		(fp_line
			(start 20.993354 -6.806438)
			(end 20.877784 -6.753606)
			(stroke
				(width 0.1)
				(type default)
			)
			(layer "F.SilkS")
		)
		(fp_line
			(start 20.996148 -6.462522)
			(end 18.775934 -4.33324)
			(stroke
				(width 0.1)
				(type default)
			)
			(layer "F.SilkS")
		)
		(fp_line
			(start 20.996148 -6.462522)
			(end 18.775934 -4.33324)
			(stroke
				(width 0.1)
				(type default)
			)
			(layer "F.SilkS")
		)
		(fp_line
			(start 20.996148 -6.462522)
			(end 21.008086 -6.532118)
			(stroke
				(width 0.1)
				(type default)
			)
			(layer "F.SilkS")
		)
		(fp_line
			(start 20.996148 -6.462522)
			(end 21.008086 -6.532118)
			(stroke
				(width 0.1)
				(type default)
			)
			(layer "F.SilkS")
		)
		(fp_line
			(start 21.008086 -6.532118)
			(end 19.651726 -5.23113)
			(stroke
				(width 0.1)
				(type default)
			)
			(layer "F.SilkS")
		)
		(fp_line
			(start 21.008086 -6.532118)
			(end 19.651726 -5.23113)
			(stroke
				(width 0.1)
				(type default)
			)
			(layer "F.SilkS")
		)
		(fp_line
			(start 21.008086 -6.532118)
			(end 21.020278 -6.60146)
			(stroke
				(width 0.1)
				(type default)
			)
			(layer "F.SilkS")
		)
		(fp_line
			(start 21.008086 -6.532118)
			(end 21.020278 -6.60146)
			(stroke
				(width 0.1)
				(type default)
			)
			(layer "F.SilkS")
		)
		(fp_line
			(start 21.00961 -4.109466)
			(end 20.949666 -4.109466)
			(stroke
				(width 0.1)
				(type default)
			)
			(layer "F.SilkS")
		)
		(fp_line
			(start 21.00961 -4.109466)
			(end 20.949666 -4.109466)
			(stroke
				(width 0.1)
				(type default)
			)
			(layer "F.SilkS")
		)
		(fp_line
			(start 21.00961 -4.109466)
			(end 21.069554 -4.109466)
			(stroke
				(width 0.1)
				(type default)
			)
			(layer "F.SilkS")
		)
		(fp_line
			(start 21.00961 -4.109466)
			(end 21.069554 -4.109466)
			(stroke
				(width 0.1)
				(type default)
			)
			(layer "F.SilkS")
		)
		(fp_line
			(start 21.00961 -1.281684)
			(end 20.98294 -1.198626)
			(stroke
				(width 0.1)
				(type default)
			)
			(layer "F.SilkS")
		)
		(fp_line
			(start 21.00961 -1.281684)
			(end 20.98294 -1.198626)
			(stroke
				(width 0.1)
				(type default)
			)
			(layer "F.SilkS")
		)
		(fp_line
			(start 21.020278 -6.60146)
			(end 19.664172 -5.300472)
			(stroke
				(width 0.1)
				(type default)
			)
			(layer "F.SilkS")
		)
		(fp_line
			(start 21.020278 -6.60146)
			(end 19.664172 -5.300472)
			(stroke
				(width 0.1)
				(type default)
			)
			(layer "F.SilkS")
		)
		(fp_line
			(start 21.020278 -6.60146)
			(end 21.03247 -6.671056)
			(stroke
				(width 0.1)
				(type default)
			)
			(layer "F.SilkS")
		)
		(fp_line
			(start 21.020278 -6.60146)
			(end 21.03247 -6.671056)
			(stroke
				(width 0.1)
				(type default)
			)
			(layer "F.SilkS")
		)
		(fp_line
			(start 21.03247 -6.671056)
			(end 19.676364 -5.370068)
			(stroke
				(width 0.1)
				(type default)
			)
			(layer "F.SilkS")
		)
		(fp_line
			(start 21.03247 -6.671056)
			(end 19.676364 -5.370068)
			(stroke
				(width 0.1)
				(type default)
			)
			(layer "F.SilkS")
		)
		(fp_line
			(start 21.03247 -6.671056)
			(end 21.044662 -6.740144)
			(stroke
				(width 0.1)
				(type default)
			)
			(layer "F.SilkS")
		)
		(fp_line
			(start 21.03247 -6.671056)
			(end 21.044662 -6.740144)
			(stroke
				(width 0.1)
				(type default)
			)
			(layer "F.SilkS")
		)
		(fp_line
			(start 21.033994 -5.171694)
			(end 19.35988 -3.56616)
			(stroke
				(width 0.1)
				(type default)
			)
			(layer "F.SilkS")
		)
		(fp_line
			(start 21.033994 -5.171694)
			(end 19.35988 -3.56616)
			(stroke
				(width 0.1)
				(type default)
			)
			(layer "F.SilkS")
		)
		(fp_line
			(start 21.033994 -5.171694)
			(end 20.973542 -5.171694)
			(stroke
				(width 0.1)
				(type default)
			)
			(layer "F.SilkS")
		)
		(fp_line
			(start 21.033994 -5.171694)
			(end 20.973542 -5.171694)
			(stroke
				(width 0.1)
				(type default)
			)
			(layer "F.SilkS")
		)
		(fp_line
			(start 21.035772 -1.364742)
			(end 21.00961 -1.281684)
			(stroke
				(width 0.1)
				(type default)
			)
			(layer "F.SilkS")
		)
		(fp_line
			(start 21.035772 -1.364742)
			(end 21.00961 -1.281684)
			(stroke
				(width 0.1)
				(type default)
			)
			(layer "F.SilkS")
		)
		(fp_line
			(start 21.044662 -6.740144)
			(end 19.688302 -5.439156)
			(stroke
				(width 0.1)
				(type default)
			)
			(layer "F.SilkS")
		)
		(fp_line
			(start 21.044662 -6.740144)
			(end 19.688302 -5.439156)
			(stroke
				(width 0.1)
				(type default)
			)
			(layer "F.SilkS")
		)
		(fp_line
			(start 21.044662 -6.740144)
			(end 21.057108 -6.80974)
			(stroke
				(width 0.1)
				(type default)
			)
			(layer "F.SilkS")
		)
		(fp_line
			(start 21.044662 -6.740144)
			(end 21.057108 -6.80974)
			(stroke
				(width 0.1)
				(type default)
			)
			(layer "F.SilkS")
		)
		(fp_line
			(start 21.057108 -6.80974)
			(end 19.700748 -5.508752)
			(stroke
				(width 0.1)
				(type default)
			)
			(layer "F.SilkS")
		)
		(fp_line
			(start 21.057108 -6.80974)
			(end 19.700748 -5.508752)
			(stroke
				(width 0.1)
				(type default)
			)
			(layer "F.SilkS")
		)
		(fp_line
			(start 21.057108 -6.80974)
			(end 21.061934 -6.838188)
			(stroke
				(width 0.1)
				(type default)
			)
			(layer "F.SilkS")
		)
		(fp_line
			(start 21.057108 -6.80974)
			(end 21.061934 -6.838188)
			(stroke
				(width 0.1)
				(type default)
			)
			(layer "F.SilkS")
		)
		(fp_line
			(start 21.061934 -6.838188)
			(end 20.993354 -6.806438)
			(stroke
				(width 0.1)
				(type default)
			)
			(layer "F.SilkS")
		)
		(fp_line
			(start 21.061934 -6.838188)
			(end 20.993354 -6.806438)
			(stroke
				(width 0.1)
				(type default)
			)
			(layer "F.SilkS")
		)
		(fp_line
			(start 21.062188 -1.447546)
			(end 21.035772 -1.364742)
			(stroke
				(width 0.1)
				(type default)
			)
			(layer "F.SilkS")
		)
		(fp_line
			(start 21.062188 -1.447546)
			(end 21.035772 -1.364742)
			(stroke
				(width 0.1)
				(type default)
			)
			(layer "F.SilkS")
		)
		(fp_line
			(start 21.069554 -4.109466)
			(end 21.129752 -4.109466)
			(stroke
				(width 0.1)
				(type default)
			)
			(layer "F.SilkS")
		)
		(fp_line
			(start 21.069554 -4.109466)
			(end 21.129752 -4.109466)
			(stroke
				(width 0.1)
				(type default)
			)
			(layer "F.SilkS")
		)
		(fp_line
			(start 21.088858 -1.530604)
			(end 21.062188 -1.447546)
			(stroke
				(width 0.1)
				(type default)
			)
			(layer "F.SilkS")
		)
		(fp_line
			(start 21.088858 -1.530604)
			(end 21.062188 -1.447546)
			(stroke
				(width 0.1)
				(type default)
			)
			(layer "F.SilkS")
		)
		(fp_line
			(start 21.093938 -5.171694)
			(end 19.347942 -3.496564)
			(stroke
				(width 0.1)
				(type default)
			)
			(layer "F.SilkS")
		)
		(fp_line
			(start 21.093938 -5.171694)
			(end 19.347942 -3.496564)
			(stroke
				(width 0.1)
				(type default)
			)
			(layer "F.SilkS")
		)
		(fp_line
			(start 21.093938 -5.171694)
			(end 21.033994 -5.171694)
			(stroke
				(width 0.1)
				(type default)
			)
			(layer "F.SilkS")
		)
		(fp_line
			(start 21.093938 -5.171694)
			(end 21.033994 -5.171694)
			(stroke
				(width 0.1)
				(type default)
			)
			(layer "F.SilkS")
		)
		(fp_line
			(start 21.115274 -1.613916)
			(end 21.088858 -1.530604)
			(stroke
				(width 0.1)
				(type default)
			)
			(layer "F.SilkS")
		)
		(fp_line
			(start 21.115274 -1.613916)
			(end 21.088858 -1.530604)
			(stroke
				(width 0.1)
				(type default)
			)
			(layer "F.SilkS")
		)
		(fp_line
			(start 21.129752 -4.109466)
			(end 21.18995 -4.109466)
			(stroke
				(width 0.1)
				(type default)
			)
			(layer "F.SilkS")
		)
		(fp_line
			(start 21.129752 -4.109466)
			(end 21.18995 -4.109466)
			(stroke
				(width 0.1)
				(type default)
			)
			(layer "F.SilkS")
		)
		(fp_line
			(start 21.141436 -1.69672)
			(end 21.115274 -1.613916)
			(stroke
				(width 0.1)
				(type default)
			)
			(layer "F.SilkS")
		)
		(fp_line
			(start 21.141436 -1.69672)
			(end 21.115274 -1.613916)
			(stroke
				(width 0.1)
				(type default)
			)
			(layer "F.SilkS")
		)
		(fp_line
			(start 21.154136 -5.171694)
			(end 19.33575 -3.427476)
			(stroke
				(width 0.1)
				(type default)
			)
			(layer "F.SilkS")
		)
		(fp_line
			(start 21.154136 -5.171694)
			(end 19.33575 -3.427476)
			(stroke
				(width 0.1)
				(type default)
			)
			(layer "F.SilkS")
		)
		(fp_line
			(start 21.154136 -5.171694)
			(end 21.093938 -5.171694)
			(stroke
				(width 0.1)
				(type default)
			)
			(layer "F.SilkS")
		)
		(fp_line
			(start 21.154136 -5.171694)
			(end 21.093938 -5.171694)
			(stroke
				(width 0.1)
				(type default)
			)
			(layer "F.SilkS")
		)
		(fp_line
			(start 21.167852 -1.779778)
			(end 21.141436 -1.69672)
			(stroke
				(width 0.1)
				(type default)
			)
			(layer "F.SilkS")
		)
		(fp_line
			(start 21.167852 -1.779778)
			(end 21.141436 -1.69672)
			(stroke
				(width 0.1)
				(type default)
			)
			(layer "F.SilkS")
		)
		(fp_line
			(start 21.18995 -4.109466)
			(end 21.250402 -4.109466)
			(stroke
				(width 0.1)
				(type default)
			)
			(layer "F.SilkS")
		)
		(fp_line
			(start 21.18995 -4.109466)
			(end 21.250402 -4.109466)
			(stroke
				(width 0.1)
				(type default)
			)
			(layer "F.SilkS")
		)
		(fp_line
			(start 21.194268 -1.862836)
			(end 21.167852 -1.779778)
			(stroke
				(width 0.1)
				(type default)
			)
			(layer "F.SilkS")
		)
		(fp_line
			(start 21.194268 -1.862836)
			(end 21.167852 -1.779778)
			(stroke
				(width 0.1)
				(type default)
			)
			(layer "F.SilkS")
		)
		(fp_line
			(start 21.21408 -5.171694)
			(end 19.323558 -3.358134)
			(stroke
				(width 0.1)
				(type default)
			)
			(layer "F.SilkS")
		)
		(fp_line
			(start 21.21408 -5.171694)
			(end 19.323558 -3.358134)
			(stroke
				(width 0.1)
				(type default)
			)
			(layer "F.SilkS")
		)
		(fp_line
			(start 21.21408 -5.171694)
			(end 21.154136 -5.171694)
			(stroke
				(width 0.1)
				(type default)
			)
			(layer "F.SilkS")
		)
		(fp_line
			(start 21.21408 -5.171694)
			(end 21.154136 -5.171694)
			(stroke
				(width 0.1)
				(type default)
			)
			(layer "F.SilkS")
		)
		(fp_line
			(start 21.220684 -1.946148)
			(end 21.194268 -1.862836)
			(stroke
				(width 0.1)
				(type default)
			)
			(layer "F.SilkS")
		)
		(fp_line
			(start 21.220684 -1.946148)
			(end 21.194268 -1.862836)
			(stroke
				(width 0.1)
				(type default)
			)
			(layer "F.SilkS")
		)
		(fp_line
			(start 21.2471 -2.028952)
			(end 21.220684 -1.946148)
			(stroke
				(width 0.1)
				(type default)
			)
			(layer "F.SilkS")
		)
		(fp_line
			(start 21.2471 -2.028952)
			(end 21.220684 -1.946148)
			(stroke
				(width 0.1)
				(type default)
			)
			(layer "F.SilkS")
		)
		(fp_line
			(start 21.250402 -4.109466)
			(end 21.310346 -4.109466)
			(stroke
				(width 0.1)
				(type default)
			)
			(layer "F.SilkS")
		)
		(fp_line
			(start 21.250402 -4.109466)
			(end 21.310346 -4.109466)
			(stroke
				(width 0.1)
				(type default)
			)
			(layer "F.SilkS")
		)
		(fp_line
			(start 21.273516 -2.11201)
			(end 21.2471 -2.028952)
			(stroke
				(width 0.1)
				(type default)
			)
			(layer "F.SilkS")
		)
		(fp_line
			(start 21.273516 -2.11201)
			(end 21.2471 -2.028952)
			(stroke
				(width 0.1)
				(type default)
			)
			(layer "F.SilkS")
		)
		(fp_line
			(start 21.274532 -5.171694)
			(end 19.311366 -3.288538)
			(stroke
				(width 0.1)
				(type default)
			)
			(layer "F.SilkS")
		)
		(fp_line
			(start 21.274532 -5.171694)
			(end 19.311366 -3.288538)
			(stroke
				(width 0.1)
				(type default)
			)
			(layer "F.SilkS")
		)
		(fp_line
			(start 21.274532 -5.171694)
			(end 21.21408 -5.171694)
			(stroke
				(width 0.1)
				(type default)
			)
			(layer "F.SilkS")
		)
		(fp_line
			(start 21.274532 -5.171694)
			(end 21.21408 -5.171694)
			(stroke
				(width 0.1)
				(type default)
			)
			(layer "F.SilkS")
		)
		(fp_line
			(start 21.299932 -2.195068)
			(end 21.273516 -2.11201)
			(stroke
				(width 0.1)
				(type default)
			)
			(layer "F.SilkS")
		)
		(fp_line
			(start 21.299932 -2.195068)
			(end 21.273516 -2.11201)
			(stroke
				(width 0.1)
				(type default)
			)
			(layer "F.SilkS")
		)
		(fp_line
			(start 21.310346 -4.109466)
			(end 21.370544 -4.109466)
			(stroke
				(width 0.1)
				(type default)
			)
			(layer "F.SilkS")
		)
		(fp_line
			(start 21.310346 -4.109466)
			(end 21.370544 -4.109466)
			(stroke
				(width 0.1)
				(type default)
			)
			(layer "F.SilkS")
		)
		(fp_line
			(start 21.33473 -5.171694)
			(end 19.299428 -3.218942)
			(stroke
				(width 0.1)
				(type default)
			)
			(layer "F.SilkS")
		)
		(fp_line
			(start 21.33473 -5.171694)
			(end 19.299428 -3.218942)
			(stroke
				(width 0.1)
				(type default)
			)
			(layer "F.SilkS")
		)
		(fp_line
			(start 21.33473 -5.171694)
			(end 21.274532 -5.171694)
			(stroke
				(width 0.1)
				(type default)
			)
			(layer "F.SilkS")
		)
		(fp_line
			(start 21.33473 -5.171694)
			(end 21.274532 -5.171694)
			(stroke
				(width 0.1)
				(type default)
			)
			(layer "F.SilkS")
		)
		(fp_line
			(start 21.370544 -4.109466)
			(end 21.430742 -4.109466)
			(stroke
				(width 0.1)
				(type default)
			)
			(layer "F.SilkS")
		)
		(fp_line
			(start 21.370544 -4.109466)
			(end 21.430742 -4.109466)
			(stroke
				(width 0.1)
				(type default)
			)
			(layer "F.SilkS")
		)
		(fp_line
			(start 21.394674 -5.171694)
			(end 19.286982 -3.149854)
			(stroke
				(width 0.1)
				(type default)
			)
			(layer "F.SilkS")
		)
		(fp_line
			(start 21.394674 -5.171694)
			(end 19.286982 -3.149854)
			(stroke
				(width 0.1)
				(type default)
			)
			(layer "F.SilkS")
		)
		(fp_line
			(start 21.394674 -5.171694)
			(end 21.33473 -5.171694)
			(stroke
				(width 0.1)
				(type default)
			)
			(layer "F.SilkS")
		)
		(fp_line
			(start 21.394674 -5.171694)
			(end 21.33473 -5.171694)
			(stroke
				(width 0.1)
				(type default)
			)
			(layer "F.SilkS")
		)
		(fp_line
			(start 21.430742 -4.109466)
			(end 21.490686 -4.109466)
			(stroke
				(width 0.1)
				(type default)
			)
			(layer "F.SilkS")
		)
		(fp_line
			(start 21.430742 -4.109466)
			(end 21.490686 -4.109466)
			(stroke
				(width 0.1)
				(type default)
			)
			(layer "F.SilkS")
		)
		(fp_line
			(start 21.454872 -5.171694)
			(end 19.27479 -3.080512)
			(stroke
				(width 0.1)
				(type default)
			)
			(layer "F.SilkS")
		)
		(fp_line
			(start 21.454872 -5.171694)
			(end 19.27479 -3.080512)
			(stroke
				(width 0.1)
				(type default)
			)
			(layer "F.SilkS")
		)
		(fp_line
			(start 21.454872 -5.171694)
			(end 21.394674 -5.171694)
			(stroke
				(width 0.1)
				(type default)
			)
			(layer "F.SilkS")
		)
		(fp_line
			(start 21.454872 -5.171694)
			(end 21.394674 -5.171694)
			(stroke
				(width 0.1)
				(type default)
			)
			(layer "F.SilkS")
		)
		(fp_line
			(start 21.490686 -4.109466)
			(end 21.55063 -4.109466)
			(stroke
				(width 0.1)
				(type default)
			)
			(layer "F.SilkS")
		)
		(fp_line
			(start 21.490686 -4.109466)
			(end 21.55063 -4.109466)
			(stroke
				(width 0.1)
				(type default)
			)
			(layer "F.SilkS")
		)
		(fp_line
			(start 21.515324 -5.171694)
			(end 19.262852 -3.01117)
			(stroke
				(width 0.1)
				(type default)
			)
			(layer "F.SilkS")
		)
		(fp_line
			(start 21.515324 -5.171694)
			(end 19.262852 -3.01117)
			(stroke
				(width 0.1)
				(type default)
			)
			(layer "F.SilkS")
		)
		(fp_line
			(start 21.515324 -5.171694)
			(end 21.454872 -5.171694)
			(stroke
				(width 0.1)
				(type default)
			)
			(layer "F.SilkS")
		)
		(fp_line
			(start 21.515324 -5.171694)
			(end 21.454872 -5.171694)
			(stroke
				(width 0.1)
				(type default)
			)
			(layer "F.SilkS")
		)
		(fp_line
			(start 21.55063 -4.109466)
			(end 21.611082 -4.109466)
			(stroke
				(width 0.1)
				(type default)
			)
			(layer "F.SilkS")
		)
		(fp_line
			(start 21.55063 -4.109466)
			(end 21.611082 -4.109466)
			(stroke
				(width 0.1)
				(type default)
			)
			(layer "F.SilkS")
		)
		(fp_line
			(start 21.575522 -5.171694)
			(end 19.250406 -2.941574)
			(stroke
				(width 0.1)
				(type default)
			)
			(layer "F.SilkS")
		)
		(fp_line
			(start 21.575522 -5.171694)
			(end 19.250406 -2.941574)
			(stroke
				(width 0.1)
				(type default)
			)
			(layer "F.SilkS")
		)
		(fp_line
			(start 21.575522 -5.171694)
			(end 21.515324 -5.171694)
			(stroke
				(width 0.1)
				(type default)
			)
			(layer "F.SilkS")
		)
		(fp_line
			(start 21.575522 -5.171694)
			(end 21.515324 -5.171694)
			(stroke
				(width 0.1)
				(type default)
			)
			(layer "F.SilkS")
		)
		(fp_line
			(start 21.612352 -4.109466)
			(end 21.611082 -4.109466)
			(stroke
				(width 0.1)
				(type default)
			)
			(layer "F.SilkS")
		)
		(fp_line
			(start 21.612352 -4.109466)
			(end 21.611082 -4.109466)
			(stroke
				(width 0.1)
				(type default)
			)
			(layer "F.SilkS")
		)
		(fp_line
			(start 21.61286 -4.11099)
			(end 21.611082 -4.109466)
			(stroke
				(width 0.1)
				(type default)
			)
			(layer "F.SilkS")
		)
		(fp_line
			(start 21.61286 -4.11099)
			(end 21.611082 -4.109466)
			(stroke
				(width 0.1)
				(type default)
			)
			(layer "F.SilkS")
		)
		(fp_line
			(start 21.61286 -4.11099)
			(end 21.612352 -4.109466)
			(stroke
				(width 0.1)
				(type default)
			)
			(layer "F.SilkS")
		)
		(fp_line
			(start 21.61286 -4.11099)
			(end 21.612352 -4.109466)
			(stroke
				(width 0.1)
				(type default)
			)
			(layer "F.SilkS")
		)
		(fp_line
			(start 21.61286 -4.11099)
			(end 21.624798 -4.180586)
			(stroke
				(width 0.1)
				(type default)
			)
			(layer "F.SilkS")
		)
		(fp_line
			(start 21.61286 -4.11099)
			(end 21.624798 -4.180586)
			(stroke
				(width 0.1)
				(type default)
			)
			(layer "F.SilkS")
		)
		(fp_line
			(start 21.624798 -4.180586)
			(end 21.55063 -4.109466)
			(stroke
				(width 0.1)
				(type default)
			)
			(layer "F.SilkS")
		)
		(fp_line
			(start 21.624798 -4.180586)
			(end 21.55063 -4.109466)
			(stroke
				(width 0.1)
				(type default)
			)
			(layer "F.SilkS")
		)
		(fp_line
			(start 21.624798 -4.180586)
			(end 21.636736 -4.249674)
			(stroke
				(width 0.1)
				(type default)
			)
			(layer "F.SilkS")
		)
		(fp_line
			(start 21.624798 -4.180586)
			(end 21.636736 -4.249674)
			(stroke
				(width 0.1)
				(type default)
			)
			(layer "F.SilkS")
		)
		(fp_line
			(start 21.635466 -5.171694)
			(end 21.575522 -5.171694)
			(stroke
				(width 0.1)
				(type default)
			)
			(layer "F.SilkS")
		)
		(fp_line
			(start 21.635466 -5.171694)
			(end 21.575522 -5.171694)
			(stroke
				(width 0.1)
				(type default)
			)
			(layer "F.SilkS")
		)
		(fp_line
			(start 21.636736 -4.249674)
			(end 21.490686 -4.109466)
			(stroke
				(width 0.1)
				(type default)
			)
			(layer "F.SilkS")
		)
		(fp_line
			(start 21.636736 -4.249674)
			(end 21.490686 -4.109466)
			(stroke
				(width 0.1)
				(type default)
			)
			(layer "F.SilkS")
		)
		(fp_line
			(start 21.636736 -4.249674)
			(end 21.649182 -4.319016)
			(stroke
				(width 0.1)
				(type default)
			)
			(layer "F.SilkS")
		)
		(fp_line
			(start 21.636736 -4.249674)
			(end 21.649182 -4.319016)
			(stroke
				(width 0.1)
				(type default)
			)
			(layer "F.SilkS")
		)
		(fp_line
			(start 21.649182 -4.319016)
			(end 21.430742 -4.109466)
			(stroke
				(width 0.1)
				(type default)
			)
			(layer "F.SilkS")
		)
		(fp_line
			(start 21.649182 -4.319016)
			(end 21.430742 -4.109466)
			(stroke
				(width 0.1)
				(type default)
			)
			(layer "F.SilkS")
		)
		(fp_line
			(start 21.649182 -4.319016)
			(end 21.661374 -4.388358)
			(stroke
				(width 0.1)
				(type default)
			)
			(layer "F.SilkS")
		)
		(fp_line
			(start 21.649182 -4.319016)
			(end 21.661374 -4.388358)
			(stroke
				(width 0.1)
				(type default)
			)
			(layer "F.SilkS")
		)
		(fp_line
			(start 21.661374 -4.388358)
			(end 21.370544 -4.109466)
			(stroke
				(width 0.1)
				(type default)
			)
			(layer "F.SilkS")
		)
		(fp_line
			(start 21.661374 -4.388358)
			(end 21.370544 -4.109466)
			(stroke
				(width 0.1)
				(type default)
			)
			(layer "F.SilkS")
		)
		(fp_line
			(start 21.661374 -4.388358)
			(end 21.673312 -4.457954)
			(stroke
				(width 0.1)
				(type default)
			)
			(layer "F.SilkS")
		)
		(fp_line
			(start 21.661374 -4.388358)
			(end 21.673312 -4.457954)
			(stroke
				(width 0.1)
				(type default)
			)
			(layer "F.SilkS")
		)
		(fp_line
			(start 21.673312 -4.457954)
			(end 21.310346 -4.109466)
			(stroke
				(width 0.1)
				(type default)
			)
			(layer "F.SilkS")
		)
		(fp_line
			(start 21.673312 -4.457954)
			(end 21.310346 -4.109466)
			(stroke
				(width 0.1)
				(type default)
			)
			(layer "F.SilkS")
		)
		(fp_line
			(start 21.673312 -4.457954)
			(end 21.685504 -4.527296)
			(stroke
				(width 0.1)
				(type default)
			)
			(layer "F.SilkS")
		)
		(fp_line
			(start 21.673312 -4.457954)
			(end 21.685504 -4.527296)
			(stroke
				(width 0.1)
				(type default)
			)
			(layer "F.SilkS")
		)
		(fp_line
			(start 21.685504 -4.527296)
			(end 21.250402 -4.109466)
			(stroke
				(width 0.1)
				(type default)
			)
			(layer "F.SilkS")
		)
		(fp_line
			(start 21.685504 -4.527296)
			(end 21.250402 -4.109466)
			(stroke
				(width 0.1)
				(type default)
			)
			(layer "F.SilkS")
		)
		(fp_line
			(start 21.685504 -4.527296)
			(end 21.69795 -4.596638)
			(stroke
				(width 0.1)
				(type default)
			)
			(layer "F.SilkS")
		)
		(fp_line
			(start 21.685504 -4.527296)
			(end 21.69795 -4.596638)
			(stroke
				(width 0.1)
				(type default)
			)
			(layer "F.SilkS")
		)
		(fp_line
			(start 21.69541 -5.171694)
			(end 20.588224 -4.109466)
			(stroke
				(width 0.1)
				(type default)
			)
			(layer "F.SilkS")
		)
		(fp_line
			(start 21.69541 -5.171694)
			(end 20.588224 -4.109466)
			(stroke
				(width 0.1)
				(type default)
			)
			(layer "F.SilkS")
		)
		(fp_line
			(start 21.69541 -5.171694)
			(end 21.635466 -5.171694)
			(stroke
				(width 0.1)
				(type default)
			)
			(layer "F.SilkS")
		)
		(fp_line
			(start 21.69541 -5.171694)
			(end 21.635466 -5.171694)
			(stroke
				(width 0.1)
				(type default)
			)
			(layer "F.SilkS")
		)
		(fp_line
			(start 21.69795 -4.596638)
			(end 21.18995 -4.109466)
			(stroke
				(width 0.1)
				(type default)
			)
			(layer "F.SilkS")
		)
		(fp_line
			(start 21.69795 -4.596638)
			(end 21.18995 -4.109466)
			(stroke
				(width 0.1)
				(type default)
			)
			(layer "F.SilkS")
		)
		(fp_line
			(start 21.69795 -4.596638)
			(end 21.709888 -4.66598)
			(stroke
				(width 0.1)
				(type default)
			)
			(layer "F.SilkS")
		)
		(fp_line
			(start 21.69795 -4.596638)
			(end 21.709888 -4.66598)
			(stroke
				(width 0.1)
				(type default)
			)
			(layer "F.SilkS")
		)
		(fp_line
			(start 21.709888 -4.66598)
			(end 21.129752 -4.109466)
			(stroke
				(width 0.1)
				(type default)
			)
			(layer "F.SilkS")
		)
		(fp_line
			(start 21.709888 -4.66598)
			(end 21.129752 -4.109466)
			(stroke
				(width 0.1)
				(type default)
			)
			(layer "F.SilkS")
		)
		(fp_line
			(start 21.709888 -4.66598)
			(end 21.721826 -4.735576)
			(stroke
				(width 0.1)
				(type default)
			)
			(layer "F.SilkS")
		)
		(fp_line
			(start 21.709888 -4.66598)
			(end 21.721826 -4.735576)
			(stroke
				(width 0.1)
				(type default)
			)
			(layer "F.SilkS")
		)
		(fp_line
			(start 21.721826 -4.735576)
			(end 21.069554 -4.109466)
			(stroke
				(width 0.1)
				(type default)
			)
			(layer "F.SilkS")
		)
		(fp_line
			(start 21.721826 -4.735576)
			(end 21.069554 -4.109466)
			(stroke
				(width 0.1)
				(type default)
			)
			(layer "F.SilkS")
		)
		(fp_line
			(start 21.721826 -4.735576)
			(end 21.734018 -4.804664)
			(stroke
				(width 0.1)
				(type default)
			)
			(layer "F.SilkS")
		)
		(fp_line
			(start 21.721826 -4.735576)
			(end 21.734018 -4.804664)
			(stroke
				(width 0.1)
				(type default)
			)
			(layer "F.SilkS")
		)
		(fp_line
			(start 21.734018 -4.804664)
			(end 21.00961 -4.109466)
			(stroke
				(width 0.1)
				(type default)
			)
			(layer "F.SilkS")
		)
		(fp_line
			(start 21.734018 -4.804664)
			(end 21.00961 -4.109466)
			(stroke
				(width 0.1)
				(type default)
			)
			(layer "F.SilkS")
		)
		(fp_line
			(start 21.734018 -4.804664)
			(end 21.746464 -4.874006)
			(stroke
				(width 0.1)
				(type default)
			)
			(layer "F.SilkS")
		)
		(fp_line
			(start 21.734018 -4.804664)
			(end 21.746464 -4.874006)
			(stroke
				(width 0.1)
				(type default)
			)
			(layer "F.SilkS")
		)
		(fp_line
			(start 21.746464 -4.874006)
			(end 20.949666 -4.109466)
			(stroke
				(width 0.1)
				(type default)
			)
			(layer "F.SilkS")
		)
		(fp_line
			(start 21.746464 -4.874006)
			(end 20.949666 -4.109466)
			(stroke
				(width 0.1)
				(type default)
			)
			(layer "F.SilkS")
		)
		(fp_line
			(start 21.746464 -4.874006)
			(end 21.758402 -4.943348)
			(stroke
				(width 0.1)
				(type default)
			)
			(layer "F.SilkS")
		)
		(fp_line
			(start 21.746464 -4.874006)
			(end 21.758402 -4.943348)
			(stroke
				(width 0.1)
				(type default)
			)
			(layer "F.SilkS")
		)
		(fp_line
			(start 21.755608 -5.171694)
			(end 20.648422 -4.109466)
			(stroke
				(width 0.1)
				(type default)
			)
			(layer "F.SilkS")
		)
		(fp_line
			(start 21.755608 -5.171694)
			(end 20.648422 -4.109466)
			(stroke
				(width 0.1)
				(type default)
			)
			(layer "F.SilkS")
		)
		(fp_line
			(start 21.755608 -5.171694)
			(end 21.69541 -5.171694)
			(stroke
				(width 0.1)
				(type default)
			)
			(layer "F.SilkS")
		)
		(fp_line
			(start 21.755608 -5.171694)
			(end 21.69541 -5.171694)
			(stroke
				(width 0.1)
				(type default)
			)
			(layer "F.SilkS")
		)
		(fp_line
			(start 21.758402 -4.943348)
			(end 20.889214 -4.109466)
			(stroke
				(width 0.1)
				(type default)
			)
			(layer "F.SilkS")
		)
		(fp_line
			(start 21.758402 -4.943348)
			(end 20.889214 -4.109466)
			(stroke
				(width 0.1)
				(type default)
			)
			(layer "F.SilkS")
		)
		(fp_line
			(start 21.758402 -4.943348)
			(end 21.770594 -5.012944)
			(stroke
				(width 0.1)
				(type default)
			)
			(layer "F.SilkS")
		)
		(fp_line
			(start 21.758402 -4.943348)
			(end 21.770594 -5.012944)
			(stroke
				(width 0.1)
				(type default)
			)
			(layer "F.SilkS")
		)
		(fp_line
			(start 21.770594 -5.012944)
			(end 20.829016 -4.109466)
			(stroke
				(width 0.1)
				(type default)
			)
			(layer "F.SilkS")
		)
		(fp_line
			(start 21.770594 -5.012944)
			(end 20.829016 -4.109466)
			(stroke
				(width 0.1)
				(type default)
			)
			(layer "F.SilkS")
		)
		(fp_line
			(start 21.770594 -5.012944)
			(end 21.78304 -5.082032)
			(stroke
				(width 0.1)
				(type default)
			)
			(layer "F.SilkS")
		)
		(fp_line
			(start 21.770594 -5.012944)
			(end 21.78304 -5.082032)
			(stroke
				(width 0.1)
				(type default)
			)
			(layer "F.SilkS")
		)
		(fp_line
			(start 21.78304 -5.082032)
			(end 20.768564 -4.109466)
			(stroke
				(width 0.1)
				(type default)
			)
			(layer "F.SilkS")
		)
		(fp_line
			(start 21.78304 -5.082032)
			(end 20.768564 -4.109466)
			(stroke
				(width 0.1)
				(type default)
			)
			(layer "F.SilkS")
		)
		(fp_line
			(start 21.78304 -5.082032)
			(end 21.794978 -5.151374)
			(stroke
				(width 0.1)
				(type default)
			)
			(layer "F.SilkS")
		)
		(fp_line
			(start 21.78304 -5.082032)
			(end 21.794978 -5.151374)
			(stroke
				(width 0.1)
				(type default)
			)
			(layer "F.SilkS")
		)
		(fp_line
			(start 21.794978 -5.151374)
			(end 20.70862 -4.109466)
			(stroke
				(width 0.1)
				(type default)
			)
			(layer "F.SilkS")
		)
		(fp_line
			(start 21.794978 -5.151374)
			(end 20.70862 -4.109466)
			(stroke
				(width 0.1)
				(type default)
			)
			(layer "F.SilkS")
		)
		(fp_line
			(start 21.794978 -5.151374)
			(end 21.798534 -5.171694)
			(stroke
				(width 0.1)
				(type default)
			)
			(layer "F.SilkS")
		)
		(fp_line
			(start 21.794978 -5.151374)
			(end 21.798534 -5.171694)
			(stroke
				(width 0.1)
				(type default)
			)
			(layer "F.SilkS")
		)
		(fp_line
			(start 21.798534 -5.171694)
			(end 21.755608 -5.171694)
			(stroke
				(width 0.1)
				(type default)
			)
			(layer "F.SilkS")
		)
		(fp_line
			(start 21.798534 -5.171694)
			(end 21.755608 -5.171694)
			(stroke
				(width 0.1)
				(type default)
			)
			(layer "F.SilkS")
		)
		(fp_line
			(start 21.838158 -2.018792)
			(end 23.619206 -3.727196)
			(stroke
				(width 0.1)
				(type default)
			)
			(layer "F.SilkS")
		)
		(fp_line
			(start 21.838158 -2.018792)
			(end 23.619206 -3.727196)
			(stroke
				(width 0.1)
				(type default)
			)
			(layer "F.SilkS")
		)
		(fp_line
			(start 21.839428 -2.07772)
			(end 23.55469 -3.723386)
			(stroke
				(width 0.1)
				(type default)
			)
			(layer "F.SilkS")
		)
		(fp_line
			(start 21.839428 -2.07772)
			(end 23.55469 -3.723386)
			(stroke
				(width 0.1)
				(type default)
			)
			(layer "F.SilkS")
		)
		(fp_line
			(start 21.841206 -2.137156)
			(end 23.489666 -3.71856)
			(stroke
				(width 0.1)
				(type default)
			)
			(layer "F.SilkS")
		)
		(fp_line
			(start 21.841206 -2.137156)
			(end 23.489666 -3.71856)
			(stroke
				(width 0.1)
				(type default)
			)
			(layer "F.SilkS")
		)
		(fp_line
			(start 21.841206 -1.90627)
			(end 23.747984 -3.735324)
			(stroke
				(width 0.1)
				(type default)
			)
			(layer "F.SilkS")
		)
		(fp_line
			(start 21.841206 -1.90627)
			(end 23.747984 -3.735324)
			(stroke
				(width 0.1)
				(type default)
			)
			(layer "F.SilkS")
		)
		(fp_line
			(start 21.846032 -1.853184)
			(end 23.811992 -3.739388)
			(stroke
				(width 0.1)
				(type default)
			)
			(layer "F.SilkS")
		)
		(fp_line
			(start 21.846032 -1.853184)
			(end 23.811992 -3.739388)
			(stroke
				(width 0.1)
				(type default)
			)
			(layer "F.SilkS")
		)
		(fp_line
			(start 21.849334 -2.202942)
			(end 23.414228 -3.703828)
			(stroke
				(width 0.1)
				(type default)
			)
			(layer "F.SilkS")
		)
		(fp_line
			(start 21.849334 -2.202942)
			(end 23.414228 -3.703828)
			(stroke
				(width 0.1)
				(type default)
			)
			(layer "F.SilkS")
		)
		(fp_line
			(start 21.850858 -1.799844)
			(end 23.874222 -3.740912)
			(stroke
				(width 0.1)
				(type default)
			)
			(layer "F.SilkS")
		)
		(fp_line
			(start 21.850858 -1.799844)
			(end 23.874222 -3.740912)
			(stroke
				(width 0.1)
				(type default)
			)
			(layer "F.SilkS")
		)
		(fp_line
			(start 21.85797 -2.268728)
			(end 23.338282 -3.688842)
			(stroke
				(width 0.1)
				(type default)
			)
			(layer "F.SilkS")
		)
		(fp_line
			(start 21.85797 -2.268728)
			(end 23.338282 -3.688842)
			(stroke
				(width 0.1)
				(type default)
			)
			(layer "F.SilkS")
		)
		(fp_line
			(start 21.86051 -1.75133)
			(end 23.930864 -3.737864)
			(stroke
				(width 0.1)
				(type default)
			)
			(layer "F.SilkS")
		)
		(fp_line
			(start 21.86051 -1.75133)
			(end 23.930864 -3.737864)
			(stroke
				(width 0.1)
				(type default)
			)
			(layer "F.SilkS")
		)
		(fp_line
			(start 21.869146 -2.337308)
			(end 23.26259 -3.673856)
			(stroke
				(width 0.1)
				(type default)
			)
			(layer "F.SilkS")
		)
		(fp_line
			(start 21.869146 -2.337308)
			(end 23.26259 -3.673856)
			(stroke
				(width 0.1)
				(type default)
			)
			(layer "F.SilkS")
		)
		(fp_line
			(start 21.870416 -1.703578)
			(end 23.98776 -3.734816)
			(stroke
				(width 0.1)
				(type default)
			)
			(layer "F.SilkS")
		)
		(fp_line
			(start 21.870416 -1.703578)
			(end 23.98776 -3.734816)
			(stroke
				(width 0.1)
				(type default)
			)
			(layer "F.SilkS")
		)
		(fp_line
			(start 21.88083 -1.655826)
			(end 24.04491 -3.731768)
			(stroke
				(width 0.1)
				(type default)
			)
			(layer "F.SilkS")
		)
		(fp_line
			(start 21.88083 -1.655826)
			(end 24.04491 -3.731768)
			(stroke
				(width 0.1)
				(type default)
			)
			(layer "F.SilkS")
		)
		(fp_line
			(start 21.89099 -2.416048)
			(end 23.187152 -3.659124)
			(stroke
				(width 0.1)
				(type default)
			)
			(layer "F.SilkS")
		)
		(fp_line
			(start 21.89099 -2.416048)
			(end 23.187152 -3.659124)
			(stroke
				(width 0.1)
				(type default)
			)
			(layer "F.SilkS")
		)
		(fp_line
			(start 21.894546 -1.611376)
			(end 24.101806 -3.728974)
			(stroke
				(width 0.1)
				(type default)
			)
			(layer "F.SilkS")
		)
		(fp_line
			(start 21.894546 -1.611376)
			(end 24.101806 -3.728974)
			(stroke
				(width 0.1)
				(type default)
			)
			(layer "F.SilkS")
		)
		(fp_line
			(start 21.909786 -1.568196)
			(end 24.154892 -3.721862)
			(stroke
				(width 0.1)
				(type default)
			)
			(layer "F.SilkS")
		)
		(fp_line
			(start 21.909786 -1.568196)
			(end 24.154892 -3.721862)
			(stroke
				(width 0.1)
				(type default)
			)
			(layer "F.SilkS")
		)
		(fp_line
			(start 21.913088 -2.494788)
			(end 23.10003 -3.63347)
			(stroke
				(width 0.1)
				(type default)
			)
			(layer "F.SilkS")
		)
		(fp_line
			(start 21.913088 -2.494788)
			(end 23.10003 -3.63347)
			(stroke
				(width 0.1)
				(type default)
			)
			(layer "F.SilkS")
		)
		(fp_line
			(start 21.924772 -1.525016)
			(end 24.205946 -3.712972)
			(stroke
				(width 0.1)
				(type default)
			)
			(layer "F.SilkS")
		)
		(fp_line
			(start 21.924772 -1.525016)
			(end 24.205946 -3.712972)
			(stroke
				(width 0.1)
				(type default)
			)
			(layer "F.SilkS")
		)
		(fp_line
			(start 21.93544 -2.573782)
			(end 23.00478 -3.599942)
			(stroke
				(width 0.1)
				(type default)
			)
			(layer "F.SilkS")
		)
		(fp_line
			(start 21.93544 -2.573782)
			(end 23.00478 -3.599942)
			(stroke
				(width 0.1)
				(type default)
			)
			(layer "F.SilkS")
		)
		(fp_line
			(start 21.942806 -1.484376)
			(end 23.220934 -2.710688)
			(stroke
				(width 0.1)
				(type default)
			)
			(layer "F.SilkS")
		)
		(fp_line
			(start 21.942806 -1.484376)
			(end 23.220934 -2.710688)
			(stroke
				(width 0.1)
				(type default)
			)
			(layer "F.SilkS")
		)
		(fp_line
			(start 21.957538 -2.652776)
			(end 22.909784 -3.56616)
			(stroke
				(width 0.1)
				(type default)
			)
			(layer "F.SilkS")
		)
		(fp_line
			(start 21.957538 -2.652776)
			(end 22.909784 -3.56616)
			(stroke
				(width 0.1)
				(type default)
			)
			(layer "F.SilkS")
		)
		(fp_line
			(start 21.962364 -1.445514)
			(end 23.052786 -2.491486)
			(stroke
				(width 0.1)
				(type default)
			)
			(layer "F.SilkS")
		)
		(fp_line
			(start 21.962364 -1.445514)
			(end 23.052786 -2.491486)
			(stroke
				(width 0.1)
				(type default)
			)
			(layer "F.SilkS")
		)
		(fp_line
			(start 21.981922 -1.406652)
			(end 23.020782 -2.403094)
			(stroke
				(width 0.1)
				(type default)
			)
			(layer "F.SilkS")
		)
		(fp_line
			(start 21.981922 -1.406652)
			(end 23.020782 -2.403094)
			(stroke
				(width 0.1)
				(type default)
			)
			(layer "F.SilkS")
		)
		(fp_line
			(start 22.003004 -1.36906)
			(end 22.99081 -2.31648)
			(stroke
				(width 0.1)
				(type default)
			)
			(layer "F.SilkS")
		)
		(fp_line
			(start 22.003004 -1.36906)
			(end 22.99081 -2.31648)
			(stroke
				(width 0.1)
				(type default)
			)
			(layer "F.SilkS")
		)
		(fp_line
			(start 22.017228 -2.767838)
			(end 22.802342 -3.521202)
			(stroke
				(width 0.1)
				(type default)
			)
			(layer "F.SilkS")
		)
		(fp_line
			(start 22.017228 -2.767838)
			(end 22.802342 -3.521202)
			(stroke
				(width 0.1)
				(type default)
			)
			(layer "F.SilkS")
		)
		(fp_line
			(start 22.02688 -1.334262)
			(end 22.984206 -2.252726)
			(stroke
				(width 0.1)
				(type default)
			)
			(layer "F.SilkS")
		)
		(fp_line
			(start 22.02688 -1.334262)
			(end 22.984206 -2.252726)
			(stroke
				(width 0.1)
				(type default)
			)
			(layer "F.SilkS")
		)
		(fp_line
			(start 22.05101 -1.299464)
			(end 22.981158 -2.19202)
			(stroke
				(width 0.1)
				(type default)
			)
			(layer "F.SilkS")
		)
		(fp_line
			(start 22.05101 -1.299464)
			(end 22.981158 -2.19202)
			(stroke
				(width 0.1)
				(type default)
			)
			(layer "F.SilkS")
		)
		(fp_line
			(start 22.07514 -1.265174)
			(end 22.985222 -2.137918)
			(stroke
				(width 0.1)
				(type default)
			)
			(layer "F.SilkS")
		)
		(fp_line
			(start 22.07514 -1.265174)
			(end 22.985222 -2.137918)
			(stroke
				(width 0.1)
				(type default)
			)
			(layer "F.SilkS")
		)
		(fp_line
			(start 22.077934 -2.883408)
			(end 22.662896 -3.444748)
			(stroke
				(width 0.1)
				(type default)
			)
			(layer "F.SilkS")
		)
		(fp_line
			(start 22.077934 -2.883408)
			(end 22.662896 -3.444748)
			(stroke
				(width 0.1)
				(type default)
			)
			(layer "F.SilkS")
		)
		(fp_line
			(start 22.10308 -1.233932)
			(end 22.992588 -2.087372)
			(stroke
				(width 0.1)
				(type default)
			)
			(layer "F.SilkS")
		)
		(fp_line
			(start 22.10308 -1.233932)
			(end 22.992588 -2.087372)
			(stroke
				(width 0.1)
				(type default)
			)
			(layer "F.SilkS")
		)
		(fp_line
			(start 22.130512 -1.202944)
			(end 23.005542 -2.042414)
			(stroke
				(width 0.1)
				(type default)
			)
			(layer "F.SilkS")
		)
		(fp_line
			(start 22.130512 -1.202944)
			(end 23.005542 -2.042414)
			(stroke
				(width 0.1)
				(type default)
			)
			(layer "F.SilkS")
		)
		(fp_line
			(start 22.158452 -1.171956)
			(end 23.020782 -1.99898)
			(stroke
				(width 0.1)
				(type default)
			)
			(layer "F.SilkS")
		)
		(fp_line
			(start 22.158452 -1.171956)
			(end 23.020782 -1.99898)
			(stroke
				(width 0.1)
				(type default)
			)
			(layer "F.SilkS")
		)
		(fp_line
			(start 22.18944 -1.143762)
			(end 23.042372 -1.96215)
			(stroke
				(width 0.1)
				(type default)
			)
			(layer "F.SilkS")
		)
		(fp_line
			(start 22.18944 -1.143762)
			(end 23.042372 -1.96215)
			(stroke
				(width 0.1)
				(type default)
			)
			(layer "F.SilkS")
		)
		(fp_line
			(start 22.22119 -1.11633)
			(end 23.06447 -1.925828)
			(stroke
				(width 0.1)
				(type default)
			)
			(layer "F.SilkS")
		)
		(fp_line
			(start 22.22119 -1.11633)
			(end 23.06447 -1.925828)
			(stroke
				(width 0.1)
				(type default)
			)
			(layer "F.SilkS")
		)
		(fp_line
			(start 22.252432 -1.089152)
			(end 23.094188 -1.896364)
			(stroke
				(width 0.1)
				(type default)
			)
			(layer "F.SilkS")
		)
		(fp_line
			(start 22.252432 -1.089152)
			(end 23.094188 -1.896364)
			(stroke
				(width 0.1)
				(type default)
			)
			(layer "F.SilkS")
		)
		(fp_line
			(start 22.286214 -1.063752)
			(end 23.124414 -1.867916)
			(stroke
				(width 0.1)
				(type default)
			)
			(layer "F.SilkS")
		)
		(fp_line
			(start 22.286214 -1.063752)
			(end 23.124414 -1.867916)
			(stroke
				(width 0.1)
				(type default)
			)
			(layer "F.SilkS")
		)
		(fp_line
			(start 22.321774 -1.039622)
			(end 23.158196 -1.842262)
			(stroke
				(width 0.1)
				(type default)
			)
			(layer "F.SilkS")
		)
		(fp_line
			(start 22.321774 -1.039622)
			(end 23.158196 -1.842262)
			(stroke
				(width 0.1)
				(type default)
			)
			(layer "F.SilkS")
		)
		(fp_line
			(start 22.356572 -1.015746)
			(end 23.197058 -1.821942)
			(stroke
				(width 0.1)
				(type default)
			)
			(layer "F.SilkS")
		)
		(fp_line
			(start 22.356572 -1.015746)
			(end 23.197058 -1.821942)
			(stroke
				(width 0.1)
				(type default)
			)
			(layer "F.SilkS")
		)
		(fp_line
			(start 22.393402 -0.993394)
			(end 23.235666 -1.801622)
			(stroke
				(width 0.1)
				(type default)
			)
			(layer "F.SilkS")
		)
		(fp_line
			(start 22.393402 -0.993394)
			(end 23.235666 -1.801622)
			(stroke
				(width 0.1)
				(type default)
			)
			(layer "F.SilkS")
		)
		(fp_line
			(start 22.43201 -0.97282)
			(end 23.280878 -1.786636)
			(stroke
				(width 0.1)
				(type default)
			)
			(layer "F.SilkS")
		)
		(fp_line
			(start 22.43201 -0.97282)
			(end 23.280878 -1.786636)
			(stroke
				(width 0.1)
				(type default)
			)
			(layer "F.SilkS")
		)
		(fp_line
			(start 22.470872 -0.952246)
			(end 23.328122 -1.774444)
			(stroke
				(width 0.1)
				(type default)
			)
			(layer "F.SilkS")
		)
		(fp_line
			(start 22.470872 -0.952246)
			(end 23.328122 -1.774444)
			(stroke
				(width 0.1)
				(type default)
			)
			(layer "F.SilkS")
		)
		(fp_line
			(start 22.510496 -0.932688)
			(end 23.375366 -1.761998)
			(stroke
				(width 0.1)
				(type default)
			)
			(layer "F.SilkS")
		)
		(fp_line
			(start 22.510496 -0.932688)
			(end 23.375366 -1.761998)
			(stroke
				(width 0.1)
				(type default)
			)
			(layer "F.SilkS")
		)
		(fp_line
			(start 22.552914 -0.91567)
			(end 23.430484 -1.757172)
			(stroke
				(width 0.1)
				(type default)
			)
			(layer "F.SilkS")
		)
		(fp_line
			(start 22.552914 -0.91567)
			(end 23.430484 -1.757172)
			(stroke
				(width 0.1)
				(type default)
			)
			(layer "F.SilkS")
		)
		(fp_line
			(start 22.595332 -0.898398)
			(end 23.48611 -1.752854)
			(stroke
				(width 0.1)
				(type default)
			)
			(layer "F.SilkS")
		)
		(fp_line
			(start 22.595332 -0.898398)
			(end 23.48611 -1.752854)
			(stroke
				(width 0.1)
				(type default)
			)
			(layer "F.SilkS")
		)
		(fp_line
			(start 22.638258 -0.881888)
			(end 23.54199 -1.74879)
			(stroke
				(width 0.1)
				(type default)
			)
			(layer "F.SilkS")
		)
		(fp_line
			(start 22.638258 -0.881888)
			(end 23.54199 -1.74879)
			(stroke
				(width 0.1)
				(type default)
			)
			(layer "F.SilkS")
		)
		(fp_line
			(start 22.651212 -4.81838)
			(end 22.66696 -4.776216)
			(stroke
				(width 0.1)
				(type default)
			)
			(layer "F.SilkS")
		)
		(fp_line
			(start 22.651212 -4.81838)
			(end 22.66696 -4.776216)
			(stroke
				(width 0.1)
				(type default)
			)
			(layer "F.SilkS")
		)
		(fp_line
			(start 22.651212 -4.81838)
			(end 22.676358 -4.842764)
			(stroke
				(width 0.1)
				(type default)
			)
			(layer "F.SilkS")
		)
		(fp_line
			(start 22.651212 -4.81838)
			(end 22.676358 -4.842764)
			(stroke
				(width 0.1)
				(type default)
			)
			(layer "F.SilkS")
		)
		(fp_line
			(start 22.66696 -4.776216)
			(end 22.682708 -4.733798)
			(stroke
				(width 0.1)
				(type default)
			)
			(layer "F.SilkS")
		)
		(fp_line
			(start 22.66696 -4.776216)
			(end 22.682708 -4.733798)
			(stroke
				(width 0.1)
				(type default)
			)
			(layer "F.SilkS")
		)
		(fp_line
			(start 22.66696 -4.776216)
			(end 22.802088 -4.905756)
			(stroke
				(width 0.1)
				(type default)
			)
			(layer "F.SilkS")
		)
		(fp_line
			(start 22.66696 -4.776216)
			(end 22.802088 -4.905756)
			(stroke
				(width 0.1)
				(type default)
			)
			(layer "F.SilkS")
		)
		(fp_line
			(start 22.682708 -4.733798)
			(end 22.698964 -4.69138)
			(stroke
				(width 0.1)
				(type default)
			)
			(layer "F.SilkS")
		)
		(fp_line
			(start 22.682708 -4.733798)
			(end 22.698964 -4.69138)
			(stroke
				(width 0.1)
				(type default)
			)
			(layer "F.SilkS")
		)
		(fp_line
			(start 22.682708 -4.733798)
			(end 22.919436 -4.960874)
			(stroke
				(width 0.1)
				(type default)
			)
			(layer "F.SilkS")
		)
		(fp_line
			(start 22.682708 -4.733798)
			(end 22.919436 -4.960874)
			(stroke
				(width 0.1)
				(type default)
			)
			(layer "F.SilkS")
		)
		(fp_line
			(start 22.684232 -0.868172)
			(end 23.610316 -1.756664)
			(stroke
				(width 0.1)
				(type default)
			)
			(layer "F.SilkS")
		)
		(fp_line
			(start 22.684232 -0.868172)
			(end 23.610316 -1.756664)
			(stroke
				(width 0.1)
				(type default)
			)
			(layer "F.SilkS")
		)
		(fp_line
			(start 22.698964 -4.69138)
			(end 22.714712 -4.648962)
			(stroke
				(width 0.1)
				(type default)
			)
			(layer "F.SilkS")
		)
		(fp_line
			(start 22.698964 -4.69138)
			(end 22.714712 -4.648962)
			(stroke
				(width 0.1)
				(type default)
			)
			(layer "F.SilkS")
		)
		(fp_line
			(start 22.698964 -4.69138)
			(end 23.03272 -5.01142)
			(stroke
				(width 0.1)
				(type default)
			)
			(layer "F.SilkS")
		)
		(fp_line
			(start 22.698964 -4.69138)
			(end 23.03272 -5.01142)
			(stroke
				(width 0.1)
				(type default)
			)
			(layer "F.SilkS")
		)
		(fp_line
			(start 22.714712 -4.648962)
			(end 22.730714 -4.606544)
			(stroke
				(width 0.1)
				(type default)
			)
			(layer "F.SilkS")
		)
		(fp_line
			(start 22.714712 -4.648962)
			(end 22.730714 -4.606544)
			(stroke
				(width 0.1)
				(type default)
			)
			(layer "F.SilkS")
		)
		(fp_line
			(start 22.714712 -4.648962)
			(end 23.13432 -5.051298)
			(stroke
				(width 0.1)
				(type default)
			)
			(layer "F.SilkS")
		)
		(fp_line
			(start 22.714712 -4.648962)
			(end 23.13432 -5.051298)
			(stroke
				(width 0.1)
				(type default)
			)
			(layer "F.SilkS")
		)
		(fp_line
			(start 22.729952 -0.85471)
			(end 23.67915 -1.765046)
			(stroke
				(width 0.1)
				(type default)
			)
			(layer "F.SilkS")
		)
		(fp_line
			(start 22.729952 -0.85471)
			(end 23.67915 -1.765046)
			(stroke
				(width 0.1)
				(type default)
			)
			(layer "F.SilkS")
		)
		(fp_line
			(start 22.730714 -4.606544)
			(end 22.74697 -4.564126)
			(stroke
				(width 0.1)
				(type default)
			)
			(layer "F.SilkS")
		)
		(fp_line
			(start 22.730714 -4.606544)
			(end 22.74697 -4.564126)
			(stroke
				(width 0.1)
				(type default)
			)
			(layer "F.SilkS")
		)
		(fp_line
			(start 22.730714 -4.606544)
			(end 23.234396 -5.089652)
			(stroke
				(width 0.1)
				(type default)
			)
			(layer "F.SilkS")
		)
		(fp_line
			(start 22.730714 -4.606544)
			(end 23.234396 -5.089652)
			(stroke
				(width 0.1)
				(type default)
			)
			(layer "F.SilkS")
		)
		(fp_line
			(start 22.74697 -4.564126)
			(end 22.762718 -4.521708)
			(stroke
				(width 0.1)
				(type default)
			)
			(layer "F.SilkS")
		)
		(fp_line
			(start 22.74697 -4.564126)
			(end 22.762718 -4.521708)
			(stroke
				(width 0.1)
				(type default)
			)
			(layer "F.SilkS")
		)
		(fp_line
			(start 22.74697 -4.564126)
			(end 23.32355 -5.117592)
			(stroke
				(width 0.1)
				(type default)
			)
			(layer "F.SilkS")
		)
		(fp_line
			(start 22.74697 -4.564126)
			(end 23.32355 -5.117592)
			(stroke
				(width 0.1)
				(type default)
			)
			(layer "F.SilkS")
		)
		(fp_line
			(start 22.762718 -4.521708)
			(end 22.778466 -4.47929)
			(stroke
				(width 0.1)
				(type default)
			)
			(layer "F.SilkS")
		)
		(fp_line
			(start 22.762718 -4.521708)
			(end 22.778466 -4.47929)
			(stroke
				(width 0.1)
				(type default)
			)
			(layer "F.SilkS")
		)
		(fp_line
			(start 22.762718 -4.521708)
			(end 23.412704 -5.145278)
			(stroke
				(width 0.1)
				(type default)
			)
			(layer "F.SilkS")
		)
		(fp_line
			(start 22.762718 -4.521708)
			(end 23.412704 -5.145278)
			(stroke
				(width 0.1)
				(type default)
			)
			(layer "F.SilkS")
		)
		(fp_line
			(start 22.777196 -0.841756)
			(end 23.748238 -1.773682)
			(stroke
				(width 0.1)
				(type default)
			)
			(layer "F.SilkS")
		)
		(fp_line
			(start 22.777196 -0.841756)
			(end 23.748238 -1.773682)
			(stroke
				(width 0.1)
				(type default)
			)
			(layer "F.SilkS")
		)
		(fp_line
			(start 22.778466 -4.47929)
			(end 22.794722 -4.436872)
			(stroke
				(width 0.1)
				(type default)
			)
			(layer "F.SilkS")
		)
		(fp_line
			(start 22.778466 -4.47929)
			(end 22.794722 -4.436872)
			(stroke
				(width 0.1)
				(type default)
			)
			(layer "F.SilkS")
		)
		(fp_line
			(start 22.778466 -4.47929)
			(end 23.494746 -5.166106)
			(stroke
				(width 0.1)
				(type default)
			)
			(layer "F.SilkS")
		)
		(fp_line
			(start 22.778466 -4.47929)
			(end 23.494746 -5.166106)
			(stroke
				(width 0.1)
				(type default)
			)
			(layer "F.SilkS")
		)
		(fp_line
			(start 22.794722 -4.436872)
			(end 22.81047 -4.394708)
			(stroke
				(width 0.1)
				(type default)
			)
			(layer "F.SilkS")
		)
		(fp_line
			(start 22.794722 -4.436872)
			(end 22.81047 -4.394708)
			(stroke
				(width 0.1)
				(type default)
			)
			(layer "F.SilkS")
		)
		(fp_line
			(start 22.794722 -4.436872)
			(end 23.573994 -5.184648)
			(stroke
				(width 0.1)
				(type default)
			)
			(layer "F.SilkS")
		)
		(fp_line
			(start 22.794722 -4.436872)
			(end 23.573994 -5.184648)
			(stroke
				(width 0.1)
				(type default)
			)
			(layer "F.SilkS")
		)
		(fp_line
			(start 22.81047 -4.394708)
			(end 22.826472 -4.352036)
			(stroke
				(width 0.1)
				(type default)
			)
			(layer "F.SilkS")
		)
		(fp_line
			(start 22.81047 -4.394708)
			(end 22.826472 -4.352036)
			(stroke
				(width 0.1)
				(type default)
			)
			(layer "F.SilkS")
		)
		(fp_line
			(start 22.81047 -4.394708)
			(end 23.652226 -5.20192)
			(stroke
				(width 0.1)
				(type default)
			)
			(layer "F.SilkS")
		)
		(fp_line
			(start 22.81047 -4.394708)
			(end 23.652226 -5.20192)
			(stroke
				(width 0.1)
				(type default)
			)
			(layer "F.SilkS")
		)
		(fp_line
			(start 22.826472 -4.352036)
			(end 22.842728 -4.309618)
			(stroke
				(width 0.1)
				(type default)
			)
			(layer "F.SilkS")
		)
		(fp_line
			(start 22.826472 -4.352036)
			(end 22.842728 -4.309618)
			(stroke
				(width 0.1)
				(type default)
			)
			(layer "F.SilkS")
		)
		(fp_line
			(start 22.826472 -4.352036)
			(end 23.724616 -5.21335)
			(stroke
				(width 0.1)
				(type default)
			)
			(layer "F.SilkS")
		)
		(fp_line
			(start 22.826472 -4.352036)
			(end 23.724616 -5.21335)
			(stroke
				(width 0.1)
				(type default)
			)
			(layer "F.SilkS")
		)
		(fp_line
			(start 22.826726 -0.831596)
			(end 23.82012 -1.78435)
			(stroke
				(width 0.1)
				(type default)
			)
			(layer "F.SilkS")
		)
		(fp_line
			(start 22.826726 -0.831596)
			(end 23.82012 -1.78435)
			(stroke
				(width 0.1)
				(type default)
			)
			(layer "F.SilkS")
		)
		(fp_line
			(start 22.842728 -4.309618)
			(end 22.858476 -4.267454)
			(stroke
				(width 0.1)
				(type default)
			)
			(layer "F.SilkS")
		)
		(fp_line
			(start 22.842728 -4.309618)
			(end 22.858476 -4.267454)
			(stroke
				(width 0.1)
				(type default)
			)
			(layer "F.SilkS")
		)
		(fp_line
			(start 22.842728 -4.309618)
			(end 23.796498 -5.22478)
			(stroke
				(width 0.1)
				(type default)
			)
			(layer "F.SilkS")
		)
		(fp_line
			(start 22.842728 -4.309618)
			(end 23.796498 -5.22478)
			(stroke
				(width 0.1)
				(type default)
			)
			(layer "F.SilkS")
		)
		(fp_line
			(start 22.858476 -4.267454)
			(end 22.874224 -4.225036)
			(stroke
				(width 0.1)
				(type default)
			)
			(layer "F.SilkS")
		)
		(fp_line
			(start 22.858476 -4.267454)
			(end 22.874224 -4.225036)
			(stroke
				(width 0.1)
				(type default)
			)
			(layer "F.SilkS")
		)
		(fp_line
			(start 22.858476 -4.267454)
			(end 23.86711 -5.235194)
			(stroke
				(width 0.1)
				(type default)
			)
			(layer "F.SilkS")
		)
		(fp_line
			(start 22.858476 -4.267454)
			(end 23.86711 -5.235194)
			(stroke
				(width 0.1)
				(type default)
			)
			(layer "F.SilkS")
		)
		(fp_line
			(start 22.874224 -4.225036)
			(end 22.89048 -4.182618)
			(stroke
				(width 0.1)
				(type default)
			)
			(layer "F.SilkS")
		)
		(fp_line
			(start 22.874224 -4.225036)
			(end 22.89048 -4.182618)
			(stroke
				(width 0.1)
				(type default)
			)
			(layer "F.SilkS")
		)
		(fp_line
			(start 22.874224 -4.225036)
			(end 23.933658 -5.241036)
			(stroke
				(width 0.1)
				(type default)
			)
			(layer "F.SilkS")
		)
		(fp_line
			(start 22.874224 -4.225036)
			(end 23.933658 -5.241036)
			(stroke
				(width 0.1)
				(type default)
			)
			(layer "F.SilkS")
		)
		(fp_line
			(start 22.87651 -0.821436)
			(end 23.916894 -1.819656)
			(stroke
				(width 0.1)
				(type default)
			)
			(layer "F.SilkS")
		)
		(fp_line
			(start 22.87651 -0.821436)
			(end 23.916894 -1.819656)
			(stroke
				(width 0.1)
				(type default)
			)
			(layer "F.SilkS")
		)
		(fp_line
			(start 22.89048 -4.182618)
			(end 22.906482 -4.139946)
			(stroke
				(width 0.1)
				(type default)
			)
			(layer "F.SilkS")
		)
		(fp_line
			(start 22.89048 -4.182618)
			(end 22.906482 -4.139946)
			(stroke
				(width 0.1)
				(type default)
			)
			(layer "F.SilkS")
		)
		(fp_line
			(start 22.89048 -4.182618)
			(end 24.000206 -5.246878)
			(stroke
				(width 0.1)
				(type default)
			)
			(layer "F.SilkS")
		)
		(fp_line
			(start 22.89048 -4.182618)
			(end 24.000206 -5.246878)
			(stroke
				(width 0.1)
				(type default)
			)
			(layer "F.SilkS")
		)
		(fp_line
			(start 22.906482 -4.139946)
			(end 22.92223 -4.097782)
			(stroke
				(width 0.1)
				(type default)
			)
			(layer "F.SilkS")
		)
		(fp_line
			(start 22.906482 -4.139946)
			(end 22.92223 -4.097782)
			(stroke
				(width 0.1)
				(type default)
			)
			(layer "F.SilkS")
		)
		(fp_line
			(start 22.906482 -4.139946)
			(end 24.066246 -5.252974)
			(stroke
				(width 0.1)
				(type default)
			)
			(layer "F.SilkS")
		)
		(fp_line
			(start 22.906482 -4.139946)
			(end 24.066246 -5.252974)
			(stroke
				(width 0.1)
				(type default)
			)
			(layer "F.SilkS")
		)
		(fp_line
			(start 22.92223 -4.097782)
			(end 22.938486 -4.055364)
			(stroke
				(width 0.1)
				(type default)
			)
			(layer "F.SilkS")
		)
		(fp_line
			(start 22.92223 -4.097782)
			(end 22.938486 -4.055364)
			(stroke
				(width 0.1)
				(type default)
			)
			(layer "F.SilkS")
		)
		(fp_line
			(start 22.92223 -4.097782)
			(end 24.129492 -5.255768)
			(stroke
				(width 0.1)
				(type default)
			)
			(layer "F.SilkS")
		)
		(fp_line
			(start 22.92223 -4.097782)
			(end 24.129492 -5.255768)
			(stroke
				(width 0.1)
				(type default)
			)
			(layer "F.SilkS")
		)
		(fp_line
			(start 22.927818 -0.813308)
			(end 24.013668 -1.854962)
			(stroke
				(width 0.1)
				(type default)
			)
			(layer "F.SilkS")
		)
		(fp_line
			(start 22.927818 -0.813308)
			(end 24.013668 -1.854962)
			(stroke
				(width 0.1)
				(type default)
			)
			(layer "F.SilkS")
		)
		(fp_line
			(start 22.938486 -4.055364)
			(end 24.191468 -5.257546)
			(stroke
				(width 0.1)
				(type default)
			)
			(layer "F.SilkS")
		)
		(fp_line
			(start 22.938486 -4.055364)
			(end 24.191468 -5.257546)
			(stroke
				(width 0.1)
				(type default)
			)
			(layer "F.SilkS")
		)
		(fp_line
			(start 22.981158 -0.806704)
			(end 24.158956 -1.93675)
			(stroke
				(width 0.1)
				(type default)
			)
			(layer "F.SilkS")
		)
		(fp_line
			(start 22.981158 -0.806704)
			(end 24.158956 -1.93675)
			(stroke
				(width 0.1)
				(type default)
			)
			(layer "F.SilkS")
		)
		(fp_line
			(start 23.029672 -4.085336)
			(end 24.253444 -5.25907)
			(stroke
				(width 0.1)
				(type default)
			)
			(layer "F.SilkS")
		)
		(fp_line
			(start 23.029672 -4.085336)
			(end 24.253444 -5.25907)
			(stroke
				(width 0.1)
				(type default)
			)
			(layer "F.SilkS")
		)
		(fp_line
			(start 23.091394 -0.797052)
			(end 25.733502 -3.331464)
			(stroke
				(width 0.1)
				(type default)
			)
			(layer "F.SilkS")
		)
		(fp_line
			(start 23.091394 -0.797052)
			(end 25.733502 -3.331464)
			(stroke
				(width 0.1)
				(type default)
			)
			(layer "F.SilkS")
		)
		(fp_line
			(start 23.143718 -4.136898)
			(end 24.31542 -5.260848)
			(stroke
				(width 0.1)
				(type default)
			)
			(layer "F.SilkS")
		)
		(fp_line
			(start 23.143718 -4.136898)
			(end 24.31542 -5.260848)
			(stroke
				(width 0.1)
				(type default)
			)
			(layer "F.SilkS")
		)
		(fp_line
			(start 23.149306 -0.79502)
			(end 25.721056 -3.262122)
			(stroke
				(width 0.1)
				(type default)
			)
			(layer "F.SilkS")
		)
		(fp_line
			(start 23.149306 -0.79502)
			(end 25.721056 -3.262122)
			(stroke
				(width 0.1)
				(type default)
			)
			(layer "F.SilkS")
		)
		(fp_line
			(start 23.208488 -0.794258)
			(end 25.708864 -3.19278)
			(stroke
				(width 0.1)
				(type default)
			)
			(layer "F.SilkS")
		)
		(fp_line
			(start 23.208488 -0.794258)
			(end 25.708864 -3.19278)
			(stroke
				(width 0.1)
				(type default)
			)
			(layer "F.SilkS")
		)
		(fp_line
			(start 23.23084 -2.720086)
			(end 24.256492 -3.704082)
			(stroke
				(width 0.1)
				(type default)
			)
			(layer "F.SilkS")
		)
		(fp_line
			(start 23.23084 -2.720086)
			(end 24.256492 -3.704082)
			(stroke
				(width 0.1)
				(type default)
			)
			(layer "F.SilkS")
		)
		(fp_line
			(start 23.249382 -4.180586)
			(end 24.372824 -5.258562)
			(stroke
				(width 0.1)
				(type default)
			)
			(layer "F.SilkS")
		)
		(fp_line
			(start 23.249382 -4.180586)
			(end 24.372824 -5.258562)
			(stroke
				(width 0.1)
				(type default)
			)
			(layer "F.SilkS")
		)
		(fp_line
			(start 23.275798 -0.800608)
			(end 25.696926 -3.123184)
			(stroke
				(width 0.1)
				(type default)
			)
			(layer "F.SilkS")
		)
		(fp_line
			(start 23.275798 -0.800608)
			(end 25.696926 -3.123184)
			(stroke
				(width 0.1)
				(type default)
			)
			(layer "F.SilkS")
		)
		(fp_line
			(start 23.3426 -0.807466)
			(end 25.68448 -3.054096)
			(stroke
				(width 0.1)
				(type default)
			)
			(layer "F.SilkS")
		)
		(fp_line
			(start 23.3426 -0.807466)
			(end 25.68448 -3.054096)
			(stroke
				(width 0.1)
				(type default)
			)
			(layer "F.SilkS")
		)
		(fp_line
			(start 23.344632 -4.214114)
			(end 24.429212 -5.254752)
			(stroke
				(width 0.1)
				(type default)
			)
			(layer "F.SilkS")
		)
		(fp_line
			(start 23.344632 -4.214114)
			(end 24.429212 -5.254752)
			(stroke
				(width 0.1)
				(type default)
			)
			(layer "F.SilkS")
		)
		(fp_line
			(start 23.34895 -2.775712)
			(end 24.307546 -3.695192)
			(stroke
				(width 0.1)
				(type default)
			)
			(layer "F.SilkS")
		)
		(fp_line
			(start 23.34895 -2.775712)
			(end 24.307546 -3.695192)
			(stroke
				(width 0.1)
				(type default)
			)
			(layer "F.SilkS")
		)
		(fp_line
			(start 23.409402 -0.813562)
			(end 25.672542 -2.984754)
			(stroke
				(width 0.1)
				(type default)
			)
			(layer "F.SilkS")
		)
		(fp_line
			(start 23.409402 -0.813562)
			(end 25.672542 -2.984754)
			(stroke
				(width 0.1)
				(type default)
			)
			(layer "F.SilkS")
		)
		(fp_line
			(start 23.46071 -2.825242)
			(end 24.35606 -3.684016)
			(stroke
				(width 0.1)
				(type default)
			)
			(layer "F.SilkS")
		)
		(fp_line
			(start 23.46071 -2.825242)
			(end 24.35606 -3.684016)
			(stroke
				(width 0.1)
				(type default)
			)
			(layer "F.SilkS")
		)
		(fp_line
			(start 23.476458 -0.82042)
			(end 25.66035 -2.915412)
			(stroke
				(width 0.1)
				(type default)
			)
			(layer "F.SilkS")
		)
		(fp_line
			(start 23.476458 -0.82042)
			(end 25.66035 -2.915412)
			(stroke
				(width 0.1)
				(type default)
			)
			(layer "F.SilkS")
		)
		(fp_line
			(start 23.530052 -2.833878)
			(end 24.401272 -3.669538)
			(stroke
				(width 0.1)
				(type default)
			)
			(layer "F.SilkS")
		)
		(fp_line
			(start 23.530052 -2.833878)
			(end 24.401272 -3.669538)
			(stroke
				(width 0.1)
				(type default)
			)
			(layer "F.SilkS")
		)
		(fp_line
			(start 23.557484 -0.840232)
			(end 25.648412 -2.845816)
			(stroke
				(width 0.1)
				(type default)
			)
			(layer "F.SilkS")
		)
		(fp_line
			(start 23.557484 -0.840232)
			(end 25.648412 -2.845816)
			(stroke
				(width 0.1)
				(type default)
			)
			(layer "F.SilkS")
		)
		(fp_line
			(start 23.642828 -0.864616)
			(end 25.635966 -2.776474)
			(stroke
				(width 0.1)
				(type default)
			)
			(layer "F.SilkS")
		)
		(fp_line
			(start 23.642828 -0.864616)
			(end 25.635966 -2.776474)
			(stroke
				(width 0.1)
				(type default)
			)
			(layer "F.SilkS")
		)
		(fp_line
			(start 23.683468 -3.731514)
			(end 21.836634 -1.95961)
			(stroke
				(width 0.1)
				(type default)
			)
			(layer "F.SilkS")
		)
		(fp_line
			(start 23.683468 -3.731514)
			(end 21.836634 -1.95961)
			(stroke
				(width 0.1)
				(type default)
			)
			(layer "F.SilkS")
		)
		(fp_line
			(start 23.728426 -0.888746)
			(end 25.623774 -2.707132)
			(stroke
				(width 0.1)
				(type default)
			)
			(layer "F.SilkS")
		)
		(fp_line
			(start 23.728426 -0.888746)
			(end 25.623774 -2.707132)
			(stroke
				(width 0.1)
				(type default)
			)
			(layer "F.SilkS")
		)
		(fp_line
			(start 23.831296 -0.929894)
			(end 25.611836 -2.63779)
			(stroke
				(width 0.1)
				(type default)
			)
			(layer "F.SilkS")
		)
		(fp_line
			(start 23.831296 -0.929894)
			(end 25.611836 -2.63779)
			(stroke
				(width 0.1)
				(type default)
			)
			(layer "F.SilkS")
		)
		(fp_line
			(start 23.951692 -0.987552)
			(end 25.59939 -2.568194)
			(stroke
				(width 0.1)
				(type default)
			)
			(layer "F.SilkS")
		)
		(fp_line
			(start 23.951692 -0.987552)
			(end 25.59939 -2.568194)
			(stroke
				(width 0.1)
				(type default)
			)
			(layer "F.SilkS")
		)
		(fp_line
			(start 24.122888 -1.094232)
			(end 25.587452 -2.498852)
			(stroke
				(width 0.1)
				(type default)
			)
			(layer "F.SilkS")
		)
		(fp_line
			(start 24.122888 -1.094232)
			(end 25.587452 -2.498852)
			(stroke
				(width 0.1)
				(type default)
			)
			(layer "F.SilkS")
		)
		(fp_line
			(start 24.17699 -0.882904)
			(end 24.203406 -0.882904)
			(stroke
				(width 0.1)
				(type default)
			)
			(layer "F.SilkS")
		)
		(fp_line
			(start 24.17699 -0.882904)
			(end 24.203406 -0.882904)
			(stroke
				(width 0.1)
				(type default)
			)
			(layer "F.SilkS")
		)
		(fp_line
			(start 24.183848 -0.921512)
			(end 24.17699 -0.882904)
			(stroke
				(width 0.1)
				(type default)
			)
			(layer "F.SilkS")
		)
		(fp_line
			(start 24.183848 -0.921512)
			(end 24.17699 -0.882904)
			(stroke
				(width 0.1)
				(type default)
			)
			(layer "F.SilkS")
		)
		(fp_line
			(start 24.183848 -0.921512)
			(end 25.538684 -2.221484)
			(stroke
				(width 0.1)
				(type default)
			)
			(layer "F.SilkS")
		)
		(fp_line
			(start 24.183848 -0.921512)
			(end 25.538684 -2.221484)
			(stroke
				(width 0.1)
				(type default)
			)
			(layer "F.SilkS")
		)
		(fp_line
			(start 24.195786 -0.991108)
			(end 24.183848 -0.921512)
			(stroke
				(width 0.1)
				(type default)
			)
			(layer "F.SilkS")
		)
		(fp_line
			(start 24.195786 -0.991108)
			(end 24.183848 -0.921512)
			(stroke
				(width 0.1)
				(type default)
			)
			(layer "F.SilkS")
		)
		(fp_line
			(start 24.195786 -0.991108)
			(end 25.550876 -2.290826)
			(stroke
				(width 0.1)
				(type default)
			)
			(layer "F.SilkS")
		)
		(fp_line
			(start 24.195786 -0.991108)
			(end 25.550876 -2.290826)
			(stroke
				(width 0.1)
				(type default)
			)
			(layer "F.SilkS")
		)
		(fp_line
			(start 24.203406 -0.882904)
			(end 24.263858 -0.882904)
			(stroke
				(width 0.1)
				(type default)
			)
			(layer "F.SilkS")
		)
		(fp_line
			(start 24.203406 -0.882904)
			(end 24.263858 -0.882904)
			(stroke
				(width 0.1)
				(type default)
			)
			(layer "F.SilkS")
		)
		(fp_line
			(start 24.203406 -0.882904)
			(end 25.526746 -2.152142)
			(stroke
				(width 0.1)
				(type default)
			)
			(layer "F.SilkS")
		)
		(fp_line
			(start 24.203406 -0.882904)
			(end 25.526746 -2.152142)
			(stroke
				(width 0.1)
				(type default)
			)
			(layer "F.SilkS")
		)
		(fp_line
			(start 24.208232 -1.06045)
			(end 24.195786 -0.991108)
			(stroke
				(width 0.1)
				(type default)
			)
			(layer "F.SilkS")
		)
		(fp_line
			(start 24.208232 -1.06045)
			(end 24.195786 -0.991108)
			(stroke
				(width 0.1)
				(type default)
			)
			(layer "F.SilkS")
		)
		(fp_line
			(start 24.208232 -1.06045)
			(end 25.563322 -2.360422)
			(stroke
				(width 0.1)
				(type default)
			)
			(layer "F.SilkS")
		)
		(fp_line
			(start 24.208232 -1.06045)
			(end 25.563322 -2.360422)
			(stroke
				(width 0.1)
				(type default)
			)
			(layer "F.SilkS")
		)
		(fp_line
			(start 24.220424 -1.130046)
			(end 24.208232 -1.06045)
			(stroke
				(width 0.1)
				(type default)
			)
			(layer "F.SilkS")
		)
		(fp_line
			(start 24.220424 -1.130046)
			(end 24.208232 -1.06045)
			(stroke
				(width 0.1)
				(type default)
			)
			(layer "F.SilkS")
		)
		(fp_line
			(start 24.263858 -0.882904)
			(end 24.324056 -0.882904)
			(stroke
				(width 0.1)
				(type default)
			)
			(layer "F.SilkS")
		)
		(fp_line
			(start 24.263858 -0.882904)
			(end 24.324056 -0.882904)
			(stroke
				(width 0.1)
				(type default)
			)
			(layer "F.SilkS")
		)
		(fp_line
			(start 24.263858 -0.882904)
			(end 25.5143 -2.0828)
			(stroke
				(width 0.1)
				(type default)
			)
			(layer "F.SilkS")
		)
		(fp_line
			(start 24.263858 -0.882904)
			(end 25.5143 -2.0828)
			(stroke
				(width 0.1)
				(type default)
			)
			(layer "F.SilkS")
		)
		(fp_line
			(start 24.324056 -0.882904)
			(end 24.384 -0.882904)
			(stroke
				(width 0.1)
				(type default)
			)
			(layer "F.SilkS")
		)
		(fp_line
			(start 24.324056 -0.882904)
			(end 24.384 -0.882904)
			(stroke
				(width 0.1)
				(type default)
			)
			(layer "F.SilkS")
		)
		(fp_line
			(start 24.324056 -0.882904)
			(end 25.502362 -2.013204)
			(stroke
				(width 0.1)
				(type default)
			)
			(layer "F.SilkS")
		)
		(fp_line
			(start 24.324056 -0.882904)
			(end 25.502362 -2.013204)
			(stroke
				(width 0.1)
				(type default)
			)
			(layer "F.SilkS")
		)
		(fp_line
			(start 24.384 -0.882904)
			(end 24.443944 -0.882904)
			(stroke
				(width 0.1)
				(type default)
			)
			(layer "F.SilkS")
		)
		(fp_line
			(start 24.384 -0.882904)
			(end 24.443944 -0.882904)
			(stroke
				(width 0.1)
				(type default)
			)
			(layer "F.SilkS")
		)
		(fp_line
			(start 24.384 -0.882904)
			(end 25.49017 -1.943862)
			(stroke
				(width 0.1)
				(type default)
			)
			(layer "F.SilkS")
		)
		(fp_line
			(start 24.384 -0.882904)
			(end 25.49017 -1.943862)
			(stroke
				(width 0.1)
				(type default)
			)
			(layer "F.SilkS")
		)
		(fp_line
			(start 24.414988 -2.24028)
			(end 24.402796 -2.170938)
			(stroke
				(width 0.1)
				(type default)
			)
			(layer "F.SilkS")
		)
		(fp_line
			(start 24.414988 -2.24028)
			(end 24.402796 -2.170938)
			(stroke
				(width 0.1)
				(type default)
			)
			(layer "F.SilkS")
		)
		(fp_line
			(start 24.427434 -2.309368)
			(end 24.414988 -2.24028)
			(stroke
				(width 0.1)
				(type default)
			)
			(layer "F.SilkS")
		)
		(fp_line
			(start 24.427434 -2.309368)
			(end 24.414988 -2.24028)
			(stroke
				(width 0.1)
				(type default)
			)
			(layer "F.SilkS")
		)
		(fp_line
			(start 24.439372 -2.37871)
			(end 24.427434 -2.309368)
			(stroke
				(width 0.1)
				(type default)
			)
			(layer "F.SilkS")
		)
		(fp_line
			(start 24.439372 -2.37871)
			(end 24.427434 -2.309368)
			(stroke
				(width 0.1)
				(type default)
			)
			(layer "F.SilkS")
		)
		(fp_line
			(start 24.443944 -0.882904)
			(end 24.504142 -0.882904)
			(stroke
				(width 0.1)
				(type default)
			)
			(layer "F.SilkS")
		)
		(fp_line
			(start 24.443944 -0.882904)
			(end 24.504142 -0.882904)
			(stroke
				(width 0.1)
				(type default)
			)
			(layer "F.SilkS")
		)
		(fp_line
			(start 24.443944 -0.882904)
			(end 25.478232 -1.874774)
			(stroke
				(width 0.1)
				(type default)
			)
			(layer "F.SilkS")
		)
		(fp_line
			(start 24.443944 -0.882904)
			(end 25.478232 -1.874774)
			(stroke
				(width 0.1)
				(type default)
			)
			(layer "F.SilkS")
		)
		(fp_line
			(start 24.44623 -3.655568)
			(end 23.598886 -2.842514)
			(stroke
				(width 0.1)
				(type default)
			)
			(layer "F.SilkS")
		)
		(fp_line
			(start 24.44623 -3.655568)
			(end 23.598886 -2.842514)
			(stroke
				(width 0.1)
				(type default)
			)
			(layer "F.SilkS")
		)
		(fp_line
			(start 24.451564 -2.448306)
			(end 24.439372 -2.37871)
			(stroke
				(width 0.1)
				(type default)
			)
			(layer "F.SilkS")
		)
		(fp_line
			(start 24.451564 -2.448306)
			(end 24.439372 -2.37871)
			(stroke
				(width 0.1)
				(type default)
			)
			(layer "F.SilkS")
		)
		(fp_line
			(start 24.46401 -2.517648)
			(end 24.451564 -2.448306)
			(stroke
				(width 0.1)
				(type default)
			)
			(layer "F.SilkS")
		)
		(fp_line
			(start 24.46401 -2.517648)
			(end 24.451564 -2.448306)
			(stroke
				(width 0.1)
				(type default)
			)
			(layer "F.SilkS")
		)
		(fp_line
			(start 24.475948 -2.58699)
			(end 24.46401 -2.517648)
			(stroke
				(width 0.1)
				(type default)
			)
			(layer "F.SilkS")
		)
		(fp_line
			(start 24.475948 -2.58699)
			(end 24.46401 -2.517648)
			(stroke
				(width 0.1)
				(type default)
			)
			(layer "F.SilkS")
		)
		(fp_line
			(start 24.485346 -5.250942)
			(end 23.433532 -4.2418)
			(stroke
				(width 0.1)
				(type default)
			)
			(layer "F.SilkS")
		)
		(fp_line
			(start 24.485346 -5.250942)
			(end 23.433532 -4.2418)
			(stroke
				(width 0.1)
				(type default)
			)
			(layer "F.SilkS")
		)
		(fp_line
			(start 24.487886 -2.656332)
			(end 24.475948 -2.58699)
			(stroke
				(width 0.1)
				(type default)
			)
			(layer "F.SilkS")
		)
		(fp_line
			(start 24.487886 -2.656332)
			(end 24.475948 -2.58699)
			(stroke
				(width 0.1)
				(type default)
			)
			(layer "F.SilkS")
		)
		(fp_line
			(start 24.491696 -3.64109)
			(end 23.668482 -2.85115)
			(stroke
				(width 0.1)
				(type default)
			)
			(layer "F.SilkS")
		)
		(fp_line
			(start 24.491696 -3.64109)
			(end 23.668482 -2.85115)
			(stroke
				(width 0.1)
				(type default)
			)
			(layer "F.SilkS")
		)
		(fp_line
			(start 24.504142 -0.882904)
			(end 24.564594 -0.882904)
			(stroke
				(width 0.1)
				(type default)
			)
			(layer "F.SilkS")
		)
		(fp_line
			(start 24.504142 -0.882904)
			(end 24.564594 -0.882904)
			(stroke
				(width 0.1)
				(type default)
			)
			(layer "F.SilkS")
		)
		(fp_line
			(start 24.504142 -0.882904)
			(end 25.465786 -1.805178)
			(stroke
				(width 0.1)
				(type default)
			)
			(layer "F.SilkS")
		)
		(fp_line
			(start 24.504142 -0.882904)
			(end 25.465786 -1.805178)
			(stroke
				(width 0.1)
				(type default)
			)
			(layer "F.SilkS")
		)
		(fp_line
			(start 24.534114 -3.624072)
			(end 23.73757 -2.859786)
			(stroke
				(width 0.1)
				(type default)
			)
			(layer "F.SilkS")
		)
		(fp_line
			(start 24.534114 -3.624072)
			(end 23.73757 -2.859786)
			(stroke
				(width 0.1)
				(type default)
			)
			(layer "F.SilkS")
		)
		(fp_line
			(start 24.541734 -5.246878)
			(end 23.518114 -4.265168)
			(stroke
				(width 0.1)
				(type default)
			)
			(layer "F.SilkS")
		)
		(fp_line
			(start 24.541734 -5.246878)
			(end 23.518114 -4.265168)
			(stroke
				(width 0.1)
				(type default)
			)
			(layer "F.SilkS")
		)
		(fp_line
			(start 24.564594 -0.882904)
			(end 24.624538 -0.882904)
			(stroke
				(width 0.1)
				(type default)
			)
			(layer "F.SilkS")
		)
		(fp_line
			(start 24.564594 -0.882904)
			(end 24.624538 -0.882904)
			(stroke
				(width 0.1)
				(type default)
			)
			(layer "F.SilkS")
		)
		(fp_line
			(start 24.564594 -0.882904)
			(end 25.453594 -1.735836)
			(stroke
				(width 0.1)
				(type default)
			)
			(layer "F.SilkS")
		)
		(fp_line
			(start 24.564594 -0.882904)
			(end 25.453594 -1.735836)
			(stroke
				(width 0.1)
				(type default)
			)
			(layer "F.SilkS")
		)
		(fp_line
			(start 24.5745 -3.605276)
			(end 23.797006 -2.859024)
			(stroke
				(width 0.1)
				(type default)
			)
			(layer "F.SilkS")
		)
		(fp_line
			(start 24.5745 -3.605276)
			(end 23.797006 -2.859024)
			(stroke
				(width 0.1)
				(type default)
			)
			(layer "F.SilkS")
		)
		(fp_line
			(start 24.597614 -5.243068)
			(end 23.594822 -4.280916)
			(stroke
				(width 0.1)
				(type default)
			)
			(layer "F.SilkS")
		)
		(fp_line
			(start 24.597614 -5.243068)
			(end 23.594822 -4.280916)
			(stroke
				(width 0.1)
				(type default)
			)
			(layer "F.SilkS")
		)
		(fp_line
			(start 24.614886 -3.586226)
			(end 23.855426 -2.857754)
			(stroke
				(width 0.1)
				(type default)
			)
			(layer "F.SilkS")
		)
		(fp_line
			(start 24.614886 -3.586226)
			(end 23.855426 -2.857754)
			(stroke
				(width 0.1)
				(type default)
			)
			(layer "F.SilkS")
		)
		(fp_line
			(start 24.624538 -0.882904)
			(end 24.684736 -0.882904)
			(stroke
				(width 0.1)
				(type default)
			)
			(layer "F.SilkS")
		)
		(fp_line
			(start 24.624538 -0.882904)
			(end 24.684736 -0.882904)
			(stroke
				(width 0.1)
				(type default)
			)
			(layer "F.SilkS")
		)
		(fp_line
			(start 24.624538 -0.882904)
			(end 25.441656 -1.666494)
			(stroke
				(width 0.1)
				(type default)
			)
			(layer "F.SilkS")
		)
		(fp_line
			(start 24.624538 -0.882904)
			(end 25.441656 -1.666494)
			(stroke
				(width 0.1)
				(type default)
			)
			(layer "F.SilkS")
		)
		(fp_line
			(start 24.653748 -5.239258)
			(end 23.67026 -4.295902)
			(stroke
				(width 0.1)
				(type default)
			)
			(layer "F.SilkS")
		)
		(fp_line
			(start 24.653748 -5.239258)
			(end 23.67026 -4.295902)
			(stroke
				(width 0.1)
				(type default)
			)
			(layer "F.SilkS")
		)
		(fp_line
			(start 24.67102 -3.697478)
			(end 24.658574 -3.627882)
			(stroke
				(width 0.1)
				(type default)
			)
			(layer "F.SilkS")
		)
		(fp_line
			(start 24.67102 -3.697478)
			(end 24.658574 -3.627882)
			(stroke
				(width 0.1)
				(type default)
			)
			(layer "F.SilkS")
		)
		(fp_line
			(start 24.682958 -3.76682)
			(end 24.67102 -3.697478)
			(stroke
				(width 0.1)
				(type default)
			)
			(layer "F.SilkS")
		)
		(fp_line
			(start 24.682958 -3.76682)
			(end 24.67102 -3.697478)
			(stroke
				(width 0.1)
				(type default)
			)
			(layer "F.SilkS")
		)
		(fp_line
			(start 24.684736 -0.882904)
			(end 24.744934 -0.882904)
			(stroke
				(width 0.1)
				(type default)
			)
			(layer "F.SilkS")
		)
		(fp_line
			(start 24.684736 -0.882904)
			(end 24.744934 -0.882904)
			(stroke
				(width 0.1)
				(type default)
			)
			(layer "F.SilkS")
		)
		(fp_line
			(start 24.684736 -0.882904)
			(end 25.42921 -1.597406)
			(stroke
				(width 0.1)
				(type default)
			)
			(layer "F.SilkS")
		)
		(fp_line
			(start 24.684736 -0.882904)
			(end 25.42921 -1.597406)
			(stroke
				(width 0.1)
				(type default)
			)
			(layer "F.SilkS")
		)
		(fp_line
			(start 24.708866 -5.234432)
			(end 23.739856 -4.304792)
			(stroke
				(width 0.1)
				(type default)
			)
			(layer "F.SilkS")
		)
		(fp_line
			(start 24.708866 -5.234432)
			(end 23.739856 -4.304792)
			(stroke
				(width 0.1)
				(type default)
			)
			(layer "F.SilkS")
		)
		(fp_line
			(start 24.744934 -0.882904)
			(end 24.805386 -0.882904)
			(stroke
				(width 0.1)
				(type default)
			)
			(layer "F.SilkS")
		)
		(fp_line
			(start 24.744934 -0.882904)
			(end 24.805386 -0.882904)
			(stroke
				(width 0.1)
				(type default)
			)
			(layer "F.SilkS")
		)
		(fp_line
			(start 24.744934 -0.882904)
			(end 25.417272 -1.52781)
			(stroke
				(width 0.1)
				(type default)
			)
			(layer "F.SilkS")
		)
		(fp_line
			(start 24.744934 -0.882904)
			(end 25.417272 -1.52781)
			(stroke
				(width 0.1)
				(type default)
			)
			(layer "F.SilkS")
		)
		(fp_line
			(start 24.75738 -5.223256)
			(end 23.809452 -4.313936)
			(stroke
				(width 0.1)
				(type default)
			)
			(layer "F.SilkS")
		)
		(fp_line
			(start 24.75738 -5.223256)
			(end 23.809452 -4.313936)
			(stroke
				(width 0.1)
				(type default)
			)
			(layer "F.SilkS")
		)
		(fp_line
			(start 24.805386 -0.882904)
			(end 24.86533 -0.882904)
			(stroke
				(width 0.1)
				(type default)
			)
			(layer "F.SilkS")
		)
		(fp_line
			(start 24.805386 -0.882904)
			(end 24.86533 -0.882904)
			(stroke
				(width 0.1)
				(type default)
			)
			(layer "F.SilkS")
		)
		(fp_line
			(start 24.805386 -0.882904)
			(end 25.40508 -1.458214)
			(stroke
				(width 0.1)
				(type default)
			)
			(layer "F.SilkS")
		)
		(fp_line
			(start 24.805386 -0.882904)
			(end 25.40508 -1.458214)
			(stroke
				(width 0.1)
				(type default)
			)
			(layer "F.SilkS")
		)
		(fp_line
			(start 24.805894 -5.21208)
			(end 23.87473 -4.318762)
			(stroke
				(width 0.1)
				(type default)
			)
			(layer "F.SilkS")
		)
		(fp_line
			(start 24.805894 -5.21208)
			(end 23.87473 -4.318762)
			(stroke
				(width 0.1)
				(type default)
			)
			(layer "F.SilkS")
		)
		(fp_line
			(start 24.854154 -5.200904)
			(end 23.9395 -4.323334)
			(stroke
				(width 0.1)
				(type default)
			)
			(layer "F.SilkS")
		)
		(fp_line
			(start 24.854154 -5.200904)
			(end 23.9395 -4.323334)
			(stroke
				(width 0.1)
				(type default)
			)
			(layer "F.SilkS")
		)
		(fp_line
			(start 24.86533 -0.882904)
			(end 24.925274 -0.882904)
			(stroke
				(width 0.1)
				(type default)
			)
			(layer "F.SilkS")
		)
		(fp_line
			(start 24.86533 -0.882904)
			(end 24.925274 -0.882904)
			(stroke
				(width 0.1)
				(type default)
			)
			(layer "F.SilkS")
		)
		(fp_line
			(start 24.86533 -0.882904)
			(end 25.392634 -1.388872)
			(stroke
				(width 0.1)
				(type default)
			)
			(layer "F.SilkS")
		)
		(fp_line
			(start 24.86533 -0.882904)
			(end 25.392634 -1.388872)
			(stroke
				(width 0.1)
				(type default)
			)
			(layer "F.SilkS")
		)
		(fp_line
			(start 24.903176 -5.189728)
			(end 24.003254 -4.32689)
			(stroke
				(width 0.1)
				(type default)
			)
			(layer "F.SilkS")
		)
		(fp_line
			(start 24.903176 -5.189728)
			(end 24.003254 -4.32689)
			(stroke
				(width 0.1)
				(type default)
			)
			(layer "F.SilkS")
		)
		(fp_line
			(start 24.925274 -0.882904)
			(end 24.985472 -0.882904)
			(stroke
				(width 0.1)
				(type default)
			)
			(layer "F.SilkS")
		)
		(fp_line
			(start 24.925274 -0.882904)
			(end 24.985472 -0.882904)
			(stroke
				(width 0.1)
				(type default)
			)
			(layer "F.SilkS")
		)
		(fp_line
			(start 24.925274 -0.882904)
			(end 25.380696 -1.319784)
			(stroke
				(width 0.1)
				(type default)
			)
			(layer "F.SilkS")
		)
		(fp_line
			(start 24.925274 -0.882904)
			(end 25.380696 -1.319784)
			(stroke
				(width 0.1)
				(type default)
			)
			(layer "F.SilkS")
		)
		(fp_line
			(start 24.95169 -5.178552)
			(end 24.064976 -4.327906)
			(stroke
				(width 0.1)
				(type default)
			)
			(layer "F.SilkS")
		)
		(fp_line
			(start 24.95169 -5.178552)
			(end 24.064976 -4.327906)
			(stroke
				(width 0.1)
				(type default)
			)
			(layer "F.SilkS")
		)
		(fp_line
			(start 24.985472 -0.882904)
			(end 25.04567 -0.882904)
			(stroke
				(width 0.1)
				(type default)
			)
			(layer "F.SilkS")
		)
		(fp_line
			(start 24.985472 -0.882904)
			(end 25.04567 -0.882904)
			(stroke
				(width 0.1)
				(type default)
			)
			(layer "F.SilkS")
		)
		(fp_line
			(start 24.985472 -0.882904)
			(end 25.368504 -1.250188)
			(stroke
				(width 0.1)
				(type default)
			)
			(layer "F.SilkS")
		)
		(fp_line
			(start 24.985472 -0.882904)
			(end 25.368504 -1.250188)
			(stroke
				(width 0.1)
				(type default)
			)
			(layer "F.SilkS")
		)
		(fp_line
			(start 24.99995 -5.16763)
			(end 24.12619 -4.329176)
			(stroke
				(width 0.1)
				(type default)
			)
			(layer "F.SilkS")
		)
		(fp_line
			(start 24.99995 -5.16763)
			(end 24.12619 -4.329176)
			(stroke
				(width 0.1)
				(type default)
			)
			(layer "F.SilkS")
		)
		(fp_line
			(start 25.045162 -5.152898)
			(end 24.18588 -4.328922)
			(stroke
				(width 0.1)
				(type default)
			)
			(layer "F.SilkS")
		)
		(fp_line
			(start 25.045162 -5.152898)
			(end 24.18588 -4.328922)
			(stroke
				(width 0.1)
				(type default)
			)
			(layer "F.SilkS")
		)
		(fp_line
			(start 25.04567 -0.882904)
			(end 25.106122 -0.882904)
			(stroke
				(width 0.1)
				(type default)
			)
			(layer "F.SilkS")
		)
		(fp_line
			(start 25.04567 -0.882904)
			(end 25.106122 -0.882904)
			(stroke
				(width 0.1)
				(type default)
			)
			(layer "F.SilkS")
		)
		(fp_line
			(start 25.04567 -0.882904)
			(end 25.356058 -1.180592)
			(stroke
				(width 0.1)
				(type default)
			)
			(layer "F.SilkS")
		)
		(fp_line
			(start 25.04567 -0.882904)
			(end 25.356058 -1.180592)
			(stroke
				(width 0.1)
				(type default)
			)
			(layer "F.SilkS")
		)
		(fp_line
			(start 25.086056 -5.13461)
			(end 24.241252 -4.32435)
			(stroke
				(width 0.1)
				(type default)
			)
			(layer "F.SilkS")
		)
		(fp_line
			(start 25.086056 -5.13461)
			(end 24.241252 -4.32435)
			(stroke
				(width 0.1)
				(type default)
			)
			(layer "F.SilkS")
		)
		(fp_line
			(start 25.106122 -0.882904)
			(end 25.166066 -0.882904)
			(stroke
				(width 0.1)
				(type default)
			)
			(layer "F.SilkS")
		)
		(fp_line
			(start 25.106122 -0.882904)
			(end 25.166066 -0.882904)
			(stroke
				(width 0.1)
				(type default)
			)
			(layer "F.SilkS")
		)
		(fp_line
			(start 25.106122 -0.882904)
			(end 25.34412 -1.111504)
			(stroke
				(width 0.1)
				(type default)
			)
			(layer "F.SilkS")
		)
		(fp_line
			(start 25.106122 -0.882904)
			(end 25.34412 -1.111504)
			(stroke
				(width 0.1)
				(type default)
			)
			(layer "F.SilkS")
		)
		(fp_line
			(start 25.127458 -5.116322)
			(end 24.297132 -4.320032)
			(stroke
				(width 0.1)
				(type default)
			)
			(layer "F.SilkS")
		)
		(fp_line
			(start 25.127458 -5.116322)
			(end 24.297132 -4.320032)
			(stroke
				(width 0.1)
				(type default)
			)
			(layer "F.SilkS")
		)
		(fp_line
			(start 25.166066 -0.882904)
			(end 25.226264 -0.882904)
			(stroke
				(width 0.1)
				(type default)
			)
			(layer "F.SilkS")
		)
		(fp_line
			(start 25.166066 -0.882904)
			(end 25.226264 -0.882904)
			(stroke
				(width 0.1)
				(type default)
			)
			(layer "F.SilkS")
		)
		(fp_line
			(start 25.166066 -0.882904)
			(end 25.332182 -1.042416)
			(stroke
				(width 0.1)
				(type default)
			)
			(layer "F.SilkS")
		)
		(fp_line
			(start 25.166066 -0.882904)
			(end 25.332182 -1.042416)
			(stroke
				(width 0.1)
				(type default)
			)
			(layer "F.SilkS")
		)
		(fp_line
			(start 25.168352 -5.098034)
			(end 24.346408 -4.309618)
			(stroke
				(width 0.1)
				(type default)
			)
			(layer "F.SilkS")
		)
		(fp_line
			(start 25.168352 -5.098034)
			(end 24.346408 -4.309618)
			(stroke
				(width 0.1)
				(type default)
			)
			(layer "F.SilkS")
		)
		(fp_line
			(start 25.2095 -5.08)
			(end 24.393398 -4.296918)
			(stroke
				(width 0.1)
				(type default)
			)
			(layer "F.SilkS")
		)
		(fp_line
			(start 25.2095 -5.08)
			(end 24.393398 -4.296918)
			(stroke
				(width 0.1)
				(type default)
			)
			(layer "F.SilkS")
		)
		(fp_line
			(start 25.226264 -0.882904)
			(end 25.286462 -0.882904)
			(stroke
				(width 0.1)
				(type default)
			)
			(layer "F.SilkS")
		)
		(fp_line
			(start 25.226264 -0.882904)
			(end 25.286462 -0.882904)
			(stroke
				(width 0.1)
				(type default)
			)
			(layer "F.SilkS")
		)
		(fp_line
			(start 25.226264 -0.882904)
			(end 25.31999 -0.97282)
			(stroke
				(width 0.1)
				(type default)
			)
			(layer "F.SilkS")
		)
		(fp_line
			(start 25.226264 -0.882904)
			(end 25.31999 -0.97282)
			(stroke
				(width 0.1)
				(type default)
			)
			(layer "F.SilkS")
		)
		(fp_line
			(start 25.250648 -5.061712)
			(end 24.438356 -4.28244)
			(stroke
				(width 0.1)
				(type default)
			)
			(layer "F.SilkS")
		)
		(fp_line
			(start 25.250648 -5.061712)
			(end 24.438356 -4.28244)
			(stroke
				(width 0.1)
				(type default)
			)
			(layer "F.SilkS")
		)
		(fp_line
			(start 25.286462 -0.882904)
			(end 25.304242 -0.882904)
			(stroke
				(width 0.1)
				(type default)
			)
			(layer "F.SilkS")
		)
		(fp_line
			(start 25.286462 -0.882904)
			(end 25.304242 -0.882904)
			(stroke
				(width 0.1)
				(type default)
			)
			(layer "F.SilkS")
		)
		(fp_line
			(start 25.286462 -0.882904)
			(end 25.307544 -0.903224)
			(stroke
				(width 0.1)
				(type default)
			)
			(layer "F.SilkS")
		)
		(fp_line
			(start 25.286462 -0.882904)
			(end 25.307544 -0.903224)
			(stroke
				(width 0.1)
				(type default)
			)
			(layer "F.SilkS")
		)
		(fp_line
			(start 25.29205 -5.043424)
			(end 24.477726 -4.26212)
			(stroke
				(width 0.1)
				(type default)
			)
			(layer "F.SilkS")
		)
		(fp_line
			(start 25.29205 -5.043424)
			(end 24.477726 -4.26212)
			(stroke
				(width 0.1)
				(type default)
			)
			(layer "F.SilkS")
		)
		(fp_line
			(start 25.304242 -0.882904)
			(end 25.307544 -0.903224)
			(stroke
				(width 0.1)
				(type default)
			)
			(layer "F.SilkS")
		)
		(fp_line
			(start 25.304242 -0.882904)
			(end 25.307544 -0.903224)
			(stroke
				(width 0.1)
				(type default)
			)
			(layer "F.SilkS")
		)
		(fp_line
			(start 25.307544 -0.903224)
			(end 25.31999 -0.97282)
			(stroke
				(width 0.1)
				(type default)
			)
			(layer "F.SilkS")
		)
		(fp_line
			(start 25.307544 -0.903224)
			(end 25.31999 -0.97282)
			(stroke
				(width 0.1)
				(type default)
			)
			(layer "F.SilkS")
		)
		(fp_line
			(start 25.31999 -0.97282)
			(end 25.332182 -1.042416)
			(stroke
				(width 0.1)
				(type default)
			)
			(layer "F.SilkS")
		)
		(fp_line
			(start 25.31999 -0.97282)
			(end 25.332182 -1.042416)
			(stroke
				(width 0.1)
				(type default)
			)
			(layer "F.SilkS")
		)
		(fp_line
			(start 25.327356 -5.019294)
			(end 24.516334 -4.2418)
			(stroke
				(width 0.1)
				(type default)
			)
			(layer "F.SilkS")
		)
		(fp_line
			(start 25.327356 -5.019294)
			(end 24.516334 -4.2418)
			(stroke
				(width 0.1)
				(type default)
			)
			(layer "F.SilkS")
		)
		(fp_line
			(start 25.332182 -1.042416)
			(end 25.34412 -1.111504)
			(stroke
				(width 0.1)
				(type default)
			)
			(layer "F.SilkS")
		)
		(fp_line
			(start 25.332182 -1.042416)
			(end 25.34412 -1.111504)
			(stroke
				(width 0.1)
				(type default)
			)
			(layer "F.SilkS")
		)
		(fp_line
			(start 25.34412 -1.111504)
			(end 25.356058 -1.180592)
			(stroke
				(width 0.1)
				(type default)
			)
			(layer "F.SilkS")
		)
		(fp_line
			(start 25.34412 -1.111504)
			(end 25.356058 -1.180592)
			(stroke
				(width 0.1)
				(type default)
			)
			(layer "F.SilkS")
		)
		(fp_line
			(start 25.356058 -1.180592)
			(end 25.368504 -1.250188)
			(stroke
				(width 0.1)
				(type default)
			)
			(layer "F.SilkS")
		)
		(fp_line
			(start 25.356058 -1.180592)
			(end 25.368504 -1.250188)
			(stroke
				(width 0.1)
				(type default)
			)
			(layer "F.SilkS")
		)
		(fp_line
			(start 25.36063 -4.994148)
			(end 24.549354 -4.215892)
			(stroke
				(width 0.1)
				(type default)
			)
			(layer "F.SilkS")
		)
		(fp_line
			(start 25.36063 -4.994148)
			(end 24.549354 -4.215892)
			(stroke
				(width 0.1)
				(type default)
			)
			(layer "F.SilkS")
		)
		(fp_line
			(start 25.368504 -1.250188)
			(end 25.380696 -1.319784)
			(stroke
				(width 0.1)
				(type default)
			)
			(layer "F.SilkS")
		)
		(fp_line
			(start 25.368504 -1.250188)
			(end 25.380696 -1.319784)
			(stroke
				(width 0.1)
				(type default)
			)
			(layer "F.SilkS")
		)
		(fp_line
			(start 25.380696 -1.319784)
			(end 25.392634 -1.388872)
			(stroke
				(width 0.1)
				(type default)
			)
			(layer "F.SilkS")
		)
		(fp_line
			(start 25.380696 -1.319784)
			(end 25.392634 -1.388872)
			(stroke
				(width 0.1)
				(type default)
			)
			(layer "F.SilkS")
		)
		(fp_line
			(start 25.392634 -1.388872)
			(end 25.40508 -1.458214)
			(stroke
				(width 0.1)
				(type default)
			)
			(layer "F.SilkS")
		)
		(fp_line
			(start 25.392634 -1.388872)
			(end 25.40508 -1.458214)
			(stroke
				(width 0.1)
				(type default)
			)
			(layer "F.SilkS")
		)
		(fp_line
			(start 25.394412 -4.968494)
			(end 24.580596 -4.187952)
			(stroke
				(width 0.1)
				(type default)
			)
			(layer "F.SilkS")
		)
		(fp_line
			(start 25.394412 -4.968494)
			(end 24.580596 -4.187952)
			(stroke
				(width 0.1)
				(type default)
			)
			(layer "F.SilkS")
		)
		(fp_line
			(start 25.40508 -1.458214)
			(end 25.417272 -1.52781)
			(stroke
				(width 0.1)
				(type default)
			)
			(layer "F.SilkS")
		)
		(fp_line
			(start 25.40508 -1.458214)
			(end 25.417272 -1.52781)
			(stroke
				(width 0.1)
				(type default)
			)
			(layer "F.SilkS")
		)
		(fp_line
			(start 25.417272 -1.52781)
			(end 25.42921 -1.597406)
			(stroke
				(width 0.1)
				(type default)
			)
			(layer "F.SilkS")
		)
		(fp_line
			(start 25.417272 -1.52781)
			(end 25.42921 -1.597406)
			(stroke
				(width 0.1)
				(type default)
			)
			(layer "F.SilkS")
		)
		(fp_line
			(start 25.428194 -4.943094)
			(end 24.609044 -4.157218)
			(stroke
				(width 0.1)
				(type default)
			)
			(layer "F.SilkS")
		)
		(fp_line
			(start 25.428194 -4.943094)
			(end 24.609044 -4.157218)
			(stroke
				(width 0.1)
				(type default)
			)
			(layer "F.SilkS")
		)
		(fp_line
			(start 25.42921 -1.597406)
			(end 25.441656 -1.666494)
			(stroke
				(width 0.1)
				(type default)
			)
			(layer "F.SilkS")
		)
		(fp_line
			(start 25.42921 -1.597406)
			(end 25.441656 -1.666494)
			(stroke
				(width 0.1)
				(type default)
			)
			(layer "F.SilkS")
		)
		(fp_line
			(start 25.441656 -1.666494)
			(end 25.453594 -1.735836)
			(stroke
				(width 0.1)
				(type default)
			)
			(layer "F.SilkS")
		)
		(fp_line
			(start 25.441656 -1.666494)
			(end 25.453594 -1.735836)
			(stroke
				(width 0.1)
				(type default)
			)
			(layer "F.SilkS")
		)
		(fp_line
			(start 25.453594 -1.735836)
			(end 25.465786 -1.805178)
			(stroke
				(width 0.1)
				(type default)
			)
			(layer "F.SilkS")
		)
		(fp_line
			(start 25.453594 -1.735836)
			(end 25.465786 -1.805178)
			(stroke
				(width 0.1)
				(type default)
			)
			(layer "F.SilkS")
		)
		(fp_line
			(start 25.461722 -4.917694)
			(end 24.631904 -4.121912)
			(stroke
				(width 0.1)
				(type default)
			)
			(layer "F.SilkS")
		)
		(fp_line
			(start 25.461722 -4.917694)
			(end 24.631904 -4.121912)
			(stroke
				(width 0.1)
				(type default)
			)
			(layer "F.SilkS")
		)
		(fp_line
			(start 25.465786 -1.805178)
			(end 25.478232 -1.874774)
			(stroke
				(width 0.1)
				(type default)
			)
			(layer "F.SilkS")
		)
		(fp_line
			(start 25.465786 -1.805178)
			(end 25.478232 -1.874774)
			(stroke
				(width 0.1)
				(type default)
			)
			(layer "F.SilkS")
		)
		(fp_line
			(start 25.478232 -1.874774)
			(end 25.49017 -1.943862)
			(stroke
				(width 0.1)
				(type default)
			)
			(layer "F.SilkS")
		)
		(fp_line
			(start 25.478232 -1.874774)
			(end 25.49017 -1.943862)
			(stroke
				(width 0.1)
				(type default)
			)
			(layer "F.SilkS")
		)
		(fp_line
			(start 25.49017 -1.943862)
			(end 25.502362 -2.013204)
			(stroke
				(width 0.1)
				(type default)
			)
			(layer "F.SilkS")
		)
		(fp_line
			(start 25.49017 -1.943862)
			(end 25.502362 -2.013204)
			(stroke
				(width 0.1)
				(type default)
			)
			(layer "F.SilkS")
		)
		(fp_line
			(start 25.49525 -4.892294)
			(end 24.65451 -4.085844)
			(stroke
				(width 0.1)
				(type default)
			)
			(layer "F.SilkS")
		)
		(fp_line
			(start 25.49525 -4.892294)
			(end 24.65451 -4.085844)
			(stroke
				(width 0.1)
				(type default)
			)
			(layer "F.SilkS")
		)
		(fp_line
			(start 25.502362 -2.013204)
			(end 25.5143 -2.0828)
			(stroke
				(width 0.1)
				(type default)
			)
			(layer "F.SilkS")
		)
		(fp_line
			(start 25.502362 -2.013204)
			(end 25.5143 -2.0828)
			(stroke
				(width 0.1)
				(type default)
			)
			(layer "F.SilkS")
		)
		(fp_line
			(start 25.5143 -2.0828)
			(end 25.526746 -2.152142)
			(stroke
				(width 0.1)
				(type default)
			)
			(layer "F.SilkS")
		)
		(fp_line
			(start 25.5143 -2.0828)
			(end 25.526746 -2.152142)
			(stroke
				(width 0.1)
				(type default)
			)
			(layer "F.SilkS")
		)
		(fp_line
			(start 25.526746 -2.152142)
			(end 25.538684 -2.221484)
			(stroke
				(width 0.1)
				(type default)
			)
			(layer "F.SilkS")
		)
		(fp_line
			(start 25.526746 -2.152142)
			(end 25.538684 -2.221484)
			(stroke
				(width 0.1)
				(type default)
			)
			(layer "F.SilkS")
		)
		(fp_line
			(start 25.527508 -4.865624)
			(end 24.669242 -4.042156)
			(stroke
				(width 0.1)
				(type default)
			)
			(layer "F.SilkS")
		)
		(fp_line
			(start 25.527508 -4.865624)
			(end 24.669242 -4.042156)
			(stroke
				(width 0.1)
				(type default)
			)
			(layer "F.SilkS")
		)
		(fp_line
			(start 25.538684 -2.221484)
			(end 25.550876 -2.290826)
			(stroke
				(width 0.1)
				(type default)
			)
			(layer "F.SilkS")
		)
		(fp_line
			(start 25.538684 -2.221484)
			(end 25.550876 -2.290826)
			(stroke
				(width 0.1)
				(type default)
			)
			(layer "F.SilkS")
		)
		(fp_line
			(start 25.550876 -2.290826)
			(end 25.563322 -2.360422)
			(stroke
				(width 0.1)
				(type default)
			)
			(layer "F.SilkS")
		)
		(fp_line
			(start 25.550876 -2.290826)
			(end 25.563322 -2.360422)
			(stroke
				(width 0.1)
				(type default)
			)
			(layer "F.SilkS")
		)
		(fp_line
			(start 25.553162 -4.83235)
			(end 24.683974 -3.998722)
			(stroke
				(width 0.1)
				(type default)
			)
			(layer "F.SilkS")
		)
		(fp_line
			(start 25.553162 -4.83235)
			(end 24.683974 -3.998722)
			(stroke
				(width 0.1)
				(type default)
			)
			(layer "F.SilkS")
		)
		(fp_line
			(start 25.563322 -2.360422)
			(end 25.57526 -2.429764)
			(stroke
				(width 0.1)
				(type default)
			)
			(layer "F.SilkS")
		)
		(fp_line
			(start 25.563322 -2.360422)
			(end 25.57526 -2.429764)
			(stroke
				(width 0.1)
				(type default)
			)
			(layer "F.SilkS")
		)
		(fp_line
			(start 25.57526 -2.429764)
			(end 24.220424 -1.130046)
			(stroke
				(width 0.1)
				(type default)
			)
			(layer "F.SilkS")
		)
		(fp_line
			(start 25.57526 -2.429764)
			(end 24.220424 -1.130046)
			(stroke
				(width 0.1)
				(type default)
			)
			(layer "F.SilkS")
		)
		(fp_line
			(start 25.57526 -2.429764)
			(end 25.587452 -2.498852)
			(stroke
				(width 0.1)
				(type default)
			)
			(layer "F.SilkS")
		)
		(fp_line
			(start 25.57526 -2.429764)
			(end 25.587452 -2.498852)
			(stroke
				(width 0.1)
				(type default)
			)
			(layer "F.SilkS")
		)
		(fp_line
			(start 25.57907 -4.79933)
			(end 24.690324 -3.946652)
			(stroke
				(width 0.1)
				(type default)
			)
			(layer "F.SilkS")
		)
		(fp_line
			(start 25.57907 -4.79933)
			(end 24.690324 -3.946652)
			(stroke
				(width 0.1)
				(type default)
			)
			(layer "F.SilkS")
		)
		(fp_line
			(start 25.587452 -2.498852)
			(end 25.59939 -2.568194)
			(stroke
				(width 0.1)
				(type default)
			)
			(layer "F.SilkS")
		)
		(fp_line
			(start 25.587452 -2.498852)
			(end 25.59939 -2.568194)
			(stroke
				(width 0.1)
				(type default)
			)
			(layer "F.SilkS")
		)
		(fp_line
			(start 25.59939 -2.568194)
			(end 25.611836 -2.63779)
			(stroke
				(width 0.1)
				(type default)
			)
			(layer "F.SilkS")
		)
		(fp_line
			(start 25.59939 -2.568194)
			(end 25.611836 -2.63779)
			(stroke
				(width 0.1)
				(type default)
			)
			(layer "F.SilkS")
		)
		(fp_line
			(start 25.60447 -4.766564)
			(end 24.695658 -3.894328)
			(stroke
				(width 0.1)
				(type default)
			)
			(layer "F.SilkS")
		)
		(fp_line
			(start 25.60447 -4.766564)
			(end 24.695658 -3.894328)
			(stroke
				(width 0.1)
				(type default)
			)
			(layer "F.SilkS")
		)
		(fp_line
			(start 25.611836 -2.63779)
			(end 25.623774 -2.707132)
			(stroke
				(width 0.1)
				(type default)
			)
			(layer "F.SilkS")
		)
		(fp_line
			(start 25.611836 -2.63779)
			(end 25.623774 -2.707132)
			(stroke
				(width 0.1)
				(type default)
			)
			(layer "F.SilkS")
		)
		(fp_line
			(start 25.623774 -2.707132)
			(end 25.635966 -2.776474)
			(stroke
				(width 0.1)
				(type default)
			)
			(layer "F.SilkS")
		)
		(fp_line
			(start 25.623774 -2.707132)
			(end 25.635966 -2.776474)
			(stroke
				(width 0.1)
				(type default)
			)
			(layer "F.SilkS")
		)
		(fp_line
			(start 25.630378 -4.73329)
			(end 24.690324 -3.83159)
			(stroke
				(width 0.1)
				(type default)
			)
			(layer "F.SilkS")
		)
		(fp_line
			(start 25.630378 -4.73329)
			(end 24.690324 -3.83159)
			(stroke
				(width 0.1)
				(type default)
			)
			(layer "F.SilkS")
		)
		(fp_line
			(start 25.635966 -2.776474)
			(end 25.648412 -2.845816)
			(stroke
				(width 0.1)
				(type default)
			)
			(layer "F.SilkS")
		)
		(fp_line
			(start 25.635966 -2.776474)
			(end 25.648412 -2.845816)
			(stroke
				(width 0.1)
				(type default)
			)
			(layer "F.SilkS")
		)
		(fp_line
			(start 25.648412 -2.845816)
			(end 25.66035 -2.915412)
			(stroke
				(width 0.1)
				(type default)
			)
			(layer "F.SilkS")
		)
		(fp_line
			(start 25.648412 -2.845816)
			(end 25.66035 -2.915412)
			(stroke
				(width 0.1)
				(type default)
			)
			(layer "F.SilkS")
		)
		(fp_line
			(start 25.656286 -4.70027)
			(end 24.682958 -3.76682)
			(stroke
				(width 0.1)
				(type default)
			)
			(layer "F.SilkS")
		)
		(fp_line
			(start 25.656286 -4.70027)
			(end 24.682958 -3.76682)
			(stroke
				(width 0.1)
				(type default)
			)
			(layer "F.SilkS")
		)
		(fp_line
			(start 25.66035 -2.915412)
			(end 25.672542 -2.984754)
			(stroke
				(width 0.1)
				(type default)
			)
			(layer "F.SilkS")
		)
		(fp_line
			(start 25.66035 -2.915412)
			(end 25.672542 -2.984754)
			(stroke
				(width 0.1)
				(type default)
			)
			(layer "F.SilkS")
		)
		(fp_line
			(start 25.672542 -2.984754)
			(end 25.68448 -3.054096)
			(stroke
				(width 0.1)
				(type default)
			)
			(layer "F.SilkS")
		)
		(fp_line
			(start 25.672542 -2.984754)
			(end 25.68448 -3.054096)
			(stroke
				(width 0.1)
				(type default)
			)
			(layer "F.SilkS")
		)
		(fp_line
			(start 25.681686 -4.66725)
			(end 24.67102 -3.697478)
			(stroke
				(width 0.1)
				(type default)
			)
			(layer "F.SilkS")
		)
		(fp_line
			(start 25.681686 -4.66725)
			(end 24.67102 -3.697478)
			(stroke
				(width 0.1)
				(type default)
			)
			(layer "F.SilkS")
		)
		(fp_line
			(start 25.68448 -3.054096)
			(end 25.696926 -3.123184)
			(stroke
				(width 0.1)
				(type default)
			)
			(layer "F.SilkS")
		)
		(fp_line
			(start 25.68448 -3.054096)
			(end 25.696926 -3.123184)
			(stroke
				(width 0.1)
				(type default)
			)
			(layer "F.SilkS")
		)
		(fp_line
			(start 25.696926 -3.123184)
			(end 25.708864 -3.19278)
			(stroke
				(width 0.1)
				(type default)
			)
			(layer "F.SilkS")
		)
		(fp_line
			(start 25.696926 -3.123184)
			(end 25.708864 -3.19278)
			(stroke
				(width 0.1)
				(type default)
			)
			(layer "F.SilkS")
		)
		(fp_line
			(start 25.701498 -4.628388)
			(end 24.658574 -3.627882)
			(stroke
				(width 0.1)
				(type default)
			)
			(layer "F.SilkS")
		)
		(fp_line
			(start 25.701498 -4.628388)
			(end 24.658574 -3.627882)
			(stroke
				(width 0.1)
				(type default)
			)
			(layer "F.SilkS")
		)
		(fp_line
			(start 25.708864 -3.19278)
			(end 25.721056 -3.262122)
			(stroke
				(width 0.1)
				(type default)
			)
			(layer "F.SilkS")
		)
		(fp_line
			(start 25.708864 -3.19278)
			(end 25.721056 -3.262122)
			(stroke
				(width 0.1)
				(type default)
			)
			(layer "F.SilkS")
		)
		(fp_line
			(start 25.718516 -4.586986)
			(end 23.913084 -2.85496)
			(stroke
				(width 0.1)
				(type default)
			)
			(layer "F.SilkS")
		)
		(fp_line
			(start 25.718516 -4.586986)
			(end 23.913084 -2.85496)
			(stroke
				(width 0.1)
				(type default)
			)
			(layer "F.SilkS")
		)
		(fp_line
			(start 25.721056 -3.262122)
			(end 25.733502 -3.331464)
			(stroke
				(width 0.1)
				(type default)
			)
			(layer "F.SilkS")
		)
		(fp_line
			(start 25.721056 -3.262122)
			(end 25.733502 -3.331464)
			(stroke
				(width 0.1)
				(type default)
			)
			(layer "F.SilkS")
		)
		(fp_line
			(start 25.733502 -3.331464)
			(end 25.74544 -3.400806)
			(stroke
				(width 0.1)
				(type default)
			)
			(layer "F.SilkS")
		)
		(fp_line
			(start 25.733502 -3.331464)
			(end 25.74544 -3.400806)
			(stroke
				(width 0.1)
				(type default)
			)
			(layer "F.SilkS")
		)
		(fp_line
			(start 25.735534 -4.54533)
			(end 23.969472 -2.85115)
			(stroke
				(width 0.1)
				(type default)
			)
			(layer "F.SilkS")
		)
		(fp_line
			(start 25.735534 -4.54533)
			(end 23.969472 -2.85115)
			(stroke
				(width 0.1)
				(type default)
			)
			(layer "F.SilkS")
		)
		(fp_line
			(start 25.74544 -3.400806)
			(end 23.034752 -0.800608)
			(stroke
				(width 0.1)
				(type default)
			)
			(layer "F.SilkS")
		)
		(fp_line
			(start 25.74544 -3.400806)
			(end 23.034752 -0.800608)
			(stroke
				(width 0.1)
				(type default)
			)
			(layer "F.SilkS")
		)
		(fp_line
			(start 25.74544 -3.400806)
			(end 25.757632 -3.470402)
			(stroke
				(width 0.1)
				(type default)
			)
			(layer "F.SilkS")
		)
		(fp_line
			(start 25.74544 -3.400806)
			(end 25.757632 -3.470402)
			(stroke
				(width 0.1)
				(type default)
			)
			(layer "F.SilkS")
		)
		(fp_line
			(start 25.752298 -4.503928)
			(end 24.024336 -2.846324)
			(stroke
				(width 0.1)
				(type default)
			)
			(layer "F.SilkS")
		)
		(fp_line
			(start 25.752298 -4.503928)
			(end 24.024336 -2.846324)
			(stroke
				(width 0.1)
				(type default)
			)
			(layer "F.SilkS")
		)
		(fp_line
			(start 25.757632 -3.470402)
			(end 24.402796 -2.170938)
			(stroke
				(width 0.1)
				(type default)
			)
			(layer "F.SilkS")
		)
		(fp_line
			(start 25.757632 -3.470402)
			(end 24.402796 -2.170938)
			(stroke
				(width 0.1)
				(type default)
			)
			(layer "F.SilkS")
		)
		(fp_line
			(start 25.757632 -3.470402)
			(end 25.769824 -3.539744)
			(stroke
				(width 0.1)
				(type default)
			)
			(layer "F.SilkS")
		)
		(fp_line
			(start 25.757632 -3.470402)
			(end 25.769824 -3.539744)
			(stroke
				(width 0.1)
				(type default)
			)
			(layer "F.SilkS")
		)
		(fp_line
			(start 25.769316 -4.46278)
			(end 24.076914 -2.839466)
			(stroke
				(width 0.1)
				(type default)
			)
			(layer "F.SilkS")
		)
		(fp_line
			(start 25.769316 -4.46278)
			(end 24.076914 -2.839466)
			(stroke
				(width 0.1)
				(type default)
			)
			(layer "F.SilkS")
		)
		(fp_line
			(start 25.769824 -3.539744)
			(end 24.414988 -2.24028)
			(stroke
				(width 0.1)
				(type default)
			)
			(layer "F.SilkS")
		)
		(fp_line
			(start 25.769824 -3.539744)
			(end 24.414988 -2.24028)
			(stroke
				(width 0.1)
				(type default)
			)
			(layer "F.SilkS")
		)
		(fp_line
			(start 25.769824 -3.539744)
			(end 25.782016 -3.609086)
			(stroke
				(width 0.1)
				(type default)
			)
			(layer "F.SilkS")
		)
		(fp_line
			(start 25.769824 -3.539744)
			(end 25.782016 -3.609086)
			(stroke
				(width 0.1)
				(type default)
			)
			(layer "F.SilkS")
		)
		(fp_line
			(start 25.782016 -3.609086)
			(end 24.427434 -2.309368)
			(stroke
				(width 0.1)
				(type default)
			)
			(layer "F.SilkS")
		)
		(fp_line
			(start 25.782016 -3.609086)
			(end 24.427434 -2.309368)
			(stroke
				(width 0.1)
				(type default)
			)
			(layer "F.SilkS")
		)
		(fp_line
			(start 25.782016 -3.609086)
			(end 25.793954 -3.678174)
			(stroke
				(width 0.1)
				(type default)
			)
			(layer "F.SilkS")
		)
		(fp_line
			(start 25.782016 -3.609086)
			(end 25.793954 -3.678174)
			(stroke
				(width 0.1)
				(type default)
			)
			(layer "F.SilkS")
		)
		(fp_line
			(start 25.786588 -4.421378)
			(end 24.12873 -2.831084)
			(stroke
				(width 0.1)
				(type default)
			)
			(layer "F.SilkS")
		)
		(fp_line
			(start 25.786588 -4.421378)
			(end 24.12873 -2.831084)
			(stroke
				(width 0.1)
				(type default)
			)
			(layer "F.SilkS")
		)
		(fp_line
			(start 25.793954 -3.678174)
			(end 24.439372 -2.37871)
			(stroke
				(width 0.1)
				(type default)
			)
			(layer "F.SilkS")
		)
		(fp_line
			(start 25.793954 -3.678174)
			(end 24.439372 -2.37871)
			(stroke
				(width 0.1)
				(type default)
			)
			(layer "F.SilkS")
		)
		(fp_line
			(start 25.793954 -3.678174)
			(end 25.806146 -3.74777)
			(stroke
				(width 0.1)
				(type default)
			)
			(layer "F.SilkS")
		)
		(fp_line
			(start 25.793954 -3.678174)
			(end 25.806146 -3.74777)
			(stroke
				(width 0.1)
				(type default)
			)
			(layer "F.SilkS")
		)
		(fp_line
			(start 25.798526 -4.37515)
			(end 24.17826 -2.82067)
			(stroke
				(width 0.1)
				(type default)
			)
			(layer "F.SilkS")
		)
		(fp_line
			(start 25.798526 -4.37515)
			(end 24.17826 -2.82067)
			(stroke
				(width 0.1)
				(type default)
			)
			(layer "F.SilkS")
		)
		(fp_line
			(start 25.805384 -4.324096)
			(end 24.225504 -2.808478)
			(stroke
				(width 0.1)
				(type default)
			)
			(layer "F.SilkS")
		)
		(fp_line
			(start 25.805384 -4.324096)
			(end 24.225504 -2.808478)
			(stroke
				(width 0.1)
				(type default)
			)
			(layer "F.SilkS")
		)
		(fp_line
			(start 25.806146 -3.74777)
			(end 24.451564 -2.448306)
			(stroke
				(width 0.1)
				(type default)
			)
			(layer "F.SilkS")
		)
		(fp_line
			(start 25.806146 -3.74777)
			(end 24.451564 -2.448306)
			(stroke
				(width 0.1)
				(type default)
			)
			(layer "F.SilkS")
		)
		(fp_line
			(start 25.812242 -4.273296)
			(end 24.27097 -2.794508)
			(stroke
				(width 0.1)
				(type default)
			)
			(layer "F.SilkS")
		)
		(fp_line
			(start 25.812242 -4.273296)
			(end 24.27097 -2.794508)
			(stroke
				(width 0.1)
				(type default)
			)
			(layer "F.SilkS")
		)
		(fp_line
			(start 25.81275 -3.811524)
			(end 24.46401 -2.517648)
			(stroke
				(width 0.1)
				(type default)
			)
			(layer "F.SilkS")
		)
		(fp_line
			(start 25.81275 -3.811524)
			(end 24.46401 -2.517648)
			(stroke
				(width 0.1)
				(type default)
			)
			(layer "F.SilkS")
		)
		(fp_line
			(start 25.817576 -3.874008)
			(end 24.475948 -2.58699)
			(stroke
				(width 0.1)
				(type default)
			)
			(layer "F.SilkS")
		)
		(fp_line
			(start 25.817576 -3.874008)
			(end 24.475948 -2.58699)
			(stroke
				(width 0.1)
				(type default)
			)
			(layer "F.SilkS")
		)
		(fp_line
			(start 25.819608 -4.222242)
			(end 24.31415 -2.777998)
			(stroke
				(width 0.1)
				(type default)
			)
			(layer "F.SilkS")
		)
		(fp_line
			(start 25.819608 -4.222242)
			(end 24.31415 -2.777998)
			(stroke
				(width 0.1)
				(type default)
			)
			(layer "F.SilkS")
		)
		(fp_line
			(start 25.822656 -3.936492)
			(end 24.487886 -2.656332)
			(stroke
				(width 0.1)
				(type default)
			)
			(layer "F.SilkS")
		)
		(fp_line
			(start 25.822656 -3.936492)
			(end 24.487886 -2.656332)
			(stroke
				(width 0.1)
				(type default)
			)
			(layer "F.SilkS")
		)
		(fp_line
			(start 25.826466 -4.170934)
			(end 24.35606 -2.760472)
			(stroke
				(width 0.1)
				(type default)
			)
			(layer "F.SilkS")
		)
		(fp_line
			(start 25.826466 -4.170934)
			(end 24.35606 -2.760472)
			(stroke
				(width 0.1)
				(type default)
			)
			(layer "F.SilkS")
		)
		(fp_line
			(start 25.827736 -3.99923)
			(end 24.468836 -2.695448)
			(stroke
				(width 0.1)
				(type default)
			)
			(layer "F.SilkS")
		)
		(fp_line
			(start 25.827736 -3.99923)
			(end 24.468836 -2.695448)
			(stroke
				(width 0.1)
				(type default)
			)
			(layer "F.SilkS")
		)
		(fp_line
			(start 25.83307 -4.062222)
			(end 24.432514 -2.718816)
			(stroke
				(width 0.1)
				(type default)
			)
			(layer "F.SilkS")
		)
		(fp_line
			(start 25.83307 -4.062222)
			(end 24.432514 -2.718816)
			(stroke
				(width 0.1)
				(type default)
			)
			(layer "F.SilkS")
		)
		(fp_line
			(start 25.833324 -4.120134)
			(end 24.394668 -2.739898)
			(stroke
				(width 0.1)
				(type default)
			)
			(layer "F.SilkS")
		)
		(fp_line
			(start 25.833324 -4.120134)
			(end 24.394668 -2.739898)
			(stroke
				(width 0.1)
				(type default)
			)
			(layer "F.SilkS")
		)
		(fp_poly
			(pts
				(xy 0 0) (xy 5.1054 0) (xy 5.3086 0) (xy 5.3086 -0.7874) (xy 25.8572 -0.7874) (xy 25.8572 -5.2832)
				(xy 21.844 -5.2832) (xy 21.082 -5.2832) (xy 21.082 -6.858) (xy 19.558 -6.858) (xy 19.558 -5.3086)
				(xy 4.0386 -5.3086) (xy 4.0386 -5.715) (xy 0 -5.715)
			)
			(stroke
				(width 0)
				(type default)
			)
			(fill no)
			(layer "F.CrtYd")
		)
	)
	(footprint ""
		(layer "F.Cu")
		(at 193.48958 -413.964882 90)
		(property "Reference" "R3770"
			(at 0 0 90)
			(layer "F.SilkS")
			(hide yes)
			(effects
				(font
					(size 1.27 1.27)
				)
			)
		)
		(property "Value" ""
			(at 0 0 90)
			(layer "F.Fab")
			(effects
				(font
					(size 1.27 1.27)
				)
			)
		)
		(duplicate_pad_numbers_are_jumpers no)
		(fp_line
			(start 0.7874 -0.4064)
			(end 0.7874 0.4064)
			(stroke
				(width 0.1524)
				(type default)
			)
			(layer "F.SilkS")
		)
		(fp_line
			(start -0.7874 -0.4064)
			(end 0.7874 -0.4064)
			(stroke
				(width 0.1524)
				(type default)
			)
			(layer "F.SilkS")
		)
		(fp_line
			(start 0.7874 0.4064)
			(end -0.7874 0.4064)
			(stroke
				(width 0.1524)
				(type default)
			)
			(layer "F.SilkS")
		)
		(fp_line
			(start -0.7874 0.4064)
			(end -0.7874 -0.4064)
			(stroke
				(width 0.1524)
				(type default)
			)
			(layer "F.SilkS")
		)
		(fp_line
			(start -0.12065 -0.305054)
			(end -0.12065 -0.2794)
			(stroke
				(width 0.1)
				(type default)
			)
			(layer "F.Fab")
		)
		(fp_line
			(start -0.67945 -0.305054)
			(end -0.12065 -0.305054)
			(stroke
				(width 0.1)
				(type default)
			)
			(layer "F.Fab")
		)
		(fp_line
			(start 0.67945 -0.3048)
			(end 0.67945 0.3048)
			(stroke
				(width 0.1)
				(type default)
			)
			(layer "F.Fab")
		)
		(fp_line
			(start 0.12065 -0.3048)
			(end 0.67945 -0.3048)
			(stroke
				(width 0.1)
				(type default)
			)
			(layer "F.Fab")
		)
		(fp_line
			(start 0.12065 -0.2794)
			(end 0.12065 -0.3048)
			(stroke
				(width 0.1)
				(type default)
			)
			(layer "F.Fab")
		)
		(fp_line
			(start -0.12065 -0.2794)
			(end 0.12065 -0.2794)
			(stroke
				(width 0.1)
				(type default)
			)
			(layer "F.Fab")
		)
		(fp_line
			(start 0.120396 0.2794)
			(end -0.12065 0.2794)
			(stroke
				(width 0.1)
				(type default)
			)
			(layer "F.Fab")
		)
		(fp_line
			(start -0.12065 0.2794)
			(end -0.12065 0.3048)
			(stroke
				(width 0.1)
				(type default)
			)
			(layer "F.Fab")
		)
		(fp_line
			(start 0.67945 0.3048)
			(end 0.120396 0.3048)
			(stroke
				(width 0.1)
				(type default)
			)
			(layer "F.Fab")
		)
		(fp_line
			(start 0.120396 0.3048)
			(end 0.120396 0.2794)
			(stroke
				(width 0.1)
				(type default)
			)
			(layer "F.Fab")
		)
		(fp_line
			(start -0.12065 0.3048)
			(end -0.67945 0.3048)
			(stroke
				(width 0.1)
				(type default)
			)
			(layer "F.Fab")
		)
		(fp_line
			(start -0.67945 0.3048)
			(end -0.67945 -0.305054)
			(stroke
				(width 0.1)
				(type default)
			)
			(layer "F.Fab")
		)
		(pad "1" smd circle
			(at -0.40005 0 90)
			(size 0 0)
			(layers "F.Cu" "F.Mask" "F.Paste")
			(net "GPU_PRSNT")
		)
		(pad "2" smd circle
			(at 0.40005 0 90)
			(size 0 0)
			(layers "F.Cu" "F.Mask" "F.Paste")
			(net "GPU_PRSNT_R")
		)
	)
	(footprint ""
		(layer "F.Cu")
		(at 80.550512 -339.644736 -90)
		(property "Reference" "PC386"
			(at 0 0 270)
			(layer "F.SilkS")
			(hide yes)
			(effects
				(font
					(size 1.27 1.27)
				)
			)
		)
		(property "Value" ""
			(at 0 0 270)
			(layer "F.Fab")
			(effects
				(font
					(size 1.27 1.27)
				)
			)
		)
		(duplicate_pad_numbers_are_jumpers no)
		(fp_line
			(start -0.7874 0.4064)
			(end -0.7874 -0.4064)
			(stroke
				(width 0.1524)
				(type default)
			)
			(layer "F.SilkS")
		)
		(fp_line
			(start 0.7874 0.4064)
			(end -0.7874 0.4064)
			(stroke
				(width 0.1524)
				(type default)
			)
			(layer "F.SilkS")
		)
		(fp_line
			(start -0.7874 -0.4064)
			(end 0.7874 -0.4064)
			(stroke
				(width 0.1524)
				(type default)
			)
			(layer "F.SilkS")
		)
		(fp_line
			(start 0.7874 -0.4064)
			(end 0.7874 0.4064)
			(stroke
				(width 0.1524)
				(type default)
			)
			(layer "F.SilkS")
		)
		(fp_line
			(start -0.67945 0.3048)
			(end -0.67945 -0.305054)
			(stroke
				(width 0.1)
				(type default)
			)
			(layer "F.Fab")
		)
		(fp_line
			(start -0.12065 0.3048)
			(end -0.67945 0.3048)
			(stroke
				(width 0.1)
				(type default)
			)
			(layer "F.Fab")
		)
		(fp_line
			(start 0.120396 0.3048)
			(end 0.120396 0.2794)
			(stroke
				(width 0.1)
				(type default)
			)
			(layer "F.Fab")
		)
		(fp_line
			(start 0.67945 0.3048)
			(end 0.120396 0.3048)
			(stroke
				(width 0.1)
				(type default)
			)
			(layer "F.Fab")
		)
		(fp_line
			(start -0.12065 0.2794)
			(end -0.12065 0.3048)
			(stroke
				(width 0.1)
				(type default)
			)
			(layer "F.Fab")
		)
		(fp_line
			(start 0.120396 0.2794)
			(end -0.12065 0.2794)
			(stroke
				(width 0.1)
				(type default)
			)
			(layer "F.Fab")
		)
		(fp_line
			(start -0.12065 -0.2794)
			(end 0.12065 -0.2794)
			(stroke
				(width 0.1)
				(type default)
			)
			(layer "F.Fab")
		)
		(fp_line
			(start 0.12065 -0.2794)
			(end 0.12065 -0.3048)
			(stroke
				(width 0.1)
				(type default)
			)
			(layer "F.Fab")
		)
		(fp_line
			(start 0.12065 -0.3048)
			(end 0.67945 -0.3048)
			(stroke
				(width 0.1)
				(type default)
			)
			(layer "F.Fab")
		)
		(fp_line
			(start 0.67945 -0.3048)
			(end 0.67945 0.3048)
			(stroke
				(width 0.1)
				(type default)
			)
			(layer "F.Fab")
		)
		(fp_line
			(start -0.67945 -0.305054)
			(end -0.12065 -0.305054)
			(stroke
				(width 0.1)
				(type default)
			)
			(layer "F.Fab")
		)
		(fp_line
			(start -0.12065 -0.305054)
			(end -0.12065 -0.2794)
			(stroke
				(width 0.1)
				(type default)
			)
			(layer "F.Fab")
		)
		(pad "1" smd circle
			(at -0.40005 0 270)
			(size 0 0)
			(layers "F.Cu" "F.Mask" "F.Paste")
			(net "SW_PVDDCR_CPU1_P1_BOOT2_R")
		)
		(pad "2" smd circle
			(at 0.40005 0 270)
			(size 0 0)
			(layers "F.Cu" "F.Mask" "F.Paste")
			(net "SW_PVDDCR_CPU1_P1_BOOTR2")
		)
	)
	(footprint ""
		(layer "F.Cu")
		(at 421.284654 -428.285402 -90)
		(property "Reference" "U16"
			(at 1.53289 -3.07594 90)
			(unlocked yes)
			(layer "F.SilkS")
			(effects
				(font
					(size 0.7874 0.5842)
					(thickness 0.1524)
				)
				(justify left)
			)
		)
		(property "Value" ""
			(at 0 0 270)
			(layer "F.Fab")
			(effects
				(font
					(size 1.27 1.27)
				)
			)
		)
		(duplicate_pad_numbers_are_jumpers no)
		(fp_line
			(start -1.8288 2.500122)
			(end 1.8288 2.500122)
			(stroke
				(width 0.1524)
				(type default)
			)
			(layer "F.SilkS")
		)
		(fp_line
			(start 1.8288 2.500122)
			(end 1.8288 -2.500122)
			(stroke
				(width 0.1524)
				(type default)
			)
			(layer "F.SilkS")
		)
		(fp_line
			(start 0 -1.4224)
			(end -1.077722 -2.500122)
			(stroke
				(width 0.1524)
				(type default)
			)
			(layer "F.SilkS")
		)
		(fp_line
			(start -1.8288 -2.500122)
			(end -1.8288 2.500122)
			(stroke
				(width 0.1524)
				(type default)
			)
			(layer "F.SilkS")
		)
		(fp_line
			(start -1.077722 -2.500122)
			(end -1.8288 -2.500122)
			(stroke
				(width 0.1524)
				(type default)
			)
			(layer "F.SilkS")
		)
		(fp_line
			(start 1.077722 -2.500122)
			(end 0 -1.4224)
			(stroke
				(width 0.1524)
				(type default)
			)
			(layer "F.SilkS")
		)
		(fp_line
			(start 1.8288 -2.500122)
			(end 1.077722 -2.500122)
			(stroke
				(width 0.1524)
				(type default)
			)
			(layer "F.SilkS")
		)
		(fp_poly
			(pts
				(xy -4.5085 -2.413) (xy -4.5085 -1.397) (xy -3.4925 -1.905)
			)
			(stroke
				(width 0)
				(type default)
			)
			(fill yes)
			(layer "F.SilkS")
		)
		(fp_line
			(start -1.999996 2.500122)
			(end 1.999996 2.500122)
			(stroke
				(width 0.1)
				(type default)
			)
			(layer "F.Fab")
		)
		(fp_line
			(start 1.999996 2.500122)
			(end 1.999996 -2.500122)
			(stroke
				(width 0.1)
				(type default)
			)
			(layer "F.Fab")
		)
		(fp_line
			(start -1.999996 -2.500122)
			(end -1.999996 2.500122)
			(stroke
				(width 0.1)
				(type default)
			)
			(layer "F.Fab")
		)
		(fp_line
			(start 1.999996 -2.500122)
			(end -1.999996 -2.500122)
			(stroke
				(width 0.1)
				(type default)
			)
			(layer "F.Fab")
		)
		(fp_poly
			(pts
				(xy -4.5085 -2.413) (xy -4.5085 -1.397) (xy -3.4925 -1.905)
			)
			(stroke
				(width 0)
				(type default)
			)
			(fill yes)
			(layer "F.Fab")
		)
		(pad "1" smd rect
			(at -2.599944 -1.905 180)
			(size 0.889 1.27)
			(layers "F.Cu" "F.Mask" "F.Paste")
			(net "Net_10841")
		)
		(pad "2" smd rect
			(at -2.599944 -0.635 180)
			(size 0.889 1.27)
			(layers "F.Cu" "F.Mask" "F.Paste")
			(net "Net_10840")
		)
		(pad "3" smd rect
			(at -2.599944 0.635 180)
			(size 0.889 1.27)
			(layers "F.Cu" "F.Mask" "F.Paste")
			(net "U16_E2")
		)
		(pad "4" smd rect
			(at -2.599944 1.905 180)
			(size 0.889 1.27)
			(layers "F.Cu" "F.Mask" "F.Paste")
			(net "GND")
		)
		(pad "5" smd rect
			(at 2.599944 1.905 180)
			(size 0.889 1.27)
			(layers "F.Cu" "F.Mask" "F.Paste")
			(net "SMB_RT_CPU0_P2_ROM_SDA")
		)
		(pad "6" smd rect
			(at 2.599944 0.635 180)
			(size 0.889 1.27)
			(layers "F.Cu" "F.Mask" "F.Paste")
			(net "SMB_RT_CPU0_P2_ROM_SCL")
		)
		(pad "7" smd rect
			(at 2.599944 -0.635 180)
			(size 0.889 1.27)
			(layers "F.Cu" "F.Mask" "F.Paste")
			(net "GND")
		)
		(pad "8" smd rect
			(at 2.599944 -1.905 180)
			(size 0.889 1.27)
			(layers "F.Cu" "F.Mask" "F.Paste")
			(net "P1V8_CPU0_RT_1D")
		)
	)
	(footprint ""
		(layer "F.Cu")
		(at 304.419 -366.395)
		(property "Reference" "R8071"
			(at 0 0 0)
			(layer "F.SilkS")
			(hide yes)
			(effects
				(font
					(size 1.27 1.27)
				)
			)
		)
		(property "Value" ""
			(at 0 0 0)
			(layer "F.Fab")
			(effects
				(font
					(size 1.27 1.27)
				)
			)
		)
		(duplicate_pad_numbers_are_jumpers no)
		(fp_line
			(start -0.7874 -0.4064)
			(end 0.7874 -0.4064)
			(stroke
				(width 0.1524)
				(type default)
			)
			(layer "F.SilkS")
		)
		(fp_line
			(start -0.7874 0.4064)
			(end -0.7874 -0.4064)
			(stroke
				(width 0.1524)
				(type default)
			)
			(layer "F.SilkS")
		)
		(fp_line
			(start 0.7874 -0.4064)
			(end 0.7874 0.4064)
			(stroke
				(width 0.1524)
				(type default)
			)
			(layer "F.SilkS")
		)
		(fp_line
			(start 0.7874 0.4064)
			(end -0.7874 0.4064)
			(stroke
				(width 0.1524)
				(type default)
			)
			(layer "F.SilkS")
		)
		(fp_line
			(start -0.67945 -0.305054)
			(end -0.12065 -0.305054)
			(stroke
				(width 0.1)
				(type default)
			)
			(layer "F.Fab")
		)
		(fp_line
			(start -0.67945 0.3048)
			(end -0.67945 -0.305054)
			(stroke
				(width 0.1)
				(type default)
			)
			(layer "F.Fab")
		)
		(fp_line
			(start -0.12065 -0.305054)
			(end -0.12065 -0.2794)
			(stroke
				(width 0.1)
				(type default)
			)
			(layer "F.Fab")
		)
		(fp_line
			(start -0.12065 -0.2794)
			(end 0.12065 -0.2794)
			(stroke
				(width 0.1)
				(type default)
			)
			(layer "F.Fab")
		)
		(fp_line
			(start -0.12065 0.2794)
			(end -0.12065 0.3048)
			(stroke
				(width 0.1)
				(type default)
			)
			(layer "F.Fab")
		)
		(fp_line
			(start -0.12065 0.3048)
			(end -0.67945 0.3048)
			(stroke
				(width 0.1)
				(type default)
			)
			(layer "F.Fab")
		)
		(fp_line
			(start 0.120396 0.2794)
			(end -0.12065 0.2794)
			(stroke
				(width 0.1)
				(type default)
			)
			(layer "F.Fab")
		)
		(fp_line
			(start 0.120396 0.3048)
			(end 0.120396 0.2794)
			(stroke
				(width 0.1)
				(type default)
			)
			(layer "F.Fab")
		)
		(fp_line
			(start 0.12065 -0.3048)
			(end 0.67945 -0.3048)
			(stroke
				(width 0.1)
				(type default)
			)
			(layer "F.Fab")
		)
		(fp_line
			(start 0.12065 -0.2794)
			(end 0.12065 -0.3048)
			(stroke
				(width 0.1)
				(type default)
			)
			(layer "F.Fab")
		)
		(fp_line
			(start 0.67945 -0.3048)
			(end 0.67945 0.3048)
			(stroke
				(width 0.1)
				(type default)
			)
			(layer "F.Fab")
		)
		(fp_line
			(start 0.67945 0.3048)
			(end 0.120396 0.3048)
			(stroke
				(width 0.1)
				(type default)
			)
			(layer "F.Fab")
		)
		(pad "1" smd circle
			(at -0.40005 0)
			(size 0 0)
			(layers "F.Cu" "F.Mask" "F.Paste")
			(net "SMB_SCM_2_R5_SCL")
		)
		(pad "2" smd circle
			(at 0.40005 0)
			(size 0 0)
			(layers "F.Cu" "F.Mask" "F.Paste")
			(net "SMB_CLK_PVDDCR_CPU1_P0_R")
		)
	)
	(footprint ""
		(layer "F.Cu")
		(at 318.34582 -334.995266)
		(property "Reference" "PU15"
			(at 3.34518 -7.624064 0)
			(unlocked yes)
			(layer "F.SilkS")
			(effects
				(font
					(size 0.7874 0.5842)
					(thickness 0.1524)
				)
				(justify left)
			)
		)
		(property "Value" ""
			(at 0 0 0)
			(layer "F.Fab")
			(effects
				(font
					(size 1.27 1.27)
				)
			)
		)
		(duplicate_pad_numbers_are_jumpers no)
		(fp_line
			(start -2.500122 -2.999994)
			(end -2.24409 -2.999994)
			(stroke
				(width 0.1524)
				(type default)
			)
			(layer "F.SilkS")
		)
		(fp_line
			(start -2.500122 -2.529078)
			(end -2.500122 -2.999994)
			(stroke
				(width 0.1524)
				(type default)
			)
			(layer "F.SilkS")
		)
		(fp_line
			(start -2.500122 0.6604)
			(end -2.500122 0.229108)
			(stroke
				(width 0.1524)
				(type default)
			)
			(layer "F.SilkS")
		)
		(fp_line
			(start -2.500122 2.999994)
			(end -2.500122 2.339594)
			(stroke
				(width 0.1524)
				(type default)
			)
			(layer "F.SilkS")
		)
		(fp_line
			(start -2.2987 2.999994)
			(end -2.500122 2.999994)
			(stroke
				(width 0.1524)
				(type default)
			)
			(layer "F.SilkS")
		)
		(fp_line
			(start 2.31394 -2.999994)
			(end 2.500122 -2.999994)
			(stroke
				(width 0.1524)
				(type default)
			)
			(layer "F.SilkS")
		)
		(fp_line
			(start 2.500122 -2.999994)
			(end 2.500122 -2.44348)
			(stroke
				(width 0.1524)
				(type default)
			)
			(layer "F.SilkS")
		)
		(fp_line
			(start 2.500122 2.339594)
			(end 2.500122 2.999994)
			(stroke
				(width 0.1524)
				(type default)
			)
			(layer "F.SilkS")
		)
		(fp_line
			(start 2.500122 2.999994)
			(end 2.2987 2.999994)
			(stroke
				(width 0.1524)
				(type default)
			)
			(layer "F.SilkS")
		)
		(fp_poly
			(pts
				(xy -2.780792 -2.420112) (xy -3.4544 -2.644648) (xy -3.005328 -3.09372)
			)
			(stroke
				(width 0)
				(type default)
			)
			(fill yes)
			(layer "F.SilkS")
		)
		(fp_line
			(start -2.500122 -2.999994)
			(end 2.500122 -2.999994)
			(stroke
				(width 0.1)
				(type default)
			)
			(layer "F.Fab")
		)
		(fp_line
			(start -2.500122 2.999994)
			(end -2.500122 -2.999994)
			(stroke
				(width 0.1)
				(type default)
			)
			(layer "F.Fab")
		)
		(fp_line
			(start 2.500122 -2.999994)
			(end 2.500122 2.999994)
			(stroke
				(width 0.1)
				(type default)
			)
			(layer "F.Fab")
		)
		(fp_line
			(start 2.500122 2.999994)
			(end -2.500122 2.999994)
			(stroke
				(width 0.1)
				(type default)
			)
			(layer "F.Fab")
		)
		(fp_poly
			(pts
				(xy -4.218432 -2.783078) (xy -4.218432 -1.767078) (xy -3.202432 -2.275078)
			)
			(stroke
				(width 0)
				(type default)
			)
			(fill yes)
			(layer "F.Fab")
		)
		(pad "1" smd rect
			(at -2.400046 -2.275078 90)
			(size 0.2286 0.6096)
			(layers "F.Cu" "F.Mask" "F.Paste")
			(net "PVDDCR_CPU1_P0_VOS3")
		)
		(pad "2" smd rect
			(at -2.400046 -1.82499 90)
			(size 0.2286 0.6096)
			(layers "F.Cu" "F.Mask" "F.Paste")
			(net "GND")
		)
		(pad "3" smd rect
			(at -2.400046 -1.374902 90)
			(size 0.2286 0.6096)
			(layers "F.Cu" "F.Mask" "F.Paste")
			(net "PVDDCR_CPU1_P0_VCC3")
		)
		(pad "4" smd rect
			(at -2.400046 -0.925068 90)
			(size 0.2286 0.6096)
			(layers "F.Cu" "F.Mask" "F.Paste")
			(net "PVDDCR_CPU1_P0_PVCC")
		)
		(pad "5" smd rect
			(at -2.400046 -0.47498 90)
			(size 0.2286 0.6096)
			(layers "F.Cu" "F.Mask" "F.Paste")
			(net "GND")
		)
		(pad "6" smd rect
			(at -2.400046 -0.024892 90)
			(size 0.2286 0.6096)
			(layers "F.Cu" "F.Mask" "F.Paste")
			(net "NC_PVDDCR_CPU1_P0_GL1_3")
		)
		(pad "7_9-20_24" smd circle
			(at 0 1.150112 90)
			(size 0 0)
			(layers "F.Cu" "F.Mask" "F.Paste")
			(net "GND")
		)
		(pad "10_19" smd rect
			(at 0 2.899918 90)
			(size 0.6096 4.318)
			(layers "F.Cu" "F.Mask" "F.Paste")
			(net "SW_PVDDCR_CPU1_P0_SW3")
		)
		(pad "25_29" smd rect
			(at 1.549908 -1.279906 270)
			(size 2.0574 2.3114)
			(layers "F.Cu" "F.Mask" "F.Paste")
			(net "SW_P12V_AUX_PVDDCR_CPU1_P0_FLT")
		)
		(pad "30" smd rect
			(at 2.05994 -2.899918)
			(size 0.2286 0.6096)
			(layers "F.Cu" "F.Mask" "F.Paste")
			(net "SW_P12V_AUX_PVDDCR_CPU1_P0_FLT")
		)
		(pad "31" smd rect
			(at 1.610106 -2.899918)
			(size 0.2286 0.6096)
			(layers "F.Cu" "F.Mask" "F.Paste")
			(net "NC_PVDDCR_CPU1_P0_DNC3")
		)
		(pad "32" smd rect
			(at 1.160018 -2.899918)
			(size 0.2286 0.6096)
			(layers "F.Cu" "F.Mask" "F.Paste")
			(net "SW_PVDDCR_CPU1_P0_BOOTR3")
		)
		(pad "33" smd rect
			(at 0.70993 -2.899918)
			(size 0.2286 0.6096)
			(layers "F.Cu" "F.Mask" "F.Paste")
			(net "SW_PVDDCR_CPU1_P0_BOOT3")
		)
		(pad "34" smd rect
			(at 0.260096 -2.899918)
			(size 0.2286 0.6096)
			(layers "F.Cu" "F.Mask" "F.Paste")
			(net "PVDDCR_CPU1_P0_PWM3")
		)
		(pad "35" smd rect
			(at -0.189992 -2.899918)
			(size 0.2286 0.6096)
			(layers "F.Cu" "F.Mask" "F.Paste")
			(net "PVDDCR_CPU1_P0_VCC3")
		)
		(pad "36" smd rect
			(at -0.64008 -2.899918)
			(size 0.2286 0.6096)
			(layers "F.Cu" "F.Mask" "F.Paste")
			(net "PVDDCR_CPU1_P0_TEMP0")
		)
		(pad "37" smd rect
			(at -1.089914 -2.899918)
			(size 0.2286 0.6096)
			(layers "F.Cu" "F.Mask" "F.Paste")
			(net "PVDDCR_CPU1_P0_LSET3")
		)
		(pad "38" smd rect
			(at -1.540002 -2.899918)
			(size 0.2286 0.6096)
			(layers "F.Cu" "F.Mask" "F.Paste")
			(net "PVDDCR_CPU1_P0_IMON3")
		)
		(pad "39" smd rect
			(at -1.99009 -2.899918)
			(size 0.2286 0.6096)
			(layers "F.Cu" "F.Mask" "F.Paste")
			(net "PVDDCR_CPU1_P0_VCCS")
		)
		(pad "40" smd rect
			(at -0.87503 -1.27508)
			(size 1.7526 1.9558)
			(layers "F.Cu" "F.Mask" "F.Paste")
			(net "GND")
		)
		(pad "41" smd rect
			(at -1.525016 0.249936 270)
			(size 0.3048 0.4572)
			(layers "F.Cu" "F.Mask" "F.Paste")
			(net "NC_PVDDCR_CPU1_P0_GL2_3")
		)
		(zone
			(layer "F.Cu")
			(hatch none 0.5)
			(connect_pads
				(clearance 0)
			)
			(min_thickness 0.25)
			(keepout
				(tracks not_allowed)
				(vias allowed)
				(pads allowed)
				(copperpour not_allowed)
				(footprints allowed)
			)
			(placement
				(enabled no)
				(sheetname "")
			)
			(fill
				(thermal_gap 0.5)
				(thermal_bridge_width 0.5)
				(island_removal_mode 0)
			)
			(polygon
				(pts
					(xy 315.845698 -332.417674) (xy 315.845698 -332.744572) (xy 320.845942 -332.744572) (xy 320.845942 -332.418436)
					(xy 320.55562 -332.418436) (xy 320.55562 -332.450948) (xy 316.13602 -332.450948) (xy 316.13602 -332.417674)
				)
			)
		)
		(zone
			(layer "F.Cu")
			(hatch none 0.5)
			(connect_pads
				(clearance 0)
			)
			(min_thickness 0.25)
			(keepout
				(tracks not_allowed)
				(vias allowed)
				(pads allowed)
				(copperpour not_allowed)
				(footprints allowed)
			)
			(placement
				(enabled no)
				(sheetname "")
			)
			(fill
				(thermal_gap 0.5)
				(thermal_bridge_width 0.5)
				(island_removal_mode 0)
			)
			(polygon
				(pts
					(xy 318.39789 -335.241646) (xy 318.39789 -337.299046) (xy 316.54369 -337.299046) (xy 316.54369 -337.058)
					(xy 316.301374 -337.058) (xy 316.301374 -337.539584) (xy 320.226182 -337.539584) (xy 320.226182 -337.354672)
					(xy 318.689228 -337.354672) (xy 318.689228 -335.195672) (xy 320.845942 -335.195672) (xy 320.845942 -334.94599)
					(xy 318.693546 -334.94599)
				)
			)
		)
	)
	(footprint ""
		(layer "F.Cu")
		(at 96.715834 -136.052052 -90)
		(property "Reference" "R6087"
			(at 0 0 270)
			(layer "F.SilkS")
			(hide yes)
			(effects
				(font
					(size 1.27 1.27)
				)
			)
		)
		(property "Value" ""
			(at 0 0 270)
			(layer "F.Fab")
			(effects
				(font
					(size 1.27 1.27)
				)
			)
		)
		(duplicate_pad_numbers_are_jumpers no)
		(fp_line
			(start -0.7874 0.4064)
			(end -0.7874 -0.4064)
			(stroke
				(width 0.1524)
				(type default)
			)
			(layer "F.SilkS")
		)
		(fp_line
			(start 0.7874 0.4064)
			(end -0.7874 0.4064)
			(stroke
				(width 0.1524)
				(type default)
			)
			(layer "F.SilkS")
		)
		(fp_line
			(start -0.7874 -0.4064)
			(end 0.7874 -0.4064)
			(stroke
				(width 0.1524)
				(type default)
			)
			(layer "F.SilkS")
		)
		(fp_line
			(start 0.7874 -0.4064)
			(end 0.7874 0.4064)
			(stroke
				(width 0.1524)
				(type default)
			)
			(layer "F.SilkS")
		)
		(fp_line
			(start -0.67945 0.3048)
			(end -0.67945 -0.305054)
			(stroke
				(width 0.1)
				(type default)
			)
			(layer "F.Fab")
		)
		(fp_line
			(start -0.12065 0.3048)
			(end -0.67945 0.3048)
			(stroke
				(width 0.1)
				(type default)
			)
			(layer "F.Fab")
		)
		(fp_line
			(start 0.120396 0.3048)
			(end 0.120396 0.2794)
			(stroke
				(width 0.1)
				(type default)
			)
			(layer "F.Fab")
		)
		(fp_line
			(start 0.67945 0.3048)
			(end 0.120396 0.3048)
			(stroke
				(width 0.1)
				(type default)
			)
			(layer "F.Fab")
		)
		(fp_line
			(start -0.12065 0.2794)
			(end -0.12065 0.3048)
			(stroke
				(width 0.1)
				(type default)
			)
			(layer "F.Fab")
		)
		(fp_line
			(start 0.120396 0.2794)
			(end -0.12065 0.2794)
			(stroke
				(width 0.1)
				(type default)
			)
			(layer "F.Fab")
		)
		(fp_line
			(start -0.12065 -0.2794)
			(end 0.12065 -0.2794)
			(stroke
				(width 0.1)
				(type default)
			)
			(layer "F.Fab")
		)
		(fp_line
			(start 0.12065 -0.2794)
			(end 0.12065 -0.3048)
			(stroke
				(width 0.1)
				(type default)
			)
			(layer "F.Fab")
		)
		(fp_line
			(start 0.12065 -0.3048)
			(end 0.67945 -0.3048)
			(stroke
				(width 0.1)
				(type default)
			)
			(layer "F.Fab")
		)
		(fp_line
			(start 0.67945 -0.3048)
			(end 0.67945 0.3048)
			(stroke
				(width 0.1)
				(type default)
			)
			(layer "F.Fab")
		)
		(fp_line
			(start -0.67945 -0.305054)
			(end -0.12065 -0.305054)
			(stroke
				(width 0.1)
				(type default)
			)
			(layer "F.Fab")
		)
		(fp_line
			(start -0.12065 -0.305054)
			(end -0.12065 -0.2794)
			(stroke
				(width 0.1)
				(type default)
			)
			(layer "F.Fab")
		)
		(pad "1" smd circle
			(at -0.40005 0 270)
			(size 0 0)
			(layers "F.Cu" "F.Mask" "F.Paste")
			(net "PVDDCR_SOC_P1_EN_RC")
		)
		(pad "2" smd circle
			(at 0.40005 0 270)
			(size 0 0)
			(layers "F.Cu" "F.Mask" "F.Paste")
			(net "GND")
		)
	)
	(footprint ""
		(layer "F.Cu")
		(at 439.276744 -428.92091 -90)
		(property "Reference" "R650"
			(at 0 0 270)
			(layer "F.SilkS")
			(hide yes)
			(effects
				(font
					(size 1.27 1.27)
				)
			)
		)
		(property "Value" ""
			(at 0 0 270)
			(layer "F.Fab")
			(effects
				(font
					(size 1.27 1.27)
				)
			)
		)
		(duplicate_pad_numbers_are_jumpers no)
		(fp_line
			(start -0.7874 0.4064)
			(end -0.7874 -0.4064)
			(stroke
				(width 0.1524)
				(type default)
			)
			(layer "F.SilkS")
		)
		(fp_line
			(start 0.7874 0.4064)
			(end -0.7874 0.4064)
			(stroke
				(width 0.1524)
				(type default)
			)
			(layer "F.SilkS")
		)
		(fp_line
			(start -0.7874 -0.4064)
			(end 0.7874 -0.4064)
			(stroke
				(width 0.1524)
				(type default)
			)
			(layer "F.SilkS")
		)
		(fp_line
			(start 0.7874 -0.4064)
			(end 0.7874 0.4064)
			(stroke
				(width 0.1524)
				(type default)
			)
			(layer "F.SilkS")
		)
		(fp_line
			(start -0.67945 0.3048)
			(end -0.67945 -0.305054)
			(stroke
				(width 0.1)
				(type default)
			)
			(layer "F.Fab")
		)
		(fp_line
			(start -0.12065 0.3048)
			(end -0.67945 0.3048)
			(stroke
				(width 0.1)
				(type default)
			)
			(layer "F.Fab")
		)
		(fp_line
			(start 0.120396 0.3048)
			(end 0.120396 0.2794)
			(stroke
				(width 0.1)
				(type default)
			)
			(layer "F.Fab")
		)
		(fp_line
			(start 0.67945 0.3048)
			(end 0.120396 0.3048)
			(stroke
				(width 0.1)
				(type default)
			)
			(layer "F.Fab")
		)
		(fp_line
			(start -0.12065 0.2794)
			(end -0.12065 0.3048)
			(stroke
				(width 0.1)
				(type default)
			)
			(layer "F.Fab")
		)
		(fp_line
			(start 0.120396 0.2794)
			(end -0.12065 0.2794)
			(stroke
				(width 0.1)
				(type default)
			)
			(layer "F.Fab")
		)
		(fp_line
			(start -0.12065 -0.2794)
			(end 0.12065 -0.2794)
			(stroke
				(width 0.1)
				(type default)
			)
			(layer "F.Fab")
		)
		(fp_line
			(start 0.12065 -0.2794)
			(end 0.12065 -0.3048)
			(stroke
				(width 0.1)
				(type default)
			)
			(layer "F.Fab")
		)
		(fp_line
			(start 0.12065 -0.3048)
			(end 0.67945 -0.3048)
			(stroke
				(width 0.1)
				(type default)
			)
			(layer "F.Fab")
		)
		(fp_line
			(start 0.67945 -0.3048)
			(end 0.67945 0.3048)
			(stroke
				(width 0.1)
				(type default)
			)
			(layer "F.Fab")
		)
		(fp_line
			(start -0.67945 -0.305054)
			(end -0.12065 -0.305054)
			(stroke
				(width 0.1)
				(type default)
			)
			(layer "F.Fab")
		)
		(fp_line
			(start -0.12065 -0.305054)
			(end -0.12065 -0.2794)
			(stroke
				(width 0.1)
				(type default)
			)
			(layer "F.Fab")
		)
		(pad "1" smd circle
			(at -0.40005 0 270)
			(size 0 0)
			(layers "F.Cu" "F.Mask" "F.Paste")
			(net "PWRGD_P0V9_RETIMER_CPU0")
		)
		(pad "2" smd circle
			(at 0.40005 0 270)
			(size 0 0)
			(layers "F.Cu" "F.Mask" "F.Paste")
			(net "PWRGD_P0V9_RETIMER_CPU0_R")
		)
	)
	(footprint ""
		(layer "F.Cu")
		(at 81.464404 -408.517344 -90)
		(property "Reference" "C6652"
			(at 0 0 270)
			(layer "F.SilkS")
			(hide yes)
			(effects
				(font
					(size 1.27 1.27)
				)
			)
		)
		(property "Value" ""
			(at 0 0 270)
			(layer "F.Fab")
			(effects
				(font
					(size 1.27 1.27)
				)
			)
		)
		(duplicate_pad_numbers_are_jumpers no)
		(fp_line
			(start -0.299974 0.150114)
			(end -0.299974 -0.150114)
			(stroke
				(width 0.1)
				(type default)
			)
			(layer "F.Fab")
		)
		(fp_line
			(start 0.299974 0.150114)
			(end -0.299974 0.150114)
			(stroke
				(width 0.1)
				(type default)
			)
			(layer "F.Fab")
		)
		(fp_line
			(start -0.299974 -0.150114)
			(end 0.299974 -0.150114)
			(stroke
				(width 0.1)
				(type default)
			)
			(layer "F.Fab")
		)
		(fp_line
			(start 0.299974 -0.150114)
			(end 0.299974 0.150114)
			(stroke
				(width 0.1)
				(type default)
			)
			(layer "F.Fab")
		)
		(pad "1" smd rect
			(at -0.2667 0 270)
			(size 0.3048 0.381)
			(layers "F.Cu" "F.Mask" "F.Paste")
			(net "P5E_CPU1_P0_TX_BUF_C_DN<11>")
		)
		(pad "2" smd rect
			(at 0.2667 0 270)
			(size 0.3048 0.381)
			(layers "F.Cu" "F.Mask" "F.Paste")
			(net "P5E_CPU1_P0_TX_BUF_DN<11>")
		)
	)
	(footprint ""
		(layer "F.Cu")
		(at 60.936124 -408.517344 -90)
		(property "Reference" "C6637"
			(at 0 0 270)
			(layer "F.SilkS")
			(hide yes)
			(effects
				(font
					(size 1.27 1.27)
				)
			)
		)
		(property "Value" ""
			(at 0 0 270)
			(layer "F.Fab")
			(effects
				(font
					(size 1.27 1.27)
				)
			)
		)
		(duplicate_pad_numbers_are_jumpers no)
		(fp_line
			(start -0.299974 0.150114)
			(end -0.299974 -0.150114)
			(stroke
				(width 0.1)
				(type default)
			)
			(layer "F.Fab")
		)
		(fp_line
			(start 0.299974 0.150114)
			(end -0.299974 0.150114)
			(stroke
				(width 0.1)
				(type default)
			)
			(layer "F.Fab")
		)
		(fp_line
			(start -0.299974 -0.150114)
			(end 0.299974 -0.150114)
			(stroke
				(width 0.1)
				(type default)
			)
			(layer "F.Fab")
		)
		(fp_line
			(start 0.299974 -0.150114)
			(end 0.299974 0.150114)
			(stroke
				(width 0.1)
				(type default)
			)
			(layer "F.Fab")
		)
		(pad "1" smd rect
			(at -0.2667 0 270)
			(size 0.3048 0.381)
			(layers "F.Cu" "F.Mask" "F.Paste")
			(net "P5E_CPU1_P0_TX_BUF_C_DP<4>")
		)
		(pad "2" smd rect
			(at 0.2667 0 270)
			(size 0.3048 0.381)
			(layers "F.Cu" "F.Mask" "F.Paste")
			(net "P5E_CPU1_P0_TX_BUF_DP<4>")
		)
	)
	(footprint ""
		(layer "F.Cu")
		(at 90.209878 -147.93341 180)
		(property "Reference" "R8160"
			(at 0 0 180)
			(layer "F.SilkS")
			(hide yes)
			(effects
				(font
					(size 1.27 1.27)
				)
			)
		)
		(property "Value" ""
			(at 0 0 180)
			(layer "F.Fab")
			(effects
				(font
					(size 1.27 1.27)
				)
			)
		)
		(duplicate_pad_numbers_are_jumpers no)
		(fp_line
			(start 0.7874 0.4064)
			(end -0.7874 0.4064)
			(stroke
				(width 0.1524)
				(type default)
			)
			(layer "F.SilkS")
		)
		(fp_line
			(start 0.7874 -0.4064)
			(end 0.7874 0.4064)
			(stroke
				(width 0.1524)
				(type default)
			)
			(layer "F.SilkS")
		)
		(fp_line
			(start -0.7874 0.4064)
			(end -0.7874 -0.4064)
			(stroke
				(width 0.1524)
				(type default)
			)
			(layer "F.SilkS")
		)
		(fp_line
			(start -0.7874 -0.4064)
			(end 0.7874 -0.4064)
			(stroke
				(width 0.1524)
				(type default)
			)
			(layer "F.SilkS")
		)
		(fp_line
			(start 0.67945 0.3048)
			(end 0.120396 0.3048)
			(stroke
				(width 0.1)
				(type default)
			)
			(layer "F.Fab")
		)
		(fp_line
			(start 0.67945 -0.3048)
			(end 0.67945 0.3048)
			(stroke
				(width 0.1)
				(type default)
			)
			(layer "F.Fab")
		)
		(fp_line
			(start 0.12065 -0.2794)
			(end 0.12065 -0.3048)
			(stroke
				(width 0.1)
				(type default)
			)
			(layer "F.Fab")
		)
		(fp_line
			(start 0.12065 -0.3048)
			(end 0.67945 -0.3048)
			(stroke
				(width 0.1)
				(type default)
			)
			(layer "F.Fab")
		)
		(fp_line
			(start 0.120396 0.3048)
			(end 0.120396 0.2794)
			(stroke
				(width 0.1)
				(type default)
			)
			(layer "F.Fab")
		)
		(fp_line
			(start 0.120396 0.2794)
			(end -0.12065 0.2794)
			(stroke
				(width 0.1)
				(type default)
			)
			(layer "F.Fab")
		)
		(fp_line
			(start -0.12065 0.3048)
			(end -0.67945 0.3048)
			(stroke
				(width 0.1)
				(type default)
			)
			(layer "F.Fab")
		)
		(fp_line
			(start -0.12065 0.2794)
			(end -0.12065 0.3048)
			(stroke
				(width 0.1)
				(type default)
			)
			(layer "F.Fab")
		)
		(fp_line
			(start -0.12065 -0.2794)
			(end 0.12065 -0.2794)
			(stroke
				(width 0.1)
				(type default)
			)
			(layer "F.Fab")
		)
		(fp_line
			(start -0.12065 -0.305054)
			(end -0.12065 -0.2794)
			(stroke
				(width 0.1)
				(type default)
			)
			(layer "F.Fab")
		)
		(fp_line
			(start -0.67945 0.3048)
			(end -0.67945 -0.305054)
			(stroke
				(width 0.1)
				(type default)
			)
			(layer "F.Fab")
		)
		(fp_line
			(start -0.67945 -0.305054)
			(end -0.12065 -0.305054)
			(stroke
				(width 0.1)
				(type default)
			)
			(layer "F.Fab")
		)
		(pad "1" smd circle
			(at -0.40005 0 180)
			(size 0 0)
			(layers "F.Cu" "F.Mask" "F.Paste")
			(net "PVDD18_S5_P1")
		)
		(pad "2" smd circle
			(at 0.40005 0 180)
			(size 0 0)
			(layers "F.Cu" "F.Mask" "F.Paste")
			(net "SVID_PVDDCR_CPU0_P1_SVC_R")
		)
	)
	(footprint ""
		(layer "F.Cu")
		(at 101.767894 -177.83556 -90)
		(property "Reference" "PC284_3"
			(at 0 0 270)
			(layer "F.SilkS")
			(hide yes)
			(effects
				(font
					(size 1.27 1.27)
				)
			)
		)
		(property "Value" ""
			(at 0 0 270)
			(layer "F.Fab")
			(effects
				(font
					(size 1.27 1.27)
				)
			)
		)
		(duplicate_pad_numbers_are_jumpers no)
		(fp_line
			(start -0.7874 0.4064)
			(end -0.7874 -0.4064)
			(stroke
				(width 0.1524)
				(type default)
			)
			(layer "F.SilkS")
		)
		(fp_line
			(start 0.7874 0.4064)
			(end -0.7874 0.4064)
			(stroke
				(width 0.1524)
				(type default)
			)
			(layer "F.SilkS")
		)
		(fp_line
			(start -0.7874 -0.4064)
			(end 0.7874 -0.4064)
			(stroke
				(width 0.1524)
				(type default)
			)
			(layer "F.SilkS")
		)
		(fp_line
			(start 0.7874 -0.4064)
			(end 0.7874 0.4064)
			(stroke
				(width 0.1524)
				(type default)
			)
			(layer "F.SilkS")
		)
		(fp_line
			(start -0.67945 0.3048)
			(end -0.67945 -0.305054)
			(stroke
				(width 0.1)
				(type default)
			)
			(layer "F.Fab")
		)
		(fp_line
			(start -0.12065 0.3048)
			(end -0.67945 0.3048)
			(stroke
				(width 0.1)
				(type default)
			)
			(layer "F.Fab")
		)
		(fp_line
			(start 0.120396 0.3048)
			(end 0.120396 0.2794)
			(stroke
				(width 0.1)
				(type default)
			)
			(layer "F.Fab")
		)
		(fp_line
			(start 0.67945 0.3048)
			(end 0.120396 0.3048)
			(stroke
				(width 0.1)
				(type default)
			)
			(layer "F.Fab")
		)
		(fp_line
			(start -0.12065 0.2794)
			(end -0.12065 0.3048)
			(stroke
				(width 0.1)
				(type default)
			)
			(layer "F.Fab")
		)
		(fp_line
			(start 0.120396 0.2794)
			(end -0.12065 0.2794)
			(stroke
				(width 0.1)
				(type default)
			)
			(layer "F.Fab")
		)
		(fp_line
			(start -0.12065 -0.2794)
			(end 0.12065 -0.2794)
			(stroke
				(width 0.1)
				(type default)
			)
			(layer "F.Fab")
		)
		(fp_line
			(start 0.12065 -0.2794)
			(end 0.12065 -0.3048)
			(stroke
				(width 0.1)
				(type default)
			)
			(layer "F.Fab")
		)
		(fp_line
			(start 0.12065 -0.3048)
			(end 0.67945 -0.3048)
			(stroke
				(width 0.1)
				(type default)
			)
			(layer "F.Fab")
		)
		(fp_line
			(start 0.67945 -0.3048)
			(end 0.67945 0.3048)
			(stroke
				(width 0.1)
				(type default)
			)
			(layer "F.Fab")
		)
		(fp_line
			(start -0.67945 -0.305054)
			(end -0.12065 -0.305054)
			(stroke
				(width 0.1)
				(type default)
			)
			(layer "F.Fab")
		)
		(fp_line
			(start -0.12065 -0.305054)
			(end -0.12065 -0.2794)
			(stroke
				(width 0.1)
				(type default)
			)
			(layer "F.Fab")
		)
		(pad "1" smd circle
			(at -0.40005 0 270)
			(size 0 0)
			(layers "F.Cu" "F.Mask" "F.Paste")
			(net "PVDDCR_CPU0_P1_VCCS")
		)
		(pad "2" smd circle
			(at 0.40005 0 270)
			(size 0 0)
			(layers "F.Cu" "F.Mask" "F.Paste")
			(net "GND")
		)
	)
	(footprint ""
		(layer "F.Cu")
		(at 137.971784 -50.611024 180)
		(property "Reference" "R6215"
			(at 0 0 180)
			(layer "F.SilkS")
			(hide yes)
			(effects
				(font
					(size 1.27 1.27)
				)
			)
		)
		(property "Value" ""
			(at 0 0 180)
			(layer "F.Fab")
			(effects
				(font
					(size 1.27 1.27)
				)
			)
		)
		(duplicate_pad_numbers_are_jumpers no)
		(fp_line
			(start 0.7874 0.4064)
			(end -0.7874 0.4064)
			(stroke
				(width 0.1524)
				(type default)
			)
			(layer "F.SilkS")
		)
		(fp_line
			(start 0.7874 -0.4064)
			(end 0.7874 0.4064)
			(stroke
				(width 0.1524)
				(type default)
			)
			(layer "F.SilkS")
		)
		(fp_line
			(start -0.7874 0.4064)
			(end -0.7874 -0.4064)
			(stroke
				(width 0.1524)
				(type default)
			)
			(layer "F.SilkS")
		)
		(fp_line
			(start -0.7874 -0.4064)
			(end 0.7874 -0.4064)
			(stroke
				(width 0.1524)
				(type default)
			)
			(layer "F.SilkS")
		)
		(fp_line
			(start 0.67945 0.3048)
			(end 0.120396 0.3048)
			(stroke
				(width 0.1)
				(type default)
			)
			(layer "F.Fab")
		)
		(fp_line
			(start 0.67945 -0.3048)
			(end 0.67945 0.3048)
			(stroke
				(width 0.1)
				(type default)
			)
			(layer "F.Fab")
		)
		(fp_line
			(start 0.12065 -0.2794)
			(end 0.12065 -0.3048)
			(stroke
				(width 0.1)
				(type default)
			)
			(layer "F.Fab")
		)
		(fp_line
			(start 0.12065 -0.3048)
			(end 0.67945 -0.3048)
			(stroke
				(width 0.1)
				(type default)
			)
			(layer "F.Fab")
		)
		(fp_line
			(start 0.120396 0.3048)
			(end 0.120396 0.2794)
			(stroke
				(width 0.1)
				(type default)
			)
			(layer "F.Fab")
		)
		(fp_line
			(start 0.120396 0.2794)
			(end -0.12065 0.2794)
			(stroke
				(width 0.1)
				(type default)
			)
			(layer "F.Fab")
		)
		(fp_line
			(start -0.12065 0.3048)
			(end -0.67945 0.3048)
			(stroke
				(width 0.1)
				(type default)
			)
			(layer "F.Fab")
		)
		(fp_line
			(start -0.12065 0.2794)
			(end -0.12065 0.3048)
			(stroke
				(width 0.1)
				(type default)
			)
			(layer "F.Fab")
		)
		(fp_line
			(start -0.12065 -0.2794)
			(end 0.12065 -0.2794)
			(stroke
				(width 0.1)
				(type default)
			)
			(layer "F.Fab")
		)
		(fp_line
			(start -0.12065 -0.305054)
			(end -0.12065 -0.2794)
			(stroke
				(width 0.1)
				(type default)
			)
			(layer "F.Fab")
		)
		(fp_line
			(start -0.67945 0.3048)
			(end -0.67945 -0.305054)
			(stroke
				(width 0.1)
				(type default)
			)
			(layer "F.Fab")
		)
		(fp_line
			(start -0.67945 -0.305054)
			(end -0.12065 -0.305054)
			(stroke
				(width 0.1)
				(type default)
			)
			(layer "F.Fab")
		)
		(pad "1" smd circle
			(at -0.40005 0 180)
			(size 0 0)
			(layers "F.Cu" "F.Mask" "F.Paste")
			(net "P3V3_AUX")
		)
		(pad "2" smd circle
			(at 0.40005 0 180)
			(size 0 0)
			(layers "F.Cu" "F.Mask" "F.Paste")
			(net "USB_CPU0_HUB1_MODE_SEL0")
		)
	)
	(footprint ""
		(layer "F.Cu")
		(at 75.546458 -21.839682 180)
		(property "Reference" "PR3823"
			(at 0 0 180)
			(layer "F.SilkS")
			(hide yes)
			(effects
				(font
					(size 1.27 1.27)
				)
			)
		)
		(property "Value" ""
			(at 0 0 180)
			(layer "F.Fab")
			(effects
				(font
					(size 1.27 1.27)
				)
			)
		)
		(duplicate_pad_numbers_are_jumpers no)
		(fp_line
			(start 0.7874 0.4064)
			(end -0.7874 0.4064)
			(stroke
				(width 0.1524)
				(type default)
			)
			(layer "F.SilkS")
		)
		(fp_line
			(start 0.7874 -0.4064)
			(end 0.7874 0.4064)
			(stroke
				(width 0.1524)
				(type default)
			)
			(layer "F.SilkS")
		)
		(fp_line
			(start -0.7874 0.4064)
			(end -0.7874 -0.4064)
			(stroke
				(width 0.1524)
				(type default)
			)
			(layer "F.SilkS")
		)
		(fp_line
			(start -0.7874 -0.4064)
			(end 0.7874 -0.4064)
			(stroke
				(width 0.1524)
				(type default)
			)
			(layer "F.SilkS")
		)
		(fp_line
			(start 0.67945 0.3048)
			(end 0.120396 0.3048)
			(stroke
				(width 0.1)
				(type default)
			)
			(layer "F.Fab")
		)
		(fp_line
			(start 0.67945 -0.3048)
			(end 0.67945 0.3048)
			(stroke
				(width 0.1)
				(type default)
			)
			(layer "F.Fab")
		)
		(fp_line
			(start 0.12065 -0.2794)
			(end 0.12065 -0.3048)
			(stroke
				(width 0.1)
				(type default)
			)
			(layer "F.Fab")
		)
		(fp_line
			(start 0.12065 -0.3048)
			(end 0.67945 -0.3048)
			(stroke
				(width 0.1)
				(type default)
			)
			(layer "F.Fab")
		)
		(fp_line
			(start 0.120396 0.3048)
			(end 0.120396 0.2794)
			(stroke
				(width 0.1)
				(type default)
			)
			(layer "F.Fab")
		)
		(fp_line
			(start 0.120396 0.2794)
			(end -0.12065 0.2794)
			(stroke
				(width 0.1)
				(type default)
			)
			(layer "F.Fab")
		)
		(fp_line
			(start -0.12065 0.3048)
			(end -0.67945 0.3048)
			(stroke
				(width 0.1)
				(type default)
			)
			(layer "F.Fab")
		)
		(fp_line
			(start -0.12065 0.2794)
			(end -0.12065 0.3048)
			(stroke
				(width 0.1)
				(type default)
			)
			(layer "F.Fab")
		)
		(fp_line
			(start -0.12065 -0.2794)
			(end 0.12065 -0.2794)
			(stroke
				(width 0.1)
				(type default)
			)
			(layer "F.Fab")
		)
		(fp_line
			(start -0.12065 -0.305054)
			(end -0.12065 -0.2794)
			(stroke
				(width 0.1)
				(type default)
			)
			(layer "F.Fab")
		)
		(fp_line
			(start -0.67945 0.3048)
			(end -0.67945 -0.305054)
			(stroke
				(width 0.1)
				(type default)
			)
			(layer "F.Fab")
		)
		(fp_line
			(start -0.67945 -0.305054)
			(end -0.12065 -0.305054)
			(stroke
				(width 0.1)
				(type default)
			)
			(layer "F.Fab")
		)
		(pad "1" smd circle
			(at -0.40005 0 180)
			(size 0 0)
			(layers "F.Cu" "F.Mask" "F.Paste")
			(net "P12V_OCP_SENSE_2")
		)
		(pad "2" smd circle
			(at 0.40005 0 180)
			(size 0 0)
			(layers "F.Cu" "F.Mask" "F.Paste")
			(net "GND")
		)
	)
	(footprint ""
		(layer "F.Cu")
		(at 122.55627 -35.430968)
		(property "Reference" "C6026"
			(at 0 0 0)
			(layer "F.SilkS")
			(hide yes)
			(effects
				(font
					(size 1.27 1.27)
				)
			)
		)
		(property "Value" ""
			(at 0 0 0)
			(layer "F.Fab")
			(effects
				(font
					(size 1.27 1.27)
				)
			)
		)
		(duplicate_pad_numbers_are_jumpers no)
		(fp_line
			(start -0.7874 -0.4064)
			(end 0.7874 -0.4064)
			(stroke
				(width 0.1524)
				(type default)
			)
			(layer "F.SilkS")
		)
		(fp_line
			(start -0.7874 0.4064)
			(end -0.7874 -0.4064)
			(stroke
				(width 0.1524)
				(type default)
			)
			(layer "F.SilkS")
		)
		(fp_line
			(start 0.7874 -0.4064)
			(end 0.7874 0.4064)
			(stroke
				(width 0.1524)
				(type default)
			)
			(layer "F.SilkS")
		)
		(fp_line
			(start 0.7874 0.4064)
			(end -0.7874 0.4064)
			(stroke
				(width 0.1524)
				(type default)
			)
			(layer "F.SilkS")
		)
		(fp_line
			(start -0.6858 -0.3048)
			(end -0.1016 -0.3048)
			(stroke
				(width 0.1)
				(type default)
			)
			(layer "F.Fab")
		)
		(fp_line
			(start -0.6858 0.3048)
			(end -0.6858 -0.3048)
			(stroke
				(width 0.1)
				(type default)
			)
			(layer "F.Fab")
		)
		(fp_line
			(start -0.1016 -0.3048)
			(end -0.1016 -0.2794)
			(stroke
				(width 0.1)
				(type default)
			)
			(layer "F.Fab")
		)
		(fp_line
			(start -0.1016 -0.2794)
			(end 0.1016 -0.2794)
			(stroke
				(width 0.1)
				(type default)
			)
			(layer "F.Fab")
		)
		(fp_line
			(start -0.1016 0.2794)
			(end -0.1016 0.3048)
			(stroke
				(width 0.1)
				(type default)
			)
			(layer "F.Fab")
		)
		(fp_line
			(start -0.1016 0.3048)
			(end -0.6858 0.3048)
			(stroke
				(width 0.1)
				(type default)
			)
			(layer "F.Fab")
		)
		(fp_line
			(start 0.1016 -0.3048)
			(end 0.6858 -0.3048)
			(stroke
				(width 0.1)
				(type default)
			)
			(layer "F.Fab")
		)
		(fp_line
			(start 0.1016 -0.2794)
			(end 0.1016 -0.3048)
			(stroke
				(width 0.1)
				(type default)
			)
			(layer "F.Fab")
		)
		(fp_line
			(start 0.1016 0.2794)
			(end -0.1016 0.2794)
			(stroke
				(width 0.1)
				(type default)
			)
			(layer "F.Fab")
		)
		(fp_line
			(start 0.1016 0.3048)
			(end 0.1016 0.2794)
			(stroke
				(width 0.1)
				(type default)
			)
			(layer "F.Fab")
		)
		(fp_line
			(start 0.6858 -0.3048)
			(end 0.6858 0.3048)
			(stroke
				(width 0.1)
				(type default)
			)
			(layer "F.Fab")
		)
		(fp_line
			(start 0.6858 0.3048)
			(end 0.1016 0.3048)
			(stroke
				(width 0.1)
				(type default)
			)
			(layer "F.Fab")
		)
		(pad "1" smd rect
			(at -0.40005 0 180)
			(size 0.4572 0.508)
			(layers "F.Cu" "F.Mask" "F.Paste")
			(net "USB3_CPU0_BMC_HUB2_TX_DN")
		)
		(pad "2" smd rect
			(at 0.40005 0 180)
			(size 0.4572 0.508)
			(layers "F.Cu" "F.Mask" "F.Paste")
			(net "USB3_CPU0_BMC_TX_BUF_C_DN")
		)
	)
	(footprint ""
		(layer "F.Cu")
		(at 32.744918 -351.10547)
		(property "Reference" "PC622_3"
			(at 0 0 0)
			(layer "F.SilkS")
			(hide yes)
			(effects
				(font
					(size 1.27 1.27)
				)
			)
		)
		(property "Value" ""
			(at 0 0 0)
			(layer "F.Fab")
			(effects
				(font
					(size 1.27 1.27)
				)
			)
		)
		(duplicate_pad_numbers_are_jumpers no)
		(fp_line
			(start -0.7874 -0.4064)
			(end 0.7874 -0.4064)
			(stroke
				(width 0.1524)
				(type default)
			)
			(layer "F.SilkS")
		)
		(fp_line
			(start -0.7874 0.4064)
			(end -0.7874 -0.4064)
			(stroke
				(width 0.1524)
				(type default)
			)
			(layer "F.SilkS")
		)
		(fp_line
			(start 0.7874 -0.4064)
			(end 0.7874 0.4064)
			(stroke
				(width 0.1524)
				(type default)
			)
			(layer "F.SilkS")
		)
		(fp_line
			(start 0.7874 0.4064)
			(end -0.7874 0.4064)
			(stroke
				(width 0.1524)
				(type default)
			)
			(layer "F.SilkS")
		)
		(fp_line
			(start -0.67945 -0.305054)
			(end -0.12065 -0.305054)
			(stroke
				(width 0.1)
				(type default)
			)
			(layer "F.Fab")
		)
		(fp_line
			(start -0.67945 0.3048)
			(end -0.67945 -0.305054)
			(stroke
				(width 0.1)
				(type default)
			)
			(layer "F.Fab")
		)
		(fp_line
			(start -0.12065 -0.305054)
			(end -0.12065 -0.2794)
			(stroke
				(width 0.1)
				(type default)
			)
			(layer "F.Fab")
		)
		(fp_line
			(start -0.12065 -0.2794)
			(end 0.12065 -0.2794)
			(stroke
				(width 0.1)
				(type default)
			)
			(layer "F.Fab")
		)
		(fp_line
			(start -0.12065 0.2794)
			(end -0.12065 0.3048)
			(stroke
				(width 0.1)
				(type default)
			)
			(layer "F.Fab")
		)
		(fp_line
			(start -0.12065 0.3048)
			(end -0.67945 0.3048)
			(stroke
				(width 0.1)
				(type default)
			)
			(layer "F.Fab")
		)
		(fp_line
			(start 0.120396 0.2794)
			(end -0.12065 0.2794)
			(stroke
				(width 0.1)
				(type default)
			)
			(layer "F.Fab")
		)
		(fp_line
			(start 0.120396 0.3048)
			(end 0.120396 0.2794)
			(stroke
				(width 0.1)
				(type default)
			)
			(layer "F.Fab")
		)
		(fp_line
			(start 0.12065 -0.3048)
			(end 0.67945 -0.3048)
			(stroke
				(width 0.1)
				(type default)
			)
			(layer "F.Fab")
		)
		(fp_line
			(start 0.12065 -0.2794)
			(end 0.12065 -0.3048)
			(stroke
				(width 0.1)
				(type default)
			)
			(layer "F.Fab")
		)
		(fp_line
			(start 0.67945 -0.3048)
			(end 0.67945 0.3048)
			(stroke
				(width 0.1)
				(type default)
			)
			(layer "F.Fab")
		)
		(fp_line
			(start 0.67945 0.3048)
			(end 0.120396 0.3048)
			(stroke
				(width 0.1)
				(type default)
			)
			(layer "F.Fab")
		)
		(pad "1" smd circle
			(at -0.40005 0)
			(size 0 0)
			(layers "F.Cu" "F.Mask" "F.Paste")
			(net "SW_P12V_AUX_PVDDIO_P1_FLT")
		)
		(pad "2" smd circle
			(at 0.40005 0)
			(size 0 0)
			(layers "F.Cu" "F.Mask" "F.Paste")
			(net "GND")
		)
	)
	(footprint ""
		(layer "F.Cu")
		(at 396.509748 -16.100298 90)
		(property "Reference" "C1553"
			(at 0 0 90)
			(layer "F.SilkS")
			(hide yes)
			(effects
				(font
					(size 1.27 1.27)
				)
			)
		)
		(property "Value" ""
			(at 0 0 90)
			(layer "F.Fab")
			(effects
				(font
					(size 1.27 1.27)
				)
			)
		)
		(duplicate_pad_numbers_are_jumpers no)
		(fp_line
			(start 0.299974 -0.150114)
			(end 0.299974 0.150114)
			(stroke
				(width 0.1)
				(type default)
			)
			(layer "F.Fab")
		)
		(fp_line
			(start -0.299974 -0.150114)
			(end 0.299974 -0.150114)
			(stroke
				(width 0.1)
				(type default)
			)
			(layer "F.Fab")
		)
		(fp_line
			(start 0.299974 0.150114)
			(end -0.299974 0.150114)
			(stroke
				(width 0.1)
				(type default)
			)
			(layer "F.Fab")
		)
		(fp_line
			(start -0.299974 0.150114)
			(end -0.299974 -0.150114)
			(stroke
				(width 0.1)
				(type default)
			)
			(layer "F.Fab")
		)
		(pad "1" smd rect
			(at -0.2667 0 90)
			(size 0.3048 0.381)
			(layers "F.Cu" "F.Mask" "F.Paste")
			(net "P5E_CPU0_G3_TX_C_DP<13>")
		)
		(pad "2" smd rect
			(at 0.2667 0 90)
			(size 0.3048 0.381)
			(layers "F.Cu" "F.Mask" "F.Paste")
			(net "P5E_CPU0_G3_TX_DP<13>")
		)
	)
	(footprint ""
		(layer "F.Cu")
		(at 22.742906 19.444716 -90)
		(property "Reference" "JP12_12"
			(at 0 0 270)
			(layer "F.SilkS")
			(hide yes)
			(effects
				(font
					(size 1.27 1.27)
				)
			)
		)
		(property "Value" ""
			(at 0 0 270)
			(layer "F.Fab")
			(effects
				(font
					(size 1.27 1.27)
				)
			)
		)
		(duplicate_pad_numbers_are_jumpers no)
		(pad "1" smd circle
			(at 0 0 270)
			(size 0.762 0.762)
			(layers "F.Cu" "F.Mask" "F.Paste")
			(net "Net_10794")
		)
	)
	(footprint ""
		(layer "F.Cu")
		(at 125.749812 -440.489848)
		(property "Reference" "J110"
			(at -4.40944 23.347172 0)
			(unlocked yes)
			(layer "F.SilkS")
			(effects
				(font
					(size 0.7874 0.5842)
					(thickness 0.1524)
				)
				(justify left)
			)
		)
		(property "Value" ""
			(at 0 0 0)
			(layer "F.Fab")
			(effects
				(font
					(size 1.27 1.27)
				)
			)
		)
		(duplicate_pad_numbers_are_jumpers no)
		(fp_line
			(start -4.249928 22.400006)
			(end -4.249928 -0.484124)
			(stroke
				(width 0.1524)
				(type default)
			)
			(layer "F.SilkS")
		)
		(fp_line
			(start -1.249934 -1.500124)
			(end 15.649956 -1.500124)
			(stroke
				(width 0.1524)
				(type default)
			)
			(layer "F.SilkS")
		)
		(fp_line
			(start -1.249934 -0.484124)
			(end -1.249934 19.400012)
			(stroke
				(width 0.1524)
				(type default)
			)
			(layer "F.SilkS")
		)
		(fp_line
			(start -1.249934 19.400012)
			(end 15.649956 19.400012)
			(stroke
				(width 0.1524)
				(type default)
			)
			(layer "F.SilkS")
		)
		(fp_line
			(start 0.0254 -0.9144)
			(end 1.0414 -0.9144)
			(stroke
				(width 0.1524)
				(type default)
			)
			(layer "F.SilkS")
		)
		(fp_line
			(start 0.5334 -1.4224)
			(end 0.0254 -0.9144)
			(stroke
				(width 0.1524)
				(type default)
			)
			(layer "F.SilkS")
		)
		(fp_line
			(start 0.5334 -1.4224)
			(end 0.5334 -0.5588)
			(stroke
				(width 0.1524)
				(type default)
			)
			(layer "F.SilkS")
		)
		(fp_line
			(start 0.5334 -0.5588)
			(end 1.8034 -0.5588)
			(stroke
				(width 0.1524)
				(type default)
			)
			(layer "F.SilkS")
		)
		(fp_line
			(start 1.0414 -0.9144)
			(end 0.5334 -1.4224)
			(stroke
				(width 0.1524)
				(type default)
			)
			(layer "F.SilkS")
		)
		(fp_line
			(start 1.8034 -0.5588)
			(end 2.032 -0.7874)
			(stroke
				(width 0.1524)
				(type default)
			)
			(layer "F.SilkS")
		)
		(fp_line
			(start 15.649956 19.400012)
			(end 15.649956 16.563848)
			(stroke
				(width 0.1524)
				(type default)
			)
			(layer "F.SilkS")
		)
		(fp_line
			(start 18.64995 16.612108)
			(end 18.64995 22.400006)
			(stroke
				(width 0.1524)
				(type default)
			)
			(layer "F.SilkS")
		)
		(fp_line
			(start 18.64995 22.400006)
			(end -4.249928 22.400006)
			(stroke
				(width 0.1524)
				(type default)
			)
			(layer "F.SilkS")
		)
		(fp_poly
			(pts
				(xy -1.654048 0) (xy -2.670048 0.508) (xy -2.670048 -0.508)
			)
			(stroke
				(width 0)
				(type default)
			)
			(fill yes)
			(layer "F.SilkS")
		)
		(fp_line
			(start -4.249928 -11.999976)
			(end 18.64995 -11.999976)
			(stroke
				(width 0.1524)
				(type default)
			)
			(layer "B.SilkS")
		)
		(fp_line
			(start -4.249928 4.244848)
			(end -4.249928 -11.999976)
			(stroke
				(width 0.1524)
				(type default)
			)
			(layer "B.SilkS")
		)
		(fp_line
			(start -4.249928 16.487648)
			(end -4.249928 8.994648)
			(stroke
				(width 0.1524)
				(type default)
			)
			(layer "B.SilkS")
		)
		(fp_line
			(start -4.249928 22.400006)
			(end -4.249928 17.783048)
			(stroke
				(width 0.1524)
				(type default)
			)
			(layer "B.SilkS")
		)
		(fp_line
			(start 18.64995 -11.999976)
			(end 18.64995 -0.824992)
			(stroke
				(width 0.1524)
				(type default)
			)
			(layer "B.SilkS")
		)
		(fp_line
			(start 18.64995 17.272508)
			(end 18.64995 22.400006)
			(stroke
				(width 0.1524)
				(type default)
			)
			(layer "B.SilkS")
		)
		(fp_line
			(start 18.64995 22.400006)
			(end -4.249928 22.400006)
			(stroke
				(width 0.1524)
				(type default)
			)
			(layer "B.SilkS")
		)
		(fp_line
			(start -4.249928 -11.999976)
			(end 18.64995 -11.999976)
			(stroke
				(width 0.1)
				(type default)
			)
			(layer "B.Fab")
		)
		(fp_line
			(start -4.249928 22.400006)
			(end -4.249928 -11.999976)
			(stroke
				(width 0.1)
				(type default)
			)
			(layer "B.Fab")
		)
		(fp_line
			(start 18.64995 -11.999976)
			(end 18.64995 22.400006)
			(stroke
				(width 0.1)
				(type default)
			)
			(layer "B.Fab")
		)
		(fp_line
			(start 18.64995 22.400006)
			(end -4.249928 22.400006)
			(stroke
				(width 0.1)
				(type default)
			)
			(layer "B.Fab")
		)
		(fp_line
			(start -1.249934 -8.999982)
			(end -1.249934 19.400012)
			(stroke
				(width 0.1)
				(type default)
			)
			(layer "F.Fab")
		)
		(fp_line
			(start -1.249934 19.400012)
			(end 15.649956 19.400012)
			(stroke
				(width 0.1)
				(type default)
			)
			(layer "F.Fab")
		)
		(fp_line
			(start 15.649956 -8.999982)
			(end -1.249934 -8.999982)
			(stroke
				(width 0.1)
				(type default)
			)
			(layer "F.Fab")
		)
		(fp_line
			(start 15.649956 19.400012)
			(end 15.649956 -8.999982)
			(stroke
				(width 0.1)
				(type default)
			)
			(layer "F.Fab")
		)
		(fp_poly
			(pts
				(xy -2.670048 -0.508) (xy -2.670048 0.508) (xy -1.654048 0)
			)
			(stroke
				(width 0)
				(type default)
			)
			(fill yes)
			(layer "F.Fab")
		)
		(fp_text user "PRESS-FIT"
			(at -2.91592 26.268426 0)
			(unlocked yes)
			(layer "F.SilkS")
			(effects
				(font
					(size 1.905 1.4224)
					(thickness 0.1524)
				)
				(justify left)
			)
		)
		(fp_text user "B"
			(at -2.253742 1.199896 90)
			(unlocked yes)
			(layer "F.SilkS")
			(effects
				(font
					(size 0.7874 0.5842)
					(thickness 0.1524)
				)
			)
		)
		(fp_text user "C"
			(at -2.253742 2.400046 90)
			(unlocked yes)
			(layer "F.SilkS")
			(effects
				(font
					(size 0.7874 0.5842)
					(thickness 0.1524)
				)
			)
		)
		(fp_text user "D"
			(at -2.253742 3.599942 90)
			(unlocked yes)
			(layer "F.SilkS")
			(effects
				(font
					(size 0.7874 0.5842)
					(thickness 0.1524)
				)
			)
		)
		(fp_text user "E"
			(at -2.253742 4.800092 90)
			(unlocked yes)
			(layer "F.SilkS")
			(effects
				(font
					(size 0.7874 0.5842)
					(thickness 0.1524)
				)
			)
		)
		(fp_text user "F"
			(at -2.253742 5.999988 90)
			(unlocked yes)
			(layer "F.SilkS")
			(effects
				(font
					(size 0.7874 0.5842)
					(thickness 0.1524)
				)
			)
		)
		(fp_text user "G"
			(at -2.253742 7.199884 90)
			(unlocked yes)
			(layer "F.SilkS")
			(effects
				(font
					(size 0.7874 0.5842)
					(thickness 0.1524)
				)
			)
		)
		(fp_text user "H"
			(at -2.253742 8.400034 90)
			(unlocked yes)
			(layer "F.SilkS")
			(effects
				(font
					(size 0.7874 0.5842)
					(thickness 0.1524)
				)
			)
		)
		(fp_text user "I"
			(at -2.253742 9.59993 90)
			(unlocked yes)
			(layer "F.SilkS")
			(effects
				(font
					(size 0.7874 0.5842)
					(thickness 0.1524)
				)
			)
		)
		(fp_text user "J"
			(at -2.253742 10.80008 90)
			(unlocked yes)
			(layer "F.SilkS")
			(effects
				(font
					(size 0.7874 0.5842)
					(thickness 0.1524)
				)
			)
		)
		(fp_text user "K"
			(at -2.253742 11.999976 90)
			(unlocked yes)
			(layer "F.SilkS")
			(effects
				(font
					(size 0.7874 0.5842)
					(thickness 0.1524)
				)
			)
		)
		(fp_text user "L"
			(at -2.253742 13.200126 90)
			(unlocked yes)
			(layer "F.SilkS")
			(effects
				(font
					(size 0.7874 0.5842)
					(thickness 0.1524)
				)
			)
		)
		(fp_text user "M"
			(at -2.253742 14.400022 90)
			(unlocked yes)
			(layer "F.SilkS")
			(effects
				(font
					(size 0.7874 0.5842)
					(thickness 0.1524)
				)
			)
		)
		(fp_text user "N"
			(at -2.253742 15.599918 90)
			(unlocked yes)
			(layer "F.SilkS")
			(effects
				(font
					(size 0.7874 0.5842)
					(thickness 0.1524)
				)
			)
		)
		(fp_text user "1"
			(at 0.111252 19.8628 90)
			(unlocked yes)
			(layer "F.SilkS")
			(effects
				(font
					(size 0.7874 0.5842)
					(thickness 0.1524)
				)
			)
		)
		(fp_text user "2"
			(at 2.111248 19.8628 90)
			(unlocked yes)
			(layer "F.SilkS")
			(effects
				(font
					(size 0.7874 0.5842)
					(thickness 0.1524)
				)
			)
		)
		(fp_text user "EDGE OF DAUGHTER CARD"
			(at 2.2479 -0.899668 0)
			(unlocked yes)
			(layer "F.SilkS")
			(effects
				(font
					(size 0.635 0.4064)
					(thickness 0.1524)
				)
				(justify left)
			)
		)
		(fp_text user "3"
			(at 4.111244 19.8628 90)
			(unlocked yes)
			(layer "F.SilkS")
			(effects
				(font
					(size 0.7874 0.5842)
					(thickness 0.1524)
				)
			)
		)
		(fp_text user "4"
			(at 6.11124 19.8628 90)
			(unlocked yes)
			(layer "F.SilkS")
			(effects
				(font
					(size 0.7874 0.5842)
					(thickness 0.1524)
				)
			)
		)
		(fp_text user "5"
			(at 8.111236 19.8628 90)
			(unlocked yes)
			(layer "F.SilkS")
			(effects
				(font
					(size 0.7874 0.5842)
					(thickness 0.1524)
				)
			)
		)
		(fp_text user "6"
			(at 10.111232 19.8628 90)
			(unlocked yes)
			(layer "F.SilkS")
			(effects
				(font
					(size 0.7874 0.5842)
					(thickness 0.1524)
				)
			)
		)
		(fp_text user "7"
			(at 12.111228 19.8628 90)
			(unlocked yes)
			(layer "F.SilkS")
			(effects
				(font
					(size 0.7874 0.5842)
					(thickness 0.1524)
				)
			)
		)
		(fp_text user "8"
			(at 14.111224 19.8628 90)
			(unlocked yes)
			(layer "F.SilkS")
			(effects
				(font
					(size 0.7874 0.5842)
					(thickness 0.1524)
				)
			)
		)
		(fp_text user "PRESS-FIT"
			(at -2.655062 -0.479552 90)
			(unlocked yes)
			(layer "B.SilkS")
			(effects
				(font
					(size 1.905 1.4224)
					(thickness 0.1524)
				)
				(justify left mirror)
			)
		)
		(fp_text user "A"
			(at -1.199134 0 90)
			(unlocked yes)
			(layer "B.SilkS")
			(effects
				(font
					(size 0.7874 0.5842)
					(thickness 0.1524)
				)
				(justify mirror)
			)
		)
		(fp_text user "G"
			(at -1.173734 7.4168 90)
			(unlocked yes)
			(layer "B.SilkS")
			(effects
				(font
					(size 0.7874 0.5842)
					(thickness 0.1524)
				)
				(justify mirror)
			)
		)
		(fp_text user "H"
			(at -1.148334 8.636 90)
			(unlocked yes)
			(layer "B.SilkS")
			(effects
				(font
					(size 0.7874 0.5842)
					(thickness 0.1524)
				)
				(justify mirror)
			)
		)
		(fp_text user "B"
			(at -1.14681 1.326896 90)
			(unlocked yes)
			(layer "B.SilkS")
			(effects
				(font
					(size 0.7874 0.5842)
					(thickness 0.1524)
				)
				(justify mirror)
			)
		)
		(fp_text user "C"
			(at -1.14681 2.527046 90)
			(unlocked yes)
			(layer "B.SilkS")
			(effects
				(font
					(size 0.7874 0.5842)
					(thickness 0.1524)
				)
				(justify mirror)
			)
		)
		(fp_text user "D"
			(at -1.14681 3.726942 90)
			(unlocked yes)
			(layer "B.SilkS")
			(effects
				(font
					(size 0.7874 0.5842)
					(thickness 0.1524)
				)
				(justify mirror)
			)
		)
		(fp_text user "E"
			(at -1.14681 4.927092 90)
			(unlocked yes)
			(layer "B.SilkS")
			(effects
				(font
					(size 0.7874 0.5842)
					(thickness 0.1524)
				)
				(justify mirror)
			)
		)
		(fp_text user "F"
			(at -1.14681 6.126988 90)
			(unlocked yes)
			(layer "B.SilkS")
			(effects
				(font
					(size 0.7874 0.5842)
					(thickness 0.1524)
				)
				(justify mirror)
			)
		)
		(fp_text user "I"
			(at -1.14681 9.72693 90)
			(unlocked yes)
			(layer "B.SilkS")
			(effects
				(font
					(size 0.7874 0.5842)
					(thickness 0.1524)
				)
				(justify mirror)
			)
		)
		(fp_text user "J"
			(at -1.14681 10.92708 90)
			(unlocked yes)
			(layer "B.SilkS")
			(effects
				(font
					(size 0.7874 0.5842)
					(thickness 0.1524)
				)
				(justify mirror)
			)
		)
		(fp_text user "K"
			(at -1.14681 12.126976 90)
			(unlocked yes)
			(layer "B.SilkS")
			(effects
				(font
					(size 0.7874 0.5842)
					(thickness 0.1524)
				)
				(justify mirror)
			)
		)
		(fp_text user "L"
			(at -1.14681 13.327126 90)
			(unlocked yes)
			(layer "B.SilkS")
			(effects
				(font
					(size 0.7874 0.5842)
					(thickness 0.1524)
				)
				(justify mirror)
			)
		)
		(fp_text user "M"
			(at -1.14681 14.527022 90)
			(unlocked yes)
			(layer "B.SilkS")
			(effects
				(font
					(size 0.7874 0.5842)
					(thickness 0.1524)
				)
				(justify mirror)
			)
		)
		(fp_text user "N"
			(at -1.14681 15.726918 90)
			(unlocked yes)
			(layer "B.SilkS")
			(effects
				(font
					(size 0.7874 0.5842)
					(thickness 0.1524)
				)
				(justify mirror)
			)
		)
		(fp_text user "1"
			(at 0.060452 16.764 90)
			(unlocked yes)
			(layer "B.SilkS")
			(effects
				(font
					(size 0.7874 0.5842)
					(thickness 0.1524)
				)
				(justify mirror)
			)
		)
		(fp_text user "2"
			(at 2.060448 16.764 90)
			(unlocked yes)
			(layer "B.SilkS")
			(effects
				(font
					(size 0.7874 0.5842)
					(thickness 0.1524)
				)
				(justify mirror)
			)
		)
		(fp_text user "3"
			(at 4.060444 16.764 90)
			(unlocked yes)
			(layer "B.SilkS")
			(effects
				(font
					(size 0.7874 0.5842)
					(thickness 0.1524)
				)
				(justify mirror)
			)
		)
		(fp_text user "4"
			(at 6.06044 16.764 90)
			(unlocked yes)
			(layer "B.SilkS")
			(effects
				(font
					(size 0.7874 0.5842)
					(thickness 0.1524)
				)
				(justify mirror)
			)
		)
		(fp_text user "5"
			(at 8.060436 16.764 90)
			(unlocked yes)
			(layer "B.SilkS")
			(effects
				(font
					(size 0.7874 0.5842)
					(thickness 0.1524)
				)
				(justify mirror)
			)
		)
		(fp_text user "6"
			(at 10.060432 16.764 90)
			(unlocked yes)
			(layer "B.SilkS")
			(effects
				(font
					(size 0.7874 0.5842)
					(thickness 0.1524)
				)
				(justify mirror)
			)
		)
		(fp_text user "7"
			(at 12.060428 16.764 90)
			(unlocked yes)
			(layer "B.SilkS")
			(effects
				(font
					(size 0.7874 0.5842)
					(thickness 0.1524)
				)
				(justify mirror)
			)
		)
		(fp_text user "8"
			(at 14.060424 16.764 90)
			(unlocked yes)
			(layer "B.SilkS")
			(effects
				(font
					(size 0.7874 0.5842)
					(thickness 0.1524)
				)
				(justify mirror)
			)
		)
		(fp_text user "A"
			(at -1.199134 0 90)
			(unlocked yes)
			(layer "B.Fab")
			(effects
				(font
					(size 0.7874 0.5842)
					(thickness 0.1524)
				)
				(justify mirror)
			)
		)
		(fp_text user "G"
			(at -1.173734 7.4168 90)
			(unlocked yes)
			(layer "B.Fab")
			(effects
				(font
					(size 0.7874 0.5842)
					(thickness 0.1524)
				)
				(justify mirror)
			)
		)
		(fp_text user "H"
			(at -1.148334 8.636 90)
			(unlocked yes)
			(layer "B.Fab")
			(effects
				(font
					(size 0.7874 0.5842)
					(thickness 0.1524)
				)
				(justify mirror)
			)
		)
		(fp_text user "B"
			(at -1.14681 1.326896 90)
			(unlocked yes)
			(layer "B.Fab")
			(effects
				(font
					(size 0.7874 0.5842)
					(thickness 0.1524)
				)
				(justify mirror)
			)
		)
		(fp_text user "C"
			(at -1.14681 2.527046 90)
			(unlocked yes)
			(layer "B.Fab")
			(effects
				(font
					(size 0.7874 0.5842)
					(thickness 0.1524)
				)
				(justify mirror)
			)
		)
		(fp_text user "D"
			(at -1.14681 3.726942 90)
			(unlocked yes)
			(layer "B.Fab")
			(effects
				(font
					(size 0.7874 0.5842)
					(thickness 0.1524)
				)
				(justify mirror)
			)
		)
		(fp_text user "E"
			(at -1.14681 4.927092 90)
			(unlocked yes)
			(layer "B.Fab")
			(effects
				(font
					(size 0.7874 0.5842)
					(thickness 0.1524)
				)
				(justify mirror)
			)
		)
		(fp_text user "F"
			(at -1.14681 6.126988 90)
			(unlocked yes)
			(layer "B.Fab")
			(effects
				(font
					(size 0.7874 0.5842)
					(thickness 0.1524)
				)
				(justify mirror)
			)
		)
		(fp_text user "I"
			(at -1.14681 9.72693 90)
			(unlocked yes)
			(layer "B.Fab")
			(effects
				(font
					(size 0.7874 0.5842)
					(thickness 0.1524)
				)
				(justify mirror)
			)
		)
		(fp_text user "J"
			(at -1.14681 10.92708 90)
			(unlocked yes)
			(layer "B.Fab")
			(effects
				(font
					(size 0.7874 0.5842)
					(thickness 0.1524)
				)
				(justify mirror)
			)
		)
		(fp_text user "K"
			(at -1.14681 12.126976 90)
			(unlocked yes)
			(layer "B.Fab")
			(effects
				(font
					(size 0.7874 0.5842)
					(thickness 0.1524)
				)
				(justify mirror)
			)
		)
		(fp_text user "L"
			(at -1.14681 13.327126 90)
			(unlocked yes)
			(layer "B.Fab")
			(effects
				(font
					(size 0.7874 0.5842)
					(thickness 0.1524)
				)
				(justify mirror)
			)
		)
		(fp_text user "M"
			(at -1.14681 14.527022 90)
			(unlocked yes)
			(layer "B.Fab")
			(effects
				(font
					(size 0.7874 0.5842)
					(thickness 0.1524)
				)
				(justify mirror)
			)
		)
		(fp_text user "N"
			(at -1.14681 15.726918 90)
			(unlocked yes)
			(layer "B.Fab")
			(effects
				(font
					(size 0.7874 0.5842)
					(thickness 0.1524)
				)
				(justify mirror)
			)
		)
		(fp_text user "1"
			(at 0.060452 16.764 90)
			(unlocked yes)
			(layer "B.Fab")
			(effects
				(font
					(size 0.7874 0.5842)
					(thickness 0.1524)
				)
				(justify mirror)
			)
		)
		(fp_text user "2"
			(at 2.060448 16.764 90)
			(unlocked yes)
			(layer "B.Fab")
			(effects
				(font
					(size 0.7874 0.5842)
					(thickness 0.1524)
				)
				(justify mirror)
			)
		)
		(fp_text user "3"
			(at 4.060444 16.764 90)
			(unlocked yes)
			(layer "B.Fab")
			(effects
				(font
					(size 0.7874 0.5842)
					(thickness 0.1524)
				)
				(justify mirror)
			)
		)
		(fp_text user "4"
			(at 6.06044 16.764 90)
			(unlocked yes)
			(layer "B.Fab")
			(effects
				(font
					(size 0.7874 0.5842)
					(thickness 0.1524)
				)
				(justify mirror)
			)
		)
		(fp_text user "5"
			(at 8.060436 16.764 90)
			(unlocked yes)
			(layer "B.Fab")
			(effects
				(font
					(size 0.7874 0.5842)
					(thickness 0.1524)
				)
				(justify mirror)
			)
		)
		(fp_text user "6"
			(at 10.060432 16.764 90)
			(unlocked yes)
			(layer "B.Fab")
			(effects
				(font
					(size 0.7874 0.5842)
					(thickness 0.1524)
				)
				(justify mirror)
			)
		)
		(fp_text user "7"
			(at 12.060428 16.764 90)
			(unlocked yes)
			(layer "B.Fab")
			(effects
				(font
					(size 0.7874 0.5842)
					(thickness 0.1524)
				)
				(justify mirror)
			)
		)
		(fp_text user "8"
			(at 14.060424 16.764 90)
			(unlocked yes)
			(layer "B.Fab")
			(effects
				(font
					(size 0.7874 0.5842)
					(thickness 0.1524)
				)
				(justify mirror)
			)
		)
		(fp_text user "PRESS-FIT"
			(at 17.23771 -0.0762 90)
			(unlocked yes)
			(layer "B.Fab")
			(effects
				(font
					(size 1.905 1.4224)
					(thickness 0.1524)
				)
				(justify left mirror)
			)
		)
		(fp_text user "B"
			(at -2.253742 1.199896 90)
			(unlocked yes)
			(layer "F.Fab")
			(effects
				(font
					(size 0.7874 0.5842)
					(thickness 0.1524)
				)
			)
		)
		(fp_text user "C"
			(at -2.253742 2.400046 90)
			(unlocked yes)
			(layer "F.Fab")
			(effects
				(font
					(size 0.7874 0.5842)
					(thickness 0.1524)
				)
			)
		)
		(fp_text user "D"
			(at -2.253742 3.599942 90)
			(unlocked yes)
			(layer "F.Fab")
			(effects
				(font
					(size 0.7874 0.5842)
					(thickness 0.1524)
				)
			)
		)
		(fp_text user "E"
			(at -2.253742 4.800092 90)
			(unlocked yes)
			(layer "F.Fab")
			(effects
				(font
					(size 0.7874 0.5842)
					(thickness 0.1524)
				)
			)
		)
		(fp_text user "F"
			(at -2.253742 5.999988 90)
			(unlocked yes)
			(layer "F.Fab")
			(effects
				(font
					(size 0.7874 0.5842)
					(thickness 0.1524)
				)
			)
		)
		(fp_text user "G"
			(at -2.253742 7.199884 90)
			(unlocked yes)
			(layer "F.Fab")
			(effects
				(font
					(size 0.7874 0.5842)
					(thickness 0.1524)
				)
			)
		)
		(fp_text user "H"
			(at -2.253742 8.400034 90)
			(unlocked yes)
			(layer "F.Fab")
			(effects
				(font
					(size 0.7874 0.5842)
					(thickness 0.1524)
				)
			)
		)
		(fp_text user "I"
			(at -2.253742 9.59993 90)
			(unlocked yes)
			(layer "F.Fab")
			(effects
				(font
					(size 0.7874 0.5842)
					(thickness 0.1524)
				)
			)
		)
		(fp_text user "J"
			(at -2.253742 10.80008 90)
			(unlocked yes)
			(layer "F.Fab")
			(effects
				(font
					(size 0.7874 0.5842)
					(thickness 0.1524)
				)
			)
		)
		(fp_text user "K"
			(at -2.253742 11.999976 90)
			(unlocked yes)
			(layer "F.Fab")
			(effects
				(font
					(size 0.7874 0.5842)
					(thickness 0.1524)
				)
			)
		)
		(fp_text user "L"
			(at -2.253742 13.200126 90)
			(unlocked yes)
			(layer "F.Fab")
			(effects
				(font
					(size 0.7874 0.5842)
					(thickness 0.1524)
				)
			)
		)
		(fp_text user "M"
			(at -2.253742 14.400022 90)
			(unlocked yes)
			(layer "F.Fab")
			(effects
				(font
					(size 0.7874 0.5842)
					(thickness 0.1524)
				)
			)
		)
		(fp_text user "N"
			(at -2.253742 15.599918 90)
			(unlocked yes)
			(layer "F.Fab")
			(effects
				(font
					(size 0.7874 0.5842)
					(thickness 0.1524)
				)
			)
		)
		(fp_text user "1"
			(at 0.111252 19.8628 90)
			(unlocked yes)
			(layer "F.Fab")
			(effects
				(font
					(size 0.7874 0.5842)
					(thickness 0.1524)
				)
			)
		)
		(fp_text user "2"
			(at 2.111248 19.8628 90)
			(unlocked yes)
			(layer "F.Fab")
			(effects
				(font
					(size 0.7874 0.5842)
					(thickness 0.1524)
				)
			)
		)
		(fp_text user "3"
			(at 4.111244 19.8628 90)
			(unlocked yes)
			(layer "F.Fab")
			(effects
				(font
					(size 0.7874 0.5842)
					(thickness 0.1524)
				)
			)
		)
		(fp_text user "4"
			(at 6.11124 19.8628 90)
			(unlocked yes)
			(layer "F.Fab")
			(effects
				(font
					(size 0.7874 0.5842)
					(thickness 0.1524)
				)
			)
		)
		(fp_text user "5"
			(at 8.111236 19.8628 90)
			(unlocked yes)
			(layer "F.Fab")
			(effects
				(font
					(size 0.7874 0.5842)
					(thickness 0.1524)
				)
			)
		)
		(fp_text user "6"
			(at 10.111232 19.8628 90)
			(unlocked yes)
			(layer "F.Fab")
			(effects
				(font
					(size 0.7874 0.5842)
					(thickness 0.1524)
				)
			)
		)
		(fp_text user "7"
			(at 12.111228 19.8628 90)
			(unlocked yes)
			(layer "F.Fab")
			(effects
				(font
					(size 0.7874 0.5842)
					(thickness 0.1524)
				)
			)
		)
		(fp_text user "8"
			(at 14.111224 19.8628 90)
			(unlocked yes)
			(layer "F.Fab")
			(effects
				(font
					(size 0.7874 0.5842)
					(thickness 0.1524)
				)
			)
		)
		(fp_text user "PRESS-FIT"
			(at 17.240758 16.521684 90)
			(unlocked yes)
			(layer "F.Fab")
			(effects
				(font
					(size 1.905 1.4224)
					(thickness 0.1524)
				)
				(justify left)
			)
		)
		(pad "A1" thru_hole rect
			(at 0 0 180)
			(size 0.766318 0.766318)
			(drill 0.359918)
			(layers "*.Cu" "*.Mask")
			(remove_unused_layers no)
			(net "GPU_FPGA_EROT_RECOV_BUF_N")
			(clearance 0.0508)
			(thermal_gap 0.0508)
			(padstack
				(mode front_inner_back)
				(layer "Inner"
					(shape circle)
					(size 0.766318 0.766318)
					(clearance 0.0508)
				)
				(layer "B.Cu"
					(shape rect)
					(size 0.766318 0.766318)
					(clearance 0.0508)
				)
			)
		)
		(pad "A2" thru_hole circle
			(at 1.999996 0.199898 180)
			(size 0.906272 0.906272)
			(drill 0.499872)
			(layers "*.Cu" "*.Mask")
			(remove_unused_layers no)
			(net "GND")
			(clearance 0.0508)
			(thermal_gap 0.0508)
		)
		(pad "A3" thru_hole circle
			(at 3.999992 0 180)
			(size 0.766318 0.766318)
			(drill 0.359918)
			(layers "*.Cu" "*.Mask")
			(remove_unused_layers no)
			(net "GPU_HMC_PRSNT_N")
			(clearance 0.0508)
			(thermal_gap 0.0508)
		)
		(pad "A4" thru_hole circle
			(at 5.999988 0.199898 180)
			(size 0.906272 0.906272)
			(drill 0.499872)
			(layers "*.Cu" "*.Mask")
			(remove_unused_layers no)
			(net "GND")
			(clearance 0.0508)
			(thermal_gap 0.0508)
		)
		(pad "A5" thru_hole circle
			(at 7.999984 0 180)
			(size 0.766318 0.766318)
			(drill 0.359918)
			(layers "*.Cu" "*.Mask")
			(remove_unused_layers no)
			(net "GPU_BASE_HMC_READY")
			(clearance 0.0508)
			(thermal_gap 0.0508)
		)
		(pad "A6" thru_hole circle
			(at 9.99998 0.199898 180)
			(size 0.906272 0.906272)
			(drill 0.499872)
			(layers "*.Cu" "*.Mask")
			(remove_unused_layers no)
			(net "GND")
			(clearance 0.0508)
			(thermal_gap 0.0508)
		)
		(pad "A7" thru_hole circle
			(at 11.999976 0 180)
			(size 0.766318 0.766318)
			(drill 0.359918)
			(layers "*.Cu" "*.Mask")
			(remove_unused_layers no)
			(net "GPU_BASE_STBY_EN_BUF")
			(clearance 0.0508)
			(thermal_gap 0.0508)
		)
		(pad "A8" thru_hole circle
			(at 13.999972 0.199898 180)
			(size 0.906272 0.906272)
			(drill 0.499872)
			(layers "*.Cu" "*.Mask")
			(remove_unused_layers no)
			(net "GND")
			(clearance 0.0508)
			(thermal_gap 0.0508)
		)
		(pad "B1" thru_hole circle
			(at 0 1.199896 180)
			(size 0.906272 0.906272)
			(drill 0.499872)
			(layers "*.Cu" "*.Mask")
			(remove_unused_layers no)
			(net "GND")
			(clearance 0.0508)
			(thermal_gap 0.0508)
		)
		(pad "B3" thru_hole circle
			(at 3.999992 1.199896 180)
			(size 0.906272 0.906272)
			(drill 0.499872)
			(layers "*.Cu" "*.Mask")
			(remove_unused_layers no)
			(net "GND")
			(clearance 0.0508)
			(thermal_gap 0.0508)
		)
		(pad "B5" thru_hole circle
			(at 7.999984 1.199896 180)
			(size 0.906272 0.906272)
			(drill 0.499872)
			(layers "*.Cu" "*.Mask")
			(remove_unused_layers no)
			(net "GND")
			(clearance 0.0508)
			(thermal_gap 0.0508)
		)
		(pad "B7" thru_hole circle
			(at 11.999976 1.199896 180)
			(size 0.906272 0.906272)
			(drill 0.499872)
			(layers "*.Cu" "*.Mask")
			(remove_unused_layers no)
			(net "GND")
			(clearance 0.0508)
			(thermal_gap 0.0508)
		)
		(pad "D2" thru_hole circle
			(at 1.999996 3.800094 180)
			(size 0.906272 0.906272)
			(drill 0.499872)
			(layers "*.Cu" "*.Mask")
			(remove_unused_layers no)
			(net "GND")
			(clearance 0.0508)
			(thermal_gap 0.0508)
		)
		(pad "D4" thru_hole circle
			(at 5.999988 3.800094 180)
			(size 0.906272 0.906272)
			(drill 0.499872)
			(layers "*.Cu" "*.Mask")
			(remove_unused_layers no)
			(net "GND")
			(clearance 0.0508)
			(thermal_gap 0.0508)
		)
		(pad "D6" thru_hole circle
			(at 9.99998 3.800094 180)
			(size 0.906272 0.906272)
			(drill 0.499872)
			(layers "*.Cu" "*.Mask")
			(remove_unused_layers no)
			(net "GND")
			(clearance 0.0508)
			(thermal_gap 0.0508)
		)
		(pad "D8" thru_hole circle
			(at 13.999972 3.800094 180)
			(size 0.906272 0.906272)
			(drill 0.499872)
			(layers "*.Cu" "*.Mask")
			(remove_unused_layers no)
			(net "GND")
			(clearance 0.0508)
			(thermal_gap 0.0508)
		)
		(pad "E1" thru_hole circle
			(at 0 4.800092 180)
			(size 0.906272 0.906272)
			(drill 0.499872)
			(layers "*.Cu" "*.Mask")
			(remove_unused_layers no)
			(net "GND")
			(clearance 0.0508)
			(thermal_gap 0.0508)
		)
		(pad "E3" thru_hole circle
			(at 3.999992 4.800092 180)
			(size 0.906272 0.906272)
			(drill 0.499872)
			(layers "*.Cu" "*.Mask")
			(remove_unused_layers no)
			(net "GND")
			(clearance 0.0508)
			(thermal_gap 0.0508)
		)
		(pad "E5" thru_hole circle
			(at 7.999984 4.800092 180)
			(size 0.906272 0.906272)
			(drill 0.499872)
			(layers "*.Cu" "*.Mask")
			(remove_unused_layers no)
			(net "GND")
			(clearance 0.0508)
			(thermal_gap 0.0508)
		)
		(pad "E7" thru_hole circle
			(at 11.999976 4.800092 180)
			(size 0.906272 0.906272)
			(drill 0.499872)
			(layers "*.Cu" "*.Mask")
			(remove_unused_layers no)
			(net "GND")
			(clearance 0.0508)
			(thermal_gap 0.0508)
		)
		(pad "G2" thru_hole circle
			(at 1.999996 7.400036 180)
			(size 0.906272 0.906272)
			(drill 0.499872)
			(layers "*.Cu" "*.Mask")
			(remove_unused_layers no)
			(net "GND")
			(clearance 0.0508)
			(thermal_gap 0.0508)
		)
		(pad "G4" thru_hole circle
			(at 5.999988 7.400036 180)
			(size 0.906272 0.906272)
			(drill 0.499872)
			(layers "*.Cu" "*.Mask")
			(remove_unused_layers no)
			(net "GND")
			(clearance 0.0508)
			(thermal_gap 0.0508)
		)
		(pad "G6" thru_hole circle
			(at 9.99998 7.400036 180)
			(size 0.906272 0.906272)
			(drill 0.499872)
			(layers "*.Cu" "*.Mask")
			(remove_unused_layers no)
			(net "GND")
			(clearance 0.0508)
			(thermal_gap 0.0508)
		)
		(pad "G8" thru_hole circle
			(at 13.999972 7.400036 180)
			(size 0.906272 0.906272)
			(drill 0.499872)
			(layers "*.Cu" "*.Mask")
			(remove_unused_layers no)
			(net "GND")
			(clearance 0.0508)
			(thermal_gap 0.0508)
		)
		(pad "H1" thru_hole circle
			(at 0 8.400034 180)
			(size 0.906272 0.906272)
			(drill 0.499872)
			(layers "*.Cu" "*.Mask")
			(remove_unused_layers no)
			(net "GND")
			(clearance 0.0508)
			(thermal_gap 0.0508)
		)
		(pad "H3" thru_hole circle
			(at 3.999992 8.400034 180)
			(size 0.906272 0.906272)
			(drill 0.499872)
			(layers "*.Cu" "*.Mask")
			(remove_unused_layers no)
			(net "GND")
			(clearance 0.0508)
			(thermal_gap 0.0508)
		)
		(pad "H5" thru_hole circle
			(at 7.999984 8.400034 180)
			(size 0.906272 0.906272)
			(drill 0.499872)
			(layers "*.Cu" "*.Mask")
			(remove_unused_layers no)
			(net "GND")
			(clearance 0.0508)
			(thermal_gap 0.0508)
		)
		(pad "H7" thru_hole circle
			(at 11.999976 8.400034 180)
			(size 0.906272 0.906272)
			(drill 0.499872)
			(layers "*.Cu" "*.Mask")
			(remove_unused_layers no)
			(net "GND")
			(clearance 0.0508)
			(thermal_gap 0.0508)
		)
		(pad "J2" thru_hole circle
			(at 1.999996 10.999978 180)
			(size 0.906272 0.906272)
			(drill 0.499872)
			(layers "*.Cu" "*.Mask")
			(remove_unused_layers no)
			(net "GND")
			(clearance 0.0508)
			(thermal_gap 0.0508)
		)
		(pad "J4" thru_hole circle
			(at 5.999988 10.999978 180)
			(size 0.906272 0.906272)
			(drill 0.499872)
			(layers "*.Cu" "*.Mask")
			(remove_unused_layers no)
			(net "GND")
			(clearance 0.0508)
			(thermal_gap 0.0508)
		)
		(pad "J6" thru_hole circle
			(at 9.99998 10.999978 180)
			(size 0.906272 0.906272)
			(drill 0.499872)
			(layers "*.Cu" "*.Mask")
			(remove_unused_layers no)
			(net "GND")
			(clearance 0.0508)
			(thermal_gap 0.0508)
		)
		(pad "J8" thru_hole circle
			(at 13.999972 10.999978 180)
			(size 0.906272 0.906272)
			(drill 0.499872)
			(layers "*.Cu" "*.Mask")
			(remove_unused_layers no)
			(net "GND")
			(clearance 0.0508)
			(thermal_gap 0.0508)
		)
		(pad "K1" thru_hole circle
			(at 0 11.999976 180)
			(size 0.906272 0.906272)
			(drill 0.499872)
			(layers "*.Cu" "*.Mask")
			(remove_unused_layers no)
			(net "GND")
			(clearance 0.0508)
			(thermal_gap 0.0508)
		)
		(pad "K3" thru_hole circle
			(at 3.999992 11.999976 180)
			(size 0.906272 0.906272)
			(drill 0.499872)
			(layers "*.Cu" "*.Mask")
			(remove_unused_layers no)
			(net "GND")
			(clearance 0.0508)
			(thermal_gap 0.0508)
		)
		(pad "K5" thru_hole circle
			(at 7.999984 11.999976 180)
			(size 0.906272 0.906272)
			(drill 0.499872)
			(layers "*.Cu" "*.Mask")
			(remove_unused_layers no)
			(net "GND")
			(clearance 0.0508)
			(thermal_gap 0.0508)
		)
		(pad "K7" thru_hole circle
			(at 11.999976 11.999976 180)
			(size 0.906272 0.906272)
			(drill 0.499872)
			(layers "*.Cu" "*.Mask")
			(remove_unused_layers no)
			(net "GND")
			(clearance 0.0508)
			(thermal_gap 0.0508)
		)
		(pad "M2" thru_hole circle
			(at 1.999996 14.59992 180)
			(size 0.906272 0.906272)
			(drill 0.499872)
			(layers "*.Cu" "*.Mask")
			(remove_unused_layers no)
			(net "GND")
			(clearance 0.0508)
			(thermal_gap 0.0508)
		)
		(pad "M4" thru_hole circle
			(at 5.999988 14.59992 180)
			(size 0.906272 0.906272)
			(drill 0.499872)
			(layers "*.Cu" "*.Mask")
			(remove_unused_layers no)
			(net "GND")
			(clearance 0.0508)
			(thermal_gap 0.0508)
		)
		(pad "M6" thru_hole circle
			(at 9.99998 14.59992 180)
			(size 0.906272 0.906272)
			(drill 0.499872)
			(layers "*.Cu" "*.Mask")
			(remove_unused_layers no)
			(net "GND")
			(clearance 0.0508)
			(thermal_gap 0.0508)
		)
		(pad "M8" thru_hole circle
			(at 13.999972 14.59992 180)
			(size 0.906272 0.906272)
			(drill 0.499872)
			(layers "*.Cu" "*.Mask")
			(remove_unused_layers no)
			(net "GND")
			(clearance 0.0508)
			(thermal_gap 0.0508)
		)
		(pad "N1" thru_hole circle
			(at 0 15.599918 180)
			(size 0.906272 0.906272)
			(drill 0.499872)
			(layers "*.Cu" "*.Mask")
			(remove_unused_layers no)
			(net "GND")
			(clearance 0.0508)
			(thermal_gap 0.0508)
		)
		(pad "N2" thru_hole circle
			(at 1.999996 15.80007 180)
			(size 0.766318 0.766318)
			(drill 0.359918)
			(layers "*.Cu" "*.Mask")
			(remove_unused_layers no)
			(net "GPU_FPGA_BOOT_EN_BUF")
			(clearance 0.0508)
			(thermal_gap 0.0508)
		)
		(pad "N3" thru_hole circle
			(at 3.999992 15.599918 180)
			(size 0.906272 0.906272)
			(drill 0.499872)
			(layers "*.Cu" "*.Mask")
			(remove_unused_layers no)
			(net "GND")
			(clearance 0.0508)
			(thermal_gap 0.0508)
		)
		(pad "N4" thru_hole circle
			(at 5.999988 15.80007 180)
			(size 0.766318 0.766318)
			(drill 0.359918)
			(layers "*.Cu" "*.Mask")
			(remove_unused_layers no)
			(net "FM_SMB_1_ALERT_GPU_N")
			(clearance 0.0508)
			(thermal_gap 0.0508)
		)
		(pad "N5" thru_hole circle
			(at 7.999984 15.599918 180)
			(size 0.906272 0.906272)
			(drill 0.499872)
			(layers "*.Cu" "*.Mask")
			(remove_unused_layers no)
			(net "GND")
			(clearance 0.0508)
			(thermal_gap 0.0508)
		)
		(pad "N6" thru_hole circle
			(at 9.99998 15.80007 180)
			(size 0.766318 0.766318)
			(drill 0.359918)
			(layers "*.Cu" "*.Mask")
			(remove_unused_layers no)
			(net "FM_SMB_2_ALERT_GPU_N")
			(clearance 0.0508)
			(thermal_gap 0.0508)
		)
		(pad "N7" thru_hole circle
			(at 11.999976 15.599918 180)
			(size 0.906272 0.906272)
			(drill 0.499872)
			(layers "*.Cu" "*.Mask")
			(remove_unused_layers no)
			(net "GND")
			(clearance 0.0508)
			(thermal_gap 0.0508)
		)
		(pad "N8" thru_hole circle
			(at 13.999972 15.80007 180)
			(size 0.766318 0.766318)
			(drill 0.359918)
			(layers "*.Cu" "*.Mask")
			(remove_unused_layers no)
			(net "GPU_FPGA_EROT_RST_BUF_N")
			(clearance 0.0508)
			(thermal_gap 0.0508)
		)
		(zone
			(layer "B.Cu")
			(hatch none 0.5)
			(connect_pads
				(clearance 0)
			)
			(min_thickness 0.25)
			(keepout
				(tracks allowed)
				(vias not_allowed)
				(pads allowed)
				(copperpour not_allowed)
				(footprints allowed)
			)
			(placement
				(enabled no)
				(sheetname "")
			)
			(fill
				(thermal_gap 0.5)
				(thermal_bridge_width 0.5)
				(island_removal_mode 0)
			)
			(polygon
				(pts
					(xy 125.241812 -424.246548) (xy 140.265912 -424.246548) (xy 140.265912 -440.934348) (xy 125.241812 -440.934348)
				)
			)
		)
	)
	(footprint ""
		(layer "F.Cu")
		(at 423.627296 -361.818682)
		(property "Reference" "PC198"
			(at 0 0 0)
			(layer "F.SilkS")
			(hide yes)
			(effects
				(font
					(size 1.27 1.27)
				)
			)
		)
		(property "Value" ""
			(at 0 0 0)
			(layer "F.Fab")
			(effects
				(font
					(size 1.27 1.27)
				)
			)
		)
		(duplicate_pad_numbers_are_jumpers no)
		(fp_line
			(start -0.7874 -0.4064)
			(end 0.7874 -0.4064)
			(stroke
				(width 0.1524)
				(type default)
			)
			(layer "F.SilkS")
		)
		(fp_line
			(start -0.7874 0.4064)
			(end -0.7874 -0.4064)
			(stroke
				(width 0.1524)
				(type default)
			)
			(layer "F.SilkS")
		)
		(fp_line
			(start 0.7874 -0.4064)
			(end 0.7874 0.4064)
			(stroke
				(width 0.1524)
				(type default)
			)
			(layer "F.SilkS")
		)
		(fp_line
			(start 0.7874 0.4064)
			(end -0.7874 0.4064)
			(stroke
				(width 0.1524)
				(type default)
			)
			(layer "F.SilkS")
		)
		(fp_line
			(start -0.67945 -0.305054)
			(end -0.12065 -0.305054)
			(stroke
				(width 0.1)
				(type default)
			)
			(layer "F.Fab")
		)
		(fp_line
			(start -0.67945 0.3048)
			(end -0.67945 -0.305054)
			(stroke
				(width 0.1)
				(type default)
			)
			(layer "F.Fab")
		)
		(fp_line
			(start -0.12065 -0.305054)
			(end -0.12065 -0.2794)
			(stroke
				(width 0.1)
				(type default)
			)
			(layer "F.Fab")
		)
		(fp_line
			(start -0.12065 -0.2794)
			(end 0.12065 -0.2794)
			(stroke
				(width 0.1)
				(type default)
			)
			(layer "F.Fab")
		)
		(fp_line
			(start -0.12065 0.2794)
			(end -0.12065 0.3048)
			(stroke
				(width 0.1)
				(type default)
			)
			(layer "F.Fab")
		)
		(fp_line
			(start -0.12065 0.3048)
			(end -0.67945 0.3048)
			(stroke
				(width 0.1)
				(type default)
			)
			(layer "F.Fab")
		)
		(fp_line
			(start 0.120396 0.2794)
			(end -0.12065 0.2794)
			(stroke
				(width 0.1)
				(type default)
			)
			(layer "F.Fab")
		)
		(fp_line
			(start 0.120396 0.3048)
			(end 0.120396 0.2794)
			(stroke
				(width 0.1)
				(type default)
			)
			(layer "F.Fab")
		)
		(fp_line
			(start 0.12065 -0.3048)
			(end 0.67945 -0.3048)
			(stroke
				(width 0.1)
				(type default)
			)
			(layer "F.Fab")
		)
		(fp_line
			(start 0.12065 -0.2794)
			(end 0.12065 -0.3048)
			(stroke
				(width 0.1)
				(type default)
			)
			(layer "F.Fab")
		)
		(fp_line
			(start 0.67945 -0.3048)
			(end 0.67945 0.3048)
			(stroke
				(width 0.1)
				(type default)
			)
			(layer "F.Fab")
		)
		(fp_line
			(start 0.67945 0.3048)
			(end 0.120396 0.3048)
			(stroke
				(width 0.1)
				(type default)
			)
			(layer "F.Fab")
		)
		(pad "1" smd circle
			(at -0.40005 0)
			(size 0 0)
			(layers "F.Cu" "F.Mask" "F.Paste")
			(net "PVDD11_S3_P0_TEMP0")
		)
		(pad "2" smd circle
			(at 0.40005 0)
			(size 0 0)
			(layers "F.Cu" "F.Mask" "F.Paste")
			(net "GND")
		)
	)
	(footprint ""
		(layer "F.Cu")
		(at 351.783904 -330.617322)
		(property "Reference" "PL7"
			(at -1.591056 -16.141446 0)
			(unlocked yes)
			(layer "F.SilkS")
			(effects
				(font
					(size 0.7874 0.5842)
					(thickness 0.1524)
				)
				(justify left)
			)
		)
		(property "Value" ""
			(at 0 0 0)
			(layer "F.Fab")
			(effects
				(font
					(size 1.27 1.27)
				)
			)
		)
		(duplicate_pad_numbers_are_jumpers no)
		(fp_line
			(start -3.750056 -5.500116)
			(end -2.393442 -5.500116)
			(stroke
				(width 0.1524)
				(type default)
			)
			(layer "F.SilkS")
		)
		(fp_line
			(start -3.750056 5.500116)
			(end -3.750056 -5.500116)
			(stroke
				(width 0.1524)
				(type default)
			)
			(layer "F.SilkS")
		)
		(fp_line
			(start -2.393442 5.500116)
			(end -3.750056 5.500116)
			(stroke
				(width 0.1524)
				(type default)
			)
			(layer "F.SilkS")
		)
		(fp_line
			(start 2.393442 5.500116)
			(end 3.750056 5.500116)
			(stroke
				(width 0.1524)
				(type default)
			)
			(layer "F.SilkS")
		)
		(fp_line
			(start 3.750056 -5.500116)
			(end 2.393442 -5.500116)
			(stroke
				(width 0.1524)
				(type default)
			)
			(layer "F.SilkS")
		)
		(fp_line
			(start 3.750056 5.500116)
			(end 3.750056 -5.500116)
			(stroke
				(width 0.1524)
				(type default)
			)
			(layer "F.SilkS")
		)
		(fp_poly
			(pts
				(xy -3.924808 -3.63601) (xy -4.283964 -2.558288) (xy -5.00253 -3.276854)
			)
			(stroke
				(width 0)
				(type default)
			)
			(fill yes)
			(layer "F.SilkS")
		)
		(fp_line
			(start -3.750056 -5.500116)
			(end -3.750056 5.500116)
			(stroke
				(width 0.1)
				(type default)
			)
			(layer "F.Fab")
		)
		(fp_line
			(start -3.750056 5.500116)
			(end 3.750056 5.500116)
			(stroke
				(width 0.1)
				(type default)
			)
			(layer "F.Fab")
		)
		(fp_line
			(start 3.750056 -5.500116)
			(end -3.750056 -5.500116)
			(stroke
				(width 0.1)
				(type default)
			)
			(layer "F.Fab")
		)
		(fp_line
			(start 3.750056 5.500116)
			(end 3.750056 -5.500116)
			(stroke
				(width 0.1)
				(type default)
			)
			(layer "F.Fab")
		)
		(fp_poly
			(pts
				(xy -4.9276 -4.757928) (xy -4.9276 -3.741928) (xy -3.9116 -4.249928)
			)
			(stroke
				(width 0)
				(type default)
			)
			(fill yes)
			(layer "F.Fab")
		)
		(pad "1" smd rect
			(at 0 -4.249928 270)
			(size 2.413 4.5212)
			(layers "F.Cu" "F.Mask" "F.Paste")
			(net "SW_PVDDCR_CPU1_P0_SW6")
		)
		(pad "2" smd rect
			(at 0 -1.175004 270)
			(size 1.3716 4.5212)
			(layers "F.Cu" "F.Mask" "F.Paste")
			(net "IND_CPU1_P0_CPL0")
		)
		(pad "3" smd rect
			(at 0 1.175004 270)
			(size 1.3716 4.5212)
			(layers "F.Cu" "F.Mask" "F.Paste")
			(net "IND_CPU1_P0_CPL6")
		)
		(pad "4" smd rect
			(at 0 4.249928 270)
			(size 2.413 4.5212)
			(layers "F.Cu" "F.Mask" "F.Paste")
			(net "PVDDCR_CPU1_P0")
		)
	)
	(footprint ""
		(layer "F.Cu")
		(at 221.67088 -44.922948 180)
		(property "Reference" "R3532"
			(at 0 0 180)
			(layer "F.SilkS")
			(hide yes)
			(effects
				(font
					(size 1.27 1.27)
				)
			)
		)
		(property "Value" ""
			(at 0 0 180)
			(layer "F.Fab")
			(effects
				(font
					(size 1.27 1.27)
				)
			)
		)
		(duplicate_pad_numbers_are_jumpers no)
		(fp_line
			(start 0.7874 0.4064)
			(end -0.7874 0.4064)
			(stroke
				(width 0.1524)
				(type default)
			)
			(layer "F.SilkS")
		)
		(fp_line
			(start 0.7874 -0.4064)
			(end 0.7874 0.4064)
			(stroke
				(width 0.1524)
				(type default)
			)
			(layer "F.SilkS")
		)
		(fp_line
			(start -0.7874 0.4064)
			(end -0.7874 -0.4064)
			(stroke
				(width 0.1524)
				(type default)
			)
			(layer "F.SilkS")
		)
		(fp_line
			(start -0.7874 -0.4064)
			(end 0.7874 -0.4064)
			(stroke
				(width 0.1524)
				(type default)
			)
			(layer "F.SilkS")
		)
		(fp_line
			(start 0.67945 0.3048)
			(end 0.120396 0.3048)
			(stroke
				(width 0.1)
				(type default)
			)
			(layer "F.Fab")
		)
		(fp_line
			(start 0.67945 -0.3048)
			(end 0.67945 0.3048)
			(stroke
				(width 0.1)
				(type default)
			)
			(layer "F.Fab")
		)
		(fp_line
			(start 0.12065 -0.2794)
			(end 0.12065 -0.3048)
			(stroke
				(width 0.1)
				(type default)
			)
			(layer "F.Fab")
		)
		(fp_line
			(start 0.12065 -0.3048)
			(end 0.67945 -0.3048)
			(stroke
				(width 0.1)
				(type default)
			)
			(layer "F.Fab")
		)
		(fp_line
			(start 0.120396 0.3048)
			(end 0.120396 0.2794)
			(stroke
				(width 0.1)
				(type default)
			)
			(layer "F.Fab")
		)
		(fp_line
			(start 0.120396 0.2794)
			(end -0.12065 0.2794)
			(stroke
				(width 0.1)
				(type default)
			)
			(layer "F.Fab")
		)
		(fp_line
			(start -0.12065 0.3048)
			(end -0.67945 0.3048)
			(stroke
				(width 0.1)
				(type default)
			)
			(layer "F.Fab")
		)
		(fp_line
			(start -0.12065 0.2794)
			(end -0.12065 0.3048)
			(stroke
				(width 0.1)
				(type default)
			)
			(layer "F.Fab")
		)
		(fp_line
			(start -0.12065 -0.2794)
			(end 0.12065 -0.2794)
			(stroke
				(width 0.1)
				(type default)
			)
			(layer "F.Fab")
		)
		(fp_line
			(start -0.12065 -0.305054)
			(end -0.12065 -0.2794)
			(stroke
				(width 0.1)
				(type default)
			)
			(layer "F.Fab")
		)
		(fp_line
			(start -0.67945 0.3048)
			(end -0.67945 -0.305054)
			(stroke
				(width 0.1)
				(type default)
			)
			(layer "F.Fab")
		)
		(fp_line
			(start -0.67945 -0.305054)
			(end -0.12065 -0.305054)
			(stroke
				(width 0.1)
				(type default)
			)
			(layer "F.Fab")
		)
		(pad "1" smd circle
			(at -0.40005 0 180)
			(size 0 0)
			(layers "F.Cu" "F.Mask" "F.Paste")
			(net "P3V3_E1S_0")
		)
		(pad "2" smd circle
			(at 0.40005 0 180)
			(size 0 0)
			(layers "F.Cu" "F.Mask" "F.Paste")
			(net "SMB_E1S_3V3AUX_ISO_SDA_R")
		)
	)
	(footprint ""
		(layer "F.Cu")
		(at 315.771022 -31.429706 180)
		(property "Reference" "C2044"
			(at 0 0 180)
			(layer "F.SilkS")
			(hide yes)
			(effects
				(font
					(size 1.27 1.27)
				)
			)
		)
		(property "Value" ""
			(at 0 0 180)
			(layer "F.Fab")
			(effects
				(font
					(size 1.27 1.27)
				)
			)
		)
		(duplicate_pad_numbers_are_jumpers no)
		(fp_line
			(start 0.7874 0.4064)
			(end -0.7874 0.4064)
			(stroke
				(width 0.1524)
				(type default)
			)
			(layer "F.SilkS")
		)
		(fp_line
			(start 0.7874 -0.4064)
			(end 0.7874 0.4064)
			(stroke
				(width 0.1524)
				(type default)
			)
			(layer "F.SilkS")
		)
		(fp_line
			(start -0.7874 0.4064)
			(end -0.7874 -0.4064)
			(stroke
				(width 0.1524)
				(type default)
			)
			(layer "F.SilkS")
		)
		(fp_line
			(start -0.7874 -0.4064)
			(end 0.7874 -0.4064)
			(stroke
				(width 0.1524)
				(type default)
			)
			(layer "F.SilkS")
		)
		(fp_line
			(start 0.67945 0.3048)
			(end 0.120396 0.3048)
			(stroke
				(width 0.1)
				(type default)
			)
			(layer "F.Fab")
		)
		(fp_line
			(start 0.67945 -0.3048)
			(end 0.67945 0.3048)
			(stroke
				(width 0.1)
				(type default)
			)
			(layer "F.Fab")
		)
		(fp_line
			(start 0.12065 -0.2794)
			(end 0.12065 -0.3048)
			(stroke
				(width 0.1)
				(type default)
			)
			(layer "F.Fab")
		)
		(fp_line
			(start 0.12065 -0.3048)
			(end 0.67945 -0.3048)
			(stroke
				(width 0.1)
				(type default)
			)
			(layer "F.Fab")
		)
		(fp_line
			(start 0.120396 0.3048)
			(end 0.120396 0.2794)
			(stroke
				(width 0.1)
				(type default)
			)
			(layer "F.Fab")
		)
		(fp_line
			(start 0.120396 0.2794)
			(end -0.12065 0.2794)
			(stroke
				(width 0.1)
				(type default)
			)
			(layer "F.Fab")
		)
		(fp_line
			(start -0.12065 0.3048)
			(end -0.67945 0.3048)
			(stroke
				(width 0.1)
				(type default)
			)
			(layer "F.Fab")
		)
		(fp_line
			(start -0.12065 0.2794)
			(end -0.12065 0.3048)
			(stroke
				(width 0.1)
				(type default)
			)
			(layer "F.Fab")
		)
		(fp_line
			(start -0.12065 -0.2794)
			(end 0.12065 -0.2794)
			(stroke
				(width 0.1)
				(type default)
			)
			(layer "F.Fab")
		)
		(fp_line
			(start -0.12065 -0.305054)
			(end -0.12065 -0.2794)
			(stroke
				(width 0.1)
				(type default)
			)
			(layer "F.Fab")
		)
		(fp_line
			(start -0.67945 0.3048)
			(end -0.67945 -0.305054)
			(stroke
				(width 0.1)
				(type default)
			)
			(layer "F.Fab")
		)
		(fp_line
			(start -0.67945 -0.305054)
			(end -0.12065 -0.305054)
			(stroke
				(width 0.1)
				(type default)
			)
			(layer "F.Fab")
		)
		(pad "1" smd circle
			(at -0.40005 0 180)
			(size 0 0)
			(layers "F.Cu" "F.Mask" "F.Paste")
			(net "P5V_ADC_MAM")
		)
		(pad "2" smd circle
			(at 0.40005 0 180)
			(size 0 0)
			(layers "F.Cu" "F.Mask" "F.Paste")
			(net "GND")
		)
	)
	(footprint ""
		(layer "F.Cu")
		(at 323.637148 -43.573954)
		(property "Reference" "R3685"
			(at 0 0 0)
			(layer "F.SilkS")
			(hide yes)
			(effects
				(font
					(size 1.27 1.27)
				)
			)
		)
		(property "Value" ""
			(at 0 0 0)
			(layer "F.Fab")
			(effects
				(font
					(size 1.27 1.27)
				)
			)
		)
		(duplicate_pad_numbers_are_jumpers no)
		(fp_line
			(start -0.7874 -0.4064)
			(end 0.7874 -0.4064)
			(stroke
				(width 0.1524)
				(type default)
			)
			(layer "F.SilkS")
		)
		(fp_line
			(start -0.7874 0.4064)
			(end -0.7874 -0.4064)
			(stroke
				(width 0.1524)
				(type default)
			)
			(layer "F.SilkS")
		)
		(fp_line
			(start 0.7874 -0.4064)
			(end 0.7874 0.4064)
			(stroke
				(width 0.1524)
				(type default)
			)
			(layer "F.SilkS")
		)
		(fp_line
			(start 0.7874 0.4064)
			(end -0.7874 0.4064)
			(stroke
				(width 0.1524)
				(type default)
			)
			(layer "F.SilkS")
		)
		(fp_line
			(start -0.67945 -0.305054)
			(end -0.12065 -0.305054)
			(stroke
				(width 0.1)
				(type default)
			)
			(layer "F.Fab")
		)
		(fp_line
			(start -0.67945 0.3048)
			(end -0.67945 -0.305054)
			(stroke
				(width 0.1)
				(type default)
			)
			(layer "F.Fab")
		)
		(fp_line
			(start -0.12065 -0.305054)
			(end -0.12065 -0.2794)
			(stroke
				(width 0.1)
				(type default)
			)
			(layer "F.Fab")
		)
		(fp_line
			(start -0.12065 -0.2794)
			(end 0.12065 -0.2794)
			(stroke
				(width 0.1)
				(type default)
			)
			(layer "F.Fab")
		)
		(fp_line
			(start -0.12065 0.2794)
			(end -0.12065 0.3048)
			(stroke
				(width 0.1)
				(type default)
			)
			(layer "F.Fab")
		)
		(fp_line
			(start -0.12065 0.3048)
			(end -0.67945 0.3048)
			(stroke
				(width 0.1)
				(type default)
			)
			(layer "F.Fab")
		)
		(fp_line
			(start 0.120396 0.2794)
			(end -0.12065 0.2794)
			(stroke
				(width 0.1)
				(type default)
			)
			(layer "F.Fab")
		)
		(fp_line
			(start 0.120396 0.3048)
			(end 0.120396 0.2794)
			(stroke
				(width 0.1)
				(type default)
			)
			(layer "F.Fab")
		)
		(fp_line
			(start 0.12065 -0.3048)
			(end 0.67945 -0.3048)
			(stroke
				(width 0.1)
				(type default)
			)
			(layer "F.Fab")
		)
		(fp_line
			(start 0.12065 -0.2794)
			(end 0.12065 -0.3048)
			(stroke
				(width 0.1)
				(type default)
			)
			(layer "F.Fab")
		)
		(fp_line
			(start 0.67945 -0.3048)
			(end 0.67945 0.3048)
			(stroke
				(width 0.1)
				(type default)
			)
			(layer "F.Fab")
		)
		(fp_line
			(start 0.67945 0.3048)
			(end 0.120396 0.3048)
			(stroke
				(width 0.1)
				(type default)
			)
			(layer "F.Fab")
		)
		(pad "1" smd rect
			(at -0.40005 0 180)
			(size 0.4572 0.508)
			(layers "F.Cu" "F.Mask" "F.Paste")
			(net "P5V_ADC")
		)
		(pad "2" smd rect
			(at 0.40005 0 180)
			(size 0.4572 0.508)
			(layers "F.Cu" "F.Mask" "F.Paste")
			(net "P5V_ADC_MAM")
		)
	)
	(footprint ""
		(layer "F.Cu")
		(at 118.718584 -56.582056 180)
		(property "Reference" "R6101"
			(at 0 0 180)
			(layer "F.SilkS")
			(hide yes)
			(effects
				(font
					(size 1.27 1.27)
				)
			)
		)
		(property "Value" ""
			(at 0 0 180)
			(layer "F.Fab")
			(effects
				(font
					(size 1.27 1.27)
				)
			)
		)
		(duplicate_pad_numbers_are_jumpers no)
		(fp_line
			(start 0.7874 0.4064)
			(end -0.7874 0.4064)
			(stroke
				(width 0.1524)
				(type default)
			)
			(layer "F.SilkS")
		)
		(fp_line
			(start 0.7874 -0.4064)
			(end 0.7874 0.4064)
			(stroke
				(width 0.1524)
				(type default)
			)
			(layer "F.SilkS")
		)
		(fp_line
			(start -0.7874 0.4064)
			(end -0.7874 -0.4064)
			(stroke
				(width 0.1524)
				(type default)
			)
			(layer "F.SilkS")
		)
		(fp_line
			(start -0.7874 -0.4064)
			(end 0.7874 -0.4064)
			(stroke
				(width 0.1524)
				(type default)
			)
			(layer "F.SilkS")
		)
		(fp_line
			(start 0.67945 0.3048)
			(end 0.120396 0.3048)
			(stroke
				(width 0.1)
				(type default)
			)
			(layer "F.Fab")
		)
		(fp_line
			(start 0.67945 -0.3048)
			(end 0.67945 0.3048)
			(stroke
				(width 0.1)
				(type default)
			)
			(layer "F.Fab")
		)
		(fp_line
			(start 0.12065 -0.2794)
			(end 0.12065 -0.3048)
			(stroke
				(width 0.1)
				(type default)
			)
			(layer "F.Fab")
		)
		(fp_line
			(start 0.12065 -0.3048)
			(end 0.67945 -0.3048)
			(stroke
				(width 0.1)
				(type default)
			)
			(layer "F.Fab")
		)
		(fp_line
			(start 0.120396 0.3048)
			(end 0.120396 0.2794)
			(stroke
				(width 0.1)
				(type default)
			)
			(layer "F.Fab")
		)
		(fp_line
			(start 0.120396 0.2794)
			(end -0.12065 0.2794)
			(stroke
				(width 0.1)
				(type default)
			)
			(layer "F.Fab")
		)
		(fp_line
			(start -0.12065 0.3048)
			(end -0.67945 0.3048)
			(stroke
				(width 0.1)
				(type default)
			)
			(layer "F.Fab")
		)
		(fp_line
			(start -0.12065 0.2794)
			(end -0.12065 0.3048)
			(stroke
				(width 0.1)
				(type default)
			)
			(layer "F.Fab")
		)
		(fp_line
			(start -0.12065 -0.2794)
			(end 0.12065 -0.2794)
			(stroke
				(width 0.1)
				(type default)
			)
			(layer "F.Fab")
		)
		(fp_line
			(start -0.12065 -0.305054)
			(end -0.12065 -0.2794)
			(stroke
				(width 0.1)
				(type default)
			)
			(layer "F.Fab")
		)
		(fp_line
			(start -0.67945 0.3048)
			(end -0.67945 -0.305054)
			(stroke
				(width 0.1)
				(type default)
			)
			(layer "F.Fab")
		)
		(fp_line
			(start -0.67945 -0.305054)
			(end -0.12065 -0.305054)
			(stroke
				(width 0.1)
				(type default)
			)
			(layer "F.Fab")
		)
		(pad "1" smd circle
			(at -0.40005 0 180)
			(size 0 0)
			(layers "F.Cu" "F.Mask" "F.Paste")
			(net "SCM_JTAG_MUX_S0")
		)
		(pad "2" smd circle
			(at 0.40005 0 180)
			(size 0 0)
			(layers "F.Cu" "F.Mask" "F.Paste")
			(net "SCM_JTAG_MUX_S0_R1")
		)
	)
	(footprint ""
		(layer "F.Cu")
		(at 248.59615 -268.092936 180)
		(property "Reference" "PC6500"
			(at 0 0 180)
			(layer "F.SilkS")
			(hide yes)
			(effects
				(font
					(size 1.27 1.27)
				)
			)
		)
		(property "Value" ""
			(at 0 0 180)
			(layer "F.Fab")
			(effects
				(font
					(size 1.27 1.27)
				)
			)
		)
		(duplicate_pad_numbers_are_jumpers no)
		(fp_line
			(start 0.7874 0.4064)
			(end -0.7874 0.4064)
			(stroke
				(width 0.1524)
				(type default)
			)
			(layer "F.SilkS")
		)
		(fp_line
			(start 0.7874 -0.4064)
			(end 0.7874 0.4064)
			(stroke
				(width 0.1524)
				(type default)
			)
			(layer "F.SilkS")
		)
		(fp_line
			(start -0.7874 0.4064)
			(end -0.7874 -0.4064)
			(stroke
				(width 0.1524)
				(type default)
			)
			(layer "F.SilkS")
		)
		(fp_line
			(start -0.7874 -0.4064)
			(end 0.7874 -0.4064)
			(stroke
				(width 0.1524)
				(type default)
			)
			(layer "F.SilkS")
		)
		(fp_line
			(start 0.67945 0.3048)
			(end 0.120396 0.3048)
			(stroke
				(width 0.1)
				(type default)
			)
			(layer "F.Fab")
		)
		(fp_line
			(start 0.67945 -0.3048)
			(end 0.67945 0.3048)
			(stroke
				(width 0.1)
				(type default)
			)
			(layer "F.Fab")
		)
		(fp_line
			(start 0.12065 -0.2794)
			(end 0.12065 -0.3048)
			(stroke
				(width 0.1)
				(type default)
			)
			(layer "F.Fab")
		)
		(fp_line
			(start 0.12065 -0.3048)
			(end 0.67945 -0.3048)
			(stroke
				(width 0.1)
				(type default)
			)
			(layer "F.Fab")
		)
		(fp_line
			(start 0.120396 0.3048)
			(end 0.120396 0.2794)
			(stroke
				(width 0.1)
				(type default)
			)
			(layer "F.Fab")
		)
		(fp_line
			(start 0.120396 0.2794)
			(end -0.12065 0.2794)
			(stroke
				(width 0.1)
				(type default)
			)
			(layer "F.Fab")
		)
		(fp_line
			(start -0.12065 0.3048)
			(end -0.67945 0.3048)
			(stroke
				(width 0.1)
				(type default)
			)
			(layer "F.Fab")
		)
		(fp_line
			(start -0.12065 0.2794)
			(end -0.12065 0.3048)
			(stroke
				(width 0.1)
				(type default)
			)
			(layer "F.Fab")
		)
		(fp_line
			(start -0.12065 -0.2794)
			(end 0.12065 -0.2794)
			(stroke
				(width 0.1)
				(type default)
			)
			(layer "F.Fab")
		)
		(fp_line
			(start -0.12065 -0.305054)
			(end -0.12065 -0.2794)
			(stroke
				(width 0.1)
				(type default)
			)
			(layer "F.Fab")
		)
		(fp_line
			(start -0.67945 0.3048)
			(end -0.67945 -0.305054)
			(stroke
				(width 0.1)
				(type default)
			)
			(layer "F.Fab")
		)
		(fp_line
			(start -0.67945 -0.305054)
			(end -0.12065 -0.305054)
			(stroke
				(width 0.1)
				(type default)
			)
			(layer "F.Fab")
		)
		(pad "1" smd circle
			(at -0.40005 0 180)
			(size 0 0)
			(layers "F.Cu" "F.Mask" "F.Paste")
			(net "P12V_AUX")
		)
		(pad "2" smd circle
			(at 0.40005 0 180)
			(size 0 0)
			(layers "F.Cu" "F.Mask" "F.Paste")
			(net "GND")
		)
	)
	(footprint ""
		(layer "F.Cu")
		(at 224.20961 -46.524926)
		(property "Reference" "R1673"
			(at 0 0 0)
			(layer "F.SilkS")
			(hide yes)
			(effects
				(font
					(size 1.27 1.27)
				)
			)
		)
		(property "Value" ""
			(at 0 0 0)
			(layer "F.Fab")
			(effects
				(font
					(size 1.27 1.27)
				)
			)
		)
		(duplicate_pad_numbers_are_jumpers no)
		(fp_line
			(start -0.7874 -0.4064)
			(end 0.7874 -0.4064)
			(stroke
				(width 0.1524)
				(type default)
			)
			(layer "F.SilkS")
		)
		(fp_line
			(start -0.7874 0.4064)
			(end -0.7874 -0.4064)
			(stroke
				(width 0.1524)
				(type default)
			)
			(layer "F.SilkS")
		)
		(fp_line
			(start 0.7874 -0.4064)
			(end 0.7874 0.4064)
			(stroke
				(width 0.1524)
				(type default)
			)
			(layer "F.SilkS")
		)
		(fp_line
			(start 0.7874 0.4064)
			(end -0.7874 0.4064)
			(stroke
				(width 0.1524)
				(type default)
			)
			(layer "F.SilkS")
		)
		(fp_line
			(start -0.67945 -0.305054)
			(end -0.12065 -0.305054)
			(stroke
				(width 0.1)
				(type default)
			)
			(layer "F.Fab")
		)
		(fp_line
			(start -0.67945 0.3048)
			(end -0.67945 -0.305054)
			(stroke
				(width 0.1)
				(type default)
			)
			(layer "F.Fab")
		)
		(fp_line
			(start -0.12065 -0.305054)
			(end -0.12065 -0.2794)
			(stroke
				(width 0.1)
				(type default)
			)
			(layer "F.Fab")
		)
		(fp_line
			(start -0.12065 -0.2794)
			(end 0.12065 -0.2794)
			(stroke
				(width 0.1)
				(type default)
			)
			(layer "F.Fab")
		)
		(fp_line
			(start -0.12065 0.2794)
			(end -0.12065 0.3048)
			(stroke
				(width 0.1)
				(type default)
			)
			(layer "F.Fab")
		)
		(fp_line
			(start -0.12065 0.3048)
			(end -0.67945 0.3048)
			(stroke
				(width 0.1)
				(type default)
			)
			(layer "F.Fab")
		)
		(fp_line
			(start 0.120396 0.2794)
			(end -0.12065 0.2794)
			(stroke
				(width 0.1)
				(type default)
			)
			(layer "F.Fab")
		)
		(fp_line
			(start 0.120396 0.3048)
			(end 0.120396 0.2794)
			(stroke
				(width 0.1)
				(type default)
			)
			(layer "F.Fab")
		)
		(fp_line
			(start 0.12065 -0.3048)
			(end 0.67945 -0.3048)
			(stroke
				(width 0.1)
				(type default)
			)
			(layer "F.Fab")
		)
		(fp_line
			(start 0.12065 -0.2794)
			(end 0.12065 -0.3048)
			(stroke
				(width 0.1)
				(type default)
			)
			(layer "F.Fab")
		)
		(fp_line
			(start 0.67945 -0.3048)
			(end 0.67945 0.3048)
			(stroke
				(width 0.1)
				(type default)
			)
			(layer "F.Fab")
		)
		(fp_line
			(start 0.67945 0.3048)
			(end 0.120396 0.3048)
			(stroke
				(width 0.1)
				(type default)
			)
			(layer "F.Fab")
		)
		(pad "1" smd circle
			(at -0.40005 0)
			(size 0 0)
			(layers "F.Cu" "F.Mask" "F.Paste")
			(net "P3V3_E1S_0")
		)
		(pad "2" smd circle
			(at 0.40005 0)
			(size 0 0)
			(layers "F.Cu" "F.Mask" "F.Paste")
			(net "RST_SMB_E1S_0_N")
		)
	)
	(footprint ""
		(layer "F.Cu")
		(at 260.171184 -393.91336 -90)
		(property "Reference" "PR2534"
			(at -4.64312 3.085084 90)
			(unlocked yes)
			(layer "F.SilkS")
			(effects
				(font
					(size 0.7874 0.5842)
					(thickness 0.1524)
				)
				(justify left)
			)
		)
		(property "Value" ""
			(at 0 0 270)
			(layer "F.Fab")
			(effects
				(font
					(size 1.27 1.27)
				)
			)
		)
		(duplicate_pad_numbers_are_jumpers no)
		(fp_line
			(start -3.9878 3.5814)
			(end -3.9878 -3.5814)
			(stroke
				(width 0.1524)
				(type default)
			)
			(layer "F.SilkS")
		)
		(fp_line
			(start 3.9878 3.5814)
			(end -3.9878 3.5814)
			(stroke
				(width 0.1524)
				(type default)
			)
			(layer "F.SilkS")
		)
		(fp_line
			(start -3.9878 -3.5814)
			(end 3.9878 -3.5814)
			(stroke
				(width 0.1524)
				(type default)
			)
			(layer "F.SilkS")
		)
		(fp_line
			(start 3.9878 -3.5814)
			(end 3.9878 3.5814)
			(stroke
				(width 0.1524)
				(type default)
			)
			(layer "F.SilkS")
		)
		(fp_line
			(start -3.5306 3.353054)
			(end -3.5306 -3.353054)
			(stroke
				(width 0.1)
				(type default)
			)
			(layer "F.Fab")
		)
		(fp_line
			(start 3.5306 3.353054)
			(end -3.5306 3.353054)
			(stroke
				(width 0.1)
				(type default)
			)
			(layer "F.Fab")
		)
		(fp_line
			(start -3.5306 -3.353054)
			(end 3.5306 -3.353054)
			(stroke
				(width 0.1)
				(type default)
			)
			(layer "F.Fab")
		)
		(fp_line
			(start 3.5306 -3.353054)
			(end 3.5306 3.353054)
			(stroke
				(width 0.1)
				(type default)
			)
			(layer "F.Fab")
		)
		(pad "1A" smd rect
			(at -2.249932 0 90)
			(size 3.2004 6.858)
			(layers "F.Cu" "F.Mask" "F.Paste")
			(net "P12V_PSU")
		)
		(pad "1B" smd rect
			(at -0.776732 0 270)
			(size 0.254 0.508)
			(layers "F.Cu" "F.Mask" "F.Paste")
			(net "P12V_HSC_SENSE2_R4_P")
		)
		(pad "2A" smd rect
			(at 2.249932 0 90)
			(size 3.2004 6.858)
			(layers "F.Cu" "F.Mask" "F.Paste")
			(net "P12V_MAIN_R")
		)
		(pad "2B" smd rect
			(at 0.776732 0 270)
			(size 0.254 0.508)
			(layers "F.Cu" "F.Mask" "F.Paste")
			(net "P12V_HSC_SENSE2_R4_N")
		)
	)
	(footprint ""
		(layer "F.Cu")
		(at 77.460094 -340.204552)
		(property "Reference" "PR254"
			(at 0 0 0)
			(layer "F.SilkS")
			(hide yes)
			(effects
				(font
					(size 1.27 1.27)
				)
			)
		)
		(property "Value" ""
			(at 0 0 0)
			(layer "F.Fab")
			(effects
				(font
					(size 1.27 1.27)
				)
			)
		)
		(duplicate_pad_numbers_are_jumpers no)
		(fp_line
			(start -0.7874 -0.4064)
			(end 0.7874 -0.4064)
			(stroke
				(width 0.1524)
				(type default)
			)
			(layer "F.SilkS")
		)
		(fp_line
			(start -0.7874 0.4064)
			(end -0.7874 -0.4064)
			(stroke
				(width 0.1524)
				(type default)
			)
			(layer "F.SilkS")
		)
		(fp_line
			(start 0.7874 -0.4064)
			(end 0.7874 0.4064)
			(stroke
				(width 0.1524)
				(type default)
			)
			(layer "F.SilkS")
		)
		(fp_line
			(start 0.7874 0.4064)
			(end -0.7874 0.4064)
			(stroke
				(width 0.1524)
				(type default)
			)
			(layer "F.SilkS")
		)
		(fp_line
			(start -0.67945 -0.305054)
			(end -0.12065 -0.305054)
			(stroke
				(width 0.1)
				(type default)
			)
			(layer "F.Fab")
		)
		(fp_line
			(start -0.67945 0.3048)
			(end -0.67945 -0.305054)
			(stroke
				(width 0.1)
				(type default)
			)
			(layer "F.Fab")
		)
		(fp_line
			(start -0.12065 -0.305054)
			(end -0.12065 -0.2794)
			(stroke
				(width 0.1)
				(type default)
			)
			(layer "F.Fab")
		)
		(fp_line
			(start -0.12065 -0.2794)
			(end 0.12065 -0.2794)
			(stroke
				(width 0.1)
				(type default)
			)
			(layer "F.Fab")
		)
		(fp_line
			(start -0.12065 0.2794)
			(end -0.12065 0.3048)
			(stroke
				(width 0.1)
				(type default)
			)
			(layer "F.Fab")
		)
		(fp_line
			(start -0.12065 0.3048)
			(end -0.67945 0.3048)
			(stroke
				(width 0.1)
				(type default)
			)
			(layer "F.Fab")
		)
		(fp_line
			(start 0.120396 0.2794)
			(end -0.12065 0.2794)
			(stroke
				(width 0.1)
				(type default)
			)
			(layer "F.Fab")
		)
		(fp_line
			(start 0.120396 0.3048)
			(end 0.120396 0.2794)
			(stroke
				(width 0.1)
				(type default)
			)
			(layer "F.Fab")
		)
		(fp_line
			(start 0.12065 -0.3048)
			(end 0.67945 -0.3048)
			(stroke
				(width 0.1)
				(type default)
			)
			(layer "F.Fab")
		)
		(fp_line
			(start 0.12065 -0.2794)
			(end 0.12065 -0.3048)
			(stroke
				(width 0.1)
				(type default)
			)
			(layer "F.Fab")
		)
		(fp_line
			(start 0.67945 -0.3048)
			(end 0.67945 0.3048)
			(stroke
				(width 0.1)
				(type default)
			)
			(layer "F.Fab")
		)
		(fp_line
			(start 0.67945 0.3048)
			(end 0.120396 0.3048)
			(stroke
				(width 0.1)
				(type default)
			)
			(layer "F.Fab")
		)
		(pad "1" smd circle
			(at -0.40005 0)
			(size 0 0)
			(layers "F.Cu" "F.Mask" "F.Paste")
			(net "PVDDCR_CPU1_P1_LSET2")
		)
		(pad "2" smd circle
			(at 0.40005 0)
			(size 0 0)
			(layers "F.Cu" "F.Mask" "F.Paste")
			(net "GND")
		)
	)
	(footprint ""
		(layer "F.Cu")
		(at 176.657 -100.294948 90)
		(property "Reference" "R237"
			(at 0 0 90)
			(layer "F.SilkS")
			(hide yes)
			(effects
				(font
					(size 1.27 1.27)
				)
			)
		)
		(property "Value" ""
			(at 0 0 90)
			(layer "F.Fab")
			(effects
				(font
					(size 1.27 1.27)
				)
			)
		)
		(duplicate_pad_numbers_are_jumpers no)
		(fp_line
			(start 0.7874 -0.4064)
			(end 0.7874 0.4064)
			(stroke
				(width 0.1524)
				(type default)
			)
			(layer "F.SilkS")
		)
		(fp_line
			(start -0.7874 -0.4064)
			(end 0.7874 -0.4064)
			(stroke
				(width 0.1524)
				(type default)
			)
			(layer "F.SilkS")
		)
		(fp_line
			(start 0.7874 0.4064)
			(end -0.7874 0.4064)
			(stroke
				(width 0.1524)
				(type default)
			)
			(layer "F.SilkS")
		)
		(fp_line
			(start -0.7874 0.4064)
			(end -0.7874 -0.4064)
			(stroke
				(width 0.1524)
				(type default)
			)
			(layer "F.SilkS")
		)
		(fp_line
			(start -0.12065 -0.305054)
			(end -0.12065 -0.2794)
			(stroke
				(width 0.1)
				(type default)
			)
			(layer "F.Fab")
		)
		(fp_line
			(start -0.67945 -0.305054)
			(end -0.12065 -0.305054)
			(stroke
				(width 0.1)
				(type default)
			)
			(layer "F.Fab")
		)
		(fp_line
			(start 0.67945 -0.3048)
			(end 0.67945 0.3048)
			(stroke
				(width 0.1)
				(type default)
			)
			(layer "F.Fab")
		)
		(fp_line
			(start 0.12065 -0.3048)
			(end 0.67945 -0.3048)
			(stroke
				(width 0.1)
				(type default)
			)
			(layer "F.Fab")
		)
		(fp_line
			(start 0.12065 -0.2794)
			(end 0.12065 -0.3048)
			(stroke
				(width 0.1)
				(type default)
			)
			(layer "F.Fab")
		)
		(fp_line
			(start -0.12065 -0.2794)
			(end 0.12065 -0.2794)
			(stroke
				(width 0.1)
				(type default)
			)
			(layer "F.Fab")
		)
		(fp_line
			(start 0.120396 0.2794)
			(end -0.12065 0.2794)
			(stroke
				(width 0.1)
				(type default)
			)
			(layer "F.Fab")
		)
		(fp_line
			(start -0.12065 0.2794)
			(end -0.12065 0.3048)
			(stroke
				(width 0.1)
				(type default)
			)
			(layer "F.Fab")
		)
		(fp_line
			(start 0.67945 0.3048)
			(end 0.120396 0.3048)
			(stroke
				(width 0.1)
				(type default)
			)
			(layer "F.Fab")
		)
		(fp_line
			(start 0.120396 0.3048)
			(end 0.120396 0.2794)
			(stroke
				(width 0.1)
				(type default)
			)
			(layer "F.Fab")
		)
		(fp_line
			(start -0.12065 0.3048)
			(end -0.67945 0.3048)
			(stroke
				(width 0.1)
				(type default)
			)
			(layer "F.Fab")
		)
		(fp_line
			(start -0.67945 0.3048)
			(end -0.67945 -0.305054)
			(stroke
				(width 0.1)
				(type default)
			)
			(layer "F.Fab")
		)
		(pad "1" smd circle
			(at -0.40005 0 90)
			(size 0 0)
			(layers "F.Cu" "F.Mask" "F.Paste")
			(net "CPU0_XTRIG_L5")
		)
		(pad "2" smd circle
			(at 0.40005 0 90)
			(size 0 0)
			(layers "F.Cu" "F.Mask" "F.Paste")
			(net "FM_CPU0_XTRIG_L5")
		)
	)
	(footprint ""
		(layer "F.Cu")
		(at 150.500842 -53.083714)
		(property "Reference" "R4090"
			(at 0 0 0)
			(layer "F.SilkS")
			(hide yes)
			(effects
				(font
					(size 1.27 1.27)
				)
			)
		)
		(property "Value" ""
			(at 0 0 0)
			(layer "F.Fab")
			(effects
				(font
					(size 1.27 1.27)
				)
			)
		)
		(duplicate_pad_numbers_are_jumpers no)
		(fp_line
			(start -0.7874 -0.4064)
			(end 0.7874 -0.4064)
			(stroke
				(width 0.1524)
				(type default)
			)
			(layer "F.SilkS")
		)
		(fp_line
			(start -0.7874 0.4064)
			(end -0.7874 -0.4064)
			(stroke
				(width 0.1524)
				(type default)
			)
			(layer "F.SilkS")
		)
		(fp_line
			(start 0.7874 -0.4064)
			(end 0.7874 0.4064)
			(stroke
				(width 0.1524)
				(type default)
			)
			(layer "F.SilkS")
		)
		(fp_line
			(start 0.7874 0.4064)
			(end -0.7874 0.4064)
			(stroke
				(width 0.1524)
				(type default)
			)
			(layer "F.SilkS")
		)
		(fp_line
			(start -0.67945 -0.305054)
			(end -0.12065 -0.305054)
			(stroke
				(width 0.1)
				(type default)
			)
			(layer "F.Fab")
		)
		(fp_line
			(start -0.67945 0.3048)
			(end -0.67945 -0.305054)
			(stroke
				(width 0.1)
				(type default)
			)
			(layer "F.Fab")
		)
		(fp_line
			(start -0.12065 -0.305054)
			(end -0.12065 -0.2794)
			(stroke
				(width 0.1)
				(type default)
			)
			(layer "F.Fab")
		)
		(fp_line
			(start -0.12065 -0.2794)
			(end 0.12065 -0.2794)
			(stroke
				(width 0.1)
				(type default)
			)
			(layer "F.Fab")
		)
		(fp_line
			(start -0.12065 0.2794)
			(end -0.12065 0.3048)
			(stroke
				(width 0.1)
				(type default)
			)
			(layer "F.Fab")
		)
		(fp_line
			(start -0.12065 0.3048)
			(end -0.67945 0.3048)
			(stroke
				(width 0.1)
				(type default)
			)
			(layer "F.Fab")
		)
		(fp_line
			(start 0.120396 0.2794)
			(end -0.12065 0.2794)
			(stroke
				(width 0.1)
				(type default)
			)
			(layer "F.Fab")
		)
		(fp_line
			(start 0.120396 0.3048)
			(end 0.120396 0.2794)
			(stroke
				(width 0.1)
				(type default)
			)
			(layer "F.Fab")
		)
		(fp_line
			(start 0.12065 -0.3048)
			(end 0.67945 -0.3048)
			(stroke
				(width 0.1)
				(type default)
			)
			(layer "F.Fab")
		)
		(fp_line
			(start 0.12065 -0.2794)
			(end 0.12065 -0.3048)
			(stroke
				(width 0.1)
				(type default)
			)
			(layer "F.Fab")
		)
		(fp_line
			(start 0.67945 -0.3048)
			(end 0.67945 0.3048)
			(stroke
				(width 0.1)
				(type default)
			)
			(layer "F.Fab")
		)
		(fp_line
			(start 0.67945 0.3048)
			(end 0.120396 0.3048)
			(stroke
				(width 0.1)
				(type default)
			)
			(layer "F.Fab")
		)
		(pad "1" smd circle
			(at -0.40005 0)
			(size 0 0)
			(layers "F.Cu" "F.Mask" "F.Paste")
			(net "P3V3_AUX")
		)
		(pad "2" smd circle
			(at 0.40005 0)
			(size 0 0)
			(layers "F.Cu" "F.Mask" "F.Paste")
			(net "M2_0_P3V3_ADC_ALERT_R")
		)
	)
	(footprint ""
		(layer "F.Cu")
		(at 128.906778 -47.121064)
		(property "Reference" "R6204"
			(at 0 0 0)
			(layer "F.SilkS")
			(hide yes)
			(effects
				(font
					(size 1.27 1.27)
				)
			)
		)
		(property "Value" ""
			(at 0 0 0)
			(layer "F.Fab")
			(effects
				(font
					(size 1.27 1.27)
				)
			)
		)
		(duplicate_pad_numbers_are_jumpers no)
		(fp_line
			(start -0.7874 -0.4064)
			(end 0.7874 -0.4064)
			(stroke
				(width 0.1524)
				(type default)
			)
			(layer "F.SilkS")
		)
		(fp_line
			(start -0.7874 0.4064)
			(end -0.7874 -0.4064)
			(stroke
				(width 0.1524)
				(type default)
			)
			(layer "F.SilkS")
		)
		(fp_line
			(start 0.7874 -0.4064)
			(end 0.7874 0.4064)
			(stroke
				(width 0.1524)
				(type default)
			)
			(layer "F.SilkS")
		)
		(fp_line
			(start 0.7874 0.4064)
			(end -0.7874 0.4064)
			(stroke
				(width 0.1524)
				(type default)
			)
			(layer "F.SilkS")
		)
		(fp_line
			(start -0.67945 -0.305054)
			(end -0.12065 -0.305054)
			(stroke
				(width 0.1)
				(type default)
			)
			(layer "F.Fab")
		)
		(fp_line
			(start -0.67945 0.3048)
			(end -0.67945 -0.305054)
			(stroke
				(width 0.1)
				(type default)
			)
			(layer "F.Fab")
		)
		(fp_line
			(start -0.12065 -0.305054)
			(end -0.12065 -0.2794)
			(stroke
				(width 0.1)
				(type default)
			)
			(layer "F.Fab")
		)
		(fp_line
			(start -0.12065 -0.2794)
			(end 0.12065 -0.2794)
			(stroke
				(width 0.1)
				(type default)
			)
			(layer "F.Fab")
		)
		(fp_line
			(start -0.12065 0.2794)
			(end -0.12065 0.3048)
			(stroke
				(width 0.1)
				(type default)
			)
			(layer "F.Fab")
		)
		(fp_line
			(start -0.12065 0.3048)
			(end -0.67945 0.3048)
			(stroke
				(width 0.1)
				(type default)
			)
			(layer "F.Fab")
		)
		(fp_line
			(start 0.120396 0.2794)
			(end -0.12065 0.2794)
			(stroke
				(width 0.1)
				(type default)
			)
			(layer "F.Fab")
		)
		(fp_line
			(start 0.120396 0.3048)
			(end 0.120396 0.2794)
			(stroke
				(width 0.1)
				(type default)
			)
			(layer "F.Fab")
		)
		(fp_line
			(start 0.12065 -0.3048)
			(end 0.67945 -0.3048)
			(stroke
				(width 0.1)
				(type default)
			)
			(layer "F.Fab")
		)
		(fp_line
			(start 0.12065 -0.2794)
			(end 0.12065 -0.3048)
			(stroke
				(width 0.1)
				(type default)
			)
			(layer "F.Fab")
		)
		(fp_line
			(start 0.67945 -0.3048)
			(end 0.67945 0.3048)
			(stroke
				(width 0.1)
				(type default)
			)
			(layer "F.Fab")
		)
		(fp_line
			(start 0.67945 0.3048)
			(end 0.120396 0.3048)
			(stroke
				(width 0.1)
				(type default)
			)
			(layer "F.Fab")
		)
		(pad "1" smd circle
			(at -0.40005 0)
			(size 0 0)
			(layers "F.Cu" "F.Mask" "F.Paste")
			(net "P3V3_AUX")
		)
		(pad "2" smd circle
			(at 0.40005 0)
			(size 0 0)
			(layers "F.Cu" "F.Mask" "F.Paste")
			(net "PU_CPU0_USB_HUB_PWR_EN")
		)
	)
	(footprint ""
		(layer "F.Cu")
		(at 203.454 -337.82)
		(property "Reference" "PR8000"
			(at 0 0 0)
			(layer "F.SilkS")
			(hide yes)
			(effects
				(font
					(size 1.27 1.27)
				)
			)
		)
		(property "Value" ""
			(at 0 0 0)
			(layer "F.Fab")
			(effects
				(font
					(size 1.27 1.27)
				)
			)
		)
		(duplicate_pad_numbers_are_jumpers no)
		(fp_line
			(start -0.7874 -0.4064)
			(end 0.7874 -0.4064)
			(stroke
				(width 0.1524)
				(type default)
			)
			(layer "F.SilkS")
		)
		(fp_line
			(start -0.7874 0.4064)
			(end -0.7874 -0.4064)
			(stroke
				(width 0.1524)
				(type default)
			)
			(layer "F.SilkS")
		)
		(fp_line
			(start 0.7874 -0.4064)
			(end 0.7874 0.4064)
			(stroke
				(width 0.1524)
				(type default)
			)
			(layer "F.SilkS")
		)
		(fp_line
			(start 0.7874 0.4064)
			(end -0.7874 0.4064)
			(stroke
				(width 0.1524)
				(type default)
			)
			(layer "F.SilkS")
		)
		(fp_line
			(start -0.67945 -0.305054)
			(end -0.12065 -0.305054)
			(stroke
				(width 0.1)
				(type default)
			)
			(layer "F.Fab")
		)
		(fp_line
			(start -0.67945 0.3048)
			(end -0.67945 -0.305054)
			(stroke
				(width 0.1)
				(type default)
			)
			(layer "F.Fab")
		)
		(fp_line
			(start -0.12065 -0.305054)
			(end -0.12065 -0.2794)
			(stroke
				(width 0.1)
				(type default)
			)
			(layer "F.Fab")
		)
		(fp_line
			(start -0.12065 -0.2794)
			(end 0.12065 -0.2794)
			(stroke
				(width 0.1)
				(type default)
			)
			(layer "F.Fab")
		)
		(fp_line
			(start -0.12065 0.2794)
			(end -0.12065 0.3048)
			(stroke
				(width 0.1)
				(type default)
			)
			(layer "F.Fab")
		)
		(fp_line
			(start -0.12065 0.3048)
			(end -0.67945 0.3048)
			(stroke
				(width 0.1)
				(type default)
			)
			(layer "F.Fab")
		)
		(fp_line
			(start 0.120396 0.2794)
			(end -0.12065 0.2794)
			(stroke
				(width 0.1)
				(type default)
			)
			(layer "F.Fab")
		)
		(fp_line
			(start 0.120396 0.3048)
			(end 0.120396 0.2794)
			(stroke
				(width 0.1)
				(type default)
			)
			(layer "F.Fab")
		)
		(fp_line
			(start 0.12065 -0.3048)
			(end 0.67945 -0.3048)
			(stroke
				(width 0.1)
				(type default)
			)
			(layer "F.Fab")
		)
		(fp_line
			(start 0.12065 -0.2794)
			(end 0.12065 -0.3048)
			(stroke
				(width 0.1)
				(type default)
			)
			(layer "F.Fab")
		)
		(fp_line
			(start 0.67945 -0.3048)
			(end 0.67945 0.3048)
			(stroke
				(width 0.1)
				(type default)
			)
			(layer "F.Fab")
		)
		(fp_line
			(start 0.67945 0.3048)
			(end 0.120396 0.3048)
			(stroke
				(width 0.1)
				(type default)
			)
			(layer "F.Fab")
		)
		(pad "1" smd circle
			(at -0.40005 0)
			(size 0 0)
			(layers "F.Cu" "F.Mask" "F.Paste")
			(net "SW_PVDD_33_S5_BST")
		)
		(pad "2" smd circle
			(at 0.40005 0)
			(size 0 0)
			(layers "F.Cu" "F.Mask" "F.Paste")
			(net "SW_PVDD_33_S5_BST_R")
		)
	)
	(footprint ""
		(layer "F.Cu")
		(at 347.983048 -342.599772 90)
		(property "Reference" "PC112"
			(at 0 0 90)
			(layer "F.SilkS")
			(hide yes)
			(effects
				(font
					(size 1.27 1.27)
				)
			)
		)
		(property "Value" ""
			(at 0 0 90)
			(layer "F.Fab")
			(effects
				(font
					(size 1.27 1.27)
				)
			)
		)
		(duplicate_pad_numbers_are_jumpers no)
		(fp_line
			(start 0.7874 -0.4064)
			(end 0.7874 0.4064)
			(stroke
				(width 0.1524)
				(type default)
			)
			(layer "F.SilkS")
		)
		(fp_line
			(start -0.7874 -0.4064)
			(end 0.7874 -0.4064)
			(stroke
				(width 0.1524)
				(type default)
			)
			(layer "F.SilkS")
		)
		(fp_line
			(start 0.7874 0.4064)
			(end 0.376428 0.4064)
			(stroke
				(width 0.1524)
				(type default)
			)
			(layer "F.SilkS")
		)
		(fp_line
			(start -0.182372 0.4064)
			(end -0.7874 0.4064)
			(stroke
				(width 0.1524)
				(type default)
			)
			(layer "F.SilkS")
		)
		(fp_line
			(start -0.7874 0.4064)
			(end -0.7874 -0.4064)
			(stroke
				(width 0.1524)
				(type default)
			)
			(layer "F.SilkS")
		)
		(fp_line
			(start -0.12065 -0.305054)
			(end -0.12065 -0.2794)
			(stroke
				(width 0.1)
				(type default)
			)
			(layer "F.Fab")
		)
		(fp_line
			(start -0.67945 -0.305054)
			(end -0.12065 -0.305054)
			(stroke
				(width 0.1)
				(type default)
			)
			(layer "F.Fab")
		)
		(fp_line
			(start 0.67945 -0.3048)
			(end 0.67945 0.3048)
			(stroke
				(width 0.1)
				(type default)
			)
			(layer "F.Fab")
		)
		(fp_line
			(start 0.12065 -0.3048)
			(end 0.67945 -0.3048)
			(stroke
				(width 0.1)
				(type default)
			)
			(layer "F.Fab")
		)
		(fp_line
			(start 0.12065 -0.2794)
			(end 0.12065 -0.3048)
			(stroke
				(width 0.1)
				(type default)
			)
			(layer "F.Fab")
		)
		(fp_line
			(start -0.12065 -0.2794)
			(end 0.12065 -0.2794)
			(stroke
				(width 0.1)
				(type default)
			)
			(layer "F.Fab")
		)
		(fp_line
			(start 0.120396 0.2794)
			(end -0.12065 0.2794)
			(stroke
				(width 0.1)
				(type default)
			)
			(layer "F.Fab")
		)
		(fp_line
			(start -0.12065 0.2794)
			(end -0.12065 0.3048)
			(stroke
				(width 0.1)
				(type default)
			)
			(layer "F.Fab")
		)
		(fp_line
			(start 0.67945 0.3048)
			(end 0.120396 0.3048)
			(stroke
				(width 0.1)
				(type default)
			)
			(layer "F.Fab")
		)
		(fp_line
			(start 0.120396 0.3048)
			(end 0.120396 0.2794)
			(stroke
				(width 0.1)
				(type default)
			)
			(layer "F.Fab")
		)
		(fp_line
			(start -0.12065 0.3048)
			(end -0.67945 0.3048)
			(stroke
				(width 0.1)
				(type default)
			)
			(layer "F.Fab")
		)
		(fp_line
			(start -0.67945 0.3048)
			(end -0.67945 -0.305054)
			(stroke
				(width 0.1)
				(type default)
			)
			(layer "F.Fab")
		)
		(pad "1" smd circle
			(at -0.40005 0 90)
			(size 0 0)
			(layers "F.Cu" "F.Mask" "F.Paste")
			(net "PVDDCR_CPU1_P0_VCC6")
		)
		(pad "2" smd circle
			(at 0.40005 0 90)
			(size 0 0)
			(layers "F.Cu" "F.Mask" "F.Paste")
			(net "GND")
		)
	)
	(footprint ""
		(layer "F.Cu")
		(at 297.486324 -115.148614 180)
		(property "Reference" "R67"
			(at 0 0 180)
			(layer "F.SilkS")
			(hide yes)
			(effects
				(font
					(size 1.27 1.27)
				)
			)
		)
		(property "Value" ""
			(at 0 0 180)
			(layer "F.Fab")
			(effects
				(font
					(size 1.27 1.27)
				)
			)
		)
		(duplicate_pad_numbers_are_jumpers no)
		(fp_line
			(start 0.7874 0.4064)
			(end -0.7874 0.4064)
			(stroke
				(width 0.1524)
				(type default)
			)
			(layer "F.SilkS")
		)
		(fp_line
			(start 0.7874 -0.4064)
			(end 0.7874 0.4064)
			(stroke
				(width 0.1524)
				(type default)
			)
			(layer "F.SilkS")
		)
		(fp_line
			(start -0.7874 0.4064)
			(end -0.7874 -0.4064)
			(stroke
				(width 0.1524)
				(type default)
			)
			(layer "F.SilkS")
		)
		(fp_line
			(start -0.7874 -0.4064)
			(end 0.7874 -0.4064)
			(stroke
				(width 0.1524)
				(type default)
			)
			(layer "F.SilkS")
		)
		(fp_line
			(start 0.67945 0.3048)
			(end 0.120396 0.3048)
			(stroke
				(width 0.1)
				(type default)
			)
			(layer "F.Fab")
		)
		(fp_line
			(start 0.67945 -0.3048)
			(end 0.67945 0.3048)
			(stroke
				(width 0.1)
				(type default)
			)
			(layer "F.Fab")
		)
		(fp_line
			(start 0.12065 -0.2794)
			(end 0.12065 -0.3048)
			(stroke
				(width 0.1)
				(type default)
			)
			(layer "F.Fab")
		)
		(fp_line
			(start 0.12065 -0.3048)
			(end 0.67945 -0.3048)
			(stroke
				(width 0.1)
				(type default)
			)
			(layer "F.Fab")
		)
		(fp_line
			(start 0.120396 0.3048)
			(end 0.120396 0.2794)
			(stroke
				(width 0.1)
				(type default)
			)
			(layer "F.Fab")
		)
		(fp_line
			(start 0.120396 0.2794)
			(end -0.12065 0.2794)
			(stroke
				(width 0.1)
				(type default)
			)
			(layer "F.Fab")
		)
		(fp_line
			(start -0.12065 0.3048)
			(end -0.67945 0.3048)
			(stroke
				(width 0.1)
				(type default)
			)
			(layer "F.Fab")
		)
		(fp_line
			(start -0.12065 0.2794)
			(end -0.12065 0.3048)
			(stroke
				(width 0.1)
				(type default)
			)
			(layer "F.Fab")
		)
		(fp_line
			(start -0.12065 -0.2794)
			(end 0.12065 -0.2794)
			(stroke
				(width 0.1)
				(type default)
			)
			(layer "F.Fab")
		)
		(fp_line
			(start -0.12065 -0.305054)
			(end -0.12065 -0.2794)
			(stroke
				(width 0.1)
				(type default)
			)
			(layer "F.Fab")
		)
		(fp_line
			(start -0.67945 0.3048)
			(end -0.67945 -0.305054)
			(stroke
				(width 0.1)
				(type default)
			)
			(layer "F.Fab")
		)
		(fp_line
			(start -0.67945 -0.305054)
			(end -0.12065 -0.305054)
			(stroke
				(width 0.1)
				(type default)
			)
			(layer "F.Fab")
		)
		(pad "1" smd circle
			(at -0.40005 0 180)
			(size 0 0)
			(layers "F.Cu" "F.Mask" "F.Paste")
			(net "P3V3_AUX")
		)
		(pad "2" smd circle
			(at 0.40005 0 180)
			(size 0 0)
			(layers "F.Cu" "F.Mask" "F.Paste")
			(net "SMB_FRU_3V3AUX_SDA")
		)
	)
	(footprint ""
		(layer "F.Cu")
		(at 401.110958 -321.002152 -90)
		(property "Reference" "R287"
			(at 0 0 270)
			(layer "F.SilkS")
			(hide yes)
			(effects
				(font
					(size 1.27 1.27)
				)
			)
		)
		(property "Value" ""
			(at 0 0 270)
			(layer "F.Fab")
			(effects
				(font
					(size 1.27 1.27)
				)
			)
		)
		(duplicate_pad_numbers_are_jumpers no)
		(fp_line
			(start -0.7874 0.4064)
			(end -0.7874 -0.4064)
			(stroke
				(width 0.1524)
				(type default)
			)
			(layer "F.SilkS")
		)
		(fp_line
			(start 0.7874 0.4064)
			(end -0.7874 0.4064)
			(stroke
				(width 0.1524)
				(type default)
			)
			(layer "F.SilkS")
		)
		(fp_line
			(start -0.7874 -0.4064)
			(end 0.7874 -0.4064)
			(stroke
				(width 0.1524)
				(type default)
			)
			(layer "F.SilkS")
		)
		(fp_line
			(start 0.7874 -0.4064)
			(end 0.7874 0.4064)
			(stroke
				(width 0.1524)
				(type default)
			)
			(layer "F.SilkS")
		)
		(fp_line
			(start -0.67945 0.3048)
			(end -0.67945 -0.305054)
			(stroke
				(width 0.1)
				(type default)
			)
			(layer "F.Fab")
		)
		(fp_line
			(start -0.12065 0.3048)
			(end -0.67945 0.3048)
			(stroke
				(width 0.1)
				(type default)
			)
			(layer "F.Fab")
		)
		(fp_line
			(start 0.120396 0.3048)
			(end 0.120396 0.2794)
			(stroke
				(width 0.1)
				(type default)
			)
			(layer "F.Fab")
		)
		(fp_line
			(start 0.67945 0.3048)
			(end 0.120396 0.3048)
			(stroke
				(width 0.1)
				(type default)
			)
			(layer "F.Fab")
		)
		(fp_line
			(start -0.12065 0.2794)
			(end -0.12065 0.3048)
			(stroke
				(width 0.1)
				(type default)
			)
			(layer "F.Fab")
		)
		(fp_line
			(start 0.120396 0.2794)
			(end -0.12065 0.2794)
			(stroke
				(width 0.1)
				(type default)
			)
			(layer "F.Fab")
		)
		(fp_line
			(start -0.12065 -0.2794)
			(end 0.12065 -0.2794)
			(stroke
				(width 0.1)
				(type default)
			)
			(layer "F.Fab")
		)
		(fp_line
			(start 0.12065 -0.2794)
			(end 0.12065 -0.3048)
			(stroke
				(width 0.1)
				(type default)
			)
			(layer "F.Fab")
		)
		(fp_line
			(start 0.12065 -0.3048)
			(end 0.67945 -0.3048)
			(stroke
				(width 0.1)
				(type default)
			)
			(layer "F.Fab")
		)
		(fp_line
			(start 0.67945 -0.3048)
			(end 0.67945 0.3048)
			(stroke
				(width 0.1)
				(type default)
			)
			(layer "F.Fab")
		)
		(fp_line
			(start -0.67945 -0.305054)
			(end -0.12065 -0.305054)
			(stroke
				(width 0.1)
				(type default)
			)
			(layer "F.Fab")
		)
		(fp_line
			(start -0.12065 -0.305054)
			(end -0.12065 -0.2794)
			(stroke
				(width 0.1)
				(type default)
			)
			(layer "F.Fab")
		)
		(pad "1" smd circle
			(at -0.40005 0 270)
			(size 0 0)
			(layers "F.Cu" "F.Mask" "F.Paste")
			(net "GND")
		)
		(pad "2" smd circle
			(at 0.40005 0 270)
			(size 0 0)
			(layers "F.Cu" "F.Mask" "F.Paste")
			(net "CPU0_PWR_GOOD")
		)
	)
	(footprint ""
		(layer "F.Cu")
		(at 304.419 -362.839 180)
		(property "Reference" "C8069"
			(at 0 0 180)
			(layer "F.SilkS")
			(hide yes)
			(effects
				(font
					(size 1.27 1.27)
				)
			)
		)
		(property "Value" ""
			(at 0 0 180)
			(layer "F.Fab")
			(effects
				(font
					(size 1.27 1.27)
				)
			)
		)
		(duplicate_pad_numbers_are_jumpers no)
		(fp_line
			(start 0.7874 0.4064)
			(end -0.7874 0.4064)
			(stroke
				(width 0.1524)
				(type default)
			)
			(layer "F.SilkS")
		)
		(fp_line
			(start 0.7874 -0.4064)
			(end 0.7874 0.4064)
			(stroke
				(width 0.1524)
				(type default)
			)
			(layer "F.SilkS")
		)
		(fp_line
			(start -0.7874 0.4064)
			(end -0.7874 -0.4064)
			(stroke
				(width 0.1524)
				(type default)
			)
			(layer "F.SilkS")
		)
		(fp_line
			(start -0.7874 -0.4064)
			(end 0.7874 -0.4064)
			(stroke
				(width 0.1524)
				(type default)
			)
			(layer "F.SilkS")
		)
		(fp_line
			(start 0.67945 0.3048)
			(end 0.120396 0.3048)
			(stroke
				(width 0.1)
				(type default)
			)
			(layer "F.Fab")
		)
		(fp_line
			(start 0.67945 -0.3048)
			(end 0.67945 0.3048)
			(stroke
				(width 0.1)
				(type default)
			)
			(layer "F.Fab")
		)
		(fp_line
			(start 0.12065 -0.2794)
			(end 0.12065 -0.3048)
			(stroke
				(width 0.1)
				(type default)
			)
			(layer "F.Fab")
		)
		(fp_line
			(start 0.12065 -0.3048)
			(end 0.67945 -0.3048)
			(stroke
				(width 0.1)
				(type default)
			)
			(layer "F.Fab")
		)
		(fp_line
			(start 0.120396 0.3048)
			(end 0.120396 0.2794)
			(stroke
				(width 0.1)
				(type default)
			)
			(layer "F.Fab")
		)
		(fp_line
			(start 0.120396 0.2794)
			(end -0.12065 0.2794)
			(stroke
				(width 0.1)
				(type default)
			)
			(layer "F.Fab")
		)
		(fp_line
			(start -0.12065 0.3048)
			(end -0.67945 0.3048)
			(stroke
				(width 0.1)
				(type default)
			)
			(layer "F.Fab")
		)
		(fp_line
			(start -0.12065 0.2794)
			(end -0.12065 0.3048)
			(stroke
				(width 0.1)
				(type default)
			)
			(layer "F.Fab")
		)
		(fp_line
			(start -0.12065 -0.2794)
			(end 0.12065 -0.2794)
			(stroke
				(width 0.1)
				(type default)
			)
			(layer "F.Fab")
		)
		(fp_line
			(start -0.12065 -0.305054)
			(end -0.12065 -0.2794)
			(stroke
				(width 0.1)
				(type default)
			)
			(layer "F.Fab")
		)
		(fp_line
			(start -0.67945 0.3048)
			(end -0.67945 -0.305054)
			(stroke
				(width 0.1)
				(type default)
			)
			(layer "F.Fab")
		)
		(fp_line
			(start -0.67945 -0.305054)
			(end -0.12065 -0.305054)
			(stroke
				(width 0.1)
				(type default)
			)
			(layer "F.Fab")
		)
		(pad "1" smd circle
			(at -0.40005 0 180)
			(size 0 0)
			(layers "F.Cu" "F.Mask" "F.Paste")
			(net "PVDDCR_CPU1_P0_EN_R")
		)
		(pad "2" smd circle
			(at 0.40005 0 180)
			(size 0 0)
			(layers "F.Cu" "F.Mask" "F.Paste")
			(net "GND")
		)
	)
	(footprint ""
		(layer "F.Cu")
		(at 171.776644 -128.24333)
		(property "Reference" "R6850"
			(at 0 0 0)
			(layer "F.SilkS")
			(hide yes)
			(effects
				(font
					(size 1.27 1.27)
				)
			)
		)
		(property "Value" ""
			(at 0 0 0)
			(layer "F.Fab")
			(effects
				(font
					(size 1.27 1.27)
				)
			)
		)
		(duplicate_pad_numbers_are_jumpers no)
		(fp_line
			(start -0.7874 -0.4064)
			(end 0.7874 -0.4064)
			(stroke
				(width 0.1524)
				(type default)
			)
			(layer "F.SilkS")
		)
		(fp_line
			(start -0.7874 0.4064)
			(end -0.7874 -0.4064)
			(stroke
				(width 0.1524)
				(type default)
			)
			(layer "F.SilkS")
		)
		(fp_line
			(start 0.7874 -0.4064)
			(end 0.7874 0.4064)
			(stroke
				(width 0.1524)
				(type default)
			)
			(layer "F.SilkS")
		)
		(fp_line
			(start 0.7874 0.4064)
			(end -0.7874 0.4064)
			(stroke
				(width 0.1524)
				(type default)
			)
			(layer "F.SilkS")
		)
		(fp_line
			(start -0.67945 -0.305054)
			(end -0.12065 -0.305054)
			(stroke
				(width 0.1)
				(type default)
			)
			(layer "F.Fab")
		)
		(fp_line
			(start -0.67945 0.3048)
			(end -0.67945 -0.305054)
			(stroke
				(width 0.1)
				(type default)
			)
			(layer "F.Fab")
		)
		(fp_line
			(start -0.12065 -0.305054)
			(end -0.12065 -0.2794)
			(stroke
				(width 0.1)
				(type default)
			)
			(layer "F.Fab")
		)
		(fp_line
			(start -0.12065 -0.2794)
			(end 0.12065 -0.2794)
			(stroke
				(width 0.1)
				(type default)
			)
			(layer "F.Fab")
		)
		(fp_line
			(start -0.12065 0.2794)
			(end -0.12065 0.3048)
			(stroke
				(width 0.1)
				(type default)
			)
			(layer "F.Fab")
		)
		(fp_line
			(start -0.12065 0.3048)
			(end -0.67945 0.3048)
			(stroke
				(width 0.1)
				(type default)
			)
			(layer "F.Fab")
		)
		(fp_line
			(start 0.120396 0.2794)
			(end -0.12065 0.2794)
			(stroke
				(width 0.1)
				(type default)
			)
			(layer "F.Fab")
		)
		(fp_line
			(start 0.120396 0.3048)
			(end 0.120396 0.2794)
			(stroke
				(width 0.1)
				(type default)
			)
			(layer "F.Fab")
		)
		(fp_line
			(start 0.12065 -0.3048)
			(end 0.67945 -0.3048)
			(stroke
				(width 0.1)
				(type default)
			)
			(layer "F.Fab")
		)
		(fp_line
			(start 0.12065 -0.2794)
			(end 0.12065 -0.3048)
			(stroke
				(width 0.1)
				(type default)
			)
			(layer "F.Fab")
		)
		(fp_line
			(start 0.67945 -0.3048)
			(end 0.67945 0.3048)
			(stroke
				(width 0.1)
				(type default)
			)
			(layer "F.Fab")
		)
		(fp_line
			(start 0.67945 0.3048)
			(end 0.120396 0.3048)
			(stroke
				(width 0.1)
				(type default)
			)
			(layer "F.Fab")
		)
		(pad "1" smd circle
			(at -0.40005 0)
			(size 0 0)
			(layers "F.Cu" "F.Mask" "F.Paste")
			(net "P1V8_RETIMER_CPU0_EN")
		)
		(pad "2" smd circle
			(at 0.40005 0)
			(size 0 0)
			(layers "F.Cu" "F.Mask" "F.Paste")
			(net "P1V8_RETIMER_CPU0_R_EN")
		)
	)
	(footprint ""
		(layer "F.Cu")
		(at 120.396 -431.038 180)
		(property "Reference" "R3448"
			(at 0 0 180)
			(layer "F.SilkS")
			(hide yes)
			(effects
				(font
					(size 1.27 1.27)
				)
			)
		)
		(property "Value" ""
			(at 0 0 180)
			(layer "F.Fab")
			(effects
				(font
					(size 1.27 1.27)
				)
			)
		)
		(duplicate_pad_numbers_are_jumpers no)
		(fp_line
			(start 0.7874 0.4064)
			(end -0.7874 0.4064)
			(stroke
				(width 0.1524)
				(type default)
			)
			(layer "F.SilkS")
		)
		(fp_line
			(start 0.7874 -0.4064)
			(end 0.7874 0.4064)
			(stroke
				(width 0.1524)
				(type default)
			)
			(layer "F.SilkS")
		)
		(fp_line
			(start -0.7874 0.4064)
			(end -0.7874 -0.4064)
			(stroke
				(width 0.1524)
				(type default)
			)
			(layer "F.SilkS")
		)
		(fp_line
			(start -0.7874 -0.4064)
			(end 0.7874 -0.4064)
			(stroke
				(width 0.1524)
				(type default)
			)
			(layer "F.SilkS")
		)
		(fp_line
			(start 0.67945 0.3048)
			(end 0.120396 0.3048)
			(stroke
				(width 0.1)
				(type default)
			)
			(layer "F.Fab")
		)
		(fp_line
			(start 0.67945 -0.3048)
			(end 0.67945 0.3048)
			(stroke
				(width 0.1)
				(type default)
			)
			(layer "F.Fab")
		)
		(fp_line
			(start 0.12065 -0.2794)
			(end 0.12065 -0.3048)
			(stroke
				(width 0.1)
				(type default)
			)
			(layer "F.Fab")
		)
		(fp_line
			(start 0.12065 -0.3048)
			(end 0.67945 -0.3048)
			(stroke
				(width 0.1)
				(type default)
			)
			(layer "F.Fab")
		)
		(fp_line
			(start 0.120396 0.3048)
			(end 0.120396 0.2794)
			(stroke
				(width 0.1)
				(type default)
			)
			(layer "F.Fab")
		)
		(fp_line
			(start 0.120396 0.2794)
			(end -0.12065 0.2794)
			(stroke
				(width 0.1)
				(type default)
			)
			(layer "F.Fab")
		)
		(fp_line
			(start -0.12065 0.3048)
			(end -0.67945 0.3048)
			(stroke
				(width 0.1)
				(type default)
			)
			(layer "F.Fab")
		)
		(fp_line
			(start -0.12065 0.2794)
			(end -0.12065 0.3048)
			(stroke
				(width 0.1)
				(type default)
			)
			(layer "F.Fab")
		)
		(fp_line
			(start -0.12065 -0.2794)
			(end 0.12065 -0.2794)
			(stroke
				(width 0.1)
				(type default)
			)
			(layer "F.Fab")
		)
		(fp_line
			(start -0.12065 -0.305054)
			(end -0.12065 -0.2794)
			(stroke
				(width 0.1)
				(type default)
			)
			(layer "F.Fab")
		)
		(fp_line
			(start -0.67945 0.3048)
			(end -0.67945 -0.305054)
			(stroke
				(width 0.1)
				(type default)
			)
			(layer "F.Fab")
		)
		(fp_line
			(start -0.67945 -0.305054)
			(end -0.12065 -0.305054)
			(stroke
				(width 0.1)
				(type default)
			)
			(layer "F.Fab")
		)
		(pad "1" smd circle
			(at -0.40005 0 180)
			(size 0 0)
			(layers "F.Cu" "F.Mask" "F.Paste")
			(net "P3V3_AUX")
		)
		(pad "2" smd circle
			(at 0.40005 0 180)
			(size 0 0)
			(layers "F.Cu" "F.Mask" "F.Paste")
			(net "GPU_FPGA_BOOT_EN")
		)
	)
	(footprint ""
		(layer "F.Cu")
		(at 124.058426 -408.517344 -90)
		(property "Reference" "C6700"
			(at 0 0 270)
			(layer "F.SilkS")
			(hide yes)
			(effects
				(font
					(size 1.27 1.27)
				)
			)
		)
		(property "Value" ""
			(at 0 0 270)
			(layer "F.Fab")
			(effects
				(font
					(size 1.27 1.27)
				)
			)
		)
		(duplicate_pad_numbers_are_jumpers no)
		(fp_line
			(start -0.299974 0.150114)
			(end -0.299974 -0.150114)
			(stroke
				(width 0.1)
				(type default)
			)
			(layer "F.Fab")
		)
		(fp_line
			(start 0.299974 0.150114)
			(end -0.299974 0.150114)
			(stroke
				(width 0.1)
				(type default)
			)
			(layer "F.Fab")
		)
		(fp_line
			(start -0.299974 -0.150114)
			(end 0.299974 -0.150114)
			(stroke
				(width 0.1)
				(type default)
			)
			(layer "F.Fab")
		)
		(fp_line
			(start 0.299974 -0.150114)
			(end 0.299974 0.150114)
			(stroke
				(width 0.1)
				(type default)
			)
			(layer "F.Fab")
		)
		(pad "1" smd rect
			(at -0.2667 0 270)
			(size 0.3048 0.381)
			(layers "F.Cu" "F.Mask" "F.Paste")
			(net "P5E_CPU1_P2_TX_BUF_C_DN<3>")
		)
		(pad "2" smd rect
			(at 0.2667 0 270)
			(size 0.3048 0.381)
			(layers "F.Cu" "F.Mask" "F.Paste")
			(net "P5E_CPU1_P2_TX_BUF_DN<3>")
		)
	)
	(footprint ""
		(layer "F.Cu")
		(at 142.893542 -384.66268)
		(property "Reference" "R876"
			(at 0 0 0)
			(layer "F.SilkS")
			(hide yes)
			(effects
				(font
					(size 1.27 1.27)
				)
			)
		)
		(property "Value" ""
			(at 0 0 0)
			(layer "F.Fab")
			(effects
				(font
					(size 1.27 1.27)
				)
			)
		)
		(duplicate_pad_numbers_are_jumpers no)
		(fp_line
			(start -0.32512 -0.175006)
			(end 0.32512 -0.175006)
			(stroke
				(width 0.1)
				(type default)
			)
			(layer "F.Fab")
		)
		(fp_line
			(start -0.32512 0.175006)
			(end -0.32512 -0.175006)
			(stroke
				(width 0.1)
				(type default)
			)
			(layer "F.Fab")
		)
		(fp_line
			(start 0.32512 -0.175006)
			(end 0.32512 0.175006)
			(stroke
				(width 0.1)
				(type default)
			)
			(layer "F.Fab")
		)
		(fp_line
			(start 0.32512 0.175006)
			(end -0.32512 0.175006)
			(stroke
				(width 0.1)
				(type default)
			)
			(layer "F.Fab")
		)
		(pad "1" smd rect
			(at -0.2667 0)
			(size 0.3048 0.381)
			(layers "F.Cu" "F.Mask" "F.Paste")
			(net "GPIO3_RT_CPU1_P2")
		)
		(pad "2" smd rect
			(at 0.2667 0 180)
			(size 0.3048 0.381)
			(layers "F.Cu" "F.Mask" "F.Paste")
			(net "GND")
		)
	)
	(footprint ""
		(layer "F.Cu")
		(at 189.366398 -426.375068 -90)
		(property "Reference" "R9013"
			(at 0 0 270)
			(layer "F.SilkS")
			(hide yes)
			(effects
				(font
					(size 1.27 1.27)
				)
			)
		)
		(property "Value" ""
			(at 0 0 270)
			(layer "F.Fab")
			(effects
				(font
					(size 1.27 1.27)
				)
			)
		)
		(duplicate_pad_numbers_are_jumpers no)
		(fp_line
			(start -0.7874 0.4064)
			(end -0.7874 -0.4064)
			(stroke
				(width 0.1524)
				(type default)
			)
			(layer "F.SilkS")
		)
		(fp_line
			(start 0.7874 0.4064)
			(end -0.7874 0.4064)
			(stroke
				(width 0.1524)
				(type default)
			)
			(layer "F.SilkS")
		)
		(fp_line
			(start -0.7874 -0.4064)
			(end 0.7874 -0.4064)
			(stroke
				(width 0.1524)
				(type default)
			)
			(layer "F.SilkS")
		)
		(fp_line
			(start 0.7874 -0.4064)
			(end 0.7874 0.4064)
			(stroke
				(width 0.1524)
				(type default)
			)
			(layer "F.SilkS")
		)
		(fp_line
			(start -0.67945 0.3048)
			(end -0.67945 -0.305054)
			(stroke
				(width 0.1)
				(type default)
			)
			(layer "F.Fab")
		)
		(fp_line
			(start -0.12065 0.3048)
			(end -0.67945 0.3048)
			(stroke
				(width 0.1)
				(type default)
			)
			(layer "F.Fab")
		)
		(fp_line
			(start 0.120396 0.3048)
			(end 0.120396 0.2794)
			(stroke
				(width 0.1)
				(type default)
			)
			(layer "F.Fab")
		)
		(fp_line
			(start 0.67945 0.3048)
			(end 0.120396 0.3048)
			(stroke
				(width 0.1)
				(type default)
			)
			(layer "F.Fab")
		)
		(fp_line
			(start -0.12065 0.2794)
			(end -0.12065 0.3048)
			(stroke
				(width 0.1)
				(type default)
			)
			(layer "F.Fab")
		)
		(fp_line
			(start 0.120396 0.2794)
			(end -0.12065 0.2794)
			(stroke
				(width 0.1)
				(type default)
			)
			(layer "F.Fab")
		)
		(fp_line
			(start -0.12065 -0.2794)
			(end 0.12065 -0.2794)
			(stroke
				(width 0.1)
				(type default)
			)
			(layer "F.Fab")
		)
		(fp_line
			(start 0.12065 -0.2794)
			(end 0.12065 -0.3048)
			(stroke
				(width 0.1)
				(type default)
			)
			(layer "F.Fab")
		)
		(fp_line
			(start 0.12065 -0.3048)
			(end 0.67945 -0.3048)
			(stroke
				(width 0.1)
				(type default)
			)
			(layer "F.Fab")
		)
		(fp_line
			(start 0.67945 -0.3048)
			(end 0.67945 0.3048)
			(stroke
				(width 0.1)
				(type default)
			)
			(layer "F.Fab")
		)
		(fp_line
			(start -0.67945 -0.305054)
			(end -0.12065 -0.305054)
			(stroke
				(width 0.1)
				(type default)
			)
			(layer "F.Fab")
		)
		(fp_line
			(start -0.12065 -0.305054)
			(end -0.12065 -0.2794)
			(stroke
				(width 0.1)
				(type default)
			)
			(layer "F.Fab")
		)
		(pad "1" smd circle
			(at -0.40005 0 270)
			(size 0 0)
			(layers "F.Cu" "F.Mask" "F.Paste")
			(net "PRSNT_CABLE_GPU_A2_ISO_N")
		)
		(pad "2" smd circle
			(at 0.40005 0 270)
			(size 0 0)
			(layers "F.Cu" "F.Mask" "F.Paste")
			(net "PRSNT_CABLE_GPU_A2_ISO_R1_N")
		)
	)
	(footprint ""
		(layer "F.Cu")
		(at 84.074 -69.596)
		(property "Reference" "U34"
			(at -2.032 -2.377948 0)
			(unlocked yes)
			(layer "F.SilkS")
			(effects
				(font
					(size 0.7874 0.5842)
					(thickness 0.1524)
				)
				(justify left)
			)
		)
		(property "Value" ""
			(at 0 0 0)
			(layer "F.Fab")
			(effects
				(font
					(size 1.27 1.27)
				)
			)
		)
		(duplicate_pad_numbers_are_jumpers no)
		(fp_line
			(start -2.0574 -1.651)
			(end -0.381 -1.651)
			(stroke
				(width 0.1524)
				(type default)
			)
			(layer "F.SilkS")
		)
		(fp_line
			(start -2.0574 1.651)
			(end -2.0574 -1.651)
			(stroke
				(width 0.1524)
				(type default)
			)
			(layer "F.SilkS")
		)
		(fp_line
			(start -0.381 -1.651)
			(end 0 -1.016)
			(stroke
				(width 0.1524)
				(type default)
			)
			(layer "F.SilkS")
		)
		(fp_line
			(start 0 -1.016)
			(end 0.381 -1.651)
			(stroke
				(width 0.1524)
				(type default)
			)
			(layer "F.SilkS")
		)
		(fp_line
			(start 0.381 -1.651)
			(end 2.0574 -1.651)
			(stroke
				(width 0.1524)
				(type default)
			)
			(layer "F.SilkS")
		)
		(fp_line
			(start 2.0574 -1.651)
			(end 2.0574 1.651)
			(stroke
				(width 0.1524)
				(type default)
			)
			(layer "F.SilkS")
		)
		(fp_line
			(start 2.0574 1.651)
			(end -2.0574 1.651)
			(stroke
				(width 0.1524)
				(type default)
			)
			(layer "F.SilkS")
		)
		(fp_poly
			(pts
				(xy -2.71272 -0.719328) (xy -2.71272 -1.344168) (xy -2.159 -1.016)
			)
			(stroke
				(width 0)
				(type default)
			)
			(fill yes)
			(layer "F.SilkS")
		)
		(fp_line
			(start -1.599946 -1.199896)
			(end -0.899922 -1.199896)
			(stroke
				(width 0.1)
				(type default)
			)
			(layer "F.Fab")
		)
		(fp_line
			(start -1.599946 1.199896)
			(end -1.599946 -1.199896)
			(stroke
				(width 0.1)
				(type default)
			)
			(layer "F.Fab")
		)
		(fp_line
			(start -0.899922 -1.549908)
			(end 0.899922 -1.549908)
			(stroke
				(width 0.1)
				(type default)
			)
			(layer "F.Fab")
		)
		(fp_line
			(start -0.899922 -1.199896)
			(end -0.899922 -1.549908)
			(stroke
				(width 0.1)
				(type default)
			)
			(layer "F.Fab")
		)
		(fp_line
			(start -0.899922 1.199896)
			(end -1.599946 1.199896)
			(stroke
				(width 0.1)
				(type default)
			)
			(layer "F.Fab")
		)
		(fp_line
			(start -0.899922 1.549908)
			(end -0.899922 1.199896)
			(stroke
				(width 0.1)
				(type default)
			)
			(layer "F.Fab")
		)
		(fp_line
			(start 0.899922 -1.549908)
			(end 0.899922 -1.199896)
			(stroke
				(width 0.1)
				(type default)
			)
			(layer "F.Fab")
		)
		(fp_line
			(start 0.899922 -1.199896)
			(end 1.599946 -1.199896)
			(stroke
				(width 0.1)
				(type default)
			)
			(layer "F.Fab")
		)
		(fp_line
			(start 0.899922 1.199896)
			(end 0.899922 1.549908)
			(stroke
				(width 0.1)
				(type default)
			)
			(layer "F.Fab")
		)
		(fp_line
			(start 0.899922 1.549908)
			(end -0.899922 1.549908)
			(stroke
				(width 0.1)
				(type default)
			)
			(layer "F.Fab")
		)
		(fp_line
			(start 1.599946 -1.199896)
			(end 1.599946 1.199896)
			(stroke
				(width 0.1)
				(type default)
			)
			(layer "F.Fab")
		)
		(fp_line
			(start 1.599946 1.199896)
			(end 0.899922 1.199896)
			(stroke
				(width 0.1)
				(type default)
			)
			(layer "F.Fab")
		)
		(fp_poly
			(pts
				(xy -2.71272 -0.719328) (xy -2.71272 -1.344168) (xy -2.159 -1.016)
			)
			(stroke
				(width 0)
				(type default)
			)
			(fill yes)
			(layer "F.Fab")
		)
		(pad "1" smd rect
			(at -1.225042 -0.94996 270)
			(size 0.5588 1.3462)
			(layers "F.Cu" "F.Mask" "F.Paste")
			(net "Net_10852")
		)
		(pad "2" smd rect
			(at -1.225042 0 270)
			(size 0.5588 1.3462)
			(layers "F.Cu" "F.Mask" "F.Paste")
			(net "OCP_V3_2_P3V3_R2_PWRGD")
		)
		(pad "3" smd rect
			(at -1.225042 0.94996 270)
			(size 0.5588 1.3462)
			(layers "F.Cu" "F.Mask" "F.Paste")
			(net "GND")
		)
		(pad "4" smd rect
			(at 1.225042 0.94996 270)
			(size 0.5588 1.3462)
			(layers "F.Cu" "F.Mask" "F.Paste")
			(net "OCP_V3_2_P3V3_PLD_PWRGD")
		)
		(pad "5" smd rect
			(at 1.225042 -0.94996 270)
			(size 0.5588 1.3462)
			(layers "F.Cu" "F.Mask" "F.Paste")
			(net "P3V3_AUX")
		)
	)
	(footprint ""
		(layer "F.Cu")
		(at 35.821112 -368.455448 90)
		(property "Reference" "PC29"
			(at 0 0 90)
			(layer "F.SilkS")
			(hide yes)
			(effects
				(font
					(size 1.27 1.27)
				)
			)
		)
		(property "Value" ""
			(at 0 0 90)
			(layer "F.Fab")
			(effects
				(font
					(size 1.27 1.27)
				)
			)
		)
		(duplicate_pad_numbers_are_jumpers no)
		(fp_line
			(start 0.7874 -0.4064)
			(end 0.7874 0.4064)
			(stroke
				(width 0.1524)
				(type default)
			)
			(layer "F.SilkS")
		)
		(fp_line
			(start -0.7874 -0.4064)
			(end 0.7874 -0.4064)
			(stroke
				(width 0.1524)
				(type default)
			)
			(layer "F.SilkS")
		)
		(fp_line
			(start 0.7874 0.4064)
			(end -0.7874 0.4064)
			(stroke
				(width 0.1524)
				(type default)
			)
			(layer "F.SilkS")
		)
		(fp_line
			(start -0.7874 0.4064)
			(end -0.7874 -0.4064)
			(stroke
				(width 0.1524)
				(type default)
			)
			(layer "F.SilkS")
		)
		(fp_line
			(start -0.12065 -0.305054)
			(end -0.12065 -0.2794)
			(stroke
				(width 0.1)
				(type default)
			)
			(layer "F.Fab")
		)
		(fp_line
			(start -0.67945 -0.305054)
			(end -0.12065 -0.305054)
			(stroke
				(width 0.1)
				(type default)
			)
			(layer "F.Fab")
		)
		(fp_line
			(start 0.67945 -0.3048)
			(end 0.67945 0.3048)
			(stroke
				(width 0.1)
				(type default)
			)
			(layer "F.Fab")
		)
		(fp_line
			(start 0.12065 -0.3048)
			(end 0.67945 -0.3048)
			(stroke
				(width 0.1)
				(type default)
			)
			(layer "F.Fab")
		)
		(fp_line
			(start 0.12065 -0.2794)
			(end 0.12065 -0.3048)
			(stroke
				(width 0.1)
				(type default)
			)
			(layer "F.Fab")
		)
		(fp_line
			(start -0.12065 -0.2794)
			(end 0.12065 -0.2794)
			(stroke
				(width 0.1)
				(type default)
			)
			(layer "F.Fab")
		)
		(fp_line
			(start 0.120396 0.2794)
			(end -0.12065 0.2794)
			(stroke
				(width 0.1)
				(type default)
			)
			(layer "F.Fab")
		)
		(fp_line
			(start -0.12065 0.2794)
			(end -0.12065 0.3048)
			(stroke
				(width 0.1)
				(type default)
			)
			(layer "F.Fab")
		)
		(fp_line
			(start 0.67945 0.3048)
			(end 0.120396 0.3048)
			(stroke
				(width 0.1)
				(type default)
			)
			(layer "F.Fab")
		)
		(fp_line
			(start 0.120396 0.3048)
			(end 0.120396 0.2794)
			(stroke
				(width 0.1)
				(type default)
			)
			(layer "F.Fab")
		)
		(fp_line
			(start -0.12065 0.3048)
			(end -0.67945 0.3048)
			(stroke
				(width 0.1)
				(type default)
			)
			(layer "F.Fab")
		)
		(fp_line
			(start -0.67945 0.3048)
			(end -0.67945 -0.305054)
			(stroke
				(width 0.1)
				(type default)
			)
			(layer "F.Fab")
		)
		(pad "1" smd circle
			(at -0.40005 0 90)
			(size 0 0)
			(layers "F.Cu" "F.Mask" "F.Paste")
			(net "PVDDCR_CPU1_P1_VCC")
		)
		(pad "2" smd circle
			(at 0.40005 0 90)
			(size 0 0)
			(layers "F.Cu" "F.Mask" "F.Paste")
			(net "GND")
		)
	)
	(footprint ""
		(layer "F.Cu")
		(at 22.036278 -437.980074)
		(property "Reference" "R3108"
			(at 0 0 0)
			(layer "F.SilkS")
			(hide yes)
			(effects
				(font
					(size 1.27 1.27)
				)
			)
		)
		(property "Value" ""
			(at 0 0 0)
			(layer "F.Fab")
			(effects
				(font
					(size 1.27 1.27)
				)
			)
		)
		(duplicate_pad_numbers_are_jumpers no)
		(fp_line
			(start -0.7874 -0.4064)
			(end 0.7874 -0.4064)
			(stroke
				(width 0.1524)
				(type default)
			)
			(layer "F.SilkS")
		)
		(fp_line
			(start -0.7874 0.4064)
			(end -0.7874 -0.4064)
			(stroke
				(width 0.1524)
				(type default)
			)
			(layer "F.SilkS")
		)
		(fp_line
			(start 0.7874 -0.4064)
			(end 0.7874 0.4064)
			(stroke
				(width 0.1524)
				(type default)
			)
			(layer "F.SilkS")
		)
		(fp_line
			(start 0.7874 0.4064)
			(end -0.7874 0.4064)
			(stroke
				(width 0.1524)
				(type default)
			)
			(layer "F.SilkS")
		)
		(fp_line
			(start -0.67945 -0.305054)
			(end -0.12065 -0.305054)
			(stroke
				(width 0.1)
				(type default)
			)
			(layer "F.Fab")
		)
		(fp_line
			(start -0.67945 0.3048)
			(end -0.67945 -0.305054)
			(stroke
				(width 0.1)
				(type default)
			)
			(layer "F.Fab")
		)
		(fp_line
			(start -0.12065 -0.305054)
			(end -0.12065 -0.2794)
			(stroke
				(width 0.1)
				(type default)
			)
			(layer "F.Fab")
		)
		(fp_line
			(start -0.12065 -0.2794)
			(end 0.12065 -0.2794)
			(stroke
				(width 0.1)
				(type default)
			)
			(layer "F.Fab")
		)
		(fp_line
			(start -0.12065 0.2794)
			(end -0.12065 0.3048)
			(stroke
				(width 0.1)
				(type default)
			)
			(layer "F.Fab")
		)
		(fp_line
			(start -0.12065 0.3048)
			(end -0.67945 0.3048)
			(stroke
				(width 0.1)
				(type default)
			)
			(layer "F.Fab")
		)
		(fp_line
			(start 0.120396 0.2794)
			(end -0.12065 0.2794)
			(stroke
				(width 0.1)
				(type default)
			)
			(layer "F.Fab")
		)
		(fp_line
			(start 0.120396 0.3048)
			(end 0.120396 0.2794)
			(stroke
				(width 0.1)
				(type default)
			)
			(layer "F.Fab")
		)
		(fp_line
			(start 0.12065 -0.3048)
			(end 0.67945 -0.3048)
			(stroke
				(width 0.1)
				(type default)
			)
			(layer "F.Fab")
		)
		(fp_line
			(start 0.12065 -0.2794)
			(end 0.12065 -0.3048)
			(stroke
				(width 0.1)
				(type default)
			)
			(layer "F.Fab")
		)
		(fp_line
			(start 0.67945 -0.3048)
			(end 0.67945 0.3048)
			(stroke
				(width 0.1)
				(type default)
			)
			(layer "F.Fab")
		)
		(fp_line
			(start 0.67945 0.3048)
			(end 0.120396 0.3048)
			(stroke
				(width 0.1)
				(type default)
			)
			(layer "F.Fab")
		)
		(pad "1" smd circle
			(at -0.40005 0)
			(size 0 0)
			(layers "F.Cu" "F.Mask" "F.Paste")
			(net "SMB_2_BMC_GPU_SDA")
		)
		(pad "2" smd circle
			(at 0.40005 0)
			(size 0 0)
			(layers "F.Cu" "F.Mask" "F.Paste")
			(net "SMB_2_BMC_GPU_R_SDA")
		)
	)
	(footprint ""
		(layer "F.Cu")
		(at 204.994764 -96.77908)
		(property "Reference" "R1133"
			(at 0 0 0)
			(layer "F.SilkS")
			(hide yes)
			(effects
				(font
					(size 1.27 1.27)
				)
			)
		)
		(property "Value" ""
			(at 0 0 0)
			(layer "F.Fab")
			(effects
				(font
					(size 1.27 1.27)
				)
			)
		)
		(duplicate_pad_numbers_are_jumpers no)
		(fp_line
			(start -0.7874 -0.4064)
			(end 0.7874 -0.4064)
			(stroke
				(width 0.1524)
				(type default)
			)
			(layer "F.SilkS")
		)
		(fp_line
			(start -0.7874 0.4064)
			(end -0.7874 -0.4064)
			(stroke
				(width 0.1524)
				(type default)
			)
			(layer "F.SilkS")
		)
		(fp_line
			(start 0.7874 -0.4064)
			(end 0.7874 0.4064)
			(stroke
				(width 0.1524)
				(type default)
			)
			(layer "F.SilkS")
		)
		(fp_line
			(start 0.7874 0.4064)
			(end -0.7874 0.4064)
			(stroke
				(width 0.1524)
				(type default)
			)
			(layer "F.SilkS")
		)
		(fp_line
			(start -0.67945 -0.305054)
			(end -0.12065 -0.305054)
			(stroke
				(width 0.1)
				(type default)
			)
			(layer "F.Fab")
		)
		(fp_line
			(start -0.67945 0.3048)
			(end -0.67945 -0.305054)
			(stroke
				(width 0.1)
				(type default)
			)
			(layer "F.Fab")
		)
		(fp_line
			(start -0.12065 -0.305054)
			(end -0.12065 -0.2794)
			(stroke
				(width 0.1)
				(type default)
			)
			(layer "F.Fab")
		)
		(fp_line
			(start -0.12065 -0.2794)
			(end 0.12065 -0.2794)
			(stroke
				(width 0.1)
				(type default)
			)
			(layer "F.Fab")
		)
		(fp_line
			(start -0.12065 0.2794)
			(end -0.12065 0.3048)
			(stroke
				(width 0.1)
				(type default)
			)
			(layer "F.Fab")
		)
		(fp_line
			(start -0.12065 0.3048)
			(end -0.67945 0.3048)
			(stroke
				(width 0.1)
				(type default)
			)
			(layer "F.Fab")
		)
		(fp_line
			(start 0.120396 0.2794)
			(end -0.12065 0.2794)
			(stroke
				(width 0.1)
				(type default)
			)
			(layer "F.Fab")
		)
		(fp_line
			(start 0.120396 0.3048)
			(end 0.120396 0.2794)
			(stroke
				(width 0.1)
				(type default)
			)
			(layer "F.Fab")
		)
		(fp_line
			(start 0.12065 -0.3048)
			(end 0.67945 -0.3048)
			(stroke
				(width 0.1)
				(type default)
			)
			(layer "F.Fab")
		)
		(fp_line
			(start 0.12065 -0.2794)
			(end 0.12065 -0.3048)
			(stroke
				(width 0.1)
				(type default)
			)
			(layer "F.Fab")
		)
		(fp_line
			(start 0.67945 -0.3048)
			(end 0.67945 0.3048)
			(stroke
				(width 0.1)
				(type default)
			)
			(layer "F.Fab")
		)
		(fp_line
			(start 0.67945 0.3048)
			(end 0.120396 0.3048)
			(stroke
				(width 0.1)
				(type default)
			)
			(layer "F.Fab")
		)
		(pad "1" smd circle
			(at -0.40005 0)
			(size 0 0)
			(layers "F.Cu" "F.Mask" "F.Paste")
			(net "P3V3_AUX")
		)
		(pad "2" smd circle
			(at 0.40005 0)
			(size 0 0)
			(layers "F.Cu" "F.Mask" "F.Paste")
			(net "P12V_OCP_V3_1_PLD_PWRGD")
		)
	)
	(footprint ""
		(layer "F.Cu")
		(at 216.18575 -43.738292 180)
		(property "Reference" "U279"
			(at 0.6731 2.330704 0)
			(unlocked yes)
			(layer "F.SilkS")
			(effects
				(font
					(size 0.7874 0.5842)
					(thickness 0.1524)
				)
				(justify left)
			)
		)
		(property "Value" ""
			(at 0 0 180)
			(layer "F.Fab")
			(effects
				(font
					(size 1.27 1.27)
				)
			)
		)
		(duplicate_pad_numbers_are_jumpers no)
		(fp_line
			(start 1.463548 1.549908)
			(end -1.463548 1.549908)
			(stroke
				(width 0.1524)
				(type default)
			)
			(layer "F.SilkS")
		)
		(fp_line
			(start 1.463548 -1.549908)
			(end 1.463548 1.549908)
			(stroke
				(width 0.1524)
				(type default)
			)
			(layer "F.SilkS")
		)
		(fp_line
			(start 0.762 -1.549908)
			(end 1.463548 -1.549908)
			(stroke
				(width 0.1524)
				(type default)
			)
			(layer "F.SilkS")
		)
		(fp_line
			(start 0 -0.762)
			(end 0.762 -1.549908)
			(stroke
				(width 0.1524)
				(type default)
			)
			(layer "F.SilkS")
		)
		(fp_line
			(start -0.787908 -1.549908)
			(end 0 -0.762)
			(stroke
				(width 0.1524)
				(type default)
			)
			(layer "F.SilkS")
		)
		(fp_line
			(start -1.463548 1.549908)
			(end -1.463548 -1.549908)
			(stroke
				(width 0.1524)
				(type default)
			)
			(layer "F.SilkS")
		)
		(fp_line
			(start -1.463548 -1.549908)
			(end -0.787908 -1.549908)
			(stroke
				(width 0.1524)
				(type default)
			)
			(layer "F.SilkS")
		)
		(fp_poly
			(pts
				(xy -2.453386 -2.164842) (xy -1.833626 -2.164842) (xy -2.143506 -1.545082)
			)
			(stroke
				(width 0)
				(type default)
			)
			(fill yes)
			(layer "F.SilkS")
		)
		(fp_line
			(start 1.549908 1.549908)
			(end -1.549908 1.549908)
			(stroke
				(width 0.1)
				(type default)
			)
			(layer "F.Fab")
		)
		(fp_line
			(start 1.549908 -1.549908)
			(end 1.549908 1.549908)
			(stroke
				(width 0.1)
				(type default)
			)
			(layer "F.Fab")
		)
		(fp_line
			(start -1.549908 1.549908)
			(end -1.549908 -1.549908)
			(stroke
				(width 0.1)
				(type default)
			)
			(layer "F.Fab")
		)
		(fp_line
			(start -1.549908 -1.549908)
			(end 1.549908 -1.549908)
			(stroke
				(width 0.1)
				(type default)
			)
			(layer "F.Fab")
		)
		(fp_poly
			(pts
				(xy -3.4798 -1.359916) (xy -2.86004 -1.050036) (xy -3.4798 -0.740156)
			)
			(stroke
				(width 0)
				(type default)
			)
			(fill yes)
			(layer "F.Fab")
		)
		(pad "1" smd rect
			(at -2.175002 -1.050036 270)
			(size 0.6096 1.1684)
			(layers "F.Cu" "F.Mask" "F.Paste")
			(net "P3V3_E1S_0")
		)
		(pad "2" smd rect
			(at -2.175002 -0.32512 270)
			(size 0.4318 1.1684)
			(layers "F.Cu" "F.Mask" "F.Paste")
			(net "SMB_E1S_3V3AUX_ISO_SCL_R")
		)
		(pad "3" smd rect
			(at -2.175002 0.32512 270)
			(size 0.4318 1.1684)
			(layers "F.Cu" "F.Mask" "F.Paste")
			(net "SMB_E1S_3V3AUX_ISO_SDA_R")
		)
		(pad "4" smd rect
			(at -2.175002 1.050036 270)
			(size 0.6096 1.1684)
			(layers "F.Cu" "F.Mask" "F.Paste")
			(net "GND")
		)
		(pad "5" smd rect
			(at 2.175002 1.050036 270)
			(size 0.6096 1.1684)
			(layers "F.Cu" "F.Mask" "F.Paste")
			(net "SMB_PCIE_E1S_ISO_EN_R")
		)
		(pad "6" smd rect
			(at 2.175002 0.32512 270)
			(size 0.4318 1.1684)
			(layers "F.Cu" "F.Mask" "F.Paste")
			(net "SMB_SENSOR_E1S_3V3AUX_SDA")
		)
		(pad "7" smd rect
			(at 2.175002 -0.32512 270)
			(size 0.4318 1.1684)
			(layers "F.Cu" "F.Mask" "F.Paste")
			(net "SMB_SENSOR_E1S_3V3AUX_SCL")
		)
		(pad "8" smd rect
			(at 2.175002 -1.050036 270)
			(size 0.6096 1.1684)
			(layers "F.Cu" "F.Mask" "F.Paste")
			(net "P3V3_AUX")
		)
	)
	(footprint ""
		(layer "F.Cu")
		(at 314.651898 -331.990954 180)
		(property "Reference" "PC192"
			(at 0 0 180)
			(layer "F.SilkS")
			(hide yes)
			(effects
				(font
					(size 1.27 1.27)
				)
			)
		)
		(property "Value" ""
			(at 0 0 180)
			(layer "F.Fab")
			(effects
				(font
					(size 1.27 1.27)
				)
			)
		)
		(duplicate_pad_numbers_are_jumpers no)
		(fp_line
			(start 0.7874 0.4064)
			(end -0.7874 0.4064)
			(stroke
				(width 0.1524)
				(type default)
			)
			(layer "F.SilkS")
		)
		(fp_line
			(start 0.7874 -0.4064)
			(end 0.7874 0.4064)
			(stroke
				(width 0.1524)
				(type default)
			)
			(layer "F.SilkS")
		)
		(fp_line
			(start -0.7874 0.4064)
			(end -0.7874 -0.4064)
			(stroke
				(width 0.1524)
				(type default)
			)
			(layer "F.SilkS")
		)
		(fp_line
			(start -0.7874 -0.4064)
			(end 0.7874 -0.4064)
			(stroke
				(width 0.1524)
				(type default)
			)
			(layer "F.SilkS")
		)
		(fp_line
			(start 0.67945 0.3048)
			(end 0.120396 0.3048)
			(stroke
				(width 0.1)
				(type default)
			)
			(layer "F.Fab")
		)
		(fp_line
			(start 0.67945 -0.3048)
			(end 0.67945 0.3048)
			(stroke
				(width 0.1)
				(type default)
			)
			(layer "F.Fab")
		)
		(fp_line
			(start 0.12065 -0.2794)
			(end 0.12065 -0.3048)
			(stroke
				(width 0.1)
				(type default)
			)
			(layer "F.Fab")
		)
		(fp_line
			(start 0.12065 -0.3048)
			(end 0.67945 -0.3048)
			(stroke
				(width 0.1)
				(type default)
			)
			(layer "F.Fab")
		)
		(fp_line
			(start 0.120396 0.3048)
			(end 0.120396 0.2794)
			(stroke
				(width 0.1)
				(type default)
			)
			(layer "F.Fab")
		)
		(fp_line
			(start 0.120396 0.2794)
			(end -0.12065 0.2794)
			(stroke
				(width 0.1)
				(type default)
			)
			(layer "F.Fab")
		)
		(fp_line
			(start -0.12065 0.3048)
			(end -0.67945 0.3048)
			(stroke
				(width 0.1)
				(type default)
			)
			(layer "F.Fab")
		)
		(fp_line
			(start -0.12065 0.2794)
			(end -0.12065 0.3048)
			(stroke
				(width 0.1)
				(type default)
			)
			(layer "F.Fab")
		)
		(fp_line
			(start -0.12065 -0.2794)
			(end 0.12065 -0.2794)
			(stroke
				(width 0.1)
				(type default)
			)
			(layer "F.Fab")
		)
		(fp_line
			(start -0.12065 -0.305054)
			(end -0.12065 -0.2794)
			(stroke
				(width 0.1)
				(type default)
			)
			(layer "F.Fab")
		)
		(fp_line
			(start -0.67945 0.3048)
			(end -0.67945 -0.305054)
			(stroke
				(width 0.1)
				(type default)
			)
			(layer "F.Fab")
		)
		(fp_line
			(start -0.67945 -0.305054)
			(end -0.12065 -0.305054)
			(stroke
				(width 0.1)
				(type default)
			)
			(layer "F.Fab")
		)
		(pad "1" smd circle
			(at -0.40005 0 180)
			(size 0 0)
			(layers "F.Cu" "F.Mask" "F.Paste")
			(net "SW_PVDDCR_CPU1_P0_SW3")
		)
		(pad "2" smd circle
			(at 0.40005 0 180)
			(size 0 0)
			(layers "F.Cu" "F.Mask" "F.Paste")
			(net "SW_PVDDCR_CPU1_P0_SW3_RC")
		)
	)
	(footprint ""
		(layer "F.Cu")
		(at 325.862188 -393.47648 180)
		(property "Reference" "R951"
			(at 0 0 180)
			(layer "F.SilkS")
			(hide yes)
			(effects
				(font
					(size 1.27 1.27)
				)
			)
		)
		(property "Value" ""
			(at 0 0 180)
			(layer "F.Fab")
			(effects
				(font
					(size 1.27 1.27)
				)
			)
		)
		(duplicate_pad_numbers_are_jumpers no)
		(fp_line
			(start 0.7874 0.4064)
			(end -0.7874 0.4064)
			(stroke
				(width 0.1524)
				(type default)
			)
			(layer "F.SilkS")
		)
		(fp_line
			(start 0.7874 -0.4064)
			(end 0.7874 0.4064)
			(stroke
				(width 0.1524)
				(type default)
			)
			(layer "F.SilkS")
		)
		(fp_line
			(start -0.7874 0.4064)
			(end -0.7874 -0.4064)
			(stroke
				(width 0.1524)
				(type default)
			)
			(layer "F.SilkS")
		)
		(fp_line
			(start -0.7874 -0.4064)
			(end 0.7874 -0.4064)
			(stroke
				(width 0.1524)
				(type default)
			)
			(layer "F.SilkS")
		)
		(fp_line
			(start 0.67945 0.3048)
			(end 0.120396 0.3048)
			(stroke
				(width 0.1)
				(type default)
			)
			(layer "F.Fab")
		)
		(fp_line
			(start 0.67945 -0.3048)
			(end 0.67945 0.3048)
			(stroke
				(width 0.1)
				(type default)
			)
			(layer "F.Fab")
		)
		(fp_line
			(start 0.12065 -0.2794)
			(end 0.12065 -0.3048)
			(stroke
				(width 0.1)
				(type default)
			)
			(layer "F.Fab")
		)
		(fp_line
			(start 0.12065 -0.3048)
			(end 0.67945 -0.3048)
			(stroke
				(width 0.1)
				(type default)
			)
			(layer "F.Fab")
		)
		(fp_line
			(start 0.120396 0.3048)
			(end 0.120396 0.2794)
			(stroke
				(width 0.1)
				(type default)
			)
			(layer "F.Fab")
		)
		(fp_line
			(start 0.120396 0.2794)
			(end -0.12065 0.2794)
			(stroke
				(width 0.1)
				(type default)
			)
			(layer "F.Fab")
		)
		(fp_line
			(start -0.12065 0.3048)
			(end -0.67945 0.3048)
			(stroke
				(width 0.1)
				(type default)
			)
			(layer "F.Fab")
		)
		(fp_line
			(start -0.12065 0.2794)
			(end -0.12065 0.3048)
			(stroke
				(width 0.1)
				(type default)
			)
			(layer "F.Fab")
		)
		(fp_line
			(start -0.12065 -0.2794)
			(end 0.12065 -0.2794)
			(stroke
				(width 0.1)
				(type default)
			)
			(layer "F.Fab")
		)
		(fp_line
			(start -0.12065 -0.305054)
			(end -0.12065 -0.2794)
			(stroke
				(width 0.1)
				(type default)
			)
			(layer "F.Fab")
		)
		(fp_line
			(start -0.67945 0.3048)
			(end -0.67945 -0.305054)
			(stroke
				(width 0.1)
				(type default)
			)
			(layer "F.Fab")
		)
		(fp_line
			(start -0.67945 -0.305054)
			(end -0.12065 -0.305054)
			(stroke
				(width 0.1)
				(type default)
			)
			(layer "F.Fab")
		)
		(pad "1" smd rect
			(at -0.40005 0)
			(size 0.4572 0.508)
			(layers "F.Cu" "F.Mask" "F.Paste")
			(net "P1V8_CPU0_RT0_1A_1D")
		)
		(pad "2" smd rect
			(at 0.40005 0)
			(size 0.4572 0.508)
			(layers "F.Cu" "F.Mask" "F.Paste")
			(net "P1V8_CPU0_RT0_1A")
		)
	)
	(footprint ""
		(layer "F.Cu")
		(at 357.517192 -261.747762 -90)
		(property "Reference" "C2601"
			(at 0 0 270)
			(layer "F.SilkS")
			(hide yes)
			(effects
				(font
					(size 1.27 1.27)
				)
			)
		)
		(property "Value" ""
			(at 0 0 270)
			(layer "F.Fab")
			(effects
				(font
					(size 1.27 1.27)
				)
			)
		)
		(duplicate_pad_numbers_are_jumpers no)
		(fp_line
			(start -0.7874 0.4064)
			(end -0.7874 -0.4064)
			(stroke
				(width 0.1524)
				(type default)
			)
			(layer "F.SilkS")
		)
		(fp_line
			(start 0.7874 0.4064)
			(end -0.7874 0.4064)
			(stroke
				(width 0.1524)
				(type default)
			)
			(layer "F.SilkS")
		)
		(fp_line
			(start -0.7874 -0.4064)
			(end 0.7874 -0.4064)
			(stroke
				(width 0.1524)
				(type default)
			)
			(layer "F.SilkS")
		)
		(fp_line
			(start 0.7874 -0.4064)
			(end 0.7874 0.4064)
			(stroke
				(width 0.1524)
				(type default)
			)
			(layer "F.SilkS")
		)
		(fp_line
			(start -0.67945 0.3048)
			(end -0.67945 -0.305054)
			(stroke
				(width 0.1)
				(type default)
			)
			(layer "F.Fab")
		)
		(fp_line
			(start -0.12065 0.3048)
			(end -0.67945 0.3048)
			(stroke
				(width 0.1)
				(type default)
			)
			(layer "F.Fab")
		)
		(fp_line
			(start 0.120396 0.3048)
			(end 0.120396 0.2794)
			(stroke
				(width 0.1)
				(type default)
			)
			(layer "F.Fab")
		)
		(fp_line
			(start 0.67945 0.3048)
			(end 0.120396 0.3048)
			(stroke
				(width 0.1)
				(type default)
			)
			(layer "F.Fab")
		)
		(fp_line
			(start -0.12065 0.2794)
			(end -0.12065 0.3048)
			(stroke
				(width 0.1)
				(type default)
			)
			(layer "F.Fab")
		)
		(fp_line
			(start 0.120396 0.2794)
			(end -0.12065 0.2794)
			(stroke
				(width 0.1)
				(type default)
			)
			(layer "F.Fab")
		)
		(fp_line
			(start -0.12065 -0.2794)
			(end 0.12065 -0.2794)
			(stroke
				(width 0.1)
				(type default)
			)
			(layer "F.Fab")
		)
		(fp_line
			(start 0.12065 -0.2794)
			(end 0.12065 -0.3048)
			(stroke
				(width 0.1)
				(type default)
			)
			(layer "F.Fab")
		)
		(fp_line
			(start 0.12065 -0.3048)
			(end 0.67945 -0.3048)
			(stroke
				(width 0.1)
				(type default)
			)
			(layer "F.Fab")
		)
		(fp_line
			(start 0.67945 -0.3048)
			(end 0.67945 0.3048)
			(stroke
				(width 0.1)
				(type default)
			)
			(layer "F.Fab")
		)
		(fp_line
			(start -0.67945 -0.305054)
			(end -0.12065 -0.305054)
			(stroke
				(width 0.1)
				(type default)
			)
			(layer "F.Fab")
		)
		(fp_line
			(start -0.12065 -0.305054)
			(end -0.12065 -0.2794)
			(stroke
				(width 0.1)
				(type default)
			)
			(layer "F.Fab")
		)
		(pad "1" smd circle
			(at -0.40005 0 270)
			(size 0 0)
			(layers "F.Cu" "F.Mask" "F.Paste")
			(net "PVDD11_S3_P0")
		)
		(pad "2" smd circle
			(at 0.40005 0 270)
			(size 0 0)
			(layers "F.Cu" "F.Mask" "F.Paste")
			(net "GND")
		)
	)
	(footprint ""
		(layer "F.Cu")
		(at 189.357 -51.054 90)
		(property "Reference" "R8031"
			(at 0 0 90)
			(layer "F.SilkS")
			(hide yes)
			(effects
				(font
					(size 1.27 1.27)
				)
			)
		)
		(property "Value" ""
			(at 0 0 90)
			(layer "F.Fab")
			(effects
				(font
					(size 1.27 1.27)
				)
			)
		)
		(duplicate_pad_numbers_are_jumpers no)
		(fp_line
			(start 0.7874 -0.4064)
			(end 0.7874 0.4064)
			(stroke
				(width 0.1524)
				(type default)
			)
			(layer "F.SilkS")
		)
		(fp_line
			(start -0.7874 -0.4064)
			(end 0.7874 -0.4064)
			(stroke
				(width 0.1524)
				(type default)
			)
			(layer "F.SilkS")
		)
		(fp_line
			(start 0.7874 0.4064)
			(end -0.7874 0.4064)
			(stroke
				(width 0.1524)
				(type default)
			)
			(layer "F.SilkS")
		)
		(fp_line
			(start -0.7874 0.4064)
			(end -0.7874 -0.4064)
			(stroke
				(width 0.1524)
				(type default)
			)
			(layer "F.SilkS")
		)
		(fp_line
			(start -0.12065 -0.305054)
			(end -0.12065 -0.2794)
			(stroke
				(width 0.1)
				(type default)
			)
			(layer "F.Fab")
		)
		(fp_line
			(start -0.67945 -0.305054)
			(end -0.12065 -0.305054)
			(stroke
				(width 0.1)
				(type default)
			)
			(layer "F.Fab")
		)
		(fp_line
			(start 0.67945 -0.3048)
			(end 0.67945 0.3048)
			(stroke
				(width 0.1)
				(type default)
			)
			(layer "F.Fab")
		)
		(fp_line
			(start 0.12065 -0.3048)
			(end 0.67945 -0.3048)
			(stroke
				(width 0.1)
				(type default)
			)
			(layer "F.Fab")
		)
		(fp_line
			(start 0.12065 -0.2794)
			(end 0.12065 -0.3048)
			(stroke
				(width 0.1)
				(type default)
			)
			(layer "F.Fab")
		)
		(fp_line
			(start -0.12065 -0.2794)
			(end 0.12065 -0.2794)
			(stroke
				(width 0.1)
				(type default)
			)
			(layer "F.Fab")
		)
		(fp_line
			(start 0.120396 0.2794)
			(end -0.12065 0.2794)
			(stroke
				(width 0.1)
				(type default)
			)
			(layer "F.Fab")
		)
		(fp_line
			(start -0.12065 0.2794)
			(end -0.12065 0.3048)
			(stroke
				(width 0.1)
				(type default)
			)
			(layer "F.Fab")
		)
		(fp_line
			(start 0.67945 0.3048)
			(end 0.120396 0.3048)
			(stroke
				(width 0.1)
				(type default)
			)
			(layer "F.Fab")
		)
		(fp_line
			(start 0.120396 0.3048)
			(end 0.120396 0.2794)
			(stroke
				(width 0.1)
				(type default)
			)
			(layer "F.Fab")
		)
		(fp_line
			(start -0.12065 0.3048)
			(end -0.67945 0.3048)
			(stroke
				(width 0.1)
				(type default)
			)
			(layer "F.Fab")
		)
		(fp_line
			(start -0.67945 0.3048)
			(end -0.67945 -0.305054)
			(stroke
				(width 0.1)
				(type default)
			)
			(layer "F.Fab")
		)
		(pad "1" smd circle
			(at -0.40005 0 90)
			(size 0 0)
			(layers "F.Cu" "F.Mask" "F.Paste")
			(net "P12V_SCM_FLTB_N")
		)
		(pad "2" smd circle
			(at 0.40005 0 90)
			(size 0 0)
			(layers "F.Cu" "F.Mask" "F.Paste")
			(net "P12V_SCM_FAULT_R_N")
		)
	)
	(footprint ""
		(layer "F.Cu")
		(at 396.250668 -400.903694)
		(property "Reference" "L21"
			(at -3.06197 -1.343914 90)
			(unlocked yes)
			(layer "F.SilkS")
			(effects
				(font
					(size 0.7874 0.5842)
					(thickness 0.1524)
				)
				(justify left)
			)
		)
		(property "Value" ""
			(at 0 0 0)
			(layer "F.Fab")
			(effects
				(font
					(size 1.27 1.27)
				)
			)
		)
		(duplicate_pad_numbers_are_jumpers no)
		(fp_line
			(start -2.249932 -2.249932)
			(end 2.249932 -2.249932)
			(stroke
				(width 0.1524)
				(type default)
			)
			(layer "F.SilkS")
		)
		(fp_line
			(start -2.249932 -1.3843)
			(end -2.249932 -2.249932)
			(stroke
				(width 0.1524)
				(type default)
			)
			(layer "F.SilkS")
		)
		(fp_line
			(start -2.249932 2.249932)
			(end -2.249932 1.3843)
			(stroke
				(width 0.1524)
				(type default)
			)
			(layer "F.SilkS")
		)
		(fp_line
			(start 2.249932 -2.249932)
			(end 2.249932 -1.3843)
			(stroke
				(width 0.1524)
				(type default)
			)
			(layer "F.SilkS")
		)
		(fp_line
			(start 2.249932 1.3843)
			(end 2.249932 2.249932)
			(stroke
				(width 0.1524)
				(type default)
			)
			(layer "F.SilkS")
		)
		(fp_line
			(start 2.249932 2.249932)
			(end -2.249932 2.249932)
			(stroke
				(width 0.1524)
				(type default)
			)
			(layer "F.SilkS")
		)
		(fp_line
			(start -2.249932 -2.249932)
			(end 2.249932 -2.249932)
			(stroke
				(width 0.1)
				(type default)
			)
			(layer "F.Fab")
		)
		(fp_line
			(start -2.249932 2.249932)
			(end -2.249932 -2.249932)
			(stroke
				(width 0.1)
				(type default)
			)
			(layer "F.Fab")
		)
		(fp_line
			(start 2.249932 -2.249932)
			(end 2.249932 2.249932)
			(stroke
				(width 0.1)
				(type default)
			)
			(layer "F.Fab")
		)
		(fp_line
			(start 2.249932 2.249932)
			(end -2.249932 2.249932)
			(stroke
				(width 0.1)
				(type default)
			)
			(layer "F.Fab")
		)
		(pad "1" smd rect
			(at -1.82499 0)
			(size 1.0668 2.5146)
			(layers "F.Cu" "F.Mask" "F.Paste")
			(net "P0V9_CPU0_RT_2D")
		)
		(pad "2" smd rect
			(at 1.82499 0)
			(size 1.0668 2.5146)
			(layers "F.Cu" "F.Mask" "F.Paste")
			(net "P0V9_CPU0_RT2_2A")
		)
	)
	(footprint ""
		(layer "F.Cu")
		(at 290.890198 -395.231366 90)
		(property "Reference" "U48"
			(at 0.91948 3.869182 90)
			(unlocked yes)
			(layer "F.SilkS")
			(effects
				(font
					(size 0.7874 0.5842)
					(thickness 0.1524)
				)
			)
		)
		(property "Value" ""
			(at 0 0 90)
			(layer "F.Fab")
			(effects
				(font
					(size 1.27 1.27)
				)
			)
		)
		(duplicate_pad_numbers_are_jumpers no)
		(fp_line
			(start 1.03378 -1.284478)
			(end 1.03378 1.284478)
			(stroke
				(width 0.1524)
				(type default)
			)
			(layer "F.SilkS")
		)
		(fp_line
			(start -1.03378 -1.284478)
			(end 1.03378 -1.284478)
			(stroke
				(width 0.1524)
				(type default)
			)
			(layer "F.SilkS")
		)
		(fp_line
			(start 1.03378 1.284478)
			(end -1.03378 1.284478)
			(stroke
				(width 0.1524)
				(type default)
			)
			(layer "F.SilkS")
		)
		(fp_line
			(start -1.03378 1.284478)
			(end -1.03378 -1.284478)
			(stroke
				(width 0.1524)
				(type default)
			)
			(layer "F.SilkS")
		)
		(fp_poly
			(pts
				(xy -1.23952 -1.219454) (xy -1.894586 -1.387602) (xy -1.498092 -1.844548)
			)
			(stroke
				(width 0)
				(type default)
			)
			(fill yes)
			(layer "F.SilkS")
		)
		(fp_line
			(start 0.774954 -1.02489)
			(end 0.774954 1.02489)
			(stroke
				(width 0.1)
				(type default)
			)
			(layer "F.Fab")
		)
		(fp_line
			(start -0.774954 -1.02489)
			(end 0.774954 -1.02489)
			(stroke
				(width 0.1)
				(type default)
			)
			(layer "F.Fab")
		)
		(fp_line
			(start 0.774954 1.02489)
			(end -0.774954 1.02489)
			(stroke
				(width 0.1)
				(type default)
			)
			(layer "F.Fab")
		)
		(fp_line
			(start -0.774954 1.02489)
			(end -0.774954 -1.02489)
			(stroke
				(width 0.1)
				(type default)
			)
			(layer "F.Fab")
		)
		(fp_poly
			(pts
				(xy -1.201674 -0.750062) (xy -1.806702 -0.447548) (xy -1.806702 -1.052576)
			)
			(stroke
				(width 0)
				(type default)
			)
			(fill yes)
			(layer "F.Fab")
		)
		(pad "1" smd rect
			(at -0.64008 -0.750062 180)
			(size 0.3048 0.5334)
			(layers "F.Cu" "F.Mask" "F.Paste")
			(net "SMB_RT_CPU0_P1_ROM_MUX_1D_SCL")
		)
		(pad "2" smd rect
			(at -0.64008 -0.249936 180)
			(size 0.254 0.5334)
			(layers "F.Cu" "F.Mask" "F.Paste")
			(net "SMB_RT_CPU0_P1_ROM_MUX_1D_SDA")
		)
		(pad "3" smd rect
			(at -0.64008 0.249936 180)
			(size 0.254 0.5334)
			(layers "F.Cu" "F.Mask" "F.Paste")
			(net "SMB_RT_CPU0_P1_ROM_MUX_2D_SCL")
		)
		(pad "4" smd rect
			(at -0.64008 0.750062 180)
			(size 0.3048 0.5334)
			(layers "F.Cu" "F.Mask" "F.Paste")
			(net "SMB_RT_CPU0_P1_ROM_MUX_2D_SDA")
		)
		(pad "5" smd rect
			(at 0 0.839978 90)
			(size 0.3302 0.635)
			(layers "F.Cu" "F.Mask" "F.Paste")
			(net "GND")
		)
		(pad "6" smd rect
			(at 0.64008 0.750062 180)
			(size 0.3048 0.5334)
			(layers "F.Cu" "F.Mask" "F.Paste")
			(net "RT_ROM_MUX6_OE_N")
		)
		(pad "7" smd rect
			(at 0.64008 0.249936 180)
			(size 0.254 0.5334)
			(layers "F.Cu" "F.Mask" "F.Paste")
			(net "SMB_RT_CPU0_P1_ROM_R_SDA")
		)
		(pad "8" smd rect
			(at 0.64008 -0.249936 180)
			(size 0.254 0.5334)
			(layers "F.Cu" "F.Mask" "F.Paste")
			(net "SMB_RT_CPU0_P1_ROM_R_SCL")
		)
		(pad "9" smd rect
			(at 0.64008 -0.750062 180)
			(size 0.3048 0.5334)
			(layers "F.Cu" "F.Mask" "F.Paste")
			(net "FM_SMB_RT_ROM_MUX6_SEL")
		)
		(pad "10" smd rect
			(at 0 -0.839978 90)
			(size 0.3302 0.635)
			(layers "F.Cu" "F.Mask" "F.Paste")
			(net "P3V3_AUX")
		)
	)
	(footprint ""
		(layer "F.Cu")
		(at 369.330478 -159.907732 -90)
		(property "Reference" "PL53"
			(at -0.072136 3.778504 90)
			(unlocked yes)
			(layer "F.SilkS")
			(effects
				(font
					(size 0.7874 0.5842)
					(thickness 0.1524)
				)
				(justify left)
			)
		)
		(property "Value" ""
			(at 0 0 270)
			(layer "F.Fab")
			(effects
				(font
					(size 1.27 1.27)
				)
			)
		)
		(duplicate_pad_numbers_are_jumpers no)
		(fp_line
			(start -3.050032 2.999994)
			(end 3.050032 2.999994)
			(stroke
				(width 0.1524)
				(type default)
			)
			(layer "F.SilkS")
		)
		(fp_line
			(start 3.050032 2.999994)
			(end 3.050032 1.4478)
			(stroke
				(width 0.1524)
				(type default)
			)
			(layer "F.SilkS")
		)
		(fp_line
			(start -3.050032 1.4478)
			(end -3.050032 2.999994)
			(stroke
				(width 0.1524)
				(type default)
			)
			(layer "F.SilkS")
		)
		(fp_line
			(start 3.050032 -1.4478)
			(end 3.050032 -2.999994)
			(stroke
				(width 0.1524)
				(type default)
			)
			(layer "F.SilkS")
		)
		(fp_line
			(start -3.050032 -2.999994)
			(end -3.050032 -1.4478)
			(stroke
				(width 0.1524)
				(type default)
			)
			(layer "F.SilkS")
		)
		(fp_line
			(start 3.050032 -2.999994)
			(end -3.050032 -2.999994)
			(stroke
				(width 0.1524)
				(type default)
			)
			(layer "F.SilkS")
		)
		(fp_line
			(start -3.050032 2.999994)
			(end 3.050032 2.999994)
			(stroke
				(width 0.1)
				(type default)
			)
			(layer "F.Fab")
		)
		(fp_line
			(start 3.050032 2.999994)
			(end 3.050032 -2.999994)
			(stroke
				(width 0.1)
				(type default)
			)
			(layer "F.Fab")
		)
		(fp_line
			(start -3.050032 -2.999994)
			(end -3.050032 2.999994)
			(stroke
				(width 0.1)
				(type default)
			)
			(layer "F.Fab")
		)
		(fp_line
			(start 3.050032 -2.999994)
			(end -3.050032 -2.999994)
			(stroke
				(width 0.1)
				(type default)
			)
			(layer "F.Fab")
		)
		(pad "1" smd rect
			(at -2.525014 0 270)
			(size 1.651 2.6162)
			(layers "F.Cu" "F.Mask" "F.Paste")
			(net "SW_P12V_AUX_PVDDCR_CPU0_P0_FLT")
		)
		(pad "2" smd rect
			(at 2.525014 0 270)
			(size 1.651 2.6162)
			(layers "F.Cu" "F.Mask" "F.Paste")
			(net "P12V_AUX")
		)
	)
	(footprint ""
		(layer "F.Cu")
		(at 405.388572 -163.942014 -90)
		(property "Reference" "PR361"
			(at 0 0 270)
			(layer "F.SilkS")
			(hide yes)
			(effects
				(font
					(size 1.27 1.27)
				)
			)
		)
		(property "Value" ""
			(at 0 0 270)
			(layer "F.Fab")
			(effects
				(font
					(size 1.27 1.27)
				)
			)
		)
		(duplicate_pad_numbers_are_jumpers no)
		(fp_line
			(start -0.7874 0.4064)
			(end -0.7874 -0.4064)
			(stroke
				(width 0.1524)
				(type default)
			)
			(layer "F.SilkS")
		)
		(fp_line
			(start 0.7874 0.4064)
			(end -0.7874 0.4064)
			(stroke
				(width 0.1524)
				(type default)
			)
			(layer "F.SilkS")
		)
		(fp_line
			(start -0.7874 -0.4064)
			(end 0.7874 -0.4064)
			(stroke
				(width 0.1524)
				(type default)
			)
			(layer "F.SilkS")
		)
		(fp_line
			(start 0.7874 -0.4064)
			(end 0.7874 0.4064)
			(stroke
				(width 0.1524)
				(type default)
			)
			(layer "F.SilkS")
		)
		(fp_line
			(start -0.67945 0.3048)
			(end -0.67945 -0.305054)
			(stroke
				(width 0.1)
				(type default)
			)
			(layer "F.Fab")
		)
		(fp_line
			(start -0.12065 0.3048)
			(end -0.67945 0.3048)
			(stroke
				(width 0.1)
				(type default)
			)
			(layer "F.Fab")
		)
		(fp_line
			(start 0.120396 0.3048)
			(end 0.120396 0.2794)
			(stroke
				(width 0.1)
				(type default)
			)
			(layer "F.Fab")
		)
		(fp_line
			(start 0.67945 0.3048)
			(end 0.120396 0.3048)
			(stroke
				(width 0.1)
				(type default)
			)
			(layer "F.Fab")
		)
		(fp_line
			(start -0.12065 0.2794)
			(end -0.12065 0.3048)
			(stroke
				(width 0.1)
				(type default)
			)
			(layer "F.Fab")
		)
		(fp_line
			(start 0.120396 0.2794)
			(end -0.12065 0.2794)
			(stroke
				(width 0.1)
				(type default)
			)
			(layer "F.Fab")
		)
		(fp_line
			(start -0.12065 -0.2794)
			(end 0.12065 -0.2794)
			(stroke
				(width 0.1)
				(type default)
			)
			(layer "F.Fab")
		)
		(fp_line
			(start 0.12065 -0.2794)
			(end 0.12065 -0.3048)
			(stroke
				(width 0.1)
				(type default)
			)
			(layer "F.Fab")
		)
		(fp_line
			(start 0.12065 -0.3048)
			(end 0.67945 -0.3048)
			(stroke
				(width 0.1)
				(type default)
			)
			(layer "F.Fab")
		)
		(fp_line
			(start 0.67945 -0.3048)
			(end 0.67945 0.3048)
			(stroke
				(width 0.1)
				(type default)
			)
			(layer "F.Fab")
		)
		(fp_line
			(start -0.67945 -0.305054)
			(end -0.12065 -0.305054)
			(stroke
				(width 0.1)
				(type default)
			)
			(layer "F.Fab")
		)
		(fp_line
			(start -0.12065 -0.305054)
			(end -0.12065 -0.2794)
			(stroke
				(width 0.1)
				(type default)
			)
			(layer "F.Fab")
		)
		(pad "1" smd circle
			(at -0.40005 0 270)
			(size 0 0)
			(layers "F.Cu" "F.Mask" "F.Paste")
			(net "SW_PVDDCR_SOC_P0_BOOT2")
		)
		(pad "2" smd circle
			(at 0.40005 0 270)
			(size 0 0)
			(layers "F.Cu" "F.Mask" "F.Paste")
			(net "SW_PVDDCR_SOC_P0_BOOT2_RC")
		)
	)
	(footprint ""
		(layer "F.Cu")
		(at 358.467152 -261.747762 -90)
		(property "Reference" "C2156"
			(at 0 0 270)
			(layer "F.SilkS")
			(hide yes)
			(effects
				(font
					(size 1.27 1.27)
				)
			)
		)
		(property "Value" ""
			(at 0 0 270)
			(layer "F.Fab")
			(effects
				(font
					(size 1.27 1.27)
				)
			)
		)
		(duplicate_pad_numbers_are_jumpers no)
		(fp_line
			(start -0.7874 0.4064)
			(end -0.7874 -0.4064)
			(stroke
				(width 0.1524)
				(type default)
			)
			(layer "F.SilkS")
		)
		(fp_line
			(start 0.7874 0.4064)
			(end -0.7874 0.4064)
			(stroke
				(width 0.1524)
				(type default)
			)
			(layer "F.SilkS")
		)
		(fp_line
			(start -0.7874 -0.4064)
			(end 0.7874 -0.4064)
			(stroke
				(width 0.1524)
				(type default)
			)
			(layer "F.SilkS")
		)
		(fp_line
			(start 0.7874 -0.4064)
			(end 0.7874 0.4064)
			(stroke
				(width 0.1524)
				(type default)
			)
			(layer "F.SilkS")
		)
		(fp_line
			(start -0.67945 0.3048)
			(end -0.67945 -0.305054)
			(stroke
				(width 0.1)
				(type default)
			)
			(layer "F.Fab")
		)
		(fp_line
			(start -0.12065 0.3048)
			(end -0.67945 0.3048)
			(stroke
				(width 0.1)
				(type default)
			)
			(layer "F.Fab")
		)
		(fp_line
			(start 0.120396 0.3048)
			(end 0.120396 0.2794)
			(stroke
				(width 0.1)
				(type default)
			)
			(layer "F.Fab")
		)
		(fp_line
			(start 0.67945 0.3048)
			(end 0.120396 0.3048)
			(stroke
				(width 0.1)
				(type default)
			)
			(layer "F.Fab")
		)
		(fp_line
			(start -0.12065 0.2794)
			(end -0.12065 0.3048)
			(stroke
				(width 0.1)
				(type default)
			)
			(layer "F.Fab")
		)
		(fp_line
			(start 0.120396 0.2794)
			(end -0.12065 0.2794)
			(stroke
				(width 0.1)
				(type default)
			)
			(layer "F.Fab")
		)
		(fp_line
			(start -0.12065 -0.2794)
			(end 0.12065 -0.2794)
			(stroke
				(width 0.1)
				(type default)
			)
			(layer "F.Fab")
		)
		(fp_line
			(start 0.12065 -0.2794)
			(end 0.12065 -0.3048)
			(stroke
				(width 0.1)
				(type default)
			)
			(layer "F.Fab")
		)
		(fp_line
			(start 0.12065 -0.3048)
			(end 0.67945 -0.3048)
			(stroke
				(width 0.1)
				(type default)
			)
			(layer "F.Fab")
		)
		(fp_line
			(start 0.67945 -0.3048)
			(end 0.67945 0.3048)
			(stroke
				(width 0.1)
				(type default)
			)
			(layer "F.Fab")
		)
		(fp_line
			(start -0.67945 -0.305054)
			(end -0.12065 -0.305054)
			(stroke
				(width 0.1)
				(type default)
			)
			(layer "F.Fab")
		)
		(fp_line
			(start -0.12065 -0.305054)
			(end -0.12065 -0.2794)
			(stroke
				(width 0.1)
				(type default)
			)
			(layer "F.Fab")
		)
		(pad "1" smd circle
			(at -0.40005 0 270)
			(size 0 0)
			(layers "F.Cu" "F.Mask" "F.Paste")
			(net "PVDD11_S3_P0")
		)
		(pad "2" smd circle
			(at 0.40005 0 270)
			(size 0 0)
			(layers "F.Cu" "F.Mask" "F.Paste")
			(net "GND")
		)
	)
	(footprint ""
		(layer "F.Cu")
		(at 102.354126 -412.578296 90)
		(property "Reference" "R6862"
			(at 0 0 90)
			(layer "F.SilkS")
			(hide yes)
			(effects
				(font
					(size 1.27 1.27)
				)
			)
		)
		(property "Value" ""
			(at 0 0 90)
			(layer "F.Fab")
			(effects
				(font
					(size 1.27 1.27)
				)
			)
		)
		(duplicate_pad_numbers_are_jumpers no)
		(fp_line
			(start 0.7874 -0.4064)
			(end 0.7874 0.4064)
			(stroke
				(width 0.1524)
				(type default)
			)
			(layer "F.SilkS")
		)
		(fp_line
			(start -0.7874 -0.4064)
			(end 0.7874 -0.4064)
			(stroke
				(width 0.1524)
				(type default)
			)
			(layer "F.SilkS")
		)
		(fp_line
			(start 0.7874 0.4064)
			(end -0.7874 0.4064)
			(stroke
				(width 0.1524)
				(type default)
			)
			(layer "F.SilkS")
		)
		(fp_line
			(start -0.7874 0.4064)
			(end -0.7874 -0.4064)
			(stroke
				(width 0.1524)
				(type default)
			)
			(layer "F.SilkS")
		)
		(fp_line
			(start -0.12065 -0.305054)
			(end -0.12065 -0.2794)
			(stroke
				(width 0.1)
				(type default)
			)
			(layer "F.Fab")
		)
		(fp_line
			(start -0.67945 -0.305054)
			(end -0.12065 -0.305054)
			(stroke
				(width 0.1)
				(type default)
			)
			(layer "F.Fab")
		)
		(fp_line
			(start 0.67945 -0.3048)
			(end 0.67945 0.3048)
			(stroke
				(width 0.1)
				(type default)
			)
			(layer "F.Fab")
		)
		(fp_line
			(start 0.12065 -0.3048)
			(end 0.67945 -0.3048)
			(stroke
				(width 0.1)
				(type default)
			)
			(layer "F.Fab")
		)
		(fp_line
			(start 0.12065 -0.2794)
			(end 0.12065 -0.3048)
			(stroke
				(width 0.1)
				(type default)
			)
			(layer "F.Fab")
		)
		(fp_line
			(start -0.12065 -0.2794)
			(end 0.12065 -0.2794)
			(stroke
				(width 0.1)
				(type default)
			)
			(layer "F.Fab")
		)
		(fp_line
			(start 0.120396 0.2794)
			(end -0.12065 0.2794)
			(stroke
				(width 0.1)
				(type default)
			)
			(layer "F.Fab")
		)
		(fp_line
			(start -0.12065 0.2794)
			(end -0.12065 0.3048)
			(stroke
				(width 0.1)
				(type default)
			)
			(layer "F.Fab")
		)
		(fp_line
			(start 0.67945 0.3048)
			(end 0.120396 0.3048)
			(stroke
				(width 0.1)
				(type default)
			)
			(layer "F.Fab")
		)
		(fp_line
			(start 0.120396 0.3048)
			(end 0.120396 0.2794)
			(stroke
				(width 0.1)
				(type default)
			)
			(layer "F.Fab")
		)
		(fp_line
			(start -0.12065 0.3048)
			(end -0.67945 0.3048)
			(stroke
				(width 0.1)
				(type default)
			)
			(layer "F.Fab")
		)
		(fp_line
			(start -0.67945 0.3048)
			(end -0.67945 -0.305054)
			(stroke
				(width 0.1)
				(type default)
			)
			(layer "F.Fab")
		)
		(pad "1" smd circle
			(at -0.40005 0 90)
			(size 0 0)
			(layers "F.Cu" "F.Mask" "F.Paste")
			(net "SMB_HOST_CLK_3V3AUX_SCL_R1")
		)
		(pad "2" smd circle
			(at 0.40005 0 90)
			(size 0 0)
			(layers "F.Cu" "F.Mask" "F.Paste")
			(net "SMB_9ZXL045_P1_SCL")
		)
	)
	(footprint ""
		(layer "F.Cu")
		(at 43.543982 -386.684774 -90)
		(property "Reference" "R627"
			(at 0 0 270)
			(layer "F.SilkS")
			(hide yes)
			(effects
				(font
					(size 1.27 1.27)
				)
			)
		)
		(property "Value" ""
			(at 0 0 270)
			(layer "F.Fab")
			(effects
				(font
					(size 1.27 1.27)
				)
			)
		)
		(duplicate_pad_numbers_are_jumpers no)
		(fp_line
			(start -0.32512 0.175006)
			(end -0.32512 -0.175006)
			(stroke
				(width 0.1)
				(type default)
			)
			(layer "F.Fab")
		)
		(fp_line
			(start 0.32512 0.175006)
			(end -0.32512 0.175006)
			(stroke
				(width 0.1)
				(type default)
			)
			(layer "F.Fab")
		)
		(fp_line
			(start -0.32512 -0.175006)
			(end 0.32512 -0.175006)
			(stroke
				(width 0.1)
				(type default)
			)
			(layer "F.Fab")
		)
		(fp_line
			(start 0.32512 -0.175006)
			(end 0.32512 0.175006)
			(stroke
				(width 0.1)
				(type default)
			)
			(layer "F.Fab")
		)
		(pad "1" smd rect
			(at -0.2667 0 270)
			(size 0.3048 0.381)
			(layers "F.Cu" "F.Mask" "F.Paste")
			(net "CLK_100M_RETIMER_CPU1_P0_DN")
		)
		(pad "2" smd rect
			(at 0.2667 0 90)
			(size 0.3048 0.381)
			(layers "F.Cu" "F.Mask" "F.Paste")
			(net "GND")
		)
	)
	(footprint ""
		(layer "F.Cu")
		(at 14.064996 -99.136454 -90)
		(property "Reference" "U268"
			(at -3.448304 -3.957828 0)
			(unlocked yes)
			(layer "F.SilkS")
			(effects
				(font
					(size 0.7874 0.5842)
					(thickness 0.1524)
				)
				(justify left)
			)
		)
		(property "Value" ""
			(at 0 0 270)
			(layer "F.Fab")
			(effects
				(font
					(size 1.27 1.27)
				)
			)
		)
		(duplicate_pad_numbers_are_jumpers no)
		(fp_line
			(start -0.508 2.921)
			(end -0.508 3.683)
			(stroke
				(width 0.1524)
				(type default)
			)
			(layer "F.SilkS")
		)
		(fp_line
			(start -2.500122 2.500122)
			(end -2.500122 1.778)
			(stroke
				(width 0.1524)
				(type default)
			)
			(layer "F.SilkS")
		)
		(fp_line
			(start -1.778 2.500122)
			(end -2.500122 2.500122)
			(stroke
				(width 0.1524)
				(type default)
			)
			(layer "F.SilkS")
		)
		(fp_line
			(start 2.500122 2.500122)
			(end 1.778 2.500122)
			(stroke
				(width 0.1524)
				(type default)
			)
			(layer "F.SilkS")
		)
		(fp_line
			(start 2.500122 1.778)
			(end 2.500122 2.500122)
			(stroke
				(width 0.1524)
				(type default)
			)
			(layer "F.SilkS")
		)
		(fp_line
			(start 2.921 1.524)
			(end 3.302 1.524)
			(stroke
				(width 0.1524)
				(type default)
			)
			(layer "F.SilkS")
		)
		(fp_line
			(start -2.921 0.508)
			(end -3.302 0.508)
			(stroke
				(width 0.1524)
				(type default)
			)
			(layer "F.SilkS")
		)
		(fp_line
			(start 2.921 -1.016)
			(end 3.683 -1.016)
			(stroke
				(width 0.1524)
				(type default)
			)
			(layer "F.SilkS")
		)
		(fp_line
			(start -2.500122 -1.778)
			(end -2.500122 -2.500122)
			(stroke
				(width 0.1524)
				(type default)
			)
			(layer "F.SilkS")
		)
		(fp_line
			(start -2.500122 -2.500122)
			(end -1.778 -2.500122)
			(stroke
				(width 0.1524)
				(type default)
			)
			(layer "F.SilkS")
		)
		(fp_line
			(start 1.778 -2.500122)
			(end 2.500122 -2.500122)
			(stroke
				(width 0.1524)
				(type default)
			)
			(layer "F.SilkS")
		)
		(fp_line
			(start 2.500122 -2.500122)
			(end 2.500122 -1.778)
			(stroke
				(width 0.1524)
				(type default)
			)
			(layer "F.SilkS")
		)
		(fp_line
			(start 0 -2.921)
			(end 0 -3.302)
			(stroke
				(width 0.1524)
				(type default)
			)
			(layer "F.SilkS")
		)
		(fp_poly
			(pts
				(xy -3.016504 -2.991358) (xy -2.71018 -2.07264) (xy -3.629152 -2.37871)
			)
			(stroke
				(width 0)
				(type default)
			)
			(fill yes)
			(layer "F.SilkS")
		)
		(fp_line
			(start -0.508 2.921)
			(end -0.508 3.683)
			(stroke
				(width 0.1)
				(type default)
			)
			(layer "F.Fab")
		)
		(fp_line
			(start -2.500122 2.500122)
			(end -2.500122 -2.500122)
			(stroke
				(width 0.1)
				(type default)
			)
			(layer "F.Fab")
		)
		(fp_line
			(start 2.500122 2.500122)
			(end -2.500122 2.500122)
			(stroke
				(width 0.1)
				(type default)
			)
			(layer "F.Fab")
		)
		(fp_line
			(start 2.921 1.524)
			(end 3.302 1.524)
			(stroke
				(width 0.1)
				(type default)
			)
			(layer "F.Fab")
		)
		(fp_line
			(start -2.921 0.508)
			(end -3.302 0.508)
			(stroke
				(width 0.1)
				(type default)
			)
			(layer "F.Fab")
		)
		(fp_line
			(start 2.921 -1.016)
			(end 3.683 -1.016)
			(stroke
				(width 0.1)
				(type default)
			)
			(layer "F.Fab")
		)
		(fp_line
			(start -2.500122 -2.500122)
			(end 2.500122 -2.500122)
			(stroke
				(width 0.1)
				(type default)
			)
			(layer "F.Fab")
		)
		(fp_line
			(start 2.500122 -2.500122)
			(end 2.500122 2.500122)
			(stroke
				(width 0.1)
				(type default)
			)
			(layer "F.Fab")
		)
		(fp_line
			(start 0 -2.921)
			(end 0 -3.302)
			(stroke
				(width 0.1)
				(type default)
			)
			(layer "F.Fab")
		)
		(fp_poly
			(pts
				(xy -3.7592 -1.933194) (xy -2.892806 -1.500124) (xy -3.7592 -1.0668)
			)
			(stroke
				(width 0)
				(type default)
			)
			(fill yes)
			(layer "F.Fab")
		)
		(fp_text user "15"
			(at 4.098036 4.054856 0)
			(unlocked yes)
			(layer "F.SilkS")
			(effects
				(font
					(size 0.635 0.4064)
					(thickness 0.1524)
				)
			)
		)
		(fp_text user "14"
			(at 1.306576 3.310636 0)
			(unlocked yes)
			(layer "F.SilkS")
			(effects
				(font
					(size 0.635 0.4064)
					(thickness 0.1524)
				)
			)
		)
		(fp_text user "8"
			(at -2.064004 2.993136 0)
			(unlocked yes)
			(layer "F.SilkS")
			(effects
				(font
					(size 0.635 0.4064)
					(thickness 0.1524)
				)
			)
		)
		(fp_text user "7"
			(at -3.147568 1.8034 0)
			(unlocked yes)
			(layer "F.SilkS")
			(effects
				(font
					(size 0.635 0.4064)
					(thickness 0.1524)
				)
			)
		)
		(fp_text user "21"
			(at 4.557776 -3.974084 0)
			(unlocked yes)
			(layer "F.SilkS")
			(effects
				(font
					(size 0.635 0.4064)
					(thickness 0.1524)
				)
			)
		)
		(fp_text user "28"
			(at -1.357884 -4.0513 0)
			(unlocked yes)
			(layer "F.SilkS")
			(effects
				(font
					(size 0.635 0.4064)
					(thickness 0.1524)
				)
			)
		)
		(fp_text user "22"
			(at 3.315716 -4.591304 0)
			(unlocked yes)
			(layer "F.SilkS")
			(effects
				(font
					(size 0.635 0.4064)
					(thickness 0.1524)
				)
			)
		)
		(fp_text user "8"
			(at -1.8796 3.253232 270)
			(unlocked yes)
			(layer "F.Fab")
			(effects
				(font
					(size 0.635 0.4064)
					(thickness 0.1524)
				)
			)
		)
		(fp_text user "14"
			(at 2.1336 3.253232 270)
			(unlocked yes)
			(layer "F.Fab")
			(effects
				(font
					(size 0.635 0.4064)
					(thickness 0.1524)
				)
			)
		)
		(fp_text user "15"
			(at 3.253232 2.2352 0)
			(unlocked yes)
			(layer "F.Fab")
			(effects
				(font
					(size 0.635 0.4064)
					(thickness 0.1524)
				)
			)
		)
		(fp_text user "7"
			(at -3.147568 1.8034 0)
			(unlocked yes)
			(layer "F.Fab")
			(effects
				(font
					(size 0.635 0.4064)
					(thickness 0.1524)
				)
			)
		)
		(fp_text user "21"
			(at 3.227832 -2.2606 0)
			(unlocked yes)
			(layer "F.Fab")
			(effects
				(font
					(size 0.635 0.4064)
					(thickness 0.1524)
				)
			)
		)
		(fp_text user "28"
			(at -2.2098 -3.172968 270)
			(unlocked yes)
			(layer "F.Fab")
			(effects
				(font
					(size 0.635 0.4064)
					(thickness 0.1524)
				)
			)
		)
		(fp_text user "22"
			(at 2.2352 -3.172968 270)
			(unlocked yes)
			(layer "F.Fab")
			(effects
				(font
					(size 0.635 0.4064)
					(thickness 0.1524)
				)
			)
		)
		(pad "1" smd rect
			(at -2.412492 -1.500124)
			(size 0.254 0.7366)
			(layers "F.Cu" "F.Mask" "F.Paste")
			(net "USB2_P0_R_DN")
		)
		(pad "2" smd rect
			(at -2.412492 -0.999998)
			(size 0.254 0.7366)
			(layers "F.Cu" "F.Mask" "F.Paste")
			(net "USB2_P0_R_DP")
		)
		(pad "3" smd rect
			(at -2.412492 -0.499872)
			(size 0.254 0.7366)
			(layers "F.Cu" "F.Mask" "F.Paste")
			(net "USB2_HUB_SWB_DN")
		)
		(pad "4" smd rect
			(at -2.412492 0)
			(size 0.254 0.7366)
			(layers "F.Cu" "F.Mask" "F.Paste")
			(net "USB2_HUB_SWB_DP")
		)
		(pad "5" smd rect
			(at -2.412492 0.499872)
			(size 0.254 0.7366)
			(layers "F.Cu" "F.Mask" "F.Paste")
			(net "P3V3_AUX_USB_HUB")
		)
		(pad "6" smd rect
			(at -2.412492 0.999998)
			(size 0.254 0.7366)
			(layers "F.Cu" "F.Mask" "F.Paste")
			(net "NC_USB_HUB_DM2")
		)
		(pad "7" smd rect
			(at -2.412492 1.500124)
			(size 0.254 0.7366)
			(layers "F.Cu" "F.Mask" "F.Paste")
			(net "NC_USB_HUB_DP2")
		)
		(pad "8" smd rect
			(at -1.500124 2.412492 270)
			(size 0.254 0.7366)
			(layers "F.Cu" "F.Mask" "F.Paste")
			(net "USB_HUB_RREF")
		)
		(pad "9" smd rect
			(at -0.999998 2.412492 270)
			(size 0.254 0.7366)
			(layers "F.Cu" "F.Mask" "F.Paste")
			(net "P3V3_AUX_USB_HUB")
		)
		(pad "10" smd rect
			(at -0.499872 2.412492 270)
			(size 0.254 0.7366)
			(layers "F.Cu" "F.Mask" "F.Paste")
			(net "USB_HUB_XTAL_IN")
		)
		(pad "11" smd rect
			(at 0 2.412492 270)
			(size 0.254 0.7366)
			(layers "F.Cu" "F.Mask" "F.Paste")
			(net "USB_HUB_XTAL_OUT")
		)
		(pad "12" smd rect
			(at 0.499872 2.412492 270)
			(size 0.254 0.7366)
			(layers "F.Cu" "F.Mask" "F.Paste")
			(net "NC_USB_HUB_DM3")
		)
		(pad "13" smd rect
			(at 0.999998 2.412492 270)
			(size 0.254 0.7366)
			(layers "F.Cu" "F.Mask" "F.Paste")
			(net "NC_USB_HUB_DP3")
		)
		(pad "14" smd rect
			(at 1.500124 2.412492 270)
			(size 0.254 0.7366)
			(layers "F.Cu" "F.Mask" "F.Paste")
			(net "P3V3_AUX_USB_HUB")
		)
		(pad "15" smd rect
			(at 2.412492 1.500124)
			(size 0.254 0.7366)
			(layers "F.Cu" "F.Mask" "F.Paste")
			(net "NC_USB_HUB_DM4")
		)
		(pad "16" smd rect
			(at 2.412492 0.999998)
			(size 0.254 0.7366)
			(layers "F.Cu" "F.Mask" "F.Paste")
			(net "NC_USB_HUB_DP4")
		)
		(pad "17" smd rect
			(at 2.412492 0.499872)
			(size 0.254 0.7366)
			(layers "F.Cu" "F.Mask" "F.Paste")
			(net "RST_USB_HUB_R_N")
		)
		(pad "18" smd rect
			(at 2.412492 0)
			(size 0.254 0.7366)
			(layers "F.Cu" "F.Mask" "F.Paste")
			(net "USB_HUB_TEST")
		)
		(pad "19" smd rect
			(at 2.412492 -0.499872)
			(size 0.254 0.7366)
			(layers "F.Cu" "F.Mask" "F.Paste")
			(net "USB_HUB_OVCUR4")
		)
		(pad "20" smd rect
			(at 2.412492 -0.999998)
			(size 0.254 0.7366)
			(layers "F.Cu" "F.Mask" "F.Paste")
			(net "USB_HUB_OVCUR3")
		)
		(pad "21" smd rect
			(at 2.412492 -1.500124)
			(size 0.254 0.7366)
			(layers "F.Cu" "F.Mask" "F.Paste")
			(net "USB_HUB_DVDD")
		)
		(pad "22" smd rect
			(at 1.500124 -2.412492 270)
			(size 0.254 0.7366)
			(layers "F.Cu" "F.Mask" "F.Paste")
			(net "USB_HUB_PSELF")
		)
		(pad "23" smd rect
			(at 0.999998 -2.412492 270)
			(size 0.254 0.7366)
			(layers "F.Cu" "F.Mask" "F.Paste")
			(net "USB_HUB_PGANG")
		)
		(pad "24" smd rect
			(at 0.499872 -2.412492 270)
			(size 0.254 0.7366)
			(layers "F.Cu" "F.Mask" "F.Paste")
			(net "USB_HUB_OVCUR2")
		)
		(pad "25" smd rect
			(at 0 -2.412492 270)
			(size 0.254 0.7366)
			(layers "F.Cu" "F.Mask" "F.Paste")
			(net "USB_HUB_OVCUR1")
		)
		(pad "26" smd rect
			(at -0.499872 -2.412492 270)
			(size 0.254 0.7366)
			(layers "F.Cu" "F.Mask" "F.Paste")
			(net "NC_USB_HUB_SDA")
		)
		(pad "27" smd rect
			(at -0.999998 -2.412492 270)
			(size 0.254 0.7366)
			(layers "F.Cu" "F.Mask" "F.Paste")
			(net "P3V3_AUX_USB_HUB")
		)
		(pad "28" smd rect
			(at -1.500124 -2.412492 270)
			(size 0.254 0.7366)
			(layers "F.Cu" "F.Mask" "F.Paste")
			(net "P3V3_AUX_USB_HUB")
		)
		(pad "TH" smd rect
			(at 0 0 270)
			(size 3.556 3.556)
			(layers "F.Cu" "F.Mask" "F.Paste")
			(net "GND")
		)
		(zone
			(layer "F.Cu")
			(hatch none 0.5)
			(connect_pads
				(clearance 0)
			)
			(min_thickness 0.25)
			(keepout
				(tracks not_allowed)
				(vias allowed)
				(pads allowed)
				(copperpour not_allowed)
				(footprints allowed)
			)
			(placement
				(enabled no)
				(sheetname "")
			)
			(fill
				(thermal_gap 0.5)
				(thermal_bridge_width 0.5)
				(island_removal_mode 0)
			)
			(polygon
				(pts
					(xy 16.046196 -98.196654) (xy 15.893796 -98.196654) (xy 15.893796 -100.965254) (xy 12.236196 -100.965254)
					(xy 12.236196 -97.307654) (xy 15.893796 -97.307654) (xy 15.893796 -98.171254) (xy 16.046196 -98.171254)
					(xy 16.046196 -97.155254) (xy 12.083796 -97.155254) (xy 12.083796 -101.117654) (xy 16.046196 -101.117654)
				)
			)
		)
	)
	(footprint ""
		(layer "F.Cu")
		(at 85.322156 -41.95318)
		(property "Reference" "C1821"
			(at 0 0 0)
			(layer "F.SilkS")
			(hide yes)
			(effects
				(font
					(size 1.27 1.27)
				)
			)
		)
		(property "Value" ""
			(at 0 0 0)
			(layer "F.Fab")
			(effects
				(font
					(size 1.27 1.27)
				)
			)
		)
		(duplicate_pad_numbers_are_jumpers no)
		(fp_line
			(start -0.7874 -0.4064)
			(end 0.7874 -0.4064)
			(stroke
				(width 0.1524)
				(type default)
			)
			(layer "F.SilkS")
		)
		(fp_line
			(start -0.7874 0.4064)
			(end -0.7874 -0.4064)
			(stroke
				(width 0.1524)
				(type default)
			)
			(layer "F.SilkS")
		)
		(fp_line
			(start 0.7874 -0.4064)
			(end 0.7874 0.4064)
			(stroke
				(width 0.1524)
				(type default)
			)
			(layer "F.SilkS")
		)
		(fp_line
			(start 0.7874 0.4064)
			(end -0.7874 0.4064)
			(stroke
				(width 0.1524)
				(type default)
			)
			(layer "F.SilkS")
		)
		(fp_line
			(start -0.67945 -0.305054)
			(end -0.12065 -0.305054)
			(stroke
				(width 0.1)
				(type default)
			)
			(layer "F.Fab")
		)
		(fp_line
			(start -0.67945 0.3048)
			(end -0.67945 -0.305054)
			(stroke
				(width 0.1)
				(type default)
			)
			(layer "F.Fab")
		)
		(fp_line
			(start -0.12065 -0.305054)
			(end -0.12065 -0.2794)
			(stroke
				(width 0.1)
				(type default)
			)
			(layer "F.Fab")
		)
		(fp_line
			(start -0.12065 -0.2794)
			(end 0.12065 -0.2794)
			(stroke
				(width 0.1)
				(type default)
			)
			(layer "F.Fab")
		)
		(fp_line
			(start -0.12065 0.2794)
			(end -0.12065 0.3048)
			(stroke
				(width 0.1)
				(type default)
			)
			(layer "F.Fab")
		)
		(fp_line
			(start -0.12065 0.3048)
			(end -0.67945 0.3048)
			(stroke
				(width 0.1)
				(type default)
			)
			(layer "F.Fab")
		)
		(fp_line
			(start 0.120396 0.2794)
			(end -0.12065 0.2794)
			(stroke
				(width 0.1)
				(type default)
			)
			(layer "F.Fab")
		)
		(fp_line
			(start 0.120396 0.3048)
			(end 0.120396 0.2794)
			(stroke
				(width 0.1)
				(type default)
			)
			(layer "F.Fab")
		)
		(fp_line
			(start 0.12065 -0.3048)
			(end 0.67945 -0.3048)
			(stroke
				(width 0.1)
				(type default)
			)
			(layer "F.Fab")
		)
		(fp_line
			(start 0.12065 -0.2794)
			(end 0.12065 -0.3048)
			(stroke
				(width 0.1)
				(type default)
			)
			(layer "F.Fab")
		)
		(fp_line
			(start 0.67945 -0.3048)
			(end 0.67945 0.3048)
			(stroke
				(width 0.1)
				(type default)
			)
			(layer "F.Fab")
		)
		(fp_line
			(start 0.67945 0.3048)
			(end 0.120396 0.3048)
			(stroke
				(width 0.1)
				(type default)
			)
			(layer "F.Fab")
		)
		(pad "1" smd circle
			(at -0.40005 0)
			(size 0 0)
			(layers "F.Cu" "F.Mask" "F.Paste")
			(net "P3V3_AUX")
		)
		(pad "2" smd circle
			(at 0.40005 0)
			(size 0 0)
			(layers "F.Cu" "F.Mask" "F.Paste")
			(net "GND")
		)
	)
	(footprint ""
		(layer "F.Cu")
		(at 191.41694 -400.309842)
		(property "Reference" "R3934"
			(at 0 0 0)
			(layer "F.SilkS")
			(hide yes)
			(effects
				(font
					(size 1.27 1.27)
				)
			)
		)
		(property "Value" ""
			(at 0 0 0)
			(layer "F.Fab")
			(effects
				(font
					(size 1.27 1.27)
				)
			)
		)
		(duplicate_pad_numbers_are_jumpers no)
		(fp_line
			(start -0.7874 -0.4064)
			(end 0.7874 -0.4064)
			(stroke
				(width 0.1524)
				(type default)
			)
			(layer "F.SilkS")
		)
		(fp_line
			(start -0.7874 0.4064)
			(end -0.7874 -0.4064)
			(stroke
				(width 0.1524)
				(type default)
			)
			(layer "F.SilkS")
		)
		(fp_line
			(start 0.7874 -0.4064)
			(end 0.7874 0.4064)
			(stroke
				(width 0.1524)
				(type default)
			)
			(layer "F.SilkS")
		)
		(fp_line
			(start 0.7874 0.4064)
			(end -0.7874 0.4064)
			(stroke
				(width 0.1524)
				(type default)
			)
			(layer "F.SilkS")
		)
		(fp_line
			(start -0.67945 -0.305054)
			(end -0.12065 -0.305054)
			(stroke
				(width 0.1)
				(type default)
			)
			(layer "F.Fab")
		)
		(fp_line
			(start -0.67945 0.3048)
			(end -0.67945 -0.305054)
			(stroke
				(width 0.1)
				(type default)
			)
			(layer "F.Fab")
		)
		(fp_line
			(start -0.12065 -0.305054)
			(end -0.12065 -0.2794)
			(stroke
				(width 0.1)
				(type default)
			)
			(layer "F.Fab")
		)
		(fp_line
			(start -0.12065 -0.2794)
			(end 0.12065 -0.2794)
			(stroke
				(width 0.1)
				(type default)
			)
			(layer "F.Fab")
		)
		(fp_line
			(start -0.12065 0.2794)
			(end -0.12065 0.3048)
			(stroke
				(width 0.1)
				(type default)
			)
			(layer "F.Fab")
		)
		(fp_line
			(start -0.12065 0.3048)
			(end -0.67945 0.3048)
			(stroke
				(width 0.1)
				(type default)
			)
			(layer "F.Fab")
		)
		(fp_line
			(start 0.120396 0.2794)
			(end -0.12065 0.2794)
			(stroke
				(width 0.1)
				(type default)
			)
			(layer "F.Fab")
		)
		(fp_line
			(start 0.120396 0.3048)
			(end 0.120396 0.2794)
			(stroke
				(width 0.1)
				(type default)
			)
			(layer "F.Fab")
		)
		(fp_line
			(start 0.12065 -0.3048)
			(end 0.67945 -0.3048)
			(stroke
				(width 0.1)
				(type default)
			)
			(layer "F.Fab")
		)
		(fp_line
			(start 0.12065 -0.2794)
			(end 0.12065 -0.3048)
			(stroke
				(width 0.1)
				(type default)
			)
			(layer "F.Fab")
		)
		(fp_line
			(start 0.67945 -0.3048)
			(end 0.67945 0.3048)
			(stroke
				(width 0.1)
				(type default)
			)
			(layer "F.Fab")
		)
		(fp_line
			(start 0.67945 0.3048)
			(end 0.120396 0.3048)
			(stroke
				(width 0.1)
				(type default)
			)
			(layer "F.Fab")
		)
		(pad "1" smd circle
			(at -0.40005 0)
			(size 0 0)
			(layers "F.Cu" "F.Mask" "F.Paste")
			(net "HSC_D_OC_R")
		)
		(pad "2" smd circle
			(at 0.40005 0)
			(size 0 0)
			(layers "F.Cu" "F.Mask" "F.Paste")
			(net "HSC_D_OC")
		)
	)
	(footprint ""
		(layer "F.Cu")
		(at 173.2788 -385.5212 90)
		(property "Reference" "C366"
			(at 0 0 90)
			(layer "F.SilkS")
			(hide yes)
			(effects
				(font
					(size 1.27 1.27)
				)
			)
		)
		(property "Value" ""
			(at 0 0 90)
			(layer "F.Fab")
			(effects
				(font
					(size 1.27 1.27)
				)
			)
		)
		(duplicate_pad_numbers_are_jumpers no)
		(fp_line
			(start 1.524 -0.762)
			(end 1.524 0.762)
			(stroke
				(width 0.1524)
				(type default)
			)
			(layer "F.SilkS")
		)
		(fp_line
			(start -1.524 -0.762)
			(end 1.524 -0.762)
			(stroke
				(width 0.1524)
				(type default)
			)
			(layer "F.SilkS")
		)
		(fp_line
			(start 1.524 0.762)
			(end -1.524 0.762)
			(stroke
				(width 0.1524)
				(type default)
			)
			(layer "F.SilkS")
		)
		(fp_line
			(start -1.524 0.762)
			(end -1.524 -0.762)
			(stroke
				(width 0.1524)
				(type default)
			)
			(layer "F.SilkS")
		)
		(fp_line
			(start 1.1049 -0.724916)
			(end -1.1049 -0.724916)
			(stroke
				(width 0.1)
				(type default)
			)
			(layer "F.Fab")
		)
		(fp_line
			(start -1.1049 -0.724916)
			(end -1.1049 0.724916)
			(stroke
				(width 0.1)
				(type default)
			)
			(layer "F.Fab")
		)
		(fp_line
			(start 1.1049 0.724916)
			(end 1.1049 -0.724916)
			(stroke
				(width 0.1)
				(type default)
			)
			(layer "F.Fab")
		)
		(fp_line
			(start -1.1049 0.724916)
			(end 1.1049 0.724916)
			(stroke
				(width 0.1)
				(type default)
			)
			(layer "F.Fab")
		)
		(pad "1" smd rect
			(at -0.889 0 270)
			(size 1.016 1.27)
			(layers "F.Cu" "F.Mask" "F.Paste")
			(net "P1V8_CPU1_RT_1D")
		)
		(pad "2" smd rect
			(at 0.889 0 270)
			(size 1.016 1.27)
			(layers "F.Cu" "F.Mask" "F.Paste")
			(net "GND")
		)
	)
	(footprint ""
		(layer "F.Cu")
		(at 137.196068 -74.236072 180)
		(property "Reference" "PC6020"
			(at 0 0 180)
			(layer "F.SilkS")
			(hide yes)
			(effects
				(font
					(size 1.27 1.27)
				)
			)
		)
		(property "Value" ""
			(at 0 0 180)
			(layer "F.Fab")
			(effects
				(font
					(size 1.27 1.27)
				)
			)
		)
		(duplicate_pad_numbers_are_jumpers no)
		(fp_line
			(start 0.7874 0.4064)
			(end -0.7874 0.4064)
			(stroke
				(width 0.1524)
				(type default)
			)
			(layer "F.SilkS")
		)
		(fp_line
			(start 0.7874 -0.4064)
			(end 0.7874 0.4064)
			(stroke
				(width 0.1524)
				(type default)
			)
			(layer "F.SilkS")
		)
		(fp_line
			(start -0.7874 0.4064)
			(end -0.7874 -0.4064)
			(stroke
				(width 0.1524)
				(type default)
			)
			(layer "F.SilkS")
		)
		(fp_line
			(start -0.7874 -0.4064)
			(end 0.7874 -0.4064)
			(stroke
				(width 0.1524)
				(type default)
			)
			(layer "F.SilkS")
		)
		(fp_line
			(start 0.67945 0.3048)
			(end 0.120396 0.3048)
			(stroke
				(width 0.1)
				(type default)
			)
			(layer "F.Fab")
		)
		(fp_line
			(start 0.67945 -0.3048)
			(end 0.67945 0.3048)
			(stroke
				(width 0.1)
				(type default)
			)
			(layer "F.Fab")
		)
		(fp_line
			(start 0.12065 -0.2794)
			(end 0.12065 -0.3048)
			(stroke
				(width 0.1)
				(type default)
			)
			(layer "F.Fab")
		)
		(fp_line
			(start 0.12065 -0.3048)
			(end 0.67945 -0.3048)
			(stroke
				(width 0.1)
				(type default)
			)
			(layer "F.Fab")
		)
		(fp_line
			(start 0.120396 0.3048)
			(end 0.120396 0.2794)
			(stroke
				(width 0.1)
				(type default)
			)
			(layer "F.Fab")
		)
		(fp_line
			(start 0.120396 0.2794)
			(end -0.12065 0.2794)
			(stroke
				(width 0.1)
				(type default)
			)
			(layer "F.Fab")
		)
		(fp_line
			(start -0.12065 0.3048)
			(end -0.67945 0.3048)
			(stroke
				(width 0.1)
				(type default)
			)
			(layer "F.Fab")
		)
		(fp_line
			(start -0.12065 0.2794)
			(end -0.12065 0.3048)
			(stroke
				(width 0.1)
				(type default)
			)
			(layer "F.Fab")
		)
		(fp_line
			(start -0.12065 -0.2794)
			(end 0.12065 -0.2794)
			(stroke
				(width 0.1)
				(type default)
			)
			(layer "F.Fab")
		)
		(fp_line
			(start -0.12065 -0.305054)
			(end -0.12065 -0.2794)
			(stroke
				(width 0.1)
				(type default)
			)
			(layer "F.Fab")
		)
		(fp_line
			(start -0.67945 0.3048)
			(end -0.67945 -0.305054)
			(stroke
				(width 0.1)
				(type default)
			)
			(layer "F.Fab")
		)
		(fp_line
			(start -0.67945 -0.305054)
			(end -0.12065 -0.305054)
			(stroke
				(width 0.1)
				(type default)
			)
			(layer "F.Fab")
		)
		(pad "1" smd circle
			(at -0.40005 0 180)
			(size 0 0)
			(layers "F.Cu" "F.Mask" "F.Paste")
			(net "P12V_AUX")
		)
		(pad "2" smd circle
			(at 0.40005 0 180)
			(size 0 0)
			(layers "F.Cu" "F.Mask" "F.Paste")
			(net "GND")
		)
	)
	(footprint ""
		(layer "F.Cu")
		(at 295.30421 -404.422102 -90)
		(property "Reference" "C664"
			(at 0 0 270)
			(layer "F.SilkS")
			(hide yes)
			(effects
				(font
					(size 1.27 1.27)
				)
			)
		)
		(property "Value" ""
			(at 0 0 270)
			(layer "F.Fab")
			(effects
				(font
					(size 1.27 1.27)
				)
			)
		)
		(duplicate_pad_numbers_are_jumpers no)
		(fp_line
			(start -0.299974 0.150114)
			(end -0.299974 -0.150114)
			(stroke
				(width 0.1)
				(type default)
			)
			(layer "F.Fab")
		)
		(fp_line
			(start 0.299974 0.150114)
			(end -0.299974 0.150114)
			(stroke
				(width 0.1)
				(type default)
			)
			(layer "F.Fab")
		)
		(fp_line
			(start -0.299974 -0.150114)
			(end 0.299974 -0.150114)
			(stroke
				(width 0.1)
				(type default)
			)
			(layer "F.Fab")
		)
		(fp_line
			(start 0.299974 -0.150114)
			(end 0.299974 0.150114)
			(stroke
				(width 0.1)
				(type default)
			)
			(layer "F.Fab")
		)
		(pad "1" smd rect
			(at -0.2667 0 270)
			(size 0.3048 0.381)
			(layers "F.Cu" "F.Mask" "F.Paste")
			(net "P1V8_CPU0_RT_1D")
		)
		(pad "2" smd rect
			(at 0.2667 0 270)
			(size 0.3048 0.381)
			(layers "F.Cu" "F.Mask" "F.Paste")
			(net "GND")
		)
	)
	(footprint ""
		(layer "F.Cu")
		(at 453.043544 -25.638506 180)
		(property "Reference" "PR4524"
			(at 0 0 180)
			(layer "F.SilkS")
			(hide yes)
			(effects
				(font
					(size 1.27 1.27)
				)
			)
		)
		(property "Value" ""
			(at 0 0 180)
			(layer "F.Fab")
			(effects
				(font
					(size 1.27 1.27)
				)
			)
		)
		(duplicate_pad_numbers_are_jumpers no)
		(fp_line
			(start 0.7874 0.4064)
			(end -0.7874 0.4064)
			(stroke
				(width 0.1524)
				(type default)
			)
			(layer "F.SilkS")
		)
		(fp_line
			(start 0.7874 -0.4064)
			(end 0.7874 0.4064)
			(stroke
				(width 0.1524)
				(type default)
			)
			(layer "F.SilkS")
		)
		(fp_line
			(start -0.7874 0.4064)
			(end -0.7874 -0.4064)
			(stroke
				(width 0.1524)
				(type default)
			)
			(layer "F.SilkS")
		)
		(fp_line
			(start -0.7874 -0.4064)
			(end 0.7874 -0.4064)
			(stroke
				(width 0.1524)
				(type default)
			)
			(layer "F.SilkS")
		)
		(fp_line
			(start 0.67945 0.3048)
			(end 0.120396 0.3048)
			(stroke
				(width 0.1)
				(type default)
			)
			(layer "F.Fab")
		)
		(fp_line
			(start 0.67945 -0.3048)
			(end 0.67945 0.3048)
			(stroke
				(width 0.1)
				(type default)
			)
			(layer "F.Fab")
		)
		(fp_line
			(start 0.12065 -0.2794)
			(end 0.12065 -0.3048)
			(stroke
				(width 0.1)
				(type default)
			)
			(layer "F.Fab")
		)
		(fp_line
			(start 0.12065 -0.3048)
			(end 0.67945 -0.3048)
			(stroke
				(width 0.1)
				(type default)
			)
			(layer "F.Fab")
		)
		(fp_line
			(start 0.120396 0.3048)
			(end 0.120396 0.2794)
			(stroke
				(width 0.1)
				(type default)
			)
			(layer "F.Fab")
		)
		(fp_line
			(start 0.120396 0.2794)
			(end -0.12065 0.2794)
			(stroke
				(width 0.1)
				(type default)
			)
			(layer "F.Fab")
		)
		(fp_line
			(start -0.12065 0.3048)
			(end -0.67945 0.3048)
			(stroke
				(width 0.1)
				(type default)
			)
			(layer "F.Fab")
		)
		(fp_line
			(start -0.12065 0.2794)
			(end -0.12065 0.3048)
			(stroke
				(width 0.1)
				(type default)
			)
			(layer "F.Fab")
		)
		(fp_line
			(start -0.12065 -0.2794)
			(end 0.12065 -0.2794)
			(stroke
				(width 0.1)
				(type default)
			)
			(layer "F.Fab")
		)
		(fp_line
			(start -0.12065 -0.305054)
			(end -0.12065 -0.2794)
			(stroke
				(width 0.1)
				(type default)
			)
			(layer "F.Fab")
		)
		(fp_line
			(start -0.67945 0.3048)
			(end -0.67945 -0.305054)
			(stroke
				(width 0.1)
				(type default)
			)
			(layer "F.Fab")
		)
		(fp_line
			(start -0.67945 -0.305054)
			(end -0.12065 -0.305054)
			(stroke
				(width 0.1)
				(type default)
			)
			(layer "F.Fab")
		)
		(pad "1" smd circle
			(at -0.40005 0 180)
			(size 0 0)
			(layers "F.Cu" "F.Mask" "F.Paste")
			(net "P12V_OCP_SFF")
		)
		(pad "2" smd circle
			(at 0.40005 0 180)
			(size 0 0)
			(layers "F.Cu" "F.Mask" "F.Paste")
			(net "P12V_OCP_GATE_1")
		)
	)
	(footprint ""
		(layer "F.Cu")
		(at 338.693506 -335.12379 -90)
		(property "Reference" "PC87_1"
			(at 0 0 270)
			(layer "F.SilkS")
			(hide yes)
			(effects
				(font
					(size 1.27 1.27)
				)
			)
		)
		(property "Value" ""
			(at 0 0 270)
			(layer "F.Fab")
			(effects
				(font
					(size 1.27 1.27)
				)
			)
		)
		(duplicate_pad_numbers_are_jumpers no)
		(fp_line
			(start -0.7874 0.4064)
			(end -0.7874 -0.4064)
			(stroke
				(width 0.1524)
				(type default)
			)
			(layer "F.SilkS")
		)
		(fp_line
			(start 0.7874 0.4064)
			(end -0.7874 0.4064)
			(stroke
				(width 0.1524)
				(type default)
			)
			(layer "F.SilkS")
		)
		(fp_line
			(start -0.7874 -0.4064)
			(end 0.7874 -0.4064)
			(stroke
				(width 0.1524)
				(type default)
			)
			(layer "F.SilkS")
		)
		(fp_line
			(start 0.7874 -0.4064)
			(end 0.7874 0.4064)
			(stroke
				(width 0.1524)
				(type default)
			)
			(layer "F.SilkS")
		)
		(fp_line
			(start -0.67945 0.3048)
			(end -0.67945 -0.305054)
			(stroke
				(width 0.1)
				(type default)
			)
			(layer "F.Fab")
		)
		(fp_line
			(start -0.12065 0.3048)
			(end -0.67945 0.3048)
			(stroke
				(width 0.1)
				(type default)
			)
			(layer "F.Fab")
		)
		(fp_line
			(start 0.120396 0.3048)
			(end 0.120396 0.2794)
			(stroke
				(width 0.1)
				(type default)
			)
			(layer "F.Fab")
		)
		(fp_line
			(start 0.67945 0.3048)
			(end 0.120396 0.3048)
			(stroke
				(width 0.1)
				(type default)
			)
			(layer "F.Fab")
		)
		(fp_line
			(start -0.12065 0.2794)
			(end -0.12065 0.3048)
			(stroke
				(width 0.1)
				(type default)
			)
			(layer "F.Fab")
		)
		(fp_line
			(start 0.120396 0.2794)
			(end -0.12065 0.2794)
			(stroke
				(width 0.1)
				(type default)
			)
			(layer "F.Fab")
		)
		(fp_line
			(start -0.12065 -0.2794)
			(end 0.12065 -0.2794)
			(stroke
				(width 0.1)
				(type default)
			)
			(layer "F.Fab")
		)
		(fp_line
			(start 0.12065 -0.2794)
			(end 0.12065 -0.3048)
			(stroke
				(width 0.1)
				(type default)
			)
			(layer "F.Fab")
		)
		(fp_line
			(start 0.12065 -0.3048)
			(end 0.67945 -0.3048)
			(stroke
				(width 0.1)
				(type default)
			)
			(layer "F.Fab")
		)
		(fp_line
			(start 0.67945 -0.3048)
			(end 0.67945 0.3048)
			(stroke
				(width 0.1)
				(type default)
			)
			(layer "F.Fab")
		)
		(fp_line
			(start -0.67945 -0.305054)
			(end -0.12065 -0.305054)
			(stroke
				(width 0.1)
				(type default)
			)
			(layer "F.Fab")
		)
		(fp_line
			(start -0.12065 -0.305054)
			(end -0.12065 -0.2794)
			(stroke
				(width 0.1)
				(type default)
			)
			(layer "F.Fab")
		)
		(pad "1" smd circle
			(at -0.40005 0 270)
			(size 0 0)
			(layers "F.Cu" "F.Mask" "F.Paste")
			(net "SW_P12V_AUX_PVDDCR_CPU1_P0_FLT")
		)
		(pad "2" smd circle
			(at 0.40005 0 270)
			(size 0 0)
			(layers "F.Cu" "F.Mask" "F.Paste")
			(net "GND")
		)
	)
	(footprint ""
		(layer "F.Cu")
		(at 335.315306 -416.899344 -90)
		(property "Reference" "C6521"
			(at 0 0 270)
			(layer "F.SilkS")
			(hide yes)
			(effects
				(font
					(size 1.27 1.27)
				)
			)
		)
		(property "Value" ""
			(at 0 0 270)
			(layer "F.Fab")
			(effects
				(font
					(size 1.27 1.27)
				)
			)
		)
		(duplicate_pad_numbers_are_jumpers no)
		(fp_line
			(start -0.299974 0.150114)
			(end -0.299974 -0.150114)
			(stroke
				(width 0.1)
				(type default)
			)
			(layer "F.Fab")
		)
		(fp_line
			(start 0.299974 0.150114)
			(end -0.299974 0.150114)
			(stroke
				(width 0.1)
				(type default)
			)
			(layer "F.Fab")
		)
		(fp_line
			(start -0.299974 -0.150114)
			(end 0.299974 -0.150114)
			(stroke
				(width 0.1)
				(type default)
			)
			(layer "F.Fab")
		)
		(fp_line
			(start 0.299974 -0.150114)
			(end 0.299974 0.150114)
			(stroke
				(width 0.1)
				(type default)
			)
			(layer "F.Fab")
		)
		(pad "1" smd rect
			(at -0.2667 0 270)
			(size 0.3048 0.381)
			(layers "F.Cu" "F.Mask" "F.Paste")
			(net "P5E_CPU0_P0_TX_BUF_C_DP<10>")
		)
		(pad "2" smd rect
			(at 0.2667 0 270)
			(size 0.3048 0.381)
			(layers "F.Cu" "F.Mask" "F.Paste")
			(net "P5E_CPU0_P0_TX_BUF_DP<10>")
		)
	)
	(footprint ""
		(layer "F.Cu")
		(at 426.687488 -332.63586 -90)
		(property "Reference" "PC230"
			(at -4.97078 -12.749276 90)
			(unlocked yes)
			(layer "F.SilkS")
			(effects
				(font
					(size 0.7874 0.5842)
					(thickness 0.1524)
				)
				(justify left)
			)
		)
		(property "Value" ""
			(at 0 0 270)
			(layer "F.Fab")
			(effects
				(font
					(size 1.27 1.27)
				)
			)
		)
		(duplicate_pad_numbers_are_jumpers no)
		(fp_line
			(start -1.988058 2.750058)
			(end 2.750058 2.750058)
			(stroke
				(width 0.1524)
				(type default)
			)
			(layer "F.SilkS")
		)
		(fp_line
			(start 2.750058 2.750058)
			(end 2.750058 0.9398)
			(stroke
				(width 0.1524)
				(type default)
			)
			(layer "F.SilkS")
		)
		(fp_line
			(start -2.750058 1.988058)
			(end -1.988058 2.750058)
			(stroke
				(width 0.1524)
				(type default)
			)
			(layer "F.SilkS")
		)
		(fp_line
			(start -2.750058 0.9398)
			(end -2.750058 1.988058)
			(stroke
				(width 0.1524)
				(type default)
			)
			(layer "F.SilkS")
		)
		(fp_line
			(start 2.750058 -0.9398)
			(end 2.750058 -2.750058)
			(stroke
				(width 0.1524)
				(type default)
			)
			(layer "F.SilkS")
		)
		(fp_line
			(start -2.750058 -1.988058)
			(end -2.750058 -0.9398)
			(stroke
				(width 0.1524)
				(type default)
			)
			(layer "F.SilkS")
		)
		(fp_line
			(start -1.988058 -2.750058)
			(end -2.750058 -1.988058)
			(stroke
				(width 0.1524)
				(type default)
			)
			(layer "F.SilkS")
		)
		(fp_line
			(start 2.750058 -2.750058)
			(end -1.988058 -2.750058)
			(stroke
				(width 0.1524)
				(type default)
			)
			(layer "F.SilkS")
		)
		(fp_line
			(start -2.750058 2.750058)
			(end 2.750058 2.750058)
			(stroke
				(width 0.1)
				(type default)
			)
			(layer "F.Fab")
		)
		(fp_line
			(start 2.750058 2.750058)
			(end 2.750058 -2.750058)
			(stroke
				(width 0.1)
				(type default)
			)
			(layer "F.Fab")
		)
		(fp_line
			(start -2.750058 -2.750058)
			(end -2.750058 2.750058)
			(stroke
				(width 0.1)
				(type default)
			)
			(layer "F.Fab")
		)
		(fp_line
			(start 2.750058 -2.750058)
			(end -2.750058 -2.750058)
			(stroke
				(width 0.1)
				(type default)
			)
			(layer "F.Fab")
		)
		(pad "1" smd rect
			(at -2.199894 0)
			(size 1.6002 3.0226)
			(layers "F.Cu" "F.Mask" "F.Paste")
			(net "PVDD11_S3_P0")
		)
		(pad "2" smd rect
			(at 2.199894 0)
			(size 1.6002 3.0226)
			(layers "F.Cu" "F.Mask" "F.Paste")
			(net "GND")
		)
	)
	(footprint ""
		(layer "F.Cu")
		(at 83.445096 -333.24419 90)
		(property "Reference" "PR512"
			(at 0 0 90)
			(layer "F.SilkS")
			(hide yes)
			(effects
				(font
					(size 1.27 1.27)
				)
			)
		)
		(property "Value" ""
			(at 0 0 90)
			(layer "F.Fab")
			(effects
				(font
					(size 1.27 1.27)
				)
			)
		)
		(duplicate_pad_numbers_are_jumpers no)
		(fp_line
			(start 0.7874 -0.4064)
			(end 0.7874 0.4064)
			(stroke
				(width 0.1524)
				(type default)
			)
			(layer "F.SilkS")
		)
		(fp_line
			(start -0.7874 -0.4064)
			(end 0.7874 -0.4064)
			(stroke
				(width 0.1524)
				(type default)
			)
			(layer "F.SilkS")
		)
		(fp_line
			(start 0.7874 0.4064)
			(end -0.7874 0.4064)
			(stroke
				(width 0.1524)
				(type default)
			)
			(layer "F.SilkS")
		)
		(fp_line
			(start -0.7874 0.4064)
			(end -0.7874 -0.4064)
			(stroke
				(width 0.1524)
				(type default)
			)
			(layer "F.SilkS")
		)
		(fp_line
			(start -0.12065 -0.305054)
			(end -0.12065 -0.2794)
			(stroke
				(width 0.1)
				(type default)
			)
			(layer "F.Fab")
		)
		(fp_line
			(start -0.67945 -0.305054)
			(end -0.12065 -0.305054)
			(stroke
				(width 0.1)
				(type default)
			)
			(layer "F.Fab")
		)
		(fp_line
			(start 0.67945 -0.3048)
			(end 0.67945 0.3048)
			(stroke
				(width 0.1)
				(type default)
			)
			(layer "F.Fab")
		)
		(fp_line
			(start 0.12065 -0.3048)
			(end 0.67945 -0.3048)
			(stroke
				(width 0.1)
				(type default)
			)
			(layer "F.Fab")
		)
		(fp_line
			(start 0.12065 -0.2794)
			(end 0.12065 -0.3048)
			(stroke
				(width 0.1)
				(type default)
			)
			(layer "F.Fab")
		)
		(fp_line
			(start -0.12065 -0.2794)
			(end 0.12065 -0.2794)
			(stroke
				(width 0.1)
				(type default)
			)
			(layer "F.Fab")
		)
		(fp_line
			(start 0.120396 0.2794)
			(end -0.12065 0.2794)
			(stroke
				(width 0.1)
				(type default)
			)
			(layer "F.Fab")
		)
		(fp_line
			(start -0.12065 0.2794)
			(end -0.12065 0.3048)
			(stroke
				(width 0.1)
				(type default)
			)
			(layer "F.Fab")
		)
		(fp_line
			(start 0.67945 0.3048)
			(end 0.120396 0.3048)
			(stroke
				(width 0.1)
				(type default)
			)
			(layer "F.Fab")
		)
		(fp_line
			(start 0.120396 0.3048)
			(end 0.120396 0.2794)
			(stroke
				(width 0.1)
				(type default)
			)
			(layer "F.Fab")
		)
		(fp_line
			(start -0.12065 0.3048)
			(end -0.67945 0.3048)
			(stroke
				(width 0.1)
				(type default)
			)
			(layer "F.Fab")
		)
		(fp_line
			(start -0.67945 0.3048)
			(end -0.67945 -0.305054)
			(stroke
				(width 0.1)
				(type default)
			)
			(layer "F.Fab")
		)
		(pad "1" smd circle
			(at -0.40005 0 90)
			(size 0 0)
			(layers "F.Cu" "F.Mask" "F.Paste")
			(net "SW_PVDDCR_CPU1_P1_SW1_RC")
		)
		(pad "2" smd circle
			(at 0.40005 0 90)
			(size 0 0)
			(layers "F.Cu" "F.Mask" "F.Paste")
			(net "GND")
		)
	)
	(footprint ""
		(layer "F.Cu")
		(at 137.971784 -49.595024)
		(property "Reference" "R6216"
			(at 0 0 0)
			(layer "F.SilkS")
			(hide yes)
			(effects
				(font
					(size 1.27 1.27)
				)
			)
		)
		(property "Value" ""
			(at 0 0 0)
			(layer "F.Fab")
			(effects
				(font
					(size 1.27 1.27)
				)
			)
		)
		(duplicate_pad_numbers_are_jumpers no)
		(fp_line
			(start -0.7874 -0.4064)
			(end 0.7874 -0.4064)
			(stroke
				(width 0.1524)
				(type default)
			)
			(layer "F.SilkS")
		)
		(fp_line
			(start -0.7874 0.4064)
			(end -0.7874 -0.4064)
			(stroke
				(width 0.1524)
				(type default)
			)
			(layer "F.SilkS")
		)
		(fp_line
			(start 0.7874 -0.4064)
			(end 0.7874 0.4064)
			(stroke
				(width 0.1524)
				(type default)
			)
			(layer "F.SilkS")
		)
		(fp_line
			(start 0.7874 0.4064)
			(end -0.7874 0.4064)
			(stroke
				(width 0.1524)
				(type default)
			)
			(layer "F.SilkS")
		)
		(fp_line
			(start -0.67945 -0.305054)
			(end -0.12065 -0.305054)
			(stroke
				(width 0.1)
				(type default)
			)
			(layer "F.Fab")
		)
		(fp_line
			(start -0.67945 0.3048)
			(end -0.67945 -0.305054)
			(stroke
				(width 0.1)
				(type default)
			)
			(layer "F.Fab")
		)
		(fp_line
			(start -0.12065 -0.305054)
			(end -0.12065 -0.2794)
			(stroke
				(width 0.1)
				(type default)
			)
			(layer "F.Fab")
		)
		(fp_line
			(start -0.12065 -0.2794)
			(end 0.12065 -0.2794)
			(stroke
				(width 0.1)
				(type default)
			)
			(layer "F.Fab")
		)
		(fp_line
			(start -0.12065 0.2794)
			(end -0.12065 0.3048)
			(stroke
				(width 0.1)
				(type default)
			)
			(layer "F.Fab")
		)
		(fp_line
			(start -0.12065 0.3048)
			(end -0.67945 0.3048)
			(stroke
				(width 0.1)
				(type default)
			)
			(layer "F.Fab")
		)
		(fp_line
			(start 0.120396 0.2794)
			(end -0.12065 0.2794)
			(stroke
				(width 0.1)
				(type default)
			)
			(layer "F.Fab")
		)
		(fp_line
			(start 0.120396 0.3048)
			(end 0.120396 0.2794)
			(stroke
				(width 0.1)
				(type default)
			)
			(layer "F.Fab")
		)
		(fp_line
			(start 0.12065 -0.3048)
			(end 0.67945 -0.3048)
			(stroke
				(width 0.1)
				(type default)
			)
			(layer "F.Fab")
		)
		(fp_line
			(start 0.12065 -0.2794)
			(end 0.12065 -0.3048)
			(stroke
				(width 0.1)
				(type default)
			)
			(layer "F.Fab")
		)
		(fp_line
			(start 0.67945 -0.3048)
			(end 0.67945 0.3048)
			(stroke
				(width 0.1)
				(type default)
			)
			(layer "F.Fab")
		)
		(fp_line
			(start 0.67945 0.3048)
			(end 0.120396 0.3048)
			(stroke
				(width 0.1)
				(type default)
			)
			(layer "F.Fab")
		)
		(pad "1" smd circle
			(at -0.40005 0)
			(size 0 0)
			(layers "F.Cu" "F.Mask" "F.Paste")
			(net "USB_CPU0_HUB1_MODE_SEL0")
		)
		(pad "2" smd circle
			(at 0.40005 0)
			(size 0 0)
			(layers "F.Cu" "F.Mask" "F.Paste")
			(net "GND")
		)
	)
	(footprint ""
		(layer "F.Cu")
		(at 157.933644 -370.57203 -90)
		(property "Reference" "C755"
			(at 0 0 270)
			(layer "F.SilkS")
			(hide yes)
			(effects
				(font
					(size 1.27 1.27)
				)
			)
		)
		(property "Value" ""
			(at 0 0 270)
			(layer "F.Fab")
			(effects
				(font
					(size 1.27 1.27)
				)
			)
		)
		(duplicate_pad_numbers_are_jumpers no)
		(fp_line
			(start -0.299974 0.150114)
			(end -0.299974 -0.150114)
			(stroke
				(width 0.1)
				(type default)
			)
			(layer "F.Fab")
		)
		(fp_line
			(start 0.299974 0.150114)
			(end -0.299974 0.150114)
			(stroke
				(width 0.1)
				(type default)
			)
			(layer "F.Fab")
		)
		(fp_line
			(start -0.299974 -0.150114)
			(end 0.299974 -0.150114)
			(stroke
				(width 0.1)
				(type default)
			)
			(layer "F.Fab")
		)
		(fp_line
			(start 0.299974 -0.150114)
			(end 0.299974 0.150114)
			(stroke
				(width 0.1)
				(type default)
			)
			(layer "F.Fab")
		)
		(pad "1" smd rect
			(at -0.2667 0 270)
			(size 0.3048 0.381)
			(layers "F.Cu" "F.Mask" "F.Paste")
			(net "P5E_CPU1_P2_TX_C_DP<9>")
		)
		(pad "2" smd rect
			(at 0.2667 0 270)
			(size 0.3048 0.381)
			(layers "F.Cu" "F.Mask" "F.Paste")
			(net "P5E_CPU1_P2_TX_DP<9>")
		)
	)
	(footprint ""
		(layer "F.Cu")
		(at 13.537946 -139.26693 -90)
		(property "Reference" "R4078"
			(at 0 0 270)
			(layer "F.SilkS")
			(hide yes)
			(effects
				(font
					(size 1.27 1.27)
				)
			)
		)
		(property "Value" ""
			(at 0 0 270)
			(layer "F.Fab")
			(effects
				(font
					(size 1.27 1.27)
				)
			)
		)
		(duplicate_pad_numbers_are_jumpers no)
		(fp_line
			(start -0.7874 0.4064)
			(end -0.7874 -0.4064)
			(stroke
				(width 0.1524)
				(type default)
			)
			(layer "F.SilkS")
		)
		(fp_line
			(start 0.7874 0.4064)
			(end -0.7874 0.4064)
			(stroke
				(width 0.1524)
				(type default)
			)
			(layer "F.SilkS")
		)
		(fp_line
			(start -0.7874 -0.4064)
			(end 0.7874 -0.4064)
			(stroke
				(width 0.1524)
				(type default)
			)
			(layer "F.SilkS")
		)
		(fp_line
			(start 0.7874 -0.4064)
			(end 0.7874 0.4064)
			(stroke
				(width 0.1524)
				(type default)
			)
			(layer "F.SilkS")
		)
		(fp_line
			(start -0.67945 0.3048)
			(end -0.67945 -0.305054)
			(stroke
				(width 0.1)
				(type default)
			)
			(layer "F.Fab")
		)
		(fp_line
			(start -0.12065 0.3048)
			(end -0.67945 0.3048)
			(stroke
				(width 0.1)
				(type default)
			)
			(layer "F.Fab")
		)
		(fp_line
			(start 0.120396 0.3048)
			(end 0.120396 0.2794)
			(stroke
				(width 0.1)
				(type default)
			)
			(layer "F.Fab")
		)
		(fp_line
			(start 0.67945 0.3048)
			(end 0.120396 0.3048)
			(stroke
				(width 0.1)
				(type default)
			)
			(layer "F.Fab")
		)
		(fp_line
			(start -0.12065 0.2794)
			(end -0.12065 0.3048)
			(stroke
				(width 0.1)
				(type default)
			)
			(layer "F.Fab")
		)
		(fp_line
			(start 0.120396 0.2794)
			(end -0.12065 0.2794)
			(stroke
				(width 0.1)
				(type default)
			)
			(layer "F.Fab")
		)
		(fp_line
			(start -0.12065 -0.2794)
			(end 0.12065 -0.2794)
			(stroke
				(width 0.1)
				(type default)
			)
			(layer "F.Fab")
		)
		(fp_line
			(start 0.12065 -0.2794)
			(end 0.12065 -0.3048)
			(stroke
				(width 0.1)
				(type default)
			)
			(layer "F.Fab")
		)
		(fp_line
			(start 0.12065 -0.3048)
			(end 0.67945 -0.3048)
			(stroke
				(width 0.1)
				(type default)
			)
			(layer "F.Fab")
		)
		(fp_line
			(start 0.67945 -0.3048)
			(end 0.67945 0.3048)
			(stroke
				(width 0.1)
				(type default)
			)
			(layer "F.Fab")
		)
		(fp_line
			(start -0.67945 -0.305054)
			(end -0.12065 -0.305054)
			(stroke
				(width 0.1)
				(type default)
			)
			(layer "F.Fab")
		)
		(fp_line
			(start -0.12065 -0.305054)
			(end -0.12065 -0.2794)
			(stroke
				(width 0.1)
				(type default)
			)
			(layer "F.Fab")
		)
		(pad "1" smd circle
			(at -0.40005 0 270)
			(size 0 0)
			(layers "F.Cu" "F.Mask" "F.Paste")
			(net "P3V3_AUX")
		)
		(pad "2" smd circle
			(at 0.40005 0 270)
			(size 0 0)
			(layers "F.Cu" "F.Mask" "F.Paste")
			(net "FG_SS_EN")
		)
	)
	(footprint ""
		(layer "F.Cu")
		(at 94.817946 -178.29149 180)
		(property "Reference" "PC290_3"
			(at 0 0 180)
			(layer "F.SilkS")
			(hide yes)
			(effects
				(font
					(size 1.27 1.27)
				)
			)
		)
		(property "Value" ""
			(at 0 0 180)
			(layer "F.Fab")
			(effects
				(font
					(size 1.27 1.27)
				)
			)
		)
		(duplicate_pad_numbers_are_jumpers no)
		(fp_line
			(start 0.7874 0.4064)
			(end -0.7874 0.4064)
			(stroke
				(width 0.1524)
				(type default)
			)
			(layer "F.SilkS")
		)
		(fp_line
			(start 0.7874 -0.4064)
			(end 0.7874 0.4064)
			(stroke
				(width 0.1524)
				(type default)
			)
			(layer "F.SilkS")
		)
		(fp_line
			(start -0.7874 0.4064)
			(end -0.7874 -0.4064)
			(stroke
				(width 0.1524)
				(type default)
			)
			(layer "F.SilkS")
		)
		(fp_line
			(start -0.7874 -0.4064)
			(end 0.7874 -0.4064)
			(stroke
				(width 0.1524)
				(type default)
			)
			(layer "F.SilkS")
		)
		(fp_line
			(start 0.67945 0.3048)
			(end 0.120396 0.3048)
			(stroke
				(width 0.1)
				(type default)
			)
			(layer "F.Fab")
		)
		(fp_line
			(start 0.67945 -0.3048)
			(end 0.67945 0.3048)
			(stroke
				(width 0.1)
				(type default)
			)
			(layer "F.Fab")
		)
		(fp_line
			(start 0.12065 -0.2794)
			(end 0.12065 -0.3048)
			(stroke
				(width 0.1)
				(type default)
			)
			(layer "F.Fab")
		)
		(fp_line
			(start 0.12065 -0.3048)
			(end 0.67945 -0.3048)
			(stroke
				(width 0.1)
				(type default)
			)
			(layer "F.Fab")
		)
		(fp_line
			(start 0.120396 0.3048)
			(end 0.120396 0.2794)
			(stroke
				(width 0.1)
				(type default)
			)
			(layer "F.Fab")
		)
		(fp_line
			(start 0.120396 0.2794)
			(end -0.12065 0.2794)
			(stroke
				(width 0.1)
				(type default)
			)
			(layer "F.Fab")
		)
		(fp_line
			(start -0.12065 0.3048)
			(end -0.67945 0.3048)
			(stroke
				(width 0.1)
				(type default)
			)
			(layer "F.Fab")
		)
		(fp_line
			(start -0.12065 0.2794)
			(end -0.12065 0.3048)
			(stroke
				(width 0.1)
				(type default)
			)
			(layer "F.Fab")
		)
		(fp_line
			(start -0.12065 -0.2794)
			(end 0.12065 -0.2794)
			(stroke
				(width 0.1)
				(type default)
			)
			(layer "F.Fab")
		)
		(fp_line
			(start -0.12065 -0.305054)
			(end -0.12065 -0.2794)
			(stroke
				(width 0.1)
				(type default)
			)
			(layer "F.Fab")
		)
		(fp_line
			(start -0.67945 0.3048)
			(end -0.67945 -0.305054)
			(stroke
				(width 0.1)
				(type default)
			)
			(layer "F.Fab")
		)
		(fp_line
			(start -0.67945 -0.305054)
			(end -0.12065 -0.305054)
			(stroke
				(width 0.1)
				(type default)
			)
			(layer "F.Fab")
		)
		(pad "1" smd circle
			(at -0.40005 0 180)
			(size 0 0)
			(layers "F.Cu" "F.Mask" "F.Paste")
			(net "SW_P12V_AUX_PVDDCR_CPU0_P1_FLT")
		)
		(pad "2" smd circle
			(at 0.40005 0 180)
			(size 0 0)
			(layers "F.Cu" "F.Mask" "F.Paste")
			(net "GND")
		)
	)
	(footprint ""
		(layer "F.Cu")
		(at 301.423324 -489.286042)
		(property "Reference" "ME9"
			(at 0 0 0)
			(layer "F.SilkS")
			(hide yes)
			(effects
				(font
					(size 1.27 1.27)
				)
			)
		)
		(property "Value" ""
			(at 0 0 0)
			(layer "F.Fab")
			(effects
				(font
					(size 1.27 1.27)
				)
			)
		)
		(duplicate_pad_numbers_are_jumpers no)
	)
	(footprint ""
		(layer "F.Cu")
		(at 210.439 -104.013 180)
		(property "Reference" "R8037"
			(at 0 0 180)
			(layer "F.SilkS")
			(hide yes)
			(effects
				(font
					(size 1.27 1.27)
				)
			)
		)
		(property "Value" ""
			(at 0 0 180)
			(layer "F.Fab")
			(effects
				(font
					(size 1.27 1.27)
				)
			)
		)
		(duplicate_pad_numbers_are_jumpers no)
		(fp_line
			(start 0.7874 0.4064)
			(end -0.7874 0.4064)
			(stroke
				(width 0.1524)
				(type default)
			)
			(layer "F.SilkS")
		)
		(fp_line
			(start 0.7874 -0.4064)
			(end 0.7874 0.4064)
			(stroke
				(width 0.1524)
				(type default)
			)
			(layer "F.SilkS")
		)
		(fp_line
			(start -0.7874 0.4064)
			(end -0.7874 -0.4064)
			(stroke
				(width 0.1524)
				(type default)
			)
			(layer "F.SilkS")
		)
		(fp_line
			(start -0.7874 -0.4064)
			(end 0.7874 -0.4064)
			(stroke
				(width 0.1524)
				(type default)
			)
			(layer "F.SilkS")
		)
		(fp_line
			(start 0.67945 0.3048)
			(end 0.120396 0.3048)
			(stroke
				(width 0.1)
				(type default)
			)
			(layer "F.Fab")
		)
		(fp_line
			(start 0.67945 -0.3048)
			(end 0.67945 0.3048)
			(stroke
				(width 0.1)
				(type default)
			)
			(layer "F.Fab")
		)
		(fp_line
			(start 0.12065 -0.2794)
			(end 0.12065 -0.3048)
			(stroke
				(width 0.1)
				(type default)
			)
			(layer "F.Fab")
		)
		(fp_line
			(start 0.12065 -0.3048)
			(end 0.67945 -0.3048)
			(stroke
				(width 0.1)
				(type default)
			)
			(layer "F.Fab")
		)
		(fp_line
			(start 0.120396 0.3048)
			(end 0.120396 0.2794)
			(stroke
				(width 0.1)
				(type default)
			)
			(layer "F.Fab")
		)
		(fp_line
			(start 0.120396 0.2794)
			(end -0.12065 0.2794)
			(stroke
				(width 0.1)
				(type default)
			)
			(layer "F.Fab")
		)
		(fp_line
			(start -0.12065 0.3048)
			(end -0.67945 0.3048)
			(stroke
				(width 0.1)
				(type default)
			)
			(layer "F.Fab")
		)
		(fp_line
			(start -0.12065 0.2794)
			(end -0.12065 0.3048)
			(stroke
				(width 0.1)
				(type default)
			)
			(layer "F.Fab")
		)
		(fp_line
			(start -0.12065 -0.2794)
			(end 0.12065 -0.2794)
			(stroke
				(width 0.1)
				(type default)
			)
			(layer "F.Fab")
		)
		(fp_line
			(start -0.12065 -0.305054)
			(end -0.12065 -0.2794)
			(stroke
				(width 0.1)
				(type default)
			)
			(layer "F.Fab")
		)
		(fp_line
			(start -0.67945 0.3048)
			(end -0.67945 -0.305054)
			(stroke
				(width 0.1)
				(type default)
			)
			(layer "F.Fab")
		)
		(fp_line
			(start -0.67945 -0.305054)
			(end -0.12065 -0.305054)
			(stroke
				(width 0.1)
				(type default)
			)
			(layer "F.Fab")
		)
		(pad "1" smd circle
			(at -0.40005 0 180)
			(size 0 0)
			(layers "F.Cu" "F.Mask" "F.Paste")
			(net "P3V3_AUX")
		)
		(pad "2" smd circle
			(at 0.40005 0 180)
			(size 0 0)
			(layers "F.Cu" "F.Mask" "F.Paste")
			(net "PWRGD_CHAF_CPU0")
		)
	)
	(footprint ""
		(layer "F.Cu")
		(at 421.65524 -378.95403 -90)
		(property "Reference" "C844"
			(at 0 0 270)
			(layer "F.SilkS")
			(hide yes)
			(effects
				(font
					(size 1.27 1.27)
				)
			)
		)
		(property "Value" ""
			(at 0 0 270)
			(layer "F.Fab")
			(effects
				(font
					(size 1.27 1.27)
				)
			)
		)
		(duplicate_pad_numbers_are_jumpers no)
		(fp_line
			(start -0.299974 0.150114)
			(end -0.299974 -0.150114)
			(stroke
				(width 0.1)
				(type default)
			)
			(layer "F.Fab")
		)
		(fp_line
			(start 0.299974 0.150114)
			(end -0.299974 0.150114)
			(stroke
				(width 0.1)
				(type default)
			)
			(layer "F.Fab")
		)
		(fp_line
			(start -0.299974 -0.150114)
			(end 0.299974 -0.150114)
			(stroke
				(width 0.1)
				(type default)
			)
			(layer "F.Fab")
		)
		(fp_line
			(start 0.299974 -0.150114)
			(end 0.299974 0.150114)
			(stroke
				(width 0.1)
				(type default)
			)
			(layer "F.Fab")
		)
		(pad "1" smd rect
			(at -0.2667 0 270)
			(size 0.3048 0.381)
			(layers "F.Cu" "F.Mask" "F.Paste")
			(net "P5E_CPU0_P2_TX_C_DN<12>")
		)
		(pad "2" smd rect
			(at 0.2667 0 270)
			(size 0.3048 0.381)
			(layers "F.Cu" "F.Mask" "F.Paste")
			(net "P5E_CPU0_P2_TX_DN<12>")
		)
	)
	(footprint ""
		(layer "F.Cu")
		(at 367.791492 -378.95403 -90)
		(property "Reference" "C895"
			(at 0 0 270)
			(layer "F.SilkS")
			(hide yes)
			(effects
				(font
					(size 1.27 1.27)
				)
			)
		)
		(property "Value" ""
			(at 0 0 270)
			(layer "F.Fab")
			(effects
				(font
					(size 1.27 1.27)
				)
			)
		)
		(duplicate_pad_numbers_are_jumpers no)
		(fp_line
			(start -0.299974 0.150114)
			(end -0.299974 -0.150114)
			(stroke
				(width 0.1)
				(type default)
			)
			(layer "F.Fab")
		)
		(fp_line
			(start 0.299974 0.150114)
			(end -0.299974 0.150114)
			(stroke
				(width 0.1)
				(type default)
			)
			(layer "F.Fab")
		)
		(fp_line
			(start -0.299974 -0.150114)
			(end 0.299974 -0.150114)
			(stroke
				(width 0.1)
				(type default)
			)
			(layer "F.Fab")
		)
		(fp_line
			(start 0.299974 -0.150114)
			(end 0.299974 0.150114)
			(stroke
				(width 0.1)
				(type default)
			)
			(layer "F.Fab")
		)
		(pad "1" smd rect
			(at -0.2667 0 270)
			(size 0.3048 0.381)
			(layers "F.Cu" "F.Mask" "F.Paste")
			(net "P5E_CPU0_P3_TX_C_DP<3>")
		)
		(pad "2" smd rect
			(at 0.2667 0 270)
			(size 0.3048 0.381)
			(layers "F.Cu" "F.Mask" "F.Paste")
			(net "P5E_CPU0_P3_TX_DP<3>")
		)
	)
	(footprint ""
		(layer "F.Cu")
		(at 180.528468 -50.974498)
		(property "Reference" "C1101"
			(at 0 0 0)
			(layer "F.SilkS")
			(hide yes)
			(effects
				(font
					(size 1.27 1.27)
				)
			)
		)
		(property "Value" ""
			(at 0 0 0)
			(layer "F.Fab")
			(effects
				(font
					(size 1.27 1.27)
				)
			)
		)
		(duplicate_pad_numbers_are_jumpers no)
		(fp_line
			(start -0.299974 -0.150114)
			(end 0.299974 -0.150114)
			(stroke
				(width 0.1)
				(type default)
			)
			(layer "F.Fab")
		)
		(fp_line
			(start -0.299974 0.150114)
			(end -0.299974 -0.150114)
			(stroke
				(width 0.1)
				(type default)
			)
			(layer "F.Fab")
		)
		(fp_line
			(start 0.299974 -0.150114)
			(end 0.299974 0.150114)
			(stroke
				(width 0.1)
				(type default)
			)
			(layer "F.Fab")
		)
		(fp_line
			(start 0.299974 0.150114)
			(end -0.299974 0.150114)
			(stroke
				(width 0.1)
				(type default)
			)
			(layer "F.Fab")
		)
		(pad "1" smd rect
			(at -0.2667 0)
			(size 0.3048 0.381)
			(layers "F.Cu" "F.Mask" "F.Paste")
			(net "P3E_CPU1_P4_TX_C_DN<2>")
		)
		(pad "2" smd rect
			(at 0.2667 0)
			(size 0.3048 0.381)
			(layers "F.Cu" "F.Mask" "F.Paste")
			(net "P3E_CPU1_P4_TX_DN<2>")
		)
	)
	(footprint ""
		(layer "F.Cu")
		(at 314.668662 -333.260954 90)
		(property "Reference" "PR510"
			(at 0 0 90)
			(layer "F.SilkS")
			(hide yes)
			(effects
				(font
					(size 1.27 1.27)
				)
			)
		)
		(property "Value" ""
			(at 0 0 90)
			(layer "F.Fab")
			(effects
				(font
					(size 1.27 1.27)
				)
			)
		)
		(duplicate_pad_numbers_are_jumpers no)
		(fp_line
			(start 0.7874 -0.4064)
			(end 0.7874 0.4064)
			(stroke
				(width 0.1524)
				(type default)
			)
			(layer "F.SilkS")
		)
		(fp_line
			(start -0.7874 -0.4064)
			(end 0.7874 -0.4064)
			(stroke
				(width 0.1524)
				(type default)
			)
			(layer "F.SilkS")
		)
		(fp_line
			(start 0.7874 0.4064)
			(end -0.7874 0.4064)
			(stroke
				(width 0.1524)
				(type default)
			)
			(layer "F.SilkS")
		)
		(fp_line
			(start -0.7874 0.4064)
			(end -0.7874 -0.4064)
			(stroke
				(width 0.1524)
				(type default)
			)
			(layer "F.SilkS")
		)
		(fp_line
			(start -0.12065 -0.305054)
			(end -0.12065 -0.2794)
			(stroke
				(width 0.1)
				(type default)
			)
			(layer "F.Fab")
		)
		(fp_line
			(start -0.67945 -0.305054)
			(end -0.12065 -0.305054)
			(stroke
				(width 0.1)
				(type default)
			)
			(layer "F.Fab")
		)
		(fp_line
			(start 0.67945 -0.3048)
			(end 0.67945 0.3048)
			(stroke
				(width 0.1)
				(type default)
			)
			(layer "F.Fab")
		)
		(fp_line
			(start 0.12065 -0.3048)
			(end 0.67945 -0.3048)
			(stroke
				(width 0.1)
				(type default)
			)
			(layer "F.Fab")
		)
		(fp_line
			(start 0.12065 -0.2794)
			(end 0.12065 -0.3048)
			(stroke
				(width 0.1)
				(type default)
			)
			(layer "F.Fab")
		)
		(fp_line
			(start -0.12065 -0.2794)
			(end 0.12065 -0.2794)
			(stroke
				(width 0.1)
				(type default)
			)
			(layer "F.Fab")
		)
		(fp_line
			(start 0.120396 0.2794)
			(end -0.12065 0.2794)
			(stroke
				(width 0.1)
				(type default)
			)
			(layer "F.Fab")
		)
		(fp_line
			(start -0.12065 0.2794)
			(end -0.12065 0.3048)
			(stroke
				(width 0.1)
				(type default)
			)
			(layer "F.Fab")
		)
		(fp_line
			(start 0.67945 0.3048)
			(end 0.120396 0.3048)
			(stroke
				(width 0.1)
				(type default)
			)
			(layer "F.Fab")
		)
		(fp_line
			(start 0.120396 0.3048)
			(end 0.120396 0.2794)
			(stroke
				(width 0.1)
				(type default)
			)
			(layer "F.Fab")
		)
		(fp_line
			(start -0.12065 0.3048)
			(end -0.67945 0.3048)
			(stroke
				(width 0.1)
				(type default)
			)
			(layer "F.Fab")
		)
		(fp_line
			(start -0.67945 0.3048)
			(end -0.67945 -0.305054)
			(stroke
				(width 0.1)
				(type default)
			)
			(layer "F.Fab")
		)
		(pad "1" smd circle
			(at -0.40005 0 90)
			(size 0 0)
			(layers "F.Cu" "F.Mask" "F.Paste")
			(net "SW_PVDDCR_CPU1_P0_SW3_RC")
		)
		(pad "2" smd circle
			(at 0.40005 0 90)
			(size 0 0)
			(layers "F.Cu" "F.Mask" "F.Paste")
			(net "GND")
		)
	)
	(footprint ""
		(layer "F.Cu")
		(at 292.767512 -351.368106 90)
		(property "Reference" "PR102"
			(at 0 0 90)
			(layer "F.SilkS")
			(hide yes)
			(effects
				(font
					(size 1.27 1.27)
				)
			)
		)
		(property "Value" ""
			(at 0 0 90)
			(layer "F.Fab")
			(effects
				(font
					(size 1.27 1.27)
				)
			)
		)
		(duplicate_pad_numbers_are_jumpers no)
		(fp_line
			(start 0.7874 -0.4064)
			(end 0.7874 0.4064)
			(stroke
				(width 0.1524)
				(type default)
			)
			(layer "F.SilkS")
		)
		(fp_line
			(start -0.7874 -0.4064)
			(end 0.7874 -0.4064)
			(stroke
				(width 0.1524)
				(type default)
			)
			(layer "F.SilkS")
		)
		(fp_line
			(start 0.7874 0.4064)
			(end -0.7874 0.4064)
			(stroke
				(width 0.1524)
				(type default)
			)
			(layer "F.SilkS")
		)
		(fp_line
			(start -0.7874 0.4064)
			(end -0.7874 -0.4064)
			(stroke
				(width 0.1524)
				(type default)
			)
			(layer "F.SilkS")
		)
		(fp_line
			(start -0.12065 -0.305054)
			(end -0.12065 -0.2794)
			(stroke
				(width 0.1)
				(type default)
			)
			(layer "F.Fab")
		)
		(fp_line
			(start -0.67945 -0.305054)
			(end -0.12065 -0.305054)
			(stroke
				(width 0.1)
				(type default)
			)
			(layer "F.Fab")
		)
		(fp_line
			(start 0.67945 -0.3048)
			(end 0.67945 0.3048)
			(stroke
				(width 0.1)
				(type default)
			)
			(layer "F.Fab")
		)
		(fp_line
			(start 0.12065 -0.3048)
			(end 0.67945 -0.3048)
			(stroke
				(width 0.1)
				(type default)
			)
			(layer "F.Fab")
		)
		(fp_line
			(start 0.12065 -0.2794)
			(end 0.12065 -0.3048)
			(stroke
				(width 0.1)
				(type default)
			)
			(layer "F.Fab")
		)
		(fp_line
			(start -0.12065 -0.2794)
			(end 0.12065 -0.2794)
			(stroke
				(width 0.1)
				(type default)
			)
			(layer "F.Fab")
		)
		(fp_line
			(start 0.120396 0.2794)
			(end -0.12065 0.2794)
			(stroke
				(width 0.1)
				(type default)
			)
			(layer "F.Fab")
		)
		(fp_line
			(start -0.12065 0.2794)
			(end -0.12065 0.3048)
			(stroke
				(width 0.1)
				(type default)
			)
			(layer "F.Fab")
		)
		(fp_line
			(start 0.67945 0.3048)
			(end 0.120396 0.3048)
			(stroke
				(width 0.1)
				(type default)
			)
			(layer "F.Fab")
		)
		(fp_line
			(start 0.120396 0.3048)
			(end 0.120396 0.2794)
			(stroke
				(width 0.1)
				(type default)
			)
			(layer "F.Fab")
		)
		(fp_line
			(start -0.12065 0.3048)
			(end -0.67945 0.3048)
			(stroke
				(width 0.1)
				(type default)
			)
			(layer "F.Fab")
		)
		(fp_line
			(start -0.67945 0.3048)
			(end -0.67945 -0.305054)
			(stroke
				(width 0.1)
				(type default)
			)
			(layer "F.Fab")
		)
		(pad "1" smd circle
			(at -0.40005 0 90)
			(size 0 0)
			(layers "F.Cu" "F.Mask" "F.Paste")
			(net "SW_PVDDIO_P0_BOOT2")
		)
		(pad "2" smd circle
			(at 0.40005 0 90)
			(size 0 0)
			(layers "F.Cu" "F.Mask" "F.Paste")
			(net "SW_PVDDIO_P0_BOOT2_R")
		)
	)
	(footprint ""
		(layer "F.Cu")
		(at 424.14444 -378.95403 -90)
		(property "Reference" "C843"
			(at 0 0 270)
			(layer "F.SilkS")
			(hide yes)
			(effects
				(font
					(size 1.27 1.27)
				)
			)
		)
		(property "Value" ""
			(at 0 0 270)
			(layer "F.Fab")
			(effects
				(font
					(size 1.27 1.27)
				)
			)
		)
		(duplicate_pad_numbers_are_jumpers no)
		(fp_line
			(start -0.299974 0.150114)
			(end -0.299974 -0.150114)
			(stroke
				(width 0.1)
				(type default)
			)
			(layer "F.Fab")
		)
		(fp_line
			(start 0.299974 0.150114)
			(end -0.299974 0.150114)
			(stroke
				(width 0.1)
				(type default)
			)
			(layer "F.Fab")
		)
		(fp_line
			(start -0.299974 -0.150114)
			(end 0.299974 -0.150114)
			(stroke
				(width 0.1)
				(type default)
			)
			(layer "F.Fab")
		)
		(fp_line
			(start 0.299974 -0.150114)
			(end 0.299974 0.150114)
			(stroke
				(width 0.1)
				(type default)
			)
			(layer "F.Fab")
		)
		(pad "1" smd rect
			(at -0.2667 0 270)
			(size 0.3048 0.381)
			(layers "F.Cu" "F.Mask" "F.Paste")
			(net "P5E_CPU0_P2_TX_C_DP<13>")
		)
		(pad "2" smd rect
			(at 0.2667 0 270)
			(size 0.3048 0.381)
			(layers "F.Cu" "F.Mask" "F.Paste")
			(net "P5E_CPU0_P2_TX_DP<13>")
		)
	)
	(footprint ""
		(layer "F.Cu")
		(at 68.516754 -370.57203 -90)
		(property "Reference" "C810"
			(at 0 0 270)
			(layer "F.SilkS")
			(hide yes)
			(effects
				(font
					(size 1.27 1.27)
				)
			)
		)
		(property "Value" ""
			(at 0 0 270)
			(layer "F.Fab")
			(effects
				(font
					(size 1.27 1.27)
				)
			)
		)
		(duplicate_pad_numbers_are_jumpers no)
		(fp_line
			(start -0.299974 0.150114)
			(end -0.299974 -0.150114)
			(stroke
				(width 0.1)
				(type default)
			)
			(layer "F.Fab")
		)
		(fp_line
			(start 0.299974 0.150114)
			(end -0.299974 0.150114)
			(stroke
				(width 0.1)
				(type default)
			)
			(layer "F.Fab")
		)
		(fp_line
			(start -0.299974 -0.150114)
			(end 0.299974 -0.150114)
			(stroke
				(width 0.1)
				(type default)
			)
			(layer "F.Fab")
		)
		(fp_line
			(start 0.299974 -0.150114)
			(end 0.299974 0.150114)
			(stroke
				(width 0.1)
				(type default)
			)
			(layer "F.Fab")
		)
		(pad "1" smd rect
			(at -0.2667 0 270)
			(size 0.3048 0.381)
			(layers "F.Cu" "F.Mask" "F.Paste")
			(net "P5E_CPU1_P0_TX_C_DN<13>")
		)
		(pad "2" smd rect
			(at 0.2667 0 270)
			(size 0.3048 0.381)
			(layers "F.Cu" "F.Mask" "F.Paste")
			(net "P5E_CPU1_P0_TX_DN<13>")
		)
	)
	(footprint ""
		(layer "F.Cu")
		(at 75.64501 -148.451316 90)
		(property "Reference" "R8009"
			(at 0 0 90)
			(layer "F.SilkS")
			(hide yes)
			(effects
				(font
					(size 1.27 1.27)
				)
			)
		)
		(property "Value" ""
			(at 0 0 90)
			(layer "F.Fab")
			(effects
				(font
					(size 1.27 1.27)
				)
			)
		)
		(duplicate_pad_numbers_are_jumpers no)
		(fp_line
			(start 0.7874 -0.4064)
			(end 0.7874 0.4064)
			(stroke
				(width 0.1524)
				(type default)
			)
			(layer "F.SilkS")
		)
		(fp_line
			(start -0.7874 -0.4064)
			(end 0.7874 -0.4064)
			(stroke
				(width 0.1524)
				(type default)
			)
			(layer "F.SilkS")
		)
		(fp_line
			(start 0.7874 0.4064)
			(end -0.7874 0.4064)
			(stroke
				(width 0.1524)
				(type default)
			)
			(layer "F.SilkS")
		)
		(fp_line
			(start -0.7874 0.4064)
			(end -0.7874 -0.4064)
			(stroke
				(width 0.1524)
				(type default)
			)
			(layer "F.SilkS")
		)
		(fp_line
			(start -0.12065 -0.305054)
			(end -0.12065 -0.2794)
			(stroke
				(width 0.1)
				(type default)
			)
			(layer "F.Fab")
		)
		(fp_line
			(start -0.67945 -0.305054)
			(end -0.12065 -0.305054)
			(stroke
				(width 0.1)
				(type default)
			)
			(layer "F.Fab")
		)
		(fp_line
			(start 0.67945 -0.3048)
			(end 0.67945 0.3048)
			(stroke
				(width 0.1)
				(type default)
			)
			(layer "F.Fab")
		)
		(fp_line
			(start 0.12065 -0.3048)
			(end 0.67945 -0.3048)
			(stroke
				(width 0.1)
				(type default)
			)
			(layer "F.Fab")
		)
		(fp_line
			(start 0.12065 -0.2794)
			(end 0.12065 -0.3048)
			(stroke
				(width 0.1)
				(type default)
			)
			(layer "F.Fab")
		)
		(fp_line
			(start -0.12065 -0.2794)
			(end 0.12065 -0.2794)
			(stroke
				(width 0.1)
				(type default)
			)
			(layer "F.Fab")
		)
		(fp_line
			(start 0.120396 0.2794)
			(end -0.12065 0.2794)
			(stroke
				(width 0.1)
				(type default)
			)
			(layer "F.Fab")
		)
		(fp_line
			(start -0.12065 0.2794)
			(end -0.12065 0.3048)
			(stroke
				(width 0.1)
				(type default)
			)
			(layer "F.Fab")
		)
		(fp_line
			(start 0.67945 0.3048)
			(end 0.120396 0.3048)
			(stroke
				(width 0.1)
				(type default)
			)
			(layer "F.Fab")
		)
		(fp_line
			(start 0.120396 0.3048)
			(end 0.120396 0.2794)
			(stroke
				(width 0.1)
				(type default)
			)
			(layer "F.Fab")
		)
		(fp_line
			(start -0.12065 0.3048)
			(end -0.67945 0.3048)
			(stroke
				(width 0.1)
				(type default)
			)
			(layer "F.Fab")
		)
		(fp_line
			(start -0.67945 0.3048)
			(end -0.67945 -0.305054)
			(stroke
				(width 0.1)
				(type default)
			)
			(layer "F.Fab")
		)
		(pad "1" smd circle
			(at -0.40005 0 90)
			(size 0 0)
			(layers "F.Cu" "F.Mask" "F.Paste")
			(net "P3V3_AUX")
		)
		(pad "2" smd circle
			(at 0.40005 0 90)
			(size 0 0)
			(layers "F.Cu" "F.Mask" "F.Paste")
			(net "PWRGD_PVDD18_S5_P1")
		)
	)
	(footprint ""
		(layer "F.Cu")
		(at 179.9082 -96.103948 90)
		(property "Reference" "R187"
			(at 0 0 90)
			(layer "F.SilkS")
			(hide yes)
			(effects
				(font
					(size 1.27 1.27)
				)
			)
		)
		(property "Value" ""
			(at 0 0 90)
			(layer "F.Fab")
			(effects
				(font
					(size 1.27 1.27)
				)
			)
		)
		(duplicate_pad_numbers_are_jumpers no)
		(fp_line
			(start 0.7874 -0.4064)
			(end 0.7874 0.4064)
			(stroke
				(width 0.1524)
				(type default)
			)
			(layer "F.SilkS")
		)
		(fp_line
			(start -0.7874 -0.4064)
			(end 0.7874 -0.4064)
			(stroke
				(width 0.1524)
				(type default)
			)
			(layer "F.SilkS")
		)
		(fp_line
			(start 0.7874 0.4064)
			(end -0.7874 0.4064)
			(stroke
				(width 0.1524)
				(type default)
			)
			(layer "F.SilkS")
		)
		(fp_line
			(start -0.7874 0.4064)
			(end -0.7874 -0.4064)
			(stroke
				(width 0.1524)
				(type default)
			)
			(layer "F.SilkS")
		)
		(fp_line
			(start -0.12065 -0.305054)
			(end -0.12065 -0.2794)
			(stroke
				(width 0.1)
				(type default)
			)
			(layer "F.Fab")
		)
		(fp_line
			(start -0.67945 -0.305054)
			(end -0.12065 -0.305054)
			(stroke
				(width 0.1)
				(type default)
			)
			(layer "F.Fab")
		)
		(fp_line
			(start 0.67945 -0.3048)
			(end 0.67945 0.3048)
			(stroke
				(width 0.1)
				(type default)
			)
			(layer "F.Fab")
		)
		(fp_line
			(start 0.12065 -0.3048)
			(end 0.67945 -0.3048)
			(stroke
				(width 0.1)
				(type default)
			)
			(layer "F.Fab")
		)
		(fp_line
			(start 0.12065 -0.2794)
			(end 0.12065 -0.3048)
			(stroke
				(width 0.1)
				(type default)
			)
			(layer "F.Fab")
		)
		(fp_line
			(start -0.12065 -0.2794)
			(end 0.12065 -0.2794)
			(stroke
				(width 0.1)
				(type default)
			)
			(layer "F.Fab")
		)
		(fp_line
			(start 0.120396 0.2794)
			(end -0.12065 0.2794)
			(stroke
				(width 0.1)
				(type default)
			)
			(layer "F.Fab")
		)
		(fp_line
			(start -0.12065 0.2794)
			(end -0.12065 0.3048)
			(stroke
				(width 0.1)
				(type default)
			)
			(layer "F.Fab")
		)
		(fp_line
			(start 0.67945 0.3048)
			(end 0.120396 0.3048)
			(stroke
				(width 0.1)
				(type default)
			)
			(layer "F.Fab")
		)
		(fp_line
			(start 0.120396 0.3048)
			(end 0.120396 0.2794)
			(stroke
				(width 0.1)
				(type default)
			)
			(layer "F.Fab")
		)
		(fp_line
			(start -0.12065 0.3048)
			(end -0.67945 0.3048)
			(stroke
				(width 0.1)
				(type default)
			)
			(layer "F.Fab")
		)
		(fp_line
			(start -0.67945 0.3048)
			(end -0.67945 -0.305054)
			(stroke
				(width 0.1)
				(type default)
			)
			(layer "F.Fab")
		)
		(pad "1" smd circle
			(at -0.40005 0 90)
			(size 0 0)
			(layers "F.Cu" "F.Mask" "F.Paste")
			(net "IRQ_CPU_BMC_NMI_N")
		)
		(pad "2" smd circle
			(at 0.40005 0 90)
			(size 0 0)
			(layers "F.Cu" "F.Mask" "F.Paste")
			(net "IRQ_CPU_BMC_NMI_R_N")
		)
	)
	(footprint ""
		(layer "F.Cu")
		(at 214.344504 -17.766792 -90)
		(property "Reference" "U90"
			(at -0.832612 -2.35331 90)
			(unlocked yes)
			(layer "F.SilkS")
			(effects
				(font
					(size 0.7874 0.5842)
					(thickness 0.1524)
				)
				(justify left)
			)
		)
		(property "Value" ""
			(at 0 0 270)
			(layer "F.Fab")
			(effects
				(font
					(size 1.27 1.27)
				)
			)
		)
		(duplicate_pad_numbers_are_jumpers no)
		(fp_line
			(start -2.25044 1.5494)
			(end -2.25044 1.3208)
			(stroke
				(width 0.1524)
				(type default)
			)
			(layer "F.SilkS")
		)
		(fp_line
			(start 2.25044 1.5494)
			(end -2.25044 1.5494)
			(stroke
				(width 0.1524)
				(type default)
			)
			(layer "F.SilkS")
		)
		(fp_line
			(start 2.25044 1.3208)
			(end 2.25044 1.5494)
			(stroke
				(width 0.1524)
				(type default)
			)
			(layer "F.SilkS")
		)
		(fp_line
			(start 0 -0.9652)
			(end -0.5842 -1.5494)
			(stroke
				(width 0.1524)
				(type default)
			)
			(layer "F.SilkS")
		)
		(fp_line
			(start 2.25044 -1.3208)
			(end 2.25044 -1.5494)
			(stroke
				(width 0.1524)
				(type default)
			)
			(layer "F.SilkS")
		)
		(fp_line
			(start -2.25044 -1.5494)
			(end -2.25044 -1.3208)
			(stroke
				(width 0.1524)
				(type default)
			)
			(layer "F.SilkS")
		)
		(fp_line
			(start -0.5842 -1.5494)
			(end -2.25044 -1.5494)
			(stroke
				(width 0.1524)
				(type default)
			)
			(layer "F.SilkS")
		)
		(fp_line
			(start 0.5842 -1.5494)
			(end 0 -0.9652)
			(stroke
				(width 0.1524)
				(type default)
			)
			(layer "F.SilkS")
		)
		(fp_line
			(start 2.0066 -1.5494)
			(end 0.5842 -1.5494)
			(stroke
				(width 0.1524)
				(type default)
			)
			(layer "F.SilkS")
		)
		(fp_line
			(start 2.25044 -1.5494)
			(end 0.5842 -1.5494)
			(stroke
				(width 0.1524)
				(type default)
			)
			(layer "F.SilkS")
		)
		(fp_poly
			(pts
				(xy -3.81 -1.016) (xy -4.36372 -0.719328) (xy -4.36372 -1.344168)
			)
			(stroke
				(width 0)
				(type default)
			)
			(fill yes)
			(layer "F.SilkS")
		)
		(fp_line
			(start -2.25044 1.5494)
			(end 2.25044 1.5494)
			(stroke
				(width 0.1)
				(type default)
			)
			(layer "F.Fab")
		)
		(fp_line
			(start -2.25044 1.5494)
			(end -2.25044 1.12522)
			(stroke
				(width 0.1)
				(type default)
			)
			(layer "F.Fab")
		)
		(fp_line
			(start 2.25044 1.5494)
			(end 2.25044 1.12522)
			(stroke
				(width 0.1)
				(type default)
			)
			(layer "F.Fab")
		)
		(fp_line
			(start 2.25044 1.5494)
			(end 2.25044 -1.5494)
			(stroke
				(width 0.1)
				(type default)
			)
			(layer "F.Fab")
		)
		(fp_line
			(start 2.25044 1.143)
			(end 2.25044 1.0922)
			(stroke
				(width 0.1)
				(type default)
			)
			(layer "F.Fab")
		)
		(fp_line
			(start -3.302 1.12522)
			(end -3.302 -1.12522)
			(stroke
				(width 0.1)
				(type default)
			)
			(layer "F.Fab")
		)
		(fp_line
			(start -2.25044 1.12522)
			(end -3.302 1.12522)
			(stroke
				(width 0.1)
				(type default)
			)
			(layer "F.Fab")
		)
		(fp_line
			(start 2.25044 1.12522)
			(end 3.302 1.12522)
			(stroke
				(width 0.1)
				(type default)
			)
			(layer "F.Fab")
		)
		(fp_line
			(start 3.302 1.12522)
			(end 3.302 -1.12522)
			(stroke
				(width 0.1)
				(type default)
			)
			(layer "F.Fab")
		)
		(fp_line
			(start -3.302 -1.12522)
			(end -2.25044 -1.12522)
			(stroke
				(width 0.1)
				(type default)
			)
			(layer "F.Fab")
		)
		(fp_line
			(start -2.25044 -1.12522)
			(end -2.25044 -1.5494)
			(stroke
				(width 0.1)
				(type default)
			)
			(layer "F.Fab")
		)
		(fp_line
			(start 2.25044 -1.12522)
			(end 2.25044 -1.4986)
			(stroke
				(width 0.1)
				(type default)
			)
			(layer "F.Fab")
		)
		(fp_line
			(start 3.302 -1.12522)
			(end 2.25044 -1.12522)
			(stroke
				(width 0.1)
				(type default)
			)
			(layer "F.Fab")
		)
		(fp_line
			(start -2.25044 -1.5494)
			(end -2.25044 1.5494)
			(stroke
				(width 0.1)
				(type default)
			)
			(layer "F.Fab")
		)
		(fp_line
			(start 2.25044 -1.5494)
			(end -2.25044 -1.5494)
			(stroke
				(width 0.1)
				(type default)
			)
			(layer "F.Fab")
		)
		(fp_poly
			(pts
				(xy -4.36372 -0.719328) (xy -4.36372 -1.344168) (xy -3.81 -1.016)
			)
			(stroke
				(width 0)
				(type default)
			)
			(fill yes)
			(layer "F.Fab")
		)
		(pad "1" smd rect
			(at -2.921 -0.975106 180)
			(size 0.3556 1.4986)
			(layers "F.Cu" "F.Mask" "F.Paste")
			(net "CLK_50M_RMII_R")
		)
		(pad "2" smd rect
			(at -2.921 -0.32512 180)
			(size 0.3556 1.4986)
			(layers "F.Cu" "F.Mask" "F.Paste")
			(net "CLK_50M_EN")
		)
		(pad "3" smd rect
			(at -2.921 0.32512 180)
			(size 0.3556 1.4986)
			(layers "F.Cu" "F.Mask" "F.Paste")
			(net "CLK_50M_BMC_MAC_R")
		)
		(pad "4" smd rect
			(at -2.921 0.975106 180)
			(size 0.3556 1.4986)
			(layers "F.Cu" "F.Mask" "F.Paste")
			(net "GND")
		)
		(pad "5" smd rect
			(at 2.921 0.975106 180)
			(size 0.3556 1.4986)
			(layers "F.Cu" "F.Mask" "F.Paste")
			(net "CLK_50M_NCSI_OCP_1")
		)
		(pad "6" smd rect
			(at 2.921 0.32512 180)
			(size 0.3556 1.4986)
			(layers "F.Cu" "F.Mask" "F.Paste")
			(net "P3V3_AUX")
		)
		(pad "7" smd rect
			(at 2.921 -0.32512 180)
			(size 0.3556 1.4986)
			(layers "F.Cu" "F.Mask" "F.Paste")
			(net "CLK_50M_NCSI_OCP_2")
		)
		(pad "8" smd rect
			(at 2.921 -0.975106 180)
			(size 0.3556 1.4986)
			(layers "F.Cu" "F.Mask" "F.Paste")
			(net "TP_CLK_50M_Y3")
		)
	)
	(footprint ""
		(layer "F.Cu")
		(at 280.67 -426.212 90)
		(property "Reference" "C77"
			(at 0 0 90)
			(layer "F.SilkS")
			(hide yes)
			(effects
				(font
					(size 1.27 1.27)
				)
			)
		)
		(property "Value" ""
			(at 0 0 90)
			(layer "F.Fab")
			(effects
				(font
					(size 1.27 1.27)
				)
			)
		)
		(duplicate_pad_numbers_are_jumpers no)
		(fp_line
			(start 0.7874 -0.4064)
			(end 0.7874 0.4064)
			(stroke
				(width 0.1524)
				(type default)
			)
			(layer "F.SilkS")
		)
		(fp_line
			(start -0.7874 -0.4064)
			(end 0.7874 -0.4064)
			(stroke
				(width 0.1524)
				(type default)
			)
			(layer "F.SilkS")
		)
		(fp_line
			(start 0.7874 0.4064)
			(end -0.7874 0.4064)
			(stroke
				(width 0.1524)
				(type default)
			)
			(layer "F.SilkS")
		)
		(fp_line
			(start -0.7874 0.4064)
			(end -0.7874 -0.4064)
			(stroke
				(width 0.1524)
				(type default)
			)
			(layer "F.SilkS")
		)
		(fp_line
			(start -0.12065 -0.305054)
			(end -0.12065 -0.2794)
			(stroke
				(width 0.1)
				(type default)
			)
			(layer "F.Fab")
		)
		(fp_line
			(start -0.67945 -0.305054)
			(end -0.12065 -0.305054)
			(stroke
				(width 0.1)
				(type default)
			)
			(layer "F.Fab")
		)
		(fp_line
			(start 0.67945 -0.3048)
			(end 0.67945 0.3048)
			(stroke
				(width 0.1)
				(type default)
			)
			(layer "F.Fab")
		)
		(fp_line
			(start 0.12065 -0.3048)
			(end 0.67945 -0.3048)
			(stroke
				(width 0.1)
				(type default)
			)
			(layer "F.Fab")
		)
		(fp_line
			(start 0.12065 -0.2794)
			(end 0.12065 -0.3048)
			(stroke
				(width 0.1)
				(type default)
			)
			(layer "F.Fab")
		)
		(fp_line
			(start -0.12065 -0.2794)
			(end 0.12065 -0.2794)
			(stroke
				(width 0.1)
				(type default)
			)
			(layer "F.Fab")
		)
		(fp_line
			(start 0.120396 0.2794)
			(end -0.12065 0.2794)
			(stroke
				(width 0.1)
				(type default)
			)
			(layer "F.Fab")
		)
		(fp_line
			(start -0.12065 0.2794)
			(end -0.12065 0.3048)
			(stroke
				(width 0.1)
				(type default)
			)
			(layer "F.Fab")
		)
		(fp_line
			(start 0.67945 0.3048)
			(end 0.120396 0.3048)
			(stroke
				(width 0.1)
				(type default)
			)
			(layer "F.Fab")
		)
		(fp_line
			(start 0.120396 0.3048)
			(end 0.120396 0.2794)
			(stroke
				(width 0.1)
				(type default)
			)
			(layer "F.Fab")
		)
		(fp_line
			(start -0.12065 0.3048)
			(end -0.67945 0.3048)
			(stroke
				(width 0.1)
				(type default)
			)
			(layer "F.Fab")
		)
		(fp_line
			(start -0.67945 0.3048)
			(end -0.67945 -0.305054)
			(stroke
				(width 0.1)
				(type default)
			)
			(layer "F.Fab")
		)
		(pad "1" smd circle
			(at -0.40005 0 90)
			(size 0 0)
			(layers "F.Cu" "F.Mask" "F.Paste")
			(net "P3V3_9ZXL045_P0_VDDR")
		)
		(pad "2" smd circle
			(at 0.40005 0 90)
			(size 0 0)
			(layers "F.Cu" "F.Mask" "F.Paste")
			(net "GND")
		)
	)
	(footprint ""
		(layer "F.Cu")
		(at 445.19088 -95.872808 180)
		(property "Reference" "R3601"
			(at 0 0 180)
			(layer "F.SilkS")
			(hide yes)
			(effects
				(font
					(size 1.27 1.27)
				)
			)
		)
		(property "Value" ""
			(at 0 0 180)
			(layer "F.Fab")
			(effects
				(font
					(size 1.27 1.27)
				)
			)
		)
		(duplicate_pad_numbers_are_jumpers no)
		(fp_line
			(start 0.7874 0.4064)
			(end -0.7874 0.4064)
			(stroke
				(width 0.1524)
				(type default)
			)
			(layer "F.SilkS")
		)
		(fp_line
			(start 0.7874 -0.4064)
			(end 0.7874 0.4064)
			(stroke
				(width 0.1524)
				(type default)
			)
			(layer "F.SilkS")
		)
		(fp_line
			(start -0.7874 0.4064)
			(end -0.7874 -0.4064)
			(stroke
				(width 0.1524)
				(type default)
			)
			(layer "F.SilkS")
		)
		(fp_line
			(start -0.7874 -0.4064)
			(end 0.7874 -0.4064)
			(stroke
				(width 0.1524)
				(type default)
			)
			(layer "F.SilkS")
		)
		(fp_line
			(start 0.67945 0.3048)
			(end 0.120396 0.3048)
			(stroke
				(width 0.1)
				(type default)
			)
			(layer "F.Fab")
		)
		(fp_line
			(start 0.67945 -0.3048)
			(end 0.67945 0.3048)
			(stroke
				(width 0.1)
				(type default)
			)
			(layer "F.Fab")
		)
		(fp_line
			(start 0.12065 -0.2794)
			(end 0.12065 -0.3048)
			(stroke
				(width 0.1)
				(type default)
			)
			(layer "F.Fab")
		)
		(fp_line
			(start 0.12065 -0.3048)
			(end 0.67945 -0.3048)
			(stroke
				(width 0.1)
				(type default)
			)
			(layer "F.Fab")
		)
		(fp_line
			(start 0.120396 0.3048)
			(end 0.120396 0.2794)
			(stroke
				(width 0.1)
				(type default)
			)
			(layer "F.Fab")
		)
		(fp_line
			(start 0.120396 0.2794)
			(end -0.12065 0.2794)
			(stroke
				(width 0.1)
				(type default)
			)
			(layer "F.Fab")
		)
		(fp_line
			(start -0.12065 0.3048)
			(end -0.67945 0.3048)
			(stroke
				(width 0.1)
				(type default)
			)
			(layer "F.Fab")
		)
		(fp_line
			(start -0.12065 0.2794)
			(end -0.12065 0.3048)
			(stroke
				(width 0.1)
				(type default)
			)
			(layer "F.Fab")
		)
		(fp_line
			(start -0.12065 -0.2794)
			(end 0.12065 -0.2794)
			(stroke
				(width 0.1)
				(type default)
			)
			(layer "F.Fab")
		)
		(fp_line
			(start -0.12065 -0.305054)
			(end -0.12065 -0.2794)
			(stroke
				(width 0.1)
				(type default)
			)
			(layer "F.Fab")
		)
		(fp_line
			(start -0.67945 0.3048)
			(end -0.67945 -0.305054)
			(stroke
				(width 0.1)
				(type default)
			)
			(layer "F.Fab")
		)
		(fp_line
			(start -0.67945 -0.305054)
			(end -0.12065 -0.305054)
			(stroke
				(width 0.1)
				(type default)
			)
			(layer "F.Fab")
		)
		(pad "1" smd circle
			(at -0.40005 0 180)
			(size 0 0)
			(layers "F.Cu" "F.Mask" "F.Paste")
			(net "SMB_INA230_1_3V3AUX_SDA_R")
		)
		(pad "2" smd circle
			(at 0.40005 0 180)
			(size 0 0)
			(layers "F.Cu" "F.Mask" "F.Paste")
			(net "SMB_INA230_1_3V3AUX_SDA_R1")
		)
	)
	(footprint ""
		(layer "F.Cu")
		(at 365.701326 -45.267118 -90)
		(property "Reference" "R813"
			(at 0 0 270)
			(layer "F.SilkS")
			(hide yes)
			(effects
				(font
					(size 1.27 1.27)
				)
			)
		)
		(property "Value" ""
			(at 0 0 270)
			(layer "F.Fab")
			(effects
				(font
					(size 1.27 1.27)
				)
			)
		)
		(duplicate_pad_numbers_are_jumpers no)
		(fp_line
			(start -0.7874 0.4064)
			(end -0.7874 -0.4064)
			(stroke
				(width 0.1524)
				(type default)
			)
			(layer "F.SilkS")
		)
		(fp_line
			(start 0.7874 0.4064)
			(end -0.7874 0.4064)
			(stroke
				(width 0.1524)
				(type default)
			)
			(layer "F.SilkS")
		)
		(fp_line
			(start -0.7874 -0.4064)
			(end 0.7874 -0.4064)
			(stroke
				(width 0.1524)
				(type default)
			)
			(layer "F.SilkS")
		)
		(fp_line
			(start 0.7874 -0.4064)
			(end 0.7874 0.4064)
			(stroke
				(width 0.1524)
				(type default)
			)
			(layer "F.SilkS")
		)
		(fp_line
			(start -0.67945 0.3048)
			(end -0.67945 -0.305054)
			(stroke
				(width 0.1)
				(type default)
			)
			(layer "F.Fab")
		)
		(fp_line
			(start -0.12065 0.3048)
			(end -0.67945 0.3048)
			(stroke
				(width 0.1)
				(type default)
			)
			(layer "F.Fab")
		)
		(fp_line
			(start 0.120396 0.3048)
			(end 0.120396 0.2794)
			(stroke
				(width 0.1)
				(type default)
			)
			(layer "F.Fab")
		)
		(fp_line
			(start 0.67945 0.3048)
			(end 0.120396 0.3048)
			(stroke
				(width 0.1)
				(type default)
			)
			(layer "F.Fab")
		)
		(fp_line
			(start -0.12065 0.2794)
			(end -0.12065 0.3048)
			(stroke
				(width 0.1)
				(type default)
			)
			(layer "F.Fab")
		)
		(fp_line
			(start 0.120396 0.2794)
			(end -0.12065 0.2794)
			(stroke
				(width 0.1)
				(type default)
			)
			(layer "F.Fab")
		)
		(fp_line
			(start -0.12065 -0.2794)
			(end 0.12065 -0.2794)
			(stroke
				(width 0.1)
				(type default)
			)
			(layer "F.Fab")
		)
		(fp_line
			(start 0.12065 -0.2794)
			(end 0.12065 -0.3048)
			(stroke
				(width 0.1)
				(type default)
			)
			(layer "F.Fab")
		)
		(fp_line
			(start 0.12065 -0.3048)
			(end 0.67945 -0.3048)
			(stroke
				(width 0.1)
				(type default)
			)
			(layer "F.Fab")
		)
		(fp_line
			(start 0.67945 -0.3048)
			(end 0.67945 0.3048)
			(stroke
				(width 0.1)
				(type default)
			)
			(layer "F.Fab")
		)
		(fp_line
			(start -0.67945 -0.305054)
			(end -0.12065 -0.305054)
			(stroke
				(width 0.1)
				(type default)
			)
			(layer "F.Fab")
		)
		(fp_line
			(start -0.12065 -0.305054)
			(end -0.12065 -0.2794)
			(stroke
				(width 0.1)
				(type default)
			)
			(layer "F.Fab")
		)
		(pad "1" smd circle
			(at -0.40005 0 270)
			(size 0 0)
			(layers "F.Cu" "F.Mask" "F.Paste")
			(net "PVDD18_S5_P0")
		)
		(pad "2" smd circle
			(at 0.40005 0 270)
			(size 0 0)
			(layers "F.Cu" "F.Mask" "F.Paste")
			(net "UART_CPU0_UART0_RX")
		)
	)
	(footprint ""
		(layer "F.Cu")
		(at 15.288006 -105.53573 90)
		(property "Reference" "R2790"
			(at 0 0 90)
			(layer "F.SilkS")
			(hide yes)
			(effects
				(font
					(size 1.27 1.27)
				)
			)
		)
		(property "Value" ""
			(at 0 0 90)
			(layer "F.Fab")
			(effects
				(font
					(size 1.27 1.27)
				)
			)
		)
		(duplicate_pad_numbers_are_jumpers no)
		(fp_line
			(start 0.7874 -0.4064)
			(end 0.7874 0.4064)
			(stroke
				(width 0.1524)
				(type default)
			)
			(layer "F.SilkS")
		)
		(fp_line
			(start -0.7874 -0.4064)
			(end 0.7874 -0.4064)
			(stroke
				(width 0.1524)
				(type default)
			)
			(layer "F.SilkS")
		)
		(fp_line
			(start 0.7874 0.4064)
			(end -0.7874 0.4064)
			(stroke
				(width 0.1524)
				(type default)
			)
			(layer "F.SilkS")
		)
		(fp_line
			(start -0.7874 0.4064)
			(end -0.7874 -0.4064)
			(stroke
				(width 0.1524)
				(type default)
			)
			(layer "F.SilkS")
		)
		(fp_line
			(start -0.12065 -0.305054)
			(end -0.12065 -0.2794)
			(stroke
				(width 0.1)
				(type default)
			)
			(layer "F.Fab")
		)
		(fp_line
			(start -0.67945 -0.305054)
			(end -0.12065 -0.305054)
			(stroke
				(width 0.1)
				(type default)
			)
			(layer "F.Fab")
		)
		(fp_line
			(start 0.67945 -0.3048)
			(end 0.67945 0.3048)
			(stroke
				(width 0.1)
				(type default)
			)
			(layer "F.Fab")
		)
		(fp_line
			(start 0.12065 -0.3048)
			(end 0.67945 -0.3048)
			(stroke
				(width 0.1)
				(type default)
			)
			(layer "F.Fab")
		)
		(fp_line
			(start 0.12065 -0.2794)
			(end 0.12065 -0.3048)
			(stroke
				(width 0.1)
				(type default)
			)
			(layer "F.Fab")
		)
		(fp_line
			(start -0.12065 -0.2794)
			(end 0.12065 -0.2794)
			(stroke
				(width 0.1)
				(type default)
			)
			(layer "F.Fab")
		)
		(fp_line
			(start 0.120396 0.2794)
			(end -0.12065 0.2794)
			(stroke
				(width 0.1)
				(type default)
			)
			(layer "F.Fab")
		)
		(fp_line
			(start -0.12065 0.2794)
			(end -0.12065 0.3048)
			(stroke
				(width 0.1)
				(type default)
			)
			(layer "F.Fab")
		)
		(fp_line
			(start 0.67945 0.3048)
			(end 0.120396 0.3048)
			(stroke
				(width 0.1)
				(type default)
			)
			(layer "F.Fab")
		)
		(fp_line
			(start 0.120396 0.3048)
			(end 0.120396 0.2794)
			(stroke
				(width 0.1)
				(type default)
			)
			(layer "F.Fab")
		)
		(fp_line
			(start -0.12065 0.3048)
			(end -0.67945 0.3048)
			(stroke
				(width 0.1)
				(type default)
			)
			(layer "F.Fab")
		)
		(fp_line
			(start -0.67945 0.3048)
			(end -0.67945 -0.305054)
			(stroke
				(width 0.1)
				(type default)
			)
			(layer "F.Fab")
		)
		(pad "1" smd rect
			(at -0.40005 0 270)
			(size 0.4572 0.508)
			(layers "F.Cu" "F.Mask" "F.Paste")
			(net "USB2_HOST_BMC_B_DP")
		)
		(pad "2" smd rect
			(at 0.40005 0 270)
			(size 0.4572 0.508)
			(layers "F.Cu" "F.Mask" "F.Paste")
			(net "USB2_HOST_BMC_B_BUF_DP")
		)
	)
	(footprint ""
		(layer "F.Cu")
		(at 447.919602 -428.61611 90)
		(property "Reference" "PC6605"
			(at 0 0 90)
			(layer "F.SilkS")
			(hide yes)
			(effects
				(font
					(size 1.27 1.27)
				)
			)
		)
		(property "Value" ""
			(at 0 0 90)
			(layer "F.Fab")
			(effects
				(font
					(size 1.27 1.27)
				)
			)
		)
		(duplicate_pad_numbers_are_jumpers no)
		(fp_line
			(start 0.7874 -0.4064)
			(end 0.7874 0.4064)
			(stroke
				(width 0.1524)
				(type default)
			)
			(layer "F.SilkS")
		)
		(fp_line
			(start -0.7874 -0.4064)
			(end 0.7874 -0.4064)
			(stroke
				(width 0.1524)
				(type default)
			)
			(layer "F.SilkS")
		)
		(fp_line
			(start 0.7874 0.4064)
			(end -0.7874 0.4064)
			(stroke
				(width 0.1524)
				(type default)
			)
			(layer "F.SilkS")
		)
		(fp_line
			(start -0.7874 0.4064)
			(end -0.7874 -0.4064)
			(stroke
				(width 0.1524)
				(type default)
			)
			(layer "F.SilkS")
		)
		(fp_line
			(start -0.12065 -0.305054)
			(end -0.12065 -0.2794)
			(stroke
				(width 0.1)
				(type default)
			)
			(layer "F.Fab")
		)
		(fp_line
			(start -0.67945 -0.305054)
			(end -0.12065 -0.305054)
			(stroke
				(width 0.1)
				(type default)
			)
			(layer "F.Fab")
		)
		(fp_line
			(start 0.67945 -0.3048)
			(end 0.67945 0.3048)
			(stroke
				(width 0.1)
				(type default)
			)
			(layer "F.Fab")
		)
		(fp_line
			(start 0.12065 -0.3048)
			(end 0.67945 -0.3048)
			(stroke
				(width 0.1)
				(type default)
			)
			(layer "F.Fab")
		)
		(fp_line
			(start 0.12065 -0.2794)
			(end 0.12065 -0.3048)
			(stroke
				(width 0.1)
				(type default)
			)
			(layer "F.Fab")
		)
		(fp_line
			(start -0.12065 -0.2794)
			(end 0.12065 -0.2794)
			(stroke
				(width 0.1)
				(type default)
			)
			(layer "F.Fab")
		)
		(fp_line
			(start 0.120396 0.2794)
			(end -0.12065 0.2794)
			(stroke
				(width 0.1)
				(type default)
			)
			(layer "F.Fab")
		)
		(fp_line
			(start -0.12065 0.2794)
			(end -0.12065 0.3048)
			(stroke
				(width 0.1)
				(type default)
			)
			(layer "F.Fab")
		)
		(fp_line
			(start 0.67945 0.3048)
			(end 0.120396 0.3048)
			(stroke
				(width 0.1)
				(type default)
			)
			(layer "F.Fab")
		)
		(fp_line
			(start 0.120396 0.3048)
			(end 0.120396 0.2794)
			(stroke
				(width 0.1)
				(type default)
			)
			(layer "F.Fab")
		)
		(fp_line
			(start -0.12065 0.3048)
			(end -0.67945 0.3048)
			(stroke
				(width 0.1)
				(type default)
			)
			(layer "F.Fab")
		)
		(fp_line
			(start -0.67945 0.3048)
			(end -0.67945 -0.305054)
			(stroke
				(width 0.1)
				(type default)
			)
			(layer "F.Fab")
		)
		(pad "1" smd circle
			(at -0.40005 0 90)
			(size 0 0)
			(layers "F.Cu" "F.Mask" "F.Paste")
			(net "PV09_RETIMER_CPU0_VCCS")
		)
		(pad "2" smd circle
			(at 0.40005 0 90)
			(size 0 0)
			(layers "F.Cu" "F.Mask" "F.Paste")
			(net "GND")
		)
	)
	(footprint ""
		(layer "F.Cu")
		(at 39.27856 -108.72216 90)
		(property "Reference" "Q7000"
			(at -1.78816 2.61493 90)
			(unlocked yes)
			(layer "F.SilkS")
			(effects
				(font
					(size 0.7874 0.5842)
					(thickness 0.1524)
				)
				(justify left)
			)
		)
		(property "Value" ""
			(at 0 0 90)
			(layer "F.Fab")
			(effects
				(font
					(size 1.27 1.27)
				)
			)
		)
		(duplicate_pad_numbers_are_jumpers no)
		(fp_line
			(start 1.603248 -1.500124)
			(end 1.603248 1.500124)
			(stroke
				(width 0.1524)
				(type default)
			)
			(layer "F.SilkS")
		)
		(fp_line
			(start -1.603248 -1.500124)
			(end 1.603248 -1.500124)
			(stroke
				(width 0.1524)
				(type default)
			)
			(layer "F.SilkS")
		)
		(fp_line
			(start 1.603248 1.500124)
			(end -1.603248 1.500124)
			(stroke
				(width 0.1524)
				(type default)
			)
			(layer "F.SilkS")
		)
		(fp_line
			(start -1.603248 1.500124)
			(end -1.603248 -1.500124)
			(stroke
				(width 0.1524)
				(type default)
			)
			(layer "F.SilkS")
		)
		(fp_line
			(start 0.700024 -1.500124)
			(end -0.700024 -1.500124)
			(stroke
				(width 0.1)
				(type default)
			)
			(layer "F.Fab")
		)
		(fp_line
			(start -0.700024 -1.500124)
			(end -0.700024 -1.169924)
			(stroke
				(width 0.1)
				(type default)
			)
			(layer "F.Fab")
		)
		(fp_line
			(start -0.700024 -1.169924)
			(end -1.249934 -1.169924)
			(stroke
				(width 0.1)
				(type default)
			)
			(layer "F.Fab")
		)
		(fp_line
			(start -1.249934 -1.169924)
			(end -1.249934 -0.729996)
			(stroke
				(width 0.1)
				(type default)
			)
			(layer "F.Fab")
		)
		(fp_line
			(start -0.6985 -0.729996)
			(end -0.6985 0.729996)
			(stroke
				(width 0.1)
				(type default)
			)
			(layer "F.Fab")
		)
		(fp_line
			(start -1.249934 -0.729996)
			(end -0.6985 -0.729996)
			(stroke
				(width 0.1)
				(type default)
			)
			(layer "F.Fab")
		)
		(fp_line
			(start 1.249934 -0.219964)
			(end 0.700024 -0.219964)
			(stroke
				(width 0.1)
				(type default)
			)
			(layer "F.Fab")
		)
		(fp_line
			(start 0.700024 -0.219964)
			(end 0.700024 -1.500124)
			(stroke
				(width 0.1)
				(type default)
			)
			(layer "F.Fab")
		)
		(fp_line
			(start 1.249934 0.219964)
			(end 1.249934 -0.219964)
			(stroke
				(width 0.1)
				(type default)
			)
			(layer "F.Fab")
		)
		(fp_line
			(start 0.700024 0.219964)
			(end 1.249934 0.219964)
			(stroke
				(width 0.1)
				(type default)
			)
			(layer "F.Fab")
		)
		(fp_line
			(start -0.6985 0.729996)
			(end -1.249934 0.729996)
			(stroke
				(width 0.1)
				(type default)
			)
			(layer "F.Fab")
		)
		(fp_line
			(start -1.249934 0.729996)
			(end -1.249934 1.169924)
			(stroke
				(width 0.1)
				(type default)
			)
			(layer "F.Fab")
		)
		(fp_line
			(start -0.700024 1.169924)
			(end -0.700024 1.500124)
			(stroke
				(width 0.1)
				(type default)
			)
			(layer "F.Fab")
		)
		(fp_line
			(start -1.249934 1.169924)
			(end -0.700024 1.169924)
			(stroke
				(width 0.1)
				(type default)
			)
			(layer "F.Fab")
		)
		(fp_line
			(start 0.700024 1.500124)
			(end 0.700024 0.219964)
			(stroke
				(width 0.1)
				(type default)
			)
			(layer "F.Fab")
		)
		(fp_line
			(start -0.700024 1.500124)
			(end 0.700024 1.500124)
			(stroke
				(width 0.1)
				(type default)
			)
			(layer "F.Fab")
		)
		(fp_rect
			(start -0.700024 1.500124)
			(end 0.700024 -1.500124)
			(stroke
				(width 0)
				(type default)
			)
			(fill no)
			(layer "F.Fab")
		)
		(pad "D" smd rect
			(at 0.999998 0)
			(size 0.8128 0.9144)
			(layers "F.Cu" "F.Mask" "F.Paste")
			(net "P12V_AUX_DSC_G2")
		)
		(pad "G" smd rect
			(at -0.999998 -0.94996)
			(size 0.8128 0.9144)
			(layers "F.Cu" "F.Mask" "F.Paste")
			(net "P12V_AUX_DSC_G1")
		)
		(pad "S" smd rect
			(at -0.999998 0.94996)
			(size 0.8128 0.9144)
			(layers "F.Cu" "F.Mask" "F.Paste")
			(net "P12V_AUX_DSC_S1")
		)
	)
	(footprint ""
		(layer "F.Cu")
		(at 307.404516 -439.276744 90)
		(property "Reference" "C17"
			(at 0 0 90)
			(layer "F.SilkS")
			(hide yes)
			(effects
				(font
					(size 1.27 1.27)
				)
			)
		)
		(property "Value" ""
			(at 0 0 90)
			(layer "F.Fab")
			(effects
				(font
					(size 1.27 1.27)
				)
			)
		)
		(duplicate_pad_numbers_are_jumpers no)
		(fp_line
			(start 0.7874 -0.4064)
			(end 0.7874 0.4064)
			(stroke
				(width 0.1524)
				(type default)
			)
			(layer "F.SilkS")
		)
		(fp_line
			(start -0.7874 -0.4064)
			(end 0.7874 -0.4064)
			(stroke
				(width 0.1524)
				(type default)
			)
			(layer "F.SilkS")
		)
		(fp_line
			(start 0.7874 0.4064)
			(end -0.7874 0.4064)
			(stroke
				(width 0.1524)
				(type default)
			)
			(layer "F.SilkS")
		)
		(fp_line
			(start -0.7874 0.4064)
			(end -0.7874 -0.4064)
			(stroke
				(width 0.1524)
				(type default)
			)
			(layer "F.SilkS")
		)
		(fp_line
			(start -0.12065 -0.305054)
			(end -0.12065 -0.2794)
			(stroke
				(width 0.1)
				(type default)
			)
			(layer "F.Fab")
		)
		(fp_line
			(start -0.67945 -0.305054)
			(end -0.12065 -0.305054)
			(stroke
				(width 0.1)
				(type default)
			)
			(layer "F.Fab")
		)
		(fp_line
			(start 0.67945 -0.3048)
			(end 0.67945 0.3048)
			(stroke
				(width 0.1)
				(type default)
			)
			(layer "F.Fab")
		)
		(fp_line
			(start 0.12065 -0.3048)
			(end 0.67945 -0.3048)
			(stroke
				(width 0.1)
				(type default)
			)
			(layer "F.Fab")
		)
		(fp_line
			(start 0.12065 -0.2794)
			(end 0.12065 -0.3048)
			(stroke
				(width 0.1)
				(type default)
			)
			(layer "F.Fab")
		)
		(fp_line
			(start -0.12065 -0.2794)
			(end 0.12065 -0.2794)
			(stroke
				(width 0.1)
				(type default)
			)
			(layer "F.Fab")
		)
		(fp_line
			(start 0.120396 0.2794)
			(end -0.12065 0.2794)
			(stroke
				(width 0.1)
				(type default)
			)
			(layer "F.Fab")
		)
		(fp_line
			(start -0.12065 0.2794)
			(end -0.12065 0.3048)
			(stroke
				(width 0.1)
				(type default)
			)
			(layer "F.Fab")
		)
		(fp_line
			(start 0.67945 0.3048)
			(end 0.120396 0.3048)
			(stroke
				(width 0.1)
				(type default)
			)
			(layer "F.Fab")
		)
		(fp_line
			(start 0.120396 0.3048)
			(end 0.120396 0.2794)
			(stroke
				(width 0.1)
				(type default)
			)
			(layer "F.Fab")
		)
		(fp_line
			(start -0.12065 0.3048)
			(end -0.67945 0.3048)
			(stroke
				(width 0.1)
				(type default)
			)
			(layer "F.Fab")
		)
		(fp_line
			(start -0.67945 0.3048)
			(end -0.67945 -0.305054)
			(stroke
				(width 0.1)
				(type default)
			)
			(layer "F.Fab")
		)
		(pad "1" smd circle
			(at -0.40005 0 90)
			(size 0 0)
			(layers "F.Cu" "F.Mask" "F.Paste")
			(net "GPU_3V3IO_RSVD5_FFU_ISO")
		)
		(pad "2" smd circle
			(at 0.40005 0 90)
			(size 0 0)
			(layers "F.Cu" "F.Mask" "F.Paste")
			(net "GND")
		)
	)
	(footprint ""
		(layer "F.Cu")
		(at 275.14169 -99.371404 180)
		(property "Reference" "R1645"
			(at 0 0 180)
			(layer "F.SilkS")
			(hide yes)
			(effects
				(font
					(size 1.27 1.27)
				)
			)
		)
		(property "Value" ""
			(at 0 0 180)
			(layer "F.Fab")
			(effects
				(font
					(size 1.27 1.27)
				)
			)
		)
		(duplicate_pad_numbers_are_jumpers no)
		(fp_line
			(start 0.7874 0.4064)
			(end -0.7874 0.4064)
			(stroke
				(width 0.1524)
				(type default)
			)
			(layer "F.SilkS")
		)
		(fp_line
			(start 0.7874 -0.4064)
			(end 0.7874 0.4064)
			(stroke
				(width 0.1524)
				(type default)
			)
			(layer "F.SilkS")
		)
		(fp_line
			(start -0.7874 0.4064)
			(end -0.7874 -0.4064)
			(stroke
				(width 0.1524)
				(type default)
			)
			(layer "F.SilkS")
		)
		(fp_line
			(start -0.7874 -0.4064)
			(end 0.7874 -0.4064)
			(stroke
				(width 0.1524)
				(type default)
			)
			(layer "F.SilkS")
		)
		(fp_line
			(start 0.67945 0.3048)
			(end 0.120396 0.3048)
			(stroke
				(width 0.1)
				(type default)
			)
			(layer "F.Fab")
		)
		(fp_line
			(start 0.67945 -0.3048)
			(end 0.67945 0.3048)
			(stroke
				(width 0.1)
				(type default)
			)
			(layer "F.Fab")
		)
		(fp_line
			(start 0.12065 -0.2794)
			(end 0.12065 -0.3048)
			(stroke
				(width 0.1)
				(type default)
			)
			(layer "F.Fab")
		)
		(fp_line
			(start 0.12065 -0.3048)
			(end 0.67945 -0.3048)
			(stroke
				(width 0.1)
				(type default)
			)
			(layer "F.Fab")
		)
		(fp_line
			(start 0.120396 0.3048)
			(end 0.120396 0.2794)
			(stroke
				(width 0.1)
				(type default)
			)
			(layer "F.Fab")
		)
		(fp_line
			(start 0.120396 0.2794)
			(end -0.12065 0.2794)
			(stroke
				(width 0.1)
				(type default)
			)
			(layer "F.Fab")
		)
		(fp_line
			(start -0.12065 0.3048)
			(end -0.67945 0.3048)
			(stroke
				(width 0.1)
				(type default)
			)
			(layer "F.Fab")
		)
		(fp_line
			(start -0.12065 0.2794)
			(end -0.12065 0.3048)
			(stroke
				(width 0.1)
				(type default)
			)
			(layer "F.Fab")
		)
		(fp_line
			(start -0.12065 -0.2794)
			(end 0.12065 -0.2794)
			(stroke
				(width 0.1)
				(type default)
			)
			(layer "F.Fab")
		)
		(fp_line
			(start -0.12065 -0.305054)
			(end -0.12065 -0.2794)
			(stroke
				(width 0.1)
				(type default)
			)
			(layer "F.Fab")
		)
		(fp_line
			(start -0.67945 0.3048)
			(end -0.67945 -0.305054)
			(stroke
				(width 0.1)
				(type default)
			)
			(layer "F.Fab")
		)
		(fp_line
			(start -0.67945 -0.305054)
			(end -0.12065 -0.305054)
			(stroke
				(width 0.1)
				(type default)
			)
			(layer "F.Fab")
		)
		(pad "1" smd circle
			(at -0.40005 0 180)
			(size 0 0)
			(layers "F.Cu" "F.Mask" "F.Paste")
			(net "JTAG_P1_R_DBREQ_N")
		)
		(pad "2" smd circle
			(at 0.40005 0 180)
			(size 0 0)
			(layers "F.Cu" "F.Mask" "F.Paste")
			(net "JTAG_CPU1_DBREQ_N")
		)
	)
	(footprint ""
		(layer "F.Cu")
		(at 393.363958 -322.627752 180)
		(property "Reference" "R389"
			(at 0 0 180)
			(layer "F.SilkS")
			(hide yes)
			(effects
				(font
					(size 1.27 1.27)
				)
			)
		)
		(property "Value" ""
			(at 0 0 180)
			(layer "F.Fab")
			(effects
				(font
					(size 1.27 1.27)
				)
			)
		)
		(duplicate_pad_numbers_are_jumpers no)
		(fp_line
			(start 0.7874 0.4064)
			(end -0.7874 0.4064)
			(stroke
				(width 0.1524)
				(type default)
			)
			(layer "F.SilkS")
		)
		(fp_line
			(start 0.7874 -0.4064)
			(end 0.7874 0.4064)
			(stroke
				(width 0.1524)
				(type default)
			)
			(layer "F.SilkS")
		)
		(fp_line
			(start -0.7874 0.4064)
			(end -0.7874 -0.4064)
			(stroke
				(width 0.1524)
				(type default)
			)
			(layer "F.SilkS")
		)
		(fp_line
			(start -0.7874 -0.4064)
			(end 0.7874 -0.4064)
			(stroke
				(width 0.1524)
				(type default)
			)
			(layer "F.SilkS")
		)
		(fp_line
			(start 0.67945 0.3048)
			(end 0.120396 0.3048)
			(stroke
				(width 0.1)
				(type default)
			)
			(layer "F.Fab")
		)
		(fp_line
			(start 0.67945 -0.3048)
			(end 0.67945 0.3048)
			(stroke
				(width 0.1)
				(type default)
			)
			(layer "F.Fab")
		)
		(fp_line
			(start 0.12065 -0.2794)
			(end 0.12065 -0.3048)
			(stroke
				(width 0.1)
				(type default)
			)
			(layer "F.Fab")
		)
		(fp_line
			(start 0.12065 -0.3048)
			(end 0.67945 -0.3048)
			(stroke
				(width 0.1)
				(type default)
			)
			(layer "F.Fab")
		)
		(fp_line
			(start 0.120396 0.3048)
			(end 0.120396 0.2794)
			(stroke
				(width 0.1)
				(type default)
			)
			(layer "F.Fab")
		)
		(fp_line
			(start 0.120396 0.2794)
			(end -0.12065 0.2794)
			(stroke
				(width 0.1)
				(type default)
			)
			(layer "F.Fab")
		)
		(fp_line
			(start -0.12065 0.3048)
			(end -0.67945 0.3048)
			(stroke
				(width 0.1)
				(type default)
			)
			(layer "F.Fab")
		)
		(fp_line
			(start -0.12065 0.2794)
			(end -0.12065 0.3048)
			(stroke
				(width 0.1)
				(type default)
			)
			(layer "F.Fab")
		)
		(fp_line
			(start -0.12065 -0.2794)
			(end 0.12065 -0.2794)
			(stroke
				(width 0.1)
				(type default)
			)
			(layer "F.Fab")
		)
		(fp_line
			(start -0.12065 -0.305054)
			(end -0.12065 -0.2794)
			(stroke
				(width 0.1)
				(type default)
			)
			(layer "F.Fab")
		)
		(fp_line
			(start -0.67945 0.3048)
			(end -0.67945 -0.305054)
			(stroke
				(width 0.1)
				(type default)
			)
			(layer "F.Fab")
		)
		(fp_line
			(start -0.67945 -0.305054)
			(end -0.12065 -0.305054)
			(stroke
				(width 0.1)
				(type default)
			)
			(layer "F.Fab")
		)
		(pad "1" smd circle
			(at -0.40005 0 180)
			(size 0 0)
			(layers "F.Cu" "F.Mask" "F.Paste")
			(net "P3V3_AUX")
		)
		(pad "2" smd circle
			(at 0.40005 0 180)
			(size 0 0)
			(layers "F.Cu" "F.Mask" "F.Paste")
			(net "CPU0_SP5R4")
		)
	)
	(footprint ""
		(layer "F.Cu")
		(at 332.763876 -70.098412 90)
		(property "Reference" "D78"
			(at -3.934714 -0.691642 90)
			(unlocked yes)
			(layer "F.SilkS")
			(effects
				(font
					(size 0.7874 0.5842)
					(thickness 0.1524)
				)
				(justify left)
			)
		)
		(property "Value" ""
			(at 0 0 90)
			(layer "F.Fab")
			(effects
				(font
					(size 1.27 1.27)
				)
			)
		)
		(duplicate_pad_numbers_are_jumpers no)
		(fp_line
			(start 1.16078 -0.4826)
			(end 1.16078 0.4826)
			(stroke
				(width 0.1524)
				(type default)
			)
			(layer "F.SilkS")
		)
		(fp_line
			(start 1.03378 -0.4826)
			(end 1.03378 0.4826)
			(stroke
				(width 0.1524)
				(type default)
			)
			(layer "F.SilkS")
		)
		(fp_line
			(start 0.90678 -0.4826)
			(end 0.90678 0.4826)
			(stroke
				(width 0.1524)
				(type default)
			)
			(layer "F.SilkS")
		)
		(fp_line
			(start -0.64008 -0.4826)
			(end 1.16078 -0.4826)
			(stroke
				(width 0.1524)
				(type default)
			)
			(layer "F.SilkS")
		)
		(fp_line
			(start -0.79248 -0.4826)
			(end 1.03378 -0.4826)
			(stroke
				(width 0.1524)
				(type default)
			)
			(layer "F.SilkS")
		)
		(fp_line
			(start -0.89408 -0.4826)
			(end 0.90678 -0.4826)
			(stroke
				(width 0.1524)
				(type default)
			)
			(layer "F.SilkS")
		)
		(fp_line
			(start 1.16078 0.4826)
			(end -0.64008 0.4826)
			(stroke
				(width 0.1524)
				(type default)
			)
			(layer "F.SilkS")
		)
		(fp_line
			(start 1.03378 0.4826)
			(end -0.79248 0.4826)
			(stroke
				(width 0.1524)
				(type default)
			)
			(layer "F.SilkS")
		)
		(fp_line
			(start 0.90678 0.4826)
			(end -0.90678 0.4826)
			(stroke
				(width 0.1524)
				(type default)
			)
			(layer "F.SilkS")
		)
		(fp_line
			(start -0.90678 0.4826)
			(end -0.90678 -0.4699)
			(stroke
				(width 0.1524)
				(type default)
			)
			(layer "F.SilkS")
		)
		(fp_line
			(start 0.499872 -0.249936)
			(end 0.499872 0.249936)
			(stroke
				(width 0.1)
				(type default)
			)
			(layer "F.Fab")
		)
		(fp_line
			(start -0.499872 -0.249936)
			(end 0.499872 -0.249936)
			(stroke
				(width 0.1)
				(type default)
			)
			(layer "F.Fab")
		)
		(fp_line
			(start 0.499872 0.249936)
			(end -0.499872 0.249936)
			(stroke
				(width 0.1)
				(type default)
			)
			(layer "F.Fab")
		)
		(fp_line
			(start -0.499872 0.249936)
			(end -0.499872 -0.249936)
			(stroke
				(width 0.1)
				(type default)
			)
			(layer "F.Fab")
		)
		(pad "A" smd rect
			(at -0.47498 0 90)
			(size 0.6096 0.7112)
			(layers "F.Cu" "F.Mask" "F.Paste")
			(net "LED_PWRGD_PVDD11_S3_P0_R")
		)
		(pad "C" smd rect
			(at 0.47498 0 90)
			(size 0.6096 0.7112)
			(layers "F.Cu" "F.Mask" "F.Paste")
			(net "LED_PWRGD_PVDD11_S3_P0_D")
		)
	)
	(footprint ""
		(layer "F.Cu")
		(at 305.009296 -383.88163 -90)
		(property "Reference" "C924"
			(at 0 0 270)
			(layer "F.SilkS")
			(hide yes)
			(effects
				(font
					(size 1.27 1.27)
				)
			)
		)
		(property "Value" ""
			(at 0 0 270)
			(layer "F.Fab")
			(effects
				(font
					(size 1.27 1.27)
				)
			)
		)
		(duplicate_pad_numbers_are_jumpers no)
		(fp_line
			(start -0.299974 0.150114)
			(end -0.299974 -0.150114)
			(stroke
				(width 0.1)
				(type default)
			)
			(layer "F.Fab")
		)
		(fp_line
			(start 0.299974 0.150114)
			(end -0.299974 0.150114)
			(stroke
				(width 0.1)
				(type default)
			)
			(layer "F.Fab")
		)
		(fp_line
			(start -0.299974 -0.150114)
			(end 0.299974 -0.150114)
			(stroke
				(width 0.1)
				(type default)
			)
			(layer "F.Fab")
		)
		(fp_line
			(start 0.299974 -0.150114)
			(end 0.299974 0.150114)
			(stroke
				(width 0.1)
				(type default)
			)
			(layer "F.Fab")
		)
		(pad "1" smd rect
			(at -0.2667 0 270)
			(size 0.3048 0.381)
			(layers "F.Cu" "F.Mask" "F.Paste")
			(net "P5E_CPU0_P0_TX_C_DN<4>")
		)
		(pad "2" smd rect
			(at 0.2667 0 270)
			(size 0.3048 0.381)
			(layers "F.Cu" "F.Mask" "F.Paste")
			(net "P5E_CPU0_P0_TX_DN<4>")
		)
	)
	(footprint ""
		(layer "F.Cu")
		(at 506.185424 -306.9209 -90)
		(property "Reference" "X9002"
			(at -1.89738 4.962398 0)
			(unlocked yes)
			(layer "F.SilkS")
			(effects
				(font
					(size 0.7874 0.5842)
					(thickness 0.1524)
				)
				(justify left)
			)
		)
		(property "Value" ""
			(at 0 0 270)
			(layer "F.Fab")
			(effects
				(font
					(size 1.27 1.27)
				)
			)
		)
		(property "User Part Number" "N_A"
			(at 1.30175 1.27 0)
			(unlocked yes)
			(layer "Cmts.User")
			(hide yes)
			(effects
				(font
					(size 0.635 0.4064)
					(thickness 0.1524)
				)
			)
		)
		(property "Device Type" "TP_TDR_4P_FTS_TH-TP_TDR_4P_DIP,EMPTY,TP15"
			(at 1.30175 1.27 0)
			(unlocked yes)
			(layer "F.Fab")
			(hide yes)
			(effects
				(font
					(size 0.635 0.4064)
					(thickness 0.1524)
				)
			)
		)
		(duplicate_pad_numbers_are_jumpers no)
		(fp_line
			(start 0 3.81)
			(end 2.54 3.81)
			(stroke
				(width 0.1524)
				(type default)
			)
			(layer "F.SilkS")
		)
		(fp_line
			(start 2.54 3.81)
			(end 2.54 3.6703)
			(stroke
				(width 0.1524)
				(type default)
			)
			(layer "F.SilkS")
		)
		(fp_line
			(start 0 3.175)
			(end 0 3.81)
			(stroke
				(width 0.1524)
				(type default)
			)
			(layer "F.SilkS")
		)
		(fp_line
			(start 2.54 1.4097)
			(end 2.54 1.1303)
			(stroke
				(width 0.1524)
				(type default)
			)
			(layer "F.SilkS")
		)
		(fp_line
			(start 0 0.635)
			(end 0 1.905)
			(stroke
				(width 0.1524)
				(type default)
			)
			(layer "F.SilkS")
		)
		(fp_line
			(start 2.54 -1.1303)
			(end 2.54 -1.27)
			(stroke
				(width 0.1524)
				(type default)
			)
			(layer "F.SilkS")
		)
		(fp_line
			(start 0 -1.27)
			(end 0 -0.635)
			(stroke
				(width 0.1524)
				(type default)
			)
			(layer "F.SilkS")
		)
		(fp_line
			(start 2.54 -1.27)
			(end 0 -1.27)
			(stroke
				(width 0.1524)
				(type default)
			)
			(layer "F.SilkS")
		)
		(fp_poly
			(pts
				(xy -2.285746 -0.762) (xy -0.761746 0) (xy -2.285746 0.762)
			)
			(stroke
				(width 0)
				(type default)
			)
			(fill yes)
			(layer "F.SilkS")
		)
		(fp_line
			(start 0 3.81)
			(end 2.54 3.81)
			(stroke
				(width 0.1)
				(type default)
			)
			(layer "F.Fab")
		)
		(fp_line
			(start 2.54 3.81)
			(end 2.54 -1.27)
			(stroke
				(width 0.1)
				(type default)
			)
			(layer "F.Fab")
		)
		(fp_line
			(start 0 -1.27)
			(end 0 3.81)
			(stroke
				(width 0.1)
				(type default)
			)
			(layer "F.Fab")
		)
		(fp_line
			(start 2.54 -1.27)
			(end 0 -1.27)
			(stroke
				(width 0.1)
				(type default)
			)
			(layer "F.Fab")
		)
		(fp_poly
			(pts
				(xy -0.761746 0) (xy -2.285746 -0.762) (xy -2.285746 0.762)
			)
			(stroke
				(width 0)
				(type default)
			)
			(fill yes)
			(layer "F.Fab")
		)
		(pad "1" thru_hole circle
			(at 0 0 270)
			(size 1.0033 1.0033)
			(drill 0.249936)
			(layers "*.Cu" "*.Mask")
			(remove_unused_layers no)
			(net "TDR_DIFF_85_NECK_IN1_DP")
			(clearance 0.10795)
			(thermal_gap 0.10795)
			(padstack
				(mode front_inner_back)
				(layer "Inner"
					(shape circle)
					(size 0.8001 0.8001)
					(clearance 0.1524)
				)
				(layer "B.Cu"
					(shape circle)
					(size 1.0033 1.0033)
					(clearance 0.10795)
				)
			)
		)
		(pad "2" thru_hole circle
			(at 2.54 0 270)
			(size 1.9939 1.9939)
			(drill 0.249936)
			(layers "*.Cu" "*.Mask")
			(remove_unused_layers no)
			(net "T1_GND")
			(clearance 0.10795)
			(thermal_gap 0.10795)
			(padstack
				(mode front_inner_back)
				(layer "Inner"
					(shape circle)
					(size 0.8001 0.8001)
					(clearance 0.1524)
				)
				(layer "B.Cu"
					(shape circle)
					(size 1.9939 1.9939)
					(clearance 0.10795)
				)
			)
		)
		(pad "3" thru_hole circle
			(at 2.54 2.54 270)
			(size 1.9939 1.9939)
			(drill 0.249936)
			(layers "*.Cu" "*.Mask")
			(remove_unused_layers no)
			(net "T1_GND")
			(clearance 0.10795)
			(thermal_gap 0.10795)
			(padstack
				(mode front_inner_back)
				(layer "Inner"
					(shape circle)
					(size 0.8001 0.8001)
					(clearance 0.1524)
				)
				(layer "B.Cu"
					(shape circle)
					(size 1.9939 1.9939)
					(clearance 0.10795)
				)
			)
		)
		(pad "4" thru_hole circle
			(at 0 2.54 270)
			(size 1.0033 1.0033)
			(drill 0.249936)
			(layers "*.Cu" "*.Mask")
			(remove_unused_layers no)
			(net "TDR_DIFF_85_NECK_IN1_DN")
			(clearance 0.10795)
			(thermal_gap 0.10795)
			(padstack
				(mode front_inner_back)
				(layer "Inner"
					(shape circle)
					(size 0.8001 0.8001)
					(clearance 0.1524)
				)
				(layer "B.Cu"
					(shape circle)
					(size 1.0033 1.0033)
					(clearance 0.10795)
				)
			)
		)
	)
	(footprint ""
		(layer "F.Cu")
		(at 394.092684 -394.82268 90)
		(property "Reference" "C992"
			(at 0 0 90)
			(layer "F.SilkS")
			(hide yes)
			(effects
				(font
					(size 1.27 1.27)
				)
			)
		)
		(property "Value" ""
			(at 0 0 90)
			(layer "F.Fab")
			(effects
				(font
					(size 1.27 1.27)
				)
			)
		)
		(duplicate_pad_numbers_are_jumpers no)
		(fp_line
			(start 0.7874 -0.4064)
			(end 0.7874 0.4064)
			(stroke
				(width 0.1524)
				(type default)
			)
			(layer "F.SilkS")
		)
		(fp_line
			(start -0.7874 -0.4064)
			(end 0.7874 -0.4064)
			(stroke
				(width 0.1524)
				(type default)
			)
			(layer "F.SilkS")
		)
		(fp_line
			(start 0.7874 0.4064)
			(end -0.7874 0.4064)
			(stroke
				(width 0.1524)
				(type default)
			)
			(layer "F.SilkS")
		)
		(fp_line
			(start -0.7874 0.4064)
			(end -0.7874 -0.4064)
			(stroke
				(width 0.1524)
				(type default)
			)
			(layer "F.SilkS")
		)
		(fp_line
			(start -0.12065 -0.305054)
			(end -0.12065 -0.2794)
			(stroke
				(width 0.1)
				(type default)
			)
			(layer "F.Fab")
		)
		(fp_line
			(start -0.67945 -0.305054)
			(end -0.12065 -0.305054)
			(stroke
				(width 0.1)
				(type default)
			)
			(layer "F.Fab")
		)
		(fp_line
			(start 0.67945 -0.3048)
			(end 0.67945 0.3048)
			(stroke
				(width 0.1)
				(type default)
			)
			(layer "F.Fab")
		)
		(fp_line
			(start 0.12065 -0.3048)
			(end 0.67945 -0.3048)
			(stroke
				(width 0.1)
				(type default)
			)
			(layer "F.Fab")
		)
		(fp_line
			(start 0.12065 -0.2794)
			(end 0.12065 -0.3048)
			(stroke
				(width 0.1)
				(type default)
			)
			(layer "F.Fab")
		)
		(fp_line
			(start -0.12065 -0.2794)
			(end 0.12065 -0.2794)
			(stroke
				(width 0.1)
				(type default)
			)
			(layer "F.Fab")
		)
		(fp_line
			(start 0.120396 0.2794)
			(end -0.12065 0.2794)
			(stroke
				(width 0.1)
				(type default)
			)
			(layer "F.Fab")
		)
		(fp_line
			(start -0.12065 0.2794)
			(end -0.12065 0.3048)
			(stroke
				(width 0.1)
				(type default)
			)
			(layer "F.Fab")
		)
		(fp_line
			(start 0.67945 0.3048)
			(end 0.120396 0.3048)
			(stroke
				(width 0.1)
				(type default)
			)
			(layer "F.Fab")
		)
		(fp_line
			(start 0.120396 0.3048)
			(end 0.120396 0.2794)
			(stroke
				(width 0.1)
				(type default)
			)
			(layer "F.Fab")
		)
		(fp_line
			(start -0.12065 0.3048)
			(end -0.67945 0.3048)
			(stroke
				(width 0.1)
				(type default)
			)
			(layer "F.Fab")
		)
		(fp_line
			(start -0.67945 0.3048)
			(end -0.67945 -0.305054)
			(stroke
				(width 0.1)
				(type default)
			)
			(layer "F.Fab")
		)
		(pad "1" smd circle
			(at -0.40005 0 90)
			(size 0 0)
			(layers "F.Cu" "F.Mask" "F.Paste")
			(net "P1V8_CPU0_RT_1D")
		)
		(pad "2" smd circle
			(at 0.40005 0 90)
			(size 0 0)
			(layers "F.Cu" "F.Mask" "F.Paste")
			(net "GND")
		)
	)
	(footprint ""
		(layer "F.Cu")
		(at 366.415066 -424.002962 90)
		(property "Reference" "C2010"
			(at 0 0 90)
			(layer "F.SilkS")
			(hide yes)
			(effects
				(font
					(size 1.27 1.27)
				)
			)
		)
		(property "Value" ""
			(at 0 0 90)
			(layer "F.Fab")
			(effects
				(font
					(size 1.27 1.27)
				)
			)
		)
		(duplicate_pad_numbers_are_jumpers no)
		(fp_line
			(start 0.7874 -0.4064)
			(end 0.7874 0.4064)
			(stroke
				(width 0.1524)
				(type default)
			)
			(layer "F.SilkS")
		)
		(fp_line
			(start -0.7874 -0.4064)
			(end 0.7874 -0.4064)
			(stroke
				(width 0.1524)
				(type default)
			)
			(layer "F.SilkS")
		)
		(fp_line
			(start 0.7874 0.4064)
			(end -0.7874 0.4064)
			(stroke
				(width 0.1524)
				(type default)
			)
			(layer "F.SilkS")
		)
		(fp_line
			(start -0.7874 0.4064)
			(end -0.7874 -0.4064)
			(stroke
				(width 0.1524)
				(type default)
			)
			(layer "F.SilkS")
		)
		(fp_line
			(start -0.12065 -0.305054)
			(end -0.12065 -0.2794)
			(stroke
				(width 0.1)
				(type default)
			)
			(layer "F.Fab")
		)
		(fp_line
			(start -0.67945 -0.305054)
			(end -0.12065 -0.305054)
			(stroke
				(width 0.1)
				(type default)
			)
			(layer "F.Fab")
		)
		(fp_line
			(start 0.67945 -0.3048)
			(end 0.67945 0.3048)
			(stroke
				(width 0.1)
				(type default)
			)
			(layer "F.Fab")
		)
		(fp_line
			(start 0.12065 -0.3048)
			(end 0.67945 -0.3048)
			(stroke
				(width 0.1)
				(type default)
			)
			(layer "F.Fab")
		)
		(fp_line
			(start 0.12065 -0.2794)
			(end 0.12065 -0.3048)
			(stroke
				(width 0.1)
				(type default)
			)
			(layer "F.Fab")
		)
		(fp_line
			(start -0.12065 -0.2794)
			(end 0.12065 -0.2794)
			(stroke
				(width 0.1)
				(type default)
			)
			(layer "F.Fab")
		)
		(fp_line
			(start 0.120396 0.2794)
			(end -0.12065 0.2794)
			(stroke
				(width 0.1)
				(type default)
			)
			(layer "F.Fab")
		)
		(fp_line
			(start -0.12065 0.2794)
			(end -0.12065 0.3048)
			(stroke
				(width 0.1)
				(type default)
			)
			(layer "F.Fab")
		)
		(fp_line
			(start 0.67945 0.3048)
			(end 0.120396 0.3048)
			(stroke
				(width 0.1)
				(type default)
			)
			(layer "F.Fab")
		)
		(fp_line
			(start 0.120396 0.3048)
			(end 0.120396 0.2794)
			(stroke
				(width 0.1)
				(type default)
			)
			(layer "F.Fab")
		)
		(fp_line
			(start -0.12065 0.3048)
			(end -0.67945 0.3048)
			(stroke
				(width 0.1)
				(type default)
			)
			(layer "F.Fab")
		)
		(fp_line
			(start -0.67945 0.3048)
			(end -0.67945 -0.305054)
			(stroke
				(width 0.1)
				(type default)
			)
			(layer "F.Fab")
		)
		(pad "1" smd circle
			(at -0.40005 0 90)
			(size 0 0)
			(layers "F.Cu" "F.Mask" "F.Paste")
			(net "P3V3_AUX")
		)
		(pad "2" smd circle
			(at 0.40005 0 90)
			(size 0 0)
			(layers "F.Cu" "F.Mask" "F.Paste")
			(net "GND")
		)
	)
	(footprint ""
		(layer "F.Cu")
		(at 387.099302 -416.899344 -90)
		(property "Reference" "C6575"
			(at 0 0 270)
			(layer "F.SilkS")
			(hide yes)
			(effects
				(font
					(size 1.27 1.27)
				)
			)
		)
		(property "Value" ""
			(at 0 0 270)
			(layer "F.Fab")
			(effects
				(font
					(size 1.27 1.27)
				)
			)
		)
		(duplicate_pad_numbers_are_jumpers no)
		(fp_line
			(start -0.299974 0.150114)
			(end -0.299974 -0.150114)
			(stroke
				(width 0.1)
				(type default)
			)
			(layer "F.Fab")
		)
		(fp_line
			(start 0.299974 0.150114)
			(end -0.299974 0.150114)
			(stroke
				(width 0.1)
				(type default)
			)
			(layer "F.Fab")
		)
		(fp_line
			(start -0.299974 -0.150114)
			(end 0.299974 -0.150114)
			(stroke
				(width 0.1)
				(type default)
			)
			(layer "F.Fab")
		)
		(fp_line
			(start 0.299974 -0.150114)
			(end 0.299974 0.150114)
			(stroke
				(width 0.1)
				(type default)
			)
			(layer "F.Fab")
		)
		(pad "1" smd rect
			(at -0.2667 0 270)
			(size 0.3048 0.381)
			(layers "F.Cu" "F.Mask" "F.Paste")
			(net "P5E_CPU0_P2_TX_BUF_C_DP<5>")
		)
		(pad "2" smd rect
			(at 0.2667 0 270)
			(size 0.3048 0.381)
			(layers "F.Cu" "F.Mask" "F.Paste")
			(net "P5E_CPU0_P2_TX_BUF_DP<5>")
		)
	)
	(footprint ""
		(layer "F.Cu")
		(at 402.097748 -16.100298 90)
		(property "Reference" "C1557"
			(at 0 0 90)
			(layer "F.SilkS")
			(hide yes)
			(effects
				(font
					(size 1.27 1.27)
				)
			)
		)
		(property "Value" ""
			(at 0 0 90)
			(layer "F.Fab")
			(effects
				(font
					(size 1.27 1.27)
				)
			)
		)
		(duplicate_pad_numbers_are_jumpers no)
		(fp_line
			(start 0.299974 -0.150114)
			(end 0.299974 0.150114)
			(stroke
				(width 0.1)
				(type default)
			)
			(layer "F.Fab")
		)
		(fp_line
			(start -0.299974 -0.150114)
			(end 0.299974 -0.150114)
			(stroke
				(width 0.1)
				(type default)
			)
			(layer "F.Fab")
		)
		(fp_line
			(start 0.299974 0.150114)
			(end -0.299974 0.150114)
			(stroke
				(width 0.1)
				(type default)
			)
			(layer "F.Fab")
		)
		(fp_line
			(start -0.299974 0.150114)
			(end -0.299974 -0.150114)
			(stroke
				(width 0.1)
				(type default)
			)
			(layer "F.Fab")
		)
		(pad "1" smd rect
			(at -0.2667 0 90)
			(size 0.3048 0.381)
			(layers "F.Cu" "F.Mask" "F.Paste")
			(net "P5E_CPU0_G3_TX_C_DP<11>")
		)
		(pad "2" smd rect
			(at 0.2667 0 90)
			(size 0.3048 0.381)
			(layers "F.Cu" "F.Mask" "F.Paste")
			(net "P5E_CPU0_G3_TX_DP<11>")
		)
	)
	(footprint ""
		(layer "F.Cu")
		(at 111.252 -415.036 180)
		(property "Reference" "L1"
			(at 0 0 180)
			(layer "F.SilkS")
			(hide yes)
			(effects
				(font
					(size 1.27 1.27)
				)
			)
		)
		(property "Value" ""
			(at 0 0 180)
			(layer "F.Fab")
			(effects
				(font
					(size 1.27 1.27)
				)
			)
		)
		(duplicate_pad_numbers_are_jumpers no)
		(fp_line
			(start 1.63576 0.8128)
			(end -1.63576 0.8128)
			(stroke
				(width 0.1524)
				(type default)
			)
			(layer "F.SilkS")
		)
		(fp_line
			(start 1.63576 -0.8128)
			(end 1.63576 0.8128)
			(stroke
				(width 0.1524)
				(type default)
			)
			(layer "F.SilkS")
		)
		(fp_line
			(start -1.63576 -0.8128)
			(end 1.63576 -0.8128)
			(stroke
				(width 0.1524)
				(type default)
			)
			(layer "F.SilkS")
		)
		(fp_line
			(start -1.63576 -0.8128)
			(end -1.63576 0.8128)
			(stroke
				(width 0.1524)
				(type default)
			)
			(layer "F.SilkS")
		)
		(fp_line
			(start 1.560576 0.7366)
			(end 1.560576 -0.738632)
			(stroke
				(width 0.1)
				(type default)
			)
			(layer "F.Fab")
		)
		(fp_line
			(start 1.560576 -0.738632)
			(end -1.56083 -0.738632)
			(stroke
				(width 0.1)
				(type default)
			)
			(layer "F.Fab")
		)
		(fp_line
			(start 1.524 0.7366)
			(end 1.560576 0.7366)
			(stroke
				(width 0.1)
				(type default)
			)
			(layer "F.Fab")
		)
		(fp_line
			(start -1.524 0.7366)
			(end 1.524 0.7366)
			(stroke
				(width 0.1)
				(type default)
			)
			(layer "F.Fab")
		)
		(fp_line
			(start -1.56083 0.7366)
			(end -1.524 0.7366)
			(stroke
				(width 0.1)
				(type default)
			)
			(layer "F.Fab")
		)
		(fp_line
			(start -1.56083 -0.738632)
			(end -1.56083 0.7366)
			(stroke
				(width 0.1)
				(type default)
			)
			(layer "F.Fab")
		)
		(pad "1" smd rect
			(at -0.94996 0)
			(size 1.1176 1.3716)
			(layers "F.Cu" "F.Mask" "F.Paste")
			(net "P3V3_AUX")
		)
		(pad "2" smd rect
			(at 0.94996 0)
			(size 1.1176 1.3716)
			(layers "F.Cu" "F.Mask" "F.Paste")
			(net "P3V3_9ZXL045_P1")
		)
	)
	(footprint ""
		(layer "F.Cu")
		(at 177.378106 -426.332396)
		(property "Reference" "R2695"
			(at 0 0 0)
			(layer "F.SilkS")
			(hide yes)
			(effects
				(font
					(size 1.27 1.27)
				)
			)
		)
		(property "Value" ""
			(at 0 0 0)
			(layer "F.Fab")
			(effects
				(font
					(size 1.27 1.27)
				)
			)
		)
		(duplicate_pad_numbers_are_jumpers no)
		(fp_line
			(start -0.7874 -0.4064)
			(end 0.7874 -0.4064)
			(stroke
				(width 0.1524)
				(type default)
			)
			(layer "F.SilkS")
		)
		(fp_line
			(start -0.7874 0.4064)
			(end -0.7874 -0.4064)
			(stroke
				(width 0.1524)
				(type default)
			)
			(layer "F.SilkS")
		)
		(fp_line
			(start 0.7874 -0.4064)
			(end 0.7874 0.4064)
			(stroke
				(width 0.1524)
				(type default)
			)
			(layer "F.SilkS")
		)
		(fp_line
			(start 0.7874 0.4064)
			(end -0.7874 0.4064)
			(stroke
				(width 0.1524)
				(type default)
			)
			(layer "F.SilkS")
		)
		(fp_line
			(start -0.67945 -0.305054)
			(end -0.12065 -0.305054)
			(stroke
				(width 0.1)
				(type default)
			)
			(layer "F.Fab")
		)
		(fp_line
			(start -0.67945 0.3048)
			(end -0.67945 -0.305054)
			(stroke
				(width 0.1)
				(type default)
			)
			(layer "F.Fab")
		)
		(fp_line
			(start -0.12065 -0.305054)
			(end -0.12065 -0.2794)
			(stroke
				(width 0.1)
				(type default)
			)
			(layer "F.Fab")
		)
		(fp_line
			(start -0.12065 -0.2794)
			(end 0.12065 -0.2794)
			(stroke
				(width 0.1)
				(type default)
			)
			(layer "F.Fab")
		)
		(fp_line
			(start -0.12065 0.2794)
			(end -0.12065 0.3048)
			(stroke
				(width 0.1)
				(type default)
			)
			(layer "F.Fab")
		)
		(fp_line
			(start -0.12065 0.3048)
			(end -0.67945 0.3048)
			(stroke
				(width 0.1)
				(type default)
			)
			(layer "F.Fab")
		)
		(fp_line
			(start 0.120396 0.2794)
			(end -0.12065 0.2794)
			(stroke
				(width 0.1)
				(type default)
			)
			(layer "F.Fab")
		)
		(fp_line
			(start 0.120396 0.3048)
			(end 0.120396 0.2794)
			(stroke
				(width 0.1)
				(type default)
			)
			(layer "F.Fab")
		)
		(fp_line
			(start 0.12065 -0.3048)
			(end 0.67945 -0.3048)
			(stroke
				(width 0.1)
				(type default)
			)
			(layer "F.Fab")
		)
		(fp_line
			(start 0.12065 -0.2794)
			(end 0.12065 -0.3048)
			(stroke
				(width 0.1)
				(type default)
			)
			(layer "F.Fab")
		)
		(fp_line
			(start 0.67945 -0.3048)
			(end 0.67945 0.3048)
			(stroke
				(width 0.1)
				(type default)
			)
			(layer "F.Fab")
		)
		(fp_line
			(start 0.67945 0.3048)
			(end 0.120396 0.3048)
			(stroke
				(width 0.1)
				(type default)
			)
			(layer "F.Fab")
		)
		(pad "1" smd circle
			(at -0.40005 0)
			(size 0 0)
			(layers "F.Cu" "F.Mask" "F.Paste")
			(net "P3V3_AUX")
		)
		(pad "2" smd circle
			(at 0.40005 0)
			(size 0 0)
			(layers "F.Cu" "F.Mask" "F.Paste")
			(net "TCA9539_0_ADD0")
		)
	)
	(footprint ""
		(layer "F.Cu")
		(at 59.497722 -181.819042 180)
		(property "Reference" "PR161"
			(at 0 0 180)
			(layer "F.SilkS")
			(hide yes)
			(effects
				(font
					(size 1.27 1.27)
				)
			)
		)
		(property "Value" ""
			(at 0 0 180)
			(layer "F.Fab")
			(effects
				(font
					(size 1.27 1.27)
				)
			)
		)
		(duplicate_pad_numbers_are_jumpers no)
		(fp_line
			(start 0.7874 0.4064)
			(end -0.7874 0.4064)
			(stroke
				(width 0.1524)
				(type default)
			)
			(layer "F.SilkS")
		)
		(fp_line
			(start 0.7874 -0.4064)
			(end 0.7874 0.4064)
			(stroke
				(width 0.1524)
				(type default)
			)
			(layer "F.SilkS")
		)
		(fp_line
			(start -0.7874 0.4064)
			(end -0.7874 -0.4064)
			(stroke
				(width 0.1524)
				(type default)
			)
			(layer "F.SilkS")
		)
		(fp_line
			(start -0.7874 -0.4064)
			(end 0.7874 -0.4064)
			(stroke
				(width 0.1524)
				(type default)
			)
			(layer "F.SilkS")
		)
		(fp_line
			(start 0.67945 0.3048)
			(end 0.120396 0.3048)
			(stroke
				(width 0.1)
				(type default)
			)
			(layer "F.Fab")
		)
		(fp_line
			(start 0.67945 -0.3048)
			(end 0.67945 0.3048)
			(stroke
				(width 0.1)
				(type default)
			)
			(layer "F.Fab")
		)
		(fp_line
			(start 0.12065 -0.2794)
			(end 0.12065 -0.3048)
			(stroke
				(width 0.1)
				(type default)
			)
			(layer "F.Fab")
		)
		(fp_line
			(start 0.12065 -0.3048)
			(end 0.67945 -0.3048)
			(stroke
				(width 0.1)
				(type default)
			)
			(layer "F.Fab")
		)
		(fp_line
			(start 0.120396 0.3048)
			(end 0.120396 0.2794)
			(stroke
				(width 0.1)
				(type default)
			)
			(layer "F.Fab")
		)
		(fp_line
			(start 0.120396 0.2794)
			(end -0.12065 0.2794)
			(stroke
				(width 0.1)
				(type default)
			)
			(layer "F.Fab")
		)
		(fp_line
			(start -0.12065 0.3048)
			(end -0.67945 0.3048)
			(stroke
				(width 0.1)
				(type default)
			)
			(layer "F.Fab")
		)
		(fp_line
			(start -0.12065 0.2794)
			(end -0.12065 0.3048)
			(stroke
				(width 0.1)
				(type default)
			)
			(layer "F.Fab")
		)
		(fp_line
			(start -0.12065 -0.2794)
			(end 0.12065 -0.2794)
			(stroke
				(width 0.1)
				(type default)
			)
			(layer "F.Fab")
		)
		(fp_line
			(start -0.12065 -0.305054)
			(end -0.12065 -0.2794)
			(stroke
				(width 0.1)
				(type default)
			)
			(layer "F.Fab")
		)
		(fp_line
			(start -0.67945 0.3048)
			(end -0.67945 -0.305054)
			(stroke
				(width 0.1)
				(type default)
			)
			(layer "F.Fab")
		)
		(fp_line
			(start -0.67945 -0.305054)
			(end -0.12065 -0.305054)
			(stroke
				(width 0.1)
				(type default)
			)
			(layer "F.Fab")
		)
		(pad "1" smd circle
			(at -0.40005 0 180)
			(size 0 0)
			(layers "F.Cu" "F.Mask" "F.Paste")
			(net "PVDDCR_CPU0_P1")
		)
		(pad "2" smd circle
			(at 0.40005 0 180)
			(size 0 0)
			(layers "F.Cu" "F.Mask" "F.Paste")
			(net "VSENSE_PVDDCR_CPU0_P1_DP")
		)
	)
	(footprint ""
		(layer "F.Cu")
		(at 28.71851 -337.403948)
		(property "Reference" "PL67"
			(at -3.242056 -15.887446 0)
			(unlocked yes)
			(layer "F.SilkS")
			(effects
				(font
					(size 0.7874 0.5842)
					(thickness 0.1524)
				)
				(justify left)
			)
		)
		(property "Value" ""
			(at 0 0 0)
			(layer "F.Fab")
			(effects
				(font
					(size 1.27 1.27)
				)
			)
		)
		(duplicate_pad_numbers_are_jumpers no)
		(fp_line
			(start -3.750056 -5.500116)
			(end -2.393442 -5.500116)
			(stroke
				(width 0.1524)
				(type default)
			)
			(layer "F.SilkS")
		)
		(fp_line
			(start -3.750056 5.500116)
			(end -3.750056 -5.500116)
			(stroke
				(width 0.1524)
				(type default)
			)
			(layer "F.SilkS")
		)
		(fp_line
			(start -2.393442 5.500116)
			(end -3.750056 5.500116)
			(stroke
				(width 0.1524)
				(type default)
			)
			(layer "F.SilkS")
		)
		(fp_line
			(start 2.393442 5.500116)
			(end 3.750056 5.500116)
			(stroke
				(width 0.1524)
				(type default)
			)
			(layer "F.SilkS")
		)
		(fp_line
			(start 3.750056 -5.500116)
			(end 2.393442 -5.500116)
			(stroke
				(width 0.1524)
				(type default)
			)
			(layer "F.SilkS")
		)
		(fp_line
			(start 3.750056 5.500116)
			(end 3.750056 -5.500116)
			(stroke
				(width 0.1524)
				(type default)
			)
			(layer "F.SilkS")
		)
		(fp_poly
			(pts
				(xy -3.9116 -4.249928) (xy -4.2164 -4.097528) (xy -4.2164 -4.402328)
			)
			(stroke
				(width 0)
				(type default)
			)
			(fill yes)
			(layer "F.SilkS")
		)
		(fp_line
			(start -3.750056 -5.500116)
			(end -3.750056 5.500116)
			(stroke
				(width 0.1)
				(type default)
			)
			(layer "F.Fab")
		)
		(fp_line
			(start -3.750056 5.500116)
			(end 3.750056 5.500116)
			(stroke
				(width 0.1)
				(type default)
			)
			(layer "F.Fab")
		)
		(fp_line
			(start 3.750056 -5.500116)
			(end -3.750056 -5.500116)
			(stroke
				(width 0.1)
				(type default)
			)
			(layer "F.Fab")
		)
		(fp_line
			(start 3.750056 5.500116)
			(end 3.750056 -5.500116)
			(stroke
				(width 0.1)
				(type default)
			)
			(layer "F.Fab")
		)
		(fp_poly
			(pts
				(xy -4.9276 -4.757928) (xy -4.9276 -3.741928) (xy -3.9116 -4.249928)
			)
			(stroke
				(width 0)
				(type default)
			)
			(fill yes)
			(layer "F.Fab")
		)
		(pad "1" smd rect
			(at 0 -4.249928 270)
			(size 2.413 4.5212)
			(layers "F.Cu" "F.Mask" "F.Paste")
			(net "SW_PVDDIO_P1_SW4")
		)
		(pad "2" smd rect
			(at 0 -1.175004 270)
			(size 1.3716 4.5212)
			(layers "F.Cu" "F.Mask" "F.Paste")
			(net "IND_PVDDIO_P1_CPL0")
		)
		(pad "3" smd rect
			(at 0 1.175004 270)
			(size 1.3716 4.5212)
			(layers "F.Cu" "F.Mask" "F.Paste")
			(net "IND_PVDDIO_P1_CPL4")
		)
		(pad "4" smd rect
			(at 0 4.249928 270)
			(size 2.413 4.5212)
			(layers "F.Cu" "F.Mask" "F.Paste")
			(net "PVDDIO_P1")
		)
	)
	(footprint ""
		(layer "F.Cu")
		(at 143.171672 -386.684774 -90)
		(property "Reference" "R637"
			(at 0 0 270)
			(layer "F.SilkS")
			(hide yes)
			(effects
				(font
					(size 1.27 1.27)
				)
			)
		)
		(property "Value" ""
			(at 0 0 270)
			(layer "F.Fab")
			(effects
				(font
					(size 1.27 1.27)
				)
			)
		)
		(duplicate_pad_numbers_are_jumpers no)
		(fp_line
			(start -0.32512 0.175006)
			(end -0.32512 -0.175006)
			(stroke
				(width 0.1)
				(type default)
			)
			(layer "F.Fab")
		)
		(fp_line
			(start 0.32512 0.175006)
			(end -0.32512 0.175006)
			(stroke
				(width 0.1)
				(type default)
			)
			(layer "F.Fab")
		)
		(fp_line
			(start -0.32512 -0.175006)
			(end 0.32512 -0.175006)
			(stroke
				(width 0.1)
				(type default)
			)
			(layer "F.Fab")
		)
		(fp_line
			(start 0.32512 -0.175006)
			(end 0.32512 0.175006)
			(stroke
				(width 0.1)
				(type default)
			)
			(layer "F.Fab")
		)
		(pad "1" smd rect
			(at -0.2667 0 270)
			(size 0.3048 0.381)
			(layers "F.Cu" "F.Mask" "F.Paste")
			(net "CLK_100M_RETIMER_CPU1_P2_DN")
		)
		(pad "2" smd rect
			(at 0.2667 0 90)
			(size 0.3048 0.381)
			(layers "F.Cu" "F.Mask" "F.Paste")
			(net "GND")
		)
	)
	(footprint ""
		(layer "F.Cu")
		(at 95.26143 -58.07583)
		(property "Reference" "PR3822"
			(at 0 0 0)
			(layer "F.SilkS")
			(hide yes)
			(effects
				(font
					(size 1.27 1.27)
				)
			)
		)
		(property "Value" ""
			(at 0 0 0)
			(layer "F.Fab")
			(effects
				(font
					(size 1.27 1.27)
				)
			)
		)
		(duplicate_pad_numbers_are_jumpers no)
		(fp_line
			(start -0.7874 -0.4064)
			(end 0.7874 -0.4064)
			(stroke
				(width 0.1524)
				(type default)
			)
			(layer "F.SilkS")
		)
		(fp_line
			(start -0.7874 0.4064)
			(end -0.7874 -0.4064)
			(stroke
				(width 0.1524)
				(type default)
			)
			(layer "F.SilkS")
		)
		(fp_line
			(start 0.7874 -0.4064)
			(end 0.7874 0.4064)
			(stroke
				(width 0.1524)
				(type default)
			)
			(layer "F.SilkS")
		)
		(fp_line
			(start 0.7874 0.4064)
			(end -0.7874 0.4064)
			(stroke
				(width 0.1524)
				(type default)
			)
			(layer "F.SilkS")
		)
		(fp_line
			(start -0.67945 -0.305054)
			(end -0.12065 -0.305054)
			(stroke
				(width 0.1)
				(type default)
			)
			(layer "F.Fab")
		)
		(fp_line
			(start -0.67945 0.3048)
			(end -0.67945 -0.305054)
			(stroke
				(width 0.1)
				(type default)
			)
			(layer "F.Fab")
		)
		(fp_line
			(start -0.12065 -0.305054)
			(end -0.12065 -0.2794)
			(stroke
				(width 0.1)
				(type default)
			)
			(layer "F.Fab")
		)
		(fp_line
			(start -0.12065 -0.2794)
			(end 0.12065 -0.2794)
			(stroke
				(width 0.1)
				(type default)
			)
			(layer "F.Fab")
		)
		(fp_line
			(start -0.12065 0.2794)
			(end -0.12065 0.3048)
			(stroke
				(width 0.1)
				(type default)
			)
			(layer "F.Fab")
		)
		(fp_line
			(start -0.12065 0.3048)
			(end -0.67945 0.3048)
			(stroke
				(width 0.1)
				(type default)
			)
			(layer "F.Fab")
		)
		(fp_line
			(start 0.120396 0.2794)
			(end -0.12065 0.2794)
			(stroke
				(width 0.1)
				(type default)
			)
			(layer "F.Fab")
		)
		(fp_line
			(start 0.120396 0.3048)
			(end 0.120396 0.2794)
			(stroke
				(width 0.1)
				(type default)
			)
			(layer "F.Fab")
		)
		(fp_line
			(start 0.12065 -0.3048)
			(end 0.67945 -0.3048)
			(stroke
				(width 0.1)
				(type default)
			)
			(layer "F.Fab")
		)
		(fp_line
			(start 0.12065 -0.2794)
			(end 0.12065 -0.3048)
			(stroke
				(width 0.1)
				(type default)
			)
			(layer "F.Fab")
		)
		(fp_line
			(start 0.67945 -0.3048)
			(end 0.67945 0.3048)
			(stroke
				(width 0.1)
				(type default)
			)
			(layer "F.Fab")
		)
		(fp_line
			(start 0.67945 0.3048)
			(end 0.120396 0.3048)
			(stroke
				(width 0.1)
				(type default)
			)
			(layer "F.Fab")
		)
		(pad "1" smd circle
			(at -0.40005 0)
			(size 0 0)
			(layers "F.Cu" "F.Mask" "F.Paste")
			(net "P3V3_OCP_CB_2")
		)
		(pad "2" smd circle
			(at 0.40005 0)
			(size 0 0)
			(layers "F.Cu" "F.Mask" "F.Paste")
			(net "GND")
		)
	)
	(footprint ""
		(layer "F.Cu")
		(at 398.595088 -385.23926 180)
		(property "Reference" "C866"
			(at 0 0 180)
			(layer "F.SilkS")
			(hide yes)
			(effects
				(font
					(size 1.27 1.27)
				)
			)
		)
		(property "Value" ""
			(at 0 0 180)
			(layer "F.Fab")
			(effects
				(font
					(size 1.27 1.27)
				)
			)
		)
		(duplicate_pad_numbers_are_jumpers no)
		(fp_line
			(start 0.299974 0.150114)
			(end -0.299974 0.150114)
			(stroke
				(width 0.1)
				(type default)
			)
			(layer "F.Fab")
		)
		(fp_line
			(start 0.299974 -0.150114)
			(end 0.299974 0.150114)
			(stroke
				(width 0.1)
				(type default)
			)
			(layer "F.Fab")
		)
		(fp_line
			(start -0.299974 0.150114)
			(end -0.299974 -0.150114)
			(stroke
				(width 0.1)
				(type default)
			)
			(layer "F.Fab")
		)
		(fp_line
			(start -0.299974 -0.150114)
			(end 0.299974 -0.150114)
			(stroke
				(width 0.1)
				(type default)
			)
			(layer "F.Fab")
		)
		(pad "1" smd rect
			(at -0.2667 0 180)
			(size 0.3048 0.381)
			(layers "F.Cu" "F.Mask" "F.Paste")
			(net "P5E_CPU0_P2_TX_C_DN<1>")
		)
		(pad "2" smd rect
			(at 0.2667 0 180)
			(size 0.3048 0.381)
			(layers "F.Cu" "F.Mask" "F.Paste")
			(net "P5E_CPU0_P2_TX_DN<1>")
		)
	)
	(footprint ""
		(layer "F.Cu")
		(at 126.571756 -29.697172 90)
		(property "Reference" "C93"
			(at 0 0 90)
			(layer "F.SilkS")
			(hide yes)
			(effects
				(font
					(size 1.27 1.27)
				)
			)
		)
		(property "Value" ""
			(at 0 0 90)
			(layer "F.Fab")
			(effects
				(font
					(size 1.27 1.27)
				)
			)
		)
		(duplicate_pad_numbers_are_jumpers no)
		(fp_line
			(start 0.7874 -0.4064)
			(end 0.7874 0.4064)
			(stroke
				(width 0.1524)
				(type default)
			)
			(layer "F.SilkS")
		)
		(fp_line
			(start -0.7874 -0.4064)
			(end 0.7874 -0.4064)
			(stroke
				(width 0.1524)
				(type default)
			)
			(layer "F.SilkS")
		)
		(fp_line
			(start 0.7874 0.4064)
			(end -0.7874 0.4064)
			(stroke
				(width 0.1524)
				(type default)
			)
			(layer "F.SilkS")
		)
		(fp_line
			(start -0.7874 0.4064)
			(end -0.7874 -0.4064)
			(stroke
				(width 0.1524)
				(type default)
			)
			(layer "F.SilkS")
		)
		(fp_line
			(start -0.12065 -0.305054)
			(end -0.12065 -0.2794)
			(stroke
				(width 0.1)
				(type default)
			)
			(layer "F.Fab")
		)
		(fp_line
			(start -0.67945 -0.305054)
			(end -0.12065 -0.305054)
			(stroke
				(width 0.1)
				(type default)
			)
			(layer "F.Fab")
		)
		(fp_line
			(start 0.67945 -0.3048)
			(end 0.67945 0.3048)
			(stroke
				(width 0.1)
				(type default)
			)
			(layer "F.Fab")
		)
		(fp_line
			(start 0.12065 -0.3048)
			(end 0.67945 -0.3048)
			(stroke
				(width 0.1)
				(type default)
			)
			(layer "F.Fab")
		)
		(fp_line
			(start 0.12065 -0.2794)
			(end 0.12065 -0.3048)
			(stroke
				(width 0.1)
				(type default)
			)
			(layer "F.Fab")
		)
		(fp_line
			(start -0.12065 -0.2794)
			(end 0.12065 -0.2794)
			(stroke
				(width 0.1)
				(type default)
			)
			(layer "F.Fab")
		)
		(fp_line
			(start 0.120396 0.2794)
			(end -0.12065 0.2794)
			(stroke
				(width 0.1)
				(type default)
			)
			(layer "F.Fab")
		)
		(fp_line
			(start -0.12065 0.2794)
			(end -0.12065 0.3048)
			(stroke
				(width 0.1)
				(type default)
			)
			(layer "F.Fab")
		)
		(fp_line
			(start 0.67945 0.3048)
			(end 0.120396 0.3048)
			(stroke
				(width 0.1)
				(type default)
			)
			(layer "F.Fab")
		)
		(fp_line
			(start 0.120396 0.3048)
			(end 0.120396 0.2794)
			(stroke
				(width 0.1)
				(type default)
			)
			(layer "F.Fab")
		)
		(fp_line
			(start -0.12065 0.3048)
			(end -0.67945 0.3048)
			(stroke
				(width 0.1)
				(type default)
			)
			(layer "F.Fab")
		)
		(fp_line
			(start -0.67945 0.3048)
			(end -0.67945 -0.305054)
			(stroke
				(width 0.1)
				(type default)
			)
			(layer "F.Fab")
		)
		(pad "1" smd circle
			(at -0.40005 0 90)
			(size 0 0)
			(layers "F.Cu" "F.Mask" "F.Paste")
			(net "XTAL_USB_CPU0_HUB1_XOUT")
		)
		(pad "2" smd circle
			(at 0.40005 0 90)
			(size 0 0)
			(layers "F.Cu" "F.Mask" "F.Paste")
			(net "GND")
		)
	)
	(footprint ""
		(layer "F.Cu")
		(at 479.445066 -297.569128 180)
		(property "Reference" "DB4"
			(at -3.05943 -2.144014 0)
			(unlocked yes)
			(layer "F.SilkS")
			(effects
				(font
					(size 0.7874 0.5842)
					(thickness 0.1524)
				)
				(justify left)
			)
		)
		(property "Value" ""
			(at 0 0 180)
			(layer "F.Fab")
			(effects
				(font
					(size 1.27 1.27)
				)
			)
		)
		(duplicate_pad_numbers_are_jumpers no)
		(fp_line
			(start 3.330702 -4.771136)
			(end 3.21564 -4.46786)
			(stroke
				(width 0.1524)
				(type default)
			)
			(layer "F.SilkS")
		)
		(fp_line
			(start 2.502916 -2.588514)
			(end 0 4.011168)
			(stroke
				(width 0.1524)
				(type default)
			)
			(layer "F.SilkS")
		)
		(fp_line
			(start 0 4.011168)
			(end -3.330702 -4.771136)
			(stroke
				(width 0.1524)
				(type default)
			)
			(layer "F.SilkS")
		)
		(fp_line
			(start -3.330702 -4.771136)
			(end 3.330702 -4.771136)
			(stroke
				(width 0.1524)
				(type default)
			)
			(layer "F.SilkS")
		)
		(fp_line
			(start 3.330702 -4.771136)
			(end 0 4.011168)
			(stroke
				(width 0.1)
				(type default)
			)
			(layer "F.Fab")
		)
		(fp_line
			(start 0 4.011168)
			(end -3.330702 -4.771136)
			(stroke
				(width 0.1)
				(type default)
			)
			(layer "F.Fab")
		)
		(fp_line
			(start -3.330702 -4.771136)
			(end 3.330702 -4.771136)
			(stroke
				(width 0.1)
				(type default)
			)
			(layer "F.Fab")
		)
		(pad "1" thru_hole circle
			(at 0 0 180)
			(size 2.159 2.159)
			(drill 1.7018)
			(layers "*.Cu" "*.Mask")
			(remove_unused_layers no)
			(net "T1_GND")
			(clearance 0.0254)
			(thermal_gap 0.0254)
		)
		(pad "2" thru_hole circle
			(at -1.27 -3.348736 180)
			(size 2.159 2.159)
			(drill 1.7018)
			(layers "*.Cu" "*.Mask")
			(remove_unused_layers no)
			(net "TDR_SE_45_OHM_IN3")
			(clearance 0.0254)
			(thermal_gap 0.0254)
		)
		(pad "3" thru_hole circle
			(at 1.27 -3.348736 180)
			(size 2.159 2.159)
			(drill 1.7018)
			(layers "*.Cu" "*.Mask")
			(remove_unused_layers no)
			(net "TDR_SE_45_OHM_IN3")
			(clearance 0.0254)
			(thermal_gap 0.0254)
		)
	)
	(footprint ""
		(layer "F.Cu")
		(at 106.934 -416.306 180)
		(property "Reference" "C83"
			(at 0 0 180)
			(layer "F.SilkS")
			(hide yes)
			(effects
				(font
					(size 1.27 1.27)
				)
			)
		)
		(property "Value" ""
			(at 0 0 180)
			(layer "F.Fab")
			(effects
				(font
					(size 1.27 1.27)
				)
			)
		)
		(duplicate_pad_numbers_are_jumpers no)
		(fp_line
			(start 0.7874 0.4064)
			(end -0.7874 0.4064)
			(stroke
				(width 0.1524)
				(type default)
			)
			(layer "F.SilkS")
		)
		(fp_line
			(start 0.7874 -0.4064)
			(end 0.7874 0.4064)
			(stroke
				(width 0.1524)
				(type default)
			)
			(layer "F.SilkS")
		)
		(fp_line
			(start -0.7874 0.4064)
			(end -0.7874 -0.4064)
			(stroke
				(width 0.1524)
				(type default)
			)
			(layer "F.SilkS")
		)
		(fp_line
			(start -0.7874 -0.4064)
			(end 0.7874 -0.4064)
			(stroke
				(width 0.1524)
				(type default)
			)
			(layer "F.SilkS")
		)
		(fp_line
			(start 0.67945 0.3048)
			(end 0.120396 0.3048)
			(stroke
				(width 0.1)
				(type default)
			)
			(layer "F.Fab")
		)
		(fp_line
			(start 0.67945 -0.3048)
			(end 0.67945 0.3048)
			(stroke
				(width 0.1)
				(type default)
			)
			(layer "F.Fab")
		)
		(fp_line
			(start 0.12065 -0.2794)
			(end 0.12065 -0.3048)
			(stroke
				(width 0.1)
				(type default)
			)
			(layer "F.Fab")
		)
		(fp_line
			(start 0.12065 -0.3048)
			(end 0.67945 -0.3048)
			(stroke
				(width 0.1)
				(type default)
			)
			(layer "F.Fab")
		)
		(fp_line
			(start 0.120396 0.3048)
			(end 0.120396 0.2794)
			(stroke
				(width 0.1)
				(type default)
			)
			(layer "F.Fab")
		)
		(fp_line
			(start 0.120396 0.2794)
			(end -0.12065 0.2794)
			(stroke
				(width 0.1)
				(type default)
			)
			(layer "F.Fab")
		)
		(fp_line
			(start -0.12065 0.3048)
			(end -0.67945 0.3048)
			(stroke
				(width 0.1)
				(type default)
			)
			(layer "F.Fab")
		)
		(fp_line
			(start -0.12065 0.2794)
			(end -0.12065 0.3048)
			(stroke
				(width 0.1)
				(type default)
			)
			(layer "F.Fab")
		)
		(fp_line
			(start -0.12065 -0.2794)
			(end 0.12065 -0.2794)
			(stroke
				(width 0.1)
				(type default)
			)
			(layer "F.Fab")
		)
		(fp_line
			(start -0.12065 -0.305054)
			(end -0.12065 -0.2794)
			(stroke
				(width 0.1)
				(type default)
			)
			(layer "F.Fab")
		)
		(fp_line
			(start -0.67945 0.3048)
			(end -0.67945 -0.305054)
			(stroke
				(width 0.1)
				(type default)
			)
			(layer "F.Fab")
		)
		(fp_line
			(start -0.67945 -0.305054)
			(end -0.12065 -0.305054)
			(stroke
				(width 0.1)
				(type default)
			)
			(layer "F.Fab")
		)
		(pad "1" smd circle
			(at -0.40005 0 180)
			(size 0 0)
			(layers "F.Cu" "F.Mask" "F.Paste")
			(net "P3V3_9ZXL045_P1_VDDR")
		)
		(pad "2" smd circle
			(at 0.40005 0 180)
			(size 0 0)
			(layers "F.Cu" "F.Mask" "F.Paste")
			(net "GND")
		)
	)
	(footprint ""
		(layer "F.Cu")
		(at 118.363238 -41.17975 90)
		(property "Reference" "R6281"
			(at 0 0 90)
			(layer "F.SilkS")
			(hide yes)
			(effects
				(font
					(size 1.27 1.27)
				)
			)
		)
		(property "Value" ""
			(at 0 0 90)
			(layer "F.Fab")
			(effects
				(font
					(size 1.27 1.27)
				)
			)
		)
		(duplicate_pad_numbers_are_jumpers no)
		(fp_line
			(start 0.7874 -0.4064)
			(end 0.7874 0.4064)
			(stroke
				(width 0.1524)
				(type default)
			)
			(layer "F.SilkS")
		)
		(fp_line
			(start -0.7874 -0.4064)
			(end 0.7874 -0.4064)
			(stroke
				(width 0.1524)
				(type default)
			)
			(layer "F.SilkS")
		)
		(fp_line
			(start 0.7874 0.4064)
			(end -0.7874 0.4064)
			(stroke
				(width 0.1524)
				(type default)
			)
			(layer "F.SilkS")
		)
		(fp_line
			(start -0.7874 0.4064)
			(end -0.7874 -0.4064)
			(stroke
				(width 0.1524)
				(type default)
			)
			(layer "F.SilkS")
		)
		(fp_line
			(start -0.12065 -0.305054)
			(end -0.12065 -0.2794)
			(stroke
				(width 0.1)
				(type default)
			)
			(layer "F.Fab")
		)
		(fp_line
			(start -0.67945 -0.305054)
			(end -0.12065 -0.305054)
			(stroke
				(width 0.1)
				(type default)
			)
			(layer "F.Fab")
		)
		(fp_line
			(start 0.67945 -0.3048)
			(end 0.67945 0.3048)
			(stroke
				(width 0.1)
				(type default)
			)
			(layer "F.Fab")
		)
		(fp_line
			(start 0.12065 -0.3048)
			(end 0.67945 -0.3048)
			(stroke
				(width 0.1)
				(type default)
			)
			(layer "F.Fab")
		)
		(fp_line
			(start 0.12065 -0.2794)
			(end 0.12065 -0.3048)
			(stroke
				(width 0.1)
				(type default)
			)
			(layer "F.Fab")
		)
		(fp_line
			(start -0.12065 -0.2794)
			(end 0.12065 -0.2794)
			(stroke
				(width 0.1)
				(type default)
			)
			(layer "F.Fab")
		)
		(fp_line
			(start 0.120396 0.2794)
			(end -0.12065 0.2794)
			(stroke
				(width 0.1)
				(type default)
			)
			(layer "F.Fab")
		)
		(fp_line
			(start -0.12065 0.2794)
			(end -0.12065 0.3048)
			(stroke
				(width 0.1)
				(type default)
			)
			(layer "F.Fab")
		)
		(fp_line
			(start 0.67945 0.3048)
			(end 0.120396 0.3048)
			(stroke
				(width 0.1)
				(type default)
			)
			(layer "F.Fab")
		)
		(fp_line
			(start 0.120396 0.3048)
			(end 0.120396 0.2794)
			(stroke
				(width 0.1)
				(type default)
			)
			(layer "F.Fab")
		)
		(fp_line
			(start -0.12065 0.3048)
			(end -0.67945 0.3048)
			(stroke
				(width 0.1)
				(type default)
			)
			(layer "F.Fab")
		)
		(fp_line
			(start -0.67945 0.3048)
			(end -0.67945 -0.305054)
			(stroke
				(width 0.1)
				(type default)
			)
			(layer "F.Fab")
		)
		(pad "1" smd circle
			(at -0.40005 0 90)
			(size 0 0)
			(layers "F.Cu" "F.Mask" "F.Paste")
			(net "USB_HUB2_TI_SMBUSZ_MRP_PROG_FUNC2")
		)
		(pad "2" smd circle
			(at 0.40005 0 90)
			(size 0 0)
			(layers "F.Cu" "F.Mask" "F.Paste")
			(net "GND")
		)
	)
	(footprint ""
		(layer "F.Cu")
		(at 277.895304 -153.766012)
		(property "Reference" "H125"
			(at 5.0038 5.03047 0)
			(unlocked yes)
			(layer "F.SilkS")
			(effects
				(font
					(size 0.7874 0.5842)
					(thickness 0.1524)
				)
				(justify left)
			)
		)
		(property "Value" ""
			(at 0 0 0)
			(layer "F.Fab")
			(effects
				(font
					(size 1.27 1.27)
				)
			)
		)
		(duplicate_pad_numbers_are_jumpers no)
		(fp_circle
			(center 0 0)
			(end 5.8166 0)
			(stroke
				(width 0.1524)
				(type default)
			)
			(fill no)
			(layer "F.SilkS")
		)
		(fp_circle
			(center 0 0)
			(end 5.8166 0)
			(stroke
				(width 0.1524)
				(type default)
			)
			(fill no)
			(layer "B.SilkS")
		)
		(fp_circle
			(center 0 0)
			(end 5.8166 0)
			(stroke
				(width 0.1)
				(type default)
			)
			(fill no)
			(layer "B.Fab")
		)
		(fp_circle
			(center 0 0)
			(end 5.8166 0)
			(stroke
				(width 0.1)
				(type default)
			)
			(fill no)
			(layer "F.Fab")
		)
		(pad "" np_thru_hole circle
			(at 0 0)
			(size 10.0076 10.0076)
			(drill 10.0076)
			(layers "*.Cu" "*.Mask")
			(clearance 0.381)
			(thermal_gap 0.381)
		)
	)
	(footprint ""
		(layer "F.Cu")
		(at 403.682962 -59.4995 180)
		(property "Reference" "R476"
			(at 0 0 180)
			(layer "F.SilkS")
			(hide yes)
			(effects
				(font
					(size 1.27 1.27)
				)
			)
		)
		(property "Value" ""
			(at 0 0 180)
			(layer "F.Fab")
			(effects
				(font
					(size 1.27 1.27)
				)
			)
		)
		(duplicate_pad_numbers_are_jumpers no)
		(fp_line
			(start 0.7874 0.4064)
			(end -0.7874 0.4064)
			(stroke
				(width 0.1524)
				(type default)
			)
			(layer "F.SilkS")
		)
		(fp_line
			(start 0.7874 -0.4064)
			(end 0.7874 0.4064)
			(stroke
				(width 0.1524)
				(type default)
			)
			(layer "F.SilkS")
		)
		(fp_line
			(start -0.7874 0.4064)
			(end -0.7874 -0.4064)
			(stroke
				(width 0.1524)
				(type default)
			)
			(layer "F.SilkS")
		)
		(fp_line
			(start -0.7874 -0.4064)
			(end 0.7874 -0.4064)
			(stroke
				(width 0.1524)
				(type default)
			)
			(layer "F.SilkS")
		)
		(fp_line
			(start 0.67945 0.3048)
			(end 0.120396 0.3048)
			(stroke
				(width 0.1)
				(type default)
			)
			(layer "F.Fab")
		)
		(fp_line
			(start 0.67945 -0.3048)
			(end 0.67945 0.3048)
			(stroke
				(width 0.1)
				(type default)
			)
			(layer "F.Fab")
		)
		(fp_line
			(start 0.12065 -0.2794)
			(end 0.12065 -0.3048)
			(stroke
				(width 0.1)
				(type default)
			)
			(layer "F.Fab")
		)
		(fp_line
			(start 0.12065 -0.3048)
			(end 0.67945 -0.3048)
			(stroke
				(width 0.1)
				(type default)
			)
			(layer "F.Fab")
		)
		(fp_line
			(start 0.120396 0.3048)
			(end 0.120396 0.2794)
			(stroke
				(width 0.1)
				(type default)
			)
			(layer "F.Fab")
		)
		(fp_line
			(start 0.120396 0.2794)
			(end -0.12065 0.2794)
			(stroke
				(width 0.1)
				(type default)
			)
			(layer "F.Fab")
		)
		(fp_line
			(start -0.12065 0.3048)
			(end -0.67945 0.3048)
			(stroke
				(width 0.1)
				(type default)
			)
			(layer "F.Fab")
		)
		(fp_line
			(start -0.12065 0.2794)
			(end -0.12065 0.3048)
			(stroke
				(width 0.1)
				(type default)
			)
			(layer "F.Fab")
		)
		(fp_line
			(start -0.12065 -0.2794)
			(end 0.12065 -0.2794)
			(stroke
				(width 0.1)
				(type default)
			)
			(layer "F.Fab")
		)
		(fp_line
			(start -0.12065 -0.305054)
			(end -0.12065 -0.2794)
			(stroke
				(width 0.1)
				(type default)
			)
			(layer "F.Fab")
		)
		(fp_line
			(start -0.67945 0.3048)
			(end -0.67945 -0.305054)
			(stroke
				(width 0.1)
				(type default)
			)
			(layer "F.Fab")
		)
		(fp_line
			(start -0.67945 -0.305054)
			(end -0.12065 -0.305054)
			(stroke
				(width 0.1)
				(type default)
			)
			(layer "F.Fab")
		)
		(pad "1" smd circle
			(at -0.40005 0 180)
			(size 0 0)
			(layers "F.Cu" "F.Mask" "F.Paste")
			(net "CPU0_XTRIG_L6")
		)
		(pad "2" smd circle
			(at 0.40005 0 180)
			(size 0 0)
			(layers "F.Cu" "F.Mask" "F.Paste")
			(net "HDT_CPU0_XTRIG_L6")
		)
	)
	(footprint ""
		(layer "F.Cu")
		(at 130.067304 -54.17439 180)
		(property "Reference" "U152"
			(at -2.417064 -3.52171 0)
			(unlocked yes)
			(layer "F.SilkS")
			(effects
				(font
					(size 0.7874 0.5842)
					(thickness 0.1524)
				)
				(justify left)
			)
		)
		(property "Value" ""
			(at 0 0 180)
			(layer "F.Fab")
			(effects
				(font
					(size 1.27 1.27)
				)
			)
		)
		(duplicate_pad_numbers_are_jumpers no)
		(fp_line
			(start 1.245616 1.445768)
			(end -1.245616 1.445768)
			(stroke
				(width 0.1524)
				(type default)
			)
			(layer "F.SilkS")
		)
		(fp_line
			(start 1.245616 -1.445768)
			(end 1.245616 1.445768)
			(stroke
				(width 0.1524)
				(type default)
			)
			(layer "F.SilkS")
		)
		(fp_line
			(start -1.245616 1.445768)
			(end -1.245616 -1.445768)
			(stroke
				(width 0.1524)
				(type default)
			)
			(layer "F.SilkS")
		)
		(fp_line
			(start -1.245616 -1.445768)
			(end 1.245616 -1.445768)
			(stroke
				(width 0.1524)
				(type default)
			)
			(layer "F.SilkS")
		)
		(fp_poly
			(pts
				(xy -1.809496 -0.216662) (xy -2.317496 0.037338) (xy -2.317496 -0.470662)
			)
			(stroke
				(width 0)
				(type default)
			)
			(fill yes)
			(layer "F.SilkS")
		)
		(fp_line
			(start 0.724916 0.925068)
			(end -0.724916 0.925068)
			(stroke
				(width 0.1)
				(type default)
			)
			(layer "F.Fab")
		)
		(fp_line
			(start 0.724916 -0.925068)
			(end 0.724916 0.925068)
			(stroke
				(width 0.1)
				(type default)
			)
			(layer "F.Fab")
		)
		(fp_line
			(start -0.724916 0.925068)
			(end -0.724916 -0.925068)
			(stroke
				(width 0.1)
				(type default)
			)
			(layer "F.Fab")
		)
		(fp_line
			(start -0.724916 -0.925068)
			(end 0.724916 -0.925068)
			(stroke
				(width 0.1)
				(type default)
			)
			(layer "F.Fab")
		)
		(fp_poly
			(pts
				(xy -1.894586 -0.453898) (xy -1.894586 0.054102) (xy -1.386586 -0.199898)
			)
			(stroke
				(width 0)
				(type default)
			)
			(fill yes)
			(layer "F.Fab")
		)
		(pad "1" smd circle
			(at -0.649986 -0.199898 90)
			(size 0 0)
			(layers "F.Cu" "F.Mask" "F.Paste")
			(net "GND")
		)
		(pad "2" smd rect
			(at -0.700024 0.199898 270)
			(size 0.1778 0.8128)
			(layers "F.Cu" "F.Mask" "F.Paste")
			(net "U152_OE_N")
		)
		(pad "3" smd rect
			(at -0.40005 0.899922 180)
			(size 0.1778 0.8128)
			(layers "F.Cu" "F.Mask" "F.Paste")
			(net "GND")
		)
		(pad "4" smd rect
			(at 0 0.899922 180)
			(size 0.1778 0.8128)
			(layers "F.Cu" "F.Mask" "F.Paste")
			(net "JTAG_CPUX_TDO")
		)
		(pad "5" smd rect
			(at 0.40005 0.899922 180)
			(size 0.1778 0.8128)
			(layers "F.Cu" "F.Mask" "F.Paste")
			(net "JTAG_CPUX_TDI_R1")
		)
		(pad "6" smd rect
			(at 0.700024 0.199898 90)
			(size 0.1778 0.8128)
			(layers "F.Cu" "F.Mask" "F.Paste")
			(net "PVDD18_S5_P0")
		)
		(pad "7" smd rect
			(at 0.700024 -0.199898 90)
			(size 0.1778 0.8128)
			(layers "F.Cu" "F.Mask" "F.Paste")
			(net "PVDD18_S5_P0")
		)
		(pad "8" smd rect
			(at 0.40005 -0.899922 180)
			(size 0.1778 0.8128)
			(layers "F.Cu" "F.Mask" "F.Paste")
			(net "JTAG_TDI")
		)
		(pad "9" smd rect
			(at 0 -0.899922 180)
			(size 0.1778 0.8128)
			(layers "F.Cu" "F.Mask" "F.Paste")
			(net "JTAG_TDO_R")
		)
		(pad "10" smd rect
			(at -0.40005 -0.912622 180)
			(size 0.1778 0.7874)
			(layers "F.Cu" "F.Mask" "F.Paste")
			(net "PVDD18_S5_P0")
		)
	)
	(footprint ""
		(layer "F.Cu")
		(at 41.11244 -105.2195)
		(property "Reference" "C1113"
			(at 0 0 0)
			(layer "F.SilkS")
			(hide yes)
			(effects
				(font
					(size 1.27 1.27)
				)
			)
		)
		(property "Value" ""
			(at 0 0 0)
			(layer "F.Fab")
			(effects
				(font
					(size 1.27 1.27)
				)
			)
		)
		(duplicate_pad_numbers_are_jumpers no)
		(fp_line
			(start -1.524 -0.762)
			(end 1.524 -0.762)
			(stroke
				(width 0.1524)
				(type default)
			)
			(layer "F.SilkS")
		)
		(fp_line
			(start -1.524 0.762)
			(end -1.524 -0.762)
			(stroke
				(width 0.1524)
				(type default)
			)
			(layer "F.SilkS")
		)
		(fp_line
			(start 1.524 -0.762)
			(end 1.524 0.762)
			(stroke
				(width 0.1524)
				(type default)
			)
			(layer "F.SilkS")
		)
		(fp_line
			(start 1.524 0.762)
			(end -1.524 0.762)
			(stroke
				(width 0.1524)
				(type default)
			)
			(layer "F.SilkS")
		)
		(fp_line
			(start -1.1049 -0.724916)
			(end -1.1049 0.724916)
			(stroke
				(width 0.1)
				(type default)
			)
			(layer "F.Fab")
		)
		(fp_line
			(start -1.1049 0.724916)
			(end 1.1049 0.724916)
			(stroke
				(width 0.1)
				(type default)
			)
			(layer "F.Fab")
		)
		(fp_line
			(start 1.1049 -0.724916)
			(end -1.1049 -0.724916)
			(stroke
				(width 0.1)
				(type default)
			)
			(layer "F.Fab")
		)
		(fp_line
			(start 1.1049 0.724916)
			(end 1.1049 -0.724916)
			(stroke
				(width 0.1)
				(type default)
			)
			(layer "F.Fab")
		)
		(pad "1" smd rect
			(at -0.889 0 180)
			(size 1.016 1.27)
			(layers "F.Cu" "F.Mask" "F.Paste")
			(net "P12V_AUX_DSC_S1")
		)
		(pad "2" smd rect
			(at 0.889 0 180)
			(size 1.016 1.27)
			(layers "F.Cu" "F.Mask" "F.Paste")
			(net "GND")
		)
	)
	(footprint ""
		(layer "F.Cu")
		(at 370.813584 -15.236952 90)
		(property "Reference" "C72"
			(at 0 0 90)
			(layer "F.SilkS")
			(hide yes)
			(effects
				(font
					(size 1.27 1.27)
				)
			)
		)
		(property "Value" ""
			(at 0 0 90)
			(layer "F.Fab")
			(effects
				(font
					(size 1.27 1.27)
				)
			)
		)
		(duplicate_pad_numbers_are_jumpers no)
		(fp_line
			(start 0.7874 -0.4064)
			(end 0.7874 0.4064)
			(stroke
				(width 0.1524)
				(type default)
			)
			(layer "F.SilkS")
		)
		(fp_line
			(start -0.7874 -0.4064)
			(end 0.7874 -0.4064)
			(stroke
				(width 0.1524)
				(type default)
			)
			(layer "F.SilkS")
		)
		(fp_line
			(start 0.7874 0.4064)
			(end -0.7874 0.4064)
			(stroke
				(width 0.1524)
				(type default)
			)
			(layer "F.SilkS")
		)
		(fp_line
			(start -0.7874 0.4064)
			(end -0.7874 -0.4064)
			(stroke
				(width 0.1524)
				(type default)
			)
			(layer "F.SilkS")
		)
		(fp_line
			(start -0.12065 -0.305054)
			(end -0.12065 -0.2794)
			(stroke
				(width 0.1)
				(type default)
			)
			(layer "F.Fab")
		)
		(fp_line
			(start -0.67945 -0.305054)
			(end -0.12065 -0.305054)
			(stroke
				(width 0.1)
				(type default)
			)
			(layer "F.Fab")
		)
		(fp_line
			(start 0.67945 -0.3048)
			(end 0.67945 0.3048)
			(stroke
				(width 0.1)
				(type default)
			)
			(layer "F.Fab")
		)
		(fp_line
			(start 0.12065 -0.3048)
			(end 0.67945 -0.3048)
			(stroke
				(width 0.1)
				(type default)
			)
			(layer "F.Fab")
		)
		(fp_line
			(start 0.12065 -0.2794)
			(end 0.12065 -0.3048)
			(stroke
				(width 0.1)
				(type default)
			)
			(layer "F.Fab")
		)
		(fp_line
			(start -0.12065 -0.2794)
			(end 0.12065 -0.2794)
			(stroke
				(width 0.1)
				(type default)
			)
			(layer "F.Fab")
		)
		(fp_line
			(start 0.120396 0.2794)
			(end -0.12065 0.2794)
			(stroke
				(width 0.1)
				(type default)
			)
			(layer "F.Fab")
		)
		(fp_line
			(start -0.12065 0.2794)
			(end -0.12065 0.3048)
			(stroke
				(width 0.1)
				(type default)
			)
			(layer "F.Fab")
		)
		(fp_line
			(start 0.67945 0.3048)
			(end 0.120396 0.3048)
			(stroke
				(width 0.1)
				(type default)
			)
			(layer "F.Fab")
		)
		(fp_line
			(start 0.120396 0.3048)
			(end 0.120396 0.2794)
			(stroke
				(width 0.1)
				(type default)
			)
			(layer "F.Fab")
		)
		(fp_line
			(start -0.12065 0.3048)
			(end -0.67945 0.3048)
			(stroke
				(width 0.1)
				(type default)
			)
			(layer "F.Fab")
		)
		(fp_line
			(start -0.67945 0.3048)
			(end -0.67945 -0.305054)
			(stroke
				(width 0.1)
				(type default)
			)
			(layer "F.Fab")
		)
		(pad "1" smd circle
			(at -0.40005 0 90)
			(size 0 0)
			(layers "F.Cu" "F.Mask" "F.Paste")
			(net "P3V3_AUX")
		)
		(pad "2" smd circle
			(at 0.40005 0 90)
			(size 0 0)
			(layers "F.Cu" "F.Mask" "F.Paste")
			(net "GND")
		)
	)
	(footprint ""
		(layer "F.Cu")
		(at 107.675934 -256.012442 90)
		(property "Reference" "C2412"
			(at 0 0 90)
			(layer "F.SilkS")
			(hide yes)
			(effects
				(font
					(size 1.27 1.27)
				)
			)
		)
		(property "Value" ""
			(at 0 0 90)
			(layer "F.Fab")
			(effects
				(font
					(size 1.27 1.27)
				)
			)
		)
		(duplicate_pad_numbers_are_jumpers no)
		(fp_line
			(start 0.7874 -0.4064)
			(end 0.7874 0.4064)
			(stroke
				(width 0.1524)
				(type default)
			)
			(layer "F.SilkS")
		)
		(fp_line
			(start -0.7874 -0.4064)
			(end 0.7874 -0.4064)
			(stroke
				(width 0.1524)
				(type default)
			)
			(layer "F.SilkS")
		)
		(fp_line
			(start 0.7874 0.4064)
			(end -0.7874 0.4064)
			(stroke
				(width 0.1524)
				(type default)
			)
			(layer "F.SilkS")
		)
		(fp_line
			(start -0.7874 0.4064)
			(end -0.7874 -0.4064)
			(stroke
				(width 0.1524)
				(type default)
			)
			(layer "F.SilkS")
		)
		(fp_line
			(start -0.12065 -0.305054)
			(end -0.12065 -0.2794)
			(stroke
				(width 0.1)
				(type default)
			)
			(layer "F.Fab")
		)
		(fp_line
			(start -0.67945 -0.305054)
			(end -0.12065 -0.305054)
			(stroke
				(width 0.1)
				(type default)
			)
			(layer "F.Fab")
		)
		(fp_line
			(start 0.67945 -0.3048)
			(end 0.67945 0.3048)
			(stroke
				(width 0.1)
				(type default)
			)
			(layer "F.Fab")
		)
		(fp_line
			(start 0.12065 -0.3048)
			(end 0.67945 -0.3048)
			(stroke
				(width 0.1)
				(type default)
			)
			(layer "F.Fab")
		)
		(fp_line
			(start 0.12065 -0.2794)
			(end 0.12065 -0.3048)
			(stroke
				(width 0.1)
				(type default)
			)
			(layer "F.Fab")
		)
		(fp_line
			(start -0.12065 -0.2794)
			(end 0.12065 -0.2794)
			(stroke
				(width 0.1)
				(type default)
			)
			(layer "F.Fab")
		)
		(fp_line
			(start 0.120396 0.2794)
			(end -0.12065 0.2794)
			(stroke
				(width 0.1)
				(type default)
			)
			(layer "F.Fab")
		)
		(fp_line
			(start -0.12065 0.2794)
			(end -0.12065 0.3048)
			(stroke
				(width 0.1)
				(type default)
			)
			(layer "F.Fab")
		)
		(fp_line
			(start 0.67945 0.3048)
			(end 0.120396 0.3048)
			(stroke
				(width 0.1)
				(type default)
			)
			(layer "F.Fab")
		)
		(fp_line
			(start 0.120396 0.3048)
			(end 0.120396 0.2794)
			(stroke
				(width 0.1)
				(type default)
			)
			(layer "F.Fab")
		)
		(fp_line
			(start -0.12065 0.3048)
			(end -0.67945 0.3048)
			(stroke
				(width 0.1)
				(type default)
			)
			(layer "F.Fab")
		)
		(fp_line
			(start -0.67945 0.3048)
			(end -0.67945 -0.305054)
			(stroke
				(width 0.1)
				(type default)
			)
			(layer "F.Fab")
		)
		(pad "1" smd circle
			(at -0.40005 0 90)
			(size 0 0)
			(layers "F.Cu" "F.Mask" "F.Paste")
			(net "PVDDCR_SOC_P1")
		)
		(pad "2" smd circle
			(at 0.40005 0 90)
			(size 0 0)
			(layers "F.Cu" "F.Mask" "F.Paste")
			(net "GND")
		)
	)
	(footprint ""
		(layer "F.Cu")
		(at 326.330056 -23.826216 -90)
		(property "Reference" "R5053"
			(at 0 0 270)
			(layer "F.SilkS")
			(hide yes)
			(effects
				(font
					(size 1.27 1.27)
				)
			)
		)
		(property "Value" ""
			(at 0 0 270)
			(layer "F.Fab")
			(effects
				(font
					(size 1.27 1.27)
				)
			)
		)
		(duplicate_pad_numbers_are_jumpers no)
		(fp_line
			(start -0.7874 0.4064)
			(end -0.7874 -0.4064)
			(stroke
				(width 0.1524)
				(type default)
			)
			(layer "F.SilkS")
		)
		(fp_line
			(start 0.7874 0.4064)
			(end -0.7874 0.4064)
			(stroke
				(width 0.1524)
				(type default)
			)
			(layer "F.SilkS")
		)
		(fp_line
			(start -0.7874 -0.4064)
			(end 0.7874 -0.4064)
			(stroke
				(width 0.1524)
				(type default)
			)
			(layer "F.SilkS")
		)
		(fp_line
			(start 0.7874 -0.4064)
			(end 0.7874 0.4064)
			(stroke
				(width 0.1524)
				(type default)
			)
			(layer "F.SilkS")
		)
		(fp_line
			(start -0.67945 0.3048)
			(end -0.67945 -0.305054)
			(stroke
				(width 0.1)
				(type default)
			)
			(layer "F.Fab")
		)
		(fp_line
			(start -0.12065 0.3048)
			(end -0.67945 0.3048)
			(stroke
				(width 0.1)
				(type default)
			)
			(layer "F.Fab")
		)
		(fp_line
			(start 0.120396 0.3048)
			(end 0.120396 0.2794)
			(stroke
				(width 0.1)
				(type default)
			)
			(layer "F.Fab")
		)
		(fp_line
			(start 0.67945 0.3048)
			(end 0.120396 0.3048)
			(stroke
				(width 0.1)
				(type default)
			)
			(layer "F.Fab")
		)
		(fp_line
			(start -0.12065 0.2794)
			(end -0.12065 0.3048)
			(stroke
				(width 0.1)
				(type default)
			)
			(layer "F.Fab")
		)
		(fp_line
			(start 0.120396 0.2794)
			(end -0.12065 0.2794)
			(stroke
				(width 0.1)
				(type default)
			)
			(layer "F.Fab")
		)
		(fp_line
			(start -0.12065 -0.2794)
			(end 0.12065 -0.2794)
			(stroke
				(width 0.1)
				(type default)
			)
			(layer "F.Fab")
		)
		(fp_line
			(start 0.12065 -0.2794)
			(end 0.12065 -0.3048)
			(stroke
				(width 0.1)
				(type default)
			)
			(layer "F.Fab")
		)
		(fp_line
			(start 0.12065 -0.3048)
			(end 0.67945 -0.3048)
			(stroke
				(width 0.1)
				(type default)
			)
			(layer "F.Fab")
		)
		(fp_line
			(start 0.67945 -0.3048)
			(end 0.67945 0.3048)
			(stroke
				(width 0.1)
				(type default)
			)
			(layer "F.Fab")
		)
		(fp_line
			(start -0.67945 -0.305054)
			(end -0.12065 -0.305054)
			(stroke
				(width 0.1)
				(type default)
			)
			(layer "F.Fab")
		)
		(fp_line
			(start -0.12065 -0.305054)
			(end -0.12065 -0.2794)
			(stroke
				(width 0.1)
				(type default)
			)
			(layer "F.Fab")
		)
		(pad "1" smd circle
			(at -0.40005 0 270)
			(size 0 0)
			(layers "F.Cu" "F.Mask" "F.Paste")
			(net "P1V5_BAT_OUT")
		)
		(pad "2" smd circle
			(at 0.40005 0 270)
			(size 0 0)
			(layers "F.Cu" "F.Mask" "F.Paste")
			(net "P1V5_BAT_OUT_R")
		)
	)
	(footprint ""
		(layer "F.Cu")
		(at 100.285296 -412.931102 90)
		(property "Reference" "R4213"
			(at 0 0 90)
			(layer "F.SilkS")
			(hide yes)
			(effects
				(font
					(size 1.27 1.27)
				)
			)
		)
		(property "Value" ""
			(at 0 0 90)
			(layer "F.Fab")
			(effects
				(font
					(size 1.27 1.27)
				)
			)
		)
		(duplicate_pad_numbers_are_jumpers no)
		(fp_line
			(start 0.7874 -0.4064)
			(end 0.7874 0.4064)
			(stroke
				(width 0.1524)
				(type default)
			)
			(layer "F.SilkS")
		)
		(fp_line
			(start -0.7874 -0.4064)
			(end 0.7874 -0.4064)
			(stroke
				(width 0.1524)
				(type default)
			)
			(layer "F.SilkS")
		)
		(fp_line
			(start 0.7874 0.4064)
			(end -0.7874 0.4064)
			(stroke
				(width 0.1524)
				(type default)
			)
			(layer "F.SilkS")
		)
		(fp_line
			(start -0.7874 0.4064)
			(end -0.7874 -0.4064)
			(stroke
				(width 0.1524)
				(type default)
			)
			(layer "F.SilkS")
		)
		(fp_line
			(start -0.12065 -0.305054)
			(end -0.12065 -0.2794)
			(stroke
				(width 0.1)
				(type default)
			)
			(layer "F.Fab")
		)
		(fp_line
			(start -0.67945 -0.305054)
			(end -0.12065 -0.305054)
			(stroke
				(width 0.1)
				(type default)
			)
			(layer "F.Fab")
		)
		(fp_line
			(start 0.67945 -0.3048)
			(end 0.67945 0.3048)
			(stroke
				(width 0.1)
				(type default)
			)
			(layer "F.Fab")
		)
		(fp_line
			(start 0.12065 -0.3048)
			(end 0.67945 -0.3048)
			(stroke
				(width 0.1)
				(type default)
			)
			(layer "F.Fab")
		)
		(fp_line
			(start 0.12065 -0.2794)
			(end 0.12065 -0.3048)
			(stroke
				(width 0.1)
				(type default)
			)
			(layer "F.Fab")
		)
		(fp_line
			(start -0.12065 -0.2794)
			(end 0.12065 -0.2794)
			(stroke
				(width 0.1)
				(type default)
			)
			(layer "F.Fab")
		)
		(fp_line
			(start 0.120396 0.2794)
			(end -0.12065 0.2794)
			(stroke
				(width 0.1)
				(type default)
			)
			(layer "F.Fab")
		)
		(fp_line
			(start -0.12065 0.2794)
			(end -0.12065 0.3048)
			(stroke
				(width 0.1)
				(type default)
			)
			(layer "F.Fab")
		)
		(fp_line
			(start 0.67945 0.3048)
			(end 0.120396 0.3048)
			(stroke
				(width 0.1)
				(type default)
			)
			(layer "F.Fab")
		)
		(fp_line
			(start 0.120396 0.3048)
			(end 0.120396 0.2794)
			(stroke
				(width 0.1)
				(type default)
			)
			(layer "F.Fab")
		)
		(fp_line
			(start -0.12065 0.3048)
			(end -0.67945 0.3048)
			(stroke
				(width 0.1)
				(type default)
			)
			(layer "F.Fab")
		)
		(fp_line
			(start -0.67945 0.3048)
			(end -0.67945 -0.305054)
			(stroke
				(width 0.1)
				(type default)
			)
			(layer "F.Fab")
		)
		(pad "1" smd circle
			(at -0.40005 0 90)
			(size 0 0)
			(layers "F.Cu" "F.Mask" "F.Paste")
			(net "FM_THERMAL_ALERT_N")
		)
		(pad "2" smd circle
			(at 0.40005 0 90)
			(size 0 0)
			(layers "F.Cu" "F.Mask" "F.Paste")
			(net "FM_LM75_2_ALERT_N")
		)
	)
	(footprint ""
		(layer "F.Cu")
		(at 169.418 -135.509 180)
		(property "Reference" "R479"
			(at 0 0 180)
			(layer "F.SilkS")
			(hide yes)
			(effects
				(font
					(size 1.27 1.27)
				)
			)
		)
		(property "Value" ""
			(at 0 0 180)
			(layer "F.Fab")
			(effects
				(font
					(size 1.27 1.27)
				)
			)
		)
		(duplicate_pad_numbers_are_jumpers no)
		(fp_line
			(start 0.7874 0.4064)
			(end -0.7874 0.4064)
			(stroke
				(width 0.1524)
				(type default)
			)
			(layer "F.SilkS")
		)
		(fp_line
			(start 0.7874 -0.4064)
			(end 0.7874 0.4064)
			(stroke
				(width 0.1524)
				(type default)
			)
			(layer "F.SilkS")
		)
		(fp_line
			(start -0.7874 0.4064)
			(end -0.7874 -0.4064)
			(stroke
				(width 0.1524)
				(type default)
			)
			(layer "F.SilkS")
		)
		(fp_line
			(start -0.7874 -0.4064)
			(end 0.7874 -0.4064)
			(stroke
				(width 0.1524)
				(type default)
			)
			(layer "F.SilkS")
		)
		(fp_line
			(start 0.67945 0.3048)
			(end 0.120396 0.3048)
			(stroke
				(width 0.1)
				(type default)
			)
			(layer "F.Fab")
		)
		(fp_line
			(start 0.67945 -0.3048)
			(end 0.67945 0.3048)
			(stroke
				(width 0.1)
				(type default)
			)
			(layer "F.Fab")
		)
		(fp_line
			(start 0.12065 -0.2794)
			(end 0.12065 -0.3048)
			(stroke
				(width 0.1)
				(type default)
			)
			(layer "F.Fab")
		)
		(fp_line
			(start 0.12065 -0.3048)
			(end 0.67945 -0.3048)
			(stroke
				(width 0.1)
				(type default)
			)
			(layer "F.Fab")
		)
		(fp_line
			(start 0.120396 0.3048)
			(end 0.120396 0.2794)
			(stroke
				(width 0.1)
				(type default)
			)
			(layer "F.Fab")
		)
		(fp_line
			(start 0.120396 0.2794)
			(end -0.12065 0.2794)
			(stroke
				(width 0.1)
				(type default)
			)
			(layer "F.Fab")
		)
		(fp_line
			(start -0.12065 0.3048)
			(end -0.67945 0.3048)
			(stroke
				(width 0.1)
				(type default)
			)
			(layer "F.Fab")
		)
		(fp_line
			(start -0.12065 0.2794)
			(end -0.12065 0.3048)
			(stroke
				(width 0.1)
				(type default)
			)
			(layer "F.Fab")
		)
		(fp_line
			(start -0.12065 -0.2794)
			(end 0.12065 -0.2794)
			(stroke
				(width 0.1)
				(type default)
			)
			(layer "F.Fab")
		)
		(fp_line
			(start -0.12065 -0.305054)
			(end -0.12065 -0.2794)
			(stroke
				(width 0.1)
				(type default)
			)
			(layer "F.Fab")
		)
		(fp_line
			(start -0.67945 0.3048)
			(end -0.67945 -0.305054)
			(stroke
				(width 0.1)
				(type default)
			)
			(layer "F.Fab")
		)
		(fp_line
			(start -0.67945 -0.305054)
			(end -0.12065 -0.305054)
			(stroke
				(width 0.1)
				(type default)
			)
			(layer "F.Fab")
		)
		(pad "1" smd circle
			(at -0.40005 0 180)
			(size 0 0)
			(layers "F.Cu" "F.Mask" "F.Paste")
			(net "P5V")
		)
		(pad "2" smd circle
			(at 0.40005 0 180)
			(size 0 0)
			(layers "F.Cu" "F.Mask" "F.Paste")
			(net "PWRGD_P5V_R")
		)
	)
	(footprint ""
		(layer "F.Cu")
		(at 411.44444 -383.88163 -90)
		(property "Reference" "C854"
			(at 0 0 270)
			(layer "F.SilkS")
			(hide yes)
			(effects
				(font
					(size 1.27 1.27)
				)
			)
		)
		(property "Value" ""
			(at 0 0 270)
			(layer "F.Fab")
			(effects
				(font
					(size 1.27 1.27)
				)
			)
		)
		(duplicate_pad_numbers_are_jumpers no)
		(fp_line
			(start -0.299974 0.150114)
			(end -0.299974 -0.150114)
			(stroke
				(width 0.1)
				(type default)
			)
			(layer "F.Fab")
		)
		(fp_line
			(start 0.299974 0.150114)
			(end -0.299974 0.150114)
			(stroke
				(width 0.1)
				(type default)
			)
			(layer "F.Fab")
		)
		(fp_line
			(start -0.299974 -0.150114)
			(end 0.299974 -0.150114)
			(stroke
				(width 0.1)
				(type default)
			)
			(layer "F.Fab")
		)
		(fp_line
			(start 0.299974 -0.150114)
			(end 0.299974 0.150114)
			(stroke
				(width 0.1)
				(type default)
			)
			(layer "F.Fab")
		)
		(pad "1" smd rect
			(at -0.2667 0 270)
			(size 0.3048 0.381)
			(layers "F.Cu" "F.Mask" "F.Paste")
			(net "P5E_CPU0_P2_TX_C_DN<7>")
		)
		(pad "2" smd rect
			(at 0.2667 0 270)
			(size 0.3048 0.381)
			(layers "F.Cu" "F.Mask" "F.Paste")
			(net "P5E_CPU0_P2_TX_DN<7>")
		)
	)
	(footprint ""
		(layer "F.Cu")
		(at 353.900232 -261.255002)
		(property "Reference" "C2149"
			(at 0 0 0)
			(layer "F.SilkS")
			(hide yes)
			(effects
				(font
					(size 1.27 1.27)
				)
			)
		)
		(property "Value" ""
			(at 0 0 0)
			(layer "F.Fab")
			(effects
				(font
					(size 1.27 1.27)
				)
			)
		)
		(duplicate_pad_numbers_are_jumpers no)
		(fp_line
			(start -0.7874 -0.4064)
			(end 0.7874 -0.4064)
			(stroke
				(width 0.1524)
				(type default)
			)
			(layer "F.SilkS")
		)
		(fp_line
			(start -0.7874 0.4064)
			(end -0.7874 -0.4064)
			(stroke
				(width 0.1524)
				(type default)
			)
			(layer "F.SilkS")
		)
		(fp_line
			(start 0.7874 -0.4064)
			(end 0.7874 0.4064)
			(stroke
				(width 0.1524)
				(type default)
			)
			(layer "F.SilkS")
		)
		(fp_line
			(start 0.7874 0.4064)
			(end -0.7874 0.4064)
			(stroke
				(width 0.1524)
				(type default)
			)
			(layer "F.SilkS")
		)
		(fp_line
			(start -0.67945 -0.305054)
			(end -0.12065 -0.305054)
			(stroke
				(width 0.1)
				(type default)
			)
			(layer "F.Fab")
		)
		(fp_line
			(start -0.67945 0.3048)
			(end -0.67945 -0.305054)
			(stroke
				(width 0.1)
				(type default)
			)
			(layer "F.Fab")
		)
		(fp_line
			(start -0.12065 -0.305054)
			(end -0.12065 -0.2794)
			(stroke
				(width 0.1)
				(type default)
			)
			(layer "F.Fab")
		)
		(fp_line
			(start -0.12065 -0.2794)
			(end 0.12065 -0.2794)
			(stroke
				(width 0.1)
				(type default)
			)
			(layer "F.Fab")
		)
		(fp_line
			(start -0.12065 0.2794)
			(end -0.12065 0.3048)
			(stroke
				(width 0.1)
				(type default)
			)
			(layer "F.Fab")
		)
		(fp_line
			(start -0.12065 0.3048)
			(end -0.67945 0.3048)
			(stroke
				(width 0.1)
				(type default)
			)
			(layer "F.Fab")
		)
		(fp_line
			(start 0.120396 0.2794)
			(end -0.12065 0.2794)
			(stroke
				(width 0.1)
				(type default)
			)
			(layer "F.Fab")
		)
		(fp_line
			(start 0.120396 0.3048)
			(end 0.120396 0.2794)
			(stroke
				(width 0.1)
				(type default)
			)
			(layer "F.Fab")
		)
		(fp_line
			(start 0.12065 -0.3048)
			(end 0.67945 -0.3048)
			(stroke
				(width 0.1)
				(type default)
			)
			(layer "F.Fab")
		)
		(fp_line
			(start 0.12065 -0.2794)
			(end 0.12065 -0.3048)
			(stroke
				(width 0.1)
				(type default)
			)
			(layer "F.Fab")
		)
		(fp_line
			(start 0.67945 -0.3048)
			(end 0.67945 0.3048)
			(stroke
				(width 0.1)
				(type default)
			)
			(layer "F.Fab")
		)
		(fp_line
			(start 0.67945 0.3048)
			(end 0.120396 0.3048)
			(stroke
				(width 0.1)
				(type default)
			)
			(layer "F.Fab")
		)
		(pad "1" smd circle
			(at -0.40005 0)
			(size 0 0)
			(layers "F.Cu" "F.Mask" "F.Paste")
			(net "PVDDIO_P0")
		)
		(pad "2" smd circle
			(at 0.40005 0)
			(size 0 0)
			(layers "F.Cu" "F.Mask" "F.Paste")
			(net "GND")
		)
	)
	(footprint ""
		(layer "F.Cu")
		(at 10.873486 -92.687648 90)
		(property "Reference" "R3661"
			(at 0 0 90)
			(layer "F.SilkS")
			(hide yes)
			(effects
				(font
					(size 1.27 1.27)
				)
			)
		)
		(property "Value" ""
			(at 0 0 90)
			(layer "F.Fab")
			(effects
				(font
					(size 1.27 1.27)
				)
			)
		)
		(duplicate_pad_numbers_are_jumpers no)
		(fp_line
			(start 0.7874 -0.4064)
			(end 0.7874 0.4064)
			(stroke
				(width 0.1524)
				(type default)
			)
			(layer "F.SilkS")
		)
		(fp_line
			(start -0.7874 -0.4064)
			(end 0.7874 -0.4064)
			(stroke
				(width 0.1524)
				(type default)
			)
			(layer "F.SilkS")
		)
		(fp_line
			(start 0.7874 0.4064)
			(end -0.7874 0.4064)
			(stroke
				(width 0.1524)
				(type default)
			)
			(layer "F.SilkS")
		)
		(fp_line
			(start -0.7874 0.4064)
			(end -0.7874 -0.4064)
			(stroke
				(width 0.1524)
				(type default)
			)
			(layer "F.SilkS")
		)
		(fp_line
			(start -0.12065 -0.305054)
			(end -0.12065 -0.2794)
			(stroke
				(width 0.1)
				(type default)
			)
			(layer "F.Fab")
		)
		(fp_line
			(start -0.67945 -0.305054)
			(end -0.12065 -0.305054)
			(stroke
				(width 0.1)
				(type default)
			)
			(layer "F.Fab")
		)
		(fp_line
			(start 0.67945 -0.3048)
			(end 0.67945 0.3048)
			(stroke
				(width 0.1)
				(type default)
			)
			(layer "F.Fab")
		)
		(fp_line
			(start 0.12065 -0.3048)
			(end 0.67945 -0.3048)
			(stroke
				(width 0.1)
				(type default)
			)
			(layer "F.Fab")
		)
		(fp_line
			(start 0.12065 -0.2794)
			(end 0.12065 -0.3048)
			(stroke
				(width 0.1)
				(type default)
			)
			(layer "F.Fab")
		)
		(fp_line
			(start -0.12065 -0.2794)
			(end 0.12065 -0.2794)
			(stroke
				(width 0.1)
				(type default)
			)
			(layer "F.Fab")
		)
		(fp_line
			(start 0.120396 0.2794)
			(end -0.12065 0.2794)
			(stroke
				(width 0.1)
				(type default)
			)
			(layer "F.Fab")
		)
		(fp_line
			(start -0.12065 0.2794)
			(end -0.12065 0.3048)
			(stroke
				(width 0.1)
				(type default)
			)
			(layer "F.Fab")
		)
		(fp_line
			(start 0.67945 0.3048)
			(end 0.120396 0.3048)
			(stroke
				(width 0.1)
				(type default)
			)
			(layer "F.Fab")
		)
		(fp_line
			(start 0.120396 0.3048)
			(end 0.120396 0.2794)
			(stroke
				(width 0.1)
				(type default)
			)
			(layer "F.Fab")
		)
		(fp_line
			(start -0.12065 0.3048)
			(end -0.67945 0.3048)
			(stroke
				(width 0.1)
				(type default)
			)
			(layer "F.Fab")
		)
		(fp_line
			(start -0.67945 0.3048)
			(end -0.67945 -0.305054)
			(stroke
				(width 0.1)
				(type default)
			)
			(layer "F.Fab")
		)
		(pad "1" smd circle
			(at -0.40005 0 90)
			(size 0 0)
			(layers "F.Cu" "F.Mask" "F.Paste")
			(net "GND")
		)
		(pad "2" smd circle
			(at 0.40005 0 90)
			(size 0 0)
			(layers "F.Cu" "F.Mask" "F.Paste")
			(net "RST_USB_HUB_R_N")
		)
	)
	(footprint ""
		(layer "F.Cu")
		(at 346.046044 -381.41783 -90)
		(property "Reference" "C948"
			(at 0 0 270)
			(layer "F.SilkS")
			(hide yes)
			(effects
				(font
					(size 1.27 1.27)
				)
			)
		)
		(property "Value" ""
			(at 0 0 270)
			(layer "F.Fab")
			(effects
				(font
					(size 1.27 1.27)
				)
			)
		)
		(duplicate_pad_numbers_are_jumpers no)
		(fp_line
			(start -0.299974 0.150114)
			(end -0.299974 -0.150114)
			(stroke
				(width 0.1)
				(type default)
			)
			(layer "F.Fab")
		)
		(fp_line
			(start 0.299974 0.150114)
			(end -0.299974 0.150114)
			(stroke
				(width 0.1)
				(type default)
			)
			(layer "F.Fab")
		)
		(fp_line
			(start -0.299974 -0.150114)
			(end 0.299974 -0.150114)
			(stroke
				(width 0.1)
				(type default)
			)
			(layer "F.Fab")
		)
		(fp_line
			(start 0.299974 -0.150114)
			(end 0.299974 0.150114)
			(stroke
				(width 0.1)
				(type default)
			)
			(layer "F.Fab")
		)
		(pad "1" smd rect
			(at -0.2667 0 270)
			(size 0.3048 0.381)
			(layers "F.Cu" "F.Mask" "F.Paste")
			(net "P5E_CPU0_P1_TX_C_DN<8>")
		)
		(pad "2" smd rect
			(at 0.2667 0 270)
			(size 0.3048 0.381)
			(layers "F.Cu" "F.Mask" "F.Paste")
			(net "P5E_CPU0_P1_TX_DN<8>")
		)
	)
	(footprint ""
		(layer "F.Cu")
		(at 95.26143 -57.18683)
		(property "Reference" "PR3824"
			(at 0 0 0)
			(layer "F.SilkS")
			(hide yes)
			(effects
				(font
					(size 1.27 1.27)
				)
			)
		)
		(property "Value" ""
			(at 0 0 0)
			(layer "F.Fab")
			(effects
				(font
					(size 1.27 1.27)
				)
			)
		)
		(duplicate_pad_numbers_are_jumpers no)
		(fp_line
			(start -0.7874 -0.4064)
			(end 0.7874 -0.4064)
			(stroke
				(width 0.1524)
				(type default)
			)
			(layer "F.SilkS")
		)
		(fp_line
			(start -0.7874 0.4064)
			(end -0.7874 -0.4064)
			(stroke
				(width 0.1524)
				(type default)
			)
			(layer "F.SilkS")
		)
		(fp_line
			(start 0.7874 -0.4064)
			(end 0.7874 0.4064)
			(stroke
				(width 0.1524)
				(type default)
			)
			(layer "F.SilkS")
		)
		(fp_line
			(start 0.7874 0.4064)
			(end -0.7874 0.4064)
			(stroke
				(width 0.1524)
				(type default)
			)
			(layer "F.SilkS")
		)
		(fp_line
			(start -0.67945 -0.305054)
			(end -0.12065 -0.305054)
			(stroke
				(width 0.1)
				(type default)
			)
			(layer "F.Fab")
		)
		(fp_line
			(start -0.67945 0.3048)
			(end -0.67945 -0.305054)
			(stroke
				(width 0.1)
				(type default)
			)
			(layer "F.Fab")
		)
		(fp_line
			(start -0.12065 -0.305054)
			(end -0.12065 -0.2794)
			(stroke
				(width 0.1)
				(type default)
			)
			(layer "F.Fab")
		)
		(fp_line
			(start -0.12065 -0.2794)
			(end 0.12065 -0.2794)
			(stroke
				(width 0.1)
				(type default)
			)
			(layer "F.Fab")
		)
		(fp_line
			(start -0.12065 0.2794)
			(end -0.12065 0.3048)
			(stroke
				(width 0.1)
				(type default)
			)
			(layer "F.Fab")
		)
		(fp_line
			(start -0.12065 0.3048)
			(end -0.67945 0.3048)
			(stroke
				(width 0.1)
				(type default)
			)
			(layer "F.Fab")
		)
		(fp_line
			(start 0.120396 0.2794)
			(end -0.12065 0.2794)
			(stroke
				(width 0.1)
				(type default)
			)
			(layer "F.Fab")
		)
		(fp_line
			(start 0.120396 0.3048)
			(end 0.120396 0.2794)
			(stroke
				(width 0.1)
				(type default)
			)
			(layer "F.Fab")
		)
		(fp_line
			(start 0.12065 -0.3048)
			(end 0.67945 -0.3048)
			(stroke
				(width 0.1)
				(type default)
			)
			(layer "F.Fab")
		)
		(fp_line
			(start 0.12065 -0.2794)
			(end 0.12065 -0.3048)
			(stroke
				(width 0.1)
				(type default)
			)
			(layer "F.Fab")
		)
		(fp_line
			(start 0.67945 -0.3048)
			(end 0.67945 0.3048)
			(stroke
				(width 0.1)
				(type default)
			)
			(layer "F.Fab")
		)
		(fp_line
			(start 0.67945 0.3048)
			(end 0.120396 0.3048)
			(stroke
				(width 0.1)
				(type default)
			)
			(layer "F.Fab")
		)
		(pad "1" smd circle
			(at -0.40005 0)
			(size 0 0)
			(layers "F.Cu" "F.Mask" "F.Paste")
			(net "P3V3_OCP_SENSE_2")
		)
		(pad "2" smd circle
			(at 0.40005 0)
			(size 0 0)
			(layers "F.Cu" "F.Mask" "F.Paste")
			(net "GND")
		)
	)
	(footprint ""
		(layer "F.Cu")
		(at 104.816148 -382.27)
		(property "Reference" "R796"
			(at 0 0 0)
			(layer "F.SilkS")
			(hide yes)
			(effects
				(font
					(size 1.27 1.27)
				)
			)
		)
		(property "Value" ""
			(at 0 0 0)
			(layer "F.Fab")
			(effects
				(font
					(size 1.27 1.27)
				)
			)
		)
		(duplicate_pad_numbers_are_jumpers no)
		(fp_line
			(start -0.32512 -0.175006)
			(end 0.32512 -0.175006)
			(stroke
				(width 0.1)
				(type default)
			)
			(layer "F.Fab")
		)
		(fp_line
			(start -0.32512 0.175006)
			(end -0.32512 -0.175006)
			(stroke
				(width 0.1)
				(type default)
			)
			(layer "F.Fab")
		)
		(fp_line
			(start 0.32512 -0.175006)
			(end 0.32512 0.175006)
			(stroke
				(width 0.1)
				(type default)
			)
			(layer "F.Fab")
		)
		(fp_line
			(start 0.32512 0.175006)
			(end -0.32512 0.175006)
			(stroke
				(width 0.1)
				(type default)
			)
			(layer "F.Fab")
		)
		(pad "1" smd rect
			(at -0.2667 0)
			(size 0.3048 0.381)
			(layers "F.Cu" "F.Mask" "F.Paste")
			(net "RT_CPU1_P1_ADDR1")
		)
		(pad "2" smd rect
			(at 0.2667 0 180)
			(size 0.3048 0.381)
			(layers "F.Cu" "F.Mask" "F.Paste")
			(net "GND")
		)
	)
	(footprint ""
		(layer "F.Cu")
		(at 359.867962 -258.880102 180)
		(property "Reference" "U25"
			(at -45.78477 -62.086744 0)
			(unlocked yes)
			(layer "F.SilkS")
			(effects
				(font
					(size 0.7874 0.5842)
					(thickness 0.1524)
				)
			)
		)
		(property "Value" ""
			(at 0 0 180)
			(layer "F.Fab")
			(effects
				(font
					(size 1.27 1.27)
				)
			)
		)
		(duplicate_pad_numbers_are_jumpers no)
		(fp_line
			(start 46.699932 95.149924)
			(end 21.895562 95.149924)
			(stroke
				(width 0.1524)
				(type default)
			)
			(layer "F.SilkS")
		)
		(fp_line
			(start 46.699932 89.437718)
			(end 46.699932 95.149924)
			(stroke
				(width 0.1524)
				(type default)
			)
			(layer "F.SilkS")
		)
		(fp_line
			(start 46.699932 60.149994)
			(end -0.253238 60.149994)
			(stroke
				(width 0.1524)
				(type default)
			)
			(layer "F.SilkS")
		)
		(fp_line
			(start 46.699932 52.041298)
			(end 46.699932 86.549738)
			(stroke
				(width 0.1524)
				(type default)
			)
			(layer "F.SilkS")
		)
		(fp_line
			(start 46.699932 43.430698)
			(end 46.699932 49.120298)
			(stroke
				(width 0.1524)
				(type default)
			)
			(layer "F.SilkS")
		)
		(fp_line
			(start 46.699932 34.058098)
			(end 46.699932 39.671498)
			(stroke
				(width 0.1524)
				(type default)
			)
			(layer "F.SilkS")
		)
		(fp_line
			(start 46.699932 23.618698)
			(end 46.699932 27.962098)
			(stroke
				(width 0.1524)
				(type default)
			)
			(layer "F.SilkS")
		)
		(fp_line
			(start 46.699932 15.211298)
			(end 46.699932 20.240498)
			(stroke
				(width 0.1524)
				(type default)
			)
			(layer "F.SilkS")
		)
		(fp_line
			(start 46.699932 -2.187702)
			(end 46.699932 11.274298)
			(stroke
				(width 0.1524)
				(type default)
			)
			(layer "F.SilkS")
		)
		(fp_line
			(start 46.699932 -11.712702)
			(end 46.699932 -3.457702)
			(stroke
				(width 0.1524)
				(type default)
			)
			(layer "F.SilkS")
		)
		(fp_line
			(start 46.699932 -21.085302)
			(end 46.699932 -16.411702)
			(stroke
				(width 0.1524)
				(type default)
			)
			(layer "F.SilkS")
		)
		(fp_line
			(start 46.699932 -28.908502)
			(end 46.699932 -25.454102)
			(stroke
				(width 0.1524)
				(type default)
			)
			(layer "F.SilkS")
		)
		(fp_line
			(start 46.699932 -42.776902)
			(end 46.699932 -38.433502)
			(stroke
				(width 0.1524)
				(type default)
			)
			(layer "F.SilkS")
		)
		(fp_line
			(start 46.699932 -51.057302)
			(end 46.699932 -47.247302)
			(stroke
				(width 0.1524)
				(type default)
			)
			(layer "F.SilkS")
		)
		(fp_line
			(start 46.699932 -60.300108)
			(end 46.699932 -54.867302)
			(stroke
				(width 0.1524)
				(type default)
			)
			(layer "F.SilkS")
		)
		(fp_line
			(start 35.999928 37.69995)
			(end 14.707362 37.69995)
			(stroke
				(width 0.1524)
				(type default)
			)
			(layer "F.SilkS")
		)
		(fp_line
			(start 35.999928 33.600898)
			(end 35.999928 37.69995)
			(stroke
				(width 0.1524)
				(type default)
			)
			(layer "F.SilkS")
		)
		(fp_line
			(start 35.999928 27.860498)
			(end 35.999928 30.959298)
			(stroke
				(width 0.1524)
				(type default)
			)
			(layer "F.SilkS")
		)
		(fp_line
			(start 35.999928 22.958298)
			(end 35.999928 26.031698)
			(stroke
				(width 0.1524)
				(type default)
			)
			(layer "F.SilkS")
		)
		(fp_line
			(start 35.999928 18.208498)
			(end 35.999928 21.154898)
			(stroke
				(width 0.1524)
				(type default)
			)
			(layer "F.SilkS")
		)
		(fp_line
			(start 35.999928 13.357098)
			(end 35.999928 15.998698)
			(stroke
				(width 0.1524)
				(type default)
			)
			(layer "F.SilkS")
		)
		(fp_line
			(start 35.999928 -0.714502)
			(end 35.999928 11.452098)
			(stroke
				(width 0.1524)
				(type default)
			)
			(layer "F.SilkS")
		)
		(fp_line
			(start 35.999928 -10.493502)
			(end 35.999928 -1.730502)
			(stroke
				(width 0.1524)
				(type default)
			)
			(layer "F.SilkS")
		)
		(fp_line
			(start 35.999928 -15.421102)
			(end 35.999928 -12.754102)
			(stroke
				(width 0.1524)
				(type default)
			)
			(layer "F.SilkS")
		)
		(fp_line
			(start 35.999928 -20.272502)
			(end 35.999928 -17.326102)
			(stroke
				(width 0.1524)
				(type default)
			)
			(layer "F.SilkS")
		)
		(fp_line
			(start 35.999928 -25.149302)
			(end 35.999928 -22.101302)
			(stroke
				(width 0.1524)
				(type default)
			)
			(layer "F.SilkS")
		)
		(fp_line
			(start 35.999928 -30.711902)
			(end 35.999928 -27.282902)
			(stroke
				(width 0.1524)
				(type default)
			)
			(layer "F.SilkS")
		)
		(fp_line
			(start 35.999928 -37.69995)
			(end 35.999928 -33.251902)
			(stroke
				(width 0.1524)
				(type default)
			)
			(layer "F.SilkS")
		)
		(fp_line
			(start 27.500072 -40.999918)
			(end 27.500072 -37.69995)
			(stroke
				(width 0.1524)
				(type default)
			)
			(layer "F.SilkS")
		)
		(fp_line
			(start 26.049986 40.999918)
			(end 26.049986 37.69995)
			(stroke
				(width 0.1524)
				(type default)
			)
			(layer "F.SilkS")
		)
		(fp_line
			(start 23.999952 -41.500044)
			(end 26.999946 -41.500044)
			(stroke
				(width 0.1524)
				(type default)
			)
			(layer "F.SilkS")
		)
		(fp_line
			(start 23.50008 -37.69995)
			(end 23.50008 -40.999918)
			(stroke
				(width 0.1524)
				(type default)
			)
			(layer "F.SilkS")
		)
		(fp_line
			(start 22.55012 41.500044)
			(end 25.550114 41.500044)
			(stroke
				(width 0.1524)
				(type default)
			)
			(layer "F.SilkS")
		)
		(fp_line
			(start 22.049994 37.69995)
			(end 22.049994 40.999918)
			(stroke
				(width 0.1524)
				(type default)
			)
			(layer "F.SilkS")
		)
		(fp_line
			(start 13.132562 37.69995)
			(end 6.503162 37.69995)
			(stroke
				(width 0.1524)
				(type default)
			)
			(layer "F.SilkS")
		)
		(fp_line
			(start 7.050024 3.999992)
			(end -7.050024 3.999992)
			(stroke
				(width 0.1524)
				(type default)
			)
			(layer "F.SilkS")
		)
		(fp_line
			(start 7.050024 -3.999992)
			(end 7.050024 3.999992)
			(stroke
				(width 0.1524)
				(type default)
			)
			(layer "F.SilkS")
		)
		(fp_line
			(start 5.055362 37.69995)
			(end 3.277362 37.69995)
			(stroke
				(width 0.1524)
				(type default)
			)
			(layer "F.SilkS")
		)
		(fp_line
			(start 2.083562 37.69995)
			(end -35.999928 37.69995)
			(stroke
				(width 0.1524)
				(type default)
			)
			(layer "F.SilkS")
		)
		(fp_line
			(start -1.218438 60.149994)
			(end -3.707638 60.149994)
			(stroke
				(width 0.1524)
				(type default)
			)
			(layer "F.SilkS")
		)
		(fp_line
			(start -5.130038 60.149994)
			(end -46.699932 60.149994)
			(stroke
				(width 0.1524)
				(type default)
			)
			(layer "F.SilkS")
		)
		(fp_line
			(start -7.050024 3.999992)
			(end -7.050024 -3.999992)
			(stroke
				(width 0.1524)
				(type default)
			)
			(layer "F.SilkS")
		)
		(fp_line
			(start -7.050024 -3.999992)
			(end 7.050024 -3.999992)
			(stroke
				(width 0.1524)
				(type default)
			)
			(layer "F.SilkS")
		)
		(fp_line
			(start -15.848838 -37.69995)
			(end 35.999928 -37.69995)
			(stroke
				(width 0.1524)
				(type default)
			)
			(layer "F.SilkS")
		)
		(fp_line
			(start -22.049994 37.69995)
			(end -22.049994 40.999918)
			(stroke
				(width 0.1524)
				(type default)
			)
			(layer "F.SilkS")
		)
		(fp_line
			(start -22.55012 41.500044)
			(end -25.550114 41.500044)
			(stroke
				(width 0.1524)
				(type default)
			)
			(layer "F.SilkS")
		)
		(fp_line
			(start -23.50008 -40.999918)
			(end -23.50008 -37.69995)
			(stroke
				(width 0.1524)
				(type default)
			)
			(layer "F.SilkS")
		)
		(fp_line
			(start -26.049986 40.999918)
			(end -26.049986 37.69995)
			(stroke
				(width 0.1524)
				(type default)
			)
			(layer "F.SilkS")
		)
		(fp_line
			(start -26.999946 -41.500044)
			(end -23.999952 -41.500044)
			(stroke
				(width 0.1524)
				(type default)
			)
			(layer "F.SilkS")
		)
		(fp_line
			(start -27.500072 -37.69995)
			(end -27.500072 -40.999918)
			(stroke
				(width 0.1524)
				(type default)
			)
			(layer "F.SilkS")
		)
		(fp_line
			(start -35.999928 37.69995)
			(end -35.999928 33.321498)
			(stroke
				(width 0.1524)
				(type default)
			)
			(layer "F.SilkS")
		)
		(fp_line
			(start -35.999928 30.959298)
			(end -35.999928 28.139898)
			(stroke
				(width 0.1524)
				(type default)
			)
			(layer "F.SilkS")
		)
		(fp_line
			(start -35.999928 26.082498)
			(end -35.999928 23.313898)
			(stroke
				(width 0.1524)
				(type default)
			)
			(layer "F.SilkS")
		)
		(fp_line
			(start -35.999928 20.875498)
			(end -35.999928 18.284698)
			(stroke
				(width 0.1524)
				(type default)
			)
			(layer "F.SilkS")
		)
		(fp_line
			(start -35.999928 16.430498)
			(end -35.999928 13.280898)
			(stroke
				(width 0.1524)
				(type default)
			)
			(layer "F.SilkS")
		)
		(fp_line
			(start -35.999928 11.375898)
			(end -35.999928 -1.476502)
			(stroke
				(width 0.1524)
				(type default)
			)
			(layer "F.SilkS")
		)
		(fp_line
			(start -35.999928 -2.771902)
			(end -35.999928 -10.772902)
			(stroke
				(width 0.1524)
				(type default)
			)
			(layer "F.SilkS")
		)
		(fp_line
			(start -35.999928 -12.703302)
			(end -35.999928 -15.294102)
			(stroke
				(width 0.1524)
				(type default)
			)
			(layer "F.SilkS")
		)
		(fp_line
			(start -35.999928 -17.300702)
			(end -35.999928 -20.272502)
			(stroke
				(width 0.1524)
				(type default)
			)
			(layer "F.SilkS")
		)
		(fp_line
			(start -35.999928 -22.329902)
			(end -35.999928 -25.174702)
			(stroke
				(width 0.1524)
				(type default)
			)
			(layer "F.SilkS")
		)
		(fp_line
			(start -35.999928 -27.435302)
			(end -35.999928 -31.118302)
			(stroke
				(width 0.1524)
				(type default)
			)
			(layer "F.SilkS")
		)
		(fp_line
			(start -35.999928 -33.759902)
			(end -35.999928 -37.69995)
			(stroke
				(width 0.1524)
				(type default)
			)
			(layer "F.SilkS")
		)
		(fp_line
			(start -35.999928 -37.69995)
			(end -17.499838 -37.69995)
			(stroke
				(width 0.1524)
				(type default)
			)
			(layer "F.SilkS")
		)
		(fp_line
			(start -46.699932 95.149924)
			(end -46.699932 60.149994)
			(stroke
				(width 0.1524)
				(type default)
			)
			(layer "F.SilkS")
		)
		(fp_line
			(start -46.699932 60.149994)
			(end -46.699932 51.812698)
			(stroke
				(width 0.1524)
				(type default)
			)
			(layer "F.SilkS")
		)
		(fp_line
			(start -46.699932 47.570898)
			(end -46.699932 42.948098)
			(stroke
				(width 0.1524)
				(type default)
			)
			(layer "F.SilkS")
		)
		(fp_line
			(start -46.699932 38.807898)
			(end -46.699932 31.086298)
			(stroke
				(width 0.1524)
				(type default)
			)
			(layer "F.SilkS")
		)
		(fp_line
			(start -46.699932 28.444698)
			(end -46.699932 24.075898)
			(stroke
				(width 0.1524)
				(type default)
			)
			(layer "F.SilkS")
		)
		(fp_line
			(start -46.699932 19.453098)
			(end -46.699932 15.211298)
			(stroke
				(width 0.1524)
				(type default)
			)
			(layer "F.SilkS")
		)
		(fp_line
			(start -46.699932 11.020298)
			(end -46.699932 -1.247902)
			(stroke
				(width 0.1524)
				(type default)
			)
			(layer "F.SilkS")
		)
		(fp_line
			(start -46.699932 -3.762502)
			(end -46.699932 -12.525502)
			(stroke
				(width 0.1524)
				(type default)
			)
			(layer "F.SilkS")
		)
		(fp_line
			(start -46.699932 -17.148302)
			(end -46.699932 -20.399502)
			(stroke
				(width 0.1524)
				(type default)
			)
			(layer "F.SilkS")
		)
		(fp_line
			(start -46.699932 -23.422102)
			(end -46.699932 -29.441902)
			(stroke
				(width 0.1524)
				(type default)
			)
			(layer "F.SilkS")
		)
		(fp_line
			(start -46.699932 -36.426902)
			(end -46.699932 -41.964102)
			(stroke
				(width 0.1524)
				(type default)
			)
			(layer "F.SilkS")
		)
		(fp_line
			(start -46.699932 -46.485302)
			(end -46.699932 -50.676302)
			(stroke
				(width 0.1524)
				(type default)
			)
			(layer "F.SilkS")
		)
		(fp_line
			(start -46.699932 -55.045102)
			(end -46.699932 -60.300108)
			(stroke
				(width 0.1524)
				(type default)
			)
			(layer "F.SilkS")
		)
		(fp_line
			(start -46.699932 -60.300108)
			(end 46.699932 -60.300108)
			(stroke
				(width 0.1524)
				(type default)
			)
			(layer "F.SilkS")
		)
		(fp_arc
			(start 26.999946 -41.500044)
			(mid 27.353604 -41.353567)
			(end 27.500072 -40.999918)
			(stroke
				(width 0.1524)
				(type default)
			)
			(layer "F.SilkS")
		)
		(fp_arc
			(start 26.049986 40.999918)
			(mid 25.903673 41.353545)
			(end 25.550114 41.500044)
			(stroke
				(width 0.1524)
				(type default)
			)
			(layer "F.SilkS")
		)
		(fp_arc
			(start 23.50008 -40.999918)
			(mid 23.646482 -41.353445)
			(end 23.999952 -41.500044)
			(stroke
				(width 0.1524)
				(type default)
			)
			(layer "F.SilkS")
		)
		(fp_arc
			(start 22.55012 41.500044)
			(mid 22.196498 41.353547)
			(end 22.049994 40.999918)
			(stroke
				(width 0.1524)
				(type default)
			)
			(layer "F.SilkS")
		)
		(fp_arc
			(start -22.049994 40.999918)
			(mid -22.196396 41.353642)
			(end -22.55012 41.500044)
			(stroke
				(width 0.1524)
				(type default)
			)
			(layer "F.SilkS")
		)
		(fp_arc
			(start -23.999952 -41.500044)
			(mid -23.646401 -41.353548)
			(end -23.50008 -40.999918)
			(stroke
				(width 0.1524)
				(type default)
			)
			(layer "F.SilkS")
		)
		(fp_arc
			(start -25.550114 41.500044)
			(mid -25.903585 41.353464)
			(end -26.049986 40.999918)
			(stroke
				(width 0.1524)
				(type default)
			)
			(layer "F.SilkS")
		)
		(fp_arc
			(start -27.500072 -40.999918)
			(mid -27.353583 -41.353553)
			(end -26.999946 -41.500044)
			(stroke
				(width 0.1524)
				(type default)
			)
			(layer "F.SilkS")
		)
		(fp_poly
			(pts
				(xy -36.761928 -35.189922) (xy -36.761928 -38.46195) (xy -33.219898 -38.46195) (xy -33.219898 -37.69995)
				(xy -35.999928 -37.69995) (xy -35.999928 -35.189922)
			)
			(stroke
				(width 0)
				(type default)
			)
			(fill yes)
			(layer "F.SilkS")
		)
		(fp_line
			(start 49.800002 5.500116)
			(end 49.800002 -5.500116)
			(stroke
				(width 0.1524)
				(type default)
			)
			(layer "B.SilkS")
		)
		(fp_line
			(start 49.800002 -5.500116)
			(end 46.699932 -8.50011)
			(stroke
				(width 0.1524)
				(type default)
			)
			(layer "B.SilkS")
		)
		(fp_line
			(start 46.699932 48.891698)
			(end 46.699932 8.50011)
			(stroke
				(width 0.1524)
				(type default)
			)
			(layer "B.SilkS")
		)
		(fp_line
			(start 46.699932 8.50011)
			(end 49.800002 5.500116)
			(stroke
				(width 0.1524)
				(type default)
			)
			(layer "B.SilkS")
		)
		(fp_line
			(start 46.699932 -8.50011)
			(end 46.699932 -50.500026)
			(stroke
				(width 0.1524)
				(type default)
			)
			(layer "B.SilkS")
		)
		(fp_line
			(start 26.45791 52.999894)
			(end 44.200064 52.999894)
			(stroke
				(width 0.1524)
				(type default)
			)
			(layer "B.SilkS")
		)
		(fp_line
			(start 26.45791 -52.999894)
			(end 44.200064 -52.999894)
			(stroke
				(width 0.1524)
				(type default)
			)
			(layer "B.SilkS")
		)
		(fp_line
			(start 22.900894 43.15206)
			(end 23.981918 50.848006)
			(stroke
				(width 0.1524)
				(type default)
			)
			(layer "B.SilkS")
		)
		(fp_line
			(start 22.900894 -43.15206)
			(end 23.981918 -50.848006)
			(stroke
				(width 0.1524)
				(type default)
			)
			(layer "B.SilkS")
		)
		(fp_line
			(start 19.076162 -40.999918)
			(end 13.107162 -40.999918)
			(stroke
				(width 0.1524)
				(type default)
			)
			(layer "B.SilkS")
		)
		(fp_line
			(start 16.002762 40.999918)
			(end 9.855962 40.999918)
			(stroke
				(width 0.1524)
				(type default)
			)
			(layer "B.SilkS")
		)
		(fp_line
			(start 14.500098 -11.500104)
			(end 14.500098 11.500104)
			(stroke
				(width 0.1524)
				(type default)
			)
			(layer "B.SilkS")
		)
		(fp_line
			(start 8.331962 40.999918)
			(end -20.424902 40.999918)
			(stroke
				(width 0.1524)
				(type default)
			)
			(layer "B.SilkS")
		)
		(fp_line
			(start 5.461762 -40.999918)
			(end 2.616962 -40.999918)
			(stroke
				(width 0.1524)
				(type default)
			)
			(layer "B.SilkS")
		)
		(fp_line
			(start -9.244838 -40.999918)
			(end -13.080238 -40.999918)
			(stroke
				(width 0.1524)
				(type default)
			)
			(layer "B.SilkS")
		)
		(fp_line
			(start -11.999976 13.999972)
			(end 11.999976 13.999972)
			(stroke
				(width 0.1524)
				(type default)
			)
			(layer "B.SilkS")
		)
		(fp_line
			(start -11.999976 -13.999972)
			(end 11.999976 -13.999972)
			(stroke
				(width 0.1524)
				(type default)
			)
			(layer "B.SilkS")
		)
		(fp_line
			(start -14.500098 11.500104)
			(end -14.500098 -11.500104)
			(stroke
				(width 0.1524)
				(type default)
			)
			(layer "B.SilkS")
		)
		(fp_line
			(start -19.023838 -40.999918)
			(end -20.424902 -40.999918)
			(stroke
				(width 0.1524)
				(type default)
			)
			(layer "B.SilkS")
		)
		(fp_line
			(start -22.900894 43.15206)
			(end -23.981918 50.848006)
			(stroke
				(width 0.1524)
				(type default)
			)
			(layer "B.SilkS")
		)
		(fp_line
			(start -23.0124 -43.945302)
			(end -23.981918 -50.848006)
			(stroke
				(width 0.1524)
				(type default)
			)
			(layer "B.SilkS")
		)
		(fp_line
			(start -26.45791 52.999894)
			(end -44.200064 52.999894)
			(stroke
				(width 0.1524)
				(type default)
			)
			(layer "B.SilkS")
		)
		(fp_line
			(start -26.45791 -52.999894)
			(end -44.200064 -52.999894)
			(stroke
				(width 0.1524)
				(type default)
			)
			(layer "B.SilkS")
		)
		(fp_line
			(start -46.699932 8.50011)
			(end -46.699932 50.500026)
			(stroke
				(width 0.1524)
				(type default)
			)
			(layer "B.SilkS")
		)
		(fp_line
			(start -46.699932 -8.50011)
			(end -48.233838 -7.015734)
			(stroke
				(width 0.1524)
				(type default)
			)
			(layer "B.SilkS")
		)
		(fp_line
			(start -46.699932 -50.500026)
			(end -46.699932 -8.50011)
			(stroke
				(width 0.1524)
				(type default)
			)
			(layer "B.SilkS")
		)
		(fp_line
			(start -48.233838 7.015734)
			(end -46.699932 8.50011)
			(stroke
				(width 0.1524)
				(type default)
			)
			(layer "B.SilkS")
		)
		(fp_arc
			(start 46.638464 51.050698)
			(mid 45.76094 52.452719)
			(end 44.200064 52.999894)
			(stroke
				(width 0.1524)
				(type default)
			)
			(layer "B.SilkS")
		)
		(fp_arc
			(start 44.200064 -52.999894)
			(mid 45.967745 -52.2677)
			(end 46.699932 -50.500026)
			(stroke
				(width 0.1524)
				(type default)
			)
			(layer "B.SilkS")
		)
		(fp_arc
			(start 26.45791 52.999894)
			(mid 24.817644 52.386812)
			(end 23.981918 50.848006)
			(stroke
				(width 0.1524)
				(type default)
			)
			(layer "B.SilkS")
		)
		(fp_arc
			(start 23.981918 -50.848006)
			(mid 24.817633 -52.386826)
			(end 26.45791 -52.999894)
			(stroke
				(width 0.1524)
				(type default)
			)
			(layer "B.SilkS")
		)
		(fp_arc
			(start 22.900894 -43.15206)
			(mid 22.655523 -42.370437)
			(end 22.170644 -41.710102)
			(stroke
				(width 0.1524)
				(type default)
			)
			(layer "B.SilkS")
		)
		(fp_arc
			(start 20.424902 40.999918)
			(mid 22.065236 41.613109)
			(end 22.900894 43.15206)
			(stroke
				(width 0.1524)
				(type default)
			)
			(layer "B.SilkS")
		)
		(fp_arc
			(start 14.500098 11.500104)
			(mid 13.767757 13.267829)
			(end 11.999976 13.999972)
			(stroke
				(width 0.1524)
				(type default)
			)
			(layer "B.SilkS")
		)
		(fp_arc
			(start 11.999976 -13.999972)
			(mid 13.767747 -13.267791)
			(end 14.500098 -11.500104)
			(stroke
				(width 0.1524)
				(type default)
			)
			(layer "B.SilkS")
		)
		(fp_arc
			(start -11.999976 13.999972)
			(mid -13.767698 13.267777)
			(end -14.500098 11.500104)
			(stroke
				(width 0.1524)
				(type default)
			)
			(layer "B.SilkS")
		)
		(fp_arc
			(start -14.500098 -11.500104)
			(mid -13.767725 -13.267775)
			(end -11.999976 -13.999972)
			(stroke
				(width 0.1524)
				(type default)
			)
			(layer "B.SilkS")
		)
		(fp_arc
			(start -20.424902 -40.999918)
			(mid -21.066529 -41.083565)
			(end -21.665184 -41.329102)
			(stroke
				(width 0.1524)
				(type default)
			)
			(layer "B.SilkS")
		)
		(fp_arc
			(start -22.900894 43.15206)
			(mid -22.065276 41.613065)
			(end -20.424902 40.999918)
			(stroke
				(width 0.1524)
				(type default)
			)
			(layer "B.SilkS")
		)
		(fp_arc
			(start -23.981918 50.848006)
			(mid -24.817636 52.386814)
			(end -26.45791 52.999894)
			(stroke
				(width 0.1524)
				(type default)
			)
			(layer "B.SilkS")
		)
		(fp_arc
			(start -26.45791 -52.999894)
			(mid -24.817631 -52.38682)
			(end -23.981918 -50.848006)
			(stroke
				(width 0.1524)
				(type default)
			)
			(layer "B.SilkS")
		)
		(fp_arc
			(start -44.200064 52.999894)
			(mid -45.967731 52.267692)
			(end -46.699932 50.500026)
			(stroke
				(width 0.1524)
				(type default)
			)
			(layer "B.SilkS")
		)
		(fp_arc
			(start -46.699932 -50.500026)
			(mid -45.967731 -52.267693)
			(end -44.200064 -52.999894)
			(stroke
				(width 0.1524)
				(type default)
			)
			(layer "B.SilkS")
		)
		(fp_line
			(start 49.800002 5.500116)
			(end 49.800002 -5.500116)
			(stroke
				(width 0.1)
				(type default)
			)
			(layer "B.Fab")
		)
		(fp_line
			(start 49.800002 -5.500116)
			(end 46.699932 -8.50011)
			(stroke
				(width 0.1)
				(type default)
			)
			(layer "B.Fab")
		)
		(fp_line
			(start 46.699932 50.500026)
			(end 46.699932 8.50011)
			(stroke
				(width 0.1)
				(type default)
			)
			(layer "B.Fab")
		)
		(fp_line
			(start 46.699932 8.50011)
			(end 49.800002 5.500116)
			(stroke
				(width 0.1)
				(type default)
			)
			(layer "B.Fab")
		)
		(fp_line
			(start 46.699932 -8.50011)
			(end 46.699932 -50.500026)
			(stroke
				(width 0.1)
				(type default)
			)
			(layer "B.Fab")
		)
		(fp_line
			(start 26.45791 52.999894)
			(end 44.200064 52.999894)
			(stroke
				(width 0.1)
				(type default)
			)
			(layer "B.Fab")
		)
		(fp_line
			(start 26.45791 -52.999894)
			(end 44.200064 -52.999894)
			(stroke
				(width 0.1)
				(type default)
			)
			(layer "B.Fab")
		)
		(fp_line
			(start 22.900894 43.15206)
			(end 23.981918 50.848006)
			(stroke
				(width 0.1)
				(type default)
			)
			(layer "B.Fab")
		)
		(fp_line
			(start 22.900894 -43.15206)
			(end 23.981918 -50.848006)
			(stroke
				(width 0.1)
				(type default)
			)
			(layer "B.Fab")
		)
		(fp_line
			(start 20.424902 40.999918)
			(end -20.424902 40.999918)
			(stroke
				(width 0.1)
				(type default)
			)
			(layer "B.Fab")
		)
		(fp_line
			(start 20.424902 -40.999918)
			(end -20.424902 -40.999918)
			(stroke
				(width 0.1)
				(type default)
			)
			(layer "B.Fab")
		)
		(fp_line
			(start 14.500098 -11.500104)
			(end 14.500098 11.500104)
			(stroke
				(width 0.1)
				(type default)
			)
			(layer "B.Fab")
		)
		(fp_line
			(start -11.999976 13.999972)
			(end 11.999976 13.999972)
			(stroke
				(width 0.1)
				(type default)
			)
			(layer "B.Fab")
		)
		(fp_line
			(start -11.999976 -13.999972)
			(end 11.999976 -13.999972)
			(stroke
				(width 0.1)
				(type default)
			)
			(layer "B.Fab")
		)
		(fp_line
			(start -14.500098 11.500104)
			(end -14.500098 -11.500104)
			(stroke
				(width 0.1)
				(type default)
			)
			(layer "B.Fab")
		)
		(fp_line
			(start -22.900894 43.15206)
			(end -23.981918 50.848006)
			(stroke
				(width 0.1)
				(type default)
			)
			(layer "B.Fab")
		)
		(fp_line
			(start -22.900894 -43.15206)
			(end -23.981918 -50.848006)
			(stroke
				(width 0.1)
				(type default)
			)
			(layer "B.Fab")
		)
		(fp_line
			(start -26.45791 52.999894)
			(end -44.200064 52.999894)
			(stroke
				(width 0.1)
				(type default)
			)
			(layer "B.Fab")
		)
		(fp_line
			(start -26.45791 -52.999894)
			(end -44.200064 -52.999894)
			(stroke
				(width 0.1)
				(type default)
			)
			(layer "B.Fab")
		)
		(fp_line
			(start -46.699932 8.50011)
			(end -46.699932 50.500026)
			(stroke
				(width 0.1)
				(type default)
			)
			(layer "B.Fab")
		)
		(fp_line
			(start -46.699932 -8.50011)
			(end -49.800002 -5.500116)
			(stroke
				(width 0.1)
				(type default)
			)
			(layer "B.Fab")
		)
		(fp_line
			(start -46.699932 -50.500026)
			(end -46.699932 -8.50011)
			(stroke
				(width 0.1)
				(type default)
			)
			(layer "B.Fab")
		)
		(fp_line
			(start -49.800002 5.500116)
			(end -46.699932 8.50011)
			(stroke
				(width 0.1)
				(type default)
			)
			(layer "B.Fab")
		)
		(fp_line
			(start -49.800002 -5.500116)
			(end -49.800002 5.500116)
			(stroke
				(width 0.1)
				(type default)
			)
			(layer "B.Fab")
		)
		(fp_arc
			(start 46.699932 50.500026)
			(mid 45.967728 52.267682)
			(end 44.200064 52.999894)
			(stroke
				(width 0.1)
				(type default)
			)
			(layer "B.Fab")
		)
		(fp_arc
			(start 44.200064 -52.999894)
			(mid 45.967745 -52.2677)
			(end 46.699932 -50.500026)
			(stroke
				(width 0.1)
				(type default)
			)
			(layer "B.Fab")
		)
		(fp_arc
			(start 26.45791 52.999894)
			(mid 24.817644 52.386812)
			(end 23.981918 50.848006)
			(stroke
				(width 0.1)
				(type default)
			)
			(layer "B.Fab")
		)
		(fp_arc
			(start 23.981918 -50.848006)
			(mid 24.817633 -52.386826)
			(end 26.45791 -52.999894)
			(stroke
				(width 0.1)
				(type default)
			)
			(layer "B.Fab")
		)
		(fp_arc
			(start 22.900894 -43.15206)
			(mid 22.06528 -41.613038)
			(end 20.424902 -40.999918)
			(stroke
				(width 0.1)
				(type default)
			)
			(layer "B.Fab")
		)
		(fp_arc
			(start 20.424902 40.999918)
			(mid 22.065236 41.613109)
			(end 22.900894 43.15206)
			(stroke
				(width 0.1)
				(type default)
			)
			(layer "B.Fab")
		)
		(fp_arc
			(start 14.500098 11.500104)
			(mid 13.767757 13.267829)
			(end 11.999976 13.999972)
			(stroke
				(width 0.1)
				(type default)
			)
			(layer "B.Fab")
		)
		(fp_arc
			(start 11.999976 -13.999972)
			(mid 13.767747 -13.267791)
			(end 14.500098 -11.500104)
			(stroke
				(width 0.1)
				(type default)
			)
			(layer "B.Fab")
		)
		(fp_arc
			(start -11.999976 13.999972)
			(mid -13.767698 13.267777)
			(end -14.500098 11.500104)
			(stroke
				(width 0.1)
				(type default)
			)
			(layer "B.Fab")
		)
		(fp_arc
			(start -14.500098 -11.500104)
			(mid -13.767725 -13.267775)
			(end -11.999976 -13.999972)
			(stroke
				(width 0.1)
				(type default)
			)
			(layer "B.Fab")
		)
		(fp_arc
			(start -20.424902 -40.999918)
			(mid -22.065224 -41.613118)
			(end -22.900894 -43.15206)
			(stroke
				(width 0.1)
				(type default)
			)
			(layer "B.Fab")
		)
		(fp_arc
			(start -22.900894 43.15206)
			(mid -22.065276 41.613065)
			(end -20.424902 40.999918)
			(stroke
				(width 0.1)
				(type default)
			)
			(layer "B.Fab")
		)
		(fp_arc
			(start -23.981918 50.848006)
			(mid -24.817636 52.386814)
			(end -26.45791 52.999894)
			(stroke
				(width 0.1)
				(type default)
			)
			(layer "B.Fab")
		)
		(fp_arc
			(start -26.45791 -52.999894)
			(mid -24.817631 -52.38682)
			(end -23.981918 -50.848006)
			(stroke
				(width 0.1)
				(type default)
			)
			(layer "B.Fab")
		)
		(fp_arc
			(start -44.200064 52.999894)
			(mid -45.967731 52.267692)
			(end -46.699932 50.500026)
			(stroke
				(width 0.1)
				(type default)
			)
			(layer "B.Fab")
		)
		(fp_arc
			(start -46.699932 -50.500026)
			(mid -45.967731 -52.267693)
			(end -44.200064 -52.999894)
			(stroke
				(width 0.1)
				(type default)
			)
			(layer "B.Fab")
		)
		(fp_line
			(start 46.699932 95.149924)
			(end -46.699932 95.149924)
			(stroke
				(width 0.1)
				(type default)
			)
			(layer "F.Fab")
		)
		(fp_line
			(start 46.699932 60.149994)
			(end -46.699932 60.149994)
			(stroke
				(width 0.1)
				(type default)
			)
			(layer "F.Fab")
		)
		(fp_line
			(start 46.699932 -60.300108)
			(end 46.699932 95.149924)
			(stroke
				(width 0.1)
				(type default)
			)
			(layer "F.Fab")
		)
		(fp_line
			(start 35.999928 37.69995)
			(end -35.999928 37.69995)
			(stroke
				(width 0.1)
				(type default)
			)
			(layer "F.Fab")
		)
		(fp_line
			(start 35.999928 -37.69995)
			(end 35.999928 37.69995)
			(stroke
				(width 0.1)
				(type default)
			)
			(layer "F.Fab")
		)
		(fp_line
			(start 7.050024 3.999992)
			(end -7.050024 3.999992)
			(stroke
				(width 0.1)
				(type default)
			)
			(layer "F.Fab")
		)
		(fp_line
			(start 7.050024 -3.999992)
			(end 7.050024 3.999992)
			(stroke
				(width 0.1)
				(type default)
			)
			(layer "F.Fab")
		)
		(fp_line
			(start -7.050024 3.999992)
			(end -7.050024 -3.999992)
			(stroke
				(width 0.1)
				(type default)
			)
			(layer "F.Fab")
		)
		(fp_line
			(start -7.050024 -3.999992)
			(end 7.050024 -3.999992)
			(stroke
				(width 0.1)
				(type default)
			)
			(layer "F.Fab")
		)
		(fp_line
			(start -35.999928 37.69995)
			(end -35.999928 -37.69995)
			(stroke
				(width 0.1)
				(type default)
			)
			(layer "F.Fab")
		)
		(fp_line
			(start -35.999928 -37.69995)
			(end 35.999928 -37.69995)
			(stroke
				(width 0.1)
				(type default)
			)
			(layer "F.Fab")
		)
		(fp_line
			(start -46.699932 95.149924)
			(end -46.699932 60.149994)
			(stroke
				(width 0.1)
				(type default)
			)
			(layer "F.Fab")
		)
		(fp_line
			(start -46.699932 90.149934)
			(end 46.699932 90.149934)
			(stroke
				(width 0.1)
				(type default)
			)
			(layer "F.Fab")
		)
		(fp_line
			(start -46.699932 85.149944)
			(end 46.699932 85.149944)
			(stroke
				(width 0.1)
				(type default)
			)
			(layer "F.Fab")
		)
		(fp_line
			(start -46.699932 80.149954)
			(end 46.699932 80.149954)
			(stroke
				(width 0.1)
				(type default)
			)
			(layer "F.Fab")
		)
		(fp_line
			(start -46.699932 75.149964)
			(end 46.699932 75.149964)
			(stroke
				(width 0.1)
				(type default)
			)
			(layer "F.Fab")
		)
		(fp_line
			(start -46.699932 70.149974)
			(end 46.699932 70.149974)
			(stroke
				(width 0.1)
				(type default)
			)
			(layer "F.Fab")
		)
		(fp_line
			(start -46.699932 65.149984)
			(end 46.699932 65.149984)
			(stroke
				(width 0.1)
				(type default)
			)
			(layer "F.Fab")
		)
		(fp_line
			(start -46.699932 60.149994)
			(end -46.699932 -60.300108)
			(stroke
				(width 0.1)
				(type default)
			)
			(layer "F.Fab")
		)
		(fp_line
			(start -46.699932 -60.300108)
			(end 46.699932 -60.300108)
			(stroke
				(width 0.1)
				(type default)
			)
			(layer "F.Fab")
		)
		(fp_poly
			(pts
				(xy -36.761928 -35.189922) (xy -36.761928 -38.46195) (xy -33.219898 -38.46195) (xy -33.219898 -37.69995)
				(xy -35.999928 -37.69995) (xy -35.999928 -35.189922)
			)
			(stroke
				(width 0)
				(type default)
			)
			(fill yes)
			(layer "F.Fab")
		)
		(pad "" np_thru_hole circle
			(at -42.099992 0 180)
			(size 4.0132 4.0132)
			(drill 4.0132)
			(layers "*.Cu" "*.Mask")
			(clearance 0.381)
			(thermal_gap 0.381)
		)
		(pad "" np_thru_hole circle
			(at -30.599888 -45.900086 180)
			(size 4.0132 4.0132)
			(drill 4.0132)
			(layers "*.Cu" "*.Mask")
			(clearance 0.381)
			(thermal_gap 0.381)
		)
		(pad "" np_thru_hole circle
			(at -30.599888 45.900086 180)
			(size 4.0132 4.0132)
			(drill 4.0132)
			(layers "*.Cu" "*.Mask")
			(clearance 0.381)
			(thermal_gap 0.381)
		)
		(pad "" np_thru_hole circle
			(at 30.599888 -45.900086 180)
			(size 4.0132 4.0132)
			(drill 4.0132)
			(layers "*.Cu" "*.Mask")
			(clearance 0.381)
			(thermal_gap 0.381)
		)
		(pad "" np_thru_hole circle
			(at 30.599888 45.900086 180)
			(size 4.0132 4.0132)
			(drill 4.0132)
			(layers "*.Cu" "*.Mask")
			(clearance 0.381)
			(thermal_gap 0.381)
		)
		(pad "" np_thru_hole circle
			(at 42.099992 0 180)
			(size 4.0132 4.0132)
			(drill 4.0132)
			(layers "*.Cu" "*.Mask")
			(clearance 0.381)
			(thermal_gap 0.381)
		)
		(pad "A3" smd circle
			(at -32.280098 -36.809934 180)
			(size 0.450088 0.450088)
			(layers "F.Cu" "F.Mask" "F.Paste")
			(net "GND")
		)
		(pad "A4" smd circle
			(at -31.340044 -36.809934 180)
			(size 0.450088 0.450088)
			(layers "F.Cu" "F.Mask" "F.Paste")
			(net "SMB_CPU0_3_R_SCL")
		)
		(pad "A5" smd circle
			(at -30.39999 -36.809934 180)
			(size 0.450088 0.450088)
			(layers "F.Cu" "F.Mask" "F.Paste")
			(net "I3C_1_SPD_DDRGL_CPU0_R_SDA")
		)
		(pad "A7" smd circle
			(at -28.519882 -36.809934 180)
			(size 0.450088 0.450088)
			(layers "F.Cu" "F.Mask" "F.Paste")
			(net "CLK_100M_CPU0_CLK01_R_DN")
		)
		(pad "A8" smd circle
			(at -27.580082 -36.809934 180)
			(size 0.450088 0.450088)
			(layers "F.Cu" "F.Mask" "F.Paste")
			(net "CLK_100M_CPU0_CLK01_R_DP")
		)
		(pad "A9" smd circle
			(at -26.640028 -36.809934 180)
			(size 0.450088 0.450088)
			(layers "F.Cu" "F.Mask" "F.Paste")
			(net "GND")
		)
		(pad "A10" smd circle
			(at -25.699974 -36.809934 180)
			(size 0.450088 0.450088)
			(layers "F.Cu" "F.Mask" "F.Paste")
			(net "CLK_100M_CPU0_CLK03_R_DP")
		)
		(pad "A11" smd circle
			(at -24.75992 -36.809934 180)
			(size 0.450088 0.450088)
			(layers "F.Cu" "F.Mask" "F.Paste")
			(net "CLK_100M_CPU0_CLK03_R_DN")
		)
		(pad "A13" smd circle
			(at -22.880066 -36.809934 180)
			(size 0.450088 0.450088)
			(layers "F.Cu" "F.Mask" "F.Paste")
			(net "FAB_REV_ID2")
		)
		(pad "A14" smd circle
			(at -21.940012 -36.809934 180)
			(size 0.450088 0.450088)
			(layers "F.Cu" "F.Mask" "F.Paste")
			(net "FAB_REV_ID0")
		)
		(pad "A15" smd circle
			(at -20.999958 -36.809934 180)
			(size 0.450088 0.450088)
			(layers "F.Cu" "F.Mask" "F.Paste")
			(net "GND")
		)
		(pad "A16" smd circle
			(at -20.059904 -36.809934 180)
			(size 0.450088 0.450088)
			(layers "F.Cu" "F.Mask" "F.Paste")
			(net "JTAG_CPU0_TMS")
		)
		(pad "A17" smd circle
			(at -19.120104 -36.809934 180)
			(size 0.450088 0.450088)
			(layers "F.Cu" "F.Mask" "F.Paste")
			(net "JTAG_CPU0_TRST_N")
		)
		(pad "A19" smd circle
			(at -17.239996 -36.809934 180)
			(size 0.450088 0.450088)
			(layers "F.Cu" "F.Mask" "F.Paste")
			(net "CLK_100M_REF_OUT_DP")
		)
		(pad "A20" smd circle
			(at -16.299942 -36.809934 180)
			(size 0.450088 0.450088)
			(layers "F.Cu" "F.Mask" "F.Paste")
			(net "CLK_100M_REF_OUT_DN")
		)
		(pad "A21" smd circle
			(at -15.359888 -36.809934 180)
			(size 0.450088 0.450088)
			(layers "F.Cu" "F.Mask" "F.Paste")
			(net "GND")
		)
		(pad "A22" smd circle
			(at -14.420088 -36.809934 180)
			(size 0.450088 0.450088)
			(layers "F.Cu" "F.Mask" "F.Paste")
			(net "SVID_PVDDCR_CPU0_P0_SVD")
		)
		(pad "A23" smd circle
			(at -13.480034 -36.809934 180)
			(size 0.450088 0.450088)
			(layers "F.Cu" "F.Mask" "F.Paste")
			(net "SVID_PVDDCR_CPU0_P0_SVC")
		)
		(pad "A25" smd circle
			(at -11.599926 -36.809934 180)
			(size 0.450088 0.450088)
			(layers "F.Cu" "F.Mask" "F.Paste")
			(net "USB2_CPU0_P0_DN")
		)
		(pad "A26" smd circle
			(at -10.659872 -36.809934 180)
			(size 0.450088 0.450088)
			(layers "F.Cu" "F.Mask" "F.Paste")
			(net "USB2_CPU0_P0_DP")
		)
		(pad "A27" smd circle
			(at -9.720072 -36.809934 180)
			(size 0.450088 0.450088)
			(layers "F.Cu" "F.Mask" "F.Paste")
			(net "GND")
		)
		(pad "A28" smd circle
			(at -8.780018 -36.809934 180)
			(size 0.450088 0.450088)
			(layers "F.Cu" "F.Mask" "F.Paste")
			(net "USB2_CPU0_P1_DP")
		)
		(pad "A29" smd circle
			(at -7.839964 -36.809934 180)
			(size 0.450088 0.450088)
			(layers "F.Cu" "F.Mask" "F.Paste")
			(net "USB2_CPU0_P1_DN")
		)
		(pad "A31" smd circle
			(at -5.96011 -36.809934 180)
			(size 0.450088 0.450088)
			(layers "F.Cu" "F.Mask" "F.Paste")
			(net "Net_1898")
		)
		(pad "A32" smd circle
			(at -5.020056 -36.809934 180)
			(size 0.450088 0.450088)
			(layers "F.Cu" "F.Mask" "F.Paste")
			(net "NC_CPU0_AZ_SDOUT")
		)
		(pad "A33" smd circle
			(at -4.080002 -36.809934 180)
			(size 0.450088 0.450088)
			(layers "F.Cu" "F.Mask" "F.Paste")
			(net "NC_CPU0_AZ_SDIN2")
		)
		(pad "A34" smd circle
			(at -3.139948 -36.809934 180)
			(size 0.450088 0.450088)
			(layers "F.Cu" "F.Mask" "F.Paste")
			(net "NC_CPU0_AZ_RST_N")
		)
		(pad "A35" smd circle
			(at -2.199894 -36.809934 180)
			(size 0.450088 0.450088)
			(layers "F.Cu" "F.Mask" "F.Paste")
			(net "Net_1899")
		)
		(pad "A41" smd circle
			(at 2.500122 -36.809934 180)
			(size 0.450088 0.450088)
			(layers "F.Cu" "F.Mask" "F.Paste")
			(net "Net_1900")
		)
		(pad "A42" smd circle
			(at 3.439922 -36.809934 180)
			(size 0.450088 0.450088)
			(layers "F.Cu" "F.Mask" "F.Paste")
			(net "Net_1901")
		)
		(pad "A43" smd circle
			(at 4.379976 -36.809934 180)
			(size 0.450088 0.450088)
			(layers "F.Cu" "F.Mask" "F.Paste")
			(net "GND")
		)
		(pad "A44" smd circle
			(at 5.32003 -36.809934 180)
			(size 0.450088 0.450088)
			(layers "F.Cu" "F.Mask" "F.Paste")
			(net "GND")
		)
		(pad "A45" smd circle
			(at 6.260084 -36.809934 180)
			(size 0.450088 0.450088)
			(layers "F.Cu" "F.Mask" "F.Paste")
			(net "Net_1902")
		)
		(pad "A47" smd circle
			(at 8.139938 -36.809934 180)
			(size 0.450088 0.450088)
			(layers "F.Cu" "F.Mask" "F.Paste")
			(net "GND")
		)
		(pad "A48" smd circle
			(at 9.079992 -36.809934 180)
			(size 0.450088 0.450088)
			(layers "F.Cu" "F.Mask" "F.Paste")
			(net "Net_1903")
		)
		(pad "A49" smd circle
			(at 10.020046 -36.809934 180)
			(size 0.450088 0.450088)
			(layers "F.Cu" "F.Mask" "F.Paste")
			(net "GND")
		)
		(pad "A50" smd circle
			(at 10.9601 -36.809934 180)
			(size 0.450088 0.450088)
			(layers "F.Cu" "F.Mask" "F.Paste")
			(net "Net_1904")
		)
		(pad "A51" smd circle
			(at 11.8999 -36.809934 180)
			(size 0.450088 0.450088)
			(layers "F.Cu" "F.Mask" "F.Paste")
			(net "Net_1905")
		)
		(pad "A53" smd circle
			(at 13.780008 -36.809934 180)
			(size 0.450088 0.450088)
			(layers "F.Cu" "F.Mask" "F.Paste")
			(net "GND")
		)
		(pad "A54" smd circle
			(at 14.720062 -36.809934 180)
			(size 0.450088 0.450088)
			(layers "F.Cu" "F.Mask" "F.Paste")
			(net "Net_1906")
		)
		(pad "A55" smd circle
			(at 15.660116 -36.809934 180)
			(size 0.450088 0.450088)
			(layers "F.Cu" "F.Mask" "F.Paste")
			(net "Net_1907")
		)
		(pad "A56" smd circle
			(at 16.599916 -36.809934 180)
			(size 0.450088 0.450088)
			(layers "F.Cu" "F.Mask" "F.Paste")
			(net "Net_1908")
		)
		(pad "A57" smd circle
			(at 17.53997 -36.809934 180)
			(size 0.450088 0.450088)
			(layers "F.Cu" "F.Mask" "F.Paste")
			(net "Net_1909")
		)
		(pad "A59" smd circle
			(at 19.420078 -36.809934 180)
			(size 0.450088 0.450088)
			(layers "F.Cu" "F.Mask" "F.Paste")
			(net "Net_1910")
		)
		(pad "A60" smd circle
			(at 20.359878 -36.809934 180)
			(size 0.450088 0.450088)
			(layers "F.Cu" "F.Mask" "F.Paste")
			(net "Net_1911")
		)
		(pad "A61" smd circle
			(at 21.299932 -36.809934 180)
			(size 0.450088 0.450088)
			(layers "F.Cu" "F.Mask" "F.Paste")
			(net "GND")
		)
		(pad "A62" smd circle
			(at 22.239986 -36.809934 180)
			(size 0.450088 0.450088)
			(layers "F.Cu" "F.Mask" "F.Paste")
			(net "CPU0_BP3")
		)
		(pad "A63" smd circle
			(at 23.18004 -36.809934 180)
			(size 0.450088 0.450088)
			(layers "F.Cu" "F.Mask" "F.Paste")
			(net "CPU0_BP2")
		)
		(pad "A65" smd circle
			(at 25.059894 -36.809934 180)
			(size 0.450088 0.450088)
			(layers "F.Cu" "F.Mask" "F.Paste")
			(net "CPU0_XTRIG_R2_L7")
		)
		(pad "A66" smd circle
			(at 25.999948 -36.809934 180)
			(size 0.450088 0.450088)
			(layers "F.Cu" "F.Mask" "F.Paste")
			(net "CPU0_XTRIG_R2_L6")
		)
		(pad "A67" smd circle
			(at 26.940002 -36.809934 180)
			(size 0.450088 0.450088)
			(layers "F.Cu" "F.Mask" "F.Paste")
			(net "GND")
		)
		(pad "A68" smd circle
			(at 27.880056 -36.809934 180)
			(size 0.450088 0.450088)
			(layers "F.Cu" "F.Mask" "F.Paste")
			(net "APML_CPU0_ALERT_N")
		)
		(pad "A69" smd circle
			(at 28.82011 -36.809934 180)
			(size 0.450088 0.450088)
			(layers "F.Cu" "F.Mask" "F.Paste")
			(net "CPU0_PROCHOT_N")
		)
		(pad "A71" smd circle
			(at 30.699964 -36.809934 180)
			(size 0.450088 0.450088)
			(layers "F.Cu" "F.Mask" "F.Paste")
			(net "I3C_0_SPD_DDRAF_CPU0_R_SCL")
		)
		(pad "A72" smd circle
			(at 31.640018 -36.809934 180)
			(size 0.450088 0.450088)
			(layers "F.Cu" "F.Mask" "F.Paste")
			(net "GND")
		)
		(pad "A73" smd circle
			(at 32.580072 -36.809934 180)
			(size 0.450088 0.450088)
			(layers "F.Cu" "F.Mask" "F.Paste")
			(net "GND")
		)
		(pad "AA1" smd circle
			(at -34.159952 -20.610068 180)
			(size 0.450088 0.450088)
			(layers "F.Cu" "F.Mask" "F.Paste")
			(net "GND")
		)
		(pad "AA2" smd circle
			(at -33.219898 -20.610068 180)
			(size 0.450088 0.450088)
			(layers "F.Cu" "F.Mask" "F.Paste")
			(net "M_G_CPU0_SA_DQ<20>")
		)
		(pad "AA3" smd circle
			(at -32.280098 -20.610068 180)
			(size 0.450088 0.450088)
			(layers "F.Cu" "F.Mask" "F.Paste")
			(net "M_G_CPU0_SA_DQS_DP<7>")
		)
		(pad "AA4" smd circle
			(at -31.340044 -20.610068 180)
			(size 0.450088 0.450088)
			(layers "F.Cu" "F.Mask" "F.Paste")
			(net "GND")
		)
		(pad "AA5" smd circle
			(at -30.39999 -20.610068 180)
			(size 0.450088 0.450088)
			(layers "F.Cu" "F.Mask" "F.Paste")
			(net "M_K_CPU0_SA_DQ<20>")
		)
		(pad "AA6" smd circle
			(at -29.459936 -20.610068 180)
			(size 0.450088 0.450088)
			(layers "F.Cu" "F.Mask" "F.Paste")
			(net "GND")
		)
		(pad "AA7" smd circle
			(at -28.519882 -20.610068 180)
			(size 0.450088 0.450088)
			(layers "F.Cu" "F.Mask" "F.Paste")
			(net "M_K_CPU0_SA_DQS_DP<7>")
		)
		(pad "AA8" smd circle
			(at -27.580082 -20.610068 180)
			(size 0.450088 0.450088)
			(layers "F.Cu" "F.Mask" "F.Paste")
			(net "GND")
		)
		(pad "AA9" smd circle
			(at -26.640028 -20.610068 180)
			(size 0.450088 0.450088)
			(layers "F.Cu" "F.Mask" "F.Paste")
			(net "M_L_CPU0_SA_DQ<20>")
		)
		(pad "AA10" smd circle
			(at -25.699974 -20.610068 180)
			(size 0.450088 0.450088)
			(layers "F.Cu" "F.Mask" "F.Paste")
			(net "M_L_CPU0_SA_DQS_DP<7>")
		)
		(pad "AA11" smd circle
			(at -24.75992 -20.610068 180)
			(size 0.450088 0.450088)
			(layers "F.Cu" "F.Mask" "F.Paste")
			(net "GND")
		)
		(pad "AA12" smd circle
			(at -23.82012 -20.610068 180)
			(size 0.450088 0.450088)
			(layers "F.Cu" "F.Mask" "F.Paste")
			(net "M_H_CPU0_SA_DQ<20>")
		)
		(pad "AA13" smd circle
			(at -22.880066 -20.610068 180)
			(size 0.450088 0.450088)
			(layers "F.Cu" "F.Mask" "F.Paste")
			(net "GND")
		)
		(pad "AA14" smd circle
			(at -21.940012 -20.610068 180)
			(size 0.450088 0.450088)
			(layers "F.Cu" "F.Mask" "F.Paste")
			(net "M_H_CPU0_SA_DQS_DP<7>")
		)
		(pad "AA15" smd circle
			(at -20.999958 -20.610068 180)
			(size 0.450088 0.450088)
			(layers "F.Cu" "F.Mask" "F.Paste")
			(net "GND")
		)
		(pad "AA16" smd circle
			(at -20.059904 -20.610068 180)
			(size 0.450088 0.450088)
			(layers "F.Cu" "F.Mask" "F.Paste")
			(net "M_J_CPU0_SA_DQ<20>")
		)
		(pad "AA17" smd circle
			(at -19.120104 -20.610068 180)
			(size 0.450088 0.450088)
			(layers "F.Cu" "F.Mask" "F.Paste")
			(net "M_J_CPU0_SA_DQS_DP<7>")
		)
		(pad "AA18" smd circle
			(at -18.18005 -20.610068 180)
			(size 0.450088 0.450088)
			(layers "F.Cu" "F.Mask" "F.Paste")
			(net "GND")
		)
		(pad "AA19" smd circle
			(at -17.239996 -20.610068 180)
			(size 0.450088 0.450088)
			(layers "F.Cu" "F.Mask" "F.Paste")
			(net "M_I_CPU0_SA_DQ<20>")
		)
		(pad "AA20" smd circle
			(at -16.299942 -20.610068 180)
			(size 0.450088 0.450088)
			(layers "F.Cu" "F.Mask" "F.Paste")
			(net "GND")
		)
		(pad "AA21" smd circle
			(at -15.359888 -20.610068 180)
			(size 0.450088 0.450088)
			(layers "F.Cu" "F.Mask" "F.Paste")
			(net "M_I_CPU0_SA_DQS_DP<7>")
		)
		(pad "AA22" smd circle
			(at -14.420088 -20.610068 180)
			(size 0.450088 0.450088)
			(layers "F.Cu" "F.Mask" "F.Paste")
			(net "PVDDCR_SOC_P0")
		)
		(pad "AA23" smd circle
			(at -13.480034 -20.610068 180)
			(size 0.450088 0.450088)
			(layers "F.Cu" "F.Mask" "F.Paste")
			(net "TP_CPU0_TEST6_X3D4")
		)
		(pad "AA24" smd circle
			(at -12.53998 -20.610068 180)
			(size 0.450088 0.450088)
			(layers "F.Cu" "F.Mask" "F.Paste")
			(net "TP_CPU0_TEST5_IOD")
		)
		(pad "AA25" smd circle
			(at -11.599926 -20.610068 180)
			(size 0.450088 0.450088)
			(layers "F.Cu" "F.Mask" "F.Paste")
			(net "TP_CPU0_TEST4_IOD")
		)
		(pad "AA26" smd circle
			(at -10.659872 -20.610068 180)
			(size 0.450088 0.450088)
			(layers "F.Cu" "F.Mask" "F.Paste")
			(net "TP_CPU0_TEST5_CCD7")
		)
		(pad "AA27" smd circle
			(at -9.720072 -20.610068 180)
			(size 0.450088 0.450088)
			(layers "F.Cu" "F.Mask" "F.Paste")
			(net "TP_CPU0_TEST4_CCD7")
		)
		(pad "AA28" smd circle
			(at -8.780018 -20.610068 180)
			(size 0.450088 0.450088)
			(layers "F.Cu" "F.Mask" "F.Paste")
			(net "TP_CPU0_TEST4_CCD11")
		)
		(pad "AA29" smd circle
			(at -7.839964 -20.610068 180)
			(size 0.450088 0.450088)
			(layers "F.Cu" "F.Mask" "F.Paste")
			(net "TP_CPU0_TEST6_X3D2")
		)
		(pad "AA30" smd circle
			(at -6.89991 -20.610068 180)
			(size 0.450088 0.450088)
			(layers "F.Cu" "F.Mask" "F.Paste")
			(net "TP_CPU0_TEST4_CCD3")
		)
		(pad "AA31" smd circle
			(at -5.96011 -20.610068 180)
			(size 0.450088 0.450088)
			(layers "F.Cu" "F.Mask" "F.Paste")
			(net "GND")
		)
		(pad "AA32" smd circle
			(at -5.020056 -20.610068 180)
			(size 0.450088 0.450088)
			(layers "F.Cu" "F.Mask" "F.Paste")
			(net "GMI_CPU1_G0_CPU0_G2_TX_DN<11>")
		)
		(pad "AA33" smd circle
			(at -4.080002 -20.610068 180)
			(size 0.450088 0.450088)
			(layers "F.Cu" "F.Mask" "F.Paste")
			(net "GMI_CPU1_G0_CPU0_G2_TX_DP<11>")
		)
		(pad "AA34" smd circle
			(at -3.139948 -20.610068 180)
			(size 0.450088 0.450088)
			(layers "F.Cu" "F.Mask" "F.Paste")
			(net "GND")
		)
		(pad "AA35" smd circle
			(at -2.199894 -20.610068 180)
			(size 0.450088 0.450088)
			(layers "F.Cu" "F.Mask" "F.Paste")
			(net "GND")
		)
		(pad "AA36" smd circle
			(at -1.260094 -20.610068 180)
			(size 0.450088 0.450088)
			(layers "F.Cu" "F.Mask" "F.Paste")
			(net "GND")
		)
		(pad "AA40" smd circle
			(at 1.560068 -20.610068 180)
			(size 0.450088 0.450088)
			(layers "F.Cu" "F.Mask" "F.Paste")
			(net "GND")
		)
		(pad "AA41" smd circle
			(at 2.500122 -20.610068 180)
			(size 0.450088 0.450088)
			(layers "F.Cu" "F.Mask" "F.Paste")
			(net "GND")
		)
		(pad "AA42" smd circle
			(at 3.439922 -20.610068 180)
			(size 0.450088 0.450088)
			(layers "F.Cu" "F.Mask" "F.Paste")
			(net "GND")
		)
		(pad "AA43" smd circle
			(at 4.379976 -20.610068 180)
			(size 0.450088 0.450088)
			(layers "F.Cu" "F.Mask" "F.Paste")
			(net "GMI_CPU0_G0_CPU1_G2_TX_DP<4>")
		)
		(pad "AA44" smd circle
			(at 5.32003 -20.610068 180)
			(size 0.450088 0.450088)
			(layers "F.Cu" "F.Mask" "F.Paste")
			(net "GMI_CPU0_G0_CPU1_G2_TX_DN<4>")
		)
		(pad "AA45" smd circle
			(at 6.260084 -20.610068 180)
			(size 0.450088 0.450088)
			(layers "F.Cu" "F.Mask" "F.Paste")
			(net "GND")
		)
		(pad "AA46" smd circle
			(at 7.199884 -20.610068 180)
			(size 0.450088 0.450088)
			(layers "F.Cu" "F.Mask" "F.Paste")
			(net "TP_CPU0_TEST6_CCD0")
		)
		(pad "AA47" smd circle
			(at 8.139938 -20.610068 180)
			(size 0.450088 0.450088)
			(layers "F.Cu" "F.Mask" "F.Paste")
			(net "TP_CPU0_TEST6_X3D0")
		)
		(pad "AA48" smd circle
			(at 9.079992 -20.610068 180)
			(size 0.450088 0.450088)
			(layers "F.Cu" "F.Mask" "F.Paste")
			(net "TP_CPU0_TEST4_CCD8")
		)
		(pad "AA49" smd circle
			(at 10.020046 -20.610068 180)
			(size 0.450088 0.450088)
			(layers "F.Cu" "F.Mask" "F.Paste")
			(net "TP_CPU0_TEST6_IOD")
		)
		(pad "AA50" smd circle
			(at 10.9601 -20.610068 180)
			(size 0.450088 0.450088)
			(layers "F.Cu" "F.Mask" "F.Paste")
			(net "TP_CPU0_TEST4_CCD0")
		)
		(pad "AA51" smd circle
			(at 11.8999 -20.610068 180)
			(size 0.450088 0.450088)
			(layers "F.Cu" "F.Mask" "F.Paste")
			(net "TP_CPU0_TEST5_CCD0")
		)
		(pad "AA52" smd circle
			(at 12.839954 -20.610068 180)
			(size 0.450088 0.450088)
			(layers "F.Cu" "F.Mask" "F.Paste")
			(net "TP_CPU0_TEST4_CCD4")
		)
		(pad "AA53" smd circle
			(at 13.780008 -20.610068 180)
			(size 0.450088 0.450088)
			(layers "F.Cu" "F.Mask" "F.Paste")
			(net "TP_CPU0_TEST5_CCD4")
		)
		(pad "AA54" smd circle
			(at 14.720062 -20.610068 180)
			(size 0.450088 0.450088)
			(layers "F.Cu" "F.Mask" "F.Paste")
			(net "PVDDIO_P0")
		)
		(pad "AA55" smd circle
			(at 15.660116 -20.610068 180)
			(size 0.450088 0.450088)
			(layers "F.Cu" "F.Mask" "F.Paste")
			(net "M_C_CPU0_SA_DQS_DP<7>")
		)
		(pad "AA56" smd circle
			(at 16.599916 -20.610068 180)
			(size 0.450088 0.450088)
			(layers "F.Cu" "F.Mask" "F.Paste")
			(net "GND")
		)
		(pad "AA57" smd circle
			(at 17.53997 -20.610068 180)
			(size 0.450088 0.450088)
			(layers "F.Cu" "F.Mask" "F.Paste")
			(net "M_C_CPU0_SA_DQ<20>")
		)
		(pad "AA58" smd circle
			(at 18.480024 -20.610068 180)
			(size 0.450088 0.450088)
			(layers "F.Cu" "F.Mask" "F.Paste")
			(net "GND")
		)
		(pad "AA59" smd circle
			(at 19.420078 -20.610068 180)
			(size 0.450088 0.450088)
			(layers "F.Cu" "F.Mask" "F.Paste")
			(net "M_D_CPU0_SA_DQS_DP<7>")
		)
		(pad "AA60" smd circle
			(at 20.359878 -20.610068 180)
			(size 0.450088 0.450088)
			(layers "F.Cu" "F.Mask" "F.Paste")
			(net "M_D_CPU0_SA_DQ<20>")
		)
		(pad "AA61" smd circle
			(at 21.299932 -20.610068 180)
			(size 0.450088 0.450088)
			(layers "F.Cu" "F.Mask" "F.Paste")
			(net "GND")
		)
		(pad "AA62" smd circle
			(at 22.239986 -20.610068 180)
			(size 0.450088 0.450088)
			(layers "F.Cu" "F.Mask" "F.Paste")
			(net "M_B_CPU0_SA_DQS_DP<7>")
		)
		(pad "AA63" smd circle
			(at 23.18004 -20.610068 180)
			(size 0.450088 0.450088)
			(layers "F.Cu" "F.Mask" "F.Paste")
			(net "GND")
		)
		(pad "AA64" smd circle
			(at 24.120094 -20.610068 180)
			(size 0.450088 0.450088)
			(layers "F.Cu" "F.Mask" "F.Paste")
			(net "M_B_CPU0_SA_DQ<20>")
		)
		(pad "AA65" smd circle
			(at 25.059894 -20.610068 180)
			(size 0.450088 0.450088)
			(layers "F.Cu" "F.Mask" "F.Paste")
			(net "GND")
		)
		(pad "AA66" smd circle
			(at 25.999948 -20.610068 180)
			(size 0.450088 0.450088)
			(layers "F.Cu" "F.Mask" "F.Paste")
			(net "M_F_CPU0_SA_DQS_DP<7>")
		)
		(pad "AA67" smd circle
			(at 26.940002 -20.610068 180)
			(size 0.450088 0.450088)
			(layers "F.Cu" "F.Mask" "F.Paste")
			(net "M_F_CPU0_SA_DQ<20>")
		)
		(pad "AA68" smd circle
			(at 27.880056 -20.610068 180)
			(size 0.450088 0.450088)
			(layers "F.Cu" "F.Mask" "F.Paste")
			(net "GND")
		)
		(pad "AA69" smd circle
			(at 28.82011 -20.610068 180)
			(size 0.450088 0.450088)
			(layers "F.Cu" "F.Mask" "F.Paste")
			(net "M_E_CPU0_SA_DQS_DP<7>")
		)
		(pad "AA70" smd circle
			(at 29.75991 -20.610068 180)
			(size 0.450088 0.450088)
			(layers "F.Cu" "F.Mask" "F.Paste")
			(net "GND")
		)
		(pad "AA71" smd circle
			(at 30.699964 -20.610068 180)
			(size 0.450088 0.450088)
			(layers "F.Cu" "F.Mask" "F.Paste")
			(net "M_E_CPU0_SA_DQ<20>")
		)
		(pad "AA72" smd circle
			(at 31.640018 -20.610068 180)
			(size 0.450088 0.450088)
			(layers "F.Cu" "F.Mask" "F.Paste")
			(net "GND")
		)
		(pad "AA73" smd circle
			(at 32.580072 -20.610068 180)
			(size 0.450088 0.450088)
			(layers "F.Cu" "F.Mask" "F.Paste")
			(net "M_A_CPU0_SA_DQS_DP<7>")
		)
		(pad "AA74" smd circle
			(at 33.519872 -20.610068 180)
			(size 0.450088 0.450088)
			(layers "F.Cu" "F.Mask" "F.Paste")
			(net "M_A_CPU0_SA_DQ<20>")
		)
		(pad "AA75" smd circle
			(at 34.459926 -20.610068 180)
			(size 0.450088 0.450088)
			(layers "F.Cu" "F.Mask" "F.Paste")
			(net "GND")
		)
		(pad "AB2" smd circle
			(at -33.690052 -19.800062 180)
			(size 0.450088 0.450088)
			(layers "F.Cu" "F.Mask" "F.Paste")
			(net "M_G_CPU0_SA_DQ<22>")
		)
		(pad "AB3" smd circle
			(at -32.749998 -19.800062 180)
			(size 0.450088 0.450088)
			(layers "F.Cu" "F.Mask" "F.Paste")
			(net "GND")
		)
		(pad "AB4" smd circle
			(at -31.809944 -19.800062 180)
			(size 0.450088 0.450088)
			(layers "F.Cu" "F.Mask" "F.Paste")
			(net "M_G_CPU0_SA_DQ<21>")
		)
		(pad "AB5" smd circle
			(at -30.86989 -19.800062 180)
			(size 0.450088 0.450088)
			(layers "F.Cu" "F.Mask" "F.Paste")
			(net "GND")
		)
		(pad "AB6" smd circle
			(at -29.93009 -19.800062 180)
			(size 0.450088 0.450088)
			(layers "F.Cu" "F.Mask" "F.Paste")
			(net "M_K_CPU0_SA_DQ<22>")
		)
		(pad "AB7" smd circle
			(at -28.990036 -19.800062 180)
			(size 0.450088 0.450088)
			(layers "F.Cu" "F.Mask" "F.Paste")
			(net "M_K_CPU0_SA_DQ<21>")
		)
		(pad "AB8" smd circle
			(at -28.049982 -19.800062 180)
			(size 0.450088 0.450088)
			(layers "F.Cu" "F.Mask" "F.Paste")
			(net "GND")
		)
		(pad "AB9" smd circle
			(at -27.109928 -19.800062 180)
			(size 0.450088 0.450088)
			(layers "F.Cu" "F.Mask" "F.Paste")
			(net "M_L_CPU0_SA_DQ<22>")
		)
		(pad "AB10" smd circle
			(at -26.170128 -19.800062 180)
			(size 0.450088 0.450088)
			(layers "F.Cu" "F.Mask" "F.Paste")
			(net "GND")
		)
		(pad "AB11" smd circle
			(at -25.230074 -19.800062 180)
			(size 0.450088 0.450088)
			(layers "F.Cu" "F.Mask" "F.Paste")
			(net "M_L_CPU0_SA_DQ<21>")
		)
		(pad "AB12" smd circle
			(at -24.29002 -19.800062 180)
			(size 0.450088 0.450088)
			(layers "F.Cu" "F.Mask" "F.Paste")
			(net "GND")
		)
		(pad "AB13" smd circle
			(at -23.349966 -19.800062 180)
			(size 0.450088 0.450088)
			(layers "F.Cu" "F.Mask" "F.Paste")
			(net "M_H_CPU0_SA_DQ<22>")
		)
		(pad "AB14" smd circle
			(at -22.409912 -19.800062 180)
			(size 0.450088 0.450088)
			(layers "F.Cu" "F.Mask" "F.Paste")
			(net "M_H_CPU0_SA_DQ<21>")
		)
		(pad "AB15" smd circle
			(at -21.470112 -19.800062 180)
			(size 0.450088 0.450088)
			(layers "F.Cu" "F.Mask" "F.Paste")
			(net "GND")
		)
		(pad "AB16" smd circle
			(at -20.530058 -19.800062 180)
			(size 0.450088 0.450088)
			(layers "F.Cu" "F.Mask" "F.Paste")
			(net "M_J_CPU0_SA_DQ<22>")
		)
		(pad "AB17" smd circle
			(at -19.590004 -19.800062 180)
			(size 0.450088 0.450088)
			(layers "F.Cu" "F.Mask" "F.Paste")
			(net "GND")
		)
		(pad "AB18" smd circle
			(at -18.64995 -19.800062 180)
			(size 0.450088 0.450088)
			(layers "F.Cu" "F.Mask" "F.Paste")
			(net "M_J_CPU0_SA_DQ<21>")
		)
		(pad "AB19" smd circle
			(at -17.709896 -19.800062 180)
			(size 0.450088 0.450088)
			(layers "F.Cu" "F.Mask" "F.Paste")
			(net "GND")
		)
		(pad "AB20" smd circle
			(at -16.770096 -19.800062 180)
			(size 0.450088 0.450088)
			(layers "F.Cu" "F.Mask" "F.Paste")
			(net "M_I_CPU0_SA_DQ<22>")
		)
		(pad "AB21" smd circle
			(at -15.830042 -19.800062 180)
			(size 0.450088 0.450088)
			(layers "F.Cu" "F.Mask" "F.Paste")
			(net "M_I_CPU0_SA_DQ<21>")
		)
		(pad "AB22" smd circle
			(at -14.889988 -19.800062 180)
			(size 0.450088 0.450088)
			(layers "F.Cu" "F.Mask" "F.Paste")
			(net "GND")
		)
		(pad "AB23" smd circle
			(at -13.949934 -19.800062 180)
			(size 0.450088 0.450088)
			(layers "F.Cu" "F.Mask" "F.Paste")
			(net "PVDDCR_CPU0_P0")
		)
		(pad "AB24" smd circle
			(at -13.00988 -19.800062 180)
			(size 0.450088 0.450088)
			(layers "F.Cu" "F.Mask" "F.Paste")
			(net "PVDDCR_CPU0_P0")
		)
		(pad "AB25" smd circle
			(at -12.07008 -19.800062 180)
			(size 0.450088 0.450088)
			(layers "F.Cu" "F.Mask" "F.Paste")
			(net "GND")
		)
		(pad "AB26" smd circle
			(at -11.130026 -19.800062 180)
			(size 0.450088 0.450088)
			(layers "F.Cu" "F.Mask" "F.Paste")
			(net "PVDDCR_CPU0_P0")
		)
		(pad "AB27" smd circle
			(at -10.189972 -19.800062 180)
			(size 0.450088 0.450088)
			(layers "F.Cu" "F.Mask" "F.Paste")
			(net "PVDDCR_CPU0_P0")
		)
		(pad "AB28" smd circle
			(at -9.249918 -19.800062 180)
			(size 0.450088 0.450088)
			(layers "F.Cu" "F.Mask" "F.Paste")
			(net "GND")
		)
		(pad "AB29" smd circle
			(at -8.310118 -19.800062 180)
			(size 0.450088 0.450088)
			(layers "F.Cu" "F.Mask" "F.Paste")
			(net "PVDDCR_CPU0_P0")
		)
		(pad "AB30" smd circle
			(at -7.370064 -19.800062 180)
			(size 0.450088 0.450088)
			(layers "F.Cu" "F.Mask" "F.Paste")
			(net "PVDDCR_CPU0_P0")
		)
		(pad "AB31" smd circle
			(at -6.43001 -19.800062 180)
			(size 0.450088 0.450088)
			(layers "F.Cu" "F.Mask" "F.Paste")
			(net "GND")
		)
		(pad "AB32" smd circle
			(at -5.489956 -19.800062 180)
			(size 0.450088 0.450088)
			(layers "F.Cu" "F.Mask" "F.Paste")
			(net "PVDDCR_CPU0_P0")
		)
		(pad "AB33" smd circle
			(at -4.549902 -19.800062 180)
			(size 0.450088 0.450088)
			(layers "F.Cu" "F.Mask" "F.Paste")
			(net "PVDDCR_CPU0_P0")
		)
		(pad "AB34" smd circle
			(at -3.610102 -19.800062 180)
			(size 0.450088 0.450088)
			(layers "F.Cu" "F.Mask" "F.Paste")
			(net "GND")
		)
		(pad "AB35" smd circle
			(at -2.670048 -19.800062 180)
			(size 0.450088 0.450088)
			(layers "F.Cu" "F.Mask" "F.Paste")
			(net "GMI_CPU1_G0_CPU0_G2_TX_DN<13>")
		)
		(pad "AB36" smd circle
			(at -1.729994 -19.800062 180)
			(size 0.450088 0.450088)
			(layers "F.Cu" "F.Mask" "F.Paste")
			(net "GMI_CPU1_G0_CPU0_G2_TX_DP<13>")
		)
		(pad "AB37" smd circle
			(at -0.78994 -19.800062 180)
			(size 0.450088 0.450088)
			(layers "F.Cu" "F.Mask" "F.Paste")
			(net "GND")
		)
		(pad "AB39" smd circle
			(at 1.089914 -19.800062 180)
			(size 0.450088 0.450088)
			(layers "F.Cu" "F.Mask" "F.Paste")
			(net "GND")
		)
		(pad "AB40" smd circle
			(at 2.029968 -19.800062 180)
			(size 0.450088 0.450088)
			(layers "F.Cu" "F.Mask" "F.Paste")
			(net "GMI_CPU0_G0_CPU1_G2_TX_DP<2>")
		)
		(pad "AB41" smd circle
			(at 2.970022 -19.800062 180)
			(size 0.450088 0.450088)
			(layers "F.Cu" "F.Mask" "F.Paste")
			(net "GMI_CPU0_G0_CPU1_G2_TX_DN<2>")
		)
		(pad "AB42" smd circle
			(at 3.910076 -19.800062 180)
			(size 0.450088 0.450088)
			(layers "F.Cu" "F.Mask" "F.Paste")
			(net "GND")
		)
		(pad "AB43" smd circle
			(at 4.849876 -19.800062 180)
			(size 0.450088 0.450088)
			(layers "F.Cu" "F.Mask" "F.Paste")
			(net "PVDDCR_CPU0_P0")
		)
		(pad "AB44" smd circle
			(at 5.78993 -19.800062 180)
			(size 0.450088 0.450088)
			(layers "F.Cu" "F.Mask" "F.Paste")
			(net "PVDDCR_CPU0_P0")
		)
		(pad "AB45" smd circle
			(at 6.729984 -19.800062 180)
			(size 0.450088 0.450088)
			(layers "F.Cu" "F.Mask" "F.Paste")
			(net "GND")
		)
		(pad "AB46" smd circle
			(at 7.670038 -19.800062 180)
			(size 0.450088 0.450088)
			(layers "F.Cu" "F.Mask" "F.Paste")
			(net "PVDDCR_CPU0_P0")
		)
		(pad "AB47" smd circle
			(at 8.610092 -19.800062 180)
			(size 0.450088 0.450088)
			(layers "F.Cu" "F.Mask" "F.Paste")
			(net "PVDDCR_CPU0_P0")
		)
		(pad "AB48" smd circle
			(at 9.549892 -19.800062 180)
			(size 0.450088 0.450088)
			(layers "F.Cu" "F.Mask" "F.Paste")
			(net "GND")
		)
		(pad "AB49" smd circle
			(at 10.489946 -19.800062 180)
			(size 0.450088 0.450088)
			(layers "F.Cu" "F.Mask" "F.Paste")
			(net "PVDDCR_CPU0_P0")
		)
		(pad "AB50" smd circle
			(at 11.43 -19.800062 180)
			(size 0.450088 0.450088)
			(layers "F.Cu" "F.Mask" "F.Paste")
			(net "PVDDCR_CPU0_P0")
		)
		(pad "AB51" smd circle
			(at 12.370054 -19.800062 180)
			(size 0.450088 0.450088)
			(layers "F.Cu" "F.Mask" "F.Paste")
			(net "GND")
		)
		(pad "AB52" smd circle
			(at 13.310108 -19.800062 180)
			(size 0.450088 0.450088)
			(layers "F.Cu" "F.Mask" "F.Paste")
			(net "PVDDCR_CPU0_P0")
		)
		(pad "AB53" smd circle
			(at 14.249908 -19.800062 180)
			(size 0.450088 0.450088)
			(layers "F.Cu" "F.Mask" "F.Paste")
			(net "PVDDCR_CPU0_P0")
		)
		(pad "AB54" smd circle
			(at 15.189962 -19.800062 180)
			(size 0.450088 0.450088)
			(layers "F.Cu" "F.Mask" "F.Paste")
			(net "GND")
		)
		(pad "AB55" smd circle
			(at 16.130016 -19.800062 180)
			(size 0.450088 0.450088)
			(layers "F.Cu" "F.Mask" "F.Paste")
			(net "M_C_CPU0_SA_DQ<21>")
		)
		(pad "AB56" smd circle
			(at 17.07007 -19.800062 180)
			(size 0.450088 0.450088)
			(layers "F.Cu" "F.Mask" "F.Paste")
			(net "M_C_CPU0_SA_DQ<22>")
		)
		(pad "AB57" smd circle
			(at 18.010124 -19.800062 180)
			(size 0.450088 0.450088)
			(layers "F.Cu" "F.Mask" "F.Paste")
			(net "GND")
		)
		(pad "AB58" smd circle
			(at 18.949924 -19.800062 180)
			(size 0.450088 0.450088)
			(layers "F.Cu" "F.Mask" "F.Paste")
			(net "M_D_CPU0_SA_DQ<21>")
		)
		(pad "AB59" smd circle
			(at 19.889978 -19.800062 180)
			(size 0.450088 0.450088)
			(layers "F.Cu" "F.Mask" "F.Paste")
			(net "GND")
		)
		(pad "AB60" smd circle
			(at 20.830032 -19.800062 180)
			(size 0.450088 0.450088)
			(layers "F.Cu" "F.Mask" "F.Paste")
			(net "M_D_CPU0_SA_DQ<22>")
		)
		(pad "AB61" smd circle
			(at 21.770086 -19.800062 180)
			(size 0.450088 0.450088)
			(layers "F.Cu" "F.Mask" "F.Paste")
			(net "GND")
		)
		(pad "AB62" smd circle
			(at 22.709886 -19.800062 180)
			(size 0.450088 0.450088)
			(layers "F.Cu" "F.Mask" "F.Paste")
			(net "M_B_CPU0_SA_DQ<21>")
		)
		(pad "AB63" smd circle
			(at 23.64994 -19.800062 180)
			(size 0.450088 0.450088)
			(layers "F.Cu" "F.Mask" "F.Paste")
			(net "M_B_CPU0_SA_DQ<22>")
		)
		(pad "AB64" smd circle
			(at 24.589994 -19.800062 180)
			(size 0.450088 0.450088)
			(layers "F.Cu" "F.Mask" "F.Paste")
			(net "GND")
		)
		(pad "AB65" smd circle
			(at 25.530048 -19.800062 180)
			(size 0.450088 0.450088)
			(layers "F.Cu" "F.Mask" "F.Paste")
			(net "M_F_CPU0_SA_DQ<21>")
		)
		(pad "AB66" smd circle
			(at 26.470102 -19.800062 180)
			(size 0.450088 0.450088)
			(layers "F.Cu" "F.Mask" "F.Paste")
			(net "GND")
		)
		(pad "AB67" smd circle
			(at 27.409902 -19.800062 180)
			(size 0.450088 0.450088)
			(layers "F.Cu" "F.Mask" "F.Paste")
			(net "M_F_CPU0_SA_DQ<22>")
		)
		(pad "AB68" smd circle
			(at 28.349956 -19.800062 180)
			(size 0.450088 0.450088)
			(layers "F.Cu" "F.Mask" "F.Paste")
			(net "GND")
		)
		(pad "AB69" smd circle
			(at 29.29001 -19.800062 180)
			(size 0.450088 0.450088)
			(layers "F.Cu" "F.Mask" "F.Paste")
			(net "M_E_CPU0_SA_DQ<21>")
		)
		(pad "AB70" smd circle
			(at 30.230064 -19.800062 180)
			(size 0.450088 0.450088)
			(layers "F.Cu" "F.Mask" "F.Paste")
			(net "M_E_CPU0_SA_DQ<22>")
		)
		(pad "AB71" smd circle
			(at 31.170118 -19.800062 180)
			(size 0.450088 0.450088)
			(layers "F.Cu" "F.Mask" "F.Paste")
			(net "GND")
		)
		(pad "AB72" smd circle
			(at 32.109918 -19.800062 180)
			(size 0.450088 0.450088)
			(layers "F.Cu" "F.Mask" "F.Paste")
			(net "M_A_CPU0_SA_DQ<21>")
		)
		(pad "AB73" smd circle
			(at 33.049972 -19.800062 180)
			(size 0.450088 0.450088)
			(layers "F.Cu" "F.Mask" "F.Paste")
			(net "GND")
		)
		(pad "AB74" smd circle
			(at 33.990026 -19.800062 180)
			(size 0.450088 0.450088)
			(layers "F.Cu" "F.Mask" "F.Paste")
			(net "M_A_CPU0_SA_DQ<22>")
		)
		(pad "AC1" smd circle
			(at -34.159952 -18.990056 180)
			(size 0.450088 0.450088)
			(layers "F.Cu" "F.Mask" "F.Paste")
			(net "GND")
		)
		(pad "AC2" smd circle
			(at -33.219898 -18.990056 180)
			(size 0.450088 0.450088)
			(layers "F.Cu" "F.Mask" "F.Paste")
			(net "M_G_CPU0_SA_DQ<24>")
		)
		(pad "AC3" smd circle
			(at -32.280098 -18.990056 180)
			(size 0.450088 0.450088)
			(layers "F.Cu" "F.Mask" "F.Paste")
			(net "M_G_CPU0_SA_DQ<23>")
		)
		(pad "AC4" smd circle
			(at -31.340044 -18.990056 180)
			(size 0.450088 0.450088)
			(layers "F.Cu" "F.Mask" "F.Paste")
			(net "PVDDCR_SOC_P0")
		)
		(pad "AC5" smd circle
			(at -30.39999 -18.990056 180)
			(size 0.450088 0.450088)
			(layers "F.Cu" "F.Mask" "F.Paste")
			(net "M_K_CPU0_SA_DQ<24>")
		)
		(pad "AC6" smd circle
			(at -29.459936 -18.990056 180)
			(size 0.450088 0.450088)
			(layers "F.Cu" "F.Mask" "F.Paste")
			(net "GND")
		)
		(pad "AC7" smd circle
			(at -28.519882 -18.990056 180)
			(size 0.450088 0.450088)
			(layers "F.Cu" "F.Mask" "F.Paste")
			(net "M_K_CPU0_SA_DQ<23>")
		)
		(pad "AC8" smd circle
			(at -27.580082 -18.990056 180)
			(size 0.450088 0.450088)
			(layers "F.Cu" "F.Mask" "F.Paste")
			(net "GND")
		)
		(pad "AC9" smd circle
			(at -26.640028 -18.990056 180)
			(size 0.450088 0.450088)
			(layers "F.Cu" "F.Mask" "F.Paste")
			(net "M_L_CPU0_SA_DQ<24>")
		)
		(pad "AC10" smd circle
			(at -25.699974 -18.990056 180)
			(size 0.450088 0.450088)
			(layers "F.Cu" "F.Mask" "F.Paste")
			(net "M_L_CPU0_SA_DQ<23>")
		)
		(pad "AC11" smd circle
			(at -24.75992 -18.990056 180)
			(size 0.450088 0.450088)
			(layers "F.Cu" "F.Mask" "F.Paste")
			(net "PVDDCR_SOC_P0")
		)
		(pad "AC12" smd circle
			(at -23.82012 -18.990056 180)
			(size 0.450088 0.450088)
			(layers "F.Cu" "F.Mask" "F.Paste")
			(net "M_H_CPU0_SA_DQ<24>")
		)
		(pad "AC13" smd circle
			(at -22.880066 -18.990056 180)
			(size 0.450088 0.450088)
			(layers "F.Cu" "F.Mask" "F.Paste")
			(net "GND")
		)
		(pad "AC14" smd circle
			(at -21.940012 -18.990056 180)
			(size 0.450088 0.450088)
			(layers "F.Cu" "F.Mask" "F.Paste")
			(net "M_H_CPU0_SA_DQ<23>")
		)
		(pad "AC15" smd circle
			(at -20.999958 -18.990056 180)
			(size 0.450088 0.450088)
			(layers "F.Cu" "F.Mask" "F.Paste")
			(net "GND")
		)
		(pad "AC16" smd circle
			(at -20.059904 -18.990056 180)
			(size 0.450088 0.450088)
			(layers "F.Cu" "F.Mask" "F.Paste")
			(net "M_J_CPU0_SA_DQ<24>")
		)
		(pad "AC17" smd circle
			(at -19.120104 -18.990056 180)
			(size 0.450088 0.450088)
			(layers "F.Cu" "F.Mask" "F.Paste")
			(net "M_J_CPU0_SA_DQ<23>")
		)
		(pad "AC18" smd circle
			(at -18.18005 -18.990056 180)
			(size 0.450088 0.450088)
			(layers "F.Cu" "F.Mask" "F.Paste")
			(net "PVDDCR_SOC_P0")
		)
		(pad "AC19" smd circle
			(at -17.239996 -18.990056 180)
			(size 0.450088 0.450088)
			(layers "F.Cu" "F.Mask" "F.Paste")
			(net "M_I_CPU0_SA_DQ<24>")
		)
		(pad "AC20" smd circle
			(at -16.299942 -18.990056 180)
			(size 0.450088 0.450088)
			(layers "F.Cu" "F.Mask" "F.Paste")
			(net "GND")
		)
		(pad "AC21" smd circle
			(at -15.359888 -18.990056 180)
			(size 0.450088 0.450088)
			(layers "F.Cu" "F.Mask" "F.Paste")
			(net "M_I_CPU0_SA_DQ<23>")
		)
		(pad "AC22" smd circle
			(at -14.420088 -18.990056 180)
			(size 0.450088 0.450088)
			(layers "F.Cu" "F.Mask" "F.Paste")
			(net "GND")
		)
		(pad "AC23" smd circle
			(at -13.480034 -18.990056 180)
			(size 0.450088 0.450088)
			(layers "F.Cu" "F.Mask" "F.Paste")
			(net "GMI_CPU1_G0_CPU0_G2_TX_DN<1>")
		)
		(pad "AC24" smd circle
			(at -12.53998 -18.990056 180)
			(size 0.450088 0.450088)
			(layers "F.Cu" "F.Mask" "F.Paste")
			(net "GMI_CPU1_G0_CPU0_G2_TX_DP<1>")
		)
		(pad "AC25" smd circle
			(at -11.599926 -18.990056 180)
			(size 0.450088 0.450088)
			(layers "F.Cu" "F.Mask" "F.Paste")
			(net "GND")
		)
		(pad "AC26" smd circle
			(at -10.659872 -18.990056 180)
			(size 0.450088 0.450088)
			(layers "F.Cu" "F.Mask" "F.Paste")
			(net "GMI_CPU1_G0_CPU0_G2_TX_DN<4>")
		)
		(pad "AC27" smd circle
			(at -9.720072 -18.990056 180)
			(size 0.450088 0.450088)
			(layers "F.Cu" "F.Mask" "F.Paste")
			(net "GMI_CPU1_G0_CPU0_G2_TX_DP<4>")
		)
		(pad "AC28" smd circle
			(at -8.780018 -18.990056 180)
			(size 0.450088 0.450088)
			(layers "F.Cu" "F.Mask" "F.Paste")
			(net "GND")
		)
		(pad "AC29" smd circle
			(at -7.839964 -18.990056 180)
			(size 0.450088 0.450088)
			(layers "F.Cu" "F.Mask" "F.Paste")
			(net "GMI_CPU1_G0_CPU0_G2_TX_DN<7>")
		)
		(pad "AC30" smd circle
			(at -6.89991 -18.990056 180)
			(size 0.450088 0.450088)
			(layers "F.Cu" "F.Mask" "F.Paste")
			(net "GMI_CPU1_G0_CPU0_G2_TX_DP<7>")
		)
		(pad "AC31" smd circle
			(at -5.96011 -18.990056 180)
			(size 0.450088 0.450088)
			(layers "F.Cu" "F.Mask" "F.Paste")
			(net "GND")
		)
		(pad "AC32" smd circle
			(at -5.020056 -18.990056 180)
			(size 0.450088 0.450088)
			(layers "F.Cu" "F.Mask" "F.Paste")
			(net "GMI_CPU1_G0_CPU0_G2_TX_DN<10>")
		)
		(pad "AC33" smd circle
			(at -4.080002 -18.990056 180)
			(size 0.450088 0.450088)
			(layers "F.Cu" "F.Mask" "F.Paste")
			(net "GMI_CPU1_G0_CPU0_G2_TX_DP<10>")
		)
		(pad "AC34" smd circle
			(at -3.139948 -18.990056 180)
			(size 0.450088 0.450088)
			(layers "F.Cu" "F.Mask" "F.Paste")
			(net "GND")
		)
		(pad "AC35" smd circle
			(at -2.199894 -18.990056 180)
			(size 0.450088 0.450088)
			(layers "F.Cu" "F.Mask" "F.Paste")
			(net "PVDDCR_CPU0_P0")
		)
		(pad "AC36" smd circle
			(at -1.260094 -18.990056 180)
			(size 0.450088 0.450088)
			(layers "F.Cu" "F.Mask" "F.Paste")
			(net "PVDDCR_CPU0_P0")
		)
		(pad "AC40" smd circle
			(at 1.560068 -18.990056 180)
			(size 0.450088 0.450088)
			(layers "F.Cu" "F.Mask" "F.Paste")
			(net "PVDDCR_CPU0_P0")
		)
		(pad "AC41" smd circle
			(at 2.500122 -18.990056 180)
			(size 0.450088 0.450088)
			(layers "F.Cu" "F.Mask" "F.Paste")
			(net "PVDDCR_CPU0_P0")
		)
		(pad "AC42" smd circle
			(at 3.439922 -18.990056 180)
			(size 0.450088 0.450088)
			(layers "F.Cu" "F.Mask" "F.Paste")
			(net "GND")
		)
		(pad "AC43" smd circle
			(at 4.379976 -18.990056 180)
			(size 0.450088 0.450088)
			(layers "F.Cu" "F.Mask" "F.Paste")
			(net "GMI_CPU0_G0_CPU1_G2_TX_DP<5>")
		)
		(pad "AC44" smd circle
			(at 5.32003 -18.990056 180)
			(size 0.450088 0.450088)
			(layers "F.Cu" "F.Mask" "F.Paste")
			(net "GMI_CPU0_G0_CPU1_G2_TX_DN<5>")
		)
		(pad "AC45" smd circle
			(at 6.260084 -18.990056 180)
			(size 0.450088 0.450088)
			(layers "F.Cu" "F.Mask" "F.Paste")
			(net "GND")
		)
		(pad "AC46" smd circle
			(at 7.199884 -18.990056 180)
			(size 0.450088 0.450088)
			(layers "F.Cu" "F.Mask" "F.Paste")
			(net "GMI_CPU0_G0_CPU1_G2_TX_DP<8>")
		)
		(pad "AC47" smd circle
			(at 8.139938 -18.990056 180)
			(size 0.450088 0.450088)
			(layers "F.Cu" "F.Mask" "F.Paste")
			(net "GMI_CPU0_G0_CPU1_G2_TX_DN<8>")
		)
		(pad "AC48" smd circle
			(at 9.079992 -18.990056 180)
			(size 0.450088 0.450088)
			(layers "F.Cu" "F.Mask" "F.Paste")
			(net "GND")
		)
		(pad "AC49" smd circle
			(at 10.020046 -18.990056 180)
			(size 0.450088 0.450088)
			(layers "F.Cu" "F.Mask" "F.Paste")
			(net "GMI_CPU0_G0_CPU1_G2_TX_DP<11>")
		)
		(pad "AC50" smd circle
			(at 10.9601 -18.990056 180)
			(size 0.450088 0.450088)
			(layers "F.Cu" "F.Mask" "F.Paste")
			(net "GMI_CPU0_G0_CPU1_G2_TX_DN<11>")
		)
		(pad "AC51" smd circle
			(at 11.8999 -18.990056 180)
			(size 0.450088 0.450088)
			(layers "F.Cu" "F.Mask" "F.Paste")
			(net "GND")
		)
		(pad "AC52" smd circle
			(at 12.839954 -18.990056 180)
			(size 0.450088 0.450088)
			(layers "F.Cu" "F.Mask" "F.Paste")
			(net "GMI_CPU0_G0_CPU1_G2_TX_DP<14>")
		)
		(pad "AC53" smd circle
			(at 13.780008 -18.990056 180)
			(size 0.450088 0.450088)
			(layers "F.Cu" "F.Mask" "F.Paste")
			(net "GMI_CPU0_G0_CPU1_G2_TX_DN<14>")
		)
		(pad "AC54" smd circle
			(at 14.720062 -18.990056 180)
			(size 0.450088 0.450088)
			(layers "F.Cu" "F.Mask" "F.Paste")
			(net "GND")
		)
		(pad "AC55" smd circle
			(at 15.660116 -18.990056 180)
			(size 0.450088 0.450088)
			(layers "F.Cu" "F.Mask" "F.Paste")
			(net "M_C_CPU0_SA_DQ<23>")
		)
		(pad "AC56" smd circle
			(at 16.599916 -18.990056 180)
			(size 0.450088 0.450088)
			(layers "F.Cu" "F.Mask" "F.Paste")
			(net "GND")
		)
		(pad "AC57" smd circle
			(at 17.53997 -18.990056 180)
			(size 0.450088 0.450088)
			(layers "F.Cu" "F.Mask" "F.Paste")
			(net "M_C_CPU0_SA_DQ<24>")
		)
		(pad "AC58" smd circle
			(at 18.480024 -18.990056 180)
			(size 0.450088 0.450088)
			(layers "F.Cu" "F.Mask" "F.Paste")
			(net "PVDDIO_P0")
		)
		(pad "AC59" smd circle
			(at 19.420078 -18.990056 180)
			(size 0.450088 0.450088)
			(layers "F.Cu" "F.Mask" "F.Paste")
			(net "M_D_CPU0_SA_DQ<23>")
		)
		(pad "AC60" smd circle
			(at 20.359878 -18.990056 180)
			(size 0.450088 0.450088)
			(layers "F.Cu" "F.Mask" "F.Paste")
			(net "M_D_CPU0_SA_DQ<24>")
		)
		(pad "AC61" smd circle
			(at 21.299932 -18.990056 180)
			(size 0.450088 0.450088)
			(layers "F.Cu" "F.Mask" "F.Paste")
			(net "GND")
		)
		(pad "AC62" smd circle
			(at 22.239986 -18.990056 180)
			(size 0.450088 0.450088)
			(layers "F.Cu" "F.Mask" "F.Paste")
			(net "M_B_CPU0_SA_DQ<23>")
		)
		(pad "AC63" smd circle
			(at 23.18004 -18.990056 180)
			(size 0.450088 0.450088)
			(layers "F.Cu" "F.Mask" "F.Paste")
			(net "GND")
		)
		(pad "AC64" smd circle
			(at 24.120094 -18.990056 180)
			(size 0.450088 0.450088)
			(layers "F.Cu" "F.Mask" "F.Paste")
			(net "M_B_CPU0_SA_DQ<24>")
		)
		(pad "AC65" smd circle
			(at 25.059894 -18.990056 180)
			(size 0.450088 0.450088)
			(layers "F.Cu" "F.Mask" "F.Paste")
			(net "PVDDIO_P0")
		)
		(pad "AC66" smd circle
			(at 25.999948 -18.990056 180)
			(size 0.450088 0.450088)
			(layers "F.Cu" "F.Mask" "F.Paste")
			(net "M_F_CPU0_SA_DQ<23>")
		)
		(pad "AC67" smd circle
			(at 26.940002 -18.990056 180)
			(size 0.450088 0.450088)
			(layers "F.Cu" "F.Mask" "F.Paste")
			(net "M_F_CPU0_SA_DQ<24>")
		)
		(pad "AC68" smd circle
			(at 27.880056 -18.990056 180)
			(size 0.450088 0.450088)
			(layers "F.Cu" "F.Mask" "F.Paste")
			(net "GND")
		)
		(pad "AC69" smd circle
			(at 28.82011 -18.990056 180)
			(size 0.450088 0.450088)
			(layers "F.Cu" "F.Mask" "F.Paste")
			(net "M_E_CPU0_SA_DQ<23>")
		)
		(pad "AC70" smd circle
			(at 29.75991 -18.990056 180)
			(size 0.450088 0.450088)
			(layers "F.Cu" "F.Mask" "F.Paste")
			(net "GND")
		)
		(pad "AC71" smd circle
			(at 30.699964 -18.990056 180)
			(size 0.450088 0.450088)
			(layers "F.Cu" "F.Mask" "F.Paste")
			(net "M_E_CPU0_SA_DQ<24>")
		)
		(pad "AC72" smd circle
			(at 31.640018 -18.990056 180)
			(size 0.450088 0.450088)
			(layers "F.Cu" "F.Mask" "F.Paste")
			(net "PVDDIO_P0")
		)
		(pad "AC73" smd circle
			(at 32.580072 -18.990056 180)
			(size 0.450088 0.450088)
			(layers "F.Cu" "F.Mask" "F.Paste")
			(net "M_A_CPU0_SA_DQ<23>")
		)
		(pad "AC74" smd circle
			(at 33.519872 -18.990056 180)
			(size 0.450088 0.450088)
			(layers "F.Cu" "F.Mask" "F.Paste")
			(net "M_A_CPU0_SA_DQ<24>")
		)
		(pad "AC75" smd circle
			(at 34.459926 -18.990056 180)
			(size 0.450088 0.450088)
			(layers "F.Cu" "F.Mask" "F.Paste")
			(net "GND")
		)
		(pad "AD2" smd circle
			(at -33.690052 -18.18005 180)
			(size 0.450088 0.450088)
			(layers "F.Cu" "F.Mask" "F.Paste")
			(net "M_G_CPU0_SA_DQ<26>")
		)
		(pad "AD3" smd circle
			(at -32.749998 -18.18005 180)
			(size 0.450088 0.450088)
			(layers "F.Cu" "F.Mask" "F.Paste")
			(net "GND")
		)
		(pad "AD4" smd circle
			(at -31.809944 -18.18005 180)
			(size 0.450088 0.450088)
			(layers "F.Cu" "F.Mask" "F.Paste")
			(net "M_G_CPU0_SA_DQ<25>")
		)
		(pad "AD5" smd circle
			(at -30.86989 -18.18005 180)
			(size 0.450088 0.450088)
			(layers "F.Cu" "F.Mask" "F.Paste")
			(net "GND")
		)
		(pad "AD6" smd circle
			(at -29.93009 -18.18005 180)
			(size 0.450088 0.450088)
			(layers "F.Cu" "F.Mask" "F.Paste")
			(net "M_K_CPU0_SA_DQ<26>")
		)
		(pad "AD7" smd circle
			(at -28.990036 -18.18005 180)
			(size 0.450088 0.450088)
			(layers "F.Cu" "F.Mask" "F.Paste")
			(net "M_K_CPU0_SA_DQ<25>")
		)
		(pad "AD8" smd circle
			(at -28.049982 -18.18005 180)
			(size 0.450088 0.450088)
			(layers "F.Cu" "F.Mask" "F.Paste")
			(net "GND")
		)
		(pad "AD9" smd circle
			(at -27.109928 -18.18005 180)
			(size 0.450088 0.450088)
			(layers "F.Cu" "F.Mask" "F.Paste")
			(net "M_L_CPU0_SA_DQ<26>")
		)
		(pad "AD10" smd circle
			(at -26.170128 -18.18005 180)
			(size 0.450088 0.450088)
			(layers "F.Cu" "F.Mask" "F.Paste")
			(net "GND")
		)
		(pad "AD11" smd circle
			(at -25.230074 -18.18005 180)
			(size 0.450088 0.450088)
			(layers "F.Cu" "F.Mask" "F.Paste")
			(net "M_L_CPU0_SA_DQ<25>")
		)
		(pad "AD12" smd circle
			(at -24.29002 -18.18005 180)
			(size 0.450088 0.450088)
			(layers "F.Cu" "F.Mask" "F.Paste")
			(net "GND")
		)
		(pad "AD13" smd circle
			(at -23.349966 -18.18005 180)
			(size 0.450088 0.450088)
			(layers "F.Cu" "F.Mask" "F.Paste")
			(net "M_H_CPU0_SA_DQ<26>")
		)
		(pad "AD14" smd circle
			(at -22.409912 -18.18005 180)
			(size 0.450088 0.450088)
			(layers "F.Cu" "F.Mask" "F.Paste")
			(net "M_H_CPU0_SA_DQ<25>")
		)
		(pad "AD15" smd circle
			(at -21.470112 -18.18005 180)
			(size 0.450088 0.450088)
			(layers "F.Cu" "F.Mask" "F.Paste")
			(net "GND")
		)
		(pad "AD16" smd circle
			(at -20.530058 -18.18005 180)
			(size 0.450088 0.450088)
			(layers "F.Cu" "F.Mask" "F.Paste")
			(net "M_J_CPU0_SA_DQ<26>")
		)
		(pad "AD17" smd circle
			(at -19.590004 -18.18005 180)
			(size 0.450088 0.450088)
			(layers "F.Cu" "F.Mask" "F.Paste")
			(net "GND")
		)
		(pad "AD18" smd circle
			(at -18.64995 -18.18005 180)
			(size 0.450088 0.450088)
			(layers "F.Cu" "F.Mask" "F.Paste")
			(net "M_J_CPU0_SA_DQ<25>")
		)
		(pad "AD19" smd circle
			(at -17.709896 -18.18005 180)
			(size 0.450088 0.450088)
			(layers "F.Cu" "F.Mask" "F.Paste")
			(net "GND")
		)
		(pad "AD20" smd circle
			(at -16.770096 -18.18005 180)
			(size 0.450088 0.450088)
			(layers "F.Cu" "F.Mask" "F.Paste")
			(net "M_I_CPU0_SA_DQ<26>")
		)
		(pad "AD21" smd circle
			(at -15.830042 -18.18005 180)
			(size 0.450088 0.450088)
			(layers "F.Cu" "F.Mask" "F.Paste")
			(net "M_I_CPU0_SA_DQ<25>")
		)
		(pad "AD22" smd circle
			(at -14.889988 -18.18005 180)
			(size 0.450088 0.450088)
			(layers "F.Cu" "F.Mask" "F.Paste")
			(net "PVDDCR_SOC_P0")
		)
		(pad "AD23" smd circle
			(at -13.949934 -18.18005 180)
			(size 0.450088 0.450088)
			(layers "F.Cu" "F.Mask" "F.Paste")
			(net "GND")
		)
		(pad "AD24" smd circle
			(at -13.00988 -18.18005 180)
			(size 0.450088 0.450088)
			(layers "F.Cu" "F.Mask" "F.Paste")
			(net "GND")
		)
		(pad "AD25" smd circle
			(at -12.07008 -18.18005 180)
			(size 0.450088 0.450088)
			(layers "F.Cu" "F.Mask" "F.Paste")
			(net "GND")
		)
		(pad "AD26" smd circle
			(at -11.130026 -18.18005 180)
			(size 0.450088 0.450088)
			(layers "F.Cu" "F.Mask" "F.Paste")
			(net "GND")
		)
		(pad "AD27" smd circle
			(at -10.189972 -18.18005 180)
			(size 0.450088 0.450088)
			(layers "F.Cu" "F.Mask" "F.Paste")
			(net "GND")
		)
		(pad "AD28" smd circle
			(at -9.249918 -18.18005 180)
			(size 0.450088 0.450088)
			(layers "F.Cu" "F.Mask" "F.Paste")
			(net "GND")
		)
		(pad "AD29" smd circle
			(at -8.310118 -18.18005 180)
			(size 0.450088 0.450088)
			(layers "F.Cu" "F.Mask" "F.Paste")
			(net "GND")
		)
		(pad "AD30" smd circle
			(at -7.370064 -18.18005 180)
			(size 0.450088 0.450088)
			(layers "F.Cu" "F.Mask" "F.Paste")
			(net "GND")
		)
		(pad "AD31" smd circle
			(at -6.43001 -18.18005 180)
			(size 0.450088 0.450088)
			(layers "F.Cu" "F.Mask" "F.Paste")
			(net "GND")
		)
		(pad "AD32" smd circle
			(at -5.489956 -18.18005 180)
			(size 0.450088 0.450088)
			(layers "F.Cu" "F.Mask" "F.Paste")
			(net "GND")
		)
		(pad "AD33" smd circle
			(at -4.549902 -18.18005 180)
			(size 0.450088 0.450088)
			(layers "F.Cu" "F.Mask" "F.Paste")
			(net "GND")
		)
		(pad "AD34" smd circle
			(at -3.610102 -18.18005 180)
			(size 0.450088 0.450088)
			(layers "F.Cu" "F.Mask" "F.Paste")
			(net "GND")
		)
		(pad "AD35" smd circle
			(at -2.670048 -18.18005 180)
			(size 0.450088 0.450088)
			(layers "F.Cu" "F.Mask" "F.Paste")
			(net "GMI_CPU1_G0_CPU0_G2_TX_DN<14>")
		)
		(pad "AD36" smd circle
			(at -1.729994 -18.18005 180)
			(size 0.450088 0.450088)
			(layers "F.Cu" "F.Mask" "F.Paste")
			(net "GMI_CPU1_G0_CPU0_G2_TX_DP<14>")
		)
		(pad "AD37" smd circle
			(at -0.78994 -18.18005 180)
			(size 0.450088 0.450088)
			(layers "F.Cu" "F.Mask" "F.Paste")
			(net "GND")
		)
		(pad "AD39" smd circle
			(at 1.089914 -18.18005 180)
			(size 0.450088 0.450088)
			(layers "F.Cu" "F.Mask" "F.Paste")
			(net "GND")
		)
		(pad "AD40" smd circle
			(at 2.029968 -18.18005 180)
			(size 0.450088 0.450088)
			(layers "F.Cu" "F.Mask" "F.Paste")
			(net "GMI_CPU0_G0_CPU1_G2_TX_DP<1>")
		)
		(pad "AD41" smd circle
			(at 2.970022 -18.18005 180)
			(size 0.450088 0.450088)
			(layers "F.Cu" "F.Mask" "F.Paste")
			(net "GMI_CPU0_G0_CPU1_G2_TX_DN<1>")
		)
		(pad "AD42" smd circle
			(at 3.910076 -18.18005 180)
			(size 0.450088 0.450088)
			(layers "F.Cu" "F.Mask" "F.Paste")
			(net "GND")
		)
		(pad "AD43" smd circle
			(at 4.849876 -18.18005 180)
			(size 0.450088 0.450088)
			(layers "F.Cu" "F.Mask" "F.Paste")
			(net "GND")
		)
		(pad "AD44" smd circle
			(at 5.78993 -18.18005 180)
			(size 0.450088 0.450088)
			(layers "F.Cu" "F.Mask" "F.Paste")
			(net "GND")
		)
		(pad "AD45" smd circle
			(at 6.729984 -18.18005 180)
			(size 0.450088 0.450088)
			(layers "F.Cu" "F.Mask" "F.Paste")
			(net "GND")
		)
		(pad "AD46" smd circle
			(at 7.670038 -18.18005 180)
			(size 0.450088 0.450088)
			(layers "F.Cu" "F.Mask" "F.Paste")
			(net "GND")
		)
		(pad "AD47" smd circle
			(at 8.610092 -18.18005 180)
			(size 0.450088 0.450088)
			(layers "F.Cu" "F.Mask" "F.Paste")
			(net "GND")
		)
		(pad "AD48" smd circle
			(at 9.549892 -18.18005 180)
			(size 0.450088 0.450088)
			(layers "F.Cu" "F.Mask" "F.Paste")
			(net "GND")
		)
		(pad "AD49" smd circle
			(at 10.489946 -18.18005 180)
			(size 0.450088 0.450088)
			(layers "F.Cu" "F.Mask" "F.Paste")
			(net "GND")
		)
		(pad "AD50" smd circle
			(at 11.43 -18.18005 180)
			(size 0.450088 0.450088)
			(layers "F.Cu" "F.Mask" "F.Paste")
			(net "GND")
		)
		(pad "AD51" smd circle
			(at 12.370054 -18.18005 180)
			(size 0.450088 0.450088)
			(layers "F.Cu" "F.Mask" "F.Paste")
			(net "GND")
		)
		(pad "AD52" smd circle
			(at 13.310108 -18.18005 180)
			(size 0.450088 0.450088)
			(layers "F.Cu" "F.Mask" "F.Paste")
			(net "GND")
		)
		(pad "AD53" smd circle
			(at 14.249908 -18.18005 180)
			(size 0.450088 0.450088)
			(layers "F.Cu" "F.Mask" "F.Paste")
			(net "GND")
		)
		(pad "AD54" smd circle
			(at 15.189962 -18.18005 180)
			(size 0.450088 0.450088)
			(layers "F.Cu" "F.Mask" "F.Paste")
			(net "PVDDIO_P0")
		)
		(pad "AD55" smd circle
			(at 16.130016 -18.18005 180)
			(size 0.450088 0.450088)
			(layers "F.Cu" "F.Mask" "F.Paste")
			(net "M_C_CPU0_SA_DQ<25>")
		)
		(pad "AD56" smd circle
			(at 17.07007 -18.18005 180)
			(size 0.450088 0.450088)
			(layers "F.Cu" "F.Mask" "F.Paste")
			(net "M_C_CPU0_SA_DQ<26>")
		)
		(pad "AD57" smd circle
			(at 18.010124 -18.18005 180)
			(size 0.450088 0.450088)
			(layers "F.Cu" "F.Mask" "F.Paste")
			(net "GND")
		)
		(pad "AD58" smd circle
			(at 18.949924 -18.18005 180)
			(size 0.450088 0.450088)
			(layers "F.Cu" "F.Mask" "F.Paste")
			(net "M_D_CPU0_SA_DQ<25>")
		)
		(pad "AD59" smd circle
			(at 19.889978 -18.18005 180)
			(size 0.450088 0.450088)
			(layers "F.Cu" "F.Mask" "F.Paste")
			(net "GND")
		)
		(pad "AD60" smd circle
			(at 20.830032 -18.18005 180)
			(size 0.450088 0.450088)
			(layers "F.Cu" "F.Mask" "F.Paste")
			(net "M_D_CPU0_SA_DQ<26>")
		)
		(pad "AD61" smd circle
			(at 21.770086 -18.18005 180)
			(size 0.450088 0.450088)
			(layers "F.Cu" "F.Mask" "F.Paste")
			(net "GND")
		)
		(pad "AD62" smd circle
			(at 22.709886 -18.18005 180)
			(size 0.450088 0.450088)
			(layers "F.Cu" "F.Mask" "F.Paste")
			(net "M_B_CPU0_SA_DQ<25>")
		)
		(pad "AD63" smd circle
			(at 23.64994 -18.18005 180)
			(size 0.450088 0.450088)
			(layers "F.Cu" "F.Mask" "F.Paste")
			(net "M_B_CPU0_SA_DQ<26>")
		)
		(pad "AD64" smd circle
			(at 24.589994 -18.18005 180)
			(size 0.450088 0.450088)
			(layers "F.Cu" "F.Mask" "F.Paste")
			(net "GND")
		)
		(pad "AD65" smd circle
			(at 25.530048 -18.18005 180)
			(size 0.450088 0.450088)
			(layers "F.Cu" "F.Mask" "F.Paste")
			(net "M_F_CPU0_SA_DQ<25>")
		)
		(pad "AD66" smd circle
			(at 26.470102 -18.18005 180)
			(size 0.450088 0.450088)
			(layers "F.Cu" "F.Mask" "F.Paste")
			(net "GND")
		)
		(pad "AD67" smd circle
			(at 27.409902 -18.18005 180)
			(size 0.450088 0.450088)
			(layers "F.Cu" "F.Mask" "F.Paste")
			(net "M_F_CPU0_SA_DQ<26>")
		)
		(pad "AD68" smd circle
			(at 28.349956 -18.18005 180)
			(size 0.450088 0.450088)
			(layers "F.Cu" "F.Mask" "F.Paste")
			(net "GND")
		)
		(pad "AD69" smd circle
			(at 29.29001 -18.18005 180)
			(size 0.450088 0.450088)
			(layers "F.Cu" "F.Mask" "F.Paste")
			(net "M_E_CPU0_SA_DQ<25>")
		)
		(pad "AD70" smd circle
			(at 30.230064 -18.18005 180)
			(size 0.450088 0.450088)
			(layers "F.Cu" "F.Mask" "F.Paste")
			(net "M_E_CPU0_SA_DQ<26>")
		)
		(pad "AD71" smd circle
			(at 31.170118 -18.18005 180)
			(size 0.450088 0.450088)
			(layers "F.Cu" "F.Mask" "F.Paste")
			(net "GND")
		)
		(pad "AD72" smd circle
			(at 32.109918 -18.18005 180)
			(size 0.450088 0.450088)
			(layers "F.Cu" "F.Mask" "F.Paste")
			(net "M_A_CPU0_SA_DQ<25>")
		)
		(pad "AD73" smd circle
			(at 33.049972 -18.18005 180)
			(size 0.450088 0.450088)
			(layers "F.Cu" "F.Mask" "F.Paste")
			(net "GND")
		)
		(pad "AD74" smd circle
			(at 33.990026 -18.18005 180)
			(size 0.450088 0.450088)
			(layers "F.Cu" "F.Mask" "F.Paste")
			(net "M_A_CPU0_SA_DQ<26>")
		)
		(pad "AE1" smd circle
			(at -34.159952 -17.370044 180)
			(size 0.450088 0.450088)
			(layers "F.Cu" "F.Mask" "F.Paste")
			(net "GND")
		)
		(pad "AE2" smd circle
			(at -33.219898 -17.370044 180)
			(size 0.450088 0.450088)
			(layers "F.Cu" "F.Mask" "F.Paste")
			(net "M_G_CPU0_SA_DQS_DP<3>")
		)
		(pad "AE3" smd circle
			(at -32.280098 -17.370044 180)
			(size 0.450088 0.450088)
			(layers "F.Cu" "F.Mask" "F.Paste")
			(net "M_G_CPU0_SA_DQ<27>")
		)
		(pad "AE4" smd circle
			(at -31.340044 -17.370044 180)
			(size 0.450088 0.450088)
			(layers "F.Cu" "F.Mask" "F.Paste")
			(net "GND")
		)
		(pad "AE5" smd circle
			(at -30.39999 -17.370044 180)
			(size 0.450088 0.450088)
			(layers "F.Cu" "F.Mask" "F.Paste")
			(net "M_K_CPU0_SA_DQS_DP<3>")
		)
		(pad "AE6" smd circle
			(at -29.459936 -17.370044 180)
			(size 0.450088 0.450088)
			(layers "F.Cu" "F.Mask" "F.Paste")
			(net "GND")
		)
		(pad "AE7" smd circle
			(at -28.519882 -17.370044 180)
			(size 0.450088 0.450088)
			(layers "F.Cu" "F.Mask" "F.Paste")
			(net "M_K_CPU0_SA_DQ<27>")
		)
		(pad "AE8" smd circle
			(at -27.580082 -17.370044 180)
			(size 0.450088 0.450088)
			(layers "F.Cu" "F.Mask" "F.Paste")
			(net "GND")
		)
		(pad "AE9" smd circle
			(at -26.640028 -17.370044 180)
			(size 0.450088 0.450088)
			(layers "F.Cu" "F.Mask" "F.Paste")
			(net "M_L_CPU0_SA_DQS_DP<3>")
		)
		(pad "AE10" smd circle
			(at -25.699974 -17.370044 180)
			(size 0.450088 0.450088)
			(layers "F.Cu" "F.Mask" "F.Paste")
			(net "M_L_CPU0_SA_DQ<27>")
		)
		(pad "AE11" smd circle
			(at -24.75992 -17.370044 180)
			(size 0.450088 0.450088)
			(layers "F.Cu" "F.Mask" "F.Paste")
			(net "GND")
		)
		(pad "AE12" smd circle
			(at -23.82012 -17.370044 180)
			(size 0.450088 0.450088)
			(layers "F.Cu" "F.Mask" "F.Paste")
			(net "M_H_CPU0_SA_DQS_DP<3>")
		)
		(pad "AE13" smd circle
			(at -22.880066 -17.370044 180)
			(size 0.450088 0.450088)
			(layers "F.Cu" "F.Mask" "F.Paste")
			(net "GND")
		)
		(pad "AE14" smd circle
			(at -21.940012 -17.370044 180)
			(size 0.450088 0.450088)
			(layers "F.Cu" "F.Mask" "F.Paste")
			(net "M_H_CPU0_SA_DQ<27>")
		)
		(pad "AE15" smd circle
			(at -20.999958 -17.370044 180)
			(size 0.450088 0.450088)
			(layers "F.Cu" "F.Mask" "F.Paste")
			(net "GND")
		)
		(pad "AE16" smd circle
			(at -20.059904 -17.370044 180)
			(size 0.450088 0.450088)
			(layers "F.Cu" "F.Mask" "F.Paste")
			(net "M_J_CPU0_SA_DQS_DP<3>")
		)
		(pad "AE17" smd circle
			(at -19.120104 -17.370044 180)
			(size 0.450088 0.450088)
			(layers "F.Cu" "F.Mask" "F.Paste")
			(net "M_J_CPU0_SA_DQ<27>")
		)
		(pad "AE18" smd circle
			(at -18.18005 -17.370044 180)
			(size 0.450088 0.450088)
			(layers "F.Cu" "F.Mask" "F.Paste")
			(net "GND")
		)
		(pad "AE19" smd circle
			(at -17.239996 -17.370044 180)
			(size 0.450088 0.450088)
			(layers "F.Cu" "F.Mask" "F.Paste")
			(net "M_I_CPU0_SA_DQS_DP<3>")
		)
		(pad "AE20" smd circle
			(at -16.299942 -17.370044 180)
			(size 0.450088 0.450088)
			(layers "F.Cu" "F.Mask" "F.Paste")
			(net "GND")
		)
		(pad "AE21" smd circle
			(at -15.359888 -17.370044 180)
			(size 0.450088 0.450088)
			(layers "F.Cu" "F.Mask" "F.Paste")
			(net "M_I_CPU0_SA_DQ<27>")
		)
		(pad "AE22" smd circle
			(at -14.420088 -17.370044 180)
			(size 0.450088 0.450088)
			(layers "F.Cu" "F.Mask" "F.Paste")
			(net "GND")
		)
		(pad "AE23" smd circle
			(at -13.480034 -17.370044 180)
			(size 0.450088 0.450088)
			(layers "F.Cu" "F.Mask" "F.Paste")
			(net "GMI_CPU1_G0_CPU0_G2_TX_DN<0>")
		)
		(pad "AE24" smd circle
			(at -12.53998 -17.370044 180)
			(size 0.450088 0.450088)
			(layers "F.Cu" "F.Mask" "F.Paste")
			(net "GMI_CPU1_G0_CPU0_G2_TX_DP<0>")
		)
		(pad "AE25" smd circle
			(at -11.599926 -17.370044 180)
			(size 0.450088 0.450088)
			(layers "F.Cu" "F.Mask" "F.Paste")
			(net "GND")
		)
		(pad "AE26" smd circle
			(at -10.659872 -17.370044 180)
			(size 0.450088 0.450088)
			(layers "F.Cu" "F.Mask" "F.Paste")
			(net "GMI_CPU1_G0_CPU0_G2_TX_DN<3>")
		)
		(pad "AE27" smd circle
			(at -9.720072 -17.370044 180)
			(size 0.450088 0.450088)
			(layers "F.Cu" "F.Mask" "F.Paste")
			(net "GMI_CPU1_G0_CPU0_G2_TX_DP<3>")
		)
		(pad "AE28" smd circle
			(at -8.780018 -17.370044 180)
			(size 0.450088 0.450088)
			(layers "F.Cu" "F.Mask" "F.Paste")
			(net "GND")
		)
		(pad "AE29" smd circle
			(at -7.839964 -17.370044 180)
			(size 0.450088 0.450088)
			(layers "F.Cu" "F.Mask" "F.Paste")
			(net "GMI_CPU1_G0_CPU0_G2_TX_DN<6>")
		)
		(pad "AE30" smd circle
			(at -6.89991 -17.370044 180)
			(size 0.450088 0.450088)
			(layers "F.Cu" "F.Mask" "F.Paste")
			(net "GMI_CPU1_G0_CPU0_G2_TX_DP<6>")
		)
		(pad "AE31" smd circle
			(at -5.96011 -17.370044 180)
			(size 0.450088 0.450088)
			(layers "F.Cu" "F.Mask" "F.Paste")
			(net "GND")
		)
		(pad "AE32" smd circle
			(at -5.020056 -17.370044 180)
			(size 0.450088 0.450088)
			(layers "F.Cu" "F.Mask" "F.Paste")
			(net "GMI_CPU1_G0_CPU0_G2_TX_DN<9>")
		)
		(pad "AE33" smd circle
			(at -4.080002 -17.370044 180)
			(size 0.450088 0.450088)
			(layers "F.Cu" "F.Mask" "F.Paste")
			(net "GMI_CPU1_G0_CPU0_G2_TX_DP<9>")
		)
		(pad "AE34" smd circle
			(at -3.139948 -17.370044 180)
			(size 0.450088 0.450088)
			(layers "F.Cu" "F.Mask" "F.Paste")
			(net "GND")
		)
		(pad "AE35" smd circle
			(at -2.199894 -17.370044 180)
			(size 0.450088 0.450088)
			(layers "F.Cu" "F.Mask" "F.Paste")
			(net "GND")
		)
		(pad "AE36" smd circle
			(at -1.260094 -17.370044 180)
			(size 0.450088 0.450088)
			(layers "F.Cu" "F.Mask" "F.Paste")
			(net "GND")
		)
		(pad "AE40" smd circle
			(at 1.560068 -17.370044 180)
			(size 0.450088 0.450088)
			(layers "F.Cu" "F.Mask" "F.Paste")
			(net "GND")
		)
		(pad "AE41" smd circle
			(at 2.500122 -17.370044 180)
			(size 0.450088 0.450088)
			(layers "F.Cu" "F.Mask" "F.Paste")
			(net "GND")
		)
		(pad "AE42" smd circle
			(at 3.439922 -17.370044 180)
			(size 0.450088 0.450088)
			(layers "F.Cu" "F.Mask" "F.Paste")
			(net "GND")
		)
		(pad "AE43" smd circle
			(at 4.379976 -17.370044 180)
			(size 0.450088 0.450088)
			(layers "F.Cu" "F.Mask" "F.Paste")
			(net "GMI_CPU0_G0_CPU1_G2_TX_DP<6>")
		)
		(pad "AE44" smd circle
			(at 5.32003 -17.370044 180)
			(size 0.450088 0.450088)
			(layers "F.Cu" "F.Mask" "F.Paste")
			(net "GMI_CPU0_G0_CPU1_G2_TX_DN<6>")
		)
		(pad "AE45" smd circle
			(at 6.260084 -17.370044 180)
			(size 0.450088 0.450088)
			(layers "F.Cu" "F.Mask" "F.Paste")
			(net "GND")
		)
		(pad "AE46" smd circle
			(at 7.199884 -17.370044 180)
			(size 0.450088 0.450088)
			(layers "F.Cu" "F.Mask" "F.Paste")
			(net "GMI_CPU0_G0_CPU1_G2_TX_DP<9>")
		)
		(pad "AE47" smd circle
			(at 8.139938 -17.370044 180)
			(size 0.450088 0.450088)
			(layers "F.Cu" "F.Mask" "F.Paste")
			(net "GMI_CPU0_G0_CPU1_G2_TX_DN<9>")
		)
		(pad "AE48" smd circle
			(at 9.079992 -17.370044 180)
			(size 0.450088 0.450088)
			(layers "F.Cu" "F.Mask" "F.Paste")
			(net "GND")
		)
		(pad "AE49" smd circle
			(at 10.020046 -17.370044 180)
			(size 0.450088 0.450088)
			(layers "F.Cu" "F.Mask" "F.Paste")
			(net "GMI_CPU0_G0_CPU1_G2_TX_DP<12>")
		)
		(pad "AE50" smd circle
			(at 10.9601 -17.370044 180)
			(size 0.450088 0.450088)
			(layers "F.Cu" "F.Mask" "F.Paste")
			(net "GMI_CPU0_G0_CPU1_G2_TX_DN<12>")
		)
		(pad "AE51" smd circle
			(at 11.8999 -17.370044 180)
			(size 0.450088 0.450088)
			(layers "F.Cu" "F.Mask" "F.Paste")
			(net "GND")
		)
		(pad "AE52" smd circle
			(at 12.839954 -17.370044 180)
			(size 0.450088 0.450088)
			(layers "F.Cu" "F.Mask" "F.Paste")
			(net "GMI_CPU0_G0_CPU1_G2_TX_DP<15>")
		)
		(pad "AE53" smd circle
			(at 13.780008 -17.370044 180)
			(size 0.450088 0.450088)
			(layers "F.Cu" "F.Mask" "F.Paste")
			(net "GMI_CPU0_G0_CPU1_G2_TX_DN<15>")
		)
		(pad "AE54" smd circle
			(at 14.720062 -17.370044 180)
			(size 0.450088 0.450088)
			(layers "F.Cu" "F.Mask" "F.Paste")
			(net "GND")
		)
		(pad "AE55" smd circle
			(at 15.660116 -17.370044 180)
			(size 0.450088 0.450088)
			(layers "F.Cu" "F.Mask" "F.Paste")
			(net "M_C_CPU0_SA_DQ<27>")
		)
		(pad "AE56" smd circle
			(at 16.599916 -17.370044 180)
			(size 0.450088 0.450088)
			(layers "F.Cu" "F.Mask" "F.Paste")
			(net "GND")
		)
		(pad "AE57" smd circle
			(at 17.53997 -17.370044 180)
			(size 0.450088 0.450088)
			(layers "F.Cu" "F.Mask" "F.Paste")
			(net "M_C_CPU0_SA_DQS_DP<3>")
		)
		(pad "AE58" smd circle
			(at 18.480024 -17.370044 180)
			(size 0.450088 0.450088)
			(layers "F.Cu" "F.Mask" "F.Paste")
			(net "GND")
		)
		(pad "AE59" smd circle
			(at 19.420078 -17.370044 180)
			(size 0.450088 0.450088)
			(layers "F.Cu" "F.Mask" "F.Paste")
			(net "M_D_CPU0_SA_DQ<27>")
		)
		(pad "AE60" smd circle
			(at 20.359878 -17.370044 180)
			(size 0.450088 0.450088)
			(layers "F.Cu" "F.Mask" "F.Paste")
			(net "M_D_CPU0_SA_DQS_DP<3>")
		)
		(pad "AE61" smd circle
			(at 21.299932 -17.370044 180)
			(size 0.450088 0.450088)
			(layers "F.Cu" "F.Mask" "F.Paste")
			(net "GND")
		)
		(pad "AE62" smd circle
			(at 22.239986 -17.370044 180)
			(size 0.450088 0.450088)
			(layers "F.Cu" "F.Mask" "F.Paste")
			(net "M_B_CPU0_SA_DQ<27>")
		)
		(pad "AE63" smd circle
			(at 23.18004 -17.370044 180)
			(size 0.450088 0.450088)
			(layers "F.Cu" "F.Mask" "F.Paste")
			(net "GND")
		)
		(pad "AE64" smd circle
			(at 24.120094 -17.370044 180)
			(size 0.450088 0.450088)
			(layers "F.Cu" "F.Mask" "F.Paste")
			(net "M_B_CPU0_SA_DQS_DP<3>")
		)
		(pad "AE65" smd circle
			(at 25.059894 -17.370044 180)
			(size 0.450088 0.450088)
			(layers "F.Cu" "F.Mask" "F.Paste")
			(net "GND")
		)
		(pad "AE66" smd circle
			(at 25.999948 -17.370044 180)
			(size 0.450088 0.450088)
			(layers "F.Cu" "F.Mask" "F.Paste")
			(net "M_F_CPU0_SA_DQ<27>")
		)
		(pad "AE67" smd circle
			(at 26.940002 -17.370044 180)
			(size 0.450088 0.450088)
			(layers "F.Cu" "F.Mask" "F.Paste")
			(net "M_F_CPU0_SA_DQS_DP<3>")
		)
		(pad "AE68" smd circle
			(at 27.880056 -17.370044 180)
			(size 0.450088 0.450088)
			(layers "F.Cu" "F.Mask" "F.Paste")
			(net "GND")
		)
		(pad "AE69" smd circle
			(at 28.82011 -17.370044 180)
			(size 0.450088 0.450088)
			(layers "F.Cu" "F.Mask" "F.Paste")
			(net "M_E_CPU0_SA_DQ<27>")
		)
		(pad "AE70" smd circle
			(at 29.75991 -17.370044 180)
			(size 0.450088 0.450088)
			(layers "F.Cu" "F.Mask" "F.Paste")
			(net "GND")
		)
		(pad "AE71" smd circle
			(at 30.699964 -17.370044 180)
			(size 0.450088 0.450088)
			(layers "F.Cu" "F.Mask" "F.Paste")
			(net "M_E_CPU0_SA_DQS_DP<3>")
		)
		(pad "AE72" smd circle
			(at 31.640018 -17.370044 180)
			(size 0.450088 0.450088)
			(layers "F.Cu" "F.Mask" "F.Paste")
			(net "GND")
		)
		(pad "AE73" smd circle
			(at 32.580072 -17.370044 180)
			(size 0.450088 0.450088)
			(layers "F.Cu" "F.Mask" "F.Paste")
			(net "M_A_CPU0_SA_DQ<27>")
		)
		(pad "AE74" smd circle
			(at 33.519872 -17.370044 180)
			(size 0.450088 0.450088)
			(layers "F.Cu" "F.Mask" "F.Paste")
			(net "M_A_CPU0_SA_DQS_DP<3>")
		)
		(pad "AE75" smd circle
			(at 34.459926 -17.370044 180)
			(size 0.450088 0.450088)
			(layers "F.Cu" "F.Mask" "F.Paste")
			(net "GND")
		)
		(pad "AF2" smd circle
			(at -33.690052 -16.560038 180)
			(size 0.450088 0.450088)
			(layers "F.Cu" "F.Mask" "F.Paste")
			(net "M_G_CPU0_SA_DQS_DN<3>")
		)
		(pad "AF3" smd circle
			(at -32.749998 -16.560038 180)
			(size 0.450088 0.450088)
			(layers "F.Cu" "F.Mask" "F.Paste")
			(net "GND")
		)
		(pad "AF4" smd circle
			(at -31.809944 -16.560038 180)
			(size 0.450088 0.450088)
			(layers "F.Cu" "F.Mask" "F.Paste")
			(net "M_G_CPU0_SA_DQS_DN<8>")
		)
		(pad "AF5" smd circle
			(at -30.86989 -16.560038 180)
			(size 0.450088 0.450088)
			(layers "F.Cu" "F.Mask" "F.Paste")
			(net "PVDDCR_SOC_P0")
		)
		(pad "AF6" smd circle
			(at -29.93009 -16.560038 180)
			(size 0.450088 0.450088)
			(layers "F.Cu" "F.Mask" "F.Paste")
			(net "M_K_CPU0_SA_DQS_DN<3>")
		)
		(pad "AF7" smd circle
			(at -28.990036 -16.560038 180)
			(size 0.450088 0.450088)
			(layers "F.Cu" "F.Mask" "F.Paste")
			(net "M_K_CPU0_SA_DQS_DN<8>")
		)
		(pad "AF8" smd circle
			(at -28.049982 -16.560038 180)
			(size 0.450088 0.450088)
			(layers "F.Cu" "F.Mask" "F.Paste")
			(net "GND")
		)
		(pad "AF9" smd circle
			(at -27.109928 -16.560038 180)
			(size 0.450088 0.450088)
			(layers "F.Cu" "F.Mask" "F.Paste")
			(net "M_L_CPU0_SA_DQS_DN<3>")
		)
		(pad "AF10" smd circle
			(at -26.170128 -16.560038 180)
			(size 0.450088 0.450088)
			(layers "F.Cu" "F.Mask" "F.Paste")
			(net "GND")
		)
		(pad "AF11" smd circle
			(at -25.230074 -16.560038 180)
			(size 0.450088 0.450088)
			(layers "F.Cu" "F.Mask" "F.Paste")
			(net "M_L_CPU0_SA_DQS_DN<8>")
		)
		(pad "AF12" smd circle
			(at -24.29002 -16.560038 180)
			(size 0.450088 0.450088)
			(layers "F.Cu" "F.Mask" "F.Paste")
			(net "PVDDCR_SOC_P0")
		)
		(pad "AF13" smd circle
			(at -23.349966 -16.560038 180)
			(size 0.450088 0.450088)
			(layers "F.Cu" "F.Mask" "F.Paste")
			(net "M_H_CPU0_SA_DQS_DN<3>")
		)
		(pad "AF14" smd circle
			(at -22.409912 -16.560038 180)
			(size 0.450088 0.450088)
			(layers "F.Cu" "F.Mask" "F.Paste")
			(net "M_H_CPU0_SA_DQS_DN<8>")
		)
		(pad "AF15" smd circle
			(at -21.470112 -16.560038 180)
			(size 0.450088 0.450088)
			(layers "F.Cu" "F.Mask" "F.Paste")
			(net "GND")
		)
		(pad "AF16" smd circle
			(at -20.530058 -16.560038 180)
			(size 0.450088 0.450088)
			(layers "F.Cu" "F.Mask" "F.Paste")
			(net "M_J_CPU0_SA_DQS_DN<3>")
		)
		(pad "AF17" smd circle
			(at -19.590004 -16.560038 180)
			(size 0.450088 0.450088)
			(layers "F.Cu" "F.Mask" "F.Paste")
			(net "GND")
		)
		(pad "AF18" smd circle
			(at -18.64995 -16.560038 180)
			(size 0.450088 0.450088)
			(layers "F.Cu" "F.Mask" "F.Paste")
			(net "M_J_CPU0_SA_DQS_DN<8>")
		)
		(pad "AF19" smd circle
			(at -17.709896 -16.560038 180)
			(size 0.450088 0.450088)
			(layers "F.Cu" "F.Mask" "F.Paste")
			(net "PVDDCR_SOC_P0")
		)
		(pad "AF20" smd circle
			(at -16.770096 -16.560038 180)
			(size 0.450088 0.450088)
			(layers "F.Cu" "F.Mask" "F.Paste")
			(net "M_I_CPU0_SA_DQS_DN<3>")
		)
		(pad "AF21" smd circle
			(at -15.830042 -16.560038 180)
			(size 0.450088 0.450088)
			(layers "F.Cu" "F.Mask" "F.Paste")
			(net "M_I_CPU0_SA_DQS_DN<8>")
		)
		(pad "AF22" smd circle
			(at -14.889988 -16.560038 180)
			(size 0.450088 0.450088)
			(layers "F.Cu" "F.Mask" "F.Paste")
			(net "GND")
		)
		(pad "AF23" smd circle
			(at -13.949934 -16.560038 180)
			(size 0.450088 0.450088)
			(layers "F.Cu" "F.Mask" "F.Paste")
			(net "PVDDCR_CPU0_P0")
		)
		(pad "AF24" smd circle
			(at -13.00988 -16.560038 180)
			(size 0.450088 0.450088)
			(layers "F.Cu" "F.Mask" "F.Paste")
			(net "PVDDCR_CPU0_P0")
		)
		(pad "AF25" smd circle
			(at -12.07008 -16.560038 180)
			(size 0.450088 0.450088)
			(layers "F.Cu" "F.Mask" "F.Paste")
			(net "GND")
		)
		(pad "AF26" smd circle
			(at -11.130026 -16.560038 180)
			(size 0.450088 0.450088)
			(layers "F.Cu" "F.Mask" "F.Paste")
			(net "PVDDCR_CPU0_P0")
		)
		(pad "AF27" smd circle
			(at -10.189972 -16.560038 180)
			(size 0.450088 0.450088)
			(layers "F.Cu" "F.Mask" "F.Paste")
			(net "PVDDCR_CPU0_P0")
		)
		(pad "AF28" smd circle
			(at -9.249918 -16.560038 180)
			(size 0.450088 0.450088)
			(layers "F.Cu" "F.Mask" "F.Paste")
			(net "GND")
		)
		(pad "AF29" smd circle
			(at -8.310118 -16.560038 180)
			(size 0.450088 0.450088)
			(layers "F.Cu" "F.Mask" "F.Paste")
			(net "PVDDCR_CPU0_P0")
		)
		(pad "AF30" smd circle
			(at -7.370064 -16.560038 180)
			(size 0.450088 0.450088)
			(layers "F.Cu" "F.Mask" "F.Paste")
			(net "PVDDCR_CPU0_P0")
		)
		(pad "AF31" smd circle
			(at -6.43001 -16.560038 180)
			(size 0.450088 0.450088)
			(layers "F.Cu" "F.Mask" "F.Paste")
			(net "GND")
		)
		(pad "AF32" smd circle
			(at -5.489956 -16.560038 180)
			(size 0.450088 0.450088)
			(layers "F.Cu" "F.Mask" "F.Paste")
			(net "PVDDCR_CPU0_P0")
		)
		(pad "AF33" smd circle
			(at -4.549902 -16.560038 180)
			(size 0.450088 0.450088)
			(layers "F.Cu" "F.Mask" "F.Paste")
			(net "PVDDCR_CPU0_P0")
		)
		(pad "AF34" smd circle
			(at -3.610102 -16.560038 180)
			(size 0.450088 0.450088)
			(layers "F.Cu" "F.Mask" "F.Paste")
			(net "GND")
		)
		(pad "AF35" smd circle
			(at -2.670048 -16.560038 180)
			(size 0.450088 0.450088)
			(layers "F.Cu" "F.Mask" "F.Paste")
			(net "GMI_CPU1_G0_CPU0_G2_TX_DN<15>")
		)
		(pad "AF36" smd circle
			(at -1.729994 -16.560038 180)
			(size 0.450088 0.450088)
			(layers "F.Cu" "F.Mask" "F.Paste")
			(net "GMI_CPU1_G0_CPU0_G2_TX_DP<15>")
		)
		(pad "AF37" smd circle
			(at -0.78994 -16.560038 180)
			(size 0.450088 0.450088)
			(layers "F.Cu" "F.Mask" "F.Paste")
			(net "GND")
		)
		(pad "AF39" smd circle
			(at 1.089914 -16.560038 180)
			(size 0.450088 0.450088)
			(layers "F.Cu" "F.Mask" "F.Paste")
			(net "GND")
		)
		(pad "AF40" smd circle
			(at 2.029968 -16.560038 180)
			(size 0.450088 0.450088)
			(layers "F.Cu" "F.Mask" "F.Paste")
			(net "GMI_CPU0_G0_CPU1_G2_TX_DP<0>")
		)
		(pad "AF41" smd circle
			(at 2.970022 -16.560038 180)
			(size 0.450088 0.450088)
			(layers "F.Cu" "F.Mask" "F.Paste")
			(net "GMI_CPU0_G0_CPU1_G2_TX_DN<0>")
		)
		(pad "AF42" smd circle
			(at 3.910076 -16.560038 180)
			(size 0.450088 0.450088)
			(layers "F.Cu" "F.Mask" "F.Paste")
			(net "GND")
		)
		(pad "AF43" smd circle
			(at 4.849876 -16.560038 180)
			(size 0.450088 0.450088)
			(layers "F.Cu" "F.Mask" "F.Paste")
			(net "PVDDCR_CPU0_P0")
		)
		(pad "AF44" smd circle
			(at 5.78993 -16.560038 180)
			(size 0.450088 0.450088)
			(layers "F.Cu" "F.Mask" "F.Paste")
			(net "PVDDCR_CPU0_P0")
		)
		(pad "AF45" smd circle
			(at 6.729984 -16.560038 180)
			(size 0.450088 0.450088)
			(layers "F.Cu" "F.Mask" "F.Paste")
			(net "GND")
		)
		(pad "AF46" smd circle
			(at 7.670038 -16.560038 180)
			(size 0.450088 0.450088)
			(layers "F.Cu" "F.Mask" "F.Paste")
			(net "PVDDCR_CPU0_P0")
		)
		(pad "AF47" smd circle
			(at 8.610092 -16.560038 180)
			(size 0.450088 0.450088)
			(layers "F.Cu" "F.Mask" "F.Paste")
			(net "PVDDCR_CPU0_P0")
		)
		(pad "AF48" smd circle
			(at 9.549892 -16.560038 180)
			(size 0.450088 0.450088)
			(layers "F.Cu" "F.Mask" "F.Paste")
			(net "GND")
		)
		(pad "AF49" smd circle
			(at 10.489946 -16.560038 180)
			(size 0.450088 0.450088)
			(layers "F.Cu" "F.Mask" "F.Paste")
			(net "PVDDCR_CPU0_P0")
		)
		(pad "AF50" smd circle
			(at 11.43 -16.560038 180)
			(size 0.450088 0.450088)
			(layers "F.Cu" "F.Mask" "F.Paste")
			(net "PVDDCR_CPU0_P0")
		)
		(pad "AF51" smd circle
			(at 12.370054 -16.560038 180)
			(size 0.450088 0.450088)
			(layers "F.Cu" "F.Mask" "F.Paste")
			(net "GND")
		)
		(pad "AF52" smd circle
			(at 13.310108 -16.560038 180)
			(size 0.450088 0.450088)
			(layers "F.Cu" "F.Mask" "F.Paste")
			(net "PVDDCR_CPU0_P0")
		)
		(pad "AF53" smd circle
			(at 14.249908 -16.560038 180)
			(size 0.450088 0.450088)
			(layers "F.Cu" "F.Mask" "F.Paste")
			(net "PVDDCR_CPU0_P0")
		)
		(pad "AF54" smd circle
			(at 15.189962 -16.560038 180)
			(size 0.450088 0.450088)
			(layers "F.Cu" "F.Mask" "F.Paste")
			(net "GND")
		)
		(pad "AF55" smd circle
			(at 16.130016 -16.560038 180)
			(size 0.450088 0.450088)
			(layers "F.Cu" "F.Mask" "F.Paste")
			(net "M_C_CPU0_SA_DQS_DN<8>")
		)
		(pad "AF56" smd circle
			(at 17.07007 -16.560038 180)
			(size 0.450088 0.450088)
			(layers "F.Cu" "F.Mask" "F.Paste")
			(net "M_C_CPU0_SA_DQS_DN<3>")
		)
		(pad "AF57" smd circle
			(at 18.010124 -16.560038 180)
			(size 0.450088 0.450088)
			(layers "F.Cu" "F.Mask" "F.Paste")
			(net "PVDDIO_P0")
		)
		(pad "AF58" smd circle
			(at 18.949924 -16.560038 180)
			(size 0.450088 0.450088)
			(layers "F.Cu" "F.Mask" "F.Paste")
			(net "M_D_CPU0_SA_DQS_DN<8>")
		)
		(pad "AF59" smd circle
			(at 19.889978 -16.560038 180)
			(size 0.450088 0.450088)
			(layers "F.Cu" "F.Mask" "F.Paste")
			(net "GND")
		)
		(pad "AF60" smd circle
			(at 20.830032 -16.560038 180)
			(size 0.450088 0.450088)
			(layers "F.Cu" "F.Mask" "F.Paste")
			(net "M_D_CPU0_SA_DQS_DN<3>")
		)
		(pad "AF61" smd circle
			(at 21.770086 -16.560038 180)
			(size 0.450088 0.450088)
			(layers "F.Cu" "F.Mask" "F.Paste")
			(net "GND")
		)
		(pad "AF62" smd circle
			(at 22.709886 -16.560038 180)
			(size 0.450088 0.450088)
			(layers "F.Cu" "F.Mask" "F.Paste")
			(net "M_B_CPU0_SA_DQS_DN<8>")
		)
		(pad "AF63" smd circle
			(at 23.64994 -16.560038 180)
			(size 0.450088 0.450088)
			(layers "F.Cu" "F.Mask" "F.Paste")
			(net "M_B_CPU0_SA_DQS_DN<3>")
		)
		(pad "AF64" smd circle
			(at 24.589994 -16.560038 180)
			(size 0.450088 0.450088)
			(layers "F.Cu" "F.Mask" "F.Paste")
			(net "PVDDIO_P0")
		)
		(pad "AF65" smd circle
			(at 25.530048 -16.560038 180)
			(size 0.450088 0.450088)
			(layers "F.Cu" "F.Mask" "F.Paste")
			(net "M_F_CPU0_SA_DQS_DN<8>")
		)
		(pad "AF66" smd circle
			(at 26.470102 -16.560038 180)
			(size 0.450088 0.450088)
			(layers "F.Cu" "F.Mask" "F.Paste")
			(net "GND")
		)
		(pad "AF67" smd circle
			(at 27.409902 -16.560038 180)
			(size 0.450088 0.450088)
			(layers "F.Cu" "F.Mask" "F.Paste")
			(net "M_F_CPU0_SA_DQS_DN<3>")
		)
		(pad "AF68" smd circle
			(at 28.349956 -16.560038 180)
			(size 0.450088 0.450088)
			(layers "F.Cu" "F.Mask" "F.Paste")
			(net "GND")
		)
		(pad "AF69" smd circle
			(at 29.29001 -16.560038 180)
			(size 0.450088 0.450088)
			(layers "F.Cu" "F.Mask" "F.Paste")
			(net "M_E_CPU0_SA_DQS_DN<8>")
		)
		(pad "AF70" smd circle
			(at 30.230064 -16.560038 180)
			(size 0.450088 0.450088)
			(layers "F.Cu" "F.Mask" "F.Paste")
			(net "M_E_CPU0_SA_DQS_DN<3>")
		)
		(pad "AF71" smd circle
			(at 31.170118 -16.560038 180)
			(size 0.450088 0.450088)
			(layers "F.Cu" "F.Mask" "F.Paste")
			(net "PVDDIO_P0")
		)
		(pad "AF72" smd circle
			(at 32.109918 -16.560038 180)
			(size 0.450088 0.450088)
			(layers "F.Cu" "F.Mask" "F.Paste")
			(net "M_A_CPU0_SA_DQS_DN<8>")
		)
		(pad "AF73" smd circle
			(at 33.049972 -16.560038 180)
			(size 0.450088 0.450088)
			(layers "F.Cu" "F.Mask" "F.Paste")
			(net "GND")
		)
		(pad "AF74" smd circle
			(at 33.990026 -16.560038 180)
			(size 0.450088 0.450088)
			(layers "F.Cu" "F.Mask" "F.Paste")
			(net "M_A_CPU0_SA_DQS_DN<3>")
		)
		(pad "AG1" smd circle
			(at -34.159952 -15.750032 180)
			(size 0.450088 0.450088)
			(layers "F.Cu" "F.Mask" "F.Paste")
			(net "GND")
		)
		(pad "AG2" smd circle
			(at -33.219898 -15.750032 180)
			(size 0.450088 0.450088)
			(layers "F.Cu" "F.Mask" "F.Paste")
			(net "M_G_CPU0_SA_DQ<28>")
		)
		(pad "AG3" smd circle
			(at -32.280098 -15.750032 180)
			(size 0.450088 0.450088)
			(layers "F.Cu" "F.Mask" "F.Paste")
			(net "M_G_CPU0_SA_DQS_DP<8>")
		)
		(pad "AG4" smd circle
			(at -31.340044 -15.750032 180)
			(size 0.450088 0.450088)
			(layers "F.Cu" "F.Mask" "F.Paste")
			(net "GND")
		)
		(pad "AG5" smd circle
			(at -30.39999 -15.750032 180)
			(size 0.450088 0.450088)
			(layers "F.Cu" "F.Mask" "F.Paste")
			(net "M_K_CPU0_SA_DQ<28>")
		)
		(pad "AG6" smd circle
			(at -29.459936 -15.750032 180)
			(size 0.450088 0.450088)
			(layers "F.Cu" "F.Mask" "F.Paste")
			(net "GND")
		)
		(pad "AG7" smd circle
			(at -28.519882 -15.750032 180)
			(size 0.450088 0.450088)
			(layers "F.Cu" "F.Mask" "F.Paste")
			(net "M_K_CPU0_SA_DQS_DP<8>")
		)
		(pad "AG8" smd circle
			(at -27.580082 -15.750032 180)
			(size 0.450088 0.450088)
			(layers "F.Cu" "F.Mask" "F.Paste")
			(net "GND")
		)
		(pad "AG9" smd circle
			(at -26.640028 -15.750032 180)
			(size 0.450088 0.450088)
			(layers "F.Cu" "F.Mask" "F.Paste")
			(net "M_L_CPU0_SA_DQ<28>")
		)
		(pad "AG10" smd circle
			(at -25.699974 -15.750032 180)
			(size 0.450088 0.450088)
			(layers "F.Cu" "F.Mask" "F.Paste")
			(net "M_L_CPU0_SA_DQS_DP<8>")
		)
		(pad "AG11" smd circle
			(at -24.75992 -15.750032 180)
			(size 0.450088 0.450088)
			(layers "F.Cu" "F.Mask" "F.Paste")
			(net "GND")
		)
		(pad "AG12" smd circle
			(at -23.82012 -15.750032 180)
			(size 0.450088 0.450088)
			(layers "F.Cu" "F.Mask" "F.Paste")
			(net "M_H_CPU0_SA_DQ<28>")
		)
		(pad "AG13" smd circle
			(at -22.880066 -15.750032 180)
			(size 0.450088 0.450088)
			(layers "F.Cu" "F.Mask" "F.Paste")
			(net "GND")
		)
		(pad "AG14" smd circle
			(at -21.940012 -15.750032 180)
			(size 0.450088 0.450088)
			(layers "F.Cu" "F.Mask" "F.Paste")
			(net "M_H_CPU0_SA_DQS_DP<8>")
		)
		(pad "AG15" smd circle
			(at -20.999958 -15.750032 180)
			(size 0.450088 0.450088)
			(layers "F.Cu" "F.Mask" "F.Paste")
			(net "GND")
		)
		(pad "AG16" smd circle
			(at -20.059904 -15.750032 180)
			(size 0.450088 0.450088)
			(layers "F.Cu" "F.Mask" "F.Paste")
			(net "M_J_CPU0_SA_DQ<28>")
		)
		(pad "AG17" smd circle
			(at -19.120104 -15.750032 180)
			(size 0.450088 0.450088)
			(layers "F.Cu" "F.Mask" "F.Paste")
			(net "M_J_CPU0_SA_DQS_DP<8>")
		)
		(pad "AG18" smd circle
			(at -18.18005 -15.750032 180)
			(size 0.450088 0.450088)
			(layers "F.Cu" "F.Mask" "F.Paste")
			(net "GND")
		)
		(pad "AG19" smd circle
			(at -17.239996 -15.750032 180)
			(size 0.450088 0.450088)
			(layers "F.Cu" "F.Mask" "F.Paste")
			(net "M_I_CPU0_SA_DQ<28>")
		)
		(pad "AG20" smd circle
			(at -16.299942 -15.750032 180)
			(size 0.450088 0.450088)
			(layers "F.Cu" "F.Mask" "F.Paste")
			(net "GND")
		)
		(pad "AG21" smd circle
			(at -15.359888 -15.750032 180)
			(size 0.450088 0.450088)
			(layers "F.Cu" "F.Mask" "F.Paste")
			(net "M_I_CPU0_SA_DQS_DP<8>")
		)
		(pad "AG22" smd circle
			(at -14.420088 -15.750032 180)
			(size 0.450088 0.450088)
			(layers "F.Cu" "F.Mask" "F.Paste")
			(net "GND")
		)
		(pad "AG23" smd circle
			(at -13.480034 -15.750032 180)
			(size 0.450088 0.450088)
			(layers "F.Cu" "F.Mask" "F.Paste")
			(net "GMI_CPU1_G0_CPU0_G2_TX_DN<2>")
		)
		(pad "AG24" smd circle
			(at -12.53998 -15.750032 180)
			(size 0.450088 0.450088)
			(layers "F.Cu" "F.Mask" "F.Paste")
			(net "GMI_CPU1_G0_CPU0_G2_TX_DP<2>")
		)
		(pad "AG25" smd circle
			(at -11.599926 -15.750032 180)
			(size 0.450088 0.450088)
			(layers "F.Cu" "F.Mask" "F.Paste")
			(net "GND")
		)
		(pad "AG26" smd circle
			(at -10.659872 -15.750032 180)
			(size 0.450088 0.450088)
			(layers "F.Cu" "F.Mask" "F.Paste")
			(net "GMI_CPU1_G0_CPU0_G2_TX_DN<5>")
		)
		(pad "AG27" smd circle
			(at -9.720072 -15.750032 180)
			(size 0.450088 0.450088)
			(layers "F.Cu" "F.Mask" "F.Paste")
			(net "GMI_CPU1_G0_CPU0_G2_TX_DP<5>")
		)
		(pad "AG28" smd circle
			(at -8.780018 -15.750032 180)
			(size 0.450088 0.450088)
			(layers "F.Cu" "F.Mask" "F.Paste")
			(net "GND")
		)
		(pad "AG29" smd circle
			(at -7.839964 -15.750032 180)
			(size 0.450088 0.450088)
			(layers "F.Cu" "F.Mask" "F.Paste")
			(net "GMI_CPU1_G0_CPU0_G2_TX_DN<8>")
		)
		(pad "AG30" smd circle
			(at -6.89991 -15.750032 180)
			(size 0.450088 0.450088)
			(layers "F.Cu" "F.Mask" "F.Paste")
			(net "GMI_CPU1_G0_CPU0_G2_TX_DP<8>")
		)
		(pad "AG31" smd circle
			(at -5.96011 -15.750032 180)
			(size 0.450088 0.450088)
			(layers "F.Cu" "F.Mask" "F.Paste")
			(net "GND")
		)
		(pad "AG32" smd circle
			(at -5.020056 -15.750032 180)
			(size 0.450088 0.450088)
			(layers "F.Cu" "F.Mask" "F.Paste")
			(net "GMI_CPU1_G0_CPU0_G2_TX_DN<12>")
		)
		(pad "AG33" smd circle
			(at -4.080002 -15.750032 180)
			(size 0.450088 0.450088)
			(layers "F.Cu" "F.Mask" "F.Paste")
			(net "GMI_CPU1_G0_CPU0_G2_TX_DP<12>")
		)
		(pad "AG34" smd circle
			(at -3.139948 -15.750032 180)
			(size 0.450088 0.450088)
			(layers "F.Cu" "F.Mask" "F.Paste")
			(net "GND")
		)
		(pad "AG35" smd circle
			(at -2.199894 -15.750032 180)
			(size 0.450088 0.450088)
			(layers "F.Cu" "F.Mask" "F.Paste")
			(net "PVDDCR_CPU0_P0")
		)
		(pad "AG36" smd circle
			(at -1.260094 -15.750032 180)
			(size 0.450088 0.450088)
			(layers "F.Cu" "F.Mask" "F.Paste")
			(net "PVDDCR_CPU0_P0")
		)
		(pad "AG40" smd circle
			(at 1.560068 -15.750032 180)
			(size 0.450088 0.450088)
			(layers "F.Cu" "F.Mask" "F.Paste")
			(net "PVDDCR_CPU0_P0")
		)
		(pad "AG41" smd circle
			(at 2.500122 -15.750032 180)
			(size 0.450088 0.450088)
			(layers "F.Cu" "F.Mask" "F.Paste")
			(net "PVDDCR_CPU0_P0")
		)
		(pad "AG42" smd circle
			(at 3.439922 -15.750032 180)
			(size 0.450088 0.450088)
			(layers "F.Cu" "F.Mask" "F.Paste")
			(net "GND")
		)
		(pad "AG43" smd circle
			(at 4.379976 -15.750032 180)
			(size 0.450088 0.450088)
			(layers "F.Cu" "F.Mask" "F.Paste")
			(net "GMI_CPU0_G0_CPU1_G2_TX_DP<3>")
		)
		(pad "AG44" smd circle
			(at 5.32003 -15.750032 180)
			(size 0.450088 0.450088)
			(layers "F.Cu" "F.Mask" "F.Paste")
			(net "GMI_CPU0_G0_CPU1_G2_TX_DN<3>")
		)
		(pad "AG45" smd circle
			(at 6.260084 -15.750032 180)
			(size 0.450088 0.450088)
			(layers "F.Cu" "F.Mask" "F.Paste")
			(net "GND")
		)
		(pad "AG46" smd circle
			(at 7.199884 -15.750032 180)
			(size 0.450088 0.450088)
			(layers "F.Cu" "F.Mask" "F.Paste")
			(net "GMI_CPU0_G0_CPU1_G2_TX_DP<7>")
		)
		(pad "AG47" smd circle
			(at 8.139938 -15.750032 180)
			(size 0.450088 0.450088)
			(layers "F.Cu" "F.Mask" "F.Paste")
			(net "GMI_CPU0_G0_CPU1_G2_TX_DN<7>")
		)
		(pad "AG48" smd circle
			(at 9.079992 -15.750032 180)
			(size 0.450088 0.450088)
			(layers "F.Cu" "F.Mask" "F.Paste")
			(net "GND")
		)
		(pad "AG49" smd circle
			(at 10.020046 -15.750032 180)
			(size 0.450088 0.450088)
			(layers "F.Cu" "F.Mask" "F.Paste")
			(net "GMI_CPU0_G0_CPU1_G2_TX_DP<10>")
		)
		(pad "AG50" smd circle
			(at 10.9601 -15.750032 180)
			(size 0.450088 0.450088)
			(layers "F.Cu" "F.Mask" "F.Paste")
			(net "GMI_CPU0_G0_CPU1_G2_TX_DN<10>")
		)
		(pad "AG51" smd circle
			(at 11.8999 -15.750032 180)
			(size 0.450088 0.450088)
			(layers "F.Cu" "F.Mask" "F.Paste")
			(net "GND")
		)
		(pad "AG52" smd circle
			(at 12.839954 -15.750032 180)
			(size 0.450088 0.450088)
			(layers "F.Cu" "F.Mask" "F.Paste")
			(net "GMI_CPU0_G0_CPU1_G2_TX_DP<13>")
		)
		(pad "AG53" smd circle
			(at 13.780008 -15.750032 180)
			(size 0.450088 0.450088)
			(layers "F.Cu" "F.Mask" "F.Paste")
			(net "GMI_CPU0_G0_CPU1_G2_TX_DN<13>")
		)
		(pad "AG54" smd circle
			(at 14.720062 -15.750032 180)
			(size 0.450088 0.450088)
			(layers "F.Cu" "F.Mask" "F.Paste")
			(net "GND")
		)
		(pad "AG55" smd circle
			(at 15.660116 -15.750032 180)
			(size 0.450088 0.450088)
			(layers "F.Cu" "F.Mask" "F.Paste")
			(net "M_C_CPU0_SA_DQS_DP<8>")
		)
		(pad "AG56" smd circle
			(at 16.599916 -15.750032 180)
			(size 0.450088 0.450088)
			(layers "F.Cu" "F.Mask" "F.Paste")
			(net "GND")
		)
		(pad "AG57" smd circle
			(at 17.53997 -15.750032 180)
			(size 0.450088 0.450088)
			(layers "F.Cu" "F.Mask" "F.Paste")
			(net "M_C_CPU0_SA_DQ<28>")
		)
		(pad "AG58" smd circle
			(at 18.480024 -15.750032 180)
			(size 0.450088 0.450088)
			(layers "F.Cu" "F.Mask" "F.Paste")
			(net "GND")
		)
		(pad "AG59" smd circle
			(at 19.420078 -15.750032 180)
			(size 0.450088 0.450088)
			(layers "F.Cu" "F.Mask" "F.Paste")
			(net "M_D_CPU0_SA_DQS_DP<8>")
		)
		(pad "AG60" smd circle
			(at 20.359878 -15.750032 180)
			(size 0.450088 0.450088)
			(layers "F.Cu" "F.Mask" "F.Paste")
			(net "M_D_CPU0_SA_DQ<28>")
		)
		(pad "AG61" smd circle
			(at 21.299932 -15.750032 180)
			(size 0.450088 0.450088)
			(layers "F.Cu" "F.Mask" "F.Paste")
			(net "GND")
		)
		(pad "AG62" smd circle
			(at 22.239986 -15.750032 180)
			(size 0.450088 0.450088)
			(layers "F.Cu" "F.Mask" "F.Paste")
			(net "M_B_CPU0_SA_DQS_DP<8>")
		)
		(pad "AG63" smd circle
			(at 23.18004 -15.750032 180)
			(size 0.450088 0.450088)
			(layers "F.Cu" "F.Mask" "F.Paste")
			(net "GND")
		)
		(pad "AG64" smd circle
			(at 24.120094 -15.750032 180)
			(size 0.450088 0.450088)
			(layers "F.Cu" "F.Mask" "F.Paste")
			(net "M_B_CPU0_SA_DQ<28>")
		)
		(pad "AG65" smd circle
			(at 25.059894 -15.750032 180)
			(size 0.450088 0.450088)
			(layers "F.Cu" "F.Mask" "F.Paste")
			(net "GND")
		)
		(pad "AG66" smd circle
			(at 25.999948 -15.750032 180)
			(size 0.450088 0.450088)
			(layers "F.Cu" "F.Mask" "F.Paste")
			(net "M_F_CPU0_SA_DQS_DP<8>")
		)
		(pad "AG67" smd circle
			(at 26.940002 -15.750032 180)
			(size 0.450088 0.450088)
			(layers "F.Cu" "F.Mask" "F.Paste")
			(net "M_F_CPU0_SA_DQ<28>")
		)
		(pad "AG68" smd circle
			(at 27.880056 -15.750032 180)
			(size 0.450088 0.450088)
			(layers "F.Cu" "F.Mask" "F.Paste")
			(net "GND")
		)
		(pad "AG69" smd circle
			(at 28.82011 -15.750032 180)
			(size 0.450088 0.450088)
			(layers "F.Cu" "F.Mask" "F.Paste")
			(net "M_E_CPU0_SA_DQS_DP<8>")
		)
		(pad "AG70" smd circle
			(at 29.75991 -15.750032 180)
			(size 0.450088 0.450088)
			(layers "F.Cu" "F.Mask" "F.Paste")
			(net "GND")
		)
		(pad "AG71" smd circle
			(at 30.699964 -15.750032 180)
			(size 0.450088 0.450088)
			(layers "F.Cu" "F.Mask" "F.Paste")
			(net "M_E_CPU0_SA_DQ<28>")
		)
		(pad "AG72" smd circle
			(at 31.640018 -15.750032 180)
			(size 0.450088 0.450088)
			(layers "F.Cu" "F.Mask" "F.Paste")
			(net "GND")
		)
		(pad "AG73" smd circle
			(at 32.580072 -15.750032 180)
			(size 0.450088 0.450088)
			(layers "F.Cu" "F.Mask" "F.Paste")
			(net "M_A_CPU0_SA_DQS_DP<8>")
		)
		(pad "AG74" smd circle
			(at 33.519872 -15.750032 180)
			(size 0.450088 0.450088)
			(layers "F.Cu" "F.Mask" "F.Paste")
			(net "M_A_CPU0_SA_DQ<28>")
		)
		(pad "AG75" smd circle
			(at 34.459926 -15.750032 180)
			(size 0.450088 0.450088)
			(layers "F.Cu" "F.Mask" "F.Paste")
			(net "GND")
		)
		(pad "AH2" smd circle
			(at -33.690052 -14.940026 180)
			(size 0.450088 0.450088)
			(layers "F.Cu" "F.Mask" "F.Paste")
			(net "M_G_CPU0_SA_DQ<30>")
		)
		(pad "AH3" smd circle
			(at -32.749998 -14.940026 180)
			(size 0.450088 0.450088)
			(layers "F.Cu" "F.Mask" "F.Paste")
			(net "GND")
		)
		(pad "AH4" smd circle
			(at -31.809944 -14.940026 180)
			(size 0.450088 0.450088)
			(layers "F.Cu" "F.Mask" "F.Paste")
			(net "M_G_CPU0_SA_DQ<29>")
		)
		(pad "AH5" smd circle
			(at -30.86989 -14.940026 180)
			(size 0.450088 0.450088)
			(layers "F.Cu" "F.Mask" "F.Paste")
			(net "GND")
		)
		(pad "AH6" smd circle
			(at -29.93009 -14.940026 180)
			(size 0.450088 0.450088)
			(layers "F.Cu" "F.Mask" "F.Paste")
			(net "M_K_CPU0_SA_DQ<30>")
		)
		(pad "AH7" smd circle
			(at -28.990036 -14.940026 180)
			(size 0.450088 0.450088)
			(layers "F.Cu" "F.Mask" "F.Paste")
			(net "M_K_CPU0_SA_DQ<29>")
		)
		(pad "AH8" smd circle
			(at -28.049982 -14.940026 180)
			(size 0.450088 0.450088)
			(layers "F.Cu" "F.Mask" "F.Paste")
			(net "GND")
		)
		(pad "AH9" smd circle
			(at -27.109928 -14.940026 180)
			(size 0.450088 0.450088)
			(layers "F.Cu" "F.Mask" "F.Paste")
			(net "M_L_CPU0_SA_DQ<30>")
		)
		(pad "AH10" smd circle
			(at -26.170128 -14.940026 180)
			(size 0.450088 0.450088)
			(layers "F.Cu" "F.Mask" "F.Paste")
			(net "GND")
		)
		(pad "AH11" smd circle
			(at -25.230074 -14.940026 180)
			(size 0.450088 0.450088)
			(layers "F.Cu" "F.Mask" "F.Paste")
			(net "M_L_CPU0_SA_DQ<29>")
		)
		(pad "AH12" smd circle
			(at -24.29002 -14.940026 180)
			(size 0.450088 0.450088)
			(layers "F.Cu" "F.Mask" "F.Paste")
			(net "GND")
		)
		(pad "AH13" smd circle
			(at -23.349966 -14.940026 180)
			(size 0.450088 0.450088)
			(layers "F.Cu" "F.Mask" "F.Paste")
			(net "M_H_CPU0_SA_DQ<30>")
		)
		(pad "AH14" smd circle
			(at -22.409912 -14.940026 180)
			(size 0.450088 0.450088)
			(layers "F.Cu" "F.Mask" "F.Paste")
			(net "M_H_CPU0_SA_DQ<29>")
		)
		(pad "AH15" smd circle
			(at -21.470112 -14.940026 180)
			(size 0.450088 0.450088)
			(layers "F.Cu" "F.Mask" "F.Paste")
			(net "GND")
		)
		(pad "AH16" smd circle
			(at -20.530058 -14.940026 180)
			(size 0.450088 0.450088)
			(layers "F.Cu" "F.Mask" "F.Paste")
			(net "M_J_CPU0_SA_DQ<30>")
		)
		(pad "AH17" smd circle
			(at -19.590004 -14.940026 180)
			(size 0.450088 0.450088)
			(layers "F.Cu" "F.Mask" "F.Paste")
			(net "GND")
		)
		(pad "AH18" smd circle
			(at -18.64995 -14.940026 180)
			(size 0.450088 0.450088)
			(layers "F.Cu" "F.Mask" "F.Paste")
			(net "M_J_CPU0_SA_DQ<29>")
		)
		(pad "AH19" smd circle
			(at -17.709896 -14.940026 180)
			(size 0.450088 0.450088)
			(layers "F.Cu" "F.Mask" "F.Paste")
			(net "GND")
		)
		(pad "AH20" smd circle
			(at -16.770096 -14.940026 180)
			(size 0.450088 0.450088)
			(layers "F.Cu" "F.Mask" "F.Paste")
			(net "M_I_CPU0_SA_DQ<30>")
		)
		(pad "AH21" smd circle
			(at -15.830042 -14.940026 180)
			(size 0.450088 0.450088)
			(layers "F.Cu" "F.Mask" "F.Paste")
			(net "M_I_CPU0_SA_DQ<29>")
		)
		(pad "AH22" smd circle
			(at -14.889988 -14.940026 180)
			(size 0.450088 0.450088)
			(layers "F.Cu" "F.Mask" "F.Paste")
			(net "PVDDCR_SOC_P0")
		)
		(pad "AH23" smd circle
			(at -13.949934 -14.940026 180)
			(size 0.450088 0.450088)
			(layers "F.Cu" "F.Mask" "F.Paste")
			(net "GND")
		)
		(pad "AH24" smd circle
			(at -13.00988 -14.940026 180)
			(size 0.450088 0.450088)
			(layers "F.Cu" "F.Mask" "F.Paste")
			(net "GND")
		)
		(pad "AH25" smd circle
			(at -12.07008 -14.940026 180)
			(size 0.450088 0.450088)
			(layers "F.Cu" "F.Mask" "F.Paste")
			(net "GND")
		)
		(pad "AH26" smd circle
			(at -11.130026 -14.940026 180)
			(size 0.450088 0.450088)
			(layers "F.Cu" "F.Mask" "F.Paste")
			(net "GND")
		)
		(pad "AH27" smd circle
			(at -10.189972 -14.940026 180)
			(size 0.450088 0.450088)
			(layers "F.Cu" "F.Mask" "F.Paste")
			(net "GND")
		)
		(pad "AH28" smd circle
			(at -9.249918 -14.940026 180)
			(size 0.450088 0.450088)
			(layers "F.Cu" "F.Mask" "F.Paste")
			(net "GND")
		)
		(pad "AH29" smd circle
			(at -8.310118 -14.940026 180)
			(size 0.450088 0.450088)
			(layers "F.Cu" "F.Mask" "F.Paste")
			(net "GND")
		)
		(pad "AH30" smd circle
			(at -7.370064 -14.940026 180)
			(size 0.450088 0.450088)
			(layers "F.Cu" "F.Mask" "F.Paste")
			(net "GND")
		)
		(pad "AH31" smd circle
			(at -6.43001 -14.940026 180)
			(size 0.450088 0.450088)
			(layers "F.Cu" "F.Mask" "F.Paste")
			(net "GND")
		)
		(pad "AH32" smd circle
			(at -5.489956 -14.940026 180)
			(size 0.450088 0.450088)
			(layers "F.Cu" "F.Mask" "F.Paste")
			(net "GND")
		)
		(pad "AH33" smd circle
			(at -4.549902 -14.940026 180)
			(size 0.450088 0.450088)
			(layers "F.Cu" "F.Mask" "F.Paste")
			(net "GND")
		)
		(pad "AH34" smd circle
			(at -3.610102 -14.940026 180)
			(size 0.450088 0.450088)
			(layers "F.Cu" "F.Mask" "F.Paste")
			(net "GND")
		)
		(pad "AH35" smd circle
			(at -2.670048 -14.940026 180)
			(size 0.450088 0.450088)
			(layers "F.Cu" "F.Mask" "F.Paste")
			(net "P5E_CPU0_G3_RX_DN<13>")
		)
		(pad "AH36" smd circle
			(at -1.729994 -14.940026 180)
			(size 0.450088 0.450088)
			(layers "F.Cu" "F.Mask" "F.Paste")
			(net "P5E_CPU0_G3_RX_DP<13>")
		)
		(pad "AH37" smd circle
			(at -0.78994 -14.940026 180)
			(size 0.450088 0.450088)
			(layers "F.Cu" "F.Mask" "F.Paste")
			(net "GND")
		)
		(pad "AH39" smd circle
			(at 1.089914 -14.940026 180)
			(size 0.450088 0.450088)
			(layers "F.Cu" "F.Mask" "F.Paste")
			(net "GND")
		)
		(pad "AH40" smd circle
			(at 2.029968 -14.940026 180)
			(size 0.450088 0.450088)
			(layers "F.Cu" "F.Mask" "F.Paste")
			(net "GMI_CPU0_G1_CPU1_G3_TX_DP<2>")
		)
		(pad "AH41" smd circle
			(at 2.970022 -14.940026 180)
			(size 0.450088 0.450088)
			(layers "F.Cu" "F.Mask" "F.Paste")
			(net "GMI_CPU0_G1_CPU1_G3_TX_DN<2>")
		)
		(pad "AH42" smd circle
			(at 3.910076 -14.940026 180)
			(size 0.450088 0.450088)
			(layers "F.Cu" "F.Mask" "F.Paste")
			(net "GND")
		)
		(pad "AH43" smd circle
			(at 4.849876 -14.940026 180)
			(size 0.450088 0.450088)
			(layers "F.Cu" "F.Mask" "F.Paste")
			(net "GND")
		)
		(pad "AH44" smd circle
			(at 5.78993 -14.940026 180)
			(size 0.450088 0.450088)
			(layers "F.Cu" "F.Mask" "F.Paste")
			(net "GND")
		)
		(pad "AH45" smd circle
			(at 6.729984 -14.940026 180)
			(size 0.450088 0.450088)
			(layers "F.Cu" "F.Mask" "F.Paste")
			(net "GND")
		)
		(pad "AH46" smd circle
			(at 7.670038 -14.940026 180)
			(size 0.450088 0.450088)
			(layers "F.Cu" "F.Mask" "F.Paste")
			(net "GND")
		)
		(pad "AH47" smd circle
			(at 8.610092 -14.940026 180)
			(size 0.450088 0.450088)
			(layers "F.Cu" "F.Mask" "F.Paste")
			(net "GND")
		)
		(pad "AH48" smd circle
			(at 9.549892 -14.940026 180)
			(size 0.450088 0.450088)
			(layers "F.Cu" "F.Mask" "F.Paste")
			(net "GND")
		)
		(pad "AH49" smd circle
			(at 10.489946 -14.940026 180)
			(size 0.450088 0.450088)
			(layers "F.Cu" "F.Mask" "F.Paste")
			(net "GND")
		)
		(pad "AH50" smd circle
			(at 11.43 -14.940026 180)
			(size 0.450088 0.450088)
			(layers "F.Cu" "F.Mask" "F.Paste")
			(net "GND")
		)
		(pad "AH51" smd circle
			(at 12.370054 -14.940026 180)
			(size 0.450088 0.450088)
			(layers "F.Cu" "F.Mask" "F.Paste")
			(net "GND")
		)
		(pad "AH52" smd circle
			(at 13.310108 -14.940026 180)
			(size 0.450088 0.450088)
			(layers "F.Cu" "F.Mask" "F.Paste")
			(net "GND")
		)
		(pad "AH53" smd circle
			(at 14.249908 -14.940026 180)
			(size 0.450088 0.450088)
			(layers "F.Cu" "F.Mask" "F.Paste")
			(net "GND")
		)
		(pad "AH54" smd circle
			(at 15.189962 -14.940026 180)
			(size 0.450088 0.450088)
			(layers "F.Cu" "F.Mask" "F.Paste")
			(net "PVDDIO_P0")
		)
		(pad "AH55" smd circle
			(at 16.130016 -14.940026 180)
			(size 0.450088 0.450088)
			(layers "F.Cu" "F.Mask" "F.Paste")
			(net "M_C_CPU0_SA_DQ<29>")
		)
		(pad "AH56" smd circle
			(at 17.07007 -14.940026 180)
			(size 0.450088 0.450088)
			(layers "F.Cu" "F.Mask" "F.Paste")
			(net "M_C_CPU0_SA_DQ<30>")
		)
		(pad "AH57" smd circle
			(at 18.010124 -14.940026 180)
			(size 0.450088 0.450088)
			(layers "F.Cu" "F.Mask" "F.Paste")
			(net "GND")
		)
		(pad "AH58" smd circle
			(at 18.949924 -14.940026 180)
			(size 0.450088 0.450088)
			(layers "F.Cu" "F.Mask" "F.Paste")
			(net "M_D_CPU0_SA_DQ<29>")
		)
		(pad "AH59" smd circle
			(at 19.889978 -14.940026 180)
			(size 0.450088 0.450088)
			(layers "F.Cu" "F.Mask" "F.Paste")
			(net "GND")
		)
		(pad "AH60" smd circle
			(at 20.830032 -14.940026 180)
			(size 0.450088 0.450088)
			(layers "F.Cu" "F.Mask" "F.Paste")
			(net "M_D_CPU0_SA_DQ<30>")
		)
		(pad "AH61" smd circle
			(at 21.770086 -14.940026 180)
			(size 0.450088 0.450088)
			(layers "F.Cu" "F.Mask" "F.Paste")
			(net "GND")
		)
		(pad "AH62" smd circle
			(at 22.709886 -14.940026 180)
			(size 0.450088 0.450088)
			(layers "F.Cu" "F.Mask" "F.Paste")
			(net "M_B_CPU0_SA_DQ<29>")
		)
		(pad "AH63" smd circle
			(at 23.64994 -14.940026 180)
			(size 0.450088 0.450088)
			(layers "F.Cu" "F.Mask" "F.Paste")
			(net "M_B_CPU0_SA_DQ<30>")
		)
		(pad "AH64" smd circle
			(at 24.589994 -14.940026 180)
			(size 0.450088 0.450088)
			(layers "F.Cu" "F.Mask" "F.Paste")
			(net "GND")
		)
		(pad "AH65" smd circle
			(at 25.530048 -14.940026 180)
			(size 0.450088 0.450088)
			(layers "F.Cu" "F.Mask" "F.Paste")
			(net "M_F_CPU0_SA_DQ<29>")
		)
		(pad "AH66" smd circle
			(at 26.470102 -14.940026 180)
			(size 0.450088 0.450088)
			(layers "F.Cu" "F.Mask" "F.Paste")
			(net "GND")
		)
		(pad "AH67" smd circle
			(at 27.409902 -14.940026 180)
			(size 0.450088 0.450088)
			(layers "F.Cu" "F.Mask" "F.Paste")
			(net "M_F_CPU0_SA_DQ<30>")
		)
		(pad "AH68" smd circle
			(at 28.349956 -14.940026 180)
			(size 0.450088 0.450088)
			(layers "F.Cu" "F.Mask" "F.Paste")
			(net "GND")
		)
		(pad "AH69" smd circle
			(at 29.29001 -14.940026 180)
			(size 0.450088 0.450088)
			(layers "F.Cu" "F.Mask" "F.Paste")
			(net "M_E_CPU0_SA_DQ<29>")
		)
		(pad "AH70" smd circle
			(at 30.230064 -14.940026 180)
			(size 0.450088 0.450088)
			(layers "F.Cu" "F.Mask" "F.Paste")
			(net "M_E_CPU0_SA_DQ<30>")
		)
		(pad "AH71" smd circle
			(at 31.170118 -14.940026 180)
			(size 0.450088 0.450088)
			(layers "F.Cu" "F.Mask" "F.Paste")
			(net "GND")
		)
		(pad "AH72" smd circle
			(at 32.109918 -14.940026 180)
			(size 0.450088 0.450088)
			(layers "F.Cu" "F.Mask" "F.Paste")
			(net "M_A_CPU0_SA_DQ<29>")
		)
		(pad "AH73" smd circle
			(at 33.049972 -14.940026 180)
			(size 0.450088 0.450088)
			(layers "F.Cu" "F.Mask" "F.Paste")
			(net "GND")
		)
		(pad "AH74" smd circle
			(at 33.990026 -14.940026 180)
			(size 0.450088 0.450088)
			(layers "F.Cu" "F.Mask" "F.Paste")
			(net "M_A_CPU0_SA_DQ<30>")
		)
		(pad "AJ1" smd circle
			(at -34.159952 -14.13002 180)
			(size 0.450088 0.450088)
			(layers "F.Cu" "F.Mask" "F.Paste")
			(net "GND")
		)
		(pad "AJ2" smd circle
			(at -33.219898 -14.13002 180)
			(size 0.450088 0.450088)
			(layers "F.Cu" "F.Mask" "F.Paste")
			(net "M_G_CPU0_SA_CB<0>")
		)
		(pad "AJ3" smd circle
			(at -32.280098 -14.13002 180)
			(size 0.450088 0.450088)
			(layers "F.Cu" "F.Mask" "F.Paste")
			(net "M_G_CPU0_SA_DQ<31>")
		)
		(pad "AJ4" smd circle
			(at -31.340044 -14.13002 180)
			(size 0.450088 0.450088)
			(layers "F.Cu" "F.Mask" "F.Paste")
			(net "PVDDCR_SOC_P0")
		)
		(pad "AJ5" smd circle
			(at -30.39999 -14.13002 180)
			(size 0.450088 0.450088)
			(layers "F.Cu" "F.Mask" "F.Paste")
			(net "M_K_CPU0_SA_CB<0>")
		)
		(pad "AJ6" smd circle
			(at -29.459936 -14.13002 180)
			(size 0.450088 0.450088)
			(layers "F.Cu" "F.Mask" "F.Paste")
			(net "GND")
		)
		(pad "AJ7" smd circle
			(at -28.519882 -14.13002 180)
			(size 0.450088 0.450088)
			(layers "F.Cu" "F.Mask" "F.Paste")
			(net "M_K_CPU0_SA_DQ<31>")
		)
		(pad "AJ8" smd circle
			(at -27.580082 -14.13002 180)
			(size 0.450088 0.450088)
			(layers "F.Cu" "F.Mask" "F.Paste")
			(net "GND")
		)
		(pad "AJ9" smd circle
			(at -26.640028 -14.13002 180)
			(size 0.450088 0.450088)
			(layers "F.Cu" "F.Mask" "F.Paste")
			(net "M_L_CPU0_SA_CB<0>")
		)
		(pad "AJ10" smd circle
			(at -25.699974 -14.13002 180)
			(size 0.450088 0.450088)
			(layers "F.Cu" "F.Mask" "F.Paste")
			(net "M_L_CPU0_SA_DQ<31>")
		)
		(pad "AJ11" smd circle
			(at -24.75992 -14.13002 180)
			(size 0.450088 0.450088)
			(layers "F.Cu" "F.Mask" "F.Paste")
			(net "PVDDCR_SOC_P0")
		)
		(pad "AJ12" smd circle
			(at -23.82012 -14.13002 180)
			(size 0.450088 0.450088)
			(layers "F.Cu" "F.Mask" "F.Paste")
			(net "M_H_CPU0_SA_CB<0>")
		)
		(pad "AJ13" smd circle
			(at -22.880066 -14.13002 180)
			(size 0.450088 0.450088)
			(layers "F.Cu" "F.Mask" "F.Paste")
			(net "GND")
		)
		(pad "AJ14" smd circle
			(at -21.940012 -14.13002 180)
			(size 0.450088 0.450088)
			(layers "F.Cu" "F.Mask" "F.Paste")
			(net "M_H_CPU0_SA_DQ<31>")
		)
		(pad "AJ15" smd circle
			(at -20.999958 -14.13002 180)
			(size 0.450088 0.450088)
			(layers "F.Cu" "F.Mask" "F.Paste")
			(net "GND")
		)
		(pad "AJ16" smd circle
			(at -20.059904 -14.13002 180)
			(size 0.450088 0.450088)
			(layers "F.Cu" "F.Mask" "F.Paste")
			(net "M_J_CPU0_SA_CB<0>")
		)
		(pad "AJ17" smd circle
			(at -19.120104 -14.13002 180)
			(size 0.450088 0.450088)
			(layers "F.Cu" "F.Mask" "F.Paste")
			(net "M_J_CPU0_SA_DQ<31>")
		)
		(pad "AJ18" smd circle
			(at -18.18005 -14.13002 180)
			(size 0.450088 0.450088)
			(layers "F.Cu" "F.Mask" "F.Paste")
			(net "PVDDCR_SOC_P0")
		)
		(pad "AJ19" smd circle
			(at -17.239996 -14.13002 180)
			(size 0.450088 0.450088)
			(layers "F.Cu" "F.Mask" "F.Paste")
			(net "M_I_CPU0_SA_CB<0>")
		)
		(pad "AJ20" smd circle
			(at -16.299942 -14.13002 180)
			(size 0.450088 0.450088)
			(layers "F.Cu" "F.Mask" "F.Paste")
			(net "GND")
		)
		(pad "AJ21" smd circle
			(at -15.359888 -14.13002 180)
			(size 0.450088 0.450088)
			(layers "F.Cu" "F.Mask" "F.Paste")
			(net "M_I_CPU0_SA_DQ<31>")
		)
		(pad "AJ22" smd circle
			(at -14.420088 -14.13002 180)
			(size 0.450088 0.450088)
			(layers "F.Cu" "F.Mask" "F.Paste")
			(net "GND")
		)
		(pad "AJ23" smd circle
			(at -13.480034 -14.13002 180)
			(size 0.450088 0.450088)
			(layers "F.Cu" "F.Mask" "F.Paste")
			(net "P5E_CPU0_G3_RX_DN<1>")
		)
		(pad "AJ24" smd circle
			(at -12.53998 -14.13002 180)
			(size 0.450088 0.450088)
			(layers "F.Cu" "F.Mask" "F.Paste")
			(net "P5E_CPU0_G3_RX_DP<1>")
		)
		(pad "AJ25" smd circle
			(at -11.599926 -14.13002 180)
			(size 0.450088 0.450088)
			(layers "F.Cu" "F.Mask" "F.Paste")
			(net "GND")
		)
		(pad "AJ26" smd circle
			(at -10.659872 -14.13002 180)
			(size 0.450088 0.450088)
			(layers "F.Cu" "F.Mask" "F.Paste")
			(net "P5E_CPU0_G3_RX_DN<4>")
		)
		(pad "AJ27" smd circle
			(at -9.720072 -14.13002 180)
			(size 0.450088 0.450088)
			(layers "F.Cu" "F.Mask" "F.Paste")
			(net "P5E_CPU0_G3_RX_DP<4>")
		)
		(pad "AJ28" smd circle
			(at -8.780018 -14.13002 180)
			(size 0.450088 0.450088)
			(layers "F.Cu" "F.Mask" "F.Paste")
			(net "GND")
		)
		(pad "AJ29" smd circle
			(at -7.839964 -14.13002 180)
			(size 0.450088 0.450088)
			(layers "F.Cu" "F.Mask" "F.Paste")
			(net "P5E_CPU0_G3_RX_DN<7>")
		)
		(pad "AJ30" smd circle
			(at -6.89991 -14.13002 180)
			(size 0.450088 0.450088)
			(layers "F.Cu" "F.Mask" "F.Paste")
			(net "P5E_CPU0_G3_RX_DP<7>")
		)
		(pad "AJ31" smd circle
			(at -5.96011 -14.13002 180)
			(size 0.450088 0.450088)
			(layers "F.Cu" "F.Mask" "F.Paste")
			(net "GND")
		)
		(pad "AJ32" smd circle
			(at -5.020056 -14.13002 180)
			(size 0.450088 0.450088)
			(layers "F.Cu" "F.Mask" "F.Paste")
			(net "P5E_CPU0_G3_RX_DN<10>")
		)
		(pad "AJ33" smd circle
			(at -4.080002 -14.13002 180)
			(size 0.450088 0.450088)
			(layers "F.Cu" "F.Mask" "F.Paste")
			(net "P5E_CPU0_G3_RX_DP<10>")
		)
		(pad "AJ34" smd circle
			(at -3.139948 -14.13002 180)
			(size 0.450088 0.450088)
			(layers "F.Cu" "F.Mask" "F.Paste")
			(net "GND")
		)
		(pad "AJ35" smd circle
			(at -2.199894 -14.13002 180)
			(size 0.450088 0.450088)
			(layers "F.Cu" "F.Mask" "F.Paste")
			(net "GND")
		)
		(pad "AJ36" smd circle
			(at -1.260094 -14.13002 180)
			(size 0.450088 0.450088)
			(layers "F.Cu" "F.Mask" "F.Paste")
			(net "GND")
		)
		(pad "AJ40" smd circle
			(at 1.560068 -14.13002 180)
			(size 0.450088 0.450088)
			(layers "F.Cu" "F.Mask" "F.Paste")
			(net "GND")
		)
		(pad "AJ41" smd circle
			(at 2.500122 -14.13002 180)
			(size 0.450088 0.450088)
			(layers "F.Cu" "F.Mask" "F.Paste")
			(net "GND")
		)
		(pad "AJ42" smd circle
			(at 3.439922 -14.13002 180)
			(size 0.450088 0.450088)
			(layers "F.Cu" "F.Mask" "F.Paste")
			(net "GND")
		)
		(pad "AJ43" smd circle
			(at 4.379976 -14.13002 180)
			(size 0.450088 0.450088)
			(layers "F.Cu" "F.Mask" "F.Paste")
			(net "GMI_CPU0_G1_CPU1_G3_TX_DP<5>")
		)
		(pad "AJ44" smd circle
			(at 5.32003 -14.13002 180)
			(size 0.450088 0.450088)
			(layers "F.Cu" "F.Mask" "F.Paste")
			(net "GMI_CPU0_G1_CPU1_G3_TX_DN<5>")
		)
		(pad "AJ45" smd circle
			(at 6.260084 -14.13002 180)
			(size 0.450088 0.450088)
			(layers "F.Cu" "F.Mask" "F.Paste")
			(net "GND")
		)
		(pad "AJ46" smd circle
			(at 7.199884 -14.13002 180)
			(size 0.450088 0.450088)
			(layers "F.Cu" "F.Mask" "F.Paste")
			(net "GMI_CPU0_G1_CPU1_G3_TX_DP<8>")
		)
		(pad "AJ47" smd circle
			(at 8.139938 -14.13002 180)
			(size 0.450088 0.450088)
			(layers "F.Cu" "F.Mask" "F.Paste")
			(net "GMI_CPU0_G1_CPU1_G3_TX_DN<8>")
		)
		(pad "AJ48" smd circle
			(at 9.079992 -14.13002 180)
			(size 0.450088 0.450088)
			(layers "F.Cu" "F.Mask" "F.Paste")
			(net "GND")
		)
		(pad "AJ49" smd circle
			(at 10.020046 -14.13002 180)
			(size 0.450088 0.450088)
			(layers "F.Cu" "F.Mask" "F.Paste")
			(net "GMI_CPU0_G1_CPU1_G3_TX_DP<11>")
		)
		(pad "AJ50" smd circle
			(at 10.9601 -14.13002 180)
			(size 0.450088 0.450088)
			(layers "F.Cu" "F.Mask" "F.Paste")
			(net "GMI_CPU0_G1_CPU1_G3_TX_DN<11>")
		)
		(pad "AJ51" smd circle
			(at 11.8999 -14.13002 180)
			(size 0.450088 0.450088)
			(layers "F.Cu" "F.Mask" "F.Paste")
			(net "GND")
		)
		(pad "AJ52" smd circle
			(at 12.839954 -14.13002 180)
			(size 0.450088 0.450088)
			(layers "F.Cu" "F.Mask" "F.Paste")
			(net "GMI_CPU0_G1_CPU1_G3_TX_DP<14>")
		)
		(pad "AJ53" smd circle
			(at 13.780008 -14.13002 180)
			(size 0.450088 0.450088)
			(layers "F.Cu" "F.Mask" "F.Paste")
			(net "GMI_CPU0_G1_CPU1_G3_TX_DN<14>")
		)
		(pad "AJ54" smd circle
			(at 14.720062 -14.13002 180)
			(size 0.450088 0.450088)
			(layers "F.Cu" "F.Mask" "F.Paste")
			(net "GND")
		)
		(pad "AJ55" smd circle
			(at 15.660116 -14.13002 180)
			(size 0.450088 0.450088)
			(layers "F.Cu" "F.Mask" "F.Paste")
			(net "M_C_CPU0_SA_DQ<31>")
		)
		(pad "AJ56" smd circle
			(at 16.599916 -14.13002 180)
			(size 0.450088 0.450088)
			(layers "F.Cu" "F.Mask" "F.Paste")
			(net "GND")
		)
		(pad "AJ57" smd circle
			(at 17.53997 -14.13002 180)
			(size 0.450088 0.450088)
			(layers "F.Cu" "F.Mask" "F.Paste")
			(net "M_C_CPU0_SA_CB<0>")
		)
		(pad "AJ58" smd circle
			(at 18.480024 -14.13002 180)
			(size 0.450088 0.450088)
			(layers "F.Cu" "F.Mask" "F.Paste")
			(net "PVDDIO_P0")
		)
		(pad "AJ59" smd circle
			(at 19.420078 -14.13002 180)
			(size 0.450088 0.450088)
			(layers "F.Cu" "F.Mask" "F.Paste")
			(net "M_D_CPU0_SA_DQ<31>")
		)
		(pad "AJ60" smd circle
			(at 20.359878 -14.13002 180)
			(size 0.450088 0.450088)
			(layers "F.Cu" "F.Mask" "F.Paste")
			(net "M_D_CPU0_SA_CB<0>")
		)
		(pad "AJ61" smd circle
			(at 21.299932 -14.13002 180)
			(size 0.450088 0.450088)
			(layers "F.Cu" "F.Mask" "F.Paste")
			(net "GND")
		)
		(pad "AJ62" smd circle
			(at 22.239986 -14.13002 180)
			(size 0.450088 0.450088)
			(layers "F.Cu" "F.Mask" "F.Paste")
			(net "M_B_CPU0_SA_DQ<31>")
		)
		(pad "AJ63" smd circle
			(at 23.18004 -14.13002 180)
			(size 0.450088 0.450088)
			(layers "F.Cu" "F.Mask" "F.Paste")
			(net "GND")
		)
		(pad "AJ64" smd circle
			(at 24.120094 -14.13002 180)
			(size 0.450088 0.450088)
			(layers "F.Cu" "F.Mask" "F.Paste")
			(net "M_B_CPU0_SA_CB<0>")
		)
		(pad "AJ65" smd circle
			(at 25.059894 -14.13002 180)
			(size 0.450088 0.450088)
			(layers "F.Cu" "F.Mask" "F.Paste")
			(net "PVDDIO_P0")
		)
		(pad "AJ66" smd circle
			(at 25.999948 -14.13002 180)
			(size 0.450088 0.450088)
			(layers "F.Cu" "F.Mask" "F.Paste")
			(net "M_F_CPU0_SA_DQ<31>")
		)
		(pad "AJ67" smd circle
			(at 26.940002 -14.13002 180)
			(size 0.450088 0.450088)
			(layers "F.Cu" "F.Mask" "F.Paste")
			(net "M_F_CPU0_SA_CB<0>")
		)
		(pad "AJ68" smd circle
			(at 27.880056 -14.13002 180)
			(size 0.450088 0.450088)
			(layers "F.Cu" "F.Mask" "F.Paste")
			(net "GND")
		)
		(pad "AJ69" smd circle
			(at 28.82011 -14.13002 180)
			(size 0.450088 0.450088)
			(layers "F.Cu" "F.Mask" "F.Paste")
			(net "M_E_CPU0_SA_DQ<31>")
		)
		(pad "AJ70" smd circle
			(at 29.75991 -14.13002 180)
			(size 0.450088 0.450088)
			(layers "F.Cu" "F.Mask" "F.Paste")
			(net "GND")
		)
		(pad "AJ71" smd circle
			(at 30.699964 -14.13002 180)
			(size 0.450088 0.450088)
			(layers "F.Cu" "F.Mask" "F.Paste")
			(net "M_E_CPU0_SA_CB<0>")
		)
		(pad "AJ72" smd circle
			(at 31.640018 -14.13002 180)
			(size 0.450088 0.450088)
			(layers "F.Cu" "F.Mask" "F.Paste")
			(net "PVDDIO_P0")
		)
		(pad "AJ73" smd circle
			(at 32.580072 -14.13002 180)
			(size 0.450088 0.450088)
			(layers "F.Cu" "F.Mask" "F.Paste")
			(net "M_A_CPU0_SA_DQ<31>")
		)
		(pad "AJ74" smd circle
			(at 33.519872 -14.13002 180)
			(size 0.450088 0.450088)
			(layers "F.Cu" "F.Mask" "F.Paste")
			(net "M_A_CPU0_SA_CB<0>")
		)
		(pad "AJ75" smd circle
			(at 34.459926 -14.13002 180)
			(size 0.450088 0.450088)
			(layers "F.Cu" "F.Mask" "F.Paste")
			(net "GND")
		)
		(pad "AK2" smd circle
			(at -33.690052 -13.320014 180)
			(size 0.450088 0.450088)
			(layers "F.Cu" "F.Mask" "F.Paste")
			(net "M_G_CPU0_SA_CB<2>")
		)
		(pad "AK3" smd circle
			(at -32.749998 -13.320014 180)
			(size 0.450088 0.450088)
			(layers "F.Cu" "F.Mask" "F.Paste")
			(net "GND")
		)
		(pad "AK4" smd circle
			(at -31.809944 -13.320014 180)
			(size 0.450088 0.450088)
			(layers "F.Cu" "F.Mask" "F.Paste")
			(net "M_G_CPU0_SA_CB<1>")
		)
		(pad "AK5" smd circle
			(at -30.86989 -13.320014 180)
			(size 0.450088 0.450088)
			(layers "F.Cu" "F.Mask" "F.Paste")
			(net "GND")
		)
		(pad "AK6" smd circle
			(at -29.93009 -13.320014 180)
			(size 0.450088 0.450088)
			(layers "F.Cu" "F.Mask" "F.Paste")
			(net "M_K_CPU0_SA_CB<2>")
		)
		(pad "AK7" smd circle
			(at -28.990036 -13.320014 180)
			(size 0.450088 0.450088)
			(layers "F.Cu" "F.Mask" "F.Paste")
			(net "M_K_CPU0_SA_CB<1>")
		)
		(pad "AK8" smd circle
			(at -28.049982 -13.320014 180)
			(size 0.450088 0.450088)
			(layers "F.Cu" "F.Mask" "F.Paste")
			(net "GND")
		)
		(pad "AK9" smd circle
			(at -27.109928 -13.320014 180)
			(size 0.450088 0.450088)
			(layers "F.Cu" "F.Mask" "F.Paste")
			(net "M_L_CPU0_SA_CB<2>")
		)
		(pad "AK10" smd circle
			(at -26.170128 -13.320014 180)
			(size 0.450088 0.450088)
			(layers "F.Cu" "F.Mask" "F.Paste")
			(net "GND")
		)
		(pad "AK11" smd circle
			(at -25.230074 -13.320014 180)
			(size 0.450088 0.450088)
			(layers "F.Cu" "F.Mask" "F.Paste")
			(net "M_L_CPU0_SA_CB<1>")
		)
		(pad "AK12" smd circle
			(at -24.29002 -13.320014 180)
			(size 0.450088 0.450088)
			(layers "F.Cu" "F.Mask" "F.Paste")
			(net "GND")
		)
		(pad "AK13" smd circle
			(at -23.349966 -13.320014 180)
			(size 0.450088 0.450088)
			(layers "F.Cu" "F.Mask" "F.Paste")
			(net "M_H_CPU0_SA_CB<2>")
		)
		(pad "AK14" smd circle
			(at -22.409912 -13.320014 180)
			(size 0.450088 0.450088)
			(layers "F.Cu" "F.Mask" "F.Paste")
			(net "M_H_CPU0_SA_CB<1>")
		)
		(pad "AK15" smd circle
			(at -21.470112 -13.320014 180)
			(size 0.450088 0.450088)
			(layers "F.Cu" "F.Mask" "F.Paste")
			(net "GND")
		)
		(pad "AK16" smd circle
			(at -20.530058 -13.320014 180)
			(size 0.450088 0.450088)
			(layers "F.Cu" "F.Mask" "F.Paste")
			(net "M_J_CPU0_SA_CB<2>")
		)
		(pad "AK17" smd circle
			(at -19.590004 -13.320014 180)
			(size 0.450088 0.450088)
			(layers "F.Cu" "F.Mask" "F.Paste")
			(net "GND")
		)
		(pad "AK18" smd circle
			(at -18.64995 -13.320014 180)
			(size 0.450088 0.450088)
			(layers "F.Cu" "F.Mask" "F.Paste")
			(net "M_J_CPU0_SA_CB<1>")
		)
		(pad "AK19" smd circle
			(at -17.709896 -13.320014 180)
			(size 0.450088 0.450088)
			(layers "F.Cu" "F.Mask" "F.Paste")
			(net "GND")
		)
		(pad "AK20" smd circle
			(at -16.770096 -13.320014 180)
			(size 0.450088 0.450088)
			(layers "F.Cu" "F.Mask" "F.Paste")
			(net "M_I_CPU0_SA_CB<2>")
		)
		(pad "AK21" smd circle
			(at -15.830042 -13.320014 180)
			(size 0.450088 0.450088)
			(layers "F.Cu" "F.Mask" "F.Paste")
			(net "M_I_CPU0_SA_CB<1>")
		)
		(pad "AK22" smd circle
			(at -14.889988 -13.320014 180)
			(size 0.450088 0.450088)
			(layers "F.Cu" "F.Mask" "F.Paste")
			(net "GND")
		)
		(pad "AK23" smd circle
			(at -13.949934 -13.320014 180)
			(size 0.450088 0.450088)
			(layers "F.Cu" "F.Mask" "F.Paste")
			(net "PVDDCR_CPU0_P0")
		)
		(pad "AK24" smd circle
			(at -13.00988 -13.320014 180)
			(size 0.450088 0.450088)
			(layers "F.Cu" "F.Mask" "F.Paste")
			(net "PVDDCR_CPU0_P0")
		)
		(pad "AK25" smd circle
			(at -12.07008 -13.320014 180)
			(size 0.450088 0.450088)
			(layers "F.Cu" "F.Mask" "F.Paste")
			(net "GND")
		)
		(pad "AK26" smd circle
			(at -11.130026 -13.320014 180)
			(size 0.450088 0.450088)
			(layers "F.Cu" "F.Mask" "F.Paste")
			(net "PVDDCR_CPU0_P0")
		)
		(pad "AK27" smd circle
			(at -10.189972 -13.320014 180)
			(size 0.450088 0.450088)
			(layers "F.Cu" "F.Mask" "F.Paste")
			(net "PVDDCR_CPU0_P0")
		)
		(pad "AK28" smd circle
			(at -9.249918 -13.320014 180)
			(size 0.450088 0.450088)
			(layers "F.Cu" "F.Mask" "F.Paste")
			(net "GND")
		)
		(pad "AK29" smd circle
			(at -8.310118 -13.320014 180)
			(size 0.450088 0.450088)
			(layers "F.Cu" "F.Mask" "F.Paste")
			(net "PVDDCR_CPU0_P0")
		)
		(pad "AK30" smd circle
			(at -7.370064 -13.320014 180)
			(size 0.450088 0.450088)
			(layers "F.Cu" "F.Mask" "F.Paste")
			(net "PVDDCR_CPU0_P0")
		)
		(pad "AK31" smd circle
			(at -6.43001 -13.320014 180)
			(size 0.450088 0.450088)
			(layers "F.Cu" "F.Mask" "F.Paste")
			(net "GND")
		)
		(pad "AK32" smd circle
			(at -5.489956 -13.320014 180)
			(size 0.450088 0.450088)
			(layers "F.Cu" "F.Mask" "F.Paste")
			(net "PVDDCR_CPU0_P0")
		)
		(pad "AK33" smd circle
			(at -4.549902 -13.320014 180)
			(size 0.450088 0.450088)
			(layers "F.Cu" "F.Mask" "F.Paste")
			(net "PVDDCR_CPU0_P0")
		)
		(pad "AK34" smd circle
			(at -3.610102 -13.320014 180)
			(size 0.450088 0.450088)
			(layers "F.Cu" "F.Mask" "F.Paste")
			(net "GND")
		)
		(pad "AK35" smd circle
			(at -2.670048 -13.320014 180)
			(size 0.450088 0.450088)
			(layers "F.Cu" "F.Mask" "F.Paste")
			(net "P5E_CPU0_G3_RX_DN<12>")
		)
		(pad "AK36" smd circle
			(at -1.729994 -13.320014 180)
			(size 0.450088 0.450088)
			(layers "F.Cu" "F.Mask" "F.Paste")
			(net "P5E_CPU0_G3_RX_DP<12>")
		)
		(pad "AK37" smd circle
			(at -0.78994 -13.320014 180)
			(size 0.450088 0.450088)
			(layers "F.Cu" "F.Mask" "F.Paste")
			(net "GND")
		)
		(pad "AK39" smd circle
			(at 1.089914 -13.320014 180)
			(size 0.450088 0.450088)
			(layers "F.Cu" "F.Mask" "F.Paste")
			(net "GND")
		)
		(pad "AK40" smd circle
			(at 2.029968 -13.320014 180)
			(size 0.450088 0.450088)
			(layers "F.Cu" "F.Mask" "F.Paste")
			(net "GMI_CPU0_G1_CPU1_G3_TX_DP<3>")
		)
		(pad "AK41" smd circle
			(at 2.970022 -13.320014 180)
			(size 0.450088 0.450088)
			(layers "F.Cu" "F.Mask" "F.Paste")
			(net "GMI_CPU0_G1_CPU1_G3_TX_DN<3>")
		)
		(pad "AK42" smd circle
			(at 3.910076 -13.320014 180)
			(size 0.450088 0.450088)
			(layers "F.Cu" "F.Mask" "F.Paste")
			(net "GND")
		)
		(pad "AK43" smd circle
			(at 4.849876 -13.320014 180)
			(size 0.450088 0.450088)
			(layers "F.Cu" "F.Mask" "F.Paste")
			(net "PVDDCR_CPU0_P0")
		)
		(pad "AK44" smd circle
			(at 5.78993 -13.320014 180)
			(size 0.450088 0.450088)
			(layers "F.Cu" "F.Mask" "F.Paste")
			(net "PVDDCR_CPU0_P0")
		)
		(pad "AK45" smd circle
			(at 6.729984 -13.320014 180)
			(size 0.450088 0.450088)
			(layers "F.Cu" "F.Mask" "F.Paste")
			(net "GND")
		)
		(pad "AK46" smd circle
			(at 7.670038 -13.320014 180)
			(size 0.450088 0.450088)
			(layers "F.Cu" "F.Mask" "F.Paste")
			(net "PVDDCR_CPU0_P0")
		)
		(pad "AK47" smd circle
			(at 8.610092 -13.320014 180)
			(size 0.450088 0.450088)
			(layers "F.Cu" "F.Mask" "F.Paste")
			(net "PVDDCR_CPU0_P0")
		)
		(pad "AK48" smd circle
			(at 9.549892 -13.320014 180)
			(size 0.450088 0.450088)
			(layers "F.Cu" "F.Mask" "F.Paste")
			(net "GND")
		)
		(pad "AK49" smd circle
			(at 10.489946 -13.320014 180)
			(size 0.450088 0.450088)
			(layers "F.Cu" "F.Mask" "F.Paste")
			(net "PVDDCR_CPU0_P0")
		)
		(pad "AK50" smd circle
			(at 11.43 -13.320014 180)
			(size 0.450088 0.450088)
			(layers "F.Cu" "F.Mask" "F.Paste")
			(net "PVDDCR_CPU0_P0")
		)
		(pad "AK51" smd circle
			(at 12.370054 -13.320014 180)
			(size 0.450088 0.450088)
			(layers "F.Cu" "F.Mask" "F.Paste")
			(net "GND")
		)
		(pad "AK52" smd circle
			(at 13.310108 -13.320014 180)
			(size 0.450088 0.450088)
			(layers "F.Cu" "F.Mask" "F.Paste")
			(net "PVDDCR_CPU0_P0")
		)
		(pad "AK53" smd circle
			(at 14.249908 -13.320014 180)
			(size 0.450088 0.450088)
			(layers "F.Cu" "F.Mask" "F.Paste")
			(net "PVDDCR_CPU0_P0")
		)
		(pad "AK54" smd circle
			(at 15.189962 -13.320014 180)
			(size 0.450088 0.450088)
			(layers "F.Cu" "F.Mask" "F.Paste")
			(net "GND")
		)
		(pad "AK55" smd circle
			(at 16.130016 -13.320014 180)
			(size 0.450088 0.450088)
			(layers "F.Cu" "F.Mask" "F.Paste")
			(net "M_C_CPU0_SA_CB<1>")
		)
		(pad "AK56" smd circle
			(at 17.07007 -13.320014 180)
			(size 0.450088 0.450088)
			(layers "F.Cu" "F.Mask" "F.Paste")
			(net "M_C_CPU0_SA_CB<2>")
		)
		(pad "AK57" smd circle
			(at 18.010124 -13.320014 180)
			(size 0.450088 0.450088)
			(layers "F.Cu" "F.Mask" "F.Paste")
			(net "GND")
		)
		(pad "AK58" smd circle
			(at 18.949924 -13.320014 180)
			(size 0.450088 0.450088)
			(layers "F.Cu" "F.Mask" "F.Paste")
			(net "M_D_CPU0_SA_CB<1>")
		)
		(pad "AK59" smd circle
			(at 19.889978 -13.320014 180)
			(size 0.450088 0.450088)
			(layers "F.Cu" "F.Mask" "F.Paste")
			(net "GND")
		)
		(pad "AK60" smd circle
			(at 20.830032 -13.320014 180)
			(size 0.450088 0.450088)
			(layers "F.Cu" "F.Mask" "F.Paste")
			(net "M_D_CPU0_SA_CB<2>")
		)
		(pad "AK61" smd circle
			(at 21.770086 -13.320014 180)
			(size 0.450088 0.450088)
			(layers "F.Cu" "F.Mask" "F.Paste")
			(net "GND")
		)
		(pad "AK62" smd circle
			(at 22.709886 -13.320014 180)
			(size 0.450088 0.450088)
			(layers "F.Cu" "F.Mask" "F.Paste")
			(net "M_B_CPU0_SA_CB<1>")
		)
		(pad "AK63" smd circle
			(at 23.64994 -13.320014 180)
			(size 0.450088 0.450088)
			(layers "F.Cu" "F.Mask" "F.Paste")
			(net "M_B_CPU0_SA_CB<2>")
		)
		(pad "AK64" smd circle
			(at 24.589994 -13.320014 180)
			(size 0.450088 0.450088)
			(layers "F.Cu" "F.Mask" "F.Paste")
			(net "GND")
		)
		(pad "AK65" smd circle
			(at 25.530048 -13.320014 180)
			(size 0.450088 0.450088)
			(layers "F.Cu" "F.Mask" "F.Paste")
			(net "M_F_CPU0_SA_CB<1>")
		)
		(pad "AK66" smd circle
			(at 26.470102 -13.320014 180)
			(size 0.450088 0.450088)
			(layers "F.Cu" "F.Mask" "F.Paste")
			(net "GND")
		)
		(pad "AK67" smd circle
			(at 27.409902 -13.320014 180)
			(size 0.450088 0.450088)
			(layers "F.Cu" "F.Mask" "F.Paste")
			(net "M_F_CPU0_SA_CB<2>")
		)
		(pad "AK68" smd circle
			(at 28.349956 -13.320014 180)
			(size 0.450088 0.450088)
			(layers "F.Cu" "F.Mask" "F.Paste")
			(net "GND")
		)
		(pad "AK69" smd circle
			(at 29.29001 -13.320014 180)
			(size 0.450088 0.450088)
			(layers "F.Cu" "F.Mask" "F.Paste")
			(net "M_E_CPU0_SA_CB<1>")
		)
		(pad "AK70" smd circle
			(at 30.230064 -13.320014 180)
			(size 0.450088 0.450088)
			(layers "F.Cu" "F.Mask" "F.Paste")
			(net "M_E_CPU0_SA_CB<2>")
		)
		(pad "AK71" smd circle
			(at 31.170118 -13.320014 180)
			(size 0.450088 0.450088)
			(layers "F.Cu" "F.Mask" "F.Paste")
			(net "GND")
		)
		(pad "AK72" smd circle
			(at 32.109918 -13.320014 180)
			(size 0.450088 0.450088)
			(layers "F.Cu" "F.Mask" "F.Paste")
			(net "M_A_CPU0_SA_CB<1>")
		)
		(pad "AK73" smd circle
			(at 33.049972 -13.320014 180)
			(size 0.450088 0.450088)
			(layers "F.Cu" "F.Mask" "F.Paste")
			(net "GND")
		)
		(pad "AK74" smd circle
			(at 33.990026 -13.320014 180)
			(size 0.450088 0.450088)
			(layers "F.Cu" "F.Mask" "F.Paste")
			(net "M_A_CPU0_SA_CB<2>")
		)
		(pad "AL1" smd circle
			(at -34.159952 -12.510008 180)
			(size 0.450088 0.450088)
			(layers "F.Cu" "F.Mask" "F.Paste")
			(net "GND")
		)
		(pad "AL2" smd circle
			(at -33.219898 -12.510008 180)
			(size 0.450088 0.450088)
			(layers "F.Cu" "F.Mask" "F.Paste")
			(net "M_G_CPU0_SA_DQS_DP<4>")
		)
		(pad "AL3" smd circle
			(at -32.280098 -12.510008 180)
			(size 0.450088 0.450088)
			(layers "F.Cu" "F.Mask" "F.Paste")
			(net "M_G_CPU0_SA_CB<3>")
		)
		(pad "AL4" smd circle
			(at -31.340044 -12.510008 180)
			(size 0.450088 0.450088)
			(layers "F.Cu" "F.Mask" "F.Paste")
			(net "GND")
		)
		(pad "AL5" smd circle
			(at -30.39999 -12.510008 180)
			(size 0.450088 0.450088)
			(layers "F.Cu" "F.Mask" "F.Paste")
			(net "M_K_CPU0_SA_DQS_DP<4>")
		)
		(pad "AL6" smd circle
			(at -29.459936 -12.510008 180)
			(size 0.450088 0.450088)
			(layers "F.Cu" "F.Mask" "F.Paste")
			(net "GND")
		)
		(pad "AL7" smd circle
			(at -28.519882 -12.510008 180)
			(size 0.450088 0.450088)
			(layers "F.Cu" "F.Mask" "F.Paste")
			(net "M_K_CPU0_SA_CB<3>")
		)
		(pad "AL8" smd circle
			(at -27.580082 -12.510008 180)
			(size 0.450088 0.450088)
			(layers "F.Cu" "F.Mask" "F.Paste")
			(net "GND")
		)
		(pad "AL9" smd circle
			(at -26.640028 -12.510008 180)
			(size 0.450088 0.450088)
			(layers "F.Cu" "F.Mask" "F.Paste")
			(net "M_L_CPU0_SA_DQS_DP<4>")
		)
		(pad "AL10" smd circle
			(at -25.699974 -12.510008 180)
			(size 0.450088 0.450088)
			(layers "F.Cu" "F.Mask" "F.Paste")
			(net "M_L_CPU0_SA_CB<3>")
		)
		(pad "AL11" smd circle
			(at -24.75992 -12.510008 180)
			(size 0.450088 0.450088)
			(layers "F.Cu" "F.Mask" "F.Paste")
			(net "GND")
		)
		(pad "AL12" smd circle
			(at -23.82012 -12.510008 180)
			(size 0.450088 0.450088)
			(layers "F.Cu" "F.Mask" "F.Paste")
			(net "M_H_CPU0_SA_DQS_DP<4>")
		)
		(pad "AL13" smd circle
			(at -22.880066 -12.510008 180)
			(size 0.450088 0.450088)
			(layers "F.Cu" "F.Mask" "F.Paste")
			(net "GND")
		)
		(pad "AL14" smd circle
			(at -21.940012 -12.510008 180)
			(size 0.450088 0.450088)
			(layers "F.Cu" "F.Mask" "F.Paste")
			(net "M_H_CPU0_SA_CB<3>")
		)
		(pad "AL15" smd circle
			(at -20.999958 -12.510008 180)
			(size 0.450088 0.450088)
			(layers "F.Cu" "F.Mask" "F.Paste")
			(net "GND")
		)
		(pad "AL16" smd circle
			(at -20.059904 -12.510008 180)
			(size 0.450088 0.450088)
			(layers "F.Cu" "F.Mask" "F.Paste")
			(net "M_J_CPU0_SA_DQS_DP<4>")
		)
		(pad "AL17" smd circle
			(at -19.120104 -12.510008 180)
			(size 0.450088 0.450088)
			(layers "F.Cu" "F.Mask" "F.Paste")
			(net "M_J_CPU0_SA_CB<3>")
		)
		(pad "AL18" smd circle
			(at -18.18005 -12.510008 180)
			(size 0.450088 0.450088)
			(layers "F.Cu" "F.Mask" "F.Paste")
			(net "GND")
		)
		(pad "AL19" smd circle
			(at -17.239996 -12.510008 180)
			(size 0.450088 0.450088)
			(layers "F.Cu" "F.Mask" "F.Paste")
			(net "M_I_CPU0_SA_DQS_DP<4>")
		)
		(pad "AL20" smd circle
			(at -16.299942 -12.510008 180)
			(size 0.450088 0.450088)
			(layers "F.Cu" "F.Mask" "F.Paste")
			(net "GND")
		)
		(pad "AL21" smd circle
			(at -15.359888 -12.510008 180)
			(size 0.450088 0.450088)
			(layers "F.Cu" "F.Mask" "F.Paste")
			(net "M_I_CPU0_SA_CB<3>")
		)
		(pad "AL22" smd circle
			(at -14.420088 -12.510008 180)
			(size 0.450088 0.450088)
			(layers "F.Cu" "F.Mask" "F.Paste")
			(net "GND")
		)
		(pad "AL23" smd circle
			(at -13.480034 -12.510008 180)
			(size 0.450088 0.450088)
			(layers "F.Cu" "F.Mask" "F.Paste")
			(net "P5E_CPU0_G3_RX_DN<0>")
		)
		(pad "AL24" smd circle
			(at -12.53998 -12.510008 180)
			(size 0.450088 0.450088)
			(layers "F.Cu" "F.Mask" "F.Paste")
			(net "P5E_CPU0_G3_RX_DP<0>")
		)
		(pad "AL25" smd circle
			(at -11.599926 -12.510008 180)
			(size 0.450088 0.450088)
			(layers "F.Cu" "F.Mask" "F.Paste")
			(net "GND")
		)
		(pad "AL26" smd circle
			(at -10.659872 -12.510008 180)
			(size 0.450088 0.450088)
			(layers "F.Cu" "F.Mask" "F.Paste")
			(net "P5E_CPU0_G3_RX_DN<3>")
		)
		(pad "AL27" smd circle
			(at -9.720072 -12.510008 180)
			(size 0.450088 0.450088)
			(layers "F.Cu" "F.Mask" "F.Paste")
			(net "P5E_CPU0_G3_RX_DP<3>")
		)
		(pad "AL28" smd circle
			(at -8.780018 -12.510008 180)
			(size 0.450088 0.450088)
			(layers "F.Cu" "F.Mask" "F.Paste")
			(net "GND")
		)
		(pad "AL29" smd circle
			(at -7.839964 -12.510008 180)
			(size 0.450088 0.450088)
			(layers "F.Cu" "F.Mask" "F.Paste")
			(net "P5E_CPU0_G3_RX_DN<6>")
		)
		(pad "AL30" smd circle
			(at -6.89991 -12.510008 180)
			(size 0.450088 0.450088)
			(layers "F.Cu" "F.Mask" "F.Paste")
			(net "P5E_CPU0_G3_RX_DP<6>")
		)
		(pad "AL31" smd circle
			(at -5.96011 -12.510008 180)
			(size 0.450088 0.450088)
			(layers "F.Cu" "F.Mask" "F.Paste")
			(net "GND")
		)
		(pad "AL32" smd circle
			(at -5.020056 -12.510008 180)
			(size 0.450088 0.450088)
			(layers "F.Cu" "F.Mask" "F.Paste")
			(net "P5E_CPU0_G3_RX_DN<9>")
		)
		(pad "AL33" smd circle
			(at -4.080002 -12.510008 180)
			(size 0.450088 0.450088)
			(layers "F.Cu" "F.Mask" "F.Paste")
			(net "P5E_CPU0_G3_RX_DP<9>")
		)
		(pad "AL34" smd circle
			(at -3.139948 -12.510008 180)
			(size 0.450088 0.450088)
			(layers "F.Cu" "F.Mask" "F.Paste")
			(net "GND")
		)
		(pad "AL35" smd circle
			(at -2.199894 -12.510008 180)
			(size 0.450088 0.450088)
			(layers "F.Cu" "F.Mask" "F.Paste")
			(net "PVDDCR_CPU0_P0")
		)
		(pad "AL36" smd circle
			(at -1.260094 -12.510008 180)
			(size 0.450088 0.450088)
			(layers "F.Cu" "F.Mask" "F.Paste")
			(net "PVDDCR_CPU0_P0")
		)
		(pad "AL40" smd circle
			(at 1.560068 -12.510008 180)
			(size 0.450088 0.450088)
			(layers "F.Cu" "F.Mask" "F.Paste")
			(net "PVDDCR_CPU0_P0")
		)
		(pad "AL41" smd circle
			(at 2.500122 -12.510008 180)
			(size 0.450088 0.450088)
			(layers "F.Cu" "F.Mask" "F.Paste")
			(net "PVDDCR_CPU0_P0")
		)
		(pad "AL42" smd circle
			(at 3.439922 -12.510008 180)
			(size 0.450088 0.450088)
			(layers "F.Cu" "F.Mask" "F.Paste")
			(net "GND")
		)
		(pad "AL43" smd circle
			(at 4.379976 -12.510008 180)
			(size 0.450088 0.450088)
			(layers "F.Cu" "F.Mask" "F.Paste")
			(net "GMI_CPU0_G1_CPU1_G3_TX_DP<6>")
		)
		(pad "AL44" smd circle
			(at 5.32003 -12.510008 180)
			(size 0.450088 0.450088)
			(layers "F.Cu" "F.Mask" "F.Paste")
			(net "GMI_CPU0_G1_CPU1_G3_TX_DN<6>")
		)
		(pad "AL45" smd circle
			(at 6.260084 -12.510008 180)
			(size 0.450088 0.450088)
			(layers "F.Cu" "F.Mask" "F.Paste")
			(net "GND")
		)
		(pad "AL46" smd circle
			(at 7.199884 -12.510008 180)
			(size 0.450088 0.450088)
			(layers "F.Cu" "F.Mask" "F.Paste")
			(net "GMI_CPU0_G1_CPU1_G3_TX_DP<9>")
		)
		(pad "AL47" smd circle
			(at 8.139938 -12.510008 180)
			(size 0.450088 0.450088)
			(layers "F.Cu" "F.Mask" "F.Paste")
			(net "GMI_CPU0_G1_CPU1_G3_TX_DN<9>")
		)
		(pad "AL48" smd circle
			(at 9.079992 -12.510008 180)
			(size 0.450088 0.450088)
			(layers "F.Cu" "F.Mask" "F.Paste")
			(net "GND")
		)
		(pad "AL49" smd circle
			(at 10.020046 -12.510008 180)
			(size 0.450088 0.450088)
			(layers "F.Cu" "F.Mask" "F.Paste")
			(net "GMI_CPU0_G1_CPU1_G3_TX_DP<12>")
		)
		(pad "AL50" smd circle
			(at 10.9601 -12.510008 180)
			(size 0.450088 0.450088)
			(layers "F.Cu" "F.Mask" "F.Paste")
			(net "GMI_CPU0_G1_CPU1_G3_TX_DN<12>")
		)
		(pad "AL51" smd circle
			(at 11.8999 -12.510008 180)
			(size 0.450088 0.450088)
			(layers "F.Cu" "F.Mask" "F.Paste")
			(net "GND")
		)
		(pad "AL52" smd circle
			(at 12.839954 -12.510008 180)
			(size 0.450088 0.450088)
			(layers "F.Cu" "F.Mask" "F.Paste")
			(net "GMI_CPU0_G1_CPU1_G3_TX_DP<15>")
		)
		(pad "AL53" smd circle
			(at 13.780008 -12.510008 180)
			(size 0.450088 0.450088)
			(layers "F.Cu" "F.Mask" "F.Paste")
			(net "GMI_CPU0_G1_CPU1_G3_TX_DN<15>")
		)
		(pad "AL54" smd circle
			(at 14.720062 -12.510008 180)
			(size 0.450088 0.450088)
			(layers "F.Cu" "F.Mask" "F.Paste")
			(net "GND")
		)
		(pad "AL55" smd circle
			(at 15.660116 -12.510008 180)
			(size 0.450088 0.450088)
			(layers "F.Cu" "F.Mask" "F.Paste")
			(net "M_C_CPU0_SA_CB<3>")
		)
		(pad "AL56" smd circle
			(at 16.599916 -12.510008 180)
			(size 0.450088 0.450088)
			(layers "F.Cu" "F.Mask" "F.Paste")
			(net "GND")
		)
		(pad "AL57" smd circle
			(at 17.53997 -12.510008 180)
			(size 0.450088 0.450088)
			(layers "F.Cu" "F.Mask" "F.Paste")
			(net "M_C_CPU0_SA_DQS_DP<4>")
		)
		(pad "AL58" smd circle
			(at 18.480024 -12.510008 180)
			(size 0.450088 0.450088)
			(layers "F.Cu" "F.Mask" "F.Paste")
			(net "GND")
		)
		(pad "AL59" smd circle
			(at 19.420078 -12.510008 180)
			(size 0.450088 0.450088)
			(layers "F.Cu" "F.Mask" "F.Paste")
			(net "M_D_CPU0_SA_CB<3>")
		)
		(pad "AL60" smd circle
			(at 20.359878 -12.510008 180)
			(size 0.450088 0.450088)
			(layers "F.Cu" "F.Mask" "F.Paste")
			(net "M_D_CPU0_SA_DQS_DP<4>")
		)
		(pad "AL61" smd circle
			(at 21.299932 -12.510008 180)
			(size 0.450088 0.450088)
			(layers "F.Cu" "F.Mask" "F.Paste")
			(net "GND")
		)
		(pad "AL62" smd circle
			(at 22.239986 -12.510008 180)
			(size 0.450088 0.450088)
			(layers "F.Cu" "F.Mask" "F.Paste")
			(net "M_B_CPU0_SA_CB<3>")
		)
		(pad "AL63" smd circle
			(at 23.18004 -12.510008 180)
			(size 0.450088 0.450088)
			(layers "F.Cu" "F.Mask" "F.Paste")
			(net "GND")
		)
		(pad "AL64" smd circle
			(at 24.120094 -12.510008 180)
			(size 0.450088 0.450088)
			(layers "F.Cu" "F.Mask" "F.Paste")
			(net "M_B_CPU0_SA_DQS_DP<4>")
		)
		(pad "AL65" smd circle
			(at 25.059894 -12.510008 180)
			(size 0.450088 0.450088)
			(layers "F.Cu" "F.Mask" "F.Paste")
			(net "GND")
		)
		(pad "AL66" smd circle
			(at 25.999948 -12.510008 180)
			(size 0.450088 0.450088)
			(layers "F.Cu" "F.Mask" "F.Paste")
			(net "M_F_CPU0_SA_CB<3>")
		)
		(pad "AL67" smd circle
			(at 26.940002 -12.510008 180)
			(size 0.450088 0.450088)
			(layers "F.Cu" "F.Mask" "F.Paste")
			(net "M_F_CPU0_SA_DQS_DP<4>")
		)
		(pad "AL68" smd circle
			(at 27.880056 -12.510008 180)
			(size 0.450088 0.450088)
			(layers "F.Cu" "F.Mask" "F.Paste")
			(net "GND")
		)
		(pad "AL69" smd circle
			(at 28.82011 -12.510008 180)
			(size 0.450088 0.450088)
			(layers "F.Cu" "F.Mask" "F.Paste")
			(net "M_E_CPU0_SA_CB<3>")
		)
		(pad "AL70" smd circle
			(at 29.75991 -12.510008 180)
			(size 0.450088 0.450088)
			(layers "F.Cu" "F.Mask" "F.Paste")
			(net "GND")
		)
		(pad "AL71" smd circle
			(at 30.699964 -12.510008 180)
			(size 0.450088 0.450088)
			(layers "F.Cu" "F.Mask" "F.Paste")
			(net "M_E_CPU0_SA_DQS_DP<4>")
		)
		(pad "AL72" smd circle
			(at 31.640018 -12.510008 180)
			(size 0.450088 0.450088)
			(layers "F.Cu" "F.Mask" "F.Paste")
			(net "GND")
		)
		(pad "AL73" smd circle
			(at 32.580072 -12.510008 180)
			(size 0.450088 0.450088)
			(layers "F.Cu" "F.Mask" "F.Paste")
			(net "M_A_CPU0_SA_CB<3>")
		)
		(pad "AL74" smd circle
			(at 33.519872 -12.510008 180)
			(size 0.450088 0.450088)
			(layers "F.Cu" "F.Mask" "F.Paste")
			(net "M_A_CPU0_SA_DQS_DP<4>")
		)
		(pad "AL75" smd circle
			(at 34.459926 -12.510008 180)
			(size 0.450088 0.450088)
			(layers "F.Cu" "F.Mask" "F.Paste")
			(net "GND")
		)
		(pad "AM2" smd circle
			(at -33.690052 -11.700002 180)
			(size 0.450088 0.450088)
			(layers "F.Cu" "F.Mask" "F.Paste")
			(net "M_G_CPU0_SA_DQS_DN<4>")
		)
		(pad "AM3" smd circle
			(at -32.749998 -11.700002 180)
			(size 0.450088 0.450088)
			(layers "F.Cu" "F.Mask" "F.Paste")
			(net "GND")
		)
		(pad "AM4" smd circle
			(at -31.809944 -11.700002 180)
			(size 0.450088 0.450088)
			(layers "F.Cu" "F.Mask" "F.Paste")
			(net "M_G_CPU0_SA_DQS_DN<9>")
		)
		(pad "AM5" smd circle
			(at -30.86989 -11.700002 180)
			(size 0.450088 0.450088)
			(layers "F.Cu" "F.Mask" "F.Paste")
			(net "PVDDCR_SOC_P0")
		)
		(pad "AM6" smd circle
			(at -29.93009 -11.700002 180)
			(size 0.450088 0.450088)
			(layers "F.Cu" "F.Mask" "F.Paste")
			(net "M_K_CPU0_SA_DQS_DN<4>")
		)
		(pad "AM7" smd circle
			(at -28.990036 -11.700002 180)
			(size 0.450088 0.450088)
			(layers "F.Cu" "F.Mask" "F.Paste")
			(net "M_K_CPU0_SA_DQS_DN<9>")
		)
		(pad "AM8" smd circle
			(at -28.049982 -11.700002 180)
			(size 0.450088 0.450088)
			(layers "F.Cu" "F.Mask" "F.Paste")
			(net "GND")
		)
		(pad "AM9" smd circle
			(at -27.109928 -11.700002 180)
			(size 0.450088 0.450088)
			(layers "F.Cu" "F.Mask" "F.Paste")
			(net "M_L_CPU0_SA_DQS_DN<4>")
		)
		(pad "AM10" smd circle
			(at -26.170128 -11.700002 180)
			(size 0.450088 0.450088)
			(layers "F.Cu" "F.Mask" "F.Paste")
			(net "GND")
		)
		(pad "AM11" smd circle
			(at -25.230074 -11.700002 180)
			(size 0.450088 0.450088)
			(layers "F.Cu" "F.Mask" "F.Paste")
			(net "M_L_CPU0_SA_DQS_DN<9>")
		)
		(pad "AM12" smd circle
			(at -24.29002 -11.700002 180)
			(size 0.450088 0.450088)
			(layers "F.Cu" "F.Mask" "F.Paste")
			(net "PVDDCR_SOC_P0")
		)
		(pad "AM13" smd circle
			(at -23.349966 -11.700002 180)
			(size 0.450088 0.450088)
			(layers "F.Cu" "F.Mask" "F.Paste")
			(net "M_H_CPU0_SA_DQS_DN<4>")
		)
		(pad "AM14" smd circle
			(at -22.409912 -11.700002 180)
			(size 0.450088 0.450088)
			(layers "F.Cu" "F.Mask" "F.Paste")
			(net "M_H_CPU0_SA_DQS_DN<9>")
		)
		(pad "AM15" smd circle
			(at -21.470112 -11.700002 180)
			(size 0.450088 0.450088)
			(layers "F.Cu" "F.Mask" "F.Paste")
			(net "GND")
		)
		(pad "AM16" smd circle
			(at -20.530058 -11.700002 180)
			(size 0.450088 0.450088)
			(layers "F.Cu" "F.Mask" "F.Paste")
			(net "M_J_CPU0_SA_DQS_DN<4>")
		)
		(pad "AM17" smd circle
			(at -19.590004 -11.700002 180)
			(size 0.450088 0.450088)
			(layers "F.Cu" "F.Mask" "F.Paste")
			(net "GND")
		)
		(pad "AM18" smd circle
			(at -18.64995 -11.700002 180)
			(size 0.450088 0.450088)
			(layers "F.Cu" "F.Mask" "F.Paste")
			(net "M_J_CPU0_SA_DQS_DN<9>")
		)
		(pad "AM19" smd circle
			(at -17.709896 -11.700002 180)
			(size 0.450088 0.450088)
			(layers "F.Cu" "F.Mask" "F.Paste")
			(net "PVDDCR_SOC_P0")
		)
		(pad "AM20" smd circle
			(at -16.770096 -11.700002 180)
			(size 0.450088 0.450088)
			(layers "F.Cu" "F.Mask" "F.Paste")
			(net "M_I_CPU0_SA_DQS_DN<4>")
		)
		(pad "AM21" smd circle
			(at -15.830042 -11.700002 180)
			(size 0.450088 0.450088)
			(layers "F.Cu" "F.Mask" "F.Paste")
			(net "M_I_CPU0_SA_DQS_DN<9>")
		)
		(pad "AM22" smd circle
			(at -14.889988 -11.700002 180)
			(size 0.450088 0.450088)
			(layers "F.Cu" "F.Mask" "F.Paste")
			(net "PVDDCR_SOC_P0")
		)
		(pad "AM23" smd circle
			(at -13.949934 -11.700002 180)
			(size 0.450088 0.450088)
			(layers "F.Cu" "F.Mask" "F.Paste")
			(net "GND")
		)
		(pad "AM24" smd circle
			(at -13.00988 -11.700002 180)
			(size 0.450088 0.450088)
			(layers "F.Cu" "F.Mask" "F.Paste")
			(net "GND")
		)
		(pad "AM25" smd circle
			(at -12.07008 -11.700002 180)
			(size 0.450088 0.450088)
			(layers "F.Cu" "F.Mask" "F.Paste")
			(net "GND")
		)
		(pad "AM26" smd circle
			(at -11.130026 -11.700002 180)
			(size 0.450088 0.450088)
			(layers "F.Cu" "F.Mask" "F.Paste")
			(net "GND")
		)
		(pad "AM27" smd circle
			(at -10.189972 -11.700002 180)
			(size 0.450088 0.450088)
			(layers "F.Cu" "F.Mask" "F.Paste")
			(net "GND")
		)
		(pad "AM28" smd circle
			(at -9.249918 -11.700002 180)
			(size 0.450088 0.450088)
			(layers "F.Cu" "F.Mask" "F.Paste")
			(net "GND")
		)
		(pad "AM29" smd circle
			(at -8.310118 -11.700002 180)
			(size 0.450088 0.450088)
			(layers "F.Cu" "F.Mask" "F.Paste")
			(net "GND")
		)
		(pad "AM30" smd circle
			(at -7.370064 -11.700002 180)
			(size 0.450088 0.450088)
			(layers "F.Cu" "F.Mask" "F.Paste")
			(net "GND")
		)
		(pad "AM31" smd circle
			(at -6.43001 -11.700002 180)
			(size 0.450088 0.450088)
			(layers "F.Cu" "F.Mask" "F.Paste")
			(net "GND")
		)
		(pad "AM32" smd circle
			(at -5.489956 -11.700002 180)
			(size 0.450088 0.450088)
			(layers "F.Cu" "F.Mask" "F.Paste")
			(net "GND")
		)
		(pad "AM33" smd circle
			(at -4.549902 -11.700002 180)
			(size 0.450088 0.450088)
			(layers "F.Cu" "F.Mask" "F.Paste")
			(net "GND")
		)
		(pad "AM34" smd circle
			(at -3.610102 -11.700002 180)
			(size 0.450088 0.450088)
			(layers "F.Cu" "F.Mask" "F.Paste")
			(net "GND")
		)
		(pad "AM35" smd circle
			(at -2.670048 -11.700002 180)
			(size 0.450088 0.450088)
			(layers "F.Cu" "F.Mask" "F.Paste")
			(net "P5E_CPU0_G3_RX_DN<14>")
		)
		(pad "AM36" smd circle
			(at -1.729994 -11.700002 180)
			(size 0.450088 0.450088)
			(layers "F.Cu" "F.Mask" "F.Paste")
			(net "P5E_CPU0_G3_RX_DP<14>")
		)
		(pad "AM37" smd circle
			(at -0.78994 -11.700002 180)
			(size 0.450088 0.450088)
			(layers "F.Cu" "F.Mask" "F.Paste")
			(net "GND")
		)
		(pad "AM39" smd circle
			(at 1.089914 -11.700002 180)
			(size 0.450088 0.450088)
			(layers "F.Cu" "F.Mask" "F.Paste")
			(net "GND")
		)
		(pad "AM40" smd circle
			(at 2.029968 -11.700002 180)
			(size 0.450088 0.450088)
			(layers "F.Cu" "F.Mask" "F.Paste")
			(net "GMI_CPU0_G1_CPU1_G3_TX_DP<1>")
		)
		(pad "AM41" smd circle
			(at 2.970022 -11.700002 180)
			(size 0.450088 0.450088)
			(layers "F.Cu" "F.Mask" "F.Paste")
			(net "GMI_CPU0_G1_CPU1_G3_TX_DN<1>")
		)
		(pad "AM42" smd circle
			(at 3.910076 -11.700002 180)
			(size 0.450088 0.450088)
			(layers "F.Cu" "F.Mask" "F.Paste")
			(net "GND")
		)
		(pad "AM43" smd circle
			(at 4.849876 -11.700002 180)
			(size 0.450088 0.450088)
			(layers "F.Cu" "F.Mask" "F.Paste")
			(net "GND")
		)
		(pad "AM44" smd circle
			(at 5.78993 -11.700002 180)
			(size 0.450088 0.450088)
			(layers "F.Cu" "F.Mask" "F.Paste")
			(net "GND")
		)
		(pad "AM45" smd circle
			(at 6.729984 -11.700002 180)
			(size 0.450088 0.450088)
			(layers "F.Cu" "F.Mask" "F.Paste")
			(net "GND")
		)
		(pad "AM46" smd circle
			(at 7.670038 -11.700002 180)
			(size 0.450088 0.450088)
			(layers "F.Cu" "F.Mask" "F.Paste")
			(net "GND")
		)
		(pad "AM47" smd circle
			(at 8.610092 -11.700002 180)
			(size 0.450088 0.450088)
			(layers "F.Cu" "F.Mask" "F.Paste")
			(net "GND")
		)
		(pad "AM48" smd circle
			(at 9.549892 -11.700002 180)
			(size 0.450088 0.450088)
			(layers "F.Cu" "F.Mask" "F.Paste")
			(net "GND")
		)
		(pad "AM49" smd circle
			(at 10.489946 -11.700002 180)
			(size 0.450088 0.450088)
			(layers "F.Cu" "F.Mask" "F.Paste")
			(net "GND")
		)
		(pad "AM50" smd circle
			(at 11.43 -11.700002 180)
			(size 0.450088 0.450088)
			(layers "F.Cu" "F.Mask" "F.Paste")
			(net "GND")
		)
		(pad "AM51" smd circle
			(at 12.370054 -11.700002 180)
			(size 0.450088 0.450088)
			(layers "F.Cu" "F.Mask" "F.Paste")
			(net "GND")
		)
		(pad "AM52" smd circle
			(at 13.310108 -11.700002 180)
			(size 0.450088 0.450088)
			(layers "F.Cu" "F.Mask" "F.Paste")
			(net "GND")
		)
		(pad "AM53" smd circle
			(at 14.249908 -11.700002 180)
			(size 0.450088 0.450088)
			(layers "F.Cu" "F.Mask" "F.Paste")
			(net "GND")
		)
		(pad "AM54" smd circle
			(at 15.189962 -11.700002 180)
			(size 0.450088 0.450088)
			(layers "F.Cu" "F.Mask" "F.Paste")
			(net "PVDDIO_P0")
		)
		(pad "AM55" smd circle
			(at 16.130016 -11.700002 180)
			(size 0.450088 0.450088)
			(layers "F.Cu" "F.Mask" "F.Paste")
			(net "M_C_CPU0_SA_DQS_DN<9>")
		)
		(pad "AM56" smd circle
			(at 17.07007 -11.700002 180)
			(size 0.450088 0.450088)
			(layers "F.Cu" "F.Mask" "F.Paste")
			(net "M_C_CPU0_SA_DQS_DN<4>")
		)
		(pad "AM57" smd circle
			(at 18.010124 -11.700002 180)
			(size 0.450088 0.450088)
			(layers "F.Cu" "F.Mask" "F.Paste")
			(net "PVDDIO_P0")
		)
		(pad "AM58" smd circle
			(at 18.949924 -11.700002 180)
			(size 0.450088 0.450088)
			(layers "F.Cu" "F.Mask" "F.Paste")
			(net "M_D_CPU0_SA_DQS_DN<9>")
		)
		(pad "AM59" smd circle
			(at 19.889978 -11.700002 180)
			(size 0.450088 0.450088)
			(layers "F.Cu" "F.Mask" "F.Paste")
			(net "GND")
		)
		(pad "AM60" smd circle
			(at 20.830032 -11.700002 180)
			(size 0.450088 0.450088)
			(layers "F.Cu" "F.Mask" "F.Paste")
			(net "M_D_CPU0_SA_DQS_DN<4>")
		)
		(pad "AM61" smd circle
			(at 21.770086 -11.700002 180)
			(size 0.450088 0.450088)
			(layers "F.Cu" "F.Mask" "F.Paste")
			(net "GND")
		)
		(pad "AM62" smd circle
			(at 22.709886 -11.700002 180)
			(size 0.450088 0.450088)
			(layers "F.Cu" "F.Mask" "F.Paste")
			(net "M_B_CPU0_SA_DQS_DN<9>")
		)
		(pad "AM63" smd circle
			(at 23.64994 -11.700002 180)
			(size 0.450088 0.450088)
			(layers "F.Cu" "F.Mask" "F.Paste")
			(net "M_B_CPU0_SA_DQS_DN<4>")
		)
		(pad "AM64" smd circle
			(at 24.589994 -11.700002 180)
			(size 0.450088 0.450088)
			(layers "F.Cu" "F.Mask" "F.Paste")
			(net "PVDDIO_P0")
		)
		(pad "AM65" smd circle
			(at 25.530048 -11.700002 180)
			(size 0.450088 0.450088)
			(layers "F.Cu" "F.Mask" "F.Paste")
			(net "M_F_CPU0_SA_DQS_DN<9>")
		)
		(pad "AM66" smd circle
			(at 26.470102 -11.700002 180)
			(size 0.450088 0.450088)
			(layers "F.Cu" "F.Mask" "F.Paste")
			(net "GND")
		)
		(pad "AM67" smd circle
			(at 27.409902 -11.700002 180)
			(size 0.450088 0.450088)
			(layers "F.Cu" "F.Mask" "F.Paste")
			(net "M_F_CPU0_SA_DQS_DN<4>")
		)
		(pad "AM68" smd circle
			(at 28.349956 -11.700002 180)
			(size 0.450088 0.450088)
			(layers "F.Cu" "F.Mask" "F.Paste")
			(net "GND")
		)
		(pad "AM69" smd circle
			(at 29.29001 -11.700002 180)
			(size 0.450088 0.450088)
			(layers "F.Cu" "F.Mask" "F.Paste")
			(net "M_E_CPU0_SA_DQS_DN<9>")
		)
		(pad "AM70" smd circle
			(at 30.230064 -11.700002 180)
			(size 0.450088 0.450088)
			(layers "F.Cu" "F.Mask" "F.Paste")
			(net "M_E_CPU0_SA_DQS_DN<4>")
		)
		(pad "AM71" smd circle
			(at 31.170118 -11.700002 180)
			(size 0.450088 0.450088)
			(layers "F.Cu" "F.Mask" "F.Paste")
			(net "PVDDIO_P0")
		)
		(pad "AM72" smd circle
			(at 32.109918 -11.700002 180)
			(size 0.450088 0.450088)
			(layers "F.Cu" "F.Mask" "F.Paste")
			(net "M_A_CPU0_SA_DQS_DN<9>")
		)
		(pad "AM73" smd circle
			(at 33.049972 -11.700002 180)
			(size 0.450088 0.450088)
			(layers "F.Cu" "F.Mask" "F.Paste")
			(net "GND")
		)
		(pad "AM74" smd circle
			(at 33.990026 -11.700002 180)
			(size 0.450088 0.450088)
			(layers "F.Cu" "F.Mask" "F.Paste")
			(net "M_A_CPU0_SA_DQS_DN<4>")
		)
		(pad "AN1" smd circle
			(at -34.159952 -10.889996 180)
			(size 0.450088 0.450088)
			(layers "F.Cu" "F.Mask" "F.Paste")
			(net "GND")
		)
		(pad "AN2" smd circle
			(at -33.219898 -10.889996 180)
			(size 0.450088 0.450088)
			(layers "F.Cu" "F.Mask" "F.Paste")
			(net "M_G_CPU0_SA_CB<4>")
		)
		(pad "AN3" smd circle
			(at -32.280098 -10.889996 180)
			(size 0.450088 0.450088)
			(layers "F.Cu" "F.Mask" "F.Paste")
			(net "M_G_CPU0_SA_DQS_DP<9>")
		)
		(pad "AN4" smd circle
			(at -31.340044 -10.889996 180)
			(size 0.450088 0.450088)
			(layers "F.Cu" "F.Mask" "F.Paste")
			(net "GND")
		)
		(pad "AN5" smd circle
			(at -30.39999 -10.889996 180)
			(size 0.450088 0.450088)
			(layers "F.Cu" "F.Mask" "F.Paste")
			(net "M_K_CPU0_SA_CB<4>")
		)
		(pad "AN6" smd circle
			(at -29.459936 -10.889996 180)
			(size 0.450088 0.450088)
			(layers "F.Cu" "F.Mask" "F.Paste")
			(net "GND")
		)
		(pad "AN7" smd circle
			(at -28.519882 -10.889996 180)
			(size 0.450088 0.450088)
			(layers "F.Cu" "F.Mask" "F.Paste")
			(net "M_K_CPU0_SA_DQS_DP<9>")
		)
		(pad "AN8" smd circle
			(at -27.580082 -10.889996 180)
			(size 0.450088 0.450088)
			(layers "F.Cu" "F.Mask" "F.Paste")
			(net "GND")
		)
		(pad "AN9" smd circle
			(at -26.640028 -10.889996 180)
			(size 0.450088 0.450088)
			(layers "F.Cu" "F.Mask" "F.Paste")
			(net "M_L_CPU0_SA_CB<4>")
		)
		(pad "AN10" smd circle
			(at -25.699974 -10.889996 180)
			(size 0.450088 0.450088)
			(layers "F.Cu" "F.Mask" "F.Paste")
			(net "M_L_CPU0_SA_DQS_DP<9>")
		)
		(pad "AN11" smd circle
			(at -24.75992 -10.889996 180)
			(size 0.450088 0.450088)
			(layers "F.Cu" "F.Mask" "F.Paste")
			(net "GND")
		)
		(pad "AN12" smd circle
			(at -23.82012 -10.889996 180)
			(size 0.450088 0.450088)
			(layers "F.Cu" "F.Mask" "F.Paste")
			(net "M_H_CPU0_SA_CB<4>")
		)
		(pad "AN13" smd circle
			(at -22.880066 -10.889996 180)
			(size 0.450088 0.450088)
			(layers "F.Cu" "F.Mask" "F.Paste")
			(net "GND")
		)
		(pad "AN14" smd circle
			(at -21.940012 -10.889996 180)
			(size 0.450088 0.450088)
			(layers "F.Cu" "F.Mask" "F.Paste")
			(net "M_H_CPU0_SA_DQS_DP<9>")
		)
		(pad "AN15" smd circle
			(at -20.999958 -10.889996 180)
			(size 0.450088 0.450088)
			(layers "F.Cu" "F.Mask" "F.Paste")
			(net "GND")
		)
		(pad "AN16" smd circle
			(at -20.059904 -10.889996 180)
			(size 0.450088 0.450088)
			(layers "F.Cu" "F.Mask" "F.Paste")
			(net "M_J_CPU0_SA_CB<4>")
		)
		(pad "AN17" smd circle
			(at -19.120104 -10.889996 180)
			(size 0.450088 0.450088)
			(layers "F.Cu" "F.Mask" "F.Paste")
			(net "M_J_CPU0_SA_DQS_DP<9>")
		)
		(pad "AN18" smd circle
			(at -18.18005 -10.889996 180)
			(size 0.450088 0.450088)
			(layers "F.Cu" "F.Mask" "F.Paste")
			(net "GND")
		)
		(pad "AN19" smd circle
			(at -17.239996 -10.889996 180)
			(size 0.450088 0.450088)
			(layers "F.Cu" "F.Mask" "F.Paste")
			(net "M_I_CPU0_SA_CB<4>")
		)
		(pad "AN20" smd circle
			(at -16.299942 -10.889996 180)
			(size 0.450088 0.450088)
			(layers "F.Cu" "F.Mask" "F.Paste")
			(net "GND")
		)
		(pad "AN21" smd circle
			(at -15.359888 -10.889996 180)
			(size 0.450088 0.450088)
			(layers "F.Cu" "F.Mask" "F.Paste")
			(net "M_I_CPU0_SA_DQS_DP<9>")
		)
		(pad "AN22" smd circle
			(at -14.420088 -10.889996 180)
			(size 0.450088 0.450088)
			(layers "F.Cu" "F.Mask" "F.Paste")
			(net "GND")
		)
		(pad "AN23" smd circle
			(at -13.480034 -10.889996 180)
			(size 0.450088 0.450088)
			(layers "F.Cu" "F.Mask" "F.Paste")
			(net "P5E_CPU0_G3_RX_DN<2>")
		)
		(pad "AN24" smd circle
			(at -12.53998 -10.889996 180)
			(size 0.450088 0.450088)
			(layers "F.Cu" "F.Mask" "F.Paste")
			(net "P5E_CPU0_G3_RX_DP<2>")
		)
		(pad "AN25" smd circle
			(at -11.599926 -10.889996 180)
			(size 0.450088 0.450088)
			(layers "F.Cu" "F.Mask" "F.Paste")
			(net "GND")
		)
		(pad "AN26" smd circle
			(at -10.659872 -10.889996 180)
			(size 0.450088 0.450088)
			(layers "F.Cu" "F.Mask" "F.Paste")
			(net "P5E_CPU0_G3_RX_DN<5>")
		)
		(pad "AN27" smd circle
			(at -9.720072 -10.889996 180)
			(size 0.450088 0.450088)
			(layers "F.Cu" "F.Mask" "F.Paste")
			(net "P5E_CPU0_G3_RX_DP<5>")
		)
		(pad "AN28" smd circle
			(at -8.780018 -10.889996 180)
			(size 0.450088 0.450088)
			(layers "F.Cu" "F.Mask" "F.Paste")
			(net "GND")
		)
		(pad "AN29" smd circle
			(at -7.839964 -10.889996 180)
			(size 0.450088 0.450088)
			(layers "F.Cu" "F.Mask" "F.Paste")
			(net "P5E_CPU0_G3_RX_DN<8>")
		)
		(pad "AN30" smd circle
			(at -6.89991 -10.889996 180)
			(size 0.450088 0.450088)
			(layers "F.Cu" "F.Mask" "F.Paste")
			(net "P5E_CPU0_G3_RX_DP<8>")
		)
		(pad "AN31" smd circle
			(at -5.96011 -10.889996 180)
			(size 0.450088 0.450088)
			(layers "F.Cu" "F.Mask" "F.Paste")
			(net "GND")
		)
		(pad "AN32" smd circle
			(at -5.020056 -10.889996 180)
			(size 0.450088 0.450088)
			(layers "F.Cu" "F.Mask" "F.Paste")
			(net "P5E_CPU0_G3_RX_DN<11>")
		)
		(pad "AN33" smd circle
			(at -4.080002 -10.889996 180)
			(size 0.450088 0.450088)
			(layers "F.Cu" "F.Mask" "F.Paste")
			(net "P5E_CPU0_G3_RX_DP<11>")
		)
		(pad "AN34" smd circle
			(at -3.139948 -10.889996 180)
			(size 0.450088 0.450088)
			(layers "F.Cu" "F.Mask" "F.Paste")
			(net "GND")
		)
		(pad "AN35" smd circle
			(at -2.199894 -10.889996 180)
			(size 0.450088 0.450088)
			(layers "F.Cu" "F.Mask" "F.Paste")
			(net "GND")
		)
		(pad "AN36" smd circle
			(at -1.260094 -10.889996 180)
			(size 0.450088 0.450088)
			(layers "F.Cu" "F.Mask" "F.Paste")
			(net "GND")
		)
		(pad "AN40" smd circle
			(at 1.560068 -10.889996 180)
			(size 0.450088 0.450088)
			(layers "F.Cu" "F.Mask" "F.Paste")
			(net "GND")
		)
		(pad "AN41" smd circle
			(at 2.500122 -10.889996 180)
			(size 0.450088 0.450088)
			(layers "F.Cu" "F.Mask" "F.Paste")
			(net "GND")
		)
		(pad "AN42" smd circle
			(at 3.439922 -10.889996 180)
			(size 0.450088 0.450088)
			(layers "F.Cu" "F.Mask" "F.Paste")
			(net "GND")
		)
		(pad "AN43" smd circle
			(at 4.379976 -10.889996 180)
			(size 0.450088 0.450088)
			(layers "F.Cu" "F.Mask" "F.Paste")
			(net "GMI_CPU0_G1_CPU1_G3_TX_DP<4>")
		)
		(pad "AN44" smd circle
			(at 5.32003 -10.889996 180)
			(size 0.450088 0.450088)
			(layers "F.Cu" "F.Mask" "F.Paste")
			(net "GMI_CPU0_G1_CPU1_G3_TX_DN<4>")
		)
		(pad "AN45" smd circle
			(at 6.260084 -10.889996 180)
			(size 0.450088 0.450088)
			(layers "F.Cu" "F.Mask" "F.Paste")
			(net "GND")
		)
		(pad "AN46" smd circle
			(at 7.199884 -10.889996 180)
			(size 0.450088 0.450088)
			(layers "F.Cu" "F.Mask" "F.Paste")
			(net "GMI_CPU0_G1_CPU1_G3_TX_DP<7>")
		)
		(pad "AN47" smd circle
			(at 8.139938 -10.889996 180)
			(size 0.450088 0.450088)
			(layers "F.Cu" "F.Mask" "F.Paste")
			(net "GMI_CPU0_G1_CPU1_G3_TX_DN<7>")
		)
		(pad "AN48" smd circle
			(at 9.079992 -10.889996 180)
			(size 0.450088 0.450088)
			(layers "F.Cu" "F.Mask" "F.Paste")
			(net "GND")
		)
		(pad "AN49" smd circle
			(at 10.020046 -10.889996 180)
			(size 0.450088 0.450088)
			(layers "F.Cu" "F.Mask" "F.Paste")
			(net "GMI_CPU0_G1_CPU1_G3_TX_DP<10>")
		)
		(pad "AN50" smd circle
			(at 10.9601 -10.889996 180)
			(size 0.450088 0.450088)
			(layers "F.Cu" "F.Mask" "F.Paste")
			(net "GMI_CPU0_G1_CPU1_G3_TX_DN<10>")
		)
		(pad "AN51" smd circle
			(at 11.8999 -10.889996 180)
			(size 0.450088 0.450088)
			(layers "F.Cu" "F.Mask" "F.Paste")
			(net "GND")
		)
		(pad "AN52" smd circle
			(at 12.839954 -10.889996 180)
			(size 0.450088 0.450088)
			(layers "F.Cu" "F.Mask" "F.Paste")
			(net "GMI_CPU0_G1_CPU1_G3_TX_DP<13>")
		)
		(pad "AN53" smd circle
			(at 13.780008 -10.889996 180)
			(size 0.450088 0.450088)
			(layers "F.Cu" "F.Mask" "F.Paste")
			(net "GMI_CPU0_G1_CPU1_G3_TX_DN<13>")
		)
		(pad "AN54" smd circle
			(at 14.720062 -10.889996 180)
			(size 0.450088 0.450088)
			(layers "F.Cu" "F.Mask" "F.Paste")
			(net "GND")
		)
		(pad "AN55" smd circle
			(at 15.660116 -10.889996 180)
			(size 0.450088 0.450088)
			(layers "F.Cu" "F.Mask" "F.Paste")
			(net "M_C_CPU0_SA_DQS_DP<9>")
		)
		(pad "AN56" smd circle
			(at 16.599916 -10.889996 180)
			(size 0.450088 0.450088)
			(layers "F.Cu" "F.Mask" "F.Paste")
			(net "GND")
		)
		(pad "AN57" smd circle
			(at 17.53997 -10.889996 180)
			(size 0.450088 0.450088)
			(layers "F.Cu" "F.Mask" "F.Paste")
			(net "M_C_CPU0_SA_CB<4>")
		)
		(pad "AN58" smd circle
			(at 18.480024 -10.889996 180)
			(size 0.450088 0.450088)
			(layers "F.Cu" "F.Mask" "F.Paste")
			(net "GND")
		)
		(pad "AN59" smd circle
			(at 19.420078 -10.889996 180)
			(size 0.450088 0.450088)
			(layers "F.Cu" "F.Mask" "F.Paste")
			(net "M_D_CPU0_SA_DQS_DP<9>")
		)
		(pad "AN60" smd circle
			(at 20.359878 -10.889996 180)
			(size 0.450088 0.450088)
			(layers "F.Cu" "F.Mask" "F.Paste")
			(net "M_D_CPU0_SA_CB<4>")
		)
		(pad "AN61" smd circle
			(at 21.299932 -10.889996 180)
			(size 0.450088 0.450088)
			(layers "F.Cu" "F.Mask" "F.Paste")
			(net "GND")
		)
		(pad "AN62" smd circle
			(at 22.239986 -10.889996 180)
			(size 0.450088 0.450088)
			(layers "F.Cu" "F.Mask" "F.Paste")
			(net "M_B_CPU0_SA_DQS_DP<9>")
		)
		(pad "AN63" smd circle
			(at 23.18004 -10.889996 180)
			(size 0.450088 0.450088)
			(layers "F.Cu" "F.Mask" "F.Paste")
			(net "GND")
		)
		(pad "AN64" smd circle
			(at 24.120094 -10.889996 180)
			(size 0.450088 0.450088)
			(layers "F.Cu" "F.Mask" "F.Paste")
			(net "M_B_CPU0_SA_CB<4>")
		)
		(pad "AN65" smd circle
			(at 25.059894 -10.889996 180)
			(size 0.450088 0.450088)
			(layers "F.Cu" "F.Mask" "F.Paste")
			(net "GND")
		)
		(pad "AN66" smd circle
			(at 25.999948 -10.889996 180)
			(size 0.450088 0.450088)
			(layers "F.Cu" "F.Mask" "F.Paste")
			(net "M_F_CPU0_SA_DQS_DP<9>")
		)
		(pad "AN67" smd circle
			(at 26.940002 -10.889996 180)
			(size 0.450088 0.450088)
			(layers "F.Cu" "F.Mask" "F.Paste")
			(net "M_F_CPU0_SA_CB<4>")
		)
		(pad "AN68" smd circle
			(at 27.880056 -10.889996 180)
			(size 0.450088 0.450088)
			(layers "F.Cu" "F.Mask" "F.Paste")
			(net "GND")
		)
		(pad "AN69" smd circle
			(at 28.82011 -10.889996 180)
			(size 0.450088 0.450088)
			(layers "F.Cu" "F.Mask" "F.Paste")
			(net "M_E_CPU0_SA_DQS_DP<9>")
		)
		(pad "AN70" smd circle
			(at 29.75991 -10.889996 180)
			(size 0.450088 0.450088)
			(layers "F.Cu" "F.Mask" "F.Paste")
			(net "GND")
		)
		(pad "AN71" smd circle
			(at 30.699964 -10.889996 180)
			(size 0.450088 0.450088)
			(layers "F.Cu" "F.Mask" "F.Paste")
			(net "M_E_CPU0_SA_CB<4>")
		)
		(pad "AN72" smd circle
			(at 31.640018 -10.889996 180)
			(size 0.450088 0.450088)
			(layers "F.Cu" "F.Mask" "F.Paste")
			(net "GND")
		)
		(pad "AN73" smd circle
			(at 32.580072 -10.889996 180)
			(size 0.450088 0.450088)
			(layers "F.Cu" "F.Mask" "F.Paste")
			(net "M_A_CPU0_SA_DQS_DP<9>")
		)
		(pad "AN74" smd circle
			(at 33.519872 -10.889996 180)
			(size 0.450088 0.450088)
			(layers "F.Cu" "F.Mask" "F.Paste")
			(net "M_A_CPU0_SA_CB<4>")
		)
		(pad "AN75" smd circle
			(at 34.459926 -10.889996 180)
			(size 0.450088 0.450088)
			(layers "F.Cu" "F.Mask" "F.Paste")
			(net "GND")
		)
		(pad "AP2" smd circle
			(at -33.690052 -10.07999 180)
			(size 0.450088 0.450088)
			(layers "F.Cu" "F.Mask" "F.Paste")
			(net "M_G_CPU0_SA_CB<6>")
		)
		(pad "AP3" smd circle
			(at -32.749998 -10.07999 180)
			(size 0.450088 0.450088)
			(layers "F.Cu" "F.Mask" "F.Paste")
			(net "GND")
		)
		(pad "AP4" smd circle
			(at -31.809944 -10.07999 180)
			(size 0.450088 0.450088)
			(layers "F.Cu" "F.Mask" "F.Paste")
			(net "M_G_CPU0_SA_CB<5>")
		)
		(pad "AP5" smd circle
			(at -30.86989 -10.07999 180)
			(size 0.450088 0.450088)
			(layers "F.Cu" "F.Mask" "F.Paste")
			(net "GND")
		)
		(pad "AP6" smd circle
			(at -29.93009 -10.07999 180)
			(size 0.450088 0.450088)
			(layers "F.Cu" "F.Mask" "F.Paste")
			(net "M_K_CPU0_SA_CB<6>")
		)
		(pad "AP7" smd circle
			(at -28.990036 -10.07999 180)
			(size 0.450088 0.450088)
			(layers "F.Cu" "F.Mask" "F.Paste")
			(net "M_K_CPU0_SA_CB<5>")
		)
		(pad "AP8" smd circle
			(at -28.049982 -10.07999 180)
			(size 0.450088 0.450088)
			(layers "F.Cu" "F.Mask" "F.Paste")
			(net "GND")
		)
		(pad "AP9" smd circle
			(at -27.109928 -10.07999 180)
			(size 0.450088 0.450088)
			(layers "F.Cu" "F.Mask" "F.Paste")
			(net "M_L_CPU0_SA_CB<6>")
		)
		(pad "AP10" smd circle
			(at -26.170128 -10.07999 180)
			(size 0.450088 0.450088)
			(layers "F.Cu" "F.Mask" "F.Paste")
			(net "GND")
		)
		(pad "AP11" smd circle
			(at -25.230074 -10.07999 180)
			(size 0.450088 0.450088)
			(layers "F.Cu" "F.Mask" "F.Paste")
			(net "M_L_CPU0_SA_CB<5>")
		)
		(pad "AP12" smd circle
			(at -24.29002 -10.07999 180)
			(size 0.450088 0.450088)
			(layers "F.Cu" "F.Mask" "F.Paste")
			(net "GND")
		)
		(pad "AP13" smd circle
			(at -23.349966 -10.07999 180)
			(size 0.450088 0.450088)
			(layers "F.Cu" "F.Mask" "F.Paste")
			(net "M_H_CPU0_SA_CB<6>")
		)
		(pad "AP14" smd circle
			(at -22.409912 -10.07999 180)
			(size 0.450088 0.450088)
			(layers "F.Cu" "F.Mask" "F.Paste")
			(net "M_H_CPU0_SA_CB<5>")
		)
		(pad "AP15" smd circle
			(at -21.470112 -10.07999 180)
			(size 0.450088 0.450088)
			(layers "F.Cu" "F.Mask" "F.Paste")
			(net "GND")
		)
		(pad "AP16" smd circle
			(at -20.530058 -10.07999 180)
			(size 0.450088 0.450088)
			(layers "F.Cu" "F.Mask" "F.Paste")
			(net "M_J_CPU0_SA_CB<6>")
		)
		(pad "AP17" smd circle
			(at -19.590004 -10.07999 180)
			(size 0.450088 0.450088)
			(layers "F.Cu" "F.Mask" "F.Paste")
			(net "GND")
		)
		(pad "AP18" smd circle
			(at -18.64995 -10.07999 180)
			(size 0.450088 0.450088)
			(layers "F.Cu" "F.Mask" "F.Paste")
			(net "M_J_CPU0_SA_CB<5>")
		)
		(pad "AP19" smd circle
			(at -17.709896 -10.07999 180)
			(size 0.450088 0.450088)
			(layers "F.Cu" "F.Mask" "F.Paste")
			(net "GND")
		)
		(pad "AP20" smd circle
			(at -16.770096 -10.07999 180)
			(size 0.450088 0.450088)
			(layers "F.Cu" "F.Mask" "F.Paste")
			(net "M_I_CPU0_SA_CB<6>")
		)
		(pad "AP21" smd circle
			(at -15.830042 -10.07999 180)
			(size 0.450088 0.450088)
			(layers "F.Cu" "F.Mask" "F.Paste")
			(net "M_I_CPU0_SA_CB<5>")
		)
		(pad "AP22" smd circle
			(at -14.889988 -10.07999 180)
			(size 0.450088 0.450088)
			(layers "F.Cu" "F.Mask" "F.Paste")
			(net "GND")
		)
		(pad "AP23" smd circle
			(at -13.949934 -10.07999 180)
			(size 0.450088 0.450088)
			(layers "F.Cu" "F.Mask" "F.Paste")
			(net "PVDDCR_CPU0_P0")
		)
		(pad "AP24" smd circle
			(at -13.00988 -10.07999 180)
			(size 0.450088 0.450088)
			(layers "F.Cu" "F.Mask" "F.Paste")
			(net "PVDDCR_CPU0_P0")
		)
		(pad "AP25" smd circle
			(at -12.07008 -10.07999 180)
			(size 0.450088 0.450088)
			(layers "F.Cu" "F.Mask" "F.Paste")
			(net "GND")
		)
		(pad "AP26" smd circle
			(at -11.130026 -10.07999 180)
			(size 0.450088 0.450088)
			(layers "F.Cu" "F.Mask" "F.Paste")
			(net "PVDDCR_CPU0_P0")
		)
		(pad "AP27" smd circle
			(at -10.189972 -10.07999 180)
			(size 0.450088 0.450088)
			(layers "F.Cu" "F.Mask" "F.Paste")
			(net "PVDDCR_CPU0_P0")
		)
		(pad "AP28" smd circle
			(at -9.249918 -10.07999 180)
			(size 0.450088 0.450088)
			(layers "F.Cu" "F.Mask" "F.Paste")
			(net "GND")
		)
		(pad "AP29" smd circle
			(at -8.310118 -10.07999 180)
			(size 0.450088 0.450088)
			(layers "F.Cu" "F.Mask" "F.Paste")
			(net "PVDDCR_CPU0_P0")
		)
		(pad "AP30" smd circle
			(at -7.370064 -10.07999 180)
			(size 0.450088 0.450088)
			(layers "F.Cu" "F.Mask" "F.Paste")
			(net "PVDDCR_CPU0_P0")
		)
		(pad "AP31" smd circle
			(at -6.43001 -10.07999 180)
			(size 0.450088 0.450088)
			(layers "F.Cu" "F.Mask" "F.Paste")
			(net "GND")
		)
		(pad "AP32" smd circle
			(at -5.489956 -10.07999 180)
			(size 0.450088 0.450088)
			(layers "F.Cu" "F.Mask" "F.Paste")
			(net "PVDDCR_CPU0_P0")
		)
		(pad "AP33" smd circle
			(at -4.549902 -10.07999 180)
			(size 0.450088 0.450088)
			(layers "F.Cu" "F.Mask" "F.Paste")
			(net "PVDDCR_CPU0_P0")
		)
		(pad "AP34" smd circle
			(at -3.610102 -10.07999 180)
			(size 0.450088 0.450088)
			(layers "F.Cu" "F.Mask" "F.Paste")
			(net "GND")
		)
		(pad "AP35" smd circle
			(at -2.670048 -10.07999 180)
			(size 0.450088 0.450088)
			(layers "F.Cu" "F.Mask" "F.Paste")
			(net "P5E_CPU0_G3_RX_DN<15>")
		)
		(pad "AP36" smd circle
			(at -1.729994 -10.07999 180)
			(size 0.450088 0.450088)
			(layers "F.Cu" "F.Mask" "F.Paste")
			(net "P5E_CPU0_G3_RX_DP<15>")
		)
		(pad "AP37" smd circle
			(at -0.78994 -10.07999 180)
			(size 0.450088 0.450088)
			(layers "F.Cu" "F.Mask" "F.Paste")
			(net "GND")
		)
		(pad "AP39" smd circle
			(at 1.089914 -10.07999 180)
			(size 0.450088 0.450088)
			(layers "F.Cu" "F.Mask" "F.Paste")
			(net "GND")
		)
		(pad "AP40" smd circle
			(at 2.029968 -10.07999 180)
			(size 0.450088 0.450088)
			(layers "F.Cu" "F.Mask" "F.Paste")
			(net "GMI_CPU0_G1_CPU1_G3_TX_DP<0>")
		)
		(pad "AP41" smd circle
			(at 2.970022 -10.07999 180)
			(size 0.450088 0.450088)
			(layers "F.Cu" "F.Mask" "F.Paste")
			(net "GMI_CPU0_G1_CPU1_G3_TX_DN<0>")
		)
		(pad "AP42" smd circle
			(at 3.910076 -10.07999 180)
			(size 0.450088 0.450088)
			(layers "F.Cu" "F.Mask" "F.Paste")
			(net "GND")
		)
		(pad "AP43" smd circle
			(at 4.849876 -10.07999 180)
			(size 0.450088 0.450088)
			(layers "F.Cu" "F.Mask" "F.Paste")
			(net "PVDDCR_CPU0_P0")
		)
		(pad "AP44" smd circle
			(at 5.78993 -10.07999 180)
			(size 0.450088 0.450088)
			(layers "F.Cu" "F.Mask" "F.Paste")
			(net "PVDDCR_CPU0_P0")
		)
		(pad "AP45" smd circle
			(at 6.729984 -10.07999 180)
			(size 0.450088 0.450088)
			(layers "F.Cu" "F.Mask" "F.Paste")
			(net "GND")
		)
		(pad "AP46" smd circle
			(at 7.670038 -10.07999 180)
			(size 0.450088 0.450088)
			(layers "F.Cu" "F.Mask" "F.Paste")
			(net "PVDDCR_CPU0_P0")
		)
		(pad "AP47" smd circle
			(at 8.610092 -10.07999 180)
			(size 0.450088 0.450088)
			(layers "F.Cu" "F.Mask" "F.Paste")
			(net "PVDDCR_CPU0_P0")
		)
		(pad "AP48" smd circle
			(at 9.549892 -10.07999 180)
			(size 0.450088 0.450088)
			(layers "F.Cu" "F.Mask" "F.Paste")
			(net "GND")
		)
		(pad "AP49" smd circle
			(at 10.489946 -10.07999 180)
			(size 0.450088 0.450088)
			(layers "F.Cu" "F.Mask" "F.Paste")
			(net "PVDDCR_CPU0_P0")
		)
		(pad "AP50" smd circle
			(at 11.43 -10.07999 180)
			(size 0.450088 0.450088)
			(layers "F.Cu" "F.Mask" "F.Paste")
			(net "PVDDCR_CPU0_P0")
		)
		(pad "AP51" smd circle
			(at 12.370054 -10.07999 180)
			(size 0.450088 0.450088)
			(layers "F.Cu" "F.Mask" "F.Paste")
			(net "GND")
		)
		(pad "AP52" smd circle
			(at 13.310108 -10.07999 180)
			(size 0.450088 0.450088)
			(layers "F.Cu" "F.Mask" "F.Paste")
			(net "PVDDCR_CPU0_P0")
		)
		(pad "AP53" smd circle
			(at 14.249908 -10.07999 180)
			(size 0.450088 0.450088)
			(layers "F.Cu" "F.Mask" "F.Paste")
			(net "PVDDCR_CPU0_P0")
		)
		(pad "AP54" smd circle
			(at 15.189962 -10.07999 180)
			(size 0.450088 0.450088)
			(layers "F.Cu" "F.Mask" "F.Paste")
			(net "GND")
		)
		(pad "AP55" smd circle
			(at 16.130016 -10.07999 180)
			(size 0.450088 0.450088)
			(layers "F.Cu" "F.Mask" "F.Paste")
			(net "M_C_CPU0_SA_CB<5>")
		)
		(pad "AP56" smd circle
			(at 17.07007 -10.07999 180)
			(size 0.450088 0.450088)
			(layers "F.Cu" "F.Mask" "F.Paste")
			(net "M_C_CPU0_SA_CB<6>")
		)
		(pad "AP57" smd circle
			(at 18.010124 -10.07999 180)
			(size 0.450088 0.450088)
			(layers "F.Cu" "F.Mask" "F.Paste")
			(net "GND")
		)
		(pad "AP58" smd circle
			(at 18.949924 -10.07999 180)
			(size 0.450088 0.450088)
			(layers "F.Cu" "F.Mask" "F.Paste")
			(net "M_D_CPU0_SA_CB<5>")
		)
		(pad "AP59" smd circle
			(at 19.889978 -10.07999 180)
			(size 0.450088 0.450088)
			(layers "F.Cu" "F.Mask" "F.Paste")
			(net "GND")
		)
		(pad "AP60" smd circle
			(at 20.830032 -10.07999 180)
			(size 0.450088 0.450088)
			(layers "F.Cu" "F.Mask" "F.Paste")
			(net "M_D_CPU0_SA_CB<6>")
		)
		(pad "AP61" smd circle
			(at 21.770086 -10.07999 180)
			(size 0.450088 0.450088)
			(layers "F.Cu" "F.Mask" "F.Paste")
			(net "GND")
		)
		(pad "AP62" smd circle
			(at 22.709886 -10.07999 180)
			(size 0.450088 0.450088)
			(layers "F.Cu" "F.Mask" "F.Paste")
			(net "M_B_CPU0_SA_CB<5>")
		)
		(pad "AP63" smd circle
			(at 23.64994 -10.07999 180)
			(size 0.450088 0.450088)
			(layers "F.Cu" "F.Mask" "F.Paste")
			(net "M_B_CPU0_SA_CB<6>")
		)
		(pad "AP64" smd circle
			(at 24.589994 -10.07999 180)
			(size 0.450088 0.450088)
			(layers "F.Cu" "F.Mask" "F.Paste")
			(net "GND")
		)
		(pad "AP65" smd circle
			(at 25.530048 -10.07999 180)
			(size 0.450088 0.450088)
			(layers "F.Cu" "F.Mask" "F.Paste")
			(net "M_F_CPU0_SA_CB<5>")
		)
		(pad "AP66" smd circle
			(at 26.470102 -10.07999 180)
			(size 0.450088 0.450088)
			(layers "F.Cu" "F.Mask" "F.Paste")
			(net "GND")
		)
		(pad "AP67" smd circle
			(at 27.409902 -10.07999 180)
			(size 0.450088 0.450088)
			(layers "F.Cu" "F.Mask" "F.Paste")
			(net "M_F_CPU0_SA_CB<6>")
		)
		(pad "AP68" smd circle
			(at 28.349956 -10.07999 180)
			(size 0.450088 0.450088)
			(layers "F.Cu" "F.Mask" "F.Paste")
			(net "GND")
		)
		(pad "AP69" smd circle
			(at 29.29001 -10.07999 180)
			(size 0.450088 0.450088)
			(layers "F.Cu" "F.Mask" "F.Paste")
			(net "M_E_CPU0_SA_CB<5>")
		)
		(pad "AP70" smd circle
			(at 30.230064 -10.07999 180)
			(size 0.450088 0.450088)
			(layers "F.Cu" "F.Mask" "F.Paste")
			(net "M_E_CPU0_SA_CB<6>")
		)
		(pad "AP71" smd circle
			(at 31.170118 -10.07999 180)
			(size 0.450088 0.450088)
			(layers "F.Cu" "F.Mask" "F.Paste")
			(net "GND")
		)
		(pad "AP72" smd circle
			(at 32.109918 -10.07999 180)
			(size 0.450088 0.450088)
			(layers "F.Cu" "F.Mask" "F.Paste")
			(net "M_A_CPU0_SA_CB<5>")
		)
		(pad "AP73" smd circle
			(at 33.049972 -10.07999 180)
			(size 0.450088 0.450088)
			(layers "F.Cu" "F.Mask" "F.Paste")
			(net "GND")
		)
		(pad "AP74" smd circle
			(at 33.990026 -10.07999 180)
			(size 0.450088 0.450088)
			(layers "F.Cu" "F.Mask" "F.Paste")
			(net "M_A_CPU0_SA_CB<6>")
		)
		(pad "AR1" smd circle
			(at -34.159952 -9.269984 180)
			(size 0.450088 0.450088)
			(layers "F.Cu" "F.Mask" "F.Paste")
			(net "GND")
		)
		(pad "AR2" smd circle
			(at -33.219898 -9.269984 180)
			(size 0.450088 0.450088)
			(layers "F.Cu" "F.Mask" "F.Paste")
			(net "M_G_CPU0_ALERT_R_N")
		)
		(pad "AR3" smd circle
			(at -32.280098 -9.269984 180)
			(size 0.450088 0.450088)
			(layers "F.Cu" "F.Mask" "F.Paste")
			(net "M_G_CPU0_SA_CB<7>")
		)
		(pad "AR4" smd circle
			(at -31.340044 -9.269984 180)
			(size 0.450088 0.450088)
			(layers "F.Cu" "F.Mask" "F.Paste")
			(net "PVDDCR_SOC_P0")
		)
		(pad "AR5" smd circle
			(at -30.39999 -9.269984 180)
			(size 0.450088 0.450088)
			(layers "F.Cu" "F.Mask" "F.Paste")
			(net "GND")
		)
		(pad "AR6" smd circle
			(at -29.459936 -9.269984 180)
			(size 0.450088 0.450088)
			(layers "F.Cu" "F.Mask" "F.Paste")
			(net "GND")
		)
		(pad "AR7" smd circle
			(at -28.519882 -9.269984 180)
			(size 0.450088 0.450088)
			(layers "F.Cu" "F.Mask" "F.Paste")
			(net "M_K_CPU0_SA_CB<7>")
		)
		(pad "AR8" smd circle
			(at -27.580082 -9.269984 180)
			(size 0.450088 0.450088)
			(layers "F.Cu" "F.Mask" "F.Paste")
			(net "GND")
		)
		(pad "AR9" smd circle
			(at -26.640028 -9.269984 180)
			(size 0.450088 0.450088)
			(layers "F.Cu" "F.Mask" "F.Paste")
			(net "GND")
		)
		(pad "AR10" smd circle
			(at -25.699974 -9.269984 180)
			(size 0.450088 0.450088)
			(layers "F.Cu" "F.Mask" "F.Paste")
			(net "M_L_CPU0_SA_CB<7>")
		)
		(pad "AR11" smd circle
			(at -24.75992 -9.269984 180)
			(size 0.450088 0.450088)
			(layers "F.Cu" "F.Mask" "F.Paste")
			(net "PVDDCR_SOC_P0")
		)
		(pad "AR12" smd circle
			(at -23.82012 -9.269984 180)
			(size 0.450088 0.450088)
			(layers "F.Cu" "F.Mask" "F.Paste")
			(net "GND")
		)
		(pad "AR13" smd circle
			(at -22.880066 -9.269984 180)
			(size 0.450088 0.450088)
			(layers "F.Cu" "F.Mask" "F.Paste")
			(net "GND")
		)
		(pad "AR14" smd circle
			(at -21.940012 -9.269984 180)
			(size 0.450088 0.450088)
			(layers "F.Cu" "F.Mask" "F.Paste")
			(net "M_H_CPU0_SA_CB<7>")
		)
		(pad "AR15" smd circle
			(at -20.999958 -9.269984 180)
			(size 0.450088 0.450088)
			(layers "F.Cu" "F.Mask" "F.Paste")
			(net "GND")
		)
		(pad "AR16" smd circle
			(at -20.059904 -9.269984 180)
			(size 0.450088 0.450088)
			(layers "F.Cu" "F.Mask" "F.Paste")
			(net "GND")
		)
		(pad "AR17" smd circle
			(at -19.120104 -9.269984 180)
			(size 0.450088 0.450088)
			(layers "F.Cu" "F.Mask" "F.Paste")
			(net "M_J_CPU0_SA_CB<7>")
		)
		(pad "AR18" smd circle
			(at -18.18005 -9.269984 180)
			(size 0.450088 0.450088)
			(layers "F.Cu" "F.Mask" "F.Paste")
			(net "PVDDCR_SOC_P0")
		)
		(pad "AR19" smd circle
			(at -17.239996 -9.269984 180)
			(size 0.450088 0.450088)
			(layers "F.Cu" "F.Mask" "F.Paste")
			(net "GND")
		)
		(pad "AR20" smd circle
			(at -16.299942 -9.269984 180)
			(size 0.450088 0.450088)
			(layers "F.Cu" "F.Mask" "F.Paste")
			(net "GND")
		)
		(pad "AR21" smd circle
			(at -15.359888 -9.269984 180)
			(size 0.450088 0.450088)
			(layers "F.Cu" "F.Mask" "F.Paste")
			(net "M_I_CPU0_SA_CB<7>")
		)
		(pad "AR22" smd circle
			(at -14.420088 -9.269984 180)
			(size 0.450088 0.450088)
			(layers "F.Cu" "F.Mask" "F.Paste")
			(net "GND")
		)
		(pad "AR23" smd circle
			(at -13.480034 -9.269984 180)
			(size 0.450088 0.450088)
			(layers "F.Cu" "F.Mask" "F.Paste")
			(net "PVDDCR_CPU0_P0")
		)
		(pad "AR24" smd circle
			(at -12.53998 -9.269984 180)
			(size 0.450088 0.450088)
			(layers "F.Cu" "F.Mask" "F.Paste")
			(net "GND")
		)
		(pad "AR25" smd circle
			(at -11.599926 -9.269984 180)
			(size 0.450088 0.450088)
			(layers "F.Cu" "F.Mask" "F.Paste")
			(net "PVDDCR_CPU0_P0")
		)
		(pad "AR26" smd circle
			(at -10.659872 -9.269984 180)
			(size 0.450088 0.450088)
			(layers "F.Cu" "F.Mask" "F.Paste")
			(net "GND")
		)
		(pad "AR27" smd circle
			(at -9.720072 -9.269984 180)
			(size 0.450088 0.450088)
			(layers "F.Cu" "F.Mask" "F.Paste")
			(net "PVDDCR_CPU0_P0")
		)
		(pad "AR28" smd circle
			(at -8.780018 -9.269984 180)
			(size 0.450088 0.450088)
			(layers "F.Cu" "F.Mask" "F.Paste")
			(net "GND")
		)
		(pad "AR29" smd circle
			(at -7.839964 -9.269984 180)
			(size 0.450088 0.450088)
			(layers "F.Cu" "F.Mask" "F.Paste")
			(net "PVDDCR_CPU0_P0")
		)
		(pad "AR30" smd circle
			(at -6.89991 -9.269984 180)
			(size 0.450088 0.450088)
			(layers "F.Cu" "F.Mask" "F.Paste")
			(net "GND")
		)
		(pad "AR31" smd circle
			(at -5.96011 -9.269984 180)
			(size 0.450088 0.450088)
			(layers "F.Cu" "F.Mask" "F.Paste")
			(net "PVDDCR_CPU0_P0")
		)
		(pad "AR32" smd circle
			(at -5.020056 -9.269984 180)
			(size 0.450088 0.450088)
			(layers "F.Cu" "F.Mask" "F.Paste")
			(net "GND")
		)
		(pad "AR33" smd circle
			(at -4.080002 -9.269984 180)
			(size 0.450088 0.450088)
			(layers "F.Cu" "F.Mask" "F.Paste")
			(net "PVDDCR_CPU0_P0")
		)
		(pad "AR34" smd circle
			(at -3.139948 -9.269984 180)
			(size 0.450088 0.450088)
			(layers "F.Cu" "F.Mask" "F.Paste")
			(net "GND")
		)
		(pad "AR35" smd circle
			(at -2.199894 -9.269984 180)
			(size 0.450088 0.450088)
			(layers "F.Cu" "F.Mask" "F.Paste")
			(net "PVDDCR_CPU0_P0")
		)
		(pad "AR36" smd circle
			(at -1.260094 -9.269984 180)
			(size 0.450088 0.450088)
			(layers "F.Cu" "F.Mask" "F.Paste")
			(net "GND")
		)
		(pad "AR40" smd circle
			(at 1.560068 -9.269984 180)
			(size 0.450088 0.450088)
			(layers "F.Cu" "F.Mask" "F.Paste")
			(net "PVDDCR_CPU0_P0")
		)
		(pad "AR41" smd circle
			(at 2.500122 -9.269984 180)
			(size 0.450088 0.450088)
			(layers "F.Cu" "F.Mask" "F.Paste")
			(net "GND")
		)
		(pad "AR42" smd circle
			(at 3.439922 -9.269984 180)
			(size 0.450088 0.450088)
			(layers "F.Cu" "F.Mask" "F.Paste")
			(net "PVDDCR_CPU0_P0")
		)
		(pad "AR43" smd circle
			(at 4.379976 -9.269984 180)
			(size 0.450088 0.450088)
			(layers "F.Cu" "F.Mask" "F.Paste")
			(net "GND")
		)
		(pad "AR44" smd circle
			(at 5.32003 -9.269984 180)
			(size 0.450088 0.450088)
			(layers "F.Cu" "F.Mask" "F.Paste")
			(net "PVDDCR_CPU0_P0")
		)
		(pad "AR45" smd circle
			(at 6.260084 -9.269984 180)
			(size 0.450088 0.450088)
			(layers "F.Cu" "F.Mask" "F.Paste")
			(net "GND")
		)
		(pad "AR46" smd circle
			(at 7.199884 -9.269984 180)
			(size 0.450088 0.450088)
			(layers "F.Cu" "F.Mask" "F.Paste")
			(net "PVDDCR_CPU0_P0")
		)
		(pad "AR47" smd circle
			(at 8.139938 -9.269984 180)
			(size 0.450088 0.450088)
			(layers "F.Cu" "F.Mask" "F.Paste")
			(net "GND")
		)
		(pad "AR48" smd circle
			(at 9.079992 -9.269984 180)
			(size 0.450088 0.450088)
			(layers "F.Cu" "F.Mask" "F.Paste")
			(net "PVDDCR_CPU0_P0")
		)
		(pad "AR49" smd circle
			(at 10.020046 -9.269984 180)
			(size 0.450088 0.450088)
			(layers "F.Cu" "F.Mask" "F.Paste")
			(net "GND")
		)
		(pad "AR50" smd circle
			(at 10.9601 -9.269984 180)
			(size 0.450088 0.450088)
			(layers "F.Cu" "F.Mask" "F.Paste")
			(net "PVDDCR_CPU0_P0")
		)
		(pad "AR51" smd circle
			(at 11.8999 -9.269984 180)
			(size 0.450088 0.450088)
			(layers "F.Cu" "F.Mask" "F.Paste")
			(net "GND")
		)
		(pad "AR52" smd circle
			(at 12.839954 -9.269984 180)
			(size 0.450088 0.450088)
			(layers "F.Cu" "F.Mask" "F.Paste")
			(net "PVDD18_S5_P0")
		)
		(pad "AR53" smd circle
			(at 13.780008 -9.269984 180)
			(size 0.450088 0.450088)
			(layers "F.Cu" "F.Mask" "F.Paste")
			(net "GND")
		)
		(pad "AR54" smd circle
			(at 14.720062 -9.269984 180)
			(size 0.450088 0.450088)
			(layers "F.Cu" "F.Mask" "F.Paste")
			(net "PVDD18_S5_P0")
		)
		(pad "AR55" smd circle
			(at 15.660116 -9.269984 180)
			(size 0.450088 0.450088)
			(layers "F.Cu" "F.Mask" "F.Paste")
			(net "M_C_CPU0_SA_CB<7>")
		)
		(pad "AR56" smd circle
			(at 16.599916 -9.269984 180)
			(size 0.450088 0.450088)
			(layers "F.Cu" "F.Mask" "F.Paste")
			(net "GND")
		)
		(pad "AR57" smd circle
			(at 17.53997 -9.269984 180)
			(size 0.450088 0.450088)
			(layers "F.Cu" "F.Mask" "F.Paste")
			(net "GND")
		)
		(pad "AR58" smd circle
			(at 18.480024 -9.269984 180)
			(size 0.450088 0.450088)
			(layers "F.Cu" "F.Mask" "F.Paste")
			(net "PVDDIO_P0")
		)
		(pad "AR59" smd circle
			(at 19.420078 -9.269984 180)
			(size 0.450088 0.450088)
			(layers "F.Cu" "F.Mask" "F.Paste")
			(net "M_D_CPU0_SA_CB<7>")
		)
		(pad "AR60" smd circle
			(at 20.359878 -9.269984 180)
			(size 0.450088 0.450088)
			(layers "F.Cu" "F.Mask" "F.Paste")
			(net "GND")
		)
		(pad "AR61" smd circle
			(at 21.299932 -9.269984 180)
			(size 0.450088 0.450088)
			(layers "F.Cu" "F.Mask" "F.Paste")
			(net "GND")
		)
		(pad "AR62" smd circle
			(at 22.239986 -9.269984 180)
			(size 0.450088 0.450088)
			(layers "F.Cu" "F.Mask" "F.Paste")
			(net "M_B_CPU0_SA_CB<7>")
		)
		(pad "AR63" smd circle
			(at 23.18004 -9.269984 180)
			(size 0.450088 0.450088)
			(layers "F.Cu" "F.Mask" "F.Paste")
			(net "GND")
		)
		(pad "AR64" smd circle
			(at 24.120094 -9.269984 180)
			(size 0.450088 0.450088)
			(layers "F.Cu" "F.Mask" "F.Paste")
			(net "GND")
		)
		(pad "AR65" smd circle
			(at 25.059894 -9.269984 180)
			(size 0.450088 0.450088)
			(layers "F.Cu" "F.Mask" "F.Paste")
			(net "PVDDIO_P0")
		)
		(pad "AR66" smd circle
			(at 25.999948 -9.269984 180)
			(size 0.450088 0.450088)
			(layers "F.Cu" "F.Mask" "F.Paste")
			(net "M_F_CPU0_SA_CB<7>")
		)
		(pad "AR67" smd circle
			(at 26.940002 -9.269984 180)
			(size 0.450088 0.450088)
			(layers "F.Cu" "F.Mask" "F.Paste")
			(net "GND")
		)
		(pad "AR68" smd circle
			(at 27.880056 -9.269984 180)
			(size 0.450088 0.450088)
			(layers "F.Cu" "F.Mask" "F.Paste")
			(net "GND")
		)
		(pad "AR69" smd circle
			(at 28.82011 -9.269984 180)
			(size 0.450088 0.450088)
			(layers "F.Cu" "F.Mask" "F.Paste")
			(net "M_E_CPU0_SA_CB<7>")
		)
		(pad "AR70" smd circle
			(at 29.75991 -9.269984 180)
			(size 0.450088 0.450088)
			(layers "F.Cu" "F.Mask" "F.Paste")
			(net "GND")
		)
		(pad "AR71" smd circle
			(at 30.699964 -9.269984 180)
			(size 0.450088 0.450088)
			(layers "F.Cu" "F.Mask" "F.Paste")
			(net "GND")
		)
		(pad "AR72" smd circle
			(at 31.640018 -9.269984 180)
			(size 0.450088 0.450088)
			(layers "F.Cu" "F.Mask" "F.Paste")
			(net "PVDDIO_P0")
		)
		(pad "AR73" smd circle
			(at 32.580072 -9.269984 180)
			(size 0.450088 0.450088)
			(layers "F.Cu" "F.Mask" "F.Paste")
			(net "M_A_CPU0_SA_CB<7>")
		)
		(pad "AR74" smd circle
			(at 33.519872 -9.269984 180)
			(size 0.450088 0.450088)
			(layers "F.Cu" "F.Mask" "F.Paste")
			(net "M_A_CPU0_ALERT_R_N")
		)
		(pad "AR75" smd circle
			(at 34.459926 -9.269984 180)
			(size 0.450088 0.450088)
			(layers "F.Cu" "F.Mask" "F.Paste")
			(net "GND")
		)
		(pad "AT2" smd circle
			(at -33.690052 -8.459978 180)
			(size 0.450088 0.450088)
			(layers "F.Cu" "F.Mask" "F.Paste")
			(net "M_G_CPU0_RESET_N")
		)
		(pad "AT3" smd circle
			(at -32.749998 -8.459978 180)
			(size 0.450088 0.450088)
			(layers "F.Cu" "F.Mask" "F.Paste")
			(net "GND")
		)
		(pad "AT4" smd circle
			(at -31.809944 -8.459978 180)
			(size 0.450088 0.450088)
			(layers "F.Cu" "F.Mask" "F.Paste")
			(net "GND")
		)
		(pad "AT5" smd circle
			(at -30.86989 -8.459978 180)
			(size 0.450088 0.450088)
			(layers "F.Cu" "F.Mask" "F.Paste")
			(net "GND")
		)
		(pad "AT6" smd circle
			(at -29.93009 -8.459978 180)
			(size 0.450088 0.450088)
			(layers "F.Cu" "F.Mask" "F.Paste")
			(net "GND")
		)
		(pad "AT7" smd circle
			(at -28.990036 -8.459978 180)
			(size 0.450088 0.450088)
			(layers "F.Cu" "F.Mask" "F.Paste")
			(net "M_K_CPU0_ALERT_R_N")
		)
		(pad "AT8" smd circle
			(at -28.049982 -8.459978 180)
			(size 0.450088 0.450088)
			(layers "F.Cu" "F.Mask" "F.Paste")
			(net "GND")
		)
		(pad "AT9" smd circle
			(at -27.109928 -8.459978 180)
			(size 0.450088 0.450088)
			(layers "F.Cu" "F.Mask" "F.Paste")
			(net "GND")
		)
		(pad "AT10" smd circle
			(at -26.170128 -8.459978 180)
			(size 0.450088 0.450088)
			(layers "F.Cu" "F.Mask" "F.Paste")
			(net "GND")
		)
		(pad "AT11" smd circle
			(at -25.230074 -8.459978 180)
			(size 0.450088 0.450088)
			(layers "F.Cu" "F.Mask" "F.Paste")
			(net "M_L_CPU0_ALERT_R_N")
		)
		(pad "AT12" smd circle
			(at -24.29002 -8.459978 180)
			(size 0.450088 0.450088)
			(layers "F.Cu" "F.Mask" "F.Paste")
			(net "GND")
		)
		(pad "AT13" smd circle
			(at -23.349966 -8.459978 180)
			(size 0.450088 0.450088)
			(layers "F.Cu" "F.Mask" "F.Paste")
			(net "GND")
		)
		(pad "AT14" smd circle
			(at -22.409912 -8.459978 180)
			(size 0.450088 0.450088)
			(layers "F.Cu" "F.Mask" "F.Paste")
			(net "M_H_CPU0_ALERT_R_N")
		)
		(pad "AT15" smd circle
			(at -21.470112 -8.459978 180)
			(size 0.450088 0.450088)
			(layers "F.Cu" "F.Mask" "F.Paste")
			(net "GND")
		)
		(pad "AT16" smd circle
			(at -20.530058 -8.459978 180)
			(size 0.450088 0.450088)
			(layers "F.Cu" "F.Mask" "F.Paste")
			(net "GND")
		)
		(pad "AT17" smd circle
			(at -19.590004 -8.459978 180)
			(size 0.450088 0.450088)
			(layers "F.Cu" "F.Mask" "F.Paste")
			(net "GND")
		)
		(pad "AT18" smd circle
			(at -18.64995 -8.459978 180)
			(size 0.450088 0.450088)
			(layers "F.Cu" "F.Mask" "F.Paste")
			(net "M_J_CPU0_ALERT_R_N")
		)
		(pad "AT19" smd circle
			(at -17.709896 -8.459978 180)
			(size 0.450088 0.450088)
			(layers "F.Cu" "F.Mask" "F.Paste")
			(net "GND")
		)
		(pad "AT20" smd circle
			(at -16.770096 -8.459978 180)
			(size 0.450088 0.450088)
			(layers "F.Cu" "F.Mask" "F.Paste")
			(net "GND")
		)
		(pad "AT21" smd circle
			(at -15.830042 -8.459978 180)
			(size 0.450088 0.450088)
			(layers "F.Cu" "F.Mask" "F.Paste")
			(net "M_I_CPU0_ALERT_R_N")
		)
		(pad "AT22" smd circle
			(at -14.889988 -8.459978 180)
			(size 0.450088 0.450088)
			(layers "F.Cu" "F.Mask" "F.Paste")
			(net "PVDDCR_SOC_P0")
		)
		(pad "AT23" smd circle
			(at -13.949934 -8.459978 180)
			(size 0.450088 0.450088)
			(layers "F.Cu" "F.Mask" "F.Paste")
			(net "GND")
		)
		(pad "AT24" smd circle
			(at -13.00988 -8.459978 180)
			(size 0.450088 0.450088)
			(layers "F.Cu" "F.Mask" "F.Paste")
			(net "PVDDCR_CPU0_P0")
		)
		(pad "AT25" smd circle
			(at -12.07008 -8.459978 180)
			(size 0.450088 0.450088)
			(layers "F.Cu" "F.Mask" "F.Paste")
			(net "GND")
		)
		(pad "AT26" smd circle
			(at -11.130026 -8.459978 180)
			(size 0.450088 0.450088)
			(layers "F.Cu" "F.Mask" "F.Paste")
			(net "PVDDCR_CPU0_P0")
		)
		(pad "AT27" smd circle
			(at -10.189972 -8.459978 180)
			(size 0.450088 0.450088)
			(layers "F.Cu" "F.Mask" "F.Paste")
			(net "GND")
		)
		(pad "AT28" smd circle
			(at -9.249918 -8.459978 180)
			(size 0.450088 0.450088)
			(layers "F.Cu" "F.Mask" "F.Paste")
			(net "PVDDCR_CPU0_P0")
		)
		(pad "AT29" smd circle
			(at -8.310118 -8.459978 180)
			(size 0.450088 0.450088)
			(layers "F.Cu" "F.Mask" "F.Paste")
			(net "GND")
		)
		(pad "AT30" smd circle
			(at -7.370064 -8.459978 180)
			(size 0.450088 0.450088)
			(layers "F.Cu" "F.Mask" "F.Paste")
			(net "PVDDCR_CPU0_P0")
		)
		(pad "AT31" smd circle
			(at -6.43001 -8.459978 180)
			(size 0.450088 0.450088)
			(layers "F.Cu" "F.Mask" "F.Paste")
			(net "GND")
		)
		(pad "AT32" smd circle
			(at -5.489956 -8.459978 180)
			(size 0.450088 0.450088)
			(layers "F.Cu" "F.Mask" "F.Paste")
			(net "PVDDCR_CPU0_P0")
		)
		(pad "AT33" smd circle
			(at -4.549902 -8.459978 180)
			(size 0.450088 0.450088)
			(layers "F.Cu" "F.Mask" "F.Paste")
			(net "GND")
		)
		(pad "AT34" smd circle
			(at -3.610102 -8.459978 180)
			(size 0.450088 0.450088)
			(layers "F.Cu" "F.Mask" "F.Paste")
			(net "PVDDCR_CPU0_P0")
		)
		(pad "AT35" smd circle
			(at -2.670048 -8.459978 180)
			(size 0.450088 0.450088)
			(layers "F.Cu" "F.Mask" "F.Paste")
			(net "GND")
		)
		(pad "AT36" smd circle
			(at -1.729994 -8.459978 180)
			(size 0.450088 0.450088)
			(layers "F.Cu" "F.Mask" "F.Paste")
			(net "PVDDCR_CPU0_P0")
		)
		(pad "AT37" smd circle
			(at -0.78994 -8.459978 180)
			(size 0.450088 0.450088)
			(layers "F.Cu" "F.Mask" "F.Paste")
			(net "GND")
		)
		(pad "AT39" smd circle
			(at 1.089914 -8.459978 180)
			(size 0.450088 0.450088)
			(layers "F.Cu" "F.Mask" "F.Paste")
			(net "PVDDCR_CPU0_P0")
		)
		(pad "AT40" smd circle
			(at 2.029968 -8.459978 180)
			(size 0.450088 0.450088)
			(layers "F.Cu" "F.Mask" "F.Paste")
			(net "GND")
		)
		(pad "AT41" smd circle
			(at 2.970022 -8.459978 180)
			(size 0.450088 0.450088)
			(layers "F.Cu" "F.Mask" "F.Paste")
			(net "PVDDCR_CPU0_P0")
		)
		(pad "AT42" smd circle
			(at 3.910076 -8.459978 180)
			(size 0.450088 0.450088)
			(layers "F.Cu" "F.Mask" "F.Paste")
			(net "GND")
		)
		(pad "AT43" smd circle
			(at 4.849876 -8.459978 180)
			(size 0.450088 0.450088)
			(layers "F.Cu" "F.Mask" "F.Paste")
			(net "PVDDCR_CPU0_P0")
		)
		(pad "AT44" smd circle
			(at 5.78993 -8.459978 180)
			(size 0.450088 0.450088)
			(layers "F.Cu" "F.Mask" "F.Paste")
			(net "GND")
		)
		(pad "AT45" smd circle
			(at 6.729984 -8.459978 180)
			(size 0.450088 0.450088)
			(layers "F.Cu" "F.Mask" "F.Paste")
			(net "PVDDCR_CPU0_P0")
		)
		(pad "AT46" smd circle
			(at 7.670038 -8.459978 180)
			(size 0.450088 0.450088)
			(layers "F.Cu" "F.Mask" "F.Paste")
			(net "GND")
		)
		(pad "AT47" smd circle
			(at 8.610092 -8.459978 180)
			(size 0.450088 0.450088)
			(layers "F.Cu" "F.Mask" "F.Paste")
			(net "PVDDCR_CPU0_P0")
		)
		(pad "AT48" smd circle
			(at 9.549892 -8.459978 180)
			(size 0.450088 0.450088)
			(layers "F.Cu" "F.Mask" "F.Paste")
			(net "GND")
		)
		(pad "AT49" smd circle
			(at 10.489946 -8.459978 180)
			(size 0.450088 0.450088)
			(layers "F.Cu" "F.Mask" "F.Paste")
			(net "PVDDCR_CPU0_P0")
		)
		(pad "AT50" smd circle
			(at 11.43 -8.459978 180)
			(size 0.450088 0.450088)
			(layers "F.Cu" "F.Mask" "F.Paste")
			(net "GND")
		)
		(pad "AT51" smd circle
			(at 12.370054 -8.459978 180)
			(size 0.450088 0.450088)
			(layers "F.Cu" "F.Mask" "F.Paste")
			(net "PVDD18_S5_P0")
		)
		(pad "AT52" smd circle
			(at 13.310108 -8.459978 180)
			(size 0.450088 0.450088)
			(layers "F.Cu" "F.Mask" "F.Paste")
			(net "GND")
		)
		(pad "AT53" smd circle
			(at 14.249908 -8.459978 180)
			(size 0.450088 0.450088)
			(layers "F.Cu" "F.Mask" "F.Paste")
			(net "PVDD18_S5_P0")
		)
		(pad "AT54" smd circle
			(at 15.189962 -8.459978 180)
			(size 0.450088 0.450088)
			(layers "F.Cu" "F.Mask" "F.Paste")
			(net "GND")
		)
		(pad "AT55" smd circle
			(at 16.130016 -8.459978 180)
			(size 0.450088 0.450088)
			(layers "F.Cu" "F.Mask" "F.Paste")
			(net "M_C_CPU0_ALERT_R_N")
		)
		(pad "AT56" smd circle
			(at 17.07007 -8.459978 180)
			(size 0.450088 0.450088)
			(layers "F.Cu" "F.Mask" "F.Paste")
			(net "GND")
		)
		(pad "AT57" smd circle
			(at 18.010124 -8.459978 180)
			(size 0.450088 0.450088)
			(layers "F.Cu" "F.Mask" "F.Paste")
			(net "GND")
		)
		(pad "AT58" smd circle
			(at 18.949924 -8.459978 180)
			(size 0.450088 0.450088)
			(layers "F.Cu" "F.Mask" "F.Paste")
			(net "M_D_CPU0_ALERT_R_N")
		)
		(pad "AT59" smd circle
			(at 19.889978 -8.459978 180)
			(size 0.450088 0.450088)
			(layers "F.Cu" "F.Mask" "F.Paste")
			(net "GND")
		)
		(pad "AT60" smd circle
			(at 20.830032 -8.459978 180)
			(size 0.450088 0.450088)
			(layers "F.Cu" "F.Mask" "F.Paste")
			(net "GND")
		)
		(pad "AT61" smd circle
			(at 21.770086 -8.459978 180)
			(size 0.450088 0.450088)
			(layers "F.Cu" "F.Mask" "F.Paste")
			(net "GND")
		)
		(pad "AT62" smd circle
			(at 22.709886 -8.459978 180)
			(size 0.450088 0.450088)
			(layers "F.Cu" "F.Mask" "F.Paste")
			(net "M_B_CPU0_ALERT_R_N")
		)
		(pad "AT63" smd circle
			(at 23.64994 -8.459978 180)
			(size 0.450088 0.450088)
			(layers "F.Cu" "F.Mask" "F.Paste")
			(net "GND")
		)
		(pad "AT64" smd circle
			(at 24.589994 -8.459978 180)
			(size 0.450088 0.450088)
			(layers "F.Cu" "F.Mask" "F.Paste")
			(net "GND")
		)
		(pad "AT65" smd circle
			(at 25.530048 -8.459978 180)
			(size 0.450088 0.450088)
			(layers "F.Cu" "F.Mask" "F.Paste")
			(net "M_F_CPU0_ALERT_R_N")
		)
		(pad "AT66" smd circle
			(at 26.470102 -8.459978 180)
			(size 0.450088 0.450088)
			(layers "F.Cu" "F.Mask" "F.Paste")
			(net "GND")
		)
		(pad "AT67" smd circle
			(at 27.409902 -8.459978 180)
			(size 0.450088 0.450088)
			(layers "F.Cu" "F.Mask" "F.Paste")
			(net "GND")
		)
		(pad "AT68" smd circle
			(at 28.349956 -8.459978 180)
			(size 0.450088 0.450088)
			(layers "F.Cu" "F.Mask" "F.Paste")
			(net "GND")
		)
		(pad "AT69" smd circle
			(at 29.29001 -8.459978 180)
			(size 0.450088 0.450088)
			(layers "F.Cu" "F.Mask" "F.Paste")
			(net "M_E_CPU0_ALERT_R_N")
		)
		(pad "AT70" smd circle
			(at 30.230064 -8.459978 180)
			(size 0.450088 0.450088)
			(layers "F.Cu" "F.Mask" "F.Paste")
			(net "GND")
		)
		(pad "AT71" smd circle
			(at 31.170118 -8.459978 180)
			(size 0.450088 0.450088)
			(layers "F.Cu" "F.Mask" "F.Paste")
			(net "GND")
		)
		(pad "AT72" smd circle
			(at 32.109918 -8.459978 180)
			(size 0.450088 0.450088)
			(layers "F.Cu" "F.Mask" "F.Paste")
			(net "GND")
		)
		(pad "AT73" smd circle
			(at 33.049972 -8.459978 180)
			(size 0.450088 0.450088)
			(layers "F.Cu" "F.Mask" "F.Paste")
			(net "GND")
		)
		(pad "AT74" smd circle
			(at 33.990026 -8.459978 180)
			(size 0.450088 0.450088)
			(layers "F.Cu" "F.Mask" "F.Paste")
			(net "M_A_CPU0_RESET_N")
		)
		(pad "AU1" smd circle
			(at -34.159952 -7.649972 180)
			(size 0.450088 0.450088)
			(layers "F.Cu" "F.Mask" "F.Paste")
			(net "GND")
		)
		(pad "AU2" smd circle
			(at -33.219898 -7.649972 180)
			(size 0.450088 0.450088)
			(layers "F.Cu" "F.Mask" "F.Paste")
			(net "M_G_CPU0_SA_CS_N<0>")
		)
		(pad "AU3" smd circle
			(at -32.280098 -7.649972 180)
			(size 0.450088 0.450088)
			(layers "F.Cu" "F.Mask" "F.Paste")
			(net "GND")
		)
		(pad "AU4" smd circle
			(at -31.340044 -7.649972 180)
			(size 0.450088 0.450088)
			(layers "F.Cu" "F.Mask" "F.Paste")
			(net "GND")
		)
		(pad "AU5" smd circle
			(at -30.39999 -7.649972 180)
			(size 0.450088 0.450088)
			(layers "F.Cu" "F.Mask" "F.Paste")
			(net "M_K_CPU0_SA_CS_N<0>")
		)
		(pad "AU6" smd circle
			(at -29.459936 -7.649972 180)
			(size 0.450088 0.450088)
			(layers "F.Cu" "F.Mask" "F.Paste")
			(net "GND")
		)
		(pad "AU7" smd circle
			(at -28.519882 -7.649972 180)
			(size 0.450088 0.450088)
			(layers "F.Cu" "F.Mask" "F.Paste")
			(net "M_K_CPU0_RESET_N")
		)
		(pad "AU8" smd circle
			(at -27.580082 -7.649972 180)
			(size 0.450088 0.450088)
			(layers "F.Cu" "F.Mask" "F.Paste")
			(net "GND")
		)
		(pad "AU9" smd circle
			(at -26.640028 -7.649972 180)
			(size 0.450088 0.450088)
			(layers "F.Cu" "F.Mask" "F.Paste")
			(net "M_L_CPU0_SA_CS_N<0>")
		)
		(pad "AU10" smd circle
			(at -25.699974 -7.649972 180)
			(size 0.450088 0.450088)
			(layers "F.Cu" "F.Mask" "F.Paste")
			(net "M_L_CPU0_RESET_N")
		)
		(pad "AU11" smd circle
			(at -24.75992 -7.649972 180)
			(size 0.450088 0.450088)
			(layers "F.Cu" "F.Mask" "F.Paste")
			(net "GND")
		)
		(pad "AU12" smd circle
			(at -23.82012 -7.649972 180)
			(size 0.450088 0.450088)
			(layers "F.Cu" "F.Mask" "F.Paste")
			(net "M_H_CPU0_SA_CS_N<0>")
		)
		(pad "AU13" smd circle
			(at -22.880066 -7.649972 180)
			(size 0.450088 0.450088)
			(layers "F.Cu" "F.Mask" "F.Paste")
			(net "GND")
		)
		(pad "AU14" smd circle
			(at -21.940012 -7.649972 180)
			(size 0.450088 0.450088)
			(layers "F.Cu" "F.Mask" "F.Paste")
			(net "M_H_CPU0_RESET_N")
		)
		(pad "AU15" smd circle
			(at -20.999958 -7.649972 180)
			(size 0.450088 0.450088)
			(layers "F.Cu" "F.Mask" "F.Paste")
			(net "GND")
		)
		(pad "AU16" smd circle
			(at -20.059904 -7.649972 180)
			(size 0.450088 0.450088)
			(layers "F.Cu" "F.Mask" "F.Paste")
			(net "M_J_CPU0_SA_CS_N<0>")
		)
		(pad "AU17" smd circle
			(at -19.120104 -7.649972 180)
			(size 0.450088 0.450088)
			(layers "F.Cu" "F.Mask" "F.Paste")
			(net "M_J_CPU0_RESET_N")
		)
		(pad "AU18" smd circle
			(at -18.18005 -7.649972 180)
			(size 0.450088 0.450088)
			(layers "F.Cu" "F.Mask" "F.Paste")
			(net "GND")
		)
		(pad "AU19" smd circle
			(at -17.239996 -7.649972 180)
			(size 0.450088 0.450088)
			(layers "F.Cu" "F.Mask" "F.Paste")
			(net "M_I_CPU0_SA_CS_N<0>")
		)
		(pad "AU20" smd circle
			(at -16.299942 -7.649972 180)
			(size 0.450088 0.450088)
			(layers "F.Cu" "F.Mask" "F.Paste")
			(net "GND")
		)
		(pad "AU21" smd circle
			(at -15.359888 -7.649972 180)
			(size 0.450088 0.450088)
			(layers "F.Cu" "F.Mask" "F.Paste")
			(net "M_I_CPU0_RESET_N")
		)
		(pad "AU22" smd circle
			(at -14.420088 -7.649972 180)
			(size 0.450088 0.450088)
			(layers "F.Cu" "F.Mask" "F.Paste")
			(net "GND")
		)
		(pad "AU23" smd circle
			(at -13.480034 -7.649972 180)
			(size 0.450088 0.450088)
			(layers "F.Cu" "F.Mask" "F.Paste")
			(net "PVDDCR_SOC_P0")
		)
		(pad "AU24" smd circle
			(at -12.53998 -7.649972 180)
			(size 0.450088 0.450088)
			(layers "F.Cu" "F.Mask" "F.Paste")
			(net "GND")
		)
		(pad "AU25" smd circle
			(at -11.599926 -7.649972 180)
			(size 0.450088 0.450088)
			(layers "F.Cu" "F.Mask" "F.Paste")
			(net "PVDDCR_CPU0_P0")
		)
		(pad "AU26" smd circle
			(at -10.659872 -7.649972 180)
			(size 0.450088 0.450088)
			(layers "F.Cu" "F.Mask" "F.Paste")
			(net "GND")
		)
		(pad "AU27" smd circle
			(at -9.720072 -7.649972 180)
			(size 0.450088 0.450088)
			(layers "F.Cu" "F.Mask" "F.Paste")
			(net "PVDDCR_SOC_P0")
		)
		(pad "AU28" smd circle
			(at -8.780018 -7.649972 180)
			(size 0.450088 0.450088)
			(layers "F.Cu" "F.Mask" "F.Paste")
			(net "GND")
		)
		(pad "AU29" smd circle
			(at -7.839964 -7.649972 180)
			(size 0.450088 0.450088)
			(layers "F.Cu" "F.Mask" "F.Paste")
			(net "PVDDCR_CPU0_P0")
		)
		(pad "AU30" smd circle
			(at -6.89991 -7.649972 180)
			(size 0.450088 0.450088)
			(layers "F.Cu" "F.Mask" "F.Paste")
			(net "GND")
		)
		(pad "AU31" smd circle
			(at -5.96011 -7.649972 180)
			(size 0.450088 0.450088)
			(layers "F.Cu" "F.Mask" "F.Paste")
			(net "PVDDCR_SOC_P0")
		)
		(pad "AU32" smd circle
			(at -5.020056 -7.649972 180)
			(size 0.450088 0.450088)
			(layers "F.Cu" "F.Mask" "F.Paste")
			(net "GND")
		)
		(pad "AU33" smd circle
			(at -4.080002 -7.649972 180)
			(size 0.450088 0.450088)
			(layers "F.Cu" "F.Mask" "F.Paste")
			(net "PVDDCR_CPU0_P0")
		)
		(pad "AU34" smd circle
			(at -3.139948 -7.649972 180)
			(size 0.450088 0.450088)
			(layers "F.Cu" "F.Mask" "F.Paste")
			(net "GND")
		)
		(pad "AU35" smd circle
			(at -2.199894 -7.649972 180)
			(size 0.450088 0.450088)
			(layers "F.Cu" "F.Mask" "F.Paste")
			(net "PVDDCR_SOC_P0")
		)
		(pad "AU36" smd circle
			(at -1.260094 -7.649972 180)
			(size 0.450088 0.450088)
			(layers "F.Cu" "F.Mask" "F.Paste")
			(net "GND")
		)
		(pad "AU40" smd circle
			(at 1.560068 -7.649972 180)
			(size 0.450088 0.450088)
			(layers "F.Cu" "F.Mask" "F.Paste")
			(net "PVDDCR_SOC_P0")
		)
		(pad "AU41" smd circle
			(at 2.500122 -7.649972 180)
			(size 0.450088 0.450088)
			(layers "F.Cu" "F.Mask" "F.Paste")
			(net "GND")
		)
		(pad "AU42" smd circle
			(at 3.439922 -7.649972 180)
			(size 0.450088 0.450088)
			(layers "F.Cu" "F.Mask" "F.Paste")
			(net "PVDDCR_CPU0_P0")
		)
		(pad "AU43" smd circle
			(at 4.379976 -7.649972 180)
			(size 0.450088 0.450088)
			(layers "F.Cu" "F.Mask" "F.Paste")
			(net "GND")
		)
		(pad "AU44" smd circle
			(at 5.32003 -7.649972 180)
			(size 0.450088 0.450088)
			(layers "F.Cu" "F.Mask" "F.Paste")
			(net "PVDDCR_CPU0_P0")
		)
		(pad "AU45" smd circle
			(at 6.260084 -7.649972 180)
			(size 0.450088 0.450088)
			(layers "F.Cu" "F.Mask" "F.Paste")
			(net "GND")
		)
		(pad "AU46" smd circle
			(at 7.199884 -7.649972 180)
			(size 0.450088 0.450088)
			(layers "F.Cu" "F.Mask" "F.Paste")
			(net "PVDDCR_CPU0_P0")
		)
		(pad "AU47" smd circle
			(at 8.139938 -7.649972 180)
			(size 0.450088 0.450088)
			(layers "F.Cu" "F.Mask" "F.Paste")
			(net "GND")
		)
		(pad "AU48" smd circle
			(at 9.079992 -7.649972 180)
			(size 0.450088 0.450088)
			(layers "F.Cu" "F.Mask" "F.Paste")
			(net "PVDDCR_CPU0_P0")
		)
		(pad "AU49" smd circle
			(at 10.020046 -7.649972 180)
			(size 0.450088 0.450088)
			(layers "F.Cu" "F.Mask" "F.Paste")
			(net "GND")
		)
		(pad "AU50" smd circle
			(at 10.9601 -7.649972 180)
			(size 0.450088 0.450088)
			(layers "F.Cu" "F.Mask" "F.Paste")
			(net "PVDD18_S5_P0")
		)
		(pad "AU51" smd circle
			(at 11.8999 -7.649972 180)
			(size 0.450088 0.450088)
			(layers "F.Cu" "F.Mask" "F.Paste")
			(net "GND")
		)
		(pad "AU52" smd circle
			(at 12.839954 -7.649972 180)
			(size 0.450088 0.450088)
			(layers "F.Cu" "F.Mask" "F.Paste")
			(net "PVDD18_S5_P0")
		)
		(pad "AU53" smd circle
			(at 13.780008 -7.649972 180)
			(size 0.450088 0.450088)
			(layers "F.Cu" "F.Mask" "F.Paste")
			(net "GND")
		)
		(pad "AU54" smd circle
			(at 14.720062 -7.649972 180)
			(size 0.450088 0.450088)
			(layers "F.Cu" "F.Mask" "F.Paste")
			(net "PVDD18_S5_P0")
		)
		(pad "AU55" smd circle
			(at 15.660116 -7.649972 180)
			(size 0.450088 0.450088)
			(layers "F.Cu" "F.Mask" "F.Paste")
			(net "M_C_CPU0_RESET_N")
		)
		(pad "AU56" smd circle
			(at 16.599916 -7.649972 180)
			(size 0.450088 0.450088)
			(layers "F.Cu" "F.Mask" "F.Paste")
			(net "GND")
		)
		(pad "AU57" smd circle
			(at 17.53997 -7.649972 180)
			(size 0.450088 0.450088)
			(layers "F.Cu" "F.Mask" "F.Paste")
			(net "Net_1805")
		)
		(pad "AU58" smd circle
			(at 18.480024 -7.649972 180)
			(size 0.450088 0.450088)
			(layers "F.Cu" "F.Mask" "F.Paste")
			(net "GND")
		)
		(pad "AU59" smd circle
			(at 19.420078 -7.649972 180)
			(size 0.450088 0.450088)
			(layers "F.Cu" "F.Mask" "F.Paste")
			(net "M_D_CPU0_RESET_N")
		)
		(pad "AU60" smd circle
			(at 20.359878 -7.649972 180)
			(size 0.450088 0.450088)
			(layers "F.Cu" "F.Mask" "F.Paste")
			(net "Net_1813")
		)
		(pad "AU61" smd circle
			(at 21.299932 -7.649972 180)
			(size 0.450088 0.450088)
			(layers "F.Cu" "F.Mask" "F.Paste")
			(net "GND")
		)
		(pad "AU62" smd circle
			(at 22.239986 -7.649972 180)
			(size 0.450088 0.450088)
			(layers "F.Cu" "F.Mask" "F.Paste")
			(net "M_B_CPU0_RESET_N")
		)
		(pad "AU63" smd circle
			(at 23.18004 -7.649972 180)
			(size 0.450088 0.450088)
			(layers "F.Cu" "F.Mask" "F.Paste")
			(net "GND")
		)
		(pad "AU64" smd circle
			(at 24.120094 -7.649972 180)
			(size 0.450088 0.450088)
			(layers "F.Cu" "F.Mask" "F.Paste")
			(net "Net_1797")
		)
		(pad "AU65" smd circle
			(at 25.059894 -7.649972 180)
			(size 0.450088 0.450088)
			(layers "F.Cu" "F.Mask" "F.Paste")
			(net "GND")
		)
		(pad "AU66" smd circle
			(at 25.999948 -7.649972 180)
			(size 0.450088 0.450088)
			(layers "F.Cu" "F.Mask" "F.Paste")
			(net "M_F_CPU0_RESET_N")
		)
		(pad "AU67" smd circle
			(at 26.940002 -7.649972 180)
			(size 0.450088 0.450088)
			(layers "F.Cu" "F.Mask" "F.Paste")
			(net "Net_1829")
		)
		(pad "AU68" smd circle
			(at 27.880056 -7.649972 180)
			(size 0.450088 0.450088)
			(layers "F.Cu" "F.Mask" "F.Paste")
			(net "GND")
		)
		(pad "AU69" smd circle
			(at 28.82011 -7.649972 180)
			(size 0.450088 0.450088)
			(layers "F.Cu" "F.Mask" "F.Paste")
			(net "M_E_CPU0_RESET_N")
		)
		(pad "AU70" smd circle
			(at 29.75991 -7.649972 180)
			(size 0.450088 0.450088)
			(layers "F.Cu" "F.Mask" "F.Paste")
			(net "GND")
		)
		(pad "AU71" smd circle
			(at 30.699964 -7.649972 180)
			(size 0.450088 0.450088)
			(layers "F.Cu" "F.Mask" "F.Paste")
			(net "Net_1821")
		)
		(pad "AU72" smd circle
			(at 31.640018 -7.649972 180)
			(size 0.450088 0.450088)
			(layers "F.Cu" "F.Mask" "F.Paste")
			(net "GND")
		)
		(pad "AU73" smd circle
			(at 32.580072 -7.649972 180)
			(size 0.450088 0.450088)
			(layers "F.Cu" "F.Mask" "F.Paste")
			(net "GND")
		)
		(pad "AU74" smd circle
			(at 33.519872 -7.649972 180)
			(size 0.450088 0.450088)
			(layers "F.Cu" "F.Mask" "F.Paste")
			(net "Net_1789")
		)
		(pad "AU75" smd circle
			(at 34.459926 -7.649972 180)
			(size 0.450088 0.450088)
			(layers "F.Cu" "F.Mask" "F.Paste")
			(net "GND")
		)
		(pad "AV2" smd circle
			(at -33.690052 -6.839966 180)
			(size 0.450088 0.450088)
			(layers "F.Cu" "F.Mask" "F.Paste")
			(net "Net_1837")
		)
		(pad "AV3" smd circle
			(at -32.749998 -6.839966 180)
			(size 0.450088 0.450088)
			(layers "F.Cu" "F.Mask" "F.Paste")
			(net "GND")
		)
		(pad "AV4" smd circle
			(at -31.809944 -6.839966 180)
			(size 0.450088 0.450088)
			(layers "F.Cu" "F.Mask" "F.Paste")
			(net "M_G_CPU0_SA_CS_N<1>")
		)
		(pad "AV5" smd circle
			(at -30.86989 -6.839966 180)
			(size 0.450088 0.450088)
			(layers "F.Cu" "F.Mask" "F.Paste")
			(net "PVDDCR_SOC_P0")
		)
		(pad "AV6" smd circle
			(at -29.93009 -6.839966 180)
			(size 0.450088 0.450088)
			(layers "F.Cu" "F.Mask" "F.Paste")
			(net "Net_1966")
		)
		(pad "AV7" smd circle
			(at -28.990036 -6.839966 180)
			(size 0.450088 0.450088)
			(layers "F.Cu" "F.Mask" "F.Paste")
			(net "M_K_CPU0_SA_CS_N<1>")
		)
		(pad "AV8" smd circle
			(at -28.049982 -6.839966 180)
			(size 0.450088 0.450088)
			(layers "F.Cu" "F.Mask" "F.Paste")
			(net "GND")
		)
		(pad "AV9" smd circle
			(at -27.109928 -6.839966 180)
			(size 0.450088 0.450088)
			(layers "F.Cu" "F.Mask" "F.Paste")
			(net "Net_1958")
		)
		(pad "AV10" smd circle
			(at -26.170128 -6.839966 180)
			(size 0.450088 0.450088)
			(layers "F.Cu" "F.Mask" "F.Paste")
			(net "GND")
		)
		(pad "AV11" smd circle
			(at -25.230074 -6.839966 180)
			(size 0.450088 0.450088)
			(layers "F.Cu" "F.Mask" "F.Paste")
			(net "M_L_CPU0_SA_CS_N<1>")
		)
		(pad "AV12" smd circle
			(at -24.29002 -6.839966 180)
			(size 0.450088 0.450088)
			(layers "F.Cu" "F.Mask" "F.Paste")
			(net "PVDDCR_SOC_P0")
		)
		(pad "AV13" smd circle
			(at -23.349966 -6.839966 180)
			(size 0.450088 0.450088)
			(layers "F.Cu" "F.Mask" "F.Paste")
			(net "Net_1845")
		)
		(pad "AV14" smd circle
			(at -22.409912 -6.839966 180)
			(size 0.450088 0.450088)
			(layers "F.Cu" "F.Mask" "F.Paste")
			(net "M_H_CPU0_SA_CS_N<1>")
		)
		(pad "AV15" smd circle
			(at -21.470112 -6.839966 180)
			(size 0.450088 0.450088)
			(layers "F.Cu" "F.Mask" "F.Paste")
			(net "GND")
		)
		(pad "AV16" smd circle
			(at -20.530058 -6.839966 180)
			(size 0.450088 0.450088)
			(layers "F.Cu" "F.Mask" "F.Paste")
			(net "Net_1861")
		)
		(pad "AV17" smd circle
			(at -19.590004 -6.839966 180)
			(size 0.450088 0.450088)
			(layers "F.Cu" "F.Mask" "F.Paste")
			(net "GND")
		)
		(pad "AV18" smd circle
			(at -18.64995 -6.839966 180)
			(size 0.450088 0.450088)
			(layers "F.Cu" "F.Mask" "F.Paste")
			(net "M_J_CPU0_SA_CS_N<1>")
		)
		(pad "AV19" smd circle
			(at -17.709896 -6.839966 180)
			(size 0.450088 0.450088)
			(layers "F.Cu" "F.Mask" "F.Paste")
			(net "PVDDCR_SOC_P0")
		)
		(pad "AV20" smd circle
			(at -16.770096 -6.839966 180)
			(size 0.450088 0.450088)
			(layers "F.Cu" "F.Mask" "F.Paste")
			(net "Net_1853")
		)
		(pad "AV21" smd circle
			(at -15.830042 -6.839966 180)
			(size 0.450088 0.450088)
			(layers "F.Cu" "F.Mask" "F.Paste")
			(net "M_I_CPU0_SA_CS_N<1>")
		)
		(pad "AV22" smd circle
			(at -14.889988 -6.839966 180)
			(size 0.450088 0.450088)
			(layers "F.Cu" "F.Mask" "F.Paste")
			(net "PVDDCR_SOC_P0")
		)
		(pad "AV23" smd circle
			(at -13.949934 -6.839966 180)
			(size 0.450088 0.450088)
			(layers "F.Cu" "F.Mask" "F.Paste")
			(net "GND")
		)
		(pad "AV24" smd circle
			(at -13.00988 -6.839966 180)
			(size 0.450088 0.450088)
			(layers "F.Cu" "F.Mask" "F.Paste")
			(net "PVDDCR_SOC_P0")
		)
		(pad "AV25" smd circle
			(at -12.07008 -6.839966 180)
			(size 0.450088 0.450088)
			(layers "F.Cu" "F.Mask" "F.Paste")
			(net "GND")
		)
		(pad "AV26" smd circle
			(at -11.130026 -6.839966 180)
			(size 0.450088 0.450088)
			(layers "F.Cu" "F.Mask" "F.Paste")
			(net "PVDDCR_SOC_P0")
		)
		(pad "AV27" smd circle
			(at -10.189972 -6.839966 180)
			(size 0.450088 0.450088)
			(layers "F.Cu" "F.Mask" "F.Paste")
			(net "GND")
		)
		(pad "AV28" smd circle
			(at -9.249918 -6.839966 180)
			(size 0.450088 0.450088)
			(layers "F.Cu" "F.Mask" "F.Paste")
			(net "PVDDCR_SOC_P0")
		)
		(pad "AV29" smd circle
			(at -8.310118 -6.839966 180)
			(size 0.450088 0.450088)
			(layers "F.Cu" "F.Mask" "F.Paste")
			(net "GND")
		)
		(pad "AV30" smd circle
			(at -7.370064 -6.839966 180)
			(size 0.450088 0.450088)
			(layers "F.Cu" "F.Mask" "F.Paste")
			(net "PVDDCR_SOC_P0")
		)
		(pad "AV31" smd circle
			(at -6.43001 -6.839966 180)
			(size 0.450088 0.450088)
			(layers "F.Cu" "F.Mask" "F.Paste")
			(net "GND")
		)
		(pad "AV32" smd circle
			(at -5.489956 -6.839966 180)
			(size 0.450088 0.450088)
			(layers "F.Cu" "F.Mask" "F.Paste")
			(net "PVDDCR_SOC_P0")
		)
		(pad "AV33" smd circle
			(at -4.549902 -6.839966 180)
			(size 0.450088 0.450088)
			(layers "F.Cu" "F.Mask" "F.Paste")
			(net "GND")
		)
		(pad "AV34" smd circle
			(at -3.610102 -6.839966 180)
			(size 0.450088 0.450088)
			(layers "F.Cu" "F.Mask" "F.Paste")
			(net "PVDDCR_SOC_P0")
		)
		(pad "AV35" smd circle
			(at -2.670048 -6.839966 180)
			(size 0.450088 0.450088)
			(layers "F.Cu" "F.Mask" "F.Paste")
			(net "GND")
		)
		(pad "AV36" smd circle
			(at -1.729994 -6.839966 180)
			(size 0.450088 0.450088)
			(layers "F.Cu" "F.Mask" "F.Paste")
			(net "PVDDCR_SOC_P0")
		)
		(pad "AV37" smd circle
			(at -0.78994 -6.839966 180)
			(size 0.450088 0.450088)
			(layers "F.Cu" "F.Mask" "F.Paste")
			(net "GND")
		)
		(pad "AV39" smd circle
			(at 1.089914 -6.839966 180)
			(size 0.450088 0.450088)
			(layers "F.Cu" "F.Mask" "F.Paste")
			(net "PVDDCR_SOC_P0")
		)
		(pad "AV40" smd circle
			(at 2.029968 -6.839966 180)
			(size 0.450088 0.450088)
			(layers "F.Cu" "F.Mask" "F.Paste")
			(net "GND")
		)
		(pad "AV41" smd circle
			(at 2.970022 -6.839966 180)
			(size 0.450088 0.450088)
			(layers "F.Cu" "F.Mask" "F.Paste")
			(net "PVDDCR_SOC_P0")
		)
		(pad "AV42" smd circle
			(at 3.910076 -6.839966 180)
			(size 0.450088 0.450088)
			(layers "F.Cu" "F.Mask" "F.Paste")
			(net "GND")
		)
		(pad "AV43" smd circle
			(at 4.849876 -6.839966 180)
			(size 0.450088 0.450088)
			(layers "F.Cu" "F.Mask" "F.Paste")
			(net "PVDDCR_SOC_P0")
		)
		(pad "AV44" smd circle
			(at 5.78993 -6.839966 180)
			(size 0.450088 0.450088)
			(layers "F.Cu" "F.Mask" "F.Paste")
			(net "GND")
		)
		(pad "AV45" smd circle
			(at 6.729984 -6.839966 180)
			(size 0.450088 0.450088)
			(layers "F.Cu" "F.Mask" "F.Paste")
			(net "PVDDCR_SOC_P0")
		)
		(pad "AV46" smd circle
			(at 7.670038 -6.839966 180)
			(size 0.450088 0.450088)
			(layers "F.Cu" "F.Mask" "F.Paste")
			(net "GND")
		)
		(pad "AV47" smd circle
			(at 8.610092 -6.839966 180)
			(size 0.450088 0.450088)
			(layers "F.Cu" "F.Mask" "F.Paste")
			(net "PVDDCR_SOC_P0")
		)
		(pad "AV48" smd circle
			(at 9.549892 -6.839966 180)
			(size 0.450088 0.450088)
			(layers "F.Cu" "F.Mask" "F.Paste")
			(net "GND")
		)
		(pad "AV49" smd circle
			(at 10.489946 -6.839966 180)
			(size 0.450088 0.450088)
			(layers "F.Cu" "F.Mask" "F.Paste")
			(net "PVDD18_S5_P0")
		)
		(pad "AV50" smd circle
			(at 11.43 -6.839966 180)
			(size 0.450088 0.450088)
			(layers "F.Cu" "F.Mask" "F.Paste")
			(net "GND")
		)
		(pad "AV51" smd circle
			(at 12.370054 -6.839966 180)
			(size 0.450088 0.450088)
			(layers "F.Cu" "F.Mask" "F.Paste")
			(net "PVDD18_S5_P0")
		)
		(pad "AV52" smd circle
			(at 13.310108 -6.839966 180)
			(size 0.450088 0.450088)
			(layers "F.Cu" "F.Mask" "F.Paste")
			(net "GND")
		)
		(pad "AV53" smd circle
			(at 14.249908 -6.839966 180)
			(size 0.450088 0.450088)
			(layers "F.Cu" "F.Mask" "F.Paste")
			(net "PVDD18_S5_P0")
		)
		(pad "AV54" smd circle
			(at 15.189962 -6.839966 180)
			(size 0.450088 0.450088)
			(layers "F.Cu" "F.Mask" "F.Paste")
			(net "GND")
		)
		(pad "AV55" smd circle
			(at 16.130016 -6.839966 180)
			(size 0.450088 0.450088)
			(layers "F.Cu" "F.Mask" "F.Paste")
			(net "Net_1806")
		)
		(pad "AV56" smd circle
			(at 17.07007 -6.839966 180)
			(size 0.450088 0.450088)
			(layers "F.Cu" "F.Mask" "F.Paste")
			(net "M_C_CPU0_SA_CS_N<0>")
		)
		(pad "AV57" smd circle
			(at 18.010124 -6.839966 180)
			(size 0.450088 0.450088)
			(layers "F.Cu" "F.Mask" "F.Paste")
			(net "PVDDIO_P0")
		)
		(pad "AV58" smd circle
			(at 18.949924 -6.839966 180)
			(size 0.450088 0.450088)
			(layers "F.Cu" "F.Mask" "F.Paste")
			(net "Net_1814")
		)
		(pad "AV59" smd circle
			(at 19.889978 -6.839966 180)
			(size 0.450088 0.450088)
			(layers "F.Cu" "F.Mask" "F.Paste")
			(net "GND")
		)
		(pad "AV60" smd circle
			(at 20.830032 -6.839966 180)
			(size 0.450088 0.450088)
			(layers "F.Cu" "F.Mask" "F.Paste")
			(net "M_D_CPU0_SA_CS_N<0>")
		)
		(pad "AV61" smd circle
			(at 21.770086 -6.839966 180)
			(size 0.450088 0.450088)
			(layers "F.Cu" "F.Mask" "F.Paste")
			(net "GND")
		)
		(pad "AV62" smd circle
			(at 22.709886 -6.839966 180)
			(size 0.450088 0.450088)
			(layers "F.Cu" "F.Mask" "F.Paste")
			(net "Net_1798")
		)
		(pad "AV63" smd circle
			(at 23.64994 -6.839966 180)
			(size 0.450088 0.450088)
			(layers "F.Cu" "F.Mask" "F.Paste")
			(net "M_B_CPU0_SA_CS_N<0>")
		)
		(pad "AV64" smd circle
			(at 24.589994 -6.839966 180)
			(size 0.450088 0.450088)
			(layers "F.Cu" "F.Mask" "F.Paste")
			(net "PVDDIO_P0")
		)
		(pad "AV65" smd circle
			(at 25.530048 -6.839966 180)
			(size 0.450088 0.450088)
			(layers "F.Cu" "F.Mask" "F.Paste")
			(net "Net_1830")
		)
		(pad "AV66" smd circle
			(at 26.470102 -6.839966 180)
			(size 0.450088 0.450088)
			(layers "F.Cu" "F.Mask" "F.Paste")
			(net "GND")
		)
		(pad "AV67" smd circle
			(at 27.409902 -6.839966 180)
			(size 0.450088 0.450088)
			(layers "F.Cu" "F.Mask" "F.Paste")
			(net "M_F_CPU0_SA_CS_N<0>")
		)
		(pad "AV68" smd circle
			(at 28.349956 -6.839966 180)
			(size 0.450088 0.450088)
			(layers "F.Cu" "F.Mask" "F.Paste")
			(net "GND")
		)
		(pad "AV69" smd circle
			(at 29.29001 -6.839966 180)
			(size 0.450088 0.450088)
			(layers "F.Cu" "F.Mask" "F.Paste")
			(net "Net_1822")
		)
		(pad "AV70" smd circle
			(at 30.230064 -6.839966 180)
			(size 0.450088 0.450088)
			(layers "F.Cu" "F.Mask" "F.Paste")
			(net "M_E_CPU0_SA_CS_N<0>")
		)
		(pad "AV71" smd circle
			(at 31.170118 -6.839966 180)
			(size 0.450088 0.450088)
			(layers "F.Cu" "F.Mask" "F.Paste")
			(net "PVDDIO_P0")
		)
		(pad "AV72" smd circle
			(at 32.109918 -6.839966 180)
			(size 0.450088 0.450088)
			(layers "F.Cu" "F.Mask" "F.Paste")
			(net "Net_1790")
		)
		(pad "AV73" smd circle
			(at 33.049972 -6.839966 180)
			(size 0.450088 0.450088)
			(layers "F.Cu" "F.Mask" "F.Paste")
			(net "GND")
		)
		(pad "AV74" smd circle
			(at 33.990026 -6.839966 180)
			(size 0.450088 0.450088)
			(layers "F.Cu" "F.Mask" "F.Paste")
			(net "M_A_CPU0_SA_CS_N<0>")
		)
		(pad "AW1" smd circle
			(at -34.159952 -6.02996 180)
			(size 0.450088 0.450088)
			(layers "F.Cu" "F.Mask" "F.Paste")
			(net "GND")
		)
		(pad "AW2" smd circle
			(at -33.219898 -6.02996 180)
			(size 0.450088 0.450088)
			(layers "F.Cu" "F.Mask" "F.Paste")
			(net "M_G_CPU0_SA_CA<0>")
		)
		(pad "AW3" smd circle
			(at -32.280098 -6.02996 180)
			(size 0.450088 0.450088)
			(layers "F.Cu" "F.Mask" "F.Paste")
			(net "Net_1838")
		)
		(pad "AW4" smd circle
			(at -31.340044 -6.02996 180)
			(size 0.450088 0.450088)
			(layers "F.Cu" "F.Mask" "F.Paste")
			(net "GND")
		)
		(pad "AW5" smd circle
			(at -30.39999 -6.02996 180)
			(size 0.450088 0.450088)
			(layers "F.Cu" "F.Mask" "F.Paste")
			(net "M_K_CPU0_SA_CA<0>")
		)
		(pad "AW6" smd circle
			(at -29.459936 -6.02996 180)
			(size 0.450088 0.450088)
			(layers "F.Cu" "F.Mask" "F.Paste")
			(net "GND")
		)
		(pad "AW7" smd circle
			(at -28.519882 -6.02996 180)
			(size 0.450088 0.450088)
			(layers "F.Cu" "F.Mask" "F.Paste")
			(net "Net_1967")
		)
		(pad "AW8" smd circle
			(at -27.580082 -6.02996 180)
			(size 0.450088 0.450088)
			(layers "F.Cu" "F.Mask" "F.Paste")
			(net "GND")
		)
		(pad "AW9" smd circle
			(at -26.640028 -6.02996 180)
			(size 0.450088 0.450088)
			(layers "F.Cu" "F.Mask" "F.Paste")
			(net "M_L_CPU0_SA_CA<0>")
		)
		(pad "AW10" smd circle
			(at -25.699974 -6.02996 180)
			(size 0.450088 0.450088)
			(layers "F.Cu" "F.Mask" "F.Paste")
			(net "Net_1959")
		)
		(pad "AW11" smd circle
			(at -24.75992 -6.02996 180)
			(size 0.450088 0.450088)
			(layers "F.Cu" "F.Mask" "F.Paste")
			(net "GND")
		)
		(pad "AW12" smd circle
			(at -23.82012 -6.02996 180)
			(size 0.450088 0.450088)
			(layers "F.Cu" "F.Mask" "F.Paste")
			(net "M_H_CPU0_SA_CA<0>")
		)
		(pad "AW13" smd circle
			(at -22.880066 -6.02996 180)
			(size 0.450088 0.450088)
			(layers "F.Cu" "F.Mask" "F.Paste")
			(net "GND")
		)
		(pad "AW14" smd circle
			(at -21.940012 -6.02996 180)
			(size 0.450088 0.450088)
			(layers "F.Cu" "F.Mask" "F.Paste")
			(net "Net_1846")
		)
		(pad "AW15" smd circle
			(at -20.999958 -6.02996 180)
			(size 0.450088 0.450088)
			(layers "F.Cu" "F.Mask" "F.Paste")
			(net "GND")
		)
		(pad "AW16" smd circle
			(at -20.059904 -6.02996 180)
			(size 0.450088 0.450088)
			(layers "F.Cu" "F.Mask" "F.Paste")
			(net "M_J_CPU0_SA_CA<0>")
		)
		(pad "AW17" smd circle
			(at -19.120104 -6.02996 180)
			(size 0.450088 0.450088)
			(layers "F.Cu" "F.Mask" "F.Paste")
			(net "Net_1862")
		)
		(pad "AW18" smd circle
			(at -18.18005 -6.02996 180)
			(size 0.450088 0.450088)
			(layers "F.Cu" "F.Mask" "F.Paste")
			(net "GND")
		)
		(pad "AW19" smd circle
			(at -17.239996 -6.02996 180)
			(size 0.450088 0.450088)
			(layers "F.Cu" "F.Mask" "F.Paste")
			(net "M_I_CPU0_SA_CA<0>")
		)
		(pad "AW20" smd circle
			(at -16.299942 -6.02996 180)
			(size 0.450088 0.450088)
			(layers "F.Cu" "F.Mask" "F.Paste")
			(net "GND")
		)
		(pad "AW21" smd circle
			(at -15.359888 -6.02996 180)
			(size 0.450088 0.450088)
			(layers "F.Cu" "F.Mask" "F.Paste")
			(net "Net_1854")
		)
		(pad "AW22" smd circle
			(at -14.420088 -6.02996 180)
			(size 0.450088 0.450088)
			(layers "F.Cu" "F.Mask" "F.Paste")
			(net "GND")
		)
		(pad "AW23" smd circle
			(at -13.480034 -6.02996 180)
			(size 0.450088 0.450088)
			(layers "F.Cu" "F.Mask" "F.Paste")
			(net "PVDDCR_SOC_P0")
		)
		(pad "AW24" smd circle
			(at -12.53998 -6.02996 180)
			(size 0.450088 0.450088)
			(layers "F.Cu" "F.Mask" "F.Paste")
			(net "GND")
		)
		(pad "AW25" smd circle
			(at -11.599926 -6.02996 180)
			(size 0.450088 0.450088)
			(layers "F.Cu" "F.Mask" "F.Paste")
			(net "PVDDCR_SOC_P0")
		)
		(pad "AW26" smd circle
			(at -10.659872 -6.02996 180)
			(size 0.450088 0.450088)
			(layers "F.Cu" "F.Mask" "F.Paste")
			(net "GND")
		)
		(pad "AW27" smd circle
			(at -9.720072 -6.02996 180)
			(size 0.450088 0.450088)
			(layers "F.Cu" "F.Mask" "F.Paste")
			(net "PVDDCR_SOC_P0")
		)
		(pad "AW28" smd circle
			(at -8.780018 -6.02996 180)
			(size 0.450088 0.450088)
			(layers "F.Cu" "F.Mask" "F.Paste")
			(net "GND")
		)
		(pad "AW48" smd circle
			(at 9.079992 -6.02996 180)
			(size 0.450088 0.450088)
			(layers "F.Cu" "F.Mask" "F.Paste")
			(net "PVDDCR_SOC_P0")
		)
		(pad "AW49" smd circle
			(at 10.020046 -6.02996 180)
			(size 0.450088 0.450088)
			(layers "F.Cu" "F.Mask" "F.Paste")
			(net "GND")
		)
		(pad "AW50" smd circle
			(at 10.9601 -6.02996 180)
			(size 0.450088 0.450088)
			(layers "F.Cu" "F.Mask" "F.Paste")
			(net "PVDD18_S5_P0")
		)
		(pad "AW51" smd circle
			(at 11.8999 -6.02996 180)
			(size 0.450088 0.450088)
			(layers "F.Cu" "F.Mask" "F.Paste")
			(net "GND")
		)
		(pad "AW52" smd circle
			(at 12.839954 -6.02996 180)
			(size 0.450088 0.450088)
			(layers "F.Cu" "F.Mask" "F.Paste")
			(net "PVDD18_S5_P0")
		)
		(pad "AW53" smd circle
			(at 13.780008 -6.02996 180)
			(size 0.450088 0.450088)
			(layers "F.Cu" "F.Mask" "F.Paste")
			(net "GND")
		)
		(pad "AW54" smd circle
			(at 14.720062 -6.02996 180)
			(size 0.450088 0.450088)
			(layers "F.Cu" "F.Mask" "F.Paste")
			(net "PVDD18_S5_P0")
		)
		(pad "AW55" smd circle
			(at 15.660116 -6.02996 180)
			(size 0.450088 0.450088)
			(layers "F.Cu" "F.Mask" "F.Paste")
			(net "M_C_CPU0_SA_CS_N<1>")
		)
		(pad "AW56" smd circle
			(at 16.599916 -6.02996 180)
			(size 0.450088 0.450088)
			(layers "F.Cu" "F.Mask" "F.Paste")
			(net "GND")
		)
		(pad "AW57" smd circle
			(at 17.53997 -6.02996 180)
			(size 0.450088 0.450088)
			(layers "F.Cu" "F.Mask" "F.Paste")
			(net "M_C_CPU0_SA_CA<0>")
		)
		(pad "AW58" smd circle
			(at 18.480024 -6.02996 180)
			(size 0.450088 0.450088)
			(layers "F.Cu" "F.Mask" "F.Paste")
			(net "GND")
		)
		(pad "AW59" smd circle
			(at 19.420078 -6.02996 180)
			(size 0.450088 0.450088)
			(layers "F.Cu" "F.Mask" "F.Paste")
			(net "M_D_CPU0_SA_CS_N<1>")
		)
		(pad "AW60" smd circle
			(at 20.359878 -6.02996 180)
			(size 0.450088 0.450088)
			(layers "F.Cu" "F.Mask" "F.Paste")
			(net "M_D_CPU0_SA_CA<0>")
		)
		(pad "AW61" smd circle
			(at 21.299932 -6.02996 180)
			(size 0.450088 0.450088)
			(layers "F.Cu" "F.Mask" "F.Paste")
			(net "GND")
		)
		(pad "AW62" smd circle
			(at 22.239986 -6.02996 180)
			(size 0.450088 0.450088)
			(layers "F.Cu" "F.Mask" "F.Paste")
			(net "M_B_CPU0_SA_CS_N<1>")
		)
		(pad "AW63" smd circle
			(at 23.18004 -6.02996 180)
			(size 0.450088 0.450088)
			(layers "F.Cu" "F.Mask" "F.Paste")
			(net "GND")
		)
		(pad "AW64" smd circle
			(at 24.120094 -6.02996 180)
			(size 0.450088 0.450088)
			(layers "F.Cu" "F.Mask" "F.Paste")
			(net "M_B_CPU0_SA_CA<0>")
		)
		(pad "AW65" smd circle
			(at 25.059894 -6.02996 180)
			(size 0.450088 0.450088)
			(layers "F.Cu" "F.Mask" "F.Paste")
			(net "GND")
		)
		(pad "AW66" smd circle
			(at 25.999948 -6.02996 180)
			(size 0.450088 0.450088)
			(layers "F.Cu" "F.Mask" "F.Paste")
			(net "M_F_CPU0_SA_CS_N<1>")
		)
		(pad "AW67" smd circle
			(at 26.940002 -6.02996 180)
			(size 0.450088 0.450088)
			(layers "F.Cu" "F.Mask" "F.Paste")
			(net "M_F_CPU0_SA_CA<0>")
		)
		(pad "AW68" smd circle
			(at 27.880056 -6.02996 180)
			(size 0.450088 0.450088)
			(layers "F.Cu" "F.Mask" "F.Paste")
			(net "GND")
		)
		(pad "AW69" smd circle
			(at 28.82011 -6.02996 180)
			(size 0.450088 0.450088)
			(layers "F.Cu" "F.Mask" "F.Paste")
			(net "M_E_CPU0_SA_CS_N<1>")
		)
		(pad "AW70" smd circle
			(at 29.75991 -6.02996 180)
			(size 0.450088 0.450088)
			(layers "F.Cu" "F.Mask" "F.Paste")
			(net "GND")
		)
		(pad "AW71" smd circle
			(at 30.699964 -6.02996 180)
			(size 0.450088 0.450088)
			(layers "F.Cu" "F.Mask" "F.Paste")
			(net "M_E_CPU0_SA_CA<0>")
		)
		(pad "AW72" smd circle
			(at 31.640018 -6.02996 180)
			(size 0.450088 0.450088)
			(layers "F.Cu" "F.Mask" "F.Paste")
			(net "GND")
		)
		(pad "AW73" smd circle
			(at 32.580072 -6.02996 180)
			(size 0.450088 0.450088)
			(layers "F.Cu" "F.Mask" "F.Paste")
			(net "M_A_CPU0_SA_CS_N<1>")
		)
		(pad "AW74" smd circle
			(at 33.519872 -6.02996 180)
			(size 0.450088 0.450088)
			(layers "F.Cu" "F.Mask" "F.Paste")
			(net "M_A_CPU0_SA_CA<0>")
		)
		(pad "AW75" smd circle
			(at 34.459926 -6.02996 180)
			(size 0.450088 0.450088)
			(layers "F.Cu" "F.Mask" "F.Paste")
			(net "GND")
		)
		(pad "AY2" smd circle
			(at -33.690052 -5.219954 180)
			(size 0.450088 0.450088)
			(layers "F.Cu" "F.Mask" "F.Paste")
			(net "M_G_CPU0_SA_CA<1>")
		)
		(pad "AY3" smd circle
			(at -32.749998 -5.219954 180)
			(size 0.450088 0.450088)
			(layers "F.Cu" "F.Mask" "F.Paste")
			(net "GND")
		)
		(pad "AY4" smd circle
			(at -31.809944 -5.219954 180)
			(size 0.450088 0.450088)
			(layers "F.Cu" "F.Mask" "F.Paste")
			(net "M_G_CPU0_SA_CA<2>")
		)
		(pad "AY5" smd circle
			(at -30.86989 -5.219954 180)
			(size 0.450088 0.450088)
			(layers "F.Cu" "F.Mask" "F.Paste")
			(net "GND")
		)
		(pad "AY6" smd circle
			(at -29.93009 -5.219954 180)
			(size 0.450088 0.450088)
			(layers "F.Cu" "F.Mask" "F.Paste")
			(net "M_K_CPU0_SA_CA<1>")
		)
		(pad "AY7" smd circle
			(at -28.990036 -5.219954 180)
			(size 0.450088 0.450088)
			(layers "F.Cu" "F.Mask" "F.Paste")
			(net "M_K_CPU0_SA_CA<2>")
		)
		(pad "AY8" smd circle
			(at -28.049982 -5.219954 180)
			(size 0.450088 0.450088)
			(layers "F.Cu" "F.Mask" "F.Paste")
			(net "GND")
		)
		(pad "AY9" smd circle
			(at -27.109928 -5.219954 180)
			(size 0.450088 0.450088)
			(layers "F.Cu" "F.Mask" "F.Paste")
			(net "M_L_CPU0_SA_CA<1>")
		)
		(pad "AY10" smd circle
			(at -26.170128 -5.219954 180)
			(size 0.450088 0.450088)
			(layers "F.Cu" "F.Mask" "F.Paste")
			(net "GND")
		)
		(pad "AY11" smd circle
			(at -25.230074 -5.219954 180)
			(size 0.450088 0.450088)
			(layers "F.Cu" "F.Mask" "F.Paste")
			(net "M_L_CPU0_SA_CA<2>")
		)
		(pad "AY12" smd circle
			(at -24.29002 -5.219954 180)
			(size 0.450088 0.450088)
			(layers "F.Cu" "F.Mask" "F.Paste")
			(net "GND")
		)
		(pad "AY13" smd circle
			(at -23.349966 -5.219954 180)
			(size 0.450088 0.450088)
			(layers "F.Cu" "F.Mask" "F.Paste")
			(net "M_H_CPU0_SA_CA<1>")
		)
		(pad "AY14" smd circle
			(at -22.409912 -5.219954 180)
			(size 0.450088 0.450088)
			(layers "F.Cu" "F.Mask" "F.Paste")
			(net "M_H_CPU0_SA_CA<2>")
		)
		(pad "AY15" smd circle
			(at -21.470112 -5.219954 180)
			(size 0.450088 0.450088)
			(layers "F.Cu" "F.Mask" "F.Paste")
			(net "GND")
		)
		(pad "AY16" smd circle
			(at -20.530058 -5.219954 180)
			(size 0.450088 0.450088)
			(layers "F.Cu" "F.Mask" "F.Paste")
			(net "M_J_CPU0_SA_CA<1>")
		)
		(pad "AY17" smd circle
			(at -19.590004 -5.219954 180)
			(size 0.450088 0.450088)
			(layers "F.Cu" "F.Mask" "F.Paste")
			(net "GND")
		)
		(pad "AY18" smd circle
			(at -18.64995 -5.219954 180)
			(size 0.450088 0.450088)
			(layers "F.Cu" "F.Mask" "F.Paste")
			(net "M_J_CPU0_SA_CA<2>")
		)
		(pad "AY19" smd circle
			(at -17.709896 -5.219954 180)
			(size 0.450088 0.450088)
			(layers "F.Cu" "F.Mask" "F.Paste")
			(net "GND")
		)
		(pad "AY20" smd circle
			(at -16.770096 -5.219954 180)
			(size 0.450088 0.450088)
			(layers "F.Cu" "F.Mask" "F.Paste")
			(net "M_I_CPU0_SA_CA<1>")
		)
		(pad "AY21" smd circle
			(at -15.830042 -5.219954 180)
			(size 0.450088 0.450088)
			(layers "F.Cu" "F.Mask" "F.Paste")
			(net "M_I_CPU0_SA_CA<2>")
		)
		(pad "AY22" smd circle
			(at -14.889988 -5.219954 180)
			(size 0.450088 0.450088)
			(layers "F.Cu" "F.Mask" "F.Paste")
			(net "PVDDCR_SOC_P0")
		)
		(pad "AY23" smd circle
			(at -13.949934 -5.219954 180)
			(size 0.450088 0.450088)
			(layers "F.Cu" "F.Mask" "F.Paste")
			(net "GND")
		)
		(pad "AY24" smd circle
			(at -13.00988 -5.219954 180)
			(size 0.450088 0.450088)
			(layers "F.Cu" "F.Mask" "F.Paste")
			(net "PVDDCR_SOC_P0")
		)
		(pad "AY25" smd circle
			(at -12.07008 -5.219954 180)
			(size 0.450088 0.450088)
			(layers "F.Cu" "F.Mask" "F.Paste")
			(net "GND")
		)
		(pad "AY26" smd circle
			(at -11.130026 -5.219954 180)
			(size 0.450088 0.450088)
			(layers "F.Cu" "F.Mask" "F.Paste")
			(net "PVDDCR_SOC_P0")
		)
		(pad "AY27" smd circle
			(at -10.189972 -5.219954 180)
			(size 0.450088 0.450088)
			(layers "F.Cu" "F.Mask" "F.Paste")
			(net "GND")
		)
		(pad "AY28" smd circle
			(at -9.249918 -5.219954 180)
			(size 0.450088 0.450088)
			(layers "F.Cu" "F.Mask" "F.Paste")
			(net "PVDDCR_SOC_P0")
		)
		(pad "AY48" smd circle
			(at 9.549892 -5.219954 180)
			(size 0.450088 0.450088)
			(layers "F.Cu" "F.Mask" "F.Paste")
			(net "GND")
		)
		(pad "AY49" smd circle
			(at 10.489946 -5.219954 180)
			(size 0.450088 0.450088)
			(layers "F.Cu" "F.Mask" "F.Paste")
			(net "PVDDCR_SOC_P0")
		)
		(pad "AY50" smd circle
			(at 11.43 -5.219954 180)
			(size 0.450088 0.450088)
			(layers "F.Cu" "F.Mask" "F.Paste")
			(net "GND")
		)
		(pad "AY51" smd circle
			(at 12.370054 -5.219954 180)
			(size 0.450088 0.450088)
			(layers "F.Cu" "F.Mask" "F.Paste")
			(net "PVDD18_S5_P0")
		)
		(pad "AY52" smd circle
			(at 13.310108 -5.219954 180)
			(size 0.450088 0.450088)
			(layers "F.Cu" "F.Mask" "F.Paste")
			(net "GND")
		)
		(pad "AY53" smd circle
			(at 14.249908 -5.219954 180)
			(size 0.450088 0.450088)
			(layers "F.Cu" "F.Mask" "F.Paste")
			(net "PVDD18_S5_P0")
		)
		(pad "AY54" smd circle
			(at 15.189962 -5.219954 180)
			(size 0.450088 0.450088)
			(layers "F.Cu" "F.Mask" "F.Paste")
			(net "GND")
		)
		(pad "AY55" smd circle
			(at 16.130016 -5.219954 180)
			(size 0.450088 0.450088)
			(layers "F.Cu" "F.Mask" "F.Paste")
			(net "M_C_CPU0_SA_CA<2>")
		)
		(pad "AY56" smd circle
			(at 17.07007 -5.219954 180)
			(size 0.450088 0.450088)
			(layers "F.Cu" "F.Mask" "F.Paste")
			(net "M_C_CPU0_SA_CA<1>")
		)
		(pad "AY57" smd circle
			(at 18.010124 -5.219954 180)
			(size 0.450088 0.450088)
			(layers "F.Cu" "F.Mask" "F.Paste")
			(net "GND")
		)
		(pad "AY58" smd circle
			(at 18.949924 -5.219954 180)
			(size 0.450088 0.450088)
			(layers "F.Cu" "F.Mask" "F.Paste")
			(net "M_D_CPU0_SA_CA<2>")
		)
		(pad "AY59" smd circle
			(at 19.889978 -5.219954 180)
			(size 0.450088 0.450088)
			(layers "F.Cu" "F.Mask" "F.Paste")
			(net "GND")
		)
		(pad "AY60" smd circle
			(at 20.830032 -5.219954 180)
			(size 0.450088 0.450088)
			(layers "F.Cu" "F.Mask" "F.Paste")
			(net "M_D_CPU0_SA_CA<1>")
		)
		(pad "AY61" smd circle
			(at 21.770086 -5.219954 180)
			(size 0.450088 0.450088)
			(layers "F.Cu" "F.Mask" "F.Paste")
			(net "GND")
		)
		(pad "AY62" smd circle
			(at 22.709886 -5.219954 180)
			(size 0.450088 0.450088)
			(layers "F.Cu" "F.Mask" "F.Paste")
			(net "M_B_CPU0_SA_CA<2>")
		)
		(pad "AY63" smd circle
			(at 23.64994 -5.219954 180)
			(size 0.450088 0.450088)
			(layers "F.Cu" "F.Mask" "F.Paste")
			(net "M_B_CPU0_SA_CA<1>")
		)
		(pad "AY64" smd circle
			(at 24.589994 -5.219954 180)
			(size 0.450088 0.450088)
			(layers "F.Cu" "F.Mask" "F.Paste")
			(net "GND")
		)
		(pad "AY65" smd circle
			(at 25.530048 -5.219954 180)
			(size 0.450088 0.450088)
			(layers "F.Cu" "F.Mask" "F.Paste")
			(net "M_F_CPU0_SA_CA<2>")
		)
		(pad "AY66" smd circle
			(at 26.470102 -5.219954 180)
			(size 0.450088 0.450088)
			(layers "F.Cu" "F.Mask" "F.Paste")
			(net "GND")
		)
		(pad "AY67" smd circle
			(at 27.409902 -5.219954 180)
			(size 0.450088 0.450088)
			(layers "F.Cu" "F.Mask" "F.Paste")
			(net "M_F_CPU0_SA_CA<1>")
		)
		(pad "AY68" smd circle
			(at 28.349956 -5.219954 180)
			(size 0.450088 0.450088)
			(layers "F.Cu" "F.Mask" "F.Paste")
			(net "GND")
		)
		(pad "AY69" smd circle
			(at 29.29001 -5.219954 180)
			(size 0.450088 0.450088)
			(layers "F.Cu" "F.Mask" "F.Paste")
			(net "M_E_CPU0_SA_CA<2>")
		)
		(pad "AY70" smd circle
			(at 30.230064 -5.219954 180)
			(size 0.450088 0.450088)
			(layers "F.Cu" "F.Mask" "F.Paste")
			(net "M_E_CPU0_SA_CA<1>")
		)
		(pad "AY71" smd circle
			(at 31.170118 -5.219954 180)
			(size 0.450088 0.450088)
			(layers "F.Cu" "F.Mask" "F.Paste")
			(net "GND")
		)
		(pad "AY72" smd circle
			(at 32.109918 -5.219954 180)
			(size 0.450088 0.450088)
			(layers "F.Cu" "F.Mask" "F.Paste")
			(net "M_A_CPU0_SA_CA<2>")
		)
		(pad "AY73" smd circle
			(at 33.049972 -5.219954 180)
			(size 0.450088 0.450088)
			(layers "F.Cu" "F.Mask" "F.Paste")
			(net "GND")
		)
		(pad "AY74" smd circle
			(at 33.990026 -5.219954 180)
			(size 0.450088 0.450088)
			(layers "F.Cu" "F.Mask" "F.Paste")
			(net "M_A_CPU0_SA_CA<1>")
		)
		(pad "B3" smd circle
			(at -32.749998 -35.999928 180)
			(size 0.450088 0.450088)
			(layers "F.Cu" "F.Mask" "F.Paste")
			(net "VSENSE_PVDDCR_SOC_P0_DP")
		)
		(pad "B4" smd circle
			(at -31.809944 -35.999928 180)
			(size 0.450088 0.450088)
			(layers "F.Cu" "F.Mask" "F.Paste")
			(net "SMB_CPU0_3_R_SDA")
		)
		(pad "B5" smd circle
			(at -30.86989 -35.999928 180)
			(size 0.450088 0.450088)
			(layers "F.Cu" "F.Mask" "F.Paste")
			(net "PVDDCR_SOC_P0")
		)
		(pad "B6" smd circle
			(at -29.93009 -35.999928 180)
			(size 0.450088 0.450088)
			(layers "F.Cu" "F.Mask" "F.Paste")
			(net "CLK_100M_CPU0_CLK02_R_DP")
		)
		(pad "B7" smd circle
			(at -28.990036 -35.999928 180)
			(size 0.450088 0.450088)
			(layers "F.Cu" "F.Mask" "F.Paste")
			(net "GND")
		)
		(pad "B8" smd circle
			(at -28.049982 -35.999928 180)
			(size 0.450088 0.450088)
			(layers "F.Cu" "F.Mask" "F.Paste")
			(net "GND")
		)
		(pad "B9" smd circle
			(at -27.109928 -35.999928 180)
			(size 0.450088 0.450088)
			(layers "F.Cu" "F.Mask" "F.Paste")
			(net "CLK_100M_CPU0_CLK05_R_DP")
		)
		(pad "B10" smd circle
			(at -26.170128 -35.999928 180)
			(size 0.450088 0.450088)
			(layers "F.Cu" "F.Mask" "F.Paste")
			(net "GND")
		)
		(pad "B11" smd circle
			(at -25.230074 -35.999928 180)
			(size 0.450088 0.450088)
			(layers "F.Cu" "F.Mask" "F.Paste")
			(net "GND")
		)
		(pad "B12" smd circle
			(at -24.29002 -35.999928 180)
			(size 0.450088 0.450088)
			(layers "F.Cu" "F.Mask" "F.Paste")
			(net "CLK_100M_CPU0_CLK04_R_DP")
		)
		(pad "B13" smd circle
			(at -23.349966 -35.999928 180)
			(size 0.450088 0.450088)
			(layers "F.Cu" "F.Mask" "F.Paste")
			(net "GND")
		)
		(pad "B14" smd circle
			(at -22.409912 -35.999928 180)
			(size 0.450088 0.450088)
			(layers "F.Cu" "F.Mask" "F.Paste")
			(net "SMB_CPU0_SEC_SCL")
		)
		(pad "B15" smd circle
			(at -21.470112 -35.999928 180)
			(size 0.450088 0.450088)
			(layers "F.Cu" "F.Mask" "F.Paste")
			(net "Net_1882")
		)
		(pad "B16" smd circle
			(at -20.530058 -35.999928 180)
			(size 0.450088 0.450088)
			(layers "F.Cu" "F.Mask" "F.Paste")
			(net "Net_1875")
		)
		(pad "B17" smd circle
			(at -19.590004 -35.999928 180)
			(size 0.450088 0.450088)
			(layers "F.Cu" "F.Mask" "F.Paste")
			(net "JTAG_CPU0_TCK")
		)
		(pad "B18" smd circle
			(at -18.64995 -35.999928 180)
			(size 0.450088 0.450088)
			(layers "F.Cu" "F.Mask" "F.Paste")
			(net "GND")
		)
		(pad "B19" smd circle
			(at -17.709896 -35.999928 180)
			(size 0.450088 0.450088)
			(layers "F.Cu" "F.Mask" "F.Paste")
			(net "PVDDCR_CPU0_P0")
		)
		(pad "B20" smd circle
			(at -16.770096 -35.999928 180)
			(size 0.450088 0.450088)
			(layers "F.Cu" "F.Mask" "F.Paste")
			(net "PVDDCR_CPU0_P0")
		)
		(pad "B21" smd circle
			(at -15.830042 -35.999928 180)
			(size 0.450088 0.450088)
			(layers "F.Cu" "F.Mask" "F.Paste")
			(net "SVID_PVDDCR_CPU0_P0_SVTO")
		)
		(pad "B22" smd circle
			(at -14.889988 -35.999928 180)
			(size 0.450088 0.450088)
			(layers "F.Cu" "F.Mask" "F.Paste")
			(net "PVDDCR_CPU0_P0")
		)
		(pad "B23" smd circle
			(at -13.949934 -35.999928 180)
			(size 0.450088 0.450088)
			(layers "F.Cu" "F.Mask" "F.Paste")
			(net "PVDDCR_CPU0_P0")
		)
		(pad "B24" smd circle
			(at -13.00988 -35.999928 180)
			(size 0.450088 0.450088)
			(layers "F.Cu" "F.Mask" "F.Paste")
			(net "GND")
		)
		(pad "B25" smd circle
			(at -12.07008 -35.999928 180)
			(size 0.450088 0.450088)
			(layers "F.Cu" "F.Mask" "F.Paste")
			(net "PVDDCR_CPU0_P0")
		)
		(pad "B26" smd circle
			(at -11.130026 -35.999928 180)
			(size 0.450088 0.450088)
			(layers "F.Cu" "F.Mask" "F.Paste")
			(net "PVDDCR_CPU0_P0")
		)
		(pad "B27" smd circle
			(at -10.189972 -35.999928 180)
			(size 0.450088 0.450088)
			(layers "F.Cu" "F.Mask" "F.Paste")
			(net "GND")
		)
		(pad "B28" smd circle
			(at -9.249918 -35.999928 180)
			(size 0.450088 0.450088)
			(layers "F.Cu" "F.Mask" "F.Paste")
			(net "PVDDCR_CPU0_P0")
		)
		(pad "B29" smd circle
			(at -8.310118 -35.999928 180)
			(size 0.450088 0.450088)
			(layers "F.Cu" "F.Mask" "F.Paste")
			(net "PVDDCR_CPU0_P0")
		)
		(pad "B30" smd circle
			(at -7.370064 -35.999928 180)
			(size 0.450088 0.450088)
			(layers "F.Cu" "F.Mask" "F.Paste")
			(net "GND")
		)
		(pad "B31" smd circle
			(at -6.43001 -35.999928 180)
			(size 0.450088 0.450088)
			(layers "F.Cu" "F.Mask" "F.Paste")
			(net "PVDDCR_CPU0_P0")
		)
		(pad "B32" smd circle
			(at -5.489956 -35.999928 180)
			(size 0.450088 0.450088)
			(layers "F.Cu" "F.Mask" "F.Paste")
			(net "PVDDCR_CPU0_P0")
		)
		(pad "B33" smd circle
			(at -4.549902 -35.999928 180)
			(size 0.450088 0.450088)
			(layers "F.Cu" "F.Mask" "F.Paste")
			(net "GND")
		)
		(pad "B34" smd circle
			(at -3.610102 -35.999928 180)
			(size 0.450088 0.450088)
			(layers "F.Cu" "F.Mask" "F.Paste")
			(net "PVDDCR_CPU0_P0")
		)
		(pad "B35" smd circle
			(at -2.670048 -35.999928 180)
			(size 0.450088 0.450088)
			(layers "F.Cu" "F.Mask" "F.Paste")
			(net "PVDDCR_CPU0_P0")
		)
		(pad "B36" smd circle
			(at -1.729994 -35.999928 180)
			(size 0.450088 0.450088)
			(layers "F.Cu" "F.Mask" "F.Paste")
			(net "Net_1954")
		)
		(pad "B37" smd circle
			(at -0.78994 -35.999928 180)
			(size 0.450088 0.450088)
			(layers "F.Cu" "F.Mask" "F.Paste")
			(net "GND")
		)
		(pad "B39" smd circle
			(at 1.089914 -35.999928 180)
			(size 0.450088 0.450088)
			(layers "F.Cu" "F.Mask" "F.Paste")
			(net "GND")
		)
		(pad "B40" smd circle
			(at 2.029968 -35.999928 180)
			(size 0.450088 0.450088)
			(layers "F.Cu" "F.Mask" "F.Paste")
			(net "Net_1912")
		)
		(pad "B41" smd circle
			(at 2.970022 -35.999928 180)
			(size 0.450088 0.450088)
			(layers "F.Cu" "F.Mask" "F.Paste")
			(net "PVDDCR_CPU0_P0")
		)
		(pad "B42" smd circle
			(at 3.910076 -35.999928 180)
			(size 0.450088 0.450088)
			(layers "F.Cu" "F.Mask" "F.Paste")
			(net "PVDDCR_CPU0_P0")
		)
		(pad "B43" smd circle
			(at 4.849876 -35.999928 180)
			(size 0.450088 0.450088)
			(layers "F.Cu" "F.Mask" "F.Paste")
			(net "GND")
		)
		(pad "B44" smd circle
			(at 5.78993 -35.999928 180)
			(size 0.450088 0.450088)
			(layers "F.Cu" "F.Mask" "F.Paste")
			(net "PVDDCR_CPU0_P0")
		)
		(pad "B45" smd circle
			(at 6.729984 -35.999928 180)
			(size 0.450088 0.450088)
			(layers "F.Cu" "F.Mask" "F.Paste")
			(net "PVDDCR_CPU0_P0")
		)
		(pad "B46" smd circle
			(at 7.670038 -35.999928 180)
			(size 0.450088 0.450088)
			(layers "F.Cu" "F.Mask" "F.Paste")
			(net "GND")
		)
		(pad "B47" smd circle
			(at 8.610092 -35.999928 180)
			(size 0.450088 0.450088)
			(layers "F.Cu" "F.Mask" "F.Paste")
			(net "PVDDCR_CPU0_P0")
		)
		(pad "B48" smd circle
			(at 9.549892 -35.999928 180)
			(size 0.450088 0.450088)
			(layers "F.Cu" "F.Mask" "F.Paste")
			(net "PVDDCR_CPU0_P0")
		)
		(pad "B49" smd circle
			(at 10.489946 -35.999928 180)
			(size 0.450088 0.450088)
			(layers "F.Cu" "F.Mask" "F.Paste")
			(net "GND")
		)
		(pad "B50" smd circle
			(at 11.43 -35.999928 180)
			(size 0.450088 0.450088)
			(layers "F.Cu" "F.Mask" "F.Paste")
			(net "PVDDCR_CPU0_P0")
		)
		(pad "B51" smd circle
			(at 12.370054 -35.999928 180)
			(size 0.450088 0.450088)
			(layers "F.Cu" "F.Mask" "F.Paste")
			(net "PVDDCR_CPU0_P0")
		)
		(pad "B52" smd circle
			(at 13.310108 -35.999928 180)
			(size 0.450088 0.450088)
			(layers "F.Cu" "F.Mask" "F.Paste")
			(net "GND")
		)
		(pad "B53" smd circle
			(at 14.249908 -35.999928 180)
			(size 0.450088 0.450088)
			(layers "F.Cu" "F.Mask" "F.Paste")
			(net "PVDDCR_CPU0_P0")
		)
		(pad "B54" smd circle
			(at 15.189962 -35.999928 180)
			(size 0.450088 0.450088)
			(layers "F.Cu" "F.Mask" "F.Paste")
			(net "PVDDCR_CPU0_P0")
		)
		(pad "B55" smd circle
			(at 16.130016 -35.999928 180)
			(size 0.450088 0.450088)
			(layers "F.Cu" "F.Mask" "F.Paste")
			(net "GND")
		)
		(pad "B56" smd circle
			(at 17.07007 -35.999928 180)
			(size 0.450088 0.450088)
			(layers "F.Cu" "F.Mask" "F.Paste")
			(net "PVDDCR_CPU0_P0")
		)
		(pad "B57" smd circle
			(at 18.010124 -35.999928 180)
			(size 0.450088 0.450088)
			(layers "F.Cu" "F.Mask" "F.Paste")
			(net "PVDDCR_CPU0_P0")
		)
		(pad "B58" smd circle
			(at 18.949924 -35.999928 180)
			(size 0.450088 0.450088)
			(layers "F.Cu" "F.Mask" "F.Paste")
			(net "TP_CPU0_TEST47_IOD0")
		)
		(pad "B59" smd circle
			(at 19.889978 -35.999928 180)
			(size 0.450088 0.450088)
			(layers "F.Cu" "F.Mask" "F.Paste")
			(net "GND")
		)
		(pad "B60" smd circle
			(at 20.830032 -35.999928 180)
			(size 0.450088 0.450088)
			(layers "F.Cu" "F.Mask" "F.Paste")
			(net "TP_CPU0_TEST47_CCD0")
		)
		(pad "B61" smd circle
			(at 21.770086 -35.999928 180)
			(size 0.450088 0.450088)
			(layers "F.Cu" "F.Mask" "F.Paste")
			(net "TP_CPU0_TEST50_IOD")
		)
		(pad "B62" smd circle
			(at 22.709886 -35.999928 180)
			(size 0.450088 0.450088)
			(layers "F.Cu" "F.Mask" "F.Paste")
			(net "GND")
		)
		(pad "B63" smd circle
			(at 23.64994 -35.999928 180)
			(size 0.450088 0.450088)
			(layers "F.Cu" "F.Mask" "F.Paste")
			(net "CPU0_FORCE_SELFREFRESH")
		)
		(pad "B64" smd circle
			(at 24.589994 -35.999928 180)
			(size 0.450088 0.450088)
			(layers "F.Cu" "F.Mask" "F.Paste")
			(net "CPU0_NV_SAVE_N")
		)
		(pad "B65" smd circle
			(at 25.530048 -35.999928 180)
			(size 0.450088 0.450088)
			(layers "F.Cu" "F.Mask" "F.Paste")
			(net "GND")
		)
		(pad "B66" smd circle
			(at 26.470102 -35.999928 180)
			(size 0.450088 0.450088)
			(layers "F.Cu" "F.Mask" "F.Paste")
			(net "PRSNT_CPU0_N")
		)
		(pad "B67" smd circle
			(at 27.409902 -35.999928 180)
			(size 0.450088 0.450088)
			(layers "F.Cu" "F.Mask" "F.Paste")
			(net "RST_CPU0_RESETL_N")
		)
		(pad "B68" smd circle
			(at 28.349956 -35.999928 180)
			(size 0.450088 0.450088)
			(layers "F.Cu" "F.Mask" "F.Paste")
			(net "GND")
		)
		(pad "B69" smd circle
			(at 29.29001 -35.999928 180)
			(size 0.450088 0.450088)
			(layers "F.Cu" "F.Mask" "F.Paste")
			(net "CPU0_CORETYPE1")
		)
		(pad "B70" smd circle
			(at 30.230064 -35.999928 180)
			(size 0.450088 0.450088)
			(layers "F.Cu" "F.Mask" "F.Paste")
			(net "GND")
		)
		(pad "B71" smd circle
			(at 31.170118 -35.999928 180)
			(size 0.450088 0.450088)
			(layers "F.Cu" "F.Mask" "F.Paste")
			(net "I3C_0_SPD_DDRAF_CPU0_R_SDA")
		)
		(pad "B72" smd circle
			(at 32.109918 -35.999928 180)
			(size 0.450088 0.450088)
			(layers "F.Cu" "F.Mask" "F.Paste")
			(net "SMB_CPU0_2_R_SDA")
		)
		(pad "B73" smd circle
			(at 33.049972 -35.999928 180)
			(size 0.450088 0.450088)
			(layers "F.Cu" "F.Mask" "F.Paste")
			(net "VSENSE_PVDD18_S5_P0_DN")
		)
		(pad "BA1" smd circle
			(at -34.159952 -4.409948 180)
			(size 0.450088 0.450088)
			(layers "F.Cu" "F.Mask" "F.Paste")
			(net "GND")
		)
		(pad "BA2" smd circle
			(at -33.219898 -4.409948 180)
			(size 0.450088 0.450088)
			(layers "F.Cu" "F.Mask" "F.Paste")
			(net "M_G_CPU0_SA_CA<4>")
		)
		(pad "BA3" smd circle
			(at -32.280098 -4.409948 180)
			(size 0.450088 0.450088)
			(layers "F.Cu" "F.Mask" "F.Paste")
			(net "M_G_CPU0_SA_CA<3>")
		)
		(pad "BA4" smd circle
			(at -31.340044 -4.409948 180)
			(size 0.450088 0.450088)
			(layers "F.Cu" "F.Mask" "F.Paste")
			(net "PVDDCR_SOC_P0")
		)
		(pad "BA5" smd circle
			(at -30.39999 -4.409948 180)
			(size 0.450088 0.450088)
			(layers "F.Cu" "F.Mask" "F.Paste")
			(net "M_K_CPU0_SA_CA<4>")
		)
		(pad "BA6" smd circle
			(at -29.459936 -4.409948 180)
			(size 0.450088 0.450088)
			(layers "F.Cu" "F.Mask" "F.Paste")
			(net "GND")
		)
		(pad "BA7" smd circle
			(at -28.519882 -4.409948 180)
			(size 0.450088 0.450088)
			(layers "F.Cu" "F.Mask" "F.Paste")
			(net "M_K_CPU0_SA_CA<3>")
		)
		(pad "BA8" smd circle
			(at -27.580082 -4.409948 180)
			(size 0.450088 0.450088)
			(layers "F.Cu" "F.Mask" "F.Paste")
			(net "GND")
		)
		(pad "BA9" smd circle
			(at -26.640028 -4.409948 180)
			(size 0.450088 0.450088)
			(layers "F.Cu" "F.Mask" "F.Paste")
			(net "M_L_CPU0_SA_CA<4>")
		)
		(pad "BA10" smd circle
			(at -25.699974 -4.409948 180)
			(size 0.450088 0.450088)
			(layers "F.Cu" "F.Mask" "F.Paste")
			(net "M_L_CPU0_SA_CA<3>")
		)
		(pad "BA11" smd circle
			(at -24.75992 -4.409948 180)
			(size 0.450088 0.450088)
			(layers "F.Cu" "F.Mask" "F.Paste")
			(net "PVDDCR_SOC_P0")
		)
		(pad "BA12" smd circle
			(at -23.82012 -4.409948 180)
			(size 0.450088 0.450088)
			(layers "F.Cu" "F.Mask" "F.Paste")
			(net "M_H_CPU0_SA_CA<4>")
		)
		(pad "BA13" smd circle
			(at -22.880066 -4.409948 180)
			(size 0.450088 0.450088)
			(layers "F.Cu" "F.Mask" "F.Paste")
			(net "GND")
		)
		(pad "BA14" smd circle
			(at -21.940012 -4.409948 180)
			(size 0.450088 0.450088)
			(layers "F.Cu" "F.Mask" "F.Paste")
			(net "M_H_CPU0_SA_CA<3>")
		)
		(pad "BA15" smd circle
			(at -20.999958 -4.409948 180)
			(size 0.450088 0.450088)
			(layers "F.Cu" "F.Mask" "F.Paste")
			(net "GND")
		)
		(pad "BA16" smd circle
			(at -20.059904 -4.409948 180)
			(size 0.450088 0.450088)
			(layers "F.Cu" "F.Mask" "F.Paste")
			(net "M_J_CPU0_SA_CA<4>")
		)
		(pad "BA17" smd circle
			(at -19.120104 -4.409948 180)
			(size 0.450088 0.450088)
			(layers "F.Cu" "F.Mask" "F.Paste")
			(net "M_J_CPU0_SA_CA<3>")
		)
		(pad "BA18" smd circle
			(at -18.18005 -4.409948 180)
			(size 0.450088 0.450088)
			(layers "F.Cu" "F.Mask" "F.Paste")
			(net "PVDDCR_SOC_P0")
		)
		(pad "BA19" smd circle
			(at -17.239996 -4.409948 180)
			(size 0.450088 0.450088)
			(layers "F.Cu" "F.Mask" "F.Paste")
			(net "M_I_CPU0_SA_CA<4>")
		)
		(pad "BA20" smd circle
			(at -16.299942 -4.409948 180)
			(size 0.450088 0.450088)
			(layers "F.Cu" "F.Mask" "F.Paste")
			(net "GND")
		)
		(pad "BA21" smd circle
			(at -15.359888 -4.409948 180)
			(size 0.450088 0.450088)
			(layers "F.Cu" "F.Mask" "F.Paste")
			(net "M_I_CPU0_SA_CA<3>")
		)
		(pad "BA22" smd circle
			(at -14.420088 -4.409948 180)
			(size 0.450088 0.450088)
			(layers "F.Cu" "F.Mask" "F.Paste")
			(net "GND")
		)
		(pad "BA23" smd circle
			(at -13.480034 -4.409948 180)
			(size 0.450088 0.450088)
			(layers "F.Cu" "F.Mask" "F.Paste")
			(net "PVDDCR_SOC_P0")
		)
		(pad "BA24" smd circle
			(at -12.53998 -4.409948 180)
			(size 0.450088 0.450088)
			(layers "F.Cu" "F.Mask" "F.Paste")
			(net "GND")
		)
		(pad "BA25" smd circle
			(at -11.599926 -4.409948 180)
			(size 0.450088 0.450088)
			(layers "F.Cu" "F.Mask" "F.Paste")
			(net "PVDDCR_SOC_P0")
		)
		(pad "BA26" smd circle
			(at -10.659872 -4.409948 180)
			(size 0.450088 0.450088)
			(layers "F.Cu" "F.Mask" "F.Paste")
			(net "GND")
		)
		(pad "BA27" smd circle
			(at -9.720072 -4.409948 180)
			(size 0.450088 0.450088)
			(layers "F.Cu" "F.Mask" "F.Paste")
			(net "PVDDCR_SOC_P0")
		)
		(pad "BA28" smd circle
			(at -8.780018 -4.409948 180)
			(size 0.450088 0.450088)
			(layers "F.Cu" "F.Mask" "F.Paste")
			(net "GND")
		)
		(pad "BA48" smd circle
			(at 9.079992 -4.409948 180)
			(size 0.450088 0.450088)
			(layers "F.Cu" "F.Mask" "F.Paste")
			(net "PVDDCR_SOC_P0")
		)
		(pad "BA49" smd circle
			(at 10.020046 -4.409948 180)
			(size 0.450088 0.450088)
			(layers "F.Cu" "F.Mask" "F.Paste")
			(net "GND")
		)
		(pad "BA50" smd circle
			(at 10.9601 -4.409948 180)
			(size 0.450088 0.450088)
			(layers "F.Cu" "F.Mask" "F.Paste")
			(net "PVDD18_S5_P0")
		)
		(pad "BA51" smd circle
			(at 11.8999 -4.409948 180)
			(size 0.450088 0.450088)
			(layers "F.Cu" "F.Mask" "F.Paste")
			(net "GND")
		)
		(pad "BA52" smd circle
			(at 12.839954 -4.409948 180)
			(size 0.450088 0.450088)
			(layers "F.Cu" "F.Mask" "F.Paste")
			(net "PVDD18_S5_P0")
		)
		(pad "BA53" smd circle
			(at 13.780008 -4.409948 180)
			(size 0.450088 0.450088)
			(layers "F.Cu" "F.Mask" "F.Paste")
			(net "GND")
		)
		(pad "BA54" smd circle
			(at 14.720062 -4.409948 180)
			(size 0.450088 0.450088)
			(layers "F.Cu" "F.Mask" "F.Paste")
			(net "PVDD18_S5_P0")
		)
		(pad "BA55" smd circle
			(at 15.660116 -4.409948 180)
			(size 0.450088 0.450088)
			(layers "F.Cu" "F.Mask" "F.Paste")
			(net "M_C_CPU0_SA_CA<3>")
		)
		(pad "BA56" smd circle
			(at 16.599916 -4.409948 180)
			(size 0.450088 0.450088)
			(layers "F.Cu" "F.Mask" "F.Paste")
			(net "GND")
		)
		(pad "BA57" smd circle
			(at 17.53997 -4.409948 180)
			(size 0.450088 0.450088)
			(layers "F.Cu" "F.Mask" "F.Paste")
			(net "M_C_CPU0_SA_CA<4>")
		)
		(pad "BA58" smd circle
			(at 18.480024 -4.409948 180)
			(size 0.450088 0.450088)
			(layers "F.Cu" "F.Mask" "F.Paste")
			(net "PVDDIO_P0")
		)
		(pad "BA59" smd circle
			(at 19.420078 -4.409948 180)
			(size 0.450088 0.450088)
			(layers "F.Cu" "F.Mask" "F.Paste")
			(net "M_D_CPU0_SA_CA<3>")
		)
		(pad "BA60" smd circle
			(at 20.359878 -4.409948 180)
			(size 0.450088 0.450088)
			(layers "F.Cu" "F.Mask" "F.Paste")
			(net "M_D_CPU0_SA_CA<4>")
		)
		(pad "BA61" smd circle
			(at 21.299932 -4.409948 180)
			(size 0.450088 0.450088)
			(layers "F.Cu" "F.Mask" "F.Paste")
			(net "GND")
		)
		(pad "BA62" smd circle
			(at 22.239986 -4.409948 180)
			(size 0.450088 0.450088)
			(layers "F.Cu" "F.Mask" "F.Paste")
			(net "M_B_CPU0_SA_CA<3>")
		)
		(pad "BA63" smd circle
			(at 23.18004 -4.409948 180)
			(size 0.450088 0.450088)
			(layers "F.Cu" "F.Mask" "F.Paste")
			(net "GND")
		)
		(pad "BA64" smd circle
			(at 24.120094 -4.409948 180)
			(size 0.450088 0.450088)
			(layers "F.Cu" "F.Mask" "F.Paste")
			(net "M_B_CPU0_SA_CA<4>")
		)
		(pad "BA65" smd circle
			(at 25.059894 -4.409948 180)
			(size 0.450088 0.450088)
			(layers "F.Cu" "F.Mask" "F.Paste")
			(net "PVDDIO_P0")
		)
		(pad "BA66" smd circle
			(at 25.999948 -4.409948 180)
			(size 0.450088 0.450088)
			(layers "F.Cu" "F.Mask" "F.Paste")
			(net "M_F_CPU0_SA_CA<3>")
		)
		(pad "BA67" smd circle
			(at 26.940002 -4.409948 180)
			(size 0.450088 0.450088)
			(layers "F.Cu" "F.Mask" "F.Paste")
			(net "M_F_CPU0_SA_CA<4>")
		)
		(pad "BA68" smd circle
			(at 27.880056 -4.409948 180)
			(size 0.450088 0.450088)
			(layers "F.Cu" "F.Mask" "F.Paste")
			(net "GND")
		)
		(pad "BA69" smd circle
			(at 28.82011 -4.409948 180)
			(size 0.450088 0.450088)
			(layers "F.Cu" "F.Mask" "F.Paste")
			(net "M_E_CPU0_SA_CA<3>")
		)
		(pad "BA70" smd circle
			(at 29.75991 -4.409948 180)
			(size 0.450088 0.450088)
			(layers "F.Cu" "F.Mask" "F.Paste")
			(net "GND")
		)
		(pad "BA71" smd circle
			(at 30.699964 -4.409948 180)
			(size 0.450088 0.450088)
			(layers "F.Cu" "F.Mask" "F.Paste")
			(net "M_E_CPU0_SA_CA<4>")
		)
		(pad "BA72" smd circle
			(at 31.640018 -4.409948 180)
			(size 0.450088 0.450088)
			(layers "F.Cu" "F.Mask" "F.Paste")
			(net "PVDDIO_P0")
		)
		(pad "BA73" smd circle
			(at 32.580072 -4.409948 180)
			(size 0.450088 0.450088)
			(layers "F.Cu" "F.Mask" "F.Paste")
			(net "M_A_CPU0_SA_CA<3>")
		)
		(pad "BA74" smd circle
			(at 33.519872 -4.409948 180)
			(size 0.450088 0.450088)
			(layers "F.Cu" "F.Mask" "F.Paste")
			(net "M_A_CPU0_SA_CA<4>")
		)
		(pad "BA75" smd circle
			(at 34.459926 -4.409948 180)
			(size 0.450088 0.450088)
			(layers "F.Cu" "F.Mask" "F.Paste")
			(net "GND")
		)
		(pad "BB2" smd circle
			(at -33.690052 -3.599942 180)
			(size 0.450088 0.450088)
			(layers "F.Cu" "F.Mask" "F.Paste")
			(net "M_G_CPU0_SA_CA<5>")
		)
		(pad "BB3" smd circle
			(at -32.749998 -3.599942 180)
			(size 0.450088 0.450088)
			(layers "F.Cu" "F.Mask" "F.Paste")
			(net "GND")
		)
		(pad "BB4" smd circle
			(at -31.809944 -3.599942 180)
			(size 0.450088 0.450088)
			(layers "F.Cu" "F.Mask" "F.Paste")
			(net "M_G_CPU0_SA_CA<6>")
		)
		(pad "BB5" smd circle
			(at -30.86989 -3.599942 180)
			(size 0.450088 0.450088)
			(layers "F.Cu" "F.Mask" "F.Paste")
			(net "GND")
		)
		(pad "BB6" smd circle
			(at -29.93009 -3.599942 180)
			(size 0.450088 0.450088)
			(layers "F.Cu" "F.Mask" "F.Paste")
			(net "M_K_CPU0_SA_CA<5>")
		)
		(pad "BB7" smd circle
			(at -28.990036 -3.599942 180)
			(size 0.450088 0.450088)
			(layers "F.Cu" "F.Mask" "F.Paste")
			(net "M_K_CPU0_SA_CA<6>")
		)
		(pad "BB8" smd circle
			(at -28.049982 -3.599942 180)
			(size 0.450088 0.450088)
			(layers "F.Cu" "F.Mask" "F.Paste")
			(net "GND")
		)
		(pad "BB9" smd circle
			(at -27.109928 -3.599942 180)
			(size 0.450088 0.450088)
			(layers "F.Cu" "F.Mask" "F.Paste")
			(net "M_L_CPU0_SA_CA<5>")
		)
		(pad "BB10" smd circle
			(at -26.170128 -3.599942 180)
			(size 0.450088 0.450088)
			(layers "F.Cu" "F.Mask" "F.Paste")
			(net "GND")
		)
		(pad "BB11" smd circle
			(at -25.230074 -3.599942 180)
			(size 0.450088 0.450088)
			(layers "F.Cu" "F.Mask" "F.Paste")
			(net "M_L_CPU0_SA_CA<6>")
		)
		(pad "BB12" smd circle
			(at -24.29002 -3.599942 180)
			(size 0.450088 0.450088)
			(layers "F.Cu" "F.Mask" "F.Paste")
			(net "GND")
		)
		(pad "BB13" smd circle
			(at -23.349966 -3.599942 180)
			(size 0.450088 0.450088)
			(layers "F.Cu" "F.Mask" "F.Paste")
			(net "M_H_CPU0_SA_CA<5>")
		)
		(pad "BB14" smd circle
			(at -22.409912 -3.599942 180)
			(size 0.450088 0.450088)
			(layers "F.Cu" "F.Mask" "F.Paste")
			(net "M_H_CPU0_SA_CA<6>")
		)
		(pad "BB15" smd circle
			(at -21.470112 -3.599942 180)
			(size 0.450088 0.450088)
			(layers "F.Cu" "F.Mask" "F.Paste")
			(net "GND")
		)
		(pad "BB16" smd circle
			(at -20.530058 -3.599942 180)
			(size 0.450088 0.450088)
			(layers "F.Cu" "F.Mask" "F.Paste")
			(net "M_J_CPU0_SA_CA<5>")
		)
		(pad "BB17" smd circle
			(at -19.590004 -3.599942 180)
			(size 0.450088 0.450088)
			(layers "F.Cu" "F.Mask" "F.Paste")
			(net "GND")
		)
		(pad "BB18" smd circle
			(at -18.64995 -3.599942 180)
			(size 0.450088 0.450088)
			(layers "F.Cu" "F.Mask" "F.Paste")
			(net "M_J_CPU0_SA_CA<6>")
		)
		(pad "BB19" smd circle
			(at -17.709896 -3.599942 180)
			(size 0.450088 0.450088)
			(layers "F.Cu" "F.Mask" "F.Paste")
			(net "GND")
		)
		(pad "BB20" smd circle
			(at -16.770096 -3.599942 180)
			(size 0.450088 0.450088)
			(layers "F.Cu" "F.Mask" "F.Paste")
			(net "M_I_CPU0_SA_CA<5>")
		)
		(pad "BB21" smd circle
			(at -15.830042 -3.599942 180)
			(size 0.450088 0.450088)
			(layers "F.Cu" "F.Mask" "F.Paste")
			(net "M_I_CPU0_SA_CA<6>")
		)
		(pad "BB22" smd circle
			(at -14.889988 -3.599942 180)
			(size 0.450088 0.450088)
			(layers "F.Cu" "F.Mask" "F.Paste")
			(net "PVDDCR_SOC_P0")
		)
		(pad "BB23" smd circle
			(at -13.949934 -3.599942 180)
			(size 0.450088 0.450088)
			(layers "F.Cu" "F.Mask" "F.Paste")
			(net "GND")
		)
		(pad "BB24" smd circle
			(at -13.00988 -3.599942 180)
			(size 0.450088 0.450088)
			(layers "F.Cu" "F.Mask" "F.Paste")
			(net "PVDDCR_SOC_P0")
		)
		(pad "BB25" smd circle
			(at -12.07008 -3.599942 180)
			(size 0.450088 0.450088)
			(layers "F.Cu" "F.Mask" "F.Paste")
			(net "GND")
		)
		(pad "BB26" smd circle
			(at -11.130026 -3.599942 180)
			(size 0.450088 0.450088)
			(layers "F.Cu" "F.Mask" "F.Paste")
			(net "PVDDCR_SOC_P0")
		)
		(pad "BB27" smd circle
			(at -10.189972 -3.599942 180)
			(size 0.450088 0.450088)
			(layers "F.Cu" "F.Mask" "F.Paste")
			(net "GND")
		)
		(pad "BB28" smd circle
			(at -9.249918 -3.599942 180)
			(size 0.450088 0.450088)
			(layers "F.Cu" "F.Mask" "F.Paste")
			(net "PVDDCR_SOC_P0")
		)
		(pad "BB48" smd circle
			(at 9.549892 -3.599942 180)
			(size 0.450088 0.450088)
			(layers "F.Cu" "F.Mask" "F.Paste")
			(net "GND")
		)
		(pad "BB49" smd circle
			(at 10.489946 -3.599942 180)
			(size 0.450088 0.450088)
			(layers "F.Cu" "F.Mask" "F.Paste")
			(net "PVDDCR_SOC_P0")
		)
		(pad "BB50" smd circle
			(at 11.43 -3.599942 180)
			(size 0.450088 0.450088)
			(layers "F.Cu" "F.Mask" "F.Paste")
			(net "GND")
		)
		(pad "BB51" smd circle
			(at 12.370054 -3.599942 180)
			(size 0.450088 0.450088)
			(layers "F.Cu" "F.Mask" "F.Paste")
			(net "PVDD18_S5_P0")
		)
		(pad "BB52" smd circle
			(at 13.310108 -3.599942 180)
			(size 0.450088 0.450088)
			(layers "F.Cu" "F.Mask" "F.Paste")
			(net "GND")
		)
		(pad "BB53" smd circle
			(at 14.249908 -3.599942 180)
			(size 0.450088 0.450088)
			(layers "F.Cu" "F.Mask" "F.Paste")
			(net "PVDD18_S5_P0")
		)
		(pad "BB54" smd circle
			(at 15.189962 -3.599942 180)
			(size 0.450088 0.450088)
			(layers "F.Cu" "F.Mask" "F.Paste")
			(net "GND")
		)
		(pad "BB55" smd circle
			(at 16.130016 -3.599942 180)
			(size 0.450088 0.450088)
			(layers "F.Cu" "F.Mask" "F.Paste")
			(net "M_C_CPU0_SA_CA<6>")
		)
		(pad "BB56" smd circle
			(at 17.07007 -3.599942 180)
			(size 0.450088 0.450088)
			(layers "F.Cu" "F.Mask" "F.Paste")
			(net "M_C_CPU0_SA_CA<5>")
		)
		(pad "BB57" smd circle
			(at 18.010124 -3.599942 180)
			(size 0.450088 0.450088)
			(layers "F.Cu" "F.Mask" "F.Paste")
			(net "GND")
		)
		(pad "BB58" smd circle
			(at 18.949924 -3.599942 180)
			(size 0.450088 0.450088)
			(layers "F.Cu" "F.Mask" "F.Paste")
			(net "M_D_CPU0_SA_CA<6>")
		)
		(pad "BB59" smd circle
			(at 19.889978 -3.599942 180)
			(size 0.450088 0.450088)
			(layers "F.Cu" "F.Mask" "F.Paste")
			(net "GND")
		)
		(pad "BB60" smd circle
			(at 20.830032 -3.599942 180)
			(size 0.450088 0.450088)
			(layers "F.Cu" "F.Mask" "F.Paste")
			(net "M_D_CPU0_SA_CA<5>")
		)
		(pad "BB61" smd circle
			(at 21.770086 -3.599942 180)
			(size 0.450088 0.450088)
			(layers "F.Cu" "F.Mask" "F.Paste")
			(net "GND")
		)
		(pad "BB62" smd circle
			(at 22.709886 -3.599942 180)
			(size 0.450088 0.450088)
			(layers "F.Cu" "F.Mask" "F.Paste")
			(net "M_B_CPU0_SA_CA<6>")
		)
		(pad "BB63" smd circle
			(at 23.64994 -3.599942 180)
			(size 0.450088 0.450088)
			(layers "F.Cu" "F.Mask" "F.Paste")
			(net "M_B_CPU0_SA_CA<5>")
		)
		(pad "BB64" smd circle
			(at 24.589994 -3.599942 180)
			(size 0.450088 0.450088)
			(layers "F.Cu" "F.Mask" "F.Paste")
			(net "GND")
		)
		(pad "BB65" smd circle
			(at 25.530048 -3.599942 180)
			(size 0.450088 0.450088)
			(layers "F.Cu" "F.Mask" "F.Paste")
			(net "M_F_CPU0_SA_CA<6>")
		)
		(pad "BB66" smd circle
			(at 26.470102 -3.599942 180)
			(size 0.450088 0.450088)
			(layers "F.Cu" "F.Mask" "F.Paste")
			(net "GND")
		)
		(pad "BB67" smd circle
			(at 27.409902 -3.599942 180)
			(size 0.450088 0.450088)
			(layers "F.Cu" "F.Mask" "F.Paste")
			(net "M_F_CPU0_SA_CA<5>")
		)
		(pad "BB68" smd circle
			(at 28.349956 -3.599942 180)
			(size 0.450088 0.450088)
			(layers "F.Cu" "F.Mask" "F.Paste")
			(net "GND")
		)
		(pad "BB69" smd circle
			(at 29.29001 -3.599942 180)
			(size 0.450088 0.450088)
			(layers "F.Cu" "F.Mask" "F.Paste")
			(net "M_E_CPU0_SA_CA<6>")
		)
		(pad "BB70" smd circle
			(at 30.230064 -3.599942 180)
			(size 0.450088 0.450088)
			(layers "F.Cu" "F.Mask" "F.Paste")
			(net "M_E_CPU0_SA_CA<5>")
		)
		(pad "BB71" smd circle
			(at 31.170118 -3.599942 180)
			(size 0.450088 0.450088)
			(layers "F.Cu" "F.Mask" "F.Paste")
			(net "GND")
		)
		(pad "BB72" smd circle
			(at 32.109918 -3.599942 180)
			(size 0.450088 0.450088)
			(layers "F.Cu" "F.Mask" "F.Paste")
			(net "M_A_CPU0_SA_CA<6>")
		)
		(pad "BB73" smd circle
			(at 33.049972 -3.599942 180)
			(size 0.450088 0.450088)
			(layers "F.Cu" "F.Mask" "F.Paste")
			(net "GND")
		)
		(pad "BB74" smd circle
			(at 33.990026 -3.599942 180)
			(size 0.450088 0.450088)
			(layers "F.Cu" "F.Mask" "F.Paste")
			(net "M_A_CPU0_SA_CA<5>")
		)
		(pad "BC1" smd circle
			(at -34.159952 -2.789936 180)
			(size 0.450088 0.450088)
			(layers "F.Cu" "F.Mask" "F.Paste")
			(net "GND")
		)
		(pad "BC2" smd circle
			(at -33.219898 -2.789936 180)
			(size 0.450088 0.450088)
			(layers "F.Cu" "F.Mask" "F.Paste")
			(net "M_G_CPU0_CLK_DP<0>")
		)
		(pad "BC3" smd circle
			(at -32.280098 -2.789936 180)
			(size 0.450088 0.450088)
			(layers "F.Cu" "F.Mask" "F.Paste")
			(net "M_G_CPU0_SA_PAR")
		)
		(pad "BC4" smd circle
			(at -31.340044 -2.789936 180)
			(size 0.450088 0.450088)
			(layers "F.Cu" "F.Mask" "F.Paste")
			(net "GND")
		)
		(pad "BC5" smd circle
			(at -30.39999 -2.789936 180)
			(size 0.450088 0.450088)
			(layers "F.Cu" "F.Mask" "F.Paste")
			(net "M_K_CPU0_CLK_DP<0>")
		)
		(pad "BC6" smd circle
			(at -29.459936 -2.789936 180)
			(size 0.450088 0.450088)
			(layers "F.Cu" "F.Mask" "F.Paste")
			(net "GND")
		)
		(pad "BC7" smd circle
			(at -28.519882 -2.789936 180)
			(size 0.450088 0.450088)
			(layers "F.Cu" "F.Mask" "F.Paste")
			(net "M_K_CPU0_SA_PAR")
		)
		(pad "BC8" smd circle
			(at -27.580082 -2.789936 180)
			(size 0.450088 0.450088)
			(layers "F.Cu" "F.Mask" "F.Paste")
			(net "GND")
		)
		(pad "BC9" smd circle
			(at -26.640028 -2.789936 180)
			(size 0.450088 0.450088)
			(layers "F.Cu" "F.Mask" "F.Paste")
			(net "M_L_CPU0_CLK_DP<0>")
		)
		(pad "BC10" smd circle
			(at -25.699974 -2.789936 180)
			(size 0.450088 0.450088)
			(layers "F.Cu" "F.Mask" "F.Paste")
			(net "M_L_CPU0_SA_PAR")
		)
		(pad "BC11" smd circle
			(at -24.75992 -2.789936 180)
			(size 0.450088 0.450088)
			(layers "F.Cu" "F.Mask" "F.Paste")
			(net "GND")
		)
		(pad "BC12" smd circle
			(at -23.82012 -2.789936 180)
			(size 0.450088 0.450088)
			(layers "F.Cu" "F.Mask" "F.Paste")
			(net "M_H_CPU0_CLK_DP<0>")
		)
		(pad "BC13" smd circle
			(at -22.880066 -2.789936 180)
			(size 0.450088 0.450088)
			(layers "F.Cu" "F.Mask" "F.Paste")
			(net "GND")
		)
		(pad "BC14" smd circle
			(at -21.940012 -2.789936 180)
			(size 0.450088 0.450088)
			(layers "F.Cu" "F.Mask" "F.Paste")
			(net "M_H_CPU0_SA_PAR")
		)
		(pad "BC15" smd circle
			(at -20.999958 -2.789936 180)
			(size 0.450088 0.450088)
			(layers "F.Cu" "F.Mask" "F.Paste")
			(net "GND")
		)
		(pad "BC16" smd circle
			(at -20.059904 -2.789936 180)
			(size 0.450088 0.450088)
			(layers "F.Cu" "F.Mask" "F.Paste")
			(net "M_J_CPU0_CLK_DP<0>")
		)
		(pad "BC17" smd circle
			(at -19.120104 -2.789936 180)
			(size 0.450088 0.450088)
			(layers "F.Cu" "F.Mask" "F.Paste")
			(net "M_J_CPU0_SA_PAR")
		)
		(pad "BC18" smd circle
			(at -18.18005 -2.789936 180)
			(size 0.450088 0.450088)
			(layers "F.Cu" "F.Mask" "F.Paste")
			(net "GND")
		)
		(pad "BC19" smd circle
			(at -17.239996 -2.789936 180)
			(size 0.450088 0.450088)
			(layers "F.Cu" "F.Mask" "F.Paste")
			(net "M_I_CPU0_CLK_DP<0>")
		)
		(pad "BC20" smd circle
			(at -16.299942 -2.789936 180)
			(size 0.450088 0.450088)
			(layers "F.Cu" "F.Mask" "F.Paste")
			(net "GND")
		)
		(pad "BC21" smd circle
			(at -15.359888 -2.789936 180)
			(size 0.450088 0.450088)
			(layers "F.Cu" "F.Mask" "F.Paste")
			(net "M_I_CPU0_SA_PAR")
		)
		(pad "BC22" smd circle
			(at -14.420088 -2.789936 180)
			(size 0.450088 0.450088)
			(layers "F.Cu" "F.Mask" "F.Paste")
			(net "GND")
		)
		(pad "BC23" smd circle
			(at -13.480034 -2.789936 180)
			(size 0.450088 0.450088)
			(layers "F.Cu" "F.Mask" "F.Paste")
			(net "PVDDCR_SOC_P0")
		)
		(pad "BC24" smd circle
			(at -12.53998 -2.789936 180)
			(size 0.450088 0.450088)
			(layers "F.Cu" "F.Mask" "F.Paste")
			(net "GND")
		)
		(pad "BC25" smd circle
			(at -11.599926 -2.789936 180)
			(size 0.450088 0.450088)
			(layers "F.Cu" "F.Mask" "F.Paste")
			(net "PVDDCR_SOC_P0")
		)
		(pad "BC26" smd circle
			(at -10.659872 -2.789936 180)
			(size 0.450088 0.450088)
			(layers "F.Cu" "F.Mask" "F.Paste")
			(net "GND")
		)
		(pad "BC27" smd circle
			(at -9.720072 -2.789936 180)
			(size 0.450088 0.450088)
			(layers "F.Cu" "F.Mask" "F.Paste")
			(net "PVDDCR_SOC_P0")
		)
		(pad "BC28" smd circle
			(at -8.780018 -2.789936 180)
			(size 0.450088 0.450088)
			(layers "F.Cu" "F.Mask" "F.Paste")
			(net "GND")
		)
		(pad "BC48" smd circle
			(at 9.079992 -2.789936 180)
			(size 0.450088 0.450088)
			(layers "F.Cu" "F.Mask" "F.Paste")
			(net "PVDDCR_SOC_P0")
		)
		(pad "BC49" smd circle
			(at 10.020046 -2.789936 180)
			(size 0.450088 0.450088)
			(layers "F.Cu" "F.Mask" "F.Paste")
			(net "GND")
		)
		(pad "BC50" smd circle
			(at 10.9601 -2.789936 180)
			(size 0.450088 0.450088)
			(layers "F.Cu" "F.Mask" "F.Paste")
			(net "GND")
		)
		(pad "BC51" smd circle
			(at 11.8999 -2.789936 180)
			(size 0.450088 0.450088)
			(layers "F.Cu" "F.Mask" "F.Paste")
			(net "GND")
		)
		(pad "BC52" smd circle
			(at 12.839954 -2.789936 180)
			(size 0.450088 0.450088)
			(layers "F.Cu" "F.Mask" "F.Paste")
			(net "PVDD18_S5_P0")
		)
		(pad "BC53" smd circle
			(at 13.780008 -2.789936 180)
			(size 0.450088 0.450088)
			(layers "F.Cu" "F.Mask" "F.Paste")
			(net "GND")
		)
		(pad "BC54" smd circle
			(at 14.720062 -2.789936 180)
			(size 0.450088 0.450088)
			(layers "F.Cu" "F.Mask" "F.Paste")
			(net "PVDD18_S5_P0")
		)
		(pad "BC55" smd circle
			(at 15.660116 -2.789936 180)
			(size 0.450088 0.450088)
			(layers "F.Cu" "F.Mask" "F.Paste")
			(net "M_C_CPU0_SA_PAR")
		)
		(pad "BC56" smd circle
			(at 16.599916 -2.789936 180)
			(size 0.450088 0.450088)
			(layers "F.Cu" "F.Mask" "F.Paste")
			(net "GND")
		)
		(pad "BC57" smd circle
			(at 17.53997 -2.789936 180)
			(size 0.450088 0.450088)
			(layers "F.Cu" "F.Mask" "F.Paste")
			(net "M_C_CPU0_CLK_DP<0>")
		)
		(pad "BC58" smd circle
			(at 18.480024 -2.789936 180)
			(size 0.450088 0.450088)
			(layers "F.Cu" "F.Mask" "F.Paste")
			(net "GND")
		)
		(pad "BC59" smd circle
			(at 19.420078 -2.789936 180)
			(size 0.450088 0.450088)
			(layers "F.Cu" "F.Mask" "F.Paste")
			(net "M_D_CPU0_SA_PAR")
		)
		(pad "BC60" smd circle
			(at 20.359878 -2.789936 180)
			(size 0.450088 0.450088)
			(layers "F.Cu" "F.Mask" "F.Paste")
			(net "M_D_CPU0_CLK_DP<0>")
		)
		(pad "BC61" smd circle
			(at 21.299932 -2.789936 180)
			(size 0.450088 0.450088)
			(layers "F.Cu" "F.Mask" "F.Paste")
			(net "GND")
		)
		(pad "BC62" smd circle
			(at 22.239986 -2.789936 180)
			(size 0.450088 0.450088)
			(layers "F.Cu" "F.Mask" "F.Paste")
			(net "M_B_CPU0_SA_PAR")
		)
		(pad "BC63" smd circle
			(at 23.18004 -2.789936 180)
			(size 0.450088 0.450088)
			(layers "F.Cu" "F.Mask" "F.Paste")
			(net "GND")
		)
		(pad "BC64" smd circle
			(at 24.120094 -2.789936 180)
			(size 0.450088 0.450088)
			(layers "F.Cu" "F.Mask" "F.Paste")
			(net "M_B_CPU0_CLK_DP<0>")
		)
		(pad "BC65" smd circle
			(at 25.059894 -2.789936 180)
			(size 0.450088 0.450088)
			(layers "F.Cu" "F.Mask" "F.Paste")
			(net "GND")
		)
		(pad "BC66" smd circle
			(at 25.999948 -2.789936 180)
			(size 0.450088 0.450088)
			(layers "F.Cu" "F.Mask" "F.Paste")
			(net "M_F_CPU0_SA_PAR")
		)
		(pad "BC67" smd circle
			(at 26.940002 -2.789936 180)
			(size 0.450088 0.450088)
			(layers "F.Cu" "F.Mask" "F.Paste")
			(net "M_F_CPU0_CLK_DP<0>")
		)
		(pad "BC68" smd circle
			(at 27.880056 -2.789936 180)
			(size 0.450088 0.450088)
			(layers "F.Cu" "F.Mask" "F.Paste")
			(net "GND")
		)
		(pad "BC69" smd circle
			(at 28.82011 -2.789936 180)
			(size 0.450088 0.450088)
			(layers "F.Cu" "F.Mask" "F.Paste")
			(net "M_E_CPU0_SA_PAR")
		)
		(pad "BC70" smd circle
			(at 29.75991 -2.789936 180)
			(size 0.450088 0.450088)
			(layers "F.Cu" "F.Mask" "F.Paste")
			(net "GND")
		)
		(pad "BC71" smd circle
			(at 30.699964 -2.789936 180)
			(size 0.450088 0.450088)
			(layers "F.Cu" "F.Mask" "F.Paste")
			(net "M_E_CPU0_CLK_DP<0>")
		)
		(pad "BC72" smd circle
			(at 31.640018 -2.789936 180)
			(size 0.450088 0.450088)
			(layers "F.Cu" "F.Mask" "F.Paste")
			(net "GND")
		)
		(pad "BC73" smd circle
			(at 32.580072 -2.789936 180)
			(size 0.450088 0.450088)
			(layers "F.Cu" "F.Mask" "F.Paste")
			(net "M_A_CPU0_SA_PAR")
		)
		(pad "BC74" smd circle
			(at 33.519872 -2.789936 180)
			(size 0.450088 0.450088)
			(layers "F.Cu" "F.Mask" "F.Paste")
			(net "M_A_CPU0_CLK_DP<0>")
		)
		(pad "BC75" smd circle
			(at 34.459926 -2.789936 180)
			(size 0.450088 0.450088)
			(layers "F.Cu" "F.Mask" "F.Paste")
			(net "GND")
		)
		(pad "BD2" smd circle
			(at -33.690052 -1.97993 180)
			(size 0.450088 0.450088)
			(layers "F.Cu" "F.Mask" "F.Paste")
			(net "M_G_CPU0_CLK_DN<0>")
		)
		(pad "BD3" smd circle
			(at -32.749998 -1.97993 180)
			(size 0.450088 0.450088)
			(layers "F.Cu" "F.Mask" "F.Paste")
			(net "GND")
		)
		(pad "BD4" smd circle
			(at -31.809944 -1.97993 180)
			(size 0.450088 0.450088)
			(layers "F.Cu" "F.Mask" "F.Paste")
			(net "Net_1917")
		)
		(pad "BD5" smd circle
			(at -30.86989 -1.97993 180)
			(size 0.450088 0.450088)
			(layers "F.Cu" "F.Mask" "F.Paste")
			(net "PVDDCR_SOC_P0")
		)
		(pad "BD6" smd circle
			(at -29.93009 -1.97993 180)
			(size 0.450088 0.450088)
			(layers "F.Cu" "F.Mask" "F.Paste")
			(net "M_K_CPU0_CLK_DN<0>")
		)
		(pad "BD7" smd circle
			(at -28.990036 -1.97993 180)
			(size 0.450088 0.450088)
			(layers "F.Cu" "F.Mask" "F.Paste")
			(net "Net_1923")
		)
		(pad "BD8" smd circle
			(at -28.049982 -1.97993 180)
			(size 0.450088 0.450088)
			(layers "F.Cu" "F.Mask" "F.Paste")
			(net "GND")
		)
		(pad "BD9" smd circle
			(at -27.109928 -1.97993 180)
			(size 0.450088 0.450088)
			(layers "F.Cu" "F.Mask" "F.Paste")
			(net "M_L_CPU0_CLK_DN<0>")
		)
		(pad "BD10" smd circle
			(at -26.170128 -1.97993 180)
			(size 0.450088 0.450088)
			(layers "F.Cu" "F.Mask" "F.Paste")
			(net "GND")
		)
		(pad "BD11" smd circle
			(at -25.230074 -1.97993 180)
			(size 0.450088 0.450088)
			(layers "F.Cu" "F.Mask" "F.Paste")
			(net "Net_1913")
		)
		(pad "BD12" smd circle
			(at -24.29002 -1.97993 180)
			(size 0.450088 0.450088)
			(layers "F.Cu" "F.Mask" "F.Paste")
			(net "PVDDCR_SOC_P0")
		)
		(pad "BD13" smd circle
			(at -23.349966 -1.97993 180)
			(size 0.450088 0.450088)
			(layers "F.Cu" "F.Mask" "F.Paste")
			(net "M_H_CPU0_CLK_DN<0>")
		)
		(pad "BD14" smd circle
			(at -22.409912 -1.97993 180)
			(size 0.450088 0.450088)
			(layers "F.Cu" "F.Mask" "F.Paste")
			(net "Net_1914")
		)
		(pad "BD15" smd circle
			(at -21.470112 -1.97993 180)
			(size 0.450088 0.450088)
			(layers "F.Cu" "F.Mask" "F.Paste")
			(net "GND")
		)
		(pad "BD16" smd circle
			(at -20.530058 -1.97993 180)
			(size 0.450088 0.450088)
			(layers "F.Cu" "F.Mask" "F.Paste")
			(net "M_J_CPU0_CLK_DN<0>")
		)
		(pad "BD17" smd circle
			(at -19.590004 -1.97993 180)
			(size 0.450088 0.450088)
			(layers "F.Cu" "F.Mask" "F.Paste")
			(net "GND")
		)
		(pad "BD18" smd circle
			(at -18.64995 -1.97993 180)
			(size 0.450088 0.450088)
			(layers "F.Cu" "F.Mask" "F.Paste")
			(net "Net_1915")
		)
		(pad "BD19" smd circle
			(at -17.709896 -1.97993 180)
			(size 0.450088 0.450088)
			(layers "F.Cu" "F.Mask" "F.Paste")
			(net "PVDDCR_SOC_P0")
		)
		(pad "BD20" smd circle
			(at -16.770096 -1.97993 180)
			(size 0.450088 0.450088)
			(layers "F.Cu" "F.Mask" "F.Paste")
			(net "M_I_CPU0_CLK_DN<0>")
		)
		(pad "BD21" smd circle
			(at -15.830042 -1.97993 180)
			(size 0.450088 0.450088)
			(layers "F.Cu" "F.Mask" "F.Paste")
			(net "Net_1916")
		)
		(pad "BD22" smd circle
			(at -14.889988 -1.97993 180)
			(size 0.450088 0.450088)
			(layers "F.Cu" "F.Mask" "F.Paste")
			(net "PVDDCR_SOC_P0")
		)
		(pad "BD23" smd circle
			(at -13.949934 -1.97993 180)
			(size 0.450088 0.450088)
			(layers "F.Cu" "F.Mask" "F.Paste")
			(net "GND")
		)
		(pad "BD24" smd circle
			(at -13.00988 -1.97993 180)
			(size 0.450088 0.450088)
			(layers "F.Cu" "F.Mask" "F.Paste")
			(net "PVDDCR_SOC_P0")
		)
		(pad "BD25" smd circle
			(at -12.07008 -1.97993 180)
			(size 0.450088 0.450088)
			(layers "F.Cu" "F.Mask" "F.Paste")
			(net "GND")
		)
		(pad "BD26" smd circle
			(at -11.130026 -1.97993 180)
			(size 0.450088 0.450088)
			(layers "F.Cu" "F.Mask" "F.Paste")
			(net "PVDDCR_SOC_P0")
		)
		(pad "BD27" smd circle
			(at -10.189972 -1.97993 180)
			(size 0.450088 0.450088)
			(layers "F.Cu" "F.Mask" "F.Paste")
			(net "GND")
		)
		(pad "BD28" smd circle
			(at -9.249918 -1.97993 180)
			(size 0.450088 0.450088)
			(layers "F.Cu" "F.Mask" "F.Paste")
			(net "PVDDCR_SOC_P0")
		)
		(pad "BD48" smd circle
			(at 9.549892 -1.97993 180)
			(size 0.450088 0.450088)
			(layers "F.Cu" "F.Mask" "F.Paste")
			(net "PVDDCR_SOC_P0")
		)
		(pad "BD49" smd circle
			(at 10.489946 -1.97993 180)
			(size 0.450088 0.450088)
			(layers "F.Cu" "F.Mask" "F.Paste")
			(net "GND")
		)
		(pad "BD50" smd circle
			(at 11.43 -1.97993 180)
			(size 0.450088 0.450088)
			(layers "F.Cu" "F.Mask" "F.Paste")
			(net "PVDDIO_P0")
		)
		(pad "BD51" smd circle
			(at 12.370054 -1.97993 180)
			(size 0.450088 0.450088)
			(layers "F.Cu" "F.Mask" "F.Paste")
			(net "GND")
		)
		(pad "BD52" smd circle
			(at 13.310108 -1.97993 180)
			(size 0.450088 0.450088)
			(layers "F.Cu" "F.Mask" "F.Paste")
			(net "PVDDIO_P0")
		)
		(pad "BD53" smd circle
			(at 14.249908 -1.97993 180)
			(size 0.450088 0.450088)
			(layers "F.Cu" "F.Mask" "F.Paste")
			(net "GND")
		)
		(pad "BD54" smd circle
			(at 15.189962 -1.97993 180)
			(size 0.450088 0.450088)
			(layers "F.Cu" "F.Mask" "F.Paste")
			(net "PVDDIO_P0")
		)
		(pad "BD55" smd circle
			(at 16.130016 -1.97993 180)
			(size 0.450088 0.450088)
			(layers "F.Cu" "F.Mask" "F.Paste")
			(net "Net_1918")
		)
		(pad "BD56" smd circle
			(at 17.07007 -1.97993 180)
			(size 0.450088 0.450088)
			(layers "F.Cu" "F.Mask" "F.Paste")
			(net "M_C_CPU0_CLK_DN<0>")
		)
		(pad "BD57" smd circle
			(at 18.010124 -1.97993 180)
			(size 0.450088 0.450088)
			(layers "F.Cu" "F.Mask" "F.Paste")
			(net "GND")
		)
		(pad "BD58" smd circle
			(at 18.949924 -1.97993 180)
			(size 0.450088 0.450088)
			(layers "F.Cu" "F.Mask" "F.Paste")
			(net "Net_1919")
		)
		(pad "BD59" smd circle
			(at 19.889978 -1.97993 180)
			(size 0.450088 0.450088)
			(layers "F.Cu" "F.Mask" "F.Paste")
			(net "GND")
		)
		(pad "BD60" smd circle
			(at 20.830032 -1.97993 180)
			(size 0.450088 0.450088)
			(layers "F.Cu" "F.Mask" "F.Paste")
			(net "M_D_CPU0_CLK_DN<0>")
		)
		(pad "BD61" smd circle
			(at 21.770086 -1.97993 180)
			(size 0.450088 0.450088)
			(layers "F.Cu" "F.Mask" "F.Paste")
			(net "GND")
		)
		(pad "BD62" smd circle
			(at 22.709886 -1.97993 180)
			(size 0.450088 0.450088)
			(layers "F.Cu" "F.Mask" "F.Paste")
			(net "Net_1920")
		)
		(pad "BD63" smd circle
			(at 23.64994 -1.97993 180)
			(size 0.450088 0.450088)
			(layers "F.Cu" "F.Mask" "F.Paste")
			(net "M_B_CPU0_CLK_DN<0>")
		)
		(pad "BD64" smd circle
			(at 24.589994 -1.97993 180)
			(size 0.450088 0.450088)
			(layers "F.Cu" "F.Mask" "F.Paste")
			(net "GND")
		)
		(pad "BD65" smd circle
			(at 25.530048 -1.97993 180)
			(size 0.450088 0.450088)
			(layers "F.Cu" "F.Mask" "F.Paste")
			(net "Net_1921")
		)
		(pad "BD66" smd circle
			(at 26.470102 -1.97993 180)
			(size 0.450088 0.450088)
			(layers "F.Cu" "F.Mask" "F.Paste")
			(net "GND")
		)
		(pad "BD67" smd circle
			(at 27.409902 -1.97993 180)
			(size 0.450088 0.450088)
			(layers "F.Cu" "F.Mask" "F.Paste")
			(net "M_F_CPU0_CLK_DN<0>")
		)
		(pad "BD68" smd circle
			(at 28.349956 -1.97993 180)
			(size 0.450088 0.450088)
			(layers "F.Cu" "F.Mask" "F.Paste")
			(net "GND")
		)
		(pad "BD69" smd circle
			(at 29.29001 -1.97993 180)
			(size 0.450088 0.450088)
			(layers "F.Cu" "F.Mask" "F.Paste")
			(net "Net_1922")
		)
		(pad "BD70" smd circle
			(at 30.230064 -1.97993 180)
			(size 0.450088 0.450088)
			(layers "F.Cu" "F.Mask" "F.Paste")
			(net "M_E_CPU0_CLK_DN<0>")
		)
		(pad "BD71" smd circle
			(at 31.170118 -1.97993 180)
			(size 0.450088 0.450088)
			(layers "F.Cu" "F.Mask" "F.Paste")
			(net "GND")
		)
		(pad "BD72" smd circle
			(at 32.109918 -1.97993 180)
			(size 0.450088 0.450088)
			(layers "F.Cu" "F.Mask" "F.Paste")
			(net "Net_1924")
		)
		(pad "BD73" smd circle
			(at 33.049972 -1.97993 180)
			(size 0.450088 0.450088)
			(layers "F.Cu" "F.Mask" "F.Paste")
			(net "GND")
		)
		(pad "BD74" smd circle
			(at 33.990026 -1.97993 180)
			(size 0.450088 0.450088)
			(layers "F.Cu" "F.Mask" "F.Paste")
			(net "M_A_CPU0_CLK_DN<0>")
		)
		(pad "BF2" smd circle
			(at -33.990026 1.97993 180)
			(size 0.450088 0.450088)
			(layers "F.Cu" "F.Mask" "F.Paste")
			(net "Net_1835")
		)
		(pad "BF3" smd circle
			(at -33.049972 1.97993 180)
			(size 0.450088 0.450088)
			(layers "F.Cu" "F.Mask" "F.Paste")
			(net "GND")
		)
		(pad "BF4" smd circle
			(at -32.109918 1.97993 180)
			(size 0.450088 0.450088)
			(layers "F.Cu" "F.Mask" "F.Paste")
			(net "TP_M_G_CPU0_SA_TEST39G")
		)
		(pad "BF5" smd circle
			(at -31.170118 1.97993 180)
			(size 0.450088 0.450088)
			(layers "F.Cu" "F.Mask" "F.Paste")
			(net "GND")
		)
		(pad "BF6" smd circle
			(at -30.230064 1.97993 180)
			(size 0.450088 0.450088)
			(layers "F.Cu" "F.Mask" "F.Paste")
			(net "Net_1964")
		)
		(pad "BF7" smd circle
			(at -29.29001 1.97993 180)
			(size 0.450088 0.450088)
			(layers "F.Cu" "F.Mask" "F.Paste")
			(net "TP_M_K_CPU0_SA_TEST39K")
		)
		(pad "BF8" smd circle
			(at -28.349956 1.97993 180)
			(size 0.450088 0.450088)
			(layers "F.Cu" "F.Mask" "F.Paste")
			(net "GND")
		)
		(pad "BF9" smd circle
			(at -27.409902 1.97993 180)
			(size 0.450088 0.450088)
			(layers "F.Cu" "F.Mask" "F.Paste")
			(net "Net_1956")
		)
		(pad "BF10" smd circle
			(at -26.470102 1.97993 180)
			(size 0.450088 0.450088)
			(layers "F.Cu" "F.Mask" "F.Paste")
			(net "GND")
		)
		(pad "BF11" smd circle
			(at -25.530048 1.97993 180)
			(size 0.450088 0.450088)
			(layers "F.Cu" "F.Mask" "F.Paste")
			(net "TP_M_L_CPU0_SA_TEST39L")
		)
		(pad "BF12" smd circle
			(at -24.589994 1.97993 180)
			(size 0.450088 0.450088)
			(layers "F.Cu" "F.Mask" "F.Paste")
			(net "GND")
		)
		(pad "BF13" smd circle
			(at -23.64994 1.97993 180)
			(size 0.450088 0.450088)
			(layers "F.Cu" "F.Mask" "F.Paste")
			(net "Net_1843")
		)
		(pad "BF14" smd circle
			(at -22.709886 1.97993 180)
			(size 0.450088 0.450088)
			(layers "F.Cu" "F.Mask" "F.Paste")
			(net "TP_M_H_CPU0_SA_TEST39H")
		)
		(pad "BF15" smd circle
			(at -21.770086 1.97993 180)
			(size 0.450088 0.450088)
			(layers "F.Cu" "F.Mask" "F.Paste")
			(net "GND")
		)
		(pad "BF16" smd circle
			(at -20.830032 1.97993 180)
			(size 0.450088 0.450088)
			(layers "F.Cu" "F.Mask" "F.Paste")
			(net "Net_1859")
		)
		(pad "BF17" smd circle
			(at -19.889978 1.97993 180)
			(size 0.450088 0.450088)
			(layers "F.Cu" "F.Mask" "F.Paste")
			(net "GND")
		)
		(pad "BF18" smd circle
			(at -18.949924 1.97993 180)
			(size 0.450088 0.450088)
			(layers "F.Cu" "F.Mask" "F.Paste")
			(net "TP_M_J_CPU0_SA_TEST39J")
		)
		(pad "BF19" smd circle
			(at -18.010124 1.97993 180)
			(size 0.450088 0.450088)
			(layers "F.Cu" "F.Mask" "F.Paste")
			(net "GND")
		)
		(pad "BF20" smd circle
			(at -17.07007 1.97993 180)
			(size 0.450088 0.450088)
			(layers "F.Cu" "F.Mask" "F.Paste")
			(net "Net_1851")
		)
		(pad "BF21" smd circle
			(at -16.130016 1.97993 180)
			(size 0.450088 0.450088)
			(layers "F.Cu" "F.Mask" "F.Paste")
			(net "TP_M_I_CPU0_SA_TEST39I")
		)
		(pad "BF22" smd circle
			(at -15.189962 1.97993 180)
			(size 0.450088 0.450088)
			(layers "F.Cu" "F.Mask" "F.Paste")
			(net "GND")
		)
		(pad "BF23" smd circle
			(at -14.249908 1.97993 180)
			(size 0.450088 0.450088)
			(layers "F.Cu" "F.Mask" "F.Paste")
			(net "PVDDCR_SOC_P0")
		)
		(pad "BF24" smd circle
			(at -13.310108 1.97993 180)
			(size 0.450088 0.450088)
			(layers "F.Cu" "F.Mask" "F.Paste")
			(net "GND")
		)
		(pad "BF25" smd circle
			(at -12.370054 1.97993 180)
			(size 0.450088 0.450088)
			(layers "F.Cu" "F.Mask" "F.Paste")
			(net "PVDDCR_SOC_P0")
		)
		(pad "BF26" smd circle
			(at -11.43 1.97993 180)
			(size 0.450088 0.450088)
			(layers "F.Cu" "F.Mask" "F.Paste")
			(net "GND")
		)
		(pad "BF27" smd circle
			(at -10.489946 1.97993 180)
			(size 0.450088 0.450088)
			(layers "F.Cu" "F.Mask" "F.Paste")
			(net "PVDDCR_SOC_P0")
		)
		(pad "BF28" smd circle
			(at -9.549892 1.97993 180)
			(size 0.450088 0.450088)
			(layers "F.Cu" "F.Mask" "F.Paste")
			(net "GND")
		)
		(pad "BF48" smd circle
			(at 9.249918 1.97993 180)
			(size 0.450088 0.450088)
			(layers "F.Cu" "F.Mask" "F.Paste")
			(net "PVDDCR_SOC_P0")
		)
		(pad "BF49" smd circle
			(at 10.189972 1.97993 180)
			(size 0.450088 0.450088)
			(layers "F.Cu" "F.Mask" "F.Paste")
			(net "GND")
		)
		(pad "BF50" smd circle
			(at 11.130026 1.97993 180)
			(size 0.450088 0.450088)
			(layers "F.Cu" "F.Mask" "F.Paste")
			(net "GND")
		)
		(pad "BF51" smd circle
			(at 12.07008 1.97993 180)
			(size 0.450088 0.450088)
			(layers "F.Cu" "F.Mask" "F.Paste")
			(net "PVDDIO_P0")
		)
		(pad "BF52" smd circle
			(at 13.00988 1.97993 180)
			(size 0.450088 0.450088)
			(layers "F.Cu" "F.Mask" "F.Paste")
			(net "GND")
		)
		(pad "BF53" smd circle
			(at 13.949934 1.97993 180)
			(size 0.450088 0.450088)
			(layers "F.Cu" "F.Mask" "F.Paste")
			(net "PVDDIO_P0")
		)
		(pad "BF54" smd circle
			(at 14.889988 1.97993 180)
			(size 0.450088 0.450088)
			(layers "F.Cu" "F.Mask" "F.Paste")
			(net "GND")
		)
		(pad "BF55" smd circle
			(at 15.830042 1.97993 180)
			(size 0.450088 0.450088)
			(layers "F.Cu" "F.Mask" "F.Paste")
			(net "TP_M_C_CPU0_SA_TEST39C")
		)
		(pad "BF56" smd circle
			(at 16.770096 1.97993 180)
			(size 0.450088 0.450088)
			(layers "F.Cu" "F.Mask" "F.Paste")
			(net "Net_1803")
		)
		(pad "BF57" smd circle
			(at 17.709896 1.97993 180)
			(size 0.450088 0.450088)
			(layers "F.Cu" "F.Mask" "F.Paste")
			(net "PVDDIO_P0")
		)
		(pad "BF58" smd circle
			(at 18.64995 1.97993 180)
			(size 0.450088 0.450088)
			(layers "F.Cu" "F.Mask" "F.Paste")
			(net "TP_M_D_CPU0_SA_TEST39D")
		)
		(pad "BF59" smd circle
			(at 19.590004 1.97993 180)
			(size 0.450088 0.450088)
			(layers "F.Cu" "F.Mask" "F.Paste")
			(net "GND")
		)
		(pad "BF60" smd circle
			(at 20.530058 1.97993 180)
			(size 0.450088 0.450088)
			(layers "F.Cu" "F.Mask" "F.Paste")
			(net "Net_1811")
		)
		(pad "BF61" smd circle
			(at 21.470112 1.97993 180)
			(size 0.450088 0.450088)
			(layers "F.Cu" "F.Mask" "F.Paste")
			(net "GND")
		)
		(pad "BF62" smd circle
			(at 22.409912 1.97993 180)
			(size 0.450088 0.450088)
			(layers "F.Cu" "F.Mask" "F.Paste")
			(net "TP_M_B_CPU0_SA_TEST39B")
		)
		(pad "BF63" smd circle
			(at 23.349966 1.97993 180)
			(size 0.450088 0.450088)
			(layers "F.Cu" "F.Mask" "F.Paste")
			(net "Net_1795")
		)
		(pad "BF64" smd circle
			(at 24.29002 1.97993 180)
			(size 0.450088 0.450088)
			(layers "F.Cu" "F.Mask" "F.Paste")
			(net "PVDDIO_P0")
		)
		(pad "BF65" smd circle
			(at 25.230074 1.97993 180)
			(size 0.450088 0.450088)
			(layers "F.Cu" "F.Mask" "F.Paste")
			(net "TP_M_F_CPU0_SA_TEST39F")
		)
		(pad "BF66" smd circle
			(at 26.170128 1.97993 180)
			(size 0.450088 0.450088)
			(layers "F.Cu" "F.Mask" "F.Paste")
			(net "GND")
		)
		(pad "BF67" smd circle
			(at 27.109928 1.97993 180)
			(size 0.450088 0.450088)
			(layers "F.Cu" "F.Mask" "F.Paste")
			(net "Net_1827")
		)
		(pad "BF68" smd circle
			(at 28.049982 1.97993 180)
			(size 0.450088 0.450088)
			(layers "F.Cu" "F.Mask" "F.Paste")
			(net "GND")
		)
		(pad "BF69" smd circle
			(at 28.990036 1.97993 180)
			(size 0.450088 0.450088)
			(layers "F.Cu" "F.Mask" "F.Paste")
			(net "TP_M_E_CPU0_SA_TEST39E")
		)
		(pad "BF70" smd circle
			(at 29.93009 1.97993 180)
			(size 0.450088 0.450088)
			(layers "F.Cu" "F.Mask" "F.Paste")
			(net "Net_1819")
		)
		(pad "BF71" smd circle
			(at 30.86989 1.97993 180)
			(size 0.450088 0.450088)
			(layers "F.Cu" "F.Mask" "F.Paste")
			(net "PVDDIO_P0")
		)
		(pad "BF72" smd circle
			(at 31.809944 1.97993 180)
			(size 0.450088 0.450088)
			(layers "F.Cu" "F.Mask" "F.Paste")
			(net "TP_M_A_CPU0_SA_TEST39A")
		)
		(pad "BF73" smd circle
			(at 32.749998 1.97993 180)
			(size 0.450088 0.450088)
			(layers "F.Cu" "F.Mask" "F.Paste")
			(net "GND")
		)
		(pad "BF74" smd circle
			(at 33.690052 1.97993 180)
			(size 0.450088 0.450088)
			(layers "F.Cu" "F.Mask" "F.Paste")
			(net "Net_1787")
		)
		(pad "BG1" smd circle
			(at -34.459926 2.789936 180)
			(size 0.450088 0.450088)
			(layers "F.Cu" "F.Mask" "F.Paste")
			(net "GND")
		)
		(pad "BG2" smd circle
			(at -33.519872 2.789936 180)
			(size 0.450088 0.450088)
			(layers "F.Cu" "F.Mask" "F.Paste")
			(net "Net_1836")
		)
		(pad "BG3" smd circle
			(at -32.580072 2.789936 180)
			(size 0.450088 0.450088)
			(layers "F.Cu" "F.Mask" "F.Paste")
			(net "M_G_CPU0_SB_CA<0>")
		)
		(pad "BG4" smd circle
			(at -31.640018 2.789936 180)
			(size 0.450088 0.450088)
			(layers "F.Cu" "F.Mask" "F.Paste")
			(net "GND")
		)
		(pad "BG5" smd circle
			(at -30.699964 2.789936 180)
			(size 0.450088 0.450088)
			(layers "F.Cu" "F.Mask" "F.Paste")
			(net "Net_1965")
		)
		(pad "BG6" smd circle
			(at -29.75991 2.789936 180)
			(size 0.450088 0.450088)
			(layers "F.Cu" "F.Mask" "F.Paste")
			(net "GND")
		)
		(pad "BG7" smd circle
			(at -28.82011 2.789936 180)
			(size 0.450088 0.450088)
			(layers "F.Cu" "F.Mask" "F.Paste")
			(net "M_K_CPU0_SB_CA<0>")
		)
		(pad "BG8" smd circle
			(at -27.880056 2.789936 180)
			(size 0.450088 0.450088)
			(layers "F.Cu" "F.Mask" "F.Paste")
			(net "GND")
		)
		(pad "BG9" smd circle
			(at -26.940002 2.789936 180)
			(size 0.450088 0.450088)
			(layers "F.Cu" "F.Mask" "F.Paste")
			(net "Net_1957")
		)
		(pad "BG10" smd circle
			(at -25.999948 2.789936 180)
			(size 0.450088 0.450088)
			(layers "F.Cu" "F.Mask" "F.Paste")
			(net "M_L_CPU0_SB_CA<0>")
		)
		(pad "BG11" smd circle
			(at -25.059894 2.789936 180)
			(size 0.450088 0.450088)
			(layers "F.Cu" "F.Mask" "F.Paste")
			(net "GND")
		)
		(pad "BG12" smd circle
			(at -24.120094 2.789936 180)
			(size 0.450088 0.450088)
			(layers "F.Cu" "F.Mask" "F.Paste")
			(net "Net_1844")
		)
		(pad "BG13" smd circle
			(at -23.18004 2.789936 180)
			(size 0.450088 0.450088)
			(layers "F.Cu" "F.Mask" "F.Paste")
			(net "GND")
		)
		(pad "BG14" smd circle
			(at -22.239986 2.789936 180)
			(size 0.450088 0.450088)
			(layers "F.Cu" "F.Mask" "F.Paste")
			(net "M_H_CPU0_SB_CA<0>")
		)
		(pad "BG15" smd circle
			(at -21.299932 2.789936 180)
			(size 0.450088 0.450088)
			(layers "F.Cu" "F.Mask" "F.Paste")
			(net "GND")
		)
		(pad "BG16" smd circle
			(at -20.359878 2.789936 180)
			(size 0.450088 0.450088)
			(layers "F.Cu" "F.Mask" "F.Paste")
			(net "Net_1860")
		)
		(pad "BG17" smd circle
			(at -19.420078 2.789936 180)
			(size 0.450088 0.450088)
			(layers "F.Cu" "F.Mask" "F.Paste")
			(net "M_J_CPU0_SB_CA<0>")
		)
		(pad "BG18" smd circle
			(at -18.480024 2.789936 180)
			(size 0.450088 0.450088)
			(layers "F.Cu" "F.Mask" "F.Paste")
			(net "GND")
		)
		(pad "BG19" smd circle
			(at -17.53997 2.789936 180)
			(size 0.450088 0.450088)
			(layers "F.Cu" "F.Mask" "F.Paste")
			(net "Net_1852")
		)
		(pad "BG20" smd circle
			(at -16.599916 2.789936 180)
			(size 0.450088 0.450088)
			(layers "F.Cu" "F.Mask" "F.Paste")
			(net "GND")
		)
		(pad "BG21" smd circle
			(at -15.660116 2.789936 180)
			(size 0.450088 0.450088)
			(layers "F.Cu" "F.Mask" "F.Paste")
			(net "M_I_CPU0_SB_CA<0>")
		)
		(pad "BG22" smd circle
			(at -14.720062 2.789936 180)
			(size 0.450088 0.450088)
			(layers "F.Cu" "F.Mask" "F.Paste")
			(net "PVDDCR_SOC_P0")
		)
		(pad "BG23" smd circle
			(at -13.780008 2.789936 180)
			(size 0.450088 0.450088)
			(layers "F.Cu" "F.Mask" "F.Paste")
			(net "GND")
		)
		(pad "BG24" smd circle
			(at -12.839954 2.789936 180)
			(size 0.450088 0.450088)
			(layers "F.Cu" "F.Mask" "F.Paste")
			(net "PVDDCR_SOC_P0")
		)
		(pad "BG25" smd circle
			(at -11.8999 2.789936 180)
			(size 0.450088 0.450088)
			(layers "F.Cu" "F.Mask" "F.Paste")
			(net "GND")
		)
		(pad "BG26" smd circle
			(at -10.9601 2.789936 180)
			(size 0.450088 0.450088)
			(layers "F.Cu" "F.Mask" "F.Paste")
			(net "PVDDCR_SOC_P0")
		)
		(pad "BG27" smd circle
			(at -10.020046 2.789936 180)
			(size 0.450088 0.450088)
			(layers "F.Cu" "F.Mask" "F.Paste")
			(net "GND")
		)
		(pad "BG28" smd circle
			(at -9.079992 2.789936 180)
			(size 0.450088 0.450088)
			(layers "F.Cu" "F.Mask" "F.Paste")
			(net "PVDDCR_SOC_P0")
		)
		(pad "BG48" smd circle
			(at 8.780018 2.789936 180)
			(size 0.450088 0.450088)
			(layers "F.Cu" "F.Mask" "F.Paste")
			(net "PVDDCR_SOC_P0")
		)
		(pad "BG49" smd circle
			(at 9.720072 2.789936 180)
			(size 0.450088 0.450088)
			(layers "F.Cu" "F.Mask" "F.Paste")
			(net "GND")
		)
		(pad "BG50" smd circle
			(at 10.659872 2.789936 180)
			(size 0.450088 0.450088)
			(layers "F.Cu" "F.Mask" "F.Paste")
			(net "PVDDIO_P0")
		)
		(pad "BG51" smd circle
			(at 11.599926 2.789936 180)
			(size 0.450088 0.450088)
			(layers "F.Cu" "F.Mask" "F.Paste")
			(net "GND")
		)
		(pad "BG52" smd circle
			(at 12.53998 2.789936 180)
			(size 0.450088 0.450088)
			(layers "F.Cu" "F.Mask" "F.Paste")
			(net "PVDDIO_P0")
		)
		(pad "BG53" smd circle
			(at 13.480034 2.789936 180)
			(size 0.450088 0.450088)
			(layers "F.Cu" "F.Mask" "F.Paste")
			(net "GND")
		)
		(pad "BG54" smd circle
			(at 14.420088 2.789936 180)
			(size 0.450088 0.450088)
			(layers "F.Cu" "F.Mask" "F.Paste")
			(net "PVDDIO_P0")
		)
		(pad "BG55" smd circle
			(at 15.359888 2.789936 180)
			(size 0.450088 0.450088)
			(layers "F.Cu" "F.Mask" "F.Paste")
			(net "M_C_CPU0_SB_CA<0>")
		)
		(pad "BG56" smd circle
			(at 16.299942 2.789936 180)
			(size 0.450088 0.450088)
			(layers "F.Cu" "F.Mask" "F.Paste")
			(net "GND")
		)
		(pad "BG57" smd circle
			(at 17.239996 2.789936 180)
			(size 0.450088 0.450088)
			(layers "F.Cu" "F.Mask" "F.Paste")
			(net "Net_1804")
		)
		(pad "BG58" smd circle
			(at 18.18005 2.789936 180)
			(size 0.450088 0.450088)
			(layers "F.Cu" "F.Mask" "F.Paste")
			(net "GND")
		)
		(pad "BG59" smd circle
			(at 19.120104 2.789936 180)
			(size 0.450088 0.450088)
			(layers "F.Cu" "F.Mask" "F.Paste")
			(net "M_D_CPU0_SB_CA<0>")
		)
		(pad "BG60" smd circle
			(at 20.059904 2.789936 180)
			(size 0.450088 0.450088)
			(layers "F.Cu" "F.Mask" "F.Paste")
			(net "Net_1812")
		)
		(pad "BG61" smd circle
			(at 20.999958 2.789936 180)
			(size 0.450088 0.450088)
			(layers "F.Cu" "F.Mask" "F.Paste")
			(net "GND")
		)
		(pad "BG62" smd circle
			(at 21.940012 2.789936 180)
			(size 0.450088 0.450088)
			(layers "F.Cu" "F.Mask" "F.Paste")
			(net "M_B_CPU0_SB_CA<0>")
		)
		(pad "BG63" smd circle
			(at 22.880066 2.789936 180)
			(size 0.450088 0.450088)
			(layers "F.Cu" "F.Mask" "F.Paste")
			(net "GND")
		)
		(pad "BG64" smd circle
			(at 23.82012 2.789936 180)
			(size 0.450088 0.450088)
			(layers "F.Cu" "F.Mask" "F.Paste")
			(net "Net_1796")
		)
		(pad "BG65" smd circle
			(at 24.75992 2.789936 180)
			(size 0.450088 0.450088)
			(layers "F.Cu" "F.Mask" "F.Paste")
			(net "GND")
		)
		(pad "BG66" smd circle
			(at 25.699974 2.789936 180)
			(size 0.450088 0.450088)
			(layers "F.Cu" "F.Mask" "F.Paste")
			(net "M_F_CPU0_SB_CA<0>")
		)
		(pad "BG67" smd circle
			(at 26.640028 2.789936 180)
			(size 0.450088 0.450088)
			(layers "F.Cu" "F.Mask" "F.Paste")
			(net "Net_1828")
		)
		(pad "BG68" smd circle
			(at 27.580082 2.789936 180)
			(size 0.450088 0.450088)
			(layers "F.Cu" "F.Mask" "F.Paste")
			(net "GND")
		)
		(pad "BG69" smd circle
			(at 28.519882 2.789936 180)
			(size 0.450088 0.450088)
			(layers "F.Cu" "F.Mask" "F.Paste")
			(net "M_E_CPU0_SB_CA<0>")
		)
		(pad "BG70" smd circle
			(at 29.459936 2.789936 180)
			(size 0.450088 0.450088)
			(layers "F.Cu" "F.Mask" "F.Paste")
			(net "GND")
		)
		(pad "BG71" smd circle
			(at 30.39999 2.789936 180)
			(size 0.450088 0.450088)
			(layers "F.Cu" "F.Mask" "F.Paste")
			(net "Net_1820")
		)
		(pad "BG72" smd circle
			(at 31.340044 2.789936 180)
			(size 0.450088 0.450088)
			(layers "F.Cu" "F.Mask" "F.Paste")
			(net "GND")
		)
		(pad "BG73" smd circle
			(at 32.280098 2.789936 180)
			(size 0.450088 0.450088)
			(layers "F.Cu" "F.Mask" "F.Paste")
			(net "M_A_CPU0_SB_CA<0>")
		)
		(pad "BG74" smd circle
			(at 33.219898 2.789936 180)
			(size 0.450088 0.450088)
			(layers "F.Cu" "F.Mask" "F.Paste")
			(net "Net_1788")
		)
		(pad "BG75" smd circle
			(at 34.159952 2.789936 180)
			(size 0.450088 0.450088)
			(layers "F.Cu" "F.Mask" "F.Paste")
			(net "GND")
		)
		(pad "BH2" smd circle
			(at -33.990026 3.599942 180)
			(size 0.450088 0.450088)
			(layers "F.Cu" "F.Mask" "F.Paste")
			(net "M_G_CPU0_SB_CA<2>")
		)
		(pad "BH3" smd circle
			(at -33.049972 3.599942 180)
			(size 0.450088 0.450088)
			(layers "F.Cu" "F.Mask" "F.Paste")
			(net "GND")
		)
		(pad "BH4" smd circle
			(at -32.109918 3.599942 180)
			(size 0.450088 0.450088)
			(layers "F.Cu" "F.Mask" "F.Paste")
			(net "M_G_CPU0_SB_CA<1>")
		)
		(pad "BH5" smd circle
			(at -31.170118 3.599942 180)
			(size 0.450088 0.450088)
			(layers "F.Cu" "F.Mask" "F.Paste")
			(net "GND")
		)
		(pad "BH6" smd circle
			(at -30.230064 3.599942 180)
			(size 0.450088 0.450088)
			(layers "F.Cu" "F.Mask" "F.Paste")
			(net "M_K_CPU0_SB_CA<2>")
		)
		(pad "BH7" smd circle
			(at -29.29001 3.599942 180)
			(size 0.450088 0.450088)
			(layers "F.Cu" "F.Mask" "F.Paste")
			(net "M_K_CPU0_SB_CA<1>")
		)
		(pad "BH8" smd circle
			(at -28.349956 3.599942 180)
			(size 0.450088 0.450088)
			(layers "F.Cu" "F.Mask" "F.Paste")
			(net "GND")
		)
		(pad "BH9" smd circle
			(at -27.409902 3.599942 180)
			(size 0.450088 0.450088)
			(layers "F.Cu" "F.Mask" "F.Paste")
			(net "M_L_CPU0_SB_CA<2>")
		)
		(pad "BH10" smd circle
			(at -26.470102 3.599942 180)
			(size 0.450088 0.450088)
			(layers "F.Cu" "F.Mask" "F.Paste")
			(net "GND")
		)
		(pad "BH11" smd circle
			(at -25.530048 3.599942 180)
			(size 0.450088 0.450088)
			(layers "F.Cu" "F.Mask" "F.Paste")
			(net "M_L_CPU0_SB_CA<1>")
		)
		(pad "BH12" smd circle
			(at -24.589994 3.599942 180)
			(size 0.450088 0.450088)
			(layers "F.Cu" "F.Mask" "F.Paste")
			(net "GND")
		)
		(pad "BH13" smd circle
			(at -23.64994 3.599942 180)
			(size 0.450088 0.450088)
			(layers "F.Cu" "F.Mask" "F.Paste")
			(net "M_H_CPU0_SB_CA<2>")
		)
		(pad "BH14" smd circle
			(at -22.709886 3.599942 180)
			(size 0.450088 0.450088)
			(layers "F.Cu" "F.Mask" "F.Paste")
			(net "M_H_CPU0_SB_CA<1>")
		)
		(pad "BH15" smd circle
			(at -21.770086 3.599942 180)
			(size 0.450088 0.450088)
			(layers "F.Cu" "F.Mask" "F.Paste")
			(net "GND")
		)
		(pad "BH16" smd circle
			(at -20.830032 3.599942 180)
			(size 0.450088 0.450088)
			(layers "F.Cu" "F.Mask" "F.Paste")
			(net "M_J_CPU0_SB_CA<2>")
		)
		(pad "BH17" smd circle
			(at -19.889978 3.599942 180)
			(size 0.450088 0.450088)
			(layers "F.Cu" "F.Mask" "F.Paste")
			(net "GND")
		)
		(pad "BH18" smd circle
			(at -18.949924 3.599942 180)
			(size 0.450088 0.450088)
			(layers "F.Cu" "F.Mask" "F.Paste")
			(net "M_J_CPU0_SB_CA<1>")
		)
		(pad "BH19" smd circle
			(at -18.010124 3.599942 180)
			(size 0.450088 0.450088)
			(layers "F.Cu" "F.Mask" "F.Paste")
			(net "GND")
		)
		(pad "BH20" smd circle
			(at -17.07007 3.599942 180)
			(size 0.450088 0.450088)
			(layers "F.Cu" "F.Mask" "F.Paste")
			(net "M_I_CPU0_SB_CA<2>")
		)
		(pad "BH21" smd circle
			(at -16.130016 3.599942 180)
			(size 0.450088 0.450088)
			(layers "F.Cu" "F.Mask" "F.Paste")
			(net "M_I_CPU0_SB_CA<1>")
		)
		(pad "BH22" smd circle
			(at -15.189962 3.599942 180)
			(size 0.450088 0.450088)
			(layers "F.Cu" "F.Mask" "F.Paste")
			(net "GND")
		)
		(pad "BH23" smd circle
			(at -14.249908 3.599942 180)
			(size 0.450088 0.450088)
			(layers "F.Cu" "F.Mask" "F.Paste")
			(net "PVDDCR_SOC_P0")
		)
		(pad "BH24" smd circle
			(at -13.310108 3.599942 180)
			(size 0.450088 0.450088)
			(layers "F.Cu" "F.Mask" "F.Paste")
			(net "GND")
		)
		(pad "BH25" smd circle
			(at -12.370054 3.599942 180)
			(size 0.450088 0.450088)
			(layers "F.Cu" "F.Mask" "F.Paste")
			(net "PVDDCR_SOC_P0")
		)
		(pad "BH26" smd circle
			(at -11.43 3.599942 180)
			(size 0.450088 0.450088)
			(layers "F.Cu" "F.Mask" "F.Paste")
			(net "GND")
		)
		(pad "BH27" smd circle
			(at -10.489946 3.599942 180)
			(size 0.450088 0.450088)
			(layers "F.Cu" "F.Mask" "F.Paste")
			(net "PVDD18_S5_P0")
		)
		(pad "BH28" smd circle
			(at -9.549892 3.599942 180)
			(size 0.450088 0.450088)
			(layers "F.Cu" "F.Mask" "F.Paste")
			(net "GND")
		)
		(pad "BH48" smd circle
			(at 9.249918 3.599942 180)
			(size 0.450088 0.450088)
			(layers "F.Cu" "F.Mask" "F.Paste")
			(net "PVDDCR_SOC_P0")
		)
		(pad "BH49" smd circle
			(at 10.189972 3.599942 180)
			(size 0.450088 0.450088)
			(layers "F.Cu" "F.Mask" "F.Paste")
			(net "GND")
		)
		(pad "BH50" smd circle
			(at 11.130026 3.599942 180)
			(size 0.450088 0.450088)
			(layers "F.Cu" "F.Mask" "F.Paste")
			(net "GND")
		)
		(pad "BH51" smd circle
			(at 12.07008 3.599942 180)
			(size 0.450088 0.450088)
			(layers "F.Cu" "F.Mask" "F.Paste")
			(net "PVDDIO_P0")
		)
		(pad "BH52" smd circle
			(at 13.00988 3.599942 180)
			(size 0.450088 0.450088)
			(layers "F.Cu" "F.Mask" "F.Paste")
			(net "GND")
		)
		(pad "BH53" smd circle
			(at 13.949934 3.599942 180)
			(size 0.450088 0.450088)
			(layers "F.Cu" "F.Mask" "F.Paste")
			(net "PVDDIO_P0")
		)
		(pad "BH54" smd circle
			(at 14.889988 3.599942 180)
			(size 0.450088 0.450088)
			(layers "F.Cu" "F.Mask" "F.Paste")
			(net "GND")
		)
		(pad "BH55" smd circle
			(at 15.830042 3.599942 180)
			(size 0.450088 0.450088)
			(layers "F.Cu" "F.Mask" "F.Paste")
			(net "M_C_CPU0_SB_CA<1>")
		)
		(pad "BH56" smd circle
			(at 16.770096 3.599942 180)
			(size 0.450088 0.450088)
			(layers "F.Cu" "F.Mask" "F.Paste")
			(net "M_C_CPU0_SB_CA<2>")
		)
		(pad "BH57" smd circle
			(at 17.709896 3.599942 180)
			(size 0.450088 0.450088)
			(layers "F.Cu" "F.Mask" "F.Paste")
			(net "GND")
		)
		(pad "BH58" smd circle
			(at 18.64995 3.599942 180)
			(size 0.450088 0.450088)
			(layers "F.Cu" "F.Mask" "F.Paste")
			(net "M_D_CPU0_SB_CA<1>")
		)
		(pad "BH59" smd circle
			(at 19.590004 3.599942 180)
			(size 0.450088 0.450088)
			(layers "F.Cu" "F.Mask" "F.Paste")
			(net "GND")
		)
		(pad "BH60" smd circle
			(at 20.530058 3.599942 180)
			(size 0.450088 0.450088)
			(layers "F.Cu" "F.Mask" "F.Paste")
			(net "M_D_CPU0_SB_CA<2>")
		)
		(pad "BH61" smd circle
			(at 21.470112 3.599942 180)
			(size 0.450088 0.450088)
			(layers "F.Cu" "F.Mask" "F.Paste")
			(net "GND")
		)
		(pad "BH62" smd circle
			(at 22.409912 3.599942 180)
			(size 0.450088 0.450088)
			(layers "F.Cu" "F.Mask" "F.Paste")
			(net "M_B_CPU0_SB_CA<1>")
		)
		(pad "BH63" smd circle
			(at 23.349966 3.599942 180)
			(size 0.450088 0.450088)
			(layers "F.Cu" "F.Mask" "F.Paste")
			(net "M_B_CPU0_SB_CA<2>")
		)
		(pad "BH64" smd circle
			(at 24.29002 3.599942 180)
			(size 0.450088 0.450088)
			(layers "F.Cu" "F.Mask" "F.Paste")
			(net "GND")
		)
		(pad "BH65" smd circle
			(at 25.230074 3.599942 180)
			(size 0.450088 0.450088)
			(layers "F.Cu" "F.Mask" "F.Paste")
			(net "M_F_CPU0_SB_CA<1>")
		)
		(pad "BH66" smd circle
			(at 26.170128 3.599942 180)
			(size 0.450088 0.450088)
			(layers "F.Cu" "F.Mask" "F.Paste")
			(net "GND")
		)
		(pad "BH67" smd circle
			(at 27.109928 3.599942 180)
			(size 0.450088 0.450088)
			(layers "F.Cu" "F.Mask" "F.Paste")
			(net "M_F_CPU0_SB_CA<2>")
		)
		(pad "BH68" smd circle
			(at 28.049982 3.599942 180)
			(size 0.450088 0.450088)
			(layers "F.Cu" "F.Mask" "F.Paste")
			(net "GND")
		)
		(pad "BH69" smd circle
			(at 28.990036 3.599942 180)
			(size 0.450088 0.450088)
			(layers "F.Cu" "F.Mask" "F.Paste")
			(net "M_E_CPU0_SB_CA<1>")
		)
		(pad "BH70" smd circle
			(at 29.93009 3.599942 180)
			(size 0.450088 0.450088)
			(layers "F.Cu" "F.Mask" "F.Paste")
			(net "M_E_CPU0_SB_CA<2>")
		)
		(pad "BH71" smd circle
			(at 30.86989 3.599942 180)
			(size 0.450088 0.450088)
			(layers "F.Cu" "F.Mask" "F.Paste")
			(net "GND")
		)
		(pad "BH72" smd circle
			(at 31.809944 3.599942 180)
			(size 0.450088 0.450088)
			(layers "F.Cu" "F.Mask" "F.Paste")
			(net "M_A_CPU0_SB_CA<1>")
		)
		(pad "BH73" smd circle
			(at 32.749998 3.599942 180)
			(size 0.450088 0.450088)
			(layers "F.Cu" "F.Mask" "F.Paste")
			(net "GND")
		)
		(pad "BH74" smd circle
			(at 33.690052 3.599942 180)
			(size 0.450088 0.450088)
			(layers "F.Cu" "F.Mask" "F.Paste")
			(net "M_A_CPU0_SB_CA<2>")
		)
		(pad "BJ1" smd circle
			(at -34.459926 4.409948 180)
			(size 0.450088 0.450088)
			(layers "F.Cu" "F.Mask" "F.Paste")
			(net "GND")
		)
		(pad "BJ2" smd circle
			(at -33.519872 4.409948 180)
			(size 0.450088 0.450088)
			(layers "F.Cu" "F.Mask" "F.Paste")
			(net "M_G_CPU0_SB_CA<3>")
		)
		(pad "BJ3" smd circle
			(at -32.580072 4.409948 180)
			(size 0.450088 0.450088)
			(layers "F.Cu" "F.Mask" "F.Paste")
			(net "M_G_CPU0_SB_CA<4>")
		)
		(pad "BJ4" smd circle
			(at -31.640018 4.409948 180)
			(size 0.450088 0.450088)
			(layers "F.Cu" "F.Mask" "F.Paste")
			(net "PVDDCR_SOC_P0")
		)
		(pad "BJ5" smd circle
			(at -30.699964 4.409948 180)
			(size 0.450088 0.450088)
			(layers "F.Cu" "F.Mask" "F.Paste")
			(net "M_K_CPU0_SB_CA<3>")
		)
		(pad "BJ6" smd circle
			(at -29.75991 4.409948 180)
			(size 0.450088 0.450088)
			(layers "F.Cu" "F.Mask" "F.Paste")
			(net "GND")
		)
		(pad "BJ7" smd circle
			(at -28.82011 4.409948 180)
			(size 0.450088 0.450088)
			(layers "F.Cu" "F.Mask" "F.Paste")
			(net "M_K_CPU0_SB_CA<4>")
		)
		(pad "BJ8" smd circle
			(at -27.880056 4.409948 180)
			(size 0.450088 0.450088)
			(layers "F.Cu" "F.Mask" "F.Paste")
			(net "GND")
		)
		(pad "BJ9" smd circle
			(at -26.940002 4.409948 180)
			(size 0.450088 0.450088)
			(layers "F.Cu" "F.Mask" "F.Paste")
			(net "M_L_CPU0_SB_CA<3>")
		)
		(pad "BJ10" smd circle
			(at -25.999948 4.409948 180)
			(size 0.450088 0.450088)
			(layers "F.Cu" "F.Mask" "F.Paste")
			(net "M_L_CPU0_SB_CA<4>")
		)
		(pad "BJ11" smd circle
			(at -25.059894 4.409948 180)
			(size 0.450088 0.450088)
			(layers "F.Cu" "F.Mask" "F.Paste")
			(net "PVDDCR_SOC_P0")
		)
		(pad "BJ12" smd circle
			(at -24.120094 4.409948 180)
			(size 0.450088 0.450088)
			(layers "F.Cu" "F.Mask" "F.Paste")
			(net "M_H_CPU0_SB_CA<3>")
		)
		(pad "BJ13" smd circle
			(at -23.18004 4.409948 180)
			(size 0.450088 0.450088)
			(layers "F.Cu" "F.Mask" "F.Paste")
			(net "GND")
		)
		(pad "BJ14" smd circle
			(at -22.239986 4.409948 180)
			(size 0.450088 0.450088)
			(layers "F.Cu" "F.Mask" "F.Paste")
			(net "M_H_CPU0_SB_CA<4>")
		)
		(pad "BJ15" smd circle
			(at -21.299932 4.409948 180)
			(size 0.450088 0.450088)
			(layers "F.Cu" "F.Mask" "F.Paste")
			(net "GND")
		)
		(pad "BJ16" smd circle
			(at -20.359878 4.409948 180)
			(size 0.450088 0.450088)
			(layers "F.Cu" "F.Mask" "F.Paste")
			(net "M_J_CPU0_SB_CA<3>")
		)
		(pad "BJ17" smd circle
			(at -19.420078 4.409948 180)
			(size 0.450088 0.450088)
			(layers "F.Cu" "F.Mask" "F.Paste")
			(net "M_J_CPU0_SB_CA<4>")
		)
		(pad "BJ18" smd circle
			(at -18.480024 4.409948 180)
			(size 0.450088 0.450088)
			(layers "F.Cu" "F.Mask" "F.Paste")
			(net "PVDD11_S3_P0")
		)
		(pad "BJ19" smd circle
			(at -17.53997 4.409948 180)
			(size 0.450088 0.450088)
			(layers "F.Cu" "F.Mask" "F.Paste")
			(net "M_I_CPU0_SB_CA<3>")
		)
		(pad "BJ20" smd circle
			(at -16.599916 4.409948 180)
			(size 0.450088 0.450088)
			(layers "F.Cu" "F.Mask" "F.Paste")
			(net "GND")
		)
		(pad "BJ21" smd circle
			(at -15.660116 4.409948 180)
			(size 0.450088 0.450088)
			(layers "F.Cu" "F.Mask" "F.Paste")
			(net "M_I_CPU0_SB_CA<4>")
		)
		(pad "BJ22" smd circle
			(at -14.720062 4.409948 180)
			(size 0.450088 0.450088)
			(layers "F.Cu" "F.Mask" "F.Paste")
			(net "GND")
		)
		(pad "BJ23" smd circle
			(at -13.780008 4.409948 180)
			(size 0.450088 0.450088)
			(layers "F.Cu" "F.Mask" "F.Paste")
			(net "PVDD11_S3_P0")
		)
		(pad "BJ24" smd circle
			(at -12.839954 4.409948 180)
			(size 0.450088 0.450088)
			(layers "F.Cu" "F.Mask" "F.Paste")
			(net "GND")
		)
		(pad "BJ25" smd circle
			(at -11.8999 4.409948 180)
			(size 0.450088 0.450088)
			(layers "F.Cu" "F.Mask" "F.Paste")
			(net "PVDD11_S3_P0")
		)
		(pad "BJ26" smd circle
			(at -10.9601 4.409948 180)
			(size 0.450088 0.450088)
			(layers "F.Cu" "F.Mask" "F.Paste")
			(net "GND")
		)
		(pad "BJ27" smd circle
			(at -10.020046 4.409948 180)
			(size 0.450088 0.450088)
			(layers "F.Cu" "F.Mask" "F.Paste")
			(net "PVDD11_S3_P0")
		)
		(pad "BJ28" smd circle
			(at -9.079992 4.409948 180)
			(size 0.450088 0.450088)
			(layers "F.Cu" "F.Mask" "F.Paste")
			(net "GND")
		)
		(pad "BJ48" smd circle
			(at 8.780018 4.409948 180)
			(size 0.450088 0.450088)
			(layers "F.Cu" "F.Mask" "F.Paste")
			(net "PVDDCR_SOC_P0")
		)
		(pad "BJ49" smd circle
			(at 9.720072 4.409948 180)
			(size 0.450088 0.450088)
			(layers "F.Cu" "F.Mask" "F.Paste")
			(net "GND")
		)
		(pad "BJ50" smd circle
			(at 10.659872 4.409948 180)
			(size 0.450088 0.450088)
			(layers "F.Cu" "F.Mask" "F.Paste")
			(net "PVDDIO_P0")
		)
		(pad "BJ51" smd circle
			(at 11.599926 4.409948 180)
			(size 0.450088 0.450088)
			(layers "F.Cu" "F.Mask" "F.Paste")
			(net "GND")
		)
		(pad "BJ52" smd circle
			(at 12.53998 4.409948 180)
			(size 0.450088 0.450088)
			(layers "F.Cu" "F.Mask" "F.Paste")
			(net "PVDDIO_P0")
		)
		(pad "BJ53" smd circle
			(at 13.480034 4.409948 180)
			(size 0.450088 0.450088)
			(layers "F.Cu" "F.Mask" "F.Paste")
			(net "GND")
		)
		(pad "BJ54" smd circle
			(at 14.420088 4.409948 180)
			(size 0.450088 0.450088)
			(layers "F.Cu" "F.Mask" "F.Paste")
			(net "PVDDIO_P0")
		)
		(pad "BJ55" smd circle
			(at 15.359888 4.409948 180)
			(size 0.450088 0.450088)
			(layers "F.Cu" "F.Mask" "F.Paste")
			(net "M_C_CPU0_SB_CA<4>")
		)
		(pad "BJ56" smd circle
			(at 16.299942 4.409948 180)
			(size 0.450088 0.450088)
			(layers "F.Cu" "F.Mask" "F.Paste")
			(net "GND")
		)
		(pad "BJ57" smd circle
			(at 17.239996 4.409948 180)
			(size 0.450088 0.450088)
			(layers "F.Cu" "F.Mask" "F.Paste")
			(net "M_C_CPU0_SB_CA<3>")
		)
		(pad "BJ58" smd circle
			(at 18.18005 4.409948 180)
			(size 0.450088 0.450088)
			(layers "F.Cu" "F.Mask" "F.Paste")
			(net "PVDDIO_P0")
		)
		(pad "BJ59" smd circle
			(at 19.120104 4.409948 180)
			(size 0.450088 0.450088)
			(layers "F.Cu" "F.Mask" "F.Paste")
			(net "M_D_CPU0_SB_CA<4>")
		)
		(pad "BJ60" smd circle
			(at 20.059904 4.409948 180)
			(size 0.450088 0.450088)
			(layers "F.Cu" "F.Mask" "F.Paste")
			(net "M_D_CPU0_SB_CA<3>")
		)
		(pad "BJ61" smd circle
			(at 20.999958 4.409948 180)
			(size 0.450088 0.450088)
			(layers "F.Cu" "F.Mask" "F.Paste")
			(net "GND")
		)
		(pad "BJ62" smd circle
			(at 21.940012 4.409948 180)
			(size 0.450088 0.450088)
			(layers "F.Cu" "F.Mask" "F.Paste")
			(net "M_B_CPU0_SB_CA<4>")
		)
		(pad "BJ63" smd circle
			(at 22.880066 4.409948 180)
			(size 0.450088 0.450088)
			(layers "F.Cu" "F.Mask" "F.Paste")
			(net "GND")
		)
		(pad "BJ64" smd circle
			(at 23.82012 4.409948 180)
			(size 0.450088 0.450088)
			(layers "F.Cu" "F.Mask" "F.Paste")
			(net "M_B_CPU0_SB_CA<3>")
		)
		(pad "BJ65" smd circle
			(at 24.75992 4.409948 180)
			(size 0.450088 0.450088)
			(layers "F.Cu" "F.Mask" "F.Paste")
			(net "PVDDIO_P0")
		)
		(pad "BJ66" smd circle
			(at 25.699974 4.409948 180)
			(size 0.450088 0.450088)
			(layers "F.Cu" "F.Mask" "F.Paste")
			(net "M_F_CPU0_SB_CA<4>")
		)
		(pad "BJ67" smd circle
			(at 26.640028 4.409948 180)
			(size 0.450088 0.450088)
			(layers "F.Cu" "F.Mask" "F.Paste")
			(net "M_F_CPU0_SB_CA<3>")
		)
		(pad "BJ68" smd circle
			(at 27.580082 4.409948 180)
			(size 0.450088 0.450088)
			(layers "F.Cu" "F.Mask" "F.Paste")
			(net "GND")
		)
		(pad "BJ69" smd circle
			(at 28.519882 4.409948 180)
			(size 0.450088 0.450088)
			(layers "F.Cu" "F.Mask" "F.Paste")
			(net "M_E_CPU0_SB_CA<4>")
		)
		(pad "BJ70" smd circle
			(at 29.459936 4.409948 180)
			(size 0.450088 0.450088)
			(layers "F.Cu" "F.Mask" "F.Paste")
			(net "GND")
		)
		(pad "BJ71" smd circle
			(at 30.39999 4.409948 180)
			(size 0.450088 0.450088)
			(layers "F.Cu" "F.Mask" "F.Paste")
			(net "M_E_CPU0_SB_CA<3>")
		)
		(pad "BJ72" smd circle
			(at 31.340044 4.409948 180)
			(size 0.450088 0.450088)
			(layers "F.Cu" "F.Mask" "F.Paste")
			(net "PVDDIO_P0")
		)
		(pad "BJ73" smd circle
			(at 32.280098 4.409948 180)
			(size 0.450088 0.450088)
			(layers "F.Cu" "F.Mask" "F.Paste")
			(net "M_A_CPU0_SB_CA<4>")
		)
		(pad "BJ74" smd circle
			(at 33.219898 4.409948 180)
			(size 0.450088 0.450088)
			(layers "F.Cu" "F.Mask" "F.Paste")
			(net "M_A_CPU0_SB_CA<3>")
		)
		(pad "BJ75" smd circle
			(at 34.159952 4.409948 180)
			(size 0.450088 0.450088)
			(layers "F.Cu" "F.Mask" "F.Paste")
			(net "GND")
		)
		(pad "BK2" smd circle
			(at -33.990026 5.219954 180)
			(size 0.450088 0.450088)
			(layers "F.Cu" "F.Mask" "F.Paste")
			(net "M_G_CPU0_SB_CA<6>")
		)
		(pad "BK3" smd circle
			(at -33.049972 5.219954 180)
			(size 0.450088 0.450088)
			(layers "F.Cu" "F.Mask" "F.Paste")
			(net "GND")
		)
		(pad "BK4" smd circle
			(at -32.109918 5.219954 180)
			(size 0.450088 0.450088)
			(layers "F.Cu" "F.Mask" "F.Paste")
			(net "M_G_CPU0_SB_CA<5>")
		)
		(pad "BK5" smd circle
			(at -31.170118 5.219954 180)
			(size 0.450088 0.450088)
			(layers "F.Cu" "F.Mask" "F.Paste")
			(net "GND")
		)
		(pad "BK6" smd circle
			(at -30.230064 5.219954 180)
			(size 0.450088 0.450088)
			(layers "F.Cu" "F.Mask" "F.Paste")
			(net "M_K_CPU0_SB_CA<6>")
		)
		(pad "BK7" smd circle
			(at -29.29001 5.219954 180)
			(size 0.450088 0.450088)
			(layers "F.Cu" "F.Mask" "F.Paste")
			(net "M_K_CPU0_SB_CA<5>")
		)
		(pad "BK8" smd circle
			(at -28.349956 5.219954 180)
			(size 0.450088 0.450088)
			(layers "F.Cu" "F.Mask" "F.Paste")
			(net "GND")
		)
		(pad "BK9" smd circle
			(at -27.409902 5.219954 180)
			(size 0.450088 0.450088)
			(layers "F.Cu" "F.Mask" "F.Paste")
			(net "M_L_CPU0_SB_CA<6>")
		)
		(pad "BK10" smd circle
			(at -26.470102 5.219954 180)
			(size 0.450088 0.450088)
			(layers "F.Cu" "F.Mask" "F.Paste")
			(net "GND")
		)
		(pad "BK11" smd circle
			(at -25.530048 5.219954 180)
			(size 0.450088 0.450088)
			(layers "F.Cu" "F.Mask" "F.Paste")
			(net "M_L_CPU0_SB_CA<5>")
		)
		(pad "BK12" smd circle
			(at -24.589994 5.219954 180)
			(size 0.450088 0.450088)
			(layers "F.Cu" "F.Mask" "F.Paste")
			(net "GND")
		)
		(pad "BK13" smd circle
			(at -23.64994 5.219954 180)
			(size 0.450088 0.450088)
			(layers "F.Cu" "F.Mask" "F.Paste")
			(net "M_H_CPU0_SB_CA<6>")
		)
		(pad "BK14" smd circle
			(at -22.709886 5.219954 180)
			(size 0.450088 0.450088)
			(layers "F.Cu" "F.Mask" "F.Paste")
			(net "M_H_CPU0_SB_CA<5>")
		)
		(pad "BK15" smd circle
			(at -21.770086 5.219954 180)
			(size 0.450088 0.450088)
			(layers "F.Cu" "F.Mask" "F.Paste")
			(net "GND")
		)
		(pad "BK16" smd circle
			(at -20.830032 5.219954 180)
			(size 0.450088 0.450088)
			(layers "F.Cu" "F.Mask" "F.Paste")
			(net "M_J_CPU0_SB_CA<6>")
		)
		(pad "BK17" smd circle
			(at -19.889978 5.219954 180)
			(size 0.450088 0.450088)
			(layers "F.Cu" "F.Mask" "F.Paste")
			(net "GND")
		)
		(pad "BK18" smd circle
			(at -18.949924 5.219954 180)
			(size 0.450088 0.450088)
			(layers "F.Cu" "F.Mask" "F.Paste")
			(net "M_J_CPU0_SB_CA<5>")
		)
		(pad "BK19" smd circle
			(at -18.010124 5.219954 180)
			(size 0.450088 0.450088)
			(layers "F.Cu" "F.Mask" "F.Paste")
			(net "GND")
		)
		(pad "BK20" smd circle
			(at -17.07007 5.219954 180)
			(size 0.450088 0.450088)
			(layers "F.Cu" "F.Mask" "F.Paste")
			(net "M_I_CPU0_SB_CA<6>")
		)
		(pad "BK21" smd circle
			(at -16.130016 5.219954 180)
			(size 0.450088 0.450088)
			(layers "F.Cu" "F.Mask" "F.Paste")
			(net "M_I_CPU0_SB_CA<5>")
		)
		(pad "BK22" smd circle
			(at -15.189962 5.219954 180)
			(size 0.450088 0.450088)
			(layers "F.Cu" "F.Mask" "F.Paste")
			(net "PVDD11_S3_P0")
		)
		(pad "BK23" smd circle
			(at -14.249908 5.219954 180)
			(size 0.450088 0.450088)
			(layers "F.Cu" "F.Mask" "F.Paste")
			(net "GND")
		)
		(pad "BK24" smd circle
			(at -13.310108 5.219954 180)
			(size 0.450088 0.450088)
			(layers "F.Cu" "F.Mask" "F.Paste")
			(net "PVDD11_S3_P0")
		)
		(pad "BK25" smd circle
			(at -12.370054 5.219954 180)
			(size 0.450088 0.450088)
			(layers "F.Cu" "F.Mask" "F.Paste")
			(net "GND")
		)
		(pad "BK26" smd circle
			(at -11.43 5.219954 180)
			(size 0.450088 0.450088)
			(layers "F.Cu" "F.Mask" "F.Paste")
			(net "PVDD11_S3_P0")
		)
		(pad "BK27" smd circle
			(at -10.489946 5.219954 180)
			(size 0.450088 0.450088)
			(layers "F.Cu" "F.Mask" "F.Paste")
			(net "GND")
		)
		(pad "BK28" smd circle
			(at -9.549892 5.219954 180)
			(size 0.450088 0.450088)
			(layers "F.Cu" "F.Mask" "F.Paste")
			(net "PVDD11_S3_P0")
		)
		(pad "BK48" smd circle
			(at 9.249918 5.219954 180)
			(size 0.450088 0.450088)
			(layers "F.Cu" "F.Mask" "F.Paste")
			(net "GND")
		)
		(pad "BK49" smd circle
			(at 10.189972 5.219954 180)
			(size 0.450088 0.450088)
			(layers "F.Cu" "F.Mask" "F.Paste")
			(net "PVDD11_S3_P0")
		)
		(pad "BK50" smd circle
			(at 11.130026 5.219954 180)
			(size 0.450088 0.450088)
			(layers "F.Cu" "F.Mask" "F.Paste")
			(net "GND")
		)
		(pad "BK51" smd circle
			(at 12.07008 5.219954 180)
			(size 0.450088 0.450088)
			(layers "F.Cu" "F.Mask" "F.Paste")
			(net "PVDDIO_P0")
		)
		(pad "BK52" smd circle
			(at 13.00988 5.219954 180)
			(size 0.450088 0.450088)
			(layers "F.Cu" "F.Mask" "F.Paste")
			(net "GND")
		)
		(pad "BK53" smd circle
			(at 13.949934 5.219954 180)
			(size 0.450088 0.450088)
			(layers "F.Cu" "F.Mask" "F.Paste")
			(net "PVDDIO_P0")
		)
		(pad "BK54" smd circle
			(at 14.889988 5.219954 180)
			(size 0.450088 0.450088)
			(layers "F.Cu" "F.Mask" "F.Paste")
			(net "GND")
		)
		(pad "BK55" smd circle
			(at 15.830042 5.219954 180)
			(size 0.450088 0.450088)
			(layers "F.Cu" "F.Mask" "F.Paste")
			(net "M_C_CPU0_SB_CA<5>")
		)
		(pad "BK56" smd circle
			(at 16.770096 5.219954 180)
			(size 0.450088 0.450088)
			(layers "F.Cu" "F.Mask" "F.Paste")
			(net "M_C_CPU0_SB_CA<6>")
		)
		(pad "BK57" smd circle
			(at 17.709896 5.219954 180)
			(size 0.450088 0.450088)
			(layers "F.Cu" "F.Mask" "F.Paste")
			(net "GND")
		)
		(pad "BK58" smd circle
			(at 18.64995 5.219954 180)
			(size 0.450088 0.450088)
			(layers "F.Cu" "F.Mask" "F.Paste")
			(net "M_D_CPU0_SB_CA<5>")
		)
		(pad "BK59" smd circle
			(at 19.590004 5.219954 180)
			(size 0.450088 0.450088)
			(layers "F.Cu" "F.Mask" "F.Paste")
			(net "GND")
		)
		(pad "BK60" smd circle
			(at 20.530058 5.219954 180)
			(size 0.450088 0.450088)
			(layers "F.Cu" "F.Mask" "F.Paste")
			(net "M_D_CPU0_SB_CA<6>")
		)
		(pad "BK61" smd circle
			(at 21.470112 5.219954 180)
			(size 0.450088 0.450088)
			(layers "F.Cu" "F.Mask" "F.Paste")
			(net "GND")
		)
		(pad "BK62" smd circle
			(at 22.409912 5.219954 180)
			(size 0.450088 0.450088)
			(layers "F.Cu" "F.Mask" "F.Paste")
			(net "M_B_CPU0_SB_CA<5>")
		)
		(pad "BK63" smd circle
			(at 23.349966 5.219954 180)
			(size 0.450088 0.450088)
			(layers "F.Cu" "F.Mask" "F.Paste")
			(net "M_B_CPU0_SB_CA<6>")
		)
		(pad "BK64" smd circle
			(at 24.29002 5.219954 180)
			(size 0.450088 0.450088)
			(layers "F.Cu" "F.Mask" "F.Paste")
			(net "GND")
		)
		(pad "BK65" smd circle
			(at 25.230074 5.219954 180)
			(size 0.450088 0.450088)
			(layers "F.Cu" "F.Mask" "F.Paste")
			(net "M_F_CPU0_SB_CA<5>")
		)
		(pad "BK66" smd circle
			(at 26.170128 5.219954 180)
			(size 0.450088 0.450088)
			(layers "F.Cu" "F.Mask" "F.Paste")
			(net "GND")
		)
		(pad "BK67" smd circle
			(at 27.109928 5.219954 180)
			(size 0.450088 0.450088)
			(layers "F.Cu" "F.Mask" "F.Paste")
			(net "M_F_CPU0_SB_CA<6>")
		)
		(pad "BK68" smd circle
			(at 28.049982 5.219954 180)
			(size 0.450088 0.450088)
			(layers "F.Cu" "F.Mask" "F.Paste")
			(net "GND")
		)
		(pad "BK69" smd circle
			(at 28.990036 5.219954 180)
			(size 0.450088 0.450088)
			(layers "F.Cu" "F.Mask" "F.Paste")
			(net "M_E_CPU0_SB_CA<5>")
		)
		(pad "BK70" smd circle
			(at 29.93009 5.219954 180)
			(size 0.450088 0.450088)
			(layers "F.Cu" "F.Mask" "F.Paste")
			(net "M_E_CPU0_SB_CA<6>")
		)
		(pad "BK71" smd circle
			(at 30.86989 5.219954 180)
			(size 0.450088 0.450088)
			(layers "F.Cu" "F.Mask" "F.Paste")
			(net "GND")
		)
		(pad "BK72" smd circle
			(at 31.809944 5.219954 180)
			(size 0.450088 0.450088)
			(layers "F.Cu" "F.Mask" "F.Paste")
			(net "M_A_CPU0_SB_CA<5>")
		)
		(pad "BK73" smd circle
			(at 32.749998 5.219954 180)
			(size 0.450088 0.450088)
			(layers "F.Cu" "F.Mask" "F.Paste")
			(net "GND")
		)
		(pad "BK74" smd circle
			(at 33.690052 5.219954 180)
			(size 0.450088 0.450088)
			(layers "F.Cu" "F.Mask" "F.Paste")
			(net "M_A_CPU0_SB_CA<6>")
		)
		(pad "BL1" smd circle
			(at -34.459926 6.02996 180)
			(size 0.450088 0.450088)
			(layers "F.Cu" "F.Mask" "F.Paste")
			(net "GND")
		)
		(pad "BL2" smd circle
			(at -33.519872 6.02996 180)
			(size 0.450088 0.450088)
			(layers "F.Cu" "F.Mask" "F.Paste")
			(net "Net_1840")
		)
		(pad "BL3" smd circle
			(at -32.580072 6.02996 180)
			(size 0.450088 0.450088)
			(layers "F.Cu" "F.Mask" "F.Paste")
			(net "M_G_CPU0_SB_PAR")
		)
		(pad "BL4" smd circle
			(at -31.640018 6.02996 180)
			(size 0.450088 0.450088)
			(layers "F.Cu" "F.Mask" "F.Paste")
			(net "GND")
		)
		(pad "BL5" smd circle
			(at -30.699964 6.02996 180)
			(size 0.450088 0.450088)
			(layers "F.Cu" "F.Mask" "F.Paste")
			(net "Net_1969")
		)
		(pad "BL6" smd circle
			(at -29.75991 6.02996 180)
			(size 0.450088 0.450088)
			(layers "F.Cu" "F.Mask" "F.Paste")
			(net "GND")
		)
		(pad "BL7" smd circle
			(at -28.82011 6.02996 180)
			(size 0.450088 0.450088)
			(layers "F.Cu" "F.Mask" "F.Paste")
			(net "M_K_CPU0_SB_PAR")
		)
		(pad "BL8" smd circle
			(at -27.880056 6.02996 180)
			(size 0.450088 0.450088)
			(layers "F.Cu" "F.Mask" "F.Paste")
			(net "GND")
		)
		(pad "BL9" smd circle
			(at -26.940002 6.02996 180)
			(size 0.450088 0.450088)
			(layers "F.Cu" "F.Mask" "F.Paste")
			(net "Net_1961")
		)
		(pad "BL10" smd circle
			(at -25.999948 6.02996 180)
			(size 0.450088 0.450088)
			(layers "F.Cu" "F.Mask" "F.Paste")
			(net "M_L_CPU0_SB_PAR")
		)
		(pad "BL11" smd circle
			(at -25.059894 6.02996 180)
			(size 0.450088 0.450088)
			(layers "F.Cu" "F.Mask" "F.Paste")
			(net "GND")
		)
		(pad "BL12" smd circle
			(at -24.120094 6.02996 180)
			(size 0.450088 0.450088)
			(layers "F.Cu" "F.Mask" "F.Paste")
			(net "Net_1848")
		)
		(pad "BL13" smd circle
			(at -23.18004 6.02996 180)
			(size 0.450088 0.450088)
			(layers "F.Cu" "F.Mask" "F.Paste")
			(net "GND")
		)
		(pad "BL14" smd circle
			(at -22.239986 6.02996 180)
			(size 0.450088 0.450088)
			(layers "F.Cu" "F.Mask" "F.Paste")
			(net "M_H_CPU0_SB_PAR")
		)
		(pad "BL15" smd circle
			(at -21.299932 6.02996 180)
			(size 0.450088 0.450088)
			(layers "F.Cu" "F.Mask" "F.Paste")
			(net "GND")
		)
		(pad "BL16" smd circle
			(at -20.359878 6.02996 180)
			(size 0.450088 0.450088)
			(layers "F.Cu" "F.Mask" "F.Paste")
			(net "Net_1864")
		)
		(pad "BL17" smd circle
			(at -19.420078 6.02996 180)
			(size 0.450088 0.450088)
			(layers "F.Cu" "F.Mask" "F.Paste")
			(net "M_J_CPU0_SB_PAR")
		)
		(pad "BL18" smd circle
			(at -18.480024 6.02996 180)
			(size 0.450088 0.450088)
			(layers "F.Cu" "F.Mask" "F.Paste")
			(net "GND")
		)
		(pad "BL19" smd circle
			(at -17.53997 6.02996 180)
			(size 0.450088 0.450088)
			(layers "F.Cu" "F.Mask" "F.Paste")
			(net "Net_1856")
		)
		(pad "BL20" smd circle
			(at -16.599916 6.02996 180)
			(size 0.450088 0.450088)
			(layers "F.Cu" "F.Mask" "F.Paste")
			(net "GND")
		)
		(pad "BL21" smd circle
			(at -15.660116 6.02996 180)
			(size 0.450088 0.450088)
			(layers "F.Cu" "F.Mask" "F.Paste")
			(net "M_I_CPU0_SB_PAR")
		)
		(pad "BL22" smd circle
			(at -14.720062 6.02996 180)
			(size 0.450088 0.450088)
			(layers "F.Cu" "F.Mask" "F.Paste")
			(net "GND")
		)
		(pad "BL23" smd circle
			(at -13.780008 6.02996 180)
			(size 0.450088 0.450088)
			(layers "F.Cu" "F.Mask" "F.Paste")
			(net "PVDD11_S3_P0")
		)
		(pad "BL24" smd circle
			(at -12.839954 6.02996 180)
			(size 0.450088 0.450088)
			(layers "F.Cu" "F.Mask" "F.Paste")
			(net "GND")
		)
		(pad "BL25" smd circle
			(at -11.8999 6.02996 180)
			(size 0.450088 0.450088)
			(layers "F.Cu" "F.Mask" "F.Paste")
			(net "PVDD11_S3_P0")
		)
		(pad "BL26" smd circle
			(at -10.9601 6.02996 180)
			(size 0.450088 0.450088)
			(layers "F.Cu" "F.Mask" "F.Paste")
			(net "GND")
		)
		(pad "BL27" smd circle
			(at -10.020046 6.02996 180)
			(size 0.450088 0.450088)
			(layers "F.Cu" "F.Mask" "F.Paste")
			(net "PVDD11_S3_P0")
		)
		(pad "BL28" smd circle
			(at -9.079992 6.02996 180)
			(size 0.450088 0.450088)
			(layers "F.Cu" "F.Mask" "F.Paste")
			(net "GND")
		)
		(pad "BL48" smd circle
			(at 8.780018 6.02996 180)
			(size 0.450088 0.450088)
			(layers "F.Cu" "F.Mask" "F.Paste")
			(net "PVDD11_S3_P0")
		)
		(pad "BL49" smd circle
			(at 9.720072 6.02996 180)
			(size 0.450088 0.450088)
			(layers "F.Cu" "F.Mask" "F.Paste")
			(net "GND")
		)
		(pad "BL50" smd circle
			(at 10.659872 6.02996 180)
			(size 0.450088 0.450088)
			(layers "F.Cu" "F.Mask" "F.Paste")
			(net "PVDDIO_P0")
		)
		(pad "BL51" smd circle
			(at 11.599926 6.02996 180)
			(size 0.450088 0.450088)
			(layers "F.Cu" "F.Mask" "F.Paste")
			(net "GND")
		)
		(pad "BL52" smd circle
			(at 12.53998 6.02996 180)
			(size 0.450088 0.450088)
			(layers "F.Cu" "F.Mask" "F.Paste")
			(net "PVDDIO_P0")
		)
		(pad "BL53" smd circle
			(at 13.480034 6.02996 180)
			(size 0.450088 0.450088)
			(layers "F.Cu" "F.Mask" "F.Paste")
			(net "GND")
		)
		(pad "BL54" smd circle
			(at 14.420088 6.02996 180)
			(size 0.450088 0.450088)
			(layers "F.Cu" "F.Mask" "F.Paste")
			(net "PVDDIO_P0")
		)
		(pad "BL55" smd circle
			(at 15.359888 6.02996 180)
			(size 0.450088 0.450088)
			(layers "F.Cu" "F.Mask" "F.Paste")
			(net "Net_1808")
		)
		(pad "BL56" smd circle
			(at 16.299942 6.02996 180)
			(size 0.450088 0.450088)
			(layers "F.Cu" "F.Mask" "F.Paste")
			(net "GND")
		)
		(pad "BL57" smd circle
			(at 17.239996 6.02996 180)
			(size 0.450088 0.450088)
			(layers "F.Cu" "F.Mask" "F.Paste")
			(net "M_C_CPU0_SB_PAR")
		)
		(pad "BL58" smd circle
			(at 18.18005 6.02996 180)
			(size 0.450088 0.450088)
			(layers "F.Cu" "F.Mask" "F.Paste")
			(net "GND")
		)
		(pad "BL59" smd circle
			(at 19.120104 6.02996 180)
			(size 0.450088 0.450088)
			(layers "F.Cu" "F.Mask" "F.Paste")
			(net "Net_1816")
		)
		(pad "BL60" smd circle
			(at 20.059904 6.02996 180)
			(size 0.450088 0.450088)
			(layers "F.Cu" "F.Mask" "F.Paste")
			(net "M_D_CPU0_SB_PAR")
		)
		(pad "BL61" smd circle
			(at 20.999958 6.02996 180)
			(size 0.450088 0.450088)
			(layers "F.Cu" "F.Mask" "F.Paste")
			(net "GND")
		)
		(pad "BL62" smd circle
			(at 21.940012 6.02996 180)
			(size 0.450088 0.450088)
			(layers "F.Cu" "F.Mask" "F.Paste")
			(net "Net_1800")
		)
		(pad "BL63" smd circle
			(at 22.880066 6.02996 180)
			(size 0.450088 0.450088)
			(layers "F.Cu" "F.Mask" "F.Paste")
			(net "GND")
		)
		(pad "BL64" smd circle
			(at 23.82012 6.02996 180)
			(size 0.450088 0.450088)
			(layers "F.Cu" "F.Mask" "F.Paste")
			(net "M_B_CPU0_SB_PAR")
		)
		(pad "BL65" smd circle
			(at 24.75992 6.02996 180)
			(size 0.450088 0.450088)
			(layers "F.Cu" "F.Mask" "F.Paste")
			(net "GND")
		)
		(pad "BL66" smd circle
			(at 25.699974 6.02996 180)
			(size 0.450088 0.450088)
			(layers "F.Cu" "F.Mask" "F.Paste")
			(net "Net_1832")
		)
		(pad "BL67" smd circle
			(at 26.640028 6.02996 180)
			(size 0.450088 0.450088)
			(layers "F.Cu" "F.Mask" "F.Paste")
			(net "M_F_CPU0_SB_PAR")
		)
		(pad "BL68" smd circle
			(at 27.580082 6.02996 180)
			(size 0.450088 0.450088)
			(layers "F.Cu" "F.Mask" "F.Paste")
			(net "GND")
		)
		(pad "BL69" smd circle
			(at 28.519882 6.02996 180)
			(size 0.450088 0.450088)
			(layers "F.Cu" "F.Mask" "F.Paste")
			(net "Net_1824")
		)
		(pad "BL70" smd circle
			(at 29.459936 6.02996 180)
			(size 0.450088 0.450088)
			(layers "F.Cu" "F.Mask" "F.Paste")
			(net "GND")
		)
		(pad "BL71" smd circle
			(at 30.39999 6.02996 180)
			(size 0.450088 0.450088)
			(layers "F.Cu" "F.Mask" "F.Paste")
			(net "M_E_CPU0_SB_PAR")
		)
		(pad "BL72" smd circle
			(at 31.340044 6.02996 180)
			(size 0.450088 0.450088)
			(layers "F.Cu" "F.Mask" "F.Paste")
			(net "GND")
		)
		(pad "BL73" smd circle
			(at 32.280098 6.02996 180)
			(size 0.450088 0.450088)
			(layers "F.Cu" "F.Mask" "F.Paste")
			(net "Net_1792")
		)
		(pad "BL74" smd circle
			(at 33.219898 6.02996 180)
			(size 0.450088 0.450088)
			(layers "F.Cu" "F.Mask" "F.Paste")
			(net "M_A_CPU0_SB_PAR")
		)
		(pad "BL75" smd circle
			(at 34.159952 6.02996 180)
			(size 0.450088 0.450088)
			(layers "F.Cu" "F.Mask" "F.Paste")
			(net "GND")
		)
		(pad "BM2" smd circle
			(at -33.990026 6.839966 180)
			(size 0.450088 0.450088)
			(layers "F.Cu" "F.Mask" "F.Paste")
			(net "Net_1841")
		)
		(pad "BM3" smd circle
			(at -33.049972 6.839966 180)
			(size 0.450088 0.450088)
			(layers "F.Cu" "F.Mask" "F.Paste")
			(net "GND")
		)
		(pad "BM4" smd circle
			(at -32.109918 6.839966 180)
			(size 0.450088 0.450088)
			(layers "F.Cu" "F.Mask" "F.Paste")
			(net "M_G_CPU0_SB_CS_N<0>")
		)
		(pad "BM5" smd circle
			(at -31.170118 6.839966 180)
			(size 0.450088 0.450088)
			(layers "F.Cu" "F.Mask" "F.Paste")
			(net "PVDDCR_SOC_P0")
		)
		(pad "BM6" smd circle
			(at -30.230064 6.839966 180)
			(size 0.450088 0.450088)
			(layers "F.Cu" "F.Mask" "F.Paste")
			(net "Net_1970")
		)
		(pad "BM7" smd circle
			(at -29.29001 6.839966 180)
			(size 0.450088 0.450088)
			(layers "F.Cu" "F.Mask" "F.Paste")
			(net "M_K_CPU0_SB_CS_N<0>")
		)
		(pad "BM8" smd circle
			(at -28.349956 6.839966 180)
			(size 0.450088 0.450088)
			(layers "F.Cu" "F.Mask" "F.Paste")
			(net "GND")
		)
		(pad "BM9" smd circle
			(at -27.409902 6.839966 180)
			(size 0.450088 0.450088)
			(layers "F.Cu" "F.Mask" "F.Paste")
			(net "Net_1962")
		)
		(pad "BM10" smd circle
			(at -26.470102 6.839966 180)
			(size 0.450088 0.450088)
			(layers "F.Cu" "F.Mask" "F.Paste")
			(net "GND")
		)
		(pad "BM11" smd circle
			(at -25.530048 6.839966 180)
			(size 0.450088 0.450088)
			(layers "F.Cu" "F.Mask" "F.Paste")
			(net "M_L_CPU0_SB_CS_N<0>")
		)
		(pad "BM12" smd circle
			(at -24.589994 6.839966 180)
			(size 0.450088 0.450088)
			(layers "F.Cu" "F.Mask" "F.Paste")
			(net "PVDD11_S3_P0")
		)
		(pad "BM13" smd circle
			(at -23.64994 6.839966 180)
			(size 0.450088 0.450088)
			(layers "F.Cu" "F.Mask" "F.Paste")
			(net "Net_1849")
		)
		(pad "BM14" smd circle
			(at -22.709886 6.839966 180)
			(size 0.450088 0.450088)
			(layers "F.Cu" "F.Mask" "F.Paste")
			(net "M_H_CPU0_SB_CS_N<0>")
		)
		(pad "BM15" smd circle
			(at -21.770086 6.839966 180)
			(size 0.450088 0.450088)
			(layers "F.Cu" "F.Mask" "F.Paste")
			(net "GND")
		)
		(pad "BM16" smd circle
			(at -20.830032 6.839966 180)
			(size 0.450088 0.450088)
			(layers "F.Cu" "F.Mask" "F.Paste")
			(net "Net_1865")
		)
		(pad "BM17" smd circle
			(at -19.889978 6.839966 180)
			(size 0.450088 0.450088)
			(layers "F.Cu" "F.Mask" "F.Paste")
			(net "GND")
		)
		(pad "BM18" smd circle
			(at -18.949924 6.839966 180)
			(size 0.450088 0.450088)
			(layers "F.Cu" "F.Mask" "F.Paste")
			(net "M_J_CPU0_SB_CS_N<0>")
		)
		(pad "BM19" smd circle
			(at -18.010124 6.839966 180)
			(size 0.450088 0.450088)
			(layers "F.Cu" "F.Mask" "F.Paste")
			(net "PVDD11_S3_P0")
		)
		(pad "BM20" smd circle
			(at -17.07007 6.839966 180)
			(size 0.450088 0.450088)
			(layers "F.Cu" "F.Mask" "F.Paste")
			(net "Net_1857")
		)
		(pad "BM21" smd circle
			(at -16.130016 6.839966 180)
			(size 0.450088 0.450088)
			(layers "F.Cu" "F.Mask" "F.Paste")
			(net "M_I_CPU0_SB_CS_N<0>")
		)
		(pad "BM22" smd circle
			(at -15.189962 6.839966 180)
			(size 0.450088 0.450088)
			(layers "F.Cu" "F.Mask" "F.Paste")
			(net "PVDD11_S3_P0")
		)
		(pad "BM23" smd circle
			(at -14.249908 6.839966 180)
			(size 0.450088 0.450088)
			(layers "F.Cu" "F.Mask" "F.Paste")
			(net "GND")
		)
		(pad "BM24" smd circle
			(at -13.310108 6.839966 180)
			(size 0.450088 0.450088)
			(layers "F.Cu" "F.Mask" "F.Paste")
			(net "PVDD11_S3_P0")
		)
		(pad "BM25" smd circle
			(at -12.370054 6.839966 180)
			(size 0.450088 0.450088)
			(layers "F.Cu" "F.Mask" "F.Paste")
			(net "GND")
		)
		(pad "BM26" smd circle
			(at -11.43 6.839966 180)
			(size 0.450088 0.450088)
			(layers "F.Cu" "F.Mask" "F.Paste")
			(net "PVDD11_S3_P0")
		)
		(pad "BM27" smd circle
			(at -10.489946 6.839966 180)
			(size 0.450088 0.450088)
			(layers "F.Cu" "F.Mask" "F.Paste")
			(net "GND")
		)
		(pad "BM28" smd circle
			(at -9.549892 6.839966 180)
			(size 0.450088 0.450088)
			(layers "F.Cu" "F.Mask" "F.Paste")
			(net "PVDD11_S3_P0")
		)
		(pad "BM29" smd circle
			(at -8.610092 6.839966 180)
			(size 0.450088 0.450088)
			(layers "F.Cu" "F.Mask" "F.Paste")
			(net "GND")
		)
		(pad "BM30" smd circle
			(at -7.670038 6.839966 180)
			(size 0.450088 0.450088)
			(layers "F.Cu" "F.Mask" "F.Paste")
			(net "PVDD11_S3_P0")
		)
		(pad "BM31" smd circle
			(at -6.729984 6.839966 180)
			(size 0.450088 0.450088)
			(layers "F.Cu" "F.Mask" "F.Paste")
			(net "GND")
		)
		(pad "BM32" smd circle
			(at -5.78993 6.839966 180)
			(size 0.450088 0.450088)
			(layers "F.Cu" "F.Mask" "F.Paste")
			(net "PVDD11_S3_P0")
		)
		(pad "BM33" smd circle
			(at -4.849876 6.839966 180)
			(size 0.450088 0.450088)
			(layers "F.Cu" "F.Mask" "F.Paste")
			(net "GND")
		)
		(pad "BM34" smd circle
			(at -3.910076 6.839966 180)
			(size 0.450088 0.450088)
			(layers "F.Cu" "F.Mask" "F.Paste")
			(net "PVDD11_S3_P0")
		)
		(pad "BM35" smd circle
			(at -2.970022 6.839966 180)
			(size 0.450088 0.450088)
			(layers "F.Cu" "F.Mask" "F.Paste")
			(net "GND")
		)
		(pad "BM36" smd circle
			(at -2.029968 6.839966 180)
			(size 0.450088 0.450088)
			(layers "F.Cu" "F.Mask" "F.Paste")
			(net "PVDD11_S3_P0")
		)
		(pad "BM37" smd circle
			(at -1.089914 6.839966 180)
			(size 0.450088 0.450088)
			(layers "F.Cu" "F.Mask" "F.Paste")
			(net "GND")
		)
		(pad "BM39" smd circle
			(at 0.78994 6.839966 180)
			(size 0.450088 0.450088)
			(layers "F.Cu" "F.Mask" "F.Paste")
			(net "PVDD11_S3_P0")
		)
		(pad "BM40" smd circle
			(at 1.729994 6.839966 180)
			(size 0.450088 0.450088)
			(layers "F.Cu" "F.Mask" "F.Paste")
			(net "GND")
		)
		(pad "BM41" smd circle
			(at 2.670048 6.839966 180)
			(size 0.450088 0.450088)
			(layers "F.Cu" "F.Mask" "F.Paste")
			(net "PVDD11_S3_P0")
		)
		(pad "BM42" smd circle
			(at 3.610102 6.839966 180)
			(size 0.450088 0.450088)
			(layers "F.Cu" "F.Mask" "F.Paste")
			(net "GND")
		)
		(pad "BM43" smd circle
			(at 4.549902 6.839966 180)
			(size 0.450088 0.450088)
			(layers "F.Cu" "F.Mask" "F.Paste")
			(net "PVDD11_S3_P0")
		)
		(pad "BM44" smd circle
			(at 5.489956 6.839966 180)
			(size 0.450088 0.450088)
			(layers "F.Cu" "F.Mask" "F.Paste")
			(net "GND")
		)
		(pad "BM45" smd circle
			(at 6.43001 6.839966 180)
			(size 0.450088 0.450088)
			(layers "F.Cu" "F.Mask" "F.Paste")
			(net "PVDD11_S3_P0")
		)
		(pad "BM46" smd circle
			(at 7.370064 6.839966 180)
			(size 0.450088 0.450088)
			(layers "F.Cu" "F.Mask" "F.Paste")
			(net "GND")
		)
		(pad "BM47" smd circle
			(at 8.310118 6.839966 180)
			(size 0.450088 0.450088)
			(layers "F.Cu" "F.Mask" "F.Paste")
			(net "PVDD11_S3_P0")
		)
		(pad "BM48" smd circle
			(at 9.249918 6.839966 180)
			(size 0.450088 0.450088)
			(layers "F.Cu" "F.Mask" "F.Paste")
			(net "GND")
		)
		(pad "BM49" smd circle
			(at 10.189972 6.839966 180)
			(size 0.450088 0.450088)
			(layers "F.Cu" "F.Mask" "F.Paste")
			(net "PVDD11_S3_P0")
		)
		(pad "BM50" smd circle
			(at 11.130026 6.839966 180)
			(size 0.450088 0.450088)
			(layers "F.Cu" "F.Mask" "F.Paste")
			(net "GND")
		)
		(pad "BM51" smd circle
			(at 12.07008 6.839966 180)
			(size 0.450088 0.450088)
			(layers "F.Cu" "F.Mask" "F.Paste")
			(net "PVDDIO_P0")
		)
		(pad "BM52" smd circle
			(at 13.00988 6.839966 180)
			(size 0.450088 0.450088)
			(layers "F.Cu" "F.Mask" "F.Paste")
			(net "GND")
		)
		(pad "BM53" smd circle
			(at 13.949934 6.839966 180)
			(size 0.450088 0.450088)
			(layers "F.Cu" "F.Mask" "F.Paste")
			(net "PVDDIO_P0")
		)
		(pad "BM54" smd circle
			(at 14.889988 6.839966 180)
			(size 0.450088 0.450088)
			(layers "F.Cu" "F.Mask" "F.Paste")
			(net "GND")
		)
		(pad "BM55" smd circle
			(at 15.830042 6.839966 180)
			(size 0.450088 0.450088)
			(layers "F.Cu" "F.Mask" "F.Paste")
			(net "M_C_CPU0_SB_CS_N<0>")
		)
		(pad "BM56" smd circle
			(at 16.770096 6.839966 180)
			(size 0.450088 0.450088)
			(layers "F.Cu" "F.Mask" "F.Paste")
			(net "Net_1809")
		)
		(pad "BM57" smd circle
			(at 17.709896 6.839966 180)
			(size 0.450088 0.450088)
			(layers "F.Cu" "F.Mask" "F.Paste")
			(net "PVDDIO_P0")
		)
		(pad "BM58" smd circle
			(at 18.64995 6.839966 180)
			(size 0.450088 0.450088)
			(layers "F.Cu" "F.Mask" "F.Paste")
			(net "M_D_CPU0_SB_CS_N<0>")
		)
		(pad "BM59" smd circle
			(at 19.590004 6.839966 180)
			(size 0.450088 0.450088)
			(layers "F.Cu" "F.Mask" "F.Paste")
			(net "GND")
		)
		(pad "BM60" smd circle
			(at 20.530058 6.839966 180)
			(size 0.450088 0.450088)
			(layers "F.Cu" "F.Mask" "F.Paste")
			(net "Net_1817")
		)
		(pad "BM61" smd circle
			(at 21.470112 6.839966 180)
			(size 0.450088 0.450088)
			(layers "F.Cu" "F.Mask" "F.Paste")
			(net "GND")
		)
		(pad "BM62" smd circle
			(at 22.409912 6.839966 180)
			(size 0.450088 0.450088)
			(layers "F.Cu" "F.Mask" "F.Paste")
			(net "M_B_CPU0_SB_CS_N<0>")
		)
		(pad "BM63" smd circle
			(at 23.349966 6.839966 180)
			(size 0.450088 0.450088)
			(layers "F.Cu" "F.Mask" "F.Paste")
			(net "Net_1801")
		)
		(pad "BM64" smd circle
			(at 24.29002 6.839966 180)
			(size 0.450088 0.450088)
			(layers "F.Cu" "F.Mask" "F.Paste")
			(net "PVDDIO_P0")
		)
		(pad "BM65" smd circle
			(at 25.230074 6.839966 180)
			(size 0.450088 0.450088)
			(layers "F.Cu" "F.Mask" "F.Paste")
			(net "M_F_CPU0_SB_CS_N<0>")
		)
		(pad "BM66" smd circle
			(at 26.170128 6.839966 180)
			(size 0.450088 0.450088)
			(layers "F.Cu" "F.Mask" "F.Paste")
			(net "GND")
		)
		(pad "BM67" smd circle
			(at 27.109928 6.839966 180)
			(size 0.450088 0.450088)
			(layers "F.Cu" "F.Mask" "F.Paste")
			(net "Net_1833")
		)
		(pad "BM68" smd circle
			(at 28.049982 6.839966 180)
			(size 0.450088 0.450088)
			(layers "F.Cu" "F.Mask" "F.Paste")
			(net "GND")
		)
		(pad "BM69" smd circle
			(at 28.990036 6.839966 180)
			(size 0.450088 0.450088)
			(layers "F.Cu" "F.Mask" "F.Paste")
			(net "M_E_CPU0_SB_CS_N<0>")
		)
		(pad "BM70" smd circle
			(at 29.93009 6.839966 180)
			(size 0.450088 0.450088)
			(layers "F.Cu" "F.Mask" "F.Paste")
			(net "Net_1825")
		)
		(pad "BM71" smd circle
			(at 30.86989 6.839966 180)
			(size 0.450088 0.450088)
			(layers "F.Cu" "F.Mask" "F.Paste")
			(net "PVDDIO_P0")
		)
		(pad "BM72" smd circle
			(at 31.809944 6.839966 180)
			(size 0.450088 0.450088)
			(layers "F.Cu" "F.Mask" "F.Paste")
			(net "M_A_CPU0_SB_CS_N<0>")
		)
		(pad "BM73" smd circle
			(at 32.749998 6.839966 180)
			(size 0.450088 0.450088)
			(layers "F.Cu" "F.Mask" "F.Paste")
			(net "GND")
		)
		(pad "BM74" smd circle
			(at 33.690052 6.839966 180)
			(size 0.450088 0.450088)
			(layers "F.Cu" "F.Mask" "F.Paste")
			(net "Net_1793")
		)
		(pad "BN1" smd circle
			(at -34.459926 7.649972 180)
			(size 0.450088 0.450088)
			(layers "F.Cu" "F.Mask" "F.Paste")
			(net "GND")
		)
		(pad "BN2" smd circle
			(at -33.519872 7.649972 180)
			(size 0.450088 0.450088)
			(layers "F.Cu" "F.Mask" "F.Paste")
			(net "M_G_CPU0_SB_CS_N<1>")
		)
		(pad "BN3" smd circle
			(at -32.580072 7.649972 180)
			(size 0.450088 0.450088)
			(layers "F.Cu" "F.Mask" "F.Paste")
			(net "M_G_CPU0_SA_RSP<0>")
		)
		(pad "BN4" smd circle
			(at -31.640018 7.649972 180)
			(size 0.450088 0.450088)
			(layers "F.Cu" "F.Mask" "F.Paste")
			(net "GND")
		)
		(pad "BN5" smd circle
			(at -30.699964 7.649972 180)
			(size 0.450088 0.450088)
			(layers "F.Cu" "F.Mask" "F.Paste")
			(net "M_K_CPU0_SB_CS_N<1>")
		)
		(pad "BN6" smd circle
			(at -29.75991 7.649972 180)
			(size 0.450088 0.450088)
			(layers "F.Cu" "F.Mask" "F.Paste")
			(net "GND")
		)
		(pad "BN7" smd circle
			(at -28.82011 7.649972 180)
			(size 0.450088 0.450088)
			(layers "F.Cu" "F.Mask" "F.Paste")
			(net "M_K_CPU0_SA_RSP<0>")
		)
		(pad "BN8" smd circle
			(at -27.880056 7.649972 180)
			(size 0.450088 0.450088)
			(layers "F.Cu" "F.Mask" "F.Paste")
			(net "GND")
		)
		(pad "BN9" smd circle
			(at -26.940002 7.649972 180)
			(size 0.450088 0.450088)
			(layers "F.Cu" "F.Mask" "F.Paste")
			(net "M_L_CPU0_SB_CS_N<1>")
		)
		(pad "BN10" smd circle
			(at -25.999948 7.649972 180)
			(size 0.450088 0.450088)
			(layers "F.Cu" "F.Mask" "F.Paste")
			(net "M_L_CPU0_SA_RSP<0>")
		)
		(pad "BN11" smd circle
			(at -25.059894 7.649972 180)
			(size 0.450088 0.450088)
			(layers "F.Cu" "F.Mask" "F.Paste")
			(net "GND")
		)
		(pad "BN12" smd circle
			(at -24.120094 7.649972 180)
			(size 0.450088 0.450088)
			(layers "F.Cu" "F.Mask" "F.Paste")
			(net "M_H_CPU0_SB_CS_N<1>")
		)
		(pad "BN13" smd circle
			(at -23.18004 7.649972 180)
			(size 0.450088 0.450088)
			(layers "F.Cu" "F.Mask" "F.Paste")
			(net "GND")
		)
		(pad "BN14" smd circle
			(at -22.239986 7.649972 180)
			(size 0.450088 0.450088)
			(layers "F.Cu" "F.Mask" "F.Paste")
			(net "M_H_CPU0_SA_RSP<0>")
		)
		(pad "BN15" smd circle
			(at -21.299932 7.649972 180)
			(size 0.450088 0.450088)
			(layers "F.Cu" "F.Mask" "F.Paste")
			(net "GND")
		)
		(pad "BN16" smd circle
			(at -20.359878 7.649972 180)
			(size 0.450088 0.450088)
			(layers "F.Cu" "F.Mask" "F.Paste")
			(net "M_J_CPU0_SB_CS_N<1>")
		)
		(pad "BN17" smd circle
			(at -19.420078 7.649972 180)
			(size 0.450088 0.450088)
			(layers "F.Cu" "F.Mask" "F.Paste")
			(net "M_J_CPU0_SA_RSP<0>")
		)
		(pad "BN18" smd circle
			(at -18.480024 7.649972 180)
			(size 0.450088 0.450088)
			(layers "F.Cu" "F.Mask" "F.Paste")
			(net "GND")
		)
		(pad "BN19" smd circle
			(at -17.53997 7.649972 180)
			(size 0.450088 0.450088)
			(layers "F.Cu" "F.Mask" "F.Paste")
			(net "M_I_CPU0_SB_CS_N<1>")
		)
		(pad "BN20" smd circle
			(at -16.599916 7.649972 180)
			(size 0.450088 0.450088)
			(layers "F.Cu" "F.Mask" "F.Paste")
			(net "GND")
		)
		(pad "BN21" smd circle
			(at -15.660116 7.649972 180)
			(size 0.450088 0.450088)
			(layers "F.Cu" "F.Mask" "F.Paste")
			(net "M_I_CPU0_SA_RSP<0>")
		)
		(pad "BN22" smd circle
			(at -14.720062 7.649972 180)
			(size 0.450088 0.450088)
			(layers "F.Cu" "F.Mask" "F.Paste")
			(net "GND")
		)
		(pad "BN23" smd circle
			(at -13.780008 7.649972 180)
			(size 0.450088 0.450088)
			(layers "F.Cu" "F.Mask" "F.Paste")
			(net "P1V5_BAT")
		)
		(pad "BN24" smd circle
			(at -12.839954 7.649972 180)
			(size 0.450088 0.450088)
			(layers "F.Cu" "F.Mask" "F.Paste")
			(net "GND")
		)
		(pad "BN25" smd circle
			(at -11.8999 7.649972 180)
			(size 0.450088 0.450088)
			(layers "F.Cu" "F.Mask" "F.Paste")
			(net "PVDD11_S3_P0")
		)
		(pad "BN26" smd circle
			(at -10.9601 7.649972 180)
			(size 0.450088 0.450088)
			(layers "F.Cu" "F.Mask" "F.Paste")
			(net "GND")
		)
		(pad "BN27" smd circle
			(at -10.020046 7.649972 180)
			(size 0.450088 0.450088)
			(layers "F.Cu" "F.Mask" "F.Paste")
			(net "PVDDCR_CPU1_P0")
		)
		(pad "BN28" smd circle
			(at -9.079992 7.649972 180)
			(size 0.450088 0.450088)
			(layers "F.Cu" "F.Mask" "F.Paste")
			(net "GND")
		)
		(pad "BN29" smd circle
			(at -8.139938 7.649972 180)
			(size 0.450088 0.450088)
			(layers "F.Cu" "F.Mask" "F.Paste")
			(net "PVDD11_S3_P0")
		)
		(pad "BN30" smd circle
			(at -7.199884 7.649972 180)
			(size 0.450088 0.450088)
			(layers "F.Cu" "F.Mask" "F.Paste")
			(net "GND")
		)
		(pad "BN31" smd circle
			(at -6.260084 7.649972 180)
			(size 0.450088 0.450088)
			(layers "F.Cu" "F.Mask" "F.Paste")
			(net "PVDDCR_CPU1_P0")
		)
		(pad "BN32" smd circle
			(at -5.32003 7.649972 180)
			(size 0.450088 0.450088)
			(layers "F.Cu" "F.Mask" "F.Paste")
			(net "GND")
		)
		(pad "BN33" smd circle
			(at -4.379976 7.649972 180)
			(size 0.450088 0.450088)
			(layers "F.Cu" "F.Mask" "F.Paste")
			(net "PVDD11_S3_P0")
		)
		(pad "BN34" smd circle
			(at -3.439922 7.649972 180)
			(size 0.450088 0.450088)
			(layers "F.Cu" "F.Mask" "F.Paste")
			(net "GND")
		)
		(pad "BN35" smd circle
			(at -2.500122 7.649972 180)
			(size 0.450088 0.450088)
			(layers "F.Cu" "F.Mask" "F.Paste")
			(net "PVDDCR_CPU1_P0")
		)
		(pad "BN36" smd circle
			(at -1.560068 7.649972 180)
			(size 0.450088 0.450088)
			(layers "F.Cu" "F.Mask" "F.Paste")
			(net "GND")
		)
		(pad "BN40" smd circle
			(at 1.260094 7.649972 180)
			(size 0.450088 0.450088)
			(layers "F.Cu" "F.Mask" "F.Paste")
			(net "PVDD11_S3_P0")
		)
		(pad "BN41" smd circle
			(at 2.199894 7.649972 180)
			(size 0.450088 0.450088)
			(layers "F.Cu" "F.Mask" "F.Paste")
			(net "GND")
		)
		(pad "BN42" smd circle
			(at 3.139948 7.649972 180)
			(size 0.450088 0.450088)
			(layers "F.Cu" "F.Mask" "F.Paste")
			(net "PVDDCR_CPU1_P0")
		)
		(pad "BN43" smd circle
			(at 4.080002 7.649972 180)
			(size 0.450088 0.450088)
			(layers "F.Cu" "F.Mask" "F.Paste")
			(net "GND")
		)
		(pad "BN44" smd circle
			(at 5.020056 7.649972 180)
			(size 0.450088 0.450088)
			(layers "F.Cu" "F.Mask" "F.Paste")
			(net "PVDD11_S3_P0")
		)
		(pad "BN45" smd circle
			(at 5.96011 7.649972 180)
			(size 0.450088 0.450088)
			(layers "F.Cu" "F.Mask" "F.Paste")
			(net "GND")
		)
		(pad "BN46" smd circle
			(at 6.89991 7.649972 180)
			(size 0.450088 0.450088)
			(layers "F.Cu" "F.Mask" "F.Paste")
			(net "PVDDCR_CPU1_P0")
		)
		(pad "BN47" smd circle
			(at 7.839964 7.649972 180)
			(size 0.450088 0.450088)
			(layers "F.Cu" "F.Mask" "F.Paste")
			(net "GND")
		)
		(pad "BN48" smd circle
			(at 8.780018 7.649972 180)
			(size 0.450088 0.450088)
			(layers "F.Cu" "F.Mask" "F.Paste")
			(net "PVDD11_S3_P0")
		)
		(pad "BN49" smd circle
			(at 9.720072 7.649972 180)
			(size 0.450088 0.450088)
			(layers "F.Cu" "F.Mask" "F.Paste")
			(net "GND")
		)
		(pad "BN50" smd circle
			(at 10.659872 7.649972 180)
			(size 0.450088 0.450088)
			(layers "F.Cu" "F.Mask" "F.Paste")
			(net "PVDDCR_CPU1_P0")
		)
		(pad "BN51" smd circle
			(at 11.599926 7.649972 180)
			(size 0.450088 0.450088)
			(layers "F.Cu" "F.Mask" "F.Paste")
			(net "GND")
		)
		(pad "BN52" smd circle
			(at 12.53998 7.649972 180)
			(size 0.450088 0.450088)
			(layers "F.Cu" "F.Mask" "F.Paste")
			(net "PVDD_33_S5")
		)
		(pad "BN53" smd circle
			(at 13.480034 7.649972 180)
			(size 0.450088 0.450088)
			(layers "F.Cu" "F.Mask" "F.Paste")
			(net "GND")
		)
		(pad "BN54" smd circle
			(at 14.420088 7.649972 180)
			(size 0.450088 0.450088)
			(layers "F.Cu" "F.Mask" "F.Paste")
			(net "PVDDIO_P0")
		)
		(pad "BN55" smd circle
			(at 15.359888 7.649972 180)
			(size 0.450088 0.450088)
			(layers "F.Cu" "F.Mask" "F.Paste")
			(net "M_C_CPU0_SA_RSP<0>")
		)
		(pad "BN56" smd circle
			(at 16.299942 7.649972 180)
			(size 0.450088 0.450088)
			(layers "F.Cu" "F.Mask" "F.Paste")
			(net "GND")
		)
		(pad "BN57" smd circle
			(at 17.239996 7.649972 180)
			(size 0.450088 0.450088)
			(layers "F.Cu" "F.Mask" "F.Paste")
			(net "M_C_CPU0_SB_CS_N<1>")
		)
		(pad "BN58" smd circle
			(at 18.18005 7.649972 180)
			(size 0.450088 0.450088)
			(layers "F.Cu" "F.Mask" "F.Paste")
			(net "GND")
		)
		(pad "BN59" smd circle
			(at 19.120104 7.649972 180)
			(size 0.450088 0.450088)
			(layers "F.Cu" "F.Mask" "F.Paste")
			(net "M_D_CPU0_SA_RSP<0>")
		)
		(pad "BN60" smd circle
			(at 20.059904 7.649972 180)
			(size 0.450088 0.450088)
			(layers "F.Cu" "F.Mask" "F.Paste")
			(net "M_D_CPU0_SB_CS_N<1>")
		)
		(pad "BN61" smd circle
			(at 20.999958 7.649972 180)
			(size 0.450088 0.450088)
			(layers "F.Cu" "F.Mask" "F.Paste")
			(net "GND")
		)
		(pad "BN62" smd circle
			(at 21.940012 7.649972 180)
			(size 0.450088 0.450088)
			(layers "F.Cu" "F.Mask" "F.Paste")
			(net "M_B_CPU0_SA_RSP<0>")
		)
		(pad "BN63" smd circle
			(at 22.880066 7.649972 180)
			(size 0.450088 0.450088)
			(layers "F.Cu" "F.Mask" "F.Paste")
			(net "GND")
		)
		(pad "BN64" smd circle
			(at 23.82012 7.649972 180)
			(size 0.450088 0.450088)
			(layers "F.Cu" "F.Mask" "F.Paste")
			(net "M_B_CPU0_SB_CS_N<1>")
		)
		(pad "BN65" smd circle
			(at 24.75992 7.649972 180)
			(size 0.450088 0.450088)
			(layers "F.Cu" "F.Mask" "F.Paste")
			(net "GND")
		)
		(pad "BN66" smd circle
			(at 25.699974 7.649972 180)
			(size 0.450088 0.450088)
			(layers "F.Cu" "F.Mask" "F.Paste")
			(net "M_F_CPU0_SA_RSP<0>")
		)
		(pad "BN67" smd circle
			(at 26.640028 7.649972 180)
			(size 0.450088 0.450088)
			(layers "F.Cu" "F.Mask" "F.Paste")
			(net "M_F_CPU0_SB_CS_N<1>")
		)
		(pad "BN68" smd circle
			(at 27.580082 7.649972 180)
			(size 0.450088 0.450088)
			(layers "F.Cu" "F.Mask" "F.Paste")
			(net "GND")
		)
		(pad "BN69" smd circle
			(at 28.519882 7.649972 180)
			(size 0.450088 0.450088)
			(layers "F.Cu" "F.Mask" "F.Paste")
			(net "M_E_CPU0_SA_RSP<0>")
		)
		(pad "BN70" smd circle
			(at 29.459936 7.649972 180)
			(size 0.450088 0.450088)
			(layers "F.Cu" "F.Mask" "F.Paste")
			(net "GND")
		)
		(pad "BN71" smd circle
			(at 30.39999 7.649972 180)
			(size 0.450088 0.450088)
			(layers "F.Cu" "F.Mask" "F.Paste")
			(net "M_E_CPU0_SB_CS_N<1>")
		)
		(pad "BN72" smd circle
			(at 31.340044 7.649972 180)
			(size 0.450088 0.450088)
			(layers "F.Cu" "F.Mask" "F.Paste")
			(net "GND")
		)
		(pad "BN73" smd circle
			(at 32.280098 7.649972 180)
			(size 0.450088 0.450088)
			(layers "F.Cu" "F.Mask" "F.Paste")
			(net "M_A_CPU0_SA_RSP<0>")
		)
		(pad "BN74" smd circle
			(at 33.219898 7.649972 180)
			(size 0.450088 0.450088)
			(layers "F.Cu" "F.Mask" "F.Paste")
			(net "M_A_CPU0_SB_CS_N<1>")
		)
		(pad "BN75" smd circle
			(at 34.159952 7.649972 180)
			(size 0.450088 0.450088)
			(layers "F.Cu" "F.Mask" "F.Paste")
			(net "GND")
		)
		(pad "BP2" smd circle
			(at -33.990026 8.459978 180)
			(size 0.450088 0.450088)
			(layers "F.Cu" "F.Mask" "F.Paste")
			(net "M_G_CPU0_SB_RSP<0>")
		)
		(pad "BP3" smd circle
			(at -33.049972 8.459978 180)
			(size 0.450088 0.450088)
			(layers "F.Cu" "F.Mask" "F.Paste")
			(net "GND")
		)
		(pad "BP4" smd circle
			(at -32.109918 8.459978 180)
			(size 0.450088 0.450088)
			(layers "F.Cu" "F.Mask" "F.Paste")
			(net "Net_1839")
		)
		(pad "BP5" smd circle
			(at -31.170118 8.459978 180)
			(size 0.450088 0.450088)
			(layers "F.Cu" "F.Mask" "F.Paste")
			(net "GND")
		)
		(pad "BP6" smd circle
			(at -30.230064 8.459978 180)
			(size 0.450088 0.450088)
			(layers "F.Cu" "F.Mask" "F.Paste")
			(net "M_K_CPU0_SB_RSP<0>")
		)
		(pad "BP7" smd circle
			(at -29.29001 8.459978 180)
			(size 0.450088 0.450088)
			(layers "F.Cu" "F.Mask" "F.Paste")
			(net "Net_1968")
		)
		(pad "BP8" smd circle
			(at -28.349956 8.459978 180)
			(size 0.450088 0.450088)
			(layers "F.Cu" "F.Mask" "F.Paste")
			(net "GND")
		)
		(pad "BP9" smd circle
			(at -27.409902 8.459978 180)
			(size 0.450088 0.450088)
			(layers "F.Cu" "F.Mask" "F.Paste")
			(net "M_L_CPU0_SB_RSP<0>")
		)
		(pad "BP10" smd circle
			(at -26.470102 8.459978 180)
			(size 0.450088 0.450088)
			(layers "F.Cu" "F.Mask" "F.Paste")
			(net "GND")
		)
		(pad "BP11" smd circle
			(at -25.530048 8.459978 180)
			(size 0.450088 0.450088)
			(layers "F.Cu" "F.Mask" "F.Paste")
			(net "Net_1960")
		)
		(pad "BP12" smd circle
			(at -24.589994 8.459978 180)
			(size 0.450088 0.450088)
			(layers "F.Cu" "F.Mask" "F.Paste")
			(net "GND")
		)
		(pad "BP13" smd circle
			(at -23.64994 8.459978 180)
			(size 0.450088 0.450088)
			(layers "F.Cu" "F.Mask" "F.Paste")
			(net "M_H_CPU0_SB_RSP<0>")
		)
		(pad "BP14" smd circle
			(at -22.709886 8.459978 180)
			(size 0.450088 0.450088)
			(layers "F.Cu" "F.Mask" "F.Paste")
			(net "Net_1847")
		)
		(pad "BP15" smd circle
			(at -21.770086 8.459978 180)
			(size 0.450088 0.450088)
			(layers "F.Cu" "F.Mask" "F.Paste")
			(net "GND")
		)
		(pad "BP16" smd circle
			(at -20.830032 8.459978 180)
			(size 0.450088 0.450088)
			(layers "F.Cu" "F.Mask" "F.Paste")
			(net "M_J_CPU0_SB_RSP<0>")
		)
		(pad "BP17" smd circle
			(at -19.889978 8.459978 180)
			(size 0.450088 0.450088)
			(layers "F.Cu" "F.Mask" "F.Paste")
			(net "GND")
		)
		(pad "BP18" smd circle
			(at -18.949924 8.459978 180)
			(size 0.450088 0.450088)
			(layers "F.Cu" "F.Mask" "F.Paste")
			(net "Net_1863")
		)
		(pad "BP19" smd circle
			(at -18.010124 8.459978 180)
			(size 0.450088 0.450088)
			(layers "F.Cu" "F.Mask" "F.Paste")
			(net "GND")
		)
		(pad "BP20" smd circle
			(at -17.07007 8.459978 180)
			(size 0.450088 0.450088)
			(layers "F.Cu" "F.Mask" "F.Paste")
			(net "M_I_CPU0_SB_RSP<0>")
		)
		(pad "BP21" smd circle
			(at -16.130016 8.459978 180)
			(size 0.450088 0.450088)
			(layers "F.Cu" "F.Mask" "F.Paste")
			(net "Net_1855")
		)
		(pad "BP22" smd circle
			(at -15.189962 8.459978 180)
			(size 0.450088 0.450088)
			(layers "F.Cu" "F.Mask" "F.Paste")
			(net "PVDD11_S3_P0")
		)
		(pad "BP23" smd circle
			(at -14.249908 8.459978 180)
			(size 0.450088 0.450088)
			(layers "F.Cu" "F.Mask" "F.Paste")
			(net "GND")
		)
		(pad "BP24" smd circle
			(at -13.310108 8.459978 180)
			(size 0.450088 0.450088)
			(layers "F.Cu" "F.Mask" "F.Paste")
			(net "PVDDCR_CPU1_P0")
		)
		(pad "BP25" smd circle
			(at -12.370054 8.459978 180)
			(size 0.450088 0.450088)
			(layers "F.Cu" "F.Mask" "F.Paste")
			(net "GND")
		)
		(pad "BP26" smd circle
			(at -11.43 8.459978 180)
			(size 0.450088 0.450088)
			(layers "F.Cu" "F.Mask" "F.Paste")
			(net "PVDDCR_CPU1_P0")
		)
		(pad "BP27" smd circle
			(at -10.489946 8.459978 180)
			(size 0.450088 0.450088)
			(layers "F.Cu" "F.Mask" "F.Paste")
			(net "GND")
		)
		(pad "BP28" smd circle
			(at -9.549892 8.459978 180)
			(size 0.450088 0.450088)
			(layers "F.Cu" "F.Mask" "F.Paste")
			(net "PVDDCR_CPU1_P0")
		)
		(pad "BP29" smd circle
			(at -8.610092 8.459978 180)
			(size 0.450088 0.450088)
			(layers "F.Cu" "F.Mask" "F.Paste")
			(net "GND")
		)
		(pad "BP30" smd circle
			(at -7.670038 8.459978 180)
			(size 0.450088 0.450088)
			(layers "F.Cu" "F.Mask" "F.Paste")
			(net "PVDDCR_CPU1_P0")
		)
		(pad "BP31" smd circle
			(at -6.729984 8.459978 180)
			(size 0.450088 0.450088)
			(layers "F.Cu" "F.Mask" "F.Paste")
			(net "GND")
		)
		(pad "BP32" smd circle
			(at -5.78993 8.459978 180)
			(size 0.450088 0.450088)
			(layers "F.Cu" "F.Mask" "F.Paste")
			(net "PVDDCR_CPU1_P0")
		)
		(pad "BP33" smd circle
			(at -4.849876 8.459978 180)
			(size 0.450088 0.450088)
			(layers "F.Cu" "F.Mask" "F.Paste")
			(net "GND")
		)
		(pad "BP34" smd circle
			(at -3.910076 8.459978 180)
			(size 0.450088 0.450088)
			(layers "F.Cu" "F.Mask" "F.Paste")
			(net "PVDDCR_CPU1_P0")
		)
		(pad "BP35" smd circle
			(at -2.970022 8.459978 180)
			(size 0.450088 0.450088)
			(layers "F.Cu" "F.Mask" "F.Paste")
			(net "GND")
		)
		(pad "BP36" smd circle
			(at -2.029968 8.459978 180)
			(size 0.450088 0.450088)
			(layers "F.Cu" "F.Mask" "F.Paste")
			(net "PVDDCR_CPU1_P0")
		)
		(pad "BP37" smd circle
			(at -1.089914 8.459978 180)
			(size 0.450088 0.450088)
			(layers "F.Cu" "F.Mask" "F.Paste")
			(net "GND")
		)
		(pad "BP39" smd circle
			(at 0.78994 8.459978 180)
			(size 0.450088 0.450088)
			(layers "F.Cu" "F.Mask" "F.Paste")
			(net "PVDDCR_CPU1_P0")
		)
		(pad "BP40" smd circle
			(at 1.729994 8.459978 180)
			(size 0.450088 0.450088)
			(layers "F.Cu" "F.Mask" "F.Paste")
			(net "GND")
		)
		(pad "BP41" smd circle
			(at 2.670048 8.459978 180)
			(size 0.450088 0.450088)
			(layers "F.Cu" "F.Mask" "F.Paste")
			(net "PVDDCR_CPU1_P0")
		)
		(pad "BP42" smd circle
			(at 3.610102 8.459978 180)
			(size 0.450088 0.450088)
			(layers "F.Cu" "F.Mask" "F.Paste")
			(net "GND")
		)
		(pad "BP43" smd circle
			(at 4.549902 8.459978 180)
			(size 0.450088 0.450088)
			(layers "F.Cu" "F.Mask" "F.Paste")
			(net "PVDDCR_CPU1_P0")
		)
		(pad "BP44" smd circle
			(at 5.489956 8.459978 180)
			(size 0.450088 0.450088)
			(layers "F.Cu" "F.Mask" "F.Paste")
			(net "GND")
		)
		(pad "BP45" smd circle
			(at 6.43001 8.459978 180)
			(size 0.450088 0.450088)
			(layers "F.Cu" "F.Mask" "F.Paste")
			(net "PVDDCR_CPU1_P0")
		)
		(pad "BP46" smd circle
			(at 7.370064 8.459978 180)
			(size 0.450088 0.450088)
			(layers "F.Cu" "F.Mask" "F.Paste")
			(net "GND")
		)
		(pad "BP47" smd circle
			(at 8.310118 8.459978 180)
			(size 0.450088 0.450088)
			(layers "F.Cu" "F.Mask" "F.Paste")
			(net "PVDDCR_CPU1_P0")
		)
		(pad "BP48" smd circle
			(at 9.249918 8.459978 180)
			(size 0.450088 0.450088)
			(layers "F.Cu" "F.Mask" "F.Paste")
			(net "GND")
		)
		(pad "BP49" smd circle
			(at 10.189972 8.459978 180)
			(size 0.450088 0.450088)
			(layers "F.Cu" "F.Mask" "F.Paste")
			(net "PVDDCR_CPU1_P0")
		)
		(pad "BP50" smd circle
			(at 11.130026 8.459978 180)
			(size 0.450088 0.450088)
			(layers "F.Cu" "F.Mask" "F.Paste")
			(net "GND")
		)
		(pad "BP51" smd circle
			(at 12.07008 8.459978 180)
			(size 0.450088 0.450088)
			(layers "F.Cu" "F.Mask" "F.Paste")
			(net "PVDD_33_S5")
		)
		(pad "BP52" smd circle
			(at 13.00988 8.459978 180)
			(size 0.450088 0.450088)
			(layers "F.Cu" "F.Mask" "F.Paste")
			(net "GND")
		)
		(pad "BP53" smd circle
			(at 13.949934 8.459978 180)
			(size 0.450088 0.450088)
			(layers "F.Cu" "F.Mask" "F.Paste")
			(net "TP_VSENSE_PVDD33_S5_P0")
		)
		(pad "BP54" smd circle
			(at 14.889988 8.459978 180)
			(size 0.450088 0.450088)
			(layers "F.Cu" "F.Mask" "F.Paste")
			(net "GND")
		)
		(pad "BP55" smd circle
			(at 15.830042 8.459978 180)
			(size 0.450088 0.450088)
			(layers "F.Cu" "F.Mask" "F.Paste")
			(net "Net_1807")
		)
		(pad "BP56" smd circle
			(at 16.770096 8.459978 180)
			(size 0.450088 0.450088)
			(layers "F.Cu" "F.Mask" "F.Paste")
			(net "M_C_CPU0_SB_RSP<0>")
		)
		(pad "BP57" smd circle
			(at 17.709896 8.459978 180)
			(size 0.450088 0.450088)
			(layers "F.Cu" "F.Mask" "F.Paste")
			(net "GND")
		)
		(pad "BP58" smd circle
			(at 18.64995 8.459978 180)
			(size 0.450088 0.450088)
			(layers "F.Cu" "F.Mask" "F.Paste")
			(net "Net_1815")
		)
		(pad "BP59" smd circle
			(at 19.590004 8.459978 180)
			(size 0.450088 0.450088)
			(layers "F.Cu" "F.Mask" "F.Paste")
			(net "GND")
		)
		(pad "BP60" smd circle
			(at 20.530058 8.459978 180)
			(size 0.450088 0.450088)
			(layers "F.Cu" "F.Mask" "F.Paste")
			(net "M_D_CPU0_SB_RSP<0>")
		)
		(pad "BP61" smd circle
			(at 21.470112 8.459978 180)
			(size 0.450088 0.450088)
			(layers "F.Cu" "F.Mask" "F.Paste")
			(net "GND")
		)
		(pad "BP62" smd circle
			(at 22.409912 8.459978 180)
			(size 0.450088 0.450088)
			(layers "F.Cu" "F.Mask" "F.Paste")
			(net "Net_1799")
		)
		(pad "BP63" smd circle
			(at 23.349966 8.459978 180)
			(size 0.450088 0.450088)
			(layers "F.Cu" "F.Mask" "F.Paste")
			(net "M_B_CPU0_SB_RSP<0>")
		)
		(pad "BP64" smd circle
			(at 24.29002 8.459978 180)
			(size 0.450088 0.450088)
			(layers "F.Cu" "F.Mask" "F.Paste")
			(net "GND")
		)
		(pad "BP65" smd circle
			(at 25.230074 8.459978 180)
			(size 0.450088 0.450088)
			(layers "F.Cu" "F.Mask" "F.Paste")
			(net "Net_1831")
		)
		(pad "BP66" smd circle
			(at 26.170128 8.459978 180)
			(size 0.450088 0.450088)
			(layers "F.Cu" "F.Mask" "F.Paste")
			(net "GND")
		)
		(pad "BP67" smd circle
			(at 27.109928 8.459978 180)
			(size 0.450088 0.450088)
			(layers "F.Cu" "F.Mask" "F.Paste")
			(net "M_F_CPU0_SB_RSP<0>")
		)
		(pad "BP68" smd circle
			(at 28.049982 8.459978 180)
			(size 0.450088 0.450088)
			(layers "F.Cu" "F.Mask" "F.Paste")
			(net "GND")
		)
		(pad "BP69" smd circle
			(at 28.990036 8.459978 180)
			(size 0.450088 0.450088)
			(layers "F.Cu" "F.Mask" "F.Paste")
			(net "Net_1823")
		)
		(pad "BP70" smd circle
			(at 29.93009 8.459978 180)
			(size 0.450088 0.450088)
			(layers "F.Cu" "F.Mask" "F.Paste")
			(net "M_E_CPU0_SB_RSP<0>")
		)
		(pad "BP71" smd circle
			(at 30.86989 8.459978 180)
			(size 0.450088 0.450088)
			(layers "F.Cu" "F.Mask" "F.Paste")
			(net "GND")
		)
		(pad "BP72" smd circle
			(at 31.809944 8.459978 180)
			(size 0.450088 0.450088)
			(layers "F.Cu" "F.Mask" "F.Paste")
			(net "Net_1791")
		)
		(pad "BP73" smd circle
			(at 32.749998 8.459978 180)
			(size 0.450088 0.450088)
			(layers "F.Cu" "F.Mask" "F.Paste")
			(net "GND")
		)
		(pad "BP74" smd circle
			(at 33.690052 8.459978 180)
			(size 0.450088 0.450088)
			(layers "F.Cu" "F.Mask" "F.Paste")
			(net "M_A_CPU0_SB_RSP<0>")
		)
		(pad "BR1" smd circle
			(at -34.459926 9.269984 180)
			(size 0.450088 0.450088)
			(layers "F.Cu" "F.Mask" "F.Paste")
			(net "GND")
		)
		(pad "BR2" smd circle
			(at -33.519872 9.269984 180)
			(size 0.450088 0.450088)
			(layers "F.Cu" "F.Mask" "F.Paste")
			(net "Net_1842")
		)
		(pad "BR3" smd circle
			(at -32.580072 9.269984 180)
			(size 0.450088 0.450088)
			(layers "F.Cu" "F.Mask" "F.Paste")
			(net "GND")
		)
		(pad "BR4" smd circle
			(at -31.640018 9.269984 180)
			(size 0.450088 0.450088)
			(layers "F.Cu" "F.Mask" "F.Paste")
			(net "PVDD11_S3_P0")
		)
		(pad "BR5" smd circle
			(at -30.699964 9.269984 180)
			(size 0.450088 0.450088)
			(layers "F.Cu" "F.Mask" "F.Paste")
			(net "Net_1971")
		)
		(pad "BR6" smd circle
			(at -29.75991 9.269984 180)
			(size 0.450088 0.450088)
			(layers "F.Cu" "F.Mask" "F.Paste")
			(net "GND")
		)
		(pad "BR7" smd circle
			(at -28.82011 9.269984 180)
			(size 0.450088 0.450088)
			(layers "F.Cu" "F.Mask" "F.Paste")
			(net "GND")
		)
		(pad "BR8" smd circle
			(at -27.880056 9.269984 180)
			(size 0.450088 0.450088)
			(layers "F.Cu" "F.Mask" "F.Paste")
			(net "GND")
		)
		(pad "BR9" smd circle
			(at -26.940002 9.269984 180)
			(size 0.450088 0.450088)
			(layers "F.Cu" "F.Mask" "F.Paste")
			(net "Net_1963")
		)
		(pad "BR10" smd circle
			(at -25.999948 9.269984 180)
			(size 0.450088 0.450088)
			(layers "F.Cu" "F.Mask" "F.Paste")
			(net "GND")
		)
		(pad "BR11" smd circle
			(at -25.059894 9.269984 180)
			(size 0.450088 0.450088)
			(layers "F.Cu" "F.Mask" "F.Paste")
			(net "PVDD11_S3_P0")
		)
		(pad "BR12" smd circle
			(at -24.120094 9.269984 180)
			(size 0.450088 0.450088)
			(layers "F.Cu" "F.Mask" "F.Paste")
			(net "Net_1850")
		)
		(pad "BR13" smd circle
			(at -23.18004 9.269984 180)
			(size 0.450088 0.450088)
			(layers "F.Cu" "F.Mask" "F.Paste")
			(net "GND")
		)
		(pad "BR14" smd circle
			(at -22.239986 9.269984 180)
			(size 0.450088 0.450088)
			(layers "F.Cu" "F.Mask" "F.Paste")
			(net "GND")
		)
		(pad "BR15" smd circle
			(at -21.299932 9.269984 180)
			(size 0.450088 0.450088)
			(layers "F.Cu" "F.Mask" "F.Paste")
			(net "GND")
		)
		(pad "BR16" smd circle
			(at -20.359878 9.269984 180)
			(size 0.450088 0.450088)
			(layers "F.Cu" "F.Mask" "F.Paste")
			(net "Net_1866")
		)
		(pad "BR17" smd circle
			(at -19.420078 9.269984 180)
			(size 0.450088 0.450088)
			(layers "F.Cu" "F.Mask" "F.Paste")
			(net "GND")
		)
		(pad "BR18" smd circle
			(at -18.480024 9.269984 180)
			(size 0.450088 0.450088)
			(layers "F.Cu" "F.Mask" "F.Paste")
			(net "PVDD11_S3_P0")
		)
		(pad "BR19" smd circle
			(at -17.53997 9.269984 180)
			(size 0.450088 0.450088)
			(layers "F.Cu" "F.Mask" "F.Paste")
			(net "Net_1858")
		)
		(pad "BR20" smd circle
			(at -16.599916 9.269984 180)
			(size 0.450088 0.450088)
			(layers "F.Cu" "F.Mask" "F.Paste")
			(net "GND")
		)
		(pad "BR21" smd circle
			(at -15.660116 9.269984 180)
			(size 0.450088 0.450088)
			(layers "F.Cu" "F.Mask" "F.Paste")
			(net "GND")
		)
		(pad "BR22" smd circle
			(at -14.720062 9.269984 180)
			(size 0.450088 0.450088)
			(layers "F.Cu" "F.Mask" "F.Paste")
			(net "GND")
		)
		(pad "BR23" smd circle
			(at -13.780008 9.269984 180)
			(size 0.450088 0.450088)
			(layers "F.Cu" "F.Mask" "F.Paste")
			(net "PVDDCR_CPU1_P0")
		)
		(pad "BR24" smd circle
			(at -12.839954 9.269984 180)
			(size 0.450088 0.450088)
			(layers "F.Cu" "F.Mask" "F.Paste")
			(net "GND")
		)
		(pad "BR25" smd circle
			(at -11.8999 9.269984 180)
			(size 0.450088 0.450088)
			(layers "F.Cu" "F.Mask" "F.Paste")
			(net "PVDDCR_CPU1_P0")
		)
		(pad "BR26" smd circle
			(at -10.9601 9.269984 180)
			(size 0.450088 0.450088)
			(layers "F.Cu" "F.Mask" "F.Paste")
			(net "GND")
		)
		(pad "BR27" smd circle
			(at -10.020046 9.269984 180)
			(size 0.450088 0.450088)
			(layers "F.Cu" "F.Mask" "F.Paste")
			(net "PVDDCR_CPU1_P0")
		)
		(pad "BR28" smd circle
			(at -9.079992 9.269984 180)
			(size 0.450088 0.450088)
			(layers "F.Cu" "F.Mask" "F.Paste")
			(net "GND")
		)
		(pad "BR29" smd circle
			(at -8.139938 9.269984 180)
			(size 0.450088 0.450088)
			(layers "F.Cu" "F.Mask" "F.Paste")
			(net "PVDDCR_CPU1_P0")
		)
		(pad "BR30" smd circle
			(at -7.199884 9.269984 180)
			(size 0.450088 0.450088)
			(layers "F.Cu" "F.Mask" "F.Paste")
			(net "GND")
		)
		(pad "BR31" smd circle
			(at -6.260084 9.269984 180)
			(size 0.450088 0.450088)
			(layers "F.Cu" "F.Mask" "F.Paste")
			(net "PVDDCR_CPU1_P0")
		)
		(pad "BR32" smd circle
			(at -5.32003 9.269984 180)
			(size 0.450088 0.450088)
			(layers "F.Cu" "F.Mask" "F.Paste")
			(net "GND")
		)
		(pad "BR33" smd circle
			(at -4.379976 9.269984 180)
			(size 0.450088 0.450088)
			(layers "F.Cu" "F.Mask" "F.Paste")
			(net "PVDDCR_CPU1_P0")
		)
		(pad "BR34" smd circle
			(at -3.439922 9.269984 180)
			(size 0.450088 0.450088)
			(layers "F.Cu" "F.Mask" "F.Paste")
			(net "GND")
		)
		(pad "BR35" smd circle
			(at -2.500122 9.269984 180)
			(size 0.450088 0.450088)
			(layers "F.Cu" "F.Mask" "F.Paste")
			(net "PVDDCR_CPU1_P0")
		)
		(pad "BR36" smd circle
			(at -1.560068 9.269984 180)
			(size 0.450088 0.450088)
			(layers "F.Cu" "F.Mask" "F.Paste")
			(net "GND")
		)
		(pad "BR40" smd circle
			(at 1.260094 9.269984 180)
			(size 0.450088 0.450088)
			(layers "F.Cu" "F.Mask" "F.Paste")
			(net "PVDDCR_CPU1_P0")
		)
		(pad "BR41" smd circle
			(at 2.199894 9.269984 180)
			(size 0.450088 0.450088)
			(layers "F.Cu" "F.Mask" "F.Paste")
			(net "GND")
		)
		(pad "BR42" smd circle
			(at 3.139948 9.269984 180)
			(size 0.450088 0.450088)
			(layers "F.Cu" "F.Mask" "F.Paste")
			(net "PVDDCR_CPU1_P0")
		)
		(pad "BR43" smd circle
			(at 4.080002 9.269984 180)
			(size 0.450088 0.450088)
			(layers "F.Cu" "F.Mask" "F.Paste")
			(net "GND")
		)
		(pad "BR44" smd circle
			(at 5.020056 9.269984 180)
			(size 0.450088 0.450088)
			(layers "F.Cu" "F.Mask" "F.Paste")
			(net "PVDDCR_CPU1_P0")
		)
		(pad "BR45" smd circle
			(at 5.96011 9.269984 180)
			(size 0.450088 0.450088)
			(layers "F.Cu" "F.Mask" "F.Paste")
			(net "GND")
		)
		(pad "BR46" smd circle
			(at 6.89991 9.269984 180)
			(size 0.450088 0.450088)
			(layers "F.Cu" "F.Mask" "F.Paste")
			(net "PVDDCR_CPU1_P0")
		)
		(pad "BR47" smd circle
			(at 7.839964 9.269984 180)
			(size 0.450088 0.450088)
			(layers "F.Cu" "F.Mask" "F.Paste")
			(net "GND")
		)
		(pad "BR48" smd circle
			(at 8.780018 9.269984 180)
			(size 0.450088 0.450088)
			(layers "F.Cu" "F.Mask" "F.Paste")
			(net "PVDDCR_CPU1_P0")
		)
		(pad "BR49" smd circle
			(at 9.720072 9.269984 180)
			(size 0.450088 0.450088)
			(layers "F.Cu" "F.Mask" "F.Paste")
			(net "GND")
		)
		(pad "BR50" smd circle
			(at 10.659872 9.269984 180)
			(size 0.450088 0.450088)
			(layers "F.Cu" "F.Mask" "F.Paste")
			(net "PVDDCR_CPU1_P0")
		)
		(pad "BR51" smd circle
			(at 11.599926 9.269984 180)
			(size 0.450088 0.450088)
			(layers "F.Cu" "F.Mask" "F.Paste")
			(net "GND")
		)
		(pad "BR52" smd circle
			(at 12.53998 9.269984 180)
			(size 0.450088 0.450088)
			(layers "F.Cu" "F.Mask" "F.Paste")
			(net "PVDDCR_CPU1_P0")
		)
		(pad "BR53" smd circle
			(at 13.480034 9.269984 180)
			(size 0.450088 0.450088)
			(layers "F.Cu" "F.Mask" "F.Paste")
			(net "VSENSE_PVDDIO_P0_DP")
		)
		(pad "BR54" smd circle
			(at 14.420088 9.269984 180)
			(size 0.450088 0.450088)
			(layers "F.Cu" "F.Mask" "F.Paste")
			(net "VSENSE_VSS_SENSE_B_P0")
		)
		(pad "BR55" smd circle
			(at 15.359888 9.269984 180)
			(size 0.450088 0.450088)
			(layers "F.Cu" "F.Mask" "F.Paste")
			(net "GND")
		)
		(pad "BR56" smd circle
			(at 16.299942 9.269984 180)
			(size 0.450088 0.450088)
			(layers "F.Cu" "F.Mask" "F.Paste")
			(net "GND")
		)
		(pad "BR57" smd circle
			(at 17.239996 9.269984 180)
			(size 0.450088 0.450088)
			(layers "F.Cu" "F.Mask" "F.Paste")
			(net "Net_1810")
		)
		(pad "BR58" smd circle
			(at 18.18005 9.269984 180)
			(size 0.450088 0.450088)
			(layers "F.Cu" "F.Mask" "F.Paste")
			(net "PVDDIO_P0")
		)
		(pad "BR59" smd circle
			(at 19.120104 9.269984 180)
			(size 0.450088 0.450088)
			(layers "F.Cu" "F.Mask" "F.Paste")
			(net "GND")
		)
		(pad "BR60" smd circle
			(at 20.059904 9.269984 180)
			(size 0.450088 0.450088)
			(layers "F.Cu" "F.Mask" "F.Paste")
			(net "Net_1818")
		)
		(pad "BR61" smd circle
			(at 20.999958 9.269984 180)
			(size 0.450088 0.450088)
			(layers "F.Cu" "F.Mask" "F.Paste")
			(net "GND")
		)
		(pad "BR62" smd circle
			(at 21.940012 9.269984 180)
			(size 0.450088 0.450088)
			(layers "F.Cu" "F.Mask" "F.Paste")
			(net "GND")
		)
		(pad "BR63" smd circle
			(at 22.880066 9.269984 180)
			(size 0.450088 0.450088)
			(layers "F.Cu" "F.Mask" "F.Paste")
			(net "GND")
		)
		(pad "BR64" smd circle
			(at 23.82012 9.269984 180)
			(size 0.450088 0.450088)
			(layers "F.Cu" "F.Mask" "F.Paste")
			(net "Net_1802")
		)
		(pad "BR65" smd circle
			(at 24.75992 9.269984 180)
			(size 0.450088 0.450088)
			(layers "F.Cu" "F.Mask" "F.Paste")
			(net "PVDDIO_P0")
		)
		(pad "BR66" smd circle
			(at 25.699974 9.269984 180)
			(size 0.450088 0.450088)
			(layers "F.Cu" "F.Mask" "F.Paste")
			(net "GND")
		)
		(pad "BR67" smd circle
			(at 26.640028 9.269984 180)
			(size 0.450088 0.450088)
			(layers "F.Cu" "F.Mask" "F.Paste")
			(net "Net_1834")
		)
		(pad "BR68" smd circle
			(at 27.580082 9.269984 180)
			(size 0.450088 0.450088)
			(layers "F.Cu" "F.Mask" "F.Paste")
			(net "GND")
		)
		(pad "BR69" smd circle
			(at 28.519882 9.269984 180)
			(size 0.450088 0.450088)
			(layers "F.Cu" "F.Mask" "F.Paste")
			(net "GND")
		)
		(pad "BR70" smd circle
			(at 29.459936 9.269984 180)
			(size 0.450088 0.450088)
			(layers "F.Cu" "F.Mask" "F.Paste")
			(net "GND")
		)
		(pad "BR71" smd circle
			(at 30.39999 9.269984 180)
			(size 0.450088 0.450088)
			(layers "F.Cu" "F.Mask" "F.Paste")
			(net "Net_1826")
		)
		(pad "BR72" smd circle
			(at 31.340044 9.269984 180)
			(size 0.450088 0.450088)
			(layers "F.Cu" "F.Mask" "F.Paste")
			(net "PVDDIO_P0")
		)
		(pad "BR73" smd circle
			(at 32.280098 9.269984 180)
			(size 0.450088 0.450088)
			(layers "F.Cu" "F.Mask" "F.Paste")
			(net "GND")
		)
		(pad "BR74" smd circle
			(at 33.219898 9.269984 180)
			(size 0.450088 0.450088)
			(layers "F.Cu" "F.Mask" "F.Paste")
			(net "Net_1794")
		)
		(pad "BR75" smd circle
			(at 34.159952 9.269984 180)
			(size 0.450088 0.450088)
			(layers "F.Cu" "F.Mask" "F.Paste")
			(net "GND")
		)
		(pad "BT2" smd circle
			(at -33.990026 10.07999 180)
			(size 0.450088 0.450088)
			(layers "F.Cu" "F.Mask" "F.Paste")
			(net "M_G_CPU0_SB_CB<4>")
		)
		(pad "BT3" smd circle
			(at -33.049972 10.07999 180)
			(size 0.450088 0.450088)
			(layers "F.Cu" "F.Mask" "F.Paste")
			(net "GND")
		)
		(pad "BT4" smd circle
			(at -32.109918 10.07999 180)
			(size 0.450088 0.450088)
			(layers "F.Cu" "F.Mask" "F.Paste")
			(net "GND")
		)
		(pad "BT5" smd circle
			(at -31.170118 10.07999 180)
			(size 0.450088 0.450088)
			(layers "F.Cu" "F.Mask" "F.Paste")
			(net "GND")
		)
		(pad "BT6" smd circle
			(at -30.230064 10.07999 180)
			(size 0.450088 0.450088)
			(layers "F.Cu" "F.Mask" "F.Paste")
			(net "M_K_CPU0_SB_CB<4>")
		)
		(pad "BT7" smd circle
			(at -29.29001 10.07999 180)
			(size 0.450088 0.450088)
			(layers "F.Cu" "F.Mask" "F.Paste")
			(net "GND")
		)
		(pad "BT8" smd circle
			(at -28.349956 10.07999 180)
			(size 0.450088 0.450088)
			(layers "F.Cu" "F.Mask" "F.Paste")
			(net "GND")
		)
		(pad "BT9" smd circle
			(at -27.409902 10.07999 180)
			(size 0.450088 0.450088)
			(layers "F.Cu" "F.Mask" "F.Paste")
			(net "M_L_CPU0_SB_CB<4>")
		)
		(pad "BT10" smd circle
			(at -26.470102 10.07999 180)
			(size 0.450088 0.450088)
			(layers "F.Cu" "F.Mask" "F.Paste")
			(net "GND")
		)
		(pad "BT11" smd circle
			(at -25.530048 10.07999 180)
			(size 0.450088 0.450088)
			(layers "F.Cu" "F.Mask" "F.Paste")
			(net "GND")
		)
		(pad "BT12" smd circle
			(at -24.589994 10.07999 180)
			(size 0.450088 0.450088)
			(layers "F.Cu" "F.Mask" "F.Paste")
			(net "GND")
		)
		(pad "BT13" smd circle
			(at -23.64994 10.07999 180)
			(size 0.450088 0.450088)
			(layers "F.Cu" "F.Mask" "F.Paste")
			(net "M_H_CPU0_SB_CB<4>")
		)
		(pad "BT14" smd circle
			(at -22.709886 10.07999 180)
			(size 0.450088 0.450088)
			(layers "F.Cu" "F.Mask" "F.Paste")
			(net "GND")
		)
		(pad "BT15" smd circle
			(at -21.770086 10.07999 180)
			(size 0.450088 0.450088)
			(layers "F.Cu" "F.Mask" "F.Paste")
			(net "GND")
		)
		(pad "BT16" smd circle
			(at -20.830032 10.07999 180)
			(size 0.450088 0.450088)
			(layers "F.Cu" "F.Mask" "F.Paste")
			(net "M_J_CPU0_SB_CB<4>")
		)
		(pad "BT17" smd circle
			(at -19.889978 10.07999 180)
			(size 0.450088 0.450088)
			(layers "F.Cu" "F.Mask" "F.Paste")
			(net "GND")
		)
		(pad "BT18" smd circle
			(at -18.949924 10.07999 180)
			(size 0.450088 0.450088)
			(layers "F.Cu" "F.Mask" "F.Paste")
			(net "GND")
		)
		(pad "BT19" smd circle
			(at -18.010124 10.07999 180)
			(size 0.450088 0.450088)
			(layers "F.Cu" "F.Mask" "F.Paste")
			(net "GND")
		)
		(pad "BT20" smd circle
			(at -17.07007 10.07999 180)
			(size 0.450088 0.450088)
			(layers "F.Cu" "F.Mask" "F.Paste")
			(net "M_I_CPU0_SB_CB<4>")
		)
		(pad "BT21" smd circle
			(at -16.130016 10.07999 180)
			(size 0.450088 0.450088)
			(layers "F.Cu" "F.Mask" "F.Paste")
			(net "GND")
		)
		(pad "BT22" smd circle
			(at -15.189962 10.07999 180)
			(size 0.450088 0.450088)
			(layers "F.Cu" "F.Mask" "F.Paste")
			(net "GND")
		)
		(pad "BT23" smd circle
			(at -14.249908 10.07999 180)
			(size 0.450088 0.450088)
			(layers "F.Cu" "F.Mask" "F.Paste")
			(net "PVDDCR_CPU1_P0")
		)
		(pad "BT24" smd circle
			(at -13.310108 10.07999 180)
			(size 0.450088 0.450088)
			(layers "F.Cu" "F.Mask" "F.Paste")
			(net "PVDDCR_CPU1_P0")
		)
		(pad "BT25" smd circle
			(at -12.370054 10.07999 180)
			(size 0.450088 0.450088)
			(layers "F.Cu" "F.Mask" "F.Paste")
			(net "GND")
		)
		(pad "BT26" smd circle
			(at -11.43 10.07999 180)
			(size 0.450088 0.450088)
			(layers "F.Cu" "F.Mask" "F.Paste")
			(net "PVDDCR_CPU1_P0")
		)
		(pad "BT27" smd circle
			(at -10.489946 10.07999 180)
			(size 0.450088 0.450088)
			(layers "F.Cu" "F.Mask" "F.Paste")
			(net "PVDDCR_CPU1_P0")
		)
		(pad "BT28" smd circle
			(at -9.549892 10.07999 180)
			(size 0.450088 0.450088)
			(layers "F.Cu" "F.Mask" "F.Paste")
			(net "GND")
		)
		(pad "BT29" smd circle
			(at -8.610092 10.07999 180)
			(size 0.450088 0.450088)
			(layers "F.Cu" "F.Mask" "F.Paste")
			(net "PVDDCR_CPU1_P0")
		)
		(pad "BT30" smd circle
			(at -7.670038 10.07999 180)
			(size 0.450088 0.450088)
			(layers "F.Cu" "F.Mask" "F.Paste")
			(net "PVDDCR_CPU1_P0")
		)
		(pad "BT31" smd circle
			(at -6.729984 10.07999 180)
			(size 0.450088 0.450088)
			(layers "F.Cu" "F.Mask" "F.Paste")
			(net "GND")
		)
		(pad "BT32" smd circle
			(at -5.78993 10.07999 180)
			(size 0.450088 0.450088)
			(layers "F.Cu" "F.Mask" "F.Paste")
			(net "PVDDCR_CPU1_P0")
		)
		(pad "BT33" smd circle
			(at -4.849876 10.07999 180)
			(size 0.450088 0.450088)
			(layers "F.Cu" "F.Mask" "F.Paste")
			(net "PVDDCR_CPU1_P0")
		)
		(pad "BT34" smd circle
			(at -3.910076 10.07999 180)
			(size 0.450088 0.450088)
			(layers "F.Cu" "F.Mask" "F.Paste")
			(net "GND")
		)
		(pad "BT35" smd circle
			(at -2.970022 10.07999 180)
			(size 0.450088 0.450088)
			(layers "F.Cu" "F.Mask" "F.Paste")
			(net "P5E_CPU0_P2_TX_DN<0>")
		)
		(pad "BT36" smd circle
			(at -2.029968 10.07999 180)
			(size 0.450088 0.450088)
			(layers "F.Cu" "F.Mask" "F.Paste")
			(net "P5E_CPU0_P2_TX_DP<0>")
		)
		(pad "BT37" smd circle
			(at -1.089914 10.07999 180)
			(size 0.450088 0.450088)
			(layers "F.Cu" "F.Mask" "F.Paste")
			(net "GND")
		)
		(pad "BT39" smd circle
			(at 0.78994 10.07999 180)
			(size 0.450088 0.450088)
			(layers "F.Cu" "F.Mask" "F.Paste")
			(net "GND")
		)
		(pad "BT40" smd circle
			(at 1.729994 10.07999 180)
			(size 0.450088 0.450088)
			(layers "F.Cu" "F.Mask" "F.Paste")
			(net "P5E_CPU0_P0_RX_DP<15>")
		)
		(pad "BT41" smd circle
			(at 2.670048 10.07999 180)
			(size 0.450088 0.450088)
			(layers "F.Cu" "F.Mask" "F.Paste")
			(net "P5E_CPU0_P0_RX_DN<15>")
		)
		(pad "BT42" smd circle
			(at 3.610102 10.07999 180)
			(size 0.450088 0.450088)
			(layers "F.Cu" "F.Mask" "F.Paste")
			(net "GND")
		)
		(pad "BT43" smd circle
			(at 4.549902 10.07999 180)
			(size 0.450088 0.450088)
			(layers "F.Cu" "F.Mask" "F.Paste")
			(net "PVDDCR_CPU1_P0")
		)
		(pad "BT44" smd circle
			(at 5.489956 10.07999 180)
			(size 0.450088 0.450088)
			(layers "F.Cu" "F.Mask" "F.Paste")
			(net "PVDDCR_CPU1_P0")
		)
		(pad "BT45" smd circle
			(at 6.43001 10.07999 180)
			(size 0.450088 0.450088)
			(layers "F.Cu" "F.Mask" "F.Paste")
			(net "GND")
		)
		(pad "BT46" smd circle
			(at 7.370064 10.07999 180)
			(size 0.450088 0.450088)
			(layers "F.Cu" "F.Mask" "F.Paste")
			(net "PVDDCR_CPU1_P0")
		)
		(pad "BT47" smd circle
			(at 8.310118 10.07999 180)
			(size 0.450088 0.450088)
			(layers "F.Cu" "F.Mask" "F.Paste")
			(net "PVDDCR_CPU1_P0")
		)
		(pad "BT48" smd circle
			(at 9.249918 10.07999 180)
			(size 0.450088 0.450088)
			(layers "F.Cu" "F.Mask" "F.Paste")
			(net "GND")
		)
		(pad "BT49" smd circle
			(at 10.189972 10.07999 180)
			(size 0.450088 0.450088)
			(layers "F.Cu" "F.Mask" "F.Paste")
			(net "PVDDCR_CPU1_P0")
		)
		(pad "BT50" smd circle
			(at 11.130026 10.07999 180)
			(size 0.450088 0.450088)
			(layers "F.Cu" "F.Mask" "F.Paste")
			(net "PVDDCR_CPU1_P0")
		)
		(pad "BT51" smd circle
			(at 12.07008 10.07999 180)
			(size 0.450088 0.450088)
			(layers "F.Cu" "F.Mask" "F.Paste")
			(net "GND")
		)
		(pad "BT52" smd circle
			(at 13.00988 10.07999 180)
			(size 0.450088 0.450088)
			(layers "F.Cu" "F.Mask" "F.Paste")
			(net "PVDDCR_CPU1_P0")
		)
		(pad "BT53" smd circle
			(at 13.949934 10.07999 180)
			(size 0.450088 0.450088)
			(layers "F.Cu" "F.Mask" "F.Paste")
			(net "PVDDCR_CPU1_P0")
		)
		(pad "BT54" smd circle
			(at 14.889988 10.07999 180)
			(size 0.450088 0.450088)
			(layers "F.Cu" "F.Mask" "F.Paste")
			(net "GND")
		)
		(pad "BT55" smd circle
			(at 15.830042 10.07999 180)
			(size 0.450088 0.450088)
			(layers "F.Cu" "F.Mask" "F.Paste")
			(net "GND")
		)
		(pad "BT56" smd circle
			(at 16.770096 10.07999 180)
			(size 0.450088 0.450088)
			(layers "F.Cu" "F.Mask" "F.Paste")
			(net "M_C_CPU0_SB_CB<4>")
		)
		(pad "BT57" smd circle
			(at 17.709896 10.07999 180)
			(size 0.450088 0.450088)
			(layers "F.Cu" "F.Mask" "F.Paste")
			(net "GND")
		)
		(pad "BT58" smd circle
			(at 18.64995 10.07999 180)
			(size 0.450088 0.450088)
			(layers "F.Cu" "F.Mask" "F.Paste")
			(net "GND")
		)
		(pad "BT59" smd circle
			(at 19.590004 10.07999 180)
			(size 0.450088 0.450088)
			(layers "F.Cu" "F.Mask" "F.Paste")
			(net "GND")
		)
		(pad "BT60" smd circle
			(at 20.530058 10.07999 180)
			(size 0.450088 0.450088)
			(layers "F.Cu" "F.Mask" "F.Paste")
			(net "M_D_CPU0_SB_CB<4>")
		)
		(pad "BT61" smd circle
			(at 21.470112 10.07999 180)
			(size 0.450088 0.450088)
			(layers "F.Cu" "F.Mask" "F.Paste")
			(net "GND")
		)
		(pad "BT62" smd circle
			(at 22.409912 10.07999 180)
			(size 0.450088 0.450088)
			(layers "F.Cu" "F.Mask" "F.Paste")
			(net "GND")
		)
		(pad "BT63" smd circle
			(at 23.349966 10.07999 180)
			(size 0.450088 0.450088)
			(layers "F.Cu" "F.Mask" "F.Paste")
			(net "M_B_CPU0_SB_CB<4>")
		)
		(pad "BT64" smd circle
			(at 24.29002 10.07999 180)
			(size 0.450088 0.450088)
			(layers "F.Cu" "F.Mask" "F.Paste")
			(net "GND")
		)
		(pad "BT65" smd circle
			(at 25.230074 10.07999 180)
			(size 0.450088 0.450088)
			(layers "F.Cu" "F.Mask" "F.Paste")
			(net "GND")
		)
		(pad "BT66" smd circle
			(at 26.170128 10.07999 180)
			(size 0.450088 0.450088)
			(layers "F.Cu" "F.Mask" "F.Paste")
			(net "GND")
		)
		(pad "BT67" smd circle
			(at 27.109928 10.07999 180)
			(size 0.450088 0.450088)
			(layers "F.Cu" "F.Mask" "F.Paste")
			(net "M_F_CPU0_SB_CB<4>")
		)
		(pad "BT68" smd circle
			(at 28.049982 10.07999 180)
			(size 0.450088 0.450088)
			(layers "F.Cu" "F.Mask" "F.Paste")
			(net "GND")
		)
		(pad "BT69" smd circle
			(at 28.990036 10.07999 180)
			(size 0.450088 0.450088)
			(layers "F.Cu" "F.Mask" "F.Paste")
			(net "GND")
		)
		(pad "BT70" smd circle
			(at 29.93009 10.07999 180)
			(size 0.450088 0.450088)
			(layers "F.Cu" "F.Mask" "F.Paste")
			(net "M_E_CPU0_SB_CB<4>")
		)
		(pad "BT71" smd circle
			(at 30.86989 10.07999 180)
			(size 0.450088 0.450088)
			(layers "F.Cu" "F.Mask" "F.Paste")
			(net "GND")
		)
		(pad "BT72" smd circle
			(at 31.809944 10.07999 180)
			(size 0.450088 0.450088)
			(layers "F.Cu" "F.Mask" "F.Paste")
			(net "GND")
		)
		(pad "BT73" smd circle
			(at 32.749998 10.07999 180)
			(size 0.450088 0.450088)
			(layers "F.Cu" "F.Mask" "F.Paste")
			(net "GND")
		)
		(pad "BT74" smd circle
			(at 33.690052 10.07999 180)
			(size 0.450088 0.450088)
			(layers "F.Cu" "F.Mask" "F.Paste")
			(net "M_A_CPU0_SB_CB<4>")
		)
		(pad "BU1" smd circle
			(at -34.459926 10.889996 180)
			(size 0.450088 0.450088)
			(layers "F.Cu" "F.Mask" "F.Paste")
			(net "GND")
		)
		(pad "BU2" smd circle
			(at -33.519872 10.889996 180)
			(size 0.450088 0.450088)
			(layers "F.Cu" "F.Mask" "F.Paste")
			(net "M_G_CPU0_SB_CB<6>")
		)
		(pad "BU3" smd circle
			(at -32.580072 10.889996 180)
			(size 0.450088 0.450088)
			(layers "F.Cu" "F.Mask" "F.Paste")
			(net "M_G_CPU0_SB_CB<5>")
		)
		(pad "BU4" smd circle
			(at -31.640018 10.889996 180)
			(size 0.450088 0.450088)
			(layers "F.Cu" "F.Mask" "F.Paste")
			(net "GND")
		)
		(pad "BU5" smd circle
			(at -30.699964 10.889996 180)
			(size 0.450088 0.450088)
			(layers "F.Cu" "F.Mask" "F.Paste")
			(net "M_K_CPU0_SB_CB<6>")
		)
		(pad "BU6" smd circle
			(at -29.75991 10.889996 180)
			(size 0.450088 0.450088)
			(layers "F.Cu" "F.Mask" "F.Paste")
			(net "GND")
		)
		(pad "BU7" smd circle
			(at -28.82011 10.889996 180)
			(size 0.450088 0.450088)
			(layers "F.Cu" "F.Mask" "F.Paste")
			(net "M_K_CPU0_SB_CB<5>")
		)
		(pad "BU8" smd circle
			(at -27.880056 10.889996 180)
			(size 0.450088 0.450088)
			(layers "F.Cu" "F.Mask" "F.Paste")
			(net "GND")
		)
		(pad "BU9" smd circle
			(at -26.940002 10.889996 180)
			(size 0.450088 0.450088)
			(layers "F.Cu" "F.Mask" "F.Paste")
			(net "M_L_CPU0_SB_CB<6>")
		)
		(pad "BU10" smd circle
			(at -25.999948 10.889996 180)
			(size 0.450088 0.450088)
			(layers "F.Cu" "F.Mask" "F.Paste")
			(net "M_L_CPU0_SB_CB<5>")
		)
		(pad "BU11" smd circle
			(at -25.059894 10.889996 180)
			(size 0.450088 0.450088)
			(layers "F.Cu" "F.Mask" "F.Paste")
			(net "GND")
		)
		(pad "BU12" smd circle
			(at -24.120094 10.889996 180)
			(size 0.450088 0.450088)
			(layers "F.Cu" "F.Mask" "F.Paste")
			(net "M_H_CPU0_SB_CB<6>")
		)
		(pad "BU13" smd circle
			(at -23.18004 10.889996 180)
			(size 0.450088 0.450088)
			(layers "F.Cu" "F.Mask" "F.Paste")
			(net "GND")
		)
		(pad "BU14" smd circle
			(at -22.239986 10.889996 180)
			(size 0.450088 0.450088)
			(layers "F.Cu" "F.Mask" "F.Paste")
			(net "M_H_CPU0_SB_CB<5>")
		)
		(pad "BU15" smd circle
			(at -21.299932 10.889996 180)
			(size 0.450088 0.450088)
			(layers "F.Cu" "F.Mask" "F.Paste")
			(net "GND")
		)
		(pad "BU16" smd circle
			(at -20.359878 10.889996 180)
			(size 0.450088 0.450088)
			(layers "F.Cu" "F.Mask" "F.Paste")
			(net "M_J_CPU0_SB_CB<6>")
		)
		(pad "BU17" smd circle
			(at -19.420078 10.889996 180)
			(size 0.450088 0.450088)
			(layers "F.Cu" "F.Mask" "F.Paste")
			(net "M_J_CPU0_SB_CB<5>")
		)
		(pad "BU18" smd circle
			(at -18.480024 10.889996 180)
			(size 0.450088 0.450088)
			(layers "F.Cu" "F.Mask" "F.Paste")
			(net "GND")
		)
		(pad "BU19" smd circle
			(at -17.53997 10.889996 180)
			(size 0.450088 0.450088)
			(layers "F.Cu" "F.Mask" "F.Paste")
			(net "M_I_CPU0_SB_CB<6>")
		)
		(pad "BU20" smd circle
			(at -16.599916 10.889996 180)
			(size 0.450088 0.450088)
			(layers "F.Cu" "F.Mask" "F.Paste")
			(net "GND")
		)
		(pad "BU21" smd circle
			(at -15.660116 10.889996 180)
			(size 0.450088 0.450088)
			(layers "F.Cu" "F.Mask" "F.Paste")
			(net "M_I_CPU0_SB_CB<5>")
		)
		(pad "BU22" smd circle
			(at -14.720062 10.889996 180)
			(size 0.450088 0.450088)
			(layers "F.Cu" "F.Mask" "F.Paste")
			(net "GND")
		)
		(pad "BU23" smd circle
			(at -13.780008 10.889996 180)
			(size 0.450088 0.450088)
			(layers "F.Cu" "F.Mask" "F.Paste")
			(net "P5E_CPU0_P2_TX_DN<13>")
		)
		(pad "BU24" smd circle
			(at -12.839954 10.889996 180)
			(size 0.450088 0.450088)
			(layers "F.Cu" "F.Mask" "F.Paste")
			(net "P5E_CPU0_P2_TX_DP<13>")
		)
		(pad "BU25" smd circle
			(at -11.8999 10.889996 180)
			(size 0.450088 0.450088)
			(layers "F.Cu" "F.Mask" "F.Paste")
			(net "GND")
		)
		(pad "BU26" smd circle
			(at -10.9601 10.889996 180)
			(size 0.450088 0.450088)
			(layers "F.Cu" "F.Mask" "F.Paste")
			(net "P5E_CPU0_P2_TX_DN<10>")
		)
		(pad "BU27" smd circle
			(at -10.020046 10.889996 180)
			(size 0.450088 0.450088)
			(layers "F.Cu" "F.Mask" "F.Paste")
			(net "P5E_CPU0_P2_TX_DP<10>")
		)
		(pad "BU28" smd circle
			(at -9.079992 10.889996 180)
			(size 0.450088 0.450088)
			(layers "F.Cu" "F.Mask" "F.Paste")
			(net "GND")
		)
		(pad "BU29" smd circle
			(at -8.139938 10.889996 180)
			(size 0.450088 0.450088)
			(layers "F.Cu" "F.Mask" "F.Paste")
			(net "P5E_CPU0_P2_TX_DN<7>")
		)
		(pad "BU30" smd circle
			(at -7.199884 10.889996 180)
			(size 0.450088 0.450088)
			(layers "F.Cu" "F.Mask" "F.Paste")
			(net "P5E_CPU0_P2_TX_DP<7>")
		)
		(pad "BU31" smd circle
			(at -6.260084 10.889996 180)
			(size 0.450088 0.450088)
			(layers "F.Cu" "F.Mask" "F.Paste")
			(net "GND")
		)
		(pad "BU32" smd circle
			(at -5.32003 10.889996 180)
			(size 0.450088 0.450088)
			(layers "F.Cu" "F.Mask" "F.Paste")
			(net "P5E_CPU0_P2_TX_DN<4>")
		)
		(pad "BU33" smd circle
			(at -4.379976 10.889996 180)
			(size 0.450088 0.450088)
			(layers "F.Cu" "F.Mask" "F.Paste")
			(net "P5E_CPU0_P2_TX_DP<4>")
		)
		(pad "BU34" smd circle
			(at -3.439922 10.889996 180)
			(size 0.450088 0.450088)
			(layers "F.Cu" "F.Mask" "F.Paste")
			(net "GND")
		)
		(pad "BU35" smd circle
			(at -2.500122 10.889996 180)
			(size 0.450088 0.450088)
			(layers "F.Cu" "F.Mask" "F.Paste")
			(net "GND")
		)
		(pad "BU36" smd circle
			(at -1.560068 10.889996 180)
			(size 0.450088 0.450088)
			(layers "F.Cu" "F.Mask" "F.Paste")
			(net "GND")
		)
		(pad "BU40" smd circle
			(at 1.260094 10.889996 180)
			(size 0.450088 0.450088)
			(layers "F.Cu" "F.Mask" "F.Paste")
			(net "GND")
		)
		(pad "BU41" smd circle
			(at 2.199894 10.889996 180)
			(size 0.450088 0.450088)
			(layers "F.Cu" "F.Mask" "F.Paste")
			(net "GND")
		)
		(pad "BU42" smd circle
			(at 3.139948 10.889996 180)
			(size 0.450088 0.450088)
			(layers "F.Cu" "F.Mask" "F.Paste")
			(net "GND")
		)
		(pad "BU43" smd circle
			(at 4.080002 10.889996 180)
			(size 0.450088 0.450088)
			(layers "F.Cu" "F.Mask" "F.Paste")
			(net "P5E_CPU0_P0_RX_DP<11>")
		)
		(pad "BU44" smd circle
			(at 5.020056 10.889996 180)
			(size 0.450088 0.450088)
			(layers "F.Cu" "F.Mask" "F.Paste")
			(net "P5E_CPU0_P0_RX_DN<11>")
		)
		(pad "BU45" smd circle
			(at 5.96011 10.889996 180)
			(size 0.450088 0.450088)
			(layers "F.Cu" "F.Mask" "F.Paste")
			(net "GND")
		)
		(pad "BU46" smd circle
			(at 6.89991 10.889996 180)
			(size 0.450088 0.450088)
			(layers "F.Cu" "F.Mask" "F.Paste")
			(net "P5E_CPU0_P0_RX_DP<8>")
		)
		(pad "BU47" smd circle
			(at 7.839964 10.889996 180)
			(size 0.450088 0.450088)
			(layers "F.Cu" "F.Mask" "F.Paste")
			(net "P5E_CPU0_P0_RX_DN<8>")
		)
		(pad "BU48" smd circle
			(at 8.780018 10.889996 180)
			(size 0.450088 0.450088)
			(layers "F.Cu" "F.Mask" "F.Paste")
			(net "GND")
		)
		(pad "BU49" smd circle
			(at 9.720072 10.889996 180)
			(size 0.450088 0.450088)
			(layers "F.Cu" "F.Mask" "F.Paste")
			(net "P5E_CPU0_P0_RX_DP<5>")
		)
		(pad "BU50" smd circle
			(at 10.659872 10.889996 180)
			(size 0.450088 0.450088)
			(layers "F.Cu" "F.Mask" "F.Paste")
			(net "P5E_CPU0_P0_RX_DN<5>")
		)
		(pad "BU51" smd circle
			(at 11.599926 10.889996 180)
			(size 0.450088 0.450088)
			(layers "F.Cu" "F.Mask" "F.Paste")
			(net "GND")
		)
		(pad "BU52" smd circle
			(at 12.53998 10.889996 180)
			(size 0.450088 0.450088)
			(layers "F.Cu" "F.Mask" "F.Paste")
			(net "P5E_CPU0_P0_RX_DP<2>")
		)
		(pad "BU53" smd circle
			(at 13.480034 10.889996 180)
			(size 0.450088 0.450088)
			(layers "F.Cu" "F.Mask" "F.Paste")
			(net "P5E_CPU0_P0_RX_DN<2>")
		)
		(pad "BU54" smd circle
			(at 14.420088 10.889996 180)
			(size 0.450088 0.450088)
			(layers "F.Cu" "F.Mask" "F.Paste")
			(net "GND")
		)
		(pad "BU55" smd circle
			(at 15.359888 10.889996 180)
			(size 0.450088 0.450088)
			(layers "F.Cu" "F.Mask" "F.Paste")
			(net "M_C_CPU0_SB_CB<5>")
		)
		(pad "BU56" smd circle
			(at 16.299942 10.889996 180)
			(size 0.450088 0.450088)
			(layers "F.Cu" "F.Mask" "F.Paste")
			(net "GND")
		)
		(pad "BU57" smd circle
			(at 17.239996 10.889996 180)
			(size 0.450088 0.450088)
			(layers "F.Cu" "F.Mask" "F.Paste")
			(net "M_C_CPU0_SB_CB<6>")
		)
		(pad "BU58" smd circle
			(at 18.18005 10.889996 180)
			(size 0.450088 0.450088)
			(layers "F.Cu" "F.Mask" "F.Paste")
			(net "GND")
		)
		(pad "BU59" smd circle
			(at 19.120104 10.889996 180)
			(size 0.450088 0.450088)
			(layers "F.Cu" "F.Mask" "F.Paste")
			(net "M_D_CPU0_SB_CB<5>")
		)
		(pad "BU60" smd circle
			(at 20.059904 10.889996 180)
			(size 0.450088 0.450088)
			(layers "F.Cu" "F.Mask" "F.Paste")
			(net "M_D_CPU0_SB_CB<6>")
		)
		(pad "BU61" smd circle
			(at 20.999958 10.889996 180)
			(size 0.450088 0.450088)
			(layers "F.Cu" "F.Mask" "F.Paste")
			(net "GND")
		)
		(pad "BU62" smd circle
			(at 21.940012 10.889996 180)
			(size 0.450088 0.450088)
			(layers "F.Cu" "F.Mask" "F.Paste")
			(net "M_B_CPU0_SB_CB<5>")
		)
		(pad "BU63" smd circle
			(at 22.880066 10.889996 180)
			(size 0.450088 0.450088)
			(layers "F.Cu" "F.Mask" "F.Paste")
			(net "GND")
		)
		(pad "BU64" smd circle
			(at 23.82012 10.889996 180)
			(size 0.450088 0.450088)
			(layers "F.Cu" "F.Mask" "F.Paste")
			(net "M_B_CPU0_SB_CB<6>")
		)
		(pad "BU65" smd circle
			(at 24.75992 10.889996 180)
			(size 0.450088 0.450088)
			(layers "F.Cu" "F.Mask" "F.Paste")
			(net "GND")
		)
		(pad "BU66" smd circle
			(at 25.699974 10.889996 180)
			(size 0.450088 0.450088)
			(layers "F.Cu" "F.Mask" "F.Paste")
			(net "M_F_CPU0_SB_CB<5>")
		)
		(pad "BU67" smd circle
			(at 26.640028 10.889996 180)
			(size 0.450088 0.450088)
			(layers "F.Cu" "F.Mask" "F.Paste")
			(net "M_F_CPU0_SB_CB<6>")
		)
		(pad "BU68" smd circle
			(at 27.580082 10.889996 180)
			(size 0.450088 0.450088)
			(layers "F.Cu" "F.Mask" "F.Paste")
			(net "GND")
		)
		(pad "BU69" smd circle
			(at 28.519882 10.889996 180)
			(size 0.450088 0.450088)
			(layers "F.Cu" "F.Mask" "F.Paste")
			(net "M_E_CPU0_SB_CB<5>")
		)
		(pad "BU70" smd circle
			(at 29.459936 10.889996 180)
			(size 0.450088 0.450088)
			(layers "F.Cu" "F.Mask" "F.Paste")
			(net "GND")
		)
		(pad "BU71" smd circle
			(at 30.39999 10.889996 180)
			(size 0.450088 0.450088)
			(layers "F.Cu" "F.Mask" "F.Paste")
			(net "M_E_CPU0_SB_CB<6>")
		)
		(pad "BU72" smd circle
			(at 31.340044 10.889996 180)
			(size 0.450088 0.450088)
			(layers "F.Cu" "F.Mask" "F.Paste")
			(net "GND")
		)
		(pad "BU73" smd circle
			(at 32.280098 10.889996 180)
			(size 0.450088 0.450088)
			(layers "F.Cu" "F.Mask" "F.Paste")
			(net "M_A_CPU0_SB_CB<5>")
		)
		(pad "BU74" smd circle
			(at 33.219898 10.889996 180)
			(size 0.450088 0.450088)
			(layers "F.Cu" "F.Mask" "F.Paste")
			(net "M_A_CPU0_SB_CB<6>")
		)
		(pad "BU75" smd circle
			(at 34.159952 10.889996 180)
			(size 0.450088 0.450088)
			(layers "F.Cu" "F.Mask" "F.Paste")
			(net "GND")
		)
		(pad "BV2" smd circle
			(at -33.990026 11.700002 180)
			(size 0.450088 0.450088)
			(layers "F.Cu" "F.Mask" "F.Paste")
			(net "M_G_CPU0_SB_DQS_DP<9>")
		)
		(pad "BV3" smd circle
			(at -33.049972 11.700002 180)
			(size 0.450088 0.450088)
			(layers "F.Cu" "F.Mask" "F.Paste")
			(net "GND")
		)
		(pad "BV4" smd circle
			(at -32.109918 11.700002 180)
			(size 0.450088 0.450088)
			(layers "F.Cu" "F.Mask" "F.Paste")
			(net "M_G_CPU0_SB_CB<7>")
		)
		(pad "BV5" smd circle
			(at -31.170118 11.700002 180)
			(size 0.450088 0.450088)
			(layers "F.Cu" "F.Mask" "F.Paste")
			(net "PVDD11_S3_P0")
		)
		(pad "BV6" smd circle
			(at -30.230064 11.700002 180)
			(size 0.450088 0.450088)
			(layers "F.Cu" "F.Mask" "F.Paste")
			(net "M_K_CPU0_SB_DQS_DP<9>")
		)
		(pad "BV7" smd circle
			(at -29.29001 11.700002 180)
			(size 0.450088 0.450088)
			(layers "F.Cu" "F.Mask" "F.Paste")
			(net "M_K_CPU0_SB_CB<7>")
		)
		(pad "BV8" smd circle
			(at -28.349956 11.700002 180)
			(size 0.450088 0.450088)
			(layers "F.Cu" "F.Mask" "F.Paste")
			(net "GND")
		)
		(pad "BV9" smd circle
			(at -27.409902 11.700002 180)
			(size 0.450088 0.450088)
			(layers "F.Cu" "F.Mask" "F.Paste")
			(net "M_L_CPU0_SB_DQS_DP<9>")
		)
		(pad "BV10" smd circle
			(at -26.470102 11.700002 180)
			(size 0.450088 0.450088)
			(layers "F.Cu" "F.Mask" "F.Paste")
			(net "GND")
		)
		(pad "BV11" smd circle
			(at -25.530048 11.700002 180)
			(size 0.450088 0.450088)
			(layers "F.Cu" "F.Mask" "F.Paste")
			(net "M_L_CPU0_SB_CB<7>")
		)
		(pad "BV12" smd circle
			(at -24.589994 11.700002 180)
			(size 0.450088 0.450088)
			(layers "F.Cu" "F.Mask" "F.Paste")
			(net "PVDD11_S3_P0")
		)
		(pad "BV13" smd circle
			(at -23.64994 11.700002 180)
			(size 0.450088 0.450088)
			(layers "F.Cu" "F.Mask" "F.Paste")
			(net "M_H_CPU0_SB_DQS_DP<9>")
		)
		(pad "BV14" smd circle
			(at -22.709886 11.700002 180)
			(size 0.450088 0.450088)
			(layers "F.Cu" "F.Mask" "F.Paste")
			(net "M_H_CPU0_SB_CB<7>")
		)
		(pad "BV15" smd circle
			(at -21.770086 11.700002 180)
			(size 0.450088 0.450088)
			(layers "F.Cu" "F.Mask" "F.Paste")
			(net "GND")
		)
		(pad "BV16" smd circle
			(at -20.830032 11.700002 180)
			(size 0.450088 0.450088)
			(layers "F.Cu" "F.Mask" "F.Paste")
			(net "M_J_CPU0_SB_DQS_DP<9>")
		)
		(pad "BV17" smd circle
			(at -19.889978 11.700002 180)
			(size 0.450088 0.450088)
			(layers "F.Cu" "F.Mask" "F.Paste")
			(net "GND")
		)
		(pad "BV18" smd circle
			(at -18.949924 11.700002 180)
			(size 0.450088 0.450088)
			(layers "F.Cu" "F.Mask" "F.Paste")
			(net "M_J_CPU0_SB_CB<7>")
		)
		(pad "BV19" smd circle
			(at -18.010124 11.700002 180)
			(size 0.450088 0.450088)
			(layers "F.Cu" "F.Mask" "F.Paste")
			(net "PVDD11_S3_P0")
		)
		(pad "BV20" smd circle
			(at -17.07007 11.700002 180)
			(size 0.450088 0.450088)
			(layers "F.Cu" "F.Mask" "F.Paste")
			(net "M_I_CPU0_SB_DQS_DP<9>")
		)
		(pad "BV21" smd circle
			(at -16.130016 11.700002 180)
			(size 0.450088 0.450088)
			(layers "F.Cu" "F.Mask" "F.Paste")
			(net "M_I_CPU0_SB_CB<7>")
		)
		(pad "BV22" smd circle
			(at -15.189962 11.700002 180)
			(size 0.450088 0.450088)
			(layers "F.Cu" "F.Mask" "F.Paste")
			(net "PVDD11_S3_P0")
		)
		(pad "BV23" smd circle
			(at -14.249908 11.700002 180)
			(size 0.450088 0.450088)
			(layers "F.Cu" "F.Mask" "F.Paste")
			(net "GND")
		)
		(pad "BV24" smd circle
			(at -13.310108 11.700002 180)
			(size 0.450088 0.450088)
			(layers "F.Cu" "F.Mask" "F.Paste")
			(net "GND")
		)
		(pad "BV25" smd circle
			(at -12.370054 11.700002 180)
			(size 0.450088 0.450088)
			(layers "F.Cu" "F.Mask" "F.Paste")
			(net "GND")
		)
		(pad "BV26" smd circle
			(at -11.43 11.700002 180)
			(size 0.450088 0.450088)
			(layers "F.Cu" "F.Mask" "F.Paste")
			(net "GND")
		)
		(pad "BV27" smd circle
			(at -10.489946 11.700002 180)
			(size 0.450088 0.450088)
			(layers "F.Cu" "F.Mask" "F.Paste")
			(net "GND")
		)
		(pad "BV28" smd circle
			(at -9.549892 11.700002 180)
			(size 0.450088 0.450088)
			(layers "F.Cu" "F.Mask" "F.Paste")
			(net "GND")
		)
		(pad "BV29" smd circle
			(at -8.610092 11.700002 180)
			(size 0.450088 0.450088)
			(layers "F.Cu" "F.Mask" "F.Paste")
			(net "GND")
		)
		(pad "BV30" smd circle
			(at -7.670038 11.700002 180)
			(size 0.450088 0.450088)
			(layers "F.Cu" "F.Mask" "F.Paste")
			(net "GND")
		)
		(pad "BV31" smd circle
			(at -6.729984 11.700002 180)
			(size 0.450088 0.450088)
			(layers "F.Cu" "F.Mask" "F.Paste")
			(net "GND")
		)
		(pad "BV32" smd circle
			(at -5.78993 11.700002 180)
			(size 0.450088 0.450088)
			(layers "F.Cu" "F.Mask" "F.Paste")
			(net "GND")
		)
		(pad "BV33" smd circle
			(at -4.849876 11.700002 180)
			(size 0.450088 0.450088)
			(layers "F.Cu" "F.Mask" "F.Paste")
			(net "GND")
		)
		(pad "BV34" smd circle
			(at -3.910076 11.700002 180)
			(size 0.450088 0.450088)
			(layers "F.Cu" "F.Mask" "F.Paste")
			(net "GND")
		)
		(pad "BV35" smd circle
			(at -2.970022 11.700002 180)
			(size 0.450088 0.450088)
			(layers "F.Cu" "F.Mask" "F.Paste")
			(net "P5E_CPU0_P2_TX_DN<1>")
		)
		(pad "BV36" smd circle
			(at -2.029968 11.700002 180)
			(size 0.450088 0.450088)
			(layers "F.Cu" "F.Mask" "F.Paste")
			(net "P5E_CPU0_P2_TX_DP<1>")
		)
		(pad "BV37" smd circle
			(at -1.089914 11.700002 180)
			(size 0.450088 0.450088)
			(layers "F.Cu" "F.Mask" "F.Paste")
			(net "GND")
		)
		(pad "BV39" smd circle
			(at 0.78994 11.700002 180)
			(size 0.450088 0.450088)
			(layers "F.Cu" "F.Mask" "F.Paste")
			(net "GND")
		)
		(pad "BV40" smd circle
			(at 1.729994 11.700002 180)
			(size 0.450088 0.450088)
			(layers "F.Cu" "F.Mask" "F.Paste")
			(net "P5E_CPU0_P0_RX_DP<14>")
		)
		(pad "BV41" smd circle
			(at 2.670048 11.700002 180)
			(size 0.450088 0.450088)
			(layers "F.Cu" "F.Mask" "F.Paste")
			(net "P5E_CPU0_P0_RX_DN<14>")
		)
		(pad "BV42" smd circle
			(at 3.610102 11.700002 180)
			(size 0.450088 0.450088)
			(layers "F.Cu" "F.Mask" "F.Paste")
			(net "GND")
		)
		(pad "BV43" smd circle
			(at 4.549902 11.700002 180)
			(size 0.450088 0.450088)
			(layers "F.Cu" "F.Mask" "F.Paste")
			(net "GND")
		)
		(pad "BV44" smd circle
			(at 5.489956 11.700002 180)
			(size 0.450088 0.450088)
			(layers "F.Cu" "F.Mask" "F.Paste")
			(net "GND")
		)
		(pad "BV45" smd circle
			(at 6.43001 11.700002 180)
			(size 0.450088 0.450088)
			(layers "F.Cu" "F.Mask" "F.Paste")
			(net "GND")
		)
		(pad "BV46" smd circle
			(at 7.370064 11.700002 180)
			(size 0.450088 0.450088)
			(layers "F.Cu" "F.Mask" "F.Paste")
			(net "GND")
		)
		(pad "BV47" smd circle
			(at 8.310118 11.700002 180)
			(size 0.450088 0.450088)
			(layers "F.Cu" "F.Mask" "F.Paste")
			(net "GND")
		)
		(pad "BV48" smd circle
			(at 9.249918 11.700002 180)
			(size 0.450088 0.450088)
			(layers "F.Cu" "F.Mask" "F.Paste")
			(net "GND")
		)
		(pad "BV49" smd circle
			(at 10.189972 11.700002 180)
			(size 0.450088 0.450088)
			(layers "F.Cu" "F.Mask" "F.Paste")
			(net "GND")
		)
		(pad "BV50" smd circle
			(at 11.130026 11.700002 180)
			(size 0.450088 0.450088)
			(layers "F.Cu" "F.Mask" "F.Paste")
			(net "GND")
		)
		(pad "BV51" smd circle
			(at 12.07008 11.700002 180)
			(size 0.450088 0.450088)
			(layers "F.Cu" "F.Mask" "F.Paste")
			(net "GND")
		)
		(pad "BV52" smd circle
			(at 13.00988 11.700002 180)
			(size 0.450088 0.450088)
			(layers "F.Cu" "F.Mask" "F.Paste")
			(net "GND")
		)
		(pad "BV53" smd circle
			(at 13.949934 11.700002 180)
			(size 0.450088 0.450088)
			(layers "F.Cu" "F.Mask" "F.Paste")
			(net "GND")
		)
		(pad "BV54" smd circle
			(at 14.889988 11.700002 180)
			(size 0.450088 0.450088)
			(layers "F.Cu" "F.Mask" "F.Paste")
			(net "PVDDIO_P0")
		)
		(pad "BV55" smd circle
			(at 15.830042 11.700002 180)
			(size 0.450088 0.450088)
			(layers "F.Cu" "F.Mask" "F.Paste")
			(net "M_C_CPU0_SB_CB<7>")
		)
		(pad "BV56" smd circle
			(at 16.770096 11.700002 180)
			(size 0.450088 0.450088)
			(layers "F.Cu" "F.Mask" "F.Paste")
			(net "M_C_CPU0_SB_DQS_DP<9>")
		)
		(pad "BV57" smd circle
			(at 17.709896 11.700002 180)
			(size 0.450088 0.450088)
			(layers "F.Cu" "F.Mask" "F.Paste")
			(net "PVDDIO_P0")
		)
		(pad "BV58" smd circle
			(at 18.64995 11.700002 180)
			(size 0.450088 0.450088)
			(layers "F.Cu" "F.Mask" "F.Paste")
			(net "M_D_CPU0_SB_CB<7>")
		)
		(pad "BV59" smd circle
			(at 19.590004 11.700002 180)
			(size 0.450088 0.450088)
			(layers "F.Cu" "F.Mask" "F.Paste")
			(net "GND")
		)
		(pad "BV60" smd circle
			(at 20.530058 11.700002 180)
			(size 0.450088 0.450088)
			(layers "F.Cu" "F.Mask" "F.Paste")
			(net "M_D_CPU0_SB_DQS_DP<9>")
		)
		(pad "BV61" smd circle
			(at 21.470112 11.700002 180)
			(size 0.450088 0.450088)
			(layers "F.Cu" "F.Mask" "F.Paste")
			(net "GND")
		)
		(pad "BV62" smd circle
			(at 22.409912 11.700002 180)
			(size 0.450088 0.450088)
			(layers "F.Cu" "F.Mask" "F.Paste")
			(net "M_B_CPU0_SB_CB<7>")
		)
		(pad "BV63" smd circle
			(at 23.349966 11.700002 180)
			(size 0.450088 0.450088)
			(layers "F.Cu" "F.Mask" "F.Paste")
			(net "M_B_CPU0_SB_DQS_DP<9>")
		)
		(pad "BV64" smd circle
			(at 24.29002 11.700002 180)
			(size 0.450088 0.450088)
			(layers "F.Cu" "F.Mask" "F.Paste")
			(net "PVDDIO_P0")
		)
		(pad "BV65" smd circle
			(at 25.230074 11.700002 180)
			(size 0.450088 0.450088)
			(layers "F.Cu" "F.Mask" "F.Paste")
			(net "M_F_CPU0_SB_CB<7>")
		)
		(pad "BV66" smd circle
			(at 26.170128 11.700002 180)
			(size 0.450088 0.450088)
			(layers "F.Cu" "F.Mask" "F.Paste")
			(net "GND")
		)
		(pad "BV67" smd circle
			(at 27.109928 11.700002 180)
			(size 0.450088 0.450088)
			(layers "F.Cu" "F.Mask" "F.Paste")
			(net "M_F_CPU0_SB_DQS_DP<9>")
		)
		(pad "BV68" smd circle
			(at 28.049982 11.700002 180)
			(size 0.450088 0.450088)
			(layers "F.Cu" "F.Mask" "F.Paste")
			(net "GND")
		)
		(pad "BV69" smd circle
			(at 28.990036 11.700002 180)
			(size 0.450088 0.450088)
			(layers "F.Cu" "F.Mask" "F.Paste")
			(net "M_E_CPU0_SB_CB<7>")
		)
		(pad "BV70" smd circle
			(at 29.93009 11.700002 180)
			(size 0.450088 0.450088)
			(layers "F.Cu" "F.Mask" "F.Paste")
			(net "M_E_CPU0_SB_DQS_DP<9>")
		)
		(pad "BV71" smd circle
			(at 30.86989 11.700002 180)
			(size 0.450088 0.450088)
			(layers "F.Cu" "F.Mask" "F.Paste")
			(net "PVDDIO_P0")
		)
		(pad "BV72" smd circle
			(at 31.809944 11.700002 180)
			(size 0.450088 0.450088)
			(layers "F.Cu" "F.Mask" "F.Paste")
			(net "M_A_CPU0_SB_CB<7>")
		)
		(pad "BV73" smd circle
			(at 32.749998 11.700002 180)
			(size 0.450088 0.450088)
			(layers "F.Cu" "F.Mask" "F.Paste")
			(net "GND")
		)
		(pad "BV74" smd circle
			(at 33.690052 11.700002 180)
			(size 0.450088 0.450088)
			(layers "F.Cu" "F.Mask" "F.Paste")
			(net "M_A_CPU0_SB_DQS_DP<9>")
		)
		(pad "BW1" smd circle
			(at -34.459926 12.510008 180)
			(size 0.450088 0.450088)
			(layers "F.Cu" "F.Mask" "F.Paste")
			(net "GND")
		)
		(pad "BW2" smd circle
			(at -33.519872 12.510008 180)
			(size 0.450088 0.450088)
			(layers "F.Cu" "F.Mask" "F.Paste")
			(net "M_G_CPU0_SB_DQS_DN<9>")
		)
		(pad "BW3" smd circle
			(at -32.580072 12.510008 180)
			(size 0.450088 0.450088)
			(layers "F.Cu" "F.Mask" "F.Paste")
			(net "M_G_CPU0_SB_DQS_DN<4>")
		)
		(pad "BW4" smd circle
			(at -31.640018 12.510008 180)
			(size 0.450088 0.450088)
			(layers "F.Cu" "F.Mask" "F.Paste")
			(net "GND")
		)
		(pad "BW5" smd circle
			(at -30.699964 12.510008 180)
			(size 0.450088 0.450088)
			(layers "F.Cu" "F.Mask" "F.Paste")
			(net "M_K_CPU0_SB_DQS_DN<9>")
		)
		(pad "BW6" smd circle
			(at -29.75991 12.510008 180)
			(size 0.450088 0.450088)
			(layers "F.Cu" "F.Mask" "F.Paste")
			(net "GND")
		)
		(pad "BW7" smd circle
			(at -28.82011 12.510008 180)
			(size 0.450088 0.450088)
			(layers "F.Cu" "F.Mask" "F.Paste")
			(net "M_K_CPU0_SB_DQS_DN<4>")
		)
		(pad "BW8" smd circle
			(at -27.880056 12.510008 180)
			(size 0.450088 0.450088)
			(layers "F.Cu" "F.Mask" "F.Paste")
			(net "GND")
		)
		(pad "BW9" smd circle
			(at -26.940002 12.510008 180)
			(size 0.450088 0.450088)
			(layers "F.Cu" "F.Mask" "F.Paste")
			(net "M_L_CPU0_SB_DQS_DN<9>")
		)
		(pad "BW10" smd circle
			(at -25.999948 12.510008 180)
			(size 0.450088 0.450088)
			(layers "F.Cu" "F.Mask" "F.Paste")
			(net "M_L_CPU0_SB_DQS_DN<4>")
		)
		(pad "BW11" smd circle
			(at -25.059894 12.510008 180)
			(size 0.450088 0.450088)
			(layers "F.Cu" "F.Mask" "F.Paste")
			(net "GND")
		)
		(pad "BW12" smd circle
			(at -24.120094 12.510008 180)
			(size 0.450088 0.450088)
			(layers "F.Cu" "F.Mask" "F.Paste")
			(net "M_H_CPU0_SB_DQS_DN<9>")
		)
		(pad "BW13" smd circle
			(at -23.18004 12.510008 180)
			(size 0.450088 0.450088)
			(layers "F.Cu" "F.Mask" "F.Paste")
			(net "GND")
		)
		(pad "BW14" smd circle
			(at -22.239986 12.510008 180)
			(size 0.450088 0.450088)
			(layers "F.Cu" "F.Mask" "F.Paste")
			(net "M_H_CPU0_SB_DQS_DN<4>")
		)
		(pad "BW15" smd circle
			(at -21.299932 12.510008 180)
			(size 0.450088 0.450088)
			(layers "F.Cu" "F.Mask" "F.Paste")
			(net "GND")
		)
		(pad "BW16" smd circle
			(at -20.359878 12.510008 180)
			(size 0.450088 0.450088)
			(layers "F.Cu" "F.Mask" "F.Paste")
			(net "M_J_CPU0_SB_DQS_DN<9>")
		)
		(pad "BW17" smd circle
			(at -19.420078 12.510008 180)
			(size 0.450088 0.450088)
			(layers "F.Cu" "F.Mask" "F.Paste")
			(net "M_J_CPU0_SB_DQS_DN<4>")
		)
		(pad "BW18" smd circle
			(at -18.480024 12.510008 180)
			(size 0.450088 0.450088)
			(layers "F.Cu" "F.Mask" "F.Paste")
			(net "GND")
		)
		(pad "BW19" smd circle
			(at -17.53997 12.510008 180)
			(size 0.450088 0.450088)
			(layers "F.Cu" "F.Mask" "F.Paste")
			(net "M_I_CPU0_SB_DQS_DN<9>")
		)
		(pad "BW20" smd circle
			(at -16.599916 12.510008 180)
			(size 0.450088 0.450088)
			(layers "F.Cu" "F.Mask" "F.Paste")
			(net "GND")
		)
		(pad "BW21" smd circle
			(at -15.660116 12.510008 180)
			(size 0.450088 0.450088)
			(layers "F.Cu" "F.Mask" "F.Paste")
			(net "M_I_CPU0_SB_DQS_DN<4>")
		)
		(pad "BW22" smd circle
			(at -14.720062 12.510008 180)
			(size 0.450088 0.450088)
			(layers "F.Cu" "F.Mask" "F.Paste")
			(net "GND")
		)
		(pad "BW23" smd circle
			(at -13.780008 12.510008 180)
			(size 0.450088 0.450088)
			(layers "F.Cu" "F.Mask" "F.Paste")
			(net "P5E_CPU0_P2_TX_DN<15>")
		)
		(pad "BW24" smd circle
			(at -12.839954 12.510008 180)
			(size 0.450088 0.450088)
			(layers "F.Cu" "F.Mask" "F.Paste")
			(net "P5E_CPU0_P2_TX_DP<15>")
		)
		(pad "BW25" smd circle
			(at -11.8999 12.510008 180)
			(size 0.450088 0.450088)
			(layers "F.Cu" "F.Mask" "F.Paste")
			(net "GND")
		)
		(pad "BW26" smd circle
			(at -10.9601 12.510008 180)
			(size 0.450088 0.450088)
			(layers "F.Cu" "F.Mask" "F.Paste")
			(net "P5E_CPU0_P2_TX_DN<12>")
		)
		(pad "BW27" smd circle
			(at -10.020046 12.510008 180)
			(size 0.450088 0.450088)
			(layers "F.Cu" "F.Mask" "F.Paste")
			(net "P5E_CPU0_P2_TX_DP<12>")
		)
		(pad "BW28" smd circle
			(at -9.079992 12.510008 180)
			(size 0.450088 0.450088)
			(layers "F.Cu" "F.Mask" "F.Paste")
			(net "GND")
		)
		(pad "BW29" smd circle
			(at -8.139938 12.510008 180)
			(size 0.450088 0.450088)
			(layers "F.Cu" "F.Mask" "F.Paste")
			(net "P5E_CPU0_P2_TX_DN<9>")
		)
		(pad "BW30" smd circle
			(at -7.199884 12.510008 180)
			(size 0.450088 0.450088)
			(layers "F.Cu" "F.Mask" "F.Paste")
			(net "P5E_CPU0_P2_TX_DP<9>")
		)
		(pad "BW31" smd circle
			(at -6.260084 12.510008 180)
			(size 0.450088 0.450088)
			(layers "F.Cu" "F.Mask" "F.Paste")
			(net "GND")
		)
		(pad "BW32" smd circle
			(at -5.32003 12.510008 180)
			(size 0.450088 0.450088)
			(layers "F.Cu" "F.Mask" "F.Paste")
			(net "P5E_CPU0_P2_TX_DN<6>")
		)
		(pad "BW33" smd circle
			(at -4.379976 12.510008 180)
			(size 0.450088 0.450088)
			(layers "F.Cu" "F.Mask" "F.Paste")
			(net "P5E_CPU0_P2_TX_DP<6>")
		)
		(pad "BW34" smd circle
			(at -3.439922 12.510008 180)
			(size 0.450088 0.450088)
			(layers "F.Cu" "F.Mask" "F.Paste")
			(net "GND")
		)
		(pad "BW35" smd circle
			(at -2.500122 12.510008 180)
			(size 0.450088 0.450088)
			(layers "F.Cu" "F.Mask" "F.Paste")
			(net "PVDDCR_CPU1_P0")
		)
		(pad "BW36" smd circle
			(at -1.560068 12.510008 180)
			(size 0.450088 0.450088)
			(layers "F.Cu" "F.Mask" "F.Paste")
			(net "PVDDCR_CPU1_P0")
		)
		(pad "BW40" smd circle
			(at 1.260094 12.510008 180)
			(size 0.450088 0.450088)
			(layers "F.Cu" "F.Mask" "F.Paste")
			(net "PVDDCR_CPU1_P0")
		)
		(pad "BW41" smd circle
			(at 2.199894 12.510008 180)
			(size 0.450088 0.450088)
			(layers "F.Cu" "F.Mask" "F.Paste")
			(net "PVDDCR_CPU1_P0")
		)
		(pad "BW42" smd circle
			(at 3.139948 12.510008 180)
			(size 0.450088 0.450088)
			(layers "F.Cu" "F.Mask" "F.Paste")
			(net "GND")
		)
		(pad "BW43" smd circle
			(at 4.080002 12.510008 180)
			(size 0.450088 0.450088)
			(layers "F.Cu" "F.Mask" "F.Paste")
			(net "P5E_CPU0_P0_RX_DP<9>")
		)
		(pad "BW44" smd circle
			(at 5.020056 12.510008 180)
			(size 0.450088 0.450088)
			(layers "F.Cu" "F.Mask" "F.Paste")
			(net "P5E_CPU0_P0_RX_DN<9>")
		)
		(pad "BW45" smd circle
			(at 5.96011 12.510008 180)
			(size 0.450088 0.450088)
			(layers "F.Cu" "F.Mask" "F.Paste")
			(net "GND")
		)
		(pad "BW46" smd circle
			(at 6.89991 12.510008 180)
			(size 0.450088 0.450088)
			(layers "F.Cu" "F.Mask" "F.Paste")
			(net "P5E_CPU0_P0_RX_DP<6>")
		)
		(pad "BW47" smd circle
			(at 7.839964 12.510008 180)
			(size 0.450088 0.450088)
			(layers "F.Cu" "F.Mask" "F.Paste")
			(net "P5E_CPU0_P0_RX_DN<6>")
		)
		(pad "BW48" smd circle
			(at 8.780018 12.510008 180)
			(size 0.450088 0.450088)
			(layers "F.Cu" "F.Mask" "F.Paste")
			(net "GND")
		)
		(pad "BW49" smd circle
			(at 9.720072 12.510008 180)
			(size 0.450088 0.450088)
			(layers "F.Cu" "F.Mask" "F.Paste")
			(net "P5E_CPU0_P0_RX_DP<3>")
		)
		(pad "BW50" smd circle
			(at 10.659872 12.510008 180)
			(size 0.450088 0.450088)
			(layers "F.Cu" "F.Mask" "F.Paste")
			(net "P5E_CPU0_P0_RX_DN<3>")
		)
		(pad "BW51" smd circle
			(at 11.599926 12.510008 180)
			(size 0.450088 0.450088)
			(layers "F.Cu" "F.Mask" "F.Paste")
			(net "GND")
		)
		(pad "BW52" smd circle
			(at 12.53998 12.510008 180)
			(size 0.450088 0.450088)
			(layers "F.Cu" "F.Mask" "F.Paste")
			(net "P5E_CPU0_P0_RX_DP<0>")
		)
		(pad "BW53" smd circle
			(at 13.480034 12.510008 180)
			(size 0.450088 0.450088)
			(layers "F.Cu" "F.Mask" "F.Paste")
			(net "P5E_CPU0_P0_RX_DN<0>")
		)
		(pad "BW54" smd circle
			(at 14.420088 12.510008 180)
			(size 0.450088 0.450088)
			(layers "F.Cu" "F.Mask" "F.Paste")
			(net "GND")
		)
		(pad "BW55" smd circle
			(at 15.359888 12.510008 180)
			(size 0.450088 0.450088)
			(layers "F.Cu" "F.Mask" "F.Paste")
			(net "M_C_CPU0_SB_DQS_DN<4>")
		)
		(pad "BW56" smd circle
			(at 16.299942 12.510008 180)
			(size 0.450088 0.450088)
			(layers "F.Cu" "F.Mask" "F.Paste")
			(net "GND")
		)
		(pad "BW57" smd circle
			(at 17.239996 12.510008 180)
			(size 0.450088 0.450088)
			(layers "F.Cu" "F.Mask" "F.Paste")
			(net "M_C_CPU0_SB_DQS_DN<9>")
		)
		(pad "BW58" smd circle
			(at 18.18005 12.510008 180)
			(size 0.450088 0.450088)
			(layers "F.Cu" "F.Mask" "F.Paste")
			(net "GND")
		)
		(pad "BW59" smd circle
			(at 19.120104 12.510008 180)
			(size 0.450088 0.450088)
			(layers "F.Cu" "F.Mask" "F.Paste")
			(net "M_D_CPU0_SB_DQS_DN<4>")
		)
		(pad "BW60" smd circle
			(at 20.059904 12.510008 180)
			(size 0.450088 0.450088)
			(layers "F.Cu" "F.Mask" "F.Paste")
			(net "M_D_CPU0_SB_DQS_DN<9>")
		)
		(pad "BW61" smd circle
			(at 20.999958 12.510008 180)
			(size 0.450088 0.450088)
			(layers "F.Cu" "F.Mask" "F.Paste")
			(net "GND")
		)
		(pad "BW62" smd circle
			(at 21.940012 12.510008 180)
			(size 0.450088 0.450088)
			(layers "F.Cu" "F.Mask" "F.Paste")
			(net "M_B_CPU0_SB_DQS_DN<4>")
		)
		(pad "BW63" smd circle
			(at 22.880066 12.510008 180)
			(size 0.450088 0.450088)
			(layers "F.Cu" "F.Mask" "F.Paste")
			(net "GND")
		)
		(pad "BW64" smd circle
			(at 23.82012 12.510008 180)
			(size 0.450088 0.450088)
			(layers "F.Cu" "F.Mask" "F.Paste")
			(net "M_B_CPU0_SB_DQS_DN<9>")
		)
		(pad "BW65" smd circle
			(at 24.75992 12.510008 180)
			(size 0.450088 0.450088)
			(layers "F.Cu" "F.Mask" "F.Paste")
			(net "GND")
		)
		(pad "BW66" smd circle
			(at 25.699974 12.510008 180)
			(size 0.450088 0.450088)
			(layers "F.Cu" "F.Mask" "F.Paste")
			(net "M_F_CPU0_SB_DQS_DN<4>")
		)
		(pad "BW67" smd circle
			(at 26.640028 12.510008 180)
			(size 0.450088 0.450088)
			(layers "F.Cu" "F.Mask" "F.Paste")
			(net "M_F_CPU0_SB_DQS_DN<9>")
		)
		(pad "BW68" smd circle
			(at 27.580082 12.510008 180)
			(size 0.450088 0.450088)
			(layers "F.Cu" "F.Mask" "F.Paste")
			(net "GND")
		)
		(pad "BW69" smd circle
			(at 28.519882 12.510008 180)
			(size 0.450088 0.450088)
			(layers "F.Cu" "F.Mask" "F.Paste")
			(net "M_E_CPU0_SB_DQS_DN<4>")
		)
		(pad "BW70" smd circle
			(at 29.459936 12.510008 180)
			(size 0.450088 0.450088)
			(layers "F.Cu" "F.Mask" "F.Paste")
			(net "GND")
		)
		(pad "BW71" smd circle
			(at 30.39999 12.510008 180)
			(size 0.450088 0.450088)
			(layers "F.Cu" "F.Mask" "F.Paste")
			(net "M_E_CPU0_SB_DQS_DN<9>")
		)
		(pad "BW72" smd circle
			(at 31.340044 12.510008 180)
			(size 0.450088 0.450088)
			(layers "F.Cu" "F.Mask" "F.Paste")
			(net "GND")
		)
		(pad "BW73" smd circle
			(at 32.280098 12.510008 180)
			(size 0.450088 0.450088)
			(layers "F.Cu" "F.Mask" "F.Paste")
			(net "M_A_CPU0_SB_DQS_DN<4>")
		)
		(pad "BW74" smd circle
			(at 33.219898 12.510008 180)
			(size 0.450088 0.450088)
			(layers "F.Cu" "F.Mask" "F.Paste")
			(net "M_A_CPU0_SB_DQS_DN<9>")
		)
		(pad "BW75" smd circle
			(at 34.159952 12.510008 180)
			(size 0.450088 0.450088)
			(layers "F.Cu" "F.Mask" "F.Paste")
			(net "GND")
		)
		(pad "BY2" smd circle
			(at -33.990026 13.320014 180)
			(size 0.450088 0.450088)
			(layers "F.Cu" "F.Mask" "F.Paste")
			(net "M_G_CPU0_SB_CB<0>")
		)
		(pad "BY3" smd circle
			(at -33.049972 13.320014 180)
			(size 0.450088 0.450088)
			(layers "F.Cu" "F.Mask" "F.Paste")
			(net "GND")
		)
		(pad "BY4" smd circle
			(at -32.109918 13.320014 180)
			(size 0.450088 0.450088)
			(layers "F.Cu" "F.Mask" "F.Paste")
			(net "M_G_CPU0_SB_DQS_DP<4>")
		)
		(pad "BY5" smd circle
			(at -31.170118 13.320014 180)
			(size 0.450088 0.450088)
			(layers "F.Cu" "F.Mask" "F.Paste")
			(net "GND")
		)
		(pad "BY6" smd circle
			(at -30.230064 13.320014 180)
			(size 0.450088 0.450088)
			(layers "F.Cu" "F.Mask" "F.Paste")
			(net "M_K_CPU0_SB_CB<0>")
		)
		(pad "BY7" smd circle
			(at -29.29001 13.320014 180)
			(size 0.450088 0.450088)
			(layers "F.Cu" "F.Mask" "F.Paste")
			(net "M_K_CPU0_SB_DQS_DP<4>")
		)
		(pad "BY8" smd circle
			(at -28.349956 13.320014 180)
			(size 0.450088 0.450088)
			(layers "F.Cu" "F.Mask" "F.Paste")
			(net "GND")
		)
		(pad "BY9" smd circle
			(at -27.409902 13.320014 180)
			(size 0.450088 0.450088)
			(layers "F.Cu" "F.Mask" "F.Paste")
			(net "M_L_CPU0_SB_CB<0>")
		)
		(pad "BY10" smd circle
			(at -26.470102 13.320014 180)
			(size 0.450088 0.450088)
			(layers "F.Cu" "F.Mask" "F.Paste")
			(net "GND")
		)
		(pad "BY11" smd circle
			(at -25.530048 13.320014 180)
			(size 0.450088 0.450088)
			(layers "F.Cu" "F.Mask" "F.Paste")
			(net "M_L_CPU0_SB_DQS_DP<4>")
		)
		(pad "BY12" smd circle
			(at -24.589994 13.320014 180)
			(size 0.450088 0.450088)
			(layers "F.Cu" "F.Mask" "F.Paste")
			(net "GND")
		)
		(pad "BY13" smd circle
			(at -23.64994 13.320014 180)
			(size 0.450088 0.450088)
			(layers "F.Cu" "F.Mask" "F.Paste")
			(net "M_H_CPU0_SB_CB<0>")
		)
		(pad "BY14" smd circle
			(at -22.709886 13.320014 180)
			(size 0.450088 0.450088)
			(layers "F.Cu" "F.Mask" "F.Paste")
			(net "M_H_CPU0_SB_DQS_DP<4>")
		)
		(pad "BY15" smd circle
			(at -21.770086 13.320014 180)
			(size 0.450088 0.450088)
			(layers "F.Cu" "F.Mask" "F.Paste")
			(net "GND")
		)
		(pad "BY16" smd circle
			(at -20.830032 13.320014 180)
			(size 0.450088 0.450088)
			(layers "F.Cu" "F.Mask" "F.Paste")
			(net "M_J_CPU0_SB_CB<0>")
		)
		(pad "BY17" smd circle
			(at -19.889978 13.320014 180)
			(size 0.450088 0.450088)
			(layers "F.Cu" "F.Mask" "F.Paste")
			(net "GND")
		)
		(pad "BY18" smd circle
			(at -18.949924 13.320014 180)
			(size 0.450088 0.450088)
			(layers "F.Cu" "F.Mask" "F.Paste")
			(net "M_J_CPU0_SB_DQS_DP<4>")
		)
		(pad "BY19" smd circle
			(at -18.010124 13.320014 180)
			(size 0.450088 0.450088)
			(layers "F.Cu" "F.Mask" "F.Paste")
			(net "GND")
		)
		(pad "BY20" smd circle
			(at -17.07007 13.320014 180)
			(size 0.450088 0.450088)
			(layers "F.Cu" "F.Mask" "F.Paste")
			(net "M_I_CPU0_SB_CB<0>")
		)
		(pad "BY21" smd circle
			(at -16.130016 13.320014 180)
			(size 0.450088 0.450088)
			(layers "F.Cu" "F.Mask" "F.Paste")
			(net "M_I_CPU0_SB_DQS_DP<4>")
		)
		(pad "BY22" smd circle
			(at -15.189962 13.320014 180)
			(size 0.450088 0.450088)
			(layers "F.Cu" "F.Mask" "F.Paste")
			(net "GND")
		)
		(pad "BY23" smd circle
			(at -14.249908 13.320014 180)
			(size 0.450088 0.450088)
			(layers "F.Cu" "F.Mask" "F.Paste")
			(net "PVDDCR_CPU1_P0")
		)
		(pad "BY24" smd circle
			(at -13.310108 13.320014 180)
			(size 0.450088 0.450088)
			(layers "F.Cu" "F.Mask" "F.Paste")
			(net "PVDDCR_CPU1_P0")
		)
		(pad "BY25" smd circle
			(at -12.370054 13.320014 180)
			(size 0.450088 0.450088)
			(layers "F.Cu" "F.Mask" "F.Paste")
			(net "GND")
		)
		(pad "BY26" smd circle
			(at -11.43 13.320014 180)
			(size 0.450088 0.450088)
			(layers "F.Cu" "F.Mask" "F.Paste")
			(net "PVDDCR_CPU1_P0")
		)
		(pad "BY27" smd circle
			(at -10.489946 13.320014 180)
			(size 0.450088 0.450088)
			(layers "F.Cu" "F.Mask" "F.Paste")
			(net "PVDDCR_CPU1_P0")
		)
		(pad "BY28" smd circle
			(at -9.549892 13.320014 180)
			(size 0.450088 0.450088)
			(layers "F.Cu" "F.Mask" "F.Paste")
			(net "GND")
		)
		(pad "BY29" smd circle
			(at -8.610092 13.320014 180)
			(size 0.450088 0.450088)
			(layers "F.Cu" "F.Mask" "F.Paste")
			(net "PVDDCR_CPU1_P0")
		)
		(pad "BY30" smd circle
			(at -7.670038 13.320014 180)
			(size 0.450088 0.450088)
			(layers "F.Cu" "F.Mask" "F.Paste")
			(net "PVDDCR_CPU1_P0")
		)
		(pad "BY31" smd circle
			(at -6.729984 13.320014 180)
			(size 0.450088 0.450088)
			(layers "F.Cu" "F.Mask" "F.Paste")
			(net "GND")
		)
		(pad "BY32" smd circle
			(at -5.78993 13.320014 180)
			(size 0.450088 0.450088)
			(layers "F.Cu" "F.Mask" "F.Paste")
			(net "PVDDCR_CPU1_P0")
		)
		(pad "BY33" smd circle
			(at -4.849876 13.320014 180)
			(size 0.450088 0.450088)
			(layers "F.Cu" "F.Mask" "F.Paste")
			(net "PVDDCR_CPU1_P0")
		)
		(pad "BY34" smd circle
			(at -3.910076 13.320014 180)
			(size 0.450088 0.450088)
			(layers "F.Cu" "F.Mask" "F.Paste")
			(net "GND")
		)
		(pad "BY35" smd circle
			(at -2.970022 13.320014 180)
			(size 0.450088 0.450088)
			(layers "F.Cu" "F.Mask" "F.Paste")
			(net "P5E_CPU0_P2_TX_DN<3>")
		)
		(pad "BY36" smd circle
			(at -2.029968 13.320014 180)
			(size 0.450088 0.450088)
			(layers "F.Cu" "F.Mask" "F.Paste")
			(net "P5E_CPU0_P2_TX_DP<3>")
		)
		(pad "BY37" smd circle
			(at -1.089914 13.320014 180)
			(size 0.450088 0.450088)
			(layers "F.Cu" "F.Mask" "F.Paste")
			(net "GND")
		)
		(pad "BY39" smd circle
			(at 0.78994 13.320014 180)
			(size 0.450088 0.450088)
			(layers "F.Cu" "F.Mask" "F.Paste")
			(net "GND")
		)
		(pad "BY40" smd circle
			(at 1.729994 13.320014 180)
			(size 0.450088 0.450088)
			(layers "F.Cu" "F.Mask" "F.Paste")
			(net "P5E_CPU0_P0_RX_DP<12>")
		)
		(pad "BY41" smd circle
			(at 2.670048 13.320014 180)
			(size 0.450088 0.450088)
			(layers "F.Cu" "F.Mask" "F.Paste")
			(net "P5E_CPU0_P0_RX_DN<12>")
		)
		(pad "BY42" smd circle
			(at 3.610102 13.320014 180)
			(size 0.450088 0.450088)
			(layers "F.Cu" "F.Mask" "F.Paste")
			(net "GND")
		)
		(pad "BY43" smd circle
			(at 4.549902 13.320014 180)
			(size 0.450088 0.450088)
			(layers "F.Cu" "F.Mask" "F.Paste")
			(net "PVDDCR_CPU1_P0")
		)
		(pad "BY44" smd circle
			(at 5.489956 13.320014 180)
			(size 0.450088 0.450088)
			(layers "F.Cu" "F.Mask" "F.Paste")
			(net "PVDDCR_CPU1_P0")
		)
		(pad "BY45" smd circle
			(at 6.43001 13.320014 180)
			(size 0.450088 0.450088)
			(layers "F.Cu" "F.Mask" "F.Paste")
			(net "GND")
		)
		(pad "BY46" smd circle
			(at 7.370064 13.320014 180)
			(size 0.450088 0.450088)
			(layers "F.Cu" "F.Mask" "F.Paste")
			(net "PVDDCR_CPU1_P0")
		)
		(pad "BY47" smd circle
			(at 8.310118 13.320014 180)
			(size 0.450088 0.450088)
			(layers "F.Cu" "F.Mask" "F.Paste")
			(net "PVDDCR_CPU1_P0")
		)
		(pad "BY48" smd circle
			(at 9.249918 13.320014 180)
			(size 0.450088 0.450088)
			(layers "F.Cu" "F.Mask" "F.Paste")
			(net "GND")
		)
		(pad "BY49" smd circle
			(at 10.189972 13.320014 180)
			(size 0.450088 0.450088)
			(layers "F.Cu" "F.Mask" "F.Paste")
			(net "PVDDCR_CPU1_P0")
		)
		(pad "BY50" smd circle
			(at 11.130026 13.320014 180)
			(size 0.450088 0.450088)
			(layers "F.Cu" "F.Mask" "F.Paste")
			(net "PVDDCR_CPU1_P0")
		)
		(pad "BY51" smd circle
			(at 12.07008 13.320014 180)
			(size 0.450088 0.450088)
			(layers "F.Cu" "F.Mask" "F.Paste")
			(net "GND")
		)
		(pad "BY52" smd circle
			(at 13.00988 13.320014 180)
			(size 0.450088 0.450088)
			(layers "F.Cu" "F.Mask" "F.Paste")
			(net "PVDDCR_CPU1_P0")
		)
		(pad "BY53" smd circle
			(at 13.949934 13.320014 180)
			(size 0.450088 0.450088)
			(layers "F.Cu" "F.Mask" "F.Paste")
			(net "PVDDCR_CPU1_P0")
		)
		(pad "BY54" smd circle
			(at 14.889988 13.320014 180)
			(size 0.450088 0.450088)
			(layers "F.Cu" "F.Mask" "F.Paste")
			(net "GND")
		)
		(pad "BY55" smd circle
			(at 15.830042 13.320014 180)
			(size 0.450088 0.450088)
			(layers "F.Cu" "F.Mask" "F.Paste")
			(net "M_C_CPU0_SB_DQS_DP<4>")
		)
		(pad "BY56" smd circle
			(at 16.770096 13.320014 180)
			(size 0.450088 0.450088)
			(layers "F.Cu" "F.Mask" "F.Paste")
			(net "M_C_CPU0_SB_CB<0>")
		)
		(pad "BY57" smd circle
			(at 17.709896 13.320014 180)
			(size 0.450088 0.450088)
			(layers "F.Cu" "F.Mask" "F.Paste")
			(net "GND")
		)
		(pad "BY58" smd circle
			(at 18.64995 13.320014 180)
			(size 0.450088 0.450088)
			(layers "F.Cu" "F.Mask" "F.Paste")
			(net "M_D_CPU0_SB_DQS_DP<4>")
		)
		(pad "BY59" smd circle
			(at 19.590004 13.320014 180)
			(size 0.450088 0.450088)
			(layers "F.Cu" "F.Mask" "F.Paste")
			(net "GND")
		)
		(pad "BY60" smd circle
			(at 20.530058 13.320014 180)
			(size 0.450088 0.450088)
			(layers "F.Cu" "F.Mask" "F.Paste")
			(net "M_D_CPU0_SB_CB<0>")
		)
		(pad "BY61" smd circle
			(at 21.470112 13.320014 180)
			(size 0.450088 0.450088)
			(layers "F.Cu" "F.Mask" "F.Paste")
			(net "GND")
		)
		(pad "BY62" smd circle
			(at 22.409912 13.320014 180)
			(size 0.450088 0.450088)
			(layers "F.Cu" "F.Mask" "F.Paste")
			(net "M_B_CPU0_SB_DQS_DP<4>")
		)
		(pad "BY63" smd circle
			(at 23.349966 13.320014 180)
			(size 0.450088 0.450088)
			(layers "F.Cu" "F.Mask" "F.Paste")
			(net "M_B_CPU0_SB_CB<0>")
		)
		(pad "BY64" smd circle
			(at 24.29002 13.320014 180)
			(size 0.450088 0.450088)
			(layers "F.Cu" "F.Mask" "F.Paste")
			(net "GND")
		)
		(pad "BY65" smd circle
			(at 25.230074 13.320014 180)
			(size 0.450088 0.450088)
			(layers "F.Cu" "F.Mask" "F.Paste")
			(net "M_F_CPU0_SB_DQS_DP<4>")
		)
		(pad "BY66" smd circle
			(at 26.170128 13.320014 180)
			(size 0.450088 0.450088)
			(layers "F.Cu" "F.Mask" "F.Paste")
			(net "GND")
		)
		(pad "BY67" smd circle
			(at 27.109928 13.320014 180)
			(size 0.450088 0.450088)
			(layers "F.Cu" "F.Mask" "F.Paste")
			(net "M_F_CPU0_SB_CB<0>")
		)
		(pad "BY68" smd circle
			(at 28.049982 13.320014 180)
			(size 0.450088 0.450088)
			(layers "F.Cu" "F.Mask" "F.Paste")
			(net "GND")
		)
		(pad "BY69" smd circle
			(at 28.990036 13.320014 180)
			(size 0.450088 0.450088)
			(layers "F.Cu" "F.Mask" "F.Paste")
			(net "M_E_CPU0_SB_DQS_DP<4>")
		)
		(pad "BY70" smd circle
			(at 29.93009 13.320014 180)
			(size 0.450088 0.450088)
			(layers "F.Cu" "F.Mask" "F.Paste")
			(net "M_E_CPU0_SB_CB<0>")
		)
		(pad "BY71" smd circle
			(at 30.86989 13.320014 180)
			(size 0.450088 0.450088)
			(layers "F.Cu" "F.Mask" "F.Paste")
			(net "GND")
		)
		(pad "BY72" smd circle
			(at 31.809944 13.320014 180)
			(size 0.450088 0.450088)
			(layers "F.Cu" "F.Mask" "F.Paste")
			(net "M_A_CPU0_SB_DQS_DP<4>")
		)
		(pad "BY73" smd circle
			(at 32.749998 13.320014 180)
			(size 0.450088 0.450088)
			(layers "F.Cu" "F.Mask" "F.Paste")
			(net "GND")
		)
		(pad "BY74" smd circle
			(at 33.690052 13.320014 180)
			(size 0.450088 0.450088)
			(layers "F.Cu" "F.Mask" "F.Paste")
			(net "M_A_CPU0_SB_CB<0>")
		)
		(pad "C1" smd circle
			(at -34.159952 -35.189922 180)
			(size 0.450088 0.450088)
			(layers "F.Cu" "F.Mask" "F.Paste")
			(net "GND")
		)
		(pad "C2" smd circle
			(at -33.219898 -35.189922 180)
			(size 0.450088 0.450088)
			(layers "F.Cu" "F.Mask" "F.Paste")
			(net "VSENSE_PVDDCR_CPU0_P0_DP")
		)
		(pad "C3" smd circle
			(at -32.280098 -35.189922 180)
			(size 0.450088 0.450088)
			(layers "F.Cu" "F.Mask" "F.Paste")
			(net "VSENSE_VSS_SENSE_A_P0")
		)
		(pad "C4" smd circle
			(at -31.340044 -35.189922 180)
			(size 0.450088 0.450088)
			(layers "F.Cu" "F.Mask" "F.Paste")
			(net "PVDDCR_SOC_P0")
		)
		(pad "C5" smd circle
			(at -30.39999 -35.189922 180)
			(size 0.450088 0.450088)
			(layers "F.Cu" "F.Mask" "F.Paste")
			(net "GND")
		)
		(pad "C6" smd circle
			(at -29.459936 -35.189922 180)
			(size 0.450088 0.450088)
			(layers "F.Cu" "F.Mask" "F.Paste")
			(net "CLK_100M_CPU0_CLK02_R_DN")
		)
		(pad "C7" smd circle
			(at -28.519882 -35.189922 180)
			(size 0.450088 0.450088)
			(layers "F.Cu" "F.Mask" "F.Paste")
			(net "I3C_1_SPD_DDRGL_CPU0_R_SCL")
		)
		(pad "C8" smd circle
			(at -27.580082 -35.189922 180)
			(size 0.450088 0.450088)
			(layers "F.Cu" "F.Mask" "F.Paste")
			(net "GND")
		)
		(pad "C9" smd circle
			(at -26.640028 -35.189922 180)
			(size 0.450088 0.450088)
			(layers "F.Cu" "F.Mask" "F.Paste")
			(net "CLK_100M_CPU0_CLK05_R_DN")
		)
		(pad "C10" smd circle
			(at -25.699974 -35.189922 180)
			(size 0.450088 0.450088)
			(layers "F.Cu" "F.Mask" "F.Paste")
			(net "GND")
		)
		(pad "C11" smd circle
			(at -24.75992 -35.189922 180)
			(size 0.450088 0.450088)
			(layers "F.Cu" "F.Mask" "F.Paste")
			(net "GND")
		)
		(pad "C12" smd circle
			(at -23.82012 -35.189922 180)
			(size 0.450088 0.450088)
			(layers "F.Cu" "F.Mask" "F.Paste")
			(net "CLK_100M_CPU0_CLK04_R_DN")
		)
		(pad "C13" smd circle
			(at -22.880066 -35.189922 180)
			(size 0.450088 0.450088)
			(layers "F.Cu" "F.Mask" "F.Paste")
			(net "GND")
		)
		(pad "C14" smd circle
			(at -21.940012 -35.189922 180)
			(size 0.450088 0.450088)
			(layers "F.Cu" "F.Mask" "F.Paste")
			(net "FAB_REV_ID1")
		)
		(pad "C15" smd circle
			(at -20.999958 -35.189922 180)
			(size 0.450088 0.450088)
			(layers "F.Cu" "F.Mask" "F.Paste")
			(net "GND")
		)
		(pad "C16" smd circle
			(at -20.059904 -35.189922 180)
			(size 0.450088 0.450088)
			(layers "F.Cu" "F.Mask" "F.Paste")
			(net "JTAG_CPU0_DBREQ_N")
		)
		(pad "C17" smd circle
			(at -19.120104 -35.189922 180)
			(size 0.450088 0.450088)
			(layers "F.Cu" "F.Mask" "F.Paste")
			(net "JTAG_CPU0_TDI")
		)
		(pad "C18" smd circle
			(at -18.18005 -35.189922 180)
			(size 0.450088 0.450088)
			(layers "F.Cu" "F.Mask" "F.Paste")
			(net "JTAG_CPU0_R_TDO")
		)
		(pad "C19" smd circle
			(at -17.239996 -35.189922 180)
			(size 0.450088 0.450088)
			(layers "F.Cu" "F.Mask" "F.Paste")
			(net "CPU0_SP5R1")
		)
		(pad "C20" smd circle
			(at -16.299942 -35.189922 180)
			(size 0.450088 0.450088)
			(layers "F.Cu" "F.Mask" "F.Paste")
			(net "PVDDCR_CPU0_P0")
		)
		(pad "C21" smd circle
			(at -15.359888 -35.189922 180)
			(size 0.450088 0.450088)
			(layers "F.Cu" "F.Mask" "F.Paste")
			(net "GND")
		)
		(pad "C22" smd circle
			(at -14.420088 -35.189922 180)
			(size 0.450088 0.450088)
			(layers "F.Cu" "F.Mask" "F.Paste")
			(net "FM_P0_PCC0_N")
		)
		(pad "C23" smd circle
			(at -13.480034 -35.189922 180)
			(size 0.450088 0.450088)
			(layers "F.Cu" "F.Mask" "F.Paste")
			(net "Net_1949")
		)
		(pad "C24" smd circle
			(at -12.53998 -35.189922 180)
			(size 0.450088 0.450088)
			(layers "F.Cu" "F.Mask" "F.Paste")
			(net "GND")
		)
		(pad "C25" smd circle
			(at -11.599926 -35.189922 180)
			(size 0.450088 0.450088)
			(layers "F.Cu" "F.Mask" "F.Paste")
			(net "USB3_CPU0_BMC_TX_DP")
		)
		(pad "C26" smd circle
			(at -10.659872 -35.189922 180)
			(size 0.450088 0.450088)
			(layers "F.Cu" "F.Mask" "F.Paste")
			(net "USB3_CPU0_BMC_TX_DN")
		)
		(pad "C27" smd circle
			(at -9.720072 -35.189922 180)
			(size 0.450088 0.450088)
			(layers "F.Cu" "F.Mask" "F.Paste")
			(net "GND")
		)
		(pad "C28" smd circle
			(at -8.780018 -35.189922 180)
			(size 0.450088 0.450088)
			(layers "F.Cu" "F.Mask" "F.Paste")
			(net "Net_1884")
		)
		(pad "C29" smd circle
			(at -7.839964 -35.189922 180)
			(size 0.450088 0.450088)
			(layers "F.Cu" "F.Mask" "F.Paste")
			(net "Net_1885")
		)
		(pad "C30" smd circle
			(at -6.89991 -35.189922 180)
			(size 0.450088 0.450088)
			(layers "F.Cu" "F.Mask" "F.Paste")
			(net "GND")
		)
		(pad "C31" smd circle
			(at -5.96011 -35.189922 180)
			(size 0.450088 0.450088)
			(layers "F.Cu" "F.Mask" "F.Paste")
			(net "Net_1925")
		)
		(pad "C32" smd circle
			(at -5.020056 -35.189922 180)
			(size 0.450088 0.450088)
			(layers "F.Cu" "F.Mask" "F.Paste")
			(net "NC_CPU0_AZ_BITCLK")
		)
		(pad "C33" smd circle
			(at -4.080002 -35.189922 180)
			(size 0.450088 0.450088)
			(layers "F.Cu" "F.Mask" "F.Paste")
			(net "NC_CPU0_AZ_SDIN0")
		)
		(pad "C34" smd circle
			(at -3.139948 -35.189922 180)
			(size 0.450088 0.450088)
			(layers "F.Cu" "F.Mask" "F.Paste")
			(net "Net_1926")
		)
		(pad "C35" smd circle
			(at -2.199894 -35.189922 180)
			(size 0.450088 0.450088)
			(layers "F.Cu" "F.Mask" "F.Paste")
			(net "Net_1927")
		)
		(pad "C36" smd circle
			(at -1.260094 -35.189922 180)
			(size 0.450088 0.450088)
			(layers "F.Cu" "F.Mask" "F.Paste")
			(net "GND")
		)
		(pad "C40" smd circle
			(at 1.560068 -35.189922 180)
			(size 0.450088 0.450088)
			(layers "F.Cu" "F.Mask" "F.Paste")
			(net "GND")
		)
		(pad "C41" smd circle
			(at 2.500122 -35.189922 180)
			(size 0.450088 0.450088)
			(layers "F.Cu" "F.Mask" "F.Paste")
			(net "Net_1870")
		)
		(pad "C42" smd circle
			(at 3.439922 -35.189922 180)
			(size 0.450088 0.450088)
			(layers "F.Cu" "F.Mask" "F.Paste")
			(net "Net_1869")
		)
		(pad "C43" smd circle
			(at 4.379976 -35.189922 180)
			(size 0.450088 0.450088)
			(layers "F.Cu" "F.Mask" "F.Paste")
			(net "GND")
		)
		(pad "C44" smd circle
			(at 5.32003 -35.189922 180)
			(size 0.450088 0.450088)
			(layers "F.Cu" "F.Mask" "F.Paste")
			(net "P2E_CPU0_P5_TX_DP")
		)
		(pad "C45" smd circle
			(at 6.260084 -35.189922 180)
			(size 0.450088 0.450088)
			(layers "F.Cu" "F.Mask" "F.Paste")
			(net "P2E_CPU0_P5_TX_DN")
		)
		(pad "C46" smd circle
			(at 7.199884 -35.189922 180)
			(size 0.450088 0.450088)
			(layers "F.Cu" "F.Mask" "F.Paste")
			(net "GND")
		)
		(pad "C47" smd circle
			(at 8.139938 -35.189922 180)
			(size 0.450088 0.450088)
			(layers "F.Cu" "F.Mask" "F.Paste")
			(net "Net_1874")
		)
		(pad "C48" smd circle
			(at 9.079992 -35.189922 180)
			(size 0.450088 0.450088)
			(layers "F.Cu" "F.Mask" "F.Paste")
			(net "Net_1873")
		)
		(pad "C49" smd circle
			(at 10.020046 -35.189922 180)
			(size 0.450088 0.450088)
			(layers "F.Cu" "F.Mask" "F.Paste")
			(net "GND")
		)
		(pad "C50" smd circle
			(at 10.9601 -35.189922 180)
			(size 0.450088 0.450088)
			(layers "F.Cu" "F.Mask" "F.Paste")
			(net "WAFL_CPU0_TX0_CPU1_RX1_DP")
		)
		(pad "C51" smd circle
			(at 11.8999 -35.189922 180)
			(size 0.450088 0.450088)
			(layers "F.Cu" "F.Mask" "F.Paste")
			(net "WAFL_CPU0_TX0_CPU1_RX1_DN")
		)
		(pad "C52" smd circle
			(at 12.839954 -35.189922 180)
			(size 0.450088 0.450088)
			(layers "F.Cu" "F.Mask" "F.Paste")
			(net "GND")
		)
		(pad "C53" smd circle
			(at 13.780008 -35.189922 180)
			(size 0.450088 0.450088)
			(layers "F.Cu" "F.Mask" "F.Paste")
			(net "Net_1928")
		)
		(pad "C54" smd circle
			(at 14.720062 -35.189922 180)
			(size 0.450088 0.450088)
			(layers "F.Cu" "F.Mask" "F.Paste")
			(net "Net_1929")
		)
		(pad "C55" smd circle
			(at 15.660116 -35.189922 180)
			(size 0.450088 0.450088)
			(layers "F.Cu" "F.Mask" "F.Paste")
			(net "GND")
		)
		(pad "C56" smd circle
			(at 16.599916 -35.189922 180)
			(size 0.450088 0.450088)
			(layers "F.Cu" "F.Mask" "F.Paste")
			(net "GND")
		)
		(pad "C57" smd circle
			(at 17.53997 -35.189922 180)
			(size 0.450088 0.450088)
			(layers "F.Cu" "F.Mask" "F.Paste")
			(net "GND")
		)
		(pad "C58" smd circle
			(at 18.480024 -35.189922 180)
			(size 0.450088 0.450088)
			(layers "F.Cu" "F.Mask" "F.Paste")
			(net "Net_1946")
		)
		(pad "C59" smd circle
			(at 19.420078 -35.189922 180)
			(size 0.450088 0.450088)
			(layers "F.Cu" "F.Mask" "F.Paste")
			(net "Net_1950")
		)
		(pad "C60" smd circle
			(at 20.359878 -35.189922 180)
			(size 0.450088 0.450088)
			(layers "F.Cu" "F.Mask" "F.Paste")
			(net "TP_M_A_CPU0_SA_TEST40")
		)
		(pad "C61" smd circle
			(at 21.299932 -35.189922 180)
			(size 0.450088 0.450088)
			(layers "F.Cu" "F.Mask" "F.Paste")
			(net "GND")
		)
		(pad "C62" smd circle
			(at 22.239986 -35.189922 180)
			(size 0.450088 0.450088)
			(layers "F.Cu" "F.Mask" "F.Paste")
			(net "CPU0_BP1")
		)
		(pad "C63" smd circle
			(at 23.18004 -35.189922 180)
			(size 0.450088 0.450088)
			(layers "F.Cu" "F.Mask" "F.Paste")
			(net "CPU0_BP0")
		)
		(pad "C64" smd circle
			(at 24.120094 -35.189922 180)
			(size 0.450088 0.450088)
			(layers "F.Cu" "F.Mask" "F.Paste")
			(net "GND")
		)
		(pad "C65" smd circle
			(at 25.059894 -35.189922 180)
			(size 0.450088 0.450088)
			(layers "F.Cu" "F.Mask" "F.Paste")
			(net "CPU0_XTRIG_R2_L5")
		)
		(pad "C66" smd circle
			(at 25.999948 -35.189922 180)
			(size 0.450088 0.450088)
			(layers "F.Cu" "F.Mask" "F.Paste")
			(net "CPU0_XTRIG_R2_L4")
		)
		(pad "C67" smd circle
			(at 26.940002 -35.189922 180)
			(size 0.450088 0.450088)
			(layers "F.Cu" "F.Mask" "F.Paste")
			(net "GND")
		)
		(pad "C68" smd circle
			(at 27.880056 -35.189922 180)
			(size 0.450088 0.450088)
			(layers "F.Cu" "F.Mask" "F.Paste")
			(net "CPU0_SP5R2")
		)
		(pad "C69" smd circle
			(at 28.82011 -35.189922 180)
			(size 0.450088 0.450088)
			(layers "F.Cu" "F.Mask" "F.Paste")
			(net "GND")
		)
		(pad "C70" smd circle
			(at 29.75991 -35.189922 180)
			(size 0.450088 0.450088)
			(layers "F.Cu" "F.Mask" "F.Paste")
			(net "CPU0_CORETYPE0")
		)
		(pad "C71" smd circle
			(at 30.699964 -35.189922 180)
			(size 0.450088 0.450088)
			(layers "F.Cu" "F.Mask" "F.Paste")
			(net "GND")
		)
		(pad "C72" smd circle
			(at 31.640018 -35.189922 180)
			(size 0.450088 0.450088)
			(layers "F.Cu" "F.Mask" "F.Paste")
			(net "SMB_CPU0_2_R_SCL")
		)
		(pad "C73" smd circle
			(at 32.580072 -35.189922 180)
			(size 0.450088 0.450088)
			(layers "F.Cu" "F.Mask" "F.Paste")
			(net "GND")
		)
		(pad "C74" smd circle
			(at 33.519872 -35.189922 180)
			(size 0.450088 0.450088)
			(layers "F.Cu" "F.Mask" "F.Paste")
			(net "VSENSE_PVDD18_S5_P0_DP")
		)
		(pad "C75" smd circle
			(at 34.459926 -35.189922 180)
			(size 0.450088 0.450088)
			(layers "F.Cu" "F.Mask" "F.Paste")
			(net "GND")
		)
		(pad "CA1" smd circle
			(at -34.459926 14.13002 180)
			(size 0.450088 0.450088)
			(layers "F.Cu" "F.Mask" "F.Paste")
			(net "GND")
		)
		(pad "CA2" smd circle
			(at -33.519872 14.13002 180)
			(size 0.450088 0.450088)
			(layers "F.Cu" "F.Mask" "F.Paste")
			(net "M_G_CPU0_SB_CB<2>")
		)
		(pad "CA3" smd circle
			(at -32.580072 14.13002 180)
			(size 0.450088 0.450088)
			(layers "F.Cu" "F.Mask" "F.Paste")
			(net "M_G_CPU0_SB_CB<1>")
		)
		(pad "CA4" smd circle
			(at -31.640018 14.13002 180)
			(size 0.450088 0.450088)
			(layers "F.Cu" "F.Mask" "F.Paste")
			(net "PVDD11_S3_P0")
		)
		(pad "CA5" smd circle
			(at -30.699964 14.13002 180)
			(size 0.450088 0.450088)
			(layers "F.Cu" "F.Mask" "F.Paste")
			(net "M_K_CPU0_SB_CB<2>")
		)
		(pad "CA6" smd circle
			(at -29.75991 14.13002 180)
			(size 0.450088 0.450088)
			(layers "F.Cu" "F.Mask" "F.Paste")
			(net "GND")
		)
		(pad "CA7" smd circle
			(at -28.82011 14.13002 180)
			(size 0.450088 0.450088)
			(layers "F.Cu" "F.Mask" "F.Paste")
			(net "M_K_CPU0_SB_CB<1>")
		)
		(pad "CA8" smd circle
			(at -27.880056 14.13002 180)
			(size 0.450088 0.450088)
			(layers "F.Cu" "F.Mask" "F.Paste")
			(net "GND")
		)
		(pad "CA9" smd circle
			(at -26.940002 14.13002 180)
			(size 0.450088 0.450088)
			(layers "F.Cu" "F.Mask" "F.Paste")
			(net "M_L_CPU0_SB_CB<2>")
		)
		(pad "CA10" smd circle
			(at -25.999948 14.13002 180)
			(size 0.450088 0.450088)
			(layers "F.Cu" "F.Mask" "F.Paste")
			(net "M_L_CPU0_SB_CB<1>")
		)
		(pad "CA11" smd circle
			(at -25.059894 14.13002 180)
			(size 0.450088 0.450088)
			(layers "F.Cu" "F.Mask" "F.Paste")
			(net "PVDD11_S3_P0")
		)
		(pad "CA12" smd circle
			(at -24.120094 14.13002 180)
			(size 0.450088 0.450088)
			(layers "F.Cu" "F.Mask" "F.Paste")
			(net "M_H_CPU0_SB_CB<2>")
		)
		(pad "CA13" smd circle
			(at -23.18004 14.13002 180)
			(size 0.450088 0.450088)
			(layers "F.Cu" "F.Mask" "F.Paste")
			(net "GND")
		)
		(pad "CA14" smd circle
			(at -22.239986 14.13002 180)
			(size 0.450088 0.450088)
			(layers "F.Cu" "F.Mask" "F.Paste")
			(net "M_H_CPU0_SB_CB<1>")
		)
		(pad "CA15" smd circle
			(at -21.299932 14.13002 180)
			(size 0.450088 0.450088)
			(layers "F.Cu" "F.Mask" "F.Paste")
			(net "GND")
		)
		(pad "CA16" smd circle
			(at -20.359878 14.13002 180)
			(size 0.450088 0.450088)
			(layers "F.Cu" "F.Mask" "F.Paste")
			(net "M_J_CPU0_SB_CB<2>")
		)
		(pad "CA17" smd circle
			(at -19.420078 14.13002 180)
			(size 0.450088 0.450088)
			(layers "F.Cu" "F.Mask" "F.Paste")
			(net "M_J_CPU0_SB_CB<1>")
		)
		(pad "CA18" smd circle
			(at -18.480024 14.13002 180)
			(size 0.450088 0.450088)
			(layers "F.Cu" "F.Mask" "F.Paste")
			(net "PVDD11_S3_P0")
		)
		(pad "CA19" smd circle
			(at -17.53997 14.13002 180)
			(size 0.450088 0.450088)
			(layers "F.Cu" "F.Mask" "F.Paste")
			(net "M_I_CPU0_SB_CB<2>")
		)
		(pad "CA20" smd circle
			(at -16.599916 14.13002 180)
			(size 0.450088 0.450088)
			(layers "F.Cu" "F.Mask" "F.Paste")
			(net "GND")
		)
		(pad "CA21" smd circle
			(at -15.660116 14.13002 180)
			(size 0.450088 0.450088)
			(layers "F.Cu" "F.Mask" "F.Paste")
			(net "M_I_CPU0_SB_CB<1>")
		)
		(pad "CA22" smd circle
			(at -14.720062 14.13002 180)
			(size 0.450088 0.450088)
			(layers "F.Cu" "F.Mask" "F.Paste")
			(net "GND")
		)
		(pad "CA23" smd circle
			(at -13.780008 14.13002 180)
			(size 0.450088 0.450088)
			(layers "F.Cu" "F.Mask" "F.Paste")
			(net "P5E_CPU0_P2_TX_DN<14>")
		)
		(pad "CA24" smd circle
			(at -12.839954 14.13002 180)
			(size 0.450088 0.450088)
			(layers "F.Cu" "F.Mask" "F.Paste")
			(net "P5E_CPU0_P2_TX_DP<14>")
		)
		(pad "CA25" smd circle
			(at -11.8999 14.13002 180)
			(size 0.450088 0.450088)
			(layers "F.Cu" "F.Mask" "F.Paste")
			(net "GND")
		)
		(pad "CA26" smd circle
			(at -10.9601 14.13002 180)
			(size 0.450088 0.450088)
			(layers "F.Cu" "F.Mask" "F.Paste")
			(net "P5E_CPU0_P2_TX_DN<11>")
		)
		(pad "CA27" smd circle
			(at -10.020046 14.13002 180)
			(size 0.450088 0.450088)
			(layers "F.Cu" "F.Mask" "F.Paste")
			(net "P5E_CPU0_P2_TX_DP<11>")
		)
		(pad "CA28" smd circle
			(at -9.079992 14.13002 180)
			(size 0.450088 0.450088)
			(layers "F.Cu" "F.Mask" "F.Paste")
			(net "GND")
		)
		(pad "CA29" smd circle
			(at -8.139938 14.13002 180)
			(size 0.450088 0.450088)
			(layers "F.Cu" "F.Mask" "F.Paste")
			(net "P5E_CPU0_P2_TX_DN<8>")
		)
		(pad "CA30" smd circle
			(at -7.199884 14.13002 180)
			(size 0.450088 0.450088)
			(layers "F.Cu" "F.Mask" "F.Paste")
			(net "P5E_CPU0_P2_TX_DP<8>")
		)
		(pad "CA31" smd circle
			(at -6.260084 14.13002 180)
			(size 0.450088 0.450088)
			(layers "F.Cu" "F.Mask" "F.Paste")
			(net "GND")
		)
		(pad "CA32" smd circle
			(at -5.32003 14.13002 180)
			(size 0.450088 0.450088)
			(layers "F.Cu" "F.Mask" "F.Paste")
			(net "P5E_CPU0_P2_TX_DN<5>")
		)
		(pad "CA33" smd circle
			(at -4.379976 14.13002 180)
			(size 0.450088 0.450088)
			(layers "F.Cu" "F.Mask" "F.Paste")
			(net "P5E_CPU0_P2_TX_DP<5>")
		)
		(pad "CA34" smd circle
			(at -3.439922 14.13002 180)
			(size 0.450088 0.450088)
			(layers "F.Cu" "F.Mask" "F.Paste")
			(net "GND")
		)
		(pad "CA35" smd circle
			(at -2.500122 14.13002 180)
			(size 0.450088 0.450088)
			(layers "F.Cu" "F.Mask" "F.Paste")
			(net "GND")
		)
		(pad "CA36" smd circle
			(at -1.560068 14.13002 180)
			(size 0.450088 0.450088)
			(layers "F.Cu" "F.Mask" "F.Paste")
			(net "GND")
		)
		(pad "CA40" smd circle
			(at 1.260094 14.13002 180)
			(size 0.450088 0.450088)
			(layers "F.Cu" "F.Mask" "F.Paste")
			(net "GND")
		)
		(pad "CA41" smd circle
			(at 2.199894 14.13002 180)
			(size 0.450088 0.450088)
			(layers "F.Cu" "F.Mask" "F.Paste")
			(net "GND")
		)
		(pad "CA42" smd circle
			(at 3.139948 14.13002 180)
			(size 0.450088 0.450088)
			(layers "F.Cu" "F.Mask" "F.Paste")
			(net "GND")
		)
		(pad "CA43" smd circle
			(at 4.080002 14.13002 180)
			(size 0.450088 0.450088)
			(layers "F.Cu" "F.Mask" "F.Paste")
			(net "P5E_CPU0_P0_RX_DP<10>")
		)
		(pad "CA44" smd circle
			(at 5.020056 14.13002 180)
			(size 0.450088 0.450088)
			(layers "F.Cu" "F.Mask" "F.Paste")
			(net "P5E_CPU0_P0_RX_DN<10>")
		)
		(pad "CA45" smd circle
			(at 5.96011 14.13002 180)
			(size 0.450088 0.450088)
			(layers "F.Cu" "F.Mask" "F.Paste")
			(net "GND")
		)
		(pad "CA46" smd circle
			(at 6.89991 14.13002 180)
			(size 0.450088 0.450088)
			(layers "F.Cu" "F.Mask" "F.Paste")
			(net "P5E_CPU0_P0_RX_DP<7>")
		)
		(pad "CA47" smd circle
			(at 7.839964 14.13002 180)
			(size 0.450088 0.450088)
			(layers "F.Cu" "F.Mask" "F.Paste")
			(net "P5E_CPU0_P0_RX_DN<7>")
		)
		(pad "CA48" smd circle
			(at 8.780018 14.13002 180)
			(size 0.450088 0.450088)
			(layers "F.Cu" "F.Mask" "F.Paste")
			(net "GND")
		)
		(pad "CA49" smd circle
			(at 9.720072 14.13002 180)
			(size 0.450088 0.450088)
			(layers "F.Cu" "F.Mask" "F.Paste")
			(net "P5E_CPU0_P0_RX_DP<4>")
		)
		(pad "CA50" smd circle
			(at 10.659872 14.13002 180)
			(size 0.450088 0.450088)
			(layers "F.Cu" "F.Mask" "F.Paste")
			(net "P5E_CPU0_P0_RX_DN<4>")
		)
		(pad "CA51" smd circle
			(at 11.599926 14.13002 180)
			(size 0.450088 0.450088)
			(layers "F.Cu" "F.Mask" "F.Paste")
			(net "GND")
		)
		(pad "CA52" smd circle
			(at 12.53998 14.13002 180)
			(size 0.450088 0.450088)
			(layers "F.Cu" "F.Mask" "F.Paste")
			(net "P5E_CPU0_P0_RX_DP<1>")
		)
		(pad "CA53" smd circle
			(at 13.480034 14.13002 180)
			(size 0.450088 0.450088)
			(layers "F.Cu" "F.Mask" "F.Paste")
			(net "P5E_CPU0_P0_RX_DN<1>")
		)
		(pad "CA54" smd circle
			(at 14.420088 14.13002 180)
			(size 0.450088 0.450088)
			(layers "F.Cu" "F.Mask" "F.Paste")
			(net "GND")
		)
		(pad "CA55" smd circle
			(at 15.359888 14.13002 180)
			(size 0.450088 0.450088)
			(layers "F.Cu" "F.Mask" "F.Paste")
			(net "M_C_CPU0_SB_CB<1>")
		)
		(pad "CA56" smd circle
			(at 16.299942 14.13002 180)
			(size 0.450088 0.450088)
			(layers "F.Cu" "F.Mask" "F.Paste")
			(net "GND")
		)
		(pad "CA57" smd circle
			(at 17.239996 14.13002 180)
			(size 0.450088 0.450088)
			(layers "F.Cu" "F.Mask" "F.Paste")
			(net "M_C_CPU0_SB_CB<2>")
		)
		(pad "CA58" smd circle
			(at 18.18005 14.13002 180)
			(size 0.450088 0.450088)
			(layers "F.Cu" "F.Mask" "F.Paste")
			(net "PVDDIO_P0")
		)
		(pad "CA59" smd circle
			(at 19.120104 14.13002 180)
			(size 0.450088 0.450088)
			(layers "F.Cu" "F.Mask" "F.Paste")
			(net "M_D_CPU0_SB_CB<1>")
		)
		(pad "CA60" smd circle
			(at 20.059904 14.13002 180)
			(size 0.450088 0.450088)
			(layers "F.Cu" "F.Mask" "F.Paste")
			(net "M_D_CPU0_SB_CB<2>")
		)
		(pad "CA61" smd circle
			(at 20.999958 14.13002 180)
			(size 0.450088 0.450088)
			(layers "F.Cu" "F.Mask" "F.Paste")
			(net "GND")
		)
		(pad "CA62" smd circle
			(at 21.940012 14.13002 180)
			(size 0.450088 0.450088)
			(layers "F.Cu" "F.Mask" "F.Paste")
			(net "M_B_CPU0_SB_CB<1>")
		)
		(pad "CA63" smd circle
			(at 22.880066 14.13002 180)
			(size 0.450088 0.450088)
			(layers "F.Cu" "F.Mask" "F.Paste")
			(net "GND")
		)
		(pad "CA64" smd circle
			(at 23.82012 14.13002 180)
			(size 0.450088 0.450088)
			(layers "F.Cu" "F.Mask" "F.Paste")
			(net "M_B_CPU0_SB_CB<2>")
		)
		(pad "CA65" smd circle
			(at 24.75992 14.13002 180)
			(size 0.450088 0.450088)
			(layers "F.Cu" "F.Mask" "F.Paste")
			(net "PVDDIO_P0")
		)
		(pad "CA66" smd circle
			(at 25.699974 14.13002 180)
			(size 0.450088 0.450088)
			(layers "F.Cu" "F.Mask" "F.Paste")
			(net "M_F_CPU0_SB_CB<1>")
		)
		(pad "CA67" smd circle
			(at 26.640028 14.13002 180)
			(size 0.450088 0.450088)
			(layers "F.Cu" "F.Mask" "F.Paste")
			(net "M_F_CPU0_SB_CB<2>")
		)
		(pad "CA68" smd circle
			(at 27.580082 14.13002 180)
			(size 0.450088 0.450088)
			(layers "F.Cu" "F.Mask" "F.Paste")
			(net "GND")
		)
		(pad "CA69" smd circle
			(at 28.519882 14.13002 180)
			(size 0.450088 0.450088)
			(layers "F.Cu" "F.Mask" "F.Paste")
			(net "M_E_CPU0_SB_CB<1>")
		)
		(pad "CA70" smd circle
			(at 29.459936 14.13002 180)
			(size 0.450088 0.450088)
			(layers "F.Cu" "F.Mask" "F.Paste")
			(net "GND")
		)
		(pad "CA71" smd circle
			(at 30.39999 14.13002 180)
			(size 0.450088 0.450088)
			(layers "F.Cu" "F.Mask" "F.Paste")
			(net "M_E_CPU0_SB_CB<2>")
		)
		(pad "CA72" smd circle
			(at 31.340044 14.13002 180)
			(size 0.450088 0.450088)
			(layers "F.Cu" "F.Mask" "F.Paste")
			(net "PVDDIO_P0")
		)
		(pad "CA73" smd circle
			(at 32.280098 14.13002 180)
			(size 0.450088 0.450088)
			(layers "F.Cu" "F.Mask" "F.Paste")
			(net "M_A_CPU0_SB_CB<1>")
		)
		(pad "CA74" smd circle
			(at 33.219898 14.13002 180)
			(size 0.450088 0.450088)
			(layers "F.Cu" "F.Mask" "F.Paste")
			(net "M_A_CPU0_SB_CB<2>")
		)
		(pad "CA75" smd circle
			(at 34.159952 14.13002 180)
			(size 0.450088 0.450088)
			(layers "F.Cu" "F.Mask" "F.Paste")
			(net "GND")
		)
		(pad "CB2" smd circle
			(at -33.990026 14.940026 180)
			(size 0.450088 0.450088)
			(layers "F.Cu" "F.Mask" "F.Paste")
			(net "M_G_CPU0_SB_DQ<0>")
		)
		(pad "CB3" smd circle
			(at -33.049972 14.940026 180)
			(size 0.450088 0.450088)
			(layers "F.Cu" "F.Mask" "F.Paste")
			(net "GND")
		)
		(pad "CB4" smd circle
			(at -32.109918 14.940026 180)
			(size 0.450088 0.450088)
			(layers "F.Cu" "F.Mask" "F.Paste")
			(net "M_G_CPU0_SB_CB<3>")
		)
		(pad "CB5" smd circle
			(at -31.170118 14.940026 180)
			(size 0.450088 0.450088)
			(layers "F.Cu" "F.Mask" "F.Paste")
			(net "GND")
		)
		(pad "CB6" smd circle
			(at -30.230064 14.940026 180)
			(size 0.450088 0.450088)
			(layers "F.Cu" "F.Mask" "F.Paste")
			(net "M_K_CPU0_SB_DQ<0>")
		)
		(pad "CB7" smd circle
			(at -29.29001 14.940026 180)
			(size 0.450088 0.450088)
			(layers "F.Cu" "F.Mask" "F.Paste")
			(net "M_K_CPU0_SB_CB<3>")
		)
		(pad "CB8" smd circle
			(at -28.349956 14.940026 180)
			(size 0.450088 0.450088)
			(layers "F.Cu" "F.Mask" "F.Paste")
			(net "GND")
		)
		(pad "CB9" smd circle
			(at -27.409902 14.940026 180)
			(size 0.450088 0.450088)
			(layers "F.Cu" "F.Mask" "F.Paste")
			(net "M_L_CPU0_SB_DQ<0>")
		)
		(pad "CB10" smd circle
			(at -26.470102 14.940026 180)
			(size 0.450088 0.450088)
			(layers "F.Cu" "F.Mask" "F.Paste")
			(net "GND")
		)
		(pad "CB11" smd circle
			(at -25.530048 14.940026 180)
			(size 0.450088 0.450088)
			(layers "F.Cu" "F.Mask" "F.Paste")
			(net "M_L_CPU0_SB_CB<3>")
		)
		(pad "CB12" smd circle
			(at -24.589994 14.940026 180)
			(size 0.450088 0.450088)
			(layers "F.Cu" "F.Mask" "F.Paste")
			(net "GND")
		)
		(pad "CB13" smd circle
			(at -23.64994 14.940026 180)
			(size 0.450088 0.450088)
			(layers "F.Cu" "F.Mask" "F.Paste")
			(net "M_H_CPU0_SB_DQ<0>")
		)
		(pad "CB14" smd circle
			(at -22.709886 14.940026 180)
			(size 0.450088 0.450088)
			(layers "F.Cu" "F.Mask" "F.Paste")
			(net "M_H_CPU0_SB_CB<3>")
		)
		(pad "CB15" smd circle
			(at -21.770086 14.940026 180)
			(size 0.450088 0.450088)
			(layers "F.Cu" "F.Mask" "F.Paste")
			(net "GND")
		)
		(pad "CB16" smd circle
			(at -20.830032 14.940026 180)
			(size 0.450088 0.450088)
			(layers "F.Cu" "F.Mask" "F.Paste")
			(net "M_J_CPU0_SB_DQ<0>")
		)
		(pad "CB17" smd circle
			(at -19.889978 14.940026 180)
			(size 0.450088 0.450088)
			(layers "F.Cu" "F.Mask" "F.Paste")
			(net "GND")
		)
		(pad "CB18" smd circle
			(at -18.949924 14.940026 180)
			(size 0.450088 0.450088)
			(layers "F.Cu" "F.Mask" "F.Paste")
			(net "M_J_CPU0_SB_CB<3>")
		)
		(pad "CB19" smd circle
			(at -18.010124 14.940026 180)
			(size 0.450088 0.450088)
			(layers "F.Cu" "F.Mask" "F.Paste")
			(net "GND")
		)
		(pad "CB20" smd circle
			(at -17.07007 14.940026 180)
			(size 0.450088 0.450088)
			(layers "F.Cu" "F.Mask" "F.Paste")
			(net "M_I_CPU0_SB_DQ<0>")
		)
		(pad "CB21" smd circle
			(at -16.130016 14.940026 180)
			(size 0.450088 0.450088)
			(layers "F.Cu" "F.Mask" "F.Paste")
			(net "M_I_CPU0_SB_CB<3>")
		)
		(pad "CB22" smd circle
			(at -15.189962 14.940026 180)
			(size 0.450088 0.450088)
			(layers "F.Cu" "F.Mask" "F.Paste")
			(net "PVDD11_S3_P0")
		)
		(pad "CB23" smd circle
			(at -14.249908 14.940026 180)
			(size 0.450088 0.450088)
			(layers "F.Cu" "F.Mask" "F.Paste")
			(net "GND")
		)
		(pad "CB24" smd circle
			(at -13.310108 14.940026 180)
			(size 0.450088 0.450088)
			(layers "F.Cu" "F.Mask" "F.Paste")
			(net "GND")
		)
		(pad "CB25" smd circle
			(at -12.370054 14.940026 180)
			(size 0.450088 0.450088)
			(layers "F.Cu" "F.Mask" "F.Paste")
			(net "GND")
		)
		(pad "CB26" smd circle
			(at -11.43 14.940026 180)
			(size 0.450088 0.450088)
			(layers "F.Cu" "F.Mask" "F.Paste")
			(net "GND")
		)
		(pad "CB27" smd circle
			(at -10.489946 14.940026 180)
			(size 0.450088 0.450088)
			(layers "F.Cu" "F.Mask" "F.Paste")
			(net "GND")
		)
		(pad "CB28" smd circle
			(at -9.549892 14.940026 180)
			(size 0.450088 0.450088)
			(layers "F.Cu" "F.Mask" "F.Paste")
			(net "GND")
		)
		(pad "CB29" smd circle
			(at -8.610092 14.940026 180)
			(size 0.450088 0.450088)
			(layers "F.Cu" "F.Mask" "F.Paste")
			(net "GND")
		)
		(pad "CB30" smd circle
			(at -7.670038 14.940026 180)
			(size 0.450088 0.450088)
			(layers "F.Cu" "F.Mask" "F.Paste")
			(net "GND")
		)
		(pad "CB31" smd circle
			(at -6.729984 14.940026 180)
			(size 0.450088 0.450088)
			(layers "F.Cu" "F.Mask" "F.Paste")
			(net "GND")
		)
		(pad "CB32" smd circle
			(at -5.78993 14.940026 180)
			(size 0.450088 0.450088)
			(layers "F.Cu" "F.Mask" "F.Paste")
			(net "GND")
		)
		(pad "CB33" smd circle
			(at -4.849876 14.940026 180)
			(size 0.450088 0.450088)
			(layers "F.Cu" "F.Mask" "F.Paste")
			(net "GND")
		)
		(pad "CB34" smd circle
			(at -3.910076 14.940026 180)
			(size 0.450088 0.450088)
			(layers "F.Cu" "F.Mask" "F.Paste")
			(net "GND")
		)
		(pad "CB35" smd circle
			(at -2.970022 14.940026 180)
			(size 0.450088 0.450088)
			(layers "F.Cu" "F.Mask" "F.Paste")
			(net "P5E_CPU0_P2_TX_DN<2>")
		)
		(pad "CB36" smd circle
			(at -2.029968 14.940026 180)
			(size 0.450088 0.450088)
			(layers "F.Cu" "F.Mask" "F.Paste")
			(net "P5E_CPU0_P2_TX_DP<2>")
		)
		(pad "CB37" smd circle
			(at -1.089914 14.940026 180)
			(size 0.450088 0.450088)
			(layers "F.Cu" "F.Mask" "F.Paste")
			(net "GND")
		)
		(pad "CB39" smd circle
			(at 0.78994 14.940026 180)
			(size 0.450088 0.450088)
			(layers "F.Cu" "F.Mask" "F.Paste")
			(net "GND")
		)
		(pad "CB40" smd circle
			(at 1.729994 14.940026 180)
			(size 0.450088 0.450088)
			(layers "F.Cu" "F.Mask" "F.Paste")
			(net "P5E_CPU0_P0_RX_DP<13>")
		)
		(pad "CB41" smd circle
			(at 2.670048 14.940026 180)
			(size 0.450088 0.450088)
			(layers "F.Cu" "F.Mask" "F.Paste")
			(net "P5E_CPU0_P0_RX_DN<13>")
		)
		(pad "CB42" smd circle
			(at 3.610102 14.940026 180)
			(size 0.450088 0.450088)
			(layers "F.Cu" "F.Mask" "F.Paste")
			(net "GND")
		)
		(pad "CB43" smd circle
			(at 4.549902 14.940026 180)
			(size 0.450088 0.450088)
			(layers "F.Cu" "F.Mask" "F.Paste")
			(net "GND")
		)
		(pad "CB44" smd circle
			(at 5.489956 14.940026 180)
			(size 0.450088 0.450088)
			(layers "F.Cu" "F.Mask" "F.Paste")
			(net "GND")
		)
		(pad "CB45" smd circle
			(at 6.43001 14.940026 180)
			(size 0.450088 0.450088)
			(layers "F.Cu" "F.Mask" "F.Paste")
			(net "GND")
		)
		(pad "CB46" smd circle
			(at 7.370064 14.940026 180)
			(size 0.450088 0.450088)
			(layers "F.Cu" "F.Mask" "F.Paste")
			(net "GND")
		)
		(pad "CB47" smd circle
			(at 8.310118 14.940026 180)
			(size 0.450088 0.450088)
			(layers "F.Cu" "F.Mask" "F.Paste")
			(net "GND")
		)
		(pad "CB48" smd circle
			(at 9.249918 14.940026 180)
			(size 0.450088 0.450088)
			(layers "F.Cu" "F.Mask" "F.Paste")
			(net "GND")
		)
		(pad "CB49" smd circle
			(at 10.189972 14.940026 180)
			(size 0.450088 0.450088)
			(layers "F.Cu" "F.Mask" "F.Paste")
			(net "GND")
		)
		(pad "CB50" smd circle
			(at 11.130026 14.940026 180)
			(size 0.450088 0.450088)
			(layers "F.Cu" "F.Mask" "F.Paste")
			(net "GND")
		)
		(pad "CB51" smd circle
			(at 12.07008 14.940026 180)
			(size 0.450088 0.450088)
			(layers "F.Cu" "F.Mask" "F.Paste")
			(net "GND")
		)
		(pad "CB52" smd circle
			(at 13.00988 14.940026 180)
			(size 0.450088 0.450088)
			(layers "F.Cu" "F.Mask" "F.Paste")
			(net "GND")
		)
		(pad "CB53" smd circle
			(at 13.949934 14.940026 180)
			(size 0.450088 0.450088)
			(layers "F.Cu" "F.Mask" "F.Paste")
			(net "GND")
		)
		(pad "CB54" smd circle
			(at 14.889988 14.940026 180)
			(size 0.450088 0.450088)
			(layers "F.Cu" "F.Mask" "F.Paste")
			(net "PVDDIO_P0")
		)
		(pad "CB55" smd circle
			(at 15.830042 14.940026 180)
			(size 0.450088 0.450088)
			(layers "F.Cu" "F.Mask" "F.Paste")
			(net "M_C_CPU0_SB_CB<3>")
		)
		(pad "CB56" smd circle
			(at 16.770096 14.940026 180)
			(size 0.450088 0.450088)
			(layers "F.Cu" "F.Mask" "F.Paste")
			(net "M_C_CPU0_SB_DQ<0>")
		)
		(pad "CB57" smd circle
			(at 17.709896 14.940026 180)
			(size 0.450088 0.450088)
			(layers "F.Cu" "F.Mask" "F.Paste")
			(net "GND")
		)
		(pad "CB58" smd circle
			(at 18.64995 14.940026 180)
			(size 0.450088 0.450088)
			(layers "F.Cu" "F.Mask" "F.Paste")
			(net "M_D_CPU0_SB_CB<3>")
		)
		(pad "CB59" smd circle
			(at 19.590004 14.940026 180)
			(size 0.450088 0.450088)
			(layers "F.Cu" "F.Mask" "F.Paste")
			(net "GND")
		)
		(pad "CB60" smd circle
			(at 20.530058 14.940026 180)
			(size 0.450088 0.450088)
			(layers "F.Cu" "F.Mask" "F.Paste")
			(net "M_D_CPU0_SB_DQ<0>")
		)
		(pad "CB61" smd circle
			(at 21.470112 14.940026 180)
			(size 0.450088 0.450088)
			(layers "F.Cu" "F.Mask" "F.Paste")
			(net "GND")
		)
		(pad "CB62" smd circle
			(at 22.409912 14.940026 180)
			(size 0.450088 0.450088)
			(layers "F.Cu" "F.Mask" "F.Paste")
			(net "M_B_CPU0_SB_CB<3>")
		)
		(pad "CB63" smd circle
			(at 23.349966 14.940026 180)
			(size 0.450088 0.450088)
			(layers "F.Cu" "F.Mask" "F.Paste")
			(net "M_B_CPU0_SB_DQ<0>")
		)
		(pad "CB64" smd circle
			(at 24.29002 14.940026 180)
			(size 0.450088 0.450088)
			(layers "F.Cu" "F.Mask" "F.Paste")
			(net "GND")
		)
		(pad "CB65" smd circle
			(at 25.230074 14.940026 180)
			(size 0.450088 0.450088)
			(layers "F.Cu" "F.Mask" "F.Paste")
			(net "M_F_CPU0_SB_CB<3>")
		)
		(pad "CB66" smd circle
			(at 26.170128 14.940026 180)
			(size 0.450088 0.450088)
			(layers "F.Cu" "F.Mask" "F.Paste")
			(net "GND")
		)
		(pad "CB67" smd circle
			(at 27.109928 14.940026 180)
			(size 0.450088 0.450088)
			(layers "F.Cu" "F.Mask" "F.Paste")
			(net "M_F_CPU0_SB_DQ<0>")
		)
		(pad "CB68" smd circle
			(at 28.049982 14.940026 180)
			(size 0.450088 0.450088)
			(layers "F.Cu" "F.Mask" "F.Paste")
			(net "GND")
		)
		(pad "CB69" smd circle
			(at 28.990036 14.940026 180)
			(size 0.450088 0.450088)
			(layers "F.Cu" "F.Mask" "F.Paste")
			(net "M_E_CPU0_SB_CB<3>")
		)
		(pad "CB70" smd circle
			(at 29.93009 14.940026 180)
			(size 0.450088 0.450088)
			(layers "F.Cu" "F.Mask" "F.Paste")
			(net "M_E_CPU0_SB_DQ<0>")
		)
		(pad "CB71" smd circle
			(at 30.86989 14.940026 180)
			(size 0.450088 0.450088)
			(layers "F.Cu" "F.Mask" "F.Paste")
			(net "GND")
		)
		(pad "CB72" smd circle
			(at 31.809944 14.940026 180)
			(size 0.450088 0.450088)
			(layers "F.Cu" "F.Mask" "F.Paste")
			(net "M_A_CPU0_SB_CB<3>")
		)
		(pad "CB73" smd circle
			(at 32.749998 14.940026 180)
			(size 0.450088 0.450088)
			(layers "F.Cu" "F.Mask" "F.Paste")
			(net "GND")
		)
		(pad "CB74" smd circle
			(at 33.690052 14.940026 180)
			(size 0.450088 0.450088)
			(layers "F.Cu" "F.Mask" "F.Paste")
			(net "M_A_CPU0_SB_DQ<0>")
		)
		(pad "CC1" smd circle
			(at -34.459926 15.750032 180)
			(size 0.450088 0.450088)
			(layers "F.Cu" "F.Mask" "F.Paste")
			(net "GND")
		)
		(pad "CC2" smd circle
			(at -33.519872 15.750032 180)
			(size 0.450088 0.450088)
			(layers "F.Cu" "F.Mask" "F.Paste")
			(net "M_G_CPU0_SB_DQ<2>")
		)
		(pad "CC3" smd circle
			(at -32.580072 15.750032 180)
			(size 0.450088 0.450088)
			(layers "F.Cu" "F.Mask" "F.Paste")
			(net "M_G_CPU0_SB_DQ<1>")
		)
		(pad "CC4" smd circle
			(at -31.640018 15.750032 180)
			(size 0.450088 0.450088)
			(layers "F.Cu" "F.Mask" "F.Paste")
			(net "GND")
		)
		(pad "CC5" smd circle
			(at -30.699964 15.750032 180)
			(size 0.450088 0.450088)
			(layers "F.Cu" "F.Mask" "F.Paste")
			(net "M_K_CPU0_SB_DQ<2>")
		)
		(pad "CC6" smd circle
			(at -29.75991 15.750032 180)
			(size 0.450088 0.450088)
			(layers "F.Cu" "F.Mask" "F.Paste")
			(net "GND")
		)
		(pad "CC7" smd circle
			(at -28.82011 15.750032 180)
			(size 0.450088 0.450088)
			(layers "F.Cu" "F.Mask" "F.Paste")
			(net "M_K_CPU0_SB_DQ<1>")
		)
		(pad "CC8" smd circle
			(at -27.880056 15.750032 180)
			(size 0.450088 0.450088)
			(layers "F.Cu" "F.Mask" "F.Paste")
			(net "GND")
		)
		(pad "CC9" smd circle
			(at -26.940002 15.750032 180)
			(size 0.450088 0.450088)
			(layers "F.Cu" "F.Mask" "F.Paste")
			(net "M_L_CPU0_SB_DQ<2>")
		)
		(pad "CC10" smd circle
			(at -25.999948 15.750032 180)
			(size 0.450088 0.450088)
			(layers "F.Cu" "F.Mask" "F.Paste")
			(net "M_L_CPU0_SB_DQ<1>")
		)
		(pad "CC11" smd circle
			(at -25.059894 15.750032 180)
			(size 0.450088 0.450088)
			(layers "F.Cu" "F.Mask" "F.Paste")
			(net "GND")
		)
		(pad "CC12" smd circle
			(at -24.120094 15.750032 180)
			(size 0.450088 0.450088)
			(layers "F.Cu" "F.Mask" "F.Paste")
			(net "M_H_CPU0_SB_DQ<2>")
		)
		(pad "CC13" smd circle
			(at -23.18004 15.750032 180)
			(size 0.450088 0.450088)
			(layers "F.Cu" "F.Mask" "F.Paste")
			(net "GND")
		)
		(pad "CC14" smd circle
			(at -22.239986 15.750032 180)
			(size 0.450088 0.450088)
			(layers "F.Cu" "F.Mask" "F.Paste")
			(net "M_H_CPU0_SB_DQ<1>")
		)
		(pad "CC15" smd circle
			(at -21.299932 15.750032 180)
			(size 0.450088 0.450088)
			(layers "F.Cu" "F.Mask" "F.Paste")
			(net "GND")
		)
		(pad "CC16" smd circle
			(at -20.359878 15.750032 180)
			(size 0.450088 0.450088)
			(layers "F.Cu" "F.Mask" "F.Paste")
			(net "M_J_CPU0_SB_DQ<2>")
		)
		(pad "CC17" smd circle
			(at -19.420078 15.750032 180)
			(size 0.450088 0.450088)
			(layers "F.Cu" "F.Mask" "F.Paste")
			(net "M_J_CPU0_SB_DQ<1>")
		)
		(pad "CC18" smd circle
			(at -18.480024 15.750032 180)
			(size 0.450088 0.450088)
			(layers "F.Cu" "F.Mask" "F.Paste")
			(net "GND")
		)
		(pad "CC19" smd circle
			(at -17.53997 15.750032 180)
			(size 0.450088 0.450088)
			(layers "F.Cu" "F.Mask" "F.Paste")
			(net "M_I_CPU0_SB_DQ<2>")
		)
		(pad "CC20" smd circle
			(at -16.599916 15.750032 180)
			(size 0.450088 0.450088)
			(layers "F.Cu" "F.Mask" "F.Paste")
			(net "GND")
		)
		(pad "CC21" smd circle
			(at -15.660116 15.750032 180)
			(size 0.450088 0.450088)
			(layers "F.Cu" "F.Mask" "F.Paste")
			(net "M_I_CPU0_SB_DQ<1>")
		)
		(pad "CC22" smd circle
			(at -14.720062 15.750032 180)
			(size 0.450088 0.450088)
			(layers "F.Cu" "F.Mask" "F.Paste")
			(net "GND")
		)
		(pad "CC23" smd circle
			(at -13.780008 15.750032 180)
			(size 0.450088 0.450088)
			(layers "F.Cu" "F.Mask" "F.Paste")
			(net "P5E_CPU0_P3_TX_DN<13>")
		)
		(pad "CC24" smd circle
			(at -12.839954 15.750032 180)
			(size 0.450088 0.450088)
			(layers "F.Cu" "F.Mask" "F.Paste")
			(net "P5E_CPU0_P3_TX_DP<13>")
		)
		(pad "CC25" smd circle
			(at -11.8999 15.750032 180)
			(size 0.450088 0.450088)
			(layers "F.Cu" "F.Mask" "F.Paste")
			(net "GND")
		)
		(pad "CC26" smd circle
			(at -10.9601 15.750032 180)
			(size 0.450088 0.450088)
			(layers "F.Cu" "F.Mask" "F.Paste")
			(net "P5E_CPU0_P3_TX_DN<10>")
		)
		(pad "CC27" smd circle
			(at -10.020046 15.750032 180)
			(size 0.450088 0.450088)
			(layers "F.Cu" "F.Mask" "F.Paste")
			(net "P5E_CPU0_P3_TX_DP<10>")
		)
		(pad "CC28" smd circle
			(at -9.079992 15.750032 180)
			(size 0.450088 0.450088)
			(layers "F.Cu" "F.Mask" "F.Paste")
			(net "GND")
		)
		(pad "CC29" smd circle
			(at -8.139938 15.750032 180)
			(size 0.450088 0.450088)
			(layers "F.Cu" "F.Mask" "F.Paste")
			(net "P5E_CPU0_P3_TX_DN<7>")
		)
		(pad "CC30" smd circle
			(at -7.199884 15.750032 180)
			(size 0.450088 0.450088)
			(layers "F.Cu" "F.Mask" "F.Paste")
			(net "P5E_CPU0_P3_TX_DP<7>")
		)
		(pad "CC31" smd circle
			(at -6.260084 15.750032 180)
			(size 0.450088 0.450088)
			(layers "F.Cu" "F.Mask" "F.Paste")
			(net "GND")
		)
		(pad "CC32" smd circle
			(at -5.32003 15.750032 180)
			(size 0.450088 0.450088)
			(layers "F.Cu" "F.Mask" "F.Paste")
			(net "P5E_CPU0_P3_TX_DN<3>")
		)
		(pad "CC33" smd circle
			(at -4.379976 15.750032 180)
			(size 0.450088 0.450088)
			(layers "F.Cu" "F.Mask" "F.Paste")
			(net "P5E_CPU0_P3_TX_DP<3>")
		)
		(pad "CC34" smd circle
			(at -3.439922 15.750032 180)
			(size 0.450088 0.450088)
			(layers "F.Cu" "F.Mask" "F.Paste")
			(net "GND")
		)
		(pad "CC35" smd circle
			(at -2.500122 15.750032 180)
			(size 0.450088 0.450088)
			(layers "F.Cu" "F.Mask" "F.Paste")
			(net "PVDDCR_CPU1_P0")
		)
		(pad "CC36" smd circle
			(at -1.560068 15.750032 180)
			(size 0.450088 0.450088)
			(layers "F.Cu" "F.Mask" "F.Paste")
			(net "PVDDCR_CPU1_P0")
		)
		(pad "CC40" smd circle
			(at 1.260094 15.750032 180)
			(size 0.450088 0.450088)
			(layers "F.Cu" "F.Mask" "F.Paste")
			(net "PVDDCR_CPU1_P0")
		)
		(pad "CC41" smd circle
			(at 2.199894 15.750032 180)
			(size 0.450088 0.450088)
			(layers "F.Cu" "F.Mask" "F.Paste")
			(net "PVDDCR_CPU1_P0")
		)
		(pad "CC42" smd circle
			(at 3.139948 15.750032 180)
			(size 0.450088 0.450088)
			(layers "F.Cu" "F.Mask" "F.Paste")
			(net "GND")
		)
		(pad "CC43" smd circle
			(at 4.080002 15.750032 180)
			(size 0.450088 0.450088)
			(layers "F.Cu" "F.Mask" "F.Paste")
			(net "P5E_CPU0_P1_RX_DP<12>")
		)
		(pad "CC44" smd circle
			(at 5.020056 15.750032 180)
			(size 0.450088 0.450088)
			(layers "F.Cu" "F.Mask" "F.Paste")
			(net "P5E_CPU0_P1_RX_DN<12>")
		)
		(pad "CC45" smd circle
			(at 5.96011 15.750032 180)
			(size 0.450088 0.450088)
			(layers "F.Cu" "F.Mask" "F.Paste")
			(net "GND")
		)
		(pad "CC46" smd circle
			(at 6.89991 15.750032 180)
			(size 0.450088 0.450088)
			(layers "F.Cu" "F.Mask" "F.Paste")
			(net "P5E_CPU0_P1_RX_DP<8>")
		)
		(pad "CC47" smd circle
			(at 7.839964 15.750032 180)
			(size 0.450088 0.450088)
			(layers "F.Cu" "F.Mask" "F.Paste")
			(net "P5E_CPU0_P1_RX_DN<8>")
		)
		(pad "CC48" smd circle
			(at 8.780018 15.750032 180)
			(size 0.450088 0.450088)
			(layers "F.Cu" "F.Mask" "F.Paste")
			(net "GND")
		)
		(pad "CC49" smd circle
			(at 9.720072 15.750032 180)
			(size 0.450088 0.450088)
			(layers "F.Cu" "F.Mask" "F.Paste")
			(net "P5E_CPU0_P1_RX_DP<5>")
		)
		(pad "CC50" smd circle
			(at 10.659872 15.750032 180)
			(size 0.450088 0.450088)
			(layers "F.Cu" "F.Mask" "F.Paste")
			(net "P5E_CPU0_P1_RX_DN<5>")
		)
		(pad "CC51" smd circle
			(at 11.599926 15.750032 180)
			(size 0.450088 0.450088)
			(layers "F.Cu" "F.Mask" "F.Paste")
			(net "GND")
		)
		(pad "CC52" smd circle
			(at 12.53998 15.750032 180)
			(size 0.450088 0.450088)
			(layers "F.Cu" "F.Mask" "F.Paste")
			(net "P5E_CPU0_P1_RX_DP<2>")
		)
		(pad "CC53" smd circle
			(at 13.480034 15.750032 180)
			(size 0.450088 0.450088)
			(layers "F.Cu" "F.Mask" "F.Paste")
			(net "P5E_CPU0_P1_RX_DN<2>")
		)
		(pad "CC54" smd circle
			(at 14.420088 15.750032 180)
			(size 0.450088 0.450088)
			(layers "F.Cu" "F.Mask" "F.Paste")
			(net "GND")
		)
		(pad "CC55" smd circle
			(at 15.359888 15.750032 180)
			(size 0.450088 0.450088)
			(layers "F.Cu" "F.Mask" "F.Paste")
			(net "M_C_CPU0_SB_DQ<1>")
		)
		(pad "CC56" smd circle
			(at 16.299942 15.750032 180)
			(size 0.450088 0.450088)
			(layers "F.Cu" "F.Mask" "F.Paste")
			(net "GND")
		)
		(pad "CC57" smd circle
			(at 17.239996 15.750032 180)
			(size 0.450088 0.450088)
			(layers "F.Cu" "F.Mask" "F.Paste")
			(net "M_C_CPU0_SB_DQ<2>")
		)
		(pad "CC58" smd circle
			(at 18.18005 15.750032 180)
			(size 0.450088 0.450088)
			(layers "F.Cu" "F.Mask" "F.Paste")
			(net "GND")
		)
		(pad "CC59" smd circle
			(at 19.120104 15.750032 180)
			(size 0.450088 0.450088)
			(layers "F.Cu" "F.Mask" "F.Paste")
			(net "M_D_CPU0_SB_DQ<1>")
		)
		(pad "CC60" smd circle
			(at 20.059904 15.750032 180)
			(size 0.450088 0.450088)
			(layers "F.Cu" "F.Mask" "F.Paste")
			(net "M_D_CPU0_SB_DQ<2>")
		)
		(pad "CC61" smd circle
			(at 20.999958 15.750032 180)
			(size 0.450088 0.450088)
			(layers "F.Cu" "F.Mask" "F.Paste")
			(net "GND")
		)
		(pad "CC62" smd circle
			(at 21.940012 15.750032 180)
			(size 0.450088 0.450088)
			(layers "F.Cu" "F.Mask" "F.Paste")
			(net "M_B_CPU0_SB_DQ<1>")
		)
		(pad "CC63" smd circle
			(at 22.880066 15.750032 180)
			(size 0.450088 0.450088)
			(layers "F.Cu" "F.Mask" "F.Paste")
			(net "GND")
		)
		(pad "CC64" smd circle
			(at 23.82012 15.750032 180)
			(size 0.450088 0.450088)
			(layers "F.Cu" "F.Mask" "F.Paste")
			(net "M_B_CPU0_SB_DQ<2>")
		)
		(pad "CC65" smd circle
			(at 24.75992 15.750032 180)
			(size 0.450088 0.450088)
			(layers "F.Cu" "F.Mask" "F.Paste")
			(net "GND")
		)
		(pad "CC66" smd circle
			(at 25.699974 15.750032 180)
			(size 0.450088 0.450088)
			(layers "F.Cu" "F.Mask" "F.Paste")
			(net "M_F_CPU0_SB_DQ<1>")
		)
		(pad "CC67" smd circle
			(at 26.640028 15.750032 180)
			(size 0.450088 0.450088)
			(layers "F.Cu" "F.Mask" "F.Paste")
			(net "M_F_CPU0_SB_DQ<2>")
		)
		(pad "CC68" smd circle
			(at 27.580082 15.750032 180)
			(size 0.450088 0.450088)
			(layers "F.Cu" "F.Mask" "F.Paste")
			(net "GND")
		)
		(pad "CC69" smd circle
			(at 28.519882 15.750032 180)
			(size 0.450088 0.450088)
			(layers "F.Cu" "F.Mask" "F.Paste")
			(net "M_E_CPU0_SB_DQ<1>")
		)
		(pad "CC70" smd circle
			(at 29.459936 15.750032 180)
			(size 0.450088 0.450088)
			(layers "F.Cu" "F.Mask" "F.Paste")
			(net "GND")
		)
		(pad "CC71" smd circle
			(at 30.39999 15.750032 180)
			(size 0.450088 0.450088)
			(layers "F.Cu" "F.Mask" "F.Paste")
			(net "M_E_CPU0_SB_DQ<2>")
		)
		(pad "CC72" smd circle
			(at 31.340044 15.750032 180)
			(size 0.450088 0.450088)
			(layers "F.Cu" "F.Mask" "F.Paste")
			(net "GND")
		)
		(pad "CC73" smd circle
			(at 32.280098 15.750032 180)
			(size 0.450088 0.450088)
			(layers "F.Cu" "F.Mask" "F.Paste")
			(net "M_A_CPU0_SB_DQ<1>")
		)
		(pad "CC74" smd circle
			(at 33.219898 15.750032 180)
			(size 0.450088 0.450088)
			(layers "F.Cu" "F.Mask" "F.Paste")
			(net "M_A_CPU0_SB_DQ<2>")
		)
		(pad "CC75" smd circle
			(at 34.159952 15.750032 180)
			(size 0.450088 0.450088)
			(layers "F.Cu" "F.Mask" "F.Paste")
			(net "GND")
		)
		(pad "CD2" smd circle
			(at -33.990026 16.560038 180)
			(size 0.450088 0.450088)
			(layers "F.Cu" "F.Mask" "F.Paste")
			(net "M_G_CPU0_SB_DQS_DP<0>")
		)
		(pad "CD3" smd circle
			(at -33.049972 16.560038 180)
			(size 0.450088 0.450088)
			(layers "F.Cu" "F.Mask" "F.Paste")
			(net "GND")
		)
		(pad "CD4" smd circle
			(at -32.109918 16.560038 180)
			(size 0.450088 0.450088)
			(layers "F.Cu" "F.Mask" "F.Paste")
			(net "M_G_CPU0_SB_DQ<3>")
		)
		(pad "CD5" smd circle
			(at -31.170118 16.560038 180)
			(size 0.450088 0.450088)
			(layers "F.Cu" "F.Mask" "F.Paste")
			(net "PVDD11_S3_P0")
		)
		(pad "CD6" smd circle
			(at -30.230064 16.560038 180)
			(size 0.450088 0.450088)
			(layers "F.Cu" "F.Mask" "F.Paste")
			(net "M_K_CPU0_SB_DQS_DP<0>")
		)
		(pad "CD7" smd circle
			(at -29.29001 16.560038 180)
			(size 0.450088 0.450088)
			(layers "F.Cu" "F.Mask" "F.Paste")
			(net "M_K_CPU0_SB_DQ<3>")
		)
		(pad "CD8" smd circle
			(at -28.349956 16.560038 180)
			(size 0.450088 0.450088)
			(layers "F.Cu" "F.Mask" "F.Paste")
			(net "GND")
		)
		(pad "CD9" smd circle
			(at -27.409902 16.560038 180)
			(size 0.450088 0.450088)
			(layers "F.Cu" "F.Mask" "F.Paste")
			(net "M_L_CPU0_SB_DQS_DP<0>")
		)
		(pad "CD10" smd circle
			(at -26.470102 16.560038 180)
			(size 0.450088 0.450088)
			(layers "F.Cu" "F.Mask" "F.Paste")
			(net "GND")
		)
		(pad "CD11" smd circle
			(at -25.530048 16.560038 180)
			(size 0.450088 0.450088)
			(layers "F.Cu" "F.Mask" "F.Paste")
			(net "M_L_CPU0_SB_DQ<3>")
		)
		(pad "CD12" smd circle
			(at -24.589994 16.560038 180)
			(size 0.450088 0.450088)
			(layers "F.Cu" "F.Mask" "F.Paste")
			(net "PVDD11_S3_P0")
		)
		(pad "CD13" smd circle
			(at -23.64994 16.560038 180)
			(size 0.450088 0.450088)
			(layers "F.Cu" "F.Mask" "F.Paste")
			(net "M_H_CPU0_SB_DQS_DP<0>")
		)
		(pad "CD14" smd circle
			(at -22.709886 16.560038 180)
			(size 0.450088 0.450088)
			(layers "F.Cu" "F.Mask" "F.Paste")
			(net "M_H_CPU0_SB_DQ<3>")
		)
		(pad "CD15" smd circle
			(at -21.770086 16.560038 180)
			(size 0.450088 0.450088)
			(layers "F.Cu" "F.Mask" "F.Paste")
			(net "GND")
		)
		(pad "CD16" smd circle
			(at -20.830032 16.560038 180)
			(size 0.450088 0.450088)
			(layers "F.Cu" "F.Mask" "F.Paste")
			(net "M_J_CPU0_SB_DQS_DP<0>")
		)
		(pad "CD17" smd circle
			(at -19.889978 16.560038 180)
			(size 0.450088 0.450088)
			(layers "F.Cu" "F.Mask" "F.Paste")
			(net "GND")
		)
		(pad "CD18" smd circle
			(at -18.949924 16.560038 180)
			(size 0.450088 0.450088)
			(layers "F.Cu" "F.Mask" "F.Paste")
			(net "M_J_CPU0_SB_DQ<3>")
		)
		(pad "CD19" smd circle
			(at -18.010124 16.560038 180)
			(size 0.450088 0.450088)
			(layers "F.Cu" "F.Mask" "F.Paste")
			(net "PVDD11_S3_P0")
		)
		(pad "CD20" smd circle
			(at -17.07007 16.560038 180)
			(size 0.450088 0.450088)
			(layers "F.Cu" "F.Mask" "F.Paste")
			(net "M_I_CPU0_SB_DQS_DP<0>")
		)
		(pad "CD21" smd circle
			(at -16.130016 16.560038 180)
			(size 0.450088 0.450088)
			(layers "F.Cu" "F.Mask" "F.Paste")
			(net "M_I_CPU0_SB_DQ<3>")
		)
		(pad "CD22" smd circle
			(at -15.189962 16.560038 180)
			(size 0.450088 0.450088)
			(layers "F.Cu" "F.Mask" "F.Paste")
			(net "GND")
		)
		(pad "CD23" smd circle
			(at -14.249908 16.560038 180)
			(size 0.450088 0.450088)
			(layers "F.Cu" "F.Mask" "F.Paste")
			(net "PVDDCR_CPU1_P0")
		)
		(pad "CD24" smd circle
			(at -13.310108 16.560038 180)
			(size 0.450088 0.450088)
			(layers "F.Cu" "F.Mask" "F.Paste")
			(net "PVDDCR_CPU1_P0")
		)
		(pad "CD25" smd circle
			(at -12.370054 16.560038 180)
			(size 0.450088 0.450088)
			(layers "F.Cu" "F.Mask" "F.Paste")
			(net "GND")
		)
		(pad "CD26" smd circle
			(at -11.43 16.560038 180)
			(size 0.450088 0.450088)
			(layers "F.Cu" "F.Mask" "F.Paste")
			(net "PVDDCR_CPU1_P0")
		)
		(pad "CD27" smd circle
			(at -10.489946 16.560038 180)
			(size 0.450088 0.450088)
			(layers "F.Cu" "F.Mask" "F.Paste")
			(net "PVDDCR_CPU1_P0")
		)
		(pad "CD28" smd circle
			(at -9.549892 16.560038 180)
			(size 0.450088 0.450088)
			(layers "F.Cu" "F.Mask" "F.Paste")
			(net "GND")
		)
		(pad "CD29" smd circle
			(at -8.610092 16.560038 180)
			(size 0.450088 0.450088)
			(layers "F.Cu" "F.Mask" "F.Paste")
			(net "PVDDCR_CPU1_P0")
		)
		(pad "CD30" smd circle
			(at -7.670038 16.560038 180)
			(size 0.450088 0.450088)
			(layers "F.Cu" "F.Mask" "F.Paste")
			(net "PVDDCR_CPU1_P0")
		)
		(pad "CD31" smd circle
			(at -6.729984 16.560038 180)
			(size 0.450088 0.450088)
			(layers "F.Cu" "F.Mask" "F.Paste")
			(net "GND")
		)
		(pad "CD32" smd circle
			(at -5.78993 16.560038 180)
			(size 0.450088 0.450088)
			(layers "F.Cu" "F.Mask" "F.Paste")
			(net "PVDDCR_CPU1_P0")
		)
		(pad "CD33" smd circle
			(at -4.849876 16.560038 180)
			(size 0.450088 0.450088)
			(layers "F.Cu" "F.Mask" "F.Paste")
			(net "PVDDCR_CPU1_P0")
		)
		(pad "CD34" smd circle
			(at -3.910076 16.560038 180)
			(size 0.450088 0.450088)
			(layers "F.Cu" "F.Mask" "F.Paste")
			(net "GND")
		)
		(pad "CD35" smd circle
			(at -2.970022 16.560038 180)
			(size 0.450088 0.450088)
			(layers "F.Cu" "F.Mask" "F.Paste")
			(net "P5E_CPU0_P3_TX_DN<0>")
		)
		(pad "CD36" smd circle
			(at -2.029968 16.560038 180)
			(size 0.450088 0.450088)
			(layers "F.Cu" "F.Mask" "F.Paste")
			(net "P5E_CPU0_P3_TX_DP<0>")
		)
		(pad "CD37" smd circle
			(at -1.089914 16.560038 180)
			(size 0.450088 0.450088)
			(layers "F.Cu" "F.Mask" "F.Paste")
			(net "GND")
		)
		(pad "CD39" smd circle
			(at 0.78994 16.560038 180)
			(size 0.450088 0.450088)
			(layers "F.Cu" "F.Mask" "F.Paste")
			(net "GND")
		)
		(pad "CD40" smd circle
			(at 1.729994 16.560038 180)
			(size 0.450088 0.450088)
			(layers "F.Cu" "F.Mask" "F.Paste")
			(net "P5E_CPU0_P1_RX_DP<15>")
		)
		(pad "CD41" smd circle
			(at 2.670048 16.560038 180)
			(size 0.450088 0.450088)
			(layers "F.Cu" "F.Mask" "F.Paste")
			(net "P5E_CPU0_P1_RX_DN<15>")
		)
		(pad "CD42" smd circle
			(at 3.610102 16.560038 180)
			(size 0.450088 0.450088)
			(layers "F.Cu" "F.Mask" "F.Paste")
			(net "GND")
		)
		(pad "CD43" smd circle
			(at 4.549902 16.560038 180)
			(size 0.450088 0.450088)
			(layers "F.Cu" "F.Mask" "F.Paste")
			(net "PVDDCR_CPU1_P0")
		)
		(pad "CD44" smd circle
			(at 5.489956 16.560038 180)
			(size 0.450088 0.450088)
			(layers "F.Cu" "F.Mask" "F.Paste")
			(net "PVDDCR_CPU1_P0")
		)
		(pad "CD45" smd circle
			(at 6.43001 16.560038 180)
			(size 0.450088 0.450088)
			(layers "F.Cu" "F.Mask" "F.Paste")
			(net "GND")
		)
		(pad "CD46" smd circle
			(at 7.370064 16.560038 180)
			(size 0.450088 0.450088)
			(layers "F.Cu" "F.Mask" "F.Paste")
			(net "PVDDCR_CPU1_P0")
		)
		(pad "CD47" smd circle
			(at 8.310118 16.560038 180)
			(size 0.450088 0.450088)
			(layers "F.Cu" "F.Mask" "F.Paste")
			(net "PVDDCR_CPU1_P0")
		)
		(pad "CD48" smd circle
			(at 9.249918 16.560038 180)
			(size 0.450088 0.450088)
			(layers "F.Cu" "F.Mask" "F.Paste")
			(net "GND")
		)
		(pad "CD49" smd circle
			(at 10.189972 16.560038 180)
			(size 0.450088 0.450088)
			(layers "F.Cu" "F.Mask" "F.Paste")
			(net "PVDDCR_CPU1_P0")
		)
		(pad "CD50" smd circle
			(at 11.130026 16.560038 180)
			(size 0.450088 0.450088)
			(layers "F.Cu" "F.Mask" "F.Paste")
			(net "PVDDCR_CPU1_P0")
		)
		(pad "CD51" smd circle
			(at 12.07008 16.560038 180)
			(size 0.450088 0.450088)
			(layers "F.Cu" "F.Mask" "F.Paste")
			(net "GND")
		)
		(pad "CD52" smd circle
			(at 13.00988 16.560038 180)
			(size 0.450088 0.450088)
			(layers "F.Cu" "F.Mask" "F.Paste")
			(net "PVDDCR_CPU1_P0")
		)
		(pad "CD53" smd circle
			(at 13.949934 16.560038 180)
			(size 0.450088 0.450088)
			(layers "F.Cu" "F.Mask" "F.Paste")
			(net "PVDDCR_CPU1_P0")
		)
		(pad "CD54" smd circle
			(at 14.889988 16.560038 180)
			(size 0.450088 0.450088)
			(layers "F.Cu" "F.Mask" "F.Paste")
			(net "GND")
		)
		(pad "CD55" smd circle
			(at 15.830042 16.560038 180)
			(size 0.450088 0.450088)
			(layers "F.Cu" "F.Mask" "F.Paste")
			(net "M_C_CPU0_SB_DQ<3>")
		)
		(pad "CD56" smd circle
			(at 16.770096 16.560038 180)
			(size 0.450088 0.450088)
			(layers "F.Cu" "F.Mask" "F.Paste")
			(net "M_C_CPU0_SB_DQS_DP<0>")
		)
		(pad "CD57" smd circle
			(at 17.709896 16.560038 180)
			(size 0.450088 0.450088)
			(layers "F.Cu" "F.Mask" "F.Paste")
			(net "PVDDIO_P0")
		)
		(pad "CD58" smd circle
			(at 18.64995 16.560038 180)
			(size 0.450088 0.450088)
			(layers "F.Cu" "F.Mask" "F.Paste")
			(net "M_D_CPU0_SB_DQ<3>")
		)
		(pad "CD59" smd circle
			(at 19.590004 16.560038 180)
			(size 0.450088 0.450088)
			(layers "F.Cu" "F.Mask" "F.Paste")
			(net "GND")
		)
		(pad "CD60" smd circle
			(at 20.530058 16.560038 180)
			(size 0.450088 0.450088)
			(layers "F.Cu" "F.Mask" "F.Paste")
			(net "M_D_CPU0_SB_DQS_DP<0>")
		)
		(pad "CD61" smd circle
			(at 21.470112 16.560038 180)
			(size 0.450088 0.450088)
			(layers "F.Cu" "F.Mask" "F.Paste")
			(net "GND")
		)
		(pad "CD62" smd circle
			(at 22.409912 16.560038 180)
			(size 0.450088 0.450088)
			(layers "F.Cu" "F.Mask" "F.Paste")
			(net "M_B_CPU0_SB_DQ<3>")
		)
		(pad "CD63" smd circle
			(at 23.349966 16.560038 180)
			(size 0.450088 0.450088)
			(layers "F.Cu" "F.Mask" "F.Paste")
			(net "M_B_CPU0_SB_DQS_DP<0>")
		)
		(pad "CD64" smd circle
			(at 24.29002 16.560038 180)
			(size 0.450088 0.450088)
			(layers "F.Cu" "F.Mask" "F.Paste")
			(net "PVDDIO_P0")
		)
		(pad "CD65" smd circle
			(at 25.230074 16.560038 180)
			(size 0.450088 0.450088)
			(layers "F.Cu" "F.Mask" "F.Paste")
			(net "M_F_CPU0_SB_DQ<3>")
		)
		(pad "CD66" smd circle
			(at 26.170128 16.560038 180)
			(size 0.450088 0.450088)
			(layers "F.Cu" "F.Mask" "F.Paste")
			(net "GND")
		)
		(pad "CD67" smd circle
			(at 27.109928 16.560038 180)
			(size 0.450088 0.450088)
			(layers "F.Cu" "F.Mask" "F.Paste")
			(net "M_F_CPU0_SB_DQS_DP<0>")
		)
		(pad "CD68" smd circle
			(at 28.049982 16.560038 180)
			(size 0.450088 0.450088)
			(layers "F.Cu" "F.Mask" "F.Paste")
			(net "GND")
		)
		(pad "CD69" smd circle
			(at 28.990036 16.560038 180)
			(size 0.450088 0.450088)
			(layers "F.Cu" "F.Mask" "F.Paste")
			(net "M_E_CPU0_SB_DQ<3>")
		)
		(pad "CD70" smd circle
			(at 29.93009 16.560038 180)
			(size 0.450088 0.450088)
			(layers "F.Cu" "F.Mask" "F.Paste")
			(net "M_E_CPU0_SB_DQS_DP<0>")
		)
		(pad "CD71" smd circle
			(at 30.86989 16.560038 180)
			(size 0.450088 0.450088)
			(layers "F.Cu" "F.Mask" "F.Paste")
			(net "PVDDIO_P0")
		)
		(pad "CD72" smd circle
			(at 31.809944 16.560038 180)
			(size 0.450088 0.450088)
			(layers "F.Cu" "F.Mask" "F.Paste")
			(net "M_A_CPU0_SB_DQ<3>")
		)
		(pad "CD73" smd circle
			(at 32.749998 16.560038 180)
			(size 0.450088 0.450088)
			(layers "F.Cu" "F.Mask" "F.Paste")
			(net "GND")
		)
		(pad "CD74" smd circle
			(at 33.690052 16.560038 180)
			(size 0.450088 0.450088)
			(layers "F.Cu" "F.Mask" "F.Paste")
			(net "M_A_CPU0_SB_DQS_DP<0>")
		)
		(pad "CE1" smd circle
			(at -34.459926 17.370044 180)
			(size 0.450088 0.450088)
			(layers "F.Cu" "F.Mask" "F.Paste")
			(net "GND")
		)
		(pad "CE2" smd circle
			(at -33.519872 17.370044 180)
			(size 0.450088 0.450088)
			(layers "F.Cu" "F.Mask" "F.Paste")
			(net "M_G_CPU0_SB_DQS_DN<0>")
		)
		(pad "CE3" smd circle
			(at -32.580072 17.370044 180)
			(size 0.450088 0.450088)
			(layers "F.Cu" "F.Mask" "F.Paste")
			(net "M_G_CPU0_SB_DQS_DN<5>")
		)
		(pad "CE4" smd circle
			(at -31.640018 17.370044 180)
			(size 0.450088 0.450088)
			(layers "F.Cu" "F.Mask" "F.Paste")
			(net "GND")
		)
		(pad "CE5" smd circle
			(at -30.699964 17.370044 180)
			(size 0.450088 0.450088)
			(layers "F.Cu" "F.Mask" "F.Paste")
			(net "M_K_CPU0_SB_DQS_DN<0>")
		)
		(pad "CE6" smd circle
			(at -29.75991 17.370044 180)
			(size 0.450088 0.450088)
			(layers "F.Cu" "F.Mask" "F.Paste")
			(net "GND")
		)
		(pad "CE7" smd circle
			(at -28.82011 17.370044 180)
			(size 0.450088 0.450088)
			(layers "F.Cu" "F.Mask" "F.Paste")
			(net "M_K_CPU0_SB_DQS_DN<5>")
		)
		(pad "CE8" smd circle
			(at -27.880056 17.370044 180)
			(size 0.450088 0.450088)
			(layers "F.Cu" "F.Mask" "F.Paste")
			(net "GND")
		)
		(pad "CE9" smd circle
			(at -26.940002 17.370044 180)
			(size 0.450088 0.450088)
			(layers "F.Cu" "F.Mask" "F.Paste")
			(net "M_L_CPU0_SB_DQS_DN<0>")
		)
		(pad "CE10" smd circle
			(at -25.999948 17.370044 180)
			(size 0.450088 0.450088)
			(layers "F.Cu" "F.Mask" "F.Paste")
			(net "M_L_CPU0_SB_DQS_DN<5>")
		)
		(pad "CE11" smd circle
			(at -25.059894 17.370044 180)
			(size 0.450088 0.450088)
			(layers "F.Cu" "F.Mask" "F.Paste")
			(net "GND")
		)
		(pad "CE12" smd circle
			(at -24.120094 17.370044 180)
			(size 0.450088 0.450088)
			(layers "F.Cu" "F.Mask" "F.Paste")
			(net "M_H_CPU0_SB_DQS_DN<0>")
		)
		(pad "CE13" smd circle
			(at -23.18004 17.370044 180)
			(size 0.450088 0.450088)
			(layers "F.Cu" "F.Mask" "F.Paste")
			(net "GND")
		)
		(pad "CE14" smd circle
			(at -22.239986 17.370044 180)
			(size 0.450088 0.450088)
			(layers "F.Cu" "F.Mask" "F.Paste")
			(net "M_H_CPU0_SB_DQS_DN<5>")
		)
		(pad "CE15" smd circle
			(at -21.299932 17.370044 180)
			(size 0.450088 0.450088)
			(layers "F.Cu" "F.Mask" "F.Paste")
			(net "GND")
		)
		(pad "CE16" smd circle
			(at -20.359878 17.370044 180)
			(size 0.450088 0.450088)
			(layers "F.Cu" "F.Mask" "F.Paste")
			(net "M_J_CPU0_SB_DQS_DN<0>")
		)
		(pad "CE17" smd circle
			(at -19.420078 17.370044 180)
			(size 0.450088 0.450088)
			(layers "F.Cu" "F.Mask" "F.Paste")
			(net "M_J_CPU0_SB_DQS_DN<5>")
		)
		(pad "CE18" smd circle
			(at -18.480024 17.370044 180)
			(size 0.450088 0.450088)
			(layers "F.Cu" "F.Mask" "F.Paste")
			(net "GND")
		)
		(pad "CE19" smd circle
			(at -17.53997 17.370044 180)
			(size 0.450088 0.450088)
			(layers "F.Cu" "F.Mask" "F.Paste")
			(net "M_I_CPU0_SB_DQS_DN<0>")
		)
		(pad "CE20" smd circle
			(at -16.599916 17.370044 180)
			(size 0.450088 0.450088)
			(layers "F.Cu" "F.Mask" "F.Paste")
			(net "GND")
		)
		(pad "CE21" smd circle
			(at -15.660116 17.370044 180)
			(size 0.450088 0.450088)
			(layers "F.Cu" "F.Mask" "F.Paste")
			(net "M_I_CPU0_SB_DQS_DN<5>")
		)
		(pad "CE22" smd circle
			(at -14.720062 17.370044 180)
			(size 0.450088 0.450088)
			(layers "F.Cu" "F.Mask" "F.Paste")
			(net "GND")
		)
		(pad "CE23" smd circle
			(at -13.780008 17.370044 180)
			(size 0.450088 0.450088)
			(layers "F.Cu" "F.Mask" "F.Paste")
			(net "P5E_CPU0_P3_TX_DN<15>")
		)
		(pad "CE24" smd circle
			(at -12.839954 17.370044 180)
			(size 0.450088 0.450088)
			(layers "F.Cu" "F.Mask" "F.Paste")
			(net "P5E_CPU0_P3_TX_DP<15>")
		)
		(pad "CE25" smd circle
			(at -11.8999 17.370044 180)
			(size 0.450088 0.450088)
			(layers "F.Cu" "F.Mask" "F.Paste")
			(net "GND")
		)
		(pad "CE26" smd circle
			(at -10.9601 17.370044 180)
			(size 0.450088 0.450088)
			(layers "F.Cu" "F.Mask" "F.Paste")
			(net "P5E_CPU0_P3_TX_DN<12>")
		)
		(pad "CE27" smd circle
			(at -10.020046 17.370044 180)
			(size 0.450088 0.450088)
			(layers "F.Cu" "F.Mask" "F.Paste")
			(net "P5E_CPU0_P3_TX_DP<12>")
		)
		(pad "CE28" smd circle
			(at -9.079992 17.370044 180)
			(size 0.450088 0.450088)
			(layers "F.Cu" "F.Mask" "F.Paste")
			(net "GND")
		)
		(pad "CE29" smd circle
			(at -8.139938 17.370044 180)
			(size 0.450088 0.450088)
			(layers "F.Cu" "F.Mask" "F.Paste")
			(net "P5E_CPU0_P3_TX_DN<9>")
		)
		(pad "CE30" smd circle
			(at -7.199884 17.370044 180)
			(size 0.450088 0.450088)
			(layers "F.Cu" "F.Mask" "F.Paste")
			(net "P5E_CPU0_P3_TX_DP<9>")
		)
		(pad "CE31" smd circle
			(at -6.260084 17.370044 180)
			(size 0.450088 0.450088)
			(layers "F.Cu" "F.Mask" "F.Paste")
			(net "GND")
		)
		(pad "CE32" smd circle
			(at -5.32003 17.370044 180)
			(size 0.450088 0.450088)
			(layers "F.Cu" "F.Mask" "F.Paste")
			(net "P5E_CPU0_P3_TX_DN<6>")
		)
		(pad "CE33" smd circle
			(at -4.379976 17.370044 180)
			(size 0.450088 0.450088)
			(layers "F.Cu" "F.Mask" "F.Paste")
			(net "P5E_CPU0_P3_TX_DP<6>")
		)
		(pad "CE34" smd circle
			(at -3.439922 17.370044 180)
			(size 0.450088 0.450088)
			(layers "F.Cu" "F.Mask" "F.Paste")
			(net "GND")
		)
		(pad "CE35" smd circle
			(at -2.500122 17.370044 180)
			(size 0.450088 0.450088)
			(layers "F.Cu" "F.Mask" "F.Paste")
			(net "GND")
		)
		(pad "CE36" smd circle
			(at -1.560068 17.370044 180)
			(size 0.450088 0.450088)
			(layers "F.Cu" "F.Mask" "F.Paste")
			(net "GND")
		)
		(pad "CE40" smd circle
			(at 1.260094 17.370044 180)
			(size 0.450088 0.450088)
			(layers "F.Cu" "F.Mask" "F.Paste")
			(net "GND")
		)
		(pad "CE41" smd circle
			(at 2.199894 17.370044 180)
			(size 0.450088 0.450088)
			(layers "F.Cu" "F.Mask" "F.Paste")
			(net "GND")
		)
		(pad "CE42" smd circle
			(at 3.139948 17.370044 180)
			(size 0.450088 0.450088)
			(layers "F.Cu" "F.Mask" "F.Paste")
			(net "GND")
		)
		(pad "CE43" smd circle
			(at 4.080002 17.370044 180)
			(size 0.450088 0.450088)
			(layers "F.Cu" "F.Mask" "F.Paste")
			(net "P5E_CPU0_P1_RX_DP<9>")
		)
		(pad "CE44" smd circle
			(at 5.020056 17.370044 180)
			(size 0.450088 0.450088)
			(layers "F.Cu" "F.Mask" "F.Paste")
			(net "P5E_CPU0_P1_RX_DN<9>")
		)
		(pad "CE45" smd circle
			(at 5.96011 17.370044 180)
			(size 0.450088 0.450088)
			(layers "F.Cu" "F.Mask" "F.Paste")
			(net "GND")
		)
		(pad "CE46" smd circle
			(at 6.89991 17.370044 180)
			(size 0.450088 0.450088)
			(layers "F.Cu" "F.Mask" "F.Paste")
			(net "P5E_CPU0_P1_RX_DP<6>")
		)
		(pad "CE47" smd circle
			(at 7.839964 17.370044 180)
			(size 0.450088 0.450088)
			(layers "F.Cu" "F.Mask" "F.Paste")
			(net "P5E_CPU0_P1_RX_DN<6>")
		)
		(pad "CE48" smd circle
			(at 8.780018 17.370044 180)
			(size 0.450088 0.450088)
			(layers "F.Cu" "F.Mask" "F.Paste")
			(net "GND")
		)
		(pad "CE49" smd circle
			(at 9.720072 17.370044 180)
			(size 0.450088 0.450088)
			(layers "F.Cu" "F.Mask" "F.Paste")
			(net "P5E_CPU0_P1_RX_DP<3>")
		)
		(pad "CE50" smd circle
			(at 10.659872 17.370044 180)
			(size 0.450088 0.450088)
			(layers "F.Cu" "F.Mask" "F.Paste")
			(net "P5E_CPU0_P1_RX_DN<3>")
		)
		(pad "CE51" smd circle
			(at 11.599926 17.370044 180)
			(size 0.450088 0.450088)
			(layers "F.Cu" "F.Mask" "F.Paste")
			(net "GND")
		)
		(pad "CE52" smd circle
			(at 12.53998 17.370044 180)
			(size 0.450088 0.450088)
			(layers "F.Cu" "F.Mask" "F.Paste")
			(net "P5E_CPU0_P1_RX_DP<0>")
		)
		(pad "CE53" smd circle
			(at 13.480034 17.370044 180)
			(size 0.450088 0.450088)
			(layers "F.Cu" "F.Mask" "F.Paste")
			(net "P5E_CPU0_P1_RX_DN<0>")
		)
		(pad "CE54" smd circle
			(at 14.420088 17.370044 180)
			(size 0.450088 0.450088)
			(layers "F.Cu" "F.Mask" "F.Paste")
			(net "GND")
		)
		(pad "CE55" smd circle
			(at 15.359888 17.370044 180)
			(size 0.450088 0.450088)
			(layers "F.Cu" "F.Mask" "F.Paste")
			(net "M_C_CPU0_SB_DQS_DN<5>")
		)
		(pad "CE56" smd circle
			(at 16.299942 17.370044 180)
			(size 0.450088 0.450088)
			(layers "F.Cu" "F.Mask" "F.Paste")
			(net "GND")
		)
		(pad "CE57" smd circle
			(at 17.239996 17.370044 180)
			(size 0.450088 0.450088)
			(layers "F.Cu" "F.Mask" "F.Paste")
			(net "M_C_CPU0_SB_DQS_DN<0>")
		)
		(pad "CE58" smd circle
			(at 18.18005 17.370044 180)
			(size 0.450088 0.450088)
			(layers "F.Cu" "F.Mask" "F.Paste")
			(net "GND")
		)
		(pad "CE59" smd circle
			(at 19.120104 17.370044 180)
			(size 0.450088 0.450088)
			(layers "F.Cu" "F.Mask" "F.Paste")
			(net "M_D_CPU0_SB_DQS_DN<5>")
		)
		(pad "CE60" smd circle
			(at 20.059904 17.370044 180)
			(size 0.450088 0.450088)
			(layers "F.Cu" "F.Mask" "F.Paste")
			(net "M_D_CPU0_SB_DQS_DN<0>")
		)
		(pad "CE61" smd circle
			(at 20.999958 17.370044 180)
			(size 0.450088 0.450088)
			(layers "F.Cu" "F.Mask" "F.Paste")
			(net "GND")
		)
		(pad "CE62" smd circle
			(at 21.940012 17.370044 180)
			(size 0.450088 0.450088)
			(layers "F.Cu" "F.Mask" "F.Paste")
			(net "M_B_CPU0_SB_DQS_DN<5>")
		)
		(pad "CE63" smd circle
			(at 22.880066 17.370044 180)
			(size 0.450088 0.450088)
			(layers "F.Cu" "F.Mask" "F.Paste")
			(net "GND")
		)
		(pad "CE64" smd circle
			(at 23.82012 17.370044 180)
			(size 0.450088 0.450088)
			(layers "F.Cu" "F.Mask" "F.Paste")
			(net "M_B_CPU0_SB_DQS_DN<0>")
		)
		(pad "CE65" smd circle
			(at 24.75992 17.370044 180)
			(size 0.450088 0.450088)
			(layers "F.Cu" "F.Mask" "F.Paste")
			(net "GND")
		)
		(pad "CE66" smd circle
			(at 25.699974 17.370044 180)
			(size 0.450088 0.450088)
			(layers "F.Cu" "F.Mask" "F.Paste")
			(net "M_F_CPU0_SB_DQS_DN<5>")
		)
		(pad "CE67" smd circle
			(at 26.640028 17.370044 180)
			(size 0.450088 0.450088)
			(layers "F.Cu" "F.Mask" "F.Paste")
			(net "M_F_CPU0_SB_DQS_DN<0>")
		)
		(pad "CE68" smd circle
			(at 27.580082 17.370044 180)
			(size 0.450088 0.450088)
			(layers "F.Cu" "F.Mask" "F.Paste")
			(net "GND")
		)
		(pad "CE69" smd circle
			(at 28.519882 17.370044 180)
			(size 0.450088 0.450088)
			(layers "F.Cu" "F.Mask" "F.Paste")
			(net "M_E_CPU0_SB_DQS_DN<5>")
		)
		(pad "CE70" smd circle
			(at 29.459936 17.370044 180)
			(size 0.450088 0.450088)
			(layers "F.Cu" "F.Mask" "F.Paste")
			(net "GND")
		)
		(pad "CE71" smd circle
			(at 30.39999 17.370044 180)
			(size 0.450088 0.450088)
			(layers "F.Cu" "F.Mask" "F.Paste")
			(net "M_E_CPU0_SB_DQS_DN<0>")
		)
		(pad "CE72" smd circle
			(at 31.340044 17.370044 180)
			(size 0.450088 0.450088)
			(layers "F.Cu" "F.Mask" "F.Paste")
			(net "GND")
		)
		(pad "CE73" smd circle
			(at 32.280098 17.370044 180)
			(size 0.450088 0.450088)
			(layers "F.Cu" "F.Mask" "F.Paste")
			(net "M_A_CPU0_SB_DQS_DN<5>")
		)
		(pad "CE74" smd circle
			(at 33.219898 17.370044 180)
			(size 0.450088 0.450088)
			(layers "F.Cu" "F.Mask" "F.Paste")
			(net "M_A_CPU0_SB_DQS_DN<0>")
		)
		(pad "CE75" smd circle
			(at 34.159952 17.370044 180)
			(size 0.450088 0.450088)
			(layers "F.Cu" "F.Mask" "F.Paste")
			(net "GND")
		)
		(pad "CF2" smd circle
			(at -33.990026 18.18005 180)
			(size 0.450088 0.450088)
			(layers "F.Cu" "F.Mask" "F.Paste")
			(net "M_G_CPU0_SB_DQ<4>")
		)
		(pad "CF3" smd circle
			(at -33.049972 18.18005 180)
			(size 0.450088 0.450088)
			(layers "F.Cu" "F.Mask" "F.Paste")
			(net "GND")
		)
		(pad "CF4" smd circle
			(at -32.109918 18.18005 180)
			(size 0.450088 0.450088)
			(layers "F.Cu" "F.Mask" "F.Paste")
			(net "M_G_CPU0_SB_DQS_DP<5>")
		)
		(pad "CF5" smd circle
			(at -31.170118 18.18005 180)
			(size 0.450088 0.450088)
			(layers "F.Cu" "F.Mask" "F.Paste")
			(net "GND")
		)
		(pad "CF6" smd circle
			(at -30.230064 18.18005 180)
			(size 0.450088 0.450088)
			(layers "F.Cu" "F.Mask" "F.Paste")
			(net "M_K_CPU0_SB_DQ<4>")
		)
		(pad "CF7" smd circle
			(at -29.29001 18.18005 180)
			(size 0.450088 0.450088)
			(layers "F.Cu" "F.Mask" "F.Paste")
			(net "M_K_CPU0_SB_DQS_DP<5>")
		)
		(pad "CF8" smd circle
			(at -28.349956 18.18005 180)
			(size 0.450088 0.450088)
			(layers "F.Cu" "F.Mask" "F.Paste")
			(net "GND")
		)
		(pad "CF9" smd circle
			(at -27.409902 18.18005 180)
			(size 0.450088 0.450088)
			(layers "F.Cu" "F.Mask" "F.Paste")
			(net "M_L_CPU0_SB_DQ<4>")
		)
		(pad "CF10" smd circle
			(at -26.470102 18.18005 180)
			(size 0.450088 0.450088)
			(layers "F.Cu" "F.Mask" "F.Paste")
			(net "GND")
		)
		(pad "CF11" smd circle
			(at -25.530048 18.18005 180)
			(size 0.450088 0.450088)
			(layers "F.Cu" "F.Mask" "F.Paste")
			(net "M_L_CPU0_SB_DQS_DP<5>")
		)
		(pad "CF12" smd circle
			(at -24.589994 18.18005 180)
			(size 0.450088 0.450088)
			(layers "F.Cu" "F.Mask" "F.Paste")
			(net "GND")
		)
		(pad "CF13" smd circle
			(at -23.64994 18.18005 180)
			(size 0.450088 0.450088)
			(layers "F.Cu" "F.Mask" "F.Paste")
			(net "M_H_CPU0_SB_DQ<4>")
		)
		(pad "CF14" smd circle
			(at -22.709886 18.18005 180)
			(size 0.450088 0.450088)
			(layers "F.Cu" "F.Mask" "F.Paste")
			(net "M_H_CPU0_SB_DQS_DP<5>")
		)
		(pad "CF15" smd circle
			(at -21.770086 18.18005 180)
			(size 0.450088 0.450088)
			(layers "F.Cu" "F.Mask" "F.Paste")
			(net "GND")
		)
		(pad "CF16" smd circle
			(at -20.830032 18.18005 180)
			(size 0.450088 0.450088)
			(layers "F.Cu" "F.Mask" "F.Paste")
			(net "M_J_CPU0_SB_DQ<4>")
		)
		(pad "CF17" smd circle
			(at -19.889978 18.18005 180)
			(size 0.450088 0.450088)
			(layers "F.Cu" "F.Mask" "F.Paste")
			(net "GND")
		)
		(pad "CF18" smd circle
			(at -18.949924 18.18005 180)
			(size 0.450088 0.450088)
			(layers "F.Cu" "F.Mask" "F.Paste")
			(net "M_J_CPU0_SB_DQS_DP<5>")
		)
		(pad "CF19" smd circle
			(at -18.010124 18.18005 180)
			(size 0.450088 0.450088)
			(layers "F.Cu" "F.Mask" "F.Paste")
			(net "GND")
		)
		(pad "CF20" smd circle
			(at -17.07007 18.18005 180)
			(size 0.450088 0.450088)
			(layers "F.Cu" "F.Mask" "F.Paste")
			(net "M_I_CPU0_SB_DQ<4>")
		)
		(pad "CF21" smd circle
			(at -16.130016 18.18005 180)
			(size 0.450088 0.450088)
			(layers "F.Cu" "F.Mask" "F.Paste")
			(net "M_I_CPU0_SB_DQS_DP<5>")
		)
		(pad "CF22" smd circle
			(at -15.189962 18.18005 180)
			(size 0.450088 0.450088)
			(layers "F.Cu" "F.Mask" "F.Paste")
			(net "PVDD11_S3_P0")
		)
		(pad "CF23" smd circle
			(at -14.249908 18.18005 180)
			(size 0.450088 0.450088)
			(layers "F.Cu" "F.Mask" "F.Paste")
			(net "GND")
		)
		(pad "CF24" smd circle
			(at -13.310108 18.18005 180)
			(size 0.450088 0.450088)
			(layers "F.Cu" "F.Mask" "F.Paste")
			(net "GND")
		)
		(pad "CF25" smd circle
			(at -12.370054 18.18005 180)
			(size 0.450088 0.450088)
			(layers "F.Cu" "F.Mask" "F.Paste")
			(net "GND")
		)
		(pad "CF26" smd circle
			(at -11.43 18.18005 180)
			(size 0.450088 0.450088)
			(layers "F.Cu" "F.Mask" "F.Paste")
			(net "GND")
		)
		(pad "CF27" smd circle
			(at -10.489946 18.18005 180)
			(size 0.450088 0.450088)
			(layers "F.Cu" "F.Mask" "F.Paste")
			(net "GND")
		)
		(pad "CF28" smd circle
			(at -9.549892 18.18005 180)
			(size 0.450088 0.450088)
			(layers "F.Cu" "F.Mask" "F.Paste")
			(net "GND")
		)
		(pad "CF29" smd circle
			(at -8.610092 18.18005 180)
			(size 0.450088 0.450088)
			(layers "F.Cu" "F.Mask" "F.Paste")
			(net "GND")
		)
		(pad "CF30" smd circle
			(at -7.670038 18.18005 180)
			(size 0.450088 0.450088)
			(layers "F.Cu" "F.Mask" "F.Paste")
			(net "GND")
		)
		(pad "CF31" smd circle
			(at -6.729984 18.18005 180)
			(size 0.450088 0.450088)
			(layers "F.Cu" "F.Mask" "F.Paste")
			(net "GND")
		)
		(pad "CF32" smd circle
			(at -5.78993 18.18005 180)
			(size 0.450088 0.450088)
			(layers "F.Cu" "F.Mask" "F.Paste")
			(net "GND")
		)
		(pad "CF33" smd circle
			(at -4.849876 18.18005 180)
			(size 0.450088 0.450088)
			(layers "F.Cu" "F.Mask" "F.Paste")
			(net "GND")
		)
		(pad "CF34" smd circle
			(at -3.910076 18.18005 180)
			(size 0.450088 0.450088)
			(layers "F.Cu" "F.Mask" "F.Paste")
			(net "GND")
		)
		(pad "CF35" smd circle
			(at -2.970022 18.18005 180)
			(size 0.450088 0.450088)
			(layers "F.Cu" "F.Mask" "F.Paste")
			(net "P5E_CPU0_P3_TX_DN<1>")
		)
		(pad "CF36" smd circle
			(at -2.029968 18.18005 180)
			(size 0.450088 0.450088)
			(layers "F.Cu" "F.Mask" "F.Paste")
			(net "P5E_CPU0_P3_TX_DP<1>")
		)
		(pad "CF37" smd circle
			(at -1.089914 18.18005 180)
			(size 0.450088 0.450088)
			(layers "F.Cu" "F.Mask" "F.Paste")
			(net "GND")
		)
		(pad "CF39" smd circle
			(at 0.78994 18.18005 180)
			(size 0.450088 0.450088)
			(layers "F.Cu" "F.Mask" "F.Paste")
			(net "GND")
		)
		(pad "CF40" smd circle
			(at 1.729994 18.18005 180)
			(size 0.450088 0.450088)
			(layers "F.Cu" "F.Mask" "F.Paste")
			(net "P5E_CPU0_P1_RX_DP<14>")
		)
		(pad "CF41" smd circle
			(at 2.670048 18.18005 180)
			(size 0.450088 0.450088)
			(layers "F.Cu" "F.Mask" "F.Paste")
			(net "P5E_CPU0_P1_RX_DN<14>")
		)
		(pad "CF42" smd circle
			(at 3.610102 18.18005 180)
			(size 0.450088 0.450088)
			(layers "F.Cu" "F.Mask" "F.Paste")
			(net "GND")
		)
		(pad "CF43" smd circle
			(at 4.549902 18.18005 180)
			(size 0.450088 0.450088)
			(layers "F.Cu" "F.Mask" "F.Paste")
			(net "GND")
		)
		(pad "CF44" smd circle
			(at 5.489956 18.18005 180)
			(size 0.450088 0.450088)
			(layers "F.Cu" "F.Mask" "F.Paste")
			(net "GND")
		)
		(pad "CF45" smd circle
			(at 6.43001 18.18005 180)
			(size 0.450088 0.450088)
			(layers "F.Cu" "F.Mask" "F.Paste")
			(net "GND")
		)
		(pad "CF46" smd circle
			(at 7.370064 18.18005 180)
			(size 0.450088 0.450088)
			(layers "F.Cu" "F.Mask" "F.Paste")
			(net "GND")
		)
		(pad "CF47" smd circle
			(at 8.310118 18.18005 180)
			(size 0.450088 0.450088)
			(layers "F.Cu" "F.Mask" "F.Paste")
			(net "GND")
		)
		(pad "CF48" smd circle
			(at 9.249918 18.18005 180)
			(size 0.450088 0.450088)
			(layers "F.Cu" "F.Mask" "F.Paste")
			(net "GND")
		)
		(pad "CF49" smd circle
			(at 10.189972 18.18005 180)
			(size 0.450088 0.450088)
			(layers "F.Cu" "F.Mask" "F.Paste")
			(net "GND")
		)
		(pad "CF50" smd circle
			(at 11.130026 18.18005 180)
			(size 0.450088 0.450088)
			(layers "F.Cu" "F.Mask" "F.Paste")
			(net "GND")
		)
		(pad "CF51" smd circle
			(at 12.07008 18.18005 180)
			(size 0.450088 0.450088)
			(layers "F.Cu" "F.Mask" "F.Paste")
			(net "GND")
		)
		(pad "CF52" smd circle
			(at 13.00988 18.18005 180)
			(size 0.450088 0.450088)
			(layers "F.Cu" "F.Mask" "F.Paste")
			(net "GND")
		)
		(pad "CF53" smd circle
			(at 13.949934 18.18005 180)
			(size 0.450088 0.450088)
			(layers "F.Cu" "F.Mask" "F.Paste")
			(net "GND")
		)
		(pad "CF54" smd circle
			(at 14.889988 18.18005 180)
			(size 0.450088 0.450088)
			(layers "F.Cu" "F.Mask" "F.Paste")
			(net "PVDDIO_P0")
		)
		(pad "CF55" smd circle
			(at 15.830042 18.18005 180)
			(size 0.450088 0.450088)
			(layers "F.Cu" "F.Mask" "F.Paste")
			(net "M_C_CPU0_SB_DQS_DP<5>")
		)
		(pad "CF56" smd circle
			(at 16.770096 18.18005 180)
			(size 0.450088 0.450088)
			(layers "F.Cu" "F.Mask" "F.Paste")
			(net "M_C_CPU0_SB_DQ<4>")
		)
		(pad "CF57" smd circle
			(at 17.709896 18.18005 180)
			(size 0.450088 0.450088)
			(layers "F.Cu" "F.Mask" "F.Paste")
			(net "GND")
		)
		(pad "CF58" smd circle
			(at 18.64995 18.18005 180)
			(size 0.450088 0.450088)
			(layers "F.Cu" "F.Mask" "F.Paste")
			(net "M_D_CPU0_SB_DQS_DP<5>")
		)
		(pad "CF59" smd circle
			(at 19.590004 18.18005 180)
			(size 0.450088 0.450088)
			(layers "F.Cu" "F.Mask" "F.Paste")
			(net "GND")
		)
		(pad "CF60" smd circle
			(at 20.530058 18.18005 180)
			(size 0.450088 0.450088)
			(layers "F.Cu" "F.Mask" "F.Paste")
			(net "M_D_CPU0_SB_DQ<4>")
		)
		(pad "CF61" smd circle
			(at 21.470112 18.18005 180)
			(size 0.450088 0.450088)
			(layers "F.Cu" "F.Mask" "F.Paste")
			(net "GND")
		)
		(pad "CF62" smd circle
			(at 22.409912 18.18005 180)
			(size 0.450088 0.450088)
			(layers "F.Cu" "F.Mask" "F.Paste")
			(net "M_B_CPU0_SB_DQS_DP<5>")
		)
		(pad "CF63" smd circle
			(at 23.349966 18.18005 180)
			(size 0.450088 0.450088)
			(layers "F.Cu" "F.Mask" "F.Paste")
			(net "M_B_CPU0_SB_DQ<4>")
		)
		(pad "CF64" smd circle
			(at 24.29002 18.18005 180)
			(size 0.450088 0.450088)
			(layers "F.Cu" "F.Mask" "F.Paste")
			(net "GND")
		)
		(pad "CF65" smd circle
			(at 25.230074 18.18005 180)
			(size 0.450088 0.450088)
			(layers "F.Cu" "F.Mask" "F.Paste")
			(net "M_F_CPU0_SB_DQS_DP<5>")
		)
		(pad "CF66" smd circle
			(at 26.170128 18.18005 180)
			(size 0.450088 0.450088)
			(layers "F.Cu" "F.Mask" "F.Paste")
			(net "GND")
		)
		(pad "CF67" smd circle
			(at 27.109928 18.18005 180)
			(size 0.450088 0.450088)
			(layers "F.Cu" "F.Mask" "F.Paste")
			(net "M_F_CPU0_SB_DQ<4>")
		)
		(pad "CF68" smd circle
			(at 28.049982 18.18005 180)
			(size 0.450088 0.450088)
			(layers "F.Cu" "F.Mask" "F.Paste")
			(net "GND")
		)
		(pad "CF69" smd circle
			(at 28.990036 18.18005 180)
			(size 0.450088 0.450088)
			(layers "F.Cu" "F.Mask" "F.Paste")
			(net "M_E_CPU0_SB_DQS_DP<5>")
		)
		(pad "CF70" smd circle
			(at 29.93009 18.18005 180)
			(size 0.450088 0.450088)
			(layers "F.Cu" "F.Mask" "F.Paste")
			(net "M_E_CPU0_SB_DQ<4>")
		)
		(pad "CF71" smd circle
			(at 30.86989 18.18005 180)
			(size 0.450088 0.450088)
			(layers "F.Cu" "F.Mask" "F.Paste")
			(net "GND")
		)
		(pad "CF72" smd circle
			(at 31.809944 18.18005 180)
			(size 0.450088 0.450088)
			(layers "F.Cu" "F.Mask" "F.Paste")
			(net "M_A_CPU0_SB_DQS_DP<5>")
		)
		(pad "CF73" smd circle
			(at 32.749998 18.18005 180)
			(size 0.450088 0.450088)
			(layers "F.Cu" "F.Mask" "F.Paste")
			(net "GND")
		)
		(pad "CF74" smd circle
			(at 33.690052 18.18005 180)
			(size 0.450088 0.450088)
			(layers "F.Cu" "F.Mask" "F.Paste")
			(net "M_A_CPU0_SB_DQ<4>")
		)
		(pad "CG1" smd circle
			(at -34.459926 18.990056 180)
			(size 0.450088 0.450088)
			(layers "F.Cu" "F.Mask" "F.Paste")
			(net "GND")
		)
		(pad "CG2" smd circle
			(at -33.519872 18.990056 180)
			(size 0.450088 0.450088)
			(layers "F.Cu" "F.Mask" "F.Paste")
			(net "M_G_CPU0_SB_DQ<6>")
		)
		(pad "CG3" smd circle
			(at -32.580072 18.990056 180)
			(size 0.450088 0.450088)
			(layers "F.Cu" "F.Mask" "F.Paste")
			(net "M_G_CPU0_SB_DQ<5>")
		)
		(pad "CG4" smd circle
			(at -31.640018 18.990056 180)
			(size 0.450088 0.450088)
			(layers "F.Cu" "F.Mask" "F.Paste")
			(net "PVDD11_S3_P0")
		)
		(pad "CG5" smd circle
			(at -30.699964 18.990056 180)
			(size 0.450088 0.450088)
			(layers "F.Cu" "F.Mask" "F.Paste")
			(net "M_K_CPU0_SB_DQ<6>")
		)
		(pad "CG6" smd circle
			(at -29.75991 18.990056 180)
			(size 0.450088 0.450088)
			(layers "F.Cu" "F.Mask" "F.Paste")
			(net "GND")
		)
		(pad "CG7" smd circle
			(at -28.82011 18.990056 180)
			(size 0.450088 0.450088)
			(layers "F.Cu" "F.Mask" "F.Paste")
			(net "M_K_CPU0_SB_DQ<5>")
		)
		(pad "CG8" smd circle
			(at -27.880056 18.990056 180)
			(size 0.450088 0.450088)
			(layers "F.Cu" "F.Mask" "F.Paste")
			(net "GND")
		)
		(pad "CG9" smd circle
			(at -26.940002 18.990056 180)
			(size 0.450088 0.450088)
			(layers "F.Cu" "F.Mask" "F.Paste")
			(net "M_L_CPU0_SB_DQ<6>")
		)
		(pad "CG10" smd circle
			(at -25.999948 18.990056 180)
			(size 0.450088 0.450088)
			(layers "F.Cu" "F.Mask" "F.Paste")
			(net "M_L_CPU0_SB_DQ<5>")
		)
		(pad "CG11" smd circle
			(at -25.059894 18.990056 180)
			(size 0.450088 0.450088)
			(layers "F.Cu" "F.Mask" "F.Paste")
			(net "PVDD11_S3_P0")
		)
		(pad "CG12" smd circle
			(at -24.120094 18.990056 180)
			(size 0.450088 0.450088)
			(layers "F.Cu" "F.Mask" "F.Paste")
			(net "M_H_CPU0_SB_DQ<6>")
		)
		(pad "CG13" smd circle
			(at -23.18004 18.990056 180)
			(size 0.450088 0.450088)
			(layers "F.Cu" "F.Mask" "F.Paste")
			(net "GND")
		)
		(pad "CG14" smd circle
			(at -22.239986 18.990056 180)
			(size 0.450088 0.450088)
			(layers "F.Cu" "F.Mask" "F.Paste")
			(net "M_H_CPU0_SB_DQ<5>")
		)
		(pad "CG15" smd circle
			(at -21.299932 18.990056 180)
			(size 0.450088 0.450088)
			(layers "F.Cu" "F.Mask" "F.Paste")
			(net "GND")
		)
		(pad "CG16" smd circle
			(at -20.359878 18.990056 180)
			(size 0.450088 0.450088)
			(layers "F.Cu" "F.Mask" "F.Paste")
			(net "M_J_CPU0_SB_DQ<6>")
		)
		(pad "CG17" smd circle
			(at -19.420078 18.990056 180)
			(size 0.450088 0.450088)
			(layers "F.Cu" "F.Mask" "F.Paste")
			(net "M_J_CPU0_SB_DQ<5>")
		)
		(pad "CG18" smd circle
			(at -18.480024 18.990056 180)
			(size 0.450088 0.450088)
			(layers "F.Cu" "F.Mask" "F.Paste")
			(net "PVDD11_S3_P0")
		)
		(pad "CG19" smd circle
			(at -17.53997 18.990056 180)
			(size 0.450088 0.450088)
			(layers "F.Cu" "F.Mask" "F.Paste")
			(net "M_I_CPU0_SB_DQ<6>")
		)
		(pad "CG20" smd circle
			(at -16.599916 18.990056 180)
			(size 0.450088 0.450088)
			(layers "F.Cu" "F.Mask" "F.Paste")
			(net "GND")
		)
		(pad "CG21" smd circle
			(at -15.660116 18.990056 180)
			(size 0.450088 0.450088)
			(layers "F.Cu" "F.Mask" "F.Paste")
			(net "M_I_CPU0_SB_DQ<5>")
		)
		(pad "CG22" smd circle
			(at -14.720062 18.990056 180)
			(size 0.450088 0.450088)
			(layers "F.Cu" "F.Mask" "F.Paste")
			(net "GND")
		)
		(pad "CG23" smd circle
			(at -13.780008 18.990056 180)
			(size 0.450088 0.450088)
			(layers "F.Cu" "F.Mask" "F.Paste")
			(net "P5E_CPU0_P3_TX_DN<14>")
		)
		(pad "CG24" smd circle
			(at -12.839954 18.990056 180)
			(size 0.450088 0.450088)
			(layers "F.Cu" "F.Mask" "F.Paste")
			(net "P5E_CPU0_P3_TX_DP<14>")
		)
		(pad "CG25" smd circle
			(at -11.8999 18.990056 180)
			(size 0.450088 0.450088)
			(layers "F.Cu" "F.Mask" "F.Paste")
			(net "GND")
		)
		(pad "CG26" smd circle
			(at -10.9601 18.990056 180)
			(size 0.450088 0.450088)
			(layers "F.Cu" "F.Mask" "F.Paste")
			(net "P5E_CPU0_P3_TX_DN<11>")
		)
		(pad "CG27" smd circle
			(at -10.020046 18.990056 180)
			(size 0.450088 0.450088)
			(layers "F.Cu" "F.Mask" "F.Paste")
			(net "P5E_CPU0_P3_TX_DP<11>")
		)
		(pad "CG28" smd circle
			(at -9.079992 18.990056 180)
			(size 0.450088 0.450088)
			(layers "F.Cu" "F.Mask" "F.Paste")
			(net "GND")
		)
		(pad "CG29" smd circle
			(at -8.139938 18.990056 180)
			(size 0.450088 0.450088)
			(layers "F.Cu" "F.Mask" "F.Paste")
			(net "P5E_CPU0_P3_TX_DN<8>")
		)
		(pad "CG30" smd circle
			(at -7.199884 18.990056 180)
			(size 0.450088 0.450088)
			(layers "F.Cu" "F.Mask" "F.Paste")
			(net "P5E_CPU0_P3_TX_DP<8>")
		)
		(pad "CG31" smd circle
			(at -6.260084 18.990056 180)
			(size 0.450088 0.450088)
			(layers "F.Cu" "F.Mask" "F.Paste")
			(net "GND")
		)
		(pad "CG32" smd circle
			(at -5.32003 18.990056 180)
			(size 0.450088 0.450088)
			(layers "F.Cu" "F.Mask" "F.Paste")
			(net "P5E_CPU0_P3_TX_DN<5>")
		)
		(pad "CG33" smd circle
			(at -4.379976 18.990056 180)
			(size 0.450088 0.450088)
			(layers "F.Cu" "F.Mask" "F.Paste")
			(net "P5E_CPU0_P3_TX_DP<5>")
		)
		(pad "CG34" smd circle
			(at -3.439922 18.990056 180)
			(size 0.450088 0.450088)
			(layers "F.Cu" "F.Mask" "F.Paste")
			(net "GND")
		)
		(pad "CG35" smd circle
			(at -2.500122 18.990056 180)
			(size 0.450088 0.450088)
			(layers "F.Cu" "F.Mask" "F.Paste")
			(net "PVDDCR_CPU1_P0")
		)
		(pad "CG36" smd circle
			(at -1.560068 18.990056 180)
			(size 0.450088 0.450088)
			(layers "F.Cu" "F.Mask" "F.Paste")
			(net "PVDDCR_CPU1_P0")
		)
		(pad "CG40" smd circle
			(at 1.260094 18.990056 180)
			(size 0.450088 0.450088)
			(layers "F.Cu" "F.Mask" "F.Paste")
			(net "PVDDCR_CPU1_P0")
		)
		(pad "CG41" smd circle
			(at 2.199894 18.990056 180)
			(size 0.450088 0.450088)
			(layers "F.Cu" "F.Mask" "F.Paste")
			(net "PVDDCR_CPU1_P0")
		)
		(pad "CG42" smd circle
			(at 3.139948 18.990056 180)
			(size 0.450088 0.450088)
			(layers "F.Cu" "F.Mask" "F.Paste")
			(net "GND")
		)
		(pad "CG43" smd circle
			(at 4.080002 18.990056 180)
			(size 0.450088 0.450088)
			(layers "F.Cu" "F.Mask" "F.Paste")
			(net "P5E_CPU0_P1_RX_DP<10>")
		)
		(pad "CG44" smd circle
			(at 5.020056 18.990056 180)
			(size 0.450088 0.450088)
			(layers "F.Cu" "F.Mask" "F.Paste")
			(net "P5E_CPU0_P1_RX_DN<10>")
		)
		(pad "CG45" smd circle
			(at 5.96011 18.990056 180)
			(size 0.450088 0.450088)
			(layers "F.Cu" "F.Mask" "F.Paste")
			(net "GND")
		)
		(pad "CG46" smd circle
			(at 6.89991 18.990056 180)
			(size 0.450088 0.450088)
			(layers "F.Cu" "F.Mask" "F.Paste")
			(net "P5E_CPU0_P1_RX_DP<7>")
		)
		(pad "CG47" smd circle
			(at 7.839964 18.990056 180)
			(size 0.450088 0.450088)
			(layers "F.Cu" "F.Mask" "F.Paste")
			(net "P5E_CPU0_P1_RX_DN<7>")
		)
		(pad "CG48" smd circle
			(at 8.780018 18.990056 180)
			(size 0.450088 0.450088)
			(layers "F.Cu" "F.Mask" "F.Paste")
			(net "GND")
		)
		(pad "CG49" smd circle
			(at 9.720072 18.990056 180)
			(size 0.450088 0.450088)
			(layers "F.Cu" "F.Mask" "F.Paste")
			(net "P5E_CPU0_P1_RX_DP<4>")
		)
		(pad "CG50" smd circle
			(at 10.659872 18.990056 180)
			(size 0.450088 0.450088)
			(layers "F.Cu" "F.Mask" "F.Paste")
			(net "P5E_CPU0_P1_RX_DN<4>")
		)
		(pad "CG51" smd circle
			(at 11.599926 18.990056 180)
			(size 0.450088 0.450088)
			(layers "F.Cu" "F.Mask" "F.Paste")
			(net "GND")
		)
		(pad "CG52" smd circle
			(at 12.53998 18.990056 180)
			(size 0.450088 0.450088)
			(layers "F.Cu" "F.Mask" "F.Paste")
			(net "P5E_CPU0_P1_RX_DP<1>")
		)
		(pad "CG53" smd circle
			(at 13.480034 18.990056 180)
			(size 0.450088 0.450088)
			(layers "F.Cu" "F.Mask" "F.Paste")
			(net "P5E_CPU0_P1_RX_DN<1>")
		)
		(pad "CG54" smd circle
			(at 14.420088 18.990056 180)
			(size 0.450088 0.450088)
			(layers "F.Cu" "F.Mask" "F.Paste")
			(net "GND")
		)
		(pad "CG55" smd circle
			(at 15.359888 18.990056 180)
			(size 0.450088 0.450088)
			(layers "F.Cu" "F.Mask" "F.Paste")
			(net "M_C_CPU0_SB_DQ<5>")
		)
		(pad "CG56" smd circle
			(at 16.299942 18.990056 180)
			(size 0.450088 0.450088)
			(layers "F.Cu" "F.Mask" "F.Paste")
			(net "GND")
		)
		(pad "CG57" smd circle
			(at 17.239996 18.990056 180)
			(size 0.450088 0.450088)
			(layers "F.Cu" "F.Mask" "F.Paste")
			(net "M_C_CPU0_SB_DQ<6>")
		)
		(pad "CG58" smd circle
			(at 18.18005 18.990056 180)
			(size 0.450088 0.450088)
			(layers "F.Cu" "F.Mask" "F.Paste")
			(net "PVDDIO_P0")
		)
		(pad "CG59" smd circle
			(at 19.120104 18.990056 180)
			(size 0.450088 0.450088)
			(layers "F.Cu" "F.Mask" "F.Paste")
			(net "M_D_CPU0_SB_DQ<5>")
		)
		(pad "CG60" smd circle
			(at 20.059904 18.990056 180)
			(size 0.450088 0.450088)
			(layers "F.Cu" "F.Mask" "F.Paste")
			(net "M_D_CPU0_SB_DQ<6>")
		)
		(pad "CG61" smd circle
			(at 20.999958 18.990056 180)
			(size 0.450088 0.450088)
			(layers "F.Cu" "F.Mask" "F.Paste")
			(net "GND")
		)
		(pad "CG62" smd circle
			(at 21.940012 18.990056 180)
			(size 0.450088 0.450088)
			(layers "F.Cu" "F.Mask" "F.Paste")
			(net "M_B_CPU0_SB_DQ<5>")
		)
		(pad "CG63" smd circle
			(at 22.880066 18.990056 180)
			(size 0.450088 0.450088)
			(layers "F.Cu" "F.Mask" "F.Paste")
			(net "GND")
		)
		(pad "CG64" smd circle
			(at 23.82012 18.990056 180)
			(size 0.450088 0.450088)
			(layers "F.Cu" "F.Mask" "F.Paste")
			(net "M_B_CPU0_SB_DQ<6>")
		)
		(pad "CG65" smd circle
			(at 24.75992 18.990056 180)
			(size 0.450088 0.450088)
			(layers "F.Cu" "F.Mask" "F.Paste")
			(net "PVDDIO_P0")
		)
		(pad "CG66" smd circle
			(at 25.699974 18.990056 180)
			(size 0.450088 0.450088)
			(layers "F.Cu" "F.Mask" "F.Paste")
			(net "M_F_CPU0_SB_DQ<5>")
		)
		(pad "CG67" smd circle
			(at 26.640028 18.990056 180)
			(size 0.450088 0.450088)
			(layers "F.Cu" "F.Mask" "F.Paste")
			(net "M_F_CPU0_SB_DQ<6>")
		)
		(pad "CG68" smd circle
			(at 27.580082 18.990056 180)
			(size 0.450088 0.450088)
			(layers "F.Cu" "F.Mask" "F.Paste")
			(net "GND")
		)
		(pad "CG69" smd circle
			(at 28.519882 18.990056 180)
			(size 0.450088 0.450088)
			(layers "F.Cu" "F.Mask" "F.Paste")
			(net "M_E_CPU0_SB_DQ<5>")
		)
		(pad "CG70" smd circle
			(at 29.459936 18.990056 180)
			(size 0.450088 0.450088)
			(layers "F.Cu" "F.Mask" "F.Paste")
			(net "GND")
		)
		(pad "CG71" smd circle
			(at 30.39999 18.990056 180)
			(size 0.450088 0.450088)
			(layers "F.Cu" "F.Mask" "F.Paste")
			(net "M_E_CPU0_SB_DQ<6>")
		)
		(pad "CG72" smd circle
			(at 31.340044 18.990056 180)
			(size 0.450088 0.450088)
			(layers "F.Cu" "F.Mask" "F.Paste")
			(net "PVDDIO_P0")
		)
		(pad "CG73" smd circle
			(at 32.280098 18.990056 180)
			(size 0.450088 0.450088)
			(layers "F.Cu" "F.Mask" "F.Paste")
			(net "M_A_CPU0_SB_DQ<5>")
		)
		(pad "CG74" smd circle
			(at 33.219898 18.990056 180)
			(size 0.450088 0.450088)
			(layers "F.Cu" "F.Mask" "F.Paste")
			(net "M_A_CPU0_SB_DQ<6>")
		)
		(pad "CG75" smd circle
			(at 34.159952 18.990056 180)
			(size 0.450088 0.450088)
			(layers "F.Cu" "F.Mask" "F.Paste")
			(net "GND")
		)
		(pad "CH2" smd circle
			(at -33.990026 19.800062 180)
			(size 0.450088 0.450088)
			(layers "F.Cu" "F.Mask" "F.Paste")
			(net "M_G_CPU0_SB_DQ<8>")
		)
		(pad "CH3" smd circle
			(at -33.049972 19.800062 180)
			(size 0.450088 0.450088)
			(layers "F.Cu" "F.Mask" "F.Paste")
			(net "GND")
		)
		(pad "CH4" smd circle
			(at -32.109918 19.800062 180)
			(size 0.450088 0.450088)
			(layers "F.Cu" "F.Mask" "F.Paste")
			(net "M_G_CPU0_SB_DQ<7>")
		)
		(pad "CH5" smd circle
			(at -31.170118 19.800062 180)
			(size 0.450088 0.450088)
			(layers "F.Cu" "F.Mask" "F.Paste")
			(net "GND")
		)
		(pad "CH6" smd circle
			(at -30.230064 19.800062 180)
			(size 0.450088 0.450088)
			(layers "F.Cu" "F.Mask" "F.Paste")
			(net "M_K_CPU0_SB_DQ<8>")
		)
		(pad "CH7" smd circle
			(at -29.29001 19.800062 180)
			(size 0.450088 0.450088)
			(layers "F.Cu" "F.Mask" "F.Paste")
			(net "M_K_CPU0_SB_DQ<7>")
		)
		(pad "CH8" smd circle
			(at -28.349956 19.800062 180)
			(size 0.450088 0.450088)
			(layers "F.Cu" "F.Mask" "F.Paste")
			(net "GND")
		)
		(pad "CH9" smd circle
			(at -27.409902 19.800062 180)
			(size 0.450088 0.450088)
			(layers "F.Cu" "F.Mask" "F.Paste")
			(net "M_L_CPU0_SB_DQ<8>")
		)
		(pad "CH10" smd circle
			(at -26.470102 19.800062 180)
			(size 0.450088 0.450088)
			(layers "F.Cu" "F.Mask" "F.Paste")
			(net "GND")
		)
		(pad "CH11" smd circle
			(at -25.530048 19.800062 180)
			(size 0.450088 0.450088)
			(layers "F.Cu" "F.Mask" "F.Paste")
			(net "M_L_CPU0_SB_DQ<7>")
		)
		(pad "CH12" smd circle
			(at -24.589994 19.800062 180)
			(size 0.450088 0.450088)
			(layers "F.Cu" "F.Mask" "F.Paste")
			(net "GND")
		)
		(pad "CH13" smd circle
			(at -23.64994 19.800062 180)
			(size 0.450088 0.450088)
			(layers "F.Cu" "F.Mask" "F.Paste")
			(net "M_H_CPU0_SB_DQ<8>")
		)
		(pad "CH14" smd circle
			(at -22.709886 19.800062 180)
			(size 0.450088 0.450088)
			(layers "F.Cu" "F.Mask" "F.Paste")
			(net "M_H_CPU0_SB_DQ<7>")
		)
		(pad "CH15" smd circle
			(at -21.770086 19.800062 180)
			(size 0.450088 0.450088)
			(layers "F.Cu" "F.Mask" "F.Paste")
			(net "GND")
		)
		(pad "CH16" smd circle
			(at -20.830032 19.800062 180)
			(size 0.450088 0.450088)
			(layers "F.Cu" "F.Mask" "F.Paste")
			(net "M_J_CPU0_SB_DQ<8>")
		)
		(pad "CH17" smd circle
			(at -19.889978 19.800062 180)
			(size 0.450088 0.450088)
			(layers "F.Cu" "F.Mask" "F.Paste")
			(net "GND")
		)
		(pad "CH18" smd circle
			(at -18.949924 19.800062 180)
			(size 0.450088 0.450088)
			(layers "F.Cu" "F.Mask" "F.Paste")
			(net "M_J_CPU0_SB_DQ<7>")
		)
		(pad "CH19" smd circle
			(at -18.010124 19.800062 180)
			(size 0.450088 0.450088)
			(layers "F.Cu" "F.Mask" "F.Paste")
			(net "GND")
		)
		(pad "CH20" smd circle
			(at -17.07007 19.800062 180)
			(size 0.450088 0.450088)
			(layers "F.Cu" "F.Mask" "F.Paste")
			(net "M_I_CPU0_SB_DQ<8>")
		)
		(pad "CH21" smd circle
			(at -16.130016 19.800062 180)
			(size 0.450088 0.450088)
			(layers "F.Cu" "F.Mask" "F.Paste")
			(net "M_I_CPU0_SB_DQ<7>")
		)
		(pad "CH22" smd circle
			(at -15.189962 19.800062 180)
			(size 0.450088 0.450088)
			(layers "F.Cu" "F.Mask" "F.Paste")
			(net "GND")
		)
		(pad "CH23" smd circle
			(at -14.249908 19.800062 180)
			(size 0.450088 0.450088)
			(layers "F.Cu" "F.Mask" "F.Paste")
			(net "PVDDCR_CPU1_P0")
		)
		(pad "CH24" smd circle
			(at -13.310108 19.800062 180)
			(size 0.450088 0.450088)
			(layers "F.Cu" "F.Mask" "F.Paste")
			(net "PVDDCR_CPU1_P0")
		)
		(pad "CH25" smd circle
			(at -12.370054 19.800062 180)
			(size 0.450088 0.450088)
			(layers "F.Cu" "F.Mask" "F.Paste")
			(net "GND")
		)
		(pad "CH26" smd circle
			(at -11.43 19.800062 180)
			(size 0.450088 0.450088)
			(layers "F.Cu" "F.Mask" "F.Paste")
			(net "PVDDCR_CPU1_P0")
		)
		(pad "CH27" smd circle
			(at -10.489946 19.800062 180)
			(size 0.450088 0.450088)
			(layers "F.Cu" "F.Mask" "F.Paste")
			(net "PVDDCR_CPU1_P0")
		)
		(pad "CH28" smd circle
			(at -9.549892 19.800062 180)
			(size 0.450088 0.450088)
			(layers "F.Cu" "F.Mask" "F.Paste")
			(net "GND")
		)
		(pad "CH29" smd circle
			(at -8.610092 19.800062 180)
			(size 0.450088 0.450088)
			(layers "F.Cu" "F.Mask" "F.Paste")
			(net "PVDDCR_CPU1_P0")
		)
		(pad "CH30" smd circle
			(at -7.670038 19.800062 180)
			(size 0.450088 0.450088)
			(layers "F.Cu" "F.Mask" "F.Paste")
			(net "PVDDCR_CPU1_P0")
		)
		(pad "CH31" smd circle
			(at -6.729984 19.800062 180)
			(size 0.450088 0.450088)
			(layers "F.Cu" "F.Mask" "F.Paste")
			(net "GND")
		)
		(pad "CH32" smd circle
			(at -5.78993 19.800062 180)
			(size 0.450088 0.450088)
			(layers "F.Cu" "F.Mask" "F.Paste")
			(net "PVDDCR_CPU1_P0")
		)
		(pad "CH33" smd circle
			(at -4.849876 19.800062 180)
			(size 0.450088 0.450088)
			(layers "F.Cu" "F.Mask" "F.Paste")
			(net "PVDDCR_CPU1_P0")
		)
		(pad "CH34" smd circle
			(at -3.910076 19.800062 180)
			(size 0.450088 0.450088)
			(layers "F.Cu" "F.Mask" "F.Paste")
			(net "GND")
		)
		(pad "CH35" smd circle
			(at -2.970022 19.800062 180)
			(size 0.450088 0.450088)
			(layers "F.Cu" "F.Mask" "F.Paste")
			(net "P5E_CPU0_P3_TX_DN<2>")
		)
		(pad "CH36" smd circle
			(at -2.029968 19.800062 180)
			(size 0.450088 0.450088)
			(layers "F.Cu" "F.Mask" "F.Paste")
			(net "P5E_CPU0_P3_TX_DP<2>")
		)
		(pad "CH37" smd circle
			(at -1.089914 19.800062 180)
			(size 0.450088 0.450088)
			(layers "F.Cu" "F.Mask" "F.Paste")
			(net "GND")
		)
		(pad "CH39" smd circle
			(at 0.78994 19.800062 180)
			(size 0.450088 0.450088)
			(layers "F.Cu" "F.Mask" "F.Paste")
			(net "GND")
		)
		(pad "CH40" smd circle
			(at 1.729994 19.800062 180)
			(size 0.450088 0.450088)
			(layers "F.Cu" "F.Mask" "F.Paste")
			(net "P5E_CPU0_P1_RX_DP<13>")
		)
		(pad "CH41" smd circle
			(at 2.670048 19.800062 180)
			(size 0.450088 0.450088)
			(layers "F.Cu" "F.Mask" "F.Paste")
			(net "P5E_CPU0_P1_RX_DN<13>")
		)
		(pad "CH42" smd circle
			(at 3.610102 19.800062 180)
			(size 0.450088 0.450088)
			(layers "F.Cu" "F.Mask" "F.Paste")
			(net "GND")
		)
		(pad "CH43" smd circle
			(at 4.549902 19.800062 180)
			(size 0.450088 0.450088)
			(layers "F.Cu" "F.Mask" "F.Paste")
			(net "PVDDCR_CPU1_P0")
		)
		(pad "CH44" smd circle
			(at 5.489956 19.800062 180)
			(size 0.450088 0.450088)
			(layers "F.Cu" "F.Mask" "F.Paste")
			(net "PVDDCR_CPU1_P0")
		)
		(pad "CH45" smd circle
			(at 6.43001 19.800062 180)
			(size 0.450088 0.450088)
			(layers "F.Cu" "F.Mask" "F.Paste")
			(net "GND")
		)
		(pad "CH46" smd circle
			(at 7.370064 19.800062 180)
			(size 0.450088 0.450088)
			(layers "F.Cu" "F.Mask" "F.Paste")
			(net "PVDDCR_CPU1_P0")
		)
		(pad "CH47" smd circle
			(at 8.310118 19.800062 180)
			(size 0.450088 0.450088)
			(layers "F.Cu" "F.Mask" "F.Paste")
			(net "PVDDCR_CPU1_P0")
		)
		(pad "CH48" smd circle
			(at 9.249918 19.800062 180)
			(size 0.450088 0.450088)
			(layers "F.Cu" "F.Mask" "F.Paste")
			(net "GND")
		)
		(pad "CH49" smd circle
			(at 10.189972 19.800062 180)
			(size 0.450088 0.450088)
			(layers "F.Cu" "F.Mask" "F.Paste")
			(net "PVDDCR_CPU1_P0")
		)
		(pad "CH50" smd circle
			(at 11.130026 19.800062 180)
			(size 0.450088 0.450088)
			(layers "F.Cu" "F.Mask" "F.Paste")
			(net "PVDDCR_CPU1_P0")
		)
		(pad "CH51" smd circle
			(at 12.07008 19.800062 180)
			(size 0.450088 0.450088)
			(layers "F.Cu" "F.Mask" "F.Paste")
			(net "GND")
		)
		(pad "CH52" smd circle
			(at 13.00988 19.800062 180)
			(size 0.450088 0.450088)
			(layers "F.Cu" "F.Mask" "F.Paste")
			(net "PVDDCR_CPU1_P0")
		)
		(pad "CH53" smd circle
			(at 13.949934 19.800062 180)
			(size 0.450088 0.450088)
			(layers "F.Cu" "F.Mask" "F.Paste")
			(net "PVDDCR_CPU1_P0")
		)
		(pad "CH54" smd circle
			(at 14.889988 19.800062 180)
			(size 0.450088 0.450088)
			(layers "F.Cu" "F.Mask" "F.Paste")
			(net "GND")
		)
		(pad "CH55" smd circle
			(at 15.830042 19.800062 180)
			(size 0.450088 0.450088)
			(layers "F.Cu" "F.Mask" "F.Paste")
			(net "M_C_CPU0_SB_DQ<7>")
		)
		(pad "CH56" smd circle
			(at 16.770096 19.800062 180)
			(size 0.450088 0.450088)
			(layers "F.Cu" "F.Mask" "F.Paste")
			(net "M_C_CPU0_SB_DQ<8>")
		)
		(pad "CH57" smd circle
			(at 17.709896 19.800062 180)
			(size 0.450088 0.450088)
			(layers "F.Cu" "F.Mask" "F.Paste")
			(net "GND")
		)
		(pad "CH58" smd circle
			(at 18.64995 19.800062 180)
			(size 0.450088 0.450088)
			(layers "F.Cu" "F.Mask" "F.Paste")
			(net "M_D_CPU0_SB_DQ<7>")
		)
		(pad "CH59" smd circle
			(at 19.590004 19.800062 180)
			(size 0.450088 0.450088)
			(layers "F.Cu" "F.Mask" "F.Paste")
			(net "GND")
		)
		(pad "CH60" smd circle
			(at 20.530058 19.800062 180)
			(size 0.450088 0.450088)
			(layers "F.Cu" "F.Mask" "F.Paste")
			(net "M_D_CPU0_SB_DQ<8>")
		)
		(pad "CH61" smd circle
			(at 21.470112 19.800062 180)
			(size 0.450088 0.450088)
			(layers "F.Cu" "F.Mask" "F.Paste")
			(net "GND")
		)
		(pad "CH62" smd circle
			(at 22.409912 19.800062 180)
			(size 0.450088 0.450088)
			(layers "F.Cu" "F.Mask" "F.Paste")
			(net "M_B_CPU0_SB_DQ<7>")
		)
		(pad "CH63" smd circle
			(at 23.349966 19.800062 180)
			(size 0.450088 0.450088)
			(layers "F.Cu" "F.Mask" "F.Paste")
			(net "M_B_CPU0_SB_DQ<8>")
		)
		(pad "CH64" smd circle
			(at 24.29002 19.800062 180)
			(size 0.450088 0.450088)
			(layers "F.Cu" "F.Mask" "F.Paste")
			(net "GND")
		)
		(pad "CH65" smd circle
			(at 25.230074 19.800062 180)
			(size 0.450088 0.450088)
			(layers "F.Cu" "F.Mask" "F.Paste")
			(net "M_F_CPU0_SB_DQ<7>")
		)
		(pad "CH66" smd circle
			(at 26.170128 19.800062 180)
			(size 0.450088 0.450088)
			(layers "F.Cu" "F.Mask" "F.Paste")
			(net "GND")
		)
		(pad "CH67" smd circle
			(at 27.109928 19.800062 180)
			(size 0.450088 0.450088)
			(layers "F.Cu" "F.Mask" "F.Paste")
			(net "M_F_CPU0_SB_DQ<8>")
		)
		(pad "CH68" smd circle
			(at 28.049982 19.800062 180)
			(size 0.450088 0.450088)
			(layers "F.Cu" "F.Mask" "F.Paste")
			(net "GND")
		)
		(pad "CH69" smd circle
			(at 28.990036 19.800062 180)
			(size 0.450088 0.450088)
			(layers "F.Cu" "F.Mask" "F.Paste")
			(net "M_E_CPU0_SB_DQ<7>")
		)
		(pad "CH70" smd circle
			(at 29.93009 19.800062 180)
			(size 0.450088 0.450088)
			(layers "F.Cu" "F.Mask" "F.Paste")
			(net "M_E_CPU0_SB_DQ<8>")
		)
		(pad "CH71" smd circle
			(at 30.86989 19.800062 180)
			(size 0.450088 0.450088)
			(layers "F.Cu" "F.Mask" "F.Paste")
			(net "GND")
		)
		(pad "CH72" smd circle
			(at 31.809944 19.800062 180)
			(size 0.450088 0.450088)
			(layers "F.Cu" "F.Mask" "F.Paste")
			(net "M_A_CPU0_SB_DQ<7>")
		)
		(pad "CH73" smd circle
			(at 32.749998 19.800062 180)
			(size 0.450088 0.450088)
			(layers "F.Cu" "F.Mask" "F.Paste")
			(net "GND")
		)
		(pad "CH74" smd circle
			(at 33.690052 19.800062 180)
			(size 0.450088 0.450088)
			(layers "F.Cu" "F.Mask" "F.Paste")
			(net "M_A_CPU0_SB_DQ<8>")
		)
		(pad "CJ1" smd circle
			(at -34.459926 20.610068 180)
			(size 0.450088 0.450088)
			(layers "F.Cu" "F.Mask" "F.Paste")
			(net "GND")
		)
		(pad "CJ2" smd circle
			(at -33.519872 20.610068 180)
			(size 0.450088 0.450088)
			(layers "F.Cu" "F.Mask" "F.Paste")
			(net "M_G_CPU0_SB_DQ<10>")
		)
		(pad "CJ3" smd circle
			(at -32.580072 20.610068 180)
			(size 0.450088 0.450088)
			(layers "F.Cu" "F.Mask" "F.Paste")
			(net "M_G_CPU0_SB_DQ<9>")
		)
		(pad "CJ4" smd circle
			(at -31.640018 20.610068 180)
			(size 0.450088 0.450088)
			(layers "F.Cu" "F.Mask" "F.Paste")
			(net "GND")
		)
		(pad "CJ5" smd circle
			(at -30.699964 20.610068 180)
			(size 0.450088 0.450088)
			(layers "F.Cu" "F.Mask" "F.Paste")
			(net "M_K_CPU0_SB_DQ<10>")
		)
		(pad "CJ6" smd circle
			(at -29.75991 20.610068 180)
			(size 0.450088 0.450088)
			(layers "F.Cu" "F.Mask" "F.Paste")
			(net "GND")
		)
		(pad "CJ7" smd circle
			(at -28.82011 20.610068 180)
			(size 0.450088 0.450088)
			(layers "F.Cu" "F.Mask" "F.Paste")
			(net "M_K_CPU0_SB_DQ<9>")
		)
		(pad "CJ8" smd circle
			(at -27.880056 20.610068 180)
			(size 0.450088 0.450088)
			(layers "F.Cu" "F.Mask" "F.Paste")
			(net "GND")
		)
		(pad "CJ9" smd circle
			(at -26.940002 20.610068 180)
			(size 0.450088 0.450088)
			(layers "F.Cu" "F.Mask" "F.Paste")
			(net "M_L_CPU0_SB_DQ<10>")
		)
		(pad "CJ10" smd circle
			(at -25.999948 20.610068 180)
			(size 0.450088 0.450088)
			(layers "F.Cu" "F.Mask" "F.Paste")
			(net "M_L_CPU0_SB_DQ<9>")
		)
		(pad "CJ11" smd circle
			(at -25.059894 20.610068 180)
			(size 0.450088 0.450088)
			(layers "F.Cu" "F.Mask" "F.Paste")
			(net "GND")
		)
		(pad "CJ12" smd circle
			(at -24.120094 20.610068 180)
			(size 0.450088 0.450088)
			(layers "F.Cu" "F.Mask" "F.Paste")
			(net "M_H_CPU0_SB_DQ<10>")
		)
		(pad "CJ13" smd circle
			(at -23.18004 20.610068 180)
			(size 0.450088 0.450088)
			(layers "F.Cu" "F.Mask" "F.Paste")
			(net "GND")
		)
		(pad "CJ14" smd circle
			(at -22.239986 20.610068 180)
			(size 0.450088 0.450088)
			(layers "F.Cu" "F.Mask" "F.Paste")
			(net "M_H_CPU0_SB_DQ<9>")
		)
		(pad "CJ15" smd circle
			(at -21.299932 20.610068 180)
			(size 0.450088 0.450088)
			(layers "F.Cu" "F.Mask" "F.Paste")
			(net "GND")
		)
		(pad "CJ16" smd circle
			(at -20.359878 20.610068 180)
			(size 0.450088 0.450088)
			(layers "F.Cu" "F.Mask" "F.Paste")
			(net "M_J_CPU0_SB_DQ<10>")
		)
		(pad "CJ17" smd circle
			(at -19.420078 20.610068 180)
			(size 0.450088 0.450088)
			(layers "F.Cu" "F.Mask" "F.Paste")
			(net "M_J_CPU0_SB_DQ<9>")
		)
		(pad "CJ18" smd circle
			(at -18.480024 20.610068 180)
			(size 0.450088 0.450088)
			(layers "F.Cu" "F.Mask" "F.Paste")
			(net "GND")
		)
		(pad "CJ19" smd circle
			(at -17.53997 20.610068 180)
			(size 0.450088 0.450088)
			(layers "F.Cu" "F.Mask" "F.Paste")
			(net "M_I_CPU0_SB_DQ<10>")
		)
		(pad "CJ20" smd circle
			(at -16.599916 20.610068 180)
			(size 0.450088 0.450088)
			(layers "F.Cu" "F.Mask" "F.Paste")
			(net "GND")
		)
		(pad "CJ21" smd circle
			(at -15.660116 20.610068 180)
			(size 0.450088 0.450088)
			(layers "F.Cu" "F.Mask" "F.Paste")
			(net "M_I_CPU0_SB_DQ<9>")
		)
		(pad "CJ22" smd circle
			(at -14.720062 20.610068 180)
			(size 0.450088 0.450088)
			(layers "F.Cu" "F.Mask" "F.Paste")
			(net "PVDD11_S3_P0")
		)
		(pad "CJ23" smd circle
			(at -13.780008 20.610068 180)
			(size 0.450088 0.450088)
			(layers "F.Cu" "F.Mask" "F.Paste")
			(net "GND")
		)
		(pad "CJ24" smd circle
			(at -12.839954 20.610068 180)
			(size 0.450088 0.450088)
			(layers "F.Cu" "F.Mask" "F.Paste")
			(net "TP_CPU0_TEST47_CCD1")
		)
		(pad "CJ25" smd circle
			(at -11.8999 20.610068 180)
			(size 0.450088 0.450088)
			(layers "F.Cu" "F.Mask" "F.Paste")
			(net "TP_CPU0_TEST5_CCD5")
		)
		(pad "CJ26" smd circle
			(at -10.9601 20.610068 180)
			(size 0.450088 0.450088)
			(layers "F.Cu" "F.Mask" "F.Paste")
			(net "TP_CPU0_TEST4_CCD5")
		)
		(pad "CJ27" smd circle
			(at -10.020046 20.610068 180)
			(size 0.450088 0.450088)
			(layers "F.Cu" "F.Mask" "F.Paste")
			(net "TP_CPU0_TEST5_CCD1")
		)
		(pad "CJ28" smd circle
			(at -9.079992 20.610068 180)
			(size 0.450088 0.450088)
			(layers "F.Cu" "F.Mask" "F.Paste")
			(net "TP_CPU0_TEST4_CCD1")
		)
		(pad "CJ29" smd circle
			(at -8.139938 20.610068 180)
			(size 0.450088 0.450088)
			(layers "F.Cu" "F.Mask" "F.Paste")
			(net "TP_CPU0_TEST6_X3D1")
		)
		(pad "CJ30" smd circle
			(at -7.199884 20.610068 180)
			(size 0.450088 0.450088)
			(layers "F.Cu" "F.Mask" "F.Paste")
			(net "TP_CPU0_TEST6_CCD1")
		)
		(pad "CJ31" smd circle
			(at -6.260084 20.610068 180)
			(size 0.450088 0.450088)
			(layers "F.Cu" "F.Mask" "F.Paste")
			(net "GND")
		)
		(pad "CJ32" smd circle
			(at -5.32003 20.610068 180)
			(size 0.450088 0.450088)
			(layers "F.Cu" "F.Mask" "F.Paste")
			(net "P5E_CPU0_P3_TX_DN<4>")
		)
		(pad "CJ33" smd circle
			(at -4.379976 20.610068 180)
			(size 0.450088 0.450088)
			(layers "F.Cu" "F.Mask" "F.Paste")
			(net "P5E_CPU0_P3_TX_DP<4>")
		)
		(pad "CJ34" smd circle
			(at -3.439922 20.610068 180)
			(size 0.450088 0.450088)
			(layers "F.Cu" "F.Mask" "F.Paste")
			(net "GND")
		)
		(pad "CJ35" smd circle
			(at -2.500122 20.610068 180)
			(size 0.450088 0.450088)
			(layers "F.Cu" "F.Mask" "F.Paste")
			(net "GND")
		)
		(pad "CJ36" smd circle
			(at -1.560068 20.610068 180)
			(size 0.450088 0.450088)
			(layers "F.Cu" "F.Mask" "F.Paste")
			(net "GND")
		)
		(pad "CJ40" smd circle
			(at 1.260094 20.610068 180)
			(size 0.450088 0.450088)
			(layers "F.Cu" "F.Mask" "F.Paste")
			(net "GND")
		)
		(pad "CJ41" smd circle
			(at 2.199894 20.610068 180)
			(size 0.450088 0.450088)
			(layers "F.Cu" "F.Mask" "F.Paste")
			(net "GND")
		)
		(pad "CJ42" smd circle
			(at 3.139948 20.610068 180)
			(size 0.450088 0.450088)
			(layers "F.Cu" "F.Mask" "F.Paste")
			(net "GND")
		)
		(pad "CJ43" smd circle
			(at 4.080002 20.610068 180)
			(size 0.450088 0.450088)
			(layers "F.Cu" "F.Mask" "F.Paste")
			(net "P5E_CPU0_P1_RX_DP<11>")
		)
		(pad "CJ44" smd circle
			(at 5.020056 20.610068 180)
			(size 0.450088 0.450088)
			(layers "F.Cu" "F.Mask" "F.Paste")
			(net "P5E_CPU0_P1_RX_DN<11>")
		)
		(pad "CJ45" smd circle
			(at 5.96011 20.610068 180)
			(size 0.450088 0.450088)
			(layers "F.Cu" "F.Mask" "F.Paste")
			(net "GND")
		)
		(pad "CJ46" smd circle
			(at 6.89991 20.610068 180)
			(size 0.450088 0.450088)
			(layers "F.Cu" "F.Mask" "F.Paste")
			(net "TP_CPU0_TEST6_CCD2")
		)
		(pad "CJ47" smd circle
			(at 7.839964 20.610068 180)
			(size 0.450088 0.450088)
			(layers "F.Cu" "F.Mask" "F.Paste")
			(net "TP_CPU0_TEST4_CCD10")
		)
		(pad "CJ48" smd circle
			(at 8.780018 20.610068 180)
			(size 0.450088 0.450088)
			(layers "F.Cu" "F.Mask" "F.Paste")
			(net "TP_CPU0_TEST4_CCD2")
		)
		(pad "CJ49" smd circle
			(at 9.720072 20.610068 180)
			(size 0.450088 0.450088)
			(layers "F.Cu" "F.Mask" "F.Paste")
			(net "TP_CPU0_TEST5_CCD2")
		)
		(pad "CJ50" smd circle
			(at 10.659872 20.610068 180)
			(size 0.450088 0.450088)
			(layers "F.Cu" "F.Mask" "F.Paste")
			(net "TP_CPU0_TEST4_CCD6")
		)
		(pad "CJ51" smd circle
			(at 11.599926 20.610068 180)
			(size 0.450088 0.450088)
			(layers "F.Cu" "F.Mask" "F.Paste")
			(net "TP_CPU0_TEST5_CCD6")
		)
		(pad "CJ52" smd circle
			(at 12.53998 20.610068 180)
			(size 0.450088 0.450088)
			(layers "F.Cu" "F.Mask" "F.Paste")
			(net "TP_CPU0_TEST6_X3D3")
		)
		(pad "CJ53" smd circle
			(at 13.480034 20.610068 180)
			(size 0.450088 0.450088)
			(layers "F.Cu" "F.Mask" "F.Paste")
			(net "TP_CPU0_TEST6_X3D5")
		)
		(pad "CJ54" smd circle
			(at 14.420088 20.610068 180)
			(size 0.450088 0.450088)
			(layers "F.Cu" "F.Mask" "F.Paste")
			(net "PVDDIO_P0")
		)
		(pad "CJ55" smd circle
			(at 15.359888 20.610068 180)
			(size 0.450088 0.450088)
			(layers "F.Cu" "F.Mask" "F.Paste")
			(net "M_C_CPU0_SB_DQ<9>")
		)
		(pad "CJ56" smd circle
			(at 16.299942 20.610068 180)
			(size 0.450088 0.450088)
			(layers "F.Cu" "F.Mask" "F.Paste")
			(net "GND")
		)
		(pad "CJ57" smd circle
			(at 17.239996 20.610068 180)
			(size 0.450088 0.450088)
			(layers "F.Cu" "F.Mask" "F.Paste")
			(net "M_C_CPU0_SB_DQ<10>")
		)
		(pad "CJ58" smd circle
			(at 18.18005 20.610068 180)
			(size 0.450088 0.450088)
			(layers "F.Cu" "F.Mask" "F.Paste")
			(net "GND")
		)
		(pad "CJ59" smd circle
			(at 19.120104 20.610068 180)
			(size 0.450088 0.450088)
			(layers "F.Cu" "F.Mask" "F.Paste")
			(net "M_D_CPU0_SB_DQ<9>")
		)
		(pad "CJ60" smd circle
			(at 20.059904 20.610068 180)
			(size 0.450088 0.450088)
			(layers "F.Cu" "F.Mask" "F.Paste")
			(net "M_D_CPU0_SB_DQ<10>")
		)
		(pad "CJ61" smd circle
			(at 20.999958 20.610068 180)
			(size 0.450088 0.450088)
			(layers "F.Cu" "F.Mask" "F.Paste")
			(net "GND")
		)
		(pad "CJ62" smd circle
			(at 21.940012 20.610068 180)
			(size 0.450088 0.450088)
			(layers "F.Cu" "F.Mask" "F.Paste")
			(net "M_B_CPU0_SB_DQ<9>")
		)
		(pad "CJ63" smd circle
			(at 22.880066 20.610068 180)
			(size 0.450088 0.450088)
			(layers "F.Cu" "F.Mask" "F.Paste")
			(net "GND")
		)
		(pad "CJ64" smd circle
			(at 23.82012 20.610068 180)
			(size 0.450088 0.450088)
			(layers "F.Cu" "F.Mask" "F.Paste")
			(net "M_B_CPU0_SB_DQ<10>")
		)
		(pad "CJ65" smd circle
			(at 24.75992 20.610068 180)
			(size 0.450088 0.450088)
			(layers "F.Cu" "F.Mask" "F.Paste")
			(net "GND")
		)
		(pad "CJ66" smd circle
			(at 25.699974 20.610068 180)
			(size 0.450088 0.450088)
			(layers "F.Cu" "F.Mask" "F.Paste")
			(net "M_F_CPU0_SB_DQ<9>")
		)
		(pad "CJ67" smd circle
			(at 26.640028 20.610068 180)
			(size 0.450088 0.450088)
			(layers "F.Cu" "F.Mask" "F.Paste")
			(net "M_F_CPU0_SB_DQ<10>")
		)
		(pad "CJ68" smd circle
			(at 27.580082 20.610068 180)
			(size 0.450088 0.450088)
			(layers "F.Cu" "F.Mask" "F.Paste")
			(net "GND")
		)
		(pad "CJ69" smd circle
			(at 28.519882 20.610068 180)
			(size 0.450088 0.450088)
			(layers "F.Cu" "F.Mask" "F.Paste")
			(net "M_E_CPU0_SB_DQ<9>")
		)
		(pad "CJ70" smd circle
			(at 29.459936 20.610068 180)
			(size 0.450088 0.450088)
			(layers "F.Cu" "F.Mask" "F.Paste")
			(net "GND")
		)
		(pad "CJ71" smd circle
			(at 30.39999 20.610068 180)
			(size 0.450088 0.450088)
			(layers "F.Cu" "F.Mask" "F.Paste")
			(net "M_E_CPU0_SB_DQ<10>")
		)
		(pad "CJ72" smd circle
			(at 31.340044 20.610068 180)
			(size 0.450088 0.450088)
			(layers "F.Cu" "F.Mask" "F.Paste")
			(net "GND")
		)
		(pad "CJ73" smd circle
			(at 32.280098 20.610068 180)
			(size 0.450088 0.450088)
			(layers "F.Cu" "F.Mask" "F.Paste")
			(net "M_A_CPU0_SB_DQ<9>")
		)
		(pad "CJ74" smd circle
			(at 33.219898 20.610068 180)
			(size 0.450088 0.450088)
			(layers "F.Cu" "F.Mask" "F.Paste")
			(net "M_A_CPU0_SB_DQ<10>")
		)
		(pad "CJ75" smd circle
			(at 34.159952 20.610068 180)
			(size 0.450088 0.450088)
			(layers "F.Cu" "F.Mask" "F.Paste")
			(net "GND")
		)
		(pad "CK2" smd circle
			(at -33.990026 21.420074 180)
			(size 0.450088 0.450088)
			(layers "F.Cu" "F.Mask" "F.Paste")
			(net "M_G_CPU0_SB_DQS_DP<1>")
		)
		(pad "CK3" smd circle
			(at -33.049972 21.420074 180)
			(size 0.450088 0.450088)
			(layers "F.Cu" "F.Mask" "F.Paste")
			(net "GND")
		)
		(pad "CK4" smd circle
			(at -32.109918 21.420074 180)
			(size 0.450088 0.450088)
			(layers "F.Cu" "F.Mask" "F.Paste")
			(net "M_G_CPU0_SB_DQ<11>")
		)
		(pad "CK5" smd circle
			(at -31.170118 21.420074 180)
			(size 0.450088 0.450088)
			(layers "F.Cu" "F.Mask" "F.Paste")
			(net "PVDD11_S3_P0")
		)
		(pad "CK6" smd circle
			(at -30.230064 21.420074 180)
			(size 0.450088 0.450088)
			(layers "F.Cu" "F.Mask" "F.Paste")
			(net "M_K_CPU0_SB_DQS_DP<1>")
		)
		(pad "CK7" smd circle
			(at -29.29001 21.420074 180)
			(size 0.450088 0.450088)
			(layers "F.Cu" "F.Mask" "F.Paste")
			(net "M_K_CPU0_SB_DQ<11>")
		)
		(pad "CK8" smd circle
			(at -28.349956 21.420074 180)
			(size 0.450088 0.450088)
			(layers "F.Cu" "F.Mask" "F.Paste")
			(net "GND")
		)
		(pad "CK9" smd circle
			(at -27.409902 21.420074 180)
			(size 0.450088 0.450088)
			(layers "F.Cu" "F.Mask" "F.Paste")
			(net "M_L_CPU0_SB_DQS_DP<1>")
		)
		(pad "CK10" smd circle
			(at -26.470102 21.420074 180)
			(size 0.450088 0.450088)
			(layers "F.Cu" "F.Mask" "F.Paste")
			(net "GND")
		)
		(pad "CK11" smd circle
			(at -25.530048 21.420074 180)
			(size 0.450088 0.450088)
			(layers "F.Cu" "F.Mask" "F.Paste")
			(net "M_L_CPU0_SB_DQ<11>")
		)
		(pad "CK12" smd circle
			(at -24.589994 21.420074 180)
			(size 0.450088 0.450088)
			(layers "F.Cu" "F.Mask" "F.Paste")
			(net "PVDD11_S3_P0")
		)
		(pad "CK13" smd circle
			(at -23.64994 21.420074 180)
			(size 0.450088 0.450088)
			(layers "F.Cu" "F.Mask" "F.Paste")
			(net "M_H_CPU0_SB_DQS_DP<1>")
		)
		(pad "CK14" smd circle
			(at -22.709886 21.420074 180)
			(size 0.450088 0.450088)
			(layers "F.Cu" "F.Mask" "F.Paste")
			(net "M_H_CPU0_SB_DQ<11>")
		)
		(pad "CK15" smd circle
			(at -21.770086 21.420074 180)
			(size 0.450088 0.450088)
			(layers "F.Cu" "F.Mask" "F.Paste")
			(net "GND")
		)
		(pad "CK16" smd circle
			(at -20.830032 21.420074 180)
			(size 0.450088 0.450088)
			(layers "F.Cu" "F.Mask" "F.Paste")
			(net "M_J_CPU0_SB_DQS_DP<1>")
		)
		(pad "CK17" smd circle
			(at -19.889978 21.420074 180)
			(size 0.450088 0.450088)
			(layers "F.Cu" "F.Mask" "F.Paste")
			(net "GND")
		)
		(pad "CK18" smd circle
			(at -18.949924 21.420074 180)
			(size 0.450088 0.450088)
			(layers "F.Cu" "F.Mask" "F.Paste")
			(net "M_J_CPU0_SB_DQ<11>")
		)
		(pad "CK19" smd circle
			(at -18.010124 21.420074 180)
			(size 0.450088 0.450088)
			(layers "F.Cu" "F.Mask" "F.Paste")
			(net "PVDD11_S3_P0")
		)
		(pad "CK20" smd circle
			(at -17.07007 21.420074 180)
			(size 0.450088 0.450088)
			(layers "F.Cu" "F.Mask" "F.Paste")
			(net "M_I_CPU0_SB_DQS_DP<1>")
		)
		(pad "CK21" smd circle
			(at -16.130016 21.420074 180)
			(size 0.450088 0.450088)
			(layers "F.Cu" "F.Mask" "F.Paste")
			(net "M_I_CPU0_SB_DQ<11>")
		)
		(pad "CK22" smd circle
			(at -15.189962 21.420074 180)
			(size 0.450088 0.450088)
			(layers "F.Cu" "F.Mask" "F.Paste")
			(net "GND")
		)
		(pad "CK23" smd circle
			(at -14.249908 21.420074 180)
			(size 0.450088 0.450088)
			(layers "F.Cu" "F.Mask" "F.Paste")
			(net "GND")
		)
		(pad "CK24" smd circle
			(at -13.310108 21.420074 180)
			(size 0.450088 0.450088)
			(layers "F.Cu" "F.Mask" "F.Paste")
			(net "GND")
		)
		(pad "CK25" smd circle
			(at -12.370054 21.420074 180)
			(size 0.450088 0.450088)
			(layers "F.Cu" "F.Mask" "F.Paste")
			(net "GND")
		)
		(pad "CK26" smd circle
			(at -11.43 21.420074 180)
			(size 0.450088 0.450088)
			(layers "F.Cu" "F.Mask" "F.Paste")
			(net "GND")
		)
		(pad "CK27" smd circle
			(at -10.489946 21.420074 180)
			(size 0.450088 0.450088)
			(layers "F.Cu" "F.Mask" "F.Paste")
			(net "GND")
		)
		(pad "CK28" smd circle
			(at -9.549892 21.420074 180)
			(size 0.450088 0.450088)
			(layers "F.Cu" "F.Mask" "F.Paste")
			(net "GND")
		)
		(pad "CK29" smd circle
			(at -8.610092 21.420074 180)
			(size 0.450088 0.450088)
			(layers "F.Cu" "F.Mask" "F.Paste")
			(net "TP_CPU0_TEST5_CCD9")
		)
		(pad "CK30" smd circle
			(at -7.670038 21.420074 180)
			(size 0.450088 0.450088)
			(layers "F.Cu" "F.Mask" "F.Paste")
			(net "TP_CPU0_TEST4_CCD9")
		)
		(pad "CK31" smd circle
			(at -6.729984 21.420074 180)
			(size 0.450088 0.450088)
			(layers "F.Cu" "F.Mask" "F.Paste")
			(net "GND")
		)
		(pad "CK32" smd circle
			(at -5.78993 21.420074 180)
			(size 0.450088 0.450088)
			(layers "F.Cu" "F.Mask" "F.Paste")
			(net "GND")
		)
		(pad "CK33" smd circle
			(at -4.849876 21.420074 180)
			(size 0.450088 0.450088)
			(layers "F.Cu" "F.Mask" "F.Paste")
			(net "GND")
		)
		(pad "CK34" smd circle
			(at -3.910076 21.420074 180)
			(size 0.450088 0.450088)
			(layers "F.Cu" "F.Mask" "F.Paste")
			(net "GND")
		)
		(pad "CK35" smd circle
			(at -2.970022 21.420074 180)
			(size 0.450088 0.450088)
			(layers "F.Cu" "F.Mask" "F.Paste")
			(net "PVDDCR_CPU1_P0")
		)
		(pad "CK36" smd circle
			(at -2.029968 21.420074 180)
			(size 0.450088 0.450088)
			(layers "F.Cu" "F.Mask" "F.Paste")
			(net "PVDDCR_CPU1_P0")
		)
		(pad "CK37" smd circle
			(at -1.089914 21.420074 180)
			(size 0.450088 0.450088)
			(layers "F.Cu" "F.Mask" "F.Paste")
			(net "GND")
		)
		(pad "CK39" smd circle
			(at 0.78994 21.420074 180)
			(size 0.450088 0.450088)
			(layers "F.Cu" "F.Mask" "F.Paste")
			(net "GND")
		)
		(pad "CK40" smd circle
			(at 1.729994 21.420074 180)
			(size 0.450088 0.450088)
			(layers "F.Cu" "F.Mask" "F.Paste")
			(net "PVDDCR_CPU1_P0")
		)
		(pad "CK41" smd circle
			(at 2.670048 21.420074 180)
			(size 0.450088 0.450088)
			(layers "F.Cu" "F.Mask" "F.Paste")
			(net "PVDDCR_CPU1_P0")
		)
		(pad "CK42" smd circle
			(at 3.610102 21.420074 180)
			(size 0.450088 0.450088)
			(layers "F.Cu" "F.Mask" "F.Paste")
			(net "GND")
		)
		(pad "CK43" smd circle
			(at 4.549902 21.420074 180)
			(size 0.450088 0.450088)
			(layers "F.Cu" "F.Mask" "F.Paste")
			(net "GND")
		)
		(pad "CK44" smd circle
			(at 5.489956 21.420074 180)
			(size 0.450088 0.450088)
			(layers "F.Cu" "F.Mask" "F.Paste")
			(net "GND")
		)
		(pad "CK45" smd circle
			(at 6.43001 21.420074 180)
			(size 0.450088 0.450088)
			(layers "F.Cu" "F.Mask" "F.Paste")
			(net "GND")
		)
		(pad "CK46" smd circle
			(at 7.370064 21.420074 180)
			(size 0.450088 0.450088)
			(layers "F.Cu" "F.Mask" "F.Paste")
			(net "TP_CPU0_TEST47_CCD2")
		)
		(pad "CK47" smd circle
			(at 8.310118 21.420074 180)
			(size 0.450088 0.450088)
			(layers "F.Cu" "F.Mask" "F.Paste")
			(net "TP_CPU0_TEST5_CCD10")
		)
		(pad "CK48" smd circle
			(at 9.249918 21.420074 180)
			(size 0.450088 0.450088)
			(layers "F.Cu" "F.Mask" "F.Paste")
			(net "GND")
		)
		(pad "CK49" smd circle
			(at 10.189972 21.420074 180)
			(size 0.450088 0.450088)
			(layers "F.Cu" "F.Mask" "F.Paste")
			(net "GND")
		)
		(pad "CK50" smd circle
			(at 11.130026 21.420074 180)
			(size 0.450088 0.450088)
			(layers "F.Cu" "F.Mask" "F.Paste")
			(net "GND")
		)
		(pad "CK51" smd circle
			(at 12.07008 21.420074 180)
			(size 0.450088 0.450088)
			(layers "F.Cu" "F.Mask" "F.Paste")
			(net "GND")
		)
		(pad "CK52" smd circle
			(at 13.00988 21.420074 180)
			(size 0.450088 0.450088)
			(layers "F.Cu" "F.Mask" "F.Paste")
			(net "GND")
		)
		(pad "CK53" smd circle
			(at 13.949934 21.420074 180)
			(size 0.450088 0.450088)
			(layers "F.Cu" "F.Mask" "F.Paste")
			(net "GND")
		)
		(pad "CK54" smd circle
			(at 14.889988 21.420074 180)
			(size 0.450088 0.450088)
			(layers "F.Cu" "F.Mask" "F.Paste")
			(net "GND")
		)
		(pad "CK55" smd circle
			(at 15.830042 21.420074 180)
			(size 0.450088 0.450088)
			(layers "F.Cu" "F.Mask" "F.Paste")
			(net "M_C_CPU0_SB_DQ<11>")
		)
		(pad "CK56" smd circle
			(at 16.770096 21.420074 180)
			(size 0.450088 0.450088)
			(layers "F.Cu" "F.Mask" "F.Paste")
			(net "M_C_CPU0_SB_DQS_DP<1>")
		)
		(pad "CK57" smd circle
			(at 17.709896 21.420074 180)
			(size 0.450088 0.450088)
			(layers "F.Cu" "F.Mask" "F.Paste")
			(net "PVDDIO_P0")
		)
		(pad "CK58" smd circle
			(at 18.64995 21.420074 180)
			(size 0.450088 0.450088)
			(layers "F.Cu" "F.Mask" "F.Paste")
			(net "M_D_CPU0_SB_DQ<11>")
		)
		(pad "CK59" smd circle
			(at 19.590004 21.420074 180)
			(size 0.450088 0.450088)
			(layers "F.Cu" "F.Mask" "F.Paste")
			(net "GND")
		)
		(pad "CK60" smd circle
			(at 20.530058 21.420074 180)
			(size 0.450088 0.450088)
			(layers "F.Cu" "F.Mask" "F.Paste")
			(net "M_D_CPU0_SB_DQS_DP<1>")
		)
		(pad "CK61" smd circle
			(at 21.470112 21.420074 180)
			(size 0.450088 0.450088)
			(layers "F.Cu" "F.Mask" "F.Paste")
			(net "GND")
		)
		(pad "CK62" smd circle
			(at 22.409912 21.420074 180)
			(size 0.450088 0.450088)
			(layers "F.Cu" "F.Mask" "F.Paste")
			(net "M_B_CPU0_SB_DQ<11>")
		)
		(pad "CK63" smd circle
			(at 23.349966 21.420074 180)
			(size 0.450088 0.450088)
			(layers "F.Cu" "F.Mask" "F.Paste")
			(net "M_B_CPU0_SB_DQS_DP<1>")
		)
		(pad "CK64" smd circle
			(at 24.29002 21.420074 180)
			(size 0.450088 0.450088)
			(layers "F.Cu" "F.Mask" "F.Paste")
			(net "PVDDIO_P0")
		)
		(pad "CK65" smd circle
			(at 25.230074 21.420074 180)
			(size 0.450088 0.450088)
			(layers "F.Cu" "F.Mask" "F.Paste")
			(net "M_F_CPU0_SB_DQ<11>")
		)
		(pad "CK66" smd circle
			(at 26.170128 21.420074 180)
			(size 0.450088 0.450088)
			(layers "F.Cu" "F.Mask" "F.Paste")
			(net "GND")
		)
		(pad "CK67" smd circle
			(at 27.109928 21.420074 180)
			(size 0.450088 0.450088)
			(layers "F.Cu" "F.Mask" "F.Paste")
			(net "M_F_CPU0_SB_DQS_DP<1>")
		)
		(pad "CK68" smd circle
			(at 28.049982 21.420074 180)
			(size 0.450088 0.450088)
			(layers "F.Cu" "F.Mask" "F.Paste")
			(net "GND")
		)
		(pad "CK69" smd circle
			(at 28.990036 21.420074 180)
			(size 0.450088 0.450088)
			(layers "F.Cu" "F.Mask" "F.Paste")
			(net "M_E_CPU0_SB_DQ<11>")
		)
		(pad "CK70" smd circle
			(at 29.93009 21.420074 180)
			(size 0.450088 0.450088)
			(layers "F.Cu" "F.Mask" "F.Paste")
			(net "M_E_CPU0_SB_DQS_DP<1>")
		)
		(pad "CK71" smd circle
			(at 30.86989 21.420074 180)
			(size 0.450088 0.450088)
			(layers "F.Cu" "F.Mask" "F.Paste")
			(net "PVDDIO_P0")
		)
		(pad "CK72" smd circle
			(at 31.809944 21.420074 180)
			(size 0.450088 0.450088)
			(layers "F.Cu" "F.Mask" "F.Paste")
			(net "M_A_CPU0_SB_DQ<11>")
		)
		(pad "CK73" smd circle
			(at 32.749998 21.420074 180)
			(size 0.450088 0.450088)
			(layers "F.Cu" "F.Mask" "F.Paste")
			(net "GND")
		)
		(pad "CK74" smd circle
			(at 33.690052 21.420074 180)
			(size 0.450088 0.450088)
			(layers "F.Cu" "F.Mask" "F.Paste")
			(net "M_A_CPU0_SB_DQS_DP<1>")
		)
		(pad "CL1" smd circle
			(at -34.459926 22.23008 180)
			(size 0.450088 0.450088)
			(layers "F.Cu" "F.Mask" "F.Paste")
			(net "GND")
		)
		(pad "CL2" smd circle
			(at -33.519872 22.23008 180)
			(size 0.450088 0.450088)
			(layers "F.Cu" "F.Mask" "F.Paste")
			(net "M_G_CPU0_SB_DQS_DN<1>")
		)
		(pad "CL3" smd circle
			(at -32.580072 22.23008 180)
			(size 0.450088 0.450088)
			(layers "F.Cu" "F.Mask" "F.Paste")
			(net "M_G_CPU0_SB_DQS_DN<6>")
		)
		(pad "CL4" smd circle
			(at -31.640018 22.23008 180)
			(size 0.450088 0.450088)
			(layers "F.Cu" "F.Mask" "F.Paste")
			(net "GND")
		)
		(pad "CL5" smd circle
			(at -30.699964 22.23008 180)
			(size 0.450088 0.450088)
			(layers "F.Cu" "F.Mask" "F.Paste")
			(net "M_K_CPU0_SB_DQS_DN<1>")
		)
		(pad "CL6" smd circle
			(at -29.75991 22.23008 180)
			(size 0.450088 0.450088)
			(layers "F.Cu" "F.Mask" "F.Paste")
			(net "GND")
		)
		(pad "CL7" smd circle
			(at -28.82011 22.23008 180)
			(size 0.450088 0.450088)
			(layers "F.Cu" "F.Mask" "F.Paste")
			(net "M_K_CPU0_SB_DQS_DN<6>")
		)
		(pad "CL8" smd circle
			(at -27.880056 22.23008 180)
			(size 0.450088 0.450088)
			(layers "F.Cu" "F.Mask" "F.Paste")
			(net "GND")
		)
		(pad "CL9" smd circle
			(at -26.940002 22.23008 180)
			(size 0.450088 0.450088)
			(layers "F.Cu" "F.Mask" "F.Paste")
			(net "M_L_CPU0_SB_DQS_DN<1>")
		)
		(pad "CL10" smd circle
			(at -25.999948 22.23008 180)
			(size 0.450088 0.450088)
			(layers "F.Cu" "F.Mask" "F.Paste")
			(net "M_L_CPU0_SB_DQS_DN<6>")
		)
		(pad "CL11" smd circle
			(at -25.059894 22.23008 180)
			(size 0.450088 0.450088)
			(layers "F.Cu" "F.Mask" "F.Paste")
			(net "GND")
		)
		(pad "CL12" smd circle
			(at -24.120094 22.23008 180)
			(size 0.450088 0.450088)
			(layers "F.Cu" "F.Mask" "F.Paste")
			(net "M_H_CPU0_SB_DQS_DN<1>")
		)
		(pad "CL13" smd circle
			(at -23.18004 22.23008 180)
			(size 0.450088 0.450088)
			(layers "F.Cu" "F.Mask" "F.Paste")
			(net "GND")
		)
		(pad "CL14" smd circle
			(at -22.239986 22.23008 180)
			(size 0.450088 0.450088)
			(layers "F.Cu" "F.Mask" "F.Paste")
			(net "M_H_CPU0_SB_DQS_DN<6>")
		)
		(pad "CL15" smd circle
			(at -21.299932 22.23008 180)
			(size 0.450088 0.450088)
			(layers "F.Cu" "F.Mask" "F.Paste")
			(net "GND")
		)
		(pad "CL16" smd circle
			(at -20.359878 22.23008 180)
			(size 0.450088 0.450088)
			(layers "F.Cu" "F.Mask" "F.Paste")
			(net "M_J_CPU0_SB_DQS_DN<1>")
		)
		(pad "CL17" smd circle
			(at -19.420078 22.23008 180)
			(size 0.450088 0.450088)
			(layers "F.Cu" "F.Mask" "F.Paste")
			(net "M_J_CPU0_SB_DQS_DN<6>")
		)
		(pad "CL18" smd circle
			(at -18.480024 22.23008 180)
			(size 0.450088 0.450088)
			(layers "F.Cu" "F.Mask" "F.Paste")
			(net "GND")
		)
		(pad "CL19" smd circle
			(at -17.53997 22.23008 180)
			(size 0.450088 0.450088)
			(layers "F.Cu" "F.Mask" "F.Paste")
			(net "M_I_CPU0_SB_DQS_DN<1>")
		)
		(pad "CL20" smd circle
			(at -16.599916 22.23008 180)
			(size 0.450088 0.450088)
			(layers "F.Cu" "F.Mask" "F.Paste")
			(net "GND")
		)
		(pad "CL21" smd circle
			(at -15.660116 22.23008 180)
			(size 0.450088 0.450088)
			(layers "F.Cu" "F.Mask" "F.Paste")
			(net "M_I_CPU0_SB_DQS_DN<6>")
		)
		(pad "CL22" smd circle
			(at -14.720062 22.23008 180)
			(size 0.450088 0.450088)
			(layers "F.Cu" "F.Mask" "F.Paste")
			(net "GND")
		)
		(pad "CL23" smd circle
			(at -13.780008 22.23008 180)
			(size 0.450088 0.450088)
			(layers "F.Cu" "F.Mask" "F.Paste")
			(net "P5E_CPU0_P2_RX_DP<13>")
		)
		(pad "CL24" smd circle
			(at -12.839954 22.23008 180)
			(size 0.450088 0.450088)
			(layers "F.Cu" "F.Mask" "F.Paste")
			(net "P5E_CPU0_P2_RX_DN<13>")
		)
		(pad "CL25" smd circle
			(at -11.8999 22.23008 180)
			(size 0.450088 0.450088)
			(layers "F.Cu" "F.Mask" "F.Paste")
			(net "GND")
		)
		(pad "CL26" smd circle
			(at -10.9601 22.23008 180)
			(size 0.450088 0.450088)
			(layers "F.Cu" "F.Mask" "F.Paste")
			(net "P5E_CPU0_P2_RX_DP<9>")
		)
		(pad "CL27" smd circle
			(at -10.020046 22.23008 180)
			(size 0.450088 0.450088)
			(layers "F.Cu" "F.Mask" "F.Paste")
			(net "P5E_CPU0_P2_RX_DN<9>")
		)
		(pad "CL28" smd circle
			(at -9.079992 22.23008 180)
			(size 0.450088 0.450088)
			(layers "F.Cu" "F.Mask" "F.Paste")
			(net "GND")
		)
		(pad "CL29" smd circle
			(at -8.139938 22.23008 180)
			(size 0.450088 0.450088)
			(layers "F.Cu" "F.Mask" "F.Paste")
			(net "PVDDCR_CPU1_P0")
		)
		(pad "CL30" smd circle
			(at -7.199884 22.23008 180)
			(size 0.450088 0.450088)
			(layers "F.Cu" "F.Mask" "F.Paste")
			(net "PVDDCR_CPU1_P0")
		)
		(pad "CL31" smd circle
			(at -6.260084 22.23008 180)
			(size 0.450088 0.450088)
			(layers "F.Cu" "F.Mask" "F.Paste")
			(net "GND")
		)
		(pad "CL32" smd circle
			(at -5.32003 22.23008 180)
			(size 0.450088 0.450088)
			(layers "F.Cu" "F.Mask" "F.Paste")
			(net "PVDDCR_CPU1_P0")
		)
		(pad "CL33" smd circle
			(at -4.379976 22.23008 180)
			(size 0.450088 0.450088)
			(layers "F.Cu" "F.Mask" "F.Paste")
			(net "PVDDCR_CPU1_P0")
		)
		(pad "CL34" smd circle
			(at -3.439922 22.23008 180)
			(size 0.450088 0.450088)
			(layers "F.Cu" "F.Mask" "F.Paste")
			(net "GND")
		)
		(pad "CL35" smd circle
			(at -2.500122 22.23008 180)
			(size 0.450088 0.450088)
			(layers "F.Cu" "F.Mask" "F.Paste")
			(net "GND")
		)
		(pad "CL36" smd circle
			(at -1.560068 22.23008 180)
			(size 0.450088 0.450088)
			(layers "F.Cu" "F.Mask" "F.Paste")
			(net "GND")
		)
		(pad "CL40" smd circle
			(at 1.260094 22.23008 180)
			(size 0.450088 0.450088)
			(layers "F.Cu" "F.Mask" "F.Paste")
			(net "GND")
		)
		(pad "CL41" smd circle
			(at 2.199894 22.23008 180)
			(size 0.450088 0.450088)
			(layers "F.Cu" "F.Mask" "F.Paste")
			(net "GND")
		)
		(pad "CL42" smd circle
			(at 3.139948 22.23008 180)
			(size 0.450088 0.450088)
			(layers "F.Cu" "F.Mask" "F.Paste")
			(net "GND")
		)
		(pad "CL43" smd circle
			(at 4.080002 22.23008 180)
			(size 0.450088 0.450088)
			(layers "F.Cu" "F.Mask" "F.Paste")
			(net "PVDDCR_CPU1_P0")
		)
		(pad "CL44" smd circle
			(at 5.020056 22.23008 180)
			(size 0.450088 0.450088)
			(layers "F.Cu" "F.Mask" "F.Paste")
			(net "PVDDCR_CPU1_P0")
		)
		(pad "CL45" smd circle
			(at 5.96011 22.23008 180)
			(size 0.450088 0.450088)
			(layers "F.Cu" "F.Mask" "F.Paste")
			(net "GND")
		)
		(pad "CL46" smd circle
			(at 6.89991 22.23008 180)
			(size 0.450088 0.450088)
			(layers "F.Cu" "F.Mask" "F.Paste")
			(net "PVDDCR_CPU1_P0")
		)
		(pad "CL47" smd circle
			(at 7.839964 22.23008 180)
			(size 0.450088 0.450088)
			(layers "F.Cu" "F.Mask" "F.Paste")
			(net "PVDDCR_CPU1_P0")
		)
		(pad "CL48" smd circle
			(at 8.780018 22.23008 180)
			(size 0.450088 0.450088)
			(layers "F.Cu" "F.Mask" "F.Paste")
			(net "GND")
		)
		(pad "CL49" smd circle
			(at 9.720072 22.23008 180)
			(size 0.450088 0.450088)
			(layers "F.Cu" "F.Mask" "F.Paste")
			(net "P5E_CPU0_P0_TX_DN<6>")
		)
		(pad "CL50" smd circle
			(at 10.659872 22.23008 180)
			(size 0.450088 0.450088)
			(layers "F.Cu" "F.Mask" "F.Paste")
			(net "P5E_CPU0_P0_TX_DP<6>")
		)
		(pad "CL51" smd circle
			(at 11.599926 22.23008 180)
			(size 0.450088 0.450088)
			(layers "F.Cu" "F.Mask" "F.Paste")
			(net "GND")
		)
		(pad "CL52" smd circle
			(at 12.53998 22.23008 180)
			(size 0.450088 0.450088)
			(layers "F.Cu" "F.Mask" "F.Paste")
			(net "P5E_CPU0_P0_TX_DN<2>")
		)
		(pad "CL53" smd circle
			(at 13.480034 22.23008 180)
			(size 0.450088 0.450088)
			(layers "F.Cu" "F.Mask" "F.Paste")
			(net "P5E_CPU0_P0_TX_DP<2>")
		)
		(pad "CL54" smd circle
			(at 14.420088 22.23008 180)
			(size 0.450088 0.450088)
			(layers "F.Cu" "F.Mask" "F.Paste")
			(net "GND")
		)
		(pad "CL55" smd circle
			(at 15.359888 22.23008 180)
			(size 0.450088 0.450088)
			(layers "F.Cu" "F.Mask" "F.Paste")
			(net "M_C_CPU0_SB_DQS_DN<6>")
		)
		(pad "CL56" smd circle
			(at 16.299942 22.23008 180)
			(size 0.450088 0.450088)
			(layers "F.Cu" "F.Mask" "F.Paste")
			(net "GND")
		)
		(pad "CL57" smd circle
			(at 17.239996 22.23008 180)
			(size 0.450088 0.450088)
			(layers "F.Cu" "F.Mask" "F.Paste")
			(net "M_C_CPU0_SB_DQS_DN<1>")
		)
		(pad "CL58" smd circle
			(at 18.18005 22.23008 180)
			(size 0.450088 0.450088)
			(layers "F.Cu" "F.Mask" "F.Paste")
			(net "GND")
		)
		(pad "CL59" smd circle
			(at 19.120104 22.23008 180)
			(size 0.450088 0.450088)
			(layers "F.Cu" "F.Mask" "F.Paste")
			(net "M_D_CPU0_SB_DQS_DN<6>")
		)
		(pad "CL60" smd circle
			(at 20.059904 22.23008 180)
			(size 0.450088 0.450088)
			(layers "F.Cu" "F.Mask" "F.Paste")
			(net "M_D_CPU0_SB_DQS_DN<1>")
		)
		(pad "CL61" smd circle
			(at 20.999958 22.23008 180)
			(size 0.450088 0.450088)
			(layers "F.Cu" "F.Mask" "F.Paste")
			(net "GND")
		)
		(pad "CL62" smd circle
			(at 21.940012 22.23008 180)
			(size 0.450088 0.450088)
			(layers "F.Cu" "F.Mask" "F.Paste")
			(net "M_B_CPU0_SB_DQS_DN<6>")
		)
		(pad "CL63" smd circle
			(at 22.880066 22.23008 180)
			(size 0.450088 0.450088)
			(layers "F.Cu" "F.Mask" "F.Paste")
			(net "GND")
		)
		(pad "CL64" smd circle
			(at 23.82012 22.23008 180)
			(size 0.450088 0.450088)
			(layers "F.Cu" "F.Mask" "F.Paste")
			(net "M_B_CPU0_SB_DQS_DN<1>")
		)
		(pad "CL65" smd circle
			(at 24.75992 22.23008 180)
			(size 0.450088 0.450088)
			(layers "F.Cu" "F.Mask" "F.Paste")
			(net "GND")
		)
		(pad "CL66" smd circle
			(at 25.699974 22.23008 180)
			(size 0.450088 0.450088)
			(layers "F.Cu" "F.Mask" "F.Paste")
			(net "M_F_CPU0_SB_DQS_DN<6>")
		)
		(pad "CL67" smd circle
			(at 26.640028 22.23008 180)
			(size 0.450088 0.450088)
			(layers "F.Cu" "F.Mask" "F.Paste")
			(net "M_F_CPU0_SB_DQS_DN<1>")
		)
		(pad "CL68" smd circle
			(at 27.580082 22.23008 180)
			(size 0.450088 0.450088)
			(layers "F.Cu" "F.Mask" "F.Paste")
			(net "GND")
		)
		(pad "CL69" smd circle
			(at 28.519882 22.23008 180)
			(size 0.450088 0.450088)
			(layers "F.Cu" "F.Mask" "F.Paste")
			(net "M_E_CPU0_SB_DQS_DN<6>")
		)
		(pad "CL70" smd circle
			(at 29.459936 22.23008 180)
			(size 0.450088 0.450088)
			(layers "F.Cu" "F.Mask" "F.Paste")
			(net "GND")
		)
		(pad "CL71" smd circle
			(at 30.39999 22.23008 180)
			(size 0.450088 0.450088)
			(layers "F.Cu" "F.Mask" "F.Paste")
			(net "M_E_CPU0_SB_DQS_DN<1>")
		)
		(pad "CL72" smd circle
			(at 31.340044 22.23008 180)
			(size 0.450088 0.450088)
			(layers "F.Cu" "F.Mask" "F.Paste")
			(net "GND")
		)
		(pad "CL73" smd circle
			(at 32.280098 22.23008 180)
			(size 0.450088 0.450088)
			(layers "F.Cu" "F.Mask" "F.Paste")
			(net "M_A_CPU0_SB_DQS_DN<6>")
		)
		(pad "CL74" smd circle
			(at 33.219898 22.23008 180)
			(size 0.450088 0.450088)
			(layers "F.Cu" "F.Mask" "F.Paste")
			(net "M_A_CPU0_SB_DQS_DN<1>")
		)
		(pad "CL75" smd circle
			(at 34.159952 22.23008 180)
			(size 0.450088 0.450088)
			(layers "F.Cu" "F.Mask" "F.Paste")
			(net "GND")
		)
		(pad "CM2" smd circle
			(at -33.990026 23.040086 180)
			(size 0.450088 0.450088)
			(layers "F.Cu" "F.Mask" "F.Paste")
			(net "M_G_CPU0_SB_DQ<12>")
		)
		(pad "CM3" smd circle
			(at -33.049972 23.040086 180)
			(size 0.450088 0.450088)
			(layers "F.Cu" "F.Mask" "F.Paste")
			(net "GND")
		)
		(pad "CM4" smd circle
			(at -32.109918 23.040086 180)
			(size 0.450088 0.450088)
			(layers "F.Cu" "F.Mask" "F.Paste")
			(net "M_G_CPU0_SB_DQS_DP<6>")
		)
		(pad "CM5" smd circle
			(at -31.170118 23.040086 180)
			(size 0.450088 0.450088)
			(layers "F.Cu" "F.Mask" "F.Paste")
			(net "GND")
		)
		(pad "CM6" smd circle
			(at -30.230064 23.040086 180)
			(size 0.450088 0.450088)
			(layers "F.Cu" "F.Mask" "F.Paste")
			(net "M_K_CPU0_SB_DQ<12>")
		)
		(pad "CM7" smd circle
			(at -29.29001 23.040086 180)
			(size 0.450088 0.450088)
			(layers "F.Cu" "F.Mask" "F.Paste")
			(net "M_K_CPU0_SB_DQS_DP<6>")
		)
		(pad "CM8" smd circle
			(at -28.349956 23.040086 180)
			(size 0.450088 0.450088)
			(layers "F.Cu" "F.Mask" "F.Paste")
			(net "GND")
		)
		(pad "CM9" smd circle
			(at -27.409902 23.040086 180)
			(size 0.450088 0.450088)
			(layers "F.Cu" "F.Mask" "F.Paste")
			(net "M_L_CPU0_SB_DQ<12>")
		)
		(pad "CM10" smd circle
			(at -26.470102 23.040086 180)
			(size 0.450088 0.450088)
			(layers "F.Cu" "F.Mask" "F.Paste")
			(net "GND")
		)
		(pad "CM11" smd circle
			(at -25.530048 23.040086 180)
			(size 0.450088 0.450088)
			(layers "F.Cu" "F.Mask" "F.Paste")
			(net "M_L_CPU0_SB_DQS_DP<6>")
		)
		(pad "CM12" smd circle
			(at -24.589994 23.040086 180)
			(size 0.450088 0.450088)
			(layers "F.Cu" "F.Mask" "F.Paste")
			(net "GND")
		)
		(pad "CM13" smd circle
			(at -23.64994 23.040086 180)
			(size 0.450088 0.450088)
			(layers "F.Cu" "F.Mask" "F.Paste")
			(net "M_H_CPU0_SB_DQ<12>")
		)
		(pad "CM14" smd circle
			(at -22.709886 23.040086 180)
			(size 0.450088 0.450088)
			(layers "F.Cu" "F.Mask" "F.Paste")
			(net "M_H_CPU0_SB_DQS_DP<6>")
		)
		(pad "CM15" smd circle
			(at -21.770086 23.040086 180)
			(size 0.450088 0.450088)
			(layers "F.Cu" "F.Mask" "F.Paste")
			(net "GND")
		)
		(pad "CM16" smd circle
			(at -20.830032 23.040086 180)
			(size 0.450088 0.450088)
			(layers "F.Cu" "F.Mask" "F.Paste")
			(net "M_J_CPU0_SB_DQ<12>")
		)
		(pad "CM17" smd circle
			(at -19.889978 23.040086 180)
			(size 0.450088 0.450088)
			(layers "F.Cu" "F.Mask" "F.Paste")
			(net "GND")
		)
		(pad "CM18" smd circle
			(at -18.949924 23.040086 180)
			(size 0.450088 0.450088)
			(layers "F.Cu" "F.Mask" "F.Paste")
			(net "M_J_CPU0_SB_DQS_DP<6>")
		)
		(pad "CM19" smd circle
			(at -18.010124 23.040086 180)
			(size 0.450088 0.450088)
			(layers "F.Cu" "F.Mask" "F.Paste")
			(net "GND")
		)
		(pad "CM20" smd circle
			(at -17.07007 23.040086 180)
			(size 0.450088 0.450088)
			(layers "F.Cu" "F.Mask" "F.Paste")
			(net "M_I_CPU0_SB_DQ<12>")
		)
		(pad "CM21" smd circle
			(at -16.130016 23.040086 180)
			(size 0.450088 0.450088)
			(layers "F.Cu" "F.Mask" "F.Paste")
			(net "M_I_CPU0_SB_DQS_DP<6>")
		)
		(pad "CM22" smd circle
			(at -15.189962 23.040086 180)
			(size 0.450088 0.450088)
			(layers "F.Cu" "F.Mask" "F.Paste")
			(net "PVDD11_S3_P0")
		)
		(pad "CM23" smd circle
			(at -14.249908 23.040086 180)
			(size 0.450088 0.450088)
			(layers "F.Cu" "F.Mask" "F.Paste")
			(net "GND")
		)
		(pad "CM24" smd circle
			(at -13.310108 23.040086 180)
			(size 0.450088 0.450088)
			(layers "F.Cu" "F.Mask" "F.Paste")
			(net "GND")
		)
		(pad "CM25" smd circle
			(at -12.370054 23.040086 180)
			(size 0.450088 0.450088)
			(layers "F.Cu" "F.Mask" "F.Paste")
			(net "GND")
		)
		(pad "CM26" smd circle
			(at -11.43 23.040086 180)
			(size 0.450088 0.450088)
			(layers "F.Cu" "F.Mask" "F.Paste")
			(net "GND")
		)
		(pad "CM27" smd circle
			(at -10.489946 23.040086 180)
			(size 0.450088 0.450088)
			(layers "F.Cu" "F.Mask" "F.Paste")
			(net "GND")
		)
		(pad "CM28" smd circle
			(at -9.549892 23.040086 180)
			(size 0.450088 0.450088)
			(layers "F.Cu" "F.Mask" "F.Paste")
			(net "GND")
		)
		(pad "CM29" smd circle
			(at -8.610092 23.040086 180)
			(size 0.450088 0.450088)
			(layers "F.Cu" "F.Mask" "F.Paste")
			(net "GND")
		)
		(pad "CM30" smd circle
			(at -7.670038 23.040086 180)
			(size 0.450088 0.450088)
			(layers "F.Cu" "F.Mask" "F.Paste")
			(net "GND")
		)
		(pad "CM31" smd circle
			(at -6.729984 23.040086 180)
			(size 0.450088 0.450088)
			(layers "F.Cu" "F.Mask" "F.Paste")
			(net "GND")
		)
		(pad "CM32" smd circle
			(at -5.78993 23.040086 180)
			(size 0.450088 0.450088)
			(layers "F.Cu" "F.Mask" "F.Paste")
			(net "GND")
		)
		(pad "CM33" smd circle
			(at -4.849876 23.040086 180)
			(size 0.450088 0.450088)
			(layers "F.Cu" "F.Mask" "F.Paste")
			(net "GND")
		)
		(pad "CM34" smd circle
			(at -3.910076 23.040086 180)
			(size 0.450088 0.450088)
			(layers "F.Cu" "F.Mask" "F.Paste")
			(net "GND")
		)
		(pad "CM35" smd circle
			(at -2.970022 23.040086 180)
			(size 0.450088 0.450088)
			(layers "F.Cu" "F.Mask" "F.Paste")
			(net "P5E_CPU0_P2_RX_DP<0>")
		)
		(pad "CM36" smd circle
			(at -2.029968 23.040086 180)
			(size 0.450088 0.450088)
			(layers "F.Cu" "F.Mask" "F.Paste")
			(net "P5E_CPU0_P2_RX_DN<0>")
		)
		(pad "CM37" smd circle
			(at -1.089914 23.040086 180)
			(size 0.450088 0.450088)
			(layers "F.Cu" "F.Mask" "F.Paste")
			(net "GND")
		)
		(pad "CM39" smd circle
			(at 0.78994 23.040086 180)
			(size 0.450088 0.450088)
			(layers "F.Cu" "F.Mask" "F.Paste")
			(net "GND")
		)
		(pad "CM40" smd circle
			(at 1.729994 23.040086 180)
			(size 0.450088 0.450088)
			(layers "F.Cu" "F.Mask" "F.Paste")
			(net "P5E_CPU0_P0_TX_DN<15>")
		)
		(pad "CM41" smd circle
			(at 2.670048 23.040086 180)
			(size 0.450088 0.450088)
			(layers "F.Cu" "F.Mask" "F.Paste")
			(net "P5E_CPU0_P0_TX_DP<15>")
		)
		(pad "CM42" smd circle
			(at 3.610102 23.040086 180)
			(size 0.450088 0.450088)
			(layers "F.Cu" "F.Mask" "F.Paste")
			(net "GND")
		)
		(pad "CM43" smd circle
			(at 4.549902 23.040086 180)
			(size 0.450088 0.450088)
			(layers "F.Cu" "F.Mask" "F.Paste")
			(net "GND")
		)
		(pad "CM44" smd circle
			(at 5.489956 23.040086 180)
			(size 0.450088 0.450088)
			(layers "F.Cu" "F.Mask" "F.Paste")
			(net "GND")
		)
		(pad "CM45" smd circle
			(at 6.43001 23.040086 180)
			(size 0.450088 0.450088)
			(layers "F.Cu" "F.Mask" "F.Paste")
			(net "GND")
		)
		(pad "CM46" smd circle
			(at 7.370064 23.040086 180)
			(size 0.450088 0.450088)
			(layers "F.Cu" "F.Mask" "F.Paste")
			(net "GND")
		)
		(pad "CM47" smd circle
			(at 8.310118 23.040086 180)
			(size 0.450088 0.450088)
			(layers "F.Cu" "F.Mask" "F.Paste")
			(net "GND")
		)
		(pad "CM48" smd circle
			(at 9.249918 23.040086 180)
			(size 0.450088 0.450088)
			(layers "F.Cu" "F.Mask" "F.Paste")
			(net "GND")
		)
		(pad "CM49" smd circle
			(at 10.189972 23.040086 180)
			(size 0.450088 0.450088)
			(layers "F.Cu" "F.Mask" "F.Paste")
			(net "GND")
		)
		(pad "CM50" smd circle
			(at 11.130026 23.040086 180)
			(size 0.450088 0.450088)
			(layers "F.Cu" "F.Mask" "F.Paste")
			(net "GND")
		)
		(pad "CM51" smd circle
			(at 12.07008 23.040086 180)
			(size 0.450088 0.450088)
			(layers "F.Cu" "F.Mask" "F.Paste")
			(net "GND")
		)
		(pad "CM52" smd circle
			(at 13.00988 23.040086 180)
			(size 0.450088 0.450088)
			(layers "F.Cu" "F.Mask" "F.Paste")
			(net "GND")
		)
		(pad "CM53" smd circle
			(at 13.949934 23.040086 180)
			(size 0.450088 0.450088)
			(layers "F.Cu" "F.Mask" "F.Paste")
			(net "GND")
		)
		(pad "CM54" smd circle
			(at 14.889988 23.040086 180)
			(size 0.450088 0.450088)
			(layers "F.Cu" "F.Mask" "F.Paste")
			(net "PVDDIO_P0")
		)
		(pad "CM55" smd circle
			(at 15.830042 23.040086 180)
			(size 0.450088 0.450088)
			(layers "F.Cu" "F.Mask" "F.Paste")
			(net "M_C_CPU0_SB_DQS_DP<6>")
		)
		(pad "CM56" smd circle
			(at 16.770096 23.040086 180)
			(size 0.450088 0.450088)
			(layers "F.Cu" "F.Mask" "F.Paste")
			(net "M_C_CPU0_SB_DQ<12>")
		)
		(pad "CM57" smd circle
			(at 17.709896 23.040086 180)
			(size 0.450088 0.450088)
			(layers "F.Cu" "F.Mask" "F.Paste")
			(net "GND")
		)
		(pad "CM58" smd circle
			(at 18.64995 23.040086 180)
			(size 0.450088 0.450088)
			(layers "F.Cu" "F.Mask" "F.Paste")
			(net "M_D_CPU0_SB_DQS_DP<6>")
		)
		(pad "CM59" smd circle
			(at 19.590004 23.040086 180)
			(size 0.450088 0.450088)
			(layers "F.Cu" "F.Mask" "F.Paste")
			(net "GND")
		)
		(pad "CM60" smd circle
			(at 20.530058 23.040086 180)
			(size 0.450088 0.450088)
			(layers "F.Cu" "F.Mask" "F.Paste")
			(net "M_D_CPU0_SB_DQ<12>")
		)
		(pad "CM61" smd circle
			(at 21.470112 23.040086 180)
			(size 0.450088 0.450088)
			(layers "F.Cu" "F.Mask" "F.Paste")
			(net "GND")
		)
		(pad "CM62" smd circle
			(at 22.409912 23.040086 180)
			(size 0.450088 0.450088)
			(layers "F.Cu" "F.Mask" "F.Paste")
			(net "M_B_CPU0_SB_DQS_DP<6>")
		)
		(pad "CM63" smd circle
			(at 23.349966 23.040086 180)
			(size 0.450088 0.450088)
			(layers "F.Cu" "F.Mask" "F.Paste")
			(net "M_B_CPU0_SB_DQ<12>")
		)
		(pad "CM64" smd circle
			(at 24.29002 23.040086 180)
			(size 0.450088 0.450088)
			(layers "F.Cu" "F.Mask" "F.Paste")
			(net "GND")
		)
		(pad "CM65" smd circle
			(at 25.230074 23.040086 180)
			(size 0.450088 0.450088)
			(layers "F.Cu" "F.Mask" "F.Paste")
			(net "M_F_CPU0_SB_DQS_DP<6>")
		)
		(pad "CM66" smd circle
			(at 26.170128 23.040086 180)
			(size 0.450088 0.450088)
			(layers "F.Cu" "F.Mask" "F.Paste")
			(net "GND")
		)
		(pad "CM67" smd circle
			(at 27.109928 23.040086 180)
			(size 0.450088 0.450088)
			(layers "F.Cu" "F.Mask" "F.Paste")
			(net "M_F_CPU0_SB_DQ<12>")
		)
		(pad "CM68" smd circle
			(at 28.049982 23.040086 180)
			(size 0.450088 0.450088)
			(layers "F.Cu" "F.Mask" "F.Paste")
			(net "GND")
		)
		(pad "CM69" smd circle
			(at 28.990036 23.040086 180)
			(size 0.450088 0.450088)
			(layers "F.Cu" "F.Mask" "F.Paste")
			(net "M_E_CPU0_SB_DQS_DP<6>")
		)
		(pad "CM70" smd circle
			(at 29.93009 23.040086 180)
			(size 0.450088 0.450088)
			(layers "F.Cu" "F.Mask" "F.Paste")
			(net "M_E_CPU0_SB_DQ<12>")
		)
		(pad "CM71" smd circle
			(at 30.86989 23.040086 180)
			(size 0.450088 0.450088)
			(layers "F.Cu" "F.Mask" "F.Paste")
			(net "GND")
		)
		(pad "CM72" smd circle
			(at 31.809944 23.040086 180)
			(size 0.450088 0.450088)
			(layers "F.Cu" "F.Mask" "F.Paste")
			(net "M_A_CPU0_SB_DQS_DP<6>")
		)
		(pad "CM73" smd circle
			(at 32.749998 23.040086 180)
			(size 0.450088 0.450088)
			(layers "F.Cu" "F.Mask" "F.Paste")
			(net "GND")
		)
		(pad "CM74" smd circle
			(at 33.690052 23.040086 180)
			(size 0.450088 0.450088)
			(layers "F.Cu" "F.Mask" "F.Paste")
			(net "M_A_CPU0_SB_DQ<12>")
		)
		(pad "CN1" smd circle
			(at -34.459926 23.850092 180)
			(size 0.450088 0.450088)
			(layers "F.Cu" "F.Mask" "F.Paste")
			(net "GND")
		)
		(pad "CN2" smd circle
			(at -33.519872 23.850092 180)
			(size 0.450088 0.450088)
			(layers "F.Cu" "F.Mask" "F.Paste")
			(net "M_G_CPU0_SB_DQ<14>")
		)
		(pad "CN3" smd circle
			(at -32.580072 23.850092 180)
			(size 0.450088 0.450088)
			(layers "F.Cu" "F.Mask" "F.Paste")
			(net "M_G_CPU0_SB_DQ<13>")
		)
		(pad "CN4" smd circle
			(at -31.640018 23.850092 180)
			(size 0.450088 0.450088)
			(layers "F.Cu" "F.Mask" "F.Paste")
			(net "PVDD11_S3_P0")
		)
		(pad "CN5" smd circle
			(at -30.699964 23.850092 180)
			(size 0.450088 0.450088)
			(layers "F.Cu" "F.Mask" "F.Paste")
			(net "M_K_CPU0_SB_DQ<14>")
		)
		(pad "CN6" smd circle
			(at -29.75991 23.850092 180)
			(size 0.450088 0.450088)
			(layers "F.Cu" "F.Mask" "F.Paste")
			(net "GND")
		)
		(pad "CN7" smd circle
			(at -28.82011 23.850092 180)
			(size 0.450088 0.450088)
			(layers "F.Cu" "F.Mask" "F.Paste")
			(net "M_K_CPU0_SB_DQ<13>")
		)
		(pad "CN8" smd circle
			(at -27.880056 23.850092 180)
			(size 0.450088 0.450088)
			(layers "F.Cu" "F.Mask" "F.Paste")
			(net "GND")
		)
		(pad "CN9" smd circle
			(at -26.940002 23.850092 180)
			(size 0.450088 0.450088)
			(layers "F.Cu" "F.Mask" "F.Paste")
			(net "M_L_CPU0_SB_DQ<14>")
		)
		(pad "CN10" smd circle
			(at -25.999948 23.850092 180)
			(size 0.450088 0.450088)
			(layers "F.Cu" "F.Mask" "F.Paste")
			(net "M_L_CPU0_SB_DQ<13>")
		)
		(pad "CN11" smd circle
			(at -25.059894 23.850092 180)
			(size 0.450088 0.450088)
			(layers "F.Cu" "F.Mask" "F.Paste")
			(net "PVDD11_S3_P0")
		)
		(pad "CN12" smd circle
			(at -24.120094 23.850092 180)
			(size 0.450088 0.450088)
			(layers "F.Cu" "F.Mask" "F.Paste")
			(net "M_H_CPU0_SB_DQ<14>")
		)
		(pad "CN13" smd circle
			(at -23.18004 23.850092 180)
			(size 0.450088 0.450088)
			(layers "F.Cu" "F.Mask" "F.Paste")
			(net "GND")
		)
		(pad "CN14" smd circle
			(at -22.239986 23.850092 180)
			(size 0.450088 0.450088)
			(layers "F.Cu" "F.Mask" "F.Paste")
			(net "M_H_CPU0_SB_DQ<13>")
		)
		(pad "CN15" smd circle
			(at -21.299932 23.850092 180)
			(size 0.450088 0.450088)
			(layers "F.Cu" "F.Mask" "F.Paste")
			(net "GND")
		)
		(pad "CN16" smd circle
			(at -20.359878 23.850092 180)
			(size 0.450088 0.450088)
			(layers "F.Cu" "F.Mask" "F.Paste")
			(net "M_J_CPU0_SB_DQ<14>")
		)
		(pad "CN17" smd circle
			(at -19.420078 23.850092 180)
			(size 0.450088 0.450088)
			(layers "F.Cu" "F.Mask" "F.Paste")
			(net "M_J_CPU0_SB_DQ<13>")
		)
		(pad "CN18" smd circle
			(at -18.480024 23.850092 180)
			(size 0.450088 0.450088)
			(layers "F.Cu" "F.Mask" "F.Paste")
			(net "PVDD11_S3_P0")
		)
		(pad "CN19" smd circle
			(at -17.53997 23.850092 180)
			(size 0.450088 0.450088)
			(layers "F.Cu" "F.Mask" "F.Paste")
			(net "M_I_CPU0_SB_DQ<14>")
		)
		(pad "CN20" smd circle
			(at -16.599916 23.850092 180)
			(size 0.450088 0.450088)
			(layers "F.Cu" "F.Mask" "F.Paste")
			(net "GND")
		)
		(pad "CN21" smd circle
			(at -15.660116 23.850092 180)
			(size 0.450088 0.450088)
			(layers "F.Cu" "F.Mask" "F.Paste")
			(net "M_I_CPU0_SB_DQ<13>")
		)
		(pad "CN22" smd circle
			(at -14.720062 23.850092 180)
			(size 0.450088 0.450088)
			(layers "F.Cu" "F.Mask" "F.Paste")
			(net "GND")
		)
		(pad "CN23" smd circle
			(at -13.780008 23.850092 180)
			(size 0.450088 0.450088)
			(layers "F.Cu" "F.Mask" "F.Paste")
			(net "P5E_CPU0_P2_RX_DP<15>")
		)
		(pad "CN24" smd circle
			(at -12.839954 23.850092 180)
			(size 0.450088 0.450088)
			(layers "F.Cu" "F.Mask" "F.Paste")
			(net "P5E_CPU0_P2_RX_DN<15>")
		)
		(pad "CN25" smd circle
			(at -11.8999 23.850092 180)
			(size 0.450088 0.450088)
			(layers "F.Cu" "F.Mask" "F.Paste")
			(net "GND")
		)
		(pad "CN26" smd circle
			(at -10.9601 23.850092 180)
			(size 0.450088 0.450088)
			(layers "F.Cu" "F.Mask" "F.Paste")
			(net "P5E_CPU0_P2_RX_DP<12>")
		)
		(pad "CN27" smd circle
			(at -10.020046 23.850092 180)
			(size 0.450088 0.450088)
			(layers "F.Cu" "F.Mask" "F.Paste")
			(net "P5E_CPU0_P2_RX_DN<12>")
		)
		(pad "CN28" smd circle
			(at -9.079992 23.850092 180)
			(size 0.450088 0.450088)
			(layers "F.Cu" "F.Mask" "F.Paste")
			(net "GND")
		)
		(pad "CN29" smd circle
			(at -8.139938 23.850092 180)
			(size 0.450088 0.450088)
			(layers "F.Cu" "F.Mask" "F.Paste")
			(net "P5E_CPU0_P2_RX_DP<6>")
		)
		(pad "CN30" smd circle
			(at -7.199884 23.850092 180)
			(size 0.450088 0.450088)
			(layers "F.Cu" "F.Mask" "F.Paste")
			(net "P5E_CPU0_P2_RX_DN<6>")
		)
		(pad "CN31" smd circle
			(at -6.260084 23.850092 180)
			(size 0.450088 0.450088)
			(layers "F.Cu" "F.Mask" "F.Paste")
			(net "GND")
		)
		(pad "CN32" smd circle
			(at -5.32003 23.850092 180)
			(size 0.450088 0.450088)
			(layers "F.Cu" "F.Mask" "F.Paste")
			(net "P5E_CPU0_P2_RX_DP<3>")
		)
		(pad "CN33" smd circle
			(at -4.379976 23.850092 180)
			(size 0.450088 0.450088)
			(layers "F.Cu" "F.Mask" "F.Paste")
			(net "P5E_CPU0_P2_RX_DN<3>")
		)
		(pad "CN34" smd circle
			(at -3.439922 23.850092 180)
			(size 0.450088 0.450088)
			(layers "F.Cu" "F.Mask" "F.Paste")
			(net "GND")
		)
		(pad "CN35" smd circle
			(at -2.500122 23.850092 180)
			(size 0.450088 0.450088)
			(layers "F.Cu" "F.Mask" "F.Paste")
			(net "PVDDCR_CPU1_P0")
		)
		(pad "CN36" smd circle
			(at -1.560068 23.850092 180)
			(size 0.450088 0.450088)
			(layers "F.Cu" "F.Mask" "F.Paste")
			(net "PVDDCR_CPU1_P0")
		)
		(pad "CN40" smd circle
			(at 1.260094 23.850092 180)
			(size 0.450088 0.450088)
			(layers "F.Cu" "F.Mask" "F.Paste")
			(net "PVDDCR_CPU1_P0")
		)
		(pad "CN41" smd circle
			(at 2.199894 23.850092 180)
			(size 0.450088 0.450088)
			(layers "F.Cu" "F.Mask" "F.Paste")
			(net "PVDDCR_CPU1_P0")
		)
		(pad "CN42" smd circle
			(at 3.139948 23.850092 180)
			(size 0.450088 0.450088)
			(layers "F.Cu" "F.Mask" "F.Paste")
			(net "GND")
		)
		(pad "CN43" smd circle
			(at 4.080002 23.850092 180)
			(size 0.450088 0.450088)
			(layers "F.Cu" "F.Mask" "F.Paste")
			(net "P5E_CPU0_P0_TX_DN<12>")
		)
		(pad "CN44" smd circle
			(at 5.020056 23.850092 180)
			(size 0.450088 0.450088)
			(layers "F.Cu" "F.Mask" "F.Paste")
			(net "P5E_CPU0_P0_TX_DP<12>")
		)
		(pad "CN45" smd circle
			(at 5.96011 23.850092 180)
			(size 0.450088 0.450088)
			(layers "F.Cu" "F.Mask" "F.Paste")
			(net "GND")
		)
		(pad "CN46" smd circle
			(at 6.89991 23.850092 180)
			(size 0.450088 0.450088)
			(layers "F.Cu" "F.Mask" "F.Paste")
			(net "P5E_CPU0_P0_TX_DN<9>")
		)
		(pad "CN47" smd circle
			(at 7.839964 23.850092 180)
			(size 0.450088 0.450088)
			(layers "F.Cu" "F.Mask" "F.Paste")
			(net "P5E_CPU0_P0_TX_DP<9>")
		)
		(pad "CN48" smd circle
			(at 8.780018 23.850092 180)
			(size 0.450088 0.450088)
			(layers "F.Cu" "F.Mask" "F.Paste")
			(net "GND")
		)
		(pad "CN49" smd circle
			(at 9.720072 23.850092 180)
			(size 0.450088 0.450088)
			(layers "F.Cu" "F.Mask" "F.Paste")
			(net "P5E_CPU0_P0_TX_DN<3>")
		)
		(pad "CN50" smd circle
			(at 10.659872 23.850092 180)
			(size 0.450088 0.450088)
			(layers "F.Cu" "F.Mask" "F.Paste")
			(net "P5E_CPU0_P0_TX_DP<3>")
		)
		(pad "CN51" smd circle
			(at 11.599926 23.850092 180)
			(size 0.450088 0.450088)
			(layers "F.Cu" "F.Mask" "F.Paste")
			(net "GND")
		)
		(pad "CN52" smd circle
			(at 12.53998 23.850092 180)
			(size 0.450088 0.450088)
			(layers "F.Cu" "F.Mask" "F.Paste")
			(net "P5E_CPU0_P0_TX_DN<0>")
		)
		(pad "CN53" smd circle
			(at 13.480034 23.850092 180)
			(size 0.450088 0.450088)
			(layers "F.Cu" "F.Mask" "F.Paste")
			(net "P5E_CPU0_P0_TX_DP<0>")
		)
		(pad "CN54" smd circle
			(at 14.420088 23.850092 180)
			(size 0.450088 0.450088)
			(layers "F.Cu" "F.Mask" "F.Paste")
			(net "GND")
		)
		(pad "CN55" smd circle
			(at 15.359888 23.850092 180)
			(size 0.450088 0.450088)
			(layers "F.Cu" "F.Mask" "F.Paste")
			(net "M_C_CPU0_SB_DQ<13>")
		)
		(pad "CN56" smd circle
			(at 16.299942 23.850092 180)
			(size 0.450088 0.450088)
			(layers "F.Cu" "F.Mask" "F.Paste")
			(net "GND")
		)
		(pad "CN57" smd circle
			(at 17.239996 23.850092 180)
			(size 0.450088 0.450088)
			(layers "F.Cu" "F.Mask" "F.Paste")
			(net "M_C_CPU0_SB_DQ<14>")
		)
		(pad "CN58" smd circle
			(at 18.18005 23.850092 180)
			(size 0.450088 0.450088)
			(layers "F.Cu" "F.Mask" "F.Paste")
			(net "PVDDIO_P0")
		)
		(pad "CN59" smd circle
			(at 19.120104 23.850092 180)
			(size 0.450088 0.450088)
			(layers "F.Cu" "F.Mask" "F.Paste")
			(net "M_D_CPU0_SB_DQ<13>")
		)
		(pad "CN60" smd circle
			(at 20.059904 23.850092 180)
			(size 0.450088 0.450088)
			(layers "F.Cu" "F.Mask" "F.Paste")
			(net "M_D_CPU0_SB_DQ<14>")
		)
		(pad "CN61" smd circle
			(at 20.999958 23.850092 180)
			(size 0.450088 0.450088)
			(layers "F.Cu" "F.Mask" "F.Paste")
			(net "GND")
		)
		(pad "CN62" smd circle
			(at 21.940012 23.850092 180)
			(size 0.450088 0.450088)
			(layers "F.Cu" "F.Mask" "F.Paste")
			(net "M_B_CPU0_SB_DQ<13>")
		)
		(pad "CN63" smd circle
			(at 22.880066 23.850092 180)
			(size 0.450088 0.450088)
			(layers "F.Cu" "F.Mask" "F.Paste")
			(net "GND")
		)
		(pad "CN64" smd circle
			(at 23.82012 23.850092 180)
			(size 0.450088 0.450088)
			(layers "F.Cu" "F.Mask" "F.Paste")
			(net "M_B_CPU0_SB_DQ<14>")
		)
		(pad "CN65" smd circle
			(at 24.75992 23.850092 180)
			(size 0.450088 0.450088)
			(layers "F.Cu" "F.Mask" "F.Paste")
			(net "PVDDIO_P0")
		)
		(pad "CN66" smd circle
			(at 25.699974 23.850092 180)
			(size 0.450088 0.450088)
			(layers "F.Cu" "F.Mask" "F.Paste")
			(net "M_F_CPU0_SB_DQ<13>")
		)
		(pad "CN67" smd circle
			(at 26.640028 23.850092 180)
			(size 0.450088 0.450088)
			(layers "F.Cu" "F.Mask" "F.Paste")
			(net "M_F_CPU0_SB_DQ<14>")
		)
		(pad "CN68" smd circle
			(at 27.580082 23.850092 180)
			(size 0.450088 0.450088)
			(layers "F.Cu" "F.Mask" "F.Paste")
			(net "GND")
		)
		(pad "CN69" smd circle
			(at 28.519882 23.850092 180)
			(size 0.450088 0.450088)
			(layers "F.Cu" "F.Mask" "F.Paste")
			(net "M_E_CPU0_SB_DQ<13>")
		)
		(pad "CN70" smd circle
			(at 29.459936 23.850092 180)
			(size 0.450088 0.450088)
			(layers "F.Cu" "F.Mask" "F.Paste")
			(net "GND")
		)
		(pad "CN71" smd circle
			(at 30.39999 23.850092 180)
			(size 0.450088 0.450088)
			(layers "F.Cu" "F.Mask" "F.Paste")
			(net "M_E_CPU0_SB_DQ<14>")
		)
		(pad "CN72" smd circle
			(at 31.340044 23.850092 180)
			(size 0.450088 0.450088)
			(layers "F.Cu" "F.Mask" "F.Paste")
			(net "PVDDIO_P0")
		)
		(pad "CN73" smd circle
			(at 32.280098 23.850092 180)
			(size 0.450088 0.450088)
			(layers "F.Cu" "F.Mask" "F.Paste")
			(net "M_A_CPU0_SB_DQ<13>")
		)
		(pad "CN74" smd circle
			(at 33.219898 23.850092 180)
			(size 0.450088 0.450088)
			(layers "F.Cu" "F.Mask" "F.Paste")
			(net "M_A_CPU0_SB_DQ<14>")
		)
		(pad "CN75" smd circle
			(at 34.159952 23.850092 180)
			(size 0.450088 0.450088)
			(layers "F.Cu" "F.Mask" "F.Paste")
			(net "GND")
		)
		(pad "CP2" smd circle
			(at -33.990026 24.660098 180)
			(size 0.450088 0.450088)
			(layers "F.Cu" "F.Mask" "F.Paste")
			(net "M_G_CPU0_SB_DQ<16>")
		)
		(pad "CP3" smd circle
			(at -33.049972 24.660098 180)
			(size 0.450088 0.450088)
			(layers "F.Cu" "F.Mask" "F.Paste")
			(net "GND")
		)
		(pad "CP4" smd circle
			(at -32.109918 24.660098 180)
			(size 0.450088 0.450088)
			(layers "F.Cu" "F.Mask" "F.Paste")
			(net "M_G_CPU0_SB_DQ<15>")
		)
		(pad "CP5" smd circle
			(at -31.170118 24.660098 180)
			(size 0.450088 0.450088)
			(layers "F.Cu" "F.Mask" "F.Paste")
			(net "GND")
		)
		(pad "CP6" smd circle
			(at -30.230064 24.660098 180)
			(size 0.450088 0.450088)
			(layers "F.Cu" "F.Mask" "F.Paste")
			(net "M_K_CPU0_SB_DQ<16>")
		)
		(pad "CP7" smd circle
			(at -29.29001 24.660098 180)
			(size 0.450088 0.450088)
			(layers "F.Cu" "F.Mask" "F.Paste")
			(net "M_K_CPU0_SB_DQ<15>")
		)
		(pad "CP8" smd circle
			(at -28.349956 24.660098 180)
			(size 0.450088 0.450088)
			(layers "F.Cu" "F.Mask" "F.Paste")
			(net "GND")
		)
		(pad "CP9" smd circle
			(at -27.409902 24.660098 180)
			(size 0.450088 0.450088)
			(layers "F.Cu" "F.Mask" "F.Paste")
			(net "M_L_CPU0_SB_DQ<16>")
		)
		(pad "CP10" smd circle
			(at -26.470102 24.660098 180)
			(size 0.450088 0.450088)
			(layers "F.Cu" "F.Mask" "F.Paste")
			(net "GND")
		)
		(pad "CP11" smd circle
			(at -25.530048 24.660098 180)
			(size 0.450088 0.450088)
			(layers "F.Cu" "F.Mask" "F.Paste")
			(net "M_L_CPU0_SB_DQ<15>")
		)
		(pad "CP12" smd circle
			(at -24.589994 24.660098 180)
			(size 0.450088 0.450088)
			(layers "F.Cu" "F.Mask" "F.Paste")
			(net "GND")
		)
		(pad "CP13" smd circle
			(at -23.64994 24.660098 180)
			(size 0.450088 0.450088)
			(layers "F.Cu" "F.Mask" "F.Paste")
			(net "M_H_CPU0_SB_DQ<16>")
		)
		(pad "CP14" smd circle
			(at -22.709886 24.660098 180)
			(size 0.450088 0.450088)
			(layers "F.Cu" "F.Mask" "F.Paste")
			(net "M_H_CPU0_SB_DQ<15>")
		)
		(pad "CP15" smd circle
			(at -21.770086 24.660098 180)
			(size 0.450088 0.450088)
			(layers "F.Cu" "F.Mask" "F.Paste")
			(net "GND")
		)
		(pad "CP16" smd circle
			(at -20.830032 24.660098 180)
			(size 0.450088 0.450088)
			(layers "F.Cu" "F.Mask" "F.Paste")
			(net "M_J_CPU0_SB_DQ<16>")
		)
		(pad "CP17" smd circle
			(at -19.889978 24.660098 180)
			(size 0.450088 0.450088)
			(layers "F.Cu" "F.Mask" "F.Paste")
			(net "GND")
		)
		(pad "CP18" smd circle
			(at -18.949924 24.660098 180)
			(size 0.450088 0.450088)
			(layers "F.Cu" "F.Mask" "F.Paste")
			(net "M_J_CPU0_SB_DQ<15>")
		)
		(pad "CP19" smd circle
			(at -18.010124 24.660098 180)
			(size 0.450088 0.450088)
			(layers "F.Cu" "F.Mask" "F.Paste")
			(net "GND")
		)
		(pad "CP20" smd circle
			(at -17.07007 24.660098 180)
			(size 0.450088 0.450088)
			(layers "F.Cu" "F.Mask" "F.Paste")
			(net "M_I_CPU0_SB_DQ<16>")
		)
		(pad "CP21" smd circle
			(at -16.130016 24.660098 180)
			(size 0.450088 0.450088)
			(layers "F.Cu" "F.Mask" "F.Paste")
			(net "M_I_CPU0_SB_DQ<15>")
		)
		(pad "CP22" smd circle
			(at -15.189962 24.660098 180)
			(size 0.450088 0.450088)
			(layers "F.Cu" "F.Mask" "F.Paste")
			(net "GND")
		)
		(pad "CP23" smd circle
			(at -14.249908 24.660098 180)
			(size 0.450088 0.450088)
			(layers "F.Cu" "F.Mask" "F.Paste")
			(net "PVDDCR_CPU1_P0")
		)
		(pad "CP24" smd circle
			(at -13.310108 24.660098 180)
			(size 0.450088 0.450088)
			(layers "F.Cu" "F.Mask" "F.Paste")
			(net "PVDDCR_CPU1_P0")
		)
		(pad "CP25" smd circle
			(at -12.370054 24.660098 180)
			(size 0.450088 0.450088)
			(layers "F.Cu" "F.Mask" "F.Paste")
			(net "GND")
		)
		(pad "CP26" smd circle
			(at -11.43 24.660098 180)
			(size 0.450088 0.450088)
			(layers "F.Cu" "F.Mask" "F.Paste")
			(net "PVDDCR_CPU1_P0")
		)
		(pad "CP27" smd circle
			(at -10.489946 24.660098 180)
			(size 0.450088 0.450088)
			(layers "F.Cu" "F.Mask" "F.Paste")
			(net "PVDDCR_CPU1_P0")
		)
		(pad "CP28" smd circle
			(at -9.549892 24.660098 180)
			(size 0.450088 0.450088)
			(layers "F.Cu" "F.Mask" "F.Paste")
			(net "GND")
		)
		(pad "CP29" smd circle
			(at -8.610092 24.660098 180)
			(size 0.450088 0.450088)
			(layers "F.Cu" "F.Mask" "F.Paste")
			(net "PVDDCR_CPU1_P0")
		)
		(pad "CP30" smd circle
			(at -7.670038 24.660098 180)
			(size 0.450088 0.450088)
			(layers "F.Cu" "F.Mask" "F.Paste")
			(net "PVDDCR_CPU1_P0")
		)
		(pad "CP31" smd circle
			(at -6.729984 24.660098 180)
			(size 0.450088 0.450088)
			(layers "F.Cu" "F.Mask" "F.Paste")
			(net "GND")
		)
		(pad "CP32" smd circle
			(at -5.78993 24.660098 180)
			(size 0.450088 0.450088)
			(layers "F.Cu" "F.Mask" "F.Paste")
			(net "PVDDCR_CPU1_P0")
		)
		(pad "CP33" smd circle
			(at -4.849876 24.660098 180)
			(size 0.450088 0.450088)
			(layers "F.Cu" "F.Mask" "F.Paste")
			(net "PVDDCR_CPU1_P0")
		)
		(pad "CP34" smd circle
			(at -3.910076 24.660098 180)
			(size 0.450088 0.450088)
			(layers "F.Cu" "F.Mask" "F.Paste")
			(net "GND")
		)
		(pad "CP35" smd circle
			(at -2.970022 24.660098 180)
			(size 0.450088 0.450088)
			(layers "F.Cu" "F.Mask" "F.Paste")
			(net "P5E_CPU0_P2_RX_DP<1>")
		)
		(pad "CP36" smd circle
			(at -2.029968 24.660098 180)
			(size 0.450088 0.450088)
			(layers "F.Cu" "F.Mask" "F.Paste")
			(net "P5E_CPU0_P2_RX_DN<1>")
		)
		(pad "CP37" smd circle
			(at -1.089914 24.660098 180)
			(size 0.450088 0.450088)
			(layers "F.Cu" "F.Mask" "F.Paste")
			(net "GND")
		)
		(pad "CP39" smd circle
			(at 0.78994 24.660098 180)
			(size 0.450088 0.450088)
			(layers "F.Cu" "F.Mask" "F.Paste")
			(net "GND")
		)
		(pad "CP40" smd circle
			(at 1.729994 24.660098 180)
			(size 0.450088 0.450088)
			(layers "F.Cu" "F.Mask" "F.Paste")
			(net "P5E_CPU0_P0_TX_DN<14>")
		)
		(pad "CP41" smd circle
			(at 2.670048 24.660098 180)
			(size 0.450088 0.450088)
			(layers "F.Cu" "F.Mask" "F.Paste")
			(net "P5E_CPU0_P0_TX_DP<14>")
		)
		(pad "CP42" smd circle
			(at 3.610102 24.660098 180)
			(size 0.450088 0.450088)
			(layers "F.Cu" "F.Mask" "F.Paste")
			(net "GND")
		)
		(pad "CP43" smd circle
			(at 4.549902 24.660098 180)
			(size 0.450088 0.450088)
			(layers "F.Cu" "F.Mask" "F.Paste")
			(net "PVDDCR_CPU1_P0")
		)
		(pad "CP44" smd circle
			(at 5.489956 24.660098 180)
			(size 0.450088 0.450088)
			(layers "F.Cu" "F.Mask" "F.Paste")
			(net "PVDDCR_CPU1_P0")
		)
		(pad "CP45" smd circle
			(at 6.43001 24.660098 180)
			(size 0.450088 0.450088)
			(layers "F.Cu" "F.Mask" "F.Paste")
			(net "GND")
		)
		(pad "CP46" smd circle
			(at 7.370064 24.660098 180)
			(size 0.450088 0.450088)
			(layers "F.Cu" "F.Mask" "F.Paste")
			(net "PVDDCR_CPU1_P0")
		)
		(pad "CP47" smd circle
			(at 8.310118 24.660098 180)
			(size 0.450088 0.450088)
			(layers "F.Cu" "F.Mask" "F.Paste")
			(net "PVDDCR_CPU1_P0")
		)
		(pad "CP48" smd circle
			(at 9.249918 24.660098 180)
			(size 0.450088 0.450088)
			(layers "F.Cu" "F.Mask" "F.Paste")
			(net "GND")
		)
		(pad "CP49" smd circle
			(at 10.189972 24.660098 180)
			(size 0.450088 0.450088)
			(layers "F.Cu" "F.Mask" "F.Paste")
			(net "PVDDCR_CPU1_P0")
		)
		(pad "CP50" smd circle
			(at 11.130026 24.660098 180)
			(size 0.450088 0.450088)
			(layers "F.Cu" "F.Mask" "F.Paste")
			(net "PVDDCR_CPU1_P0")
		)
		(pad "CP51" smd circle
			(at 12.07008 24.660098 180)
			(size 0.450088 0.450088)
			(layers "F.Cu" "F.Mask" "F.Paste")
			(net "GND")
		)
		(pad "CP52" smd circle
			(at 13.00988 24.660098 180)
			(size 0.450088 0.450088)
			(layers "F.Cu" "F.Mask" "F.Paste")
			(net "PVDDCR_CPU1_P0")
		)
		(pad "CP53" smd circle
			(at 13.949934 24.660098 180)
			(size 0.450088 0.450088)
			(layers "F.Cu" "F.Mask" "F.Paste")
			(net "PVDDCR_CPU1_P0")
		)
		(pad "CP54" smd circle
			(at 14.889988 24.660098 180)
			(size 0.450088 0.450088)
			(layers "F.Cu" "F.Mask" "F.Paste")
			(net "GND")
		)
		(pad "CP55" smd circle
			(at 15.830042 24.660098 180)
			(size 0.450088 0.450088)
			(layers "F.Cu" "F.Mask" "F.Paste")
			(net "M_C_CPU0_SB_DQ<15>")
		)
		(pad "CP56" smd circle
			(at 16.770096 24.660098 180)
			(size 0.450088 0.450088)
			(layers "F.Cu" "F.Mask" "F.Paste")
			(net "M_C_CPU0_SB_DQ<16>")
		)
		(pad "CP57" smd circle
			(at 17.709896 24.660098 180)
			(size 0.450088 0.450088)
			(layers "F.Cu" "F.Mask" "F.Paste")
			(net "GND")
		)
		(pad "CP58" smd circle
			(at 18.64995 24.660098 180)
			(size 0.450088 0.450088)
			(layers "F.Cu" "F.Mask" "F.Paste")
			(net "M_D_CPU0_SB_DQ<15>")
		)
		(pad "CP59" smd circle
			(at 19.590004 24.660098 180)
			(size 0.450088 0.450088)
			(layers "F.Cu" "F.Mask" "F.Paste")
			(net "GND")
		)
		(pad "CP60" smd circle
			(at 20.530058 24.660098 180)
			(size 0.450088 0.450088)
			(layers "F.Cu" "F.Mask" "F.Paste")
			(net "M_D_CPU0_SB_DQ<16>")
		)
		(pad "CP61" smd circle
			(at 21.470112 24.660098 180)
			(size 0.450088 0.450088)
			(layers "F.Cu" "F.Mask" "F.Paste")
			(net "GND")
		)
		(pad "CP62" smd circle
			(at 22.409912 24.660098 180)
			(size 0.450088 0.450088)
			(layers "F.Cu" "F.Mask" "F.Paste")
			(net "M_B_CPU0_SB_DQ<15>")
		)
		(pad "CP63" smd circle
			(at 23.349966 24.660098 180)
			(size 0.450088 0.450088)
			(layers "F.Cu" "F.Mask" "F.Paste")
			(net "M_B_CPU0_SB_DQ<16>")
		)
		(pad "CP64" smd circle
			(at 24.29002 24.660098 180)
			(size 0.450088 0.450088)
			(layers "F.Cu" "F.Mask" "F.Paste")
			(net "GND")
		)
		(pad "CP65" smd circle
			(at 25.230074 24.660098 180)
			(size 0.450088 0.450088)
			(layers "F.Cu" "F.Mask" "F.Paste")
			(net "M_F_CPU0_SB_DQ<15>")
		)
		(pad "CP66" smd circle
			(at 26.170128 24.660098 180)
			(size 0.450088 0.450088)
			(layers "F.Cu" "F.Mask" "F.Paste")
			(net "GND")
		)
		(pad "CP67" smd circle
			(at 27.109928 24.660098 180)
			(size 0.450088 0.450088)
			(layers "F.Cu" "F.Mask" "F.Paste")
			(net "M_F_CPU0_SB_DQ<16>")
		)
		(pad "CP68" smd circle
			(at 28.049982 24.660098 180)
			(size 0.450088 0.450088)
			(layers "F.Cu" "F.Mask" "F.Paste")
			(net "GND")
		)
		(pad "CP69" smd circle
			(at 28.990036 24.660098 180)
			(size 0.450088 0.450088)
			(layers "F.Cu" "F.Mask" "F.Paste")
			(net "M_E_CPU0_SB_DQ<15>")
		)
		(pad "CP70" smd circle
			(at 29.93009 24.660098 180)
			(size 0.450088 0.450088)
			(layers "F.Cu" "F.Mask" "F.Paste")
			(net "M_E_CPU0_SB_DQ<16>")
		)
		(pad "CP71" smd circle
			(at 30.86989 24.660098 180)
			(size 0.450088 0.450088)
			(layers "F.Cu" "F.Mask" "F.Paste")
			(net "GND")
		)
		(pad "CP72" smd circle
			(at 31.809944 24.660098 180)
			(size 0.450088 0.450088)
			(layers "F.Cu" "F.Mask" "F.Paste")
			(net "M_A_CPU0_SB_DQ<15>")
		)
		(pad "CP73" smd circle
			(at 32.749998 24.660098 180)
			(size 0.450088 0.450088)
			(layers "F.Cu" "F.Mask" "F.Paste")
			(net "GND")
		)
		(pad "CP74" smd circle
			(at 33.690052 24.660098 180)
			(size 0.450088 0.450088)
			(layers "F.Cu" "F.Mask" "F.Paste")
			(net "M_A_CPU0_SB_DQ<16>")
		)
		(pad "CR1" smd circle
			(at -34.459926 25.470104 180)
			(size 0.450088 0.450088)
			(layers "F.Cu" "F.Mask" "F.Paste")
			(net "GND")
		)
		(pad "CR2" smd circle
			(at -33.519872 25.470104 180)
			(size 0.450088 0.450088)
			(layers "F.Cu" "F.Mask" "F.Paste")
			(net "M_G_CPU0_SB_DQ<18>")
		)
		(pad "CR3" smd circle
			(at -32.580072 25.470104 180)
			(size 0.450088 0.450088)
			(layers "F.Cu" "F.Mask" "F.Paste")
			(net "M_G_CPU0_SB_DQ<17>")
		)
		(pad "CR4" smd circle
			(at -31.640018 25.470104 180)
			(size 0.450088 0.450088)
			(layers "F.Cu" "F.Mask" "F.Paste")
			(net "GND")
		)
		(pad "CR5" smd circle
			(at -30.699964 25.470104 180)
			(size 0.450088 0.450088)
			(layers "F.Cu" "F.Mask" "F.Paste")
			(net "M_K_CPU0_SB_DQ<18>")
		)
		(pad "CR6" smd circle
			(at -29.75991 25.470104 180)
			(size 0.450088 0.450088)
			(layers "F.Cu" "F.Mask" "F.Paste")
			(net "GND")
		)
		(pad "CR7" smd circle
			(at -28.82011 25.470104 180)
			(size 0.450088 0.450088)
			(layers "F.Cu" "F.Mask" "F.Paste")
			(net "M_K_CPU0_SB_DQ<17>")
		)
		(pad "CR8" smd circle
			(at -27.880056 25.470104 180)
			(size 0.450088 0.450088)
			(layers "F.Cu" "F.Mask" "F.Paste")
			(net "GND")
		)
		(pad "CR9" smd circle
			(at -26.940002 25.470104 180)
			(size 0.450088 0.450088)
			(layers "F.Cu" "F.Mask" "F.Paste")
			(net "M_L_CPU0_SB_DQ<18>")
		)
		(pad "CR10" smd circle
			(at -25.999948 25.470104 180)
			(size 0.450088 0.450088)
			(layers "F.Cu" "F.Mask" "F.Paste")
			(net "M_L_CPU0_SB_DQ<17>")
		)
		(pad "CR11" smd circle
			(at -25.059894 25.470104 180)
			(size 0.450088 0.450088)
			(layers "F.Cu" "F.Mask" "F.Paste")
			(net "GND")
		)
		(pad "CR12" smd circle
			(at -24.120094 25.470104 180)
			(size 0.450088 0.450088)
			(layers "F.Cu" "F.Mask" "F.Paste")
			(net "M_H_CPU0_SB_DQ<18>")
		)
		(pad "CR13" smd circle
			(at -23.18004 25.470104 180)
			(size 0.450088 0.450088)
			(layers "F.Cu" "F.Mask" "F.Paste")
			(net "GND")
		)
		(pad "CR14" smd circle
			(at -22.239986 25.470104 180)
			(size 0.450088 0.450088)
			(layers "F.Cu" "F.Mask" "F.Paste")
			(net "M_H_CPU0_SB_DQ<17>")
		)
		(pad "CR15" smd circle
			(at -21.299932 25.470104 180)
			(size 0.450088 0.450088)
			(layers "F.Cu" "F.Mask" "F.Paste")
			(net "GND")
		)
		(pad "CR16" smd circle
			(at -20.359878 25.470104 180)
			(size 0.450088 0.450088)
			(layers "F.Cu" "F.Mask" "F.Paste")
			(net "M_J_CPU0_SB_DQ<18>")
		)
		(pad "CR17" smd circle
			(at -19.420078 25.470104 180)
			(size 0.450088 0.450088)
			(layers "F.Cu" "F.Mask" "F.Paste")
			(net "M_J_CPU0_SB_DQ<17>")
		)
		(pad "CR18" smd circle
			(at -18.480024 25.470104 180)
			(size 0.450088 0.450088)
			(layers "F.Cu" "F.Mask" "F.Paste")
			(net "GND")
		)
		(pad "CR19" smd circle
			(at -17.53997 25.470104 180)
			(size 0.450088 0.450088)
			(layers "F.Cu" "F.Mask" "F.Paste")
			(net "M_I_CPU0_SB_DQ<18>")
		)
		(pad "CR20" smd circle
			(at -16.599916 25.470104 180)
			(size 0.450088 0.450088)
			(layers "F.Cu" "F.Mask" "F.Paste")
			(net "GND")
		)
		(pad "CR21" smd circle
			(at -15.660116 25.470104 180)
			(size 0.450088 0.450088)
			(layers "F.Cu" "F.Mask" "F.Paste")
			(net "M_I_CPU0_SB_DQ<17>")
		)
		(pad "CR22" smd circle
			(at -14.720062 25.470104 180)
			(size 0.450088 0.450088)
			(layers "F.Cu" "F.Mask" "F.Paste")
			(net "GND")
		)
		(pad "CR23" smd circle
			(at -13.780008 25.470104 180)
			(size 0.450088 0.450088)
			(layers "F.Cu" "F.Mask" "F.Paste")
			(net "P5E_CPU0_P2_RX_DP<14>")
		)
		(pad "CR24" smd circle
			(at -12.839954 25.470104 180)
			(size 0.450088 0.450088)
			(layers "F.Cu" "F.Mask" "F.Paste")
			(net "P5E_CPU0_P2_RX_DN<14>")
		)
		(pad "CR25" smd circle
			(at -11.8999 25.470104 180)
			(size 0.450088 0.450088)
			(layers "F.Cu" "F.Mask" "F.Paste")
			(net "GND")
		)
		(pad "CR26" smd circle
			(at -10.9601 25.470104 180)
			(size 0.450088 0.450088)
			(layers "F.Cu" "F.Mask" "F.Paste")
			(net "P5E_CPU0_P2_RX_DP<11>")
		)
		(pad "CR27" smd circle
			(at -10.020046 25.470104 180)
			(size 0.450088 0.450088)
			(layers "F.Cu" "F.Mask" "F.Paste")
			(net "P5E_CPU0_P2_RX_DN<11>")
		)
		(pad "CR28" smd circle
			(at -9.079992 25.470104 180)
			(size 0.450088 0.450088)
			(layers "F.Cu" "F.Mask" "F.Paste")
			(net "GND")
		)
		(pad "CR29" smd circle
			(at -8.139938 25.470104 180)
			(size 0.450088 0.450088)
			(layers "F.Cu" "F.Mask" "F.Paste")
			(net "P5E_CPU0_P2_RX_DP<8>")
		)
		(pad "CR30" smd circle
			(at -7.199884 25.470104 180)
			(size 0.450088 0.450088)
			(layers "F.Cu" "F.Mask" "F.Paste")
			(net "P5E_CPU0_P2_RX_DN<8>")
		)
		(pad "CR31" smd circle
			(at -6.260084 25.470104 180)
			(size 0.450088 0.450088)
			(layers "F.Cu" "F.Mask" "F.Paste")
			(net "GND")
		)
		(pad "CR32" smd circle
			(at -5.32003 25.470104 180)
			(size 0.450088 0.450088)
			(layers "F.Cu" "F.Mask" "F.Paste")
			(net "P5E_CPU0_P2_RX_DP<5>")
		)
		(pad "CR33" smd circle
			(at -4.379976 25.470104 180)
			(size 0.450088 0.450088)
			(layers "F.Cu" "F.Mask" "F.Paste")
			(net "P5E_CPU0_P2_RX_DN<5>")
		)
		(pad "CR34" smd circle
			(at -3.439922 25.470104 180)
			(size 0.450088 0.450088)
			(layers "F.Cu" "F.Mask" "F.Paste")
			(net "GND")
		)
		(pad "CR35" smd circle
			(at -2.500122 25.470104 180)
			(size 0.450088 0.450088)
			(layers "F.Cu" "F.Mask" "F.Paste")
			(net "GND")
		)
		(pad "CR36" smd circle
			(at -1.560068 25.470104 180)
			(size 0.450088 0.450088)
			(layers "F.Cu" "F.Mask" "F.Paste")
			(net "GND")
		)
		(pad "CR40" smd circle
			(at 1.260094 25.470104 180)
			(size 0.450088 0.450088)
			(layers "F.Cu" "F.Mask" "F.Paste")
			(net "GND")
		)
		(pad "CR41" smd circle
			(at 2.199894 25.470104 180)
			(size 0.450088 0.450088)
			(layers "F.Cu" "F.Mask" "F.Paste")
			(net "GND")
		)
		(pad "CR42" smd circle
			(at 3.139948 25.470104 180)
			(size 0.450088 0.450088)
			(layers "F.Cu" "F.Mask" "F.Paste")
			(net "GND")
		)
		(pad "CR43" smd circle
			(at 4.080002 25.470104 180)
			(size 0.450088 0.450088)
			(layers "F.Cu" "F.Mask" "F.Paste")
			(net "P5E_CPU0_P0_TX_DN<10>")
		)
		(pad "CR44" smd circle
			(at 5.020056 25.470104 180)
			(size 0.450088 0.450088)
			(layers "F.Cu" "F.Mask" "F.Paste")
			(net "P5E_CPU0_P0_TX_DP<10>")
		)
		(pad "CR45" smd circle
			(at 5.96011 25.470104 180)
			(size 0.450088 0.450088)
			(layers "F.Cu" "F.Mask" "F.Paste")
			(net "GND")
		)
		(pad "CR46" smd circle
			(at 6.89991 25.470104 180)
			(size 0.450088 0.450088)
			(layers "F.Cu" "F.Mask" "F.Paste")
			(net "P5E_CPU0_P0_TX_DN<7>")
		)
		(pad "CR47" smd circle
			(at 7.839964 25.470104 180)
			(size 0.450088 0.450088)
			(layers "F.Cu" "F.Mask" "F.Paste")
			(net "P5E_CPU0_P0_TX_DP<7>")
		)
		(pad "CR48" smd circle
			(at 8.780018 25.470104 180)
			(size 0.450088 0.450088)
			(layers "F.Cu" "F.Mask" "F.Paste")
			(net "GND")
		)
		(pad "CR49" smd circle
			(at 9.720072 25.470104 180)
			(size 0.450088 0.450088)
			(layers "F.Cu" "F.Mask" "F.Paste")
			(net "P5E_CPU0_P0_TX_DN<4>")
		)
		(pad "CR50" smd circle
			(at 10.659872 25.470104 180)
			(size 0.450088 0.450088)
			(layers "F.Cu" "F.Mask" "F.Paste")
			(net "P5E_CPU0_P0_TX_DP<4>")
		)
		(pad "CR51" smd circle
			(at 11.599926 25.470104 180)
			(size 0.450088 0.450088)
			(layers "F.Cu" "F.Mask" "F.Paste")
			(net "GND")
		)
		(pad "CR52" smd circle
			(at 12.53998 25.470104 180)
			(size 0.450088 0.450088)
			(layers "F.Cu" "F.Mask" "F.Paste")
			(net "P5E_CPU0_P0_TX_DN<1>")
		)
		(pad "CR53" smd circle
			(at 13.480034 25.470104 180)
			(size 0.450088 0.450088)
			(layers "F.Cu" "F.Mask" "F.Paste")
			(net "P5E_CPU0_P0_TX_DP<1>")
		)
		(pad "CR54" smd circle
			(at 14.420088 25.470104 180)
			(size 0.450088 0.450088)
			(layers "F.Cu" "F.Mask" "F.Paste")
			(net "GND")
		)
		(pad "CR55" smd circle
			(at 15.359888 25.470104 180)
			(size 0.450088 0.450088)
			(layers "F.Cu" "F.Mask" "F.Paste")
			(net "M_C_CPU0_SB_DQ<17>")
		)
		(pad "CR56" smd circle
			(at 16.299942 25.470104 180)
			(size 0.450088 0.450088)
			(layers "F.Cu" "F.Mask" "F.Paste")
			(net "GND")
		)
		(pad "CR57" smd circle
			(at 17.239996 25.470104 180)
			(size 0.450088 0.450088)
			(layers "F.Cu" "F.Mask" "F.Paste")
			(net "M_C_CPU0_SB_DQ<18>")
		)
		(pad "CR58" smd circle
			(at 18.18005 25.470104 180)
			(size 0.450088 0.450088)
			(layers "F.Cu" "F.Mask" "F.Paste")
			(net "GND")
		)
		(pad "CR59" smd circle
			(at 19.120104 25.470104 180)
			(size 0.450088 0.450088)
			(layers "F.Cu" "F.Mask" "F.Paste")
			(net "M_D_CPU0_SB_DQ<17>")
		)
		(pad "CR60" smd circle
			(at 20.059904 25.470104 180)
			(size 0.450088 0.450088)
			(layers "F.Cu" "F.Mask" "F.Paste")
			(net "M_D_CPU0_SB_DQ<18>")
		)
		(pad "CR61" smd circle
			(at 20.999958 25.470104 180)
			(size 0.450088 0.450088)
			(layers "F.Cu" "F.Mask" "F.Paste")
			(net "GND")
		)
		(pad "CR62" smd circle
			(at 21.940012 25.470104 180)
			(size 0.450088 0.450088)
			(layers "F.Cu" "F.Mask" "F.Paste")
			(net "M_B_CPU0_SB_DQ<17>")
		)
		(pad "CR63" smd circle
			(at 22.880066 25.470104 180)
			(size 0.450088 0.450088)
			(layers "F.Cu" "F.Mask" "F.Paste")
			(net "GND")
		)
		(pad "CR64" smd circle
			(at 23.82012 25.470104 180)
			(size 0.450088 0.450088)
			(layers "F.Cu" "F.Mask" "F.Paste")
			(net "M_B_CPU0_SB_DQ<18>")
		)
		(pad "CR65" smd circle
			(at 24.75992 25.470104 180)
			(size 0.450088 0.450088)
			(layers "F.Cu" "F.Mask" "F.Paste")
			(net "GND")
		)
		(pad "CR66" smd circle
			(at 25.699974 25.470104 180)
			(size 0.450088 0.450088)
			(layers "F.Cu" "F.Mask" "F.Paste")
			(net "M_F_CPU0_SB_DQ<17>")
		)
		(pad "CR67" smd circle
			(at 26.640028 25.470104 180)
			(size 0.450088 0.450088)
			(layers "F.Cu" "F.Mask" "F.Paste")
			(net "M_F_CPU0_SB_DQ<18>")
		)
		(pad "CR68" smd circle
			(at 27.580082 25.470104 180)
			(size 0.450088 0.450088)
			(layers "F.Cu" "F.Mask" "F.Paste")
			(net "GND")
		)
		(pad "CR69" smd circle
			(at 28.519882 25.470104 180)
			(size 0.450088 0.450088)
			(layers "F.Cu" "F.Mask" "F.Paste")
			(net "M_E_CPU0_SB_DQ<17>")
		)
		(pad "CR70" smd circle
			(at 29.459936 25.470104 180)
			(size 0.450088 0.450088)
			(layers "F.Cu" "F.Mask" "F.Paste")
			(net "GND")
		)
		(pad "CR71" smd circle
			(at 30.39999 25.470104 180)
			(size 0.450088 0.450088)
			(layers "F.Cu" "F.Mask" "F.Paste")
			(net "M_E_CPU0_SB_DQ<18>")
		)
		(pad "CR72" smd circle
			(at 31.340044 25.470104 180)
			(size 0.450088 0.450088)
			(layers "F.Cu" "F.Mask" "F.Paste")
			(net "GND")
		)
		(pad "CR73" smd circle
			(at 32.280098 25.470104 180)
			(size 0.450088 0.450088)
			(layers "F.Cu" "F.Mask" "F.Paste")
			(net "M_A_CPU0_SB_DQ<17>")
		)
		(pad "CR74" smd circle
			(at 33.219898 25.470104 180)
			(size 0.450088 0.450088)
			(layers "F.Cu" "F.Mask" "F.Paste")
			(net "M_A_CPU0_SB_DQ<18>")
		)
		(pad "CR75" smd circle
			(at 34.159952 25.470104 180)
			(size 0.450088 0.450088)
			(layers "F.Cu" "F.Mask" "F.Paste")
			(net "GND")
		)
		(pad "CT2" smd circle
			(at -33.990026 26.28011 180)
			(size 0.450088 0.450088)
			(layers "F.Cu" "F.Mask" "F.Paste")
			(net "M_G_CPU0_SB_DQS_DP<2>")
		)
		(pad "CT3" smd circle
			(at -33.049972 26.28011 180)
			(size 0.450088 0.450088)
			(layers "F.Cu" "F.Mask" "F.Paste")
			(net "GND")
		)
		(pad "CT4" smd circle
			(at -32.109918 26.28011 180)
			(size 0.450088 0.450088)
			(layers "F.Cu" "F.Mask" "F.Paste")
			(net "M_G_CPU0_SB_DQ<19>")
		)
		(pad "CT5" smd circle
			(at -31.170118 26.28011 180)
			(size 0.450088 0.450088)
			(layers "F.Cu" "F.Mask" "F.Paste")
			(net "PVDD11_S3_P0")
		)
		(pad "CT6" smd circle
			(at -30.230064 26.28011 180)
			(size 0.450088 0.450088)
			(layers "F.Cu" "F.Mask" "F.Paste")
			(net "M_K_CPU0_SB_DQS_DP<2>")
		)
		(pad "CT7" smd circle
			(at -29.29001 26.28011 180)
			(size 0.450088 0.450088)
			(layers "F.Cu" "F.Mask" "F.Paste")
			(net "M_K_CPU0_SB_DQ<19>")
		)
		(pad "CT8" smd circle
			(at -28.349956 26.28011 180)
			(size 0.450088 0.450088)
			(layers "F.Cu" "F.Mask" "F.Paste")
			(net "GND")
		)
		(pad "CT9" smd circle
			(at -27.409902 26.28011 180)
			(size 0.450088 0.450088)
			(layers "F.Cu" "F.Mask" "F.Paste")
			(net "M_L_CPU0_SB_DQS_DP<2>")
		)
		(pad "CT10" smd circle
			(at -26.470102 26.28011 180)
			(size 0.450088 0.450088)
			(layers "F.Cu" "F.Mask" "F.Paste")
			(net "GND")
		)
		(pad "CT11" smd circle
			(at -25.530048 26.28011 180)
			(size 0.450088 0.450088)
			(layers "F.Cu" "F.Mask" "F.Paste")
			(net "M_L_CPU0_SB_DQ<19>")
		)
		(pad "CT12" smd circle
			(at -24.589994 26.28011 180)
			(size 0.450088 0.450088)
			(layers "F.Cu" "F.Mask" "F.Paste")
			(net "PVDD11_S3_P0")
		)
		(pad "CT13" smd circle
			(at -23.64994 26.28011 180)
			(size 0.450088 0.450088)
			(layers "F.Cu" "F.Mask" "F.Paste")
			(net "M_H_CPU0_SB_DQS_DP<2>")
		)
		(pad "CT14" smd circle
			(at -22.709886 26.28011 180)
			(size 0.450088 0.450088)
			(layers "F.Cu" "F.Mask" "F.Paste")
			(net "M_H_CPU0_SB_DQ<19>")
		)
		(pad "CT15" smd circle
			(at -21.770086 26.28011 180)
			(size 0.450088 0.450088)
			(layers "F.Cu" "F.Mask" "F.Paste")
			(net "GND")
		)
		(pad "CT16" smd circle
			(at -20.830032 26.28011 180)
			(size 0.450088 0.450088)
			(layers "F.Cu" "F.Mask" "F.Paste")
			(net "M_J_CPU0_SB_DQS_DP<2>")
		)
		(pad "CT17" smd circle
			(at -19.889978 26.28011 180)
			(size 0.450088 0.450088)
			(layers "F.Cu" "F.Mask" "F.Paste")
			(net "GND")
		)
		(pad "CT18" smd circle
			(at -18.949924 26.28011 180)
			(size 0.450088 0.450088)
			(layers "F.Cu" "F.Mask" "F.Paste")
			(net "M_J_CPU0_SB_DQ<19>")
		)
		(pad "CT19" smd circle
			(at -18.010124 26.28011 180)
			(size 0.450088 0.450088)
			(layers "F.Cu" "F.Mask" "F.Paste")
			(net "PVDD11_S3_P0")
		)
		(pad "CT20" smd circle
			(at -17.07007 26.28011 180)
			(size 0.450088 0.450088)
			(layers "F.Cu" "F.Mask" "F.Paste")
			(net "M_I_CPU0_SB_DQS_DP<2>")
		)
		(pad "CT21" smd circle
			(at -16.130016 26.28011 180)
			(size 0.450088 0.450088)
			(layers "F.Cu" "F.Mask" "F.Paste")
			(net "M_I_CPU0_SB_DQ<19>")
		)
		(pad "CT22" smd circle
			(at -15.189962 26.28011 180)
			(size 0.450088 0.450088)
			(layers "F.Cu" "F.Mask" "F.Paste")
			(net "PVDD11_S3_P0")
		)
		(pad "CT23" smd circle
			(at -14.249908 26.28011 180)
			(size 0.450088 0.450088)
			(layers "F.Cu" "F.Mask" "F.Paste")
			(net "GND")
		)
		(pad "CT24" smd circle
			(at -13.310108 26.28011 180)
			(size 0.450088 0.450088)
			(layers "F.Cu" "F.Mask" "F.Paste")
			(net "GND")
		)
		(pad "CT25" smd circle
			(at -12.370054 26.28011 180)
			(size 0.450088 0.450088)
			(layers "F.Cu" "F.Mask" "F.Paste")
			(net "GND")
		)
		(pad "CT26" smd circle
			(at -11.43 26.28011 180)
			(size 0.450088 0.450088)
			(layers "F.Cu" "F.Mask" "F.Paste")
			(net "GND")
		)
		(pad "CT27" smd circle
			(at -10.489946 26.28011 180)
			(size 0.450088 0.450088)
			(layers "F.Cu" "F.Mask" "F.Paste")
			(net "GND")
		)
		(pad "CT28" smd circle
			(at -9.549892 26.28011 180)
			(size 0.450088 0.450088)
			(layers "F.Cu" "F.Mask" "F.Paste")
			(net "GND")
		)
		(pad "CT29" smd circle
			(at -8.610092 26.28011 180)
			(size 0.450088 0.450088)
			(layers "F.Cu" "F.Mask" "F.Paste")
			(net "GND")
		)
		(pad "CT30" smd circle
			(at -7.670038 26.28011 180)
			(size 0.450088 0.450088)
			(layers "F.Cu" "F.Mask" "F.Paste")
			(net "GND")
		)
		(pad "CT31" smd circle
			(at -6.729984 26.28011 180)
			(size 0.450088 0.450088)
			(layers "F.Cu" "F.Mask" "F.Paste")
			(net "GND")
		)
		(pad "CT32" smd circle
			(at -5.78993 26.28011 180)
			(size 0.450088 0.450088)
			(layers "F.Cu" "F.Mask" "F.Paste")
			(net "GND")
		)
		(pad "CT33" smd circle
			(at -4.849876 26.28011 180)
			(size 0.450088 0.450088)
			(layers "F.Cu" "F.Mask" "F.Paste")
			(net "GND")
		)
		(pad "CT34" smd circle
			(at -3.910076 26.28011 180)
			(size 0.450088 0.450088)
			(layers "F.Cu" "F.Mask" "F.Paste")
			(net "GND")
		)
		(pad "CT35" smd circle
			(at -2.970022 26.28011 180)
			(size 0.450088 0.450088)
			(layers "F.Cu" "F.Mask" "F.Paste")
			(net "P5E_CPU0_P2_RX_DP<2>")
		)
		(pad "CT36" smd circle
			(at -2.029968 26.28011 180)
			(size 0.450088 0.450088)
			(layers "F.Cu" "F.Mask" "F.Paste")
			(net "P5E_CPU0_P2_RX_DN<2>")
		)
		(pad "CT37" smd circle
			(at -1.089914 26.28011 180)
			(size 0.450088 0.450088)
			(layers "F.Cu" "F.Mask" "F.Paste")
			(net "GND")
		)
		(pad "CT39" smd circle
			(at 0.78994 26.28011 180)
			(size 0.450088 0.450088)
			(layers "F.Cu" "F.Mask" "F.Paste")
			(net "GND")
		)
		(pad "CT40" smd circle
			(at 1.729994 26.28011 180)
			(size 0.450088 0.450088)
			(layers "F.Cu" "F.Mask" "F.Paste")
			(net "P5E_CPU0_P0_TX_DN<13>")
		)
		(pad "CT41" smd circle
			(at 2.670048 26.28011 180)
			(size 0.450088 0.450088)
			(layers "F.Cu" "F.Mask" "F.Paste")
			(net "P5E_CPU0_P0_TX_DP<13>")
		)
		(pad "CT42" smd circle
			(at 3.610102 26.28011 180)
			(size 0.450088 0.450088)
			(layers "F.Cu" "F.Mask" "F.Paste")
			(net "GND")
		)
		(pad "CT43" smd circle
			(at 4.549902 26.28011 180)
			(size 0.450088 0.450088)
			(layers "F.Cu" "F.Mask" "F.Paste")
			(net "GND")
		)
		(pad "CT44" smd circle
			(at 5.489956 26.28011 180)
			(size 0.450088 0.450088)
			(layers "F.Cu" "F.Mask" "F.Paste")
			(net "GND")
		)
		(pad "CT45" smd circle
			(at 6.43001 26.28011 180)
			(size 0.450088 0.450088)
			(layers "F.Cu" "F.Mask" "F.Paste")
			(net "GND")
		)
		(pad "CT46" smd circle
			(at 7.370064 26.28011 180)
			(size 0.450088 0.450088)
			(layers "F.Cu" "F.Mask" "F.Paste")
			(net "GND")
		)
		(pad "CT47" smd circle
			(at 8.310118 26.28011 180)
			(size 0.450088 0.450088)
			(layers "F.Cu" "F.Mask" "F.Paste")
			(net "GND")
		)
		(pad "CT48" smd circle
			(at 9.249918 26.28011 180)
			(size 0.450088 0.450088)
			(layers "F.Cu" "F.Mask" "F.Paste")
			(net "GND")
		)
		(pad "CT49" smd circle
			(at 10.189972 26.28011 180)
			(size 0.450088 0.450088)
			(layers "F.Cu" "F.Mask" "F.Paste")
			(net "GND")
		)
		(pad "CT50" smd circle
			(at 11.130026 26.28011 180)
			(size 0.450088 0.450088)
			(layers "F.Cu" "F.Mask" "F.Paste")
			(net "GND")
		)
		(pad "CT51" smd circle
			(at 12.07008 26.28011 180)
			(size 0.450088 0.450088)
			(layers "F.Cu" "F.Mask" "F.Paste")
			(net "GND")
		)
		(pad "CT52" smd circle
			(at 13.00988 26.28011 180)
			(size 0.450088 0.450088)
			(layers "F.Cu" "F.Mask" "F.Paste")
			(net "GND")
		)
		(pad "CT53" smd circle
			(at 13.949934 26.28011 180)
			(size 0.450088 0.450088)
			(layers "F.Cu" "F.Mask" "F.Paste")
			(net "GND")
		)
		(pad "CT54" smd circle
			(at 14.889988 26.28011 180)
			(size 0.450088 0.450088)
			(layers "F.Cu" "F.Mask" "F.Paste")
			(net "PVDDIO_P0")
		)
		(pad "CT55" smd circle
			(at 15.830042 26.28011 180)
			(size 0.450088 0.450088)
			(layers "F.Cu" "F.Mask" "F.Paste")
			(net "M_C_CPU0_SB_DQ<19>")
		)
		(pad "CT56" smd circle
			(at 16.770096 26.28011 180)
			(size 0.450088 0.450088)
			(layers "F.Cu" "F.Mask" "F.Paste")
			(net "M_C_CPU0_SB_DQS_DP<2>")
		)
		(pad "CT57" smd circle
			(at 17.709896 26.28011 180)
			(size 0.450088 0.450088)
			(layers "F.Cu" "F.Mask" "F.Paste")
			(net "PVDDIO_P0")
		)
		(pad "CT58" smd circle
			(at 18.64995 26.28011 180)
			(size 0.450088 0.450088)
			(layers "F.Cu" "F.Mask" "F.Paste")
			(net "M_D_CPU0_SB_DQ<19>")
		)
		(pad "CT59" smd circle
			(at 19.590004 26.28011 180)
			(size 0.450088 0.450088)
			(layers "F.Cu" "F.Mask" "F.Paste")
			(net "GND")
		)
		(pad "CT60" smd circle
			(at 20.530058 26.28011 180)
			(size 0.450088 0.450088)
			(layers "F.Cu" "F.Mask" "F.Paste")
			(net "M_D_CPU0_SB_DQS_DP<2>")
		)
		(pad "CT61" smd circle
			(at 21.470112 26.28011 180)
			(size 0.450088 0.450088)
			(layers "F.Cu" "F.Mask" "F.Paste")
			(net "GND")
		)
		(pad "CT62" smd circle
			(at 22.409912 26.28011 180)
			(size 0.450088 0.450088)
			(layers "F.Cu" "F.Mask" "F.Paste")
			(net "M_B_CPU0_SB_DQ<19>")
		)
		(pad "CT63" smd circle
			(at 23.349966 26.28011 180)
			(size 0.450088 0.450088)
			(layers "F.Cu" "F.Mask" "F.Paste")
			(net "M_B_CPU0_SB_DQS_DP<2>")
		)
		(pad "CT64" smd circle
			(at 24.29002 26.28011 180)
			(size 0.450088 0.450088)
			(layers "F.Cu" "F.Mask" "F.Paste")
			(net "PVDDIO_P0")
		)
		(pad "CT65" smd circle
			(at 25.230074 26.28011 180)
			(size 0.450088 0.450088)
			(layers "F.Cu" "F.Mask" "F.Paste")
			(net "M_F_CPU0_SB_DQ<19>")
		)
		(pad "CT66" smd circle
			(at 26.170128 26.28011 180)
			(size 0.450088 0.450088)
			(layers "F.Cu" "F.Mask" "F.Paste")
			(net "GND")
		)
		(pad "CT67" smd circle
			(at 27.109928 26.28011 180)
			(size 0.450088 0.450088)
			(layers "F.Cu" "F.Mask" "F.Paste")
			(net "M_F_CPU0_SB_DQS_DP<2>")
		)
		(pad "CT68" smd circle
			(at 28.049982 26.28011 180)
			(size 0.450088 0.450088)
			(layers "F.Cu" "F.Mask" "F.Paste")
			(net "GND")
		)
		(pad "CT69" smd circle
			(at 28.990036 26.28011 180)
			(size 0.450088 0.450088)
			(layers "F.Cu" "F.Mask" "F.Paste")
			(net "M_E_CPU0_SB_DQ<19>")
		)
		(pad "CT70" smd circle
			(at 29.93009 26.28011 180)
			(size 0.450088 0.450088)
			(layers "F.Cu" "F.Mask" "F.Paste")
			(net "M_E_CPU0_SB_DQS_DP<2>")
		)
		(pad "CT71" smd circle
			(at 30.86989 26.28011 180)
			(size 0.450088 0.450088)
			(layers "F.Cu" "F.Mask" "F.Paste")
			(net "PVDDIO_P0")
		)
		(pad "CT72" smd circle
			(at 31.809944 26.28011 180)
			(size 0.450088 0.450088)
			(layers "F.Cu" "F.Mask" "F.Paste")
			(net "M_A_CPU0_SB_DQ<19>")
		)
		(pad "CT73" smd circle
			(at 32.749998 26.28011 180)
			(size 0.450088 0.450088)
			(layers "F.Cu" "F.Mask" "F.Paste")
			(net "GND")
		)
		(pad "CT74" smd circle
			(at 33.690052 26.28011 180)
			(size 0.450088 0.450088)
			(layers "F.Cu" "F.Mask" "F.Paste")
			(net "M_A_CPU0_SB_DQS_DP<2>")
		)
		(pad "CU1" smd circle
			(at -34.459926 27.090116 180)
			(size 0.450088 0.450088)
			(layers "F.Cu" "F.Mask" "F.Paste")
			(net "GND")
		)
		(pad "CU2" smd circle
			(at -33.519872 27.090116 180)
			(size 0.450088 0.450088)
			(layers "F.Cu" "F.Mask" "F.Paste")
			(net "M_G_CPU0_SB_DQS_DN<2>")
		)
		(pad "CU3" smd circle
			(at -32.580072 27.090116 180)
			(size 0.450088 0.450088)
			(layers "F.Cu" "F.Mask" "F.Paste")
			(net "M_G_CPU0_SB_DQS_DN<7>")
		)
		(pad "CU4" smd circle
			(at -31.640018 27.090116 180)
			(size 0.450088 0.450088)
			(layers "F.Cu" "F.Mask" "F.Paste")
			(net "GND")
		)
		(pad "CU5" smd circle
			(at -30.699964 27.090116 180)
			(size 0.450088 0.450088)
			(layers "F.Cu" "F.Mask" "F.Paste")
			(net "M_K_CPU0_SB_DQS_DN<2>")
		)
		(pad "CU6" smd circle
			(at -29.75991 27.090116 180)
			(size 0.450088 0.450088)
			(layers "F.Cu" "F.Mask" "F.Paste")
			(net "GND")
		)
		(pad "CU7" smd circle
			(at -28.82011 27.090116 180)
			(size 0.450088 0.450088)
			(layers "F.Cu" "F.Mask" "F.Paste")
			(net "M_K_CPU0_SB_DQS_DN<7>")
		)
		(pad "CU8" smd circle
			(at -27.880056 27.090116 180)
			(size 0.450088 0.450088)
			(layers "F.Cu" "F.Mask" "F.Paste")
			(net "GND")
		)
		(pad "CU9" smd circle
			(at -26.940002 27.090116 180)
			(size 0.450088 0.450088)
			(layers "F.Cu" "F.Mask" "F.Paste")
			(net "M_L_CPU0_SB_DQS_DN<2>")
		)
		(pad "CU10" smd circle
			(at -25.999948 27.090116 180)
			(size 0.450088 0.450088)
			(layers "F.Cu" "F.Mask" "F.Paste")
			(net "M_L_CPU0_SB_DQS_DN<7>")
		)
		(pad "CU11" smd circle
			(at -25.059894 27.090116 180)
			(size 0.450088 0.450088)
			(layers "F.Cu" "F.Mask" "F.Paste")
			(net "GND")
		)
		(pad "CU12" smd circle
			(at -24.120094 27.090116 180)
			(size 0.450088 0.450088)
			(layers "F.Cu" "F.Mask" "F.Paste")
			(net "M_H_CPU0_SB_DQS_DN<2>")
		)
		(pad "CU13" smd circle
			(at -23.18004 27.090116 180)
			(size 0.450088 0.450088)
			(layers "F.Cu" "F.Mask" "F.Paste")
			(net "GND")
		)
		(pad "CU14" smd circle
			(at -22.239986 27.090116 180)
			(size 0.450088 0.450088)
			(layers "F.Cu" "F.Mask" "F.Paste")
			(net "M_H_CPU0_SB_DQS_DN<7>")
		)
		(pad "CU15" smd circle
			(at -21.299932 27.090116 180)
			(size 0.450088 0.450088)
			(layers "F.Cu" "F.Mask" "F.Paste")
			(net "GND")
		)
		(pad "CU16" smd circle
			(at -20.359878 27.090116 180)
			(size 0.450088 0.450088)
			(layers "F.Cu" "F.Mask" "F.Paste")
			(net "M_J_CPU0_SB_DQS_DN<2>")
		)
		(pad "CU17" smd circle
			(at -19.420078 27.090116 180)
			(size 0.450088 0.450088)
			(layers "F.Cu" "F.Mask" "F.Paste")
			(net "M_J_CPU0_SB_DQS_DN<7>")
		)
		(pad "CU18" smd circle
			(at -18.480024 27.090116 180)
			(size 0.450088 0.450088)
			(layers "F.Cu" "F.Mask" "F.Paste")
			(net "GND")
		)
		(pad "CU19" smd circle
			(at -17.53997 27.090116 180)
			(size 0.450088 0.450088)
			(layers "F.Cu" "F.Mask" "F.Paste")
			(net "M_I_CPU0_SB_DQS_DN<2>")
		)
		(pad "CU20" smd circle
			(at -16.599916 27.090116 180)
			(size 0.450088 0.450088)
			(layers "F.Cu" "F.Mask" "F.Paste")
			(net "GND")
		)
		(pad "CU21" smd circle
			(at -15.660116 27.090116 180)
			(size 0.450088 0.450088)
			(layers "F.Cu" "F.Mask" "F.Paste")
			(net "M_I_CPU0_SB_DQS_DN<7>")
		)
		(pad "CU22" smd circle
			(at -14.720062 27.090116 180)
			(size 0.450088 0.450088)
			(layers "F.Cu" "F.Mask" "F.Paste")
			(net "GND")
		)
		(pad "CU23" smd circle
			(at -13.780008 27.090116 180)
			(size 0.450088 0.450088)
			(layers "F.Cu" "F.Mask" "F.Paste")
			(net "P5E_CPU0_P3_RX_DP<15>")
		)
		(pad "CU24" smd circle
			(at -12.839954 27.090116 180)
			(size 0.450088 0.450088)
			(layers "F.Cu" "F.Mask" "F.Paste")
			(net "P5E_CPU0_P3_RX_DN<15>")
		)
		(pad "CU25" smd circle
			(at -11.8999 27.090116 180)
			(size 0.450088 0.450088)
			(layers "F.Cu" "F.Mask" "F.Paste")
			(net "GND")
		)
		(pad "CU26" smd circle
			(at -10.9601 27.090116 180)
			(size 0.450088 0.450088)
			(layers "F.Cu" "F.Mask" "F.Paste")
			(net "P5E_CPU0_P2_RX_DP<10>")
		)
		(pad "CU27" smd circle
			(at -10.020046 27.090116 180)
			(size 0.450088 0.450088)
			(layers "F.Cu" "F.Mask" "F.Paste")
			(net "P5E_CPU0_P2_RX_DN<10>")
		)
		(pad "CU28" smd circle
			(at -9.079992 27.090116 180)
			(size 0.450088 0.450088)
			(layers "F.Cu" "F.Mask" "F.Paste")
			(net "GND")
		)
		(pad "CU29" smd circle
			(at -8.139938 27.090116 180)
			(size 0.450088 0.450088)
			(layers "F.Cu" "F.Mask" "F.Paste")
			(net "P5E_CPU0_P2_RX_DP<7>")
		)
		(pad "CU30" smd circle
			(at -7.199884 27.090116 180)
			(size 0.450088 0.450088)
			(layers "F.Cu" "F.Mask" "F.Paste")
			(net "P5E_CPU0_P2_RX_DN<7>")
		)
		(pad "CU31" smd circle
			(at -6.260084 27.090116 180)
			(size 0.450088 0.450088)
			(layers "F.Cu" "F.Mask" "F.Paste")
			(net "GND")
		)
		(pad "CU32" smd circle
			(at -5.32003 27.090116 180)
			(size 0.450088 0.450088)
			(layers "F.Cu" "F.Mask" "F.Paste")
			(net "P5E_CPU0_P2_RX_DP<4>")
		)
		(pad "CU33" smd circle
			(at -4.379976 27.090116 180)
			(size 0.450088 0.450088)
			(layers "F.Cu" "F.Mask" "F.Paste")
			(net "P5E_CPU0_P2_RX_DN<4>")
		)
		(pad "CU34" smd circle
			(at -3.439922 27.090116 180)
			(size 0.450088 0.450088)
			(layers "F.Cu" "F.Mask" "F.Paste")
			(net "GND")
		)
		(pad "CU35" smd circle
			(at -2.500122 27.090116 180)
			(size 0.450088 0.450088)
			(layers "F.Cu" "F.Mask" "F.Paste")
			(net "PVDDCR_CPU1_P0")
		)
		(pad "CU36" smd circle
			(at -1.560068 27.090116 180)
			(size 0.450088 0.450088)
			(layers "F.Cu" "F.Mask" "F.Paste")
			(net "PVDDCR_CPU1_P0")
		)
		(pad "CU40" smd circle
			(at 1.260094 27.090116 180)
			(size 0.450088 0.450088)
			(layers "F.Cu" "F.Mask" "F.Paste")
			(net "PVDDCR_CPU1_P0")
		)
		(pad "CU41" smd circle
			(at 2.199894 27.090116 180)
			(size 0.450088 0.450088)
			(layers "F.Cu" "F.Mask" "F.Paste")
			(net "PVDDCR_CPU1_P0")
		)
		(pad "CU42" smd circle
			(at 3.139948 27.090116 180)
			(size 0.450088 0.450088)
			(layers "F.Cu" "F.Mask" "F.Paste")
			(net "GND")
		)
		(pad "CU43" smd circle
			(at 4.080002 27.090116 180)
			(size 0.450088 0.450088)
			(layers "F.Cu" "F.Mask" "F.Paste")
			(net "P5E_CPU0_P0_TX_DN<11>")
		)
		(pad "CU44" smd circle
			(at 5.020056 27.090116 180)
			(size 0.450088 0.450088)
			(layers "F.Cu" "F.Mask" "F.Paste")
			(net "P5E_CPU0_P0_TX_DP<11>")
		)
		(pad "CU45" smd circle
			(at 5.96011 27.090116 180)
			(size 0.450088 0.450088)
			(layers "F.Cu" "F.Mask" "F.Paste")
			(net "GND")
		)
		(pad "CU46" smd circle
			(at 6.89991 27.090116 180)
			(size 0.450088 0.450088)
			(layers "F.Cu" "F.Mask" "F.Paste")
			(net "P5E_CPU0_P0_TX_DN<8>")
		)
		(pad "CU47" smd circle
			(at 7.839964 27.090116 180)
			(size 0.450088 0.450088)
			(layers "F.Cu" "F.Mask" "F.Paste")
			(net "P5E_CPU0_P0_TX_DP<8>")
		)
		(pad "CU48" smd circle
			(at 8.780018 27.090116 180)
			(size 0.450088 0.450088)
			(layers "F.Cu" "F.Mask" "F.Paste")
			(net "GND")
		)
		(pad "CU49" smd circle
			(at 9.720072 27.090116 180)
			(size 0.450088 0.450088)
			(layers "F.Cu" "F.Mask" "F.Paste")
			(net "P5E_CPU0_P0_TX_DN<5>")
		)
		(pad "CU50" smd circle
			(at 10.659872 27.090116 180)
			(size 0.450088 0.450088)
			(layers "F.Cu" "F.Mask" "F.Paste")
			(net "P5E_CPU0_P0_TX_DP<5>")
		)
		(pad "CU51" smd circle
			(at 11.599926 27.090116 180)
			(size 0.450088 0.450088)
			(layers "F.Cu" "F.Mask" "F.Paste")
			(net "GND")
		)
		(pad "CU52" smd circle
			(at 12.53998 27.090116 180)
			(size 0.450088 0.450088)
			(layers "F.Cu" "F.Mask" "F.Paste")
			(net "P5E_CPU0_P1_TX_DN<0>")
		)
		(pad "CU53" smd circle
			(at 13.480034 27.090116 180)
			(size 0.450088 0.450088)
			(layers "F.Cu" "F.Mask" "F.Paste")
			(net "P5E_CPU0_P1_TX_DP<0>")
		)
		(pad "CU54" smd circle
			(at 14.420088 27.090116 180)
			(size 0.450088 0.450088)
			(layers "F.Cu" "F.Mask" "F.Paste")
			(net "GND")
		)
		(pad "CU55" smd circle
			(at 15.359888 27.090116 180)
			(size 0.450088 0.450088)
			(layers "F.Cu" "F.Mask" "F.Paste")
			(net "M_C_CPU0_SB_DQS_DN<7>")
		)
		(pad "CU56" smd circle
			(at 16.299942 27.090116 180)
			(size 0.450088 0.450088)
			(layers "F.Cu" "F.Mask" "F.Paste")
			(net "GND")
		)
		(pad "CU57" smd circle
			(at 17.239996 27.090116 180)
			(size 0.450088 0.450088)
			(layers "F.Cu" "F.Mask" "F.Paste")
			(net "M_C_CPU0_SB_DQS_DN<2>")
		)
		(pad "CU58" smd circle
			(at 18.18005 27.090116 180)
			(size 0.450088 0.450088)
			(layers "F.Cu" "F.Mask" "F.Paste")
			(net "GND")
		)
		(pad "CU59" smd circle
			(at 19.120104 27.090116 180)
			(size 0.450088 0.450088)
			(layers "F.Cu" "F.Mask" "F.Paste")
			(net "M_D_CPU0_SB_DQS_DN<7>")
		)
		(pad "CU60" smd circle
			(at 20.059904 27.090116 180)
			(size 0.450088 0.450088)
			(layers "F.Cu" "F.Mask" "F.Paste")
			(net "M_D_CPU0_SB_DQS_DN<2>")
		)
		(pad "CU61" smd circle
			(at 20.999958 27.090116 180)
			(size 0.450088 0.450088)
			(layers "F.Cu" "F.Mask" "F.Paste")
			(net "GND")
		)
		(pad "CU62" smd circle
			(at 21.940012 27.090116 180)
			(size 0.450088 0.450088)
			(layers "F.Cu" "F.Mask" "F.Paste")
			(net "M_B_CPU0_SB_DQS_DN<7>")
		)
		(pad "CU63" smd circle
			(at 22.880066 27.090116 180)
			(size 0.450088 0.450088)
			(layers "F.Cu" "F.Mask" "F.Paste")
			(net "GND")
		)
		(pad "CU64" smd circle
			(at 23.82012 27.090116 180)
			(size 0.450088 0.450088)
			(layers "F.Cu" "F.Mask" "F.Paste")
			(net "M_B_CPU0_SB_DQS_DN<2>")
		)
		(pad "CU65" smd circle
			(at 24.75992 27.090116 180)
			(size 0.450088 0.450088)
			(layers "F.Cu" "F.Mask" "F.Paste")
			(net "GND")
		)
		(pad "CU66" smd circle
			(at 25.699974 27.090116 180)
			(size 0.450088 0.450088)
			(layers "F.Cu" "F.Mask" "F.Paste")
			(net "M_F_CPU0_SB_DQS_DN<7>")
		)
		(pad "CU67" smd circle
			(at 26.640028 27.090116 180)
			(size 0.450088 0.450088)
			(layers "F.Cu" "F.Mask" "F.Paste")
			(net "M_F_CPU0_SB_DQS_DN<2>")
		)
		(pad "CU68" smd circle
			(at 27.580082 27.090116 180)
			(size 0.450088 0.450088)
			(layers "F.Cu" "F.Mask" "F.Paste")
			(net "GND")
		)
		(pad "CU69" smd circle
			(at 28.519882 27.090116 180)
			(size 0.450088 0.450088)
			(layers "F.Cu" "F.Mask" "F.Paste")
			(net "M_E_CPU0_SB_DQS_DN<7>")
		)
		(pad "CU70" smd circle
			(at 29.459936 27.090116 180)
			(size 0.450088 0.450088)
			(layers "F.Cu" "F.Mask" "F.Paste")
			(net "GND")
		)
		(pad "CU71" smd circle
			(at 30.39999 27.090116 180)
			(size 0.450088 0.450088)
			(layers "F.Cu" "F.Mask" "F.Paste")
			(net "M_E_CPU0_SB_DQS_DN<2>")
		)
		(pad "CU72" smd circle
			(at 31.340044 27.090116 180)
			(size 0.450088 0.450088)
			(layers "F.Cu" "F.Mask" "F.Paste")
			(net "GND")
		)
		(pad "CU73" smd circle
			(at 32.280098 27.090116 180)
			(size 0.450088 0.450088)
			(layers "F.Cu" "F.Mask" "F.Paste")
			(net "M_A_CPU0_SB_DQS_DN<7>")
		)
		(pad "CU74" smd circle
			(at 33.219898 27.090116 180)
			(size 0.450088 0.450088)
			(layers "F.Cu" "F.Mask" "F.Paste")
			(net "M_A_CPU0_SB_DQS_DN<2>")
		)
		(pad "CU75" smd circle
			(at 34.159952 27.090116 180)
			(size 0.450088 0.450088)
			(layers "F.Cu" "F.Mask" "F.Paste")
			(net "GND")
		)
		(pad "CV2" smd circle
			(at -33.990026 27.900122 180)
			(size 0.450088 0.450088)
			(layers "F.Cu" "F.Mask" "F.Paste")
			(net "M_G_CPU0_SB_DQ<20>")
		)
		(pad "CV3" smd circle
			(at -33.049972 27.900122 180)
			(size 0.450088 0.450088)
			(layers "F.Cu" "F.Mask" "F.Paste")
			(net "GND")
		)
		(pad "CV4" smd circle
			(at -32.109918 27.900122 180)
			(size 0.450088 0.450088)
			(layers "F.Cu" "F.Mask" "F.Paste")
			(net "M_G_CPU0_SB_DQS_DP<7>")
		)
		(pad "CV5" smd circle
			(at -31.170118 27.900122 180)
			(size 0.450088 0.450088)
			(layers "F.Cu" "F.Mask" "F.Paste")
			(net "GND")
		)
		(pad "CV6" smd circle
			(at -30.230064 27.900122 180)
			(size 0.450088 0.450088)
			(layers "F.Cu" "F.Mask" "F.Paste")
			(net "M_K_CPU0_SB_DQ<20>")
		)
		(pad "CV7" smd circle
			(at -29.29001 27.900122 180)
			(size 0.450088 0.450088)
			(layers "F.Cu" "F.Mask" "F.Paste")
			(net "M_K_CPU0_SB_DQS_DP<7>")
		)
		(pad "CV8" smd circle
			(at -28.349956 27.900122 180)
			(size 0.450088 0.450088)
			(layers "F.Cu" "F.Mask" "F.Paste")
			(net "GND")
		)
		(pad "CV9" smd circle
			(at -27.409902 27.900122 180)
			(size 0.450088 0.450088)
			(layers "F.Cu" "F.Mask" "F.Paste")
			(net "M_L_CPU0_SB_DQ<20>")
		)
		(pad "CV10" smd circle
			(at -26.470102 27.900122 180)
			(size 0.450088 0.450088)
			(layers "F.Cu" "F.Mask" "F.Paste")
			(net "GND")
		)
		(pad "CV11" smd circle
			(at -25.530048 27.900122 180)
			(size 0.450088 0.450088)
			(layers "F.Cu" "F.Mask" "F.Paste")
			(net "M_L_CPU0_SB_DQS_DP<7>")
		)
		(pad "CV12" smd circle
			(at -24.589994 27.900122 180)
			(size 0.450088 0.450088)
			(layers "F.Cu" "F.Mask" "F.Paste")
			(net "GND")
		)
		(pad "CV13" smd circle
			(at -23.64994 27.900122 180)
			(size 0.450088 0.450088)
			(layers "F.Cu" "F.Mask" "F.Paste")
			(net "M_H_CPU0_SB_DQ<20>")
		)
		(pad "CV14" smd circle
			(at -22.709886 27.900122 180)
			(size 0.450088 0.450088)
			(layers "F.Cu" "F.Mask" "F.Paste")
			(net "M_H_CPU0_SB_DQS_DP<7>")
		)
		(pad "CV15" smd circle
			(at -21.770086 27.900122 180)
			(size 0.450088 0.450088)
			(layers "F.Cu" "F.Mask" "F.Paste")
			(net "GND")
		)
		(pad "CV16" smd circle
			(at -20.830032 27.900122 180)
			(size 0.450088 0.450088)
			(layers "F.Cu" "F.Mask" "F.Paste")
			(net "M_J_CPU0_SB_DQ<20>")
		)
		(pad "CV17" smd circle
			(at -19.889978 27.900122 180)
			(size 0.450088 0.450088)
			(layers "F.Cu" "F.Mask" "F.Paste")
			(net "GND")
		)
		(pad "CV18" smd circle
			(at -18.949924 27.900122 180)
			(size 0.450088 0.450088)
			(layers "F.Cu" "F.Mask" "F.Paste")
			(net "M_J_CPU0_SB_DQS_DP<7>")
		)
		(pad "CV19" smd circle
			(at -18.010124 27.900122 180)
			(size 0.450088 0.450088)
			(layers "F.Cu" "F.Mask" "F.Paste")
			(net "GND")
		)
		(pad "CV20" smd circle
			(at -17.07007 27.900122 180)
			(size 0.450088 0.450088)
			(layers "F.Cu" "F.Mask" "F.Paste")
			(net "M_I_CPU0_SB_DQ<20>")
		)
		(pad "CV21" smd circle
			(at -16.130016 27.900122 180)
			(size 0.450088 0.450088)
			(layers "F.Cu" "F.Mask" "F.Paste")
			(net "M_I_CPU0_SB_DQS_DP<7>")
		)
		(pad "CV22" smd circle
			(at -15.189962 27.900122 180)
			(size 0.450088 0.450088)
			(layers "F.Cu" "F.Mask" "F.Paste")
			(net "GND")
		)
		(pad "CV23" smd circle
			(at -14.249908 27.900122 180)
			(size 0.450088 0.450088)
			(layers "F.Cu" "F.Mask" "F.Paste")
			(net "PVDDCR_CPU1_P0")
		)
		(pad "CV24" smd circle
			(at -13.310108 27.900122 180)
			(size 0.450088 0.450088)
			(layers "F.Cu" "F.Mask" "F.Paste")
			(net "PVDDCR_CPU1_P0")
		)
		(pad "CV25" smd circle
			(at -12.370054 27.900122 180)
			(size 0.450088 0.450088)
			(layers "F.Cu" "F.Mask" "F.Paste")
			(net "GND")
		)
		(pad "CV26" smd circle
			(at -11.43 27.900122 180)
			(size 0.450088 0.450088)
			(layers "F.Cu" "F.Mask" "F.Paste")
			(net "PVDDCR_CPU1_P0")
		)
		(pad "CV27" smd circle
			(at -10.489946 27.900122 180)
			(size 0.450088 0.450088)
			(layers "F.Cu" "F.Mask" "F.Paste")
			(net "PVDDCR_CPU1_P0")
		)
		(pad "CV28" smd circle
			(at -9.549892 27.900122 180)
			(size 0.450088 0.450088)
			(layers "F.Cu" "F.Mask" "F.Paste")
			(net "GND")
		)
		(pad "CV29" smd circle
			(at -8.610092 27.900122 180)
			(size 0.450088 0.450088)
			(layers "F.Cu" "F.Mask" "F.Paste")
			(net "PVDDCR_CPU1_P0")
		)
		(pad "CV30" smd circle
			(at -7.670038 27.900122 180)
			(size 0.450088 0.450088)
			(layers "F.Cu" "F.Mask" "F.Paste")
			(net "PVDDCR_CPU1_P0")
		)
		(pad "CV31" smd circle
			(at -6.729984 27.900122 180)
			(size 0.450088 0.450088)
			(layers "F.Cu" "F.Mask" "F.Paste")
			(net "GND")
		)
		(pad "CV32" smd circle
			(at -5.78993 27.900122 180)
			(size 0.450088 0.450088)
			(layers "F.Cu" "F.Mask" "F.Paste")
			(net "PVDDCR_CPU1_P0")
		)
		(pad "CV33" smd circle
			(at -4.849876 27.900122 180)
			(size 0.450088 0.450088)
			(layers "F.Cu" "F.Mask" "F.Paste")
			(net "PVDDCR_CPU1_P0")
		)
		(pad "CV34" smd circle
			(at -3.910076 27.900122 180)
			(size 0.450088 0.450088)
			(layers "F.Cu" "F.Mask" "F.Paste")
			(net "GND")
		)
		(pad "CV35" smd circle
			(at -2.970022 27.900122 180)
			(size 0.450088 0.450088)
			(layers "F.Cu" "F.Mask" "F.Paste")
			(net "P5E_CPU0_P3_RX_DP<0>")
		)
		(pad "CV36" smd circle
			(at -2.029968 27.900122 180)
			(size 0.450088 0.450088)
			(layers "F.Cu" "F.Mask" "F.Paste")
			(net "P5E_CPU0_P3_RX_DN<0>")
		)
		(pad "CV37" smd circle
			(at -1.089914 27.900122 180)
			(size 0.450088 0.450088)
			(layers "F.Cu" "F.Mask" "F.Paste")
			(net "GND")
		)
		(pad "CV39" smd circle
			(at 0.78994 27.900122 180)
			(size 0.450088 0.450088)
			(layers "F.Cu" "F.Mask" "F.Paste")
			(net "GND")
		)
		(pad "CV40" smd circle
			(at 1.729994 27.900122 180)
			(size 0.450088 0.450088)
			(layers "F.Cu" "F.Mask" "F.Paste")
			(net "P5E_CPU0_P1_TX_DN<15>")
		)
		(pad "CV41" smd circle
			(at 2.670048 27.900122 180)
			(size 0.450088 0.450088)
			(layers "F.Cu" "F.Mask" "F.Paste")
			(net "P5E_CPU0_P1_TX_DP<15>")
		)
		(pad "CV42" smd circle
			(at 3.610102 27.900122 180)
			(size 0.450088 0.450088)
			(layers "F.Cu" "F.Mask" "F.Paste")
			(net "GND")
		)
		(pad "CV43" smd circle
			(at 4.549902 27.900122 180)
			(size 0.450088 0.450088)
			(layers "F.Cu" "F.Mask" "F.Paste")
			(net "PVDDCR_CPU1_P0")
		)
		(pad "CV44" smd circle
			(at 5.489956 27.900122 180)
			(size 0.450088 0.450088)
			(layers "F.Cu" "F.Mask" "F.Paste")
			(net "PVDDCR_CPU1_P0")
		)
		(pad "CV45" smd circle
			(at 6.43001 27.900122 180)
			(size 0.450088 0.450088)
			(layers "F.Cu" "F.Mask" "F.Paste")
			(net "GND")
		)
		(pad "CV46" smd circle
			(at 7.370064 27.900122 180)
			(size 0.450088 0.450088)
			(layers "F.Cu" "F.Mask" "F.Paste")
			(net "PVDDCR_CPU1_P0")
		)
		(pad "CV47" smd circle
			(at 8.310118 27.900122 180)
			(size 0.450088 0.450088)
			(layers "F.Cu" "F.Mask" "F.Paste")
			(net "PVDDCR_CPU1_P0")
		)
		(pad "CV48" smd circle
			(at 9.249918 27.900122 180)
			(size 0.450088 0.450088)
			(layers "F.Cu" "F.Mask" "F.Paste")
			(net "GND")
		)
		(pad "CV49" smd circle
			(at 10.189972 27.900122 180)
			(size 0.450088 0.450088)
			(layers "F.Cu" "F.Mask" "F.Paste")
			(net "PVDDCR_CPU1_P0")
		)
		(pad "CV50" smd circle
			(at 11.130026 27.900122 180)
			(size 0.450088 0.450088)
			(layers "F.Cu" "F.Mask" "F.Paste")
			(net "PVDDCR_CPU1_P0")
		)
		(pad "CV51" smd circle
			(at 12.07008 27.900122 180)
			(size 0.450088 0.450088)
			(layers "F.Cu" "F.Mask" "F.Paste")
			(net "GND")
		)
		(pad "CV52" smd circle
			(at 13.00988 27.900122 180)
			(size 0.450088 0.450088)
			(layers "F.Cu" "F.Mask" "F.Paste")
			(net "PVDDCR_CPU1_P0")
		)
		(pad "CV53" smd circle
			(at 13.949934 27.900122 180)
			(size 0.450088 0.450088)
			(layers "F.Cu" "F.Mask" "F.Paste")
			(net "PVDDCR_CPU1_P0")
		)
		(pad "CV54" smd circle
			(at 14.889988 27.900122 180)
			(size 0.450088 0.450088)
			(layers "F.Cu" "F.Mask" "F.Paste")
			(net "GND")
		)
		(pad "CV55" smd circle
			(at 15.830042 27.900122 180)
			(size 0.450088 0.450088)
			(layers "F.Cu" "F.Mask" "F.Paste")
			(net "M_C_CPU0_SB_DQS_DP<7>")
		)
		(pad "CV56" smd circle
			(at 16.770096 27.900122 180)
			(size 0.450088 0.450088)
			(layers "F.Cu" "F.Mask" "F.Paste")
			(net "M_C_CPU0_SB_DQ<20>")
		)
		(pad "CV57" smd circle
			(at 17.709896 27.900122 180)
			(size 0.450088 0.450088)
			(layers "F.Cu" "F.Mask" "F.Paste")
			(net "GND")
		)
		(pad "CV58" smd circle
			(at 18.64995 27.900122 180)
			(size 0.450088 0.450088)
			(layers "F.Cu" "F.Mask" "F.Paste")
			(net "M_D_CPU0_SB_DQS_DP<7>")
		)
		(pad "CV59" smd circle
			(at 19.590004 27.900122 180)
			(size 0.450088 0.450088)
			(layers "F.Cu" "F.Mask" "F.Paste")
			(net "GND")
		)
		(pad "CV60" smd circle
			(at 20.530058 27.900122 180)
			(size 0.450088 0.450088)
			(layers "F.Cu" "F.Mask" "F.Paste")
			(net "M_D_CPU0_SB_DQ<20>")
		)
		(pad "CV61" smd circle
			(at 21.470112 27.900122 180)
			(size 0.450088 0.450088)
			(layers "F.Cu" "F.Mask" "F.Paste")
			(net "GND")
		)
		(pad "CV62" smd circle
			(at 22.409912 27.900122 180)
			(size 0.450088 0.450088)
			(layers "F.Cu" "F.Mask" "F.Paste")
			(net "M_B_CPU0_SB_DQS_DP<7>")
		)
		(pad "CV63" smd circle
			(at 23.349966 27.900122 180)
			(size 0.450088 0.450088)
			(layers "F.Cu" "F.Mask" "F.Paste")
			(net "M_B_CPU0_SB_DQ<20>")
		)
		(pad "CV64" smd circle
			(at 24.29002 27.900122 180)
			(size 0.450088 0.450088)
			(layers "F.Cu" "F.Mask" "F.Paste")
			(net "GND")
		)
		(pad "CV65" smd circle
			(at 25.230074 27.900122 180)
			(size 0.450088 0.450088)
			(layers "F.Cu" "F.Mask" "F.Paste")
			(net "M_F_CPU0_SB_DQS_DP<7>")
		)
		(pad "CV66" smd circle
			(at 26.170128 27.900122 180)
			(size 0.450088 0.450088)
			(layers "F.Cu" "F.Mask" "F.Paste")
			(net "GND")
		)
		(pad "CV67" smd circle
			(at 27.109928 27.900122 180)
			(size 0.450088 0.450088)
			(layers "F.Cu" "F.Mask" "F.Paste")
			(net "M_F_CPU0_SB_DQ<20>")
		)
		(pad "CV68" smd circle
			(at 28.049982 27.900122 180)
			(size 0.450088 0.450088)
			(layers "F.Cu" "F.Mask" "F.Paste")
			(net "GND")
		)
		(pad "CV69" smd circle
			(at 28.990036 27.900122 180)
			(size 0.450088 0.450088)
			(layers "F.Cu" "F.Mask" "F.Paste")
			(net "M_E_CPU0_SB_DQS_DP<7>")
		)
		(pad "CV70" smd circle
			(at 29.93009 27.900122 180)
			(size 0.450088 0.450088)
			(layers "F.Cu" "F.Mask" "F.Paste")
			(net "M_E_CPU0_SB_DQ<20>")
		)
		(pad "CV71" smd circle
			(at 30.86989 27.900122 180)
			(size 0.450088 0.450088)
			(layers "F.Cu" "F.Mask" "F.Paste")
			(net "GND")
		)
		(pad "CV72" smd circle
			(at 31.809944 27.900122 180)
			(size 0.450088 0.450088)
			(layers "F.Cu" "F.Mask" "F.Paste")
			(net "M_A_CPU0_SB_DQS_DP<7>")
		)
		(pad "CV73" smd circle
			(at 32.749998 27.900122 180)
			(size 0.450088 0.450088)
			(layers "F.Cu" "F.Mask" "F.Paste")
			(net "GND")
		)
		(pad "CV74" smd circle
			(at 33.690052 27.900122 180)
			(size 0.450088 0.450088)
			(layers "F.Cu" "F.Mask" "F.Paste")
			(net "M_A_CPU0_SB_DQ<20>")
		)
		(pad "CW1" smd circle
			(at -34.459926 28.710128 180)
			(size 0.450088 0.450088)
			(layers "F.Cu" "F.Mask" "F.Paste")
			(net "GND")
		)
		(pad "CW2" smd circle
			(at -33.519872 28.710128 180)
			(size 0.450088 0.450088)
			(layers "F.Cu" "F.Mask" "F.Paste")
			(net "M_G_CPU0_SB_DQ<22>")
		)
		(pad "CW3" smd circle
			(at -32.580072 28.710128 180)
			(size 0.450088 0.450088)
			(layers "F.Cu" "F.Mask" "F.Paste")
			(net "M_G_CPU0_SB_DQ<21>")
		)
		(pad "CW4" smd circle
			(at -31.640018 28.710128 180)
			(size 0.450088 0.450088)
			(layers "F.Cu" "F.Mask" "F.Paste")
			(net "PVDD11_S3_P0")
		)
		(pad "CW5" smd circle
			(at -30.699964 28.710128 180)
			(size 0.450088 0.450088)
			(layers "F.Cu" "F.Mask" "F.Paste")
			(net "M_K_CPU0_SB_DQ<22>")
		)
		(pad "CW6" smd circle
			(at -29.75991 28.710128 180)
			(size 0.450088 0.450088)
			(layers "F.Cu" "F.Mask" "F.Paste")
			(net "GND")
		)
		(pad "CW7" smd circle
			(at -28.82011 28.710128 180)
			(size 0.450088 0.450088)
			(layers "F.Cu" "F.Mask" "F.Paste")
			(net "M_K_CPU0_SB_DQ<21>")
		)
		(pad "CW8" smd circle
			(at -27.880056 28.710128 180)
			(size 0.450088 0.450088)
			(layers "F.Cu" "F.Mask" "F.Paste")
			(net "GND")
		)
		(pad "CW9" smd circle
			(at -26.940002 28.710128 180)
			(size 0.450088 0.450088)
			(layers "F.Cu" "F.Mask" "F.Paste")
			(net "M_L_CPU0_SB_DQ<22>")
		)
		(pad "CW10" smd circle
			(at -25.999948 28.710128 180)
			(size 0.450088 0.450088)
			(layers "F.Cu" "F.Mask" "F.Paste")
			(net "M_L_CPU0_SB_DQ<21>")
		)
		(pad "CW11" smd circle
			(at -25.059894 28.710128 180)
			(size 0.450088 0.450088)
			(layers "F.Cu" "F.Mask" "F.Paste")
			(net "PVDD11_S3_P0")
		)
		(pad "CW12" smd circle
			(at -24.120094 28.710128 180)
			(size 0.450088 0.450088)
			(layers "F.Cu" "F.Mask" "F.Paste")
			(net "M_H_CPU0_SB_DQ<22>")
		)
		(pad "CW13" smd circle
			(at -23.18004 28.710128 180)
			(size 0.450088 0.450088)
			(layers "F.Cu" "F.Mask" "F.Paste")
			(net "GND")
		)
		(pad "CW14" smd circle
			(at -22.239986 28.710128 180)
			(size 0.450088 0.450088)
			(layers "F.Cu" "F.Mask" "F.Paste")
			(net "M_H_CPU0_SB_DQ<21>")
		)
		(pad "CW15" smd circle
			(at -21.299932 28.710128 180)
			(size 0.450088 0.450088)
			(layers "F.Cu" "F.Mask" "F.Paste")
			(net "GND")
		)
		(pad "CW16" smd circle
			(at -20.359878 28.710128 180)
			(size 0.450088 0.450088)
			(layers "F.Cu" "F.Mask" "F.Paste")
			(net "M_J_CPU0_SB_DQ<22>")
		)
		(pad "CW17" smd circle
			(at -19.420078 28.710128 180)
			(size 0.450088 0.450088)
			(layers "F.Cu" "F.Mask" "F.Paste")
			(net "M_J_CPU0_SB_DQ<21>")
		)
		(pad "CW18" smd circle
			(at -18.480024 28.710128 180)
			(size 0.450088 0.450088)
			(layers "F.Cu" "F.Mask" "F.Paste")
			(net "PVDD11_S3_P0")
		)
		(pad "CW19" smd circle
			(at -17.53997 28.710128 180)
			(size 0.450088 0.450088)
			(layers "F.Cu" "F.Mask" "F.Paste")
			(net "M_I_CPU0_SB_DQ<22>")
		)
		(pad "CW20" smd circle
			(at -16.599916 28.710128 180)
			(size 0.450088 0.450088)
			(layers "F.Cu" "F.Mask" "F.Paste")
			(net "GND")
		)
		(pad "CW21" smd circle
			(at -15.660116 28.710128 180)
			(size 0.450088 0.450088)
			(layers "F.Cu" "F.Mask" "F.Paste")
			(net "M_I_CPU0_SB_DQ<21>")
		)
		(pad "CW22" smd circle
			(at -14.720062 28.710128 180)
			(size 0.450088 0.450088)
			(layers "F.Cu" "F.Mask" "F.Paste")
			(net "GND")
		)
		(pad "CW23" smd circle
			(at -13.780008 28.710128 180)
			(size 0.450088 0.450088)
			(layers "F.Cu" "F.Mask" "F.Paste")
			(net "P5E_CPU0_P3_RX_DP<12>")
		)
		(pad "CW24" smd circle
			(at -12.839954 28.710128 180)
			(size 0.450088 0.450088)
			(layers "F.Cu" "F.Mask" "F.Paste")
			(net "P5E_CPU0_P3_RX_DN<12>")
		)
		(pad "CW25" smd circle
			(at -11.8999 28.710128 180)
			(size 0.450088 0.450088)
			(layers "F.Cu" "F.Mask" "F.Paste")
			(net "GND")
		)
		(pad "CW26" smd circle
			(at -10.9601 28.710128 180)
			(size 0.450088 0.450088)
			(layers "F.Cu" "F.Mask" "F.Paste")
			(net "P5E_CPU0_P3_RX_DP<9>")
		)
		(pad "CW27" smd circle
			(at -10.020046 28.710128 180)
			(size 0.450088 0.450088)
			(layers "F.Cu" "F.Mask" "F.Paste")
			(net "P5E_CPU0_P3_RX_DN<9>")
		)
		(pad "CW28" smd circle
			(at -9.079992 28.710128 180)
			(size 0.450088 0.450088)
			(layers "F.Cu" "F.Mask" "F.Paste")
			(net "GND")
		)
		(pad "CW29" smd circle
			(at -8.139938 28.710128 180)
			(size 0.450088 0.450088)
			(layers "F.Cu" "F.Mask" "F.Paste")
			(net "P5E_CPU0_P3_RX_DP<6>")
		)
		(pad "CW30" smd circle
			(at -7.199884 28.710128 180)
			(size 0.450088 0.450088)
			(layers "F.Cu" "F.Mask" "F.Paste")
			(net "P5E_CPU0_P3_RX_DN<6>")
		)
		(pad "CW31" smd circle
			(at -6.260084 28.710128 180)
			(size 0.450088 0.450088)
			(layers "F.Cu" "F.Mask" "F.Paste")
			(net "GND")
		)
		(pad "CW32" smd circle
			(at -5.32003 28.710128 180)
			(size 0.450088 0.450088)
			(layers "F.Cu" "F.Mask" "F.Paste")
			(net "P5E_CPU0_P3_RX_DP<3>")
		)
		(pad "CW33" smd circle
			(at -4.379976 28.710128 180)
			(size 0.450088 0.450088)
			(layers "F.Cu" "F.Mask" "F.Paste")
			(net "P5E_CPU0_P3_RX_DN<3>")
		)
		(pad "CW34" smd circle
			(at -3.439922 28.710128 180)
			(size 0.450088 0.450088)
			(layers "F.Cu" "F.Mask" "F.Paste")
			(net "GND")
		)
		(pad "CW35" smd circle
			(at -2.500122 28.710128 180)
			(size 0.450088 0.450088)
			(layers "F.Cu" "F.Mask" "F.Paste")
			(net "GND")
		)
		(pad "CW36" smd circle
			(at -1.560068 28.710128 180)
			(size 0.450088 0.450088)
			(layers "F.Cu" "F.Mask" "F.Paste")
			(net "GND")
		)
		(pad "CW40" smd circle
			(at 1.260094 28.710128 180)
			(size 0.450088 0.450088)
			(layers "F.Cu" "F.Mask" "F.Paste")
			(net "GND")
		)
		(pad "CW41" smd circle
			(at 2.199894 28.710128 180)
			(size 0.450088 0.450088)
			(layers "F.Cu" "F.Mask" "F.Paste")
			(net "GND")
		)
		(pad "CW42" smd circle
			(at 3.139948 28.710128 180)
			(size 0.450088 0.450088)
			(layers "F.Cu" "F.Mask" "F.Paste")
			(net "GND")
		)
		(pad "CW43" smd circle
			(at 4.080002 28.710128 180)
			(size 0.450088 0.450088)
			(layers "F.Cu" "F.Mask" "F.Paste")
			(net "P5E_CPU0_P1_TX_DN<12>")
		)
		(pad "CW44" smd circle
			(at 5.020056 28.710128 180)
			(size 0.450088 0.450088)
			(layers "F.Cu" "F.Mask" "F.Paste")
			(net "P5E_CPU0_P1_TX_DP<12>")
		)
		(pad "CW45" smd circle
			(at 5.96011 28.710128 180)
			(size 0.450088 0.450088)
			(layers "F.Cu" "F.Mask" "F.Paste")
			(net "GND")
		)
		(pad "CW46" smd circle
			(at 6.89991 28.710128 180)
			(size 0.450088 0.450088)
			(layers "F.Cu" "F.Mask" "F.Paste")
			(net "P5E_CPU0_P1_TX_DN<9>")
		)
		(pad "CW47" smd circle
			(at 7.839964 28.710128 180)
			(size 0.450088 0.450088)
			(layers "F.Cu" "F.Mask" "F.Paste")
			(net "P5E_CPU0_P1_TX_DP<9>")
		)
		(pad "CW48" smd circle
			(at 8.780018 28.710128 180)
			(size 0.450088 0.450088)
			(layers "F.Cu" "F.Mask" "F.Paste")
			(net "GND")
		)
		(pad "CW49" smd circle
			(at 9.720072 28.710128 180)
			(size 0.450088 0.450088)
			(layers "F.Cu" "F.Mask" "F.Paste")
			(net "P5E_CPU0_P1_TX_DN<6>")
		)
		(pad "CW50" smd circle
			(at 10.659872 28.710128 180)
			(size 0.450088 0.450088)
			(layers "F.Cu" "F.Mask" "F.Paste")
			(net "P5E_CPU0_P1_TX_DP<6>")
		)
		(pad "CW51" smd circle
			(at 11.599926 28.710128 180)
			(size 0.450088 0.450088)
			(layers "F.Cu" "F.Mask" "F.Paste")
			(net "GND")
		)
		(pad "CW52" smd circle
			(at 12.53998 28.710128 180)
			(size 0.450088 0.450088)
			(layers "F.Cu" "F.Mask" "F.Paste")
			(net "P5E_CPU0_P1_TX_DN<3>")
		)
		(pad "CW53" smd circle
			(at 13.480034 28.710128 180)
			(size 0.450088 0.450088)
			(layers "F.Cu" "F.Mask" "F.Paste")
			(net "P5E_CPU0_P1_TX_DP<3>")
		)
		(pad "CW54" smd circle
			(at 14.420088 28.710128 180)
			(size 0.450088 0.450088)
			(layers "F.Cu" "F.Mask" "F.Paste")
			(net "GND")
		)
		(pad "CW55" smd circle
			(at 15.359888 28.710128 180)
			(size 0.450088 0.450088)
			(layers "F.Cu" "F.Mask" "F.Paste")
			(net "M_C_CPU0_SB_DQ<21>")
		)
		(pad "CW56" smd circle
			(at 16.299942 28.710128 180)
			(size 0.450088 0.450088)
			(layers "F.Cu" "F.Mask" "F.Paste")
			(net "GND")
		)
		(pad "CW57" smd circle
			(at 17.239996 28.710128 180)
			(size 0.450088 0.450088)
			(layers "F.Cu" "F.Mask" "F.Paste")
			(net "M_C_CPU0_SB_DQ<22>")
		)
		(pad "CW58" smd circle
			(at 18.18005 28.710128 180)
			(size 0.450088 0.450088)
			(layers "F.Cu" "F.Mask" "F.Paste")
			(net "PVDDIO_P0")
		)
		(pad "CW59" smd circle
			(at 19.120104 28.710128 180)
			(size 0.450088 0.450088)
			(layers "F.Cu" "F.Mask" "F.Paste")
			(net "M_D_CPU0_SB_DQ<21>")
		)
		(pad "CW60" smd circle
			(at 20.059904 28.710128 180)
			(size 0.450088 0.450088)
			(layers "F.Cu" "F.Mask" "F.Paste")
			(net "M_D_CPU0_SB_DQ<22>")
		)
		(pad "CW61" smd circle
			(at 20.999958 28.710128 180)
			(size 0.450088 0.450088)
			(layers "F.Cu" "F.Mask" "F.Paste")
			(net "GND")
		)
		(pad "CW62" smd circle
			(at 21.940012 28.710128 180)
			(size 0.450088 0.450088)
			(layers "F.Cu" "F.Mask" "F.Paste")
			(net "M_B_CPU0_SB_DQ<21>")
		)
		(pad "CW63" smd circle
			(at 22.880066 28.710128 180)
			(size 0.450088 0.450088)
			(layers "F.Cu" "F.Mask" "F.Paste")
			(net "GND")
		)
		(pad "CW64" smd circle
			(at 23.82012 28.710128 180)
			(size 0.450088 0.450088)
			(layers "F.Cu" "F.Mask" "F.Paste")
			(net "M_B_CPU0_SB_DQ<22>")
		)
		(pad "CW65" smd circle
			(at 24.75992 28.710128 180)
			(size 0.450088 0.450088)
			(layers "F.Cu" "F.Mask" "F.Paste")
			(net "PVDDIO_P0")
		)
		(pad "CW66" smd circle
			(at 25.699974 28.710128 180)
			(size 0.450088 0.450088)
			(layers "F.Cu" "F.Mask" "F.Paste")
			(net "M_F_CPU0_SB_DQ<21>")
		)
		(pad "CW67" smd circle
			(at 26.640028 28.710128 180)
			(size 0.450088 0.450088)
			(layers "F.Cu" "F.Mask" "F.Paste")
			(net "M_F_CPU0_SB_DQ<22>")
		)
		(pad "CW68" smd circle
			(at 27.580082 28.710128 180)
			(size 0.450088 0.450088)
			(layers "F.Cu" "F.Mask" "F.Paste")
			(net "GND")
		)
		(pad "CW69" smd circle
			(at 28.519882 28.710128 180)
			(size 0.450088 0.450088)
			(layers "F.Cu" "F.Mask" "F.Paste")
			(net "M_E_CPU0_SB_DQ<21>")
		)
		(pad "CW70" smd circle
			(at 29.459936 28.710128 180)
			(size 0.450088 0.450088)
			(layers "F.Cu" "F.Mask" "F.Paste")
			(net "GND")
		)
		(pad "CW71" smd circle
			(at 30.39999 28.710128 180)
			(size 0.450088 0.450088)
			(layers "F.Cu" "F.Mask" "F.Paste")
			(net "M_E_CPU0_SB_DQ<22>")
		)
		(pad "CW72" smd circle
			(at 31.340044 28.710128 180)
			(size 0.450088 0.450088)
			(layers "F.Cu" "F.Mask" "F.Paste")
			(net "PVDDIO_P0")
		)
		(pad "CW73" smd circle
			(at 32.280098 28.710128 180)
			(size 0.450088 0.450088)
			(layers "F.Cu" "F.Mask" "F.Paste")
			(net "M_A_CPU0_SB_DQ<21>")
		)
		(pad "CW74" smd circle
			(at 33.219898 28.710128 180)
			(size 0.450088 0.450088)
			(layers "F.Cu" "F.Mask" "F.Paste")
			(net "M_A_CPU0_SB_DQ<22>")
		)
		(pad "CW75" smd circle
			(at 34.159952 28.710128 180)
			(size 0.450088 0.450088)
			(layers "F.Cu" "F.Mask" "F.Paste")
			(net "GND")
		)
		(pad "CY2" smd circle
			(at -33.990026 29.51988 180)
			(size 0.450088 0.450088)
			(layers "F.Cu" "F.Mask" "F.Paste")
			(net "M_G_CPU0_SB_DQ<24>")
		)
		(pad "CY3" smd circle
			(at -33.049972 29.51988 180)
			(size 0.450088 0.450088)
			(layers "F.Cu" "F.Mask" "F.Paste")
			(net "GND")
		)
		(pad "CY4" smd circle
			(at -32.109918 29.51988 180)
			(size 0.450088 0.450088)
			(layers "F.Cu" "F.Mask" "F.Paste")
			(net "M_G_CPU0_SB_DQ<23>")
		)
		(pad "CY5" smd circle
			(at -31.170118 29.51988 180)
			(size 0.450088 0.450088)
			(layers "F.Cu" "F.Mask" "F.Paste")
			(net "GND")
		)
		(pad "CY6" smd circle
			(at -30.230064 29.51988 180)
			(size 0.450088 0.450088)
			(layers "F.Cu" "F.Mask" "F.Paste")
			(net "M_K_CPU0_SB_DQ<24>")
		)
		(pad "CY7" smd circle
			(at -29.29001 29.51988 180)
			(size 0.450088 0.450088)
			(layers "F.Cu" "F.Mask" "F.Paste")
			(net "M_K_CPU0_SB_DQ<23>")
		)
		(pad "CY8" smd circle
			(at -28.349956 29.51988 180)
			(size 0.450088 0.450088)
			(layers "F.Cu" "F.Mask" "F.Paste")
			(net "GND")
		)
		(pad "CY9" smd circle
			(at -27.409902 29.51988 180)
			(size 0.450088 0.450088)
			(layers "F.Cu" "F.Mask" "F.Paste")
			(net "M_L_CPU0_SB_DQ<24>")
		)
		(pad "CY10" smd circle
			(at -26.470102 29.51988 180)
			(size 0.450088 0.450088)
			(layers "F.Cu" "F.Mask" "F.Paste")
			(net "GND")
		)
		(pad "CY11" smd circle
			(at -25.530048 29.51988 180)
			(size 0.450088 0.450088)
			(layers "F.Cu" "F.Mask" "F.Paste")
			(net "M_L_CPU0_SB_DQ<23>")
		)
		(pad "CY12" smd circle
			(at -24.589994 29.51988 180)
			(size 0.450088 0.450088)
			(layers "F.Cu" "F.Mask" "F.Paste")
			(net "GND")
		)
		(pad "CY13" smd circle
			(at -23.64994 29.51988 180)
			(size 0.450088 0.450088)
			(layers "F.Cu" "F.Mask" "F.Paste")
			(net "M_H_CPU0_SB_DQ<24>")
		)
		(pad "CY14" smd circle
			(at -22.709886 29.51988 180)
			(size 0.450088 0.450088)
			(layers "F.Cu" "F.Mask" "F.Paste")
			(net "M_H_CPU0_SB_DQ<23>")
		)
		(pad "CY15" smd circle
			(at -21.770086 29.51988 180)
			(size 0.450088 0.450088)
			(layers "F.Cu" "F.Mask" "F.Paste")
			(net "GND")
		)
		(pad "CY16" smd circle
			(at -20.830032 29.51988 180)
			(size 0.450088 0.450088)
			(layers "F.Cu" "F.Mask" "F.Paste")
			(net "M_J_CPU0_SB_DQ<24>")
		)
		(pad "CY17" smd circle
			(at -19.889978 29.51988 180)
			(size 0.450088 0.450088)
			(layers "F.Cu" "F.Mask" "F.Paste")
			(net "GND")
		)
		(pad "CY18" smd circle
			(at -18.949924 29.51988 180)
			(size 0.450088 0.450088)
			(layers "F.Cu" "F.Mask" "F.Paste")
			(net "M_J_CPU0_SB_DQ<23>")
		)
		(pad "CY19" smd circle
			(at -18.010124 29.51988 180)
			(size 0.450088 0.450088)
			(layers "F.Cu" "F.Mask" "F.Paste")
			(net "GND")
		)
		(pad "CY20" smd circle
			(at -17.07007 29.51988 180)
			(size 0.450088 0.450088)
			(layers "F.Cu" "F.Mask" "F.Paste")
			(net "M_I_CPU0_SB_DQ<24>")
		)
		(pad "CY21" smd circle
			(at -16.130016 29.51988 180)
			(size 0.450088 0.450088)
			(layers "F.Cu" "F.Mask" "F.Paste")
			(net "M_I_CPU0_SB_DQ<23>")
		)
		(pad "CY22" smd circle
			(at -15.189962 29.51988 180)
			(size 0.450088 0.450088)
			(layers "F.Cu" "F.Mask" "F.Paste")
			(net "PVDD11_S3_P0")
		)
		(pad "CY23" smd circle
			(at -14.249908 29.51988 180)
			(size 0.450088 0.450088)
			(layers "F.Cu" "F.Mask" "F.Paste")
			(net "GND")
		)
		(pad "CY24" smd circle
			(at -13.310108 29.51988 180)
			(size 0.450088 0.450088)
			(layers "F.Cu" "F.Mask" "F.Paste")
			(net "GND")
		)
		(pad "CY25" smd circle
			(at -12.370054 29.51988 180)
			(size 0.450088 0.450088)
			(layers "F.Cu" "F.Mask" "F.Paste")
			(net "GND")
		)
		(pad "CY26" smd circle
			(at -11.43 29.51988 180)
			(size 0.450088 0.450088)
			(layers "F.Cu" "F.Mask" "F.Paste")
			(net "GND")
		)
		(pad "CY27" smd circle
			(at -10.489946 29.51988 180)
			(size 0.450088 0.450088)
			(layers "F.Cu" "F.Mask" "F.Paste")
			(net "GND")
		)
		(pad "CY28" smd circle
			(at -9.549892 29.51988 180)
			(size 0.450088 0.450088)
			(layers "F.Cu" "F.Mask" "F.Paste")
			(net "GND")
		)
		(pad "CY29" smd circle
			(at -8.610092 29.51988 180)
			(size 0.450088 0.450088)
			(layers "F.Cu" "F.Mask" "F.Paste")
			(net "GND")
		)
		(pad "CY30" smd circle
			(at -7.670038 29.51988 180)
			(size 0.450088 0.450088)
			(layers "F.Cu" "F.Mask" "F.Paste")
			(net "GND")
		)
		(pad "CY31" smd circle
			(at -6.729984 29.51988 180)
			(size 0.450088 0.450088)
			(layers "F.Cu" "F.Mask" "F.Paste")
			(net "GND")
		)
		(pad "CY32" smd circle
			(at -5.78993 29.51988 180)
			(size 0.450088 0.450088)
			(layers "F.Cu" "F.Mask" "F.Paste")
			(net "GND")
		)
		(pad "CY33" smd circle
			(at -4.849876 29.51988 180)
			(size 0.450088 0.450088)
			(layers "F.Cu" "F.Mask" "F.Paste")
			(net "GND")
		)
		(pad "CY34" smd circle
			(at -3.910076 29.51988 180)
			(size 0.450088 0.450088)
			(layers "F.Cu" "F.Mask" "F.Paste")
			(net "GND")
		)
		(pad "CY35" smd circle
			(at -2.970022 29.51988 180)
			(size 0.450088 0.450088)
			(layers "F.Cu" "F.Mask" "F.Paste")
			(net "P5E_CPU0_P3_RX_DP<1>")
		)
		(pad "CY36" smd circle
			(at -2.029968 29.51988 180)
			(size 0.450088 0.450088)
			(layers "F.Cu" "F.Mask" "F.Paste")
			(net "P5E_CPU0_P3_RX_DN<1>")
		)
		(pad "CY37" smd circle
			(at -1.089914 29.51988 180)
			(size 0.450088 0.450088)
			(layers "F.Cu" "F.Mask" "F.Paste")
			(net "GND")
		)
		(pad "CY39" smd circle
			(at 0.78994 29.51988 180)
			(size 0.450088 0.450088)
			(layers "F.Cu" "F.Mask" "F.Paste")
			(net "GND")
		)
		(pad "CY40" smd circle
			(at 1.729994 29.51988 180)
			(size 0.450088 0.450088)
			(layers "F.Cu" "F.Mask" "F.Paste")
			(net "P5E_CPU0_P1_TX_DN<14>")
		)
		(pad "CY41" smd circle
			(at 2.670048 29.51988 180)
			(size 0.450088 0.450088)
			(layers "F.Cu" "F.Mask" "F.Paste")
			(net "P5E_CPU0_P1_TX_DP<14>")
		)
		(pad "CY42" smd circle
			(at 3.610102 29.51988 180)
			(size 0.450088 0.450088)
			(layers "F.Cu" "F.Mask" "F.Paste")
			(net "GND")
		)
		(pad "CY43" smd circle
			(at 4.549902 29.51988 180)
			(size 0.450088 0.450088)
			(layers "F.Cu" "F.Mask" "F.Paste")
			(net "GND")
		)
		(pad "CY44" smd circle
			(at 5.489956 29.51988 180)
			(size 0.450088 0.450088)
			(layers "F.Cu" "F.Mask" "F.Paste")
			(net "GND")
		)
		(pad "CY45" smd circle
			(at 6.43001 29.51988 180)
			(size 0.450088 0.450088)
			(layers "F.Cu" "F.Mask" "F.Paste")
			(net "GND")
		)
		(pad "CY46" smd circle
			(at 7.370064 29.51988 180)
			(size 0.450088 0.450088)
			(layers "F.Cu" "F.Mask" "F.Paste")
			(net "GND")
		)
		(pad "CY47" smd circle
			(at 8.310118 29.51988 180)
			(size 0.450088 0.450088)
			(layers "F.Cu" "F.Mask" "F.Paste")
			(net "GND")
		)
		(pad "CY48" smd circle
			(at 9.249918 29.51988 180)
			(size 0.450088 0.450088)
			(layers "F.Cu" "F.Mask" "F.Paste")
			(net "GND")
		)
		(pad "CY49" smd circle
			(at 10.189972 29.51988 180)
			(size 0.450088 0.450088)
			(layers "F.Cu" "F.Mask" "F.Paste")
			(net "GND")
		)
		(pad "CY50" smd circle
			(at 11.130026 29.51988 180)
			(size 0.450088 0.450088)
			(layers "F.Cu" "F.Mask" "F.Paste")
			(net "GND")
		)
		(pad "CY51" smd circle
			(at 12.07008 29.51988 180)
			(size 0.450088 0.450088)
			(layers "F.Cu" "F.Mask" "F.Paste")
			(net "GND")
		)
		(pad "CY52" smd circle
			(at 13.00988 29.51988 180)
			(size 0.450088 0.450088)
			(layers "F.Cu" "F.Mask" "F.Paste")
			(net "GND")
		)
		(pad "CY53" smd circle
			(at 13.949934 29.51988 180)
			(size 0.450088 0.450088)
			(layers "F.Cu" "F.Mask" "F.Paste")
			(net "GND")
		)
		(pad "CY54" smd circle
			(at 14.889988 29.51988 180)
			(size 0.450088 0.450088)
			(layers "F.Cu" "F.Mask" "F.Paste")
			(net "PVDDIO_P0")
		)
		(pad "CY55" smd circle
			(at 15.830042 29.51988 180)
			(size 0.450088 0.450088)
			(layers "F.Cu" "F.Mask" "F.Paste")
			(net "M_C_CPU0_SB_DQ<23>")
		)
		(pad "CY56" smd circle
			(at 16.770096 29.51988 180)
			(size 0.450088 0.450088)
			(layers "F.Cu" "F.Mask" "F.Paste")
			(net "M_C_CPU0_SB_DQ<24>")
		)
		(pad "CY57" smd circle
			(at 17.709896 29.51988 180)
			(size 0.450088 0.450088)
			(layers "F.Cu" "F.Mask" "F.Paste")
			(net "GND")
		)
		(pad "CY58" smd circle
			(at 18.64995 29.51988 180)
			(size 0.450088 0.450088)
			(layers "F.Cu" "F.Mask" "F.Paste")
			(net "M_D_CPU0_SB_DQ<23>")
		)
		(pad "CY59" smd circle
			(at 19.590004 29.51988 180)
			(size 0.450088 0.450088)
			(layers "F.Cu" "F.Mask" "F.Paste")
			(net "GND")
		)
		(pad "CY60" smd circle
			(at 20.530058 29.51988 180)
			(size 0.450088 0.450088)
			(layers "F.Cu" "F.Mask" "F.Paste")
			(net "M_D_CPU0_SB_DQ<24>")
		)
		(pad "CY61" smd circle
			(at 21.470112 29.51988 180)
			(size 0.450088 0.450088)
			(layers "F.Cu" "F.Mask" "F.Paste")
			(net "GND")
		)
		(pad "CY62" smd circle
			(at 22.409912 29.51988 180)
			(size 0.450088 0.450088)
			(layers "F.Cu" "F.Mask" "F.Paste")
			(net "M_B_CPU0_SB_DQ<23>")
		)
		(pad "CY63" smd circle
			(at 23.349966 29.51988 180)
			(size 0.450088 0.450088)
			(layers "F.Cu" "F.Mask" "F.Paste")
			(net "M_B_CPU0_SB_DQ<24>")
		)
		(pad "CY64" smd circle
			(at 24.29002 29.51988 180)
			(size 0.450088 0.450088)
			(layers "F.Cu" "F.Mask" "F.Paste")
			(net "GND")
		)
		(pad "CY65" smd circle
			(at 25.230074 29.51988 180)
			(size 0.450088 0.450088)
			(layers "F.Cu" "F.Mask" "F.Paste")
			(net "M_F_CPU0_SB_DQ<23>")
		)
		(pad "CY66" smd circle
			(at 26.170128 29.51988 180)
			(size 0.450088 0.450088)
			(layers "F.Cu" "F.Mask" "F.Paste")
			(net "GND")
		)
		(pad "CY67" smd circle
			(at 27.109928 29.51988 180)
			(size 0.450088 0.450088)
			(layers "F.Cu" "F.Mask" "F.Paste")
			(net "M_F_CPU0_SB_DQ<24>")
		)
		(pad "CY68" smd circle
			(at 28.049982 29.51988 180)
			(size 0.450088 0.450088)
			(layers "F.Cu" "F.Mask" "F.Paste")
			(net "GND")
		)
		(pad "CY69" smd circle
			(at 28.990036 29.51988 180)
			(size 0.450088 0.450088)
			(layers "F.Cu" "F.Mask" "F.Paste")
			(net "M_E_CPU0_SB_DQ<23>")
		)
		(pad "CY70" smd circle
			(at 29.93009 29.51988 180)
			(size 0.450088 0.450088)
			(layers "F.Cu" "F.Mask" "F.Paste")
			(net "M_E_CPU0_SB_DQ<24>")
		)
		(pad "CY71" smd circle
			(at 30.86989 29.51988 180)
			(size 0.450088 0.450088)
			(layers "F.Cu" "F.Mask" "F.Paste")
			(net "GND")
		)
		(pad "CY72" smd circle
			(at 31.809944 29.51988 180)
			(size 0.450088 0.450088)
			(layers "F.Cu" "F.Mask" "F.Paste")
			(net "M_A_CPU0_SB_DQ<23>")
		)
		(pad "CY73" smd circle
			(at 32.749998 29.51988 180)
			(size 0.450088 0.450088)
			(layers "F.Cu" "F.Mask" "F.Paste")
			(net "GND")
		)
		(pad "CY74" smd circle
			(at 33.690052 29.51988 180)
			(size 0.450088 0.450088)
			(layers "F.Cu" "F.Mask" "F.Paste")
			(net "M_A_CPU0_SB_DQ<24>")
		)
		(pad "D2" smd circle
			(at -33.690052 -34.379916 180)
			(size 0.450088 0.450088)
			(layers "F.Cu" "F.Mask" "F.Paste")
			(net "GND")
		)
		(pad "D3" smd circle
			(at -32.749998 -34.379916 180)
			(size 0.450088 0.450088)
			(layers "F.Cu" "F.Mask" "F.Paste")
			(net "GND")
		)
		(pad "D4" smd circle
			(at -31.809944 -34.379916 180)
			(size 0.450088 0.450088)
			(layers "F.Cu" "F.Mask" "F.Paste")
			(net "Net_1934")
		)
		(pad "D5" smd circle
			(at -30.86989 -34.379916 180)
			(size 0.450088 0.450088)
			(layers "F.Cu" "F.Mask" "F.Paste")
			(net "GND")
		)
		(pad "D6" smd circle
			(at -29.93009 -34.379916 180)
			(size 0.450088 0.450088)
			(layers "F.Cu" "F.Mask" "F.Paste")
			(net "GND")
		)
		(pad "D7" smd circle
			(at -28.990036 -34.379916 180)
			(size 0.450088 0.450088)
			(layers "F.Cu" "F.Mask" "F.Paste")
			(net "TP_CPU0_TEST47_IOD1")
		)
		(pad "D8" smd circle
			(at -28.049982 -34.379916 180)
			(size 0.450088 0.450088)
			(layers "F.Cu" "F.Mask" "F.Paste")
			(net "Net_1939")
		)
		(pad "D9" smd circle
			(at -27.109928 -34.379916 180)
			(size 0.450088 0.450088)
			(layers "F.Cu" "F.Mask" "F.Paste")
			(net "GND")
		)
		(pad "D10" smd circle
			(at -26.170128 -34.379916 180)
			(size 0.450088 0.450088)
			(layers "F.Cu" "F.Mask" "F.Paste")
			(net "GND")
		)
		(pad "D11" smd circle
			(at -25.230074 -34.379916 180)
			(size 0.450088 0.450088)
			(layers "F.Cu" "F.Mask" "F.Paste")
			(net "Net_1930")
		)
		(pad "D12" smd circle
			(at -24.29002 -34.379916 180)
			(size 0.450088 0.450088)
			(layers "F.Cu" "F.Mask" "F.Paste")
			(net "GND")
		)
		(pad "D13" smd circle
			(at -23.349966 -34.379916 180)
			(size 0.450088 0.450088)
			(layers "F.Cu" "F.Mask" "F.Paste")
			(net "GND")
		)
		(pad "D14" smd circle
			(at -22.409912 -34.379916 180)
			(size 0.450088 0.450088)
			(layers "F.Cu" "F.Mask" "F.Paste")
			(net "SMB_CPU0_SEC_SDA")
		)
		(pad "D15" smd circle
			(at -21.470112 -34.379916 180)
			(size 0.450088 0.450088)
			(layers "F.Cu" "F.Mask" "F.Paste")
			(net "Net_1881")
		)
		(pad "D16" smd circle
			(at -20.530058 -34.379916 180)
			(size 0.450088 0.450088)
			(layers "F.Cu" "F.Mask" "F.Paste")
			(net "GND")
		)
		(pad "D17" smd circle
			(at -19.590004 -34.379916 180)
			(size 0.450088 0.450088)
			(layers "F.Cu" "F.Mask" "F.Paste")
			(net "GND")
		)
		(pad "D18" smd circle
			(at -18.64995 -34.379916 180)
			(size 0.450088 0.450088)
			(layers "F.Cu" "F.Mask" "F.Paste")
			(net "RST_CPU0_PERST0_N")
		)
		(pad "D19" smd circle
			(at -17.709896 -34.379916 180)
			(size 0.450088 0.450088)
			(layers "F.Cu" "F.Mask" "F.Paste")
			(net "GND")
		)
		(pad "D20" smd circle
			(at -16.770096 -34.379916 180)
			(size 0.450088 0.450088)
			(layers "F.Cu" "F.Mask" "F.Paste")
			(net "GND")
		)
		(pad "D21" smd circle
			(at -15.830042 -34.379916 180)
			(size 0.450088 0.450088)
			(layers "F.Cu" "F.Mask" "F.Paste")
			(net "GND")
		)
		(pad "D22" smd circle
			(at -14.889988 -34.379916 180)
			(size 0.450088 0.450088)
			(layers "F.Cu" "F.Mask" "F.Paste")
			(net "Net_1931")
		)
		(pad "D23" smd circle
			(at -13.949934 -34.379916 180)
			(size 0.450088 0.450088)
			(layers "F.Cu" "F.Mask" "F.Paste")
			(net "Net_1953")
		)
		(pad "D24" smd circle
			(at -13.00988 -34.379916 180)
			(size 0.450088 0.450088)
			(layers "F.Cu" "F.Mask" "F.Paste")
			(net "GND")
		)
		(pad "D25" smd circle
			(at -12.07008 -34.379916 180)
			(size 0.450088 0.450088)
			(layers "F.Cu" "F.Mask" "F.Paste")
			(net "GND")
		)
		(pad "D26" smd circle
			(at -11.130026 -34.379916 180)
			(size 0.450088 0.450088)
			(layers "F.Cu" "F.Mask" "F.Paste")
			(net "GND")
		)
		(pad "D27" smd circle
			(at -10.189972 -34.379916 180)
			(size 0.450088 0.450088)
			(layers "F.Cu" "F.Mask" "F.Paste")
			(net "GND")
		)
		(pad "D28" smd circle
			(at -9.249918 -34.379916 180)
			(size 0.450088 0.450088)
			(layers "F.Cu" "F.Mask" "F.Paste")
			(net "GND")
		)
		(pad "D29" smd circle
			(at -8.310118 -34.379916 180)
			(size 0.450088 0.450088)
			(layers "F.Cu" "F.Mask" "F.Paste")
			(net "GND")
		)
		(pad "D30" smd circle
			(at -7.370064 -34.379916 180)
			(size 0.450088 0.450088)
			(layers "F.Cu" "F.Mask" "F.Paste")
			(net "GND")
		)
		(pad "D31" smd circle
			(at -6.43001 -34.379916 180)
			(size 0.450088 0.450088)
			(layers "F.Cu" "F.Mask" "F.Paste")
			(net "GND")
		)
		(pad "D32" smd circle
			(at -5.489956 -34.379916 180)
			(size 0.450088 0.450088)
			(layers "F.Cu" "F.Mask" "F.Paste")
			(net "NC_CPU0_AZ_SYNC")
		)
		(pad "D33" smd circle
			(at -4.549902 -34.379916 180)
			(size 0.450088 0.450088)
			(layers "F.Cu" "F.Mask" "F.Paste")
			(net "NC_CPU0_AZ_SDIN1")
		)
		(pad "D34" smd circle
			(at -3.610102 -34.379916 180)
			(size 0.450088 0.450088)
			(layers "F.Cu" "F.Mask" "F.Paste")
			(net "Net_1932")
		)
		(pad "D35" smd circle
			(at -2.670048 -34.379916 180)
			(size 0.450088 0.450088)
			(layers "F.Cu" "F.Mask" "F.Paste")
			(net "GND")
		)
		(pad "D36" smd circle
			(at -1.729994 -34.379916 180)
			(size 0.450088 0.450088)
			(layers "F.Cu" "F.Mask" "F.Paste")
			(net "Net_1933")
		)
		(pad "D37" smd circle
			(at -0.78994 -34.379916 180)
			(size 0.450088 0.450088)
			(layers "F.Cu" "F.Mask" "F.Paste")
			(net "GND")
		)
		(pad "D39" smd circle
			(at 1.089914 -34.379916 180)
			(size 0.450088 0.450088)
			(layers "F.Cu" "F.Mask" "F.Paste")
			(net "GND")
		)
		(pad "D40" smd circle
			(at 2.029968 -34.379916 180)
			(size 0.450088 0.450088)
			(layers "F.Cu" "F.Mask" "F.Paste")
			(net "GND")
		)
		(pad "D41" smd circle
			(at 2.970022 -34.379916 180)
			(size 0.450088 0.450088)
			(layers "F.Cu" "F.Mask" "F.Paste")
			(net "GND")
		)
		(pad "D42" smd circle
			(at 3.910076 -34.379916 180)
			(size 0.450088 0.450088)
			(layers "F.Cu" "F.Mask" "F.Paste")
			(net "GND")
		)
		(pad "D43" smd circle
			(at 4.849876 -34.379916 180)
			(size 0.450088 0.450088)
			(layers "F.Cu" "F.Mask" "F.Paste")
			(net "GND")
		)
		(pad "D44" smd circle
			(at 5.78993 -34.379916 180)
			(size 0.450088 0.450088)
			(layers "F.Cu" "F.Mask" "F.Paste")
			(net "GND")
		)
		(pad "D45" smd circle
			(at 6.729984 -34.379916 180)
			(size 0.450088 0.450088)
			(layers "F.Cu" "F.Mask" "F.Paste")
			(net "GND")
		)
		(pad "D46" smd circle
			(at 7.670038 -34.379916 180)
			(size 0.450088 0.450088)
			(layers "F.Cu" "F.Mask" "F.Paste")
			(net "GND")
		)
		(pad "D47" smd circle
			(at 8.610092 -34.379916 180)
			(size 0.450088 0.450088)
			(layers "F.Cu" "F.Mask" "F.Paste")
			(net "GND")
		)
		(pad "D48" smd circle
			(at 9.549892 -34.379916 180)
			(size 0.450088 0.450088)
			(layers "F.Cu" "F.Mask" "F.Paste")
			(net "GND")
		)
		(pad "D49" smd circle
			(at 10.489946 -34.379916 180)
			(size 0.450088 0.450088)
			(layers "F.Cu" "F.Mask" "F.Paste")
			(net "GND")
		)
		(pad "D50" smd circle
			(at 11.43 -34.379916 180)
			(size 0.450088 0.450088)
			(layers "F.Cu" "F.Mask" "F.Paste")
			(net "GND")
		)
		(pad "D51" smd circle
			(at 12.370054 -34.379916 180)
			(size 0.450088 0.450088)
			(layers "F.Cu" "F.Mask" "F.Paste")
			(net "GND")
		)
		(pad "D52" smd circle
			(at 13.310108 -34.379916 180)
			(size 0.450088 0.450088)
			(layers "F.Cu" "F.Mask" "F.Paste")
			(net "GND")
		)
		(pad "D53" smd circle
			(at 14.249908 -34.379916 180)
			(size 0.450088 0.450088)
			(layers "F.Cu" "F.Mask" "F.Paste")
			(net "GND")
		)
		(pad "D54" smd circle
			(at 15.189962 -34.379916 180)
			(size 0.450088 0.450088)
			(layers "F.Cu" "F.Mask" "F.Paste")
			(net "GND")
		)
		(pad "D55" smd circle
			(at 16.130016 -34.379916 180)
			(size 0.450088 0.450088)
			(layers "F.Cu" "F.Mask" "F.Paste")
			(net "PVDDCR_CPU0_P0")
		)
		(pad "D56" smd circle
			(at 17.07007 -34.379916 180)
			(size 0.450088 0.450088)
			(layers "F.Cu" "F.Mask" "F.Paste")
			(net "PVDDCR_CPU0_P0")
		)
		(pad "D57" smd circle
			(at 18.010124 -34.379916 180)
			(size 0.450088 0.450088)
			(layers "F.Cu" "F.Mask" "F.Paste")
			(net "GND")
		)
		(pad "D58" smd circle
			(at 18.949924 -34.379916 180)
			(size 0.450088 0.450088)
			(layers "F.Cu" "F.Mask" "F.Paste")
			(net "Net_1935")
		)
		(pad "D59" smd circle
			(at 19.889978 -34.379916 180)
			(size 0.450088 0.450088)
			(layers "F.Cu" "F.Mask" "F.Paste")
			(net "GND")
		)
		(pad "D60" smd circle
			(at 20.830032 -34.379916 180)
			(size 0.450088 0.450088)
			(layers "F.Cu" "F.Mask" "F.Paste")
			(net "GND")
		)
		(pad "D61" smd circle
			(at 21.770086 -34.379916 180)
			(size 0.450088 0.450088)
			(layers "F.Cu" "F.Mask" "F.Paste")
			(net "GND")
		)
		(pad "D62" smd circle
			(at 22.709886 -34.379916 180)
			(size 0.450088 0.450088)
			(layers "F.Cu" "F.Mask" "F.Paste")
			(net "Net_1936")
		)
		(pad "D63" smd circle
			(at 23.64994 -34.379916 180)
			(size 0.450088 0.450088)
			(layers "F.Cu" "F.Mask" "F.Paste")
			(net "GND")
		)
		(pad "D64" smd circle
			(at 24.589994 -34.379916 180)
			(size 0.450088 0.450088)
			(layers "F.Cu" "F.Mask" "F.Paste")
			(net "GND")
		)
		(pad "D65" smd circle
			(at 25.530048 -34.379916 180)
			(size 0.450088 0.450088)
			(layers "F.Cu" "F.Mask" "F.Paste")
			(net "Net_1937")
		)
		(pad "D66" smd circle
			(at 26.470102 -34.379916 180)
			(size 0.450088 0.450088)
			(layers "F.Cu" "F.Mask" "F.Paste")
			(net "GND")
		)
		(pad "D67" smd circle
			(at 27.409902 -34.379916 180)
			(size 0.450088 0.450088)
			(layers "F.Cu" "F.Mask" "F.Paste")
			(net "GND")
		)
		(pad "D68" smd circle
			(at 28.349956 -34.379916 180)
			(size 0.450088 0.450088)
			(layers "F.Cu" "F.Mask" "F.Paste")
			(net "CPU0_CORETYPE2")
		)
		(pad "D69" smd circle
			(at 29.29001 -34.379916 180)
			(size 0.450088 0.450088)
			(layers "F.Cu" "F.Mask" "F.Paste")
			(net "PWRGD_CPU0_PWROK")
		)
		(pad "D70" smd circle
			(at 30.230064 -34.379916 180)
			(size 0.450088 0.450088)
			(layers "F.Cu" "F.Mask" "F.Paste")
			(net "GND")
		)
		(pad "D71" smd circle
			(at 31.170118 -34.379916 180)
			(size 0.450088 0.450088)
			(layers "F.Cu" "F.Mask" "F.Paste")
			(net "GND")
		)
		(pad "D72" smd circle
			(at 32.109918 -34.379916 180)
			(size 0.450088 0.450088)
			(layers "F.Cu" "F.Mask" "F.Paste")
			(net "Net_1938")
		)
		(pad "D73" smd circle
			(at 33.049972 -34.379916 180)
			(size 0.450088 0.450088)
			(layers "F.Cu" "F.Mask" "F.Paste")
			(net "GND")
		)
		(pad "D74" smd circle
			(at 33.990026 -34.379916 180)
			(size 0.450088 0.450088)
			(layers "F.Cu" "F.Mask" "F.Paste")
			(net "GND")
		)
		(pad "DA1" smd circle
			(at -34.459926 30.329886 180)
			(size 0.450088 0.450088)
			(layers "F.Cu" "F.Mask" "F.Paste")
			(net "GND")
		)
		(pad "DA2" smd circle
			(at -33.519872 30.329886 180)
			(size 0.450088 0.450088)
			(layers "F.Cu" "F.Mask" "F.Paste")
			(net "M_G_CPU0_SB_DQ<26>")
		)
		(pad "DA3" smd circle
			(at -32.580072 30.329886 180)
			(size 0.450088 0.450088)
			(layers "F.Cu" "F.Mask" "F.Paste")
			(net "M_G_CPU0_SB_DQ<25>")
		)
		(pad "DA4" smd circle
			(at -31.640018 30.329886 180)
			(size 0.450088 0.450088)
			(layers "F.Cu" "F.Mask" "F.Paste")
			(net "GND")
		)
		(pad "DA5" smd circle
			(at -30.699964 30.329886 180)
			(size 0.450088 0.450088)
			(layers "F.Cu" "F.Mask" "F.Paste")
			(net "M_K_CPU0_SB_DQ<26>")
		)
		(pad "DA6" smd circle
			(at -29.75991 30.329886 180)
			(size 0.450088 0.450088)
			(layers "F.Cu" "F.Mask" "F.Paste")
			(net "GND")
		)
		(pad "DA7" smd circle
			(at -28.82011 30.329886 180)
			(size 0.450088 0.450088)
			(layers "F.Cu" "F.Mask" "F.Paste")
			(net "M_K_CPU0_SB_DQ<25>")
		)
		(pad "DA8" smd circle
			(at -27.880056 30.329886 180)
			(size 0.450088 0.450088)
			(layers "F.Cu" "F.Mask" "F.Paste")
			(net "GND")
		)
		(pad "DA9" smd circle
			(at -26.940002 30.329886 180)
			(size 0.450088 0.450088)
			(layers "F.Cu" "F.Mask" "F.Paste")
			(net "M_L_CPU0_SB_DQ<26>")
		)
		(pad "DA10" smd circle
			(at -25.999948 30.329886 180)
			(size 0.450088 0.450088)
			(layers "F.Cu" "F.Mask" "F.Paste")
			(net "M_L_CPU0_SB_DQ<25>")
		)
		(pad "DA11" smd circle
			(at -25.059894 30.329886 180)
			(size 0.450088 0.450088)
			(layers "F.Cu" "F.Mask" "F.Paste")
			(net "GND")
		)
		(pad "DA12" smd circle
			(at -24.120094 30.329886 180)
			(size 0.450088 0.450088)
			(layers "F.Cu" "F.Mask" "F.Paste")
			(net "M_H_CPU0_SB_DQ<26>")
		)
		(pad "DA13" smd circle
			(at -23.18004 30.329886 180)
			(size 0.450088 0.450088)
			(layers "F.Cu" "F.Mask" "F.Paste")
			(net "GND")
		)
		(pad "DA14" smd circle
			(at -22.239986 30.329886 180)
			(size 0.450088 0.450088)
			(layers "F.Cu" "F.Mask" "F.Paste")
			(net "M_H_CPU0_SB_DQ<25>")
		)
		(pad "DA15" smd circle
			(at -21.299932 30.329886 180)
			(size 0.450088 0.450088)
			(layers "F.Cu" "F.Mask" "F.Paste")
			(net "GND")
		)
		(pad "DA16" smd circle
			(at -20.359878 30.329886 180)
			(size 0.450088 0.450088)
			(layers "F.Cu" "F.Mask" "F.Paste")
			(net "M_J_CPU0_SB_DQ<26>")
		)
		(pad "DA17" smd circle
			(at -19.420078 30.329886 180)
			(size 0.450088 0.450088)
			(layers "F.Cu" "F.Mask" "F.Paste")
			(net "M_J_CPU0_SB_DQ<25>")
		)
		(pad "DA18" smd circle
			(at -18.480024 30.329886 180)
			(size 0.450088 0.450088)
			(layers "F.Cu" "F.Mask" "F.Paste")
			(net "GND")
		)
		(pad "DA19" smd circle
			(at -17.53997 30.329886 180)
			(size 0.450088 0.450088)
			(layers "F.Cu" "F.Mask" "F.Paste")
			(net "M_I_CPU0_SB_DQ<26>")
		)
		(pad "DA20" smd circle
			(at -16.599916 30.329886 180)
			(size 0.450088 0.450088)
			(layers "F.Cu" "F.Mask" "F.Paste")
			(net "GND")
		)
		(pad "DA21" smd circle
			(at -15.660116 30.329886 180)
			(size 0.450088 0.450088)
			(layers "F.Cu" "F.Mask" "F.Paste")
			(net "M_I_CPU0_SB_DQ<25>")
		)
		(pad "DA22" smd circle
			(at -14.720062 30.329886 180)
			(size 0.450088 0.450088)
			(layers "F.Cu" "F.Mask" "F.Paste")
			(net "GND")
		)
		(pad "DA23" smd circle
			(at -13.780008 30.329886 180)
			(size 0.450088 0.450088)
			(layers "F.Cu" "F.Mask" "F.Paste")
			(net "P5E_CPU0_P3_RX_DP<14>")
		)
		(pad "DA24" smd circle
			(at -12.839954 30.329886 180)
			(size 0.450088 0.450088)
			(layers "F.Cu" "F.Mask" "F.Paste")
			(net "P5E_CPU0_P3_RX_DN<14>")
		)
		(pad "DA25" smd circle
			(at -11.8999 30.329886 180)
			(size 0.450088 0.450088)
			(layers "F.Cu" "F.Mask" "F.Paste")
			(net "GND")
		)
		(pad "DA26" smd circle
			(at -10.9601 30.329886 180)
			(size 0.450088 0.450088)
			(layers "F.Cu" "F.Mask" "F.Paste")
			(net "P5E_CPU0_P3_RX_DP<11>")
		)
		(pad "DA27" smd circle
			(at -10.020046 30.329886 180)
			(size 0.450088 0.450088)
			(layers "F.Cu" "F.Mask" "F.Paste")
			(net "P5E_CPU0_P3_RX_DN<11>")
		)
		(pad "DA28" smd circle
			(at -9.079992 30.329886 180)
			(size 0.450088 0.450088)
			(layers "F.Cu" "F.Mask" "F.Paste")
			(net "GND")
		)
		(pad "DA29" smd circle
			(at -8.139938 30.329886 180)
			(size 0.450088 0.450088)
			(layers "F.Cu" "F.Mask" "F.Paste")
			(net "P5E_CPU0_P3_RX_DP<8>")
		)
		(pad "DA30" smd circle
			(at -7.199884 30.329886 180)
			(size 0.450088 0.450088)
			(layers "F.Cu" "F.Mask" "F.Paste")
			(net "P5E_CPU0_P3_RX_DN<8>")
		)
		(pad "DA31" smd circle
			(at -6.260084 30.329886 180)
			(size 0.450088 0.450088)
			(layers "F.Cu" "F.Mask" "F.Paste")
			(net "GND")
		)
		(pad "DA32" smd circle
			(at -5.32003 30.329886 180)
			(size 0.450088 0.450088)
			(layers "F.Cu" "F.Mask" "F.Paste")
			(net "P5E_CPU0_P3_RX_DP<5>")
		)
		(pad "DA33" smd circle
			(at -4.379976 30.329886 180)
			(size 0.450088 0.450088)
			(layers "F.Cu" "F.Mask" "F.Paste")
			(net "P5E_CPU0_P3_RX_DN<5>")
		)
		(pad "DA34" smd circle
			(at -3.439922 30.329886 180)
			(size 0.450088 0.450088)
			(layers "F.Cu" "F.Mask" "F.Paste")
			(net "GND")
		)
		(pad "DA35" smd circle
			(at -2.500122 30.329886 180)
			(size 0.450088 0.450088)
			(layers "F.Cu" "F.Mask" "F.Paste")
			(net "PVDDCR_CPU1_P0")
		)
		(pad "DA36" smd circle
			(at -1.560068 30.329886 180)
			(size 0.450088 0.450088)
			(layers "F.Cu" "F.Mask" "F.Paste")
			(net "PVDDCR_CPU1_P0")
		)
		(pad "DA40" smd circle
			(at 1.260094 30.329886 180)
			(size 0.450088 0.450088)
			(layers "F.Cu" "F.Mask" "F.Paste")
			(net "PVDDCR_CPU1_P0")
		)
		(pad "DA41" smd circle
			(at 2.199894 30.329886 180)
			(size 0.450088 0.450088)
			(layers "F.Cu" "F.Mask" "F.Paste")
			(net "PVDDCR_CPU1_P0")
		)
		(pad "DA42" smd circle
			(at 3.139948 30.329886 180)
			(size 0.450088 0.450088)
			(layers "F.Cu" "F.Mask" "F.Paste")
			(net "GND")
		)
		(pad "DA43" smd circle
			(at 4.080002 30.329886 180)
			(size 0.450088 0.450088)
			(layers "F.Cu" "F.Mask" "F.Paste")
			(net "P5E_CPU0_P1_TX_DN<10>")
		)
		(pad "DA44" smd circle
			(at 5.020056 30.329886 180)
			(size 0.450088 0.450088)
			(layers "F.Cu" "F.Mask" "F.Paste")
			(net "P5E_CPU0_P1_TX_DP<10>")
		)
		(pad "DA45" smd circle
			(at 5.96011 30.329886 180)
			(size 0.450088 0.450088)
			(layers "F.Cu" "F.Mask" "F.Paste")
			(net "GND")
		)
		(pad "DA46" smd circle
			(at 6.89991 30.329886 180)
			(size 0.450088 0.450088)
			(layers "F.Cu" "F.Mask" "F.Paste")
			(net "P5E_CPU0_P1_TX_DN<7>")
		)
		(pad "DA47" smd circle
			(at 7.839964 30.329886 180)
			(size 0.450088 0.450088)
			(layers "F.Cu" "F.Mask" "F.Paste")
			(net "P5E_CPU0_P1_TX_DP<7>")
		)
		(pad "DA48" smd circle
			(at 8.780018 30.329886 180)
			(size 0.450088 0.450088)
			(layers "F.Cu" "F.Mask" "F.Paste")
			(net "GND")
		)
		(pad "DA49" smd circle
			(at 9.720072 30.329886 180)
			(size 0.450088 0.450088)
			(layers "F.Cu" "F.Mask" "F.Paste")
			(net "P5E_CPU0_P1_TX_DN<4>")
		)
		(pad "DA50" smd circle
			(at 10.659872 30.329886 180)
			(size 0.450088 0.450088)
			(layers "F.Cu" "F.Mask" "F.Paste")
			(net "P5E_CPU0_P1_TX_DP<4>")
		)
		(pad "DA51" smd circle
			(at 11.599926 30.329886 180)
			(size 0.450088 0.450088)
			(layers "F.Cu" "F.Mask" "F.Paste")
			(net "GND")
		)
		(pad "DA52" smd circle
			(at 12.53998 30.329886 180)
			(size 0.450088 0.450088)
			(layers "F.Cu" "F.Mask" "F.Paste")
			(net "P5E_CPU0_P1_TX_DN<1>")
		)
		(pad "DA53" smd circle
			(at 13.480034 30.329886 180)
			(size 0.450088 0.450088)
			(layers "F.Cu" "F.Mask" "F.Paste")
			(net "P5E_CPU0_P1_TX_DP<1>")
		)
		(pad "DA54" smd circle
			(at 14.420088 30.329886 180)
			(size 0.450088 0.450088)
			(layers "F.Cu" "F.Mask" "F.Paste")
			(net "GND")
		)
		(pad "DA55" smd circle
			(at 15.359888 30.329886 180)
			(size 0.450088 0.450088)
			(layers "F.Cu" "F.Mask" "F.Paste")
			(net "M_C_CPU0_SB_DQ<25>")
		)
		(pad "DA56" smd circle
			(at 16.299942 30.329886 180)
			(size 0.450088 0.450088)
			(layers "F.Cu" "F.Mask" "F.Paste")
			(net "GND")
		)
		(pad "DA57" smd circle
			(at 17.239996 30.329886 180)
			(size 0.450088 0.450088)
			(layers "F.Cu" "F.Mask" "F.Paste")
			(net "M_C_CPU0_SB_DQ<26>")
		)
		(pad "DA58" smd circle
			(at 18.18005 30.329886 180)
			(size 0.450088 0.450088)
			(layers "F.Cu" "F.Mask" "F.Paste")
			(net "GND")
		)
		(pad "DA59" smd circle
			(at 19.120104 30.329886 180)
			(size 0.450088 0.450088)
			(layers "F.Cu" "F.Mask" "F.Paste")
			(net "M_D_CPU0_SB_DQ<25>")
		)
		(pad "DA60" smd circle
			(at 20.059904 30.329886 180)
			(size 0.450088 0.450088)
			(layers "F.Cu" "F.Mask" "F.Paste")
			(net "M_D_CPU0_SB_DQ<26>")
		)
		(pad "DA61" smd circle
			(at 20.999958 30.329886 180)
			(size 0.450088 0.450088)
			(layers "F.Cu" "F.Mask" "F.Paste")
			(net "GND")
		)
		(pad "DA62" smd circle
			(at 21.940012 30.329886 180)
			(size 0.450088 0.450088)
			(layers "F.Cu" "F.Mask" "F.Paste")
			(net "M_B_CPU0_SB_DQ<25>")
		)
		(pad "DA63" smd circle
			(at 22.880066 30.329886 180)
			(size 0.450088 0.450088)
			(layers "F.Cu" "F.Mask" "F.Paste")
			(net "GND")
		)
		(pad "DA64" smd circle
			(at 23.82012 30.329886 180)
			(size 0.450088 0.450088)
			(layers "F.Cu" "F.Mask" "F.Paste")
			(net "M_B_CPU0_SB_DQ<26>")
		)
		(pad "DA65" smd circle
			(at 24.75992 30.329886 180)
			(size 0.450088 0.450088)
			(layers "F.Cu" "F.Mask" "F.Paste")
			(net "GND")
		)
		(pad "DA66" smd circle
			(at 25.699974 30.329886 180)
			(size 0.450088 0.450088)
			(layers "F.Cu" "F.Mask" "F.Paste")
			(net "M_F_CPU0_SB_DQ<25>")
		)
		(pad "DA67" smd circle
			(at 26.640028 30.329886 180)
			(size 0.450088 0.450088)
			(layers "F.Cu" "F.Mask" "F.Paste")
			(net "M_F_CPU0_SB_DQ<26>")
		)
		(pad "DA68" smd circle
			(at 27.580082 30.329886 180)
			(size 0.450088 0.450088)
			(layers "F.Cu" "F.Mask" "F.Paste")
			(net "GND")
		)
		(pad "DA69" smd circle
			(at 28.519882 30.329886 180)
			(size 0.450088 0.450088)
			(layers "F.Cu" "F.Mask" "F.Paste")
			(net "M_E_CPU0_SB_DQ<25>")
		)
		(pad "DA70" smd circle
			(at 29.459936 30.329886 180)
			(size 0.450088 0.450088)
			(layers "F.Cu" "F.Mask" "F.Paste")
			(net "GND")
		)
		(pad "DA71" smd circle
			(at 30.39999 30.329886 180)
			(size 0.450088 0.450088)
			(layers "F.Cu" "F.Mask" "F.Paste")
			(net "M_E_CPU0_SB_DQ<26>")
		)
		(pad "DA72" smd circle
			(at 31.340044 30.329886 180)
			(size 0.450088 0.450088)
			(layers "F.Cu" "F.Mask" "F.Paste")
			(net "GND")
		)
		(pad "DA73" smd circle
			(at 32.280098 30.329886 180)
			(size 0.450088 0.450088)
			(layers "F.Cu" "F.Mask" "F.Paste")
			(net "M_A_CPU0_SB_DQ<25>")
		)
		(pad "DA74" smd circle
			(at 33.219898 30.329886 180)
			(size 0.450088 0.450088)
			(layers "F.Cu" "F.Mask" "F.Paste")
			(net "M_A_CPU0_SB_DQ<26>")
		)
		(pad "DA75" smd circle
			(at 34.159952 30.329886 180)
			(size 0.450088 0.450088)
			(layers "F.Cu" "F.Mask" "F.Paste")
			(net "GND")
		)
		(pad "DB2" smd circle
			(at -33.990026 31.139892 180)
			(size 0.450088 0.450088)
			(layers "F.Cu" "F.Mask" "F.Paste")
			(net "M_G_CPU0_SB_DQS_DP<3>")
		)
		(pad "DB3" smd circle
			(at -33.049972 31.139892 180)
			(size 0.450088 0.450088)
			(layers "F.Cu" "F.Mask" "F.Paste")
			(net "GND")
		)
		(pad "DB4" smd circle
			(at -32.109918 31.139892 180)
			(size 0.450088 0.450088)
			(layers "F.Cu" "F.Mask" "F.Paste")
			(net "M_G_CPU0_SB_DQ<27>")
		)
		(pad "DB5" smd circle
			(at -31.170118 31.139892 180)
			(size 0.450088 0.450088)
			(layers "F.Cu" "F.Mask" "F.Paste")
			(net "PVDD11_S3_P0")
		)
		(pad "DB6" smd circle
			(at -30.230064 31.139892 180)
			(size 0.450088 0.450088)
			(layers "F.Cu" "F.Mask" "F.Paste")
			(net "M_K_CPU0_SB_DQS_DP<3>")
		)
		(pad "DB7" smd circle
			(at -29.29001 31.139892 180)
			(size 0.450088 0.450088)
			(layers "F.Cu" "F.Mask" "F.Paste")
			(net "M_K_CPU0_SB_DQ<27>")
		)
		(pad "DB8" smd circle
			(at -28.349956 31.139892 180)
			(size 0.450088 0.450088)
			(layers "F.Cu" "F.Mask" "F.Paste")
			(net "GND")
		)
		(pad "DB9" smd circle
			(at -27.409902 31.139892 180)
			(size 0.450088 0.450088)
			(layers "F.Cu" "F.Mask" "F.Paste")
			(net "M_L_CPU0_SB_DQS_DP<3>")
		)
		(pad "DB10" smd circle
			(at -26.470102 31.139892 180)
			(size 0.450088 0.450088)
			(layers "F.Cu" "F.Mask" "F.Paste")
			(net "GND")
		)
		(pad "DB11" smd circle
			(at -25.530048 31.139892 180)
			(size 0.450088 0.450088)
			(layers "F.Cu" "F.Mask" "F.Paste")
			(net "M_L_CPU0_SB_DQ<27>")
		)
		(pad "DB12" smd circle
			(at -24.589994 31.139892 180)
			(size 0.450088 0.450088)
			(layers "F.Cu" "F.Mask" "F.Paste")
			(net "PVDD11_S3_P0")
		)
		(pad "DB13" smd circle
			(at -23.64994 31.139892 180)
			(size 0.450088 0.450088)
			(layers "F.Cu" "F.Mask" "F.Paste")
			(net "M_H_CPU0_SB_DQS_DP<3>")
		)
		(pad "DB14" smd circle
			(at -22.709886 31.139892 180)
			(size 0.450088 0.450088)
			(layers "F.Cu" "F.Mask" "F.Paste")
			(net "M_H_CPU0_SB_DQ<27>")
		)
		(pad "DB15" smd circle
			(at -21.770086 31.139892 180)
			(size 0.450088 0.450088)
			(layers "F.Cu" "F.Mask" "F.Paste")
			(net "GND")
		)
		(pad "DB16" smd circle
			(at -20.830032 31.139892 180)
			(size 0.450088 0.450088)
			(layers "F.Cu" "F.Mask" "F.Paste")
			(net "M_J_CPU0_SB_DQS_DP<3>")
		)
		(pad "DB17" smd circle
			(at -19.889978 31.139892 180)
			(size 0.450088 0.450088)
			(layers "F.Cu" "F.Mask" "F.Paste")
			(net "GND")
		)
		(pad "DB18" smd circle
			(at -18.949924 31.139892 180)
			(size 0.450088 0.450088)
			(layers "F.Cu" "F.Mask" "F.Paste")
			(net "M_J_CPU0_SB_DQ<27>")
		)
		(pad "DB19" smd circle
			(at -18.010124 31.139892 180)
			(size 0.450088 0.450088)
			(layers "F.Cu" "F.Mask" "F.Paste")
			(net "PVDD11_S3_P0")
		)
		(pad "DB20" smd circle
			(at -17.07007 31.139892 180)
			(size 0.450088 0.450088)
			(layers "F.Cu" "F.Mask" "F.Paste")
			(net "M_I_CPU0_SB_DQS_DP<3>")
		)
		(pad "DB21" smd circle
			(at -16.130016 31.139892 180)
			(size 0.450088 0.450088)
			(layers "F.Cu" "F.Mask" "F.Paste")
			(net "M_I_CPU0_SB_DQ<27>")
		)
		(pad "DB22" smd circle
			(at -15.189962 31.139892 180)
			(size 0.450088 0.450088)
			(layers "F.Cu" "F.Mask" "F.Paste")
			(net "GND")
		)
		(pad "DB23" smd circle
			(at -14.249908 31.139892 180)
			(size 0.450088 0.450088)
			(layers "F.Cu" "F.Mask" "F.Paste")
			(net "PVDDCR_CPU1_P0")
		)
		(pad "DB24" smd circle
			(at -13.310108 31.139892 180)
			(size 0.450088 0.450088)
			(layers "F.Cu" "F.Mask" "F.Paste")
			(net "PVDDCR_CPU1_P0")
		)
		(pad "DB25" smd circle
			(at -12.370054 31.139892 180)
			(size 0.450088 0.450088)
			(layers "F.Cu" "F.Mask" "F.Paste")
			(net "GND")
		)
		(pad "DB26" smd circle
			(at -11.43 31.139892 180)
			(size 0.450088 0.450088)
			(layers "F.Cu" "F.Mask" "F.Paste")
			(net "PVDDCR_CPU1_P0")
		)
		(pad "DB27" smd circle
			(at -10.489946 31.139892 180)
			(size 0.450088 0.450088)
			(layers "F.Cu" "F.Mask" "F.Paste")
			(net "PVDDCR_CPU1_P0")
		)
		(pad "DB28" smd circle
			(at -9.549892 31.139892 180)
			(size 0.450088 0.450088)
			(layers "F.Cu" "F.Mask" "F.Paste")
			(net "GND")
		)
		(pad "DB29" smd circle
			(at -8.610092 31.139892 180)
			(size 0.450088 0.450088)
			(layers "F.Cu" "F.Mask" "F.Paste")
			(net "PVDDCR_CPU1_P0")
		)
		(pad "DB30" smd circle
			(at -7.670038 31.139892 180)
			(size 0.450088 0.450088)
			(layers "F.Cu" "F.Mask" "F.Paste")
			(net "PVDDCR_CPU1_P0")
		)
		(pad "DB31" smd circle
			(at -6.729984 31.139892 180)
			(size 0.450088 0.450088)
			(layers "F.Cu" "F.Mask" "F.Paste")
			(net "GND")
		)
		(pad "DB32" smd circle
			(at -5.78993 31.139892 180)
			(size 0.450088 0.450088)
			(layers "F.Cu" "F.Mask" "F.Paste")
			(net "PVDDCR_CPU1_P0")
		)
		(pad "DB33" smd circle
			(at -4.849876 31.139892 180)
			(size 0.450088 0.450088)
			(layers "F.Cu" "F.Mask" "F.Paste")
			(net "PVDDCR_CPU1_P0")
		)
		(pad "DB34" smd circle
			(at -3.910076 31.139892 180)
			(size 0.450088 0.450088)
			(layers "F.Cu" "F.Mask" "F.Paste")
			(net "GND")
		)
		(pad "DB35" smd circle
			(at -2.970022 31.139892 180)
			(size 0.450088 0.450088)
			(layers "F.Cu" "F.Mask" "F.Paste")
			(net "P5E_CPU0_P3_RX_DP<2>")
		)
		(pad "DB36" smd circle
			(at -2.029968 31.139892 180)
			(size 0.450088 0.450088)
			(layers "F.Cu" "F.Mask" "F.Paste")
			(net "P5E_CPU0_P3_RX_DN<2>")
		)
		(pad "DB37" smd circle
			(at -1.089914 31.139892 180)
			(size 0.450088 0.450088)
			(layers "F.Cu" "F.Mask" "F.Paste")
			(net "GND")
		)
		(pad "DB39" smd circle
			(at 0.78994 31.139892 180)
			(size 0.450088 0.450088)
			(layers "F.Cu" "F.Mask" "F.Paste")
			(net "GND")
		)
		(pad "DB40" smd circle
			(at 1.729994 31.139892 180)
			(size 0.450088 0.450088)
			(layers "F.Cu" "F.Mask" "F.Paste")
			(net "P5E_CPU0_P1_TX_DN<13>")
		)
		(pad "DB41" smd circle
			(at 2.670048 31.139892 180)
			(size 0.450088 0.450088)
			(layers "F.Cu" "F.Mask" "F.Paste")
			(net "P5E_CPU0_P1_TX_DP<13>")
		)
		(pad "DB42" smd circle
			(at 3.610102 31.139892 180)
			(size 0.450088 0.450088)
			(layers "F.Cu" "F.Mask" "F.Paste")
			(net "GND")
		)
		(pad "DB43" smd circle
			(at 4.549902 31.139892 180)
			(size 0.450088 0.450088)
			(layers "F.Cu" "F.Mask" "F.Paste")
			(net "PVDDCR_CPU1_P0")
		)
		(pad "DB44" smd circle
			(at 5.489956 31.139892 180)
			(size 0.450088 0.450088)
			(layers "F.Cu" "F.Mask" "F.Paste")
			(net "PVDDCR_CPU1_P0")
		)
		(pad "DB45" smd circle
			(at 6.43001 31.139892 180)
			(size 0.450088 0.450088)
			(layers "F.Cu" "F.Mask" "F.Paste")
			(net "GND")
		)
		(pad "DB46" smd circle
			(at 7.370064 31.139892 180)
			(size 0.450088 0.450088)
			(layers "F.Cu" "F.Mask" "F.Paste")
			(net "PVDDCR_CPU1_P0")
		)
		(pad "DB47" smd circle
			(at 8.310118 31.139892 180)
			(size 0.450088 0.450088)
			(layers "F.Cu" "F.Mask" "F.Paste")
			(net "PVDDCR_CPU1_P0")
		)
		(pad "DB48" smd circle
			(at 9.249918 31.139892 180)
			(size 0.450088 0.450088)
			(layers "F.Cu" "F.Mask" "F.Paste")
			(net "GND")
		)
		(pad "DB49" smd circle
			(at 10.189972 31.139892 180)
			(size 0.450088 0.450088)
			(layers "F.Cu" "F.Mask" "F.Paste")
			(net "PVDDCR_CPU1_P0")
		)
		(pad "DB50" smd circle
			(at 11.130026 31.139892 180)
			(size 0.450088 0.450088)
			(layers "F.Cu" "F.Mask" "F.Paste")
			(net "PVDDCR_CPU1_P0")
		)
		(pad "DB51" smd circle
			(at 12.07008 31.139892 180)
			(size 0.450088 0.450088)
			(layers "F.Cu" "F.Mask" "F.Paste")
			(net "GND")
		)
		(pad "DB52" smd circle
			(at 13.00988 31.139892 180)
			(size 0.450088 0.450088)
			(layers "F.Cu" "F.Mask" "F.Paste")
			(net "PVDDCR_CPU1_P0")
		)
		(pad "DB53" smd circle
			(at 13.949934 31.139892 180)
			(size 0.450088 0.450088)
			(layers "F.Cu" "F.Mask" "F.Paste")
			(net "PVDDCR_CPU1_P0")
		)
		(pad "DB54" smd circle
			(at 14.889988 31.139892 180)
			(size 0.450088 0.450088)
			(layers "F.Cu" "F.Mask" "F.Paste")
			(net "GND")
		)
		(pad "DB55" smd circle
			(at 15.830042 31.139892 180)
			(size 0.450088 0.450088)
			(layers "F.Cu" "F.Mask" "F.Paste")
			(net "M_C_CPU0_SB_DQ<27>")
		)
		(pad "DB56" smd circle
			(at 16.770096 31.139892 180)
			(size 0.450088 0.450088)
			(layers "F.Cu" "F.Mask" "F.Paste")
			(net "M_C_CPU0_SB_DQS_DP<3>")
		)
		(pad "DB57" smd circle
			(at 17.709896 31.139892 180)
			(size 0.450088 0.450088)
			(layers "F.Cu" "F.Mask" "F.Paste")
			(net "PVDDIO_P0")
		)
		(pad "DB58" smd circle
			(at 18.64995 31.139892 180)
			(size 0.450088 0.450088)
			(layers "F.Cu" "F.Mask" "F.Paste")
			(net "M_D_CPU0_SB_DQ<27>")
		)
		(pad "DB59" smd circle
			(at 19.590004 31.139892 180)
			(size 0.450088 0.450088)
			(layers "F.Cu" "F.Mask" "F.Paste")
			(net "GND")
		)
		(pad "DB60" smd circle
			(at 20.530058 31.139892 180)
			(size 0.450088 0.450088)
			(layers "F.Cu" "F.Mask" "F.Paste")
			(net "M_D_CPU0_SB_DQS_DP<3>")
		)
		(pad "DB61" smd circle
			(at 21.470112 31.139892 180)
			(size 0.450088 0.450088)
			(layers "F.Cu" "F.Mask" "F.Paste")
			(net "GND")
		)
		(pad "DB62" smd circle
			(at 22.409912 31.139892 180)
			(size 0.450088 0.450088)
			(layers "F.Cu" "F.Mask" "F.Paste")
			(net "M_B_CPU0_SB_DQ<27>")
		)
		(pad "DB63" smd circle
			(at 23.349966 31.139892 180)
			(size 0.450088 0.450088)
			(layers "F.Cu" "F.Mask" "F.Paste")
			(net "M_B_CPU0_SB_DQS_DP<3>")
		)
		(pad "DB64" smd circle
			(at 24.29002 31.139892 180)
			(size 0.450088 0.450088)
			(layers "F.Cu" "F.Mask" "F.Paste")
			(net "PVDDIO_P0")
		)
		(pad "DB65" smd circle
			(at 25.230074 31.139892 180)
			(size 0.450088 0.450088)
			(layers "F.Cu" "F.Mask" "F.Paste")
			(net "M_F_CPU0_SB_DQ<27>")
		)
		(pad "DB66" smd circle
			(at 26.170128 31.139892 180)
			(size 0.450088 0.450088)
			(layers "F.Cu" "F.Mask" "F.Paste")
			(net "GND")
		)
		(pad "DB67" smd circle
			(at 27.109928 31.139892 180)
			(size 0.450088 0.450088)
			(layers "F.Cu" "F.Mask" "F.Paste")
			(net "M_F_CPU0_SB_DQS_DP<3>")
		)
		(pad "DB68" smd circle
			(at 28.049982 31.139892 180)
			(size 0.450088 0.450088)
			(layers "F.Cu" "F.Mask" "F.Paste")
			(net "GND")
		)
		(pad "DB69" smd circle
			(at 28.990036 31.139892 180)
			(size 0.450088 0.450088)
			(layers "F.Cu" "F.Mask" "F.Paste")
			(net "M_E_CPU0_SB_DQ<27>")
		)
		(pad "DB70" smd circle
			(at 29.93009 31.139892 180)
			(size 0.450088 0.450088)
			(layers "F.Cu" "F.Mask" "F.Paste")
			(net "M_E_CPU0_SB_DQS_DP<3>")
		)
		(pad "DB71" smd circle
			(at 30.86989 31.139892 180)
			(size 0.450088 0.450088)
			(layers "F.Cu" "F.Mask" "F.Paste")
			(net "PVDDIO_P0")
		)
		(pad "DB72" smd circle
			(at 31.809944 31.139892 180)
			(size 0.450088 0.450088)
			(layers "F.Cu" "F.Mask" "F.Paste")
			(net "M_A_CPU0_SB_DQ<27>")
		)
		(pad "DB73" smd circle
			(at 32.749998 31.139892 180)
			(size 0.450088 0.450088)
			(layers "F.Cu" "F.Mask" "F.Paste")
			(net "GND")
		)
		(pad "DB74" smd circle
			(at 33.690052 31.139892 180)
			(size 0.450088 0.450088)
			(layers "F.Cu" "F.Mask" "F.Paste")
			(net "M_A_CPU0_SB_DQS_DP<3>")
		)
		(pad "DC1" smd circle
			(at -34.459926 31.949898 180)
			(size 0.450088 0.450088)
			(layers "F.Cu" "F.Mask" "F.Paste")
			(net "GND")
		)
		(pad "DC2" smd circle
			(at -33.519872 31.949898 180)
			(size 0.450088 0.450088)
			(layers "F.Cu" "F.Mask" "F.Paste")
			(net "M_G_CPU0_SB_DQS_DN<3>")
		)
		(pad "DC3" smd circle
			(at -32.580072 31.949898 180)
			(size 0.450088 0.450088)
			(layers "F.Cu" "F.Mask" "F.Paste")
			(net "M_G_CPU0_SB_DQS_DN<8>")
		)
		(pad "DC4" smd circle
			(at -31.640018 31.949898 180)
			(size 0.450088 0.450088)
			(layers "F.Cu" "F.Mask" "F.Paste")
			(net "GND")
		)
		(pad "DC5" smd circle
			(at -30.699964 31.949898 180)
			(size 0.450088 0.450088)
			(layers "F.Cu" "F.Mask" "F.Paste")
			(net "M_K_CPU0_SB_DQS_DN<3>")
		)
		(pad "DC6" smd circle
			(at -29.75991 31.949898 180)
			(size 0.450088 0.450088)
			(layers "F.Cu" "F.Mask" "F.Paste")
			(net "GND")
		)
		(pad "DC7" smd circle
			(at -28.82011 31.949898 180)
			(size 0.450088 0.450088)
			(layers "F.Cu" "F.Mask" "F.Paste")
			(net "M_K_CPU0_SB_DQS_DN<8>")
		)
		(pad "DC8" smd circle
			(at -27.880056 31.949898 180)
			(size 0.450088 0.450088)
			(layers "F.Cu" "F.Mask" "F.Paste")
			(net "GND")
		)
		(pad "DC9" smd circle
			(at -26.940002 31.949898 180)
			(size 0.450088 0.450088)
			(layers "F.Cu" "F.Mask" "F.Paste")
			(net "M_L_CPU0_SB_DQS_DN<3>")
		)
		(pad "DC10" smd circle
			(at -25.999948 31.949898 180)
			(size 0.450088 0.450088)
			(layers "F.Cu" "F.Mask" "F.Paste")
			(net "M_L_CPU0_SB_DQS_DN<8>")
		)
		(pad "DC11" smd circle
			(at -25.059894 31.949898 180)
			(size 0.450088 0.450088)
			(layers "F.Cu" "F.Mask" "F.Paste")
			(net "GND")
		)
		(pad "DC12" smd circle
			(at -24.120094 31.949898 180)
			(size 0.450088 0.450088)
			(layers "F.Cu" "F.Mask" "F.Paste")
			(net "M_H_CPU0_SB_DQS_DN<3>")
		)
		(pad "DC13" smd circle
			(at -23.18004 31.949898 180)
			(size 0.450088 0.450088)
			(layers "F.Cu" "F.Mask" "F.Paste")
			(net "GND")
		)
		(pad "DC14" smd circle
			(at -22.239986 31.949898 180)
			(size 0.450088 0.450088)
			(layers "F.Cu" "F.Mask" "F.Paste")
			(net "M_H_CPU0_SB_DQS_DN<8>")
		)
		(pad "DC15" smd circle
			(at -21.299932 31.949898 180)
			(size 0.450088 0.450088)
			(layers "F.Cu" "F.Mask" "F.Paste")
			(net "GND")
		)
		(pad "DC16" smd circle
			(at -20.359878 31.949898 180)
			(size 0.450088 0.450088)
			(layers "F.Cu" "F.Mask" "F.Paste")
			(net "M_J_CPU0_SB_DQS_DN<3>")
		)
		(pad "DC17" smd circle
			(at -19.420078 31.949898 180)
			(size 0.450088 0.450088)
			(layers "F.Cu" "F.Mask" "F.Paste")
			(net "M_J_CPU0_SB_DQS_DN<8>")
		)
		(pad "DC18" smd circle
			(at -18.480024 31.949898 180)
			(size 0.450088 0.450088)
			(layers "F.Cu" "F.Mask" "F.Paste")
			(net "GND")
		)
		(pad "DC19" smd circle
			(at -17.53997 31.949898 180)
			(size 0.450088 0.450088)
			(layers "F.Cu" "F.Mask" "F.Paste")
			(net "M_I_CPU0_SB_DQS_DN<3>")
		)
		(pad "DC20" smd circle
			(at -16.599916 31.949898 180)
			(size 0.450088 0.450088)
			(layers "F.Cu" "F.Mask" "F.Paste")
			(net "GND")
		)
		(pad "DC21" smd circle
			(at -15.660116 31.949898 180)
			(size 0.450088 0.450088)
			(layers "F.Cu" "F.Mask" "F.Paste")
			(net "M_I_CPU0_SB_DQS_DN<8>")
		)
		(pad "DC22" smd circle
			(at -14.720062 31.949898 180)
			(size 0.450088 0.450088)
			(layers "F.Cu" "F.Mask" "F.Paste")
			(net "GND")
		)
		(pad "DC23" smd circle
			(at -13.780008 31.949898 180)
			(size 0.450088 0.450088)
			(layers "F.Cu" "F.Mask" "F.Paste")
			(net "P5E_CPU0_P3_RX_DP<13>")
		)
		(pad "DC24" smd circle
			(at -12.839954 31.949898 180)
			(size 0.450088 0.450088)
			(layers "F.Cu" "F.Mask" "F.Paste")
			(net "P5E_CPU0_P3_RX_DN<13>")
		)
		(pad "DC25" smd circle
			(at -11.8999 31.949898 180)
			(size 0.450088 0.450088)
			(layers "F.Cu" "F.Mask" "F.Paste")
			(net "GND")
		)
		(pad "DC26" smd circle
			(at -10.9601 31.949898 180)
			(size 0.450088 0.450088)
			(layers "F.Cu" "F.Mask" "F.Paste")
			(net "P5E_CPU0_P3_RX_DP<10>")
		)
		(pad "DC27" smd circle
			(at -10.020046 31.949898 180)
			(size 0.450088 0.450088)
			(layers "F.Cu" "F.Mask" "F.Paste")
			(net "P5E_CPU0_P3_RX_DN<10>")
		)
		(pad "DC28" smd circle
			(at -9.079992 31.949898 180)
			(size 0.450088 0.450088)
			(layers "F.Cu" "F.Mask" "F.Paste")
			(net "GND")
		)
		(pad "DC29" smd circle
			(at -8.139938 31.949898 180)
			(size 0.450088 0.450088)
			(layers "F.Cu" "F.Mask" "F.Paste")
			(net "P5E_CPU0_P3_RX_DP<7>")
		)
		(pad "DC30" smd circle
			(at -7.199884 31.949898 180)
			(size 0.450088 0.450088)
			(layers "F.Cu" "F.Mask" "F.Paste")
			(net "P5E_CPU0_P3_RX_DN<7>")
		)
		(pad "DC31" smd circle
			(at -6.260084 31.949898 180)
			(size 0.450088 0.450088)
			(layers "F.Cu" "F.Mask" "F.Paste")
			(net "GND")
		)
		(pad "DC32" smd circle
			(at -5.32003 31.949898 180)
			(size 0.450088 0.450088)
			(layers "F.Cu" "F.Mask" "F.Paste")
			(net "P5E_CPU0_P3_RX_DP<4>")
		)
		(pad "DC33" smd circle
			(at -4.379976 31.949898 180)
			(size 0.450088 0.450088)
			(layers "F.Cu" "F.Mask" "F.Paste")
			(net "P5E_CPU0_P3_RX_DN<4>")
		)
		(pad "DC34" smd circle
			(at -3.439922 31.949898 180)
			(size 0.450088 0.450088)
			(layers "F.Cu" "F.Mask" "F.Paste")
			(net "GND")
		)
		(pad "DC35" smd circle
			(at -2.500122 31.949898 180)
			(size 0.450088 0.450088)
			(layers "F.Cu" "F.Mask" "F.Paste")
			(net "PVDDCR_CPU1_P0")
		)
		(pad "DC36" smd circle
			(at -1.560068 31.949898 180)
			(size 0.450088 0.450088)
			(layers "F.Cu" "F.Mask" "F.Paste")
			(net "PVDDCR_CPU1_P0")
		)
		(pad "DC40" smd circle
			(at 1.260094 31.949898 180)
			(size 0.450088 0.450088)
			(layers "F.Cu" "F.Mask" "F.Paste")
			(net "PVDDCR_CPU1_P0")
		)
		(pad "DC41" smd circle
			(at 2.199894 31.949898 180)
			(size 0.450088 0.450088)
			(layers "F.Cu" "F.Mask" "F.Paste")
			(net "PVDDCR_CPU1_P0")
		)
		(pad "DC42" smd circle
			(at 3.139948 31.949898 180)
			(size 0.450088 0.450088)
			(layers "F.Cu" "F.Mask" "F.Paste")
			(net "GND")
		)
		(pad "DC43" smd circle
			(at 4.080002 31.949898 180)
			(size 0.450088 0.450088)
			(layers "F.Cu" "F.Mask" "F.Paste")
			(net "P5E_CPU0_P1_TX_DN<11>")
		)
		(pad "DC44" smd circle
			(at 5.020056 31.949898 180)
			(size 0.450088 0.450088)
			(layers "F.Cu" "F.Mask" "F.Paste")
			(net "P5E_CPU0_P1_TX_DP<11>")
		)
		(pad "DC45" smd circle
			(at 5.96011 31.949898 180)
			(size 0.450088 0.450088)
			(layers "F.Cu" "F.Mask" "F.Paste")
			(net "GND")
		)
		(pad "DC46" smd circle
			(at 6.89991 31.949898 180)
			(size 0.450088 0.450088)
			(layers "F.Cu" "F.Mask" "F.Paste")
			(net "P5E_CPU0_P1_TX_DN<8>")
		)
		(pad "DC47" smd circle
			(at 7.839964 31.949898 180)
			(size 0.450088 0.450088)
			(layers "F.Cu" "F.Mask" "F.Paste")
			(net "P5E_CPU0_P1_TX_DP<8>")
		)
		(pad "DC48" smd circle
			(at 8.780018 31.949898 180)
			(size 0.450088 0.450088)
			(layers "F.Cu" "F.Mask" "F.Paste")
			(net "GND")
		)
		(pad "DC49" smd circle
			(at 9.720072 31.949898 180)
			(size 0.450088 0.450088)
			(layers "F.Cu" "F.Mask" "F.Paste")
			(net "P5E_CPU0_P1_TX_DN<5>")
		)
		(pad "DC50" smd circle
			(at 10.659872 31.949898 180)
			(size 0.450088 0.450088)
			(layers "F.Cu" "F.Mask" "F.Paste")
			(net "P5E_CPU0_P1_TX_DP<5>")
		)
		(pad "DC51" smd circle
			(at 11.599926 31.949898 180)
			(size 0.450088 0.450088)
			(layers "F.Cu" "F.Mask" "F.Paste")
			(net "GND")
		)
		(pad "DC52" smd circle
			(at 12.53998 31.949898 180)
			(size 0.450088 0.450088)
			(layers "F.Cu" "F.Mask" "F.Paste")
			(net "P5E_CPU0_P1_TX_DN<2>")
		)
		(pad "DC53" smd circle
			(at 13.480034 31.949898 180)
			(size 0.450088 0.450088)
			(layers "F.Cu" "F.Mask" "F.Paste")
			(net "P5E_CPU0_P1_TX_DP<2>")
		)
		(pad "DC54" smd circle
			(at 14.420088 31.949898 180)
			(size 0.450088 0.450088)
			(layers "F.Cu" "F.Mask" "F.Paste")
			(net "GND")
		)
		(pad "DC55" smd circle
			(at 15.359888 31.949898 180)
			(size 0.450088 0.450088)
			(layers "F.Cu" "F.Mask" "F.Paste")
			(net "M_C_CPU0_SB_DQS_DN<8>")
		)
		(pad "DC56" smd circle
			(at 16.299942 31.949898 180)
			(size 0.450088 0.450088)
			(layers "F.Cu" "F.Mask" "F.Paste")
			(net "GND")
		)
		(pad "DC57" smd circle
			(at 17.239996 31.949898 180)
			(size 0.450088 0.450088)
			(layers "F.Cu" "F.Mask" "F.Paste")
			(net "M_C_CPU0_SB_DQS_DN<3>")
		)
		(pad "DC58" smd circle
			(at 18.18005 31.949898 180)
			(size 0.450088 0.450088)
			(layers "F.Cu" "F.Mask" "F.Paste")
			(net "GND")
		)
		(pad "DC59" smd circle
			(at 19.120104 31.949898 180)
			(size 0.450088 0.450088)
			(layers "F.Cu" "F.Mask" "F.Paste")
			(net "M_D_CPU0_SB_DQS_DN<8>")
		)
		(pad "DC60" smd circle
			(at 20.059904 31.949898 180)
			(size 0.450088 0.450088)
			(layers "F.Cu" "F.Mask" "F.Paste")
			(net "M_D_CPU0_SB_DQS_DN<3>")
		)
		(pad "DC61" smd circle
			(at 20.999958 31.949898 180)
			(size 0.450088 0.450088)
			(layers "F.Cu" "F.Mask" "F.Paste")
			(net "GND")
		)
		(pad "DC62" smd circle
			(at 21.940012 31.949898 180)
			(size 0.450088 0.450088)
			(layers "F.Cu" "F.Mask" "F.Paste")
			(net "M_B_CPU0_SB_DQS_DN<8>")
		)
		(pad "DC63" smd circle
			(at 22.880066 31.949898 180)
			(size 0.450088 0.450088)
			(layers "F.Cu" "F.Mask" "F.Paste")
			(net "GND")
		)
		(pad "DC64" smd circle
			(at 23.82012 31.949898 180)
			(size 0.450088 0.450088)
			(layers "F.Cu" "F.Mask" "F.Paste")
			(net "M_B_CPU0_SB_DQS_DN<3>")
		)
		(pad "DC65" smd circle
			(at 24.75992 31.949898 180)
			(size 0.450088 0.450088)
			(layers "F.Cu" "F.Mask" "F.Paste")
			(net "GND")
		)
		(pad "DC66" smd circle
			(at 25.699974 31.949898 180)
			(size 0.450088 0.450088)
			(layers "F.Cu" "F.Mask" "F.Paste")
			(net "M_F_CPU0_SB_DQS_DN<8>")
		)
		(pad "DC67" smd circle
			(at 26.640028 31.949898 180)
			(size 0.450088 0.450088)
			(layers "F.Cu" "F.Mask" "F.Paste")
			(net "M_F_CPU0_SB_DQS_DN<3>")
		)
		(pad "DC68" smd circle
			(at 27.580082 31.949898 180)
			(size 0.450088 0.450088)
			(layers "F.Cu" "F.Mask" "F.Paste")
			(net "GND")
		)
		(pad "DC69" smd circle
			(at 28.519882 31.949898 180)
			(size 0.450088 0.450088)
			(layers "F.Cu" "F.Mask" "F.Paste")
			(net "M_E_CPU0_SB_DQS_DN<8>")
		)
		(pad "DC70" smd circle
			(at 29.459936 31.949898 180)
			(size 0.450088 0.450088)
			(layers "F.Cu" "F.Mask" "F.Paste")
			(net "GND")
		)
		(pad "DC71" smd circle
			(at 30.39999 31.949898 180)
			(size 0.450088 0.450088)
			(layers "F.Cu" "F.Mask" "F.Paste")
			(net "M_E_CPU0_SB_DQS_DN<3>")
		)
		(pad "DC72" smd circle
			(at 31.340044 31.949898 180)
			(size 0.450088 0.450088)
			(layers "F.Cu" "F.Mask" "F.Paste")
			(net "GND")
		)
		(pad "DC73" smd circle
			(at 32.280098 31.949898 180)
			(size 0.450088 0.450088)
			(layers "F.Cu" "F.Mask" "F.Paste")
			(net "M_A_CPU0_SB_DQS_DN<8>")
		)
		(pad "DC74" smd circle
			(at 33.219898 31.949898 180)
			(size 0.450088 0.450088)
			(layers "F.Cu" "F.Mask" "F.Paste")
			(net "M_A_CPU0_SB_DQS_DN<3>")
		)
		(pad "DC75" smd circle
			(at 34.159952 31.949898 180)
			(size 0.450088 0.450088)
			(layers "F.Cu" "F.Mask" "F.Paste")
			(net "GND")
		)
		(pad "DD2" smd circle
			(at -33.990026 32.759904 180)
			(size 0.450088 0.450088)
			(layers "F.Cu" "F.Mask" "F.Paste")
			(net "M_G_CPU0_SB_DQ<28>")
		)
		(pad "DD3" smd circle
			(at -33.049972 32.759904 180)
			(size 0.450088 0.450088)
			(layers "F.Cu" "F.Mask" "F.Paste")
			(net "GND")
		)
		(pad "DD4" smd circle
			(at -32.109918 32.759904 180)
			(size 0.450088 0.450088)
			(layers "F.Cu" "F.Mask" "F.Paste")
			(net "M_G_CPU0_SB_DQS_DP<8>")
		)
		(pad "DD5" smd circle
			(at -31.170118 32.759904 180)
			(size 0.450088 0.450088)
			(layers "F.Cu" "F.Mask" "F.Paste")
			(net "GND")
		)
		(pad "DD6" smd circle
			(at -30.230064 32.759904 180)
			(size 0.450088 0.450088)
			(layers "F.Cu" "F.Mask" "F.Paste")
			(net "M_K_CPU0_SB_DQ<28>")
		)
		(pad "DD7" smd circle
			(at -29.29001 32.759904 180)
			(size 0.450088 0.450088)
			(layers "F.Cu" "F.Mask" "F.Paste")
			(net "M_K_CPU0_SB_DQS_DP<8>")
		)
		(pad "DD8" smd circle
			(at -28.349956 32.759904 180)
			(size 0.450088 0.450088)
			(layers "F.Cu" "F.Mask" "F.Paste")
			(net "GND")
		)
		(pad "DD9" smd circle
			(at -27.409902 32.759904 180)
			(size 0.450088 0.450088)
			(layers "F.Cu" "F.Mask" "F.Paste")
			(net "M_L_CPU0_SB_DQ<28>")
		)
		(pad "DD10" smd circle
			(at -26.470102 32.759904 180)
			(size 0.450088 0.450088)
			(layers "F.Cu" "F.Mask" "F.Paste")
			(net "GND")
		)
		(pad "DD11" smd circle
			(at -25.530048 32.759904 180)
			(size 0.450088 0.450088)
			(layers "F.Cu" "F.Mask" "F.Paste")
			(net "M_L_CPU0_SB_DQS_DP<8>")
		)
		(pad "DD12" smd circle
			(at -24.589994 32.759904 180)
			(size 0.450088 0.450088)
			(layers "F.Cu" "F.Mask" "F.Paste")
			(net "GND")
		)
		(pad "DD13" smd circle
			(at -23.64994 32.759904 180)
			(size 0.450088 0.450088)
			(layers "F.Cu" "F.Mask" "F.Paste")
			(net "M_H_CPU0_SB_DQ<28>")
		)
		(pad "DD14" smd circle
			(at -22.709886 32.759904 180)
			(size 0.450088 0.450088)
			(layers "F.Cu" "F.Mask" "F.Paste")
			(net "M_H_CPU0_SB_DQS_DP<8>")
		)
		(pad "DD15" smd circle
			(at -21.770086 32.759904 180)
			(size 0.450088 0.450088)
			(layers "F.Cu" "F.Mask" "F.Paste")
			(net "GND")
		)
		(pad "DD16" smd circle
			(at -20.830032 32.759904 180)
			(size 0.450088 0.450088)
			(layers "F.Cu" "F.Mask" "F.Paste")
			(net "M_J_CPU0_SB_DQ<28>")
		)
		(pad "DD17" smd circle
			(at -19.889978 32.759904 180)
			(size 0.450088 0.450088)
			(layers "F.Cu" "F.Mask" "F.Paste")
			(net "GND")
		)
		(pad "DD18" smd circle
			(at -18.949924 32.759904 180)
			(size 0.450088 0.450088)
			(layers "F.Cu" "F.Mask" "F.Paste")
			(net "M_J_CPU0_SB_DQS_DP<8>")
		)
		(pad "DD19" smd circle
			(at -18.010124 32.759904 180)
			(size 0.450088 0.450088)
			(layers "F.Cu" "F.Mask" "F.Paste")
			(net "GND")
		)
		(pad "DD20" smd circle
			(at -17.07007 32.759904 180)
			(size 0.450088 0.450088)
			(layers "F.Cu" "F.Mask" "F.Paste")
			(net "M_I_CPU0_SB_DQ<28>")
		)
		(pad "DD21" smd circle
			(at -16.130016 32.759904 180)
			(size 0.450088 0.450088)
			(layers "F.Cu" "F.Mask" "F.Paste")
			(net "M_I_CPU0_SB_DQS_DP<8>")
		)
		(pad "DD22" smd circle
			(at -15.189962 32.759904 180)
			(size 0.450088 0.450088)
			(layers "F.Cu" "F.Mask" "F.Paste")
			(net "PVDDCR_CPU1_P0")
		)
		(pad "DD23" smd circle
			(at -14.249908 32.759904 180)
			(size 0.450088 0.450088)
			(layers "F.Cu" "F.Mask" "F.Paste")
			(net "GND")
		)
		(pad "DD24" smd circle
			(at -13.310108 32.759904 180)
			(size 0.450088 0.450088)
			(layers "F.Cu" "F.Mask" "F.Paste")
			(net "GND")
		)
		(pad "DD25" smd circle
			(at -12.370054 32.759904 180)
			(size 0.450088 0.450088)
			(layers "F.Cu" "F.Mask" "F.Paste")
			(net "PVDDCR_CPU1_P0")
		)
		(pad "DD26" smd circle
			(at -11.43 32.759904 180)
			(size 0.450088 0.450088)
			(layers "F.Cu" "F.Mask" "F.Paste")
			(net "GND")
		)
		(pad "DD27" smd circle
			(at -10.489946 32.759904 180)
			(size 0.450088 0.450088)
			(layers "F.Cu" "F.Mask" "F.Paste")
			(net "GND")
		)
		(pad "DD28" smd circle
			(at -9.549892 32.759904 180)
			(size 0.450088 0.450088)
			(layers "F.Cu" "F.Mask" "F.Paste")
			(net "PVDDCR_CPU1_P0")
		)
		(pad "DD29" smd circle
			(at -8.610092 32.759904 180)
			(size 0.450088 0.450088)
			(layers "F.Cu" "F.Mask" "F.Paste")
			(net "GND")
		)
		(pad "DD30" smd circle
			(at -7.670038 32.759904 180)
			(size 0.450088 0.450088)
			(layers "F.Cu" "F.Mask" "F.Paste")
			(net "GND")
		)
		(pad "DD31" smd circle
			(at -6.729984 32.759904 180)
			(size 0.450088 0.450088)
			(layers "F.Cu" "F.Mask" "F.Paste")
			(net "PVDDCR_CPU1_P0")
		)
		(pad "DD32" smd circle
			(at -5.78993 32.759904 180)
			(size 0.450088 0.450088)
			(layers "F.Cu" "F.Mask" "F.Paste")
			(net "GND")
		)
		(pad "DD33" smd circle
			(at -4.849876 32.759904 180)
			(size 0.450088 0.450088)
			(layers "F.Cu" "F.Mask" "F.Paste")
			(net "GND")
		)
		(pad "DD34" smd circle
			(at -3.910076 32.759904 180)
			(size 0.450088 0.450088)
			(layers "F.Cu" "F.Mask" "F.Paste")
			(net "PVDDCR_CPU1_P0")
		)
		(pad "DD35" smd circle
			(at -2.970022 32.759904 180)
			(size 0.450088 0.450088)
			(layers "F.Cu" "F.Mask" "F.Paste")
			(net "GND")
		)
		(pad "DD36" smd circle
			(at -2.029968 32.759904 180)
			(size 0.450088 0.450088)
			(layers "F.Cu" "F.Mask" "F.Paste")
			(net "GND")
		)
		(pad "DD37" smd circle
			(at -1.089914 32.759904 180)
			(size 0.450088 0.450088)
			(layers "F.Cu" "F.Mask" "F.Paste")
			(net "GND")
		)
		(pad "DD39" smd circle
			(at 0.78994 32.759904 180)
			(size 0.450088 0.450088)
			(layers "F.Cu" "F.Mask" "F.Paste")
			(net "GND")
		)
		(pad "DD40" smd circle
			(at 1.729994 32.759904 180)
			(size 0.450088 0.450088)
			(layers "F.Cu" "F.Mask" "F.Paste")
			(net "GND")
		)
		(pad "DD41" smd circle
			(at 2.670048 32.759904 180)
			(size 0.450088 0.450088)
			(layers "F.Cu" "F.Mask" "F.Paste")
			(net "GND")
		)
		(pad "DD42" smd circle
			(at 3.610102 32.759904 180)
			(size 0.450088 0.450088)
			(layers "F.Cu" "F.Mask" "F.Paste")
			(net "PVDDCR_CPU1_P0")
		)
		(pad "DD43" smd circle
			(at 4.549902 32.759904 180)
			(size 0.450088 0.450088)
			(layers "F.Cu" "F.Mask" "F.Paste")
			(net "GND")
		)
		(pad "DD44" smd circle
			(at 5.489956 32.759904 180)
			(size 0.450088 0.450088)
			(layers "F.Cu" "F.Mask" "F.Paste")
			(net "GND")
		)
		(pad "DD45" smd circle
			(at 6.43001 32.759904 180)
			(size 0.450088 0.450088)
			(layers "F.Cu" "F.Mask" "F.Paste")
			(net "PVDDCR_CPU1_P0")
		)
		(pad "DD46" smd circle
			(at 7.370064 32.759904 180)
			(size 0.450088 0.450088)
			(layers "F.Cu" "F.Mask" "F.Paste")
			(net "GND")
		)
		(pad "DD47" smd circle
			(at 8.310118 32.759904 180)
			(size 0.450088 0.450088)
			(layers "F.Cu" "F.Mask" "F.Paste")
			(net "GND")
		)
		(pad "DD48" smd circle
			(at 9.249918 32.759904 180)
			(size 0.450088 0.450088)
			(layers "F.Cu" "F.Mask" "F.Paste")
			(net "PVDDCR_CPU1_P0")
		)
		(pad "DD49" smd circle
			(at 10.189972 32.759904 180)
			(size 0.450088 0.450088)
			(layers "F.Cu" "F.Mask" "F.Paste")
			(net "GND")
		)
		(pad "DD50" smd circle
			(at 11.130026 32.759904 180)
			(size 0.450088 0.450088)
			(layers "F.Cu" "F.Mask" "F.Paste")
			(net "GND")
		)
		(pad "DD51" smd circle
			(at 12.07008 32.759904 180)
			(size 0.450088 0.450088)
			(layers "F.Cu" "F.Mask" "F.Paste")
			(net "PVDDCR_CPU1_P0")
		)
		(pad "DD52" smd circle
			(at 13.00988 32.759904 180)
			(size 0.450088 0.450088)
			(layers "F.Cu" "F.Mask" "F.Paste")
			(net "GND")
		)
		(pad "DD53" smd circle
			(at 13.949934 32.759904 180)
			(size 0.450088 0.450088)
			(layers "F.Cu" "F.Mask" "F.Paste")
			(net "GND")
		)
		(pad "DD54" smd circle
			(at 14.889988 32.759904 180)
			(size 0.450088 0.450088)
			(layers "F.Cu" "F.Mask" "F.Paste")
			(net "PVDDCR_CPU1_P0")
		)
		(pad "DD55" smd circle
			(at 15.830042 32.759904 180)
			(size 0.450088 0.450088)
			(layers "F.Cu" "F.Mask" "F.Paste")
			(net "M_C_CPU0_SB_DQS_DP<8>")
		)
		(pad "DD56" smd circle
			(at 16.770096 32.759904 180)
			(size 0.450088 0.450088)
			(layers "F.Cu" "F.Mask" "F.Paste")
			(net "M_C_CPU0_SB_DQ<28>")
		)
		(pad "DD57" smd circle
			(at 17.709896 32.759904 180)
			(size 0.450088 0.450088)
			(layers "F.Cu" "F.Mask" "F.Paste")
			(net "GND")
		)
		(pad "DD58" smd circle
			(at 18.64995 32.759904 180)
			(size 0.450088 0.450088)
			(layers "F.Cu" "F.Mask" "F.Paste")
			(net "M_D_CPU0_SB_DQS_DP<8>")
		)
		(pad "DD59" smd circle
			(at 19.590004 32.759904 180)
			(size 0.450088 0.450088)
			(layers "F.Cu" "F.Mask" "F.Paste")
			(net "GND")
		)
		(pad "DD60" smd circle
			(at 20.530058 32.759904 180)
			(size 0.450088 0.450088)
			(layers "F.Cu" "F.Mask" "F.Paste")
			(net "M_D_CPU0_SB_DQ<28>")
		)
		(pad "DD61" smd circle
			(at 21.470112 32.759904 180)
			(size 0.450088 0.450088)
			(layers "F.Cu" "F.Mask" "F.Paste")
			(net "GND")
		)
		(pad "DD62" smd circle
			(at 22.409912 32.759904 180)
			(size 0.450088 0.450088)
			(layers "F.Cu" "F.Mask" "F.Paste")
			(net "M_B_CPU0_SB_DQS_DP<8>")
		)
		(pad "DD63" smd circle
			(at 23.349966 32.759904 180)
			(size 0.450088 0.450088)
			(layers "F.Cu" "F.Mask" "F.Paste")
			(net "M_B_CPU0_SB_DQ<28>")
		)
		(pad "DD64" smd circle
			(at 24.29002 32.759904 180)
			(size 0.450088 0.450088)
			(layers "F.Cu" "F.Mask" "F.Paste")
			(net "GND")
		)
		(pad "DD65" smd circle
			(at 25.230074 32.759904 180)
			(size 0.450088 0.450088)
			(layers "F.Cu" "F.Mask" "F.Paste")
			(net "M_F_CPU0_SB_DQS_DP<8>")
		)
		(pad "DD66" smd circle
			(at 26.170128 32.759904 180)
			(size 0.450088 0.450088)
			(layers "F.Cu" "F.Mask" "F.Paste")
			(net "GND")
		)
		(pad "DD67" smd circle
			(at 27.109928 32.759904 180)
			(size 0.450088 0.450088)
			(layers "F.Cu" "F.Mask" "F.Paste")
			(net "M_F_CPU0_SB_DQ<28>")
		)
		(pad "DD68" smd circle
			(at 28.049982 32.759904 180)
			(size 0.450088 0.450088)
			(layers "F.Cu" "F.Mask" "F.Paste")
			(net "GND")
		)
		(pad "DD69" smd circle
			(at 28.990036 32.759904 180)
			(size 0.450088 0.450088)
			(layers "F.Cu" "F.Mask" "F.Paste")
			(net "M_E_CPU0_SB_DQS_DP<8>")
		)
		(pad "DD70" smd circle
			(at 29.93009 32.759904 180)
			(size 0.450088 0.450088)
			(layers "F.Cu" "F.Mask" "F.Paste")
			(net "M_E_CPU0_SB_DQ<28>")
		)
		(pad "DD71" smd circle
			(at 30.86989 32.759904 180)
			(size 0.450088 0.450088)
			(layers "F.Cu" "F.Mask" "F.Paste")
			(net "GND")
		)
		(pad "DD72" smd circle
			(at 31.809944 32.759904 180)
			(size 0.450088 0.450088)
			(layers "F.Cu" "F.Mask" "F.Paste")
			(net "M_A_CPU0_SB_DQS_DP<8>")
		)
		(pad "DD73" smd circle
			(at 32.749998 32.759904 180)
			(size 0.450088 0.450088)
			(layers "F.Cu" "F.Mask" "F.Paste")
			(net "GND")
		)
		(pad "DD74" smd circle
			(at 33.690052 32.759904 180)
			(size 0.450088 0.450088)
			(layers "F.Cu" "F.Mask" "F.Paste")
			(net "M_A_CPU0_SB_DQ<28>")
		)
		(pad "DE1" smd circle
			(at -34.459926 33.56991 180)
			(size 0.450088 0.450088)
			(layers "F.Cu" "F.Mask" "F.Paste")
			(net "GND")
		)
		(pad "DE2" smd circle
			(at -33.519872 33.56991 180)
			(size 0.450088 0.450088)
			(layers "F.Cu" "F.Mask" "F.Paste")
			(net "M_G_CPU0_SB_DQ<30>")
		)
		(pad "DE3" smd circle
			(at -32.580072 33.56991 180)
			(size 0.450088 0.450088)
			(layers "F.Cu" "F.Mask" "F.Paste")
			(net "M_G_CPU0_SB_DQ<29>")
		)
		(pad "DE4" smd circle
			(at -31.640018 33.56991 180)
			(size 0.450088 0.450088)
			(layers "F.Cu" "F.Mask" "F.Paste")
			(net "PVDD11_S3_P0")
		)
		(pad "DE5" smd circle
			(at -30.699964 33.56991 180)
			(size 0.450088 0.450088)
			(layers "F.Cu" "F.Mask" "F.Paste")
			(net "M_K_CPU0_SB_DQ<30>")
		)
		(pad "DE6" smd circle
			(at -29.75991 33.56991 180)
			(size 0.450088 0.450088)
			(layers "F.Cu" "F.Mask" "F.Paste")
			(net "GND")
		)
		(pad "DE7" smd circle
			(at -28.82011 33.56991 180)
			(size 0.450088 0.450088)
			(layers "F.Cu" "F.Mask" "F.Paste")
			(net "M_K_CPU0_SB_DQ<29>")
		)
		(pad "DE8" smd circle
			(at -27.880056 33.56991 180)
			(size 0.450088 0.450088)
			(layers "F.Cu" "F.Mask" "F.Paste")
			(net "GND")
		)
		(pad "DE9" smd circle
			(at -26.940002 33.56991 180)
			(size 0.450088 0.450088)
			(layers "F.Cu" "F.Mask" "F.Paste")
			(net "M_L_CPU0_SB_DQ<30>")
		)
		(pad "DE10" smd circle
			(at -25.999948 33.56991 180)
			(size 0.450088 0.450088)
			(layers "F.Cu" "F.Mask" "F.Paste")
			(net "M_L_CPU0_SB_DQ<29>")
		)
		(pad "DE11" smd circle
			(at -25.059894 33.56991 180)
			(size 0.450088 0.450088)
			(layers "F.Cu" "F.Mask" "F.Paste")
			(net "PVDD11_S3_P0")
		)
		(pad "DE12" smd circle
			(at -24.120094 33.56991 180)
			(size 0.450088 0.450088)
			(layers "F.Cu" "F.Mask" "F.Paste")
			(net "M_H_CPU0_SB_DQ<30>")
		)
		(pad "DE13" smd circle
			(at -23.18004 33.56991 180)
			(size 0.450088 0.450088)
			(layers "F.Cu" "F.Mask" "F.Paste")
			(net "GND")
		)
		(pad "DE14" smd circle
			(at -22.239986 33.56991 180)
			(size 0.450088 0.450088)
			(layers "F.Cu" "F.Mask" "F.Paste")
			(net "M_H_CPU0_SB_DQ<29>")
		)
		(pad "DE15" smd circle
			(at -21.299932 33.56991 180)
			(size 0.450088 0.450088)
			(layers "F.Cu" "F.Mask" "F.Paste")
			(net "GND")
		)
		(pad "DE16" smd circle
			(at -20.359878 33.56991 180)
			(size 0.450088 0.450088)
			(layers "F.Cu" "F.Mask" "F.Paste")
			(net "M_J_CPU0_SB_DQ<30>")
		)
		(pad "DE17" smd circle
			(at -19.420078 33.56991 180)
			(size 0.450088 0.450088)
			(layers "F.Cu" "F.Mask" "F.Paste")
			(net "M_J_CPU0_SB_DQ<29>")
		)
		(pad "DE18" smd circle
			(at -18.480024 33.56991 180)
			(size 0.450088 0.450088)
			(layers "F.Cu" "F.Mask" "F.Paste")
			(net "PVDD11_S3_P0")
		)
		(pad "DE19" smd circle
			(at -17.53997 33.56991 180)
			(size 0.450088 0.450088)
			(layers "F.Cu" "F.Mask" "F.Paste")
			(net "M_I_CPU0_SB_DQ<30>")
		)
		(pad "DE20" smd circle
			(at -16.599916 33.56991 180)
			(size 0.450088 0.450088)
			(layers "F.Cu" "F.Mask" "F.Paste")
			(net "GND")
		)
		(pad "DE21" smd circle
			(at -15.660116 33.56991 180)
			(size 0.450088 0.450088)
			(layers "F.Cu" "F.Mask" "F.Paste")
			(net "M_I_CPU0_SB_DQ<29>")
		)
		(pad "DE22" smd circle
			(at -14.720062 33.56991 180)
			(size 0.450088 0.450088)
			(layers "F.Cu" "F.Mask" "F.Paste")
			(net "PVDDCR_CPU1_P0")
		)
		(pad "DE23" smd circle
			(at -13.780008 33.56991 180)
			(size 0.450088 0.450088)
			(layers "F.Cu" "F.Mask" "F.Paste")
			(net "GND")
		)
		(pad "DE24" smd circle
			(at -12.839954 33.56991 180)
			(size 0.450088 0.450088)
			(layers "F.Cu" "F.Mask" "F.Paste")
			(net "ESPI_CPU0_R_D1")
		)
		(pad "DE25" smd circle
			(at -11.8999 33.56991 180)
			(size 0.450088 0.450088)
			(layers "F.Cu" "F.Mask" "F.Paste")
			(net "PVDDCR_CPU1_P0")
		)
		(pad "DE26" smd circle
			(at -10.9601 33.56991 180)
			(size 0.450088 0.450088)
			(layers "F.Cu" "F.Mask" "F.Paste")
			(net "GND")
		)
		(pad "DE27" smd circle
			(at -10.020046 33.56991 180)
			(size 0.450088 0.450088)
			(layers "F.Cu" "F.Mask" "F.Paste")
			(net "RST_ESPI_CPU0_R_RSTOUT_N")
		)
		(pad "DE28" smd circle
			(at -9.079992 33.56991 180)
			(size 0.450088 0.450088)
			(layers "F.Cu" "F.Mask" "F.Paste")
			(net "PVDDCR_CPU1_P0")
		)
		(pad "DE29" smd circle
			(at -8.139938 33.56991 180)
			(size 0.450088 0.450088)
			(layers "F.Cu" "F.Mask" "F.Paste")
			(net "GND")
		)
		(pad "DE30" smd circle
			(at -7.199884 33.56991 180)
			(size 0.450088 0.450088)
			(layers "F.Cu" "F.Mask" "F.Paste")
			(net "BIOS_DEBUG_MODE")
		)
		(pad "DE31" smd circle
			(at -6.260084 33.56991 180)
			(size 0.450088 0.450088)
			(layers "F.Cu" "F.Mask" "F.Paste")
			(net "PVDDCR_CPU1_P0")
		)
		(pad "DE32" smd circle
			(at -5.32003 33.56991 180)
			(size 0.450088 0.450088)
			(layers "F.Cu" "F.Mask" "F.Paste")
			(net "FM_BOARD_SKU_ID1")
		)
		(pad "DE33" smd circle
			(at -4.379976 33.56991 180)
			(size 0.450088 0.450088)
			(layers "F.Cu" "F.Mask" "F.Paste")
			(net "GND")
		)
		(pad "DE34" smd circle
			(at -3.439922 33.56991 180)
			(size 0.450088 0.450088)
			(layers "F.Cu" "F.Mask" "F.Paste")
			(net "PVDDCR_CPU1_P0")
		)
		(pad "DE35" smd circle
			(at -2.500122 33.56991 180)
			(size 0.450088 0.450088)
			(layers "F.Cu" "F.Mask" "F.Paste")
			(net "PVDDCR_CPU1_P0")
		)
		(pad "DE36" smd circle
			(at -1.560068 33.56991 180)
			(size 0.450088 0.450088)
			(layers "F.Cu" "F.Mask" "F.Paste")
			(net "CPU0_SPD_HOST_CTRL_N")
		)
		(pad "DE40" smd circle
			(at 1.260094 33.56991 180)
			(size 0.450088 0.450088)
			(layers "F.Cu" "F.Mask" "F.Paste")
			(net "IRQ_BMC_SMI_N")
		)
		(pad "DE41" smd circle
			(at 2.199894 33.56991 180)
			(size 0.450088 0.450088)
			(layers "F.Cu" "F.Mask" "F.Paste")
			(net "PVDDCR_CPU1_P0")
		)
		(pad "DE42" smd circle
			(at 3.139948 33.56991 180)
			(size 0.450088 0.450088)
			(layers "F.Cu" "F.Mask" "F.Paste")
			(net "PVDDCR_CPU1_P0")
		)
		(pad "DE43" smd circle
			(at 4.080002 33.56991 180)
			(size 0.450088 0.450088)
			(layers "F.Cu" "F.Mask" "F.Paste")
			(net "P3E_CPU0_P4_TX_DN<3>")
		)
		(pad "DE44" smd circle
			(at 5.020056 33.56991 180)
			(size 0.450088 0.450088)
			(layers "F.Cu" "F.Mask" "F.Paste")
			(net "P3E_CPU0_P4_TX_DP<3>")
		)
		(pad "DE45" smd circle
			(at 5.96011 33.56991 180)
			(size 0.450088 0.450088)
			(layers "F.Cu" "F.Mask" "F.Paste")
			(net "PVDDCR_CPU1_P0")
		)
		(pad "DE46" smd circle
			(at 6.89991 33.56991 180)
			(size 0.450088 0.450088)
			(layers "F.Cu" "F.Mask" "F.Paste")
			(net "P3E_CPU0_P4_TX_DN<2>")
		)
		(pad "DE47" smd circle
			(at 7.839964 33.56991 180)
			(size 0.450088 0.450088)
			(layers "F.Cu" "F.Mask" "F.Paste")
			(net "P3E_CPU0_P4_TX_DP<2>")
		)
		(pad "DE48" smd circle
			(at 8.780018 33.56991 180)
			(size 0.450088 0.450088)
			(layers "F.Cu" "F.Mask" "F.Paste")
			(net "PVDDCR_CPU1_P0")
		)
		(pad "DE49" smd circle
			(at 9.720072 33.56991 180)
			(size 0.450088 0.450088)
			(layers "F.Cu" "F.Mask" "F.Paste")
			(net "P3E_CPU0_P4_TX_DN<1>")
		)
		(pad "DE50" smd circle
			(at 10.659872 33.56991 180)
			(size 0.450088 0.450088)
			(layers "F.Cu" "F.Mask" "F.Paste")
			(net "P3E_CPU0_P4_TX_DP<1>")
		)
		(pad "DE51" smd circle
			(at 11.599926 33.56991 180)
			(size 0.450088 0.450088)
			(layers "F.Cu" "F.Mask" "F.Paste")
			(net "PVDDCR_CPU1_P0")
		)
		(pad "DE52" smd circle
			(at 12.53998 33.56991 180)
			(size 0.450088 0.450088)
			(layers "F.Cu" "F.Mask" "F.Paste")
			(net "P3E_CPU0_P4_TX_DN<0>")
		)
		(pad "DE53" smd circle
			(at 13.480034 33.56991 180)
			(size 0.450088 0.450088)
			(layers "F.Cu" "F.Mask" "F.Paste")
			(net "P3E_CPU0_P4_TX_DP<0>")
		)
		(pad "DE54" smd circle
			(at 14.420088 33.56991 180)
			(size 0.450088 0.450088)
			(layers "F.Cu" "F.Mask" "F.Paste")
			(net "PVDDCR_CPU1_P0")
		)
		(pad "DE55" smd circle
			(at 15.359888 33.56991 180)
			(size 0.450088 0.450088)
			(layers "F.Cu" "F.Mask" "F.Paste")
			(net "M_C_CPU0_SB_DQ<29>")
		)
		(pad "DE56" smd circle
			(at 16.299942 33.56991 180)
			(size 0.450088 0.450088)
			(layers "F.Cu" "F.Mask" "F.Paste")
			(net "GND")
		)
		(pad "DE57" smd circle
			(at 17.239996 33.56991 180)
			(size 0.450088 0.450088)
			(layers "F.Cu" "F.Mask" "F.Paste")
			(net "M_C_CPU0_SB_DQ<30>")
		)
		(pad "DE58" smd circle
			(at 18.18005 33.56991 180)
			(size 0.450088 0.450088)
			(layers "F.Cu" "F.Mask" "F.Paste")
			(net "PVDDIO_P0")
		)
		(pad "DE59" smd circle
			(at 19.120104 33.56991 180)
			(size 0.450088 0.450088)
			(layers "F.Cu" "F.Mask" "F.Paste")
			(net "M_D_CPU0_SB_DQ<29>")
		)
		(pad "DE60" smd circle
			(at 20.059904 33.56991 180)
			(size 0.450088 0.450088)
			(layers "F.Cu" "F.Mask" "F.Paste")
			(net "M_D_CPU0_SB_DQ<30>")
		)
		(pad "DE61" smd circle
			(at 20.999958 33.56991 180)
			(size 0.450088 0.450088)
			(layers "F.Cu" "F.Mask" "F.Paste")
			(net "GND")
		)
		(pad "DE62" smd circle
			(at 21.940012 33.56991 180)
			(size 0.450088 0.450088)
			(layers "F.Cu" "F.Mask" "F.Paste")
			(net "M_B_CPU0_SB_DQ<29>")
		)
		(pad "DE63" smd circle
			(at 22.880066 33.56991 180)
			(size 0.450088 0.450088)
			(layers "F.Cu" "F.Mask" "F.Paste")
			(net "GND")
		)
		(pad "DE64" smd circle
			(at 23.82012 33.56991 180)
			(size 0.450088 0.450088)
			(layers "F.Cu" "F.Mask" "F.Paste")
			(net "M_B_CPU0_SB_DQ<30>")
		)
		(pad "DE65" smd circle
			(at 24.75992 33.56991 180)
			(size 0.450088 0.450088)
			(layers "F.Cu" "F.Mask" "F.Paste")
			(net "PVDDIO_P0")
		)
		(pad "DE66" smd circle
			(at 25.699974 33.56991 180)
			(size 0.450088 0.450088)
			(layers "F.Cu" "F.Mask" "F.Paste")
			(net "M_F_CPU0_SB_DQ<29>")
		)
		(pad "DE67" smd circle
			(at 26.640028 33.56991 180)
			(size 0.450088 0.450088)
			(layers "F.Cu" "F.Mask" "F.Paste")
			(net "M_F_CPU0_SB_DQ<30>")
		)
		(pad "DE68" smd circle
			(at 27.580082 33.56991 180)
			(size 0.450088 0.450088)
			(layers "F.Cu" "F.Mask" "F.Paste")
			(net "GND")
		)
		(pad "DE69" smd circle
			(at 28.519882 33.56991 180)
			(size 0.450088 0.450088)
			(layers "F.Cu" "F.Mask" "F.Paste")
			(net "M_E_CPU0_SB_DQ<29>")
		)
		(pad "DE70" smd circle
			(at 29.459936 33.56991 180)
			(size 0.450088 0.450088)
			(layers "F.Cu" "F.Mask" "F.Paste")
			(net "GND")
		)
		(pad "DE71" smd circle
			(at 30.39999 33.56991 180)
			(size 0.450088 0.450088)
			(layers "F.Cu" "F.Mask" "F.Paste")
			(net "M_E_CPU0_SB_DQ<30>")
		)
		(pad "DE72" smd circle
			(at 31.340044 33.56991 180)
			(size 0.450088 0.450088)
			(layers "F.Cu" "F.Mask" "F.Paste")
			(net "PVDDIO_P0")
		)
		(pad "DE73" smd circle
			(at 32.280098 33.56991 180)
			(size 0.450088 0.450088)
			(layers "F.Cu" "F.Mask" "F.Paste")
			(net "M_A_CPU0_SB_DQ<29>")
		)
		(pad "DE74" smd circle
			(at 33.219898 33.56991 180)
			(size 0.450088 0.450088)
			(layers "F.Cu" "F.Mask" "F.Paste")
			(net "M_A_CPU0_SB_DQ<30>")
		)
		(pad "DE75" smd circle
			(at 34.159952 33.56991 180)
			(size 0.450088 0.450088)
			(layers "F.Cu" "F.Mask" "F.Paste")
			(net "GND")
		)
		(pad "DF2" smd circle
			(at -33.990026 34.379916 180)
			(size 0.450088 0.450088)
			(layers "F.Cu" "F.Mask" "F.Paste")
			(net "M_G_CPU0_SB_DQ<31>")
		)
		(pad "DF3" smd circle
			(at -33.049972 34.379916 180)
			(size 0.450088 0.450088)
			(layers "F.Cu" "F.Mask" "F.Paste")
			(net "GND")
		)
		(pad "DF4" smd circle
			(at -32.109918 34.379916 180)
			(size 0.450088 0.450088)
			(layers "F.Cu" "F.Mask" "F.Paste")
			(net "GND")
		)
		(pad "DF5" smd circle
			(at -31.170118 34.379916 180)
			(size 0.450088 0.450088)
			(layers "F.Cu" "F.Mask" "F.Paste")
			(net "GND")
		)
		(pad "DF6" smd circle
			(at -30.230064 34.379916 180)
			(size 0.450088 0.450088)
			(layers "F.Cu" "F.Mask" "F.Paste")
			(net "GND")
		)
		(pad "DF7" smd circle
			(at -29.29001 34.379916 180)
			(size 0.450088 0.450088)
			(layers "F.Cu" "F.Mask" "F.Paste")
			(net "M_K_CPU0_SB_DQ<31>")
		)
		(pad "DF8" smd circle
			(at -28.349956 34.379916 180)
			(size 0.450088 0.450088)
			(layers "F.Cu" "F.Mask" "F.Paste")
			(net "GND")
		)
		(pad "DF9" smd circle
			(at -27.409902 34.379916 180)
			(size 0.450088 0.450088)
			(layers "F.Cu" "F.Mask" "F.Paste")
			(net "M_L_CPU0_SB_DQ<31>")
		)
		(pad "DF10" smd circle
			(at -26.470102 34.379916 180)
			(size 0.450088 0.450088)
			(layers "F.Cu" "F.Mask" "F.Paste")
			(net "GND")
		)
		(pad "DF11" smd circle
			(at -25.530048 34.379916 180)
			(size 0.450088 0.450088)
			(layers "F.Cu" "F.Mask" "F.Paste")
			(net "GND")
		)
		(pad "DF12" smd circle
			(at -24.589994 34.379916 180)
			(size 0.450088 0.450088)
			(layers "F.Cu" "F.Mask" "F.Paste")
			(net "GND")
		)
		(pad "DF13" smd circle
			(at -23.64994 34.379916 180)
			(size 0.450088 0.450088)
			(layers "F.Cu" "F.Mask" "F.Paste")
			(net "GND")
		)
		(pad "DF14" smd circle
			(at -22.709886 34.379916 180)
			(size 0.450088 0.450088)
			(layers "F.Cu" "F.Mask" "F.Paste")
			(net "M_H_CPU0_SB_DQ<31>")
		)
		(pad "DF15" smd circle
			(at -21.770086 34.379916 180)
			(size 0.450088 0.450088)
			(layers "F.Cu" "F.Mask" "F.Paste")
			(net "GND")
		)
		(pad "DF16" smd circle
			(at -20.830032 34.379916 180)
			(size 0.450088 0.450088)
			(layers "F.Cu" "F.Mask" "F.Paste")
			(net "M_J_CPU0_SB_DQ<31>")
		)
		(pad "DF17" smd circle
			(at -19.889978 34.379916 180)
			(size 0.450088 0.450088)
			(layers "F.Cu" "F.Mask" "F.Paste")
			(net "GND")
		)
		(pad "DF18" smd circle
			(at -18.949924 34.379916 180)
			(size 0.450088 0.450088)
			(layers "F.Cu" "F.Mask" "F.Paste")
			(net "GND")
		)
		(pad "DF19" smd circle
			(at -18.010124 34.379916 180)
			(size 0.450088 0.450088)
			(layers "F.Cu" "F.Mask" "F.Paste")
			(net "GND")
		)
		(pad "DF20" smd circle
			(at -17.07007 34.379916 180)
			(size 0.450088 0.450088)
			(layers "F.Cu" "F.Mask" "F.Paste")
			(net "GND")
		)
		(pad "DF21" smd circle
			(at -16.130016 34.379916 180)
			(size 0.450088 0.450088)
			(layers "F.Cu" "F.Mask" "F.Paste")
			(net "M_I_CPU0_SB_DQ<31>")
		)
		(pad "DF22" smd circle
			(at -15.189962 34.379916 180)
			(size 0.450088 0.450088)
			(layers "F.Cu" "F.Mask" "F.Paste")
			(net "GND")
		)
		(pad "DF23" smd circle
			(at -14.249908 34.379916 180)
			(size 0.450088 0.450088)
			(layers "F.Cu" "F.Mask" "F.Paste")
			(net "GND")
		)
		(pad "DF24" smd circle
			(at -13.310108 34.379916 180)
			(size 0.450088 0.450088)
			(layers "F.Cu" "F.Mask" "F.Paste")
			(net "ESPI_CPU0_R_ALERT_N")
		)
		(pad "DF25" smd circle
			(at -12.370054 34.379916 180)
			(size 0.450088 0.450088)
			(layers "F.Cu" "F.Mask" "F.Paste")
			(net "ESPI_CPU0_R_D2")
		)
		(pad "DF26" smd circle
			(at -11.43 34.379916 180)
			(size 0.450088 0.450088)
			(layers "F.Cu" "F.Mask" "F.Paste")
			(net "GND")
		)
		(pad "DF27" smd circle
			(at -10.489946 34.379916 180)
			(size 0.450088 0.450088)
			(layers "F.Cu" "F.Mask" "F.Paste")
			(net "PD_ESPI_CPU0_CLK2")
		)
		(pad "DF28" smd circle
			(at -9.549892 34.379916 180)
			(size 0.450088 0.450088)
			(layers "F.Cu" "F.Mask" "F.Paste")
			(net "SPI_CPU0_R_D0")
		)
		(pad "DF29" smd circle
			(at -8.610092 34.379916 180)
			(size 0.450088 0.450088)
			(layers "F.Cu" "F.Mask" "F.Paste")
			(net "GND")
		)
		(pad "DF30" smd circle
			(at -7.670038 34.379916 180)
			(size 0.450088 0.450088)
			(layers "F.Cu" "F.Mask" "F.Paste")
			(net "SPI_CPU0_R_CS0_N")
		)
		(pad "DF31" smd circle
			(at -6.729984 34.379916 180)
			(size 0.450088 0.450088)
			(layers "F.Cu" "F.Mask" "F.Paste")
			(net "FM_BOARD_SKU_ID2")
		)
		(pad "DF32" smd circle
			(at -5.78993 34.379916 180)
			(size 0.450088 0.450088)
			(layers "F.Cu" "F.Mask" "F.Paste")
			(net "GND")
		)
		(pad "DF33" smd circle
			(at -4.849876 34.379916 180)
			(size 0.450088 0.450088)
			(layers "F.Cu" "F.Mask" "F.Paste")
			(net "FM_BOARD_SKU_ID0")
		)
		(pad "DF34" smd circle
			(at -3.910076 34.379916 180)
			(size 0.450088 0.450088)
			(layers "F.Cu" "F.Mask" "F.Paste")
			(net "TP_UART_CPU0_UART0_RTS_N")
		)
		(pad "DF35" smd circle
			(at -2.970022 34.379916 180)
			(size 0.450088 0.450088)
			(layers "F.Cu" "F.Mask" "F.Paste")
			(net "GND")
		)
		(pad "DF36" smd circle
			(at -2.029968 34.379916 180)
			(size 0.450088 0.450088)
			(layers "F.Cu" "F.Mask" "F.Paste")
			(net "FM_PASSWORD_CLEAR_R_N")
		)
		(pad "DF37" smd circle
			(at -1.089914 34.379916 180)
			(size 0.450088 0.450088)
			(layers "F.Cu" "F.Mask" "F.Paste")
			(net "GND")
		)
		(pad "DF39" smd circle
			(at 0.78994 34.379916 180)
			(size 0.450088 0.450088)
			(layers "F.Cu" "F.Mask" "F.Paste")
			(net "GND")
		)
		(pad "DF40" smd circle
			(at 1.729994 34.379916 180)
			(size 0.450088 0.450088)
			(layers "F.Cu" "F.Mask" "F.Paste")
			(net "FM_SMM_CRASHDUMP")
		)
		(pad "DF41" smd circle
			(at 2.670048 34.379916 180)
			(size 0.450088 0.450088)
			(layers "F.Cu" "F.Mask" "F.Paste")
			(net "Net_1948")
		)
		(pad "DF42" smd circle
			(at 3.610102 34.379916 180)
			(size 0.450088 0.450088)
			(layers "F.Cu" "F.Mask" "F.Paste")
			(net "GND")
		)
		(pad "DF43" smd circle
			(at 4.549902 34.379916 180)
			(size 0.450088 0.450088)
			(layers "F.Cu" "F.Mask" "F.Paste")
			(net "GND")
		)
		(pad "DF44" smd circle
			(at 5.489956 34.379916 180)
			(size 0.450088 0.450088)
			(layers "F.Cu" "F.Mask" "F.Paste")
			(net "GND")
		)
		(pad "DF45" smd circle
			(at 6.43001 34.379916 180)
			(size 0.450088 0.450088)
			(layers "F.Cu" "F.Mask" "F.Paste")
			(net "GND")
		)
		(pad "DF46" smd circle
			(at 7.370064 34.379916 180)
			(size 0.450088 0.450088)
			(layers "F.Cu" "F.Mask" "F.Paste")
			(net "GND")
		)
		(pad "DF47" smd circle
			(at 8.310118 34.379916 180)
			(size 0.450088 0.450088)
			(layers "F.Cu" "F.Mask" "F.Paste")
			(net "GND")
		)
		(pad "DF48" smd circle
			(at 9.249918 34.379916 180)
			(size 0.450088 0.450088)
			(layers "F.Cu" "F.Mask" "F.Paste")
			(net "GND")
		)
		(pad "DF49" smd circle
			(at 10.189972 34.379916 180)
			(size 0.450088 0.450088)
			(layers "F.Cu" "F.Mask" "F.Paste")
			(net "GND")
		)
		(pad "DF50" smd circle
			(at 11.130026 34.379916 180)
			(size 0.450088 0.450088)
			(layers "F.Cu" "F.Mask" "F.Paste")
			(net "GND")
		)
		(pad "DF51" smd circle
			(at 12.07008 34.379916 180)
			(size 0.450088 0.450088)
			(layers "F.Cu" "F.Mask" "F.Paste")
			(net "GND")
		)
		(pad "DF52" smd circle
			(at 13.00988 34.379916 180)
			(size 0.450088 0.450088)
			(layers "F.Cu" "F.Mask" "F.Paste")
			(net "GND")
		)
		(pad "DF53" smd circle
			(at 13.949934 34.379916 180)
			(size 0.450088 0.450088)
			(layers "F.Cu" "F.Mask" "F.Paste")
			(net "GND")
		)
		(pad "DF54" smd circle
			(at 14.889988 34.379916 180)
			(size 0.450088 0.450088)
			(layers "F.Cu" "F.Mask" "F.Paste")
			(net "GND")
		)
		(pad "DF55" smd circle
			(at 15.830042 34.379916 180)
			(size 0.450088 0.450088)
			(layers "F.Cu" "F.Mask" "F.Paste")
			(net "M_C_CPU0_SB_DQ<31>")
		)
		(pad "DF56" smd circle
			(at 16.770096 34.379916 180)
			(size 0.450088 0.450088)
			(layers "F.Cu" "F.Mask" "F.Paste")
			(net "GND")
		)
		(pad "DF57" smd circle
			(at 17.709896 34.379916 180)
			(size 0.450088 0.450088)
			(layers "F.Cu" "F.Mask" "F.Paste")
			(net "GND")
		)
		(pad "DF58" smd circle
			(at 18.64995 34.379916 180)
			(size 0.450088 0.450088)
			(layers "F.Cu" "F.Mask" "F.Paste")
			(net "GND")
		)
		(pad "DF59" smd circle
			(at 19.590004 34.379916 180)
			(size 0.450088 0.450088)
			(layers "F.Cu" "F.Mask" "F.Paste")
			(net "GND")
		)
		(pad "DF60" smd circle
			(at 20.530058 34.379916 180)
			(size 0.450088 0.450088)
			(layers "F.Cu" "F.Mask" "F.Paste")
			(net "M_D_CPU0_SB_DQ<31>")
		)
		(pad "DF61" smd circle
			(at 21.470112 34.379916 180)
			(size 0.450088 0.450088)
			(layers "F.Cu" "F.Mask" "F.Paste")
			(net "GND")
		)
		(pad "DF62" smd circle
			(at 22.409912 34.379916 180)
			(size 0.450088 0.450088)
			(layers "F.Cu" "F.Mask" "F.Paste")
			(net "M_B_CPU0_SB_DQ<31>")
		)
		(pad "DF63" smd circle
			(at 23.349966 34.379916 180)
			(size 0.450088 0.450088)
			(layers "F.Cu" "F.Mask" "F.Paste")
			(net "GND")
		)
		(pad "DF64" smd circle
			(at 24.29002 34.379916 180)
			(size 0.450088 0.450088)
			(layers "F.Cu" "F.Mask" "F.Paste")
			(net "GND")
		)
		(pad "DF65" smd circle
			(at 25.230074 34.379916 180)
			(size 0.450088 0.450088)
			(layers "F.Cu" "F.Mask" "F.Paste")
			(net "GND")
		)
		(pad "DF66" smd circle
			(at 26.170128 34.379916 180)
			(size 0.450088 0.450088)
			(layers "F.Cu" "F.Mask" "F.Paste")
			(net "GND")
		)
		(pad "DF67" smd circle
			(at 27.109928 34.379916 180)
			(size 0.450088 0.450088)
			(layers "F.Cu" "F.Mask" "F.Paste")
			(net "M_F_CPU0_SB_DQ<31>")
		)
		(pad "DF68" smd circle
			(at 28.049982 34.379916 180)
			(size 0.450088 0.450088)
			(layers "F.Cu" "F.Mask" "F.Paste")
			(net "GND")
		)
		(pad "DF69" smd circle
			(at 28.990036 34.379916 180)
			(size 0.450088 0.450088)
			(layers "F.Cu" "F.Mask" "F.Paste")
			(net "M_E_CPU0_SB_DQ<31>")
		)
		(pad "DF70" smd circle
			(at 29.93009 34.379916 180)
			(size 0.450088 0.450088)
			(layers "F.Cu" "F.Mask" "F.Paste")
			(net "GND")
		)
		(pad "DF71" smd circle
			(at 30.86989 34.379916 180)
			(size 0.450088 0.450088)
			(layers "F.Cu" "F.Mask" "F.Paste")
			(net "GND")
		)
		(pad "DF72" smd circle
			(at 31.809944 34.379916 180)
			(size 0.450088 0.450088)
			(layers "F.Cu" "F.Mask" "F.Paste")
			(net "GND")
		)
		(pad "DF73" smd circle
			(at 32.749998 34.379916 180)
			(size 0.450088 0.450088)
			(layers "F.Cu" "F.Mask" "F.Paste")
			(net "GND")
		)
		(pad "DF74" smd circle
			(at 33.690052 34.379916 180)
			(size 0.450088 0.450088)
			(layers "F.Cu" "F.Mask" "F.Paste")
			(net "M_A_CPU0_SB_DQ<31>")
		)
		(pad "DG1" smd circle
			(at -34.459926 35.189922 180)
			(size 0.450088 0.450088)
			(layers "F.Cu" "F.Mask" "F.Paste")
			(net "GND")
		)
		(pad "DG2" smd circle
			(at -33.519872 35.189922 180)
			(size 0.450088 0.450088)
			(layers "F.Cu" "F.Mask" "F.Paste")
			(net "GND")
		)
		(pad "DG3" smd circle
			(at -32.580072 35.189922 180)
			(size 0.450088 0.450088)
			(layers "F.Cu" "F.Mask" "F.Paste")
			(net "VSENSE_PVDDCR_CPU1_P0_DP")
		)
		(pad "DG4" smd circle
			(at -31.640018 35.189922 180)
			(size 0.450088 0.450088)
			(layers "F.Cu" "F.Mask" "F.Paste")
			(net "CPU0_SLP_S5_N")
		)
		(pad "DG5" smd circle
			(at -30.699964 35.189922 180)
			(size 0.450088 0.450088)
			(layers "F.Cu" "F.Mask" "F.Paste")
			(net "PVDD11_S3_P0")
		)
		(pad "DG6" smd circle
			(at -29.75991 35.189922 180)
			(size 0.450088 0.450088)
			(layers "F.Cu" "F.Mask" "F.Paste")
			(net "GND")
		)
		(pad "DG7" smd circle
			(at -28.82011 35.189922 180)
			(size 0.450088 0.450088)
			(layers "F.Cu" "F.Mask" "F.Paste")
			(net "GND")
		)
		(pad "DG8" smd circle
			(at -27.880056 35.189922 180)
			(size 0.450088 0.450088)
			(layers "F.Cu" "F.Mask" "F.Paste")
			(net "GND")
		)
		(pad "DG9" smd circle
			(at -26.940002 35.189922 180)
			(size 0.450088 0.450088)
			(layers "F.Cu" "F.Mask" "F.Paste")
			(net "GND")
		)
		(pad "DG10" smd circle
			(at -25.999948 35.189922 180)
			(size 0.450088 0.450088)
			(layers "F.Cu" "F.Mask" "F.Paste")
			(net "RST_CPU0_RSMRST_N")
		)
		(pad "DG11" smd circle
			(at -25.059894 35.189922 180)
			(size 0.450088 0.450088)
			(layers "F.Cu" "F.Mask" "F.Paste")
			(net "Net_1876")
		)
		(pad "DG12" smd circle
			(at -24.120094 35.189922 180)
			(size 0.450088 0.450088)
			(layers "F.Cu" "F.Mask" "F.Paste")
			(net "SMB_CPU0_4_R_SCL")
		)
		(pad "DG13" smd circle
			(at -23.18004 35.189922 180)
			(size 0.450088 0.450088)
			(layers "F.Cu" "F.Mask" "F.Paste")
			(net "GND")
		)
		(pad "DG14" smd circle
			(at -22.239986 35.189922 180)
			(size 0.450088 0.450088)
			(layers "F.Cu" "F.Mask" "F.Paste")
			(net "GND")
		)
		(pad "DG15" smd circle
			(at -21.299932 35.189922 180)
			(size 0.450088 0.450088)
			(layers "F.Cu" "F.Mask" "F.Paste")
			(net "GND")
		)
		(pad "DG16" smd circle
			(at -20.359878 35.189922 180)
			(size 0.450088 0.450088)
			(layers "F.Cu" "F.Mask" "F.Paste")
			(net "GND")
		)
		(pad "DG17" smd circle
			(at -19.420078 35.189922 180)
			(size 0.450088 0.450088)
			(layers "F.Cu" "F.Mask" "F.Paste")
			(net "Net_1940")
		)
		(pad "DG18" smd circle
			(at -18.480024 35.189922 180)
			(size 0.450088 0.450088)
			(layers "F.Cu" "F.Mask" "F.Paste")
			(net "GND")
		)
		(pad "DG19" smd circle
			(at -17.53997 35.189922 180)
			(size 0.450088 0.450088)
			(layers "F.Cu" "F.Mask" "F.Paste")
			(net "PVDDCR_CPU1_P0")
		)
		(pad "DG20" smd circle
			(at -16.599916 35.189922 180)
			(size 0.450088 0.450088)
			(layers "F.Cu" "F.Mask" "F.Paste")
			(net "GND")
		)
		(pad "DG21" smd circle
			(at -15.660116 35.189922 180)
			(size 0.450088 0.450088)
			(layers "F.Cu" "F.Mask" "F.Paste")
			(net "GND")
		)
		(pad "DG22" smd circle
			(at -14.720062 35.189922 180)
			(size 0.450088 0.450088)
			(layers "F.Cu" "F.Mask" "F.Paste")
			(net "SPI_CPU0_R_D1")
		)
		(pad "DG23" smd circle
			(at -13.780008 35.189922 180)
			(size 0.450088 0.450088)
			(layers "F.Cu" "F.Mask" "F.Paste")
			(net "CLK_ESPI_CPU0_R_CLK1")
		)
		(pad "DG24" smd circle
			(at -12.839954 35.189922 180)
			(size 0.450088 0.450088)
			(layers "F.Cu" "F.Mask" "F.Paste")
			(net "GND")
		)
		(pad "DG25" smd circle
			(at -11.8999 35.189922 180)
			(size 0.450088 0.450088)
			(layers "F.Cu" "F.Mask" "F.Paste")
			(net "ESPI_CPU0_R_D3")
		)
		(pad "DG26" smd circle
			(at -10.9601 35.189922 180)
			(size 0.450088 0.450088)
			(layers "F.Cu" "F.Mask" "F.Paste")
			(net "SPI_CPU0_R_CS1_N")
		)
		(pad "DG27" smd circle
			(at -10.020046 35.189922 180)
			(size 0.450088 0.450088)
			(layers "F.Cu" "F.Mask" "F.Paste")
			(net "GND")
		)
		(pad "DG28" smd circle
			(at -9.079992 35.189922 180)
			(size 0.450088 0.450088)
			(layers "F.Cu" "F.Mask" "F.Paste")
			(net "CPU0_ESPI_CS0_N")
		)
		(pad "DG29" smd circle
			(at -8.139938 35.189922 180)
			(size 0.450088 0.450088)
			(layers "F.Cu" "F.Mask" "F.Paste")
			(net "SPI_CPU0_R_D3")
		)
		(pad "DG30" smd circle
			(at -7.199884 35.189922 180)
			(size 0.450088 0.450088)
			(layers "F.Cu" "F.Mask" "F.Paste")
			(net "GND")
		)
		(pad "DG31" smd circle
			(at -6.260084 35.189922 180)
			(size 0.450088 0.450088)
			(layers "F.Cu" "F.Mask" "F.Paste")
			(net "FM_BOARD_SKU_ID3")
		)
		(pad "DG32" smd circle
			(at -5.32003 35.189922 180)
			(size 0.450088 0.450088)
			(layers "F.Cu" "F.Mask" "F.Paste")
			(net "CPU0_ROM_TYPE_SELECT")
		)
		(pad "DG33" smd circle
			(at -4.379976 35.189922 180)
			(size 0.450088 0.450088)
			(layers "F.Cu" "F.Mask" "F.Paste")
			(net "GND")
		)
		(pad "DG34" smd circle
			(at -3.439922 35.189922 180)
			(size 0.450088 0.450088)
			(layers "F.Cu" "F.Mask" "F.Paste")
			(net "TP_CPU0_UART0_INTR")
		)
		(pad "DG35" smd circle
			(at -2.500122 35.189922 180)
			(size 0.450088 0.450088)
			(layers "F.Cu" "F.Mask" "F.Paste")
			(net "UART_CPU0_UART0_RX")
		)
		(pad "DG36" smd circle
			(at -1.560068 35.189922 180)
			(size 0.450088 0.450088)
			(layers "F.Cu" "F.Mask" "F.Paste")
			(net "RST_CPU0_PERST1_N")
		)
		(pad "DG40" smd circle
			(at 1.260094 35.189922 180)
			(size 0.450088 0.450088)
			(layers "F.Cu" "F.Mask" "F.Paste")
			(net "Net_1888")
		)
		(pad "DG41" smd circle
			(at 2.199894 35.189922 180)
			(size 0.450088 0.450088)
			(layers "F.Cu" "F.Mask" "F.Paste")
			(net "GND")
		)
		(pad "DG42" smd circle
			(at 3.139948 35.189922 180)
			(size 0.450088 0.450088)
			(layers "F.Cu" "F.Mask" "F.Paste")
			(net "Net_1952")
		)
		(pad "DG43" smd circle
			(at 4.080002 35.189922 180)
			(size 0.450088 0.450088)
			(layers "F.Cu" "F.Mask" "F.Paste")
			(net "GND")
		)
		(pad "DG44" smd circle
			(at 5.020056 35.189922 180)
			(size 0.450088 0.450088)
			(layers "F.Cu" "F.Mask" "F.Paste")
			(net "P3E_CPU0_P4_RX_DN<3>")
		)
		(pad "DG45" smd circle
			(at 5.96011 35.189922 180)
			(size 0.450088 0.450088)
			(layers "F.Cu" "F.Mask" "F.Paste")
			(net "P3E_CPU0_P4_RX_DP<3>")
		)
		(pad "DG46" smd circle
			(at 6.89991 35.189922 180)
			(size 0.450088 0.450088)
			(layers "F.Cu" "F.Mask" "F.Paste")
			(net "GND")
		)
		(pad "DG47" smd circle
			(at 7.839964 35.189922 180)
			(size 0.450088 0.450088)
			(layers "F.Cu" "F.Mask" "F.Paste")
			(net "P3E_CPU0_P4_RX_DN<2>")
		)
		(pad "DG48" smd circle
			(at 8.780018 35.189922 180)
			(size 0.450088 0.450088)
			(layers "F.Cu" "F.Mask" "F.Paste")
			(net "P3E_CPU0_P4_RX_DP<2>")
		)
		(pad "DG49" smd circle
			(at 9.720072 35.189922 180)
			(size 0.450088 0.450088)
			(layers "F.Cu" "F.Mask" "F.Paste")
			(net "GND")
		)
		(pad "DG50" smd circle
			(at 10.659872 35.189922 180)
			(size 0.450088 0.450088)
			(layers "F.Cu" "F.Mask" "F.Paste")
			(net "P3E_CPU0_P4_RX_DN<1>")
		)
		(pad "DG51" smd circle
			(at 11.599926 35.189922 180)
			(size 0.450088 0.450088)
			(layers "F.Cu" "F.Mask" "F.Paste")
			(net "P3E_CPU0_P4_RX_DP<1>")
		)
		(pad "DG52" smd circle
			(at 12.53998 35.189922 180)
			(size 0.450088 0.450088)
			(layers "F.Cu" "F.Mask" "F.Paste")
			(net "GND")
		)
		(pad "DG53" smd circle
			(at 13.480034 35.189922 180)
			(size 0.450088 0.450088)
			(layers "F.Cu" "F.Mask" "F.Paste")
			(net "P3E_CPU0_P4_RX_DN<0>")
		)
		(pad "DG54" smd circle
			(at 14.420088 35.189922 180)
			(size 0.450088 0.450088)
			(layers "F.Cu" "F.Mask" "F.Paste")
			(net "P3E_CPU0_P4_RX_DP<0>")
		)
		(pad "DG55" smd circle
			(at 15.359888 35.189922 180)
			(size 0.450088 0.450088)
			(layers "F.Cu" "F.Mask" "F.Paste")
			(net "GND")
		)
		(pad "DG56" smd circle
			(at 16.299942 35.189922 180)
			(size 0.450088 0.450088)
			(layers "F.Cu" "F.Mask" "F.Paste")
			(net "GND")
		)
		(pad "DG57" smd circle
			(at 17.239996 35.189922 180)
			(size 0.450088 0.450088)
			(layers "F.Cu" "F.Mask" "F.Paste")
			(net "PVDDCR_CPU1_P0")
		)
		(pad "DG58" smd circle
			(at 18.18005 35.189922 180)
			(size 0.450088 0.450088)
			(layers "F.Cu" "F.Mask" "F.Paste")
			(net "Net_1897")
		)
		(pad "DG59" smd circle
			(at 19.120104 35.189922 180)
			(size 0.450088 0.450088)
			(layers "F.Cu" "F.Mask" "F.Paste")
			(net "GND")
		)
		(pad "DG60" smd circle
			(at 20.059904 35.189922 180)
			(size 0.450088 0.450088)
			(layers "F.Cu" "F.Mask" "F.Paste")
			(net "GND")
		)
		(pad "DG61" smd circle
			(at 20.999958 35.189922 180)
			(size 0.450088 0.450088)
			(layers "F.Cu" "F.Mask" "F.Paste")
			(net "GND")
		)
		(pad "DG62" smd circle
			(at 21.940012 35.189922 180)
			(size 0.450088 0.450088)
			(layers "F.Cu" "F.Mask" "F.Paste")
			(net "GND")
		)
		(pad "DG63" smd circle
			(at 22.880066 35.189922 180)
			(size 0.450088 0.450088)
			(layers "F.Cu" "F.Mask" "F.Paste")
			(net "GND")
		)
		(pad "DG64" smd circle
			(at 23.82012 35.189922 180)
			(size 0.450088 0.450088)
			(layers "F.Cu" "F.Mask" "F.Paste")
			(net "PVDDIO_P0")
		)
		(pad "DG65" smd circle
			(at 24.75992 35.189922 180)
			(size 0.450088 0.450088)
			(layers "F.Cu" "F.Mask" "F.Paste")
			(net "GND")
		)
		(pad "DG66" smd circle
			(at 25.699974 35.189922 180)
			(size 0.450088 0.450088)
			(layers "F.Cu" "F.Mask" "F.Paste")
			(net "GND")
		)
		(pad "DG67" smd circle
			(at 26.640028 35.189922 180)
			(size 0.450088 0.450088)
			(layers "F.Cu" "F.Mask" "F.Paste")
			(net "GND")
		)
		(pad "DG68" smd circle
			(at 27.580082 35.189922 180)
			(size 0.450088 0.450088)
			(layers "F.Cu" "F.Mask" "F.Paste")
			(net "GND")
		)
		(pad "DG69" smd circle
			(at 28.519882 35.189922 180)
			(size 0.450088 0.450088)
			(layers "F.Cu" "F.Mask" "F.Paste")
			(net "GND")
		)
		(pad "DG70" smd circle
			(at 29.459936 35.189922 180)
			(size 0.450088 0.450088)
			(layers "F.Cu" "F.Mask" "F.Paste")
			(net "GND")
		)
		(pad "DG71" smd circle
			(at 30.39999 35.189922 180)
			(size 0.450088 0.450088)
			(layers "F.Cu" "F.Mask" "F.Paste")
			(net "PVDDIO_P0")
		)
		(pad "DG72" smd circle
			(at 31.340044 35.189922 180)
			(size 0.450088 0.450088)
			(layers "F.Cu" "F.Mask" "F.Paste")
			(net "FM_P0_PCC1_N")
		)
		(pad "DG73" smd circle
			(at 32.280098 35.189922 180)
			(size 0.450088 0.450088)
			(layers "F.Cu" "F.Mask" "F.Paste")
			(net "SVID_PVDDCR_CPU1_P0_SVTO")
		)
		(pad "DG74" smd circle
			(at 33.219898 35.189922 180)
			(size 0.450088 0.450088)
			(layers "F.Cu" "F.Mask" "F.Paste")
			(net "GND")
		)
		(pad "DG75" smd circle
			(at 34.159952 35.189922 180)
			(size 0.450088 0.450088)
			(layers "F.Cu" "F.Mask" "F.Paste")
			(net "GND")
		)
		(pad "DH3" smd circle
			(at -33.049972 35.999928 180)
			(size 0.450088 0.450088)
			(layers "F.Cu" "F.Mask" "F.Paste")
			(net "VSENSE_PVDD11_S3_P0_DP")
		)
		(pad "DH4" smd circle
			(at -32.109918 35.999928 180)
			(size 0.450088 0.450088)
			(layers "F.Cu" "F.Mask" "F.Paste")
			(net "FM_BOARD_SKU_ID4")
		)
		(pad "DH5" smd circle
			(at -31.170118 35.999928 180)
			(size 0.450088 0.450088)
			(layers "F.Cu" "F.Mask" "F.Paste")
			(net "GND")
		)
		(pad "DH6" smd circle
			(at -30.230064 35.999928 180)
			(size 0.450088 0.450088)
			(layers "F.Cu" "F.Mask" "F.Paste")
			(net "RST_CPU0_SYS_N")
		)
		(pad "DH7" smd circle
			(at -29.29001 35.999928 180)
			(size 0.450088 0.450088)
			(layers "F.Cu" "F.Mask" "F.Paste")
			(net "CPU0_PWR_BTN_N")
		)
		(pad "DH8" smd circle
			(at -28.349956 35.999928 180)
			(size 0.450088 0.450088)
			(layers "F.Cu" "F.Mask" "F.Paste")
			(net "CPU0_RTC_LDO_SELECT")
		)
		(pad "DH9" smd circle
			(at -27.409902 35.999928 180)
			(size 0.450088 0.450088)
			(layers "F.Cu" "F.Mask" "F.Paste")
			(net "CLK_CPU0_RTCCLK")
		)
		(pad "DH10" smd circle
			(at -26.470102 35.999928 180)
			(size 0.450088 0.450088)
			(layers "F.Cu" "F.Mask" "F.Paste")
			(net "CPU0_SP5R4")
		)
		(pad "DH11" smd circle
			(at -25.530048 35.999928 180)
			(size 0.450088 0.450088)
			(layers "F.Cu" "F.Mask" "F.Paste")
			(net "GND")
		)
		(pad "DH12" smd circle
			(at -24.589994 35.999928 180)
			(size 0.450088 0.450088)
			(layers "F.Cu" "F.Mask" "F.Paste")
			(net "SMB_CPU0_4_R_SDA")
		)
		(pad "DH13" smd circle
			(at -23.64994 35.999928 180)
			(size 0.450088 0.450088)
			(layers "F.Cu" "F.Mask" "F.Paste")
			(net "Net_1947")
		)
		(pad "DH14" smd circle
			(at -22.709886 35.999928 180)
			(size 0.450088 0.450088)
			(layers "F.Cu" "F.Mask" "F.Paste")
			(net "Net_1951")
		)
		(pad "DH15" smd circle
			(at -21.770086 35.999928 180)
			(size 0.450088 0.450088)
			(layers "F.Cu" "F.Mask" "F.Paste")
			(net "IRQ_TPM_SPI_R_N")
		)
		(pad "DH16" smd circle
			(at -20.830032 35.999928 180)
			(size 0.450088 0.450088)
			(layers "F.Cu" "F.Mask" "F.Paste")
			(net "IRQ_SMI_ACTIVE_N")
		)
		(pad "DH17" smd circle
			(at -19.889978 35.999928 180)
			(size 0.450088 0.450088)
			(layers "F.Cu" "F.Mask" "F.Paste")
			(net "Net_1941")
		)
		(pad "DH18" smd circle
			(at -18.949924 35.999928 180)
			(size 0.450088 0.450088)
			(layers "F.Cu" "F.Mask" "F.Paste")
			(net "GND")
		)
		(pad "DH19" smd circle
			(at -18.010124 35.999928 180)
			(size 0.450088 0.450088)
			(layers "F.Cu" "F.Mask" "F.Paste")
			(net "PVDDCR_CPU1_P0")
		)
		(pad "DH20" smd circle
			(at -17.07007 35.999928 180)
			(size 0.450088 0.450088)
			(layers "F.Cu" "F.Mask" "F.Paste")
			(net "PVDDCR_CPU1_P0")
		)
		(pad "DH21" smd circle
			(at -16.130016 35.999928 180)
			(size 0.450088 0.450088)
			(layers "F.Cu" "F.Mask" "F.Paste")
			(net "Net_1942")
		)
		(pad "DH22" smd circle
			(at -15.189962 35.999928 180)
			(size 0.450088 0.450088)
			(layers "F.Cu" "F.Mask" "F.Paste")
			(net "PVDDCR_CPU1_P0")
		)
		(pad "DH23" smd circle
			(at -14.249908 35.999928 180)
			(size 0.450088 0.450088)
			(layers "F.Cu" "F.Mask" "F.Paste")
			(net "PVDDCR_CPU1_P0")
		)
		(pad "DH24" smd circle
			(at -13.310108 35.999928 180)
			(size 0.450088 0.450088)
			(layers "F.Cu" "F.Mask" "F.Paste")
			(net "ESPI_CPU0_R_D0")
		)
		(pad "DH25" smd circle
			(at -12.370054 35.999928 180)
			(size 0.450088 0.450088)
			(layers "F.Cu" "F.Mask" "F.Paste")
			(net "PVDDCR_CPU1_P0")
		)
		(pad "DH26" smd circle
			(at -11.43 35.999928 180)
			(size 0.450088 0.450088)
			(layers "F.Cu" "F.Mask" "F.Paste")
			(net "PVDDCR_CPU1_P0")
		)
		(pad "DH27" smd circle
			(at -10.489946 35.999928 180)
			(size 0.450088 0.450088)
			(layers "F.Cu" "F.Mask" "F.Paste")
			(net "NC_CPU0_SPI_CS2_N")
		)
		(pad "DH28" smd circle
			(at -9.549892 35.999928 180)
			(size 0.450088 0.450088)
			(layers "F.Cu" "F.Mask" "F.Paste")
			(net "PVDDCR_CPU1_P0")
		)
		(pad "DH29" smd circle
			(at -8.610092 35.999928 180)
			(size 0.450088 0.450088)
			(layers "F.Cu" "F.Mask" "F.Paste")
			(net "PVDDCR_CPU1_P0")
		)
		(pad "DH30" smd circle
			(at -7.670038 35.999928 180)
			(size 0.450088 0.450088)
			(layers "F.Cu" "F.Mask" "F.Paste")
			(net "BOOT_RDY_R_H")
		)
		(pad "DH31" smd circle
			(at -6.729984 35.999928 180)
			(size 0.450088 0.450088)
			(layers "F.Cu" "F.Mask" "F.Paste")
			(net "PVDDCR_CPU1_P0")
		)
		(pad "DH32" smd circle
			(at -5.78993 35.999928 180)
			(size 0.450088 0.450088)
			(layers "F.Cu" "F.Mask" "F.Paste")
			(net "PVDDCR_CPU1_P0")
		)
		(pad "DH33" smd circle
			(at -4.849876 35.999928 180)
			(size 0.450088 0.450088)
			(layers "F.Cu" "F.Mask" "F.Paste")
			(net "UART_CPU0_SCM_UART1_RX")
		)
		(pad "DH34" smd circle
			(at -3.910076 35.999928 180)
			(size 0.450088 0.450088)
			(layers "F.Cu" "F.Mask" "F.Paste")
			(net "PVDDCR_CPU1_P0")
		)
		(pad "DH35" smd circle
			(at -2.970022 35.999928 180)
			(size 0.450088 0.450088)
			(layers "F.Cu" "F.Mask" "F.Paste")
			(net "PVDDCR_CPU1_P0")
		)
		(pad "DH36" smd circle
			(at -2.029968 35.999928 180)
			(size 0.450088 0.450088)
			(layers "F.Cu" "F.Mask" "F.Paste")
			(net "CPU0_PWR_GD_OUT")
		)
		(pad "DH37" smd circle
			(at -1.089914 35.999928 180)
			(size 0.450088 0.450088)
			(layers "F.Cu" "F.Mask" "F.Paste")
			(net "GND")
		)
		(pad "DH39" smd circle
			(at 0.78994 35.999928 180)
			(size 0.450088 0.450088)
			(layers "F.Cu" "F.Mask" "F.Paste")
			(net "GND")
		)
		(pad "DH40" smd circle
			(at 1.729994 35.999928 180)
			(size 0.450088 0.450088)
			(layers "F.Cu" "F.Mask" "F.Paste")
			(net "Net_1893")
		)
		(pad "DH41" smd circle
			(at 2.670048 35.999928 180)
			(size 0.450088 0.450088)
			(layers "F.Cu" "F.Mask" "F.Paste")
			(net "PVDDCR_CPU1_P0")
		)
		(pad "DH42" smd circle
			(at 3.610102 35.999928 180)
			(size 0.450088 0.450088)
			(layers "F.Cu" "F.Mask" "F.Paste")
			(net "PVDDCR_CPU1_P0")
		)
		(pad "DH43" smd circle
			(at 4.549902 35.999928 180)
			(size 0.450088 0.450088)
			(layers "F.Cu" "F.Mask" "F.Paste")
			(net "GND")
		)
		(pad "DH44" smd circle
			(at 5.489956 35.999928 180)
			(size 0.450088 0.450088)
			(layers "F.Cu" "F.Mask" "F.Paste")
			(net "PVDDCR_CPU1_P0")
		)
		(pad "DH45" smd circle
			(at 6.43001 35.999928 180)
			(size 0.450088 0.450088)
			(layers "F.Cu" "F.Mask" "F.Paste")
			(net "PVDDCR_CPU1_P0")
		)
		(pad "DH46" smd circle
			(at 7.370064 35.999928 180)
			(size 0.450088 0.450088)
			(layers "F.Cu" "F.Mask" "F.Paste")
			(net "GND")
		)
		(pad "DH47" smd circle
			(at 8.310118 35.999928 180)
			(size 0.450088 0.450088)
			(layers "F.Cu" "F.Mask" "F.Paste")
			(net "PVDDCR_CPU1_P0")
		)
		(pad "DH48" smd circle
			(at 9.249918 35.999928 180)
			(size 0.450088 0.450088)
			(layers "F.Cu" "F.Mask" "F.Paste")
			(net "PVDDCR_CPU1_P0")
		)
		(pad "DH49" smd circle
			(at 10.189972 35.999928 180)
			(size 0.450088 0.450088)
			(layers "F.Cu" "F.Mask" "F.Paste")
			(net "GND")
		)
		(pad "DH50" smd circle
			(at 11.130026 35.999928 180)
			(size 0.450088 0.450088)
			(layers "F.Cu" "F.Mask" "F.Paste")
			(net "PVDDCR_CPU1_P0")
		)
		(pad "DH51" smd circle
			(at 12.07008 35.999928 180)
			(size 0.450088 0.450088)
			(layers "F.Cu" "F.Mask" "F.Paste")
			(net "PVDDCR_CPU1_P0")
		)
		(pad "DH52" smd circle
			(at 13.00988 35.999928 180)
			(size 0.450088 0.450088)
			(layers "F.Cu" "F.Mask" "F.Paste")
			(net "GND")
		)
		(pad "DH53" smd circle
			(at 13.949934 35.999928 180)
			(size 0.450088 0.450088)
			(layers "F.Cu" "F.Mask" "F.Paste")
			(net "PVDDCR_CPU1_P0")
		)
		(pad "DH54" smd circle
			(at 14.889988 35.999928 180)
			(size 0.450088 0.450088)
			(layers "F.Cu" "F.Mask" "F.Paste")
			(net "PVDDCR_CPU1_P0")
		)
		(pad "DH55" smd circle
			(at 15.830042 35.999928 180)
			(size 0.450088 0.450088)
			(layers "F.Cu" "F.Mask" "F.Paste")
			(net "GND")
		)
		(pad "DH56" smd circle
			(at 16.770096 35.999928 180)
			(size 0.450088 0.450088)
			(layers "F.Cu" "F.Mask" "F.Paste")
			(net "PVDDCR_CPU1_P0")
		)
		(pad "DH57" smd circle
			(at 17.709896 35.999928 180)
			(size 0.450088 0.450088)
			(layers "F.Cu" "F.Mask" "F.Paste")
			(net "PVDDCR_CPU1_P0")
		)
		(pad "DH58" smd circle
			(at 18.64995 35.999928 180)
			(size 0.450088 0.450088)
			(layers "F.Cu" "F.Mask" "F.Paste")
			(net "Net_1896")
		)
		(pad "DH59" smd circle
			(at 19.590004 35.999928 180)
			(size 0.450088 0.450088)
			(layers "F.Cu" "F.Mask" "F.Paste")
			(net "GND")
		)
		(pad "DH60" smd circle
			(at 20.530058 35.999928 180)
			(size 0.450088 0.450088)
			(layers "F.Cu" "F.Mask" "F.Paste")
			(net "USB2_CPU0_P11_DP")
		)
		(pad "DH61" smd circle
			(at 21.470112 35.999928 180)
			(size 0.450088 0.450088)
			(layers "F.Cu" "F.Mask" "F.Paste")
			(net "GND")
		)
		(pad "DH62" smd circle
			(at 22.409912 35.999928 180)
			(size 0.450088 0.450088)
			(layers "F.Cu" "F.Mask" "F.Paste")
			(net "Net_1894")
		)
		(pad "DH63" smd circle
			(at 23.349966 35.999928 180)
			(size 0.450088 0.450088)
			(layers "F.Cu" "F.Mask" "F.Paste")
			(net "GND")
		)
		(pad "DH64" smd circle
			(at 24.29002 35.999928 180)
			(size 0.450088 0.450088)
			(layers "F.Cu" "F.Mask" "F.Paste")
			(net "GND")
		)
		(pad "DH65" smd circle
			(at 25.230074 35.999928 180)
			(size 0.450088 0.450088)
			(layers "F.Cu" "F.Mask" "F.Paste")
			(net "Net_1889")
		)
		(pad "DH66" smd circle
			(at 26.170128 35.999928 180)
			(size 0.450088 0.450088)
			(layers "F.Cu" "F.Mask" "F.Paste")
			(net "GND")
		)
		(pad "DH67" smd circle
			(at 27.109928 35.999928 180)
			(size 0.450088 0.450088)
			(layers "F.Cu" "F.Mask" "F.Paste")
			(net "USB2_CPU0_P10_DN")
		)
		(pad "DH68" smd circle
			(at 28.049982 35.999928 180)
			(size 0.450088 0.450088)
			(layers "F.Cu" "F.Mask" "F.Paste")
			(net "GND")
		)
		(pad "DH69" smd circle
			(at 28.990036 35.999928 180)
			(size 0.450088 0.450088)
			(layers "F.Cu" "F.Mask" "F.Paste")
			(net "Net_1892")
		)
		(pad "DH70" smd circle
			(at 29.93009 35.999928 180)
			(size 0.450088 0.450088)
			(layers "F.Cu" "F.Mask" "F.Paste")
			(net "GND")
		)
		(pad "DH71" smd circle
			(at 30.86989 35.999928 180)
			(size 0.450088 0.450088)
			(layers "F.Cu" "F.Mask" "F.Paste")
			(net "SMB_APML_CPU0_SDA")
		)
		(pad "DH72" smd circle
			(at 31.809944 35.999928 180)
			(size 0.450088 0.450088)
			(layers "F.Cu" "F.Mask" "F.Paste")
			(net "SVID_PVDDCR_CPU1_P0_SVD")
		)
		(pad "DH73" smd circle
			(at 32.749998 35.999928 180)
			(size 0.450088 0.450088)
			(layers "F.Cu" "F.Mask" "F.Paste")
			(net "CPU0_SP5R3")
		)
		(pad "DJ3" smd circle
			(at -32.580072 36.809934 180)
			(size 0.450088 0.450088)
			(layers "F.Cu" "F.Mask" "F.Paste")
			(net "VSENSE_VSS_SENSE_C_P0")
		)
		(pad "DJ4" smd circle
			(at -31.640018 36.809934 180)
			(size 0.450088 0.450088)
			(layers "F.Cu" "F.Mask" "F.Paste")
			(net "Net_1943")
		)
		(pad "DJ5" smd circle
			(at -30.699964 36.809934 180)
			(size 0.450088 0.450088)
			(layers "F.Cu" "F.Mask" "F.Paste")
			(net "CPU0_SLP_S3_N")
		)
		(pad "DJ7" smd circle
			(at -28.82011 36.809934 180)
			(size 0.450088 0.450088)
			(layers "F.Cu" "F.Mask" "F.Paste")
			(net "GND")
		)
		(pad "DJ8" smd circle
			(at -27.880056 36.809934 180)
			(size 0.450088 0.450088)
			(layers "F.Cu" "F.Mask" "F.Paste")
			(net "CPU0_PWR_GOOD")
		)
		(pad "DJ9" smd circle
			(at -26.940002 36.809934 180)
			(size 0.450088 0.450088)
			(layers "F.Cu" "F.Mask" "F.Paste")
			(net "CPU0_THERMTRIP_N")
		)
		(pad "DJ10" smd circle
			(at -25.999948 36.809934 180)
			(size 0.450088 0.450088)
			(layers "F.Cu" "F.Mask" "F.Paste")
			(net "IRQ_WAKE_N")
		)
		(pad "DJ11" smd circle
			(at -25.059894 36.809934 180)
			(size 0.450088 0.450088)
			(layers "F.Cu" "F.Mask" "F.Paste")
			(net "CPU0_SMERR_N")
		)
		(pad "DJ13" smd circle
			(at -23.18004 36.809934 180)
			(size 0.450088 0.450088)
			(layers "F.Cu" "F.Mask" "F.Paste")
			(net "XTAL_CPU0_X32K_X2")
		)
		(pad "DJ14" smd circle
			(at -22.239986 36.809934 180)
			(size 0.450088 0.450088)
			(layers "F.Cu" "F.Mask" "F.Paste")
			(net "XTAL_CPU0_X32K_X1")
		)
		(pad "DJ15" smd circle
			(at -21.299932 36.809934 180)
			(size 0.450088 0.450088)
			(layers "F.Cu" "F.Mask" "F.Paste")
			(net "GND")
		)
		(pad "DJ16" smd circle
			(at -20.359878 36.809934 180)
			(size 0.450088 0.450088)
			(layers "F.Cu" "F.Mask" "F.Paste")
			(net "XTAL_CPU0_X48M_X2")
		)
		(pad "DJ17" smd circle
			(at -19.420078 36.809934 180)
			(size 0.450088 0.450088)
			(layers "F.Cu" "F.Mask" "F.Paste")
			(net "XTAL_CPU0_X48M_X1")
		)
		(pad "DJ19" smd circle
			(at -17.53997 36.809934 180)
			(size 0.450088 0.450088)
			(layers "F.Cu" "F.Mask" "F.Paste")
			(net "GND")
		)
		(pad "DJ20" smd circle
			(at -16.599916 36.809934 180)
			(size 0.450088 0.450088)
			(layers "F.Cu" "F.Mask" "F.Paste")
			(net "SMB_CPU_5_R_SDA")
		)
		(pad "DJ21" smd circle
			(at -15.660116 36.809934 180)
			(size 0.450088 0.450088)
			(layers "F.Cu" "F.Mask" "F.Paste")
			(net "SMB_CPU_5_R_SCL")
		)
		(pad "DJ22" smd circle
			(at -14.720062 36.809934 180)
			(size 0.450088 0.450088)
			(layers "F.Cu" "F.Mask" "F.Paste")
			(net "CPU0_ESPI0_ALERT_N")
		)
		(pad "DJ23" smd circle
			(at -13.780008 36.809934 180)
			(size 0.450088 0.450088)
			(layers "F.Cu" "F.Mask" "F.Paste")
			(net "ESPI_CPU0_R_CS1_N")
		)
		(pad "DJ25" smd circle
			(at -11.8999 36.809934 180)
			(size 0.450088 0.450088)
			(layers "F.Cu" "F.Mask" "F.Paste")
			(net "SPI_CPU0_R_TPM_CS_N")
		)
		(pad "DJ26" smd circle
			(at -10.9601 36.809934 180)
			(size 0.450088 0.450088)
			(layers "F.Cu" "F.Mask" "F.Paste")
			(net "RST_CPU0_KBRST_R_N")
		)
		(pad "DJ27" smd circle
			(at -10.020046 36.809934 180)
			(size 0.450088 0.450088)
			(layers "F.Cu" "F.Mask" "F.Paste")
			(net "SPI_CPU0_R_CLK")
		)
		(pad "DJ28" smd circle
			(at -9.079992 36.809934 180)
			(size 0.450088 0.450088)
			(layers "F.Cu" "F.Mask" "F.Paste")
			(net "SPI_CPU0_R_D2")
		)
		(pad "DJ29" smd circle
			(at -8.139938 36.809934 180)
			(size 0.450088 0.450088)
			(layers "F.Cu" "F.Mask" "F.Paste")
			(net "FM_BIOS_POST_CMPLT_R_N")
		)
		(pad "DJ31" smd circle
			(at -6.260084 36.809934 180)
			(size 0.450088 0.450088)
			(layers "F.Cu" "F.Mask" "F.Paste")
			(net "CPU0_NMI_SYNC_FLOOD_N")
		)
		(pad "DJ32" smd circle
			(at -5.32003 36.809934 180)
			(size 0.450088 0.450088)
			(layers "F.Cu" "F.Mask" "F.Paste")
			(net "UART_CPU0_SCM_UART1_R_TX")
		)
		(pad "DJ33" smd circle
			(at -4.379976 36.809934 180)
			(size 0.450088 0.450088)
			(layers "F.Cu" "F.Mask" "F.Paste")
			(net "FM_BIOS_USB_RECOVERY_R")
		)
		(pad "DJ34" smd circle
			(at -3.439922 36.809934 180)
			(size 0.450088 0.450088)
			(layers "F.Cu" "F.Mask" "F.Paste")
			(net "UART_CPU0_UART0_R_TX")
		)
		(pad "DJ35" smd circle
			(at -2.500122 36.809934 180)
			(size 0.450088 0.450088)
			(layers "F.Cu" "F.Mask" "F.Paste")
			(net "FM_INT_CPU0_HP_UBM_N")
		)
		(pad "DJ41" smd circle
			(at 2.199894 36.809934 180)
			(size 0.450088 0.450088)
			(layers "F.Cu" "F.Mask" "F.Paste")
			(net "CLK_100M_CPU0_CLK11_R_DP")
		)
		(pad "DJ42" smd circle
			(at 3.139948 36.809934 180)
			(size 0.450088 0.450088)
			(layers "F.Cu" "F.Mask" "F.Paste")
			(net "CLK_100M_CPU0_CLK11_R_DN")
		)
		(pad "DJ43" smd circle
			(at 4.080002 36.809934 180)
			(size 0.450088 0.450088)
			(layers "F.Cu" "F.Mask" "F.Paste")
			(net "GND")
		)
		(pad "DJ44" smd circle
			(at 5.020056 36.809934 180)
			(size 0.450088 0.450088)
			(layers "F.Cu" "F.Mask" "F.Paste")
			(net "CLK_100M_CPU0_CLK12_R_DN")
		)
		(pad "DJ45" smd circle
			(at 5.96011 36.809934 180)
			(size 0.450088 0.450088)
			(layers "F.Cu" "F.Mask" "F.Paste")
			(net "CLK_100M_CPU0_CLK12_R_DP")
		)
		(pad "DJ47" smd circle
			(at 7.839964 36.809934 180)
			(size 0.450088 0.450088)
			(layers "F.Cu" "F.Mask" "F.Paste")
			(net "Net_1877")
		)
		(pad "DJ48" smd circle
			(at 8.780018 36.809934 180)
			(size 0.450088 0.450088)
			(layers "F.Cu" "F.Mask" "F.Paste")
			(net "Net_1878")
		)
		(pad "DJ49" smd circle
			(at 9.720072 36.809934 180)
			(size 0.450088 0.450088)
			(layers "F.Cu" "F.Mask" "F.Paste")
			(net "GND")
		)
		(pad "DJ50" smd circle
			(at 10.659872 36.809934 180)
			(size 0.450088 0.450088)
			(layers "F.Cu" "F.Mask" "F.Paste")
			(net "Net_1879")
		)
		(pad "DJ51" smd circle
			(at 11.599926 36.809934 180)
			(size 0.450088 0.450088)
			(layers "F.Cu" "F.Mask" "F.Paste")
			(net "Net_1880")
		)
		(pad "DJ53" smd circle
			(at 13.480034 36.809934 180)
			(size 0.450088 0.450088)
			(layers "F.Cu" "F.Mask" "F.Paste")
			(net "CLK_100M_CPU0_CLK13_R_DP")
		)
		(pad "DJ54" smd circle
			(at 14.420088 36.809934 180)
			(size 0.450088 0.450088)
			(layers "F.Cu" "F.Mask" "F.Paste")
			(net "CLK_100M_CPU0_CLK13_R_DN")
		)
		(pad "DJ55" smd circle
			(at 15.359888 36.809934 180)
			(size 0.450088 0.450088)
			(layers "F.Cu" "F.Mask" "F.Paste")
			(net "CPU0_SA0")
		)
		(pad "DJ56" smd circle
			(at 16.299942 36.809934 180)
			(size 0.450088 0.450088)
			(layers "F.Cu" "F.Mask" "F.Paste")
			(net "CPU0_SA1")
		)
		(pad "DJ57" smd circle
			(at 17.239996 36.809934 180)
			(size 0.450088 0.450088)
			(layers "F.Cu" "F.Mask" "F.Paste")
			(net "Net_1955")
		)
		(pad "DJ59" smd circle
			(at 19.120104 36.809934 180)
			(size 0.450088 0.450088)
			(layers "F.Cu" "F.Mask" "F.Paste")
			(net "GND")
		)
		(pad "DJ60" smd circle
			(at 20.059904 36.809934 180)
			(size 0.450088 0.450088)
			(layers "F.Cu" "F.Mask" "F.Paste")
			(net "USB2_CPU0_P11_DN")
		)
		(pad "DJ61" smd circle
			(at 20.999958 36.809934 180)
			(size 0.450088 0.450088)
			(layers "F.Cu" "F.Mask" "F.Paste")
			(net "GND")
		)
		(pad "DJ62" smd circle
			(at 21.940012 36.809934 180)
			(size 0.450088 0.450088)
			(layers "F.Cu" "F.Mask" "F.Paste")
			(net "Net_1895")
		)
		(pad "DJ63" smd circle
			(at 22.880066 36.809934 180)
			(size 0.450088 0.450088)
			(layers "F.Cu" "F.Mask" "F.Paste")
			(net "GND")
		)
		(pad "DJ65" smd circle
			(at 24.75992 36.809934 180)
			(size 0.450088 0.450088)
			(layers "F.Cu" "F.Mask" "F.Paste")
			(net "Net_1890")
		)
		(pad "DJ66" smd circle
			(at 25.699974 36.809934 180)
			(size 0.450088 0.450088)
			(layers "F.Cu" "F.Mask" "F.Paste")
			(net "GND")
		)
		(pad "DJ67" smd circle
			(at 26.640028 36.809934 180)
			(size 0.450088 0.450088)
			(layers "F.Cu" "F.Mask" "F.Paste")
			(net "USB2_CPU0_P10_DP")
		)
		(pad "DJ68" smd circle
			(at 27.580082 36.809934 180)
			(size 0.450088 0.450088)
			(layers "F.Cu" "F.Mask" "F.Paste")
			(net "GND")
		)
		(pad "DJ69" smd circle
			(at 28.519882 36.809934 180)
			(size 0.450088 0.450088)
			(layers "F.Cu" "F.Mask" "F.Paste")
			(net "Net_1891")
		)
		(pad "DJ71" smd circle
			(at 30.39999 36.809934 180)
			(size 0.450088 0.450088)
			(layers "F.Cu" "F.Mask" "F.Paste")
			(net "SMB_APML_CPU0_SCL")
		)
		(pad "DJ72" smd circle
			(at 31.340044 36.809934 180)
			(size 0.450088 0.450088)
			(layers "F.Cu" "F.Mask" "F.Paste")
			(net "SVID_PVDDCR_CPU1_P0_SVC")
		)
		(pad "DJ73" smd circle
			(at 32.280098 36.809934 180)
			(size 0.450088 0.450088)
			(layers "F.Cu" "F.Mask" "F.Paste")
			(net "GND")
		)
		(pad "E1" smd circle
			(at -34.159952 -33.56991 180)
			(size 0.450088 0.450088)
			(layers "F.Cu" "F.Mask" "F.Paste")
			(net "GND")
		)
		(pad "E2" smd circle
			(at -33.219898 -33.56991 180)
			(size 0.450088 0.450088)
			(layers "F.Cu" "F.Mask" "F.Paste")
			(net "M_G_CPU0_SA_DQ<0>")
		)
		(pad "E3" smd circle
			(at -32.280098 -33.56991 180)
			(size 0.450088 0.450088)
			(layers "F.Cu" "F.Mask" "F.Paste")
			(net "GND")
		)
		(pad "E4" smd circle
			(at -31.340044 -33.56991 180)
			(size 0.450088 0.450088)
			(layers "F.Cu" "F.Mask" "F.Paste")
			(net "PVDDCR_SOC_P0")
		)
		(pad "E5" smd circle
			(at -30.39999 -33.56991 180)
			(size 0.450088 0.450088)
			(layers "F.Cu" "F.Mask" "F.Paste")
			(net "M_K_CPU0_SA_DQ<0>")
		)
		(pad "E6" smd circle
			(at -29.459936 -33.56991 180)
			(size 0.450088 0.450088)
			(layers "F.Cu" "F.Mask" "F.Paste")
			(net "GND")
		)
		(pad "E7" smd circle
			(at -28.519882 -33.56991 180)
			(size 0.450088 0.450088)
			(layers "F.Cu" "F.Mask" "F.Paste")
			(net "GND")
		)
		(pad "E8" smd circle
			(at -27.580082 -33.56991 180)
			(size 0.450088 0.450088)
			(layers "F.Cu" "F.Mask" "F.Paste")
			(net "GND")
		)
		(pad "E9" smd circle
			(at -26.640028 -33.56991 180)
			(size 0.450088 0.450088)
			(layers "F.Cu" "F.Mask" "F.Paste")
			(net "M_L_CPU0_SA_DQ<0>")
		)
		(pad "E10" smd circle
			(at -25.699974 -33.56991 180)
			(size 0.450088 0.450088)
			(layers "F.Cu" "F.Mask" "F.Paste")
			(net "GND")
		)
		(pad "E11" smd circle
			(at -24.75992 -33.56991 180)
			(size 0.450088 0.450088)
			(layers "F.Cu" "F.Mask" "F.Paste")
			(net "PVDDCR_SOC_P0")
		)
		(pad "E12" smd circle
			(at -23.82012 -33.56991 180)
			(size 0.450088 0.450088)
			(layers "F.Cu" "F.Mask" "F.Paste")
			(net "M_H_CPU0_SA_DQ<0>")
		)
		(pad "E13" smd circle
			(at -22.880066 -33.56991 180)
			(size 0.450088 0.450088)
			(layers "F.Cu" "F.Mask" "F.Paste")
			(net "GND")
		)
		(pad "E14" smd circle
			(at -21.940012 -33.56991 180)
			(size 0.450088 0.450088)
			(layers "F.Cu" "F.Mask" "F.Paste")
			(net "GND")
		)
		(pad "E15" smd circle
			(at -20.999958 -33.56991 180)
			(size 0.450088 0.450088)
			(layers "F.Cu" "F.Mask" "F.Paste")
			(net "GND")
		)
		(pad "E16" smd circle
			(at -20.059904 -33.56991 180)
			(size 0.450088 0.450088)
			(layers "F.Cu" "F.Mask" "F.Paste")
			(net "M_J_CPU0_SA_DQ<0>")
		)
		(pad "E17" smd circle
			(at -19.120104 -33.56991 180)
			(size 0.450088 0.450088)
			(layers "F.Cu" "F.Mask" "F.Paste")
			(net "GND")
		)
		(pad "E18" smd circle
			(at -18.18005 -33.56991 180)
			(size 0.450088 0.450088)
			(layers "F.Cu" "F.Mask" "F.Paste")
			(net "GND")
		)
		(pad "E19" smd circle
			(at -17.239996 -33.56991 180)
			(size 0.450088 0.450088)
			(layers "F.Cu" "F.Mask" "F.Paste")
			(net "M_I_CPU0_SA_DQ<0>")
		)
		(pad "E20" smd circle
			(at -16.299942 -33.56991 180)
			(size 0.450088 0.450088)
			(layers "F.Cu" "F.Mask" "F.Paste")
			(net "GND")
		)
		(pad "E21" smd circle
			(at -15.359888 -33.56991 180)
			(size 0.450088 0.450088)
			(layers "F.Cu" "F.Mask" "F.Paste")
			(net "GND")
		)
		(pad "E22" smd circle
			(at -14.420088 -33.56991 180)
			(size 0.450088 0.450088)
			(layers "F.Cu" "F.Mask" "F.Paste")
			(net "PVDDCR_CPU0_P0")
		)
		(pad "E23" smd circle
			(at -13.480034 -33.56991 180)
			(size 0.450088 0.450088)
			(layers "F.Cu" "F.Mask" "F.Paste")
			(net "SCM_USB_OC_BUF_N")
		)
		(pad "E24" smd circle
			(at -12.53998 -33.56991 180)
			(size 0.450088 0.450088)
			(layers "F.Cu" "F.Mask" "F.Paste")
			(net "Net_1883")
		)
		(pad "E25" smd circle
			(at -11.599926 -33.56991 180)
			(size 0.450088 0.450088)
			(layers "F.Cu" "F.Mask" "F.Paste")
			(net "PVDDCR_CPU0_P0")
		)
		(pad "E26" smd circle
			(at -10.659872 -33.56991 180)
			(size 0.450088 0.450088)
			(layers "F.Cu" "F.Mask" "F.Paste")
			(net "USB3_CPU0_BMC_RX_HUB_C_DN")
		)
		(pad "E27" smd circle
			(at -9.720072 -33.56991 180)
			(size 0.450088 0.450088)
			(layers "F.Cu" "F.Mask" "F.Paste")
			(net "USB3_CPU0_BMC_RX_HUB_C_DP")
		)
		(pad "E28" smd circle
			(at -8.780018 -33.56991 180)
			(size 0.450088 0.450088)
			(layers "F.Cu" "F.Mask" "F.Paste")
			(net "PVDDCR_CPU0_P0")
		)
		(pad "E29" smd circle
			(at -7.839964 -33.56991 180)
			(size 0.450088 0.450088)
			(layers "F.Cu" "F.Mask" "F.Paste")
			(net "Net_1886")
		)
		(pad "E30" smd circle
			(at -6.89991 -33.56991 180)
			(size 0.450088 0.450088)
			(layers "F.Cu" "F.Mask" "F.Paste")
			(net "Net_1887")
		)
		(pad "E31" smd circle
			(at -5.96011 -33.56991 180)
			(size 0.450088 0.450088)
			(layers "F.Cu" "F.Mask" "F.Paste")
			(net "PVDDCR_CPU0_P0")
		)
		(pad "E32" smd circle
			(at -5.020056 -33.56991 180)
			(size 0.450088 0.450088)
			(layers "F.Cu" "F.Mask" "F.Paste")
			(net "TP_CPU0_TEST47_CCD3")
		)
		(pad "E33" smd circle
			(at -4.080002 -33.56991 180)
			(size 0.450088 0.450088)
			(layers "F.Cu" "F.Mask" "F.Paste")
			(net "Net_1944")
		)
		(pad "E34" smd circle
			(at -3.139948 -33.56991 180)
			(size 0.450088 0.450088)
			(layers "F.Cu" "F.Mask" "F.Paste")
			(net "PVDDCR_CPU0_P0")
		)
		(pad "E35" smd circle
			(at -2.199894 -33.56991 180)
			(size 0.450088 0.450088)
			(layers "F.Cu" "F.Mask" "F.Paste")
			(net "PVDDCR_CPU0_P0")
		)
		(pad "E36" smd circle
			(at -1.260094 -33.56991 180)
			(size 0.450088 0.450088)
			(layers "F.Cu" "F.Mask" "F.Paste")
			(net "Net_1945")
		)
		(pad "E40" smd circle
			(at 1.560068 -33.56991 180)
			(size 0.450088 0.450088)
			(layers "F.Cu" "F.Mask" "F.Paste")
			(net "Net_1868")
		)
		(pad "E41" smd circle
			(at 2.500122 -33.56991 180)
			(size 0.450088 0.450088)
			(layers "F.Cu" "F.Mask" "F.Paste")
			(net "Net_1867")
		)
		(pad "E42" smd circle
			(at 3.439922 -33.56991 180)
			(size 0.450088 0.450088)
			(layers "F.Cu" "F.Mask" "F.Paste")
			(net "PVDDCR_CPU0_P0")
		)
		(pad "E43" smd circle
			(at 4.379976 -33.56991 180)
			(size 0.450088 0.450088)
			(layers "F.Cu" "F.Mask" "F.Paste")
			(net "P2E_CPU0_P5_RX_DP")
		)
		(pad "E44" smd circle
			(at 5.32003 -33.56991 180)
			(size 0.450088 0.450088)
			(layers "F.Cu" "F.Mask" "F.Paste")
			(net "P2E_CPU0_P5_RX_DN")
		)
		(pad "E45" smd circle
			(at 6.260084 -33.56991 180)
			(size 0.450088 0.450088)
			(layers "F.Cu" "F.Mask" "F.Paste")
			(net "PVDDCR_CPU0_P0")
		)
		(pad "E46" smd circle
			(at 7.199884 -33.56991 180)
			(size 0.450088 0.450088)
			(layers "F.Cu" "F.Mask" "F.Paste")
			(net "Net_1872")
		)
		(pad "E47" smd circle
			(at 8.139938 -33.56991 180)
			(size 0.450088 0.450088)
			(layers "F.Cu" "F.Mask" "F.Paste")
			(net "Net_1871")
		)
		(pad "E48" smd circle
			(at 9.079992 -33.56991 180)
			(size 0.450088 0.450088)
			(layers "F.Cu" "F.Mask" "F.Paste")
			(net "PVDDCR_CPU0_P0")
		)
		(pad "E49" smd circle
			(at 10.020046 -33.56991 180)
			(size 0.450088 0.450088)
			(layers "F.Cu" "F.Mask" "F.Paste")
			(net "WAFL_CPU1_TX1_CPU0_RX0_DP")
		)
		(pad "E50" smd circle
			(at 10.9601 -33.56991 180)
			(size 0.450088 0.450088)
			(layers "F.Cu" "F.Mask" "F.Paste")
			(net "WAFL_CPU1_TX1_CPU0_RX0_DN")
		)
		(pad "E51" smd circle
			(at 11.8999 -33.56991 180)
			(size 0.450088 0.450088)
			(layers "F.Cu" "F.Mask" "F.Paste")
			(net "PVDDCR_CPU0_P0")
		)
		(pad "E52" smd circle
			(at 12.839954 -33.56991 180)
			(size 0.450088 0.450088)
			(layers "F.Cu" "F.Mask" "F.Paste")
			(net "GND")
		)
		(pad "E53" smd circle
			(at 13.780008 -33.56991 180)
			(size 0.450088 0.450088)
			(layers "F.Cu" "F.Mask" "F.Paste")
			(net "GND")
		)
		(pad "E54" smd circle
			(at 14.720062 -33.56991 180)
			(size 0.450088 0.450088)
			(layers "F.Cu" "F.Mask" "F.Paste")
			(net "PVDDCR_CPU0_P0")
		)
		(pad "E55" smd circle
			(at 15.660116 -33.56991 180)
			(size 0.450088 0.450088)
			(layers "F.Cu" "F.Mask" "F.Paste")
			(net "GND")
		)
		(pad "E56" smd circle
			(at 16.599916 -33.56991 180)
			(size 0.450088 0.450088)
			(layers "F.Cu" "F.Mask" "F.Paste")
			(net "GND")
		)
		(pad "E57" smd circle
			(at 17.53997 -33.56991 180)
			(size 0.450088 0.450088)
			(layers "F.Cu" "F.Mask" "F.Paste")
			(net "M_C_CPU0_SA_DQ<0>")
		)
		(pad "E58" smd circle
			(at 18.480024 -33.56991 180)
			(size 0.450088 0.450088)
			(layers "F.Cu" "F.Mask" "F.Paste")
			(net "GND")
		)
		(pad "E59" smd circle
			(at 19.420078 -33.56991 180)
			(size 0.450088 0.450088)
			(layers "F.Cu" "F.Mask" "F.Paste")
			(net "GND")
		)
		(pad "E60" smd circle
			(at 20.359878 -33.56991 180)
			(size 0.450088 0.450088)
			(layers "F.Cu" "F.Mask" "F.Paste")
			(net "M_D_CPU0_SA_DQ<0>")
		)
		(pad "E61" smd circle
			(at 21.299932 -33.56991 180)
			(size 0.450088 0.450088)
			(layers "F.Cu" "F.Mask" "F.Paste")
			(net "GND")
		)
		(pad "E62" smd circle
			(at 22.239986 -33.56991 180)
			(size 0.450088 0.450088)
			(layers "F.Cu" "F.Mask" "F.Paste")
			(net "GND")
		)
		(pad "E63" smd circle
			(at 23.18004 -33.56991 180)
			(size 0.450088 0.450088)
			(layers "F.Cu" "F.Mask" "F.Paste")
			(net "GND")
		)
		(pad "E64" smd circle
			(at 24.120094 -33.56991 180)
			(size 0.450088 0.450088)
			(layers "F.Cu" "F.Mask" "F.Paste")
			(net "M_B_CPU0_SA_DQ<0>")
		)
		(pad "E65" smd circle
			(at 25.059894 -33.56991 180)
			(size 0.450088 0.450088)
			(layers "F.Cu" "F.Mask" "F.Paste")
			(net "GND")
		)
		(pad "E66" smd circle
			(at 25.999948 -33.56991 180)
			(size 0.450088 0.450088)
			(layers "F.Cu" "F.Mask" "F.Paste")
			(net "GND")
		)
		(pad "E67" smd circle
			(at 26.940002 -33.56991 180)
			(size 0.450088 0.450088)
			(layers "F.Cu" "F.Mask" "F.Paste")
			(net "M_F_CPU0_SA_DQ<0>")
		)
		(pad "E68" smd circle
			(at 27.880056 -33.56991 180)
			(size 0.450088 0.450088)
			(layers "F.Cu" "F.Mask" "F.Paste")
			(net "GND")
		)
		(pad "E69" smd circle
			(at 28.82011 -33.56991 180)
			(size 0.450088 0.450088)
			(layers "F.Cu" "F.Mask" "F.Paste")
			(net "GND")
		)
		(pad "E70" smd circle
			(at 29.75991 -33.56991 180)
			(size 0.450088 0.450088)
			(layers "F.Cu" "F.Mask" "F.Paste")
			(net "GND")
		)
		(pad "E71" smd circle
			(at 30.699964 -33.56991 180)
			(size 0.450088 0.450088)
			(layers "F.Cu" "F.Mask" "F.Paste")
			(net "M_E_CPU0_SA_DQ<0>")
		)
		(pad "E72" smd circle
			(at 31.640018 -33.56991 180)
			(size 0.450088 0.450088)
			(layers "F.Cu" "F.Mask" "F.Paste")
			(net "GND")
		)
		(pad "E73" smd circle
			(at 32.580072 -33.56991 180)
			(size 0.450088 0.450088)
			(layers "F.Cu" "F.Mask" "F.Paste")
			(net "GND")
		)
		(pad "E74" smd circle
			(at 33.519872 -33.56991 180)
			(size 0.450088 0.450088)
			(layers "F.Cu" "F.Mask" "F.Paste")
			(net "M_A_CPU0_SA_DQ<0>")
		)
		(pad "E75" smd circle
			(at 34.459926 -33.56991 180)
			(size 0.450088 0.450088)
			(layers "F.Cu" "F.Mask" "F.Paste")
			(net "GND")
		)
		(pad "F2" smd circle
			(at -33.690052 -32.759904 180)
			(size 0.450088 0.450088)
			(layers "F.Cu" "F.Mask" "F.Paste")
			(net "M_G_CPU0_SA_DQ<2>")
		)
		(pad "F3" smd circle
			(at -32.749998 -32.759904 180)
			(size 0.450088 0.450088)
			(layers "F.Cu" "F.Mask" "F.Paste")
			(net "GND")
		)
		(pad "F4" smd circle
			(at -31.809944 -32.759904 180)
			(size 0.450088 0.450088)
			(layers "F.Cu" "F.Mask" "F.Paste")
			(net "M_G_CPU0_SA_DQ<1>")
		)
		(pad "F5" smd circle
			(at -30.86989 -32.759904 180)
			(size 0.450088 0.450088)
			(layers "F.Cu" "F.Mask" "F.Paste")
			(net "GND")
		)
		(pad "F6" smd circle
			(at -29.93009 -32.759904 180)
			(size 0.450088 0.450088)
			(layers "F.Cu" "F.Mask" "F.Paste")
			(net "M_K_CPU0_SA_DQ<2>")
		)
		(pad "F7" smd circle
			(at -28.990036 -32.759904 180)
			(size 0.450088 0.450088)
			(layers "F.Cu" "F.Mask" "F.Paste")
			(net "M_K_CPU0_SA_DQ<1>")
		)
		(pad "F8" smd circle
			(at -28.049982 -32.759904 180)
			(size 0.450088 0.450088)
			(layers "F.Cu" "F.Mask" "F.Paste")
			(net "GND")
		)
		(pad "F9" smd circle
			(at -27.109928 -32.759904 180)
			(size 0.450088 0.450088)
			(layers "F.Cu" "F.Mask" "F.Paste")
			(net "M_L_CPU0_SA_DQ<2>")
		)
		(pad "F10" smd circle
			(at -26.170128 -32.759904 180)
			(size 0.450088 0.450088)
			(layers "F.Cu" "F.Mask" "F.Paste")
			(net "GND")
		)
		(pad "F11" smd circle
			(at -25.230074 -32.759904 180)
			(size 0.450088 0.450088)
			(layers "F.Cu" "F.Mask" "F.Paste")
			(net "M_L_CPU0_SA_DQ<1>")
		)
		(pad "F12" smd circle
			(at -24.29002 -32.759904 180)
			(size 0.450088 0.450088)
			(layers "F.Cu" "F.Mask" "F.Paste")
			(net "GND")
		)
		(pad "F13" smd circle
			(at -23.349966 -32.759904 180)
			(size 0.450088 0.450088)
			(layers "F.Cu" "F.Mask" "F.Paste")
			(net "M_H_CPU0_SA_DQ<2>")
		)
		(pad "F14" smd circle
			(at -22.409912 -32.759904 180)
			(size 0.450088 0.450088)
			(layers "F.Cu" "F.Mask" "F.Paste")
			(net "M_H_CPU0_SA_DQ<1>")
		)
		(pad "F15" smd circle
			(at -21.470112 -32.759904 180)
			(size 0.450088 0.450088)
			(layers "F.Cu" "F.Mask" "F.Paste")
			(net "GND")
		)
		(pad "F16" smd circle
			(at -20.530058 -32.759904 180)
			(size 0.450088 0.450088)
			(layers "F.Cu" "F.Mask" "F.Paste")
			(net "M_J_CPU0_SA_DQ<2>")
		)
		(pad "F17" smd circle
			(at -19.590004 -32.759904 180)
			(size 0.450088 0.450088)
			(layers "F.Cu" "F.Mask" "F.Paste")
			(net "GND")
		)
		(pad "F18" smd circle
			(at -18.64995 -32.759904 180)
			(size 0.450088 0.450088)
			(layers "F.Cu" "F.Mask" "F.Paste")
			(net "M_J_CPU0_SA_DQ<1>")
		)
		(pad "F19" smd circle
			(at -17.709896 -32.759904 180)
			(size 0.450088 0.450088)
			(layers "F.Cu" "F.Mask" "F.Paste")
			(net "GND")
		)
		(pad "F20" smd circle
			(at -16.770096 -32.759904 180)
			(size 0.450088 0.450088)
			(layers "F.Cu" "F.Mask" "F.Paste")
			(net "M_I_CPU0_SA_DQ<2>")
		)
		(pad "F21" smd circle
			(at -15.830042 -32.759904 180)
			(size 0.450088 0.450088)
			(layers "F.Cu" "F.Mask" "F.Paste")
			(net "M_I_CPU0_SA_DQ<1>")
		)
		(pad "F22" smd circle
			(at -14.889988 -32.759904 180)
			(size 0.450088 0.450088)
			(layers "F.Cu" "F.Mask" "F.Paste")
			(net "PVDDCR_CPU0_P0")
		)
		(pad "F23" smd circle
			(at -13.949934 -32.759904 180)
			(size 0.450088 0.450088)
			(layers "F.Cu" "F.Mask" "F.Paste")
			(net "GND")
		)
		(pad "F24" smd circle
			(at -13.00988 -32.759904 180)
			(size 0.450088 0.450088)
			(layers "F.Cu" "F.Mask" "F.Paste")
			(net "GND")
		)
		(pad "F25" smd circle
			(at -12.07008 -32.759904 180)
			(size 0.450088 0.450088)
			(layers "F.Cu" "F.Mask" "F.Paste")
			(net "PVDDCR_CPU0_P0")
		)
		(pad "F26" smd circle
			(at -11.130026 -32.759904 180)
			(size 0.450088 0.450088)
			(layers "F.Cu" "F.Mask" "F.Paste")
			(net "GND")
		)
		(pad "F27" smd circle
			(at -10.189972 -32.759904 180)
			(size 0.450088 0.450088)
			(layers "F.Cu" "F.Mask" "F.Paste")
			(net "GND")
		)
		(pad "F28" smd circle
			(at -9.249918 -32.759904 180)
			(size 0.450088 0.450088)
			(layers "F.Cu" "F.Mask" "F.Paste")
			(net "PVDDCR_CPU0_P0")
		)
		(pad "F29" smd circle
			(at -8.310118 -32.759904 180)
			(size 0.450088 0.450088)
			(layers "F.Cu" "F.Mask" "F.Paste")
			(net "GND")
		)
		(pad "F30" smd circle
			(at -7.370064 -32.759904 180)
			(size 0.450088 0.450088)
			(layers "F.Cu" "F.Mask" "F.Paste")
			(net "GND")
		)
		(pad "F31" smd circle
			(at -6.43001 -32.759904 180)
			(size 0.450088 0.450088)
			(layers "F.Cu" "F.Mask" "F.Paste")
			(net "PVDDCR_CPU0_P0")
		)
		(pad "F32" smd circle
			(at -5.489956 -32.759904 180)
			(size 0.450088 0.450088)
			(layers "F.Cu" "F.Mask" "F.Paste")
			(net "GND")
		)
		(pad "F33" smd circle
			(at -4.549902 -32.759904 180)
			(size 0.450088 0.450088)
			(layers "F.Cu" "F.Mask" "F.Paste")
			(net "GND")
		)
		(pad "F34" smd circle
			(at -3.610102 -32.759904 180)
			(size 0.450088 0.450088)
			(layers "F.Cu" "F.Mask" "F.Paste")
			(net "PVDDCR_CPU0_P0")
		)
		(pad "F35" smd circle
			(at -2.670048 -32.759904 180)
			(size 0.450088 0.450088)
			(layers "F.Cu" "F.Mask" "F.Paste")
			(net "GND")
		)
		(pad "F36" smd circle
			(at -1.729994 -32.759904 180)
			(size 0.450088 0.450088)
			(layers "F.Cu" "F.Mask" "F.Paste")
			(net "GND")
		)
		(pad "F37" smd circle
			(at -0.78994 -32.759904 180)
			(size 0.450088 0.450088)
			(layers "F.Cu" "F.Mask" "F.Paste")
			(net "GND")
		)
		(pad "F39" smd circle
			(at 1.089914 -32.759904 180)
			(size 0.450088 0.450088)
			(layers "F.Cu" "F.Mask" "F.Paste")
			(net "GND")
		)
		(pad "F40" smd circle
			(at 2.029968 -32.759904 180)
			(size 0.450088 0.450088)
			(layers "F.Cu" "F.Mask" "F.Paste")
			(net "GND")
		)
		(pad "F41" smd circle
			(at 2.970022 -32.759904 180)
			(size 0.450088 0.450088)
			(layers "F.Cu" "F.Mask" "F.Paste")
			(net "GND")
		)
		(pad "F42" smd circle
			(at 3.910076 -32.759904 180)
			(size 0.450088 0.450088)
			(layers "F.Cu" "F.Mask" "F.Paste")
			(net "PVDDCR_CPU0_P0")
		)
		(pad "F43" smd circle
			(at 4.849876 -32.759904 180)
			(size 0.450088 0.450088)
			(layers "F.Cu" "F.Mask" "F.Paste")
			(net "GND")
		)
		(pad "F44" smd circle
			(at 5.78993 -32.759904 180)
			(size 0.450088 0.450088)
			(layers "F.Cu" "F.Mask" "F.Paste")
			(net "GND")
		)
		(pad "F45" smd circle
			(at 6.729984 -32.759904 180)
			(size 0.450088 0.450088)
			(layers "F.Cu" "F.Mask" "F.Paste")
			(net "PVDDCR_CPU0_P0")
		)
		(pad "F46" smd circle
			(at 7.670038 -32.759904 180)
			(size 0.450088 0.450088)
			(layers "F.Cu" "F.Mask" "F.Paste")
			(net "GND")
		)
		(pad "F47" smd circle
			(at 8.610092 -32.759904 180)
			(size 0.450088 0.450088)
			(layers "F.Cu" "F.Mask" "F.Paste")
			(net "GND")
		)
		(pad "F48" smd circle
			(at 9.549892 -32.759904 180)
			(size 0.450088 0.450088)
			(layers "F.Cu" "F.Mask" "F.Paste")
			(net "PVDDCR_CPU0_P0")
		)
		(pad "F49" smd circle
			(at 10.489946 -32.759904 180)
			(size 0.450088 0.450088)
			(layers "F.Cu" "F.Mask" "F.Paste")
			(net "GND")
		)
		(pad "F50" smd circle
			(at 11.43 -32.759904 180)
			(size 0.450088 0.450088)
			(layers "F.Cu" "F.Mask" "F.Paste")
			(net "GND")
		)
		(pad "F51" smd circle
			(at 12.370054 -32.759904 180)
			(size 0.450088 0.450088)
			(layers "F.Cu" "F.Mask" "F.Paste")
			(net "PVDDCR_CPU0_P0")
		)
		(pad "F52" smd circle
			(at 13.310108 -32.759904 180)
			(size 0.450088 0.450088)
			(layers "F.Cu" "F.Mask" "F.Paste")
			(net "GND")
		)
		(pad "F53" smd circle
			(at 14.249908 -32.759904 180)
			(size 0.450088 0.450088)
			(layers "F.Cu" "F.Mask" "F.Paste")
			(net "GND")
		)
		(pad "F54" smd circle
			(at 15.189962 -32.759904 180)
			(size 0.450088 0.450088)
			(layers "F.Cu" "F.Mask" "F.Paste")
			(net "PVDDCR_CPU0_P0")
		)
		(pad "F55" smd circle
			(at 16.130016 -32.759904 180)
			(size 0.450088 0.450088)
			(layers "F.Cu" "F.Mask" "F.Paste")
			(net "M_C_CPU0_SA_DQ<1>")
		)
		(pad "F56" smd circle
			(at 17.07007 -32.759904 180)
			(size 0.450088 0.450088)
			(layers "F.Cu" "F.Mask" "F.Paste")
			(net "M_C_CPU0_SA_DQ<2>")
		)
		(pad "F57" smd circle
			(at 18.010124 -32.759904 180)
			(size 0.450088 0.450088)
			(layers "F.Cu" "F.Mask" "F.Paste")
			(net "GND")
		)
		(pad "F58" smd circle
			(at 18.949924 -32.759904 180)
			(size 0.450088 0.450088)
			(layers "F.Cu" "F.Mask" "F.Paste")
			(net "M_D_CPU0_SA_DQ<1>")
		)
		(pad "F59" smd circle
			(at 19.889978 -32.759904 180)
			(size 0.450088 0.450088)
			(layers "F.Cu" "F.Mask" "F.Paste")
			(net "GND")
		)
		(pad "F60" smd circle
			(at 20.830032 -32.759904 180)
			(size 0.450088 0.450088)
			(layers "F.Cu" "F.Mask" "F.Paste")
			(net "M_D_CPU0_SA_DQ<2>")
		)
		(pad "F61" smd circle
			(at 21.770086 -32.759904 180)
			(size 0.450088 0.450088)
			(layers "F.Cu" "F.Mask" "F.Paste")
			(net "GND")
		)
		(pad "F62" smd circle
			(at 22.709886 -32.759904 180)
			(size 0.450088 0.450088)
			(layers "F.Cu" "F.Mask" "F.Paste")
			(net "M_B_CPU0_SA_DQ<1>")
		)
		(pad "F63" smd circle
			(at 23.64994 -32.759904 180)
			(size 0.450088 0.450088)
			(layers "F.Cu" "F.Mask" "F.Paste")
			(net "M_B_CPU0_SA_DQ<2>")
		)
		(pad "F64" smd circle
			(at 24.589994 -32.759904 180)
			(size 0.450088 0.450088)
			(layers "F.Cu" "F.Mask" "F.Paste")
			(net "GND")
		)
		(pad "F65" smd circle
			(at 25.530048 -32.759904 180)
			(size 0.450088 0.450088)
			(layers "F.Cu" "F.Mask" "F.Paste")
			(net "M_F_CPU0_SA_DQ<1>")
		)
		(pad "F66" smd circle
			(at 26.470102 -32.759904 180)
			(size 0.450088 0.450088)
			(layers "F.Cu" "F.Mask" "F.Paste")
			(net "GND")
		)
		(pad "F67" smd circle
			(at 27.409902 -32.759904 180)
			(size 0.450088 0.450088)
			(layers "F.Cu" "F.Mask" "F.Paste")
			(net "M_F_CPU0_SA_DQ<2>")
		)
		(pad "F68" smd circle
			(at 28.349956 -32.759904 180)
			(size 0.450088 0.450088)
			(layers "F.Cu" "F.Mask" "F.Paste")
			(net "GND")
		)
		(pad "F69" smd circle
			(at 29.29001 -32.759904 180)
			(size 0.450088 0.450088)
			(layers "F.Cu" "F.Mask" "F.Paste")
			(net "M_E_CPU0_SA_DQ<1>")
		)
		(pad "F70" smd circle
			(at 30.230064 -32.759904 180)
			(size 0.450088 0.450088)
			(layers "F.Cu" "F.Mask" "F.Paste")
			(net "M_E_CPU0_SA_DQ<2>")
		)
		(pad "F71" smd circle
			(at 31.170118 -32.759904 180)
			(size 0.450088 0.450088)
			(layers "F.Cu" "F.Mask" "F.Paste")
			(net "GND")
		)
		(pad "F72" smd circle
			(at 32.109918 -32.759904 180)
			(size 0.450088 0.450088)
			(layers "F.Cu" "F.Mask" "F.Paste")
			(net "M_A_CPU0_SA_DQ<1>")
		)
		(pad "F73" smd circle
			(at 33.049972 -32.759904 180)
			(size 0.450088 0.450088)
			(layers "F.Cu" "F.Mask" "F.Paste")
			(net "GND")
		)
		(pad "F74" smd circle
			(at 33.990026 -32.759904 180)
			(size 0.450088 0.450088)
			(layers "F.Cu" "F.Mask" "F.Paste")
			(net "M_A_CPU0_SA_DQ<2>")
		)
		(pad "G1" smd circle
			(at -34.159952 -31.949898 180)
			(size 0.450088 0.450088)
			(layers "F.Cu" "F.Mask" "F.Paste")
			(net "GND")
		)
		(pad "G2" smd circle
			(at -33.219898 -31.949898 180)
			(size 0.450088 0.450088)
			(layers "F.Cu" "F.Mask" "F.Paste")
			(net "M_G_CPU0_SA_DQS_DP<0>")
		)
		(pad "G3" smd circle
			(at -32.280098 -31.949898 180)
			(size 0.450088 0.450088)
			(layers "F.Cu" "F.Mask" "F.Paste")
			(net "M_G_CPU0_SA_DQ<3>")
		)
		(pad "G4" smd circle
			(at -31.340044 -31.949898 180)
			(size 0.450088 0.450088)
			(layers "F.Cu" "F.Mask" "F.Paste")
			(net "GND")
		)
		(pad "G5" smd circle
			(at -30.39999 -31.949898 180)
			(size 0.450088 0.450088)
			(layers "F.Cu" "F.Mask" "F.Paste")
			(net "M_K_CPU0_SA_DQS_DP<0>")
		)
		(pad "G6" smd circle
			(at -29.459936 -31.949898 180)
			(size 0.450088 0.450088)
			(layers "F.Cu" "F.Mask" "F.Paste")
			(net "GND")
		)
		(pad "G7" smd circle
			(at -28.519882 -31.949898 180)
			(size 0.450088 0.450088)
			(layers "F.Cu" "F.Mask" "F.Paste")
			(net "M_K_CPU0_SA_DQ<3>")
		)
		(pad "G8" smd circle
			(at -27.580082 -31.949898 180)
			(size 0.450088 0.450088)
			(layers "F.Cu" "F.Mask" "F.Paste")
			(net "GND")
		)
		(pad "G9" smd circle
			(at -26.640028 -31.949898 180)
			(size 0.450088 0.450088)
			(layers "F.Cu" "F.Mask" "F.Paste")
			(net "M_L_CPU0_SA_DQS_DP<0>")
		)
		(pad "G10" smd circle
			(at -25.699974 -31.949898 180)
			(size 0.450088 0.450088)
			(layers "F.Cu" "F.Mask" "F.Paste")
			(net "M_L_CPU0_SA_DQ<3>")
		)
		(pad "G11" smd circle
			(at -24.75992 -31.949898 180)
			(size 0.450088 0.450088)
			(layers "F.Cu" "F.Mask" "F.Paste")
			(net "GND")
		)
		(pad "G12" smd circle
			(at -23.82012 -31.949898 180)
			(size 0.450088 0.450088)
			(layers "F.Cu" "F.Mask" "F.Paste")
			(net "M_H_CPU0_SA_DQS_DP<0>")
		)
		(pad "G13" smd circle
			(at -22.880066 -31.949898 180)
			(size 0.450088 0.450088)
			(layers "F.Cu" "F.Mask" "F.Paste")
			(net "GND")
		)
		(pad "G14" smd circle
			(at -21.940012 -31.949898 180)
			(size 0.450088 0.450088)
			(layers "F.Cu" "F.Mask" "F.Paste")
			(net "M_H_CPU0_SA_DQ<3>")
		)
		(pad "G15" smd circle
			(at -20.999958 -31.949898 180)
			(size 0.450088 0.450088)
			(layers "F.Cu" "F.Mask" "F.Paste")
			(net "GND")
		)
		(pad "G16" smd circle
			(at -20.059904 -31.949898 180)
			(size 0.450088 0.450088)
			(layers "F.Cu" "F.Mask" "F.Paste")
			(net "M_J_CPU0_SA_DQS_DP<0>")
		)
		(pad "G17" smd circle
			(at -19.120104 -31.949898 180)
			(size 0.450088 0.450088)
			(layers "F.Cu" "F.Mask" "F.Paste")
			(net "M_J_CPU0_SA_DQ<3>")
		)
		(pad "G18" smd circle
			(at -18.18005 -31.949898 180)
			(size 0.450088 0.450088)
			(layers "F.Cu" "F.Mask" "F.Paste")
			(net "GND")
		)
		(pad "G19" smd circle
			(at -17.239996 -31.949898 180)
			(size 0.450088 0.450088)
			(layers "F.Cu" "F.Mask" "F.Paste")
			(net "M_I_CPU0_SA_DQS_DP<0>")
		)
		(pad "G20" smd circle
			(at -16.299942 -31.949898 180)
			(size 0.450088 0.450088)
			(layers "F.Cu" "F.Mask" "F.Paste")
			(net "GND")
		)
		(pad "G21" smd circle
			(at -15.359888 -31.949898 180)
			(size 0.450088 0.450088)
			(layers "F.Cu" "F.Mask" "F.Paste")
			(net "M_I_CPU0_SA_DQ<3>")
		)
		(pad "G22" smd circle
			(at -14.420088 -31.949898 180)
			(size 0.450088 0.450088)
			(layers "F.Cu" "F.Mask" "F.Paste")
			(net "GND")
		)
		(pad "G23" smd circle
			(at -13.480034 -31.949898 180)
			(size 0.450088 0.450088)
			(layers "F.Cu" "F.Mask" "F.Paste")
			(net "GMI_CPU0_G2_CPU1_G0_TX_DP<2>")
		)
		(pad "G24" smd circle
			(at -12.53998 -31.949898 180)
			(size 0.450088 0.450088)
			(layers "F.Cu" "F.Mask" "F.Paste")
			(net "GMI_CPU0_G2_CPU1_G0_TX_DN<2>")
		)
		(pad "G25" smd circle
			(at -11.599926 -31.949898 180)
			(size 0.450088 0.450088)
			(layers "F.Cu" "F.Mask" "F.Paste")
			(net "GND")
		)
		(pad "G26" smd circle
			(at -10.659872 -31.949898 180)
			(size 0.450088 0.450088)
			(layers "F.Cu" "F.Mask" "F.Paste")
			(net "GMI_CPU0_G2_CPU1_G0_TX_DP<5>")
		)
		(pad "G27" smd circle
			(at -9.720072 -31.949898 180)
			(size 0.450088 0.450088)
			(layers "F.Cu" "F.Mask" "F.Paste")
			(net "GMI_CPU0_G2_CPU1_G0_TX_DN<5>")
		)
		(pad "G28" smd circle
			(at -8.780018 -31.949898 180)
			(size 0.450088 0.450088)
			(layers "F.Cu" "F.Mask" "F.Paste")
			(net "GND")
		)
		(pad "G29" smd circle
			(at -7.839964 -31.949898 180)
			(size 0.450088 0.450088)
			(layers "F.Cu" "F.Mask" "F.Paste")
			(net "GMI_CPU0_G2_CPU1_G0_TX_DP<8>")
		)
		(pad "G30" smd circle
			(at -6.89991 -31.949898 180)
			(size 0.450088 0.450088)
			(layers "F.Cu" "F.Mask" "F.Paste")
			(net "GMI_CPU0_G2_CPU1_G0_TX_DN<8>")
		)
		(pad "G31" smd circle
			(at -5.96011 -31.949898 180)
			(size 0.450088 0.450088)
			(layers "F.Cu" "F.Mask" "F.Paste")
			(net "GND")
		)
		(pad "G32" smd circle
			(at -5.020056 -31.949898 180)
			(size 0.450088 0.450088)
			(layers "F.Cu" "F.Mask" "F.Paste")
			(net "GMI_CPU0_G2_CPU1_G0_TX_DP<11>")
		)
		(pad "G33" smd circle
			(at -4.080002 -31.949898 180)
			(size 0.450088 0.450088)
			(layers "F.Cu" "F.Mask" "F.Paste")
			(net "GMI_CPU0_G2_CPU1_G0_TX_DN<11>")
		)
		(pad "G34" smd circle
			(at -3.139948 -31.949898 180)
			(size 0.450088 0.450088)
			(layers "F.Cu" "F.Mask" "F.Paste")
			(net "GND")
		)
		(pad "G35" smd circle
			(at -2.199894 -31.949898 180)
			(size 0.450088 0.450088)
			(layers "F.Cu" "F.Mask" "F.Paste")
			(net "PVDDCR_CPU0_P0")
		)
		(pad "G36" smd circle
			(at -1.260094 -31.949898 180)
			(size 0.450088 0.450088)
			(layers "F.Cu" "F.Mask" "F.Paste")
			(net "PVDDCR_CPU0_P0")
		)
		(pad "G40" smd circle
			(at 1.560068 -31.949898 180)
			(size 0.450088 0.450088)
			(layers "F.Cu" "F.Mask" "F.Paste")
			(net "PVDDCR_CPU0_P0")
		)
		(pad "G41" smd circle
			(at 2.500122 -31.949898 180)
			(size 0.450088 0.450088)
			(layers "F.Cu" "F.Mask" "F.Paste")
			(net "PVDDCR_CPU0_P0")
		)
		(pad "G42" smd circle
			(at 3.439922 -31.949898 180)
			(size 0.450088 0.450088)
			(layers "F.Cu" "F.Mask" "F.Paste")
			(net "GND")
		)
		(pad "G43" smd circle
			(at 4.379976 -31.949898 180)
			(size 0.450088 0.450088)
			(layers "F.Cu" "F.Mask" "F.Paste")
			(net "GMI_CPU1_G2_CPU0_G0_TX_DN<4>")
		)
		(pad "G44" smd circle
			(at 5.32003 -31.949898 180)
			(size 0.450088 0.450088)
			(layers "F.Cu" "F.Mask" "F.Paste")
			(net "GMI_CPU1_G2_CPU0_G0_TX_DP<4>")
		)
		(pad "G45" smd circle
			(at 6.260084 -31.949898 180)
			(size 0.450088 0.450088)
			(layers "F.Cu" "F.Mask" "F.Paste")
			(net "GND")
		)
		(pad "G46" smd circle
			(at 7.199884 -31.949898 180)
			(size 0.450088 0.450088)
			(layers "F.Cu" "F.Mask" "F.Paste")
			(net "GMI_CPU1_G2_CPU0_G0_TX_DN<7>")
		)
		(pad "G47" smd circle
			(at 8.139938 -31.949898 180)
			(size 0.450088 0.450088)
			(layers "F.Cu" "F.Mask" "F.Paste")
			(net "GMI_CPU1_G2_CPU0_G0_TX_DP<7>")
		)
		(pad "G48" smd circle
			(at 9.079992 -31.949898 180)
			(size 0.450088 0.450088)
			(layers "F.Cu" "F.Mask" "F.Paste")
			(net "GND")
		)
		(pad "G49" smd circle
			(at 10.020046 -31.949898 180)
			(size 0.450088 0.450088)
			(layers "F.Cu" "F.Mask" "F.Paste")
			(net "GMI_CPU1_G2_CPU0_G0_TX_DN<10>")
		)
		(pad "G50" smd circle
			(at 10.9601 -31.949898 180)
			(size 0.450088 0.450088)
			(layers "F.Cu" "F.Mask" "F.Paste")
			(net "GMI_CPU1_G2_CPU0_G0_TX_DP<10>")
		)
		(pad "G51" smd circle
			(at 11.8999 -31.949898 180)
			(size 0.450088 0.450088)
			(layers "F.Cu" "F.Mask" "F.Paste")
			(net "GND")
		)
		(pad "G52" smd circle
			(at 12.839954 -31.949898 180)
			(size 0.450088 0.450088)
			(layers "F.Cu" "F.Mask" "F.Paste")
			(net "GMI_CPU1_G2_CPU0_G0_TX_DN<13>")
		)
		(pad "G53" smd circle
			(at 13.780008 -31.949898 180)
			(size 0.450088 0.450088)
			(layers "F.Cu" "F.Mask" "F.Paste")
			(net "GMI_CPU1_G2_CPU0_G0_TX_DP<13>")
		)
		(pad "G54" smd circle
			(at 14.720062 -31.949898 180)
			(size 0.450088 0.450088)
			(layers "F.Cu" "F.Mask" "F.Paste")
			(net "GND")
		)
		(pad "G55" smd circle
			(at 15.660116 -31.949898 180)
			(size 0.450088 0.450088)
			(layers "F.Cu" "F.Mask" "F.Paste")
			(net "M_C_CPU0_SA_DQ<3>")
		)
		(pad "G56" smd circle
			(at 16.599916 -31.949898 180)
			(size 0.450088 0.450088)
			(layers "F.Cu" "F.Mask" "F.Paste")
			(net "GND")
		)
		(pad "G57" smd circle
			(at 17.53997 -31.949898 180)
			(size 0.450088 0.450088)
			(layers "F.Cu" "F.Mask" "F.Paste")
			(net "M_C_CPU0_SA_DQS_DP<0>")
		)
		(pad "G58" smd circle
			(at 18.480024 -31.949898 180)
			(size 0.450088 0.450088)
			(layers "F.Cu" "F.Mask" "F.Paste")
			(net "GND")
		)
		(pad "G59" smd circle
			(at 19.420078 -31.949898 180)
			(size 0.450088 0.450088)
			(layers "F.Cu" "F.Mask" "F.Paste")
			(net "M_D_CPU0_SA_DQ<3>")
		)
		(pad "G60" smd circle
			(at 20.359878 -31.949898 180)
			(size 0.450088 0.450088)
			(layers "F.Cu" "F.Mask" "F.Paste")
			(net "M_D_CPU0_SA_DQS_DP<0>")
		)
		(pad "G61" smd circle
			(at 21.299932 -31.949898 180)
			(size 0.450088 0.450088)
			(layers "F.Cu" "F.Mask" "F.Paste")
			(net "GND")
		)
		(pad "G62" smd circle
			(at 22.239986 -31.949898 180)
			(size 0.450088 0.450088)
			(layers "F.Cu" "F.Mask" "F.Paste")
			(net "M_B_CPU0_SA_DQ<3>")
		)
		(pad "G63" smd circle
			(at 23.18004 -31.949898 180)
			(size 0.450088 0.450088)
			(layers "F.Cu" "F.Mask" "F.Paste")
			(net "GND")
		)
		(pad "G64" smd circle
			(at 24.120094 -31.949898 180)
			(size 0.450088 0.450088)
			(layers "F.Cu" "F.Mask" "F.Paste")
			(net "M_B_CPU0_SA_DQS_DP<0>")
		)
		(pad "G65" smd circle
			(at 25.059894 -31.949898 180)
			(size 0.450088 0.450088)
			(layers "F.Cu" "F.Mask" "F.Paste")
			(net "GND")
		)
		(pad "G66" smd circle
			(at 25.999948 -31.949898 180)
			(size 0.450088 0.450088)
			(layers "F.Cu" "F.Mask" "F.Paste")
			(net "M_F_CPU0_SA_DQ<3>")
		)
		(pad "G67" smd circle
			(at 26.940002 -31.949898 180)
			(size 0.450088 0.450088)
			(layers "F.Cu" "F.Mask" "F.Paste")
			(net "M_F_CPU0_SA_DQS_DP<0>")
		)
		(pad "G68" smd circle
			(at 27.880056 -31.949898 180)
			(size 0.450088 0.450088)
			(layers "F.Cu" "F.Mask" "F.Paste")
			(net "GND")
		)
		(pad "G69" smd circle
			(at 28.82011 -31.949898 180)
			(size 0.450088 0.450088)
			(layers "F.Cu" "F.Mask" "F.Paste")
			(net "M_E_CPU0_SA_DQ<3>")
		)
		(pad "G70" smd circle
			(at 29.75991 -31.949898 180)
			(size 0.450088 0.450088)
			(layers "F.Cu" "F.Mask" "F.Paste")
			(net "GND")
		)
		(pad "G71" smd circle
			(at 30.699964 -31.949898 180)
			(size 0.450088 0.450088)
			(layers "F.Cu" "F.Mask" "F.Paste")
			(net "M_E_CPU0_SA_DQS_DP<0>")
		)
		(pad "G72" smd circle
			(at 31.640018 -31.949898 180)
			(size 0.450088 0.450088)
			(layers "F.Cu" "F.Mask" "F.Paste")
			(net "GND")
		)
		(pad "G73" smd circle
			(at 32.580072 -31.949898 180)
			(size 0.450088 0.450088)
			(layers "F.Cu" "F.Mask" "F.Paste")
			(net "M_A_CPU0_SA_DQ<3>")
		)
		(pad "G74" smd circle
			(at 33.519872 -31.949898 180)
			(size 0.450088 0.450088)
			(layers "F.Cu" "F.Mask" "F.Paste")
			(net "M_A_CPU0_SA_DQS_DP<0>")
		)
		(pad "G75" smd circle
			(at 34.459926 -31.949898 180)
			(size 0.450088 0.450088)
			(layers "F.Cu" "F.Mask" "F.Paste")
			(net "GND")
		)
		(pad "H2" smd circle
			(at -33.690052 -31.139892 180)
			(size 0.450088 0.450088)
			(layers "F.Cu" "F.Mask" "F.Paste")
			(net "M_G_CPU0_SA_DQS_DN<0>")
		)
		(pad "H3" smd circle
			(at -32.749998 -31.139892 180)
			(size 0.450088 0.450088)
			(layers "F.Cu" "F.Mask" "F.Paste")
			(net "GND")
		)
		(pad "H4" smd circle
			(at -31.809944 -31.139892 180)
			(size 0.450088 0.450088)
			(layers "F.Cu" "F.Mask" "F.Paste")
			(net "M_G_CPU0_SA_DQS_DN<5>")
		)
		(pad "H5" smd circle
			(at -30.86989 -31.139892 180)
			(size 0.450088 0.450088)
			(layers "F.Cu" "F.Mask" "F.Paste")
			(net "PVDDCR_SOC_P0")
		)
		(pad "H6" smd circle
			(at -29.93009 -31.139892 180)
			(size 0.450088 0.450088)
			(layers "F.Cu" "F.Mask" "F.Paste")
			(net "M_K_CPU0_SA_DQS_DN<0>")
		)
		(pad "H7" smd circle
			(at -28.990036 -31.139892 180)
			(size 0.450088 0.450088)
			(layers "F.Cu" "F.Mask" "F.Paste")
			(net "M_K_CPU0_SA_DQS_DN<5>")
		)
		(pad "H8" smd circle
			(at -28.049982 -31.139892 180)
			(size 0.450088 0.450088)
			(layers "F.Cu" "F.Mask" "F.Paste")
			(net "GND")
		)
		(pad "H9" smd circle
			(at -27.109928 -31.139892 180)
			(size 0.450088 0.450088)
			(layers "F.Cu" "F.Mask" "F.Paste")
			(net "M_L_CPU0_SA_DQS_DN<0>")
		)
		(pad "H10" smd circle
			(at -26.170128 -31.139892 180)
			(size 0.450088 0.450088)
			(layers "F.Cu" "F.Mask" "F.Paste")
			(net "GND")
		)
		(pad "H11" smd circle
			(at -25.230074 -31.139892 180)
			(size 0.450088 0.450088)
			(layers "F.Cu" "F.Mask" "F.Paste")
			(net "M_L_CPU0_SA_DQS_DN<5>")
		)
		(pad "H12" smd circle
			(at -24.29002 -31.139892 180)
			(size 0.450088 0.450088)
			(layers "F.Cu" "F.Mask" "F.Paste")
			(net "PVDDCR_SOC_P0")
		)
		(pad "H13" smd circle
			(at -23.349966 -31.139892 180)
			(size 0.450088 0.450088)
			(layers "F.Cu" "F.Mask" "F.Paste")
			(net "M_H_CPU0_SA_DQS_DN<0>")
		)
		(pad "H14" smd circle
			(at -22.409912 -31.139892 180)
			(size 0.450088 0.450088)
			(layers "F.Cu" "F.Mask" "F.Paste")
			(net "M_H_CPU0_SA_DQS_DN<5>")
		)
		(pad "H15" smd circle
			(at -21.470112 -31.139892 180)
			(size 0.450088 0.450088)
			(layers "F.Cu" "F.Mask" "F.Paste")
			(net "GND")
		)
		(pad "H16" smd circle
			(at -20.530058 -31.139892 180)
			(size 0.450088 0.450088)
			(layers "F.Cu" "F.Mask" "F.Paste")
			(net "M_J_CPU0_SA_DQS_DN<0>")
		)
		(pad "H17" smd circle
			(at -19.590004 -31.139892 180)
			(size 0.450088 0.450088)
			(layers "F.Cu" "F.Mask" "F.Paste")
			(net "GND")
		)
		(pad "H18" smd circle
			(at -18.64995 -31.139892 180)
			(size 0.450088 0.450088)
			(layers "F.Cu" "F.Mask" "F.Paste")
			(net "M_J_CPU0_SA_DQS_DN<5>")
		)
		(pad "H19" smd circle
			(at -17.709896 -31.139892 180)
			(size 0.450088 0.450088)
			(layers "F.Cu" "F.Mask" "F.Paste")
			(net "PVDDCR_SOC_P0")
		)
		(pad "H20" smd circle
			(at -16.770096 -31.139892 180)
			(size 0.450088 0.450088)
			(layers "F.Cu" "F.Mask" "F.Paste")
			(net "M_I_CPU0_SA_DQS_DN<0>")
		)
		(pad "H21" smd circle
			(at -15.830042 -31.139892 180)
			(size 0.450088 0.450088)
			(layers "F.Cu" "F.Mask" "F.Paste")
			(net "M_I_CPU0_SA_DQS_DN<5>")
		)
		(pad "H22" smd circle
			(at -14.889988 -31.139892 180)
			(size 0.450088 0.450088)
			(layers "F.Cu" "F.Mask" "F.Paste")
			(net "GND")
		)
		(pad "H23" smd circle
			(at -13.949934 -31.139892 180)
			(size 0.450088 0.450088)
			(layers "F.Cu" "F.Mask" "F.Paste")
			(net "PVDDCR_CPU0_P0")
		)
		(pad "H24" smd circle
			(at -13.00988 -31.139892 180)
			(size 0.450088 0.450088)
			(layers "F.Cu" "F.Mask" "F.Paste")
			(net "PVDDCR_CPU0_P0")
		)
		(pad "H25" smd circle
			(at -12.07008 -31.139892 180)
			(size 0.450088 0.450088)
			(layers "F.Cu" "F.Mask" "F.Paste")
			(net "GND")
		)
		(pad "H26" smd circle
			(at -11.130026 -31.139892 180)
			(size 0.450088 0.450088)
			(layers "F.Cu" "F.Mask" "F.Paste")
			(net "PVDDCR_CPU0_P0")
		)
		(pad "H27" smd circle
			(at -10.189972 -31.139892 180)
			(size 0.450088 0.450088)
			(layers "F.Cu" "F.Mask" "F.Paste")
			(net "PVDDCR_CPU0_P0")
		)
		(pad "H28" smd circle
			(at -9.249918 -31.139892 180)
			(size 0.450088 0.450088)
			(layers "F.Cu" "F.Mask" "F.Paste")
			(net "GND")
		)
		(pad "H29" smd circle
			(at -8.310118 -31.139892 180)
			(size 0.450088 0.450088)
			(layers "F.Cu" "F.Mask" "F.Paste")
			(net "PVDDCR_CPU0_P0")
		)
		(pad "H30" smd circle
			(at -7.370064 -31.139892 180)
			(size 0.450088 0.450088)
			(layers "F.Cu" "F.Mask" "F.Paste")
			(net "PVDDCR_CPU0_P0")
		)
		(pad "H31" smd circle
			(at -6.43001 -31.139892 180)
			(size 0.450088 0.450088)
			(layers "F.Cu" "F.Mask" "F.Paste")
			(net "GND")
		)
		(pad "H32" smd circle
			(at -5.489956 -31.139892 180)
			(size 0.450088 0.450088)
			(layers "F.Cu" "F.Mask" "F.Paste")
			(net "PVDDCR_CPU0_P0")
		)
		(pad "H33" smd circle
			(at -4.549902 -31.139892 180)
			(size 0.450088 0.450088)
			(layers "F.Cu" "F.Mask" "F.Paste")
			(net "PVDDCR_CPU0_P0")
		)
		(pad "H34" smd circle
			(at -3.610102 -31.139892 180)
			(size 0.450088 0.450088)
			(layers "F.Cu" "F.Mask" "F.Paste")
			(net "GND")
		)
		(pad "H35" smd circle
			(at -2.670048 -31.139892 180)
			(size 0.450088 0.450088)
			(layers "F.Cu" "F.Mask" "F.Paste")
			(net "GMI_CPU0_G2_CPU1_G0_TX_DP<13>")
		)
		(pad "H36" smd circle
			(at -1.729994 -31.139892 180)
			(size 0.450088 0.450088)
			(layers "F.Cu" "F.Mask" "F.Paste")
			(net "GMI_CPU0_G2_CPU1_G0_TX_DN<13>")
		)
		(pad "H37" smd circle
			(at -0.78994 -31.139892 180)
			(size 0.450088 0.450088)
			(layers "F.Cu" "F.Mask" "F.Paste")
			(net "GND")
		)
		(pad "H39" smd circle
			(at 1.089914 -31.139892 180)
			(size 0.450088 0.450088)
			(layers "F.Cu" "F.Mask" "F.Paste")
			(net "GND")
		)
		(pad "H40" smd circle
			(at 2.029968 -31.139892 180)
			(size 0.450088 0.450088)
			(layers "F.Cu" "F.Mask" "F.Paste")
			(net "GMI_CPU1_G2_CPU0_G0_TX_DN<2>")
		)
		(pad "H41" smd circle
			(at 2.970022 -31.139892 180)
			(size 0.450088 0.450088)
			(layers "F.Cu" "F.Mask" "F.Paste")
			(net "GMI_CPU1_G2_CPU0_G0_TX_DP<2>")
		)
		(pad "H42" smd circle
			(at 3.910076 -31.139892 180)
			(size 0.450088 0.450088)
			(layers "F.Cu" "F.Mask" "F.Paste")
			(net "GND")
		)
		(pad "H43" smd circle
			(at 4.849876 -31.139892 180)
			(size 0.450088 0.450088)
			(layers "F.Cu" "F.Mask" "F.Paste")
			(net "PVDDCR_CPU0_P0")
		)
		(pad "H44" smd circle
			(at 5.78993 -31.139892 180)
			(size 0.450088 0.450088)
			(layers "F.Cu" "F.Mask" "F.Paste")
			(net "PVDDCR_CPU0_P0")
		)
		(pad "H45" smd circle
			(at 6.729984 -31.139892 180)
			(size 0.450088 0.450088)
			(layers "F.Cu" "F.Mask" "F.Paste")
			(net "GND")
		)
		(pad "H46" smd circle
			(at 7.670038 -31.139892 180)
			(size 0.450088 0.450088)
			(layers "F.Cu" "F.Mask" "F.Paste")
			(net "PVDDCR_CPU0_P0")
		)
		(pad "H47" smd circle
			(at 8.610092 -31.139892 180)
			(size 0.450088 0.450088)
			(layers "F.Cu" "F.Mask" "F.Paste")
			(net "PVDDCR_CPU0_P0")
		)
		(pad "H48" smd circle
			(at 9.549892 -31.139892 180)
			(size 0.450088 0.450088)
			(layers "F.Cu" "F.Mask" "F.Paste")
			(net "GND")
		)
		(pad "H49" smd circle
			(at 10.489946 -31.139892 180)
			(size 0.450088 0.450088)
			(layers "F.Cu" "F.Mask" "F.Paste")
			(net "PVDDCR_CPU0_P0")
		)
		(pad "H50" smd circle
			(at 11.43 -31.139892 180)
			(size 0.450088 0.450088)
			(layers "F.Cu" "F.Mask" "F.Paste")
			(net "PVDDCR_CPU0_P0")
		)
		(pad "H51" smd circle
			(at 12.370054 -31.139892 180)
			(size 0.450088 0.450088)
			(layers "F.Cu" "F.Mask" "F.Paste")
			(net "GND")
		)
		(pad "H52" smd circle
			(at 13.310108 -31.139892 180)
			(size 0.450088 0.450088)
			(layers "F.Cu" "F.Mask" "F.Paste")
			(net "PVDDCR_CPU0_P0")
		)
		(pad "H53" smd circle
			(at 14.249908 -31.139892 180)
			(size 0.450088 0.450088)
			(layers "F.Cu" "F.Mask" "F.Paste")
			(net "PVDDCR_CPU0_P0")
		)
		(pad "H54" smd circle
			(at 15.189962 -31.139892 180)
			(size 0.450088 0.450088)
			(layers "F.Cu" "F.Mask" "F.Paste")
			(net "GND")
		)
		(pad "H55" smd circle
			(at 16.130016 -31.139892 180)
			(size 0.450088 0.450088)
			(layers "F.Cu" "F.Mask" "F.Paste")
			(net "M_C_CPU0_SA_DQS_DN<5>")
		)
		(pad "H56" smd circle
			(at 17.07007 -31.139892 180)
			(size 0.450088 0.450088)
			(layers "F.Cu" "F.Mask" "F.Paste")
			(net "M_C_CPU0_SA_DQS_DN<0>")
		)
		(pad "H57" smd circle
			(at 18.010124 -31.139892 180)
			(size 0.450088 0.450088)
			(layers "F.Cu" "F.Mask" "F.Paste")
			(net "PVDDIO_P0")
		)
		(pad "H58" smd circle
			(at 18.949924 -31.139892 180)
			(size 0.450088 0.450088)
			(layers "F.Cu" "F.Mask" "F.Paste")
			(net "M_D_CPU0_SA_DQS_DN<5>")
		)
		(pad "H59" smd circle
			(at 19.889978 -31.139892 180)
			(size 0.450088 0.450088)
			(layers "F.Cu" "F.Mask" "F.Paste")
			(net "GND")
		)
		(pad "H60" smd circle
			(at 20.830032 -31.139892 180)
			(size 0.450088 0.450088)
			(layers "F.Cu" "F.Mask" "F.Paste")
			(net "M_D_CPU0_SA_DQS_DN<0>")
		)
		(pad "H61" smd circle
			(at 21.770086 -31.139892 180)
			(size 0.450088 0.450088)
			(layers "F.Cu" "F.Mask" "F.Paste")
			(net "GND")
		)
		(pad "H62" smd circle
			(at 22.709886 -31.139892 180)
			(size 0.450088 0.450088)
			(layers "F.Cu" "F.Mask" "F.Paste")
			(net "M_B_CPU0_SA_DQS_DN<5>")
		)
		(pad "H63" smd circle
			(at 23.64994 -31.139892 180)
			(size 0.450088 0.450088)
			(layers "F.Cu" "F.Mask" "F.Paste")
			(net "M_B_CPU0_SA_DQS_DN<0>")
		)
		(pad "H64" smd circle
			(at 24.589994 -31.139892 180)
			(size 0.450088 0.450088)
			(layers "F.Cu" "F.Mask" "F.Paste")
			(net "PVDDIO_P0")
		)
		(pad "H65" smd circle
			(at 25.530048 -31.139892 180)
			(size 0.450088 0.450088)
			(layers "F.Cu" "F.Mask" "F.Paste")
			(net "M_F_CPU0_SA_DQS_DN<5>")
		)
		(pad "H66" smd circle
			(at 26.470102 -31.139892 180)
			(size 0.450088 0.450088)
			(layers "F.Cu" "F.Mask" "F.Paste")
			(net "GND")
		)
		(pad "H67" smd circle
			(at 27.409902 -31.139892 180)
			(size 0.450088 0.450088)
			(layers "F.Cu" "F.Mask" "F.Paste")
			(net "M_F_CPU0_SA_DQS_DN<0>")
		)
		(pad "H68" smd circle
			(at 28.349956 -31.139892 180)
			(size 0.450088 0.450088)
			(layers "F.Cu" "F.Mask" "F.Paste")
			(net "GND")
		)
		(pad "H69" smd circle
			(at 29.29001 -31.139892 180)
			(size 0.450088 0.450088)
			(layers "F.Cu" "F.Mask" "F.Paste")
			(net "M_E_CPU0_SA_DQS_DN<5>")
		)
		(pad "H70" smd circle
			(at 30.230064 -31.139892 180)
			(size 0.450088 0.450088)
			(layers "F.Cu" "F.Mask" "F.Paste")
			(net "M_E_CPU0_SA_DQS_DN<0>")
		)
		(pad "H71" smd circle
			(at 31.170118 -31.139892 180)
			(size 0.450088 0.450088)
			(layers "F.Cu" "F.Mask" "F.Paste")
			(net "PVDDIO_P0")
		)
		(pad "H72" smd circle
			(at 32.109918 -31.139892 180)
			(size 0.450088 0.450088)
			(layers "F.Cu" "F.Mask" "F.Paste")
			(net "M_A_CPU0_SA_DQS_DN<5>")
		)
		(pad "H73" smd circle
			(at 33.049972 -31.139892 180)
			(size 0.450088 0.450088)
			(layers "F.Cu" "F.Mask" "F.Paste")
			(net "GND")
		)
		(pad "H74" smd circle
			(at 33.990026 -31.139892 180)
			(size 0.450088 0.450088)
			(layers "F.Cu" "F.Mask" "F.Paste")
			(net "M_A_CPU0_SA_DQS_DN<0>")
		)
		(pad "J1" smd circle
			(at -34.159952 -30.329886 180)
			(size 0.450088 0.450088)
			(layers "F.Cu" "F.Mask" "F.Paste")
			(net "GND")
		)
		(pad "J2" smd circle
			(at -33.219898 -30.329886 180)
			(size 0.450088 0.450088)
			(layers "F.Cu" "F.Mask" "F.Paste")
			(net "M_G_CPU0_SA_DQ<4>")
		)
		(pad "J3" smd circle
			(at -32.280098 -30.329886 180)
			(size 0.450088 0.450088)
			(layers "F.Cu" "F.Mask" "F.Paste")
			(net "M_G_CPU0_SA_DQS_DP<5>")
		)
		(pad "J4" smd circle
			(at -31.340044 -30.329886 180)
			(size 0.450088 0.450088)
			(layers "F.Cu" "F.Mask" "F.Paste")
			(net "GND")
		)
		(pad "J5" smd circle
			(at -30.39999 -30.329886 180)
			(size 0.450088 0.450088)
			(layers "F.Cu" "F.Mask" "F.Paste")
			(net "M_K_CPU0_SA_DQ<4>")
		)
		(pad "J6" smd circle
			(at -29.459936 -30.329886 180)
			(size 0.450088 0.450088)
			(layers "F.Cu" "F.Mask" "F.Paste")
			(net "GND")
		)
		(pad "J7" smd circle
			(at -28.519882 -30.329886 180)
			(size 0.450088 0.450088)
			(layers "F.Cu" "F.Mask" "F.Paste")
			(net "M_K_CPU0_SA_DQS_DP<5>")
		)
		(pad "J8" smd circle
			(at -27.580082 -30.329886 180)
			(size 0.450088 0.450088)
			(layers "F.Cu" "F.Mask" "F.Paste")
			(net "GND")
		)
		(pad "J9" smd circle
			(at -26.640028 -30.329886 180)
			(size 0.450088 0.450088)
			(layers "F.Cu" "F.Mask" "F.Paste")
			(net "M_L_CPU0_SA_DQ<4>")
		)
		(pad "J10" smd circle
			(at -25.699974 -30.329886 180)
			(size 0.450088 0.450088)
			(layers "F.Cu" "F.Mask" "F.Paste")
			(net "M_L_CPU0_SA_DQS_DP<5>")
		)
		(pad "J11" smd circle
			(at -24.75992 -30.329886 180)
			(size 0.450088 0.450088)
			(layers "F.Cu" "F.Mask" "F.Paste")
			(net "GND")
		)
		(pad "J12" smd circle
			(at -23.82012 -30.329886 180)
			(size 0.450088 0.450088)
			(layers "F.Cu" "F.Mask" "F.Paste")
			(net "M_H_CPU0_SA_DQ<4>")
		)
		(pad "J13" smd circle
			(at -22.880066 -30.329886 180)
			(size 0.450088 0.450088)
			(layers "F.Cu" "F.Mask" "F.Paste")
			(net "GND")
		)
		(pad "J14" smd circle
			(at -21.940012 -30.329886 180)
			(size 0.450088 0.450088)
			(layers "F.Cu" "F.Mask" "F.Paste")
			(net "M_H_CPU0_SA_DQS_DP<5>")
		)
		(pad "J15" smd circle
			(at -20.999958 -30.329886 180)
			(size 0.450088 0.450088)
			(layers "F.Cu" "F.Mask" "F.Paste")
			(net "GND")
		)
		(pad "J16" smd circle
			(at -20.059904 -30.329886 180)
			(size 0.450088 0.450088)
			(layers "F.Cu" "F.Mask" "F.Paste")
			(net "M_J_CPU0_SA_DQ<4>")
		)
		(pad "J17" smd circle
			(at -19.120104 -30.329886 180)
			(size 0.450088 0.450088)
			(layers "F.Cu" "F.Mask" "F.Paste")
			(net "M_J_CPU0_SA_DQS_DP<5>")
		)
		(pad "J18" smd circle
			(at -18.18005 -30.329886 180)
			(size 0.450088 0.450088)
			(layers "F.Cu" "F.Mask" "F.Paste")
			(net "GND")
		)
		(pad "J19" smd circle
			(at -17.239996 -30.329886 180)
			(size 0.450088 0.450088)
			(layers "F.Cu" "F.Mask" "F.Paste")
			(net "M_I_CPU0_SA_DQ<4>")
		)
		(pad "J20" smd circle
			(at -16.299942 -30.329886 180)
			(size 0.450088 0.450088)
			(layers "F.Cu" "F.Mask" "F.Paste")
			(net "GND")
		)
		(pad "J21" smd circle
			(at -15.359888 -30.329886 180)
			(size 0.450088 0.450088)
			(layers "F.Cu" "F.Mask" "F.Paste")
			(net "M_I_CPU0_SA_DQS_DP<5>")
		)
		(pad "J22" smd circle
			(at -14.420088 -30.329886 180)
			(size 0.450088 0.450088)
			(layers "F.Cu" "F.Mask" "F.Paste")
			(net "GND")
		)
		(pad "J23" smd circle
			(at -13.480034 -30.329886 180)
			(size 0.450088 0.450088)
			(layers "F.Cu" "F.Mask" "F.Paste")
			(net "GMI_CPU0_G2_CPU1_G0_TX_DP<1>")
		)
		(pad "J24" smd circle
			(at -12.53998 -30.329886 180)
			(size 0.450088 0.450088)
			(layers "F.Cu" "F.Mask" "F.Paste")
			(net "GMI_CPU0_G2_CPU1_G0_TX_DN<1>")
		)
		(pad "J25" smd circle
			(at -11.599926 -30.329886 180)
			(size 0.450088 0.450088)
			(layers "F.Cu" "F.Mask" "F.Paste")
			(net "GND")
		)
		(pad "J26" smd circle
			(at -10.659872 -30.329886 180)
			(size 0.450088 0.450088)
			(layers "F.Cu" "F.Mask" "F.Paste")
			(net "GMI_CPU0_G2_CPU1_G0_TX_DP<4>")
		)
		(pad "J27" smd circle
			(at -9.720072 -30.329886 180)
			(size 0.450088 0.450088)
			(layers "F.Cu" "F.Mask" "F.Paste")
			(net "GMI_CPU0_G2_CPU1_G0_TX_DN<4>")
		)
		(pad "J28" smd circle
			(at -8.780018 -30.329886 180)
			(size 0.450088 0.450088)
			(layers "F.Cu" "F.Mask" "F.Paste")
			(net "GND")
		)
		(pad "J29" smd circle
			(at -7.839964 -30.329886 180)
			(size 0.450088 0.450088)
			(layers "F.Cu" "F.Mask" "F.Paste")
			(net "GMI_CPU0_G2_CPU1_G0_TX_DP<7>")
		)
		(pad "J30" smd circle
			(at -6.89991 -30.329886 180)
			(size 0.450088 0.450088)
			(layers "F.Cu" "F.Mask" "F.Paste")
			(net "GMI_CPU0_G2_CPU1_G0_TX_DN<7>")
		)
		(pad "J31" smd circle
			(at -5.96011 -30.329886 180)
			(size 0.450088 0.450088)
			(layers "F.Cu" "F.Mask" "F.Paste")
			(net "GND")
		)
		(pad "J32" smd circle
			(at -5.020056 -30.329886 180)
			(size 0.450088 0.450088)
			(layers "F.Cu" "F.Mask" "F.Paste")
			(net "GMI_CPU0_G2_CPU1_G0_TX_DP<10>")
		)
		(pad "J33" smd circle
			(at -4.080002 -30.329886 180)
			(size 0.450088 0.450088)
			(layers "F.Cu" "F.Mask" "F.Paste")
			(net "GMI_CPU0_G2_CPU1_G0_TX_DN<10>")
		)
		(pad "J34" smd circle
			(at -3.139948 -30.329886 180)
			(size 0.450088 0.450088)
			(layers "F.Cu" "F.Mask" "F.Paste")
			(net "GND")
		)
		(pad "J35" smd circle
			(at -2.199894 -30.329886 180)
			(size 0.450088 0.450088)
			(layers "F.Cu" "F.Mask" "F.Paste")
			(net "PVDDCR_CPU0_P0")
		)
		(pad "J36" smd circle
			(at -1.260094 -30.329886 180)
			(size 0.450088 0.450088)
			(layers "F.Cu" "F.Mask" "F.Paste")
			(net "PVDDCR_CPU0_P0")
		)
		(pad "J40" smd circle
			(at 1.560068 -30.329886 180)
			(size 0.450088 0.450088)
			(layers "F.Cu" "F.Mask" "F.Paste")
			(net "PVDDCR_CPU0_P0")
		)
		(pad "J41" smd circle
			(at 2.500122 -30.329886 180)
			(size 0.450088 0.450088)
			(layers "F.Cu" "F.Mask" "F.Paste")
			(net "PVDDCR_CPU0_P0")
		)
		(pad "J42" smd circle
			(at 3.439922 -30.329886 180)
			(size 0.450088 0.450088)
			(layers "F.Cu" "F.Mask" "F.Paste")
			(net "GND")
		)
		(pad "J43" smd circle
			(at 4.379976 -30.329886 180)
			(size 0.450088 0.450088)
			(layers "F.Cu" "F.Mask" "F.Paste")
			(net "GMI_CPU1_G2_CPU0_G0_TX_DN<5>")
		)
		(pad "J44" smd circle
			(at 5.32003 -30.329886 180)
			(size 0.450088 0.450088)
			(layers "F.Cu" "F.Mask" "F.Paste")
			(net "GMI_CPU1_G2_CPU0_G0_TX_DP<5>")
		)
		(pad "J45" smd circle
			(at 6.260084 -30.329886 180)
			(size 0.450088 0.450088)
			(layers "F.Cu" "F.Mask" "F.Paste")
			(net "GND")
		)
		(pad "J46" smd circle
			(at 7.199884 -30.329886 180)
			(size 0.450088 0.450088)
			(layers "F.Cu" "F.Mask" "F.Paste")
			(net "GMI_CPU1_G2_CPU0_G0_TX_DN<8>")
		)
		(pad "J47" smd circle
			(at 8.139938 -30.329886 180)
			(size 0.450088 0.450088)
			(layers "F.Cu" "F.Mask" "F.Paste")
			(net "GMI_CPU1_G2_CPU0_G0_TX_DP<8>")
		)
		(pad "J48" smd circle
			(at 9.079992 -30.329886 180)
			(size 0.450088 0.450088)
			(layers "F.Cu" "F.Mask" "F.Paste")
			(net "GND")
		)
		(pad "J49" smd circle
			(at 10.020046 -30.329886 180)
			(size 0.450088 0.450088)
			(layers "F.Cu" "F.Mask" "F.Paste")
			(net "GMI_CPU1_G2_CPU0_G0_TX_DN<11>")
		)
		(pad "J50" smd circle
			(at 10.9601 -30.329886 180)
			(size 0.450088 0.450088)
			(layers "F.Cu" "F.Mask" "F.Paste")
			(net "GMI_CPU1_G2_CPU0_G0_TX_DP<11>")
		)
		(pad "J51" smd circle
			(at 11.8999 -30.329886 180)
			(size 0.450088 0.450088)
			(layers "F.Cu" "F.Mask" "F.Paste")
			(net "GND")
		)
		(pad "J52" smd circle
			(at 12.839954 -30.329886 180)
			(size 0.450088 0.450088)
			(layers "F.Cu" "F.Mask" "F.Paste")
			(net "GMI_CPU1_G2_CPU0_G0_TX_DN<14>")
		)
		(pad "J53" smd circle
			(at 13.780008 -30.329886 180)
			(size 0.450088 0.450088)
			(layers "F.Cu" "F.Mask" "F.Paste")
			(net "GMI_CPU1_G2_CPU0_G0_TX_DP<14>")
		)
		(pad "J54" smd circle
			(at 14.720062 -30.329886 180)
			(size 0.450088 0.450088)
			(layers "F.Cu" "F.Mask" "F.Paste")
			(net "GND")
		)
		(pad "J55" smd circle
			(at 15.660116 -30.329886 180)
			(size 0.450088 0.450088)
			(layers "F.Cu" "F.Mask" "F.Paste")
			(net "M_C_CPU0_SA_DQS_DP<5>")
		)
		(pad "J56" smd circle
			(at 16.599916 -30.329886 180)
			(size 0.450088 0.450088)
			(layers "F.Cu" "F.Mask" "F.Paste")
			(net "GND")
		)
		(pad "J57" smd circle
			(at 17.53997 -30.329886 180)
			(size 0.450088 0.450088)
			(layers "F.Cu" "F.Mask" "F.Paste")
			(net "M_C_CPU0_SA_DQ<4>")
		)
		(pad "J58" smd circle
			(at 18.480024 -30.329886 180)
			(size 0.450088 0.450088)
			(layers "F.Cu" "F.Mask" "F.Paste")
			(net "GND")
		)
		(pad "J59" smd circle
			(at 19.420078 -30.329886 180)
			(size 0.450088 0.450088)
			(layers "F.Cu" "F.Mask" "F.Paste")
			(net "M_D_CPU0_SA_DQS_DP<5>")
		)
		(pad "J60" smd circle
			(at 20.359878 -30.329886 180)
			(size 0.450088 0.450088)
			(layers "F.Cu" "F.Mask" "F.Paste")
			(net "M_D_CPU0_SA_DQ<4>")
		)
		(pad "J61" smd circle
			(at 21.299932 -30.329886 180)
			(size 0.450088 0.450088)
			(layers "F.Cu" "F.Mask" "F.Paste")
			(net "GND")
		)
		(pad "J62" smd circle
			(at 22.239986 -30.329886 180)
			(size 0.450088 0.450088)
			(layers "F.Cu" "F.Mask" "F.Paste")
			(net "M_B_CPU0_SA_DQS_DP<5>")
		)
		(pad "J63" smd circle
			(at 23.18004 -30.329886 180)
			(size 0.450088 0.450088)
			(layers "F.Cu" "F.Mask" "F.Paste")
			(net "GND")
		)
		(pad "J64" smd circle
			(at 24.120094 -30.329886 180)
			(size 0.450088 0.450088)
			(layers "F.Cu" "F.Mask" "F.Paste")
			(net "M_B_CPU0_SA_DQ<4>")
		)
		(pad "J65" smd circle
			(at 25.059894 -30.329886 180)
			(size 0.450088 0.450088)
			(layers "F.Cu" "F.Mask" "F.Paste")
			(net "GND")
		)
		(pad "J66" smd circle
			(at 25.999948 -30.329886 180)
			(size 0.450088 0.450088)
			(layers "F.Cu" "F.Mask" "F.Paste")
			(net "M_F_CPU0_SA_DQS_DP<5>")
		)
		(pad "J67" smd circle
			(at 26.940002 -30.329886 180)
			(size 0.450088 0.450088)
			(layers "F.Cu" "F.Mask" "F.Paste")
			(net "M_F_CPU0_SA_DQ<4>")
		)
		(pad "J68" smd circle
			(at 27.880056 -30.329886 180)
			(size 0.450088 0.450088)
			(layers "F.Cu" "F.Mask" "F.Paste")
			(net "GND")
		)
		(pad "J69" smd circle
			(at 28.82011 -30.329886 180)
			(size 0.450088 0.450088)
			(layers "F.Cu" "F.Mask" "F.Paste")
			(net "M_E_CPU0_SA_DQS_DP<5>")
		)
		(pad "J70" smd circle
			(at 29.75991 -30.329886 180)
			(size 0.450088 0.450088)
			(layers "F.Cu" "F.Mask" "F.Paste")
			(net "GND")
		)
		(pad "J71" smd circle
			(at 30.699964 -30.329886 180)
			(size 0.450088 0.450088)
			(layers "F.Cu" "F.Mask" "F.Paste")
			(net "M_E_CPU0_SA_DQ<4>")
		)
		(pad "J72" smd circle
			(at 31.640018 -30.329886 180)
			(size 0.450088 0.450088)
			(layers "F.Cu" "F.Mask" "F.Paste")
			(net "GND")
		)
		(pad "J73" smd circle
			(at 32.580072 -30.329886 180)
			(size 0.450088 0.450088)
			(layers "F.Cu" "F.Mask" "F.Paste")
			(net "M_A_CPU0_SA_DQS_DP<5>")
		)
		(pad "J74" smd circle
			(at 33.519872 -30.329886 180)
			(size 0.450088 0.450088)
			(layers "F.Cu" "F.Mask" "F.Paste")
			(net "M_A_CPU0_SA_DQ<4>")
		)
		(pad "J75" smd circle
			(at 34.459926 -30.329886 180)
			(size 0.450088 0.450088)
			(layers "F.Cu" "F.Mask" "F.Paste")
			(net "GND")
		)
		(pad "K2" smd circle
			(at -33.690052 -29.51988 180)
			(size 0.450088 0.450088)
			(layers "F.Cu" "F.Mask" "F.Paste")
			(net "M_G_CPU0_SA_DQ<6>")
		)
		(pad "K3" smd circle
			(at -32.749998 -29.51988 180)
			(size 0.450088 0.450088)
			(layers "F.Cu" "F.Mask" "F.Paste")
			(net "GND")
		)
		(pad "K4" smd circle
			(at -31.809944 -29.51988 180)
			(size 0.450088 0.450088)
			(layers "F.Cu" "F.Mask" "F.Paste")
			(net "M_G_CPU0_SA_DQ<5>")
		)
		(pad "K5" smd circle
			(at -30.86989 -29.51988 180)
			(size 0.450088 0.450088)
			(layers "F.Cu" "F.Mask" "F.Paste")
			(net "GND")
		)
		(pad "K6" smd circle
			(at -29.93009 -29.51988 180)
			(size 0.450088 0.450088)
			(layers "F.Cu" "F.Mask" "F.Paste")
			(net "M_K_CPU0_SA_DQ<6>")
		)
		(pad "K7" smd circle
			(at -28.990036 -29.51988 180)
			(size 0.450088 0.450088)
			(layers "F.Cu" "F.Mask" "F.Paste")
			(net "M_K_CPU0_SA_DQ<5>")
		)
		(pad "K8" smd circle
			(at -28.049982 -29.51988 180)
			(size 0.450088 0.450088)
			(layers "F.Cu" "F.Mask" "F.Paste")
			(net "GND")
		)
		(pad "K9" smd circle
			(at -27.109928 -29.51988 180)
			(size 0.450088 0.450088)
			(layers "F.Cu" "F.Mask" "F.Paste")
			(net "M_L_CPU0_SA_DQ<6>")
		)
		(pad "K10" smd circle
			(at -26.170128 -29.51988 180)
			(size 0.450088 0.450088)
			(layers "F.Cu" "F.Mask" "F.Paste")
			(net "GND")
		)
		(pad "K11" smd circle
			(at -25.230074 -29.51988 180)
			(size 0.450088 0.450088)
			(layers "F.Cu" "F.Mask" "F.Paste")
			(net "M_L_CPU0_SA_DQ<5>")
		)
		(pad "K12" smd circle
			(at -24.29002 -29.51988 180)
			(size 0.450088 0.450088)
			(layers "F.Cu" "F.Mask" "F.Paste")
			(net "GND")
		)
		(pad "K13" smd circle
			(at -23.349966 -29.51988 180)
			(size 0.450088 0.450088)
			(layers "F.Cu" "F.Mask" "F.Paste")
			(net "M_H_CPU0_SA_DQ<6>")
		)
		(pad "K14" smd circle
			(at -22.409912 -29.51988 180)
			(size 0.450088 0.450088)
			(layers "F.Cu" "F.Mask" "F.Paste")
			(net "M_H_CPU0_SA_DQ<5>")
		)
		(pad "K15" smd circle
			(at -21.470112 -29.51988 180)
			(size 0.450088 0.450088)
			(layers "F.Cu" "F.Mask" "F.Paste")
			(net "GND")
		)
		(pad "K16" smd circle
			(at -20.530058 -29.51988 180)
			(size 0.450088 0.450088)
			(layers "F.Cu" "F.Mask" "F.Paste")
			(net "M_J_CPU0_SA_DQ<6>")
		)
		(pad "K17" smd circle
			(at -19.590004 -29.51988 180)
			(size 0.450088 0.450088)
			(layers "F.Cu" "F.Mask" "F.Paste")
			(net "GND")
		)
		(pad "K18" smd circle
			(at -18.64995 -29.51988 180)
			(size 0.450088 0.450088)
			(layers "F.Cu" "F.Mask" "F.Paste")
			(net "M_J_CPU0_SA_DQ<5>")
		)
		(pad "K19" smd circle
			(at -17.709896 -29.51988 180)
			(size 0.450088 0.450088)
			(layers "F.Cu" "F.Mask" "F.Paste")
			(net "GND")
		)
		(pad "K20" smd circle
			(at -16.770096 -29.51988 180)
			(size 0.450088 0.450088)
			(layers "F.Cu" "F.Mask" "F.Paste")
			(net "M_I_CPU0_SA_DQ<6>")
		)
		(pad "K21" smd circle
			(at -15.830042 -29.51988 180)
			(size 0.450088 0.450088)
			(layers "F.Cu" "F.Mask" "F.Paste")
			(net "M_I_CPU0_SA_DQ<5>")
		)
		(pad "K22" smd circle
			(at -14.889988 -29.51988 180)
			(size 0.450088 0.450088)
			(layers "F.Cu" "F.Mask" "F.Paste")
			(net "PVDDCR_SOC_P0")
		)
		(pad "K23" smd circle
			(at -13.949934 -29.51988 180)
			(size 0.450088 0.450088)
			(layers "F.Cu" "F.Mask" "F.Paste")
			(net "GND")
		)
		(pad "K24" smd circle
			(at -13.00988 -29.51988 180)
			(size 0.450088 0.450088)
			(layers "F.Cu" "F.Mask" "F.Paste")
			(net "GND")
		)
		(pad "K25" smd circle
			(at -12.07008 -29.51988 180)
			(size 0.450088 0.450088)
			(layers "F.Cu" "F.Mask" "F.Paste")
			(net "GND")
		)
		(pad "K26" smd circle
			(at -11.130026 -29.51988 180)
			(size 0.450088 0.450088)
			(layers "F.Cu" "F.Mask" "F.Paste")
			(net "GND")
		)
		(pad "K27" smd circle
			(at -10.189972 -29.51988 180)
			(size 0.450088 0.450088)
			(layers "F.Cu" "F.Mask" "F.Paste")
			(net "GND")
		)
		(pad "K28" smd circle
			(at -9.249918 -29.51988 180)
			(size 0.450088 0.450088)
			(layers "F.Cu" "F.Mask" "F.Paste")
			(net "GND")
		)
		(pad "K29" smd circle
			(at -8.310118 -29.51988 180)
			(size 0.450088 0.450088)
			(layers "F.Cu" "F.Mask" "F.Paste")
			(net "GND")
		)
		(pad "K30" smd circle
			(at -7.370064 -29.51988 180)
			(size 0.450088 0.450088)
			(layers "F.Cu" "F.Mask" "F.Paste")
			(net "GND")
		)
		(pad "K31" smd circle
			(at -6.43001 -29.51988 180)
			(size 0.450088 0.450088)
			(layers "F.Cu" "F.Mask" "F.Paste")
			(net "GND")
		)
		(pad "K32" smd circle
			(at -5.489956 -29.51988 180)
			(size 0.450088 0.450088)
			(layers "F.Cu" "F.Mask" "F.Paste")
			(net "GND")
		)
		(pad "K33" smd circle
			(at -4.549902 -29.51988 180)
			(size 0.450088 0.450088)
			(layers "F.Cu" "F.Mask" "F.Paste")
			(net "GND")
		)
		(pad "K34" smd circle
			(at -3.610102 -29.51988 180)
			(size 0.450088 0.450088)
			(layers "F.Cu" "F.Mask" "F.Paste")
			(net "GND")
		)
		(pad "K35" smd circle
			(at -2.670048 -29.51988 180)
			(size 0.450088 0.450088)
			(layers "F.Cu" "F.Mask" "F.Paste")
			(net "GMI_CPU0_G2_CPU1_G0_TX_DP<14>")
		)
		(pad "K36" smd circle
			(at -1.729994 -29.51988 180)
			(size 0.450088 0.450088)
			(layers "F.Cu" "F.Mask" "F.Paste")
			(net "GMI_CPU0_G2_CPU1_G0_TX_DN<14>")
		)
		(pad "K37" smd circle
			(at -0.78994 -29.51988 180)
			(size 0.450088 0.450088)
			(layers "F.Cu" "F.Mask" "F.Paste")
			(net "GND")
		)
		(pad "K39" smd circle
			(at 1.089914 -29.51988 180)
			(size 0.450088 0.450088)
			(layers "F.Cu" "F.Mask" "F.Paste")
			(net "GND")
		)
		(pad "K40" smd circle
			(at 2.029968 -29.51988 180)
			(size 0.450088 0.450088)
			(layers "F.Cu" "F.Mask" "F.Paste")
			(net "GMI_CPU1_G2_CPU0_G0_TX_DN<1>")
		)
		(pad "K41" smd circle
			(at 2.970022 -29.51988 180)
			(size 0.450088 0.450088)
			(layers "F.Cu" "F.Mask" "F.Paste")
			(net "GMI_CPU1_G2_CPU0_G0_TX_DP<1>")
		)
		(pad "K42" smd circle
			(at 3.910076 -29.51988 180)
			(size 0.450088 0.450088)
			(layers "F.Cu" "F.Mask" "F.Paste")
			(net "GND")
		)
		(pad "K43" smd circle
			(at 4.849876 -29.51988 180)
			(size 0.450088 0.450088)
			(layers "F.Cu" "F.Mask" "F.Paste")
			(net "GND")
		)
		(pad "K44" smd circle
			(at 5.78993 -29.51988 180)
			(size 0.450088 0.450088)
			(layers "F.Cu" "F.Mask" "F.Paste")
			(net "GND")
		)
		(pad "K45" smd circle
			(at 6.729984 -29.51988 180)
			(size 0.450088 0.450088)
			(layers "F.Cu" "F.Mask" "F.Paste")
			(net "GND")
		)
		(pad "K46" smd circle
			(at 7.670038 -29.51988 180)
			(size 0.450088 0.450088)
			(layers "F.Cu" "F.Mask" "F.Paste")
			(net "GND")
		)
		(pad "K47" smd circle
			(at 8.610092 -29.51988 180)
			(size 0.450088 0.450088)
			(layers "F.Cu" "F.Mask" "F.Paste")
			(net "GND")
		)
		(pad "K48" smd circle
			(at 9.549892 -29.51988 180)
			(size 0.450088 0.450088)
			(layers "F.Cu" "F.Mask" "F.Paste")
			(net "GND")
		)
		(pad "K49" smd circle
			(at 10.489946 -29.51988 180)
			(size 0.450088 0.450088)
			(layers "F.Cu" "F.Mask" "F.Paste")
			(net "GND")
		)
		(pad "K50" smd circle
			(at 11.43 -29.51988 180)
			(size 0.450088 0.450088)
			(layers "F.Cu" "F.Mask" "F.Paste")
			(net "GND")
		)
		(pad "K51" smd circle
			(at 12.370054 -29.51988 180)
			(size 0.450088 0.450088)
			(layers "F.Cu" "F.Mask" "F.Paste")
			(net "GND")
		)
		(pad "K52" smd circle
			(at 13.310108 -29.51988 180)
			(size 0.450088 0.450088)
			(layers "F.Cu" "F.Mask" "F.Paste")
			(net "GND")
		)
		(pad "K53" smd circle
			(at 14.249908 -29.51988 180)
			(size 0.450088 0.450088)
			(layers "F.Cu" "F.Mask" "F.Paste")
			(net "GND")
		)
		(pad "K54" smd circle
			(at 15.189962 -29.51988 180)
			(size 0.450088 0.450088)
			(layers "F.Cu" "F.Mask" "F.Paste")
			(net "PVDDIO_P0")
		)
		(pad "K55" smd circle
			(at 16.130016 -29.51988 180)
			(size 0.450088 0.450088)
			(layers "F.Cu" "F.Mask" "F.Paste")
			(net "M_C_CPU0_SA_DQ<5>")
		)
		(pad "K56" smd circle
			(at 17.07007 -29.51988 180)
			(size 0.450088 0.450088)
			(layers "F.Cu" "F.Mask" "F.Paste")
			(net "M_C_CPU0_SA_DQ<6>")
		)
		(pad "K57" smd circle
			(at 18.010124 -29.51988 180)
			(size 0.450088 0.450088)
			(layers "F.Cu" "F.Mask" "F.Paste")
			(net "GND")
		)
		(pad "K58" smd circle
			(at 18.949924 -29.51988 180)
			(size 0.450088 0.450088)
			(layers "F.Cu" "F.Mask" "F.Paste")
			(net "M_D_CPU0_SA_DQ<5>")
		)
		(pad "K59" smd circle
			(at 19.889978 -29.51988 180)
			(size 0.450088 0.450088)
			(layers "F.Cu" "F.Mask" "F.Paste")
			(net "GND")
		)
		(pad "K60" smd circle
			(at 20.830032 -29.51988 180)
			(size 0.450088 0.450088)
			(layers "F.Cu" "F.Mask" "F.Paste")
			(net "M_D_CPU0_SA_DQ<6>")
		)
		(pad "K61" smd circle
			(at 21.770086 -29.51988 180)
			(size 0.450088 0.450088)
			(layers "F.Cu" "F.Mask" "F.Paste")
			(net "GND")
		)
		(pad "K62" smd circle
			(at 22.709886 -29.51988 180)
			(size 0.450088 0.450088)
			(layers "F.Cu" "F.Mask" "F.Paste")
			(net "M_B_CPU0_SA_DQ<5>")
		)
		(pad "K63" smd circle
			(at 23.64994 -29.51988 180)
			(size 0.450088 0.450088)
			(layers "F.Cu" "F.Mask" "F.Paste")
			(net "M_B_CPU0_SA_DQ<6>")
		)
		(pad "K64" smd circle
			(at 24.589994 -29.51988 180)
			(size 0.450088 0.450088)
			(layers "F.Cu" "F.Mask" "F.Paste")
			(net "GND")
		)
		(pad "K65" smd circle
			(at 25.530048 -29.51988 180)
			(size 0.450088 0.450088)
			(layers "F.Cu" "F.Mask" "F.Paste")
			(net "M_F_CPU0_SA_DQ<5>")
		)
		(pad "K66" smd circle
			(at 26.470102 -29.51988 180)
			(size 0.450088 0.450088)
			(layers "F.Cu" "F.Mask" "F.Paste")
			(net "GND")
		)
		(pad "K67" smd circle
			(at 27.409902 -29.51988 180)
			(size 0.450088 0.450088)
			(layers "F.Cu" "F.Mask" "F.Paste")
			(net "M_F_CPU0_SA_DQ<6>")
		)
		(pad "K68" smd circle
			(at 28.349956 -29.51988 180)
			(size 0.450088 0.450088)
			(layers "F.Cu" "F.Mask" "F.Paste")
			(net "GND")
		)
		(pad "K69" smd circle
			(at 29.29001 -29.51988 180)
			(size 0.450088 0.450088)
			(layers "F.Cu" "F.Mask" "F.Paste")
			(net "M_E_CPU0_SA_DQ<5>")
		)
		(pad "K70" smd circle
			(at 30.230064 -29.51988 180)
			(size 0.450088 0.450088)
			(layers "F.Cu" "F.Mask" "F.Paste")
			(net "M_E_CPU0_SA_DQ<6>")
		)
		(pad "K71" smd circle
			(at 31.170118 -29.51988 180)
			(size 0.450088 0.450088)
			(layers "F.Cu" "F.Mask" "F.Paste")
			(net "GND")
		)
		(pad "K72" smd circle
			(at 32.109918 -29.51988 180)
			(size 0.450088 0.450088)
			(layers "F.Cu" "F.Mask" "F.Paste")
			(net "M_A_CPU0_SA_DQ<5>")
		)
		(pad "K73" smd circle
			(at 33.049972 -29.51988 180)
			(size 0.450088 0.450088)
			(layers "F.Cu" "F.Mask" "F.Paste")
			(net "GND")
		)
		(pad "K74" smd circle
			(at 33.990026 -29.51988 180)
			(size 0.450088 0.450088)
			(layers "F.Cu" "F.Mask" "F.Paste")
			(net "M_A_CPU0_SA_DQ<6>")
		)
		(pad "L1" smd circle
			(at -34.159952 -28.710128 180)
			(size 0.450088 0.450088)
			(layers "F.Cu" "F.Mask" "F.Paste")
			(net "GND")
		)
		(pad "L2" smd circle
			(at -33.219898 -28.710128 180)
			(size 0.450088 0.450088)
			(layers "F.Cu" "F.Mask" "F.Paste")
			(net "M_G_CPU0_SA_DQ<8>")
		)
		(pad "L3" smd circle
			(at -32.280098 -28.710128 180)
			(size 0.450088 0.450088)
			(layers "F.Cu" "F.Mask" "F.Paste")
			(net "M_G_CPU0_SA_DQ<7>")
		)
		(pad "L4" smd circle
			(at -31.340044 -28.710128 180)
			(size 0.450088 0.450088)
			(layers "F.Cu" "F.Mask" "F.Paste")
			(net "PVDDCR_SOC_P0")
		)
		(pad "L5" smd circle
			(at -30.39999 -28.710128 180)
			(size 0.450088 0.450088)
			(layers "F.Cu" "F.Mask" "F.Paste")
			(net "M_K_CPU0_SA_DQ<8>")
		)
		(pad "L6" smd circle
			(at -29.459936 -28.710128 180)
			(size 0.450088 0.450088)
			(layers "F.Cu" "F.Mask" "F.Paste")
			(net "GND")
		)
		(pad "L7" smd circle
			(at -28.519882 -28.710128 180)
			(size 0.450088 0.450088)
			(layers "F.Cu" "F.Mask" "F.Paste")
			(net "M_K_CPU0_SA_DQ<7>")
		)
		(pad "L8" smd circle
			(at -27.580082 -28.710128 180)
			(size 0.450088 0.450088)
			(layers "F.Cu" "F.Mask" "F.Paste")
			(net "GND")
		)
		(pad "L9" smd circle
			(at -26.640028 -28.710128 180)
			(size 0.450088 0.450088)
			(layers "F.Cu" "F.Mask" "F.Paste")
			(net "M_L_CPU0_SA_DQ<8>")
		)
		(pad "L10" smd circle
			(at -25.699974 -28.710128 180)
			(size 0.450088 0.450088)
			(layers "F.Cu" "F.Mask" "F.Paste")
			(net "M_L_CPU0_SA_DQ<7>")
		)
		(pad "L11" smd circle
			(at -24.75992 -28.710128 180)
			(size 0.450088 0.450088)
			(layers "F.Cu" "F.Mask" "F.Paste")
			(net "PVDDCR_SOC_P0")
		)
		(pad "L12" smd circle
			(at -23.82012 -28.710128 180)
			(size 0.450088 0.450088)
			(layers "F.Cu" "F.Mask" "F.Paste")
			(net "M_H_CPU0_SA_DQ<8>")
		)
		(pad "L13" smd circle
			(at -22.880066 -28.710128 180)
			(size 0.450088 0.450088)
			(layers "F.Cu" "F.Mask" "F.Paste")
			(net "GND")
		)
		(pad "L14" smd circle
			(at -21.940012 -28.710128 180)
			(size 0.450088 0.450088)
			(layers "F.Cu" "F.Mask" "F.Paste")
			(net "M_H_CPU0_SA_DQ<7>")
		)
		(pad "L15" smd circle
			(at -20.999958 -28.710128 180)
			(size 0.450088 0.450088)
			(layers "F.Cu" "F.Mask" "F.Paste")
			(net "GND")
		)
		(pad "L16" smd circle
			(at -20.059904 -28.710128 180)
			(size 0.450088 0.450088)
			(layers "F.Cu" "F.Mask" "F.Paste")
			(net "M_J_CPU0_SA_DQ<8>")
		)
		(pad "L17" smd circle
			(at -19.120104 -28.710128 180)
			(size 0.450088 0.450088)
			(layers "F.Cu" "F.Mask" "F.Paste")
			(net "M_J_CPU0_SA_DQ<7>")
		)
		(pad "L18" smd circle
			(at -18.18005 -28.710128 180)
			(size 0.450088 0.450088)
			(layers "F.Cu" "F.Mask" "F.Paste")
			(net "PVDDCR_SOC_P0")
		)
		(pad "L19" smd circle
			(at -17.239996 -28.710128 180)
			(size 0.450088 0.450088)
			(layers "F.Cu" "F.Mask" "F.Paste")
			(net "M_I_CPU0_SA_DQ<8>")
		)
		(pad "L20" smd circle
			(at -16.299942 -28.710128 180)
			(size 0.450088 0.450088)
			(layers "F.Cu" "F.Mask" "F.Paste")
			(net "GND")
		)
		(pad "L21" smd circle
			(at -15.359888 -28.710128 180)
			(size 0.450088 0.450088)
			(layers "F.Cu" "F.Mask" "F.Paste")
			(net "M_I_CPU0_SA_DQ<7>")
		)
		(pad "L22" smd circle
			(at -14.420088 -28.710128 180)
			(size 0.450088 0.450088)
			(layers "F.Cu" "F.Mask" "F.Paste")
			(net "GND")
		)
		(pad "L23" smd circle
			(at -13.480034 -28.710128 180)
			(size 0.450088 0.450088)
			(layers "F.Cu" "F.Mask" "F.Paste")
			(net "GMI_CPU0_G2_CPU1_G0_TX_DP<3>")
		)
		(pad "L24" smd circle
			(at -12.53998 -28.710128 180)
			(size 0.450088 0.450088)
			(layers "F.Cu" "F.Mask" "F.Paste")
			(net "GMI_CPU0_G2_CPU1_G0_TX_DN<3>")
		)
		(pad "L25" smd circle
			(at -11.599926 -28.710128 180)
			(size 0.450088 0.450088)
			(layers "F.Cu" "F.Mask" "F.Paste")
			(net "GND")
		)
		(pad "L26" smd circle
			(at -10.659872 -28.710128 180)
			(size 0.450088 0.450088)
			(layers "F.Cu" "F.Mask" "F.Paste")
			(net "GMI_CPU0_G2_CPU1_G0_TX_DP<6>")
		)
		(pad "L27" smd circle
			(at -9.720072 -28.710128 180)
			(size 0.450088 0.450088)
			(layers "F.Cu" "F.Mask" "F.Paste")
			(net "GMI_CPU0_G2_CPU1_G0_TX_DN<6>")
		)
		(pad "L28" smd circle
			(at -8.780018 -28.710128 180)
			(size 0.450088 0.450088)
			(layers "F.Cu" "F.Mask" "F.Paste")
			(net "GND")
		)
		(pad "L29" smd circle
			(at -7.839964 -28.710128 180)
			(size 0.450088 0.450088)
			(layers "F.Cu" "F.Mask" "F.Paste")
			(net "GMI_CPU0_G2_CPU1_G0_TX_DP<9>")
		)
		(pad "L30" smd circle
			(at -6.89991 -28.710128 180)
			(size 0.450088 0.450088)
			(layers "F.Cu" "F.Mask" "F.Paste")
			(net "GMI_CPU0_G2_CPU1_G0_TX_DN<9>")
		)
		(pad "L31" smd circle
			(at -5.96011 -28.710128 180)
			(size 0.450088 0.450088)
			(layers "F.Cu" "F.Mask" "F.Paste")
			(net "GND")
		)
		(pad "L32" smd circle
			(at -5.020056 -28.710128 180)
			(size 0.450088 0.450088)
			(layers "F.Cu" "F.Mask" "F.Paste")
			(net "GMI_CPU0_G2_CPU1_G0_TX_DP<12>")
		)
		(pad "L33" smd circle
			(at -4.080002 -28.710128 180)
			(size 0.450088 0.450088)
			(layers "F.Cu" "F.Mask" "F.Paste")
			(net "GMI_CPU0_G2_CPU1_G0_TX_DN<12>")
		)
		(pad "L34" smd circle
			(at -3.139948 -28.710128 180)
			(size 0.450088 0.450088)
			(layers "F.Cu" "F.Mask" "F.Paste")
			(net "GND")
		)
		(pad "L35" smd circle
			(at -2.199894 -28.710128 180)
			(size 0.450088 0.450088)
			(layers "F.Cu" "F.Mask" "F.Paste")
			(net "GND")
		)
		(pad "L36" smd circle
			(at -1.260094 -28.710128 180)
			(size 0.450088 0.450088)
			(layers "F.Cu" "F.Mask" "F.Paste")
			(net "GND")
		)
		(pad "L40" smd circle
			(at 1.560068 -28.710128 180)
			(size 0.450088 0.450088)
			(layers "F.Cu" "F.Mask" "F.Paste")
			(net "GND")
		)
		(pad "L41" smd circle
			(at 2.500122 -28.710128 180)
			(size 0.450088 0.450088)
			(layers "F.Cu" "F.Mask" "F.Paste")
			(net "GND")
		)
		(pad "L42" smd circle
			(at 3.439922 -28.710128 180)
			(size 0.450088 0.450088)
			(layers "F.Cu" "F.Mask" "F.Paste")
			(net "GND")
		)
		(pad "L43" smd circle
			(at 4.379976 -28.710128 180)
			(size 0.450088 0.450088)
			(layers "F.Cu" "F.Mask" "F.Paste")
			(net "GMI_CPU1_G2_CPU0_G0_TX_DN<3>")
		)
		(pad "L44" smd circle
			(at 5.32003 -28.710128 180)
			(size 0.450088 0.450088)
			(layers "F.Cu" "F.Mask" "F.Paste")
			(net "GMI_CPU1_G2_CPU0_G0_TX_DP<3>")
		)
		(pad "L45" smd circle
			(at 6.260084 -28.710128 180)
			(size 0.450088 0.450088)
			(layers "F.Cu" "F.Mask" "F.Paste")
			(net "GND")
		)
		(pad "L46" smd circle
			(at 7.199884 -28.710128 180)
			(size 0.450088 0.450088)
			(layers "F.Cu" "F.Mask" "F.Paste")
			(net "GMI_CPU1_G2_CPU0_G0_TX_DN<6>")
		)
		(pad "L47" smd circle
			(at 8.139938 -28.710128 180)
			(size 0.450088 0.450088)
			(layers "F.Cu" "F.Mask" "F.Paste")
			(net "GMI_CPU1_G2_CPU0_G0_TX_DP<6>")
		)
		(pad "L48" smd circle
			(at 9.079992 -28.710128 180)
			(size 0.450088 0.450088)
			(layers "F.Cu" "F.Mask" "F.Paste")
			(net "GND")
		)
		(pad "L49" smd circle
			(at 10.020046 -28.710128 180)
			(size 0.450088 0.450088)
			(layers "F.Cu" "F.Mask" "F.Paste")
			(net "GMI_CPU1_G2_CPU0_G0_TX_DN<9>")
		)
		(pad "L50" smd circle
			(at 10.9601 -28.710128 180)
			(size 0.450088 0.450088)
			(layers "F.Cu" "F.Mask" "F.Paste")
			(net "GMI_CPU1_G2_CPU0_G0_TX_DP<9>")
		)
		(pad "L51" smd circle
			(at 11.8999 -28.710128 180)
			(size 0.450088 0.450088)
			(layers "F.Cu" "F.Mask" "F.Paste")
			(net "GND")
		)
		(pad "L52" smd circle
			(at 12.839954 -28.710128 180)
			(size 0.450088 0.450088)
			(layers "F.Cu" "F.Mask" "F.Paste")
			(net "GMI_CPU1_G2_CPU0_G0_TX_DN<12>")
		)
		(pad "L53" smd circle
			(at 13.780008 -28.710128 180)
			(size 0.450088 0.450088)
			(layers "F.Cu" "F.Mask" "F.Paste")
			(net "GMI_CPU1_G2_CPU0_G0_TX_DP<12>")
		)
		(pad "L54" smd circle
			(at 14.720062 -28.710128 180)
			(size 0.450088 0.450088)
			(layers "F.Cu" "F.Mask" "F.Paste")
			(net "GND")
		)
		(pad "L55" smd circle
			(at 15.660116 -28.710128 180)
			(size 0.450088 0.450088)
			(layers "F.Cu" "F.Mask" "F.Paste")
			(net "M_C_CPU0_SA_DQ<7>")
		)
		(pad "L56" smd circle
			(at 16.599916 -28.710128 180)
			(size 0.450088 0.450088)
			(layers "F.Cu" "F.Mask" "F.Paste")
			(net "GND")
		)
		(pad "L57" smd circle
			(at 17.53997 -28.710128 180)
			(size 0.450088 0.450088)
			(layers "F.Cu" "F.Mask" "F.Paste")
			(net "M_C_CPU0_SA_DQ<8>")
		)
		(pad "L58" smd circle
			(at 18.480024 -28.710128 180)
			(size 0.450088 0.450088)
			(layers "F.Cu" "F.Mask" "F.Paste")
			(net "PVDDIO_P0")
		)
		(pad "L59" smd circle
			(at 19.420078 -28.710128 180)
			(size 0.450088 0.450088)
			(layers "F.Cu" "F.Mask" "F.Paste")
			(net "M_D_CPU0_SA_DQ<7>")
		)
		(pad "L60" smd circle
			(at 20.359878 -28.710128 180)
			(size 0.450088 0.450088)
			(layers "F.Cu" "F.Mask" "F.Paste")
			(net "M_D_CPU0_SA_DQ<8>")
		)
		(pad "L61" smd circle
			(at 21.299932 -28.710128 180)
			(size 0.450088 0.450088)
			(layers "F.Cu" "F.Mask" "F.Paste")
			(net "GND")
		)
		(pad "L62" smd circle
			(at 22.239986 -28.710128 180)
			(size 0.450088 0.450088)
			(layers "F.Cu" "F.Mask" "F.Paste")
			(net "M_B_CPU0_SA_DQ<7>")
		)
		(pad "L63" smd circle
			(at 23.18004 -28.710128 180)
			(size 0.450088 0.450088)
			(layers "F.Cu" "F.Mask" "F.Paste")
			(net "GND")
		)
		(pad "L64" smd circle
			(at 24.120094 -28.710128 180)
			(size 0.450088 0.450088)
			(layers "F.Cu" "F.Mask" "F.Paste")
			(net "M_B_CPU0_SA_DQ<8>")
		)
		(pad "L65" smd circle
			(at 25.059894 -28.710128 180)
			(size 0.450088 0.450088)
			(layers "F.Cu" "F.Mask" "F.Paste")
			(net "PVDDIO_P0")
		)
		(pad "L66" smd circle
			(at 25.999948 -28.710128 180)
			(size 0.450088 0.450088)
			(layers "F.Cu" "F.Mask" "F.Paste")
			(net "M_F_CPU0_SA_DQ<7>")
		)
		(pad "L67" smd circle
			(at 26.940002 -28.710128 180)
			(size 0.450088 0.450088)
			(layers "F.Cu" "F.Mask" "F.Paste")
			(net "M_F_CPU0_SA_DQ<8>")
		)
		(pad "L68" smd circle
			(at 27.880056 -28.710128 180)
			(size 0.450088 0.450088)
			(layers "F.Cu" "F.Mask" "F.Paste")
			(net "GND")
		)
		(pad "L69" smd circle
			(at 28.82011 -28.710128 180)
			(size 0.450088 0.450088)
			(layers "F.Cu" "F.Mask" "F.Paste")
			(net "M_E_CPU0_SA_DQ<7>")
		)
		(pad "L70" smd circle
			(at 29.75991 -28.710128 180)
			(size 0.450088 0.450088)
			(layers "F.Cu" "F.Mask" "F.Paste")
			(net "GND")
		)
		(pad "L71" smd circle
			(at 30.699964 -28.710128 180)
			(size 0.450088 0.450088)
			(layers "F.Cu" "F.Mask" "F.Paste")
			(net "M_E_CPU0_SA_DQ<8>")
		)
		(pad "L72" smd circle
			(at 31.640018 -28.710128 180)
			(size 0.450088 0.450088)
			(layers "F.Cu" "F.Mask" "F.Paste")
			(net "PVDDIO_P0")
		)
		(pad "L73" smd circle
			(at 32.580072 -28.710128 180)
			(size 0.450088 0.450088)
			(layers "F.Cu" "F.Mask" "F.Paste")
			(net "M_A_CPU0_SA_DQ<7>")
		)
		(pad "L74" smd circle
			(at 33.519872 -28.710128 180)
			(size 0.450088 0.450088)
			(layers "F.Cu" "F.Mask" "F.Paste")
			(net "M_A_CPU0_SA_DQ<8>")
		)
		(pad "L75" smd circle
			(at 34.459926 -28.710128 180)
			(size 0.450088 0.450088)
			(layers "F.Cu" "F.Mask" "F.Paste")
			(net "GND")
		)
		(pad "M2" smd circle
			(at -33.690052 -27.900122 180)
			(size 0.450088 0.450088)
			(layers "F.Cu" "F.Mask" "F.Paste")
			(net "M_G_CPU0_SA_DQ<10>")
		)
		(pad "M3" smd circle
			(at -32.749998 -27.900122 180)
			(size 0.450088 0.450088)
			(layers "F.Cu" "F.Mask" "F.Paste")
			(net "GND")
		)
		(pad "M4" smd circle
			(at -31.809944 -27.900122 180)
			(size 0.450088 0.450088)
			(layers "F.Cu" "F.Mask" "F.Paste")
			(net "M_G_CPU0_SA_DQ<9>")
		)
		(pad "M5" smd circle
			(at -30.86989 -27.900122 180)
			(size 0.450088 0.450088)
			(layers "F.Cu" "F.Mask" "F.Paste")
			(net "GND")
		)
		(pad "M6" smd circle
			(at -29.93009 -27.900122 180)
			(size 0.450088 0.450088)
			(layers "F.Cu" "F.Mask" "F.Paste")
			(net "M_K_CPU0_SA_DQ<10>")
		)
		(pad "M7" smd circle
			(at -28.990036 -27.900122 180)
			(size 0.450088 0.450088)
			(layers "F.Cu" "F.Mask" "F.Paste")
			(net "M_K_CPU0_SA_DQ<9>")
		)
		(pad "M8" smd circle
			(at -28.049982 -27.900122 180)
			(size 0.450088 0.450088)
			(layers "F.Cu" "F.Mask" "F.Paste")
			(net "GND")
		)
		(pad "M9" smd circle
			(at -27.109928 -27.900122 180)
			(size 0.450088 0.450088)
			(layers "F.Cu" "F.Mask" "F.Paste")
			(net "M_L_CPU0_SA_DQ<10>")
		)
		(pad "M10" smd circle
			(at -26.170128 -27.900122 180)
			(size 0.450088 0.450088)
			(layers "F.Cu" "F.Mask" "F.Paste")
			(net "GND")
		)
		(pad "M11" smd circle
			(at -25.230074 -27.900122 180)
			(size 0.450088 0.450088)
			(layers "F.Cu" "F.Mask" "F.Paste")
			(net "M_L_CPU0_SA_DQ<9>")
		)
		(pad "M12" smd circle
			(at -24.29002 -27.900122 180)
			(size 0.450088 0.450088)
			(layers "F.Cu" "F.Mask" "F.Paste")
			(net "GND")
		)
		(pad "M13" smd circle
			(at -23.349966 -27.900122 180)
			(size 0.450088 0.450088)
			(layers "F.Cu" "F.Mask" "F.Paste")
			(net "M_H_CPU0_SA_DQ<10>")
		)
		(pad "M14" smd circle
			(at -22.409912 -27.900122 180)
			(size 0.450088 0.450088)
			(layers "F.Cu" "F.Mask" "F.Paste")
			(net "M_H_CPU0_SA_DQ<9>")
		)
		(pad "M15" smd circle
			(at -21.470112 -27.900122 180)
			(size 0.450088 0.450088)
			(layers "F.Cu" "F.Mask" "F.Paste")
			(net "GND")
		)
		(pad "M16" smd circle
			(at -20.530058 -27.900122 180)
			(size 0.450088 0.450088)
			(layers "F.Cu" "F.Mask" "F.Paste")
			(net "M_J_CPU0_SA_DQ<10>")
		)
		(pad "M17" smd circle
			(at -19.590004 -27.900122 180)
			(size 0.450088 0.450088)
			(layers "F.Cu" "F.Mask" "F.Paste")
			(net "GND")
		)
		(pad "M18" smd circle
			(at -18.64995 -27.900122 180)
			(size 0.450088 0.450088)
			(layers "F.Cu" "F.Mask" "F.Paste")
			(net "M_J_CPU0_SA_DQ<9>")
		)
		(pad "M19" smd circle
			(at -17.709896 -27.900122 180)
			(size 0.450088 0.450088)
			(layers "F.Cu" "F.Mask" "F.Paste")
			(net "GND")
		)
		(pad "M20" smd circle
			(at -16.770096 -27.900122 180)
			(size 0.450088 0.450088)
			(layers "F.Cu" "F.Mask" "F.Paste")
			(net "M_I_CPU0_SA_DQ<10>")
		)
		(pad "M21" smd circle
			(at -15.830042 -27.900122 180)
			(size 0.450088 0.450088)
			(layers "F.Cu" "F.Mask" "F.Paste")
			(net "M_I_CPU0_SA_DQ<9>")
		)
		(pad "M22" smd circle
			(at -14.889988 -27.900122 180)
			(size 0.450088 0.450088)
			(layers "F.Cu" "F.Mask" "F.Paste")
			(net "GND")
		)
		(pad "M23" smd circle
			(at -13.949934 -27.900122 180)
			(size 0.450088 0.450088)
			(layers "F.Cu" "F.Mask" "F.Paste")
			(net "PVDDCR_CPU0_P0")
		)
		(pad "M24" smd circle
			(at -13.00988 -27.900122 180)
			(size 0.450088 0.450088)
			(layers "F.Cu" "F.Mask" "F.Paste")
			(net "PVDDCR_CPU0_P0")
		)
		(pad "M25" smd circle
			(at -12.07008 -27.900122 180)
			(size 0.450088 0.450088)
			(layers "F.Cu" "F.Mask" "F.Paste")
			(net "GND")
		)
		(pad "M26" smd circle
			(at -11.130026 -27.900122 180)
			(size 0.450088 0.450088)
			(layers "F.Cu" "F.Mask" "F.Paste")
			(net "PVDDCR_CPU0_P0")
		)
		(pad "M27" smd circle
			(at -10.189972 -27.900122 180)
			(size 0.450088 0.450088)
			(layers "F.Cu" "F.Mask" "F.Paste")
			(net "PVDDCR_CPU0_P0")
		)
		(pad "M28" smd circle
			(at -9.249918 -27.900122 180)
			(size 0.450088 0.450088)
			(layers "F.Cu" "F.Mask" "F.Paste")
			(net "GND")
		)
		(pad "M29" smd circle
			(at -8.310118 -27.900122 180)
			(size 0.450088 0.450088)
			(layers "F.Cu" "F.Mask" "F.Paste")
			(net "PVDDCR_CPU0_P0")
		)
		(pad "M30" smd circle
			(at -7.370064 -27.900122 180)
			(size 0.450088 0.450088)
			(layers "F.Cu" "F.Mask" "F.Paste")
			(net "PVDDCR_CPU0_P0")
		)
		(pad "M31" smd circle
			(at -6.43001 -27.900122 180)
			(size 0.450088 0.450088)
			(layers "F.Cu" "F.Mask" "F.Paste")
			(net "GND")
		)
		(pad "M32" smd circle
			(at -5.489956 -27.900122 180)
			(size 0.450088 0.450088)
			(layers "F.Cu" "F.Mask" "F.Paste")
			(net "PVDDCR_CPU0_P0")
		)
		(pad "M33" smd circle
			(at -4.549902 -27.900122 180)
			(size 0.450088 0.450088)
			(layers "F.Cu" "F.Mask" "F.Paste")
			(net "PVDDCR_CPU0_P0")
		)
		(pad "M34" smd circle
			(at -3.610102 -27.900122 180)
			(size 0.450088 0.450088)
			(layers "F.Cu" "F.Mask" "F.Paste")
			(net "GND")
		)
		(pad "M35" smd circle
			(at -2.670048 -27.900122 180)
			(size 0.450088 0.450088)
			(layers "F.Cu" "F.Mask" "F.Paste")
			(net "GMI_CPU0_G2_CPU1_G0_TX_DP<15>")
		)
		(pad "M36" smd circle
			(at -1.729994 -27.900122 180)
			(size 0.450088 0.450088)
			(layers "F.Cu" "F.Mask" "F.Paste")
			(net "GMI_CPU0_G2_CPU1_G0_TX_DN<15>")
		)
		(pad "M37" smd circle
			(at -0.78994 -27.900122 180)
			(size 0.450088 0.450088)
			(layers "F.Cu" "F.Mask" "F.Paste")
			(net "GND")
		)
		(pad "M39" smd circle
			(at 1.089914 -27.900122 180)
			(size 0.450088 0.450088)
			(layers "F.Cu" "F.Mask" "F.Paste")
			(net "GND")
		)
		(pad "M40" smd circle
			(at 2.029968 -27.900122 180)
			(size 0.450088 0.450088)
			(layers "F.Cu" "F.Mask" "F.Paste")
			(net "GMI_CPU1_G2_CPU0_G0_TX_DN<0>")
		)
		(pad "M41" smd circle
			(at 2.970022 -27.900122 180)
			(size 0.450088 0.450088)
			(layers "F.Cu" "F.Mask" "F.Paste")
			(net "GMI_CPU1_G2_CPU0_G0_TX_DP<0>")
		)
		(pad "M42" smd circle
			(at 3.910076 -27.900122 180)
			(size 0.450088 0.450088)
			(layers "F.Cu" "F.Mask" "F.Paste")
			(net "GND")
		)
		(pad "M43" smd circle
			(at 4.849876 -27.900122 180)
			(size 0.450088 0.450088)
			(layers "F.Cu" "F.Mask" "F.Paste")
			(net "PVDDCR_CPU0_P0")
		)
		(pad "M44" smd circle
			(at 5.78993 -27.900122 180)
			(size 0.450088 0.450088)
			(layers "F.Cu" "F.Mask" "F.Paste")
			(net "PVDDCR_CPU0_P0")
		)
		(pad "M45" smd circle
			(at 6.729984 -27.900122 180)
			(size 0.450088 0.450088)
			(layers "F.Cu" "F.Mask" "F.Paste")
			(net "GND")
		)
		(pad "M46" smd circle
			(at 7.670038 -27.900122 180)
			(size 0.450088 0.450088)
			(layers "F.Cu" "F.Mask" "F.Paste")
			(net "PVDDCR_CPU0_P0")
		)
		(pad "M47" smd circle
			(at 8.610092 -27.900122 180)
			(size 0.450088 0.450088)
			(layers "F.Cu" "F.Mask" "F.Paste")
			(net "PVDDCR_CPU0_P0")
		)
		(pad "M48" smd circle
			(at 9.549892 -27.900122 180)
			(size 0.450088 0.450088)
			(layers "F.Cu" "F.Mask" "F.Paste")
			(net "GND")
		)
		(pad "M49" smd circle
			(at 10.489946 -27.900122 180)
			(size 0.450088 0.450088)
			(layers "F.Cu" "F.Mask" "F.Paste")
			(net "PVDDCR_CPU0_P0")
		)
		(pad "M50" smd circle
			(at 11.43 -27.900122 180)
			(size 0.450088 0.450088)
			(layers "F.Cu" "F.Mask" "F.Paste")
			(net "PVDDCR_CPU0_P0")
		)
		(pad "M51" smd circle
			(at 12.370054 -27.900122 180)
			(size 0.450088 0.450088)
			(layers "F.Cu" "F.Mask" "F.Paste")
			(net "GND")
		)
		(pad "M52" smd circle
			(at 13.310108 -27.900122 180)
			(size 0.450088 0.450088)
			(layers "F.Cu" "F.Mask" "F.Paste")
			(net "PVDDCR_CPU0_P0")
		)
		(pad "M53" smd circle
			(at 14.249908 -27.900122 180)
			(size 0.450088 0.450088)
			(layers "F.Cu" "F.Mask" "F.Paste")
			(net "PVDDCR_CPU0_P0")
		)
		(pad "M54" smd circle
			(at 15.189962 -27.900122 180)
			(size 0.450088 0.450088)
			(layers "F.Cu" "F.Mask" "F.Paste")
			(net "GND")
		)
		(pad "M55" smd circle
			(at 16.130016 -27.900122 180)
			(size 0.450088 0.450088)
			(layers "F.Cu" "F.Mask" "F.Paste")
			(net "M_C_CPU0_SA_DQ<9>")
		)
		(pad "M56" smd circle
			(at 17.07007 -27.900122 180)
			(size 0.450088 0.450088)
			(layers "F.Cu" "F.Mask" "F.Paste")
			(net "M_C_CPU0_SA_DQ<10>")
		)
		(pad "M57" smd circle
			(at 18.010124 -27.900122 180)
			(size 0.450088 0.450088)
			(layers "F.Cu" "F.Mask" "F.Paste")
			(net "GND")
		)
		(pad "M58" smd circle
			(at 18.949924 -27.900122 180)
			(size 0.450088 0.450088)
			(layers "F.Cu" "F.Mask" "F.Paste")
			(net "M_D_CPU0_SA_DQ<9>")
		)
		(pad "M59" smd circle
			(at 19.889978 -27.900122 180)
			(size 0.450088 0.450088)
			(layers "F.Cu" "F.Mask" "F.Paste")
			(net "GND")
		)
		(pad "M60" smd circle
			(at 20.830032 -27.900122 180)
			(size 0.450088 0.450088)
			(layers "F.Cu" "F.Mask" "F.Paste")
			(net "M_D_CPU0_SA_DQ<10>")
		)
		(pad "M61" smd circle
			(at 21.770086 -27.900122 180)
			(size 0.450088 0.450088)
			(layers "F.Cu" "F.Mask" "F.Paste")
			(net "GND")
		)
		(pad "M62" smd circle
			(at 22.709886 -27.900122 180)
			(size 0.450088 0.450088)
			(layers "F.Cu" "F.Mask" "F.Paste")
			(net "M_B_CPU0_SA_DQ<9>")
		)
		(pad "M63" smd circle
			(at 23.64994 -27.900122 180)
			(size 0.450088 0.450088)
			(layers "F.Cu" "F.Mask" "F.Paste")
			(net "M_B_CPU0_SA_DQ<10>")
		)
		(pad "M64" smd circle
			(at 24.589994 -27.900122 180)
			(size 0.450088 0.450088)
			(layers "F.Cu" "F.Mask" "F.Paste")
			(net "GND")
		)
		(pad "M65" smd circle
			(at 25.530048 -27.900122 180)
			(size 0.450088 0.450088)
			(layers "F.Cu" "F.Mask" "F.Paste")
			(net "M_F_CPU0_SA_DQ<9>")
		)
		(pad "M66" smd circle
			(at 26.470102 -27.900122 180)
			(size 0.450088 0.450088)
			(layers "F.Cu" "F.Mask" "F.Paste")
			(net "GND")
		)
		(pad "M67" smd circle
			(at 27.409902 -27.900122 180)
			(size 0.450088 0.450088)
			(layers "F.Cu" "F.Mask" "F.Paste")
			(net "M_F_CPU0_SA_DQ<10>")
		)
		(pad "M68" smd circle
			(at 28.349956 -27.900122 180)
			(size 0.450088 0.450088)
			(layers "F.Cu" "F.Mask" "F.Paste")
			(net "GND")
		)
		(pad "M69" smd circle
			(at 29.29001 -27.900122 180)
			(size 0.450088 0.450088)
			(layers "F.Cu" "F.Mask" "F.Paste")
			(net "M_E_CPU0_SA_DQ<9>")
		)
		(pad "M70" smd circle
			(at 30.230064 -27.900122 180)
			(size 0.450088 0.450088)
			(layers "F.Cu" "F.Mask" "F.Paste")
			(net "M_E_CPU0_SA_DQ<10>")
		)
		(pad "M71" smd circle
			(at 31.170118 -27.900122 180)
			(size 0.450088 0.450088)
			(layers "F.Cu" "F.Mask" "F.Paste")
			(net "GND")
		)
		(pad "M72" smd circle
			(at 32.109918 -27.900122 180)
			(size 0.450088 0.450088)
			(layers "F.Cu" "F.Mask" "F.Paste")
			(net "M_A_CPU0_SA_DQ<9>")
		)
		(pad "M73" smd circle
			(at 33.049972 -27.900122 180)
			(size 0.450088 0.450088)
			(layers "F.Cu" "F.Mask" "F.Paste")
			(net "GND")
		)
		(pad "M74" smd circle
			(at 33.990026 -27.900122 180)
			(size 0.450088 0.450088)
			(layers "F.Cu" "F.Mask" "F.Paste")
			(net "M_A_CPU0_SA_DQ<10>")
		)
		(pad "N1" smd circle
			(at -34.159952 -27.090116 180)
			(size 0.450088 0.450088)
			(layers "F.Cu" "F.Mask" "F.Paste")
			(net "GND")
		)
		(pad "N2" smd circle
			(at -33.219898 -27.090116 180)
			(size 0.450088 0.450088)
			(layers "F.Cu" "F.Mask" "F.Paste")
			(net "M_G_CPU0_SA_DQS_DP<1>")
		)
		(pad "N3" smd circle
			(at -32.280098 -27.090116 180)
			(size 0.450088 0.450088)
			(layers "F.Cu" "F.Mask" "F.Paste")
			(net "M_G_CPU0_SA_DQ<11>")
		)
		(pad "N4" smd circle
			(at -31.340044 -27.090116 180)
			(size 0.450088 0.450088)
			(layers "F.Cu" "F.Mask" "F.Paste")
			(net "GND")
		)
		(pad "N5" smd circle
			(at -30.39999 -27.090116 180)
			(size 0.450088 0.450088)
			(layers "F.Cu" "F.Mask" "F.Paste")
			(net "M_K_CPU0_SA_DQS_DP<1>")
		)
		(pad "N6" smd circle
			(at -29.459936 -27.090116 180)
			(size 0.450088 0.450088)
			(layers "F.Cu" "F.Mask" "F.Paste")
			(net "GND")
		)
		(pad "N7" smd circle
			(at -28.519882 -27.090116 180)
			(size 0.450088 0.450088)
			(layers "F.Cu" "F.Mask" "F.Paste")
			(net "M_K_CPU0_SA_DQ<11>")
		)
		(pad "N8" smd circle
			(at -27.580082 -27.090116 180)
			(size 0.450088 0.450088)
			(layers "F.Cu" "F.Mask" "F.Paste")
			(net "GND")
		)
		(pad "N9" smd circle
			(at -26.640028 -27.090116 180)
			(size 0.450088 0.450088)
			(layers "F.Cu" "F.Mask" "F.Paste")
			(net "M_L_CPU0_SA_DQS_DP<1>")
		)
		(pad "N10" smd circle
			(at -25.699974 -27.090116 180)
			(size 0.450088 0.450088)
			(layers "F.Cu" "F.Mask" "F.Paste")
			(net "M_L_CPU0_SA_DQ<11>")
		)
		(pad "N11" smd circle
			(at -24.75992 -27.090116 180)
			(size 0.450088 0.450088)
			(layers "F.Cu" "F.Mask" "F.Paste")
			(net "GND")
		)
		(pad "N12" smd circle
			(at -23.82012 -27.090116 180)
			(size 0.450088 0.450088)
			(layers "F.Cu" "F.Mask" "F.Paste")
			(net "M_H_CPU0_SA_DQS_DP<1>")
		)
		(pad "N13" smd circle
			(at -22.880066 -27.090116 180)
			(size 0.450088 0.450088)
			(layers "F.Cu" "F.Mask" "F.Paste")
			(net "GND")
		)
		(pad "N14" smd circle
			(at -21.940012 -27.090116 180)
			(size 0.450088 0.450088)
			(layers "F.Cu" "F.Mask" "F.Paste")
			(net "M_H_CPU0_SA_DQ<11>")
		)
		(pad "N15" smd circle
			(at -20.999958 -27.090116 180)
			(size 0.450088 0.450088)
			(layers "F.Cu" "F.Mask" "F.Paste")
			(net "GND")
		)
		(pad "N16" smd circle
			(at -20.059904 -27.090116 180)
			(size 0.450088 0.450088)
			(layers "F.Cu" "F.Mask" "F.Paste")
			(net "M_J_CPU0_SA_DQS_DP<1>")
		)
		(pad "N17" smd circle
			(at -19.120104 -27.090116 180)
			(size 0.450088 0.450088)
			(layers "F.Cu" "F.Mask" "F.Paste")
			(net "M_J_CPU0_SA_DQ<11>")
		)
		(pad "N18" smd circle
			(at -18.18005 -27.090116 180)
			(size 0.450088 0.450088)
			(layers "F.Cu" "F.Mask" "F.Paste")
			(net "GND")
		)
		(pad "N19" smd circle
			(at -17.239996 -27.090116 180)
			(size 0.450088 0.450088)
			(layers "F.Cu" "F.Mask" "F.Paste")
			(net "M_I_CPU0_SA_DQS_DP<1>")
		)
		(pad "N20" smd circle
			(at -16.299942 -27.090116 180)
			(size 0.450088 0.450088)
			(layers "F.Cu" "F.Mask" "F.Paste")
			(net "GND")
		)
		(pad "N21" smd circle
			(at -15.359888 -27.090116 180)
			(size 0.450088 0.450088)
			(layers "F.Cu" "F.Mask" "F.Paste")
			(net "M_I_CPU0_SA_DQ<11>")
		)
		(pad "N22" smd circle
			(at -14.420088 -27.090116 180)
			(size 0.450088 0.450088)
			(layers "F.Cu" "F.Mask" "F.Paste")
			(net "GND")
		)
		(pad "N23" smd circle
			(at -13.480034 -27.090116 180)
			(size 0.450088 0.450088)
			(layers "F.Cu" "F.Mask" "F.Paste")
			(net "GMI_CPU0_G2_CPU1_G0_TX_DP<0>")
		)
		(pad "N24" smd circle
			(at -12.53998 -27.090116 180)
			(size 0.450088 0.450088)
			(layers "F.Cu" "F.Mask" "F.Paste")
			(net "GMI_CPU0_G2_CPU1_G0_TX_DN<0>")
		)
		(pad "N25" smd circle
			(at -11.599926 -27.090116 180)
			(size 0.450088 0.450088)
			(layers "F.Cu" "F.Mask" "F.Paste")
			(net "GND")
		)
		(pad "N26" smd circle
			(at -10.659872 -27.090116 180)
			(size 0.450088 0.450088)
			(layers "F.Cu" "F.Mask" "F.Paste")
			(net "P5E_CPU0_G3_TX_DP<5>")
		)
		(pad "N27" smd circle
			(at -9.720072 -27.090116 180)
			(size 0.450088 0.450088)
			(layers "F.Cu" "F.Mask" "F.Paste")
			(net "P5E_CPU0_G3_TX_DN<5>")
		)
		(pad "N28" smd circle
			(at -8.780018 -27.090116 180)
			(size 0.450088 0.450088)
			(layers "F.Cu" "F.Mask" "F.Paste")
			(net "GND")
		)
		(pad "N29" smd circle
			(at -7.839964 -27.090116 180)
			(size 0.450088 0.450088)
			(layers "F.Cu" "F.Mask" "F.Paste")
			(net "P5E_CPU0_G3_TX_DP<8>")
		)
		(pad "N30" smd circle
			(at -6.89991 -27.090116 180)
			(size 0.450088 0.450088)
			(layers "F.Cu" "F.Mask" "F.Paste")
			(net "P5E_CPU0_G3_TX_DN<8>")
		)
		(pad "N31" smd circle
			(at -5.96011 -27.090116 180)
			(size 0.450088 0.450088)
			(layers "F.Cu" "F.Mask" "F.Paste")
			(net "GND")
		)
		(pad "N32" smd circle
			(at -5.020056 -27.090116 180)
			(size 0.450088 0.450088)
			(layers "F.Cu" "F.Mask" "F.Paste")
			(net "P5E_CPU0_G3_TX_DP<11>")
		)
		(pad "N33" smd circle
			(at -4.080002 -27.090116 180)
			(size 0.450088 0.450088)
			(layers "F.Cu" "F.Mask" "F.Paste")
			(net "P5E_CPU0_G3_TX_DN<11>")
		)
		(pad "N34" smd circle
			(at -3.139948 -27.090116 180)
			(size 0.450088 0.450088)
			(layers "F.Cu" "F.Mask" "F.Paste")
			(net "GND")
		)
		(pad "N35" smd circle
			(at -2.199894 -27.090116 180)
			(size 0.450088 0.450088)
			(layers "F.Cu" "F.Mask" "F.Paste")
			(net "PVDDCR_CPU0_P0")
		)
		(pad "N36" smd circle
			(at -1.260094 -27.090116 180)
			(size 0.450088 0.450088)
			(layers "F.Cu" "F.Mask" "F.Paste")
			(net "PVDDCR_CPU0_P0")
		)
		(pad "N40" smd circle
			(at 1.560068 -27.090116 180)
			(size 0.450088 0.450088)
			(layers "F.Cu" "F.Mask" "F.Paste")
			(net "PVDDCR_CPU0_P0")
		)
		(pad "N41" smd circle
			(at 2.500122 -27.090116 180)
			(size 0.450088 0.450088)
			(layers "F.Cu" "F.Mask" "F.Paste")
			(net "PVDDCR_CPU0_P0")
		)
		(pad "N42" smd circle
			(at 3.439922 -27.090116 180)
			(size 0.450088 0.450088)
			(layers "F.Cu" "F.Mask" "F.Paste")
			(net "GND")
		)
		(pad "N43" smd circle
			(at 4.379976 -27.090116 180)
			(size 0.450088 0.450088)
			(layers "F.Cu" "F.Mask" "F.Paste")
			(net "GMI_CPU1_G3_CPU0_G1_TX_DN<4>")
		)
		(pad "N44" smd circle
			(at 5.32003 -27.090116 180)
			(size 0.450088 0.450088)
			(layers "F.Cu" "F.Mask" "F.Paste")
			(net "GMI_CPU1_G3_CPU0_G1_TX_DP<4>")
		)
		(pad "N45" smd circle
			(at 6.260084 -27.090116 180)
			(size 0.450088 0.450088)
			(layers "F.Cu" "F.Mask" "F.Paste")
			(net "GND")
		)
		(pad "N46" smd circle
			(at 7.199884 -27.090116 180)
			(size 0.450088 0.450088)
			(layers "F.Cu" "F.Mask" "F.Paste")
			(net "GMI_CPU1_G3_CPU0_G1_TX_DN<7>")
		)
		(pad "N47" smd circle
			(at 8.139938 -27.090116 180)
			(size 0.450088 0.450088)
			(layers "F.Cu" "F.Mask" "F.Paste")
			(net "GMI_CPU1_G3_CPU0_G1_TX_DP<7>")
		)
		(pad "N48" smd circle
			(at 9.079992 -27.090116 180)
			(size 0.450088 0.450088)
			(layers "F.Cu" "F.Mask" "F.Paste")
			(net "GND")
		)
		(pad "N49" smd circle
			(at 10.020046 -27.090116 180)
			(size 0.450088 0.450088)
			(layers "F.Cu" "F.Mask" "F.Paste")
			(net "GMI_CPU1_G3_CPU0_G1_TX_DN<10>")
		)
		(pad "N50" smd circle
			(at 10.9601 -27.090116 180)
			(size 0.450088 0.450088)
			(layers "F.Cu" "F.Mask" "F.Paste")
			(net "GMI_CPU1_G3_CPU0_G1_TX_DP<10>")
		)
		(pad "N51" smd circle
			(at 11.8999 -27.090116 180)
			(size 0.450088 0.450088)
			(layers "F.Cu" "F.Mask" "F.Paste")
			(net "GND")
		)
		(pad "N52" smd circle
			(at 12.839954 -27.090116 180)
			(size 0.450088 0.450088)
			(layers "F.Cu" "F.Mask" "F.Paste")
			(net "GMI_CPU1_G2_CPU0_G0_TX_DN<15>")
		)
		(pad "N53" smd circle
			(at 13.780008 -27.090116 180)
			(size 0.450088 0.450088)
			(layers "F.Cu" "F.Mask" "F.Paste")
			(net "GMI_CPU1_G2_CPU0_G0_TX_DP<15>")
		)
		(pad "N54" smd circle
			(at 14.720062 -27.090116 180)
			(size 0.450088 0.450088)
			(layers "F.Cu" "F.Mask" "F.Paste")
			(net "GND")
		)
		(pad "N55" smd circle
			(at 15.660116 -27.090116 180)
			(size 0.450088 0.450088)
			(layers "F.Cu" "F.Mask" "F.Paste")
			(net "M_C_CPU0_SA_DQ<11>")
		)
		(pad "N56" smd circle
			(at 16.599916 -27.090116 180)
			(size 0.450088 0.450088)
			(layers "F.Cu" "F.Mask" "F.Paste")
			(net "GND")
		)
		(pad "N57" smd circle
			(at 17.53997 -27.090116 180)
			(size 0.450088 0.450088)
			(layers "F.Cu" "F.Mask" "F.Paste")
			(net "M_C_CPU0_SA_DQS_DP<1>")
		)
		(pad "N58" smd circle
			(at 18.480024 -27.090116 180)
			(size 0.450088 0.450088)
			(layers "F.Cu" "F.Mask" "F.Paste")
			(net "GND")
		)
		(pad "N59" smd circle
			(at 19.420078 -27.090116 180)
			(size 0.450088 0.450088)
			(layers "F.Cu" "F.Mask" "F.Paste")
			(net "M_D_CPU0_SA_DQ<11>")
		)
		(pad "N60" smd circle
			(at 20.359878 -27.090116 180)
			(size 0.450088 0.450088)
			(layers "F.Cu" "F.Mask" "F.Paste")
			(net "M_D_CPU0_SA_DQS_DP<1>")
		)
		(pad "N61" smd circle
			(at 21.299932 -27.090116 180)
			(size 0.450088 0.450088)
			(layers "F.Cu" "F.Mask" "F.Paste")
			(net "GND")
		)
		(pad "N62" smd circle
			(at 22.239986 -27.090116 180)
			(size 0.450088 0.450088)
			(layers "F.Cu" "F.Mask" "F.Paste")
			(net "M_B_CPU0_SA_DQ<11>")
		)
		(pad "N63" smd circle
			(at 23.18004 -27.090116 180)
			(size 0.450088 0.450088)
			(layers "F.Cu" "F.Mask" "F.Paste")
			(net "GND")
		)
		(pad "N64" smd circle
			(at 24.120094 -27.090116 180)
			(size 0.450088 0.450088)
			(layers "F.Cu" "F.Mask" "F.Paste")
			(net "M_B_CPU0_SA_DQS_DP<1>")
		)
		(pad "N65" smd circle
			(at 25.059894 -27.090116 180)
			(size 0.450088 0.450088)
			(layers "F.Cu" "F.Mask" "F.Paste")
			(net "GND")
		)
		(pad "N66" smd circle
			(at 25.999948 -27.090116 180)
			(size 0.450088 0.450088)
			(layers "F.Cu" "F.Mask" "F.Paste")
			(net "M_F_CPU0_SA_DQ<11>")
		)
		(pad "N67" smd circle
			(at 26.940002 -27.090116 180)
			(size 0.450088 0.450088)
			(layers "F.Cu" "F.Mask" "F.Paste")
			(net "M_F_CPU0_SA_DQS_DP<1>")
		)
		(pad "N68" smd circle
			(at 27.880056 -27.090116 180)
			(size 0.450088 0.450088)
			(layers "F.Cu" "F.Mask" "F.Paste")
			(net "GND")
		)
		(pad "N69" smd circle
			(at 28.82011 -27.090116 180)
			(size 0.450088 0.450088)
			(layers "F.Cu" "F.Mask" "F.Paste")
			(net "M_E_CPU0_SA_DQ<11>")
		)
		(pad "N70" smd circle
			(at 29.75991 -27.090116 180)
			(size 0.450088 0.450088)
			(layers "F.Cu" "F.Mask" "F.Paste")
			(net "GND")
		)
		(pad "N71" smd circle
			(at 30.699964 -27.090116 180)
			(size 0.450088 0.450088)
			(layers "F.Cu" "F.Mask" "F.Paste")
			(net "M_E_CPU0_SA_DQS_DP<1>")
		)
		(pad "N72" smd circle
			(at 31.640018 -27.090116 180)
			(size 0.450088 0.450088)
			(layers "F.Cu" "F.Mask" "F.Paste")
			(net "GND")
		)
		(pad "N73" smd circle
			(at 32.580072 -27.090116 180)
			(size 0.450088 0.450088)
			(layers "F.Cu" "F.Mask" "F.Paste")
			(net "M_A_CPU0_SA_DQ<11>")
		)
		(pad "N74" smd circle
			(at 33.519872 -27.090116 180)
			(size 0.450088 0.450088)
			(layers "F.Cu" "F.Mask" "F.Paste")
			(net "M_A_CPU0_SA_DQS_DP<1>")
		)
		(pad "N75" smd circle
			(at 34.459926 -27.090116 180)
			(size 0.450088 0.450088)
			(layers "F.Cu" "F.Mask" "F.Paste")
			(net "GND")
		)
		(pad "P2" smd circle
			(at -33.690052 -26.28011 180)
			(size 0.450088 0.450088)
			(layers "F.Cu" "F.Mask" "F.Paste")
			(net "M_G_CPU0_SA_DQS_DN<1>")
		)
		(pad "P3" smd circle
			(at -32.749998 -26.28011 180)
			(size 0.450088 0.450088)
			(layers "F.Cu" "F.Mask" "F.Paste")
			(net "GND")
		)
		(pad "P4" smd circle
			(at -31.809944 -26.28011 180)
			(size 0.450088 0.450088)
			(layers "F.Cu" "F.Mask" "F.Paste")
			(net "M_G_CPU0_SA_DQS_DN<6>")
		)
		(pad "P5" smd circle
			(at -30.86989 -26.28011 180)
			(size 0.450088 0.450088)
			(layers "F.Cu" "F.Mask" "F.Paste")
			(net "PVDDCR_SOC_P0")
		)
		(pad "P6" smd circle
			(at -29.93009 -26.28011 180)
			(size 0.450088 0.450088)
			(layers "F.Cu" "F.Mask" "F.Paste")
			(net "M_K_CPU0_SA_DQS_DN<1>")
		)
		(pad "P7" smd circle
			(at -28.990036 -26.28011 180)
			(size 0.450088 0.450088)
			(layers "F.Cu" "F.Mask" "F.Paste")
			(net "M_K_CPU0_SA_DQS_DN<6>")
		)
		(pad "P8" smd circle
			(at -28.049982 -26.28011 180)
			(size 0.450088 0.450088)
			(layers "F.Cu" "F.Mask" "F.Paste")
			(net "GND")
		)
		(pad "P9" smd circle
			(at -27.109928 -26.28011 180)
			(size 0.450088 0.450088)
			(layers "F.Cu" "F.Mask" "F.Paste")
			(net "M_L_CPU0_SA_DQS_DN<1>")
		)
		(pad "P10" smd circle
			(at -26.170128 -26.28011 180)
			(size 0.450088 0.450088)
			(layers "F.Cu" "F.Mask" "F.Paste")
			(net "GND")
		)
		(pad "P11" smd circle
			(at -25.230074 -26.28011 180)
			(size 0.450088 0.450088)
			(layers "F.Cu" "F.Mask" "F.Paste")
			(net "M_L_CPU0_SA_DQS_DN<6>")
		)
		(pad "P12" smd circle
			(at -24.29002 -26.28011 180)
			(size 0.450088 0.450088)
			(layers "F.Cu" "F.Mask" "F.Paste")
			(net "PVDDCR_SOC_P0")
		)
		(pad "P13" smd circle
			(at -23.349966 -26.28011 180)
			(size 0.450088 0.450088)
			(layers "F.Cu" "F.Mask" "F.Paste")
			(net "M_H_CPU0_SA_DQS_DN<1>")
		)
		(pad "P14" smd circle
			(at -22.409912 -26.28011 180)
			(size 0.450088 0.450088)
			(layers "F.Cu" "F.Mask" "F.Paste")
			(net "M_H_CPU0_SA_DQS_DN<6>")
		)
		(pad "P15" smd circle
			(at -21.470112 -26.28011 180)
			(size 0.450088 0.450088)
			(layers "F.Cu" "F.Mask" "F.Paste")
			(net "GND")
		)
		(pad "P16" smd circle
			(at -20.530058 -26.28011 180)
			(size 0.450088 0.450088)
			(layers "F.Cu" "F.Mask" "F.Paste")
			(net "M_J_CPU0_SA_DQS_DN<1>")
		)
		(pad "P17" smd circle
			(at -19.590004 -26.28011 180)
			(size 0.450088 0.450088)
			(layers "F.Cu" "F.Mask" "F.Paste")
			(net "GND")
		)
		(pad "P18" smd circle
			(at -18.64995 -26.28011 180)
			(size 0.450088 0.450088)
			(layers "F.Cu" "F.Mask" "F.Paste")
			(net "M_J_CPU0_SA_DQS_DN<6>")
		)
		(pad "P19" smd circle
			(at -17.709896 -26.28011 180)
			(size 0.450088 0.450088)
			(layers "F.Cu" "F.Mask" "F.Paste")
			(net "PVDDCR_SOC_P0")
		)
		(pad "P20" smd circle
			(at -16.770096 -26.28011 180)
			(size 0.450088 0.450088)
			(layers "F.Cu" "F.Mask" "F.Paste")
			(net "M_I_CPU0_SA_DQS_DN<1>")
		)
		(pad "P21" smd circle
			(at -15.830042 -26.28011 180)
			(size 0.450088 0.450088)
			(layers "F.Cu" "F.Mask" "F.Paste")
			(net "M_I_CPU0_SA_DQS_DN<6>")
		)
		(pad "P22" smd circle
			(at -14.889988 -26.28011 180)
			(size 0.450088 0.450088)
			(layers "F.Cu" "F.Mask" "F.Paste")
			(net "PVDDCR_SOC_P0")
		)
		(pad "P23" smd circle
			(at -13.949934 -26.28011 180)
			(size 0.450088 0.450088)
			(layers "F.Cu" "F.Mask" "F.Paste")
			(net "GND")
		)
		(pad "P24" smd circle
			(at -13.00988 -26.28011 180)
			(size 0.450088 0.450088)
			(layers "F.Cu" "F.Mask" "F.Paste")
			(net "GND")
		)
		(pad "P25" smd circle
			(at -12.07008 -26.28011 180)
			(size 0.450088 0.450088)
			(layers "F.Cu" "F.Mask" "F.Paste")
			(net "GND")
		)
		(pad "P26" smd circle
			(at -11.130026 -26.28011 180)
			(size 0.450088 0.450088)
			(layers "F.Cu" "F.Mask" "F.Paste")
			(net "GND")
		)
		(pad "P27" smd circle
			(at -10.189972 -26.28011 180)
			(size 0.450088 0.450088)
			(layers "F.Cu" "F.Mask" "F.Paste")
			(net "GND")
		)
		(pad "P28" smd circle
			(at -9.249918 -26.28011 180)
			(size 0.450088 0.450088)
			(layers "F.Cu" "F.Mask" "F.Paste")
			(net "GND")
		)
		(pad "P29" smd circle
			(at -8.310118 -26.28011 180)
			(size 0.450088 0.450088)
			(layers "F.Cu" "F.Mask" "F.Paste")
			(net "GND")
		)
		(pad "P30" smd circle
			(at -7.370064 -26.28011 180)
			(size 0.450088 0.450088)
			(layers "F.Cu" "F.Mask" "F.Paste")
			(net "GND")
		)
		(pad "P31" smd circle
			(at -6.43001 -26.28011 180)
			(size 0.450088 0.450088)
			(layers "F.Cu" "F.Mask" "F.Paste")
			(net "GND")
		)
		(pad "P32" smd circle
			(at -5.489956 -26.28011 180)
			(size 0.450088 0.450088)
			(layers "F.Cu" "F.Mask" "F.Paste")
			(net "GND")
		)
		(pad "P33" smd circle
			(at -4.549902 -26.28011 180)
			(size 0.450088 0.450088)
			(layers "F.Cu" "F.Mask" "F.Paste")
			(net "GND")
		)
		(pad "P34" smd circle
			(at -3.610102 -26.28011 180)
			(size 0.450088 0.450088)
			(layers "F.Cu" "F.Mask" "F.Paste")
			(net "GND")
		)
		(pad "P35" smd circle
			(at -2.670048 -26.28011 180)
			(size 0.450088 0.450088)
			(layers "F.Cu" "F.Mask" "F.Paste")
			(net "P5E_CPU0_G3_TX_DP<13>")
		)
		(pad "P36" smd circle
			(at -1.729994 -26.28011 180)
			(size 0.450088 0.450088)
			(layers "F.Cu" "F.Mask" "F.Paste")
			(net "P5E_CPU0_G3_TX_DN<13>")
		)
		(pad "P37" smd circle
			(at -0.78994 -26.28011 180)
			(size 0.450088 0.450088)
			(layers "F.Cu" "F.Mask" "F.Paste")
			(net "GND")
		)
		(pad "P39" smd circle
			(at 1.089914 -26.28011 180)
			(size 0.450088 0.450088)
			(layers "F.Cu" "F.Mask" "F.Paste")
			(net "GND")
		)
		(pad "P40" smd circle
			(at 2.029968 -26.28011 180)
			(size 0.450088 0.450088)
			(layers "F.Cu" "F.Mask" "F.Paste")
			(net "GMI_CPU1_G3_CPU0_G1_TX_DN<2>")
		)
		(pad "P41" smd circle
			(at 2.970022 -26.28011 180)
			(size 0.450088 0.450088)
			(layers "F.Cu" "F.Mask" "F.Paste")
			(net "GMI_CPU1_G3_CPU0_G1_TX_DP<2>")
		)
		(pad "P42" smd circle
			(at 3.910076 -26.28011 180)
			(size 0.450088 0.450088)
			(layers "F.Cu" "F.Mask" "F.Paste")
			(net "GND")
		)
		(pad "P43" smd circle
			(at 4.849876 -26.28011 180)
			(size 0.450088 0.450088)
			(layers "F.Cu" "F.Mask" "F.Paste")
			(net "GND")
		)
		(pad "P44" smd circle
			(at 5.78993 -26.28011 180)
			(size 0.450088 0.450088)
			(layers "F.Cu" "F.Mask" "F.Paste")
			(net "GND")
		)
		(pad "P45" smd circle
			(at 6.729984 -26.28011 180)
			(size 0.450088 0.450088)
			(layers "F.Cu" "F.Mask" "F.Paste")
			(net "GND")
		)
		(pad "P46" smd circle
			(at 7.670038 -26.28011 180)
			(size 0.450088 0.450088)
			(layers "F.Cu" "F.Mask" "F.Paste")
			(net "GND")
		)
		(pad "P47" smd circle
			(at 8.610092 -26.28011 180)
			(size 0.450088 0.450088)
			(layers "F.Cu" "F.Mask" "F.Paste")
			(net "GND")
		)
		(pad "P48" smd circle
			(at 9.549892 -26.28011 180)
			(size 0.450088 0.450088)
			(layers "F.Cu" "F.Mask" "F.Paste")
			(net "GND")
		)
		(pad "P49" smd circle
			(at 10.489946 -26.28011 180)
			(size 0.450088 0.450088)
			(layers "F.Cu" "F.Mask" "F.Paste")
			(net "GND")
		)
		(pad "P50" smd circle
			(at 11.43 -26.28011 180)
			(size 0.450088 0.450088)
			(layers "F.Cu" "F.Mask" "F.Paste")
			(net "GND")
		)
		(pad "P51" smd circle
			(at 12.370054 -26.28011 180)
			(size 0.450088 0.450088)
			(layers "F.Cu" "F.Mask" "F.Paste")
			(net "GND")
		)
		(pad "P52" smd circle
			(at 13.310108 -26.28011 180)
			(size 0.450088 0.450088)
			(layers "F.Cu" "F.Mask" "F.Paste")
			(net "GND")
		)
		(pad "P53" smd circle
			(at 14.249908 -26.28011 180)
			(size 0.450088 0.450088)
			(layers "F.Cu" "F.Mask" "F.Paste")
			(net "GND")
		)
		(pad "P54" smd circle
			(at 15.189962 -26.28011 180)
			(size 0.450088 0.450088)
			(layers "F.Cu" "F.Mask" "F.Paste")
			(net "PVDDIO_P0")
		)
		(pad "P55" smd circle
			(at 16.130016 -26.28011 180)
			(size 0.450088 0.450088)
			(layers "F.Cu" "F.Mask" "F.Paste")
			(net "M_C_CPU0_SA_DQS_DN<6>")
		)
		(pad "P56" smd circle
			(at 17.07007 -26.28011 180)
			(size 0.450088 0.450088)
			(layers "F.Cu" "F.Mask" "F.Paste")
			(net "M_C_CPU0_SA_DQS_DN<1>")
		)
		(pad "P57" smd circle
			(at 18.010124 -26.28011 180)
			(size 0.450088 0.450088)
			(layers "F.Cu" "F.Mask" "F.Paste")
			(net "PVDDIO_P0")
		)
		(pad "P58" smd circle
			(at 18.949924 -26.28011 180)
			(size 0.450088 0.450088)
			(layers "F.Cu" "F.Mask" "F.Paste")
			(net "M_D_CPU0_SA_DQS_DN<6>")
		)
		(pad "P59" smd circle
			(at 19.889978 -26.28011 180)
			(size 0.450088 0.450088)
			(layers "F.Cu" "F.Mask" "F.Paste")
			(net "GND")
		)
		(pad "P60" smd circle
			(at 20.830032 -26.28011 180)
			(size 0.450088 0.450088)
			(layers "F.Cu" "F.Mask" "F.Paste")
			(net "M_D_CPU0_SA_DQS_DN<1>")
		)
		(pad "P61" smd circle
			(at 21.770086 -26.28011 180)
			(size 0.450088 0.450088)
			(layers "F.Cu" "F.Mask" "F.Paste")
			(net "GND")
		)
		(pad "P62" smd circle
			(at 22.709886 -26.28011 180)
			(size 0.450088 0.450088)
			(layers "F.Cu" "F.Mask" "F.Paste")
			(net "M_B_CPU0_SA_DQS_DN<6>")
		)
		(pad "P63" smd circle
			(at 23.64994 -26.28011 180)
			(size 0.450088 0.450088)
			(layers "F.Cu" "F.Mask" "F.Paste")
			(net "M_B_CPU0_SA_DQS_DN<1>")
		)
		(pad "P64" smd circle
			(at 24.589994 -26.28011 180)
			(size 0.450088 0.450088)
			(layers "F.Cu" "F.Mask" "F.Paste")
			(net "PVDDIO_P0")
		)
		(pad "P65" smd circle
			(at 25.530048 -26.28011 180)
			(size 0.450088 0.450088)
			(layers "F.Cu" "F.Mask" "F.Paste")
			(net "M_F_CPU0_SA_DQS_DN<6>")
		)
		(pad "P66" smd circle
			(at 26.470102 -26.28011 180)
			(size 0.450088 0.450088)
			(layers "F.Cu" "F.Mask" "F.Paste")
			(net "GND")
		)
		(pad "P67" smd circle
			(at 27.409902 -26.28011 180)
			(size 0.450088 0.450088)
			(layers "F.Cu" "F.Mask" "F.Paste")
			(net "M_F_CPU0_SA_DQS_DN<1>")
		)
		(pad "P68" smd circle
			(at 28.349956 -26.28011 180)
			(size 0.450088 0.450088)
			(layers "F.Cu" "F.Mask" "F.Paste")
			(net "GND")
		)
		(pad "P69" smd circle
			(at 29.29001 -26.28011 180)
			(size 0.450088 0.450088)
			(layers "F.Cu" "F.Mask" "F.Paste")
			(net "M_E_CPU0_SA_DQS_DN<6>")
		)
		(pad "P70" smd circle
			(at 30.230064 -26.28011 180)
			(size 0.450088 0.450088)
			(layers "F.Cu" "F.Mask" "F.Paste")
			(net "M_E_CPU0_SA_DQS_DN<1>")
		)
		(pad "P71" smd circle
			(at 31.170118 -26.28011 180)
			(size 0.450088 0.450088)
			(layers "F.Cu" "F.Mask" "F.Paste")
			(net "PVDDIO_P0")
		)
		(pad "P72" smd circle
			(at 32.109918 -26.28011 180)
			(size 0.450088 0.450088)
			(layers "F.Cu" "F.Mask" "F.Paste")
			(net "M_A_CPU0_SA_DQS_DN<6>")
		)
		(pad "P73" smd circle
			(at 33.049972 -26.28011 180)
			(size 0.450088 0.450088)
			(layers "F.Cu" "F.Mask" "F.Paste")
			(net "GND")
		)
		(pad "P74" smd circle
			(at 33.990026 -26.28011 180)
			(size 0.450088 0.450088)
			(layers "F.Cu" "F.Mask" "F.Paste")
			(net "M_A_CPU0_SA_DQS_DN<1>")
		)
		(pad "R1" smd circle
			(at -34.159952 -25.470104 180)
			(size 0.450088 0.450088)
			(layers "F.Cu" "F.Mask" "F.Paste")
			(net "GND")
		)
		(pad "R2" smd circle
			(at -33.219898 -25.470104 180)
			(size 0.450088 0.450088)
			(layers "F.Cu" "F.Mask" "F.Paste")
			(net "M_G_CPU0_SA_DQ<12>")
		)
		(pad "R3" smd circle
			(at -32.280098 -25.470104 180)
			(size 0.450088 0.450088)
			(layers "F.Cu" "F.Mask" "F.Paste")
			(net "M_G_CPU0_SA_DQS_DP<6>")
		)
		(pad "R4" smd circle
			(at -31.340044 -25.470104 180)
			(size 0.450088 0.450088)
			(layers "F.Cu" "F.Mask" "F.Paste")
			(net "GND")
		)
		(pad "R5" smd circle
			(at -30.39999 -25.470104 180)
			(size 0.450088 0.450088)
			(layers "F.Cu" "F.Mask" "F.Paste")
			(net "M_K_CPU0_SA_DQ<12>")
		)
		(pad "R6" smd circle
			(at -29.459936 -25.470104 180)
			(size 0.450088 0.450088)
			(layers "F.Cu" "F.Mask" "F.Paste")
			(net "GND")
		)
		(pad "R7" smd circle
			(at -28.519882 -25.470104 180)
			(size 0.450088 0.450088)
			(layers "F.Cu" "F.Mask" "F.Paste")
			(net "M_K_CPU0_SA_DQS_DP<6>")
		)
		(pad "R8" smd circle
			(at -27.580082 -25.470104 180)
			(size 0.450088 0.450088)
			(layers "F.Cu" "F.Mask" "F.Paste")
			(net "GND")
		)
		(pad "R9" smd circle
			(at -26.640028 -25.470104 180)
			(size 0.450088 0.450088)
			(layers "F.Cu" "F.Mask" "F.Paste")
			(net "M_L_CPU0_SA_DQ<12>")
		)
		(pad "R10" smd circle
			(at -25.699974 -25.470104 180)
			(size 0.450088 0.450088)
			(layers "F.Cu" "F.Mask" "F.Paste")
			(net "M_L_CPU0_SA_DQS_DP<6>")
		)
		(pad "R11" smd circle
			(at -24.75992 -25.470104 180)
			(size 0.450088 0.450088)
			(layers "F.Cu" "F.Mask" "F.Paste")
			(net "GND")
		)
		(pad "R12" smd circle
			(at -23.82012 -25.470104 180)
			(size 0.450088 0.450088)
			(layers "F.Cu" "F.Mask" "F.Paste")
			(net "M_H_CPU0_SA_DQ<12>")
		)
		(pad "R13" smd circle
			(at -22.880066 -25.470104 180)
			(size 0.450088 0.450088)
			(layers "F.Cu" "F.Mask" "F.Paste")
			(net "GND")
		)
		(pad "R14" smd circle
			(at -21.940012 -25.470104 180)
			(size 0.450088 0.450088)
			(layers "F.Cu" "F.Mask" "F.Paste")
			(net "M_H_CPU0_SA_DQS_DP<6>")
		)
		(pad "R15" smd circle
			(at -20.999958 -25.470104 180)
			(size 0.450088 0.450088)
			(layers "F.Cu" "F.Mask" "F.Paste")
			(net "GND")
		)
		(pad "R16" smd circle
			(at -20.059904 -25.470104 180)
			(size 0.450088 0.450088)
			(layers "F.Cu" "F.Mask" "F.Paste")
			(net "M_J_CPU0_SA_DQ<12>")
		)
		(pad "R17" smd circle
			(at -19.120104 -25.470104 180)
			(size 0.450088 0.450088)
			(layers "F.Cu" "F.Mask" "F.Paste")
			(net "M_J_CPU0_SA_DQS_DP<6>")
		)
		(pad "R18" smd circle
			(at -18.18005 -25.470104 180)
			(size 0.450088 0.450088)
			(layers "F.Cu" "F.Mask" "F.Paste")
			(net "GND")
		)
		(pad "R19" smd circle
			(at -17.239996 -25.470104 180)
			(size 0.450088 0.450088)
			(layers "F.Cu" "F.Mask" "F.Paste")
			(net "M_I_CPU0_SA_DQ<12>")
		)
		(pad "R20" smd circle
			(at -16.299942 -25.470104 180)
			(size 0.450088 0.450088)
			(layers "F.Cu" "F.Mask" "F.Paste")
			(net "GND")
		)
		(pad "R21" smd circle
			(at -15.359888 -25.470104 180)
			(size 0.450088 0.450088)
			(layers "F.Cu" "F.Mask" "F.Paste")
			(net "M_I_CPU0_SA_DQS_DP<6>")
		)
		(pad "R22" smd circle
			(at -14.420088 -25.470104 180)
			(size 0.450088 0.450088)
			(layers "F.Cu" "F.Mask" "F.Paste")
			(net "GND")
		)
		(pad "R23" smd circle
			(at -13.480034 -25.470104 180)
			(size 0.450088 0.450088)
			(layers "F.Cu" "F.Mask" "F.Paste")
			(net "P5E_CPU0_G3_TX_DP<1>")
		)
		(pad "R24" smd circle
			(at -12.53998 -25.470104 180)
			(size 0.450088 0.450088)
			(layers "F.Cu" "F.Mask" "F.Paste")
			(net "P5E_CPU0_G3_TX_DN<1>")
		)
		(pad "R25" smd circle
			(at -11.599926 -25.470104 180)
			(size 0.450088 0.450088)
			(layers "F.Cu" "F.Mask" "F.Paste")
			(net "GND")
		)
		(pad "R26" smd circle
			(at -10.659872 -25.470104 180)
			(size 0.450088 0.450088)
			(layers "F.Cu" "F.Mask" "F.Paste")
			(net "P5E_CPU0_G3_TX_DP<4>")
		)
		(pad "R27" smd circle
			(at -9.720072 -25.470104 180)
			(size 0.450088 0.450088)
			(layers "F.Cu" "F.Mask" "F.Paste")
			(net "P5E_CPU0_G3_TX_DN<4>")
		)
		(pad "R28" smd circle
			(at -8.780018 -25.470104 180)
			(size 0.450088 0.450088)
			(layers "F.Cu" "F.Mask" "F.Paste")
			(net "GND")
		)
		(pad "R29" smd circle
			(at -7.839964 -25.470104 180)
			(size 0.450088 0.450088)
			(layers "F.Cu" "F.Mask" "F.Paste")
			(net "P5E_CPU0_G3_TX_DP<7>")
		)
		(pad "R30" smd circle
			(at -6.89991 -25.470104 180)
			(size 0.450088 0.450088)
			(layers "F.Cu" "F.Mask" "F.Paste")
			(net "P5E_CPU0_G3_TX_DN<7>")
		)
		(pad "R31" smd circle
			(at -5.96011 -25.470104 180)
			(size 0.450088 0.450088)
			(layers "F.Cu" "F.Mask" "F.Paste")
			(net "GND")
		)
		(pad "R32" smd circle
			(at -5.020056 -25.470104 180)
			(size 0.450088 0.450088)
			(layers "F.Cu" "F.Mask" "F.Paste")
			(net "P5E_CPU0_G3_TX_DP<10>")
		)
		(pad "R33" smd circle
			(at -4.080002 -25.470104 180)
			(size 0.450088 0.450088)
			(layers "F.Cu" "F.Mask" "F.Paste")
			(net "P5E_CPU0_G3_TX_DN<10>")
		)
		(pad "R34" smd circle
			(at -3.139948 -25.470104 180)
			(size 0.450088 0.450088)
			(layers "F.Cu" "F.Mask" "F.Paste")
			(net "GND")
		)
		(pad "R35" smd circle
			(at -2.199894 -25.470104 180)
			(size 0.450088 0.450088)
			(layers "F.Cu" "F.Mask" "F.Paste")
			(net "GND")
		)
		(pad "R36" smd circle
			(at -1.260094 -25.470104 180)
			(size 0.450088 0.450088)
			(layers "F.Cu" "F.Mask" "F.Paste")
			(net "GND")
		)
		(pad "R40" smd circle
			(at 1.560068 -25.470104 180)
			(size 0.450088 0.450088)
			(layers "F.Cu" "F.Mask" "F.Paste")
			(net "GND")
		)
		(pad "R41" smd circle
			(at 2.500122 -25.470104 180)
			(size 0.450088 0.450088)
			(layers "F.Cu" "F.Mask" "F.Paste")
			(net "GND")
		)
		(pad "R42" smd circle
			(at 3.439922 -25.470104 180)
			(size 0.450088 0.450088)
			(layers "F.Cu" "F.Mask" "F.Paste")
			(net "GND")
		)
		(pad "R43" smd circle
			(at 4.379976 -25.470104 180)
			(size 0.450088 0.450088)
			(layers "F.Cu" "F.Mask" "F.Paste")
			(net "GMI_CPU1_G3_CPU0_G1_TX_DN<5>")
		)
		(pad "R44" smd circle
			(at 5.32003 -25.470104 180)
			(size 0.450088 0.450088)
			(layers "F.Cu" "F.Mask" "F.Paste")
			(net "GMI_CPU1_G3_CPU0_G1_TX_DP<5>")
		)
		(pad "R45" smd circle
			(at 6.260084 -25.470104 180)
			(size 0.450088 0.450088)
			(layers "F.Cu" "F.Mask" "F.Paste")
			(net "GND")
		)
		(pad "R46" smd circle
			(at 7.199884 -25.470104 180)
			(size 0.450088 0.450088)
			(layers "F.Cu" "F.Mask" "F.Paste")
			(net "GMI_CPU1_G3_CPU0_G1_TX_DN<8>")
		)
		(pad "R47" smd circle
			(at 8.139938 -25.470104 180)
			(size 0.450088 0.450088)
			(layers "F.Cu" "F.Mask" "F.Paste")
			(net "GMI_CPU1_G3_CPU0_G1_TX_DP<8>")
		)
		(pad "R48" smd circle
			(at 9.079992 -25.470104 180)
			(size 0.450088 0.450088)
			(layers "F.Cu" "F.Mask" "F.Paste")
			(net "GND")
		)
		(pad "R49" smd circle
			(at 10.020046 -25.470104 180)
			(size 0.450088 0.450088)
			(layers "F.Cu" "F.Mask" "F.Paste")
			(net "GMI_CPU1_G3_CPU0_G1_TX_DN<11>")
		)
		(pad "R50" smd circle
			(at 10.9601 -25.470104 180)
			(size 0.450088 0.450088)
			(layers "F.Cu" "F.Mask" "F.Paste")
			(net "GMI_CPU1_G3_CPU0_G1_TX_DP<11>")
		)
		(pad "R51" smd circle
			(at 11.8999 -25.470104 180)
			(size 0.450088 0.450088)
			(layers "F.Cu" "F.Mask" "F.Paste")
			(net "GND")
		)
		(pad "R52" smd circle
			(at 12.839954 -25.470104 180)
			(size 0.450088 0.450088)
			(layers "F.Cu" "F.Mask" "F.Paste")
			(net "GMI_CPU1_G3_CPU0_G1_TX_DN<14>")
		)
		(pad "R53" smd circle
			(at 13.780008 -25.470104 180)
			(size 0.450088 0.450088)
			(layers "F.Cu" "F.Mask" "F.Paste")
			(net "GMI_CPU1_G3_CPU0_G1_TX_DP<14>")
		)
		(pad "R54" smd circle
			(at 14.720062 -25.470104 180)
			(size 0.450088 0.450088)
			(layers "F.Cu" "F.Mask" "F.Paste")
			(net "GND")
		)
		(pad "R55" smd circle
			(at 15.660116 -25.470104 180)
			(size 0.450088 0.450088)
			(layers "F.Cu" "F.Mask" "F.Paste")
			(net "M_C_CPU0_SA_DQS_DP<6>")
		)
		(pad "R56" smd circle
			(at 16.599916 -25.470104 180)
			(size 0.450088 0.450088)
			(layers "F.Cu" "F.Mask" "F.Paste")
			(net "GND")
		)
		(pad "R57" smd circle
			(at 17.53997 -25.470104 180)
			(size 0.450088 0.450088)
			(layers "F.Cu" "F.Mask" "F.Paste")
			(net "M_C_CPU0_SA_DQ<12>")
		)
		(pad "R58" smd circle
			(at 18.480024 -25.470104 180)
			(size 0.450088 0.450088)
			(layers "F.Cu" "F.Mask" "F.Paste")
			(net "GND")
		)
		(pad "R59" smd circle
			(at 19.420078 -25.470104 180)
			(size 0.450088 0.450088)
			(layers "F.Cu" "F.Mask" "F.Paste")
			(net "M_D_CPU0_SA_DQS_DP<6>")
		)
		(pad "R60" smd circle
			(at 20.359878 -25.470104 180)
			(size 0.450088 0.450088)
			(layers "F.Cu" "F.Mask" "F.Paste")
			(net "M_D_CPU0_SA_DQ<12>")
		)
		(pad "R61" smd circle
			(at 21.299932 -25.470104 180)
			(size 0.450088 0.450088)
			(layers "F.Cu" "F.Mask" "F.Paste")
			(net "GND")
		)
		(pad "R62" smd circle
			(at 22.239986 -25.470104 180)
			(size 0.450088 0.450088)
			(layers "F.Cu" "F.Mask" "F.Paste")
			(net "M_B_CPU0_SA_DQS_DP<6>")
		)
		(pad "R63" smd circle
			(at 23.18004 -25.470104 180)
			(size 0.450088 0.450088)
			(layers "F.Cu" "F.Mask" "F.Paste")
			(net "GND")
		)
		(pad "R64" smd circle
			(at 24.120094 -25.470104 180)
			(size 0.450088 0.450088)
			(layers "F.Cu" "F.Mask" "F.Paste")
			(net "M_B_CPU0_SA_DQ<12>")
		)
		(pad "R65" smd circle
			(at 25.059894 -25.470104 180)
			(size 0.450088 0.450088)
			(layers "F.Cu" "F.Mask" "F.Paste")
			(net "GND")
		)
		(pad "R66" smd circle
			(at 25.999948 -25.470104 180)
			(size 0.450088 0.450088)
			(layers "F.Cu" "F.Mask" "F.Paste")
			(net "M_F_CPU0_SA_DQS_DP<6>")
		)
		(pad "R67" smd circle
			(at 26.940002 -25.470104 180)
			(size 0.450088 0.450088)
			(layers "F.Cu" "F.Mask" "F.Paste")
			(net "M_F_CPU0_SA_DQ<12>")
		)
		(pad "R68" smd circle
			(at 27.880056 -25.470104 180)
			(size 0.450088 0.450088)
			(layers "F.Cu" "F.Mask" "F.Paste")
			(net "GND")
		)
		(pad "R69" smd circle
			(at 28.82011 -25.470104 180)
			(size 0.450088 0.450088)
			(layers "F.Cu" "F.Mask" "F.Paste")
			(net "M_E_CPU0_SA_DQS_DP<6>")
		)
		(pad "R70" smd circle
			(at 29.75991 -25.470104 180)
			(size 0.450088 0.450088)
			(layers "F.Cu" "F.Mask" "F.Paste")
			(net "GND")
		)
		(pad "R71" smd circle
			(at 30.699964 -25.470104 180)
			(size 0.450088 0.450088)
			(layers "F.Cu" "F.Mask" "F.Paste")
			(net "M_E_CPU0_SA_DQ<12>")
		)
		(pad "R72" smd circle
			(at 31.640018 -25.470104 180)
			(size 0.450088 0.450088)
			(layers "F.Cu" "F.Mask" "F.Paste")
			(net "GND")
		)
		(pad "R73" smd circle
			(at 32.580072 -25.470104 180)
			(size 0.450088 0.450088)
			(layers "F.Cu" "F.Mask" "F.Paste")
			(net "M_A_CPU0_SA_DQS_DP<6>")
		)
		(pad "R74" smd circle
			(at 33.519872 -25.470104 180)
			(size 0.450088 0.450088)
			(layers "F.Cu" "F.Mask" "F.Paste")
			(net "M_A_CPU0_SA_DQ<12>")
		)
		(pad "R75" smd circle
			(at 34.459926 -25.470104 180)
			(size 0.450088 0.450088)
			(layers "F.Cu" "F.Mask" "F.Paste")
			(net "GND")
		)
		(pad "T2" smd circle
			(at -33.690052 -24.660098 180)
			(size 0.450088 0.450088)
			(layers "F.Cu" "F.Mask" "F.Paste")
			(net "M_G_CPU0_SA_DQ<14>")
		)
		(pad "T3" smd circle
			(at -32.749998 -24.660098 180)
			(size 0.450088 0.450088)
			(layers "F.Cu" "F.Mask" "F.Paste")
			(net "GND")
		)
		(pad "T4" smd circle
			(at -31.809944 -24.660098 180)
			(size 0.450088 0.450088)
			(layers "F.Cu" "F.Mask" "F.Paste")
			(net "M_G_CPU0_SA_DQ<13>")
		)
		(pad "T5" smd circle
			(at -30.86989 -24.660098 180)
			(size 0.450088 0.450088)
			(layers "F.Cu" "F.Mask" "F.Paste")
			(net "GND")
		)
		(pad "T6" smd circle
			(at -29.93009 -24.660098 180)
			(size 0.450088 0.450088)
			(layers "F.Cu" "F.Mask" "F.Paste")
			(net "M_K_CPU0_SA_DQ<14>")
		)
		(pad "T7" smd circle
			(at -28.990036 -24.660098 180)
			(size 0.450088 0.450088)
			(layers "F.Cu" "F.Mask" "F.Paste")
			(net "M_K_CPU0_SA_DQ<13>")
		)
		(pad "T8" smd circle
			(at -28.049982 -24.660098 180)
			(size 0.450088 0.450088)
			(layers "F.Cu" "F.Mask" "F.Paste")
			(net "GND")
		)
		(pad "T9" smd circle
			(at -27.109928 -24.660098 180)
			(size 0.450088 0.450088)
			(layers "F.Cu" "F.Mask" "F.Paste")
			(net "M_L_CPU0_SA_DQ<14>")
		)
		(pad "T10" smd circle
			(at -26.170128 -24.660098 180)
			(size 0.450088 0.450088)
			(layers "F.Cu" "F.Mask" "F.Paste")
			(net "GND")
		)
		(pad "T11" smd circle
			(at -25.230074 -24.660098 180)
			(size 0.450088 0.450088)
			(layers "F.Cu" "F.Mask" "F.Paste")
			(net "M_L_CPU0_SA_DQ<13>")
		)
		(pad "T12" smd circle
			(at -24.29002 -24.660098 180)
			(size 0.450088 0.450088)
			(layers "F.Cu" "F.Mask" "F.Paste")
			(net "GND")
		)
		(pad "T13" smd circle
			(at -23.349966 -24.660098 180)
			(size 0.450088 0.450088)
			(layers "F.Cu" "F.Mask" "F.Paste")
			(net "M_H_CPU0_SA_DQ<14>")
		)
		(pad "T14" smd circle
			(at -22.409912 -24.660098 180)
			(size 0.450088 0.450088)
			(layers "F.Cu" "F.Mask" "F.Paste")
			(net "M_H_CPU0_SA_DQ<13>")
		)
		(pad "T15" smd circle
			(at -21.470112 -24.660098 180)
			(size 0.450088 0.450088)
			(layers "F.Cu" "F.Mask" "F.Paste")
			(net "GND")
		)
		(pad "T16" smd circle
			(at -20.530058 -24.660098 180)
			(size 0.450088 0.450088)
			(layers "F.Cu" "F.Mask" "F.Paste")
			(net "M_J_CPU0_SA_DQ<14>")
		)
		(pad "T17" smd circle
			(at -19.590004 -24.660098 180)
			(size 0.450088 0.450088)
			(layers "F.Cu" "F.Mask" "F.Paste")
			(net "GND")
		)
		(pad "T18" smd circle
			(at -18.64995 -24.660098 180)
			(size 0.450088 0.450088)
			(layers "F.Cu" "F.Mask" "F.Paste")
			(net "M_J_CPU0_SA_DQ<13>")
		)
		(pad "T19" smd circle
			(at -17.709896 -24.660098 180)
			(size 0.450088 0.450088)
			(layers "F.Cu" "F.Mask" "F.Paste")
			(net "GND")
		)
		(pad "T20" smd circle
			(at -16.770096 -24.660098 180)
			(size 0.450088 0.450088)
			(layers "F.Cu" "F.Mask" "F.Paste")
			(net "M_I_CPU0_SA_DQ<14>")
		)
		(pad "T21" smd circle
			(at -15.830042 -24.660098 180)
			(size 0.450088 0.450088)
			(layers "F.Cu" "F.Mask" "F.Paste")
			(net "M_I_CPU0_SA_DQ<13>")
		)
		(pad "T22" smd circle
			(at -14.889988 -24.660098 180)
			(size 0.450088 0.450088)
			(layers "F.Cu" "F.Mask" "F.Paste")
			(net "GND")
		)
		(pad "T23" smd circle
			(at -13.949934 -24.660098 180)
			(size 0.450088 0.450088)
			(layers "F.Cu" "F.Mask" "F.Paste")
			(net "PVDDCR_CPU0_P0")
		)
		(pad "T24" smd circle
			(at -13.00988 -24.660098 180)
			(size 0.450088 0.450088)
			(layers "F.Cu" "F.Mask" "F.Paste")
			(net "PVDDCR_CPU0_P0")
		)
		(pad "T25" smd circle
			(at -12.07008 -24.660098 180)
			(size 0.450088 0.450088)
			(layers "F.Cu" "F.Mask" "F.Paste")
			(net "GND")
		)
		(pad "T26" smd circle
			(at -11.130026 -24.660098 180)
			(size 0.450088 0.450088)
			(layers "F.Cu" "F.Mask" "F.Paste")
			(net "PVDDCR_CPU0_P0")
		)
		(pad "T27" smd circle
			(at -10.189972 -24.660098 180)
			(size 0.450088 0.450088)
			(layers "F.Cu" "F.Mask" "F.Paste")
			(net "PVDDCR_CPU0_P0")
		)
		(pad "T28" smd circle
			(at -9.249918 -24.660098 180)
			(size 0.450088 0.450088)
			(layers "F.Cu" "F.Mask" "F.Paste")
			(net "GND")
		)
		(pad "T29" smd circle
			(at -8.310118 -24.660098 180)
			(size 0.450088 0.450088)
			(layers "F.Cu" "F.Mask" "F.Paste")
			(net "PVDDCR_CPU0_P0")
		)
		(pad "T30" smd circle
			(at -7.370064 -24.660098 180)
			(size 0.450088 0.450088)
			(layers "F.Cu" "F.Mask" "F.Paste")
			(net "PVDDCR_CPU0_P0")
		)
		(pad "T31" smd circle
			(at -6.43001 -24.660098 180)
			(size 0.450088 0.450088)
			(layers "F.Cu" "F.Mask" "F.Paste")
			(net "GND")
		)
		(pad "T32" smd circle
			(at -5.489956 -24.660098 180)
			(size 0.450088 0.450088)
			(layers "F.Cu" "F.Mask" "F.Paste")
			(net "PVDDCR_CPU0_P0")
		)
		(pad "T33" smd circle
			(at -4.549902 -24.660098 180)
			(size 0.450088 0.450088)
			(layers "F.Cu" "F.Mask" "F.Paste")
			(net "PVDDCR_CPU0_P0")
		)
		(pad "T34" smd circle
			(at -3.610102 -24.660098 180)
			(size 0.450088 0.450088)
			(layers "F.Cu" "F.Mask" "F.Paste")
			(net "GND")
		)
		(pad "T35" smd circle
			(at -2.670048 -24.660098 180)
			(size 0.450088 0.450088)
			(layers "F.Cu" "F.Mask" "F.Paste")
			(net "P5E_CPU0_G3_TX_DP<14>")
		)
		(pad "T36" smd circle
			(at -1.729994 -24.660098 180)
			(size 0.450088 0.450088)
			(layers "F.Cu" "F.Mask" "F.Paste")
			(net "P5E_CPU0_G3_TX_DN<14>")
		)
		(pad "T37" smd circle
			(at -0.78994 -24.660098 180)
			(size 0.450088 0.450088)
			(layers "F.Cu" "F.Mask" "F.Paste")
			(net "GND")
		)
		(pad "T39" smd circle
			(at 1.089914 -24.660098 180)
			(size 0.450088 0.450088)
			(layers "F.Cu" "F.Mask" "F.Paste")
			(net "GND")
		)
		(pad "T40" smd circle
			(at 2.029968 -24.660098 180)
			(size 0.450088 0.450088)
			(layers "F.Cu" "F.Mask" "F.Paste")
			(net "GMI_CPU1_G3_CPU0_G1_TX_DN<1>")
		)
		(pad "T41" smd circle
			(at 2.970022 -24.660098 180)
			(size 0.450088 0.450088)
			(layers "F.Cu" "F.Mask" "F.Paste")
			(net "GMI_CPU1_G3_CPU0_G1_TX_DP<1>")
		)
		(pad "T42" smd circle
			(at 3.910076 -24.660098 180)
			(size 0.450088 0.450088)
			(layers "F.Cu" "F.Mask" "F.Paste")
			(net "GND")
		)
		(pad "T43" smd circle
			(at 4.849876 -24.660098 180)
			(size 0.450088 0.450088)
			(layers "F.Cu" "F.Mask" "F.Paste")
			(net "PVDDCR_CPU0_P0")
		)
		(pad "T44" smd circle
			(at 5.78993 -24.660098 180)
			(size 0.450088 0.450088)
			(layers "F.Cu" "F.Mask" "F.Paste")
			(net "PVDDCR_CPU0_P0")
		)
		(pad "T45" smd circle
			(at 6.729984 -24.660098 180)
			(size 0.450088 0.450088)
			(layers "F.Cu" "F.Mask" "F.Paste")
			(net "GND")
		)
		(pad "T46" smd circle
			(at 7.670038 -24.660098 180)
			(size 0.450088 0.450088)
			(layers "F.Cu" "F.Mask" "F.Paste")
			(net "PVDDCR_CPU0_P0")
		)
		(pad "T47" smd circle
			(at 8.610092 -24.660098 180)
			(size 0.450088 0.450088)
			(layers "F.Cu" "F.Mask" "F.Paste")
			(net "PVDDCR_CPU0_P0")
		)
		(pad "T48" smd circle
			(at 9.549892 -24.660098 180)
			(size 0.450088 0.450088)
			(layers "F.Cu" "F.Mask" "F.Paste")
			(net "GND")
		)
		(pad "T49" smd circle
			(at 10.489946 -24.660098 180)
			(size 0.450088 0.450088)
			(layers "F.Cu" "F.Mask" "F.Paste")
			(net "PVDDCR_CPU0_P0")
		)
		(pad "T50" smd circle
			(at 11.43 -24.660098 180)
			(size 0.450088 0.450088)
			(layers "F.Cu" "F.Mask" "F.Paste")
			(net "PVDDCR_CPU0_P0")
		)
		(pad "T51" smd circle
			(at 12.370054 -24.660098 180)
			(size 0.450088 0.450088)
			(layers "F.Cu" "F.Mask" "F.Paste")
			(net "GND")
		)
		(pad "T52" smd circle
			(at 13.310108 -24.660098 180)
			(size 0.450088 0.450088)
			(layers "F.Cu" "F.Mask" "F.Paste")
			(net "PVDDCR_CPU0_P0")
		)
		(pad "T53" smd circle
			(at 14.249908 -24.660098 180)
			(size 0.450088 0.450088)
			(layers "F.Cu" "F.Mask" "F.Paste")
			(net "PVDDCR_CPU0_P0")
		)
		(pad "T54" smd circle
			(at 15.189962 -24.660098 180)
			(size 0.450088 0.450088)
			(layers "F.Cu" "F.Mask" "F.Paste")
			(net "GND")
		)
		(pad "T55" smd circle
			(at 16.130016 -24.660098 180)
			(size 0.450088 0.450088)
			(layers "F.Cu" "F.Mask" "F.Paste")
			(net "M_C_CPU0_SA_DQ<13>")
		)
		(pad "T56" smd circle
			(at 17.07007 -24.660098 180)
			(size 0.450088 0.450088)
			(layers "F.Cu" "F.Mask" "F.Paste")
			(net "M_C_CPU0_SA_DQ<14>")
		)
		(pad "T57" smd circle
			(at 18.010124 -24.660098 180)
			(size 0.450088 0.450088)
			(layers "F.Cu" "F.Mask" "F.Paste")
			(net "GND")
		)
		(pad "T58" smd circle
			(at 18.949924 -24.660098 180)
			(size 0.450088 0.450088)
			(layers "F.Cu" "F.Mask" "F.Paste")
			(net "M_D_CPU0_SA_DQ<13>")
		)
		(pad "T59" smd circle
			(at 19.889978 -24.660098 180)
			(size 0.450088 0.450088)
			(layers "F.Cu" "F.Mask" "F.Paste")
			(net "GND")
		)
		(pad "T60" smd circle
			(at 20.830032 -24.660098 180)
			(size 0.450088 0.450088)
			(layers "F.Cu" "F.Mask" "F.Paste")
			(net "M_D_CPU0_SA_DQ<14>")
		)
		(pad "T61" smd circle
			(at 21.770086 -24.660098 180)
			(size 0.450088 0.450088)
			(layers "F.Cu" "F.Mask" "F.Paste")
			(net "GND")
		)
		(pad "T62" smd circle
			(at 22.709886 -24.660098 180)
			(size 0.450088 0.450088)
			(layers "F.Cu" "F.Mask" "F.Paste")
			(net "M_B_CPU0_SA_DQ<13>")
		)
		(pad "T63" smd circle
			(at 23.64994 -24.660098 180)
			(size 0.450088 0.450088)
			(layers "F.Cu" "F.Mask" "F.Paste")
			(net "M_B_CPU0_SA_DQ<14>")
		)
		(pad "T64" smd circle
			(at 24.589994 -24.660098 180)
			(size 0.450088 0.450088)
			(layers "F.Cu" "F.Mask" "F.Paste")
			(net "GND")
		)
		(pad "T65" smd circle
			(at 25.530048 -24.660098 180)
			(size 0.450088 0.450088)
			(layers "F.Cu" "F.Mask" "F.Paste")
			(net "M_F_CPU0_SA_DQ<13>")
		)
		(pad "T66" smd circle
			(at 26.470102 -24.660098 180)
			(size 0.450088 0.450088)
			(layers "F.Cu" "F.Mask" "F.Paste")
			(net "GND")
		)
		(pad "T67" smd circle
			(at 27.409902 -24.660098 180)
			(size 0.450088 0.450088)
			(layers "F.Cu" "F.Mask" "F.Paste")
			(net "M_F_CPU0_SA_DQ<14>")
		)
		(pad "T68" smd circle
			(at 28.349956 -24.660098 180)
			(size 0.450088 0.450088)
			(layers "F.Cu" "F.Mask" "F.Paste")
			(net "GND")
		)
		(pad "T69" smd circle
			(at 29.29001 -24.660098 180)
			(size 0.450088 0.450088)
			(layers "F.Cu" "F.Mask" "F.Paste")
			(net "M_E_CPU0_SA_DQ<13>")
		)
		(pad "T70" smd circle
			(at 30.230064 -24.660098 180)
			(size 0.450088 0.450088)
			(layers "F.Cu" "F.Mask" "F.Paste")
			(net "M_E_CPU0_SA_DQ<14>")
		)
		(pad "T71" smd circle
			(at 31.170118 -24.660098 180)
			(size 0.450088 0.450088)
			(layers "F.Cu" "F.Mask" "F.Paste")
			(net "GND")
		)
		(pad "T72" smd circle
			(at 32.109918 -24.660098 180)
			(size 0.450088 0.450088)
			(layers "F.Cu" "F.Mask" "F.Paste")
			(net "M_A_CPU0_SA_DQ<13>")
		)
		(pad "T73" smd circle
			(at 33.049972 -24.660098 180)
			(size 0.450088 0.450088)
			(layers "F.Cu" "F.Mask" "F.Paste")
			(net "GND")
		)
		(pad "T74" smd circle
			(at 33.990026 -24.660098 180)
			(size 0.450088 0.450088)
			(layers "F.Cu" "F.Mask" "F.Paste")
			(net "M_A_CPU0_SA_DQ<14>")
		)
		(pad "U1" smd circle
			(at -34.159952 -23.850092 180)
			(size 0.450088 0.450088)
			(layers "F.Cu" "F.Mask" "F.Paste")
			(net "GND")
		)
		(pad "U2" smd circle
			(at -33.219898 -23.850092 180)
			(size 0.450088 0.450088)
			(layers "F.Cu" "F.Mask" "F.Paste")
			(net "M_G_CPU0_SA_DQ<16>")
		)
		(pad "U3" smd circle
			(at -32.280098 -23.850092 180)
			(size 0.450088 0.450088)
			(layers "F.Cu" "F.Mask" "F.Paste")
			(net "M_G_CPU0_SA_DQ<15>")
		)
		(pad "U4" smd circle
			(at -31.340044 -23.850092 180)
			(size 0.450088 0.450088)
			(layers "F.Cu" "F.Mask" "F.Paste")
			(net "PVDDCR_SOC_P0")
		)
		(pad "U5" smd circle
			(at -30.39999 -23.850092 180)
			(size 0.450088 0.450088)
			(layers "F.Cu" "F.Mask" "F.Paste")
			(net "M_K_CPU0_SA_DQ<16>")
		)
		(pad "U6" smd circle
			(at -29.459936 -23.850092 180)
			(size 0.450088 0.450088)
			(layers "F.Cu" "F.Mask" "F.Paste")
			(net "GND")
		)
		(pad "U7" smd circle
			(at -28.519882 -23.850092 180)
			(size 0.450088 0.450088)
			(layers "F.Cu" "F.Mask" "F.Paste")
			(net "M_K_CPU0_SA_DQ<15>")
		)
		(pad "U8" smd circle
			(at -27.580082 -23.850092 180)
			(size 0.450088 0.450088)
			(layers "F.Cu" "F.Mask" "F.Paste")
			(net "GND")
		)
		(pad "U9" smd circle
			(at -26.640028 -23.850092 180)
			(size 0.450088 0.450088)
			(layers "F.Cu" "F.Mask" "F.Paste")
			(net "M_L_CPU0_SA_DQ<16>")
		)
		(pad "U10" smd circle
			(at -25.699974 -23.850092 180)
			(size 0.450088 0.450088)
			(layers "F.Cu" "F.Mask" "F.Paste")
			(net "M_L_CPU0_SA_DQ<15>")
		)
		(pad "U11" smd circle
			(at -24.75992 -23.850092 180)
			(size 0.450088 0.450088)
			(layers "F.Cu" "F.Mask" "F.Paste")
			(net "PVDDCR_SOC_P0")
		)
		(pad "U12" smd circle
			(at -23.82012 -23.850092 180)
			(size 0.450088 0.450088)
			(layers "F.Cu" "F.Mask" "F.Paste")
			(net "M_H_CPU0_SA_DQ<16>")
		)
		(pad "U13" smd circle
			(at -22.880066 -23.850092 180)
			(size 0.450088 0.450088)
			(layers "F.Cu" "F.Mask" "F.Paste")
			(net "GND")
		)
		(pad "U14" smd circle
			(at -21.940012 -23.850092 180)
			(size 0.450088 0.450088)
			(layers "F.Cu" "F.Mask" "F.Paste")
			(net "M_H_CPU0_SA_DQ<15>")
		)
		(pad "U15" smd circle
			(at -20.999958 -23.850092 180)
			(size 0.450088 0.450088)
			(layers "F.Cu" "F.Mask" "F.Paste")
			(net "GND")
		)
		(pad "U16" smd circle
			(at -20.059904 -23.850092 180)
			(size 0.450088 0.450088)
			(layers "F.Cu" "F.Mask" "F.Paste")
			(net "M_J_CPU0_SA_DQ<16>")
		)
		(pad "U17" smd circle
			(at -19.120104 -23.850092 180)
			(size 0.450088 0.450088)
			(layers "F.Cu" "F.Mask" "F.Paste")
			(net "M_J_CPU0_SA_DQ<15>")
		)
		(pad "U18" smd circle
			(at -18.18005 -23.850092 180)
			(size 0.450088 0.450088)
			(layers "F.Cu" "F.Mask" "F.Paste")
			(net "PVDDCR_SOC_P0")
		)
		(pad "U19" smd circle
			(at -17.239996 -23.850092 180)
			(size 0.450088 0.450088)
			(layers "F.Cu" "F.Mask" "F.Paste")
			(net "M_I_CPU0_SA_DQ<16>")
		)
		(pad "U20" smd circle
			(at -16.299942 -23.850092 180)
			(size 0.450088 0.450088)
			(layers "F.Cu" "F.Mask" "F.Paste")
			(net "GND")
		)
		(pad "U21" smd circle
			(at -15.359888 -23.850092 180)
			(size 0.450088 0.450088)
			(layers "F.Cu" "F.Mask" "F.Paste")
			(net "M_I_CPU0_SA_DQ<15>")
		)
		(pad "U22" smd circle
			(at -14.420088 -23.850092 180)
			(size 0.450088 0.450088)
			(layers "F.Cu" "F.Mask" "F.Paste")
			(net "GND")
		)
		(pad "U23" smd circle
			(at -13.480034 -23.850092 180)
			(size 0.450088 0.450088)
			(layers "F.Cu" "F.Mask" "F.Paste")
			(net "P5E_CPU0_G3_TX_DP<0>")
		)
		(pad "U24" smd circle
			(at -12.53998 -23.850092 180)
			(size 0.450088 0.450088)
			(layers "F.Cu" "F.Mask" "F.Paste")
			(net "P5E_CPU0_G3_TX_DN<0>")
		)
		(pad "U25" smd circle
			(at -11.599926 -23.850092 180)
			(size 0.450088 0.450088)
			(layers "F.Cu" "F.Mask" "F.Paste")
			(net "GND")
		)
		(pad "U26" smd circle
			(at -10.659872 -23.850092 180)
			(size 0.450088 0.450088)
			(layers "F.Cu" "F.Mask" "F.Paste")
			(net "P5E_CPU0_G3_TX_DP<3>")
		)
		(pad "U27" smd circle
			(at -9.720072 -23.850092 180)
			(size 0.450088 0.450088)
			(layers "F.Cu" "F.Mask" "F.Paste")
			(net "P5E_CPU0_G3_TX_DN<3>")
		)
		(pad "U28" smd circle
			(at -8.780018 -23.850092 180)
			(size 0.450088 0.450088)
			(layers "F.Cu" "F.Mask" "F.Paste")
			(net "GND")
		)
		(pad "U29" smd circle
			(at -7.839964 -23.850092 180)
			(size 0.450088 0.450088)
			(layers "F.Cu" "F.Mask" "F.Paste")
			(net "P5E_CPU0_G3_TX_DP<9>")
		)
		(pad "U30" smd circle
			(at -6.89991 -23.850092 180)
			(size 0.450088 0.450088)
			(layers "F.Cu" "F.Mask" "F.Paste")
			(net "P5E_CPU0_G3_TX_DN<9>")
		)
		(pad "U31" smd circle
			(at -5.96011 -23.850092 180)
			(size 0.450088 0.450088)
			(layers "F.Cu" "F.Mask" "F.Paste")
			(net "GND")
		)
		(pad "U32" smd circle
			(at -5.020056 -23.850092 180)
			(size 0.450088 0.450088)
			(layers "F.Cu" "F.Mask" "F.Paste")
			(net "P5E_CPU0_G3_TX_DP<12>")
		)
		(pad "U33" smd circle
			(at -4.080002 -23.850092 180)
			(size 0.450088 0.450088)
			(layers "F.Cu" "F.Mask" "F.Paste")
			(net "P5E_CPU0_G3_TX_DN<12>")
		)
		(pad "U34" smd circle
			(at -3.139948 -23.850092 180)
			(size 0.450088 0.450088)
			(layers "F.Cu" "F.Mask" "F.Paste")
			(net "GND")
		)
		(pad "U35" smd circle
			(at -2.199894 -23.850092 180)
			(size 0.450088 0.450088)
			(layers "F.Cu" "F.Mask" "F.Paste")
			(net "PVDDCR_CPU0_P0")
		)
		(pad "U36" smd circle
			(at -1.260094 -23.850092 180)
			(size 0.450088 0.450088)
			(layers "F.Cu" "F.Mask" "F.Paste")
			(net "PVDDCR_CPU0_P0")
		)
		(pad "U40" smd circle
			(at 1.560068 -23.850092 180)
			(size 0.450088 0.450088)
			(layers "F.Cu" "F.Mask" "F.Paste")
			(net "PVDDCR_CPU0_P0")
		)
		(pad "U41" smd circle
			(at 2.500122 -23.850092 180)
			(size 0.450088 0.450088)
			(layers "F.Cu" "F.Mask" "F.Paste")
			(net "PVDDCR_CPU0_P0")
		)
		(pad "U42" smd circle
			(at 3.439922 -23.850092 180)
			(size 0.450088 0.450088)
			(layers "F.Cu" "F.Mask" "F.Paste")
			(net "GND")
		)
		(pad "U43" smd circle
			(at 4.379976 -23.850092 180)
			(size 0.450088 0.450088)
			(layers "F.Cu" "F.Mask" "F.Paste")
			(net "GMI_CPU1_G3_CPU0_G1_TX_DN<3>")
		)
		(pad "U44" smd circle
			(at 5.32003 -23.850092 180)
			(size 0.450088 0.450088)
			(layers "F.Cu" "F.Mask" "F.Paste")
			(net "GMI_CPU1_G3_CPU0_G1_TX_DP<3>")
		)
		(pad "U45" smd circle
			(at 6.260084 -23.850092 180)
			(size 0.450088 0.450088)
			(layers "F.Cu" "F.Mask" "F.Paste")
			(net "GND")
		)
		(pad "U46" smd circle
			(at 7.199884 -23.850092 180)
			(size 0.450088 0.450088)
			(layers "F.Cu" "F.Mask" "F.Paste")
			(net "GMI_CPU1_G3_CPU0_G1_TX_DN<6>")
		)
		(pad "U47" smd circle
			(at 8.139938 -23.850092 180)
			(size 0.450088 0.450088)
			(layers "F.Cu" "F.Mask" "F.Paste")
			(net "GMI_CPU1_G3_CPU0_G1_TX_DP<6>")
		)
		(pad "U48" smd circle
			(at 9.079992 -23.850092 180)
			(size 0.450088 0.450088)
			(layers "F.Cu" "F.Mask" "F.Paste")
			(net "GND")
		)
		(pad "U49" smd circle
			(at 10.020046 -23.850092 180)
			(size 0.450088 0.450088)
			(layers "F.Cu" "F.Mask" "F.Paste")
			(net "GMI_CPU1_G3_CPU0_G1_TX_DN<12>")
		)
		(pad "U50" smd circle
			(at 10.9601 -23.850092 180)
			(size 0.450088 0.450088)
			(layers "F.Cu" "F.Mask" "F.Paste")
			(net "GMI_CPU1_G3_CPU0_G1_TX_DP<12>")
		)
		(pad "U51" smd circle
			(at 11.8999 -23.850092 180)
			(size 0.450088 0.450088)
			(layers "F.Cu" "F.Mask" "F.Paste")
			(net "GND")
		)
		(pad "U52" smd circle
			(at 12.839954 -23.850092 180)
			(size 0.450088 0.450088)
			(layers "F.Cu" "F.Mask" "F.Paste")
			(net "GMI_CPU1_G3_CPU0_G1_TX_DN<15>")
		)
		(pad "U53" smd circle
			(at 13.780008 -23.850092 180)
			(size 0.450088 0.450088)
			(layers "F.Cu" "F.Mask" "F.Paste")
			(net "GMI_CPU1_G3_CPU0_G1_TX_DP<15>")
		)
		(pad "U54" smd circle
			(at 14.720062 -23.850092 180)
			(size 0.450088 0.450088)
			(layers "F.Cu" "F.Mask" "F.Paste")
			(net "GND")
		)
		(pad "U55" smd circle
			(at 15.660116 -23.850092 180)
			(size 0.450088 0.450088)
			(layers "F.Cu" "F.Mask" "F.Paste")
			(net "M_C_CPU0_SA_DQ<15>")
		)
		(pad "U56" smd circle
			(at 16.599916 -23.850092 180)
			(size 0.450088 0.450088)
			(layers "F.Cu" "F.Mask" "F.Paste")
			(net "GND")
		)
		(pad "U57" smd circle
			(at 17.53997 -23.850092 180)
			(size 0.450088 0.450088)
			(layers "F.Cu" "F.Mask" "F.Paste")
			(net "M_C_CPU0_SA_DQ<16>")
		)
		(pad "U58" smd circle
			(at 18.480024 -23.850092 180)
			(size 0.450088 0.450088)
			(layers "F.Cu" "F.Mask" "F.Paste")
			(net "PVDDIO_P0")
		)
		(pad "U59" smd circle
			(at 19.420078 -23.850092 180)
			(size 0.450088 0.450088)
			(layers "F.Cu" "F.Mask" "F.Paste")
			(net "M_D_CPU0_SA_DQ<15>")
		)
		(pad "U60" smd circle
			(at 20.359878 -23.850092 180)
			(size 0.450088 0.450088)
			(layers "F.Cu" "F.Mask" "F.Paste")
			(net "M_D_CPU0_SA_DQ<16>")
		)
		(pad "U61" smd circle
			(at 21.299932 -23.850092 180)
			(size 0.450088 0.450088)
			(layers "F.Cu" "F.Mask" "F.Paste")
			(net "GND")
		)
		(pad "U62" smd circle
			(at 22.239986 -23.850092 180)
			(size 0.450088 0.450088)
			(layers "F.Cu" "F.Mask" "F.Paste")
			(net "M_B_CPU0_SA_DQ<15>")
		)
		(pad "U63" smd circle
			(at 23.18004 -23.850092 180)
			(size 0.450088 0.450088)
			(layers "F.Cu" "F.Mask" "F.Paste")
			(net "GND")
		)
		(pad "U64" smd circle
			(at 24.120094 -23.850092 180)
			(size 0.450088 0.450088)
			(layers "F.Cu" "F.Mask" "F.Paste")
			(net "M_B_CPU0_SA_DQ<16>")
		)
		(pad "U65" smd circle
			(at 25.059894 -23.850092 180)
			(size 0.450088 0.450088)
			(layers "F.Cu" "F.Mask" "F.Paste")
			(net "PVDDIO_P0")
		)
		(pad "U66" smd circle
			(at 25.999948 -23.850092 180)
			(size 0.450088 0.450088)
			(layers "F.Cu" "F.Mask" "F.Paste")
			(net "M_F_CPU0_SA_DQ<15>")
		)
		(pad "U67" smd circle
			(at 26.940002 -23.850092 180)
			(size 0.450088 0.450088)
			(layers "F.Cu" "F.Mask" "F.Paste")
			(net "M_F_CPU0_SA_DQ<16>")
		)
		(pad "U68" smd circle
			(at 27.880056 -23.850092 180)
			(size 0.450088 0.450088)
			(layers "F.Cu" "F.Mask" "F.Paste")
			(net "GND")
		)
		(pad "U69" smd circle
			(at 28.82011 -23.850092 180)
			(size 0.450088 0.450088)
			(layers "F.Cu" "F.Mask" "F.Paste")
			(net "M_E_CPU0_SA_DQ<15>")
		)
		(pad "U70" smd circle
			(at 29.75991 -23.850092 180)
			(size 0.450088 0.450088)
			(layers "F.Cu" "F.Mask" "F.Paste")
			(net "GND")
		)
		(pad "U71" smd circle
			(at 30.699964 -23.850092 180)
			(size 0.450088 0.450088)
			(layers "F.Cu" "F.Mask" "F.Paste")
			(net "M_E_CPU0_SA_DQ<16>")
		)
		(pad "U72" smd circle
			(at 31.640018 -23.850092 180)
			(size 0.450088 0.450088)
			(layers "F.Cu" "F.Mask" "F.Paste")
			(net "PVDDIO_P0")
		)
		(pad "U73" smd circle
			(at 32.580072 -23.850092 180)
			(size 0.450088 0.450088)
			(layers "F.Cu" "F.Mask" "F.Paste")
			(net "M_A_CPU0_SA_DQ<15>")
		)
		(pad "U74" smd circle
			(at 33.519872 -23.850092 180)
			(size 0.450088 0.450088)
			(layers "F.Cu" "F.Mask" "F.Paste")
			(net "M_A_CPU0_SA_DQ<16>")
		)
		(pad "U75" smd circle
			(at 34.459926 -23.850092 180)
			(size 0.450088 0.450088)
			(layers "F.Cu" "F.Mask" "F.Paste")
			(net "GND")
		)
		(pad "V2" smd circle
			(at -33.690052 -23.040086 180)
			(size 0.450088 0.450088)
			(layers "F.Cu" "F.Mask" "F.Paste")
			(net "M_G_CPU0_SA_DQ<18>")
		)
		(pad "V3" smd circle
			(at -32.749998 -23.040086 180)
			(size 0.450088 0.450088)
			(layers "F.Cu" "F.Mask" "F.Paste")
			(net "GND")
		)
		(pad "V4" smd circle
			(at -31.809944 -23.040086 180)
			(size 0.450088 0.450088)
			(layers "F.Cu" "F.Mask" "F.Paste")
			(net "M_G_CPU0_SA_DQ<17>")
		)
		(pad "V5" smd circle
			(at -30.86989 -23.040086 180)
			(size 0.450088 0.450088)
			(layers "F.Cu" "F.Mask" "F.Paste")
			(net "GND")
		)
		(pad "V6" smd circle
			(at -29.93009 -23.040086 180)
			(size 0.450088 0.450088)
			(layers "F.Cu" "F.Mask" "F.Paste")
			(net "M_K_CPU0_SA_DQ<18>")
		)
		(pad "V7" smd circle
			(at -28.990036 -23.040086 180)
			(size 0.450088 0.450088)
			(layers "F.Cu" "F.Mask" "F.Paste")
			(net "M_K_CPU0_SA_DQ<17>")
		)
		(pad "V8" smd circle
			(at -28.049982 -23.040086 180)
			(size 0.450088 0.450088)
			(layers "F.Cu" "F.Mask" "F.Paste")
			(net "GND")
		)
		(pad "V9" smd circle
			(at -27.109928 -23.040086 180)
			(size 0.450088 0.450088)
			(layers "F.Cu" "F.Mask" "F.Paste")
			(net "M_L_CPU0_SA_DQ<18>")
		)
		(pad "V10" smd circle
			(at -26.170128 -23.040086 180)
			(size 0.450088 0.450088)
			(layers "F.Cu" "F.Mask" "F.Paste")
			(net "GND")
		)
		(pad "V11" smd circle
			(at -25.230074 -23.040086 180)
			(size 0.450088 0.450088)
			(layers "F.Cu" "F.Mask" "F.Paste")
			(net "M_L_CPU0_SA_DQ<17>")
		)
		(pad "V12" smd circle
			(at -24.29002 -23.040086 180)
			(size 0.450088 0.450088)
			(layers "F.Cu" "F.Mask" "F.Paste")
			(net "GND")
		)
		(pad "V13" smd circle
			(at -23.349966 -23.040086 180)
			(size 0.450088 0.450088)
			(layers "F.Cu" "F.Mask" "F.Paste")
			(net "M_H_CPU0_SA_DQ<18>")
		)
		(pad "V14" smd circle
			(at -22.409912 -23.040086 180)
			(size 0.450088 0.450088)
			(layers "F.Cu" "F.Mask" "F.Paste")
			(net "M_H_CPU0_SA_DQ<17>")
		)
		(pad "V15" smd circle
			(at -21.470112 -23.040086 180)
			(size 0.450088 0.450088)
			(layers "F.Cu" "F.Mask" "F.Paste")
			(net "GND")
		)
		(pad "V16" smd circle
			(at -20.530058 -23.040086 180)
			(size 0.450088 0.450088)
			(layers "F.Cu" "F.Mask" "F.Paste")
			(net "M_J_CPU0_SA_DQ<18>")
		)
		(pad "V17" smd circle
			(at -19.590004 -23.040086 180)
			(size 0.450088 0.450088)
			(layers "F.Cu" "F.Mask" "F.Paste")
			(net "GND")
		)
		(pad "V18" smd circle
			(at -18.64995 -23.040086 180)
			(size 0.450088 0.450088)
			(layers "F.Cu" "F.Mask" "F.Paste")
			(net "M_J_CPU0_SA_DQ<17>")
		)
		(pad "V19" smd circle
			(at -17.709896 -23.040086 180)
			(size 0.450088 0.450088)
			(layers "F.Cu" "F.Mask" "F.Paste")
			(net "GND")
		)
		(pad "V20" smd circle
			(at -16.770096 -23.040086 180)
			(size 0.450088 0.450088)
			(layers "F.Cu" "F.Mask" "F.Paste")
			(net "M_I_CPU0_SA_DQ<18>")
		)
		(pad "V21" smd circle
			(at -15.830042 -23.040086 180)
			(size 0.450088 0.450088)
			(layers "F.Cu" "F.Mask" "F.Paste")
			(net "M_I_CPU0_SA_DQ<17>")
		)
		(pad "V22" smd circle
			(at -14.889988 -23.040086 180)
			(size 0.450088 0.450088)
			(layers "F.Cu" "F.Mask" "F.Paste")
			(net "PVDDCR_SOC_P0")
		)
		(pad "V23" smd circle
			(at -13.949934 -23.040086 180)
			(size 0.450088 0.450088)
			(layers "F.Cu" "F.Mask" "F.Paste")
			(net "GND")
		)
		(pad "V24" smd circle
			(at -13.00988 -23.040086 180)
			(size 0.450088 0.450088)
			(layers "F.Cu" "F.Mask" "F.Paste")
			(net "GND")
		)
		(pad "V25" smd circle
			(at -12.07008 -23.040086 180)
			(size 0.450088 0.450088)
			(layers "F.Cu" "F.Mask" "F.Paste")
			(net "GND")
		)
		(pad "V26" smd circle
			(at -11.130026 -23.040086 180)
			(size 0.450088 0.450088)
			(layers "F.Cu" "F.Mask" "F.Paste")
			(net "GND")
		)
		(pad "V27" smd circle
			(at -10.189972 -23.040086 180)
			(size 0.450088 0.450088)
			(layers "F.Cu" "F.Mask" "F.Paste")
			(net "GND")
		)
		(pad "V28" smd circle
			(at -9.249918 -23.040086 180)
			(size 0.450088 0.450088)
			(layers "F.Cu" "F.Mask" "F.Paste")
			(net "GND")
		)
		(pad "V29" smd circle
			(at -8.310118 -23.040086 180)
			(size 0.450088 0.450088)
			(layers "F.Cu" "F.Mask" "F.Paste")
			(net "GND")
		)
		(pad "V30" smd circle
			(at -7.370064 -23.040086 180)
			(size 0.450088 0.450088)
			(layers "F.Cu" "F.Mask" "F.Paste")
			(net "GND")
		)
		(pad "V31" smd circle
			(at -6.43001 -23.040086 180)
			(size 0.450088 0.450088)
			(layers "F.Cu" "F.Mask" "F.Paste")
			(net "GND")
		)
		(pad "V32" smd circle
			(at -5.489956 -23.040086 180)
			(size 0.450088 0.450088)
			(layers "F.Cu" "F.Mask" "F.Paste")
			(net "GND")
		)
		(pad "V33" smd circle
			(at -4.549902 -23.040086 180)
			(size 0.450088 0.450088)
			(layers "F.Cu" "F.Mask" "F.Paste")
			(net "GND")
		)
		(pad "V34" smd circle
			(at -3.610102 -23.040086 180)
			(size 0.450088 0.450088)
			(layers "F.Cu" "F.Mask" "F.Paste")
			(net "GND")
		)
		(pad "V35" smd circle
			(at -2.670048 -23.040086 180)
			(size 0.450088 0.450088)
			(layers "F.Cu" "F.Mask" "F.Paste")
			(net "P5E_CPU0_G3_TX_DP<15>")
		)
		(pad "V36" smd circle
			(at -1.729994 -23.040086 180)
			(size 0.450088 0.450088)
			(layers "F.Cu" "F.Mask" "F.Paste")
			(net "P5E_CPU0_G3_TX_DN<15>")
		)
		(pad "V37" smd circle
			(at -0.78994 -23.040086 180)
			(size 0.450088 0.450088)
			(layers "F.Cu" "F.Mask" "F.Paste")
			(net "GND")
		)
		(pad "V39" smd circle
			(at 1.089914 -23.040086 180)
			(size 0.450088 0.450088)
			(layers "F.Cu" "F.Mask" "F.Paste")
			(net "GND")
		)
		(pad "V40" smd circle
			(at 2.029968 -23.040086 180)
			(size 0.450088 0.450088)
			(layers "F.Cu" "F.Mask" "F.Paste")
			(net "GMI_CPU1_G3_CPU0_G1_TX_DN<0>")
		)
		(pad "V41" smd circle
			(at 2.970022 -23.040086 180)
			(size 0.450088 0.450088)
			(layers "F.Cu" "F.Mask" "F.Paste")
			(net "GMI_CPU1_G3_CPU0_G1_TX_DP<0>")
		)
		(pad "V42" smd circle
			(at 3.910076 -23.040086 180)
			(size 0.450088 0.450088)
			(layers "F.Cu" "F.Mask" "F.Paste")
			(net "GND")
		)
		(pad "V43" smd circle
			(at 4.849876 -23.040086 180)
			(size 0.450088 0.450088)
			(layers "F.Cu" "F.Mask" "F.Paste")
			(net "GND")
		)
		(pad "V44" smd circle
			(at 5.78993 -23.040086 180)
			(size 0.450088 0.450088)
			(layers "F.Cu" "F.Mask" "F.Paste")
			(net "GND")
		)
		(pad "V45" smd circle
			(at 6.729984 -23.040086 180)
			(size 0.450088 0.450088)
			(layers "F.Cu" "F.Mask" "F.Paste")
			(net "GND")
		)
		(pad "V46" smd circle
			(at 7.670038 -23.040086 180)
			(size 0.450088 0.450088)
			(layers "F.Cu" "F.Mask" "F.Paste")
			(net "GND")
		)
		(pad "V47" smd circle
			(at 8.610092 -23.040086 180)
			(size 0.450088 0.450088)
			(layers "F.Cu" "F.Mask" "F.Paste")
			(net "GND")
		)
		(pad "V48" smd circle
			(at 9.549892 -23.040086 180)
			(size 0.450088 0.450088)
			(layers "F.Cu" "F.Mask" "F.Paste")
			(net "GND")
		)
		(pad "V49" smd circle
			(at 10.489946 -23.040086 180)
			(size 0.450088 0.450088)
			(layers "F.Cu" "F.Mask" "F.Paste")
			(net "GND")
		)
		(pad "V50" smd circle
			(at 11.43 -23.040086 180)
			(size 0.450088 0.450088)
			(layers "F.Cu" "F.Mask" "F.Paste")
			(net "GND")
		)
		(pad "V51" smd circle
			(at 12.370054 -23.040086 180)
			(size 0.450088 0.450088)
			(layers "F.Cu" "F.Mask" "F.Paste")
			(net "GND")
		)
		(pad "V52" smd circle
			(at 13.310108 -23.040086 180)
			(size 0.450088 0.450088)
			(layers "F.Cu" "F.Mask" "F.Paste")
			(net "GND")
		)
		(pad "V53" smd circle
			(at 14.249908 -23.040086 180)
			(size 0.450088 0.450088)
			(layers "F.Cu" "F.Mask" "F.Paste")
			(net "GND")
		)
		(pad "V54" smd circle
			(at 15.189962 -23.040086 180)
			(size 0.450088 0.450088)
			(layers "F.Cu" "F.Mask" "F.Paste")
			(net "PVDDIO_P0")
		)
		(pad "V55" smd circle
			(at 16.130016 -23.040086 180)
			(size 0.450088 0.450088)
			(layers "F.Cu" "F.Mask" "F.Paste")
			(net "M_C_CPU0_SA_DQ<17>")
		)
		(pad "V56" smd circle
			(at 17.07007 -23.040086 180)
			(size 0.450088 0.450088)
			(layers "F.Cu" "F.Mask" "F.Paste")
			(net "M_C_CPU0_SA_DQ<18>")
		)
		(pad "V57" smd circle
			(at 18.010124 -23.040086 180)
			(size 0.450088 0.450088)
			(layers "F.Cu" "F.Mask" "F.Paste")
			(net "GND")
		)
		(pad "V58" smd circle
			(at 18.949924 -23.040086 180)
			(size 0.450088 0.450088)
			(layers "F.Cu" "F.Mask" "F.Paste")
			(net "M_D_CPU0_SA_DQ<17>")
		)
		(pad "V59" smd circle
			(at 19.889978 -23.040086 180)
			(size 0.450088 0.450088)
			(layers "F.Cu" "F.Mask" "F.Paste")
			(net "GND")
		)
		(pad "V60" smd circle
			(at 20.830032 -23.040086 180)
			(size 0.450088 0.450088)
			(layers "F.Cu" "F.Mask" "F.Paste")
			(net "M_D_CPU0_SA_DQ<18>")
		)
		(pad "V61" smd circle
			(at 21.770086 -23.040086 180)
			(size 0.450088 0.450088)
			(layers "F.Cu" "F.Mask" "F.Paste")
			(net "GND")
		)
		(pad "V62" smd circle
			(at 22.709886 -23.040086 180)
			(size 0.450088 0.450088)
			(layers "F.Cu" "F.Mask" "F.Paste")
			(net "M_B_CPU0_SA_DQ<17>")
		)
		(pad "V63" smd circle
			(at 23.64994 -23.040086 180)
			(size 0.450088 0.450088)
			(layers "F.Cu" "F.Mask" "F.Paste")
			(net "M_B_CPU0_SA_DQ<18>")
		)
		(pad "V64" smd circle
			(at 24.589994 -23.040086 180)
			(size 0.450088 0.450088)
			(layers "F.Cu" "F.Mask" "F.Paste")
			(net "GND")
		)
		(pad "V65" smd circle
			(at 25.530048 -23.040086 180)
			(size 0.450088 0.450088)
			(layers "F.Cu" "F.Mask" "F.Paste")
			(net "M_F_CPU0_SA_DQ<17>")
		)
		(pad "V66" smd circle
			(at 26.470102 -23.040086 180)
			(size 0.450088 0.450088)
			(layers "F.Cu" "F.Mask" "F.Paste")
			(net "GND")
		)
		(pad "V67" smd circle
			(at 27.409902 -23.040086 180)
			(size 0.450088 0.450088)
			(layers "F.Cu" "F.Mask" "F.Paste")
			(net "M_F_CPU0_SA_DQ<18>")
		)
		(pad "V68" smd circle
			(at 28.349956 -23.040086 180)
			(size 0.450088 0.450088)
			(layers "F.Cu" "F.Mask" "F.Paste")
			(net "GND")
		)
		(pad "V69" smd circle
			(at 29.29001 -23.040086 180)
			(size 0.450088 0.450088)
			(layers "F.Cu" "F.Mask" "F.Paste")
			(net "M_E_CPU0_SA_DQ<17>")
		)
		(pad "V70" smd circle
			(at 30.230064 -23.040086 180)
			(size 0.450088 0.450088)
			(layers "F.Cu" "F.Mask" "F.Paste")
			(net "M_E_CPU0_SA_DQ<18>")
		)
		(pad "V71" smd circle
			(at 31.170118 -23.040086 180)
			(size 0.450088 0.450088)
			(layers "F.Cu" "F.Mask" "F.Paste")
			(net "GND")
		)
		(pad "V72" smd circle
			(at 32.109918 -23.040086 180)
			(size 0.450088 0.450088)
			(layers "F.Cu" "F.Mask" "F.Paste")
			(net "M_A_CPU0_SA_DQ<17>")
		)
		(pad "V73" smd circle
			(at 33.049972 -23.040086 180)
			(size 0.450088 0.450088)
			(layers "F.Cu" "F.Mask" "F.Paste")
			(net "GND")
		)
		(pad "V74" smd circle
			(at 33.990026 -23.040086 180)
			(size 0.450088 0.450088)
			(layers "F.Cu" "F.Mask" "F.Paste")
			(net "M_A_CPU0_SA_DQ<18>")
		)
		(pad "W1" smd circle
			(at -34.159952 -22.23008 180)
			(size 0.450088 0.450088)
			(layers "F.Cu" "F.Mask" "F.Paste")
			(net "GND")
		)
		(pad "W2" smd circle
			(at -33.219898 -22.23008 180)
			(size 0.450088 0.450088)
			(layers "F.Cu" "F.Mask" "F.Paste")
			(net "M_G_CPU0_SA_DQS_DP<2>")
		)
		(pad "W3" smd circle
			(at -32.280098 -22.23008 180)
			(size 0.450088 0.450088)
			(layers "F.Cu" "F.Mask" "F.Paste")
			(net "M_G_CPU0_SA_DQ<19>")
		)
		(pad "W4" smd circle
			(at -31.340044 -22.23008 180)
			(size 0.450088 0.450088)
			(layers "F.Cu" "F.Mask" "F.Paste")
			(net "GND")
		)
		(pad "W5" smd circle
			(at -30.39999 -22.23008 180)
			(size 0.450088 0.450088)
			(layers "F.Cu" "F.Mask" "F.Paste")
			(net "M_K_CPU0_SA_DQS_DP<2>")
		)
		(pad "W6" smd circle
			(at -29.459936 -22.23008 180)
			(size 0.450088 0.450088)
			(layers "F.Cu" "F.Mask" "F.Paste")
			(net "GND")
		)
		(pad "W7" smd circle
			(at -28.519882 -22.23008 180)
			(size 0.450088 0.450088)
			(layers "F.Cu" "F.Mask" "F.Paste")
			(net "M_K_CPU0_SA_DQ<19>")
		)
		(pad "W8" smd circle
			(at -27.580082 -22.23008 180)
			(size 0.450088 0.450088)
			(layers "F.Cu" "F.Mask" "F.Paste")
			(net "GND")
		)
		(pad "W9" smd circle
			(at -26.640028 -22.23008 180)
			(size 0.450088 0.450088)
			(layers "F.Cu" "F.Mask" "F.Paste")
			(net "M_L_CPU0_SA_DQS_DP<2>")
		)
		(pad "W10" smd circle
			(at -25.699974 -22.23008 180)
			(size 0.450088 0.450088)
			(layers "F.Cu" "F.Mask" "F.Paste")
			(net "M_L_CPU0_SA_DQ<19>")
		)
		(pad "W11" smd circle
			(at -24.75992 -22.23008 180)
			(size 0.450088 0.450088)
			(layers "F.Cu" "F.Mask" "F.Paste")
			(net "GND")
		)
		(pad "W12" smd circle
			(at -23.82012 -22.23008 180)
			(size 0.450088 0.450088)
			(layers "F.Cu" "F.Mask" "F.Paste")
			(net "M_H_CPU0_SA_DQS_DP<2>")
		)
		(pad "W13" smd circle
			(at -22.880066 -22.23008 180)
			(size 0.450088 0.450088)
			(layers "F.Cu" "F.Mask" "F.Paste")
			(net "GND")
		)
		(pad "W14" smd circle
			(at -21.940012 -22.23008 180)
			(size 0.450088 0.450088)
			(layers "F.Cu" "F.Mask" "F.Paste")
			(net "M_H_CPU0_SA_DQ<19>")
		)
		(pad "W15" smd circle
			(at -20.999958 -22.23008 180)
			(size 0.450088 0.450088)
			(layers "F.Cu" "F.Mask" "F.Paste")
			(net "GND")
		)
		(pad "W16" smd circle
			(at -20.059904 -22.23008 180)
			(size 0.450088 0.450088)
			(layers "F.Cu" "F.Mask" "F.Paste")
			(net "M_J_CPU0_SA_DQS_DP<2>")
		)
		(pad "W17" smd circle
			(at -19.120104 -22.23008 180)
			(size 0.450088 0.450088)
			(layers "F.Cu" "F.Mask" "F.Paste")
			(net "M_J_CPU0_SA_DQ<19>")
		)
		(pad "W18" smd circle
			(at -18.18005 -22.23008 180)
			(size 0.450088 0.450088)
			(layers "F.Cu" "F.Mask" "F.Paste")
			(net "GND")
		)
		(pad "W19" smd circle
			(at -17.239996 -22.23008 180)
			(size 0.450088 0.450088)
			(layers "F.Cu" "F.Mask" "F.Paste")
			(net "M_I_CPU0_SA_DQS_DP<2>")
		)
		(pad "W20" smd circle
			(at -16.299942 -22.23008 180)
			(size 0.450088 0.450088)
			(layers "F.Cu" "F.Mask" "F.Paste")
			(net "GND")
		)
		(pad "W21" smd circle
			(at -15.359888 -22.23008 180)
			(size 0.450088 0.450088)
			(layers "F.Cu" "F.Mask" "F.Paste")
			(net "M_I_CPU0_SA_DQ<19>")
		)
		(pad "W22" smd circle
			(at -14.420088 -22.23008 180)
			(size 0.450088 0.450088)
			(layers "F.Cu" "F.Mask" "F.Paste")
			(net "GND")
		)
		(pad "W23" smd circle
			(at -13.480034 -22.23008 180)
			(size 0.450088 0.450088)
			(layers "F.Cu" "F.Mask" "F.Paste")
			(net "P5E_CPU0_G3_TX_DP<2>")
		)
		(pad "W24" smd circle
			(at -12.53998 -22.23008 180)
			(size 0.450088 0.450088)
			(layers "F.Cu" "F.Mask" "F.Paste")
			(net "P5E_CPU0_G3_TX_DN<2>")
		)
		(pad "W25" smd circle
			(at -11.599926 -22.23008 180)
			(size 0.450088 0.450088)
			(layers "F.Cu" "F.Mask" "F.Paste")
			(net "GND")
		)
		(pad "W26" smd circle
			(at -10.659872 -22.23008 180)
			(size 0.450088 0.450088)
			(layers "F.Cu" "F.Mask" "F.Paste")
			(net "P5E_CPU0_G3_TX_DP<6>")
		)
		(pad "W27" smd circle
			(at -9.720072 -22.23008 180)
			(size 0.450088 0.450088)
			(layers "F.Cu" "F.Mask" "F.Paste")
			(net "P5E_CPU0_G3_TX_DN<6>")
		)
		(pad "W28" smd circle
			(at -8.780018 -22.23008 180)
			(size 0.450088 0.450088)
			(layers "F.Cu" "F.Mask" "F.Paste")
			(net "GND")
		)
		(pad "W29" smd circle
			(at -7.839964 -22.23008 180)
			(size 0.450088 0.450088)
			(layers "F.Cu" "F.Mask" "F.Paste")
			(net "PVDDCR_CPU0_P0")
		)
		(pad "W30" smd circle
			(at -6.89991 -22.23008 180)
			(size 0.450088 0.450088)
			(layers "F.Cu" "F.Mask" "F.Paste")
			(net "PVDDCR_CPU0_P0")
		)
		(pad "W31" smd circle
			(at -5.96011 -22.23008 180)
			(size 0.450088 0.450088)
			(layers "F.Cu" "F.Mask" "F.Paste")
			(net "TP_CPU0_TEST41_IDO")
		)
		(pad "W32" smd circle
			(at -5.020056 -22.23008 180)
			(size 0.450088 0.450088)
			(layers "F.Cu" "F.Mask" "F.Paste")
			(net "PVDDCR_CPU0_P0")
		)
		(pad "W33" smd circle
			(at -4.080002 -22.23008 180)
			(size 0.450088 0.450088)
			(layers "F.Cu" "F.Mask" "F.Paste")
			(net "PVDDCR_CPU0_P0")
		)
		(pad "W34" smd circle
			(at -3.139948 -22.23008 180)
			(size 0.450088 0.450088)
			(layers "F.Cu" "F.Mask" "F.Paste")
			(net "GND")
		)
		(pad "W35" smd circle
			(at -2.199894 -22.23008 180)
			(size 0.450088 0.450088)
			(layers "F.Cu" "F.Mask" "F.Paste")
			(net "GND")
		)
		(pad "W36" smd circle
			(at -1.260094 -22.23008 180)
			(size 0.450088 0.450088)
			(layers "F.Cu" "F.Mask" "F.Paste")
			(net "GND")
		)
		(pad "W40" smd circle
			(at 1.560068 -22.23008 180)
			(size 0.450088 0.450088)
			(layers "F.Cu" "F.Mask" "F.Paste")
			(net "GND")
		)
		(pad "W41" smd circle
			(at 2.500122 -22.23008 180)
			(size 0.450088 0.450088)
			(layers "F.Cu" "F.Mask" "F.Paste")
			(net "GND")
		)
		(pad "W42" smd circle
			(at 3.439922 -22.23008 180)
			(size 0.450088 0.450088)
			(layers "F.Cu" "F.Mask" "F.Paste")
			(net "GND")
		)
		(pad "W43" smd circle
			(at 4.379976 -22.23008 180)
			(size 0.450088 0.450088)
			(layers "F.Cu" "F.Mask" "F.Paste")
			(net "PVDDCR_CPU0_P0")
		)
		(pad "W44" smd circle
			(at 5.32003 -22.23008 180)
			(size 0.450088 0.450088)
			(layers "F.Cu" "F.Mask" "F.Paste")
			(net "PVDDCR_CPU0_P0")
		)
		(pad "W45" smd circle
			(at 6.260084 -22.23008 180)
			(size 0.450088 0.450088)
			(layers "F.Cu" "F.Mask" "F.Paste")
			(net "GND")
		)
		(pad "W46" smd circle
			(at 7.199884 -22.23008 180)
			(size 0.450088 0.450088)
			(layers "F.Cu" "F.Mask" "F.Paste")
			(net "PVDDCR_CPU0_P0")
		)
		(pad "W47" smd circle
			(at 8.139938 -22.23008 180)
			(size 0.450088 0.450088)
			(layers "F.Cu" "F.Mask" "F.Paste")
			(net "PVDDCR_CPU0_P0")
		)
		(pad "W48" smd circle
			(at 9.079992 -22.23008 180)
			(size 0.450088 0.450088)
			(layers "F.Cu" "F.Mask" "F.Paste")
			(net "GND")
		)
		(pad "W49" smd circle
			(at 10.020046 -22.23008 180)
			(size 0.450088 0.450088)
			(layers "F.Cu" "F.Mask" "F.Paste")
			(net "GMI_CPU1_G3_CPU0_G1_TX_DN<9>")
		)
		(pad "W50" smd circle
			(at 10.9601 -22.23008 180)
			(size 0.450088 0.450088)
			(layers "F.Cu" "F.Mask" "F.Paste")
			(net "GMI_CPU1_G3_CPU0_G1_TX_DP<9>")
		)
		(pad "W51" smd circle
			(at 11.8999 -22.23008 180)
			(size 0.450088 0.450088)
			(layers "F.Cu" "F.Mask" "F.Paste")
			(net "GND")
		)
		(pad "W52" smd circle
			(at 12.839954 -22.23008 180)
			(size 0.450088 0.450088)
			(layers "F.Cu" "F.Mask" "F.Paste")
			(net "GMI_CPU1_G3_CPU0_G1_TX_DN<13>")
		)
		(pad "W53" smd circle
			(at 13.780008 -22.23008 180)
			(size 0.450088 0.450088)
			(layers "F.Cu" "F.Mask" "F.Paste")
			(net "GMI_CPU1_G3_CPU0_G1_TX_DP<13>")
		)
		(pad "W54" smd circle
			(at 14.720062 -22.23008 180)
			(size 0.450088 0.450088)
			(layers "F.Cu" "F.Mask" "F.Paste")
			(net "GND")
		)
		(pad "W55" smd circle
			(at 15.660116 -22.23008 180)
			(size 0.450088 0.450088)
			(layers "F.Cu" "F.Mask" "F.Paste")
			(net "M_C_CPU0_SA_DQ<19>")
		)
		(pad "W56" smd circle
			(at 16.599916 -22.23008 180)
			(size 0.450088 0.450088)
			(layers "F.Cu" "F.Mask" "F.Paste")
			(net "GND")
		)
		(pad "W57" smd circle
			(at 17.53997 -22.23008 180)
			(size 0.450088 0.450088)
			(layers "F.Cu" "F.Mask" "F.Paste")
			(net "M_C_CPU0_SA_DQS_DP<2>")
		)
		(pad "W58" smd circle
			(at 18.480024 -22.23008 180)
			(size 0.450088 0.450088)
			(layers "F.Cu" "F.Mask" "F.Paste")
			(net "GND")
		)
		(pad "W59" smd circle
			(at 19.420078 -22.23008 180)
			(size 0.450088 0.450088)
			(layers "F.Cu" "F.Mask" "F.Paste")
			(net "M_D_CPU0_SA_DQ<19>")
		)
		(pad "W60" smd circle
			(at 20.359878 -22.23008 180)
			(size 0.450088 0.450088)
			(layers "F.Cu" "F.Mask" "F.Paste")
			(net "M_D_CPU0_SA_DQS_DP<2>")
		)
		(pad "W61" smd circle
			(at 21.299932 -22.23008 180)
			(size 0.450088 0.450088)
			(layers "F.Cu" "F.Mask" "F.Paste")
			(net "GND")
		)
		(pad "W62" smd circle
			(at 22.239986 -22.23008 180)
			(size 0.450088 0.450088)
			(layers "F.Cu" "F.Mask" "F.Paste")
			(net "M_B_CPU0_SA_DQ<19>")
		)
		(pad "W63" smd circle
			(at 23.18004 -22.23008 180)
			(size 0.450088 0.450088)
			(layers "F.Cu" "F.Mask" "F.Paste")
			(net "GND")
		)
		(pad "W64" smd circle
			(at 24.120094 -22.23008 180)
			(size 0.450088 0.450088)
			(layers "F.Cu" "F.Mask" "F.Paste")
			(net "M_B_CPU0_SA_DQS_DP<2>")
		)
		(pad "W65" smd circle
			(at 25.059894 -22.23008 180)
			(size 0.450088 0.450088)
			(layers "F.Cu" "F.Mask" "F.Paste")
			(net "GND")
		)
		(pad "W66" smd circle
			(at 25.999948 -22.23008 180)
			(size 0.450088 0.450088)
			(layers "F.Cu" "F.Mask" "F.Paste")
			(net "M_F_CPU0_SA_DQ<19>")
		)
		(pad "W67" smd circle
			(at 26.940002 -22.23008 180)
			(size 0.450088 0.450088)
			(layers "F.Cu" "F.Mask" "F.Paste")
			(net "M_F_CPU0_SA_DQS_DP<2>")
		)
		(pad "W68" smd circle
			(at 27.880056 -22.23008 180)
			(size 0.450088 0.450088)
			(layers "F.Cu" "F.Mask" "F.Paste")
			(net "GND")
		)
		(pad "W69" smd circle
			(at 28.82011 -22.23008 180)
			(size 0.450088 0.450088)
			(layers "F.Cu" "F.Mask" "F.Paste")
			(net "M_E_CPU0_SA_DQ<19>")
		)
		(pad "W70" smd circle
			(at 29.75991 -22.23008 180)
			(size 0.450088 0.450088)
			(layers "F.Cu" "F.Mask" "F.Paste")
			(net "GND")
		)
		(pad "W71" smd circle
			(at 30.699964 -22.23008 180)
			(size 0.450088 0.450088)
			(layers "F.Cu" "F.Mask" "F.Paste")
			(net "M_E_CPU0_SA_DQS_DP<2>")
		)
		(pad "W72" smd circle
			(at 31.640018 -22.23008 180)
			(size 0.450088 0.450088)
			(layers "F.Cu" "F.Mask" "F.Paste")
			(net "GND")
		)
		(pad "W73" smd circle
			(at 32.580072 -22.23008 180)
			(size 0.450088 0.450088)
			(layers "F.Cu" "F.Mask" "F.Paste")
			(net "M_A_CPU0_SA_DQ<19>")
		)
		(pad "W74" smd circle
			(at 33.519872 -22.23008 180)
			(size 0.450088 0.450088)
			(layers "F.Cu" "F.Mask" "F.Paste")
			(net "M_A_CPU0_SA_DQS_DP<2>")
		)
		(pad "W75" smd circle
			(at 34.459926 -22.23008 180)
			(size 0.450088 0.450088)
			(layers "F.Cu" "F.Mask" "F.Paste")
			(net "GND")
		)
		(pad "Y2" smd circle
			(at -33.690052 -21.420074 180)
			(size 0.450088 0.450088)
			(layers "F.Cu" "F.Mask" "F.Paste")
			(net "M_G_CPU0_SA_DQS_DN<2>")
		)
		(pad "Y3" smd circle
			(at -32.749998 -21.420074 180)
			(size 0.450088 0.450088)
			(layers "F.Cu" "F.Mask" "F.Paste")
			(net "GND")
		)
		(pad "Y4" smd circle
			(at -31.809944 -21.420074 180)
			(size 0.450088 0.450088)
			(layers "F.Cu" "F.Mask" "F.Paste")
			(net "M_G_CPU0_SA_DQS_DN<7>")
		)
		(pad "Y5" smd circle
			(at -30.86989 -21.420074 180)
			(size 0.450088 0.450088)
			(layers "F.Cu" "F.Mask" "F.Paste")
			(net "PVDDCR_SOC_P0")
		)
		(pad "Y6" smd circle
			(at -29.93009 -21.420074 180)
			(size 0.450088 0.450088)
			(layers "F.Cu" "F.Mask" "F.Paste")
			(net "M_K_CPU0_SA_DQS_DN<2>")
		)
		(pad "Y7" smd circle
			(at -28.990036 -21.420074 180)
			(size 0.450088 0.450088)
			(layers "F.Cu" "F.Mask" "F.Paste")
			(net "M_K_CPU0_SA_DQS_DN<7>")
		)
		(pad "Y8" smd circle
			(at -28.049982 -21.420074 180)
			(size 0.450088 0.450088)
			(layers "F.Cu" "F.Mask" "F.Paste")
			(net "GND")
		)
		(pad "Y9" smd circle
			(at -27.109928 -21.420074 180)
			(size 0.450088 0.450088)
			(layers "F.Cu" "F.Mask" "F.Paste")
			(net "M_L_CPU0_SA_DQS_DN<2>")
		)
		(pad "Y10" smd circle
			(at -26.170128 -21.420074 180)
			(size 0.450088 0.450088)
			(layers "F.Cu" "F.Mask" "F.Paste")
			(net "GND")
		)
		(pad "Y11" smd circle
			(at -25.230074 -21.420074 180)
			(size 0.450088 0.450088)
			(layers "F.Cu" "F.Mask" "F.Paste")
			(net "M_L_CPU0_SA_DQS_DN<7>")
		)
		(pad "Y12" smd circle
			(at -24.29002 -21.420074 180)
			(size 0.450088 0.450088)
			(layers "F.Cu" "F.Mask" "F.Paste")
			(net "PVDDCR_SOC_P0")
		)
		(pad "Y13" smd circle
			(at -23.349966 -21.420074 180)
			(size 0.450088 0.450088)
			(layers "F.Cu" "F.Mask" "F.Paste")
			(net "M_H_CPU0_SA_DQS_DN<2>")
		)
		(pad "Y14" smd circle
			(at -22.409912 -21.420074 180)
			(size 0.450088 0.450088)
			(layers "F.Cu" "F.Mask" "F.Paste")
			(net "M_H_CPU0_SA_DQS_DN<7>")
		)
		(pad "Y15" smd circle
			(at -21.470112 -21.420074 180)
			(size 0.450088 0.450088)
			(layers "F.Cu" "F.Mask" "F.Paste")
			(net "GND")
		)
		(pad "Y16" smd circle
			(at -20.530058 -21.420074 180)
			(size 0.450088 0.450088)
			(layers "F.Cu" "F.Mask" "F.Paste")
			(net "M_J_CPU0_SA_DQS_DN<2>")
		)
		(pad "Y17" smd circle
			(at -19.590004 -21.420074 180)
			(size 0.450088 0.450088)
			(layers "F.Cu" "F.Mask" "F.Paste")
			(net "GND")
		)
		(pad "Y18" smd circle
			(at -18.64995 -21.420074 180)
			(size 0.450088 0.450088)
			(layers "F.Cu" "F.Mask" "F.Paste")
			(net "M_J_CPU0_SA_DQS_DN<7>")
		)
		(pad "Y19" smd circle
			(at -17.709896 -21.420074 180)
			(size 0.450088 0.450088)
			(layers "F.Cu" "F.Mask" "F.Paste")
			(net "PVDDCR_SOC_P0")
		)
		(pad "Y20" smd circle
			(at -16.770096 -21.420074 180)
			(size 0.450088 0.450088)
			(layers "F.Cu" "F.Mask" "F.Paste")
			(net "M_I_CPU0_SA_DQS_DN<2>")
		)
		(pad "Y21" smd circle
			(at -15.830042 -21.420074 180)
			(size 0.450088 0.450088)
			(layers "F.Cu" "F.Mask" "F.Paste")
			(net "M_I_CPU0_SA_DQS_DN<7>")
		)
		(pad "Y22" smd circle
			(at -14.889988 -21.420074 180)
			(size 0.450088 0.450088)
			(layers "F.Cu" "F.Mask" "F.Paste")
			(net "GND")
		)
		(pad "Y23" smd circle
			(at -13.949934 -21.420074 180)
			(size 0.450088 0.450088)
			(layers "F.Cu" "F.Mask" "F.Paste")
			(net "GND")
		)
		(pad "Y24" smd circle
			(at -13.00988 -21.420074 180)
			(size 0.450088 0.450088)
			(layers "F.Cu" "F.Mask" "F.Paste")
			(net "GND")
		)
		(pad "Y25" smd circle
			(at -12.07008 -21.420074 180)
			(size 0.450088 0.450088)
			(layers "F.Cu" "F.Mask" "F.Paste")
			(net "GND")
		)
		(pad "Y26" smd circle
			(at -11.130026 -21.420074 180)
			(size 0.450088 0.450088)
			(layers "F.Cu" "F.Mask" "F.Paste")
			(net "GND")
		)
		(pad "Y27" smd circle
			(at -10.189972 -21.420074 180)
			(size 0.450088 0.450088)
			(layers "F.Cu" "F.Mask" "F.Paste")
			(net "GND")
		)
		(pad "Y28" smd circle
			(at -9.249918 -21.420074 180)
			(size 0.450088 0.450088)
			(layers "F.Cu" "F.Mask" "F.Paste")
			(net "GND")
		)
		(pad "Y29" smd circle
			(at -8.310118 -21.420074 180)
			(size 0.450088 0.450088)
			(layers "F.Cu" "F.Mask" "F.Paste")
			(net "TP_CPU0_TEST5_CCD11")
		)
		(pad "Y30" smd circle
			(at -7.370064 -21.420074 180)
			(size 0.450088 0.450088)
			(layers "F.Cu" "F.Mask" "F.Paste")
			(net "TP_CPU0_TEST5_CCD3")
		)
		(pad "Y31" smd circle
			(at -6.43001 -21.420074 180)
			(size 0.450088 0.450088)
			(layers "F.Cu" "F.Mask" "F.Paste")
			(net "GND")
		)
		(pad "Y32" smd circle
			(at -5.489956 -21.420074 180)
			(size 0.450088 0.450088)
			(layers "F.Cu" "F.Mask" "F.Paste")
			(net "GND")
		)
		(pad "Y33" smd circle
			(at -4.549902 -21.420074 180)
			(size 0.450088 0.450088)
			(layers "F.Cu" "F.Mask" "F.Paste")
			(net "GND")
		)
		(pad "Y34" smd circle
			(at -3.610102 -21.420074 180)
			(size 0.450088 0.450088)
			(layers "F.Cu" "F.Mask" "F.Paste")
			(net "GND")
		)
		(pad "Y35" smd circle
			(at -2.670048 -21.420074 180)
			(size 0.450088 0.450088)
			(layers "F.Cu" "F.Mask" "F.Paste")
			(net "PVDDCR_CPU0_P0")
		)
		(pad "Y36" smd circle
			(at -1.729994 -21.420074 180)
			(size 0.450088 0.450088)
			(layers "F.Cu" "F.Mask" "F.Paste")
			(net "PVDDCR_CPU0_P0")
		)
		(pad "Y37" smd circle
			(at -0.78994 -21.420074 180)
			(size 0.450088 0.450088)
			(layers "F.Cu" "F.Mask" "F.Paste")
			(net "GND")
		)
		(pad "Y39" smd circle
			(at 1.089914 -21.420074 180)
			(size 0.450088 0.450088)
			(layers "F.Cu" "F.Mask" "F.Paste")
			(net "GND")
		)
		(pad "Y40" smd circle
			(at 2.029968 -21.420074 180)
			(size 0.450088 0.450088)
			(layers "F.Cu" "F.Mask" "F.Paste")
			(net "PVDDCR_CPU0_P0")
		)
		(pad "Y41" smd circle
			(at 2.970022 -21.420074 180)
			(size 0.450088 0.450088)
			(layers "F.Cu" "F.Mask" "F.Paste")
			(net "PVDDCR_CPU0_P0")
		)
		(pad "Y42" smd circle
			(at 3.910076 -21.420074 180)
			(size 0.450088 0.450088)
			(layers "F.Cu" "F.Mask" "F.Paste")
			(net "GND")
		)
		(pad "Y43" smd circle
			(at 4.849876 -21.420074 180)
			(size 0.450088 0.450088)
			(layers "F.Cu" "F.Mask" "F.Paste")
			(net "GND")
		)
		(pad "Y44" smd circle
			(at 5.78993 -21.420074 180)
			(size 0.450088 0.450088)
			(layers "F.Cu" "F.Mask" "F.Paste")
			(net "GND")
		)
		(pad "Y45" smd circle
			(at 6.729984 -21.420074 180)
			(size 0.450088 0.450088)
			(layers "F.Cu" "F.Mask" "F.Paste")
			(net "GND")
		)
		(pad "Y46" smd circle
			(at 7.670038 -21.420074 180)
			(size 0.450088 0.450088)
			(layers "F.Cu" "F.Mask" "F.Paste")
			(net "TP_CPU0_TEST6_CCD3")
		)
		(pad "Y47" smd circle
			(at 8.610092 -21.420074 180)
			(size 0.450088 0.450088)
			(layers "F.Cu" "F.Mask" "F.Paste")
			(net "TP_CPU0_TEST5_CCD8")
		)
		(pad "Y48" smd circle
			(at 9.549892 -21.420074 180)
			(size 0.450088 0.450088)
			(layers "F.Cu" "F.Mask" "F.Paste")
			(net "GND")
		)
		(pad "Y49" smd circle
			(at 10.489946 -21.420074 180)
			(size 0.450088 0.450088)
			(layers "F.Cu" "F.Mask" "F.Paste")
			(net "GND")
		)
		(pad "Y50" smd circle
			(at 11.43 -21.420074 180)
			(size 0.450088 0.450088)
			(layers "F.Cu" "F.Mask" "F.Paste")
			(net "GND")
		)
		(pad "Y51" smd circle
			(at 12.370054 -21.420074 180)
			(size 0.450088 0.450088)
			(layers "F.Cu" "F.Mask" "F.Paste")
			(net "GND")
		)
		(pad "Y52" smd circle
			(at 13.310108 -21.420074 180)
			(size 0.450088 0.450088)
			(layers "F.Cu" "F.Mask" "F.Paste")
			(net "GND")
		)
		(pad "Y53" smd circle
			(at 14.249908 -21.420074 180)
			(size 0.450088 0.450088)
			(layers "F.Cu" "F.Mask" "F.Paste")
			(net "GND")
		)
		(pad "Y54" smd circle
			(at 15.189962 -21.420074 180)
			(size 0.450088 0.450088)
			(layers "F.Cu" "F.Mask" "F.Paste")
			(net "GND")
		)
		(pad "Y55" smd circle
			(at 16.130016 -21.420074 180)
			(size 0.450088 0.450088)
			(layers "F.Cu" "F.Mask" "F.Paste")
			(net "M_C_CPU0_SA_DQS_DN<7>")
		)
		(pad "Y56" smd circle
			(at 17.07007 -21.420074 180)
			(size 0.450088 0.450088)
			(layers "F.Cu" "F.Mask" "F.Paste")
			(net "M_C_CPU0_SA_DQS_DN<2>")
		)
		(pad "Y57" smd circle
			(at 18.010124 -21.420074 180)
			(size 0.450088 0.450088)
			(layers "F.Cu" "F.Mask" "F.Paste")
			(net "PVDDIO_P0")
		)
		(pad "Y58" smd circle
			(at 18.949924 -21.420074 180)
			(size 0.450088 0.450088)
			(layers "F.Cu" "F.Mask" "F.Paste")
			(net "M_D_CPU0_SA_DQS_DN<7>")
		)
		(pad "Y59" smd circle
			(at 19.889978 -21.420074 180)
			(size 0.450088 0.450088)
			(layers "F.Cu" "F.Mask" "F.Paste")
			(net "GND")
		)
		(pad "Y60" smd circle
			(at 20.830032 -21.420074 180)
			(size 0.450088 0.450088)
			(layers "F.Cu" "F.Mask" "F.Paste")
			(net "M_D_CPU0_SA_DQS_DN<2>")
		)
		(pad "Y61" smd circle
			(at 21.770086 -21.420074 180)
			(size 0.450088 0.450088)
			(layers "F.Cu" "F.Mask" "F.Paste")
			(net "GND")
		)
		(pad "Y62" smd circle
			(at 22.709886 -21.420074 180)
			(size 0.450088 0.450088)
			(layers "F.Cu" "F.Mask" "F.Paste")
			(net "M_B_CPU0_SA_DQS_DN<7>")
		)
		(pad "Y63" smd circle
			(at 23.64994 -21.420074 180)
			(size 0.450088 0.450088)
			(layers "F.Cu" "F.Mask" "F.Paste")
			(net "M_B_CPU0_SA_DQS_DN<2>")
		)
		(pad "Y64" smd circle
			(at 24.589994 -21.420074 180)
			(size 0.450088 0.450088)
			(layers "F.Cu" "F.Mask" "F.Paste")
			(net "PVDDIO_P0")
		)
		(pad "Y65" smd circle
			(at 25.530048 -21.420074 180)
			(size 0.450088 0.450088)
			(layers "F.Cu" "F.Mask" "F.Paste")
			(net "M_F_CPU0_SA_DQS_DN<7>")
		)
		(pad "Y66" smd circle
			(at 26.470102 -21.420074 180)
			(size 0.450088 0.450088)
			(layers "F.Cu" "F.Mask" "F.Paste")
			(net "GND")
		)
		(pad "Y67" smd circle
			(at 27.409902 -21.420074 180)
			(size 0.450088 0.450088)
			(layers "F.Cu" "F.Mask" "F.Paste")
			(net "M_F_CPU0_SA_DQS_DN<2>")
		)
		(pad "Y68" smd circle
			(at 28.349956 -21.420074 180)
			(size 0.450088 0.450088)
			(layers "F.Cu" "F.Mask" "F.Paste")
			(net "GND")
		)
		(pad "Y69" smd circle
			(at 29.29001 -21.420074 180)
			(size 0.450088 0.450088)
			(layers "F.Cu" "F.Mask" "F.Paste")
			(net "M_E_CPU0_SA_DQS_DN<7>")
		)
		(pad "Y70" smd circle
			(at 30.230064 -21.420074 180)
			(size 0.450088 0.450088)
			(layers "F.Cu" "F.Mask" "F.Paste")
			(net "M_E_CPU0_SA_DQS_DN<2>")
		)
		(pad "Y71" smd circle
			(at 31.170118 -21.420074 180)
			(size 0.450088 0.450088)
			(layers "F.Cu" "F.Mask" "F.Paste")
			(net "PVDDIO_P0")
		)
		(pad "Y72" smd circle
			(at 32.109918 -21.420074 180)
			(size 0.450088 0.450088)
			(layers "F.Cu" "F.Mask" "F.Paste")
			(net "M_A_CPU0_SA_DQS_DN<7>")
		)
		(pad "Y73" smd circle
			(at 33.049972 -21.420074 180)
			(size 0.450088 0.450088)
			(layers "F.Cu" "F.Mask" "F.Paste")
			(net "GND")
		)
		(pad "Y74" smd circle
			(at 33.990026 -21.420074 180)
			(size 0.450088 0.450088)
			(layers "F.Cu" "F.Mask" "F.Paste")
			(net "M_A_CPU0_SA_DQS_DN<2>")
		)
		(zone
			(layers "F.Cu" "B.Cu" "In1.Cu" "In2.Cu" "In3.Cu" "In4.Cu" "In5.Cu" "In6.Cu"
				"In7.Cu" "In8.Cu" "In9.Cu" "In10.Cu" "In11.Cu" "In12.Cu" "In13.Cu" "In14.Cu"
				"In15.Cu" "In16.Cu"
			)
			(hatch none 0.5)
			(connect_pads
				(clearance 0)
			)
			(min_thickness 0.25)
			(keepout
				(tracks not_allowed)
				(vias allowed)
				(pads allowed)
				(copperpour not_allowed)
				(footprints allowed)
			)
			(placement
				(enabled no)
				(sheetname "")
			)
			(fill
				(thermal_gap 0.5)
				(thermal_bridge_width 0.5)
				(island_removal_mode 0)
			)
			(polygon
				(pts
					(arc
						(start 320.28257 -258.880102)
						(mid 315.25337 -258.880102)
						(end 320.28257 -258.880102)
					)
				)
			)
		)
		(zone
			(layers "F.Cu" "B.Cu" "In1.Cu" "In2.Cu" "In3.Cu" "In4.Cu" "In5.Cu" "In6.Cu"
				"In7.Cu" "In8.Cu" "In9.Cu" "In10.Cu" "In11.Cu" "In12.Cu" "In13.Cu" "In14.Cu"
				"In15.Cu" "In16.Cu"
			)
			(hatch none 0.5)
			(connect_pads
				(clearance 0)
			)
			(min_thickness 0.25)
			(keepout
				(tracks not_allowed)
				(vias allowed)
				(pads allowed)
				(copperpour not_allowed)
				(footprints allowed)
			)
			(placement
				(enabled no)
				(sheetname "")
			)
			(fill
				(thermal_gap 0.5)
				(thermal_bridge_width 0.5)
				(island_removal_mode 0)
			)
			(polygon
				(pts
					(arc
						(start 331.78242 -304.780188)
						(mid 326.753728 -304.780188)
						(end 331.78242 -304.780188)
					)
				)
			)
		)
		(zone
			(layers "F.Cu" "B.Cu" "In1.Cu" "In2.Cu" "In3.Cu" "In4.Cu" "In5.Cu" "In6.Cu"
				"In7.Cu" "In8.Cu" "In9.Cu" "In10.Cu" "In11.Cu" "In12.Cu" "In13.Cu" "In14.Cu"
				"In15.Cu" "In16.Cu"
			)
			(hatch none 0.5)
			(connect_pads
				(clearance 0)
			)
			(min_thickness 0.25)
			(keepout
				(tracks not_allowed)
				(vias allowed)
				(pads allowed)
				(copperpour not_allowed)
				(footprints allowed)
			)
			(placement
				(enabled no)
				(sheetname "")
			)
			(fill
				(thermal_gap 0.5)
				(thermal_bridge_width 0.5)
				(island_removal_mode 0)
			)
			(polygon
				(pts
					(arc
						(start 331.78242 -212.980016)
						(mid 326.753728 -212.980016)
						(end 331.78242 -212.980016)
					)
				)
			)
		)
		(zone
			(layers "F.Cu" "B.Cu" "In1.Cu" "In2.Cu" "In3.Cu" "In4.Cu" "In5.Cu" "In6.Cu"
				"In7.Cu" "In8.Cu" "In9.Cu" "In10.Cu" "In11.Cu" "In12.Cu" "In13.Cu" "In14.Cu"
				"In15.Cu" "In16.Cu"
			)
			(hatch none 0.5)
			(connect_pads
				(clearance 0)
			)
			(min_thickness 0.25)
			(keepout
				(tracks not_allowed)
				(vias allowed)
				(pads allowed)
				(copperpour not_allowed)
				(footprints allowed)
			)
			(placement
				(enabled no)
				(sheetname "")
			)
			(fill
				(thermal_gap 0.5)
				(thermal_bridge_width 0.5)
				(island_removal_mode 0)
			)
			(polygon
				(pts
					(arc
						(start 392.982704 -304.780188)
						(mid 387.952996 -304.780188)
						(end 392.982704 -304.780188)
					)
				)
			)
		)
		(zone
			(layers "F.Cu" "B.Cu" "In1.Cu" "In2.Cu" "In3.Cu" "In4.Cu" "In5.Cu" "In6.Cu"
				"In7.Cu" "In8.Cu" "In9.Cu" "In10.Cu" "In11.Cu" "In12.Cu" "In13.Cu" "In14.Cu"
				"In15.Cu" "In16.Cu"
			)
			(hatch none 0.5)
			(connect_pads
				(clearance 0)
			)
			(min_thickness 0.25)
			(keepout
				(tracks not_allowed)
				(vias allowed)
				(pads allowed)
				(copperpour not_allowed)
				(footprints allowed)
			)
			(placement
				(enabled no)
				(sheetname "")
			)
			(fill
				(thermal_gap 0.5)
				(thermal_bridge_width 0.5)
				(island_removal_mode 0)
			)
			(polygon
				(pts
					(arc
						(start 392.982704 -212.980016)
						(mid 387.952996 -212.980016)
						(end 392.982704 -212.980016)
					)
				)
			)
		)
		(zone
			(layers "F.Cu" "B.Cu" "In1.Cu" "In2.Cu" "In3.Cu" "In4.Cu" "In5.Cu" "In6.Cu"
				"In7.Cu" "In8.Cu" "In9.Cu" "In10.Cu" "In11.Cu" "In12.Cu" "In13.Cu" "In14.Cu"
				"In15.Cu" "In16.Cu"
			)
			(hatch none 0.5)
			(connect_pads
				(clearance 0)
			)
			(min_thickness 0.25)
			(keepout
				(tracks not_allowed)
				(vias allowed)
				(pads allowed)
				(copperpour not_allowed)
				(footprints allowed)
			)
			(placement
				(enabled no)
				(sheetname "")
			)
			(fill
				(thermal_gap 0.5)
				(thermal_bridge_width 0.5)
				(island_removal_mode 0)
			)
			(polygon
				(pts
					(arc
						(start 404.482554 -258.880102)
						(mid 399.453354 -258.880102)
						(end 404.482554 -258.880102)
					)
				)
			)
		)
	)
	(footprint ""
		(layer "F.Cu")
		(at 277.650956 -428.556166 180)
		(property "Reference" "R4266"
			(at 0 0 180)
			(layer "F.SilkS")
			(hide yes)
			(effects
				(font
					(size 1.27 1.27)
				)
			)
		)
		(property "Value" ""
			(at 0 0 180)
			(layer "F.Fab")
			(effects
				(font
					(size 1.27 1.27)
				)
			)
		)
		(duplicate_pad_numbers_are_jumpers no)
		(fp_line
			(start 0.7874 0.4064)
			(end -0.7874 0.4064)
			(stroke
				(width 0.1524)
				(type default)
			)
			(layer "F.SilkS")
		)
		(fp_line
			(start 0.7874 -0.4064)
			(end 0.7874 0.4064)
			(stroke
				(width 0.1524)
				(type default)
			)
			(layer "F.SilkS")
		)
		(fp_line
			(start -0.7874 0.4064)
			(end -0.7874 -0.4064)
			(stroke
				(width 0.1524)
				(type default)
			)
			(layer "F.SilkS")
		)
		(fp_line
			(start -0.7874 -0.4064)
			(end 0.7874 -0.4064)
			(stroke
				(width 0.1524)
				(type default)
			)
			(layer "F.SilkS")
		)
		(fp_line
			(start 0.67945 0.3048)
			(end 0.120396 0.3048)
			(stroke
				(width 0.1)
				(type default)
			)
			(layer "F.Fab")
		)
		(fp_line
			(start 0.67945 -0.3048)
			(end 0.67945 0.3048)
			(stroke
				(width 0.1)
				(type default)
			)
			(layer "F.Fab")
		)
		(fp_line
			(start 0.12065 -0.2794)
			(end 0.12065 -0.3048)
			(stroke
				(width 0.1)
				(type default)
			)
			(layer "F.Fab")
		)
		(fp_line
			(start 0.12065 -0.3048)
			(end 0.67945 -0.3048)
			(stroke
				(width 0.1)
				(type default)
			)
			(layer "F.Fab")
		)
		(fp_line
			(start 0.120396 0.3048)
			(end 0.120396 0.2794)
			(stroke
				(width 0.1)
				(type default)
			)
			(layer "F.Fab")
		)
		(fp_line
			(start 0.120396 0.2794)
			(end -0.12065 0.2794)
			(stroke
				(width 0.1)
				(type default)
			)
			(layer "F.Fab")
		)
		(fp_line
			(start -0.12065 0.3048)
			(end -0.67945 0.3048)
			(stroke
				(width 0.1)
				(type default)
			)
			(layer "F.Fab")
		)
		(fp_line
			(start -0.12065 0.2794)
			(end -0.12065 0.3048)
			(stroke
				(width 0.1)
				(type default)
			)
			(layer "F.Fab")
		)
		(fp_line
			(start -0.12065 -0.2794)
			(end 0.12065 -0.2794)
			(stroke
				(width 0.1)
				(type default)
			)
			(layer "F.Fab")
		)
		(fp_line
			(start -0.12065 -0.305054)
			(end -0.12065 -0.2794)
			(stroke
				(width 0.1)
				(type default)
			)
			(layer "F.Fab")
		)
		(fp_line
			(start -0.67945 0.3048)
			(end -0.67945 -0.305054)
			(stroke
				(width 0.1)
				(type default)
			)
			(layer "F.Fab")
		)
		(fp_line
			(start -0.67945 -0.305054)
			(end -0.12065 -0.305054)
			(stroke
				(width 0.1)
				(type default)
			)
			(layer "F.Fab")
		)
		(pad "1" smd circle
			(at -0.40005 0 180)
			(size 0 0)
			(layers "F.Cu" "F.Mask" "F.Paste")
			(net "PWRGD_P3V3_AUX_PDB_BUF_R")
		)
		(pad "2" smd circle
			(at 0.40005 0 180)
			(size 0 0)
			(layers "F.Cu" "F.Mask" "F.Paste")
			(net "PWRGD_P3V3_AUX_PDB_BUF")
		)
	)
	(footprint ""
		(layer "F.Cu")
		(at 177.81016 -394.1318)
		(property "Reference" "R1499"
			(at 0 0 0)
			(layer "F.SilkS")
			(hide yes)
			(effects
				(font
					(size 1.27 1.27)
				)
			)
		)
		(property "Value" ""
			(at 0 0 0)
			(layer "F.Fab")
			(effects
				(font
					(size 1.27 1.27)
				)
			)
		)
		(duplicate_pad_numbers_are_jumpers no)
		(fp_line
			(start -0.32512 -0.175006)
			(end 0.32512 -0.175006)
			(stroke
				(width 0.1)
				(type default)
			)
			(layer "F.Fab")
		)
		(fp_line
			(start -0.32512 0.175006)
			(end -0.32512 -0.175006)
			(stroke
				(width 0.1)
				(type default)
			)
			(layer "F.Fab")
		)
		(fp_line
			(start 0.32512 -0.175006)
			(end 0.32512 0.175006)
			(stroke
				(width 0.1)
				(type default)
			)
			(layer "F.Fab")
		)
		(fp_line
			(start 0.32512 0.175006)
			(end -0.32512 0.175006)
			(stroke
				(width 0.1)
				(type default)
			)
			(layer "F.Fab")
		)
		(pad "1" smd rect
			(at -0.2667 0)
			(size 0.3048 0.381)
			(layers "F.Cu" "F.Mask" "F.Paste")
			(net "P1V8_CPU1_RT_1D")
		)
		(pad "2" smd rect
			(at 0.2667 0 180)
			(size 0.3048 0.381)
			(layers "F.Cu" "F.Mask" "F.Paste")
			(net "JTAG_TCK_RT_CPU1_P2")
		)
	)
	(footprint ""
		(layer "F.Cu")
		(at 438.558432 -27.275536 -90)
		(property "Reference" "PR3842"
			(at 0 0 270)
			(layer "F.SilkS")
			(hide yes)
			(effects
				(font
					(size 1.27 1.27)
				)
			)
		)
		(property "Value" ""
			(at 0 0 270)
			(layer "F.Fab")
			(effects
				(font
					(size 1.27 1.27)
				)
			)
		)
		(duplicate_pad_numbers_are_jumpers no)
		(fp_line
			(start -0.7874 0.4064)
			(end -0.7874 -0.4064)
			(stroke
				(width 0.1524)
				(type default)
			)
			(layer "F.SilkS")
		)
		(fp_line
			(start 0.7874 0.4064)
			(end -0.7874 0.4064)
			(stroke
				(width 0.1524)
				(type default)
			)
			(layer "F.SilkS")
		)
		(fp_line
			(start -0.7874 -0.4064)
			(end 0.7874 -0.4064)
			(stroke
				(width 0.1524)
				(type default)
			)
			(layer "F.SilkS")
		)
		(fp_line
			(start 0.7874 -0.4064)
			(end 0.7874 0.4064)
			(stroke
				(width 0.1524)
				(type default)
			)
			(layer "F.SilkS")
		)
		(fp_line
			(start -0.67945 0.3048)
			(end -0.67945 -0.305054)
			(stroke
				(width 0.1)
				(type default)
			)
			(layer "F.Fab")
		)
		(fp_line
			(start -0.12065 0.3048)
			(end -0.67945 0.3048)
			(stroke
				(width 0.1)
				(type default)
			)
			(layer "F.Fab")
		)
		(fp_line
			(start 0.120396 0.3048)
			(end 0.120396 0.2794)
			(stroke
				(width 0.1)
				(type default)
			)
			(layer "F.Fab")
		)
		(fp_line
			(start 0.67945 0.3048)
			(end 0.120396 0.3048)
			(stroke
				(width 0.1)
				(type default)
			)
			(layer "F.Fab")
		)
		(fp_line
			(start -0.12065 0.2794)
			(end -0.12065 0.3048)
			(stroke
				(width 0.1)
				(type default)
			)
			(layer "F.Fab")
		)
		(fp_line
			(start 0.120396 0.2794)
			(end -0.12065 0.2794)
			(stroke
				(width 0.1)
				(type default)
			)
			(layer "F.Fab")
		)
		(fp_line
			(start -0.12065 -0.2794)
			(end 0.12065 -0.2794)
			(stroke
				(width 0.1)
				(type default)
			)
			(layer "F.Fab")
		)
		(fp_line
			(start 0.12065 -0.2794)
			(end 0.12065 -0.3048)
			(stroke
				(width 0.1)
				(type default)
			)
			(layer "F.Fab")
		)
		(fp_line
			(start 0.12065 -0.3048)
			(end 0.67945 -0.3048)
			(stroke
				(width 0.1)
				(type default)
			)
			(layer "F.Fab")
		)
		(fp_line
			(start 0.67945 -0.3048)
			(end 0.67945 0.3048)
			(stroke
				(width 0.1)
				(type default)
			)
			(layer "F.Fab")
		)
		(fp_line
			(start -0.67945 -0.305054)
			(end -0.12065 -0.305054)
			(stroke
				(width 0.1)
				(type default)
			)
			(layer "F.Fab")
		)
		(fp_line
			(start -0.12065 -0.305054)
			(end -0.12065 -0.2794)
			(stroke
				(width 0.1)
				(type default)
			)
			(layer "F.Fab")
		)
		(pad "1" smd circle
			(at -0.40005 0 270)
			(size 0 0)
			(layers "F.Cu" "F.Mask" "F.Paste")
			(net "P12V_OCP_OV_FB_1")
		)
		(pad "2" smd circle
			(at 0.40005 0 270)
			(size 0 0)
			(layers "F.Cu" "F.Mask" "F.Paste")
			(net "GND")
		)
	)
	(footprint ""
		(layer "F.Cu")
		(at 127.381 -108.712 90)
		(property "Reference" "C8017"
			(at 0 0 90)
			(layer "F.SilkS")
			(hide yes)
			(effects
				(font
					(size 1.27 1.27)
				)
			)
		)
		(property "Value" ""
			(at 0 0 90)
			(layer "F.Fab")
			(effects
				(font
					(size 1.27 1.27)
				)
			)
		)
		(duplicate_pad_numbers_are_jumpers no)
		(fp_line
			(start 0.7874 -0.4064)
			(end 0.7874 0.4064)
			(stroke
				(width 0.1524)
				(type default)
			)
			(layer "F.SilkS")
		)
		(fp_line
			(start -0.7874 -0.4064)
			(end 0.7874 -0.4064)
			(stroke
				(width 0.1524)
				(type default)
			)
			(layer "F.SilkS")
		)
		(fp_line
			(start 0.7874 0.4064)
			(end -0.7874 0.4064)
			(stroke
				(width 0.1524)
				(type default)
			)
			(layer "F.SilkS")
		)
		(fp_line
			(start -0.7874 0.4064)
			(end -0.7874 -0.4064)
			(stroke
				(width 0.1524)
				(type default)
			)
			(layer "F.SilkS")
		)
		(fp_line
			(start -0.12065 -0.305054)
			(end -0.12065 -0.2794)
			(stroke
				(width 0.1)
				(type default)
			)
			(layer "F.Fab")
		)
		(fp_line
			(start -0.67945 -0.305054)
			(end -0.12065 -0.305054)
			(stroke
				(width 0.1)
				(type default)
			)
			(layer "F.Fab")
		)
		(fp_line
			(start 0.67945 -0.3048)
			(end 0.67945 0.3048)
			(stroke
				(width 0.1)
				(type default)
			)
			(layer "F.Fab")
		)
		(fp_line
			(start 0.12065 -0.3048)
			(end 0.67945 -0.3048)
			(stroke
				(width 0.1)
				(type default)
			)
			(layer "F.Fab")
		)
		(fp_line
			(start 0.12065 -0.2794)
			(end 0.12065 -0.3048)
			(stroke
				(width 0.1)
				(type default)
			)
			(layer "F.Fab")
		)
		(fp_line
			(start -0.12065 -0.2794)
			(end 0.12065 -0.2794)
			(stroke
				(width 0.1)
				(type default)
			)
			(layer "F.Fab")
		)
		(fp_line
			(start 0.120396 0.2794)
			(end -0.12065 0.2794)
			(stroke
				(width 0.1)
				(type default)
			)
			(layer "F.Fab")
		)
		(fp_line
			(start -0.12065 0.2794)
			(end -0.12065 0.3048)
			(stroke
				(width 0.1)
				(type default)
			)
			(layer "F.Fab")
		)
		(fp_line
			(start 0.67945 0.3048)
			(end 0.120396 0.3048)
			(stroke
				(width 0.1)
				(type default)
			)
			(layer "F.Fab")
		)
		(fp_line
			(start 0.120396 0.3048)
			(end 0.120396 0.2794)
			(stroke
				(width 0.1)
				(type default)
			)
			(layer "F.Fab")
		)
		(fp_line
			(start -0.12065 0.3048)
			(end -0.67945 0.3048)
			(stroke
				(width 0.1)
				(type default)
			)
			(layer "F.Fab")
		)
		(fp_line
			(start -0.67945 0.3048)
			(end -0.67945 -0.305054)
			(stroke
				(width 0.1)
				(type default)
			)
			(layer "F.Fab")
		)
		(pad "1" smd circle
			(at -0.40005 0 90)
			(size 0 0)
			(layers "F.Cu" "F.Mask" "F.Paste")
			(net "UV_ADR_P2V5_COMP")
		)
		(pad "2" smd circle
			(at 0.40005 0 90)
			(size 0 0)
			(layers "F.Cu" "F.Mask" "F.Paste")
			(net "GND")
		)
	)
	(footprint ""
		(layer "F.Cu")
		(at 185.806842 -24.170132)
		(property "Reference" "PC2234"
			(at 0 0 0)
			(layer "F.SilkS")
			(hide yes)
			(effects
				(font
					(size 1.27 1.27)
				)
			)
		)
		(property "Value" ""
			(at 0 0 0)
			(layer "F.Fab")
			(effects
				(font
					(size 1.27 1.27)
				)
			)
		)
		(duplicate_pad_numbers_are_jumpers no)
		(fp_line
			(start -0.7874 -0.4064)
			(end 0.7874 -0.4064)
			(stroke
				(width 0.1524)
				(type default)
			)
			(layer "F.SilkS")
		)
		(fp_line
			(start -0.7874 0.4064)
			(end -0.7874 -0.4064)
			(stroke
				(width 0.1524)
				(type default)
			)
			(layer "F.SilkS")
		)
		(fp_line
			(start 0.7874 -0.4064)
			(end 0.7874 0.4064)
			(stroke
				(width 0.1524)
				(type default)
			)
			(layer "F.SilkS")
		)
		(fp_line
			(start 0.7874 0.4064)
			(end -0.7874 0.4064)
			(stroke
				(width 0.1524)
				(type default)
			)
			(layer "F.SilkS")
		)
		(fp_line
			(start -0.67945 -0.305054)
			(end -0.12065 -0.305054)
			(stroke
				(width 0.1)
				(type default)
			)
			(layer "F.Fab")
		)
		(fp_line
			(start -0.67945 0.3048)
			(end -0.67945 -0.305054)
			(stroke
				(width 0.1)
				(type default)
			)
			(layer "F.Fab")
		)
		(fp_line
			(start -0.12065 -0.305054)
			(end -0.12065 -0.2794)
			(stroke
				(width 0.1)
				(type default)
			)
			(layer "F.Fab")
		)
		(fp_line
			(start -0.12065 -0.2794)
			(end 0.12065 -0.2794)
			(stroke
				(width 0.1)
				(type default)
			)
			(layer "F.Fab")
		)
		(fp_line
			(start -0.12065 0.2794)
			(end -0.12065 0.3048)
			(stroke
				(width 0.1)
				(type default)
			)
			(layer "F.Fab")
		)
		(fp_line
			(start -0.12065 0.3048)
			(end -0.67945 0.3048)
			(stroke
				(width 0.1)
				(type default)
			)
			(layer "F.Fab")
		)
		(fp_line
			(start 0.120396 0.2794)
			(end -0.12065 0.2794)
			(stroke
				(width 0.1)
				(type default)
			)
			(layer "F.Fab")
		)
		(fp_line
			(start 0.120396 0.3048)
			(end 0.120396 0.2794)
			(stroke
				(width 0.1)
				(type default)
			)
			(layer "F.Fab")
		)
		(fp_line
			(start 0.12065 -0.3048)
			(end 0.67945 -0.3048)
			(stroke
				(width 0.1)
				(type default)
			)
			(layer "F.Fab")
		)
		(fp_line
			(start 0.12065 -0.2794)
			(end 0.12065 -0.3048)
			(stroke
				(width 0.1)
				(type default)
			)
			(layer "F.Fab")
		)
		(fp_line
			(start 0.67945 -0.3048)
			(end 0.67945 0.3048)
			(stroke
				(width 0.1)
				(type default)
			)
			(layer "F.Fab")
		)
		(fp_line
			(start 0.67945 0.3048)
			(end 0.120396 0.3048)
			(stroke
				(width 0.1)
				(type default)
			)
			(layer "F.Fab")
		)
		(pad "1" smd circle
			(at -0.40005 0)
			(size 0 0)
			(layers "F.Cu" "F.Mask" "F.Paste")
			(net "GND")
		)
		(pad "2" smd circle
			(at 0.40005 0)
			(size 0 0)
			(layers "F.Cu" "F.Mask" "F.Paste")
			(net "P12V_SCM_REG")
		)
	)
	(footprint ""
		(layer "F.Cu")
		(at 200.952608 -114.641376)
		(property "Reference" "R4172"
			(at 0 0 0)
			(layer "F.SilkS")
			(hide yes)
			(effects
				(font
					(size 1.27 1.27)
				)
			)
		)
		(property "Value" ""
			(at 0 0 0)
			(layer "F.Fab")
			(effects
				(font
					(size 1.27 1.27)
				)
			)
		)
		(duplicate_pad_numbers_are_jumpers no)
		(fp_line
			(start -0.7874 -0.4064)
			(end 0.7874 -0.4064)
			(stroke
				(width 0.1524)
				(type default)
			)
			(layer "F.SilkS")
		)
		(fp_line
			(start -0.7874 0.4064)
			(end -0.7874 -0.4064)
			(stroke
				(width 0.1524)
				(type default)
			)
			(layer "F.SilkS")
		)
		(fp_line
			(start 0.7874 -0.4064)
			(end 0.7874 0.4064)
			(stroke
				(width 0.1524)
				(type default)
			)
			(layer "F.SilkS")
		)
		(fp_line
			(start 0.7874 0.4064)
			(end -0.7874 0.4064)
			(stroke
				(width 0.1524)
				(type default)
			)
			(layer "F.SilkS")
		)
		(fp_line
			(start -0.67945 -0.305054)
			(end -0.12065 -0.305054)
			(stroke
				(width 0.1)
				(type default)
			)
			(layer "F.Fab")
		)
		(fp_line
			(start -0.67945 0.3048)
			(end -0.67945 -0.305054)
			(stroke
				(width 0.1)
				(type default)
			)
			(layer "F.Fab")
		)
		(fp_line
			(start -0.12065 -0.305054)
			(end -0.12065 -0.2794)
			(stroke
				(width 0.1)
				(type default)
			)
			(layer "F.Fab")
		)
		(fp_line
			(start -0.12065 -0.2794)
			(end 0.12065 -0.2794)
			(stroke
				(width 0.1)
				(type default)
			)
			(layer "F.Fab")
		)
		(fp_line
			(start -0.12065 0.2794)
			(end -0.12065 0.3048)
			(stroke
				(width 0.1)
				(type default)
			)
			(layer "F.Fab")
		)
		(fp_line
			(start -0.12065 0.3048)
			(end -0.67945 0.3048)
			(stroke
				(width 0.1)
				(type default)
			)
			(layer "F.Fab")
		)
		(fp_line
			(start 0.120396 0.2794)
			(end -0.12065 0.2794)
			(stroke
				(width 0.1)
				(type default)
			)
			(layer "F.Fab")
		)
		(fp_line
			(start 0.120396 0.3048)
			(end 0.120396 0.2794)
			(stroke
				(width 0.1)
				(type default)
			)
			(layer "F.Fab")
		)
		(fp_line
			(start 0.12065 -0.3048)
			(end 0.67945 -0.3048)
			(stroke
				(width 0.1)
				(type default)
			)
			(layer "F.Fab")
		)
		(fp_line
			(start 0.12065 -0.2794)
			(end 0.12065 -0.3048)
			(stroke
				(width 0.1)
				(type default)
			)
			(layer "F.Fab")
		)
		(fp_line
			(start 0.67945 -0.3048)
			(end 0.67945 0.3048)
			(stroke
				(width 0.1)
				(type default)
			)
			(layer "F.Fab")
		)
		(fp_line
			(start 0.67945 0.3048)
			(end 0.120396 0.3048)
			(stroke
				(width 0.1)
				(type default)
			)
			(layer "F.Fab")
		)
		(pad "1" smd circle
			(at -0.40005 0)
			(size 0 0)
			(layers "F.Cu" "F.Mask" "F.Paste")
			(net "GPU_3V3IO_RSVD4_ISO_R")
		)
		(pad "2" smd circle
			(at 0.40005 0)
			(size 0 0)
			(layers "F.Cu" "F.Mask" "F.Paste")
			(net "GPU_3V3IO_RSVD4_ISO")
		)
	)
	(footprint ""
		(layer "F.Cu")
		(at 303.348898 -15.62481)
		(property "Reference" "R4205"
			(at 0 0 0)
			(layer "F.SilkS")
			(hide yes)
			(effects
				(font
					(size 1.27 1.27)
				)
			)
		)
		(property "Value" ""
			(at 0 0 0)
			(layer "F.Fab")
			(effects
				(font
					(size 1.27 1.27)
				)
			)
		)
		(duplicate_pad_numbers_are_jumpers no)
		(fp_line
			(start -0.7874 -0.4064)
			(end 0.7874 -0.4064)
			(stroke
				(width 0.1524)
				(type default)
			)
			(layer "F.SilkS")
		)
		(fp_line
			(start -0.7874 0.4064)
			(end -0.7874 -0.4064)
			(stroke
				(width 0.1524)
				(type default)
			)
			(layer "F.SilkS")
		)
		(fp_line
			(start 0.7874 -0.4064)
			(end 0.7874 0.4064)
			(stroke
				(width 0.1524)
				(type default)
			)
			(layer "F.SilkS")
		)
		(fp_line
			(start 0.7874 0.4064)
			(end -0.7874 0.4064)
			(stroke
				(width 0.1524)
				(type default)
			)
			(layer "F.SilkS")
		)
		(fp_line
			(start -0.67945 -0.305054)
			(end -0.12065 -0.305054)
			(stroke
				(width 0.1)
				(type default)
			)
			(layer "F.Fab")
		)
		(fp_line
			(start -0.67945 0.3048)
			(end -0.67945 -0.305054)
			(stroke
				(width 0.1)
				(type default)
			)
			(layer "F.Fab")
		)
		(fp_line
			(start -0.12065 -0.305054)
			(end -0.12065 -0.2794)
			(stroke
				(width 0.1)
				(type default)
			)
			(layer "F.Fab")
		)
		(fp_line
			(start -0.12065 -0.2794)
			(end 0.12065 -0.2794)
			(stroke
				(width 0.1)
				(type default)
			)
			(layer "F.Fab")
		)
		(fp_line
			(start -0.12065 0.2794)
			(end -0.12065 0.3048)
			(stroke
				(width 0.1)
				(type default)
			)
			(layer "F.Fab")
		)
		(fp_line
			(start -0.12065 0.3048)
			(end -0.67945 0.3048)
			(stroke
				(width 0.1)
				(type default)
			)
			(layer "F.Fab")
		)
		(fp_line
			(start 0.120396 0.2794)
			(end -0.12065 0.2794)
			(stroke
				(width 0.1)
				(type default)
			)
			(layer "F.Fab")
		)
		(fp_line
			(start 0.120396 0.3048)
			(end 0.120396 0.2794)
			(stroke
				(width 0.1)
				(type default)
			)
			(layer "F.Fab")
		)
		(fp_line
			(start 0.12065 -0.3048)
			(end 0.67945 -0.3048)
			(stroke
				(width 0.1)
				(type default)
			)
			(layer "F.Fab")
		)
		(fp_line
			(start 0.12065 -0.2794)
			(end 0.12065 -0.3048)
			(stroke
				(width 0.1)
				(type default)
			)
			(layer "F.Fab")
		)
		(fp_line
			(start 0.67945 -0.3048)
			(end 0.67945 0.3048)
			(stroke
				(width 0.1)
				(type default)
			)
			(layer "F.Fab")
		)
		(fp_line
			(start 0.67945 0.3048)
			(end 0.120396 0.3048)
			(stroke
				(width 0.1)
				(type default)
			)
			(layer "F.Fab")
		)
		(pad "1" smd circle
			(at -0.40005 0)
			(size 0 0)
			(layers "F.Cu" "F.Mask" "F.Paste")
			(net "U271_1_ADD0")
		)
		(pad "2" smd circle
			(at 0.40005 0)
			(size 0 0)
			(layers "F.Cu" "F.Mask" "F.Paste")
			(net "GND")
		)
	)
	(footprint ""
		(layer "F.Cu")
		(at 325.740776 -384.449828)
		(property "Reference" "C905"
			(at 0 0 0)
			(layer "F.SilkS")
			(hide yes)
			(effects
				(font
					(size 1.27 1.27)
				)
			)
		)
		(property "Value" ""
			(at 0 0 0)
			(layer "F.Fab")
			(effects
				(font
					(size 1.27 1.27)
				)
			)
		)
		(duplicate_pad_numbers_are_jumpers no)
		(fp_line
			(start -0.299974 -0.150114)
			(end 0.299974 -0.150114)
			(stroke
				(width 0.1)
				(type default)
			)
			(layer "F.Fab")
		)
		(fp_line
			(start -0.299974 0.150114)
			(end -0.299974 -0.150114)
			(stroke
				(width 0.1)
				(type default)
			)
			(layer "F.Fab")
		)
		(fp_line
			(start 0.299974 -0.150114)
			(end 0.299974 0.150114)
			(stroke
				(width 0.1)
				(type default)
			)
			(layer "F.Fab")
		)
		(fp_line
			(start 0.299974 0.150114)
			(end -0.299974 0.150114)
			(stroke
				(width 0.1)
				(type default)
			)
			(layer "F.Fab")
		)
		(pad "1" smd rect
			(at -0.2667 0)
			(size 0.3048 0.381)
			(layers "F.Cu" "F.Mask" "F.Paste")
			(net "P5E_CPU0_P0_TX_C_DP<14>")
		)
		(pad "2" smd rect
			(at 0.2667 0)
			(size 0.3048 0.381)
			(layers "F.Cu" "F.Mask" "F.Paste")
			(net "P5E_CPU0_P0_TX_DP<14>")
		)
	)
	(footprint ""
		(layer "F.Cu")
		(at 191.41694 -401.325842 180)
		(property "Reference" "PR3928"
			(at 0 0 180)
			(layer "F.SilkS")
			(hide yes)
			(effects
				(font
					(size 1.27 1.27)
				)
			)
		)
		(property "Value" ""
			(at 0 0 180)
			(layer "F.Fab")
			(effects
				(font
					(size 1.27 1.27)
				)
			)
		)
		(duplicate_pad_numbers_are_jumpers no)
		(fp_line
			(start 0.7874 0.4064)
			(end -0.7874 0.4064)
			(stroke
				(width 0.1524)
				(type default)
			)
			(layer "F.SilkS")
		)
		(fp_line
			(start 0.7874 -0.4064)
			(end 0.7874 0.4064)
			(stroke
				(width 0.1524)
				(type default)
			)
			(layer "F.SilkS")
		)
		(fp_line
			(start -0.7874 0.4064)
			(end -0.7874 -0.4064)
			(stroke
				(width 0.1524)
				(type default)
			)
			(layer "F.SilkS")
		)
		(fp_line
			(start -0.7874 -0.4064)
			(end 0.7874 -0.4064)
			(stroke
				(width 0.1524)
				(type default)
			)
			(layer "F.SilkS")
		)
		(fp_line
			(start 0.67945 0.3048)
			(end 0.120396 0.3048)
			(stroke
				(width 0.1)
				(type default)
			)
			(layer "F.Fab")
		)
		(fp_line
			(start 0.67945 -0.3048)
			(end 0.67945 0.3048)
			(stroke
				(width 0.1)
				(type default)
			)
			(layer "F.Fab")
		)
		(fp_line
			(start 0.12065 -0.2794)
			(end 0.12065 -0.3048)
			(stroke
				(width 0.1)
				(type default)
			)
			(layer "F.Fab")
		)
		(fp_line
			(start 0.12065 -0.3048)
			(end 0.67945 -0.3048)
			(stroke
				(width 0.1)
				(type default)
			)
			(layer "F.Fab")
		)
		(fp_line
			(start 0.120396 0.3048)
			(end 0.120396 0.2794)
			(stroke
				(width 0.1)
				(type default)
			)
			(layer "F.Fab")
		)
		(fp_line
			(start 0.120396 0.2794)
			(end -0.12065 0.2794)
			(stroke
				(width 0.1)
				(type default)
			)
			(layer "F.Fab")
		)
		(fp_line
			(start -0.12065 0.3048)
			(end -0.67945 0.3048)
			(stroke
				(width 0.1)
				(type default)
			)
			(layer "F.Fab")
		)
		(fp_line
			(start -0.12065 0.2794)
			(end -0.12065 0.3048)
			(stroke
				(width 0.1)
				(type default)
			)
			(layer "F.Fab")
		)
		(fp_line
			(start -0.12065 -0.2794)
			(end 0.12065 -0.2794)
			(stroke
				(width 0.1)
				(type default)
			)
			(layer "F.Fab")
		)
		(fp_line
			(start -0.12065 -0.305054)
			(end -0.12065 -0.2794)
			(stroke
				(width 0.1)
				(type default)
			)
			(layer "F.Fab")
		)
		(fp_line
			(start -0.67945 0.3048)
			(end -0.67945 -0.305054)
			(stroke
				(width 0.1)
				(type default)
			)
			(layer "F.Fab")
		)
		(fp_line
			(start -0.67945 -0.305054)
			(end -0.12065 -0.305054)
			(stroke
				(width 0.1)
				(type default)
			)
			(layer "F.Fab")
		)
		(pad "1" smd circle
			(at -0.40005 0 180)
			(size 0 0)
			(layers "F.Cu" "F.Mask" "F.Paste")
			(net "HSC_ON")
		)
		(pad "2" smd circle
			(at 0.40005 0 180)
			(size 0 0)
			(layers "F.Cu" "F.Mask" "F.Paste")
			(net "HSC_ON_R")
		)
	)
	(footprint ""
		(layer "F.Cu")
		(at 330.057506 -23.574248 180)
		(property "Reference" "JP12"
			(at 2.044446 -1.387094 90)
			(unlocked yes)
			(layer "F.SilkS")
			(effects
				(font
					(size 0.7874 0.5842)
					(thickness 0.1524)
				)
				(justify left)
			)
		)
		(property "Value" ""
			(at 0 0 180)
			(layer "F.Fab")
			(effects
				(font
					(size 1.27 1.27)
				)
			)
		)
		(duplicate_pad_numbers_are_jumpers no)
		(fp_line
			(start 1.249934 6.400038)
			(end -1.249934 6.400038)
			(stroke
				(width 0.1524)
				(type default)
			)
			(layer "F.SilkS")
		)
		(fp_line
			(start 1.249934 -1.320038)
			(end 1.249934 6.400038)
			(stroke
				(width 0.1524)
				(type default)
			)
			(layer "F.SilkS")
		)
		(fp_line
			(start -1.249934 6.400038)
			(end -1.249934 -1.320038)
			(stroke
				(width 0.1524)
				(type default)
			)
			(layer "F.SilkS")
		)
		(fp_line
			(start -1.249934 -1.320038)
			(end 1.249934 -1.320038)
			(stroke
				(width 0.1524)
				(type default)
			)
			(layer "F.SilkS")
		)
		(fp_poly
			(pts
				(xy -2.382266 0.655828) (xy -1.465072 0.410972) (xy -1.819402 1.291844)
			)
			(stroke
				(width 0)
				(type default)
			)
			(fill yes)
			(layer "F.SilkS")
		)
		(fp_line
			(start 1.249934 6.400038)
			(end -1.249934 6.400038)
			(stroke
				(width 0.1)
				(type default)
			)
			(layer "F.Fab")
		)
		(fp_line
			(start 1.249934 -1.320038)
			(end 1.249934 6.400038)
			(stroke
				(width 0.1)
				(type default)
			)
			(layer "F.Fab")
		)
		(fp_line
			(start -1.249934 6.400038)
			(end -1.249934 -1.320038)
			(stroke
				(width 0.1)
				(type default)
			)
			(layer "F.Fab")
		)
		(fp_line
			(start -1.249934 -1.320038)
			(end 1.249934 -1.320038)
			(stroke
				(width 0.1)
				(type default)
			)
			(layer "F.Fab")
		)
		(fp_poly
			(pts
				(xy -2.5654 -0.556514) (xy -1.452372 0) (xy -2.5654 0.556514)
			)
			(stroke
				(width 0)
				(type default)
			)
			(fill yes)
			(layer "F.Fab")
		)
		(fp_text user "3"
			(at -1.778 5.13207 180)
			(unlocked yes)
			(layer "F.SilkS")
			(effects
				(font
					(size 0.7874 0.5842)
					(thickness 0.1524)
				)
			)
		)
		(fp_text user "1"
			(at -1.143 0.02667 180)
			(unlocked yes)
			(layer "B.SilkS")
			(effects
				(font
					(size 0.7874 0.5842)
					(thickness 0.1524)
				)
				(justify mirror)
			)
		)
		(fp_text user "3"
			(at -1.1557 5.18287 180)
			(unlocked yes)
			(layer "B.SilkS")
			(effects
				(font
					(size 0.7874 0.5842)
					(thickness 0.1524)
				)
				(justify mirror)
			)
		)
		(fp_text user "1"
			(at -1.143 0.02667 180)
			(unlocked yes)
			(layer "B.Fab")
			(effects
				(font
					(size 0.7874 0.5842)
					(thickness 0.1524)
				)
				(justify mirror)
			)
		)
		(fp_text user "3"
			(at -1.1557 5.18287 180)
			(unlocked yes)
			(layer "B.Fab")
			(effects
				(font
					(size 0.7874 0.5842)
					(thickness 0.1524)
				)
				(justify mirror)
			)
		)
		(fp_text user "3"
			(at -1.778 5.13207 180)
			(unlocked yes)
			(layer "F.Fab")
			(effects
				(font
					(size 0.7874 0.5842)
					(thickness 0.1524)
				)
			)
		)
		(pad "1" thru_hole rect
			(at 0 0 180)
			(size 1.5494 1.5494)
			(drill 1.0414)
			(layers "*.Cu" "*.Mask")
			(remove_unused_layers no)
			(net "P1V5_BAT_OUT_R")
			(clearance 0)
			(padstack
				(mode front_inner_back)
				(layer "Inner"
					(shape circle)
					(size 1.5494 1.5494)
					(clearance 0)
				)
				(layer "B.Cu"
					(shape rect)
					(size 1.5494 1.5494)
					(clearance 0)
				)
			)
		)
		(pad "2" thru_hole circle
			(at 0 2.54 180)
			(size 1.5494 1.5494)
			(drill 1.0414)
			(layers "*.Cu" "*.Mask")
			(remove_unused_layers no)
			(net "P1V5_BAT")
			(clearance 0)
		)
		(pad "3" thru_hole circle
			(at 0 5.08 180)
			(size 1.5494 1.5494)
			(drill 1.0414)
			(layers "*.Cu" "*.Mask")
			(remove_unused_layers no)
			(net "GND")
			(clearance 0)
		)
	)
	(footprint ""
		(layer "F.Cu")
		(at 452.153274 -50.266346 180)
		(property "Reference" "PC568"
			(at 0 0 180)
			(layer "F.SilkS")
			(hide yes)
			(effects
				(font
					(size 1.27 1.27)
				)
			)
		)
		(property "Value" ""
			(at 0 0 180)
			(layer "F.Fab")
			(effects
				(font
					(size 1.27 1.27)
				)
			)
		)
		(duplicate_pad_numbers_are_jumpers no)
		(fp_line
			(start 0.7874 0.4064)
			(end -0.7874 0.4064)
			(stroke
				(width 0.1524)
				(type default)
			)
			(layer "F.SilkS")
		)
		(fp_line
			(start 0.7874 -0.4064)
			(end 0.7874 0.4064)
			(stroke
				(width 0.1524)
				(type default)
			)
			(layer "F.SilkS")
		)
		(fp_line
			(start -0.7874 0.4064)
			(end -0.7874 -0.4064)
			(stroke
				(width 0.1524)
				(type default)
			)
			(layer "F.SilkS")
		)
		(fp_line
			(start -0.7874 -0.4064)
			(end 0.7874 -0.4064)
			(stroke
				(width 0.1524)
				(type default)
			)
			(layer "F.SilkS")
		)
		(fp_line
			(start 0.67945 0.3048)
			(end 0.120396 0.3048)
			(stroke
				(width 0.1)
				(type default)
			)
			(layer "F.Fab")
		)
		(fp_line
			(start 0.67945 -0.3048)
			(end 0.67945 0.3048)
			(stroke
				(width 0.1)
				(type default)
			)
			(layer "F.Fab")
		)
		(fp_line
			(start 0.12065 -0.2794)
			(end 0.12065 -0.3048)
			(stroke
				(width 0.1)
				(type default)
			)
			(layer "F.Fab")
		)
		(fp_line
			(start 0.12065 -0.3048)
			(end 0.67945 -0.3048)
			(stroke
				(width 0.1)
				(type default)
			)
			(layer "F.Fab")
		)
		(fp_line
			(start 0.120396 0.3048)
			(end 0.120396 0.2794)
			(stroke
				(width 0.1)
				(type default)
			)
			(layer "F.Fab")
		)
		(fp_line
			(start 0.120396 0.2794)
			(end -0.12065 0.2794)
			(stroke
				(width 0.1)
				(type default)
			)
			(layer "F.Fab")
		)
		(fp_line
			(start -0.12065 0.3048)
			(end -0.67945 0.3048)
			(stroke
				(width 0.1)
				(type default)
			)
			(layer "F.Fab")
		)
		(fp_line
			(start -0.12065 0.2794)
			(end -0.12065 0.3048)
			(stroke
				(width 0.1)
				(type default)
			)
			(layer "F.Fab")
		)
		(fp_line
			(start -0.12065 -0.2794)
			(end 0.12065 -0.2794)
			(stroke
				(width 0.1)
				(type default)
			)
			(layer "F.Fab")
		)
		(fp_line
			(start -0.12065 -0.305054)
			(end -0.12065 -0.2794)
			(stroke
				(width 0.1)
				(type default)
			)
			(layer "F.Fab")
		)
		(fp_line
			(start -0.67945 0.3048)
			(end -0.67945 -0.305054)
			(stroke
				(width 0.1)
				(type default)
			)
			(layer "F.Fab")
		)
		(fp_line
			(start -0.67945 -0.305054)
			(end -0.12065 -0.305054)
			(stroke
				(width 0.1)
				(type default)
			)
			(layer "F.Fab")
		)
		(pad "1" smd circle
			(at -0.40005 0 180)
			(size 0 0)
			(layers "F.Cu" "F.Mask" "F.Paste")
			(net "SW_P3V3_AUX_BOOTR")
		)
		(pad "2" smd circle
			(at 0.40005 0 180)
			(size 0 0)
			(layers "F.Cu" "F.Mask" "F.Paste")
			(net "SW_P3V3_AUX_BOOT_R")
		)
	)
	(footprint ""
		(layer "F.Cu")
		(at 151.257 -125.349)
		(property "Reference" "R8087"
			(at 0 0 0)
			(layer "F.SilkS")
			(hide yes)
			(effects
				(font
					(size 1.27 1.27)
				)
			)
		)
		(property "Value" ""
			(at 0 0 0)
			(layer "F.Fab")
			(effects
				(font
					(size 1.27 1.27)
				)
			)
		)
		(duplicate_pad_numbers_are_jumpers no)
		(fp_line
			(start -0.7874 -0.4064)
			(end 0.7874 -0.4064)
			(stroke
				(width 0.1524)
				(type default)
			)
			(layer "F.SilkS")
		)
		(fp_line
			(start -0.7874 0.4064)
			(end -0.7874 -0.4064)
			(stroke
				(width 0.1524)
				(type default)
			)
			(layer "F.SilkS")
		)
		(fp_line
			(start 0.7874 -0.4064)
			(end 0.7874 0.4064)
			(stroke
				(width 0.1524)
				(type default)
			)
			(layer "F.SilkS")
		)
		(fp_line
			(start 0.7874 0.4064)
			(end -0.7874 0.4064)
			(stroke
				(width 0.1524)
				(type default)
			)
			(layer "F.SilkS")
		)
		(fp_line
			(start -0.67945 -0.305054)
			(end -0.12065 -0.305054)
			(stroke
				(width 0.1)
				(type default)
			)
			(layer "F.Fab")
		)
		(fp_line
			(start -0.67945 0.3048)
			(end -0.67945 -0.305054)
			(stroke
				(width 0.1)
				(type default)
			)
			(layer "F.Fab")
		)
		(fp_line
			(start -0.12065 -0.305054)
			(end -0.12065 -0.2794)
			(stroke
				(width 0.1)
				(type default)
			)
			(layer "F.Fab")
		)
		(fp_line
			(start -0.12065 -0.2794)
			(end 0.12065 -0.2794)
			(stroke
				(width 0.1)
				(type default)
			)
			(layer "F.Fab")
		)
		(fp_line
			(start -0.12065 0.2794)
			(end -0.12065 0.3048)
			(stroke
				(width 0.1)
				(type default)
			)
			(layer "F.Fab")
		)
		(fp_line
			(start -0.12065 0.3048)
			(end -0.67945 0.3048)
			(stroke
				(width 0.1)
				(type default)
			)
			(layer "F.Fab")
		)
		(fp_line
			(start 0.120396 0.2794)
			(end -0.12065 0.2794)
			(stroke
				(width 0.1)
				(type default)
			)
			(layer "F.Fab")
		)
		(fp_line
			(start 0.120396 0.3048)
			(end 0.120396 0.2794)
			(stroke
				(width 0.1)
				(type default)
			)
			(layer "F.Fab")
		)
		(fp_line
			(start 0.12065 -0.3048)
			(end 0.67945 -0.3048)
			(stroke
				(width 0.1)
				(type default)
			)
			(layer "F.Fab")
		)
		(fp_line
			(start 0.12065 -0.2794)
			(end 0.12065 -0.3048)
			(stroke
				(width 0.1)
				(type default)
			)
			(layer "F.Fab")
		)
		(fp_line
			(start 0.67945 -0.3048)
			(end 0.67945 0.3048)
			(stroke
				(width 0.1)
				(type default)
			)
			(layer "F.Fab")
		)
		(fp_line
			(start 0.67945 0.3048)
			(end 0.120396 0.3048)
			(stroke
				(width 0.1)
				(type default)
			)
			(layer "F.Fab")
		)
		(pad "1" smd circle
			(at -0.40005 0)
			(size 0 0)
			(layers "F.Cu" "F.Mask" "F.Paste")
			(net "PWRGD_CHAF_CPU1_R1")
		)
		(pad "2" smd circle
			(at 0.40005 0)
			(size 0 0)
			(layers "F.Cu" "F.Mask" "F.Paste")
			(net "PWRGD_CHAF_CPU1_R2")
		)
	)
	(footprint ""
		(layer "F.Cu")
		(at 212.993732 -115.716812 180)
		(property "Reference" "R135"
			(at 0 0 180)
			(layer "F.SilkS")
			(hide yes)
			(effects
				(font
					(size 1.27 1.27)
				)
			)
		)
		(property "Value" ""
			(at 0 0 180)
			(layer "F.Fab")
			(effects
				(font
					(size 1.27 1.27)
				)
			)
		)
		(duplicate_pad_numbers_are_jumpers no)
		(fp_line
			(start 0.7874 0.4064)
			(end -0.7874 0.4064)
			(stroke
				(width 0.1524)
				(type default)
			)
			(layer "F.SilkS")
		)
		(fp_line
			(start 0.7874 -0.4064)
			(end 0.7874 0.4064)
			(stroke
				(width 0.1524)
				(type default)
			)
			(layer "F.SilkS")
		)
		(fp_line
			(start -0.7874 0.4064)
			(end -0.7874 -0.4064)
			(stroke
				(width 0.1524)
				(type default)
			)
			(layer "F.SilkS")
		)
		(fp_line
			(start -0.7874 -0.4064)
			(end 0.7874 -0.4064)
			(stroke
				(width 0.1524)
				(type default)
			)
			(layer "F.SilkS")
		)
		(fp_line
			(start 0.67945 0.3048)
			(end 0.120396 0.3048)
			(stroke
				(width 0.1)
				(type default)
			)
			(layer "F.Fab")
		)
		(fp_line
			(start 0.67945 -0.3048)
			(end 0.67945 0.3048)
			(stroke
				(width 0.1)
				(type default)
			)
			(layer "F.Fab")
		)
		(fp_line
			(start 0.12065 -0.2794)
			(end 0.12065 -0.3048)
			(stroke
				(width 0.1)
				(type default)
			)
			(layer "F.Fab")
		)
		(fp_line
			(start 0.12065 -0.3048)
			(end 0.67945 -0.3048)
			(stroke
				(width 0.1)
				(type default)
			)
			(layer "F.Fab")
		)
		(fp_line
			(start 0.120396 0.3048)
			(end 0.120396 0.2794)
			(stroke
				(width 0.1)
				(type default)
			)
			(layer "F.Fab")
		)
		(fp_line
			(start 0.120396 0.2794)
			(end -0.12065 0.2794)
			(stroke
				(width 0.1)
				(type default)
			)
			(layer "F.Fab")
		)
		(fp_line
			(start -0.12065 0.3048)
			(end -0.67945 0.3048)
			(stroke
				(width 0.1)
				(type default)
			)
			(layer "F.Fab")
		)
		(fp_line
			(start -0.12065 0.2794)
			(end -0.12065 0.3048)
			(stroke
				(width 0.1)
				(type default)
			)
			(layer "F.Fab")
		)
		(fp_line
			(start -0.12065 -0.2794)
			(end 0.12065 -0.2794)
			(stroke
				(width 0.1)
				(type default)
			)
			(layer "F.Fab")
		)
		(fp_line
			(start -0.12065 -0.305054)
			(end -0.12065 -0.2794)
			(stroke
				(width 0.1)
				(type default)
			)
			(layer "F.Fab")
		)
		(fp_line
			(start -0.67945 0.3048)
			(end -0.67945 -0.305054)
			(stroke
				(width 0.1)
				(type default)
			)
			(layer "F.Fab")
		)
		(fp_line
			(start -0.67945 -0.305054)
			(end -0.12065 -0.305054)
			(stroke
				(width 0.1)
				(type default)
			)
			(layer "F.Fab")
		)
		(pad "1" smd circle
			(at -0.40005 0 180)
			(size 0 0)
			(layers "F.Cu" "F.Mask" "F.Paste")
			(net "FM_APML_MUX2_SEL")
		)
		(pad "2" smd circle
			(at 0.40005 0 180)
			(size 0 0)
			(layers "F.Cu" "F.Mask" "F.Paste")
			(net "P3V3_AUX")
		)
	)
	(footprint ""
		(layer "F.Cu")
		(at 298.878498 -424.78833 -90)
		(property "Reference" "U11"
			(at 0.413766 3.240532 90)
			(unlocked yes)
			(layer "F.SilkS")
			(effects
				(font
					(size 0.7874 0.5842)
					(thickness 0.1524)
				)
				(justify left)
			)
		)
		(property "Value" ""
			(at 0 0 270)
			(layer "F.Fab")
			(effects
				(font
					(size 1.27 1.27)
				)
			)
		)
		(duplicate_pad_numbers_are_jumpers no)
		(fp_line
			(start -1.8288 2.500122)
			(end 1.8288 2.500122)
			(stroke
				(width 0.1524)
				(type default)
			)
			(layer "F.SilkS")
		)
		(fp_line
			(start 1.8288 2.500122)
			(end 1.8288 -2.500122)
			(stroke
				(width 0.1524)
				(type default)
			)
			(layer "F.SilkS")
		)
		(fp_line
			(start 0 -1.4224)
			(end -1.077722 -2.500122)
			(stroke
				(width 0.1524)
				(type default)
			)
			(layer "F.SilkS")
		)
		(fp_line
			(start -1.8288 -2.500122)
			(end -1.8288 2.500122)
			(stroke
				(width 0.1524)
				(type default)
			)
			(layer "F.SilkS")
		)
		(fp_line
			(start -1.077722 -2.500122)
			(end -1.8288 -2.500122)
			(stroke
				(width 0.1524)
				(type default)
			)
			(layer "F.SilkS")
		)
		(fp_line
			(start 1.077722 -2.500122)
			(end 0 -1.4224)
			(stroke
				(width 0.1524)
				(type default)
			)
			(layer "F.SilkS")
		)
		(fp_line
			(start 1.8288 -2.500122)
			(end 1.077722 -2.500122)
			(stroke
				(width 0.1524)
				(type default)
			)
			(layer "F.SilkS")
		)
		(fp_poly
			(pts
				(xy -4.41198 -2.683002) (xy -4.41198 -1.667002) (xy -3.39598 -2.175002)
			)
			(stroke
				(width 0)
				(type default)
			)
			(fill yes)
			(layer "F.SilkS")
		)
		(fp_line
			(start -1.999996 2.500122)
			(end 1.999996 2.500122)
			(stroke
				(width 0.1)
				(type default)
			)
			(layer "F.Fab")
		)
		(fp_line
			(start 1.999996 2.500122)
			(end 1.999996 -2.500122)
			(stroke
				(width 0.1)
				(type default)
			)
			(layer "F.Fab")
		)
		(fp_line
			(start -1.999996 -2.500122)
			(end -1.999996 2.500122)
			(stroke
				(width 0.1)
				(type default)
			)
			(layer "F.Fab")
		)
		(fp_line
			(start 1.999996 -2.500122)
			(end -1.999996 -2.500122)
			(stroke
				(width 0.1)
				(type default)
			)
			(layer "F.Fab")
		)
		(fp_poly
			(pts
				(xy -4.5085 -2.413) (xy -4.5085 -1.397) (xy -3.4925 -1.905)
			)
			(stroke
				(width 0)
				(type default)
			)
			(fill yes)
			(layer "F.Fab")
		)
		(pad "1" smd rect
			(at -2.599944 -1.905 180)
			(size 0.889 1.27)
			(layers "F.Cu" "F.Mask" "F.Paste")
			(net "Net_10847")
		)
		(pad "2" smd rect
			(at -2.599944 -0.635 180)
			(size 0.889 1.27)
			(layers "F.Cu" "F.Mask" "F.Paste")
			(net "Net_10846")
		)
		(pad "3" smd rect
			(at -2.599944 0.635 180)
			(size 0.889 1.27)
			(layers "F.Cu" "F.Mask" "F.Paste")
			(net "U11_E2")
		)
		(pad "4" smd rect
			(at -2.599944 1.905 180)
			(size 0.889 1.27)
			(layers "F.Cu" "F.Mask" "F.Paste")
			(net "GND")
		)
		(pad "5" smd rect
			(at 2.599944 1.905 180)
			(size 0.889 1.27)
			(layers "F.Cu" "F.Mask" "F.Paste")
			(net "SMB_RT_CPU0_P0_ROM_SDA")
		)
		(pad "6" smd rect
			(at 2.599944 0.635 180)
			(size 0.889 1.27)
			(layers "F.Cu" "F.Mask" "F.Paste")
			(net "SMB_RT_CPU0_P0_ROM_SCL")
		)
		(pad "7" smd rect
			(at 2.599944 -0.635 180)
			(size 0.889 1.27)
			(layers "F.Cu" "F.Mask" "F.Paste")
			(net "GND")
		)
		(pad "8" smd rect
			(at 2.599944 -1.905 180)
			(size 0.889 1.27)
			(layers "F.Cu" "F.Mask" "F.Paste")
			(net "P1V8_CPU0_RT_1D")
		)
	)
	(footprint ""
		(layer "F.Cu")
		(at 144.74063 -95.612458)
		(property "Reference" "U245"
			(at -0.08128 1.90119 0)
			(unlocked yes)
			(layer "F.SilkS")
			(effects
				(font
					(size 0.7874 0.5842)
					(thickness 0.1524)
				)
			)
		)
		(property "Value" ""
			(at 0 0 0)
			(layer "F.Fab")
			(effects
				(font
					(size 1.27 1.27)
				)
			)
		)
		(duplicate_pad_numbers_are_jumpers no)
		(fp_line
			(start -1.7272 1.1176)
			(end -1.7272 -1.1176)
			(stroke
				(width 0.1524)
				(type default)
			)
			(layer "F.SilkS")
		)
		(fp_line
			(start -0.254 -1.1176)
			(end -1.7272 -1.1176)
			(stroke
				(width 0.1524)
				(type default)
			)
			(layer "F.SilkS")
		)
		(fp_line
			(start 0 -0.7366)
			(end -0.254 -1.1176)
			(stroke
				(width 0.1524)
				(type default)
			)
			(layer "F.SilkS")
		)
		(fp_line
			(start 0.254 -1.1176)
			(end 0 -0.7366)
			(stroke
				(width 0.1524)
				(type default)
			)
			(layer "F.SilkS")
		)
		(fp_line
			(start 1.7272 -1.1176)
			(end 0.254 -1.1176)
			(stroke
				(width 0.1524)
				(type default)
			)
			(layer "F.SilkS")
		)
		(fp_line
			(start 1.7272 -1.1176)
			(end 1.7272 1.1176)
			(stroke
				(width 0.1524)
				(type default)
			)
			(layer "F.SilkS")
		)
		(fp_line
			(start 1.7272 1.1176)
			(end -1.7272 1.1176)
			(stroke
				(width 0.1524)
				(type default)
			)
			(layer "F.SilkS")
		)
		(fp_poly
			(pts
				(xy -2.7178 -1.030986) (xy -1.9558 -0.649986) (xy -2.7178 -0.268986)
			)
			(stroke
				(width 0)
				(type default)
			)
			(fill yes)
			(layer "F.SilkS")
		)
		(fp_line
			(start -1.5748 -1.1176)
			(end -1.5748 1.1176)
			(stroke
				(width 0.1)
				(type default)
			)
			(layer "F.Fab")
		)
		(fp_line
			(start -1.5748 1.1176)
			(end 1.5748 1.1176)
			(stroke
				(width 0.1)
				(type default)
			)
			(layer "F.Fab")
		)
		(fp_line
			(start 1.5748 -1.1176)
			(end -1.5748 -1.1176)
			(stroke
				(width 0.1)
				(type default)
			)
			(layer "F.Fab")
		)
		(fp_line
			(start 1.5748 1.1176)
			(end 1.5748 -1.1176)
			(stroke
				(width 0.1)
				(type default)
			)
			(layer "F.Fab")
		)
		(fp_poly
			(pts
				(xy -1.9558 -0.649986) (xy -2.7178 -0.268986) (xy -2.7178 -1.030986)
			)
			(stroke
				(width 0)
				(type default)
			)
			(fill yes)
			(layer "F.Fab")
		)
		(pad "1" smd rect
			(at -0.999998 -0.649986 270)
			(size 0.3556 1.1176)
			(layers "F.Cu" "F.Mask" "F.Paste")
			(net "OCP_V3_2_NOT_PRSNT_RBT_ARB_IN")
		)
		(pad "2" smd rect
			(at -0.999998 0 270)
			(size 0.3556 1.1176)
			(layers "F.Cu" "F.Mask" "F.Paste")
			(net "GND")
		)
		(pad "3" smd rect
			(at -0.999998 0.649986 270)
			(size 0.3556 1.1176)
			(layers "F.Cu" "F.Mask" "F.Paste")
			(net "OCP_V3_2_RBT_ARB_IN")
		)
		(pad "4" smd rect
			(at 0.999998 0.649986 270)
			(size 0.3556 1.1176)
			(layers "F.Cu" "F.Mask" "F.Paste")
			(net "OCP_SFF_RBT_ARB_IN_MUX2_R")
		)
		(pad "5" smd rect
			(at 0.999998 0 270)
			(size 0.3556 1.1176)
			(layers "F.Cu" "F.Mask" "F.Paste")
			(net "P3V3_AUX")
		)
		(pad "6" smd rect
			(at 0.999998 -0.649986 270)
			(size 0.3556 1.1176)
			(layers "F.Cu" "F.Mask" "F.Paste")
			(net "OCP_V3_2_PRSNT_ALL_R3_N")
		)
	)
	(footprint ""
		(layer "F.Cu")
		(at 438.056782 -433.49926 90)
		(property "Reference" "R9044"
			(at 0 0 90)
			(layer "F.SilkS")
			(hide yes)
			(effects
				(font
					(size 1.27 1.27)
				)
			)
		)
		(property "Value" ""
			(at 0 0 90)
			(layer "F.Fab")
			(effects
				(font
					(size 1.27 1.27)
				)
			)
		)
		(duplicate_pad_numbers_are_jumpers no)
		(fp_line
			(start 0.7874 -0.4064)
			(end 0.7874 0.4064)
			(stroke
				(width 0.1524)
				(type default)
			)
			(layer "F.SilkS")
		)
		(fp_line
			(start -0.7874 -0.4064)
			(end 0.7874 -0.4064)
			(stroke
				(width 0.1524)
				(type default)
			)
			(layer "F.SilkS")
		)
		(fp_line
			(start 0.7874 0.4064)
			(end -0.7874 0.4064)
			(stroke
				(width 0.1524)
				(type default)
			)
			(layer "F.SilkS")
		)
		(fp_line
			(start -0.7874 0.4064)
			(end -0.7874 -0.4064)
			(stroke
				(width 0.1524)
				(type default)
			)
			(layer "F.SilkS")
		)
		(fp_line
			(start -0.12065 -0.305054)
			(end -0.12065 -0.2794)
			(stroke
				(width 0.1)
				(type default)
			)
			(layer "F.Fab")
		)
		(fp_line
			(start -0.67945 -0.305054)
			(end -0.12065 -0.305054)
			(stroke
				(width 0.1)
				(type default)
			)
			(layer "F.Fab")
		)
		(fp_line
			(start 0.67945 -0.3048)
			(end 0.67945 0.3048)
			(stroke
				(width 0.1)
				(type default)
			)
			(layer "F.Fab")
		)
		(fp_line
			(start 0.12065 -0.3048)
			(end 0.67945 -0.3048)
			(stroke
				(width 0.1)
				(type default)
			)
			(layer "F.Fab")
		)
		(fp_line
			(start 0.12065 -0.2794)
			(end 0.12065 -0.3048)
			(stroke
				(width 0.1)
				(type default)
			)
			(layer "F.Fab")
		)
		(fp_line
			(start -0.12065 -0.2794)
			(end 0.12065 -0.2794)
			(stroke
				(width 0.1)
				(type default)
			)
			(layer "F.Fab")
		)
		(fp_line
			(start 0.120396 0.2794)
			(end -0.12065 0.2794)
			(stroke
				(width 0.1)
				(type default)
			)
			(layer "F.Fab")
		)
		(fp_line
			(start -0.12065 0.2794)
			(end -0.12065 0.3048)
			(stroke
				(width 0.1)
				(type default)
			)
			(layer "F.Fab")
		)
		(fp_line
			(start 0.67945 0.3048)
			(end 0.120396 0.3048)
			(stroke
				(width 0.1)
				(type default)
			)
			(layer "F.Fab")
		)
		(fp_line
			(start 0.120396 0.3048)
			(end 0.120396 0.2794)
			(stroke
				(width 0.1)
				(type default)
			)
			(layer "F.Fab")
		)
		(fp_line
			(start -0.12065 0.3048)
			(end -0.67945 0.3048)
			(stroke
				(width 0.1)
				(type default)
			)
			(layer "F.Fab")
		)
		(fp_line
			(start -0.67945 0.3048)
			(end -0.67945 -0.305054)
			(stroke
				(width 0.1)
				(type default)
			)
			(layer "F.Fab")
		)
		(pad "1" smd circle
			(at -0.40005 0 90)
			(size 0 0)
			(layers "F.Cu" "F.Mask" "F.Paste")
			(net "P3V3_AUX")
		)
		(pad "2" smd circle
			(at 0.40005 0 90)
			(size 0 0)
			(layers "F.Cu" "F.Mask" "F.Paste")
			(net "GPU_WP_HW_CTRL_ISO_N")
		)
	)
	(footprint ""
		(layer "F.Cu")
		(at 295.6814 -367.03)
		(property "Reference" "PQ10"
			(at -1.458214 -3.378454 0)
			(unlocked yes)
			(layer "F.SilkS")
			(effects
				(font
					(size 0.7874 0.5842)
					(thickness 0.1524)
				)
				(justify left)
			)
		)
		(property "Value" ""
			(at 0 0 0)
			(layer "F.Fab")
			(effects
				(font
					(size 1.27 1.27)
				)
			)
		)
		(duplicate_pad_numbers_are_jumpers no)
		(fp_line
			(start -1.603248 -1.500124)
			(end 1.603248 -1.500124)
			(stroke
				(width 0.1524)
				(type default)
			)
			(layer "F.SilkS")
		)
		(fp_line
			(start -1.603248 1.500124)
			(end -1.603248 -1.500124)
			(stroke
				(width 0.1524)
				(type default)
			)
			(layer "F.SilkS")
		)
		(fp_line
			(start 1.603248 -1.500124)
			(end 1.603248 1.500124)
			(stroke
				(width 0.1524)
				(type default)
			)
			(layer "F.SilkS")
		)
		(fp_line
			(start 1.603248 1.500124)
			(end -1.603248 1.500124)
			(stroke
				(width 0.1524)
				(type default)
			)
			(layer "F.SilkS")
		)
		(fp_line
			(start -1.249934 -1.169924)
			(end -1.249934 -0.729996)
			(stroke
				(width 0.1)
				(type default)
			)
			(layer "F.Fab")
		)
		(fp_line
			(start -1.249934 -0.729996)
			(end -0.6985 -0.729996)
			(stroke
				(width 0.1)
				(type default)
			)
			(layer "F.Fab")
		)
		(fp_line
			(start -1.249934 0.729996)
			(end -1.249934 1.169924)
			(stroke
				(width 0.1)
				(type default)
			)
			(layer "F.Fab")
		)
		(fp_line
			(start -1.249934 1.169924)
			(end -0.700024 1.169924)
			(stroke
				(width 0.1)
				(type default)
			)
			(layer "F.Fab")
		)
		(fp_line
			(start -0.700024 -1.500124)
			(end -0.700024 -1.169924)
			(stroke
				(width 0.1)
				(type default)
			)
			(layer "F.Fab")
		)
		(fp_line
			(start -0.700024 -1.169924)
			(end -1.249934 -1.169924)
			(stroke
				(width 0.1)
				(type default)
			)
			(layer "F.Fab")
		)
		(fp_line
			(start -0.700024 1.169924)
			(end -0.700024 1.500124)
			(stroke
				(width 0.1)
				(type default)
			)
			(layer "F.Fab")
		)
		(fp_line
			(start -0.700024 1.500124)
			(end 0.700024 1.500124)
			(stroke
				(width 0.1)
				(type default)
			)
			(layer "F.Fab")
		)
		(fp_line
			(start -0.6985 -0.729996)
			(end -0.6985 0.729996)
			(stroke
				(width 0.1)
				(type default)
			)
			(layer "F.Fab")
		)
		(fp_line
			(start -0.6985 0.729996)
			(end -1.249934 0.729996)
			(stroke
				(width 0.1)
				(type default)
			)
			(layer "F.Fab")
		)
		(fp_line
			(start 0.700024 -1.500124)
			(end -0.700024 -1.500124)
			(stroke
				(width 0.1)
				(type default)
			)
			(layer "F.Fab")
		)
		(fp_line
			(start 0.700024 -0.219964)
			(end 0.700024 -1.500124)
			(stroke
				(width 0.1)
				(type default)
			)
			(layer "F.Fab")
		)
		(fp_line
			(start 0.700024 0.219964)
			(end 1.249934 0.219964)
			(stroke
				(width 0.1)
				(type default)
			)
			(layer "F.Fab")
		)
		(fp_line
			(start 0.700024 1.500124)
			(end 0.700024 0.219964)
			(stroke
				(width 0.1)
				(type default)
			)
			(layer "F.Fab")
		)
		(fp_line
			(start 1.249934 -0.219964)
			(end 0.700024 -0.219964)
			(stroke
				(width 0.1)
				(type default)
			)
			(layer "F.Fab")
		)
		(fp_line
			(start 1.249934 0.219964)
			(end 1.249934 -0.219964)
			(stroke
				(width 0.1)
				(type default)
			)
			(layer "F.Fab")
		)
		(fp_rect
			(start -0.700024 1.500124)
			(end 0.700024 -1.500124)
			(stroke
				(width 0)
				(type default)
			)
			(fill no)
			(layer "F.Fab")
		)
		(pad "D" smd rect
			(at 0.999998 0 270)
			(size 0.8128 0.9144)
			(layers "F.Cu" "F.Mask" "F.Paste")
			(net "PVDDCR_CPU1_P0_EN1_ADDR_CFG")
		)
		(pad "G" smd rect
			(at -0.999998 -0.94996 270)
			(size 0.8128 0.9144)
			(layers "F.Cu" "F.Mask" "F.Paste")
			(net "PVDDIO_P0_EN_G")
		)
		(pad "S" smd rect
			(at -0.999998 0.94996 270)
			(size 0.8128 0.9144)
			(layers "F.Cu" "F.Mask" "F.Paste")
			(net "P3V3_AUX")
		)
	)
	(footprint ""
		(layer "F.Cu")
		(at 19.304 -361.442 90)
		(property "Reference" "PQ16"
			(at -0.01905 -2.928874 90)
			(unlocked yes)
			(layer "F.SilkS")
			(effects
				(font
					(size 0.7874 0.5842)
					(thickness 0.1524)
				)
			)
		)
		(property "Value" ""
			(at 0 0 90)
			(layer "F.Fab")
			(effects
				(font
					(size 1.27 1.27)
				)
			)
		)
		(duplicate_pad_numbers_are_jumpers no)
		(fp_line
			(start -1.949958 -1.610106)
			(end 1.949958 -1.610106)
			(stroke
				(width 0.1524)
				(type default)
			)
			(layer "F.SilkS")
		)
		(fp_line
			(start 1.949958 -1.560068)
			(end 1.949958 1.610106)
			(stroke
				(width 0.1524)
				(type default)
			)
			(layer "F.SilkS")
		)
		(fp_line
			(start 1.949958 1.610106)
			(end -1.949958 1.610106)
			(stroke
				(width 0.1524)
				(type default)
			)
			(layer "F.SilkS")
		)
		(fp_line
			(start -1.949958 1.610106)
			(end -1.949958 -1.610106)
			(stroke
				(width 0.1524)
				(type default)
			)
			(layer "F.SilkS")
		)
		(fp_line
			(start 0.750062 -1.560068)
			(end 0.750062 1.560068)
			(stroke
				(width 0.1)
				(type default)
			)
			(layer "F.Fab")
		)
		(fp_line
			(start -0.750062 -1.560068)
			(end 0.750062 -1.560068)
			(stroke
				(width 0.1)
				(type default)
			)
			(layer "F.Fab")
		)
		(fp_line
			(start 0.750062 1.560068)
			(end -0.750062 1.560068)
			(stroke
				(width 0.1)
				(type default)
			)
			(layer "F.Fab")
		)
		(fp_line
			(start -0.750062 1.560068)
			(end -0.750062 -1.560068)
			(stroke
				(width 0.1)
				(type default)
			)
			(layer "F.Fab")
		)
		(pad "D" smd rect
			(at 1.100074 0)
			(size 1.016 1.4224)
			(layers "F.Cu" "F.Mask" "F.Paste")
			(net "PVDDIO_P1_EN_G")
		)
		(pad "G" smd rect
			(at -1.100074 -0.94996)
			(size 1.016 1.4224)
			(layers "F.Cu" "F.Mask" "F.Paste")
			(net "PVDDIO_P1_EN_R")
		)
		(pad "S" smd rect
			(at -1.100074 0.94996)
			(size 1.016 1.4224)
			(layers "F.Cu" "F.Mask" "F.Paste")
			(net "GND")
		)
	)
	(footprint ""
		(layer "F.Cu")
		(at 118.617746 -52.48148 180)
		(property "Reference" "R6297"
			(at 0 0 180)
			(layer "F.SilkS")
			(hide yes)
			(effects
				(font
					(size 1.27 1.27)
				)
			)
		)
		(property "Value" ""
			(at 0 0 180)
			(layer "F.Fab")
			(effects
				(font
					(size 1.27 1.27)
				)
			)
		)
		(duplicate_pad_numbers_are_jumpers no)
		(fp_line
			(start 0.7874 0.4064)
			(end -0.7874 0.4064)
			(stroke
				(width 0.1524)
				(type default)
			)
			(layer "F.SilkS")
		)
		(fp_line
			(start 0.7874 -0.4064)
			(end 0.7874 0.4064)
			(stroke
				(width 0.1524)
				(type default)
			)
			(layer "F.SilkS")
		)
		(fp_line
			(start -0.7874 0.4064)
			(end -0.7874 -0.4064)
			(stroke
				(width 0.1524)
				(type default)
			)
			(layer "F.SilkS")
		)
		(fp_line
			(start -0.7874 -0.4064)
			(end 0.7874 -0.4064)
			(stroke
				(width 0.1524)
				(type default)
			)
			(layer "F.SilkS")
		)
		(fp_line
			(start 0.67945 0.3048)
			(end 0.120396 0.3048)
			(stroke
				(width 0.1)
				(type default)
			)
			(layer "F.Fab")
		)
		(fp_line
			(start 0.67945 -0.3048)
			(end 0.67945 0.3048)
			(stroke
				(width 0.1)
				(type default)
			)
			(layer "F.Fab")
		)
		(fp_line
			(start 0.12065 -0.2794)
			(end 0.12065 -0.3048)
			(stroke
				(width 0.1)
				(type default)
			)
			(layer "F.Fab")
		)
		(fp_line
			(start 0.12065 -0.3048)
			(end 0.67945 -0.3048)
			(stroke
				(width 0.1)
				(type default)
			)
			(layer "F.Fab")
		)
		(fp_line
			(start 0.120396 0.3048)
			(end 0.120396 0.2794)
			(stroke
				(width 0.1)
				(type default)
			)
			(layer "F.Fab")
		)
		(fp_line
			(start 0.120396 0.2794)
			(end -0.12065 0.2794)
			(stroke
				(width 0.1)
				(type default)
			)
			(layer "F.Fab")
		)
		(fp_line
			(start -0.12065 0.3048)
			(end -0.67945 0.3048)
			(stroke
				(width 0.1)
				(type default)
			)
			(layer "F.Fab")
		)
		(fp_line
			(start -0.12065 0.2794)
			(end -0.12065 0.3048)
			(stroke
				(width 0.1)
				(type default)
			)
			(layer "F.Fab")
		)
		(fp_line
			(start -0.12065 -0.2794)
			(end 0.12065 -0.2794)
			(stroke
				(width 0.1)
				(type default)
			)
			(layer "F.Fab")
		)
		(fp_line
			(start -0.12065 -0.305054)
			(end -0.12065 -0.2794)
			(stroke
				(width 0.1)
				(type default)
			)
			(layer "F.Fab")
		)
		(fp_line
			(start -0.67945 0.3048)
			(end -0.67945 -0.305054)
			(stroke
				(width 0.1)
				(type default)
			)
			(layer "F.Fab")
		)
		(fp_line
			(start -0.67945 -0.305054)
			(end -0.12065 -0.305054)
			(stroke
				(width 0.1)
				(type default)
			)
			(layer "F.Fab")
		)
		(pad "1" smd circle
			(at -0.40005 0 180)
			(size 0 0)
			(layers "F.Cu" "F.Mask" "F.Paste")
			(net "P3V3_AUX")
		)
		(pad "2" smd circle
			(at 0.40005 0 180)
			(size 0 0)
			(layers "F.Cu" "F.Mask" "F.Paste")
			(net "USB_HUB2_TI_OVERCCUR4")
		)
	)
	(footprint ""
		(layer "F.Cu")
		(at 56.46801 -387.342634)
		(property "Reference" "U6014"
			(at -6.735064 -7.919974 0)
			(unlocked yes)
			(layer "F.SilkS")
			(effects
				(font
					(size 0.7874 0.5842)
					(thickness 0.1524)
				)
				(justify left)
			)
		)
		(property "Value" ""
			(at 0 0 0)
			(layer "F.Fab")
			(effects
				(font
					(size 1.27 1.27)
				)
			)
		)
		(duplicate_pad_numbers_are_jumpers no)
		(fp_line
			(start -11.400028 -4.45008)
			(end -9.75741 -4.45008)
			(stroke
				(width 0.1524)
				(type default)
			)
			(layer "F.SilkS")
		)
		(fp_line
			(start -11.400028 -0.769366)
			(end -11.400028 -4.45008)
			(stroke
				(width 0.1524)
				(type default)
			)
			(layer "F.SilkS")
		)
		(fp_line
			(start -11.400028 4.45008)
			(end -11.400028 0.094234)
			(stroke
				(width 0.1524)
				(type default)
			)
			(layer "F.SilkS")
		)
		(fp_line
			(start -10.18921 4.45008)
			(end -11.400028 4.45008)
			(stroke
				(width 0.1524)
				(type default)
			)
			(layer "F.SilkS")
		)
		(fp_line
			(start 9.59739 -4.45008)
			(end 11.400028 -4.45008)
			(stroke
				(width 0.1524)
				(type default)
			)
			(layer "F.SilkS")
		)
		(fp_line
			(start 11.400028 -4.45008)
			(end 11.400028 4.45008)
			(stroke
				(width 0.1524)
				(type default)
			)
			(layer "F.SilkS")
		)
		(fp_line
			(start 11.400028 4.45008)
			(end 9.57199 4.45008)
			(stroke
				(width 0.1524)
				(type default)
			)
			(layer "F.SilkS")
		)
		(fp_poly
			(pts
				(xy 10.450068 -4.45008) (xy 10.450068 -5.21208) (xy 12.162028 -5.21208) (xy 12.162028 -3.41884)
				(xy 11.400028 -3.41884) (xy 11.400028 -4.45008)
			)
			(stroke
				(width 0)
				(type default)
			)
			(fill yes)
			(layer "F.SilkS")
		)
		(fp_line
			(start -11.400028 -4.45008)
			(end -11.400028 4.45008)
			(stroke
				(width 0.1)
				(type default)
			)
			(layer "F.Fab")
		)
		(fp_line
			(start -11.400028 4.45008)
			(end 11.400028 4.45008)
			(stroke
				(width 0.1)
				(type default)
			)
			(layer "F.Fab")
		)
		(fp_line
			(start 11.400028 -4.45008)
			(end -11.400028 -4.45008)
			(stroke
				(width 0.1)
				(type default)
			)
			(layer "F.Fab")
		)
		(fp_line
			(start 11.400028 4.45008)
			(end 11.400028 -4.45008)
			(stroke
				(width 0.1)
				(type default)
			)
			(layer "F.Fab")
		)
		(fp_poly
			(pts
				(xy 10.450068 -4.45008) (xy 10.450068 -5.21208) (xy 12.162028 -5.21208) (xy 12.162028 -3.41884)
				(xy 11.400028 -3.41884) (xy 11.400028 -4.45008)
			)
			(stroke
				(width 0)
				(type default)
			)
			(fill yes)
			(layer "F.Fab")
		)
		(pad "A1" smd oval
			(at 11.050016 -3.938524)
			(size 0.254 0.3302)
			(layers "F.Cu" "F.Mask" "F.Paste")
			(net "NCF_A1_CPU1_P0_GND")
		)
		(pad "A35" smd oval
			(at 11.050016 3.940048)
			(size 0.254 0.3302)
			(layers "F.Cu" "F.Mask" "F.Paste")
			(net "NCF_CPU1_P0_GND")
		)
		(pad "AA10" smd circle
			(at 7.602728 -1.431798)
			(size 0.381 0.381)
			(layers "F.Cu" "F.Mask" "F.Paste")
			(net "P5E_CPU1_P0_TX_BUF_DN<14>")
		)
		(pad "AA29" smd circle
			(at 7.602728 2.032254)
			(size 0.381 0.381)
			(layers "F.Cu" "F.Mask" "F.Paste")
			(net "P5E_CPU1_P0_RX_DN<14>")
		)
		(pad "AB1" smd oval
			(at 7.450074 -3.938524)
			(size 0.254 0.3302)
			(layers "F.Cu" "F.Mask" "F.Paste")
			(net "P5E_CPU1_P0_RX_BUF_DP<14>")
		)
		(pad "AB35" smd oval
			(at 7.450074 3.940048)
			(size 0.254 0.3302)
			(layers "F.Cu" "F.Mask" "F.Paste")
			(net "P5E_CPU1_P0_TX_C_DP<14>")
		)
		(pad "AC4" smd circle
			(at 7.202678 -2.817368)
			(size 0.381 0.381)
			(layers "F.Cu" "F.Mask" "F.Paste")
			(net "GND")
		)
		(pad "AC13" smd circle
			(at 7.202678 -0.79629)
			(size 0.3048 0.3048)
			(layers "F.Cu" "F.Mask" "F.Paste")
			(net "GND")
		)
		(pad "AC17" smd circle
			(at 7.202678 -0.296164)
			(size 0.3048 0.3048)
			(layers "F.Cu" "F.Mask" "F.Paste")
			(net "P0V9_CPU1_RT0_2A")
		)
		(pad "AC20" smd circle
			(at 7.202678 0.203708)
			(size 0.3048 0.3048)
			(layers "F.Cu" "F.Mask" "F.Paste")
			(net "P0V9_CPU1_RT0_2A")
		)
		(pad "AC22" smd circle
			(at 7.202678 0.703834)
			(size 0.3048 0.3048)
			(layers "F.Cu" "F.Mask" "F.Paste")
			(net "GND")
		)
		(pad "AC32" smd circle
			(at 7.202678 2.724912)
			(size 0.381 0.381)
			(layers "F.Cu" "F.Mask" "F.Paste")
			(net "GND")
		)
		(pad "AD2" smd circle
			(at 7.1501 -3.41884)
			(size 0.3048 0.3048)
			(layers "F.Cu" "F.Mask" "F.Paste")
			(net "GND")
		)
		(pad "AD34" smd circle
			(at 7.1501 3.420364)
			(size 0.3048 0.3048)
			(layers "F.Cu" "F.Mask" "F.Paste")
			(net "GND")
		)
		(pad "AE1" smd oval
			(at 6.849872 -3.938524)
			(size 0.254 0.3302)
			(layers "F.Cu" "F.Mask" "F.Paste")
			(net "GND")
		)
		(pad "AE35" smd oval
			(at 6.849872 3.940048)
			(size 0.254 0.3302)
			(layers "F.Cu" "F.Mask" "F.Paste")
			(net "GND")
		)
		(pad "AF7" smd circle
			(at 6.802628 -2.12471)
			(size 0.381 0.381)
			(layers "F.Cu" "F.Mask" "F.Paste")
			(net "P5E_CPU1_P0_TX_BUF_DP<13>")
		)
		(pad "AF26" smd circle
			(at 6.802628 1.339342)
			(size 0.381 0.381)
			(layers "F.Cu" "F.Mask" "F.Paste")
			(net "P5E_CPU1_P0_RX_DP<13>")
		)
		(pad "AG2" smd circle
			(at 6.549898 -3.41884)
			(size 0.3048 0.3048)
			(layers "F.Cu" "F.Mask" "F.Paste")
			(net "P5E_CPU1_P0_RX_BUF_DN<13>")
		)
		(pad "AG34" smd circle
			(at 6.549898 3.420364)
			(size 0.3048 0.3048)
			(layers "F.Cu" "F.Mask" "F.Paste")
			(net "P5E_CPU1_P0_TX_C_DP<13>")
		)
		(pad "AH10" smd circle
			(at 6.402578 -1.431798)
			(size 0.381 0.381)
			(layers "F.Cu" "F.Mask" "F.Paste")
			(net "P5E_CPU1_P0_TX_BUF_DN<13>")
		)
		(pad "AH29" smd circle
			(at 6.402578 2.032254)
			(size 0.381 0.381)
			(layers "F.Cu" "F.Mask" "F.Paste")
			(net "P5E_CPU1_P0_RX_DN<13>")
		)
		(pad "AJ1" smd oval
			(at 6.249924 -3.938524)
			(size 0.254 0.3302)
			(layers "F.Cu" "F.Mask" "F.Paste")
			(net "P5E_CPU1_P0_RX_BUF_DP<13>")
		)
		(pad "AJ35" smd oval
			(at 6.249924 3.940048)
			(size 0.254 0.3302)
			(layers "F.Cu" "F.Mask" "F.Paste")
			(net "P5E_CPU1_P0_TX_C_DN<13>")
		)
		(pad "AK4" smd circle
			(at 6.002528 -2.817368)
			(size 0.381 0.381)
			(layers "F.Cu" "F.Mask" "F.Paste")
			(net "GND")
		)
		(pad "AK13" smd circle
			(at 6.002528 -0.79629)
			(size 0.3048 0.3048)
			(layers "F.Cu" "F.Mask" "F.Paste")
			(net "GND")
		)
		(pad "AK17" smd circle
			(at 6.002528 -0.296164)
			(size 0.3048 0.3048)
			(layers "F.Cu" "F.Mask" "F.Paste")
			(net "P0V9_CPU1_RT0_2A")
		)
		(pad "AK20" smd circle
			(at 6.002528 0.203708)
			(size 0.3048 0.3048)
			(layers "F.Cu" "F.Mask" "F.Paste")
			(net "P0V9_CPU1_RT0_2A")
		)
		(pad "AK22" smd circle
			(at 6.002528 0.703834)
			(size 0.3048 0.3048)
			(layers "F.Cu" "F.Mask" "F.Paste")
			(net "GND")
		)
		(pad "AK32" smd circle
			(at 6.002528 2.724912)
			(size 0.381 0.381)
			(layers "F.Cu" "F.Mask" "F.Paste")
			(net "GND")
		)
		(pad "AL2" smd circle
			(at 5.94995 -3.41884)
			(size 0.3048 0.3048)
			(layers "F.Cu" "F.Mask" "F.Paste")
			(net "GND")
		)
		(pad "AL34" smd circle
			(at 5.94995 3.420364)
			(size 0.3048 0.3048)
			(layers "F.Cu" "F.Mask" "F.Paste")
			(net "GND")
		)
		(pad "AM1" smd oval
			(at 5.649976 -3.938524)
			(size 0.254 0.3302)
			(layers "F.Cu" "F.Mask" "F.Paste")
			(net "GND")
		)
		(pad "AM35" smd oval
			(at 5.649976 3.940048)
			(size 0.254 0.3302)
			(layers "F.Cu" "F.Mask" "F.Paste")
			(net "GND")
		)
		(pad "AN7" smd circle
			(at 5.602478 -2.12471)
			(size 0.381 0.381)
			(layers "F.Cu" "F.Mask" "F.Paste")
			(net "P5E_CPU1_P0_TX_BUF_DP<12>")
		)
		(pad "AN26" smd circle
			(at 5.602478 1.339342)
			(size 0.381 0.381)
			(layers "F.Cu" "F.Mask" "F.Paste")
			(net "P5E_CPU1_P0_RX_DP<12>")
		)
		(pad "AP2" smd circle
			(at 5.350002 -3.41884)
			(size 0.3048 0.3048)
			(layers "F.Cu" "F.Mask" "F.Paste")
			(net "P5E_CPU1_P0_RX_BUF_DN<12>")
		)
		(pad "AP34" smd circle
			(at 5.350002 3.420364)
			(size 0.3048 0.3048)
			(layers "F.Cu" "F.Mask" "F.Paste")
			(net "P5E_CPU1_P0_TX_C_DN<12>")
		)
		(pad "AR10" smd circle
			(at 5.202682 -1.431798)
			(size 0.381 0.381)
			(layers "F.Cu" "F.Mask" "F.Paste")
			(net "P5E_CPU1_P0_TX_BUF_DN<12>")
		)
		(pad "AR29" smd circle
			(at 5.202682 2.032254)
			(size 0.381 0.381)
			(layers "F.Cu" "F.Mask" "F.Paste")
			(net "P5E_CPU1_P0_RX_DN<12>")
		)
		(pad "AT1" smd oval
			(at 5.050028 -3.938524)
			(size 0.254 0.3302)
			(layers "F.Cu" "F.Mask" "F.Paste")
			(net "P5E_CPU1_P0_RX_BUF_DP<12>")
		)
		(pad "AT35" smd oval
			(at 5.050028 3.940048)
			(size 0.254 0.3302)
			(layers "F.Cu" "F.Mask" "F.Paste")
			(net "P5E_CPU1_P0_TX_C_DP<12>")
		)
		(pad "AU4" smd circle
			(at 4.802632 -2.817368)
			(size 0.381 0.381)
			(layers "F.Cu" "F.Mask" "F.Paste")
			(net "GND")
		)
		(pad "AU13" smd circle
			(at 4.802632 -0.79629)
			(size 0.3048 0.3048)
			(layers "F.Cu" "F.Mask" "F.Paste")
			(net "GND")
		)
		(pad "AU17" smd circle
			(at 4.802632 -0.296164)
			(size 0.3048 0.3048)
			(layers "F.Cu" "F.Mask" "F.Paste")
			(net "P0V9_CPU1_RT0_2A")
		)
		(pad "AU20" smd circle
			(at 4.802632 0.203708)
			(size 0.3048 0.3048)
			(layers "F.Cu" "F.Mask" "F.Paste")
			(net "P0V9_CPU1_RT0_2A")
		)
		(pad "AU22" smd circle
			(at 4.802632 0.703834)
			(size 0.3048 0.3048)
			(layers "F.Cu" "F.Mask" "F.Paste")
			(net "GND")
		)
		(pad "AU32" smd circle
			(at 4.802632 2.724912)
			(size 0.381 0.381)
			(layers "F.Cu" "F.Mask" "F.Paste")
			(net "GND")
		)
		(pad "AV2" smd circle
			(at 4.750054 -3.41884)
			(size 0.3048 0.3048)
			(layers "F.Cu" "F.Mask" "F.Paste")
			(net "GND")
		)
		(pad "AV34" smd circle
			(at 4.750054 3.420364)
			(size 0.3048 0.3048)
			(layers "F.Cu" "F.Mask" "F.Paste")
			(net "GND")
		)
		(pad "AW1" smd oval
			(at 4.45008 -3.938524)
			(size 0.254 0.3302)
			(layers "F.Cu" "F.Mask" "F.Paste")
			(net "GND")
		)
		(pad "AW35" smd oval
			(at 4.45008 3.940048)
			(size 0.254 0.3302)
			(layers "F.Cu" "F.Mask" "F.Paste")
			(net "GND")
		)
		(pad "AY7" smd circle
			(at 4.402582 -2.12471)
			(size 0.381 0.381)
			(layers "F.Cu" "F.Mask" "F.Paste")
			(net "P5E_CPU1_P0_TX_BUF_DP<11>")
		)
		(pad "AY26" smd circle
			(at 4.402582 1.339342)
			(size 0.381 0.381)
			(layers "F.Cu" "F.Mask" "F.Paste")
			(net "P5E_CPU1_P0_RX_DP<11>")
		)
		(pad "B3" smd oval
			(at 10.885932 -2.888488 90)
			(size 0.254 0.3302)
			(layers "F.Cu" "F.Mask" "F.Paste")
			(net "JTAG_TCK_RT_CPU1_P0")
		)
		(pad "B6" smd oval
			(at 10.885932 -2.288286 90)
			(size 0.254 0.3302)
			(layers "F.Cu" "F.Mask" "F.Paste")
			(net "JTAG_TDI_RT_CPU1_P0")
		)
		(pad "B9" smd oval
			(at 10.885932 -1.688338 90)
			(size 0.254 0.3302)
			(layers "F.Cu" "F.Mask" "F.Paste")
			(net "JTAG_TDO_RT_CPU1_P0")
		)
		(pad "B12" smd oval
			(at 10.885932 -1.08839 90)
			(size 0.254 0.3302)
			(layers "F.Cu" "F.Mask" "F.Paste")
			(net "JTAG_TMS_RT_CPU1_P0")
		)
		(pad "B16" smd oval
			(at 10.885932 -0.488442 90)
			(size 0.254 0.3302)
			(layers "F.Cu" "F.Mask" "F.Paste")
			(net "Net_2217")
		)
		(pad "B19" smd oval
			(at 10.885932 0.111506 90)
			(size 0.254 0.3302)
			(layers "F.Cu" "F.Mask" "F.Paste")
			(net "GND")
		)
		(pad "B23" smd oval
			(at 10.885932 0.711708 90)
			(size 0.254 0.3302)
			(layers "F.Cu" "F.Mask" "F.Paste")
			(net "RT_CPU1_P0_ADDR2")
		)
		(pad "B25" smd oval
			(at 10.885932 1.311656 90)
			(size 0.254 0.3302)
			(layers "F.Cu" "F.Mask" "F.Paste")
			(net "RT_CPU1_P0_ADDR3")
		)
		(pad "B28" smd oval
			(at 10.885932 1.911604 90)
			(size 0.254 0.3302)
			(layers "F.Cu" "F.Mask" "F.Paste")
			(net "SMB_RT_CPU1_P0_R2_SDA")
		)
		(pad "B31" smd oval
			(at 10.885932 2.511552 90)
			(size 0.254 0.3302)
			(layers "F.Cu" "F.Mask" "F.Paste")
			(net "SMB_RT_CPU1_P0_R2_SCL")
		)
		(pad "BA2" smd circle
			(at 4.150106 -3.41884)
			(size 0.3048 0.3048)
			(layers "F.Cu" "F.Mask" "F.Paste")
			(net "P5E_CPU1_P0_RX_BUF_DN<11>")
		)
		(pad "BA34" smd circle
			(at 4.150106 3.420364)
			(size 0.3048 0.3048)
			(layers "F.Cu" "F.Mask" "F.Paste")
			(net "P5E_CPU1_P0_TX_C_DN<11>")
		)
		(pad "BB10" smd circle
			(at 4.002532 -1.431798)
			(size 0.381 0.381)
			(layers "F.Cu" "F.Mask" "F.Paste")
			(net "P5E_CPU1_P0_TX_BUF_DN<11>")
		)
		(pad "BB29" smd circle
			(at 4.002532 2.032254)
			(size 0.381 0.381)
			(layers "F.Cu" "F.Mask" "F.Paste")
			(net "P5E_CPU1_P0_RX_DN<11>")
		)
		(pad "BC1" smd oval
			(at 3.849878 -3.938524)
			(size 0.254 0.3302)
			(layers "F.Cu" "F.Mask" "F.Paste")
			(net "P5E_CPU1_P0_RX_BUF_DP<11>")
		)
		(pad "BC35" smd oval
			(at 3.849878 3.940048)
			(size 0.254 0.3302)
			(layers "F.Cu" "F.Mask" "F.Paste")
			(net "P5E_CPU1_P0_TX_C_DP<11>")
		)
		(pad "BD4" smd circle
			(at 3.602482 -2.817368)
			(size 0.381 0.381)
			(layers "F.Cu" "F.Mask" "F.Paste")
			(net "GND")
		)
		(pad "BD13" smd circle
			(at 3.602482 -0.79629)
			(size 0.3048 0.3048)
			(layers "F.Cu" "F.Mask" "F.Paste")
			(net "GND")
		)
		(pad "BD17" smd circle
			(at 3.602482 -0.296164)
			(size 0.3048 0.3048)
			(layers "F.Cu" "F.Mask" "F.Paste")
			(net "P0V9_CPU1_RT0_2A_2D")
		)
		(pad "BD20" smd circle
			(at 3.602482 0.203708)
			(size 0.3048 0.3048)
			(layers "F.Cu" "F.Mask" "F.Paste")
			(net "P0V9_CPU1_RT0_2A_2D")
		)
		(pad "BD22" smd circle
			(at 3.602482 0.703834)
			(size 0.3048 0.3048)
			(layers "F.Cu" "F.Mask" "F.Paste")
			(net "GND")
		)
		(pad "BD32" smd circle
			(at 3.602482 2.724912)
			(size 0.381 0.381)
			(layers "F.Cu" "F.Mask" "F.Paste")
			(net "GND")
		)
		(pad "BE2" smd circle
			(at 3.549904 -3.41884)
			(size 0.3048 0.3048)
			(layers "F.Cu" "F.Mask" "F.Paste")
			(net "GND")
		)
		(pad "BE34" smd circle
			(at 3.549904 3.420364)
			(size 0.3048 0.3048)
			(layers "F.Cu" "F.Mask" "F.Paste")
			(net "GND")
		)
		(pad "BF1" smd oval
			(at 3.24993 -3.938524)
			(size 0.254 0.3302)
			(layers "F.Cu" "F.Mask" "F.Paste")
			(net "GND")
		)
		(pad "BF35" smd oval
			(at 3.24993 3.940048)
			(size 0.254 0.3302)
			(layers "F.Cu" "F.Mask" "F.Paste")
			(net "GND")
		)
		(pad "BG7" smd circle
			(at 3.202686 -2.12471)
			(size 0.381 0.381)
			(layers "F.Cu" "F.Mask" "F.Paste")
			(net "P5E_CPU1_P0_TX_BUF_DP<10>")
		)
		(pad "BG26" smd circle
			(at 3.202686 1.339342)
			(size 0.381 0.381)
			(layers "F.Cu" "F.Mask" "F.Paste")
			(net "P5E_CPU1_P0_RX_DP<10>")
		)
		(pad "BH2" smd circle
			(at 2.949956 -3.41884)
			(size 0.3048 0.3048)
			(layers "F.Cu" "F.Mask" "F.Paste")
			(net "P5E_CPU1_P0_RX_BUF_DN<10>")
		)
		(pad "BH34" smd circle
			(at 2.949956 3.420364)
			(size 0.3048 0.3048)
			(layers "F.Cu" "F.Mask" "F.Paste")
			(net "P5E_CPU1_P0_TX_C_DN<10>")
		)
		(pad "BJ10" smd circle
			(at 2.802636 -1.431798)
			(size 0.381 0.381)
			(layers "F.Cu" "F.Mask" "F.Paste")
			(net "P5E_CPU1_P0_TX_BUF_DN<10>")
		)
		(pad "BJ29" smd circle
			(at 2.802636 2.032254)
			(size 0.381 0.381)
			(layers "F.Cu" "F.Mask" "F.Paste")
			(net "P5E_CPU1_P0_RX_DN<10>")
		)
		(pad "BK1" smd oval
			(at 2.649982 -3.938524)
			(size 0.254 0.3302)
			(layers "F.Cu" "F.Mask" "F.Paste")
			(net "P5E_CPU1_P0_RX_BUF_DP<10>")
		)
		(pad "BK35" smd oval
			(at 2.649982 3.940048)
			(size 0.254 0.3302)
			(layers "F.Cu" "F.Mask" "F.Paste")
			(net "P5E_CPU1_P0_TX_C_DP<10>")
		)
		(pad "BL4" smd circle
			(at 2.402586 -2.817368)
			(size 0.381 0.381)
			(layers "F.Cu" "F.Mask" "F.Paste")
			(net "GND")
		)
		(pad "BL13" smd circle
			(at 2.402586 -0.79629)
			(size 0.3048 0.3048)
			(layers "F.Cu" "F.Mask" "F.Paste")
			(net "GND")
		)
		(pad "BL17" smd circle
			(at 2.402586 -0.296164)
			(size 0.3048 0.3048)
			(layers "F.Cu" "F.Mask" "F.Paste")
			(net "P0V9_CPU1_RT_2D")
		)
		(pad "BL20" smd circle
			(at 2.402586 0.203708)
			(size 0.3048 0.3048)
			(layers "F.Cu" "F.Mask" "F.Paste")
			(net "P0V9_CPU1_RT_2D")
		)
		(pad "BL22" smd circle
			(at 2.402586 0.703834)
			(size 0.3048 0.3048)
			(layers "F.Cu" "F.Mask" "F.Paste")
			(net "GND")
		)
		(pad "BL32" smd circle
			(at 2.402586 2.724912)
			(size 0.381 0.381)
			(layers "F.Cu" "F.Mask" "F.Paste")
			(net "GND")
		)
		(pad "BM2" smd circle
			(at 2.350008 -3.41884)
			(size 0.3048 0.3048)
			(layers "F.Cu" "F.Mask" "F.Paste")
			(net "GND")
		)
		(pad "BM34" smd circle
			(at 2.350008 3.420364)
			(size 0.3048 0.3048)
			(layers "F.Cu" "F.Mask" "F.Paste")
			(net "GND")
		)
		(pad "BN1" smd oval
			(at 2.050034 -3.938524)
			(size 0.254 0.3302)
			(layers "F.Cu" "F.Mask" "F.Paste")
			(net "GND")
		)
		(pad "BN35" smd oval
			(at 2.050034 3.940048)
			(size 0.254 0.3302)
			(layers "F.Cu" "F.Mask" "F.Paste")
			(net "GND")
		)
		(pad "BP7" smd circle
			(at 2.002536 -2.12471)
			(size 0.381 0.381)
			(layers "F.Cu" "F.Mask" "F.Paste")
			(net "P5E_CPU1_P0_TX_BUF_DP<9>")
		)
		(pad "BP26" smd circle
			(at 2.002536 1.339342)
			(size 0.381 0.381)
			(layers "F.Cu" "F.Mask" "F.Paste")
			(net "P5E_CPU1_P0_RX_DP<9>")
		)
		(pad "BR2" smd circle
			(at 1.75006 -3.41884)
			(size 0.3048 0.3048)
			(layers "F.Cu" "F.Mask" "F.Paste")
			(net "P5E_CPU1_P0_RX_BUF_DN<9>")
		)
		(pad "BR34" smd circle
			(at 1.75006 3.420364)
			(size 0.3048 0.3048)
			(layers "F.Cu" "F.Mask" "F.Paste")
			(net "P5E_CPU1_P0_TX_C_DN<9>")
		)
		(pad "BT10" smd circle
			(at 1.602486 -1.431798)
			(size 0.381 0.381)
			(layers "F.Cu" "F.Mask" "F.Paste")
			(net "P5E_CPU1_P0_TX_BUF_DN<9>")
		)
		(pad "BT29" smd circle
			(at 1.602486 2.032254)
			(size 0.381 0.381)
			(layers "F.Cu" "F.Mask" "F.Paste")
			(net "P5E_CPU1_P0_RX_DN<9>")
		)
		(pad "BU1" smd oval
			(at 1.450086 -3.938524)
			(size 0.254 0.3302)
			(layers "F.Cu" "F.Mask" "F.Paste")
			(net "P5E_CPU1_P0_RX_BUF_DP<9>")
		)
		(pad "BU35" smd oval
			(at 1.450086 3.940048)
			(size 0.254 0.3302)
			(layers "F.Cu" "F.Mask" "F.Paste")
			(net "P5E_CPU1_P0_TX_C_DP<9>")
		)
		(pad "BV4" smd circle
			(at 1.20269 -2.817368)
			(size 0.381 0.381)
			(layers "F.Cu" "F.Mask" "F.Paste")
			(net "GND")
		)
		(pad "BV13" smd circle
			(at 1.20269 -0.79629)
			(size 0.3048 0.3048)
			(layers "F.Cu" "F.Mask" "F.Paste")
			(net "GND")
		)
		(pad "BV17" smd circle
			(at 1.20269 -0.296164)
			(size 0.3048 0.3048)
			(layers "F.Cu" "F.Mask" "F.Paste")
			(net "P1V8_CPU1_RT0_1A_1D")
		)
		(pad "BV20" smd circle
			(at 1.20269 0.203708)
			(size 0.3048 0.3048)
			(layers "F.Cu" "F.Mask" "F.Paste")
			(net "P1V8_CPU1_RT0_1A")
		)
		(pad "BV22" smd circle
			(at 1.20269 0.703834)
			(size 0.3048 0.3048)
			(layers "F.Cu" "F.Mask" "F.Paste")
			(net "GND")
		)
		(pad "BV32" smd circle
			(at 1.20269 2.724912)
			(size 0.381 0.381)
			(layers "F.Cu" "F.Mask" "F.Paste")
			(net "GND")
		)
		(pad "BW2" smd circle
			(at 1.150112 -3.41884)
			(size 0.3048 0.3048)
			(layers "F.Cu" "F.Mask" "F.Paste")
			(net "GND")
		)
		(pad "BW34" smd circle
			(at 1.150112 3.420364)
			(size 0.3048 0.3048)
			(layers "F.Cu" "F.Mask" "F.Paste")
			(net "GND")
		)
		(pad "BY1" smd oval
			(at 0.849884 -3.938524)
			(size 0.254 0.3302)
			(layers "F.Cu" "F.Mask" "F.Paste")
			(net "GND")
		)
		(pad "BY35" smd oval
			(at 0.849884 3.940048)
			(size 0.254 0.3302)
			(layers "F.Cu" "F.Mask" "F.Paste")
			(net "GND")
		)
		(pad "C2" smd circle
			(at 10.750042 -3.41884)
			(size 0.3048 0.3048)
			(layers "F.Cu" "F.Mask" "F.Paste")
			(net "NCF_CPU1_P0_GND")
		)
		(pad "C34" smd circle
			(at 10.750042 3.420364)
			(size 0.3048 0.3048)
			(layers "F.Cu" "F.Mask" "F.Paste")
			(net "NCF_CPU1_P0_GND")
		)
		(pad "CA7" smd circle
			(at 0.80264 -2.12471)
			(size 0.381 0.381)
			(layers "F.Cu" "F.Mask" "F.Paste")
			(net "P5E_CPU1_P0_TX_BUF_DP<8>")
		)
		(pad "CA26" smd circle
			(at 0.80264 1.339342)
			(size 0.381 0.381)
			(layers "F.Cu" "F.Mask" "F.Paste")
			(net "P5E_CPU1_P0_RX_DP<8>")
		)
		(pad "CB2" smd circle
			(at 0.54991 -3.41884)
			(size 0.3048 0.3048)
			(layers "F.Cu" "F.Mask" "F.Paste")
			(net "P5E_CPU1_P0_RX_BUF_DN<8>")
		)
		(pad "CB34" smd circle
			(at 0.54991 3.420364)
			(size 0.3048 0.3048)
			(layers "F.Cu" "F.Mask" "F.Paste")
			(net "P5E_CPU1_P0_TX_C_DN<8>")
		)
		(pad "CC10" smd circle
			(at 0.40259 -1.431798)
			(size 0.381 0.381)
			(layers "F.Cu" "F.Mask" "F.Paste")
			(net "P5E_CPU1_P0_TX_BUF_DN<8>")
		)
		(pad "CC29" smd circle
			(at 0.40259 2.032254)
			(size 0.381 0.381)
			(layers "F.Cu" "F.Mask" "F.Paste")
			(net "P5E_CPU1_P0_RX_DN<8>")
		)
		(pad "CD1" smd oval
			(at 0.249936 -3.938524)
			(size 0.254 0.3302)
			(layers "F.Cu" "F.Mask" "F.Paste")
			(net "P5E_CPU1_P0_RX_BUF_DP<8>")
		)
		(pad "CD35" smd oval
			(at 0.249936 3.940048)
			(size 0.254 0.3302)
			(layers "F.Cu" "F.Mask" "F.Paste")
			(net "P5E_CPU1_P0_TX_C_DP<8>")
		)
		(pad "CE4" smd circle
			(at 0.00254 -2.817368)
			(size 0.381 0.381)
			(layers "F.Cu" "F.Mask" "F.Paste")
			(net "GND")
		)
		(pad "CE13" smd circle
			(at 0.00254 -0.79629)
			(size 0.3048 0.3048)
			(layers "F.Cu" "F.Mask" "F.Paste")
			(net "GND")
		)
		(pad "CE17" smd circle
			(at 0.00254 -0.296164)
			(size 0.3048 0.3048)
			(layers "F.Cu" "F.Mask" "F.Paste")
			(net "P1V8_CPU1_RT0_1A")
		)
		(pad "CE20" smd circle
			(at 0.00254 0.203708)
			(size 0.3048 0.3048)
			(layers "F.Cu" "F.Mask" "F.Paste")
			(net "P1V8_CPU1_RT0_1A")
		)
		(pad "CE22" smd circle
			(at 0.00254 0.703834)
			(size 0.3048 0.3048)
			(layers "F.Cu" "F.Mask" "F.Paste")
			(net "GND")
		)
		(pad "CE32" smd circle
			(at 0.00254 2.724912)
			(size 0.381 0.381)
			(layers "F.Cu" "F.Mask" "F.Paste")
			(net "GND")
		)
		(pad "CF2" smd circle
			(at -0.050038 -3.41884)
			(size 0.3048 0.3048)
			(layers "F.Cu" "F.Mask" "F.Paste")
			(net "GND")
		)
		(pad "CF34" smd circle
			(at -0.050038 3.420364)
			(size 0.3048 0.3048)
			(layers "F.Cu" "F.Mask" "F.Paste")
			(net "GND")
		)
		(pad "CG1" smd oval
			(at -0.350012 -3.938524)
			(size 0.254 0.3302)
			(layers "F.Cu" "F.Mask" "F.Paste")
			(net "GND")
		)
		(pad "CG35" smd oval
			(at -0.350012 3.940048)
			(size 0.254 0.3302)
			(layers "F.Cu" "F.Mask" "F.Paste")
			(net "GND")
		)
		(pad "CH7" smd circle
			(at -0.39751 -2.12471)
			(size 0.381 0.381)
			(layers "F.Cu" "F.Mask" "F.Paste")
			(net "P5E_CPU1_P0_TX_BUF_DP<7>")
		)
		(pad "CH26" smd circle
			(at -0.39751 1.339342)
			(size 0.381 0.381)
			(layers "F.Cu" "F.Mask" "F.Paste")
			(net "P5E_CPU1_P0_RX_DP<7>")
		)
		(pad "CJ2" smd circle
			(at -0.649986 -3.41884)
			(size 0.3048 0.3048)
			(layers "F.Cu" "F.Mask" "F.Paste")
			(net "P5E_CPU1_P0_RX_BUF_DN<7>")
		)
		(pad "CJ34" smd circle
			(at -0.649986 3.420364)
			(size 0.3048 0.3048)
			(layers "F.Cu" "F.Mask" "F.Paste")
			(net "P5E_CPU1_P0_TX_C_DN<7>")
		)
		(pad "CK10" smd circle
			(at -0.797306 -1.431798)
			(size 0.381 0.381)
			(layers "F.Cu" "F.Mask" "F.Paste")
			(net "P5E_CPU1_P0_TX_BUF_DN<7>")
		)
		(pad "CK29" smd circle
			(at -0.797306 2.032254)
			(size 0.381 0.381)
			(layers "F.Cu" "F.Mask" "F.Paste")
			(net "P5E_CPU1_P0_RX_DN<7>")
		)
		(pad "CL1" smd oval
			(at -0.94996 -3.938524)
			(size 0.254 0.3302)
			(layers "F.Cu" "F.Mask" "F.Paste")
			(net "P5E_CPU1_P0_RX_BUF_DP<7>")
		)
		(pad "CL35" smd oval
			(at -0.94996 3.940048)
			(size 0.254 0.3302)
			(layers "F.Cu" "F.Mask" "F.Paste")
			(net "P5E_CPU1_P0_TX_C_DP<7>")
		)
		(pad "CM4" smd circle
			(at -1.197356 -2.817368)
			(size 0.381 0.381)
			(layers "F.Cu" "F.Mask" "F.Paste")
			(net "GND")
		)
		(pad "CM13" smd circle
			(at -1.197356 -0.79629)
			(size 0.3048 0.3048)
			(layers "F.Cu" "F.Mask" "F.Paste")
			(net "GND")
		)
		(pad "CM17" smd circle
			(at -1.197356 -0.296164)
			(size 0.3048 0.3048)
			(layers "F.Cu" "F.Mask" "F.Paste")
			(net "P1V8_CPU1_RT0_1A")
		)
		(pad "CM20" smd circle
			(at -1.197356 0.203708)
			(size 0.3048 0.3048)
			(layers "F.Cu" "F.Mask" "F.Paste")
			(net "P1V8_CPU1_RT0_1A")
		)
		(pad "CM22" smd circle
			(at -1.197356 0.703834)
			(size 0.3048 0.3048)
			(layers "F.Cu" "F.Mask" "F.Paste")
			(net "GND")
		)
		(pad "CM32" smd circle
			(at -1.197356 2.724912)
			(size 0.381 0.381)
			(layers "F.Cu" "F.Mask" "F.Paste")
			(net "GND")
		)
		(pad "CN2" smd circle
			(at -1.249934 -3.41884)
			(size 0.3048 0.3048)
			(layers "F.Cu" "F.Mask" "F.Paste")
			(net "GND")
		)
		(pad "CN34" smd circle
			(at -1.249934 3.420364)
			(size 0.3048 0.3048)
			(layers "F.Cu" "F.Mask" "F.Paste")
			(net "GND")
		)
		(pad "CP1" smd oval
			(at -1.549908 -3.938524)
			(size 0.254 0.3302)
			(layers "F.Cu" "F.Mask" "F.Paste")
			(net "GND")
		)
		(pad "CP35" smd oval
			(at -1.549908 3.940048)
			(size 0.254 0.3302)
			(layers "F.Cu" "F.Mask" "F.Paste")
			(net "GND")
		)
		(pad "CR7" smd circle
			(at -1.597406 -2.12471)
			(size 0.381 0.381)
			(layers "F.Cu" "F.Mask" "F.Paste")
			(net "P5E_CPU1_P0_TX_BUF_DP<6>")
		)
		(pad "CR26" smd circle
			(at -1.597406 1.339342)
			(size 0.381 0.381)
			(layers "F.Cu" "F.Mask" "F.Paste")
			(net "P5E_CPU1_P0_RX_DP<6>")
		)
		(pad "CT2" smd circle
			(at -1.849882 -3.41884)
			(size 0.3048 0.3048)
			(layers "F.Cu" "F.Mask" "F.Paste")
			(net "P5E_CPU1_P0_RX_BUF_DN<6>")
		)
		(pad "CT34" smd circle
			(at -1.849882 3.420364)
			(size 0.3048 0.3048)
			(layers "F.Cu" "F.Mask" "F.Paste")
			(net "P5E_CPU1_P0_TX_C_DN<6>")
		)
		(pad "CU10" smd circle
			(at -1.997456 -1.431798)
			(size 0.381 0.381)
			(layers "F.Cu" "F.Mask" "F.Paste")
			(net "P5E_CPU1_P0_TX_BUF_DN<6>")
		)
		(pad "CU29" smd circle
			(at -1.997456 2.032254)
			(size 0.381 0.381)
			(layers "F.Cu" "F.Mask" "F.Paste")
			(net "P5E_CPU1_P0_RX_DN<6>")
		)
		(pad "CV1" smd oval
			(at -2.15011 -3.938524)
			(size 0.254 0.3302)
			(layers "F.Cu" "F.Mask" "F.Paste")
			(net "P5E_CPU1_P0_RX_BUF_DP<6>")
		)
		(pad "CV35" smd oval
			(at -2.15011 3.940048)
			(size 0.254 0.3302)
			(layers "F.Cu" "F.Mask" "F.Paste")
			(net "P5E_CPU1_P0_TX_C_DP<6>")
		)
		(pad "CW4" smd circle
			(at -2.397506 -2.817368)
			(size 0.381 0.381)
			(layers "F.Cu" "F.Mask" "F.Paste")
			(net "GND")
		)
		(pad "CW13" smd circle
			(at -2.397506 -0.79629)
			(size 0.3048 0.3048)
			(layers "F.Cu" "F.Mask" "F.Paste")
			(net "GND")
		)
		(pad "CW17" smd circle
			(at -2.397506 -0.296164)
			(size 0.3048 0.3048)
			(layers "F.Cu" "F.Mask" "F.Paste")
			(net "P0V9_CPU1_RT_2D")
		)
		(pad "CW20" smd circle
			(at -2.397506 0.203708)
			(size 0.3048 0.3048)
			(layers "F.Cu" "F.Mask" "F.Paste")
			(net "P0V9_CPU1_RT_2D")
		)
		(pad "CW22" smd circle
			(at -2.397506 0.703834)
			(size 0.3048 0.3048)
			(layers "F.Cu" "F.Mask" "F.Paste")
			(net "GND")
		)
		(pad "CW32" smd circle
			(at -2.397506 2.724912)
			(size 0.381 0.381)
			(layers "F.Cu" "F.Mask" "F.Paste")
			(net "GND")
		)
		(pad "CY2" smd circle
			(at -2.450084 -3.41884)
			(size 0.3048 0.3048)
			(layers "F.Cu" "F.Mask" "F.Paste")
			(net "GND")
		)
		(pad "CY34" smd circle
			(at -2.450084 3.420364)
			(size 0.3048 0.3048)
			(layers "F.Cu" "F.Mask" "F.Paste")
			(net "GND")
		)
		(pad "D1" smd oval
			(at 10.450068 -3.938524)
			(size 0.254 0.3302)
			(layers "F.Cu" "F.Mask" "F.Paste")
			(net "NCF_CPU1_P0_GND")
		)
		(pad "D35" smd oval
			(at 10.450068 3.940048)
			(size 0.254 0.3302)
			(layers "F.Cu" "F.Mask" "F.Paste")
			(net "NCF_CPU1_P0_GND")
		)
		(pad "DA1" smd oval
			(at -2.750058 -3.938524)
			(size 0.254 0.3302)
			(layers "F.Cu" "F.Mask" "F.Paste")
			(net "GND")
		)
		(pad "DA35" smd oval
			(at -2.750058 3.940048)
			(size 0.254 0.3302)
			(layers "F.Cu" "F.Mask" "F.Paste")
			(net "GND")
		)
		(pad "DB7" smd circle
			(at -2.797302 -2.12471)
			(size 0.381 0.381)
			(layers "F.Cu" "F.Mask" "F.Paste")
			(net "P5E_CPU1_P0_TX_BUF_DP<5>")
		)
		(pad "DB26" smd circle
			(at -2.797302 1.339342)
			(size 0.381 0.381)
			(layers "F.Cu" "F.Mask" "F.Paste")
			(net "P5E_CPU1_P0_RX_DP<5>")
		)
		(pad "DC2" smd circle
			(at -3.050032 -3.41884)
			(size 0.3048 0.3048)
			(layers "F.Cu" "F.Mask" "F.Paste")
			(net "P5E_CPU1_P0_RX_BUF_DN<5>")
		)
		(pad "DC34" smd circle
			(at -3.050032 3.420364)
			(size 0.3048 0.3048)
			(layers "F.Cu" "F.Mask" "F.Paste")
			(net "P5E_CPU1_P0_TX_C_DN<5>")
		)
		(pad "DD10" smd circle
			(at -3.197352 -1.431798)
			(size 0.381 0.381)
			(layers "F.Cu" "F.Mask" "F.Paste")
			(net "P5E_CPU1_P0_TX_BUF_DN<5>")
		)
		(pad "DD29" smd circle
			(at -3.197352 2.032254)
			(size 0.381 0.381)
			(layers "F.Cu" "F.Mask" "F.Paste")
			(net "P5E_CPU1_P0_RX_DN<5>")
		)
		(pad "DE1" smd oval
			(at -3.350006 -3.938524)
			(size 0.254 0.3302)
			(layers "F.Cu" "F.Mask" "F.Paste")
			(net "P5E_CPU1_P0_RX_BUF_DP<5>")
		)
		(pad "DE35" smd oval
			(at -3.350006 3.940048)
			(size 0.254 0.3302)
			(layers "F.Cu" "F.Mask" "F.Paste")
			(net "P5E_CPU1_P0_TX_C_DP<5>")
		)
		(pad "DF4" smd circle
			(at -3.597402 -2.817368)
			(size 0.381 0.381)
			(layers "F.Cu" "F.Mask" "F.Paste")
			(net "GND")
		)
		(pad "DF13" smd circle
			(at -3.597402 -0.79629)
			(size 0.3048 0.3048)
			(layers "F.Cu" "F.Mask" "F.Paste")
			(net "GND")
		)
		(pad "DF17" smd circle
			(at -3.597402 -0.296164)
			(size 0.3048 0.3048)
			(layers "F.Cu" "F.Mask" "F.Paste")
			(net "P0V9_CPU1_RT0_2A_2D")
		)
		(pad "DF20" smd circle
			(at -3.597402 0.203708)
			(size 0.3048 0.3048)
			(layers "F.Cu" "F.Mask" "F.Paste")
			(net "P0V9_CPU1_RT0_2A_2D")
		)
		(pad "DF22" smd circle
			(at -3.597402 0.703834)
			(size 0.3048 0.3048)
			(layers "F.Cu" "F.Mask" "F.Paste")
			(net "GND")
		)
		(pad "DF32" smd circle
			(at -3.597402 2.724912)
			(size 0.381 0.381)
			(layers "F.Cu" "F.Mask" "F.Paste")
			(net "GND")
		)
		(pad "DG2" smd circle
			(at -3.64998 -3.41884)
			(size 0.3048 0.3048)
			(layers "F.Cu" "F.Mask" "F.Paste")
			(net "GND")
		)
		(pad "DG34" smd circle
			(at -3.64998 3.420364)
			(size 0.3048 0.3048)
			(layers "F.Cu" "F.Mask" "F.Paste")
			(net "GND")
		)
		(pad "DH1" smd oval
			(at -3.949954 -3.938524)
			(size 0.254 0.3302)
			(layers "F.Cu" "F.Mask" "F.Paste")
			(net "GND")
		)
		(pad "DH35" smd oval
			(at -3.949954 3.940048)
			(size 0.254 0.3302)
			(layers "F.Cu" "F.Mask" "F.Paste")
			(net "GND")
		)
		(pad "DJ7" smd circle
			(at -3.997452 -2.12471)
			(size 0.381 0.381)
			(layers "F.Cu" "F.Mask" "F.Paste")
			(net "P5E_CPU1_P0_TX_BUF_DP<4>")
		)
		(pad "DJ26" smd circle
			(at -3.997452 1.339342)
			(size 0.381 0.381)
			(layers "F.Cu" "F.Mask" "F.Paste")
			(net "P5E_CPU1_P0_RX_DP<4>")
		)
		(pad "DK2" smd circle
			(at -4.249928 -3.41884)
			(size 0.3048 0.3048)
			(layers "F.Cu" "F.Mask" "F.Paste")
			(net "P5E_CPU1_P0_RX_BUF_DN<4>")
		)
		(pad "DK34" smd circle
			(at -4.249928 3.420364)
			(size 0.3048 0.3048)
			(layers "F.Cu" "F.Mask" "F.Paste")
			(net "P5E_CPU1_P0_TX_C_DN<4>")
		)
		(pad "DL10" smd circle
			(at -4.397502 -1.431798)
			(size 0.381 0.381)
			(layers "F.Cu" "F.Mask" "F.Paste")
			(net "P5E_CPU1_P0_TX_BUF_DN<4>")
		)
		(pad "DL29" smd circle
			(at -4.397502 2.032254)
			(size 0.381 0.381)
			(layers "F.Cu" "F.Mask" "F.Paste")
			(net "P5E_CPU1_P0_RX_DN<4>")
		)
		(pad "DM1" smd oval
			(at -4.549902 -3.938524)
			(size 0.254 0.3302)
			(layers "F.Cu" "F.Mask" "F.Paste")
			(net "P5E_CPU1_P0_RX_BUF_DP<4>")
		)
		(pad "DM35" smd oval
			(at -4.549902 3.940048)
			(size 0.254 0.3302)
			(layers "F.Cu" "F.Mask" "F.Paste")
			(net "P5E_CPU1_P0_TX_C_DP<4>")
		)
		(pad "DN4" smd circle
			(at -4.797298 -2.817368)
			(size 0.381 0.381)
			(layers "F.Cu" "F.Mask" "F.Paste")
			(net "GND")
		)
		(pad "DN13" smd circle
			(at -4.797298 -0.79629)
			(size 0.3048 0.3048)
			(layers "F.Cu" "F.Mask" "F.Paste")
			(net "GND")
		)
		(pad "DN17" smd circle
			(at -4.797298 -0.296164)
			(size 0.3048 0.3048)
			(layers "F.Cu" "F.Mask" "F.Paste")
			(net "P0V9_CPU1_RT0_2A")
		)
		(pad "DN20" smd circle
			(at -4.797298 0.203708)
			(size 0.3048 0.3048)
			(layers "F.Cu" "F.Mask" "F.Paste")
			(net "P0V9_CPU1_RT0_2A")
		)
		(pad "DN22" smd circle
			(at -4.797298 0.703834)
			(size 0.3048 0.3048)
			(layers "F.Cu" "F.Mask" "F.Paste")
			(net "GND")
		)
		(pad "DN32" smd circle
			(at -4.797298 2.724912)
			(size 0.381 0.381)
			(layers "F.Cu" "F.Mask" "F.Paste")
			(net "GND")
		)
		(pad "DP2" smd circle
			(at -4.849876 -3.41884)
			(size 0.3048 0.3048)
			(layers "F.Cu" "F.Mask" "F.Paste")
			(net "GND")
		)
		(pad "DP34" smd circle
			(at -4.849876 3.420364)
			(size 0.3048 0.3048)
			(layers "F.Cu" "F.Mask" "F.Paste")
			(net "GND")
		)
		(pad "DR1" smd oval
			(at -5.150104 -3.938524)
			(size 0.254 0.3302)
			(layers "F.Cu" "F.Mask" "F.Paste")
			(net "GND")
		)
		(pad "DR35" smd oval
			(at -5.150104 3.940048)
			(size 0.254 0.3302)
			(layers "F.Cu" "F.Mask" "F.Paste")
			(net "GND")
		)
		(pad "DT7" smd circle
			(at -5.197348 -2.12471)
			(size 0.381 0.381)
			(layers "F.Cu" "F.Mask" "F.Paste")
			(net "P5E_CPU1_P0_TX_BUF_DP<3>")
		)
		(pad "DT26" smd circle
			(at -5.197348 1.339342)
			(size 0.381 0.381)
			(layers "F.Cu" "F.Mask" "F.Paste")
			(net "P5E_CPU1_P0_RX_DP<3>")
		)
		(pad "DU2" smd circle
			(at -5.450078 -3.41884)
			(size 0.3048 0.3048)
			(layers "F.Cu" "F.Mask" "F.Paste")
			(net "P5E_CPU1_P0_RX_BUF_DN<3>")
		)
		(pad "DU34" smd circle
			(at -5.450078 3.420364)
			(size 0.3048 0.3048)
			(layers "F.Cu" "F.Mask" "F.Paste")
			(net "P5E_CPU1_P0_TX_C_DN<3>")
		)
		(pad "DV10" smd circle
			(at -5.597398 -1.431798)
			(size 0.381 0.381)
			(layers "F.Cu" "F.Mask" "F.Paste")
			(net "P5E_CPU1_P0_TX_BUF_DN<3>")
		)
		(pad "DV29" smd circle
			(at -5.597398 2.032254)
			(size 0.381 0.381)
			(layers "F.Cu" "F.Mask" "F.Paste")
			(net "P5E_CPU1_P0_RX_DN<3>")
		)
		(pad "DW1" smd oval
			(at -5.750052 -3.938524)
			(size 0.254 0.3302)
			(layers "F.Cu" "F.Mask" "F.Paste")
			(net "P5E_CPU1_P0_RX_BUF_DP<3>")
		)
		(pad "DW35" smd oval
			(at -5.750052 3.940048)
			(size 0.254 0.3302)
			(layers "F.Cu" "F.Mask" "F.Paste")
			(net "P5E_CPU1_P0_TX_C_DP<3>")
		)
		(pad "DY4" smd circle
			(at -5.997448 -2.817368)
			(size 0.381 0.381)
			(layers "F.Cu" "F.Mask" "F.Paste")
			(net "GND")
		)
		(pad "DY13" smd circle
			(at -5.997448 -0.79629)
			(size 0.3048 0.3048)
			(layers "F.Cu" "F.Mask" "F.Paste")
			(net "GND")
		)
		(pad "DY17" smd circle
			(at -5.997448 -0.296164)
			(size 0.3048 0.3048)
			(layers "F.Cu" "F.Mask" "F.Paste")
			(net "P0V9_CPU1_RT0_2A")
		)
		(pad "DY20" smd circle
			(at -5.997448 0.203708)
			(size 0.3048 0.3048)
			(layers "F.Cu" "F.Mask" "F.Paste")
			(net "P0V9_CPU1_RT0_2A")
		)
		(pad "DY22" smd circle
			(at -5.997448 0.703834)
			(size 0.3048 0.3048)
			(layers "F.Cu" "F.Mask" "F.Paste")
			(net "GND")
		)
		(pad "DY32" smd circle
			(at -5.997448 2.724912)
			(size 0.381 0.381)
			(layers "F.Cu" "F.Mask" "F.Paste")
			(net "GND")
		)
		(pad "E8" smd circle
			(at 10.366502 -1.988312)
			(size 0.3048 0.3048)
			(layers "F.Cu" "F.Mask" "F.Paste")
			(net "JTAG_TRST_RT_CPU1_P0_N")
		)
		(pad "E11" smd circle
			(at 10.366502 -1.388364)
			(size 0.3048 0.3048)
			(layers "F.Cu" "F.Mask" "F.Paste")
			(net "RXDET_BYP_RT_CPU1_P0")
		)
		(pad "E14" smd circle
			(at 10.366502 -0.788416)
			(size 0.3048 0.3048)
			(layers "F.Cu" "F.Mask" "F.Paste")
			(net "GND")
		)
		(pad "E18" smd circle
			(at 10.366502 -0.188468)
			(size 0.3048 0.3048)
			(layers "F.Cu" "F.Mask" "F.Paste")
			(net "Net_2216")
		)
		(pad "E27" smd circle
			(at 10.366502 1.61163)
			(size 0.3048 0.3048)
			(layers "F.Cu" "F.Mask" "F.Paste")
			(net "GND")
		)
		(pad "E30" smd circle
			(at 10.366502 2.211578)
			(size 0.3048 0.3048)
			(layers "F.Cu" "F.Mask" "F.Paste")
			(net "GND")
		)
		(pad "E33" smd circle
			(at 10.366502 2.811526)
			(size 0.3048 0.3048)
			(layers "F.Cu" "F.Mask" "F.Paste")
			(net "GND")
		)
		(pad "EA2" smd circle
			(at -6.050026 -3.41884)
			(size 0.3048 0.3048)
			(layers "F.Cu" "F.Mask" "F.Paste")
			(net "GND")
		)
		(pad "EA34" smd circle
			(at -6.050026 3.420364)
			(size 0.3048 0.3048)
			(layers "F.Cu" "F.Mask" "F.Paste")
			(net "GND")
		)
		(pad "EB1" smd oval
			(at -6.35 -3.938524)
			(size 0.254 0.3302)
			(layers "F.Cu" "F.Mask" "F.Paste")
			(net "GND")
		)
		(pad "EB35" smd oval
			(at -6.35 3.940048)
			(size 0.254 0.3302)
			(layers "F.Cu" "F.Mask" "F.Paste")
			(net "GND")
		)
		(pad "EC7" smd circle
			(at -6.397498 -2.12471)
			(size 0.381 0.381)
			(layers "F.Cu" "F.Mask" "F.Paste")
			(net "P5E_CPU1_P0_TX_BUF_DP<2>")
		)
		(pad "EC26" smd circle
			(at -6.397498 1.339342)
			(size 0.381 0.381)
			(layers "F.Cu" "F.Mask" "F.Paste")
			(net "P5E_CPU1_P0_RX_DP<2>")
		)
		(pad "ED2" smd circle
			(at -6.649974 -3.41884)
			(size 0.3048 0.3048)
			(layers "F.Cu" "F.Mask" "F.Paste")
			(net "P5E_CPU1_P0_RX_BUF_DN<2>")
		)
		(pad "ED34" smd circle
			(at -6.649974 3.420364)
			(size 0.3048 0.3048)
			(layers "F.Cu" "F.Mask" "F.Paste")
			(net "P5E_CPU1_P0_TX_C_DN<2>")
		)
		(pad "EE10" smd circle
			(at -6.797294 -1.431798)
			(size 0.381 0.381)
			(layers "F.Cu" "F.Mask" "F.Paste")
			(net "P5E_CPU1_P0_TX_BUF_DN<2>")
		)
		(pad "EE29" smd circle
			(at -6.797294 2.032254)
			(size 0.381 0.381)
			(layers "F.Cu" "F.Mask" "F.Paste")
			(net "P5E_CPU1_P0_RX_DN<2>")
		)
		(pad "EF1" smd oval
			(at -6.949948 -3.938524)
			(size 0.254 0.3302)
			(layers "F.Cu" "F.Mask" "F.Paste")
			(net "P5E_CPU1_P0_RX_BUF_DP<2>")
		)
		(pad "EF35" smd oval
			(at -6.949948 3.940048)
			(size 0.254 0.3302)
			(layers "F.Cu" "F.Mask" "F.Paste")
			(net "P5E_CPU1_P0_TX_C_DP<2>")
		)
		(pad "EG4" smd circle
			(at -7.197344 -2.817368)
			(size 0.381 0.381)
			(layers "F.Cu" "F.Mask" "F.Paste")
			(net "GND")
		)
		(pad "EG13" smd circle
			(at -7.197344 -0.79629)
			(size 0.3048 0.3048)
			(layers "F.Cu" "F.Mask" "F.Paste")
			(net "GND")
		)
		(pad "EG17" smd circle
			(at -7.197344 -0.296164)
			(size 0.3048 0.3048)
			(layers "F.Cu" "F.Mask" "F.Paste")
			(net "P0V9_CPU1_RT0_2A")
		)
		(pad "EG20" smd circle
			(at -7.197344 0.203708)
			(size 0.3048 0.3048)
			(layers "F.Cu" "F.Mask" "F.Paste")
			(net "P0V9_CPU1_RT0_2A")
		)
		(pad "EG22" smd circle
			(at -7.197344 0.703834)
			(size 0.3048 0.3048)
			(layers "F.Cu" "F.Mask" "F.Paste")
			(net "GND")
		)
		(pad "EG32" smd circle
			(at -7.197344 2.724912)
			(size 0.381 0.381)
			(layers "F.Cu" "F.Mask" "F.Paste")
			(net "GND")
		)
		(pad "EH2" smd circle
			(at -7.249922 -3.41884)
			(size 0.3048 0.3048)
			(layers "F.Cu" "F.Mask" "F.Paste")
			(net "GND")
		)
		(pad "EH34" smd circle
			(at -7.249922 3.420364)
			(size 0.3048 0.3048)
			(layers "F.Cu" "F.Mask" "F.Paste")
			(net "GND")
		)
		(pad "EJ1" smd oval
			(at -7.549896 -3.938524)
			(size 0.254 0.3302)
			(layers "F.Cu" "F.Mask" "F.Paste")
			(net "GND")
		)
		(pad "EJ35" smd oval
			(at -7.549896 3.940048)
			(size 0.254 0.3302)
			(layers "F.Cu" "F.Mask" "F.Paste")
			(net "GND")
		)
		(pad "EK7" smd circle
			(at -7.597394 -2.12471)
			(size 0.381 0.381)
			(layers "F.Cu" "F.Mask" "F.Paste")
			(net "P5E_CPU1_P0_TX_BUF_DP<1>")
		)
		(pad "EK26" smd circle
			(at -7.597394 1.339342)
			(size 0.381 0.381)
			(layers "F.Cu" "F.Mask" "F.Paste")
			(net "P5E_CPU1_P0_RX_DP<1>")
		)
		(pad "EL2" smd circle
			(at -7.850124 -3.41884)
			(size 0.3048 0.3048)
			(layers "F.Cu" "F.Mask" "F.Paste")
			(net "P5E_CPU1_P0_RX_BUF_DN<1>")
		)
		(pad "EL34" smd circle
			(at -7.850124 3.420364)
			(size 0.3048 0.3048)
			(layers "F.Cu" "F.Mask" "F.Paste")
			(net "P5E_CPU1_P0_TX_C_DP<1>")
		)
		(pad "EM10" smd circle
			(at -7.997444 -1.431798)
			(size 0.381 0.381)
			(layers "F.Cu" "F.Mask" "F.Paste")
			(net "P5E_CPU1_P0_TX_BUF_DN<1>")
		)
		(pad "EM29" smd circle
			(at -7.997444 2.032254)
			(size 0.381 0.381)
			(layers "F.Cu" "F.Mask" "F.Paste")
			(net "P5E_CPU1_P0_RX_DN<1>")
		)
		(pad "EN1" smd oval
			(at -8.150098 -3.938524)
			(size 0.254 0.3302)
			(layers "F.Cu" "F.Mask" "F.Paste")
			(net "P5E_CPU1_P0_RX_BUF_DP<1>")
		)
		(pad "EN35" smd oval
			(at -8.150098 3.940048)
			(size 0.254 0.3302)
			(layers "F.Cu" "F.Mask" "F.Paste")
			(net "P5E_CPU1_P0_TX_C_DN<1>")
		)
		(pad "EP4" smd circle
			(at -8.397494 -2.817368)
			(size 0.381 0.381)
			(layers "F.Cu" "F.Mask" "F.Paste")
			(net "GND")
		)
		(pad "EP13" smd circle
			(at -8.397494 -0.79629)
			(size 0.3048 0.3048)
			(layers "F.Cu" "F.Mask" "F.Paste")
			(net "GND")
		)
		(pad "EP17" smd circle
			(at -8.397494 -0.296164)
			(size 0.3048 0.3048)
			(layers "F.Cu" "F.Mask" "F.Paste")
			(net "P0V9_CPU1_RT0_2A")
		)
		(pad "EP20" smd circle
			(at -8.397494 0.203708)
			(size 0.3048 0.3048)
			(layers "F.Cu" "F.Mask" "F.Paste")
			(net "P0V9_CPU1_RT0_2A")
		)
		(pad "EP22" smd circle
			(at -8.397494 0.703834)
			(size 0.3048 0.3048)
			(layers "F.Cu" "F.Mask" "F.Paste")
			(net "GND")
		)
		(pad "EP32" smd circle
			(at -8.397494 2.724912)
			(size 0.381 0.381)
			(layers "F.Cu" "F.Mask" "F.Paste")
			(net "GND")
		)
		(pad "ER2" smd circle
			(at -8.450072 -3.41884)
			(size 0.3048 0.3048)
			(layers "F.Cu" "F.Mask" "F.Paste")
			(net "GND")
		)
		(pad "ER34" smd circle
			(at -8.450072 3.420364)
			(size 0.3048 0.3048)
			(layers "F.Cu" "F.Mask" "F.Paste")
			(net "GND")
		)
		(pad "ET1" smd oval
			(at -8.750046 -3.938524)
			(size 0.254 0.3302)
			(layers "F.Cu" "F.Mask" "F.Paste")
			(net "GND")
		)
		(pad "ET35" smd oval
			(at -8.750046 3.940048)
			(size 0.254 0.3302)
			(layers "F.Cu" "F.Mask" "F.Paste")
			(net "GND")
		)
		(pad "EU7" smd circle
			(at -8.79729 -2.12471)
			(size 0.381 0.381)
			(layers "F.Cu" "F.Mask" "F.Paste")
			(net "P5E_CPU1_P0_TX_BUF_DP<0>")
		)
		(pad "EU26" smd circle
			(at -8.79729 1.339342)
			(size 0.381 0.381)
			(layers "F.Cu" "F.Mask" "F.Paste")
			(net "P5E_CPU1_P0_RX_DP<0>")
		)
		(pad "EV2" smd circle
			(at -9.05002 -3.41884)
			(size 0.3048 0.3048)
			(layers "F.Cu" "F.Mask" "F.Paste")
			(net "P5E_CPU1_P0_RX_BUF_DN<0>")
		)
		(pad "EV34" smd circle
			(at -9.05002 3.420364)
			(size 0.3048 0.3048)
			(layers "F.Cu" "F.Mask" "F.Paste")
			(net "P5E_CPU1_P0_TX_C_DN<0>")
		)
		(pad "EW10" smd circle
			(at -9.19734 -1.431798)
			(size 0.381 0.381)
			(layers "F.Cu" "F.Mask" "F.Paste")
			(net "P5E_CPU1_P0_TX_BUF_DN<0>")
		)
		(pad "EW29" smd circle
			(at -9.19734 2.032254)
			(size 0.381 0.381)
			(layers "F.Cu" "F.Mask" "F.Paste")
			(net "P5E_CPU1_P0_RX_DN<0>")
		)
		(pad "EY1" smd oval
			(at -9.349994 -3.938524)
			(size 0.254 0.3302)
			(layers "F.Cu" "F.Mask" "F.Paste")
			(net "P5E_CPU1_P0_RX_BUF_DP<0>")
		)
		(pad "EY35" smd oval
			(at -9.349994 3.940048)
			(size 0.254 0.3302)
			(layers "F.Cu" "F.Mask" "F.Paste")
			(net "P5E_CPU1_P0_TX_C_DP<0>")
		)
		(pad "F2" smd circle
			(at 10.150094 -3.41884)
			(size 0.3048 0.3048)
			(layers "F.Cu" "F.Mask" "F.Paste")
			(net "RST_RT_CPU1_P0_PERST_N")
		)
		(pad "F34" smd circle
			(at 10.150094 3.420364)
			(size 0.3048 0.3048)
			(layers "F.Cu" "F.Mask" "F.Paste")
			(net "RT_CPU1_P0_ADDR1")
		)
		(pad "FA15" smd circle
			(at -9.59739 -0.738886)
			(size 0.381 0.381)
			(layers "F.Cu" "F.Mask" "F.Paste")
			(net "GND")
		)
		(pad "FA32" smd circle
			(at -9.59739 2.724912)
			(size 0.381 0.381)
			(layers "F.Cu" "F.Mask" "F.Paste")
			(net "GND")
		)
		(pad "FB2" smd circle
			(at -9.649968 -3.41884)
			(size 0.3048 0.3048)
			(layers "F.Cu" "F.Mask" "F.Paste")
			(net "GND")
		)
		(pad "FB34" smd circle
			(at -9.649968 3.420364)
			(size 0.3048 0.3048)
			(layers "F.Cu" "F.Mask" "F.Paste")
			(net "GND")
		)
		(pad "FC3" smd circle
			(at -9.846818 -2.888488)
			(size 0.3048 0.3048)
			(layers "F.Cu" "F.Mask" "F.Paste")
			(net "GND")
		)
		(pad "FC6" smd circle
			(at -9.846818 -2.288286)
			(size 0.3048 0.3048)
			(layers "F.Cu" "F.Mask" "F.Paste")
			(net "GND")
		)
		(pad "FC9" smd circle
			(at -9.846818 -1.688338)
			(size 0.3048 0.3048)
			(layers "F.Cu" "F.Mask" "F.Paste")
			(net "GND")
		)
		(pad "FC19" smd circle
			(at -9.846818 0.111506)
			(size 0.3048 0.3048)
			(layers "F.Cu" "F.Mask" "F.Paste")
			(net "GND")
		)
		(pad "FC23" smd circle
			(at -9.846818 0.711708)
			(size 0.3048 0.3048)
			(layers "F.Cu" "F.Mask" "F.Paste")
			(net "GND")
		)
		(pad "FC25" smd circle
			(at -9.846818 1.311656)
			(size 0.3048 0.3048)
			(layers "F.Cu" "F.Mask" "F.Paste")
			(net "GND")
		)
		(pad "FC28" smd circle
			(at -9.846818 1.911604)
			(size 0.3048 0.3048)
			(layers "F.Cu" "F.Mask" "F.Paste")
			(net "GND")
		)
		(pad "FD1" smd oval
			(at -9.949942 -3.938524)
			(size 0.254 0.3302)
			(layers "F.Cu" "F.Mask" "F.Paste")
			(net "GND")
		)
		(pad "FD35" smd oval
			(at -9.949942 3.940048)
			(size 0.254 0.3302)
			(layers "F.Cu" "F.Mask" "F.Paste")
			(net "GND")
		)
		(pad "FE2" smd circle
			(at -10.249916 -3.41884)
			(size 0.3048 0.3048)
			(layers "F.Cu" "F.Mask" "F.Paste")
			(net "NCF_CPU1_P0_GND")
		)
		(pad "FE34" smd circle
			(at -10.249916 3.420364)
			(size 0.3048 0.3048)
			(layers "F.Cu" "F.Mask" "F.Paste")
			(net "NCF_CPU1_P0_GND")
		)
		(pad "FF5" smd circle
			(at -10.366248 -2.588514)
			(size 0.3048 0.3048)
			(layers "F.Cu" "F.Mask" "F.Paste")
			(net "SMB_RT_CPU1_P0_ROM_MUX_1D_R_SCL")
		)
		(pad "FF8" smd circle
			(at -10.366248 -1.988312)
			(size 0.3048 0.3048)
			(layers "F.Cu" "F.Mask" "F.Paste")
			(net "JTAG_TEST_MODE_RT_CPU1_P0")
		)
		(pad "FF11" smd circle
			(at -10.366248 -1.388364)
			(size 0.3048 0.3048)
			(layers "F.Cu" "F.Mask" "F.Paste")
			(net "RST_RT_CPU1_P0_RESET_N")
		)
		(pad "FF14" smd circle
			(at -10.366248 -0.788416)
			(size 0.3048 0.3048)
			(layers "F.Cu" "F.Mask" "F.Paste")
			(net "GND")
		)
		(pad "FF18" smd circle
			(at -10.366248 -0.188468)
			(size 0.3048 0.3048)
			(layers "F.Cu" "F.Mask" "F.Paste")
			(net "CLK_100M_RETIMER_CPU1_P0_DN")
		)
		(pad "FF21" smd circle
			(at -10.366248 0.41148)
			(size 0.3048 0.3048)
			(layers "F.Cu" "F.Mask" "F.Paste")
			(net "GND")
		)
		(pad "FF24" smd circle
			(at -10.366248 1.011682)
			(size 0.3048 0.3048)
			(layers "F.Cu" "F.Mask" "F.Paste")
			(net "TEST0_RT_CPU1_P0")
		)
		(pad "FF27" smd circle
			(at -10.366248 1.61163)
			(size 0.3048 0.3048)
			(layers "F.Cu" "F.Mask" "F.Paste")
			(net "TEST1_RT_CPU1_P0")
		)
		(pad "FF30" smd circle
			(at -10.366248 2.211578)
			(size 0.3048 0.3048)
			(layers "F.Cu" "F.Mask" "F.Paste")
			(net "TEST2_RT_CPU1_P0")
		)
		(pad "FF33" smd circle
			(at -10.366248 2.811526)
			(size 0.3048 0.3048)
			(layers "F.Cu" "F.Mask" "F.Paste")
			(net "RT_CPU1_P0_SCAN_MODE")
		)
		(pad "FG1" smd oval
			(at -10.54989 -3.938524)
			(size 0.254 0.3302)
			(layers "F.Cu" "F.Mask" "F.Paste")
			(net "NCF_CPU1_P0_GND")
		)
		(pad "FG35" smd oval
			(at -10.54989 3.940048)
			(size 0.254 0.3302)
			(layers "F.Cu" "F.Mask" "F.Paste")
			(net "NCF_CPU1_P0_GND")
		)
		(pad "FH2" smd circle
			(at -10.850118 -3.41884)
			(size 0.3048 0.3048)
			(layers "F.Cu" "F.Mask" "F.Paste")
			(net "NCF_CPU1_P0_GND")
		)
		(pad "FH34" smd circle
			(at -10.850118 3.420364)
			(size 0.3048 0.3048)
			(layers "F.Cu" "F.Mask" "F.Paste")
			(net "NCF_CPU1_P0_GND")
		)
		(pad "FJ3" smd oval
			(at -10.885932 -2.888488 90)
			(size 0.254 0.3302)
			(layers "F.Cu" "F.Mask" "F.Paste")
			(net "SMB_RT_CPU1_P0_ROM_MUX_1D_R_SDA")
		)
		(pad "FJ6" smd oval
			(at -10.885932 -2.288286 90)
			(size 0.254 0.3302)
			(layers "F.Cu" "F.Mask" "F.Paste")
			(net "Net_561")
		)
		(pad "FJ9" smd oval
			(at -10.885932 -1.688338 90)
			(size 0.254 0.3302)
			(layers "F.Cu" "F.Mask" "F.Paste")
			(net "MODE_RT_CPU1_P0")
		)
		(pad "FJ12" smd oval
			(at -10.885932 -1.08839 90)
			(size 0.254 0.3302)
			(layers "F.Cu" "F.Mask" "F.Paste")
			(net "GND")
		)
		(pad "FJ16" smd oval
			(at -10.885932 -0.488442 90)
			(size 0.254 0.3302)
			(layers "F.Cu" "F.Mask" "F.Paste")
			(net "CLK_100M_RETIMER_CPU1_P0_DP")
		)
		(pad "FJ19" smd oval
			(at -10.885932 0.111506 90)
			(size 0.254 0.3302)
			(layers "F.Cu" "F.Mask" "F.Paste")
			(net "GND")
		)
		(pad "FJ23" smd oval
			(at -10.885932 0.711708 90)
			(size 0.254 0.3302)
			(layers "F.Cu" "F.Mask" "F.Paste")
			(net "Net_562")
		)
		(pad "FJ25" smd oval
			(at -10.885932 1.311656 90)
			(size 0.254 0.3302)
			(layers "F.Cu" "F.Mask" "F.Paste")
			(net "GPIO2_RT_CPU1_P0")
		)
		(pad "FJ28" smd oval
			(at -10.885932 1.911604 90)
			(size 0.254 0.3302)
			(layers "F.Cu" "F.Mask" "F.Paste")
			(net "GPIO3_RT_CPU1_P0")
		)
		(pad "FJ31" smd oval
			(at -10.885932 2.511552 90)
			(size 0.254 0.3302)
			(layers "F.Cu" "F.Mask" "F.Paste")
			(net "Net_54")
		)
		(pad "G1" smd oval
			(at 9.85012 -3.938524)
			(size 0.254 0.3302)
			(layers "F.Cu" "F.Mask" "F.Paste")
			(net "RT_CPU1_P0_VQPS")
		)
		(pad "G35" smd oval
			(at 9.85012 3.940048)
			(size 0.254 0.3302)
			(layers "F.Cu" "F.Mask" "F.Paste")
			(net "CLKREQ_RT_CPU1_P0_N")
		)
		(pad "H12" smd circle
			(at 9.846818 -1.08839)
			(size 0.3048 0.3048)
			(layers "F.Cu" "F.Mask" "F.Paste")
			(net "GND")
		)
		(pad "H16" smd circle
			(at 9.846818 -0.488442)
			(size 0.3048 0.3048)
			(layers "F.Cu" "F.Mask" "F.Paste")
			(net "GND")
		)
		(pad "H19" smd circle
			(at 9.846818 0.111506)
			(size 0.3048 0.3048)
			(layers "F.Cu" "F.Mask" "F.Paste")
			(net "GND")
		)
		(pad "H31" smd circle
			(at 9.846818 2.511552)
			(size 0.3048 0.3048)
			(layers "F.Cu" "F.Mask" "F.Paste")
			(net "GND")
		)
		(pad "J4" smd circle
			(at 9.602724 -2.817368)
			(size 0.381 0.381)
			(layers "F.Cu" "F.Mask" "F.Paste")
			(net "GND")
		)
		(pad "J22" smd circle
			(at 9.602724 0.703834)
			(size 0.3048 0.3048)
			(layers "F.Cu" "F.Mask" "F.Paste")
			(net "GND")
		)
		(pad "K2" smd circle
			(at 9.549892 -3.41884)
			(size 0.3048 0.3048)
			(layers "F.Cu" "F.Mask" "F.Paste")
			(net "GND")
		)
		(pad "K34" smd circle
			(at 9.549892 3.420364)
			(size 0.3048 0.3048)
			(layers "F.Cu" "F.Mask" "F.Paste")
			(net "GND")
		)
		(pad "L1" smd oval
			(at 9.249918 -3.938524)
			(size 0.254 0.3302)
			(layers "F.Cu" "F.Mask" "F.Paste")
			(net "GND")
		)
		(pad "L35" smd oval
			(at 9.249918 3.940048)
			(size 0.254 0.3302)
			(layers "F.Cu" "F.Mask" "F.Paste")
			(net "GND")
		)
		(pad "M7" smd circle
			(at 9.202674 -2.12471)
			(size 0.381 0.381)
			(layers "F.Cu" "F.Mask" "F.Paste")
			(net "P5E_CPU1_P0_TX_BUF_DP<15>")
		)
		(pad "M26" smd circle
			(at 9.202674 1.339342)
			(size 0.381 0.381)
			(layers "F.Cu" "F.Mask" "F.Paste")
			(net "P5E_CPU1_P0_RX_DP<15>")
		)
		(pad "N2" smd circle
			(at 8.949944 -3.41884)
			(size 0.3048 0.3048)
			(layers "F.Cu" "F.Mask" "F.Paste")
			(net "P5E_CPU1_P0_RX_BUF_DN<15>")
		)
		(pad "N34" smd circle
			(at 8.949944 3.420364)
			(size 0.3048 0.3048)
			(layers "F.Cu" "F.Mask" "F.Paste")
			(net "P5E_CPU1_P0_TX_C_DN<15>")
		)
		(pad "P10" smd circle
			(at 8.802624 -1.431798)
			(size 0.381 0.381)
			(layers "F.Cu" "F.Mask" "F.Paste")
			(net "P5E_CPU1_P0_TX_BUF_DN<15>")
		)
		(pad "P29" smd circle
			(at 8.802624 2.032254)
			(size 0.381 0.381)
			(layers "F.Cu" "F.Mask" "F.Paste")
			(net "P5E_CPU1_P0_RX_DN<15>")
		)
		(pad "R1" smd oval
			(at 8.64997 -3.938524)
			(size 0.254 0.3302)
			(layers "F.Cu" "F.Mask" "F.Paste")
			(net "P5E_CPU1_P0_RX_BUF_DP<15>")
		)
		(pad "R35" smd oval
			(at 8.64997 3.940048)
			(size 0.254 0.3302)
			(layers "F.Cu" "F.Mask" "F.Paste")
			(net "P5E_CPU1_P0_TX_C_DP<15>")
		)
		(pad "T4" smd circle
			(at 8.402574 -2.817368)
			(size 0.381 0.381)
			(layers "F.Cu" "F.Mask" "F.Paste")
			(net "GND")
		)
		(pad "T13" smd circle
			(at 8.402574 -0.79629)
			(size 0.3048 0.3048)
			(layers "F.Cu" "F.Mask" "F.Paste")
			(net "GND")
		)
		(pad "T17" smd circle
			(at 8.402574 -0.296164)
			(size 0.3048 0.3048)
			(layers "F.Cu" "F.Mask" "F.Paste")
			(net "P0V9_CPU1_RT0_2A")
		)
		(pad "T20" smd circle
			(at 8.402574 0.203708)
			(size 0.3048 0.3048)
			(layers "F.Cu" "F.Mask" "F.Paste")
			(net "P0V9_CPU1_RT0_2A")
		)
		(pad "T22" smd circle
			(at 8.402574 0.703834)
			(size 0.3048 0.3048)
			(layers "F.Cu" "F.Mask" "F.Paste")
			(net "GND")
		)
		(pad "T32" smd circle
			(at 8.402574 2.724912)
			(size 0.381 0.381)
			(layers "F.Cu" "F.Mask" "F.Paste")
			(net "GND")
		)
		(pad "U2" smd circle
			(at 8.349996 -3.41884)
			(size 0.3048 0.3048)
			(layers "F.Cu" "F.Mask" "F.Paste")
			(net "GND")
		)
		(pad "U34" smd circle
			(at 8.349996 3.420364)
			(size 0.3048 0.3048)
			(layers "F.Cu" "F.Mask" "F.Paste")
			(net "GND")
		)
		(pad "V1" smd oval
			(at 8.050022 -3.938524)
			(size 0.254 0.3302)
			(layers "F.Cu" "F.Mask" "F.Paste")
			(net "GND")
		)
		(pad "V35" smd oval
			(at 8.050022 3.940048)
			(size 0.254 0.3302)
			(layers "F.Cu" "F.Mask" "F.Paste")
			(net "GND")
		)
		(pad "W7" smd circle
			(at 8.002524 -2.12471)
			(size 0.381 0.381)
			(layers "F.Cu" "F.Mask" "F.Paste")
			(net "P5E_CPU1_P0_TX_BUF_DP<14>")
		)
		(pad "W26" smd circle
			(at 8.002524 1.339342)
			(size 0.381 0.381)
			(layers "F.Cu" "F.Mask" "F.Paste")
			(net "P5E_CPU1_P0_RX_DP<14>")
		)
		(pad "Y2" smd circle
			(at 7.750048 -3.41884)
			(size 0.3048 0.3048)
			(layers "F.Cu" "F.Mask" "F.Paste")
			(net "P5E_CPU1_P0_RX_BUF_DN<14>")
		)
		(pad "Y34" smd circle
			(at 7.750048 3.420364)
			(size 0.3048 0.3048)
			(layers "F.Cu" "F.Mask" "F.Paste")
			(net "P5E_CPU1_P0_TX_C_DN<14>")
		)
	)
	(footprint ""
		(layer "F.Cu")
		(at 352.298 -407.8732 90)
		(property "Reference" "R1471"
			(at 0 0 90)
			(layer "F.SilkS")
			(hide yes)
			(effects
				(font
					(size 1.27 1.27)
				)
			)
		)
		(property "Value" ""
			(at 0 0 90)
			(layer "F.Fab")
			(effects
				(font
					(size 1.27 1.27)
				)
			)
		)
		(duplicate_pad_numbers_are_jumpers no)
		(fp_line
			(start 0.32512 -0.175006)
			(end 0.32512 0.175006)
			(stroke
				(width 0.1)
				(type default)
			)
			(layer "F.Fab")
		)
		(fp_line
			(start -0.32512 -0.175006)
			(end 0.32512 -0.175006)
			(stroke
				(width 0.1)
				(type default)
			)
			(layer "F.Fab")
		)
		(fp_line
			(start 0.32512 0.175006)
			(end -0.32512 0.175006)
			(stroke
				(width 0.1)
				(type default)
			)
			(layer "F.Fab")
		)
		(fp_line
			(start -0.32512 0.175006)
			(end -0.32512 -0.175006)
			(stroke
				(width 0.1)
				(type default)
			)
			(layer "F.Fab")
		)
		(pad "1" smd rect
			(at -0.2667 0 90)
			(size 0.3048 0.381)
			(layers "F.Cu" "F.Mask" "F.Paste")
			(net "P1V8_CPU0_RT_1D")
		)
		(pad "2" smd rect
			(at 0.2667 0 270)
			(size 0.3048 0.381)
			(layers "F.Cu" "F.Mask" "F.Paste")
			(net "JTAG_TMS_RT_CPU0_P1")
		)
	)
	(footprint ""
		(layer "F.Cu")
		(at 348.052136 -147.904962)
		(property "Reference" "H54"
			(at -3.9116 -3.83413 0)
			(unlocked yes)
			(layer "F.SilkS")
			(effects
				(font
					(size 0.7874 0.5842)
					(thickness 0.1524)
				)
				(justify left)
			)
		)
		(property "Value" ""
			(at 0 0 0)
			(layer "F.Fab")
			(effects
				(font
					(size 1.27 1.27)
				)
			)
		)
		(duplicate_pad_numbers_are_jumpers no)
		(pad "1" thru_hole circle
			(at 0 0)
			(size 6.1976 6.1976)
			(drill 3.7338)
			(layers "*.Cu" "*.Mask")
			(remove_unused_layers no)
			(net "GND")
			(clearance -0.9779)
			(padstack
				(mode front_inner_back)
				(layer "Inner"
					(shape circle)
					(size 5.5372 5.5372)
					(clearance -0.6477)
				)
				(layer "B.Cu"
					(shape circle)
					(size 6.1976 6.1976)
					(clearance -0.9779)
				)
			)
		)
	)
	(footprint ""
		(layer "F.Cu")
		(at 213.889844 -125.643894)
		(property "Reference" "R899"
			(at 0 0 0)
			(layer "F.SilkS")
			(hide yes)
			(effects
				(font
					(size 1.27 1.27)
				)
			)
		)
		(property "Value" ""
			(at 0 0 0)
			(layer "F.Fab")
			(effects
				(font
					(size 1.27 1.27)
				)
			)
		)
		(duplicate_pad_numbers_are_jumpers no)
		(fp_line
			(start -0.7874 -0.4064)
			(end 0.7874 -0.4064)
			(stroke
				(width 0.1524)
				(type default)
			)
			(layer "F.SilkS")
		)
		(fp_line
			(start -0.7874 0.4064)
			(end -0.7874 -0.4064)
			(stroke
				(width 0.1524)
				(type default)
			)
			(layer "F.SilkS")
		)
		(fp_line
			(start 0.7874 -0.4064)
			(end 0.7874 0.4064)
			(stroke
				(width 0.1524)
				(type default)
			)
			(layer "F.SilkS")
		)
		(fp_line
			(start 0.7874 0.4064)
			(end -0.7874 0.4064)
			(stroke
				(width 0.1524)
				(type default)
			)
			(layer "F.SilkS")
		)
		(fp_line
			(start -0.67945 -0.305054)
			(end -0.12065 -0.305054)
			(stroke
				(width 0.1)
				(type default)
			)
			(layer "F.Fab")
		)
		(fp_line
			(start -0.67945 0.3048)
			(end -0.67945 -0.305054)
			(stroke
				(width 0.1)
				(type default)
			)
			(layer "F.Fab")
		)
		(fp_line
			(start -0.12065 -0.305054)
			(end -0.12065 -0.2794)
			(stroke
				(width 0.1)
				(type default)
			)
			(layer "F.Fab")
		)
		(fp_line
			(start -0.12065 -0.2794)
			(end 0.12065 -0.2794)
			(stroke
				(width 0.1)
				(type default)
			)
			(layer "F.Fab")
		)
		(fp_line
			(start -0.12065 0.2794)
			(end -0.12065 0.3048)
			(stroke
				(width 0.1)
				(type default)
			)
			(layer "F.Fab")
		)
		(fp_line
			(start -0.12065 0.3048)
			(end -0.67945 0.3048)
			(stroke
				(width 0.1)
				(type default)
			)
			(layer "F.Fab")
		)
		(fp_line
			(start 0.120396 0.2794)
			(end -0.12065 0.2794)
			(stroke
				(width 0.1)
				(type default)
			)
			(layer "F.Fab")
		)
		(fp_line
			(start 0.120396 0.3048)
			(end 0.120396 0.2794)
			(stroke
				(width 0.1)
				(type default)
			)
			(layer "F.Fab")
		)
		(fp_line
			(start 0.12065 -0.3048)
			(end 0.67945 -0.3048)
			(stroke
				(width 0.1)
				(type default)
			)
			(layer "F.Fab")
		)
		(fp_line
			(start 0.12065 -0.2794)
			(end 0.12065 -0.3048)
			(stroke
				(width 0.1)
				(type default)
			)
			(layer "F.Fab")
		)
		(fp_line
			(start 0.67945 -0.3048)
			(end 0.67945 0.3048)
			(stroke
				(width 0.1)
				(type default)
			)
			(layer "F.Fab")
		)
		(fp_line
			(start 0.67945 0.3048)
			(end 0.120396 0.3048)
			(stroke
				(width 0.1)
				(type default)
			)
			(layer "F.Fab")
		)
		(pad "1" smd circle
			(at -0.40005 0)
			(size 0 0)
			(layers "F.Cu" "F.Mask" "F.Paste")
			(net "RST_PERST_OCP_SFF_BUF2_N")
		)
		(pad "2" smd circle
			(at 0.40005 0)
			(size 0 0)
			(layers "F.Cu" "F.Mask" "F.Paste")
			(net "RST_PERST1_OCP_SFF_N")
		)
	)
	(footprint ""
		(layer "F.Cu")
		(at 184.622694 -410.144722)
		(property "Reference" "R8027"
			(at 0 0 0)
			(layer "F.SilkS")
			(hide yes)
			(effects
				(font
					(size 1.27 1.27)
				)
			)
		)
		(property "Value" ""
			(at 0 0 0)
			(layer "F.Fab")
			(effects
				(font
					(size 1.27 1.27)
				)
			)
		)
		(duplicate_pad_numbers_are_jumpers no)
		(fp_line
			(start -0.7874 -0.4064)
			(end 0.7874 -0.4064)
			(stroke
				(width 0.1524)
				(type default)
			)
			(layer "F.SilkS")
		)
		(fp_line
			(start -0.7874 0.4064)
			(end -0.7874 -0.4064)
			(stroke
				(width 0.1524)
				(type default)
			)
			(layer "F.SilkS")
		)
		(fp_line
			(start 0.7874 -0.4064)
			(end 0.7874 0.4064)
			(stroke
				(width 0.1524)
				(type default)
			)
			(layer "F.SilkS")
		)
		(fp_line
			(start 0.7874 0.4064)
			(end -0.7874 0.4064)
			(stroke
				(width 0.1524)
				(type default)
			)
			(layer "F.SilkS")
		)
		(fp_line
			(start -0.67945 -0.305054)
			(end -0.12065 -0.305054)
			(stroke
				(width 0.1)
				(type default)
			)
			(layer "F.Fab")
		)
		(fp_line
			(start -0.67945 0.3048)
			(end -0.67945 -0.305054)
			(stroke
				(width 0.1)
				(type default)
			)
			(layer "F.Fab")
		)
		(fp_line
			(start -0.12065 -0.305054)
			(end -0.12065 -0.2794)
			(stroke
				(width 0.1)
				(type default)
			)
			(layer "F.Fab")
		)
		(fp_line
			(start -0.12065 -0.2794)
			(end 0.12065 -0.2794)
			(stroke
				(width 0.1)
				(type default)
			)
			(layer "F.Fab")
		)
		(fp_line
			(start -0.12065 0.2794)
			(end -0.12065 0.3048)
			(stroke
				(width 0.1)
				(type default)
			)
			(layer "F.Fab")
		)
		(fp_line
			(start -0.12065 0.3048)
			(end -0.67945 0.3048)
			(stroke
				(width 0.1)
				(type default)
			)
			(layer "F.Fab")
		)
		(fp_line
			(start 0.120396 0.2794)
			(end -0.12065 0.2794)
			(stroke
				(width 0.1)
				(type default)
			)
			(layer "F.Fab")
		)
		(fp_line
			(start 0.120396 0.3048)
			(end 0.120396 0.2794)
			(stroke
				(width 0.1)
				(type default)
			)
			(layer "F.Fab")
		)
		(fp_line
			(start 0.12065 -0.3048)
			(end 0.67945 -0.3048)
			(stroke
				(width 0.1)
				(type default)
			)
			(layer "F.Fab")
		)
		(fp_line
			(start 0.12065 -0.2794)
			(end 0.12065 -0.3048)
			(stroke
				(width 0.1)
				(type default)
			)
			(layer "F.Fab")
		)
		(fp_line
			(start 0.67945 -0.3048)
			(end 0.67945 0.3048)
			(stroke
				(width 0.1)
				(type default)
			)
			(layer "F.Fab")
		)
		(fp_line
			(start 0.67945 0.3048)
			(end 0.120396 0.3048)
			(stroke
				(width 0.1)
				(type default)
			)
			(layer "F.Fab")
		)
		(pad "1" smd circle
			(at -0.40005 0)
			(size 0 0)
			(layers "F.Cu" "F.Mask" "F.Paste")
			(net "LED_P12V_PSU_R3")
		)
		(pad "2" smd circle
			(at 0.40005 0)
			(size 0 0)
			(layers "F.Cu" "F.Mask" "F.Paste")
			(net "P12V_PSU")
		)
	)
	(footprint ""
		(layer "F.Cu")
		(at 314.305696 -378.95403 -90)
		(property "Reference" "C915"
			(at 0 0 270)
			(layer "F.SilkS")
			(hide yes)
			(effects
				(font
					(size 1.27 1.27)
				)
			)
		)
		(property "Value" ""
			(at 0 0 270)
			(layer "F.Fab")
			(effects
				(font
					(size 1.27 1.27)
				)
			)
		)
		(duplicate_pad_numbers_are_jumpers no)
		(fp_line
			(start -0.299974 0.150114)
			(end -0.299974 -0.150114)
			(stroke
				(width 0.1)
				(type default)
			)
			(layer "F.Fab")
		)
		(fp_line
			(start 0.299974 0.150114)
			(end -0.299974 0.150114)
			(stroke
				(width 0.1)
				(type default)
			)
			(layer "F.Fab")
		)
		(fp_line
			(start -0.299974 -0.150114)
			(end 0.299974 -0.150114)
			(stroke
				(width 0.1)
				(type default)
			)
			(layer "F.Fab")
		)
		(fp_line
			(start 0.299974 -0.150114)
			(end 0.299974 0.150114)
			(stroke
				(width 0.1)
				(type default)
			)
			(layer "F.Fab")
		)
		(pad "1" smd rect
			(at -0.2667 0 270)
			(size 0.3048 0.381)
			(layers "F.Cu" "F.Mask" "F.Paste")
			(net "P5E_CPU0_P0_TX_C_DP<9>")
		)
		(pad "2" smd rect
			(at 0.2667 0 270)
			(size 0.3048 0.381)
			(layers "F.Cu" "F.Mask" "F.Paste")
			(net "P5E_CPU0_P0_TX_DP<9>")
		)
	)
	(footprint ""
		(layer "F.Cu")
		(at 180.457856 -139.947142 -90)
		(property "Reference" "R6740"
			(at 0 0 270)
			(layer "F.SilkS")
			(hide yes)
			(effects
				(font
					(size 1.27 1.27)
				)
			)
		)
		(property "Value" ""
			(at 0 0 270)
			(layer "F.Fab")
			(effects
				(font
					(size 1.27 1.27)
				)
			)
		)
		(duplicate_pad_numbers_are_jumpers no)
		(fp_line
			(start -0.7874 0.4064)
			(end -0.7874 -0.4064)
			(stroke
				(width 0.1524)
				(type default)
			)
			(layer "F.SilkS")
		)
		(fp_line
			(start 0.7874 0.4064)
			(end -0.7874 0.4064)
			(stroke
				(width 0.1524)
				(type default)
			)
			(layer "F.SilkS")
		)
		(fp_line
			(start -0.7874 -0.4064)
			(end 0.7874 -0.4064)
			(stroke
				(width 0.1524)
				(type default)
			)
			(layer "F.SilkS")
		)
		(fp_line
			(start 0.7874 -0.4064)
			(end 0.7874 0.4064)
			(stroke
				(width 0.1524)
				(type default)
			)
			(layer "F.SilkS")
		)
		(fp_line
			(start -0.67945 0.3048)
			(end -0.67945 -0.305054)
			(stroke
				(width 0.1)
				(type default)
			)
			(layer "F.Fab")
		)
		(fp_line
			(start -0.12065 0.3048)
			(end -0.67945 0.3048)
			(stroke
				(width 0.1)
				(type default)
			)
			(layer "F.Fab")
		)
		(fp_line
			(start 0.120396 0.3048)
			(end 0.120396 0.2794)
			(stroke
				(width 0.1)
				(type default)
			)
			(layer "F.Fab")
		)
		(fp_line
			(start 0.67945 0.3048)
			(end 0.120396 0.3048)
			(stroke
				(width 0.1)
				(type default)
			)
			(layer "F.Fab")
		)
		(fp_line
			(start -0.12065 0.2794)
			(end -0.12065 0.3048)
			(stroke
				(width 0.1)
				(type default)
			)
			(layer "F.Fab")
		)
		(fp_line
			(start 0.120396 0.2794)
			(end -0.12065 0.2794)
			(stroke
				(width 0.1)
				(type default)
			)
			(layer "F.Fab")
		)
		(fp_line
			(start -0.12065 -0.2794)
			(end 0.12065 -0.2794)
			(stroke
				(width 0.1)
				(type default)
			)
			(layer "F.Fab")
		)
		(fp_line
			(start 0.12065 -0.2794)
			(end 0.12065 -0.3048)
			(stroke
				(width 0.1)
				(type default)
			)
			(layer "F.Fab")
		)
		(fp_line
			(start 0.12065 -0.3048)
			(end 0.67945 -0.3048)
			(stroke
				(width 0.1)
				(type default)
			)
			(layer "F.Fab")
		)
		(fp_line
			(start 0.67945 -0.3048)
			(end 0.67945 0.3048)
			(stroke
				(width 0.1)
				(type default)
			)
			(layer "F.Fab")
		)
		(fp_line
			(start -0.67945 -0.305054)
			(end -0.12065 -0.305054)
			(stroke
				(width 0.1)
				(type default)
			)
			(layer "F.Fab")
		)
		(fp_line
			(start -0.12065 -0.305054)
			(end -0.12065 -0.2794)
			(stroke
				(width 0.1)
				(type default)
			)
			(layer "F.Fab")
		)
		(pad "1" smd circle
			(at -0.40005 0 270)
			(size 0 0)
			(layers "F.Cu" "F.Mask" "F.Paste")
			(net "RST_RT_CPU1_P1_PERST_R_N")
		)
		(pad "2" smd circle
			(at 0.40005 0 270)
			(size 0 0)
			(layers "F.Cu" "F.Mask" "F.Paste")
			(net "RST_RT_CPU1_P1_PERST_R2_N")
		)
	)
	(footprint ""
		(layer "F.Cu")
		(at 365.701326 -43.235118 -90)
		(property "Reference" "R817"
			(at 0 0 270)
			(layer "F.SilkS")
			(hide yes)
			(effects
				(font
					(size 1.27 1.27)
				)
			)
		)
		(property "Value" ""
			(at 0 0 270)
			(layer "F.Fab")
			(effects
				(font
					(size 1.27 1.27)
				)
			)
		)
		(duplicate_pad_numbers_are_jumpers no)
		(fp_line
			(start -0.7874 0.4064)
			(end -0.7874 -0.4064)
			(stroke
				(width 0.1524)
				(type default)
			)
			(layer "F.SilkS")
		)
		(fp_line
			(start 0.7874 0.4064)
			(end -0.7874 0.4064)
			(stroke
				(width 0.1524)
				(type default)
			)
			(layer "F.SilkS")
		)
		(fp_line
			(start -0.7874 -0.4064)
			(end 0.7874 -0.4064)
			(stroke
				(width 0.1524)
				(type default)
			)
			(layer "F.SilkS")
		)
		(fp_line
			(start 0.7874 -0.4064)
			(end 0.7874 0.4064)
			(stroke
				(width 0.1524)
				(type default)
			)
			(layer "F.SilkS")
		)
		(fp_line
			(start -0.67945 0.3048)
			(end -0.67945 -0.305054)
			(stroke
				(width 0.1)
				(type default)
			)
			(layer "F.Fab")
		)
		(fp_line
			(start -0.12065 0.3048)
			(end -0.67945 0.3048)
			(stroke
				(width 0.1)
				(type default)
			)
			(layer "F.Fab")
		)
		(fp_line
			(start 0.120396 0.3048)
			(end 0.120396 0.2794)
			(stroke
				(width 0.1)
				(type default)
			)
			(layer "F.Fab")
		)
		(fp_line
			(start 0.67945 0.3048)
			(end 0.120396 0.3048)
			(stroke
				(width 0.1)
				(type default)
			)
			(layer "F.Fab")
		)
		(fp_line
			(start -0.12065 0.2794)
			(end -0.12065 0.3048)
			(stroke
				(width 0.1)
				(type default)
			)
			(layer "F.Fab")
		)
		(fp_line
			(start 0.120396 0.2794)
			(end -0.12065 0.2794)
			(stroke
				(width 0.1)
				(type default)
			)
			(layer "F.Fab")
		)
		(fp_line
			(start -0.12065 -0.2794)
			(end 0.12065 -0.2794)
			(stroke
				(width 0.1)
				(type default)
			)
			(layer "F.Fab")
		)
		(fp_line
			(start 0.12065 -0.2794)
			(end 0.12065 -0.3048)
			(stroke
				(width 0.1)
				(type default)
			)
			(layer "F.Fab")
		)
		(fp_line
			(start 0.12065 -0.3048)
			(end 0.67945 -0.3048)
			(stroke
				(width 0.1)
				(type default)
			)
			(layer "F.Fab")
		)
		(fp_line
			(start 0.67945 -0.3048)
			(end 0.67945 0.3048)
			(stroke
				(width 0.1)
				(type default)
			)
			(layer "F.Fab")
		)
		(fp_line
			(start -0.67945 -0.305054)
			(end -0.12065 -0.305054)
			(stroke
				(width 0.1)
				(type default)
			)
			(layer "F.Fab")
		)
		(fp_line
			(start -0.12065 -0.305054)
			(end -0.12065 -0.2794)
			(stroke
				(width 0.1)
				(type default)
			)
			(layer "F.Fab")
		)
		(pad "1" smd circle
			(at -0.40005 0 270)
			(size 0 0)
			(layers "F.Cu" "F.Mask" "F.Paste")
			(net "UART_CPU0_UART0_RX")
		)
		(pad "2" smd circle
			(at 0.40005 0 270)
			(size 0 0)
			(layers "F.Cu" "F.Mask" "F.Paste")
			(net "UART_CPU0_UART0_R_RX")
		)
	)
	(footprint ""
		(layer "F.Cu")
		(at 253.506224 -134.892796 180)
		(property "Reference" "R608"
			(at 0 0 180)
			(layer "F.SilkS")
			(hide yes)
			(effects
				(font
					(size 1.27 1.27)
				)
			)
		)
		(property "Value" ""
			(at 0 0 180)
			(layer "F.Fab")
			(effects
				(font
					(size 1.27 1.27)
				)
			)
		)
		(duplicate_pad_numbers_are_jumpers no)
		(fp_line
			(start 0.7874 0.4064)
			(end -0.7874 0.4064)
			(stroke
				(width 0.1524)
				(type default)
			)
			(layer "F.SilkS")
		)
		(fp_line
			(start 0.7874 -0.4064)
			(end 0.7874 0.4064)
			(stroke
				(width 0.1524)
				(type default)
			)
			(layer "F.SilkS")
		)
		(fp_line
			(start -0.7874 0.4064)
			(end -0.7874 -0.4064)
			(stroke
				(width 0.1524)
				(type default)
			)
			(layer "F.SilkS")
		)
		(fp_line
			(start -0.7874 -0.4064)
			(end 0.7874 -0.4064)
			(stroke
				(width 0.1524)
				(type default)
			)
			(layer "F.SilkS")
		)
		(fp_line
			(start 0.67945 0.3048)
			(end 0.120396 0.3048)
			(stroke
				(width 0.1)
				(type default)
			)
			(layer "F.Fab")
		)
		(fp_line
			(start 0.67945 -0.3048)
			(end 0.67945 0.3048)
			(stroke
				(width 0.1)
				(type default)
			)
			(layer "F.Fab")
		)
		(fp_line
			(start 0.12065 -0.2794)
			(end 0.12065 -0.3048)
			(stroke
				(width 0.1)
				(type default)
			)
			(layer "F.Fab")
		)
		(fp_line
			(start 0.12065 -0.3048)
			(end 0.67945 -0.3048)
			(stroke
				(width 0.1)
				(type default)
			)
			(layer "F.Fab")
		)
		(fp_line
			(start 0.120396 0.3048)
			(end 0.120396 0.2794)
			(stroke
				(width 0.1)
				(type default)
			)
			(layer "F.Fab")
		)
		(fp_line
			(start 0.120396 0.2794)
			(end -0.12065 0.2794)
			(stroke
				(width 0.1)
				(type default)
			)
			(layer "F.Fab")
		)
		(fp_line
			(start -0.12065 0.3048)
			(end -0.67945 0.3048)
			(stroke
				(width 0.1)
				(type default)
			)
			(layer "F.Fab")
		)
		(fp_line
			(start -0.12065 0.2794)
			(end -0.12065 0.3048)
			(stroke
				(width 0.1)
				(type default)
			)
			(layer "F.Fab")
		)
		(fp_line
			(start -0.12065 -0.2794)
			(end 0.12065 -0.2794)
			(stroke
				(width 0.1)
				(type default)
			)
			(layer "F.Fab")
		)
		(fp_line
			(start -0.12065 -0.305054)
			(end -0.12065 -0.2794)
			(stroke
				(width 0.1)
				(type default)
			)
			(layer "F.Fab")
		)
		(fp_line
			(start -0.67945 0.3048)
			(end -0.67945 -0.305054)
			(stroke
				(width 0.1)
				(type default)
			)
			(layer "F.Fab")
		)
		(fp_line
			(start -0.67945 -0.305054)
			(end -0.12065 -0.305054)
			(stroke
				(width 0.1)
				(type default)
			)
			(layer "F.Fab")
		)
		(pad "1" smd circle
			(at -0.40005 0 180)
			(size 0 0)
			(layers "F.Cu" "F.Mask" "F.Paste")
			(net "SPI_CPU0_LVC3_R_TPM_CS_N")
		)
		(pad "2" smd circle
			(at 0.40005 0 180)
			(size 0 0)
			(layers "F.Cu" "F.Mask" "F.Paste")
			(net "SPI_CPU0_LVC3_TPM_CS_N")
		)
	)
	(footprint ""
		(layer "F.Cu")
		(at 110.620302 -389.316976 90)
		(property "Reference" "R901"
			(at 0 0 90)
			(layer "F.SilkS")
			(hide yes)
			(effects
				(font
					(size 1.27 1.27)
				)
			)
		)
		(property "Value" ""
			(at 0 0 90)
			(layer "F.Fab")
			(effects
				(font
					(size 1.27 1.27)
				)
			)
		)
		(duplicate_pad_numbers_are_jumpers no)
		(fp_line
			(start 0.32512 -0.175006)
			(end 0.32512 0.175006)
			(stroke
				(width 0.1)
				(type default)
			)
			(layer "F.Fab")
		)
		(fp_line
			(start -0.32512 -0.175006)
			(end 0.32512 -0.175006)
			(stroke
				(width 0.1)
				(type default)
			)
			(layer "F.Fab")
		)
		(fp_line
			(start 0.32512 0.175006)
			(end -0.32512 0.175006)
			(stroke
				(width 0.1)
				(type default)
			)
			(layer "F.Fab")
		)
		(fp_line
			(start -0.32512 0.175006)
			(end -0.32512 -0.175006)
			(stroke
				(width 0.1)
				(type default)
			)
			(layer "F.Fab")
		)
		(pad "1" smd rect
			(at -0.2667 0 90)
			(size 0.3048 0.381)
			(layers "F.Cu" "F.Mask" "F.Paste")
			(net "RST_RT_CPU1_P3_RESET_N")
		)
		(pad "2" smd rect
			(at 0.2667 0 270)
			(size 0.3048 0.381)
			(layers "F.Cu" "F.Mask" "F.Paste")
			(net "RST_RT_CPU1_P3_RESET_R_N")
		)
	)
	(footprint ""
		(layer "F.Cu")
		(at 108.533946 -52.86248 -90)
		(property "Reference" "R6310"
			(at 0 0 270)
			(layer "F.SilkS")
			(hide yes)
			(effects
				(font
					(size 1.27 1.27)
				)
			)
		)
		(property "Value" ""
			(at 0 0 270)
			(layer "F.Fab")
			(effects
				(font
					(size 1.27 1.27)
				)
			)
		)
		(duplicate_pad_numbers_are_jumpers no)
		(fp_line
			(start -0.7874 0.4064)
			(end -0.7874 -0.4064)
			(stroke
				(width 0.1524)
				(type default)
			)
			(layer "F.SilkS")
		)
		(fp_line
			(start 0.7874 0.4064)
			(end -0.7874 0.4064)
			(stroke
				(width 0.1524)
				(type default)
			)
			(layer "F.SilkS")
		)
		(fp_line
			(start -0.7874 -0.4064)
			(end 0.7874 -0.4064)
			(stroke
				(width 0.1524)
				(type default)
			)
			(layer "F.SilkS")
		)
		(fp_line
			(start 0.7874 -0.4064)
			(end 0.7874 0.4064)
			(stroke
				(width 0.1524)
				(type default)
			)
			(layer "F.SilkS")
		)
		(fp_line
			(start -0.67945 0.3048)
			(end -0.67945 -0.305054)
			(stroke
				(width 0.1)
				(type default)
			)
			(layer "F.Fab")
		)
		(fp_line
			(start -0.12065 0.3048)
			(end -0.67945 0.3048)
			(stroke
				(width 0.1)
				(type default)
			)
			(layer "F.Fab")
		)
		(fp_line
			(start 0.120396 0.3048)
			(end 0.120396 0.2794)
			(stroke
				(width 0.1)
				(type default)
			)
			(layer "F.Fab")
		)
		(fp_line
			(start 0.67945 0.3048)
			(end 0.120396 0.3048)
			(stroke
				(width 0.1)
				(type default)
			)
			(layer "F.Fab")
		)
		(fp_line
			(start -0.12065 0.2794)
			(end -0.12065 0.3048)
			(stroke
				(width 0.1)
				(type default)
			)
			(layer "F.Fab")
		)
		(fp_line
			(start 0.120396 0.2794)
			(end -0.12065 0.2794)
			(stroke
				(width 0.1)
				(type default)
			)
			(layer "F.Fab")
		)
		(fp_line
			(start -0.12065 -0.2794)
			(end 0.12065 -0.2794)
			(stroke
				(width 0.1)
				(type default)
			)
			(layer "F.Fab")
		)
		(fp_line
			(start 0.12065 -0.2794)
			(end 0.12065 -0.3048)
			(stroke
				(width 0.1)
				(type default)
			)
			(layer "F.Fab")
		)
		(fp_line
			(start 0.12065 -0.3048)
			(end 0.67945 -0.3048)
			(stroke
				(width 0.1)
				(type default)
			)
			(layer "F.Fab")
		)
		(fp_line
			(start 0.67945 -0.3048)
			(end 0.67945 0.3048)
			(stroke
				(width 0.1)
				(type default)
			)
			(layer "F.Fab")
		)
		(fp_line
			(start -0.67945 -0.305054)
			(end -0.12065 -0.305054)
			(stroke
				(width 0.1)
				(type default)
			)
			(layer "F.Fab")
		)
		(fp_line
			(start -0.12065 -0.305054)
			(end -0.12065 -0.2794)
			(stroke
				(width 0.1)
				(type default)
			)
			(layer "F.Fab")
		)
		(pad "1" smd circle
			(at -0.40005 0 270)
			(size 0 0)
			(layers "F.Cu" "F.Mask" "F.Paste")
			(net "USB_HUB2_TI_OVERCUR1")
		)
		(pad "2" smd circle
			(at 0.40005 0 270)
			(size 0 0)
			(layers "F.Cu" "F.Mask" "F.Paste")
			(net "USB_HUB2_TI_OVERCUR1_MRP_PROG_FUNC4")
		)
	)
	(footprint ""
		(layer "F.Cu")
		(at 373.979694 -177.532284)
		(property "Reference" "PR321"
			(at 0 0 0)
			(layer "F.SilkS")
			(hide yes)
			(effects
				(font
					(size 1.27 1.27)
				)
			)
		)
		(property "Value" ""
			(at 0 0 0)
			(layer "F.Fab")
			(effects
				(font
					(size 1.27 1.27)
				)
			)
		)
		(duplicate_pad_numbers_are_jumpers no)
		(fp_line
			(start -0.7874 -0.4064)
			(end 0.7874 -0.4064)
			(stroke
				(width 0.1524)
				(type default)
			)
			(layer "F.SilkS")
		)
		(fp_line
			(start -0.7874 0.4064)
			(end -0.7874 -0.4064)
			(stroke
				(width 0.1524)
				(type default)
			)
			(layer "F.SilkS")
		)
		(fp_line
			(start 0.7874 -0.4064)
			(end 0.7874 0.4064)
			(stroke
				(width 0.1524)
				(type default)
			)
			(layer "F.SilkS")
		)
		(fp_line
			(start 0.7874 0.4064)
			(end -0.7874 0.4064)
			(stroke
				(width 0.1524)
				(type default)
			)
			(layer "F.SilkS")
		)
		(fp_line
			(start -0.67945 -0.305054)
			(end -0.12065 -0.305054)
			(stroke
				(width 0.1)
				(type default)
			)
			(layer "F.Fab")
		)
		(fp_line
			(start -0.67945 0.3048)
			(end -0.67945 -0.305054)
			(stroke
				(width 0.1)
				(type default)
			)
			(layer "F.Fab")
		)
		(fp_line
			(start -0.12065 -0.305054)
			(end -0.12065 -0.2794)
			(stroke
				(width 0.1)
				(type default)
			)
			(layer "F.Fab")
		)
		(fp_line
			(start -0.12065 -0.2794)
			(end 0.12065 -0.2794)
			(stroke
				(width 0.1)
				(type default)
			)
			(layer "F.Fab")
		)
		(fp_line
			(start -0.12065 0.2794)
			(end -0.12065 0.3048)
			(stroke
				(width 0.1)
				(type default)
			)
			(layer "F.Fab")
		)
		(fp_line
			(start -0.12065 0.3048)
			(end -0.67945 0.3048)
			(stroke
				(width 0.1)
				(type default)
			)
			(layer "F.Fab")
		)
		(fp_line
			(start 0.120396 0.2794)
			(end -0.12065 0.2794)
			(stroke
				(width 0.1)
				(type default)
			)
			(layer "F.Fab")
		)
		(fp_line
			(start 0.120396 0.3048)
			(end 0.120396 0.2794)
			(stroke
				(width 0.1)
				(type default)
			)
			(layer "F.Fab")
		)
		(fp_line
			(start 0.12065 -0.3048)
			(end 0.67945 -0.3048)
			(stroke
				(width 0.1)
				(type default)
			)
			(layer "F.Fab")
		)
		(fp_line
			(start 0.12065 -0.2794)
			(end 0.12065 -0.3048)
			(stroke
				(width 0.1)
				(type default)
			)
			(layer "F.Fab")
		)
		(fp_line
			(start 0.67945 -0.3048)
			(end 0.67945 0.3048)
			(stroke
				(width 0.1)
				(type default)
			)
			(layer "F.Fab")
		)
		(fp_line
			(start 0.67945 0.3048)
			(end 0.120396 0.3048)
			(stroke
				(width 0.1)
				(type default)
			)
			(layer "F.Fab")
		)
		(pad "1" smd circle
			(at -0.40005 0)
			(size 0 0)
			(layers "F.Cu" "F.Mask" "F.Paste")
			(net "GND")
		)
		(pad "2" smd circle
			(at 0.40005 0)
			(size 0 0)
			(layers "F.Cu" "F.Mask" "F.Paste")
			(net "PVDDCR_CPU0_P0_LSET2")
		)
	)
	(footprint ""
		(layer "F.Cu")
		(at 257.242056 -118.91137 180)
		(property "Reference" "R3715"
			(at 0 0 180)
			(layer "F.SilkS")
			(hide yes)
			(effects
				(font
					(size 1.27 1.27)
				)
			)
		)
		(property "Value" ""
			(at 0 0 180)
			(layer "F.Fab")
			(effects
				(font
					(size 1.27 1.27)
				)
			)
		)
		(duplicate_pad_numbers_are_jumpers no)
		(fp_line
			(start 0.7874 0.4064)
			(end -0.7874 0.4064)
			(stroke
				(width 0.1524)
				(type default)
			)
			(layer "F.SilkS")
		)
		(fp_line
			(start 0.7874 -0.4064)
			(end 0.7874 0.4064)
			(stroke
				(width 0.1524)
				(type default)
			)
			(layer "F.SilkS")
		)
		(fp_line
			(start -0.7874 0.4064)
			(end -0.7874 -0.4064)
			(stroke
				(width 0.1524)
				(type default)
			)
			(layer "F.SilkS")
		)
		(fp_line
			(start -0.7874 -0.4064)
			(end 0.7874 -0.4064)
			(stroke
				(width 0.1524)
				(type default)
			)
			(layer "F.SilkS")
		)
		(fp_line
			(start 0.67945 0.3048)
			(end 0.120396 0.3048)
			(stroke
				(width 0.1)
				(type default)
			)
			(layer "F.Fab")
		)
		(fp_line
			(start 0.67945 -0.3048)
			(end 0.67945 0.3048)
			(stroke
				(width 0.1)
				(type default)
			)
			(layer "F.Fab")
		)
		(fp_line
			(start 0.12065 -0.2794)
			(end 0.12065 -0.3048)
			(stroke
				(width 0.1)
				(type default)
			)
			(layer "F.Fab")
		)
		(fp_line
			(start 0.12065 -0.3048)
			(end 0.67945 -0.3048)
			(stroke
				(width 0.1)
				(type default)
			)
			(layer "F.Fab")
		)
		(fp_line
			(start 0.120396 0.3048)
			(end 0.120396 0.2794)
			(stroke
				(width 0.1)
				(type default)
			)
			(layer "F.Fab")
		)
		(fp_line
			(start 0.120396 0.2794)
			(end -0.12065 0.2794)
			(stroke
				(width 0.1)
				(type default)
			)
			(layer "F.Fab")
		)
		(fp_line
			(start -0.12065 0.3048)
			(end -0.67945 0.3048)
			(stroke
				(width 0.1)
				(type default)
			)
			(layer "F.Fab")
		)
		(fp_line
			(start -0.12065 0.2794)
			(end -0.12065 0.3048)
			(stroke
				(width 0.1)
				(type default)
			)
			(layer "F.Fab")
		)
		(fp_line
			(start -0.12065 -0.2794)
			(end 0.12065 -0.2794)
			(stroke
				(width 0.1)
				(type default)
			)
			(layer "F.Fab")
		)
		(fp_line
			(start -0.12065 -0.305054)
			(end -0.12065 -0.2794)
			(stroke
				(width 0.1)
				(type default)
			)
			(layer "F.Fab")
		)
		(fp_line
			(start -0.67945 0.3048)
			(end -0.67945 -0.305054)
			(stroke
				(width 0.1)
				(type default)
			)
			(layer "F.Fab")
		)
		(fp_line
			(start -0.67945 -0.305054)
			(end -0.12065 -0.305054)
			(stroke
				(width 0.1)
				(type default)
			)
			(layer "F.Fab")
		)
		(pad "1" smd circle
			(at -0.40005 0 180)
			(size 0 0)
			(layers "F.Cu" "F.Mask" "F.Paste")
			(net "SMB_LM75_0_3V3AUX_SCL_R")
		)
		(pad "2" smd circle
			(at 0.40005 0 180)
			(size 0 0)
			(layers "F.Cu" "F.Mask" "F.Paste")
			(net "SMB_LM75_0_3V3AUX_SCL")
		)
	)
	(footprint ""
		(layer "F.Cu")
		(at 203.399898 -22.29993)
		(property "Reference" "H92"
			(at -5.458206 -6.02488 0)
			(unlocked yes)
			(layer "F.SilkS")
			(effects
				(font
					(size 0.7874 0.5842)
					(thickness 0.1524)
				)
				(justify left)
			)
		)
		(property "Value" ""
			(at 0 0 0)
			(layer "F.Fab")
			(effects
				(font
					(size 1.27 1.27)
				)
			)
		)
		(duplicate_pad_numbers_are_jumpers no)
		(pad "1" thru_hole circle
			(at 0 0)
			(size 10.0076 10.0076)
			(drill 5.6134)
			(layers "*.Cu" "*.Mask")
			(remove_unused_layers no)
			(net "GND")
			(clearance -1.9431)
		)
	)
	(footprint ""
		(layer "F.Cu")
		(at 322.90004 -160.50006)
		(property "Reference" "H101"
			(at -5.698998 -5.882386 0)
			(unlocked yes)
			(layer "F.SilkS")
			(effects
				(font
					(size 0.7874 0.5842)
					(thickness 0.1524)
				)
				(justify left)
			)
		)
		(property "Value" ""
			(at 0 0 0)
			(layer "F.Fab")
			(effects
				(font
					(size 1.27 1.27)
				)
			)
		)
		(duplicate_pad_numbers_are_jumpers no)
		(pad "1" thru_hole circle
			(at 0 0)
			(size 10.0076 10.0076)
			(drill 5.6134)
			(layers "*.Cu" "*.Mask")
			(remove_unused_layers no)
			(net "GND")
			(clearance -1.9431)
		)
	)
	(footprint ""
		(layer "F.Cu")
		(at 112.53216 -395.441932 -90)
		(property "Reference" "R911"
			(at 0 0 270)
			(layer "F.SilkS")
			(hide yes)
			(effects
				(font
					(size 1.27 1.27)
				)
			)
		)
		(property "Value" ""
			(at 0 0 270)
			(layer "F.Fab")
			(effects
				(font
					(size 1.27 1.27)
				)
			)
		)
		(duplicate_pad_numbers_are_jumpers no)
		(fp_line
			(start -0.32512 0.175006)
			(end -0.32512 -0.175006)
			(stroke
				(width 0.1)
				(type default)
			)
			(layer "F.Fab")
		)
		(fp_line
			(start 0.32512 0.175006)
			(end -0.32512 0.175006)
			(stroke
				(width 0.1)
				(type default)
			)
			(layer "F.Fab")
		)
		(fp_line
			(start -0.32512 -0.175006)
			(end 0.32512 -0.175006)
			(stroke
				(width 0.1)
				(type default)
			)
			(layer "F.Fab")
		)
		(fp_line
			(start 0.32512 -0.175006)
			(end 0.32512 0.175006)
			(stroke
				(width 0.1)
				(type default)
			)
			(layer "F.Fab")
		)
		(pad "1" smd rect
			(at -0.2667 0 270)
			(size 0.3048 0.381)
			(layers "F.Cu" "F.Mask" "F.Paste")
			(net "P1V8_CPU1_RT_1D")
		)
		(pad "2" smd rect
			(at 0.2667 0 90)
			(size 0.3048 0.381)
			(layers "F.Cu" "F.Mask" "F.Paste")
			(net "RST_RT_CPU1_P3_RESET_R_N")
		)
	)
	(footprint ""
		(layer "F.Cu")
		(at 135.02132 -394.35278 -90)
		(property "Reference" "R907"
			(at 0 0 270)
			(layer "F.SilkS")
			(hide yes)
			(effects
				(font
					(size 1.27 1.27)
				)
			)
		)
		(property "Value" ""
			(at 0 0 270)
			(layer "F.Fab")
			(effects
				(font
					(size 1.27 1.27)
				)
			)
		)
		(duplicate_pad_numbers_are_jumpers no)
		(fp_line
			(start -0.32512 0.175006)
			(end -0.32512 -0.175006)
			(stroke
				(width 0.1)
				(type default)
			)
			(layer "F.Fab")
		)
		(fp_line
			(start 0.32512 0.175006)
			(end -0.32512 0.175006)
			(stroke
				(width 0.1)
				(type default)
			)
			(layer "F.Fab")
		)
		(fp_line
			(start -0.32512 -0.175006)
			(end 0.32512 -0.175006)
			(stroke
				(width 0.1)
				(type default)
			)
			(layer "F.Fab")
		)
		(fp_line
			(start 0.32512 -0.175006)
			(end 0.32512 0.175006)
			(stroke
				(width 0.1)
				(type default)
			)
			(layer "F.Fab")
		)
		(pad "1" smd rect
			(at -0.2667 0 270)
			(size 0.3048 0.381)
			(layers "F.Cu" "F.Mask" "F.Paste")
			(net "RST_RT_CPU1_P3_PERST_R_N")
		)
		(pad "2" smd rect
			(at 0.2667 0 90)
			(size 0.3048 0.381)
			(layers "F.Cu" "F.Mask" "F.Paste")
			(net "GND")
		)
	)
	(footprint ""
		(layer "F.Cu")
		(at 50.832004 -408.517344 -90)
		(property "Reference" "C6632"
			(at 0 0 270)
			(layer "F.SilkS")
			(hide yes)
			(effects
				(font
					(size 1.27 1.27)
				)
			)
		)
		(property "Value" ""
			(at 0 0 270)
			(layer "F.Fab")
			(effects
				(font
					(size 1.27 1.27)
				)
			)
		)
		(duplicate_pad_numbers_are_jumpers no)
		(fp_line
			(start -0.299974 0.150114)
			(end -0.299974 -0.150114)
			(stroke
				(width 0.1)
				(type default)
			)
			(layer "F.Fab")
		)
		(fp_line
			(start 0.299974 0.150114)
			(end -0.299974 0.150114)
			(stroke
				(width 0.1)
				(type default)
			)
			(layer "F.Fab")
		)
		(fp_line
			(start -0.299974 -0.150114)
			(end 0.299974 -0.150114)
			(stroke
				(width 0.1)
				(type default)
			)
			(layer "F.Fab")
		)
		(fp_line
			(start 0.299974 -0.150114)
			(end 0.299974 0.150114)
			(stroke
				(width 0.1)
				(type default)
			)
			(layer "F.Fab")
		)
		(pad "1" smd rect
			(at -0.2667 0 270)
			(size 0.3048 0.381)
			(layers "F.Cu" "F.Mask" "F.Paste")
			(net "P5E_CPU1_P0_TX_BUF_C_DN<1>")
		)
		(pad "2" smd rect
			(at 0.2667 0 270)
			(size 0.3048 0.381)
			(layers "F.Cu" "F.Mask" "F.Paste")
			(net "P5E_CPU1_P0_TX_BUF_DN<1>")
		)
	)
	(footprint ""
		(layer "F.Cu")
		(at 382.382522 -177.532284)
		(property "Reference" "PR346"
			(at 0 0 0)
			(layer "F.SilkS")
			(hide yes)
			(effects
				(font
					(size 1.27 1.27)
				)
			)
		)
		(property "Value" ""
			(at 0 0 0)
			(layer "F.Fab")
			(effects
				(font
					(size 1.27 1.27)
				)
			)
		)
		(duplicate_pad_numbers_are_jumpers no)
		(fp_line
			(start -0.7874 -0.4064)
			(end 0.7874 -0.4064)
			(stroke
				(width 0.1524)
				(type default)
			)
			(layer "F.SilkS")
		)
		(fp_line
			(start -0.7874 0.4064)
			(end -0.7874 -0.4064)
			(stroke
				(width 0.1524)
				(type default)
			)
			(layer "F.SilkS")
		)
		(fp_line
			(start 0.7874 -0.4064)
			(end 0.7874 0.4064)
			(stroke
				(width 0.1524)
				(type default)
			)
			(layer "F.SilkS")
		)
		(fp_line
			(start 0.7874 0.4064)
			(end -0.7874 0.4064)
			(stroke
				(width 0.1524)
				(type default)
			)
			(layer "F.SilkS")
		)
		(fp_line
			(start -0.67945 -0.305054)
			(end -0.12065 -0.305054)
			(stroke
				(width 0.1)
				(type default)
			)
			(layer "F.Fab")
		)
		(fp_line
			(start -0.67945 0.3048)
			(end -0.67945 -0.305054)
			(stroke
				(width 0.1)
				(type default)
			)
			(layer "F.Fab")
		)
		(fp_line
			(start -0.12065 -0.305054)
			(end -0.12065 -0.2794)
			(stroke
				(width 0.1)
				(type default)
			)
			(layer "F.Fab")
		)
		(fp_line
			(start -0.12065 -0.2794)
			(end 0.12065 -0.2794)
			(stroke
				(width 0.1)
				(type default)
			)
			(layer "F.Fab")
		)
		(fp_line
			(start -0.12065 0.2794)
			(end -0.12065 0.3048)
			(stroke
				(width 0.1)
				(type default)
			)
			(layer "F.Fab")
		)
		(fp_line
			(start -0.12065 0.3048)
			(end -0.67945 0.3048)
			(stroke
				(width 0.1)
				(type default)
			)
			(layer "F.Fab")
		)
		(fp_line
			(start 0.120396 0.2794)
			(end -0.12065 0.2794)
			(stroke
				(width 0.1)
				(type default)
			)
			(layer "F.Fab")
		)
		(fp_line
			(start 0.120396 0.3048)
			(end 0.120396 0.2794)
			(stroke
				(width 0.1)
				(type default)
			)
			(layer "F.Fab")
		)
		(fp_line
			(start 0.12065 -0.3048)
			(end 0.67945 -0.3048)
			(stroke
				(width 0.1)
				(type default)
			)
			(layer "F.Fab")
		)
		(fp_line
			(start 0.12065 -0.2794)
			(end 0.12065 -0.3048)
			(stroke
				(width 0.1)
				(type default)
			)
			(layer "F.Fab")
		)
		(fp_line
			(start 0.67945 -0.3048)
			(end 0.67945 0.3048)
			(stroke
				(width 0.1)
				(type default)
			)
			(layer "F.Fab")
		)
		(fp_line
			(start 0.67945 0.3048)
			(end 0.120396 0.3048)
			(stroke
				(width 0.1)
				(type default)
			)
			(layer "F.Fab")
		)
		(pad "1" smd circle
			(at -0.40005 0)
			(size 0 0)
			(layers "F.Cu" "F.Mask" "F.Paste")
			(net "GND")
		)
		(pad "2" smd circle
			(at 0.40005 0)
			(size 0 0)
			(layers "F.Cu" "F.Mask" "F.Paste")
			(net "PVDDCR_CPU0_P0_LSET3")
		)
	)
	(footprint ""
		(layer "F.Cu")
		(at 145.128488 -395.436852 -90)
		(property "Reference" "R885"
			(at 0 0 270)
			(layer "F.SilkS")
			(hide yes)
			(effects
				(font
					(size 1.27 1.27)
				)
			)
		)
		(property "Value" ""
			(at 0 0 270)
			(layer "F.Fab")
			(effects
				(font
					(size 1.27 1.27)
				)
			)
		)
		(duplicate_pad_numbers_are_jumpers no)
		(fp_line
			(start -0.32512 0.175006)
			(end -0.32512 -0.175006)
			(stroke
				(width 0.1)
				(type default)
			)
			(layer "F.Fab")
		)
		(fp_line
			(start 0.32512 0.175006)
			(end -0.32512 0.175006)
			(stroke
				(width 0.1)
				(type default)
			)
			(layer "F.Fab")
		)
		(fp_line
			(start -0.32512 -0.175006)
			(end 0.32512 -0.175006)
			(stroke
				(width 0.1)
				(type default)
			)
			(layer "F.Fab")
		)
		(fp_line
			(start 0.32512 -0.175006)
			(end 0.32512 0.175006)
			(stroke
				(width 0.1)
				(type default)
			)
			(layer "F.Fab")
		)
		(pad "1" smd rect
			(at -0.2667 0 270)
			(size 0.3048 0.381)
			(layers "F.Cu" "F.Mask" "F.Paste")
			(net "P1V8_CPU1_RT_1D")
		)
		(pad "2" smd rect
			(at 0.2667 0 90)
			(size 0.3048 0.381)
			(layers "F.Cu" "F.Mask" "F.Paste")
			(net "MODE_RT_CPU1_P2")
		)
	)
	(footprint ""
		(layer "F.Cu")
		(at 12.360148 -387.30809 90)
		(property "Reference" "PR6624"
			(at 0 0 90)
			(layer "F.SilkS")
			(hide yes)
			(effects
				(font
					(size 1.27 1.27)
				)
			)
		)
		(property "Value" ""
			(at 0 0 90)
			(layer "F.Fab")
			(effects
				(font
					(size 1.27 1.27)
				)
			)
		)
		(duplicate_pad_numbers_are_jumpers no)
		(fp_line
			(start 0.7874 -0.4064)
			(end 0.7874 0.4064)
			(stroke
				(width 0.1524)
				(type default)
			)
			(layer "F.SilkS")
		)
		(fp_line
			(start -0.7874 -0.4064)
			(end 0.7874 -0.4064)
			(stroke
				(width 0.1524)
				(type default)
			)
			(layer "F.SilkS")
		)
		(fp_line
			(start 0.7874 0.4064)
			(end -0.7874 0.4064)
			(stroke
				(width 0.1524)
				(type default)
			)
			(layer "F.SilkS")
		)
		(fp_line
			(start -0.7874 0.4064)
			(end -0.7874 -0.4064)
			(stroke
				(width 0.1524)
				(type default)
			)
			(layer "F.SilkS")
		)
		(fp_line
			(start -0.12065 -0.305054)
			(end -0.12065 -0.2794)
			(stroke
				(width 0.1)
				(type default)
			)
			(layer "F.Fab")
		)
		(fp_line
			(start -0.67945 -0.305054)
			(end -0.12065 -0.305054)
			(stroke
				(width 0.1)
				(type default)
			)
			(layer "F.Fab")
		)
		(fp_line
			(start 0.67945 -0.3048)
			(end 0.67945 0.3048)
			(stroke
				(width 0.1)
				(type default)
			)
			(layer "F.Fab")
		)
		(fp_line
			(start 0.12065 -0.3048)
			(end 0.67945 -0.3048)
			(stroke
				(width 0.1)
				(type default)
			)
			(layer "F.Fab")
		)
		(fp_line
			(start 0.12065 -0.2794)
			(end 0.12065 -0.3048)
			(stroke
				(width 0.1)
				(type default)
			)
			(layer "F.Fab")
		)
		(fp_line
			(start -0.12065 -0.2794)
			(end 0.12065 -0.2794)
			(stroke
				(width 0.1)
				(type default)
			)
			(layer "F.Fab")
		)
		(fp_line
			(start 0.120396 0.2794)
			(end -0.12065 0.2794)
			(stroke
				(width 0.1)
				(type default)
			)
			(layer "F.Fab")
		)
		(fp_line
			(start -0.12065 0.2794)
			(end -0.12065 0.3048)
			(stroke
				(width 0.1)
				(type default)
			)
			(layer "F.Fab")
		)
		(fp_line
			(start 0.67945 0.3048)
			(end 0.120396 0.3048)
			(stroke
				(width 0.1)
				(type default)
			)
			(layer "F.Fab")
		)
		(fp_line
			(start 0.120396 0.3048)
			(end 0.120396 0.2794)
			(stroke
				(width 0.1)
				(type default)
			)
			(layer "F.Fab")
		)
		(fp_line
			(start -0.12065 0.3048)
			(end -0.67945 0.3048)
			(stroke
				(width 0.1)
				(type default)
			)
			(layer "F.Fab")
		)
		(fp_line
			(start -0.67945 0.3048)
			(end -0.67945 -0.305054)
			(stroke
				(width 0.1)
				(type default)
			)
			(layer "F.Fab")
		)
		(pad "1" smd circle
			(at -0.40005 0 90)
			(size 0 0)
			(layers "F.Cu" "F.Mask" "F.Paste")
			(net "SW_P0V9_RETIMER_CPU1_SW1_RC")
		)
		(pad "2" smd circle
			(at 0.40005 0 90)
			(size 0 0)
			(layers "F.Cu" "F.Mask" "F.Paste")
			(net "GND")
		)
	)
	(footprint ""
		(layer "F.Cu")
		(at 139.794742 -386.7912 90)
		(property "Reference" "R906"
			(at 0 0 90)
			(layer "F.SilkS")
			(hide yes)
			(effects
				(font
					(size 1.27 1.27)
				)
			)
		)
		(property "Value" ""
			(at 0 0 90)
			(layer "F.Fab")
			(effects
				(font
					(size 1.27 1.27)
				)
			)
		)
		(duplicate_pad_numbers_are_jumpers no)
		(fp_line
			(start 0.32512 -0.175006)
			(end 0.32512 0.175006)
			(stroke
				(width 0.1)
				(type default)
			)
			(layer "F.Fab")
		)
		(fp_line
			(start -0.32512 -0.175006)
			(end 0.32512 -0.175006)
			(stroke
				(width 0.1)
				(type default)
			)
			(layer "F.Fab")
		)
		(fp_line
			(start 0.32512 0.175006)
			(end -0.32512 0.175006)
			(stroke
				(width 0.1)
				(type default)
			)
			(layer "F.Fab")
		)
		(fp_line
			(start -0.32512 0.175006)
			(end -0.32512 -0.175006)
			(stroke
				(width 0.1)
				(type default)
			)
			(layer "F.Fab")
		)
		(pad "1" smd rect
			(at -0.2667 0 90)
			(size 0.3048 0.381)
			(layers "F.Cu" "F.Mask" "F.Paste")
			(net "RT_CPU1_P3_ADDR2")
		)
		(pad "2" smd rect
			(at 0.2667 0 270)
			(size 0.3048 0.381)
			(layers "F.Cu" "F.Mask" "F.Paste")
			(net "GND")
		)
	)
	(footprint ""
		(layer "F.Cu")
		(at 99.606862 -54.15153 90)
		(property "Reference" "C6088"
			(at 0 0 90)
			(layer "F.SilkS")
			(hide yes)
			(effects
				(font
					(size 1.27 1.27)
				)
			)
		)
		(property "Value" ""
			(at 0 0 90)
			(layer "F.Fab")
			(effects
				(font
					(size 1.27 1.27)
				)
			)
		)
		(duplicate_pad_numbers_are_jumpers no)
		(fp_line
			(start 1.524 -0.762)
			(end 1.524 0.762)
			(stroke
				(width 0.1524)
				(type default)
			)
			(layer "F.SilkS")
		)
		(fp_line
			(start -1.524 -0.762)
			(end 1.524 -0.762)
			(stroke
				(width 0.1524)
				(type default)
			)
			(layer "F.SilkS")
		)
		(fp_line
			(start 1.524 0.762)
			(end -1.524 0.762)
			(stroke
				(width 0.1524)
				(type default)
			)
			(layer "F.SilkS")
		)
		(fp_line
			(start -1.524 0.762)
			(end -1.524 -0.762)
			(stroke
				(width 0.1524)
				(type default)
			)
			(layer "F.SilkS")
		)
		(fp_line
			(start 1.1049 -0.724916)
			(end -1.1049 -0.724916)
			(stroke
				(width 0.1)
				(type default)
			)
			(layer "F.Fab")
		)
		(fp_line
			(start -1.1049 -0.724916)
			(end -1.1049 0.724916)
			(stroke
				(width 0.1)
				(type default)
			)
			(layer "F.Fab")
		)
		(fp_line
			(start 1.1049 0.724916)
			(end 1.1049 -0.724916)
			(stroke
				(width 0.1)
				(type default)
			)
			(layer "F.Fab")
		)
		(fp_line
			(start -1.1049 0.724916)
			(end 1.1049 0.724916)
			(stroke
				(width 0.1)
				(type default)
			)
			(layer "F.Fab")
		)
		(pad "1" smd rect
			(at -0.889 0 270)
			(size 1.016 1.27)
			(layers "F.Cu" "F.Mask" "F.Paste")
			(net "USB_HUB2_MRP_RESET_N")
		)
		(pad "2" smd rect
			(at 0.889 0 270)
			(size 1.016 1.27)
			(layers "F.Cu" "F.Mask" "F.Paste")
			(net "GND")
		)
	)
	(footprint ""
		(layer "F.Cu")
		(at 439.84164 -50.447448 180)
		(property "Reference" "PC566"
			(at 0.46228 -3.198368 0)
			(unlocked yes)
			(layer "F.SilkS")
			(effects
				(font
					(size 0.7874 0.5842)
					(thickness 0.1524)
				)
				(justify left)
			)
		)
		(property "Value" ""
			(at 0 0 180)
			(layer "F.Fab")
			(effects
				(font
					(size 1.27 1.27)
				)
			)
		)
		(duplicate_pad_numbers_are_jumpers no)
		(fp_line
			(start -3.400044 1.249934)
			(end 3.400044 1.249934)
			(stroke
				(width 0.1524)
				(type default)
			)
			(layer "F.SilkS")
		)
		(fp_circle
			(center 0 1.249934)
			(end -3.39979 1.249934)
			(stroke
				(width 0.1524)
				(type default)
			)
			(fill no)
			(layer "F.SilkS")
		)
		(fp_poly
			(pts
				(arc
					(start 3.400044 1.249934)
					(mid 0 4.649978)
					(end -3.400044 1.249934)
				)
			)
			(stroke
				(width 0)
				(type default)
			)
			(fill yes)
			(layer "F.SilkS")
		)
		(fp_circle
			(center 0 1.249934)
			(end -3.39979 1.249934)
			(stroke
				(width 0.1)
				(type default)
			)
			(fill no)
			(layer "F.Fab")
		)
		(pad "1" thru_hole rect
			(at 0 0 180)
			(size 1.524 1.524)
			(drill 1.016)
			(layers "*.Cu" "*.Mask")
			(remove_unused_layers no)
			(net "SW_P3V3_AUX_FLT")
			(clearance 0)
			(padstack
				(mode front_inner_back)
				(layer "Inner"
					(shape circle)
					(size 1.524 1.524)
					(clearance 0)
				)
				(layer "B.Cu"
					(shape rect)
					(size 1.524 1.524)
					(clearance 0)
				)
			)
		)
		(pad "2" thru_hole circle
			(at 0 2.500122 180)
			(size 1.524 1.524)
			(drill 1.016)
			(layers "*.Cu" "*.Mask")
			(remove_unused_layers no)
			(net "GND")
			(clearance 0)
		)
	)
	(footprint ""
		(layer "F.Cu")
		(at 365.835692 -257.455162 180)
		(property "Reference" "C2591"
			(at 0 0 180)
			(layer "F.SilkS")
			(hide yes)
			(effects
				(font
					(size 1.27 1.27)
				)
			)
		)
		(property "Value" ""
			(at 0 0 180)
			(layer "F.Fab")
			(effects
				(font
					(size 1.27 1.27)
				)
			)
		)
		(duplicate_pad_numbers_are_jumpers no)
		(fp_line
			(start 0.7874 0.4064)
			(end -0.7874 0.4064)
			(stroke
				(width 0.1524)
				(type default)
			)
			(layer "F.SilkS")
		)
		(fp_line
			(start 0.7874 -0.4064)
			(end 0.7874 0.4064)
			(stroke
				(width 0.1524)
				(type default)
			)
			(layer "F.SilkS")
		)
		(fp_line
			(start -0.7874 0.4064)
			(end -0.7874 -0.4064)
			(stroke
				(width 0.1524)
				(type default)
			)
			(layer "F.SilkS")
		)
		(fp_line
			(start -0.7874 -0.4064)
			(end 0.7874 -0.4064)
			(stroke
				(width 0.1524)
				(type default)
			)
			(layer "F.SilkS")
		)
		(fp_line
			(start 0.67945 0.3048)
			(end 0.120396 0.3048)
			(stroke
				(width 0.1)
				(type default)
			)
			(layer "F.Fab")
		)
		(fp_line
			(start 0.67945 -0.3048)
			(end 0.67945 0.3048)
			(stroke
				(width 0.1)
				(type default)
			)
			(layer "F.Fab")
		)
		(fp_line
			(start 0.12065 -0.2794)
			(end 0.12065 -0.3048)
			(stroke
				(width 0.1)
				(type default)
			)
			(layer "F.Fab")
		)
		(fp_line
			(start 0.12065 -0.3048)
			(end 0.67945 -0.3048)
			(stroke
				(width 0.1)
				(type default)
			)
			(layer "F.Fab")
		)
		(fp_line
			(start 0.120396 0.3048)
			(end 0.120396 0.2794)
			(stroke
				(width 0.1)
				(type default)
			)
			(layer "F.Fab")
		)
		(fp_line
			(start 0.120396 0.2794)
			(end -0.12065 0.2794)
			(stroke
				(width 0.1)
				(type default)
			)
			(layer "F.Fab")
		)
		(fp_line
			(start -0.12065 0.3048)
			(end -0.67945 0.3048)
			(stroke
				(width 0.1)
				(type default)
			)
			(layer "F.Fab")
		)
		(fp_line
			(start -0.12065 0.2794)
			(end -0.12065 0.3048)
			(stroke
				(width 0.1)
				(type default)
			)
			(layer "F.Fab")
		)
		(fp_line
			(start -0.12065 -0.2794)
			(end 0.12065 -0.2794)
			(stroke
				(width 0.1)
				(type default)
			)
			(layer "F.Fab")
		)
		(fp_line
			(start -0.12065 -0.305054)
			(end -0.12065 -0.2794)
			(stroke
				(width 0.1)
				(type default)
			)
			(layer "F.Fab")
		)
		(fp_line
			(start -0.67945 0.3048)
			(end -0.67945 -0.305054)
			(stroke
				(width 0.1)
				(type default)
			)
			(layer "F.Fab")
		)
		(fp_line
			(start -0.67945 -0.305054)
			(end -0.12065 -0.305054)
			(stroke
				(width 0.1)
				(type default)
			)
			(layer "F.Fab")
		)
		(pad "1" smd circle
			(at -0.40005 0 180)
			(size 0 0)
			(layers "F.Cu" "F.Mask" "F.Paste")
			(net "PVDDCR_SOC_P0")
		)
		(pad "2" smd circle
			(at 0.40005 0 180)
			(size 0 0)
			(layers "F.Cu" "F.Mask" "F.Paste")
			(net "GND")
		)
	)
	(footprint ""
		(layer "F.Cu")
		(at 380.39548 -33.228788 180)
		(property "Reference" "U320"
			(at 1.088136 2.603246 0)
			(unlocked yes)
			(layer "F.SilkS")
			(effects
				(font
					(size 0.7874 0.5842)
					(thickness 0.1524)
				)
				(justify left)
			)
		)
		(property "Value" ""
			(at 0 0 180)
			(layer "F.Fab")
			(effects
				(font
					(size 1.27 1.27)
				)
			)
		)
		(duplicate_pad_numbers_are_jumpers no)
		(fp_line
			(start 2.032 1.549908)
			(end -2.032 1.549908)
			(stroke
				(width 0.1524)
				(type default)
			)
			(layer "F.SilkS")
		)
		(fp_line
			(start 2.032 -1.549908)
			(end 2.032 1.549908)
			(stroke
				(width 0.1524)
				(type default)
			)
			(layer "F.SilkS")
		)
		(fp_line
			(start -2.032 1.549908)
			(end -2.032 -1.549908)
			(stroke
				(width 0.1524)
				(type default)
			)
			(layer "F.SilkS")
		)
		(fp_line
			(start -2.032 -1.549908)
			(end 2.032 -1.549908)
			(stroke
				(width 0.1524)
				(type default)
			)
			(layer "F.SilkS")
		)
		(fp_poly
			(pts
				(xy -2.9464 -1.2192) (xy -2.9464 -0.7112) (xy -2.1844 -0.9652)
			)
			(stroke
				(width 0)
				(type default)
			)
			(fill yes)
			(layer "F.SilkS")
		)
		(fp_line
			(start 0.849884 1.549908)
			(end 0.849884 -1.549908)
			(stroke
				(width 0.1)
				(type default)
			)
			(layer "F.Fab")
		)
		(fp_line
			(start 0.849884 -1.549908)
			(end -0.849884 -1.549908)
			(stroke
				(width 0.1)
				(type default)
			)
			(layer "F.Fab")
		)
		(fp_line
			(start -0.849884 1.549908)
			(end 0.849884 1.549908)
			(stroke
				(width 0.1)
				(type default)
			)
			(layer "F.Fab")
		)
		(fp_line
			(start -0.849884 -1.549908)
			(end -0.849884 1.549908)
			(stroke
				(width 0.1)
				(type default)
			)
			(layer "F.Fab")
		)
		(fp_poly
			(pts
				(xy -2.9464 -1.2192) (xy -2.9464 -0.7112) (xy -2.1844 -0.9652)
			)
			(stroke
				(width 0)
				(type default)
			)
			(fill yes)
			(layer "F.Fab")
		)
		(pad "1" smd rect
			(at -1.225042 -0.94996 90)
			(size 0.4572 1.3208)
			(layers "F.Cu" "F.Mask" "F.Paste")
			(net "CLK_50M_NCSI_OCP_SFF")
		)
		(pad "2" smd rect
			(at -1.225042 0 90)
			(size 0.4572 1.3208)
			(layers "F.Cu" "F.Mask" "F.Paste")
			(net "CLK_50M_NCSI_OCP_SFF_ISO_R")
		)
		(pad "3" smd rect
			(at -1.225042 0.94996 90)
			(size 0.4572 1.3208)
			(layers "F.Cu" "F.Mask" "F.Paste")
			(net "GND")
		)
		(pad "4" smd rect
			(at 1.225042 0.94996 90)
			(size 0.4572 1.3208)
			(layers "F.Cu" "F.Mask" "F.Paste")
			(net "FB_BMC_ISOLATE")
		)
		(pad "5" smd rect
			(at 1.225042 -0.94996 90)
			(size 0.4572 1.3208)
			(layers "F.Cu" "F.Mask" "F.Paste")
			(net "P3V3_AUX")
		)
	)
	(footprint ""
		(layer "F.Cu")
		(at 18.483072 -393.394184 -90)
		(property "Reference" "PC6621"
			(at 0 0 270)
			(layer "F.SilkS")
			(hide yes)
			(effects
				(font
					(size 1.27 1.27)
				)
			)
		)
		(property "Value" ""
			(at 0 0 270)
			(layer "F.Fab")
			(effects
				(font
					(size 1.27 1.27)
				)
			)
		)
		(duplicate_pad_numbers_are_jumpers no)
		(fp_line
			(start -0.7874 0.4064)
			(end -0.7874 -0.4064)
			(stroke
				(width 0.1524)
				(type default)
			)
			(layer "F.SilkS")
		)
		(fp_line
			(start 0.7874 0.4064)
			(end -0.7874 0.4064)
			(stroke
				(width 0.1524)
				(type default)
			)
			(layer "F.SilkS")
		)
		(fp_line
			(start -0.7874 -0.4064)
			(end 0.7874 -0.4064)
			(stroke
				(width 0.1524)
				(type default)
			)
			(layer "F.SilkS")
		)
		(fp_line
			(start 0.7874 -0.4064)
			(end 0.7874 0.4064)
			(stroke
				(width 0.1524)
				(type default)
			)
			(layer "F.SilkS")
		)
		(fp_line
			(start -0.67945 0.3048)
			(end -0.67945 -0.305054)
			(stroke
				(width 0.1)
				(type default)
			)
			(layer "F.Fab")
		)
		(fp_line
			(start -0.12065 0.3048)
			(end -0.67945 0.3048)
			(stroke
				(width 0.1)
				(type default)
			)
			(layer "F.Fab")
		)
		(fp_line
			(start 0.120396 0.3048)
			(end 0.120396 0.2794)
			(stroke
				(width 0.1)
				(type default)
			)
			(layer "F.Fab")
		)
		(fp_line
			(start 0.67945 0.3048)
			(end 0.120396 0.3048)
			(stroke
				(width 0.1)
				(type default)
			)
			(layer "F.Fab")
		)
		(fp_line
			(start -0.12065 0.2794)
			(end -0.12065 0.3048)
			(stroke
				(width 0.1)
				(type default)
			)
			(layer "F.Fab")
		)
		(fp_line
			(start 0.120396 0.2794)
			(end -0.12065 0.2794)
			(stroke
				(width 0.1)
				(type default)
			)
			(layer "F.Fab")
		)
		(fp_line
			(start -0.12065 -0.2794)
			(end 0.12065 -0.2794)
			(stroke
				(width 0.1)
				(type default)
			)
			(layer "F.Fab")
		)
		(fp_line
			(start 0.12065 -0.2794)
			(end 0.12065 -0.3048)
			(stroke
				(width 0.1)
				(type default)
			)
			(layer "F.Fab")
		)
		(fp_line
			(start 0.12065 -0.3048)
			(end 0.67945 -0.3048)
			(stroke
				(width 0.1)
				(type default)
			)
			(layer "F.Fab")
		)
		(fp_line
			(start 0.67945 -0.3048)
			(end 0.67945 0.3048)
			(stroke
				(width 0.1)
				(type default)
			)
			(layer "F.Fab")
		)
		(fp_line
			(start -0.67945 -0.305054)
			(end -0.12065 -0.305054)
			(stroke
				(width 0.1)
				(type default)
			)
			(layer "F.Fab")
		)
		(fp_line
			(start -0.12065 -0.305054)
			(end -0.12065 -0.2794)
			(stroke
				(width 0.1)
				(type default)
			)
			(layer "F.Fab")
		)
		(pad "1" smd circle
			(at -0.40005 0 270)
			(size 0 0)
			(layers "F.Cu" "F.Mask" "F.Paste")
			(net "SW_P0V9_RETIMER_CPU1_BOOT1_RC")
		)
		(pad "2" smd circle
			(at 0.40005 0 270)
			(size 0 0)
			(layers "F.Cu" "F.Mask" "F.Paste")
			(net "SW_P0V9_RETIMER_CPU1_PH1")
		)
	)
	(footprint ""
		(layer "F.Cu")
		(at 294.581072 -394.721842 180)
		(property "Reference" "R1415"
			(at 0 0 180)
			(layer "F.SilkS")
			(hide yes)
			(effects
				(font
					(size 1.27 1.27)
				)
			)
		)
		(property "Value" ""
			(at 0 0 180)
			(layer "F.Fab")
			(effects
				(font
					(size 1.27 1.27)
				)
			)
		)
		(duplicate_pad_numbers_are_jumpers no)
		(fp_line
			(start 0.32512 0.175006)
			(end -0.32512 0.175006)
			(stroke
				(width 0.1)
				(type default)
			)
			(layer "F.Fab")
		)
		(fp_line
			(start 0.32512 -0.175006)
			(end 0.32512 0.175006)
			(stroke
				(width 0.1)
				(type default)
			)
			(layer "F.Fab")
		)
		(fp_line
			(start -0.32512 0.175006)
			(end -0.32512 -0.175006)
			(stroke
				(width 0.1)
				(type default)
			)
			(layer "F.Fab")
		)
		(fp_line
			(start -0.32512 -0.175006)
			(end 0.32512 -0.175006)
			(stroke
				(width 0.1)
				(type default)
			)
			(layer "F.Fab")
		)
		(pad "1" smd rect
			(at -0.2667 0 180)
			(size 0.3048 0.381)
			(layers "F.Cu" "F.Mask" "F.Paste")
			(net "P1V8_CPU0_RT_1D")
		)
		(pad "2" smd rect
			(at 0.2667 0)
			(size 0.3048 0.381)
			(layers "F.Cu" "F.Mask" "F.Paste")
			(net "SMB_RT_CPU0_P1_ROM_MUX_1D_SDA")
		)
	)
	(footprint ""
		(layer "F.Cu")
		(at 23.495 -431.9143 90)
		(property "Reference" "R2893"
			(at 0 0 90)
			(layer "F.SilkS")
			(hide yes)
			(effects
				(font
					(size 1.27 1.27)
				)
			)
		)
		(property "Value" ""
			(at 0 0 90)
			(layer "F.Fab")
			(effects
				(font
					(size 1.27 1.27)
				)
			)
		)
		(duplicate_pad_numbers_are_jumpers no)
		(fp_line
			(start 0.7874 -0.4064)
			(end 0.7874 0.4064)
			(stroke
				(width 0.1524)
				(type default)
			)
			(layer "F.SilkS")
		)
		(fp_line
			(start -0.7874 -0.4064)
			(end 0.7874 -0.4064)
			(stroke
				(width 0.1524)
				(type default)
			)
			(layer "F.SilkS")
		)
		(fp_line
			(start 0.7874 0.4064)
			(end -0.7874 0.4064)
			(stroke
				(width 0.1524)
				(type default)
			)
			(layer "F.SilkS")
		)
		(fp_line
			(start -0.7874 0.4064)
			(end -0.7874 -0.4064)
			(stroke
				(width 0.1524)
				(type default)
			)
			(layer "F.SilkS")
		)
		(fp_line
			(start -0.12065 -0.305054)
			(end -0.12065 -0.2794)
			(stroke
				(width 0.1)
				(type default)
			)
			(layer "F.Fab")
		)
		(fp_line
			(start -0.67945 -0.305054)
			(end -0.12065 -0.305054)
			(stroke
				(width 0.1)
				(type default)
			)
			(layer "F.Fab")
		)
		(fp_line
			(start 0.67945 -0.3048)
			(end 0.67945 0.3048)
			(stroke
				(width 0.1)
				(type default)
			)
			(layer "F.Fab")
		)
		(fp_line
			(start 0.12065 -0.3048)
			(end 0.67945 -0.3048)
			(stroke
				(width 0.1)
				(type default)
			)
			(layer "F.Fab")
		)
		(fp_line
			(start 0.12065 -0.2794)
			(end 0.12065 -0.3048)
			(stroke
				(width 0.1)
				(type default)
			)
			(layer "F.Fab")
		)
		(fp_line
			(start -0.12065 -0.2794)
			(end 0.12065 -0.2794)
			(stroke
				(width 0.1)
				(type default)
			)
			(layer "F.Fab")
		)
		(fp_line
			(start 0.120396 0.2794)
			(end -0.12065 0.2794)
			(stroke
				(width 0.1)
				(type default)
			)
			(layer "F.Fab")
		)
		(fp_line
			(start -0.12065 0.2794)
			(end -0.12065 0.3048)
			(stroke
				(width 0.1)
				(type default)
			)
			(layer "F.Fab")
		)
		(fp_line
			(start 0.67945 0.3048)
			(end 0.120396 0.3048)
			(stroke
				(width 0.1)
				(type default)
			)
			(layer "F.Fab")
		)
		(fp_line
			(start 0.120396 0.3048)
			(end 0.120396 0.2794)
			(stroke
				(width 0.1)
				(type default)
			)
			(layer "F.Fab")
		)
		(fp_line
			(start -0.12065 0.3048)
			(end -0.67945 0.3048)
			(stroke
				(width 0.1)
				(type default)
			)
			(layer "F.Fab")
		)
		(fp_line
			(start -0.67945 0.3048)
			(end -0.67945 -0.305054)
			(stroke
				(width 0.1)
				(type default)
			)
			(layer "F.Fab")
		)
		(pad "1" smd circle
			(at -0.40005 0 90)
			(size 0 0)
			(layers "F.Cu" "F.Mask" "F.Paste")
			(net "SMB_1_BMC_GPU_R_SCL")
		)
		(pad "2" smd circle
			(at 0.40005 0 90)
			(size 0 0)
			(layers "F.Cu" "F.Mask" "F.Paste")
			(net "SMB_1_BMC_GPU_BUF_R_SCL")
		)
	)
	(footprint ""
		(layer "F.Cu")
		(at 57.901078 -175.823626 90)
		(property "Reference" "PL27"
			(at -4.994656 0.152908 0)
			(unlocked yes)
			(layer "F.SilkS")
			(effects
				(font
					(size 0.7874 0.5842)
					(thickness 0.1524)
				)
				(justify left)
			)
		)
		(property "Value" ""
			(at 0 0 90)
			(layer "F.Fab")
			(effects
				(font
					(size 1.27 1.27)
				)
			)
		)
		(duplicate_pad_numbers_are_jumpers no)
		(fp_line
			(start 3.24993 -3.24993)
			(end 3.24993 -2.2352)
			(stroke
				(width 0.1524)
				(type default)
			)
			(layer "F.SilkS")
		)
		(fp_line
			(start -3.24993 -3.24993)
			(end 3.24993 -3.24993)
			(stroke
				(width 0.1524)
				(type default)
			)
			(layer "F.SilkS")
		)
		(fp_line
			(start -3.24993 -2.2352)
			(end -3.24993 -3.24993)
			(stroke
				(width 0.1524)
				(type default)
			)
			(layer "F.SilkS")
		)
		(fp_line
			(start 3.24993 2.2352)
			(end 3.24993 3.24993)
			(stroke
				(width 0.1524)
				(type default)
			)
			(layer "F.SilkS")
		)
		(fp_line
			(start 3.24993 3.24993)
			(end -3.24993 3.24993)
			(stroke
				(width 0.1524)
				(type default)
			)
			(layer "F.SilkS")
		)
		(fp_line
			(start -3.24993 3.24993)
			(end -3.24993 2.2352)
			(stroke
				(width 0.1524)
				(type default)
			)
			(layer "F.SilkS")
		)
		(fp_line
			(start 3.24993 -3.24993)
			(end 3.24993 3.24993)
			(stroke
				(width 0.1)
				(type default)
			)
			(layer "F.Fab")
		)
		(fp_line
			(start -3.24993 -3.24993)
			(end 3.24993 -3.24993)
			(stroke
				(width 0.1)
				(type default)
			)
			(layer "F.Fab")
		)
		(fp_line
			(start 3.24993 3.24993)
			(end -3.24993 3.24993)
			(stroke
				(width 0.1)
				(type default)
			)
			(layer "F.Fab")
		)
		(fp_line
			(start -3.24993 3.24993)
			(end -3.24993 -3.24993)
			(stroke
				(width 0.1)
				(type default)
			)
			(layer "F.Fab")
		)
		(pad "1" smd rect
			(at -2.29997 0 90)
			(size 2.0066 4.2164)
			(layers "F.Cu" "F.Mask" "F.Paste")
			(net "GND")
		)
		(pad "2" smd rect
			(at 2.29997 0 90)
			(size 2.0066 4.2164)
			(layers "F.Cu" "F.Mask" "F.Paste")
			(net "IND_CPU0_P1_CPL0")
		)
	)
	(footprint ""
		(layer "F.Cu")
		(at 60.127388 -32.287972 180)
		(property "Reference" "R3868"
			(at 0 0 180)
			(layer "F.SilkS")
			(hide yes)
			(effects
				(font
					(size 1.27 1.27)
				)
			)
		)
		(property "Value" ""
			(at 0 0 180)
			(layer "F.Fab")
			(effects
				(font
					(size 1.27 1.27)
				)
			)
		)
		(duplicate_pad_numbers_are_jumpers no)
		(fp_line
			(start 0.7874 0.4064)
			(end -0.7874 0.4064)
			(stroke
				(width 0.1524)
				(type default)
			)
			(layer "F.SilkS")
		)
		(fp_line
			(start 0.7874 -0.4064)
			(end 0.7874 0.4064)
			(stroke
				(width 0.1524)
				(type default)
			)
			(layer "F.SilkS")
		)
		(fp_line
			(start -0.7874 0.4064)
			(end -0.7874 -0.4064)
			(stroke
				(width 0.1524)
				(type default)
			)
			(layer "F.SilkS")
		)
		(fp_line
			(start -0.7874 -0.4064)
			(end 0.7874 -0.4064)
			(stroke
				(width 0.1524)
				(type default)
			)
			(layer "F.SilkS")
		)
		(fp_line
			(start 0.67945 0.3048)
			(end 0.120396 0.3048)
			(stroke
				(width 0.1)
				(type default)
			)
			(layer "F.Fab")
		)
		(fp_line
			(start 0.67945 -0.3048)
			(end 0.67945 0.3048)
			(stroke
				(width 0.1)
				(type default)
			)
			(layer "F.Fab")
		)
		(fp_line
			(start 0.12065 -0.2794)
			(end 0.12065 -0.3048)
			(stroke
				(width 0.1)
				(type default)
			)
			(layer "F.Fab")
		)
		(fp_line
			(start 0.12065 -0.3048)
			(end 0.67945 -0.3048)
			(stroke
				(width 0.1)
				(type default)
			)
			(layer "F.Fab")
		)
		(fp_line
			(start 0.120396 0.3048)
			(end 0.120396 0.2794)
			(stroke
				(width 0.1)
				(type default)
			)
			(layer "F.Fab")
		)
		(fp_line
			(start 0.120396 0.2794)
			(end -0.12065 0.2794)
			(stroke
				(width 0.1)
				(type default)
			)
			(layer "F.Fab")
		)
		(fp_line
			(start -0.12065 0.3048)
			(end -0.67945 0.3048)
			(stroke
				(width 0.1)
				(type default)
			)
			(layer "F.Fab")
		)
		(fp_line
			(start -0.12065 0.2794)
			(end -0.12065 0.3048)
			(stroke
				(width 0.1)
				(type default)
			)
			(layer "F.Fab")
		)
		(fp_line
			(start -0.12065 -0.2794)
			(end 0.12065 -0.2794)
			(stroke
				(width 0.1)
				(type default)
			)
			(layer "F.Fab")
		)
		(fp_line
			(start -0.12065 -0.305054)
			(end -0.12065 -0.2794)
			(stroke
				(width 0.1)
				(type default)
			)
			(layer "F.Fab")
		)
		(fp_line
			(start -0.67945 0.3048)
			(end -0.67945 -0.305054)
			(stroke
				(width 0.1)
				(type default)
			)
			(layer "F.Fab")
		)
		(fp_line
			(start -0.67945 -0.305054)
			(end -0.12065 -0.305054)
			(stroke
				(width 0.1)
				(type default)
			)
			(layer "F.Fab")
		)
		(pad "1" smd rect
			(at -0.40005 0)
			(size 0.4572 0.508)
			(layers "F.Cu" "F.Mask" "F.Paste")
			(net "P12V_OCP_SENSE_2")
		)
		(pad "2" smd rect
			(at 0.40005 0)
			(size 0.4572 0.508)
			(layers "F.Cu" "F.Mask" "F.Paste")
			(net "P12V_OCP_V3_2_ISENSE_MAM_TIC")
		)
	)
	(footprint ""
		(layer "F.Cu")
		(at 372.237 -424.053 90)
		(property "Reference" "R1216"
			(at 0 0 90)
			(layer "F.SilkS")
			(hide yes)
			(effects
				(font
					(size 1.27 1.27)
				)
			)
		)
		(property "Value" ""
			(at 0 0 90)
			(layer "F.Fab")
			(effects
				(font
					(size 1.27 1.27)
				)
			)
		)
		(duplicate_pad_numbers_are_jumpers no)
		(fp_line
			(start 0.32512 -0.175006)
			(end 0.32512 0.175006)
			(stroke
				(width 0.1)
				(type default)
			)
			(layer "F.Fab")
		)
		(fp_line
			(start -0.32512 -0.175006)
			(end 0.32512 -0.175006)
			(stroke
				(width 0.1)
				(type default)
			)
			(layer "F.Fab")
		)
		(fp_line
			(start 0.32512 0.175006)
			(end -0.32512 0.175006)
			(stroke
				(width 0.1)
				(type default)
			)
			(layer "F.Fab")
		)
		(fp_line
			(start -0.32512 0.175006)
			(end -0.32512 -0.175006)
			(stroke
				(width 0.1)
				(type default)
			)
			(layer "F.Fab")
		)
		(pad "1" smd rect
			(at -0.2667 0 90)
			(size 0.3048 0.381)
			(layers "F.Cu" "F.Mask" "F.Paste")
			(net "GND")
		)
		(pad "2" smd rect
			(at 0.2667 0 270)
			(size 0.3048 0.381)
			(layers "F.Cu" "F.Mask" "F.Paste")
			(net "RT_ROM_MUX7_OE_N")
		)
	)
	(footprint ""
		(layer "F.Cu")
		(at 455.01306 -37.295836)
		(property "Reference" "R1824"
			(at 0 0 0)
			(layer "F.SilkS")
			(hide yes)
			(effects
				(font
					(size 1.27 1.27)
				)
			)
		)
		(property "Value" ""
			(at 0 0 0)
			(layer "F.Fab")
			(effects
				(font
					(size 1.27 1.27)
				)
			)
		)
		(duplicate_pad_numbers_are_jumpers no)
		(fp_line
			(start -0.7874 -0.4064)
			(end 0.7874 -0.4064)
			(stroke
				(width 0.1524)
				(type default)
			)
			(layer "F.SilkS")
		)
		(fp_line
			(start -0.7874 0.4064)
			(end -0.7874 -0.4064)
			(stroke
				(width 0.1524)
				(type default)
			)
			(layer "F.SilkS")
		)
		(fp_line
			(start 0.7874 -0.4064)
			(end 0.7874 0.4064)
			(stroke
				(width 0.1524)
				(type default)
			)
			(layer "F.SilkS")
		)
		(fp_line
			(start 0.7874 0.4064)
			(end -0.7874 0.4064)
			(stroke
				(width 0.1524)
				(type default)
			)
			(layer "F.SilkS")
		)
		(fp_line
			(start -0.67945 -0.305054)
			(end -0.12065 -0.305054)
			(stroke
				(width 0.1)
				(type default)
			)
			(layer "F.Fab")
		)
		(fp_line
			(start -0.67945 0.3048)
			(end -0.67945 -0.305054)
			(stroke
				(width 0.1)
				(type default)
			)
			(layer "F.Fab")
		)
		(fp_line
			(start -0.12065 -0.305054)
			(end -0.12065 -0.2794)
			(stroke
				(width 0.1)
				(type default)
			)
			(layer "F.Fab")
		)
		(fp_line
			(start -0.12065 -0.2794)
			(end 0.12065 -0.2794)
			(stroke
				(width 0.1)
				(type default)
			)
			(layer "F.Fab")
		)
		(fp_line
			(start -0.12065 0.2794)
			(end -0.12065 0.3048)
			(stroke
				(width 0.1)
				(type default)
			)
			(layer "F.Fab")
		)
		(fp_line
			(start -0.12065 0.3048)
			(end -0.67945 0.3048)
			(stroke
				(width 0.1)
				(type default)
			)
			(layer "F.Fab")
		)
		(fp_line
			(start 0.120396 0.2794)
			(end -0.12065 0.2794)
			(stroke
				(width 0.1)
				(type default)
			)
			(layer "F.Fab")
		)
		(fp_line
			(start 0.120396 0.3048)
			(end 0.120396 0.2794)
			(stroke
				(width 0.1)
				(type default)
			)
			(layer "F.Fab")
		)
		(fp_line
			(start 0.12065 -0.3048)
			(end 0.67945 -0.3048)
			(stroke
				(width 0.1)
				(type default)
			)
			(layer "F.Fab")
		)
		(fp_line
			(start 0.12065 -0.2794)
			(end 0.12065 -0.3048)
			(stroke
				(width 0.1)
				(type default)
			)
			(layer "F.Fab")
		)
		(fp_line
			(start 0.67945 -0.3048)
			(end 0.67945 0.3048)
			(stroke
				(width 0.1)
				(type default)
			)
			(layer "F.Fab")
		)
		(fp_line
			(start 0.67945 0.3048)
			(end 0.120396 0.3048)
			(stroke
				(width 0.1)
				(type default)
			)
			(layer "F.Fab")
		)
		(pad "1" smd circle
			(at -0.40005 0)
			(size 0 0)
			(layers "F.Cu" "F.Mask" "F.Paste")
			(net "P3V3_OCP_SFF")
		)
		(pad "2" smd circle
			(at 0.40005 0)
			(size 0 0)
			(layers "F.Cu" "F.Mask" "F.Paste")
			(net "IRQ_LVC3_OCP_SFF_WAKE_N")
		)
	)
	(footprint ""
		(layer "F.Cu")
		(at 423.61866 -362.79963)
		(property "Reference" "PC193"
			(at 0 0 0)
			(layer "F.SilkS")
			(hide yes)
			(effects
				(font
					(size 1.27 1.27)
				)
			)
		)
		(property "Value" ""
			(at 0 0 0)
			(layer "F.Fab")
			(effects
				(font
					(size 1.27 1.27)
				)
			)
		)
		(duplicate_pad_numbers_are_jumpers no)
		(fp_line
			(start -0.7874 -0.4064)
			(end 0.7874 -0.4064)
			(stroke
				(width 0.1524)
				(type default)
			)
			(layer "F.SilkS")
		)
		(fp_line
			(start -0.7874 0.4064)
			(end -0.7874 -0.4064)
			(stroke
				(width 0.1524)
				(type default)
			)
			(layer "F.SilkS")
		)
		(fp_line
			(start 0.7874 -0.4064)
			(end 0.7874 0.4064)
			(stroke
				(width 0.1524)
				(type default)
			)
			(layer "F.SilkS")
		)
		(fp_line
			(start 0.7874 0.4064)
			(end -0.7874 0.4064)
			(stroke
				(width 0.1524)
				(type default)
			)
			(layer "F.SilkS")
		)
		(fp_line
			(start -0.67945 -0.305054)
			(end -0.12065 -0.305054)
			(stroke
				(width 0.1)
				(type default)
			)
			(layer "F.Fab")
		)
		(fp_line
			(start -0.67945 0.3048)
			(end -0.67945 -0.305054)
			(stroke
				(width 0.1)
				(type default)
			)
			(layer "F.Fab")
		)
		(fp_line
			(start -0.12065 -0.305054)
			(end -0.12065 -0.2794)
			(stroke
				(width 0.1)
				(type default)
			)
			(layer "F.Fab")
		)
		(fp_line
			(start -0.12065 -0.2794)
			(end 0.12065 -0.2794)
			(stroke
				(width 0.1)
				(type default)
			)
			(layer "F.Fab")
		)
		(fp_line
			(start -0.12065 0.2794)
			(end -0.12065 0.3048)
			(stroke
				(width 0.1)
				(type default)
			)
			(layer "F.Fab")
		)
		(fp_line
			(start -0.12065 0.3048)
			(end -0.67945 0.3048)
			(stroke
				(width 0.1)
				(type default)
			)
			(layer "F.Fab")
		)
		(fp_line
			(start 0.120396 0.2794)
			(end -0.12065 0.2794)
			(stroke
				(width 0.1)
				(type default)
			)
			(layer "F.Fab")
		)
		(fp_line
			(start 0.120396 0.3048)
			(end 0.120396 0.2794)
			(stroke
				(width 0.1)
				(type default)
			)
			(layer "F.Fab")
		)
		(fp_line
			(start 0.12065 -0.3048)
			(end 0.67945 -0.3048)
			(stroke
				(width 0.1)
				(type default)
			)
			(layer "F.Fab")
		)
		(fp_line
			(start 0.12065 -0.2794)
			(end 0.12065 -0.3048)
			(stroke
				(width 0.1)
				(type default)
			)
			(layer "F.Fab")
		)
		(fp_line
			(start 0.67945 -0.3048)
			(end 0.67945 0.3048)
			(stroke
				(width 0.1)
				(type default)
			)
			(layer "F.Fab")
		)
		(fp_line
			(start 0.67945 0.3048)
			(end 0.120396 0.3048)
			(stroke
				(width 0.1)
				(type default)
			)
			(layer "F.Fab")
		)
		(pad "1" smd circle
			(at -0.40005 0)
			(size 0 0)
			(layers "F.Cu" "F.Mask" "F.Paste")
			(net "PVDD11_S3_P0_VMON")
		)
		(pad "2" smd circle
			(at 0.40005 0)
			(size 0 0)
			(layers "F.Cu" "F.Mask" "F.Paste")
			(net "GND")
		)
	)
	(footprint ""
		(layer "F.Cu")
		(at 300.364906 -346.71635)
		(property "Reference" "PU17"
			(at -3.057906 -7.58698 0)
			(unlocked yes)
			(layer "F.SilkS")
			(effects
				(font
					(size 0.7874 0.5842)
					(thickness 0.1524)
				)
				(justify left)
			)
		)
		(property "Value" ""
			(at 0 0 0)
			(layer "F.Fab")
			(effects
				(font
					(size 1.27 1.27)
				)
			)
		)
		(duplicate_pad_numbers_are_jumpers no)
		(fp_line
			(start -2.500122 -2.999994)
			(end -2.24409 -2.999994)
			(stroke
				(width 0.1524)
				(type default)
			)
			(layer "F.SilkS")
		)
		(fp_line
			(start -2.500122 -2.529078)
			(end -2.500122 -2.999994)
			(stroke
				(width 0.1524)
				(type default)
			)
			(layer "F.SilkS")
		)
		(fp_line
			(start -2.500122 0.6604)
			(end -2.500122 0.229108)
			(stroke
				(width 0.1524)
				(type default)
			)
			(layer "F.SilkS")
		)
		(fp_line
			(start -2.500122 2.999994)
			(end -2.500122 2.339594)
			(stroke
				(width 0.1524)
				(type default)
			)
			(layer "F.SilkS")
		)
		(fp_line
			(start -2.2987 2.999994)
			(end -2.500122 2.999994)
			(stroke
				(width 0.1524)
				(type default)
			)
			(layer "F.SilkS")
		)
		(fp_line
			(start 2.31394 -2.999994)
			(end 2.500122 -2.999994)
			(stroke
				(width 0.1524)
				(type default)
			)
			(layer "F.SilkS")
		)
		(fp_line
			(start 2.500122 -2.999994)
			(end 2.500122 -2.44348)
			(stroke
				(width 0.1524)
				(type default)
			)
			(layer "F.SilkS")
		)
		(fp_line
			(start 2.500122 2.339594)
			(end 2.500122 2.999994)
			(stroke
				(width 0.1524)
				(type default)
			)
			(layer "F.SilkS")
		)
		(fp_line
			(start 2.500122 2.999994)
			(end 2.2987 2.999994)
			(stroke
				(width 0.1524)
				(type default)
			)
			(layer "F.SilkS")
		)
		(fp_poly
			(pts
				(xy -3.438144 -2.695956) (xy -2.972562 -3.161538) (xy -2.740152 -2.463546)
			)
			(stroke
				(width 0)
				(type default)
			)
			(fill yes)
			(layer "F.SilkS")
		)
		(fp_line
			(start -2.500122 -2.999994)
			(end 2.500122 -2.999994)
			(stroke
				(width 0.1)
				(type default)
			)
			(layer "F.Fab")
		)
		(fp_line
			(start -2.500122 2.999994)
			(end -2.500122 -2.999994)
			(stroke
				(width 0.1)
				(type default)
			)
			(layer "F.Fab")
		)
		(fp_line
			(start 2.500122 -2.999994)
			(end 2.500122 2.999994)
			(stroke
				(width 0.1)
				(type default)
			)
			(layer "F.Fab")
		)
		(fp_line
			(start 2.500122 2.999994)
			(end -2.500122 2.999994)
			(stroke
				(width 0.1)
				(type default)
			)
			(layer "F.Fab")
		)
		(fp_poly
			(pts
				(xy -4.218432 -2.783078) (xy -4.218432 -1.767078) (xy -3.202432 -2.275078)
			)
			(stroke
				(width 0)
				(type default)
			)
			(fill yes)
			(layer "F.Fab")
		)
		(pad "1" smd rect
			(at -2.400046 -2.275078 90)
			(size 0.2286 0.6096)
			(layers "F.Cu" "F.Mask" "F.Paste")
			(net "PVDDIO_P0_VOS1")
		)
		(pad "2" smd rect
			(at -2.400046 -1.82499 90)
			(size 0.2286 0.6096)
			(layers "F.Cu" "F.Mask" "F.Paste")
			(net "GND")
		)
		(pad "3" smd rect
			(at -2.400046 -1.374902 90)
			(size 0.2286 0.6096)
			(layers "F.Cu" "F.Mask" "F.Paste")
			(net "PVDDIO_P0_VCC1")
		)
		(pad "4" smd rect
			(at -2.400046 -0.925068 90)
			(size 0.2286 0.6096)
			(layers "F.Cu" "F.Mask" "F.Paste")
			(net "PVDDCR_CPU1_P0_PVCC")
		)
		(pad "5" smd rect
			(at -2.400046 -0.47498 90)
			(size 0.2286 0.6096)
			(layers "F.Cu" "F.Mask" "F.Paste")
			(net "GND")
		)
		(pad "6" smd rect
			(at -2.400046 -0.024892 90)
			(size 0.2286 0.6096)
			(layers "F.Cu" "F.Mask" "F.Paste")
			(net "NC_PVDDIO_P0_GL1_1")
		)
		(pad "7_9-20_24" smd circle
			(at 0 1.150112 90)
			(size 0 0)
			(layers "F.Cu" "F.Mask" "F.Paste")
			(net "GND")
		)
		(pad "10_19" smd rect
			(at 0 2.899918 90)
			(size 0.6096 4.318)
			(layers "F.Cu" "F.Mask" "F.Paste")
			(net "SW_PVDDIO_P0_SW1")
		)
		(pad "25_29" smd rect
			(at 1.549908 -1.279906 270)
			(size 2.0574 2.3114)
			(layers "F.Cu" "F.Mask" "F.Paste")
			(net "SW_P12V_AUX_PVDDIO_P0_FLT")
		)
		(pad "30" smd rect
			(at 2.05994 -2.899918)
			(size 0.2286 0.6096)
			(layers "F.Cu" "F.Mask" "F.Paste")
			(net "SW_P12V_AUX_PVDDIO_P0_FLT")
		)
		(pad "31" smd rect
			(at 1.610106 -2.899918)
			(size 0.2286 0.6096)
			(layers "F.Cu" "F.Mask" "F.Paste")
			(net "NC_PVDDIO_P0_DNC1")
		)
		(pad "32" smd rect
			(at 1.160018 -2.899918)
			(size 0.2286 0.6096)
			(layers "F.Cu" "F.Mask" "F.Paste")
			(net "SW_PVDDIO_P0_BOOTR1")
		)
		(pad "33" smd rect
			(at 0.70993 -2.899918)
			(size 0.2286 0.6096)
			(layers "F.Cu" "F.Mask" "F.Paste")
			(net "SW_PVDDIO_P0_BOOT1")
		)
		(pad "34" smd rect
			(at 0.260096 -2.899918)
			(size 0.2286 0.6096)
			(layers "F.Cu" "F.Mask" "F.Paste")
			(net "PVDDIO_P0_PWM1")
		)
		(pad "35" smd rect
			(at -0.189992 -2.899918)
			(size 0.2286 0.6096)
			(layers "F.Cu" "F.Mask" "F.Paste")
			(net "PVDDIO_P0_VCC1")
		)
		(pad "36" smd rect
			(at -0.64008 -2.899918)
			(size 0.2286 0.6096)
			(layers "F.Cu" "F.Mask" "F.Paste")
			(net "PVDDIO_P0_TEMP1")
		)
		(pad "37" smd rect
			(at -1.089914 -2.899918)
			(size 0.2286 0.6096)
			(layers "F.Cu" "F.Mask" "F.Paste")
			(net "PVDDIO_P0_LSET1")
		)
		(pad "38" smd rect
			(at -1.540002 -2.899918)
			(size 0.2286 0.6096)
			(layers "F.Cu" "F.Mask" "F.Paste")
			(net "PVDDIO_P0_IMON1")
		)
		(pad "39" smd rect
			(at -1.99009 -2.899918)
			(size 0.2286 0.6096)
			(layers "F.Cu" "F.Mask" "F.Paste")
			(net "PVDDCR_CPU1_P0_VCCS")
		)
		(pad "40" smd rect
			(at -0.87503 -1.27508)
			(size 1.7526 1.9558)
			(layers "F.Cu" "F.Mask" "F.Paste")
			(net "GND")
		)
		(pad "41" smd rect
			(at -1.525016 0.249936 270)
			(size 0.3048 0.4572)
			(layers "F.Cu" "F.Mask" "F.Paste")
			(net "NC_PVDDIO_P0_GL2_1")
		)
		(zone
			(layer "F.Cu")
			(hatch none 0.5)
			(connect_pads
				(clearance 0)
			)
			(min_thickness 0.25)
			(keepout
				(tracks not_allowed)
				(vias allowed)
				(pads allowed)
				(copperpour not_allowed)
				(footprints allowed)
			)
			(placement
				(enabled no)
				(sheetname "")
			)
			(fill
				(thermal_gap 0.5)
				(thermal_bridge_width 0.5)
				(island_removal_mode 0)
			)
			(polygon
				(pts
					(xy 297.864784 -344.138758) (xy 297.864784 -344.465656) (xy 302.865028 -344.465656) (xy 302.865028 -344.130884)
					(xy 302.574706 -344.130884) (xy 302.574706 -344.172032) (xy 298.155106 -344.172032) (xy 298.155106 -344.138758)
				)
			)
		)
		(zone
			(layer "F.Cu")
			(hatch none 0.5)
			(connect_pads
				(clearance 0)
			)
			(min_thickness 0.25)
			(keepout
				(tracks not_allowed)
				(vias allowed)
				(pads allowed)
				(copperpour not_allowed)
				(footprints allowed)
			)
			(placement
				(enabled no)
				(sheetname "")
			)
			(fill
				(thermal_gap 0.5)
				(thermal_bridge_width 0.5)
				(island_removal_mode 0)
			)
			(polygon
				(pts
					(xy 300.416976 -346.96273) (xy 300.416976 -349.02013) (xy 298.562776 -349.02013) (xy 298.562776 -348.779084)
					(xy 298.32046 -348.779084) (xy 298.32046 -349.260668) (xy 302.123094 -349.260668) (xy 302.123094 -349.075756)
					(xy 300.708314 -349.075756) (xy 300.708314 -346.916756) (xy 302.865028 -346.916756) (xy 302.865028 -346.667074)
					(xy 300.661578 -346.667074) (xy 300.416976 -346.911676)
				)
			)
		)
	)
	(footprint ""
		(layer "F.Cu")
		(at 353.900232 -258.405122)
		(property "Reference" "C2599"
			(at 0 0 0)
			(layer "F.SilkS")
			(hide yes)
			(effects
				(font
					(size 1.27 1.27)
				)
			)
		)
		(property "Value" ""
			(at 0 0 0)
			(layer "F.Fab")
			(effects
				(font
					(size 1.27 1.27)
				)
			)
		)
		(duplicate_pad_numbers_are_jumpers no)
		(fp_line
			(start -0.7874 -0.4064)
			(end 0.7874 -0.4064)
			(stroke
				(width 0.1524)
				(type default)
			)
			(layer "F.SilkS")
		)
		(fp_line
			(start -0.7874 0.4064)
			(end -0.7874 -0.4064)
			(stroke
				(width 0.1524)
				(type default)
			)
			(layer "F.SilkS")
		)
		(fp_line
			(start 0.7874 -0.4064)
			(end 0.7874 0.4064)
			(stroke
				(width 0.1524)
				(type default)
			)
			(layer "F.SilkS")
		)
		(fp_line
			(start 0.7874 0.4064)
			(end -0.7874 0.4064)
			(stroke
				(width 0.1524)
				(type default)
			)
			(layer "F.SilkS")
		)
		(fp_line
			(start -0.67945 -0.305054)
			(end -0.12065 -0.305054)
			(stroke
				(width 0.1)
				(type default)
			)
			(layer "F.Fab")
		)
		(fp_line
			(start -0.67945 0.3048)
			(end -0.67945 -0.305054)
			(stroke
				(width 0.1)
				(type default)
			)
			(layer "F.Fab")
		)
		(fp_line
			(start -0.12065 -0.305054)
			(end -0.12065 -0.2794)
			(stroke
				(width 0.1)
				(type default)
			)
			(layer "F.Fab")
		)
		(fp_line
			(start -0.12065 -0.2794)
			(end 0.12065 -0.2794)
			(stroke
				(width 0.1)
				(type default)
			)
			(layer "F.Fab")
		)
		(fp_line
			(start -0.12065 0.2794)
			(end -0.12065 0.3048)
			(stroke
				(width 0.1)
				(type default)
			)
			(layer "F.Fab")
		)
		(fp_line
			(start -0.12065 0.3048)
			(end -0.67945 0.3048)
			(stroke
				(width 0.1)
				(type default)
			)
			(layer "F.Fab")
		)
		(fp_line
			(start 0.120396 0.2794)
			(end -0.12065 0.2794)
			(stroke
				(width 0.1)
				(type default)
			)
			(layer "F.Fab")
		)
		(fp_line
			(start 0.120396 0.3048)
			(end 0.120396 0.2794)
			(stroke
				(width 0.1)
				(type default)
			)
			(layer "F.Fab")
		)
		(fp_line
			(start 0.12065 -0.3048)
			(end 0.67945 -0.3048)
			(stroke
				(width 0.1)
				(type default)
			)
			(layer "F.Fab")
		)
		(fp_line
			(start 0.12065 -0.2794)
			(end 0.12065 -0.3048)
			(stroke
				(width 0.1)
				(type default)
			)
			(layer "F.Fab")
		)
		(fp_line
			(start 0.67945 -0.3048)
			(end 0.67945 0.3048)
			(stroke
				(width 0.1)
				(type default)
			)
			(layer "F.Fab")
		)
		(fp_line
			(start 0.67945 0.3048)
			(end 0.120396 0.3048)
			(stroke
				(width 0.1)
				(type default)
			)
			(layer "F.Fab")
		)
		(pad "1" smd circle
			(at -0.40005 0)
			(size 0 0)
			(layers "F.Cu" "F.Mask" "F.Paste")
			(net "PVDDIO_P0")
		)
		(pad "2" smd circle
			(at 0.40005 0)
			(size 0 0)
			(layers "F.Cu" "F.Mask" "F.Paste")
			(net "GND")
		)
	)
	(footprint ""
		(layer "F.Cu")
		(at 285.218124 -395.22019 -90)
		(property "Reference" "U143"
			(at 2.42951 -2.26187 90)
			(unlocked yes)
			(layer "F.SilkS")
			(effects
				(font
					(size 0.7874 0.5842)
					(thickness 0.1524)
				)
				(justify left)
			)
		)
		(property "Value" ""
			(at 0 0 270)
			(layer "F.Fab")
			(effects
				(font
					(size 1.27 1.27)
				)
			)
		)
		(duplicate_pad_numbers_are_jumpers no)
		(fp_line
			(start -1.448308 1.549908)
			(end -1.448308 -1.549908)
			(stroke
				(width 0.1524)
				(type default)
			)
			(layer "F.SilkS")
		)
		(fp_line
			(start 1.448308 1.549908)
			(end -1.448308 1.549908)
			(stroke
				(width 0.1524)
				(type default)
			)
			(layer "F.SilkS")
		)
		(fp_line
			(start 0 -0.533908)
			(end 0.774954 -1.549908)
			(stroke
				(width 0.1524)
				(type default)
			)
			(layer "F.SilkS")
		)
		(fp_line
			(start -1.448308 -1.549908)
			(end -0.774954 -1.549908)
			(stroke
				(width 0.1524)
				(type default)
			)
			(layer "F.SilkS")
		)
		(fp_line
			(start -0.774954 -1.549908)
			(end 0 -0.533908)
			(stroke
				(width 0.1524)
				(type default)
			)
			(layer "F.SilkS")
		)
		(fp_line
			(start 0.774954 -1.549908)
			(end 1.448308 -1.549908)
			(stroke
				(width 0.1524)
				(type default)
			)
			(layer "F.SilkS")
		)
		(fp_line
			(start 1.448308 -1.549908)
			(end 1.448308 1.549908)
			(stroke
				(width 0.1524)
				(type default)
			)
			(layer "F.SilkS")
		)
		(fp_rect
			(start -1.549908 -1.549908)
			(end -0.787908 -1.880108)
			(stroke
				(width 0)
				(type default)
			)
			(fill yes)
			(layer "F.SilkS")
		)
		(fp_line
			(start -1.549908 1.549908)
			(end -1.549908 -1.549908)
			(stroke
				(width 0.1)
				(type default)
			)
			(layer "F.Fab")
		)
		(fp_line
			(start 1.549908 1.549908)
			(end -1.549908 1.549908)
			(stroke
				(width 0.1)
				(type default)
			)
			(layer "F.Fab")
		)
		(fp_line
			(start -1.549908 -1.549908)
			(end 1.549908 -1.549908)
			(stroke
				(width 0.1)
				(type default)
			)
			(layer "F.Fab")
		)
		(fp_line
			(start 1.549908 -1.549908)
			(end 1.549908 1.549908)
			(stroke
				(width 0.1)
				(type default)
			)
			(layer "F.Fab")
		)
		(fp_poly
			(pts
				(xy -1.549908 -1.549908) (xy -0.787908 -1.549908) (xy -0.787908 -1.880108) (xy -1.549908 -1.880108)
			)
			(stroke
				(width 0)
				(type default)
			)
			(fill yes)
			(layer "F.Fab")
		)
		(pad "1" smd rect
			(at -2.350008 -0.975106 180)
			(size 0.4318 1.4986)
			(layers "F.Cu" "F.Mask" "F.Paste")
			(net "P3V3_AUX")
		)
		(pad "2" smd rect
			(at -2.350008 -0.32512 180)
			(size 0.4318 1.4986)
			(layers "F.Cu" "F.Mask" "F.Paste")
			(net "P12V_HSC_TEMP_D+")
		)
		(pad "3" smd rect
			(at -2.350008 0.32512 180)
			(size 0.4318 1.4986)
			(layers "F.Cu" "F.Mask" "F.Paste")
			(net "P12V_HSC_TEMP_D-")
		)
		(pad "4" smd rect
			(at -2.350008 0.975106 180)
			(size 0.4318 1.4986)
			(layers "F.Cu" "F.Mask" "F.Paste")
			(net "P12V_HSC_T_CRIT_N")
		)
		(pad "5" smd rect
			(at 2.350008 0.975106 180)
			(size 0.4318 1.4986)
			(layers "F.Cu" "F.Mask" "F.Paste")
			(net "GND")
		)
		(pad "6" smd rect
			(at 2.350008 0.32512 180)
			(size 0.4318 1.4986)
			(layers "F.Cu" "F.Mask" "F.Paste")
			(net "P12V_HSC_TEMP_ALERT_N")
		)
		(pad "7" smd rect
			(at 2.350008 -0.32512 180)
			(size 0.4318 1.4986)
			(layers "F.Cu" "F.Mask" "F.Paste")
			(net "SMB_P12V_HSC_TEMP_SDA")
		)
		(pad "8" smd rect
			(at 2.350008 -0.975106 180)
			(size 0.4318 1.4986)
			(layers "F.Cu" "F.Mask" "F.Paste")
			(net "SMB_P12V_HSC_TEMP_SCL")
		)
	)
	(footprint ""
		(layer "F.Cu")
		(at 273.183604 -108.194856 -90)
		(property "Reference" "R6070"
			(at 0 0 270)
			(layer "F.SilkS")
			(hide yes)
			(effects
				(font
					(size 1.27 1.27)
				)
			)
		)
		(property "Value" ""
			(at 0 0 270)
			(layer "F.Fab")
			(effects
				(font
					(size 1.27 1.27)
				)
			)
		)
		(duplicate_pad_numbers_are_jumpers no)
		(fp_line
			(start -0.7874 0.4064)
			(end -0.7874 -0.4064)
			(stroke
				(width 0.1524)
				(type default)
			)
			(layer "F.SilkS")
		)
		(fp_line
			(start 0.7874 0.4064)
			(end -0.7874 0.4064)
			(stroke
				(width 0.1524)
				(type default)
			)
			(layer "F.SilkS")
		)
		(fp_line
			(start -0.7874 -0.4064)
			(end 0.7874 -0.4064)
			(stroke
				(width 0.1524)
				(type default)
			)
			(layer "F.SilkS")
		)
		(fp_line
			(start 0.7874 -0.4064)
			(end 0.7874 0.4064)
			(stroke
				(width 0.1524)
				(type default)
			)
			(layer "F.SilkS")
		)
		(fp_line
			(start -0.67945 0.3048)
			(end -0.67945 -0.305054)
			(stroke
				(width 0.1)
				(type default)
			)
			(layer "F.Fab")
		)
		(fp_line
			(start -0.12065 0.3048)
			(end -0.67945 0.3048)
			(stroke
				(width 0.1)
				(type default)
			)
			(layer "F.Fab")
		)
		(fp_line
			(start 0.120396 0.3048)
			(end 0.120396 0.2794)
			(stroke
				(width 0.1)
				(type default)
			)
			(layer "F.Fab")
		)
		(fp_line
			(start 0.67945 0.3048)
			(end 0.120396 0.3048)
			(stroke
				(width 0.1)
				(type default)
			)
			(layer "F.Fab")
		)
		(fp_line
			(start -0.12065 0.2794)
			(end -0.12065 0.3048)
			(stroke
				(width 0.1)
				(type default)
			)
			(layer "F.Fab")
		)
		(fp_line
			(start 0.120396 0.2794)
			(end -0.12065 0.2794)
			(stroke
				(width 0.1)
				(type default)
			)
			(layer "F.Fab")
		)
		(fp_line
			(start -0.12065 -0.2794)
			(end 0.12065 -0.2794)
			(stroke
				(width 0.1)
				(type default)
			)
			(layer "F.Fab")
		)
		(fp_line
			(start 0.12065 -0.2794)
			(end 0.12065 -0.3048)
			(stroke
				(width 0.1)
				(type default)
			)
			(layer "F.Fab")
		)
		(fp_line
			(start 0.12065 -0.3048)
			(end 0.67945 -0.3048)
			(stroke
				(width 0.1)
				(type default)
			)
			(layer "F.Fab")
		)
		(fp_line
			(start 0.67945 -0.3048)
			(end 0.67945 0.3048)
			(stroke
				(width 0.1)
				(type default)
			)
			(layer "F.Fab")
		)
		(fp_line
			(start -0.67945 -0.305054)
			(end -0.12065 -0.305054)
			(stroke
				(width 0.1)
				(type default)
			)
			(layer "F.Fab")
		)
		(fp_line
			(start -0.12065 -0.305054)
			(end -0.12065 -0.2794)
			(stroke
				(width 0.1)
				(type default)
			)
			(layer "F.Fab")
		)
		(pad "1" smd circle
			(at -0.40005 0 270)
			(size 0 0)
			(layers "F.Cu" "F.Mask" "F.Paste")
			(net "P3V3_AUX")
		)
		(pad "2" smd circle
			(at 0.40005 0 270)
			(size 0 0)
			(layers "F.Cu" "F.Mask" "F.Paste")
			(net "JTAG_SCM_DBREQ_N")
		)
	)
	(footprint ""
		(layer "F.Cu")
		(at 361.046014 -259.845048)
		(property "Reference" "C2657"
			(at 0 0 0)
			(layer "F.SilkS")
			(hide yes)
			(effects
				(font
					(size 1.27 1.27)
				)
			)
		)
		(property "Value" ""
			(at 0 0 0)
			(layer "F.Fab")
			(effects
				(font
					(size 1.27 1.27)
				)
			)
		)
		(duplicate_pad_numbers_are_jumpers no)
		(fp_line
			(start -0.7874 -0.4064)
			(end 0.7874 -0.4064)
			(stroke
				(width 0.1524)
				(type default)
			)
			(layer "F.SilkS")
		)
		(fp_line
			(start -0.7874 0.4064)
			(end -0.7874 -0.4064)
			(stroke
				(width 0.1524)
				(type default)
			)
			(layer "F.SilkS")
		)
		(fp_line
			(start 0.7874 -0.4064)
			(end 0.7874 0.4064)
			(stroke
				(width 0.1524)
				(type default)
			)
			(layer "F.SilkS")
		)
		(fp_line
			(start 0.7874 0.4064)
			(end -0.7874 0.4064)
			(stroke
				(width 0.1524)
				(type default)
			)
			(layer "F.SilkS")
		)
		(fp_line
			(start -0.67945 -0.305054)
			(end -0.12065 -0.305054)
			(stroke
				(width 0.1)
				(type default)
			)
			(layer "F.Fab")
		)
		(fp_line
			(start -0.67945 0.3048)
			(end -0.67945 -0.305054)
			(stroke
				(width 0.1)
				(type default)
			)
			(layer "F.Fab")
		)
		(fp_line
			(start -0.12065 -0.305054)
			(end -0.12065 -0.2794)
			(stroke
				(width 0.1)
				(type default)
			)
			(layer "F.Fab")
		)
		(fp_line
			(start -0.12065 -0.2794)
			(end 0.12065 -0.2794)
			(stroke
				(width 0.1)
				(type default)
			)
			(layer "F.Fab")
		)
		(fp_line
			(start -0.12065 0.2794)
			(end -0.12065 0.3048)
			(stroke
				(width 0.1)
				(type default)
			)
			(layer "F.Fab")
		)
		(fp_line
			(start -0.12065 0.3048)
			(end -0.67945 0.3048)
			(stroke
				(width 0.1)
				(type default)
			)
			(layer "F.Fab")
		)
		(fp_line
			(start 0.120396 0.2794)
			(end -0.12065 0.2794)
			(stroke
				(width 0.1)
				(type default)
			)
			(layer "F.Fab")
		)
		(fp_line
			(start 0.120396 0.3048)
			(end 0.120396 0.2794)
			(stroke
				(width 0.1)
				(type default)
			)
			(layer "F.Fab")
		)
		(fp_line
			(start 0.12065 -0.3048)
			(end 0.67945 -0.3048)
			(stroke
				(width 0.1)
				(type default)
			)
			(layer "F.Fab")
		)
		(fp_line
			(start 0.12065 -0.2794)
			(end 0.12065 -0.3048)
			(stroke
				(width 0.1)
				(type default)
			)
			(layer "F.Fab")
		)
		(fp_line
			(start 0.67945 -0.3048)
			(end 0.67945 0.3048)
			(stroke
				(width 0.1)
				(type default)
			)
			(layer "F.Fab")
		)
		(fp_line
			(start 0.67945 0.3048)
			(end 0.120396 0.3048)
			(stroke
				(width 0.1)
				(type default)
			)
			(layer "F.Fab")
		)
		(pad "1" smd circle
			(at -0.40005 0)
			(size 0 0)
			(layers "F.Cu" "F.Mask" "F.Paste")
			(net "PVDD11_S3_P0")
		)
		(pad "2" smd circle
			(at 0.40005 0)
			(size 0 0)
			(layers "F.Cu" "F.Mask" "F.Paste")
			(net "GND")
		)
	)
	(footprint ""
		(layer "F.Cu")
		(at 43.754294 -16.099536 90)
		(property "Reference" "C698"
			(at 0 0 90)
			(layer "F.SilkS")
			(hide yes)
			(effects
				(font
					(size 1.27 1.27)
				)
			)
		)
		(property "Value" ""
			(at 0 0 90)
			(layer "F.Fab")
			(effects
				(font
					(size 1.27 1.27)
				)
			)
		)
		(duplicate_pad_numbers_are_jumpers no)
		(fp_line
			(start 0.299974 -0.150114)
			(end 0.299974 0.150114)
			(stroke
				(width 0.1)
				(type default)
			)
			(layer "F.Fab")
		)
		(fp_line
			(start -0.299974 -0.150114)
			(end 0.299974 -0.150114)
			(stroke
				(width 0.1)
				(type default)
			)
			(layer "F.Fab")
		)
		(fp_line
			(start 0.299974 0.150114)
			(end -0.299974 0.150114)
			(stroke
				(width 0.1)
				(type default)
			)
			(layer "F.Fab")
		)
		(fp_line
			(start -0.299974 0.150114)
			(end -0.299974 -0.150114)
			(stroke
				(width 0.1)
				(type default)
			)
			(layer "F.Fab")
		)
		(pad "1" smd rect
			(at -0.2667 0 90)
			(size 0.3048 0.381)
			(layers "F.Cu" "F.Mask" "F.Paste")
			(net "P5E_CPU1_G1_TX_C_DN<5>")
		)
		(pad "2" smd rect
			(at 0.2667 0 90)
			(size 0.3048 0.381)
			(layers "F.Cu" "F.Mask" "F.Paste")
			(net "P5E_CPU1_G1_TX_DN<5>")
		)
	)
	(footprint ""
		(layer "F.Cu")
		(at 211.074 -129.54 -90)
		(property "Reference" "R568"
			(at 0 0 270)
			(layer "F.SilkS")
			(hide yes)
			(effects
				(font
					(size 1.27 1.27)
				)
			)
		)
		(property "Value" ""
			(at 0 0 270)
			(layer "F.Fab")
			(effects
				(font
					(size 1.27 1.27)
				)
			)
		)
		(duplicate_pad_numbers_are_jumpers no)
		(fp_line
			(start -0.7874 0.4064)
			(end -0.7874 -0.4064)
			(stroke
				(width 0.1524)
				(type default)
			)
			(layer "F.SilkS")
		)
		(fp_line
			(start 0.7874 0.4064)
			(end -0.7874 0.4064)
			(stroke
				(width 0.1524)
				(type default)
			)
			(layer "F.SilkS")
		)
		(fp_line
			(start -0.7874 -0.4064)
			(end 0.7874 -0.4064)
			(stroke
				(width 0.1524)
				(type default)
			)
			(layer "F.SilkS")
		)
		(fp_line
			(start 0.7874 -0.4064)
			(end 0.7874 0.4064)
			(stroke
				(width 0.1524)
				(type default)
			)
			(layer "F.SilkS")
		)
		(fp_line
			(start -0.67945 0.3048)
			(end -0.67945 -0.305054)
			(stroke
				(width 0.1)
				(type default)
			)
			(layer "F.Fab")
		)
		(fp_line
			(start -0.12065 0.3048)
			(end -0.67945 0.3048)
			(stroke
				(width 0.1)
				(type default)
			)
			(layer "F.Fab")
		)
		(fp_line
			(start 0.120396 0.3048)
			(end 0.120396 0.2794)
			(stroke
				(width 0.1)
				(type default)
			)
			(layer "F.Fab")
		)
		(fp_line
			(start 0.67945 0.3048)
			(end 0.120396 0.3048)
			(stroke
				(width 0.1)
				(type default)
			)
			(layer "F.Fab")
		)
		(fp_line
			(start -0.12065 0.2794)
			(end -0.12065 0.3048)
			(stroke
				(width 0.1)
				(type default)
			)
			(layer "F.Fab")
		)
		(fp_line
			(start 0.120396 0.2794)
			(end -0.12065 0.2794)
			(stroke
				(width 0.1)
				(type default)
			)
			(layer "F.Fab")
		)
		(fp_line
			(start -0.12065 -0.2794)
			(end 0.12065 -0.2794)
			(stroke
				(width 0.1)
				(type default)
			)
			(layer "F.Fab")
		)
		(fp_line
			(start 0.12065 -0.2794)
			(end 0.12065 -0.3048)
			(stroke
				(width 0.1)
				(type default)
			)
			(layer "F.Fab")
		)
		(fp_line
			(start 0.12065 -0.3048)
			(end 0.67945 -0.3048)
			(stroke
				(width 0.1)
				(type default)
			)
			(layer "F.Fab")
		)
		(fp_line
			(start 0.67945 -0.3048)
			(end 0.67945 0.3048)
			(stroke
				(width 0.1)
				(type default)
			)
			(layer "F.Fab")
		)
		(fp_line
			(start -0.67945 -0.305054)
			(end -0.12065 -0.305054)
			(stroke
				(width 0.1)
				(type default)
			)
			(layer "F.Fab")
		)
		(fp_line
			(start -0.12065 -0.305054)
			(end -0.12065 -0.2794)
			(stroke
				(width 0.1)
				(type default)
			)
			(layer "F.Fab")
		)
		(pad "1" smd circle
			(at -0.40005 0 270)
			(size 0 0)
			(layers "F.Cu" "F.Mask" "F.Paste")
			(net "P12V_AUX")
		)
		(pad "2" smd circle
			(at 0.40005 0 270)
			(size 0 0)
			(layers "F.Cu" "F.Mask" "F.Paste")
			(net "SW_P3V3_EN_ISO_R")
		)
	)
	(footprint ""
		(layer "F.Cu")
		(at 291.509958 -397.59001 180)
		(property "Reference" "R836"
			(at 0 0 180)
			(layer "F.SilkS")
			(hide yes)
			(effects
				(font
					(size 1.27 1.27)
				)
			)
		)
		(property "Value" ""
			(at 0 0 180)
			(layer "F.Fab")
			(effects
				(font
					(size 1.27 1.27)
				)
			)
		)
		(duplicate_pad_numbers_are_jumpers no)
		(fp_line
			(start 0.32512 0.175006)
			(end -0.32512 0.175006)
			(stroke
				(width 0.1)
				(type default)
			)
			(layer "F.Fab")
		)
		(fp_line
			(start 0.32512 -0.175006)
			(end 0.32512 0.175006)
			(stroke
				(width 0.1)
				(type default)
			)
			(layer "F.Fab")
		)
		(fp_line
			(start -0.32512 0.175006)
			(end -0.32512 -0.175006)
			(stroke
				(width 0.1)
				(type default)
			)
			(layer "F.Fab")
		)
		(fp_line
			(start -0.32512 -0.175006)
			(end 0.32512 -0.175006)
			(stroke
				(width 0.1)
				(type default)
			)
			(layer "F.Fab")
		)
		(pad "1" smd rect
			(at -0.2667 0 180)
			(size 0.3048 0.381)
			(layers "F.Cu" "F.Mask" "F.Paste")
			(net "P1V8_CPU0_RT_1D")
		)
		(pad "2" smd rect
			(at 0.2667 0)
			(size 0.3048 0.381)
			(layers "F.Cu" "F.Mask" "F.Paste")
			(net "SMB_RT_CPU0_P1_ROM_R_SDA")
		)
	)
	(footprint ""
		(layer "F.Cu")
		(at 28.537662 -419.249098 90)
		(property "Reference" "R3271"
			(at 0 0 90)
			(layer "F.SilkS")
			(hide yes)
			(effects
				(font
					(size 1.27 1.27)
				)
			)
		)
		(property "Value" ""
			(at 0 0 90)
			(layer "F.Fab")
			(effects
				(font
					(size 1.27 1.27)
				)
			)
		)
		(duplicate_pad_numbers_are_jumpers no)
		(fp_line
			(start 0.7874 -0.4064)
			(end 0.7874 0.4064)
			(stroke
				(width 0.1524)
				(type default)
			)
			(layer "F.SilkS")
		)
		(fp_line
			(start -0.7874 -0.4064)
			(end 0.7874 -0.4064)
			(stroke
				(width 0.1524)
				(type default)
			)
			(layer "F.SilkS")
		)
		(fp_line
			(start 0.7874 0.4064)
			(end -0.7874 0.4064)
			(stroke
				(width 0.1524)
				(type default)
			)
			(layer "F.SilkS")
		)
		(fp_line
			(start -0.7874 0.4064)
			(end -0.7874 -0.4064)
			(stroke
				(width 0.1524)
				(type default)
			)
			(layer "F.SilkS")
		)
		(fp_line
			(start -0.12065 -0.305054)
			(end -0.12065 -0.2794)
			(stroke
				(width 0.1)
				(type default)
			)
			(layer "F.Fab")
		)
		(fp_line
			(start -0.67945 -0.305054)
			(end -0.12065 -0.305054)
			(stroke
				(width 0.1)
				(type default)
			)
			(layer "F.Fab")
		)
		(fp_line
			(start 0.67945 -0.3048)
			(end 0.67945 0.3048)
			(stroke
				(width 0.1)
				(type default)
			)
			(layer "F.Fab")
		)
		(fp_line
			(start 0.12065 -0.3048)
			(end 0.67945 -0.3048)
			(stroke
				(width 0.1)
				(type default)
			)
			(layer "F.Fab")
		)
		(fp_line
			(start 0.12065 -0.2794)
			(end 0.12065 -0.3048)
			(stroke
				(width 0.1)
				(type default)
			)
			(layer "F.Fab")
		)
		(fp_line
			(start -0.12065 -0.2794)
			(end 0.12065 -0.2794)
			(stroke
				(width 0.1)
				(type default)
			)
			(layer "F.Fab")
		)
		(fp_line
			(start 0.120396 0.2794)
			(end -0.12065 0.2794)
			(stroke
				(width 0.1)
				(type default)
			)
			(layer "F.Fab")
		)
		(fp_line
			(start -0.12065 0.2794)
			(end -0.12065 0.3048)
			(stroke
				(width 0.1)
				(type default)
			)
			(layer "F.Fab")
		)
		(fp_line
			(start 0.67945 0.3048)
			(end 0.120396 0.3048)
			(stroke
				(width 0.1)
				(type default)
			)
			(layer "F.Fab")
		)
		(fp_line
			(start 0.120396 0.3048)
			(end 0.120396 0.2794)
			(stroke
				(width 0.1)
				(type default)
			)
			(layer "F.Fab")
		)
		(fp_line
			(start -0.12065 0.3048)
			(end -0.67945 0.3048)
			(stroke
				(width 0.1)
				(type default)
			)
			(layer "F.Fab")
		)
		(fp_line
			(start -0.67945 0.3048)
			(end -0.67945 -0.305054)
			(stroke
				(width 0.1)
				(type default)
			)
			(layer "F.Fab")
		)
		(pad "1" smd circle
			(at -0.40005 0 90)
			(size 0 0)
			(layers "F.Cu" "F.Mask" "F.Paste")
			(net "P3V3_AUX")
		)
		(pad "2" smd circle
			(at 0.40005 0 90)
			(size 0 0)
			(layers "F.Cu" "F.Mask" "F.Paste")
			(net "FM_P2E_EQA1")
		)
	)
	(footprint ""
		(layer "F.Cu")
		(at 434.678836 -168.208452)
		(property "Reference" "R5008"
			(at 0 0 0)
			(layer "F.SilkS")
			(hide yes)
			(effects
				(font
					(size 1.27 1.27)
				)
			)
		)
		(property "Value" ""
			(at 0 0 0)
			(layer "F.Fab")
			(effects
				(font
					(size 1.27 1.27)
				)
			)
		)
		(duplicate_pad_numbers_are_jumpers no)
		(fp_line
			(start -0.7874 -0.4064)
			(end 0.7874 -0.4064)
			(stroke
				(width 0.1524)
				(type default)
			)
			(layer "F.SilkS")
		)
		(fp_line
			(start -0.7874 0.4064)
			(end -0.7874 -0.4064)
			(stroke
				(width 0.1524)
				(type default)
			)
			(layer "F.SilkS")
		)
		(fp_line
			(start 0.7874 -0.4064)
			(end 0.7874 0.4064)
			(stroke
				(width 0.1524)
				(type default)
			)
			(layer "F.SilkS")
		)
		(fp_line
			(start 0.7874 0.4064)
			(end -0.7874 0.4064)
			(stroke
				(width 0.1524)
				(type default)
			)
			(layer "F.SilkS")
		)
		(fp_line
			(start -0.67945 -0.305054)
			(end -0.12065 -0.305054)
			(stroke
				(width 0.1)
				(type default)
			)
			(layer "F.Fab")
		)
		(fp_line
			(start -0.67945 0.3048)
			(end -0.67945 -0.305054)
			(stroke
				(width 0.1)
				(type default)
			)
			(layer "F.Fab")
		)
		(fp_line
			(start -0.12065 -0.305054)
			(end -0.12065 -0.2794)
			(stroke
				(width 0.1)
				(type default)
			)
			(layer "F.Fab")
		)
		(fp_line
			(start -0.12065 -0.2794)
			(end 0.12065 -0.2794)
			(stroke
				(width 0.1)
				(type default)
			)
			(layer "F.Fab")
		)
		(fp_line
			(start -0.12065 0.2794)
			(end -0.12065 0.3048)
			(stroke
				(width 0.1)
				(type default)
			)
			(layer "F.Fab")
		)
		(fp_line
			(start -0.12065 0.3048)
			(end -0.67945 0.3048)
			(stroke
				(width 0.1)
				(type default)
			)
			(layer "F.Fab")
		)
		(fp_line
			(start 0.120396 0.2794)
			(end -0.12065 0.2794)
			(stroke
				(width 0.1)
				(type default)
			)
			(layer "F.Fab")
		)
		(fp_line
			(start 0.120396 0.3048)
			(end 0.120396 0.2794)
			(stroke
				(width 0.1)
				(type default)
			)
			(layer "F.Fab")
		)
		(fp_line
			(start 0.12065 -0.3048)
			(end 0.67945 -0.3048)
			(stroke
				(width 0.1)
				(type default)
			)
			(layer "F.Fab")
		)
		(fp_line
			(start 0.12065 -0.2794)
			(end 0.12065 -0.3048)
			(stroke
				(width 0.1)
				(type default)
			)
			(layer "F.Fab")
		)
		(fp_line
			(start 0.67945 -0.3048)
			(end 0.67945 0.3048)
			(stroke
				(width 0.1)
				(type default)
			)
			(layer "F.Fab")
		)
		(fp_line
			(start 0.67945 0.3048)
			(end 0.120396 0.3048)
			(stroke
				(width 0.1)
				(type default)
			)
			(layer "F.Fab")
		)
		(pad "1" smd circle
			(at -0.40005 0)
			(size 0 0)
			(layers "F.Cu" "F.Mask" "F.Paste")
			(net "PVDD11_S3_P0")
		)
		(pad "2" smd circle
			(at 0.40005 0)
			(size 0 0)
			(layers "F.Cu" "F.Mask" "F.Paste")
			(net "I3C_SPD_DDRGL_CPU0_LVC1_SCL")
		)
	)
	(footprint ""
		(layer "F.Cu")
		(at 148.494242 -104.608884)
		(property "Reference" "R5377"
			(at 0 0 0)
			(layer "F.SilkS")
			(hide yes)
			(effects
				(font
					(size 1.27 1.27)
				)
			)
		)
		(property "Value" ""
			(at 0 0 0)
			(layer "F.Fab")
			(effects
				(font
					(size 1.27 1.27)
				)
			)
		)
		(duplicate_pad_numbers_are_jumpers no)
		(fp_line
			(start -0.7874 -0.4064)
			(end 0.7874 -0.4064)
			(stroke
				(width 0.1524)
				(type default)
			)
			(layer "F.SilkS")
		)
		(fp_line
			(start -0.7874 0.4064)
			(end -0.7874 -0.4064)
			(stroke
				(width 0.1524)
				(type default)
			)
			(layer "F.SilkS")
		)
		(fp_line
			(start 0.7874 -0.4064)
			(end 0.7874 0.4064)
			(stroke
				(width 0.1524)
				(type default)
			)
			(layer "F.SilkS")
		)
		(fp_line
			(start 0.7874 0.4064)
			(end -0.7874 0.4064)
			(stroke
				(width 0.1524)
				(type default)
			)
			(layer "F.SilkS")
		)
		(fp_line
			(start -0.67945 -0.305054)
			(end -0.12065 -0.305054)
			(stroke
				(width 0.1)
				(type default)
			)
			(layer "F.Fab")
		)
		(fp_line
			(start -0.67945 0.3048)
			(end -0.67945 -0.305054)
			(stroke
				(width 0.1)
				(type default)
			)
			(layer "F.Fab")
		)
		(fp_line
			(start -0.12065 -0.305054)
			(end -0.12065 -0.2794)
			(stroke
				(width 0.1)
				(type default)
			)
			(layer "F.Fab")
		)
		(fp_line
			(start -0.12065 -0.2794)
			(end 0.12065 -0.2794)
			(stroke
				(width 0.1)
				(type default)
			)
			(layer "F.Fab")
		)
		(fp_line
			(start -0.12065 0.2794)
			(end -0.12065 0.3048)
			(stroke
				(width 0.1)
				(type default)
			)
			(layer "F.Fab")
		)
		(fp_line
			(start -0.12065 0.3048)
			(end -0.67945 0.3048)
			(stroke
				(width 0.1)
				(type default)
			)
			(layer "F.Fab")
		)
		(fp_line
			(start 0.120396 0.2794)
			(end -0.12065 0.2794)
			(stroke
				(width 0.1)
				(type default)
			)
			(layer "F.Fab")
		)
		(fp_line
			(start 0.120396 0.3048)
			(end 0.120396 0.2794)
			(stroke
				(width 0.1)
				(type default)
			)
			(layer "F.Fab")
		)
		(fp_line
			(start 0.12065 -0.3048)
			(end 0.67945 -0.3048)
			(stroke
				(width 0.1)
				(type default)
			)
			(layer "F.Fab")
		)
		(fp_line
			(start 0.12065 -0.2794)
			(end 0.12065 -0.3048)
			(stroke
				(width 0.1)
				(type default)
			)
			(layer "F.Fab")
		)
		(fp_line
			(start 0.67945 -0.3048)
			(end 0.67945 0.3048)
			(stroke
				(width 0.1)
				(type default)
			)
			(layer "F.Fab")
		)
		(fp_line
			(start 0.67945 0.3048)
			(end 0.120396 0.3048)
			(stroke
				(width 0.1)
				(type default)
			)
			(layer "F.Fab")
		)
		(pad "1" smd circle
			(at -0.40005 0)
			(size 0 0)
			(layers "F.Cu" "F.Mask" "F.Paste")
			(net "HDD_ACTIVITY_BUF_N")
		)
		(pad "2" smd circle
			(at 0.40005 0)
			(size 0 0)
			(layers "F.Cu" "F.Mask" "F.Paste")
			(net "PU_BUFFER_HDD_ACTIVITY")
		)
	)
	(footprint ""
		(layer "F.Cu")
		(at 205.232 -130.048)
		(property "Reference" "R487"
			(at 0 0 0)
			(layer "F.SilkS")
			(hide yes)
			(effects
				(font
					(size 1.27 1.27)
				)
			)
		)
		(property "Value" ""
			(at 0 0 0)
			(layer "F.Fab")
			(effects
				(font
					(size 1.27 1.27)
				)
			)
		)
		(duplicate_pad_numbers_are_jumpers no)
		(fp_line
			(start -0.7874 -0.4064)
			(end 0.7874 -0.4064)
			(stroke
				(width 0.1524)
				(type default)
			)
			(layer "F.SilkS")
		)
		(fp_line
			(start -0.7874 0.4064)
			(end -0.7874 -0.4064)
			(stroke
				(width 0.1524)
				(type default)
			)
			(layer "F.SilkS")
		)
		(fp_line
			(start 0.7874 -0.4064)
			(end 0.7874 0.4064)
			(stroke
				(width 0.1524)
				(type default)
			)
			(layer "F.SilkS")
		)
		(fp_line
			(start 0.7874 0.4064)
			(end -0.7874 0.4064)
			(stroke
				(width 0.1524)
				(type default)
			)
			(layer "F.SilkS")
		)
		(fp_line
			(start -0.67945 -0.305054)
			(end -0.12065 -0.305054)
			(stroke
				(width 0.1)
				(type default)
			)
			(layer "F.Fab")
		)
		(fp_line
			(start -0.67945 0.3048)
			(end -0.67945 -0.305054)
			(stroke
				(width 0.1)
				(type default)
			)
			(layer "F.Fab")
		)
		(fp_line
			(start -0.12065 -0.305054)
			(end -0.12065 -0.2794)
			(stroke
				(width 0.1)
				(type default)
			)
			(layer "F.Fab")
		)
		(fp_line
			(start -0.12065 -0.2794)
			(end 0.12065 -0.2794)
			(stroke
				(width 0.1)
				(type default)
			)
			(layer "F.Fab")
		)
		(fp_line
			(start -0.12065 0.2794)
			(end -0.12065 0.3048)
			(stroke
				(width 0.1)
				(type default)
			)
			(layer "F.Fab")
		)
		(fp_line
			(start -0.12065 0.3048)
			(end -0.67945 0.3048)
			(stroke
				(width 0.1)
				(type default)
			)
			(layer "F.Fab")
		)
		(fp_line
			(start 0.120396 0.2794)
			(end -0.12065 0.2794)
			(stroke
				(width 0.1)
				(type default)
			)
			(layer "F.Fab")
		)
		(fp_line
			(start 0.120396 0.3048)
			(end 0.120396 0.2794)
			(stroke
				(width 0.1)
				(type default)
			)
			(layer "F.Fab")
		)
		(fp_line
			(start 0.12065 -0.3048)
			(end 0.67945 -0.3048)
			(stroke
				(width 0.1)
				(type default)
			)
			(layer "F.Fab")
		)
		(fp_line
			(start 0.12065 -0.2794)
			(end 0.12065 -0.3048)
			(stroke
				(width 0.1)
				(type default)
			)
			(layer "F.Fab")
		)
		(fp_line
			(start 0.67945 -0.3048)
			(end 0.67945 0.3048)
			(stroke
				(width 0.1)
				(type default)
			)
			(layer "F.Fab")
		)
		(fp_line
			(start 0.67945 0.3048)
			(end 0.120396 0.3048)
			(stroke
				(width 0.1)
				(type default)
			)
			(layer "F.Fab")
		)
		(pad "1" smd circle
			(at -0.40005 0)
			(size 0 0)
			(layers "F.Cu" "F.Mask" "F.Paste")
			(net "SW_P3V3_EN")
		)
		(pad "2" smd circle
			(at 0.40005 0)
			(size 0 0)
			(layers "F.Cu" "F.Mask" "F.Paste")
			(net "SW_P3V3_EN_R")
		)
	)
	(footprint ""
		(layer "F.Cu")
		(at 269.023084 -332.029562)
		(property "Reference" "PR52"
			(at 0 0 0)
			(layer "F.SilkS")
			(hide yes)
			(effects
				(font
					(size 1.27 1.27)
				)
			)
		)
		(property "Value" ""
			(at 0 0 0)
			(layer "F.Fab")
			(effects
				(font
					(size 1.27 1.27)
				)
			)
		)
		(duplicate_pad_numbers_are_jumpers no)
		(fp_line
			(start -0.7874 -0.4064)
			(end 0.7874 -0.4064)
			(stroke
				(width 0.1524)
				(type default)
			)
			(layer "F.SilkS")
		)
		(fp_line
			(start -0.7874 0.4064)
			(end -0.7874 -0.4064)
			(stroke
				(width 0.1524)
				(type default)
			)
			(layer "F.SilkS")
		)
		(fp_line
			(start 0.7874 -0.4064)
			(end 0.7874 0.4064)
			(stroke
				(width 0.1524)
				(type default)
			)
			(layer "F.SilkS")
		)
		(fp_line
			(start 0.7874 0.4064)
			(end -0.7874 0.4064)
			(stroke
				(width 0.1524)
				(type default)
			)
			(layer "F.SilkS")
		)
		(fp_line
			(start -0.67945 -0.305054)
			(end -0.12065 -0.305054)
			(stroke
				(width 0.1)
				(type default)
			)
			(layer "F.Fab")
		)
		(fp_line
			(start -0.67945 0.3048)
			(end -0.67945 -0.305054)
			(stroke
				(width 0.1)
				(type default)
			)
			(layer "F.Fab")
		)
		(fp_line
			(start -0.12065 -0.305054)
			(end -0.12065 -0.2794)
			(stroke
				(width 0.1)
				(type default)
			)
			(layer "F.Fab")
		)
		(fp_line
			(start -0.12065 -0.2794)
			(end 0.12065 -0.2794)
			(stroke
				(width 0.1)
				(type default)
			)
			(layer "F.Fab")
		)
		(fp_line
			(start -0.12065 0.2794)
			(end -0.12065 0.3048)
			(stroke
				(width 0.1)
				(type default)
			)
			(layer "F.Fab")
		)
		(fp_line
			(start -0.12065 0.3048)
			(end -0.67945 0.3048)
			(stroke
				(width 0.1)
				(type default)
			)
			(layer "F.Fab")
		)
		(fp_line
			(start 0.120396 0.2794)
			(end -0.12065 0.2794)
			(stroke
				(width 0.1)
				(type default)
			)
			(layer "F.Fab")
		)
		(fp_line
			(start 0.120396 0.3048)
			(end 0.120396 0.2794)
			(stroke
				(width 0.1)
				(type default)
			)
			(layer "F.Fab")
		)
		(fp_line
			(start 0.12065 -0.3048)
			(end 0.67945 -0.3048)
			(stroke
				(width 0.1)
				(type default)
			)
			(layer "F.Fab")
		)
		(fp_line
			(start 0.12065 -0.2794)
			(end 0.12065 -0.3048)
			(stroke
				(width 0.1)
				(type default)
			)
			(layer "F.Fab")
		)
		(fp_line
			(start 0.67945 -0.3048)
			(end 0.67945 0.3048)
			(stroke
				(width 0.1)
				(type default)
			)
			(layer "F.Fab")
		)
		(fp_line
			(start 0.67945 0.3048)
			(end 0.120396 0.3048)
			(stroke
				(width 0.1)
				(type default)
			)
			(layer "F.Fab")
		)
		(pad "1" smd circle
			(at -0.40005 0)
			(size 0 0)
			(layers "F.Cu" "F.Mask" "F.Paste")
			(net "VSENSE_PVDDIO_P0_DP")
		)
		(pad "2" smd circle
			(at 0.40005 0)
			(size 0 0)
			(layers "F.Cu" "F.Mask" "F.Paste")
			(net "PVDDIO_P0")
		)
	)
	(footprint ""
		(layer "F.Cu")
		(at 247.591072 -385.27736 90)
		(property "Reference" "PPQ2"
			(at -7.438644 -2.150872 0)
			(unlocked yes)
			(layer "F.SilkS")
			(effects
				(font
					(size 0.7874 0.5842)
					(thickness 0.1524)
				)
				(justify left)
			)
		)
		(property "Value" ""
			(at 0 0 90)
			(layer "F.Fab")
			(effects
				(font
					(size 1.27 1.27)
				)
			)
		)
		(duplicate_pad_numbers_are_jumpers no)
		(fp_line
			(start 2.350008 -2.649982)
			(end 2.350008 -2.4892)
			(stroke
				(width 0.1524)
				(type default)
			)
			(layer "F.SilkS")
		)
		(fp_line
			(start -2.350008 -2.649982)
			(end 2.350008 -2.649982)
			(stroke
				(width 0.1524)
				(type default)
			)
			(layer "F.SilkS")
		)
		(fp_line
			(start -2.350008 -2.4384)
			(end -2.350008 -2.649982)
			(stroke
				(width 0.1524)
				(type default)
			)
			(layer "F.SilkS")
		)
		(fp_line
			(start 2.350008 2.4892)
			(end 2.350008 2.649982)
			(stroke
				(width 0.1524)
				(type default)
			)
			(layer "F.SilkS")
		)
		(fp_line
			(start 2.350008 2.649982)
			(end -2.350008 2.649982)
			(stroke
				(width 0.1524)
				(type default)
			)
			(layer "F.SilkS")
		)
		(fp_line
			(start -2.350008 2.649982)
			(end -2.350008 2.413)
			(stroke
				(width 0.1524)
				(type default)
			)
			(layer "F.SilkS")
		)
		(fp_poly
			(pts
				(xy -3.45313 -3.467354) (xy -2.653538 -3.434588) (xy -3.115056 -2.411222)
			)
			(stroke
				(width 0)
				(type default)
			)
			(fill yes)
			(layer "F.SilkS")
		)
		(fp_line
			(start 2.350008 -2.649982)
			(end 2.350008 2.649982)
			(stroke
				(width 0.1)
				(type default)
			)
			(layer "F.Fab")
		)
		(fp_line
			(start -2.350008 -2.649982)
			(end 2.350008 -2.649982)
			(stroke
				(width 0.1)
				(type default)
			)
			(layer "F.Fab")
		)
		(fp_line
			(start 2.350008 2.649982)
			(end -2.350008 2.649982)
			(stroke
				(width 0.1)
				(type default)
			)
			(layer "F.Fab")
		)
		(fp_line
			(start -2.350008 2.649982)
			(end -2.350008 -2.649982)
			(stroke
				(width 0.1)
				(type default)
			)
			(layer "F.Fab")
		)
		(fp_poly
			(pts
				(xy -3.717544 -1.905) (xy -4.758944 -2.3241) (xy -4.758944 -1.524)
			)
			(stroke
				(width 0)
				(type default)
			)
			(fill yes)
			(layer "F.Fab")
		)
		(pad "1" smd rect
			(at -2.999994 -1.905)
			(size 0.7112 1.1684)
			(layers "F.Cu" "F.Mask" "F.Paste")
			(net "P12V_AUX")
		)
		(pad "2" smd rect
			(at -2.999994 -0.635)
			(size 0.7112 1.1684)
			(layers "F.Cu" "F.Mask" "F.Paste")
			(net "P12V_AUX")
		)
		(pad "3" smd rect
			(at -2.999994 0.635)
			(size 0.7112 1.1684)
			(layers "F.Cu" "F.Mask" "F.Paste")
			(net "P12V_AUX")
		)
		(pad "4" smd rect
			(at -2.999994 1.905)
			(size 0.7112 1.1684)
			(layers "F.Cu" "F.Mask" "F.Paste")
			(net "P12V_HSC_GATE_G6")
		)
		(pad "5" smd circle
			(at 0.925068 0)
			(size 0 0)
			(layers "F.Cu" "F.Mask" "F.Paste")
			(net "P12V_MAIN_R")
		)
		(zone
			(layer "F.Cu")
			(hatch none 0.5)
			(connect_pads
				(clearance 0)
			)
			(min_thickness 0.25)
			(keepout
				(tracks not_allowed)
				(vias allowed)
				(pads allowed)
				(copperpour not_allowed)
				(footprints allowed)
			)
			(placement
				(enabled no)
				(sheetname "")
			)
			(fill
				(thermal_gap 0.5)
				(thermal_bridge_width 0.5)
				(island_removal_mode 0)
			)
			(polygon
				(pts
					(xy 244.949472 -383.7178) (xy 250.232672 -383.7178) (xy 250.232672 -382.92786) (xy 244.949472 -382.92786)
				)
			)
		)
	)
	(footprint ""
		(layer "F.Cu")
		(at 199.941942 -346.023184 180)
		(property "Reference" "PC119"
			(at 0 0 180)
			(layer "F.SilkS")
			(hide yes)
			(effects
				(font
					(size 1.27 1.27)
				)
			)
		)
		(property "Value" ""
			(at 0 0 180)
			(layer "F.Fab")
			(effects
				(font
					(size 1.27 1.27)
				)
			)
		)
		(duplicate_pad_numbers_are_jumpers no)
		(fp_line
			(start 1.524 0.762)
			(end -1.524 0.762)
			(stroke
				(width 0.1524)
				(type default)
			)
			(layer "F.SilkS")
		)
		(fp_line
			(start 1.524 -0.762)
			(end 1.524 0.762)
			(stroke
				(width 0.1524)
				(type default)
			)
			(layer "F.SilkS")
		)
		(fp_line
			(start -1.524 0.762)
			(end -1.524 -0.762)
			(stroke
				(width 0.1524)
				(type default)
			)
			(layer "F.SilkS")
		)
		(fp_line
			(start -1.524 -0.762)
			(end 1.524 -0.762)
			(stroke
				(width 0.1524)
				(type default)
			)
			(layer "F.SilkS")
		)
		(fp_line
			(start 1.1049 0.724916)
			(end 1.1049 -0.724916)
			(stroke
				(width 0.1)
				(type default)
			)
			(layer "F.Fab")
		)
		(fp_line
			(start 1.1049 -0.724916)
			(end -1.1049 -0.724916)
			(stroke
				(width 0.1)
				(type default)
			)
			(layer "F.Fab")
		)
		(fp_line
			(start -1.1049 0.724916)
			(end 1.1049 0.724916)
			(stroke
				(width 0.1)
				(type default)
			)
			(layer "F.Fab")
		)
		(fp_line
			(start -1.1049 -0.724916)
			(end -1.1049 0.724916)
			(stroke
				(width 0.1)
				(type default)
			)
			(layer "F.Fab")
		)
		(pad "1" smd rect
			(at -0.889 0)
			(size 1.016 1.27)
			(layers "F.Cu" "F.Mask" "F.Paste")
			(net "SW_P12V_AUX_PVDD_33_S5_FLT")
		)
		(pad "2" smd rect
			(at 0.889 0)
			(size 1.016 1.27)
			(layers "F.Cu" "F.Mask" "F.Paste")
			(net "GND")
		)
	)
	(footprint ""
		(layer "F.Cu")
		(at 205.147926 -331.016864 90)
		(property "Reference" "PC136"
			(at 0 0 90)
			(layer "F.SilkS")
			(hide yes)
			(effects
				(font
					(size 1.27 1.27)
				)
			)
		)
		(property "Value" ""
			(at 0 0 90)
			(layer "F.Fab")
			(effects
				(font
					(size 1.27 1.27)
				)
			)
		)
		(duplicate_pad_numbers_are_jumpers no)
		(fp_line
			(start 0.7874 -0.4064)
			(end 0.7874 0.4064)
			(stroke
				(width 0.1524)
				(type default)
			)
			(layer "F.SilkS")
		)
		(fp_line
			(start -0.7874 -0.4064)
			(end 0.7874 -0.4064)
			(stroke
				(width 0.1524)
				(type default)
			)
			(layer "F.SilkS")
		)
		(fp_line
			(start 0.7874 0.4064)
			(end -0.7874 0.4064)
			(stroke
				(width 0.1524)
				(type default)
			)
			(layer "F.SilkS")
		)
		(fp_line
			(start -0.7874 0.4064)
			(end -0.7874 -0.4064)
			(stroke
				(width 0.1524)
				(type default)
			)
			(layer "F.SilkS")
		)
		(fp_line
			(start -0.12065 -0.305054)
			(end -0.12065 -0.2794)
			(stroke
				(width 0.1)
				(type default)
			)
			(layer "F.Fab")
		)
		(fp_line
			(start -0.67945 -0.305054)
			(end -0.12065 -0.305054)
			(stroke
				(width 0.1)
				(type default)
			)
			(layer "F.Fab")
		)
		(fp_line
			(start 0.67945 -0.3048)
			(end 0.67945 0.3048)
			(stroke
				(width 0.1)
				(type default)
			)
			(layer "F.Fab")
		)
		(fp_line
			(start 0.12065 -0.3048)
			(end 0.67945 -0.3048)
			(stroke
				(width 0.1)
				(type default)
			)
			(layer "F.Fab")
		)
		(fp_line
			(start 0.12065 -0.2794)
			(end 0.12065 -0.3048)
			(stroke
				(width 0.1)
				(type default)
			)
			(layer "F.Fab")
		)
		(fp_line
			(start -0.12065 -0.2794)
			(end 0.12065 -0.2794)
			(stroke
				(width 0.1)
				(type default)
			)
			(layer "F.Fab")
		)
		(fp_line
			(start 0.120396 0.2794)
			(end -0.12065 0.2794)
			(stroke
				(width 0.1)
				(type default)
			)
			(layer "F.Fab")
		)
		(fp_line
			(start -0.12065 0.2794)
			(end -0.12065 0.3048)
			(stroke
				(width 0.1)
				(type default)
			)
			(layer "F.Fab")
		)
		(fp_line
			(start 0.67945 0.3048)
			(end 0.120396 0.3048)
			(stroke
				(width 0.1)
				(type default)
			)
			(layer "F.Fab")
		)
		(fp_line
			(start 0.120396 0.3048)
			(end 0.120396 0.2794)
			(stroke
				(width 0.1)
				(type default)
			)
			(layer "F.Fab")
		)
		(fp_line
			(start -0.12065 0.3048)
			(end -0.67945 0.3048)
			(stroke
				(width 0.1)
				(type default)
			)
			(layer "F.Fab")
		)
		(fp_line
			(start -0.67945 0.3048)
			(end -0.67945 -0.305054)
			(stroke
				(width 0.1)
				(type default)
			)
			(layer "F.Fab")
		)
		(pad "1" smd circle
			(at -0.40005 0 90)
			(size 0 0)
			(layers "F.Cu" "F.Mask" "F.Paste")
			(net "PVDD_33_S5")
		)
		(pad "2" smd circle
			(at 0.40005 0 90)
			(size 0 0)
			(layers "F.Cu" "F.Mask" "F.Paste")
			(net "GND")
		)
	)
	(footprint ""
		(layer "F.Cu")
		(at 303.023778 -46.444154)
		(property "Reference" "L16"
			(at 0 0 0)
			(layer "F.SilkS")
			(hide yes)
			(effects
				(font
					(size 1.27 1.27)
				)
			)
		)
		(property "Value" ""
			(at 0 0 0)
			(layer "F.Fab")
			(effects
				(font
					(size 1.27 1.27)
				)
			)
		)
		(duplicate_pad_numbers_are_jumpers no)
		(fp_line
			(start -1.27 -0.5842)
			(end 1.27 -0.5842)
			(stroke
				(width 0.1524)
				(type default)
			)
			(layer "F.SilkS")
		)
		(fp_line
			(start -1.27 -0.5588)
			(end -1.27 -0.5842)
			(stroke
				(width 0.1524)
				(type default)
			)
			(layer "F.SilkS")
		)
		(fp_line
			(start -1.27 0.5842)
			(end -1.27 -0.5842)
			(stroke
				(width 0.1524)
				(type default)
			)
			(layer "F.SilkS")
		)
		(fp_line
			(start 1.27 0.5842)
			(end -1.27 0.5842)
			(stroke
				(width 0.1524)
				(type default)
			)
			(layer "F.SilkS")
		)
		(fp_line
			(start 1.27 0.5842)
			(end 1.27 -0.5842)
			(stroke
				(width 0.1524)
				(type default)
			)
			(layer "F.SilkS")
		)
		(fp_line
			(start -1.194308 -0.406654)
			(end -0.9144 -0.406654)
			(stroke
				(width 0.1)
				(type default)
			)
			(layer "F.Fab")
		)
		(fp_line
			(start -1.194308 0.406654)
			(end -1.194308 -0.406654)
			(stroke
				(width 0.1)
				(type default)
			)
			(layer "F.Fab")
		)
		(fp_line
			(start -0.9144 -0.508)
			(end 0.9144 -0.508)
			(stroke
				(width 0.1)
				(type default)
			)
			(layer "F.Fab")
		)
		(fp_line
			(start -0.9144 -0.406654)
			(end -0.9144 -0.508)
			(stroke
				(width 0.1)
				(type default)
			)
			(layer "F.Fab")
		)
		(fp_line
			(start -0.9144 0.406654)
			(end -1.194308 0.406654)
			(stroke
				(width 0.1)
				(type default)
			)
			(layer "F.Fab")
		)
		(fp_line
			(start -0.9144 0.508)
			(end -0.9144 0.406654)
			(stroke
				(width 0.1)
				(type default)
			)
			(layer "F.Fab")
		)
		(fp_line
			(start 0.9144 -0.508)
			(end 0.9144 -0.406654)
			(stroke
				(width 0.1)
				(type default)
			)
			(layer "F.Fab")
		)
		(fp_line
			(start 0.9144 -0.406654)
			(end 1.1938 -0.406654)
			(stroke
				(width 0.1)
				(type default)
			)
			(layer "F.Fab")
		)
		(fp_line
			(start 0.9144 0.4064)
			(end 0.9144 0.508)
			(stroke
				(width 0.1)
				(type default)
			)
			(layer "F.Fab")
		)
		(fp_line
			(start 0.9144 0.508)
			(end -0.9144 0.508)
			(stroke
				(width 0.1)
				(type default)
			)
			(layer "F.Fab")
		)
		(fp_line
			(start 1.1938 -0.406654)
			(end 1.1938 0.4064)
			(stroke
				(width 0.1)
				(type default)
			)
			(layer "F.Fab")
		)
		(fp_line
			(start 1.1938 0.4064)
			(end 0.9144 0.4064)
			(stroke
				(width 0.1)
				(type default)
			)
			(layer "F.Fab")
		)
		(pad "1" smd rect
			(at -0.7366 0 270)
			(size 0.7112 0.8128)
			(layers "F.Cu" "F.Mask" "F.Paste")
			(net "P3V3_AUX")
		)
		(pad "2" smd rect
			(at 0.7366 0 270)
			(size 0.7112 0.8128)
			(layers "F.Cu" "F.Mask" "F.Paste")
			(net "P3V3_ADC128_VCC")
		)
	)
	(footprint ""
		(layer "F.Cu")
		(at 447.792602 -418.96411 -90)
		(property "Reference" "PR6614"
			(at 0 0 270)
			(layer "F.SilkS")
			(hide yes)
			(effects
				(font
					(size 1.27 1.27)
				)
			)
		)
		(property "Value" ""
			(at 0 0 270)
			(layer "F.Fab")
			(effects
				(font
					(size 1.27 1.27)
				)
			)
		)
		(duplicate_pad_numbers_are_jumpers no)
		(fp_line
			(start -0.7874 0.4064)
			(end -0.7874 -0.4064)
			(stroke
				(width 0.1524)
				(type default)
			)
			(layer "F.SilkS")
		)
		(fp_line
			(start 0.7874 0.4064)
			(end -0.7874 0.4064)
			(stroke
				(width 0.1524)
				(type default)
			)
			(layer "F.SilkS")
		)
		(fp_line
			(start -0.7874 -0.4064)
			(end 0.7874 -0.4064)
			(stroke
				(width 0.1524)
				(type default)
			)
			(layer "F.SilkS")
		)
		(fp_line
			(start 0.7874 -0.4064)
			(end 0.7874 0.4064)
			(stroke
				(width 0.1524)
				(type default)
			)
			(layer "F.SilkS")
		)
		(fp_line
			(start -0.67945 0.3048)
			(end -0.67945 -0.305054)
			(stroke
				(width 0.1)
				(type default)
			)
			(layer "F.Fab")
		)
		(fp_line
			(start -0.12065 0.3048)
			(end -0.67945 0.3048)
			(stroke
				(width 0.1)
				(type default)
			)
			(layer "F.Fab")
		)
		(fp_line
			(start 0.120396 0.3048)
			(end 0.120396 0.2794)
			(stroke
				(width 0.1)
				(type default)
			)
			(layer "F.Fab")
		)
		(fp_line
			(start 0.67945 0.3048)
			(end 0.120396 0.3048)
			(stroke
				(width 0.1)
				(type default)
			)
			(layer "F.Fab")
		)
		(fp_line
			(start -0.12065 0.2794)
			(end -0.12065 0.3048)
			(stroke
				(width 0.1)
				(type default)
			)
			(layer "F.Fab")
		)
		(fp_line
			(start 0.120396 0.2794)
			(end -0.12065 0.2794)
			(stroke
				(width 0.1)
				(type default)
			)
			(layer "F.Fab")
		)
		(fp_line
			(start -0.12065 -0.2794)
			(end 0.12065 -0.2794)
			(stroke
				(width 0.1)
				(type default)
			)
			(layer "F.Fab")
		)
		(fp_line
			(start 0.12065 -0.2794)
			(end 0.12065 -0.3048)
			(stroke
				(width 0.1)
				(type default)
			)
			(layer "F.Fab")
		)
		(fp_line
			(start 0.12065 -0.3048)
			(end 0.67945 -0.3048)
			(stroke
				(width 0.1)
				(type default)
			)
			(layer "F.Fab")
		)
		(fp_line
			(start 0.67945 -0.3048)
			(end 0.67945 0.3048)
			(stroke
				(width 0.1)
				(type default)
			)
			(layer "F.Fab")
		)
		(fp_line
			(start -0.67945 -0.305054)
			(end -0.12065 -0.305054)
			(stroke
				(width 0.1)
				(type default)
			)
			(layer "F.Fab")
		)
		(fp_line
			(start -0.12065 -0.305054)
			(end -0.12065 -0.2794)
			(stroke
				(width 0.1)
				(type default)
			)
			(layer "F.Fab")
		)
		(pad "1" smd circle
			(at -0.40005 0 270)
			(size 0 0)
			(layers "F.Cu" "F.Mask" "F.Paste")
			(net "NC_P0V9_RETIMER_CPU0_IMON8")
		)
		(pad "2" smd circle
			(at 0.40005 0 270)
			(size 0 0)
			(layers "F.Cu" "F.Mask" "F.Paste")
			(net "GND")
		)
	)
	(footprint ""
		(layer "F.Cu")
		(at 393.363958 -323.643752 180)
		(property "Reference" "R437"
			(at 0 0 180)
			(layer "F.SilkS")
			(hide yes)
			(effects
				(font
					(size 1.27 1.27)
				)
			)
		)
		(property "Value" ""
			(at 0 0 180)
			(layer "F.Fab")
			(effects
				(font
					(size 1.27 1.27)
				)
			)
		)
		(duplicate_pad_numbers_are_jumpers no)
		(fp_line
			(start 0.7874 0.4064)
			(end -0.7874 0.4064)
			(stroke
				(width 0.1524)
				(type default)
			)
			(layer "F.SilkS")
		)
		(fp_line
			(start 0.7874 -0.4064)
			(end 0.7874 0.4064)
			(stroke
				(width 0.1524)
				(type default)
			)
			(layer "F.SilkS")
		)
		(fp_line
			(start -0.7874 0.4064)
			(end -0.7874 -0.4064)
			(stroke
				(width 0.1524)
				(type default)
			)
			(layer "F.SilkS")
		)
		(fp_line
			(start -0.7874 -0.4064)
			(end 0.7874 -0.4064)
			(stroke
				(width 0.1524)
				(type default)
			)
			(layer "F.SilkS")
		)
		(fp_line
			(start 0.67945 0.3048)
			(end 0.120396 0.3048)
			(stroke
				(width 0.1)
				(type default)
			)
			(layer "F.Fab")
		)
		(fp_line
			(start 0.67945 -0.3048)
			(end 0.67945 0.3048)
			(stroke
				(width 0.1)
				(type default)
			)
			(layer "F.Fab")
		)
		(fp_line
			(start 0.12065 -0.2794)
			(end 0.12065 -0.3048)
			(stroke
				(width 0.1)
				(type default)
			)
			(layer "F.Fab")
		)
		(fp_line
			(start 0.12065 -0.3048)
			(end 0.67945 -0.3048)
			(stroke
				(width 0.1)
				(type default)
			)
			(layer "F.Fab")
		)
		(fp_line
			(start 0.120396 0.3048)
			(end 0.120396 0.2794)
			(stroke
				(width 0.1)
				(type default)
			)
			(layer "F.Fab")
		)
		(fp_line
			(start 0.120396 0.2794)
			(end -0.12065 0.2794)
			(stroke
				(width 0.1)
				(type default)
			)
			(layer "F.Fab")
		)
		(fp_line
			(start -0.12065 0.3048)
			(end -0.67945 0.3048)
			(stroke
				(width 0.1)
				(type default)
			)
			(layer "F.Fab")
		)
		(fp_line
			(start -0.12065 0.2794)
			(end -0.12065 0.3048)
			(stroke
				(width 0.1)
				(type default)
			)
			(layer "F.Fab")
		)
		(fp_line
			(start -0.12065 -0.2794)
			(end 0.12065 -0.2794)
			(stroke
				(width 0.1)
				(type default)
			)
			(layer "F.Fab")
		)
		(fp_line
			(start -0.12065 -0.305054)
			(end -0.12065 -0.2794)
			(stroke
				(width 0.1)
				(type default)
			)
			(layer "F.Fab")
		)
		(fp_line
			(start -0.67945 0.3048)
			(end -0.67945 -0.305054)
			(stroke
				(width 0.1)
				(type default)
			)
			(layer "F.Fab")
		)
		(fp_line
			(start -0.67945 -0.305054)
			(end -0.12065 -0.305054)
			(stroke
				(width 0.1)
				(type default)
			)
			(layer "F.Fab")
		)
		(pad "1" smd circle
			(at -0.40005 0 180)
			(size 0 0)
			(layers "F.Cu" "F.Mask" "F.Paste")
			(net "PVDD18_S5_P0")
		)
		(pad "2" smd circle
			(at 0.40005 0 180)
			(size 0 0)
			(layers "F.Cu" "F.Mask" "F.Paste")
			(net "IRQ_WAKE_N")
		)
	)
	(footprint ""
		(layer "F.Cu")
		(at 215.519 -115.951 90)
		(property "Reference" "R9022"
			(at 0 0 90)
			(layer "F.SilkS")
			(hide yes)
			(effects
				(font
					(size 1.27 1.27)
				)
			)
		)
		(property "Value" ""
			(at 0 0 90)
			(layer "F.Fab")
			(effects
				(font
					(size 1.27 1.27)
				)
			)
		)
		(duplicate_pad_numbers_are_jumpers no)
		(fp_line
			(start 0.7874 -0.4064)
			(end 0.7874 0.4064)
			(stroke
				(width 0.1524)
				(type default)
			)
			(layer "F.SilkS")
		)
		(fp_line
			(start -0.7874 -0.4064)
			(end 0.7874 -0.4064)
			(stroke
				(width 0.1524)
				(type default)
			)
			(layer "F.SilkS")
		)
		(fp_line
			(start 0.7874 0.4064)
			(end -0.7874 0.4064)
			(stroke
				(width 0.1524)
				(type default)
			)
			(layer "F.SilkS")
		)
		(fp_line
			(start -0.7874 0.4064)
			(end -0.7874 -0.4064)
			(stroke
				(width 0.1524)
				(type default)
			)
			(layer "F.SilkS")
		)
		(fp_line
			(start -0.12065 -0.305054)
			(end -0.12065 -0.2794)
			(stroke
				(width 0.1)
				(type default)
			)
			(layer "F.Fab")
		)
		(fp_line
			(start -0.67945 -0.305054)
			(end -0.12065 -0.305054)
			(stroke
				(width 0.1)
				(type default)
			)
			(layer "F.Fab")
		)
		(fp_line
			(start 0.67945 -0.3048)
			(end 0.67945 0.3048)
			(stroke
				(width 0.1)
				(type default)
			)
			(layer "F.Fab")
		)
		(fp_line
			(start 0.12065 -0.3048)
			(end 0.67945 -0.3048)
			(stroke
				(width 0.1)
				(type default)
			)
			(layer "F.Fab")
		)
		(fp_line
			(start 0.12065 -0.2794)
			(end 0.12065 -0.3048)
			(stroke
				(width 0.1)
				(type default)
			)
			(layer "F.Fab")
		)
		(fp_line
			(start -0.12065 -0.2794)
			(end 0.12065 -0.2794)
			(stroke
				(width 0.1)
				(type default)
			)
			(layer "F.Fab")
		)
		(fp_line
			(start 0.120396 0.2794)
			(end -0.12065 0.2794)
			(stroke
				(width 0.1)
				(type default)
			)
			(layer "F.Fab")
		)
		(fp_line
			(start -0.12065 0.2794)
			(end -0.12065 0.3048)
			(stroke
				(width 0.1)
				(type default)
			)
			(layer "F.Fab")
		)
		(fp_line
			(start 0.67945 0.3048)
			(end 0.120396 0.3048)
			(stroke
				(width 0.1)
				(type default)
			)
			(layer "F.Fab")
		)
		(fp_line
			(start 0.120396 0.3048)
			(end 0.120396 0.2794)
			(stroke
				(width 0.1)
				(type default)
			)
			(layer "F.Fab")
		)
		(fp_line
			(start -0.12065 0.3048)
			(end -0.67945 0.3048)
			(stroke
				(width 0.1)
				(type default)
			)
			(layer "F.Fab")
		)
		(fp_line
			(start -0.67945 0.3048)
			(end -0.67945 -0.305054)
			(stroke
				(width 0.1)
				(type default)
			)
			(layer "F.Fab")
		)
		(pad "1" smd circle
			(at -0.40005 0 90)
			(size 0 0)
			(layers "F.Cu" "F.Mask" "F.Paste")
			(net "OCP_V3_1_P3V3_R3_PWRGD")
		)
		(pad "2" smd circle
			(at 0.40005 0 90)
			(size 0 0)
			(layers "F.Cu" "F.Mask" "F.Paste")
			(net "HP_LVC3_OCP_V3_1_PWRGD")
		)
	)
	(footprint ""
		(layer "F.Cu")
		(at 142.729712 -74.609452)
		(property "Reference" "PC6019"
			(at 0 0 0)
			(layer "F.SilkS")
			(hide yes)
			(effects
				(font
					(size 1.27 1.27)
				)
			)
		)
		(property "Value" ""
			(at 0 0 0)
			(layer "F.Fab")
			(effects
				(font
					(size 1.27 1.27)
				)
			)
		)
		(duplicate_pad_numbers_are_jumpers no)
		(fp_line
			(start -0.7874 -0.4064)
			(end 0.7874 -0.4064)
			(stroke
				(width 0.1524)
				(type default)
			)
			(layer "F.SilkS")
		)
		(fp_line
			(start -0.7874 0.4064)
			(end -0.7874 -0.4064)
			(stroke
				(width 0.1524)
				(type default)
			)
			(layer "F.SilkS")
		)
		(fp_line
			(start 0.7874 -0.4064)
			(end 0.7874 0.4064)
			(stroke
				(width 0.1524)
				(type default)
			)
			(layer "F.SilkS")
		)
		(fp_line
			(start 0.7874 0.4064)
			(end -0.7874 0.4064)
			(stroke
				(width 0.1524)
				(type default)
			)
			(layer "F.SilkS")
		)
		(fp_line
			(start -0.67945 -0.305054)
			(end -0.12065 -0.305054)
			(stroke
				(width 0.1)
				(type default)
			)
			(layer "F.Fab")
		)
		(fp_line
			(start -0.67945 0.3048)
			(end -0.67945 -0.305054)
			(stroke
				(width 0.1)
				(type default)
			)
			(layer "F.Fab")
		)
		(fp_line
			(start -0.12065 -0.305054)
			(end -0.12065 -0.2794)
			(stroke
				(width 0.1)
				(type default)
			)
			(layer "F.Fab")
		)
		(fp_line
			(start -0.12065 -0.2794)
			(end 0.12065 -0.2794)
			(stroke
				(width 0.1)
				(type default)
			)
			(layer "F.Fab")
		)
		(fp_line
			(start -0.12065 0.2794)
			(end -0.12065 0.3048)
			(stroke
				(width 0.1)
				(type default)
			)
			(layer "F.Fab")
		)
		(fp_line
			(start -0.12065 0.3048)
			(end -0.67945 0.3048)
			(stroke
				(width 0.1)
				(type default)
			)
			(layer "F.Fab")
		)
		(fp_line
			(start 0.120396 0.2794)
			(end -0.12065 0.2794)
			(stroke
				(width 0.1)
				(type default)
			)
			(layer "F.Fab")
		)
		(fp_line
			(start 0.120396 0.3048)
			(end 0.120396 0.2794)
			(stroke
				(width 0.1)
				(type default)
			)
			(layer "F.Fab")
		)
		(fp_line
			(start 0.12065 -0.3048)
			(end 0.67945 -0.3048)
			(stroke
				(width 0.1)
				(type default)
			)
			(layer "F.Fab")
		)
		(fp_line
			(start 0.12065 -0.2794)
			(end 0.12065 -0.3048)
			(stroke
				(width 0.1)
				(type default)
			)
			(layer "F.Fab")
		)
		(fp_line
			(start 0.67945 -0.3048)
			(end 0.67945 0.3048)
			(stroke
				(width 0.1)
				(type default)
			)
			(layer "F.Fab")
		)
		(fp_line
			(start 0.67945 0.3048)
			(end 0.120396 0.3048)
			(stroke
				(width 0.1)
				(type default)
			)
			(layer "F.Fab")
		)
		(pad "1" smd circle
			(at -0.40005 0)
			(size 0 0)
			(layers "F.Cu" "F.Mask" "F.Paste")
			(net "P1V8_AUX_FB")
		)
		(pad "2" smd circle
			(at 0.40005 0)
			(size 0 0)
			(layers "F.Cu" "F.Mask" "F.Paste")
			(net "P1V8_AUX")
		)
	)
	(footprint ""
		(layer "F.Cu")
		(at 16.764 -73.66)
		(property "Reference" "C8003"
			(at 0 0 0)
			(layer "F.SilkS")
			(hide yes)
			(effects
				(font
					(size 1.27 1.27)
				)
			)
		)
		(property "Value" ""
			(at 0 0 0)
			(layer "F.Fab")
			(effects
				(font
					(size 1.27 1.27)
				)
			)
		)
		(duplicate_pad_numbers_are_jumpers no)
		(fp_line
			(start -0.7874 -0.4064)
			(end 0.7874 -0.4064)
			(stroke
				(width 0.1524)
				(type default)
			)
			(layer "F.SilkS")
		)
		(fp_line
			(start -0.7874 0.4064)
			(end -0.7874 -0.4064)
			(stroke
				(width 0.1524)
				(type default)
			)
			(layer "F.SilkS")
		)
		(fp_line
			(start 0.7874 -0.4064)
			(end 0.7874 0.4064)
			(stroke
				(width 0.1524)
				(type default)
			)
			(layer "F.SilkS")
		)
		(fp_line
			(start 0.7874 0.4064)
			(end -0.7874 0.4064)
			(stroke
				(width 0.1524)
				(type default)
			)
			(layer "F.SilkS")
		)
		(fp_line
			(start -0.67945 -0.305054)
			(end -0.12065 -0.305054)
			(stroke
				(width 0.1)
				(type default)
			)
			(layer "F.Fab")
		)
		(fp_line
			(start -0.67945 0.3048)
			(end -0.67945 -0.305054)
			(stroke
				(width 0.1)
				(type default)
			)
			(layer "F.Fab")
		)
		(fp_line
			(start -0.12065 -0.305054)
			(end -0.12065 -0.2794)
			(stroke
				(width 0.1)
				(type default)
			)
			(layer "F.Fab")
		)
		(fp_line
			(start -0.12065 -0.2794)
			(end 0.12065 -0.2794)
			(stroke
				(width 0.1)
				(type default)
			)
			(layer "F.Fab")
		)
		(fp_line
			(start -0.12065 0.2794)
			(end -0.12065 0.3048)
			(stroke
				(width 0.1)
				(type default)
			)
			(layer "F.Fab")
		)
		(fp_line
			(start -0.12065 0.3048)
			(end -0.67945 0.3048)
			(stroke
				(width 0.1)
				(type default)
			)
			(layer "F.Fab")
		)
		(fp_line
			(start 0.120396 0.2794)
			(end -0.12065 0.2794)
			(stroke
				(width 0.1)
				(type default)
			)
			(layer "F.Fab")
		)
		(fp_line
			(start 0.120396 0.3048)
			(end 0.120396 0.2794)
			(stroke
				(width 0.1)
				(type default)
			)
			(layer "F.Fab")
		)
		(fp_line
			(start 0.12065 -0.3048)
			(end 0.67945 -0.3048)
			(stroke
				(width 0.1)
				(type default)
			)
			(layer "F.Fab")
		)
		(fp_line
			(start 0.12065 -0.2794)
			(end 0.12065 -0.3048)
			(stroke
				(width 0.1)
				(type default)
			)
			(layer "F.Fab")
		)
		(fp_line
			(start 0.67945 -0.3048)
			(end 0.67945 0.3048)
			(stroke
				(width 0.1)
				(type default)
			)
			(layer "F.Fab")
		)
		(fp_line
			(start 0.67945 0.3048)
			(end 0.120396 0.3048)
			(stroke
				(width 0.1)
				(type default)
			)
			(layer "F.Fab")
		)
		(pad "1" smd circle
			(at -0.40005 0)
			(size 0 0)
			(layers "F.Cu" "F.Mask" "F.Paste")
			(net "OCP_V3_2_PRSNT01_R1_N")
		)
		(pad "2" smd circle
			(at 0.40005 0)
			(size 0 0)
			(layers "F.Cu" "F.Mask" "F.Paste")
			(net "GND")
		)
	)
	(footprint ""
		(layer "F.Cu")
		(at 338.859876 -70.098412 90)
		(property "Reference" "D81"
			(at -3.934714 -0.691642 90)
			(unlocked yes)
			(layer "F.SilkS")
			(effects
				(font
					(size 0.7874 0.5842)
					(thickness 0.1524)
				)
				(justify left)
			)
		)
		(property "Value" ""
			(at 0 0 90)
			(layer "F.Fab")
			(effects
				(font
					(size 1.27 1.27)
				)
			)
		)
		(duplicate_pad_numbers_are_jumpers no)
		(fp_line
			(start 1.16078 -0.4826)
			(end 1.16078 0.4826)
			(stroke
				(width 0.1524)
				(type default)
			)
			(layer "F.SilkS")
		)
		(fp_line
			(start 1.03378 -0.4826)
			(end 1.03378 0.4826)
			(stroke
				(width 0.1524)
				(type default)
			)
			(layer "F.SilkS")
		)
		(fp_line
			(start 0.90678 -0.4826)
			(end 0.90678 0.4826)
			(stroke
				(width 0.1524)
				(type default)
			)
			(layer "F.SilkS")
		)
		(fp_line
			(start -0.64008 -0.4826)
			(end 1.16078 -0.4826)
			(stroke
				(width 0.1524)
				(type default)
			)
			(layer "F.SilkS")
		)
		(fp_line
			(start -0.79248 -0.4826)
			(end 1.03378 -0.4826)
			(stroke
				(width 0.1524)
				(type default)
			)
			(layer "F.SilkS")
		)
		(fp_line
			(start -0.89408 -0.4826)
			(end 0.90678 -0.4826)
			(stroke
				(width 0.1524)
				(type default)
			)
			(layer "F.SilkS")
		)
		(fp_line
			(start 1.16078 0.4826)
			(end -0.64008 0.4826)
			(stroke
				(width 0.1524)
				(type default)
			)
			(layer "F.SilkS")
		)
		(fp_line
			(start 1.03378 0.4826)
			(end -0.79248 0.4826)
			(stroke
				(width 0.1524)
				(type default)
			)
			(layer "F.SilkS")
		)
		(fp_line
			(start 0.90678 0.4826)
			(end -0.90678 0.4826)
			(stroke
				(width 0.1524)
				(type default)
			)
			(layer "F.SilkS")
		)
		(fp_line
			(start -0.90678 0.4826)
			(end -0.90678 -0.4699)
			(stroke
				(width 0.1524)
				(type default)
			)
			(layer "F.SilkS")
		)
		(fp_line
			(start 0.499872 -0.249936)
			(end 0.499872 0.249936)
			(stroke
				(width 0.1)
				(type default)
			)
			(layer "F.Fab")
		)
		(fp_line
			(start -0.499872 -0.249936)
			(end 0.499872 -0.249936)
			(stroke
				(width 0.1)
				(type default)
			)
			(layer "F.Fab")
		)
		(fp_line
			(start 0.499872 0.249936)
			(end -0.499872 0.249936)
			(stroke
				(width 0.1)
				(type default)
			)
			(layer "F.Fab")
		)
		(fp_line
			(start -0.499872 0.249936)
			(end -0.499872 -0.249936)
			(stroke
				(width 0.1)
				(type default)
			)
			(layer "F.Fab")
		)
		(pad "A" smd rect
			(at -0.47498 0 90)
			(size 0.6096 0.7112)
			(layers "F.Cu" "F.Mask" "F.Paste")
			(net "LED_PWRGD_PVDDCR_SOC_P1_R")
		)
		(pad "C" smd rect
			(at 0.47498 0 90)
			(size 0.6096 0.7112)
			(layers "F.Cu" "F.Mask" "F.Paste")
			(net "LED_PWRGD_PVDDCR_SOC_P1_D")
		)
	)
	(footprint ""
		(layer "F.Cu")
		(at 255.831086 -380.66853)
		(property "Reference" "PR2528"
			(at 0 0 0)
			(layer "F.SilkS")
			(hide yes)
			(effects
				(font
					(size 1.27 1.27)
				)
			)
		)
		(property "Value" ""
			(at 0 0 0)
			(layer "F.Fab")
			(effects
				(font
					(size 1.27 1.27)
				)
			)
		)
		(duplicate_pad_numbers_are_jumpers no)
		(fp_line
			(start -0.7874 -0.4064)
			(end 0.7874 -0.4064)
			(stroke
				(width 0.1524)
				(type default)
			)
			(layer "F.SilkS")
		)
		(fp_line
			(start -0.7874 0.4064)
			(end -0.7874 -0.4064)
			(stroke
				(width 0.1524)
				(type default)
			)
			(layer "F.SilkS")
		)
		(fp_line
			(start 0.7874 -0.4064)
			(end 0.7874 0.4064)
			(stroke
				(width 0.1524)
				(type default)
			)
			(layer "F.SilkS")
		)
		(fp_line
			(start 0.7874 0.4064)
			(end -0.7874 0.4064)
			(stroke
				(width 0.1524)
				(type default)
			)
			(layer "F.SilkS")
		)
		(fp_line
			(start -0.67945 -0.305054)
			(end -0.12065 -0.305054)
			(stroke
				(width 0.1)
				(type default)
			)
			(layer "F.Fab")
		)
		(fp_line
			(start -0.67945 0.3048)
			(end -0.67945 -0.305054)
			(stroke
				(width 0.1)
				(type default)
			)
			(layer "F.Fab")
		)
		(fp_line
			(start -0.12065 -0.305054)
			(end -0.12065 -0.2794)
			(stroke
				(width 0.1)
				(type default)
			)
			(layer "F.Fab")
		)
		(fp_line
			(start -0.12065 -0.2794)
			(end 0.12065 -0.2794)
			(stroke
				(width 0.1)
				(type default)
			)
			(layer "F.Fab")
		)
		(fp_line
			(start -0.12065 0.2794)
			(end -0.12065 0.3048)
			(stroke
				(width 0.1)
				(type default)
			)
			(layer "F.Fab")
		)
		(fp_line
			(start -0.12065 0.3048)
			(end -0.67945 0.3048)
			(stroke
				(width 0.1)
				(type default)
			)
			(layer "F.Fab")
		)
		(fp_line
			(start 0.120396 0.2794)
			(end -0.12065 0.2794)
			(stroke
				(width 0.1)
				(type default)
			)
			(layer "F.Fab")
		)
		(fp_line
			(start 0.120396 0.3048)
			(end 0.120396 0.2794)
			(stroke
				(width 0.1)
				(type default)
			)
			(layer "F.Fab")
		)
		(fp_line
			(start 0.12065 -0.3048)
			(end 0.67945 -0.3048)
			(stroke
				(width 0.1)
				(type default)
			)
			(layer "F.Fab")
		)
		(fp_line
			(start 0.12065 -0.2794)
			(end 0.12065 -0.3048)
			(stroke
				(width 0.1)
				(type default)
			)
			(layer "F.Fab")
		)
		(fp_line
			(start 0.67945 -0.3048)
			(end 0.67945 0.3048)
			(stroke
				(width 0.1)
				(type default)
			)
			(layer "F.Fab")
		)
		(fp_line
			(start 0.67945 0.3048)
			(end 0.120396 0.3048)
			(stroke
				(width 0.1)
				(type default)
			)
			(layer "F.Fab")
		)
		(pad "1" smd circle
			(at -0.40005 0)
			(size 0 0)
			(layers "F.Cu" "F.Mask" "F.Paste")
			(net "P12V_HSC_GATE_G1")
		)
		(pad "2" smd circle
			(at 0.40005 0)
			(size 0 0)
			(layers "F.Cu" "F.Mask" "F.Paste")
			(net "P12V_HSC_GATE2")
		)
	)
	(footprint ""
		(layer "F.Cu")
		(at 425.896532 -358.570276 180)
		(property "Reference" "PC219_1"
			(at 0 0 180)
			(layer "F.SilkS")
			(hide yes)
			(effects
				(font
					(size 1.27 1.27)
				)
			)
		)
		(property "Value" ""
			(at 0 0 180)
			(layer "F.Fab")
			(effects
				(font
					(size 1.27 1.27)
				)
			)
		)
		(duplicate_pad_numbers_are_jumpers no)
		(fp_line
			(start 1.524 0.762)
			(end -1.524 0.762)
			(stroke
				(width 0.1524)
				(type default)
			)
			(layer "F.SilkS")
		)
		(fp_line
			(start 1.524 -0.762)
			(end 1.524 0.762)
			(stroke
				(width 0.1524)
				(type default)
			)
			(layer "F.SilkS")
		)
		(fp_line
			(start -1.524 0.762)
			(end -1.524 -0.762)
			(stroke
				(width 0.1524)
				(type default)
			)
			(layer "F.SilkS")
		)
		(fp_line
			(start -1.524 -0.762)
			(end 1.524 -0.762)
			(stroke
				(width 0.1524)
				(type default)
			)
			(layer "F.SilkS")
		)
		(fp_line
			(start 1.1049 0.724916)
			(end 1.1049 -0.724916)
			(stroke
				(width 0.1)
				(type default)
			)
			(layer "F.Fab")
		)
		(fp_line
			(start 1.1049 -0.724916)
			(end -1.1049 -0.724916)
			(stroke
				(width 0.1)
				(type default)
			)
			(layer "F.Fab")
		)
		(fp_line
			(start -1.1049 0.724916)
			(end 1.1049 0.724916)
			(stroke
				(width 0.1)
				(type default)
			)
			(layer "F.Fab")
		)
		(fp_line
			(start -1.1049 -0.724916)
			(end -1.1049 0.724916)
			(stroke
				(width 0.1)
				(type default)
			)
			(layer "F.Fab")
		)
		(pad "1" smd rect
			(at -0.889 0)
			(size 1.016 1.27)
			(layers "F.Cu" "F.Mask" "F.Paste")
			(net "SW_P12V_AUX_PVDD11_S3_P0_FLT")
		)
		(pad "2" smd rect
			(at 0.889 0)
			(size 1.016 1.27)
			(layers "F.Cu" "F.Mask" "F.Paste")
			(net "GND")
		)
	)
	(footprint ""
		(layer "F.Cu")
		(at 125.992636 -61.767212 180)
		(property "Reference" "R1743"
			(at 0 0 180)
			(layer "F.SilkS")
			(hide yes)
			(effects
				(font
					(size 1.27 1.27)
				)
			)
		)
		(property "Value" ""
			(at 0 0 180)
			(layer "F.Fab")
			(effects
				(font
					(size 1.27 1.27)
				)
			)
		)
		(duplicate_pad_numbers_are_jumpers no)
		(fp_line
			(start 0.7874 0.4064)
			(end -0.7874 0.4064)
			(stroke
				(width 0.1524)
				(type default)
			)
			(layer "F.SilkS")
		)
		(fp_line
			(start 0.7874 -0.4064)
			(end 0.7874 0.4064)
			(stroke
				(width 0.1524)
				(type default)
			)
			(layer "F.SilkS")
		)
		(fp_line
			(start -0.7874 0.4064)
			(end -0.7874 -0.4064)
			(stroke
				(width 0.1524)
				(type default)
			)
			(layer "F.SilkS")
		)
		(fp_line
			(start -0.7874 -0.4064)
			(end 0.7874 -0.4064)
			(stroke
				(width 0.1524)
				(type default)
			)
			(layer "F.SilkS")
		)
		(fp_line
			(start 0.67945 0.3048)
			(end 0.120396 0.3048)
			(stroke
				(width 0.1)
				(type default)
			)
			(layer "F.Fab")
		)
		(fp_line
			(start 0.67945 -0.3048)
			(end 0.67945 0.3048)
			(stroke
				(width 0.1)
				(type default)
			)
			(layer "F.Fab")
		)
		(fp_line
			(start 0.12065 -0.2794)
			(end 0.12065 -0.3048)
			(stroke
				(width 0.1)
				(type default)
			)
			(layer "F.Fab")
		)
		(fp_line
			(start 0.12065 -0.3048)
			(end 0.67945 -0.3048)
			(stroke
				(width 0.1)
				(type default)
			)
			(layer "F.Fab")
		)
		(fp_line
			(start 0.120396 0.3048)
			(end 0.120396 0.2794)
			(stroke
				(width 0.1)
				(type default)
			)
			(layer "F.Fab")
		)
		(fp_line
			(start 0.120396 0.2794)
			(end -0.12065 0.2794)
			(stroke
				(width 0.1)
				(type default)
			)
			(layer "F.Fab")
		)
		(fp_line
			(start -0.12065 0.3048)
			(end -0.67945 0.3048)
			(stroke
				(width 0.1)
				(type default)
			)
			(layer "F.Fab")
		)
		(fp_line
			(start -0.12065 0.2794)
			(end -0.12065 0.3048)
			(stroke
				(width 0.1)
				(type default)
			)
			(layer "F.Fab")
		)
		(fp_line
			(start -0.12065 -0.2794)
			(end 0.12065 -0.2794)
			(stroke
				(width 0.1)
				(type default)
			)
			(layer "F.Fab")
		)
		(fp_line
			(start -0.12065 -0.305054)
			(end -0.12065 -0.2794)
			(stroke
				(width 0.1)
				(type default)
			)
			(layer "F.Fab")
		)
		(fp_line
			(start -0.67945 0.3048)
			(end -0.67945 -0.305054)
			(stroke
				(width 0.1)
				(type default)
			)
			(layer "F.Fab")
		)
		(fp_line
			(start -0.67945 -0.305054)
			(end -0.12065 -0.305054)
			(stroke
				(width 0.1)
				(type default)
			)
			(layer "F.Fab")
		)
		(pad "1" smd circle
			(at -0.40005 0 180)
			(size 0 0)
			(layers "F.Cu" "F.Mask" "F.Paste")
			(net "JTAG_SCM_PLD_R_TDO")
		)
		(pad "2" smd circle
			(at 0.40005 0 180)
			(size 0 0)
			(layers "F.Cu" "F.Mask" "F.Paste")
			(net "JTAG_SCM_PLD_TDO")
		)
	)
	(footprint ""
		(layer "F.Cu")
		(at 328.288142 -390.652)
		(property "Reference" "R969"
			(at 0 0 0)
			(layer "F.SilkS")
			(hide yes)
			(effects
				(font
					(size 1.27 1.27)
				)
			)
		)
		(property "Value" ""
			(at 0 0 0)
			(layer "F.Fab")
			(effects
				(font
					(size 1.27 1.27)
				)
			)
		)
		(duplicate_pad_numbers_are_jumpers no)
		(fp_line
			(start -0.32512 -0.175006)
			(end 0.32512 -0.175006)
			(stroke
				(width 0.1)
				(type default)
			)
			(layer "F.Fab")
		)
		(fp_line
			(start -0.32512 0.175006)
			(end -0.32512 -0.175006)
			(stroke
				(width 0.1)
				(type default)
			)
			(layer "F.Fab")
		)
		(fp_line
			(start 0.32512 -0.175006)
			(end 0.32512 0.175006)
			(stroke
				(width 0.1)
				(type default)
			)
			(layer "F.Fab")
		)
		(fp_line
			(start 0.32512 0.175006)
			(end -0.32512 0.175006)
			(stroke
				(width 0.1)
				(type default)
			)
			(layer "F.Fab")
		)
		(pad "1" smd rect
			(at -0.2667 0)
			(size 0.3048 0.381)
			(layers "F.Cu" "F.Mask" "F.Paste")
			(net "RT_CPU0_P0_ADDR1")
		)
		(pad "2" smd rect
			(at 0.2667 0 180)
			(size 0.3048 0.381)
			(layers "F.Cu" "F.Mask" "F.Paste")
			(net "GND")
		)
	)
	(footprint ""
		(layer "F.Cu")
		(at 62.63386 -351.372932 90)
		(property "Reference" "PR266"
			(at 0 0 90)
			(layer "F.SilkS")
			(hide yes)
			(effects
				(font
					(size 1.27 1.27)
				)
			)
		)
		(property "Value" ""
			(at 0 0 90)
			(layer "F.Fab")
			(effects
				(font
					(size 1.27 1.27)
				)
			)
		)
		(duplicate_pad_numbers_are_jumpers no)
		(fp_line
			(start 0.7874 -0.4064)
			(end 0.7874 0.4064)
			(stroke
				(width 0.1524)
				(type default)
			)
			(layer "F.SilkS")
		)
		(fp_line
			(start -0.7874 -0.4064)
			(end 0.7874 -0.4064)
			(stroke
				(width 0.1524)
				(type default)
			)
			(layer "F.SilkS")
		)
		(fp_line
			(start 0.7874 0.4064)
			(end -0.7874 0.4064)
			(stroke
				(width 0.1524)
				(type default)
			)
			(layer "F.SilkS")
		)
		(fp_line
			(start -0.7874 0.4064)
			(end -0.7874 -0.4064)
			(stroke
				(width 0.1524)
				(type default)
			)
			(layer "F.SilkS")
		)
		(fp_line
			(start -0.12065 -0.305054)
			(end -0.12065 -0.2794)
			(stroke
				(width 0.1)
				(type default)
			)
			(layer "F.Fab")
		)
		(fp_line
			(start -0.67945 -0.305054)
			(end -0.12065 -0.305054)
			(stroke
				(width 0.1)
				(type default)
			)
			(layer "F.Fab")
		)
		(fp_line
			(start 0.67945 -0.3048)
			(end 0.67945 0.3048)
			(stroke
				(width 0.1)
				(type default)
			)
			(layer "F.Fab")
		)
		(fp_line
			(start 0.12065 -0.3048)
			(end 0.67945 -0.3048)
			(stroke
				(width 0.1)
				(type default)
			)
			(layer "F.Fab")
		)
		(fp_line
			(start 0.12065 -0.2794)
			(end 0.12065 -0.3048)
			(stroke
				(width 0.1)
				(type default)
			)
			(layer "F.Fab")
		)
		(fp_line
			(start -0.12065 -0.2794)
			(end 0.12065 -0.2794)
			(stroke
				(width 0.1)
				(type default)
			)
			(layer "F.Fab")
		)
		(fp_line
			(start 0.120396 0.2794)
			(end -0.12065 0.2794)
			(stroke
				(width 0.1)
				(type default)
			)
			(layer "F.Fab")
		)
		(fp_line
			(start -0.12065 0.2794)
			(end -0.12065 0.3048)
			(stroke
				(width 0.1)
				(type default)
			)
			(layer "F.Fab")
		)
		(fp_line
			(start 0.67945 0.3048)
			(end 0.120396 0.3048)
			(stroke
				(width 0.1)
				(type default)
			)
			(layer "F.Fab")
		)
		(fp_line
			(start 0.120396 0.3048)
			(end 0.120396 0.2794)
			(stroke
				(width 0.1)
				(type default)
			)
			(layer "F.Fab")
		)
		(fp_line
			(start -0.12065 0.3048)
			(end -0.67945 0.3048)
			(stroke
				(width 0.1)
				(type default)
			)
			(layer "F.Fab")
		)
		(fp_line
			(start -0.67945 0.3048)
			(end -0.67945 -0.305054)
			(stroke
				(width 0.1)
				(type default)
			)
			(layer "F.Fab")
		)
		(pad "1" smd circle
			(at -0.40005 0 90)
			(size 0 0)
			(layers "F.Cu" "F.Mask" "F.Paste")
			(net "SW_PVDDCR_CPU1_P1_BOOT4")
		)
		(pad "2" smd circle
			(at 0.40005 0 90)
			(size 0 0)
			(layers "F.Cu" "F.Mask" "F.Paste")
			(net "SW_PVDDCR_CPU1_P1_BOOT4_R")
		)
	)
	(footprint ""
		(layer "F.Cu")
		(at 43.88231 -351.932748)
		(property "Reference" "PR274"
			(at 0 0 0)
			(layer "F.SilkS")
			(hide yes)
			(effects
				(font
					(size 1.27 1.27)
				)
			)
		)
		(property "Value" ""
			(at 0 0 0)
			(layer "F.Fab")
			(effects
				(font
					(size 1.27 1.27)
				)
			)
		)
		(duplicate_pad_numbers_are_jumpers no)
		(fp_line
			(start -0.7874 -0.4064)
			(end 0.7874 -0.4064)
			(stroke
				(width 0.1524)
				(type default)
			)
			(layer "F.SilkS")
		)
		(fp_line
			(start -0.7874 0.4064)
			(end -0.7874 -0.4064)
			(stroke
				(width 0.1524)
				(type default)
			)
			(layer "F.SilkS")
		)
		(fp_line
			(start 0.7874 -0.4064)
			(end 0.7874 0.4064)
			(stroke
				(width 0.1524)
				(type default)
			)
			(layer "F.SilkS")
		)
		(fp_line
			(start 0.7874 0.4064)
			(end -0.7874 0.4064)
			(stroke
				(width 0.1524)
				(type default)
			)
			(layer "F.SilkS")
		)
		(fp_line
			(start -0.67945 -0.305054)
			(end -0.12065 -0.305054)
			(stroke
				(width 0.1)
				(type default)
			)
			(layer "F.Fab")
		)
		(fp_line
			(start -0.67945 0.3048)
			(end -0.67945 -0.305054)
			(stroke
				(width 0.1)
				(type default)
			)
			(layer "F.Fab")
		)
		(fp_line
			(start -0.12065 -0.305054)
			(end -0.12065 -0.2794)
			(stroke
				(width 0.1)
				(type default)
			)
			(layer "F.Fab")
		)
		(fp_line
			(start -0.12065 -0.2794)
			(end 0.12065 -0.2794)
			(stroke
				(width 0.1)
				(type default)
			)
			(layer "F.Fab")
		)
		(fp_line
			(start -0.12065 0.2794)
			(end -0.12065 0.3048)
			(stroke
				(width 0.1)
				(type default)
			)
			(layer "F.Fab")
		)
		(fp_line
			(start -0.12065 0.3048)
			(end -0.67945 0.3048)
			(stroke
				(width 0.1)
				(type default)
			)
			(layer "F.Fab")
		)
		(fp_line
			(start 0.120396 0.2794)
			(end -0.12065 0.2794)
			(stroke
				(width 0.1)
				(type default)
			)
			(layer "F.Fab")
		)
		(fp_line
			(start 0.120396 0.3048)
			(end 0.120396 0.2794)
			(stroke
				(width 0.1)
				(type default)
			)
			(layer "F.Fab")
		)
		(fp_line
			(start 0.12065 -0.3048)
			(end 0.67945 -0.3048)
			(stroke
				(width 0.1)
				(type default)
			)
			(layer "F.Fab")
		)
		(fp_line
			(start 0.12065 -0.2794)
			(end 0.12065 -0.3048)
			(stroke
				(width 0.1)
				(type default)
			)
			(layer "F.Fab")
		)
		(fp_line
			(start 0.67945 -0.3048)
			(end 0.67945 0.3048)
			(stroke
				(width 0.1)
				(type default)
			)
			(layer "F.Fab")
		)
		(fp_line
			(start 0.67945 0.3048)
			(end 0.120396 0.3048)
			(stroke
				(width 0.1)
				(type default)
			)
			(layer "F.Fab")
		)
		(pad "1" smd circle
			(at -0.40005 0)
			(size 0 0)
			(layers "F.Cu" "F.Mask" "F.Paste")
			(net "PVDDIO_P1_LSET2")
		)
		(pad "2" smd circle
			(at 0.40005 0)
			(size 0 0)
			(layers "F.Cu" "F.Mask" "F.Paste")
			(net "GND")
		)
	)
	(footprint ""
		(layer "F.Cu")
		(at 8.406384 -380.470156)
		(property "Reference" "PR6600"
			(at 0 0 0)
			(layer "F.SilkS")
			(hide yes)
			(effects
				(font
					(size 1.27 1.27)
				)
			)
		)
		(property "Value" ""
			(at 0 0 0)
			(layer "F.Fab")
			(effects
				(font
					(size 1.27 1.27)
				)
			)
		)
		(duplicate_pad_numbers_are_jumpers no)
		(fp_line
			(start -0.7874 -0.4064)
			(end 0.7874 -0.4064)
			(stroke
				(width 0.1524)
				(type default)
			)
			(layer "F.SilkS")
		)
		(fp_line
			(start -0.7874 0.4064)
			(end -0.7874 -0.4064)
			(stroke
				(width 0.1524)
				(type default)
			)
			(layer "F.SilkS")
		)
		(fp_line
			(start 0.7874 -0.4064)
			(end 0.7874 0.4064)
			(stroke
				(width 0.1524)
				(type default)
			)
			(layer "F.SilkS")
		)
		(fp_line
			(start 0.7874 0.4064)
			(end -0.7874 0.4064)
			(stroke
				(width 0.1524)
				(type default)
			)
			(layer "F.SilkS")
		)
		(fp_line
			(start -0.67945 -0.305054)
			(end -0.12065 -0.305054)
			(stroke
				(width 0.1)
				(type default)
			)
			(layer "F.Fab")
		)
		(fp_line
			(start -0.67945 0.3048)
			(end -0.67945 -0.305054)
			(stroke
				(width 0.1)
				(type default)
			)
			(layer "F.Fab")
		)
		(fp_line
			(start -0.12065 -0.305054)
			(end -0.12065 -0.2794)
			(stroke
				(width 0.1)
				(type default)
			)
			(layer "F.Fab")
		)
		(fp_line
			(start -0.12065 -0.2794)
			(end 0.12065 -0.2794)
			(stroke
				(width 0.1)
				(type default)
			)
			(layer "F.Fab")
		)
		(fp_line
			(start -0.12065 0.2794)
			(end -0.12065 0.3048)
			(stroke
				(width 0.1)
				(type default)
			)
			(layer "F.Fab")
		)
		(fp_line
			(start -0.12065 0.3048)
			(end -0.67945 0.3048)
			(stroke
				(width 0.1)
				(type default)
			)
			(layer "F.Fab")
		)
		(fp_line
			(start 0.120396 0.2794)
			(end -0.12065 0.2794)
			(stroke
				(width 0.1)
				(type default)
			)
			(layer "F.Fab")
		)
		(fp_line
			(start 0.120396 0.3048)
			(end 0.120396 0.2794)
			(stroke
				(width 0.1)
				(type default)
			)
			(layer "F.Fab")
		)
		(fp_line
			(start 0.12065 -0.3048)
			(end 0.67945 -0.3048)
			(stroke
				(width 0.1)
				(type default)
			)
			(layer "F.Fab")
		)
		(fp_line
			(start 0.12065 -0.2794)
			(end 0.12065 -0.3048)
			(stroke
				(width 0.1)
				(type default)
			)
			(layer "F.Fab")
		)
		(fp_line
			(start 0.67945 -0.3048)
			(end 0.67945 0.3048)
			(stroke
				(width 0.1)
				(type default)
			)
			(layer "F.Fab")
		)
		(fp_line
			(start 0.67945 0.3048)
			(end 0.120396 0.3048)
			(stroke
				(width 0.1)
				(type default)
			)
			(layer "F.Fab")
		)
		(pad "1" smd circle
			(at -0.40005 0)
			(size 0 0)
			(layers "F.Cu" "F.Mask" "F.Paste")
			(net "P0V9_RETIMER_CPU1_SENSE_SH_P")
		)
		(pad "2" smd circle
			(at 0.40005 0)
			(size 0 0)
			(layers "F.Cu" "F.Mask" "F.Paste")
			(net "P0V9_CPU1_RT_2D")
		)
	)
	(footprint ""
		(layer "F.Cu")
		(at 88.895936 -178.024028 90)
		(property "Reference" "PC271"
			(at 0 0 90)
			(layer "F.SilkS")
			(hide yes)
			(effects
				(font
					(size 1.27 1.27)
				)
			)
		)
		(property "Value" ""
			(at 0 0 90)
			(layer "F.Fab")
			(effects
				(font
					(size 1.27 1.27)
				)
			)
		)
		(duplicate_pad_numbers_are_jumpers no)
		(fp_line
			(start 0.7874 -0.4064)
			(end 0.7874 0.4064)
			(stroke
				(width 0.1524)
				(type default)
			)
			(layer "F.SilkS")
		)
		(fp_line
			(start -0.7874 -0.4064)
			(end 0.7874 -0.4064)
			(stroke
				(width 0.1524)
				(type default)
			)
			(layer "F.SilkS")
		)
		(fp_line
			(start 0.7874 0.4064)
			(end -0.7874 0.4064)
			(stroke
				(width 0.1524)
				(type default)
			)
			(layer "F.SilkS")
		)
		(fp_line
			(start -0.7874 0.4064)
			(end -0.7874 -0.4064)
			(stroke
				(width 0.1524)
				(type default)
			)
			(layer "F.SilkS")
		)
		(fp_line
			(start -0.12065 -0.305054)
			(end -0.12065 -0.2794)
			(stroke
				(width 0.1)
				(type default)
			)
			(layer "F.Fab")
		)
		(fp_line
			(start -0.67945 -0.305054)
			(end -0.12065 -0.305054)
			(stroke
				(width 0.1)
				(type default)
			)
			(layer "F.Fab")
		)
		(fp_line
			(start 0.67945 -0.3048)
			(end 0.67945 0.3048)
			(stroke
				(width 0.1)
				(type default)
			)
			(layer "F.Fab")
		)
		(fp_line
			(start 0.12065 -0.3048)
			(end 0.67945 -0.3048)
			(stroke
				(width 0.1)
				(type default)
			)
			(layer "F.Fab")
		)
		(fp_line
			(start 0.12065 -0.2794)
			(end 0.12065 -0.3048)
			(stroke
				(width 0.1)
				(type default)
			)
			(layer "F.Fab")
		)
		(fp_line
			(start -0.12065 -0.2794)
			(end 0.12065 -0.2794)
			(stroke
				(width 0.1)
				(type default)
			)
			(layer "F.Fab")
		)
		(fp_line
			(start 0.120396 0.2794)
			(end -0.12065 0.2794)
			(stroke
				(width 0.1)
				(type default)
			)
			(layer "F.Fab")
		)
		(fp_line
			(start -0.12065 0.2794)
			(end -0.12065 0.3048)
			(stroke
				(width 0.1)
				(type default)
			)
			(layer "F.Fab")
		)
		(fp_line
			(start 0.67945 0.3048)
			(end 0.120396 0.3048)
			(stroke
				(width 0.1)
				(type default)
			)
			(layer "F.Fab")
		)
		(fp_line
			(start 0.120396 0.3048)
			(end 0.120396 0.2794)
			(stroke
				(width 0.1)
				(type default)
			)
			(layer "F.Fab")
		)
		(fp_line
			(start -0.12065 0.3048)
			(end -0.67945 0.3048)
			(stroke
				(width 0.1)
				(type default)
			)
			(layer "F.Fab")
		)
		(fp_line
			(start -0.67945 0.3048)
			(end -0.67945 -0.305054)
			(stroke
				(width 0.1)
				(type default)
			)
			(layer "F.Fab")
		)
		(pad "1" smd circle
			(at -0.40005 0 90)
			(size 0 0)
			(layers "F.Cu" "F.Mask" "F.Paste")
			(net "SW_PVDDCR_CPU0_P1_BOOT2_RC")
		)
		(pad "2" smd circle
			(at 0.40005 0 90)
			(size 0 0)
			(layers "F.Cu" "F.Mask" "F.Paste")
			(net "SW_PVDDCR_CPU0_P1_PH2")
		)
	)
	(footprint ""
		(layer "F.Cu")
		(at 157.698186 -347.260164)
		(property "Reference" "R8146"
			(at 0 0 0)
			(layer "F.SilkS")
			(hide yes)
			(effects
				(font
					(size 1.27 1.27)
				)
			)
		)
		(property "Value" ""
			(at 0 0 0)
			(layer "F.Fab")
			(effects
				(font
					(size 1.27 1.27)
				)
			)
		)
		(duplicate_pad_numbers_are_jumpers no)
		(fp_line
			(start -0.7874 -0.4064)
			(end 0.7874 -0.4064)
			(stroke
				(width 0.1524)
				(type default)
			)
			(layer "F.SilkS")
		)
		(fp_line
			(start -0.7874 0.4064)
			(end -0.7874 -0.4064)
			(stroke
				(width 0.1524)
				(type default)
			)
			(layer "F.SilkS")
		)
		(fp_line
			(start 0.7874 -0.4064)
			(end 0.7874 0.4064)
			(stroke
				(width 0.1524)
				(type default)
			)
			(layer "F.SilkS")
		)
		(fp_line
			(start 0.7874 0.4064)
			(end -0.7874 0.4064)
			(stroke
				(width 0.1524)
				(type default)
			)
			(layer "F.SilkS")
		)
		(fp_line
			(start -0.67945 -0.305054)
			(end -0.12065 -0.305054)
			(stroke
				(width 0.1)
				(type default)
			)
			(layer "F.Fab")
		)
		(fp_line
			(start -0.67945 0.3048)
			(end -0.67945 -0.305054)
			(stroke
				(width 0.1)
				(type default)
			)
			(layer "F.Fab")
		)
		(fp_line
			(start -0.12065 -0.305054)
			(end -0.12065 -0.2794)
			(stroke
				(width 0.1)
				(type default)
			)
			(layer "F.Fab")
		)
		(fp_line
			(start -0.12065 -0.2794)
			(end 0.12065 -0.2794)
			(stroke
				(width 0.1)
				(type default)
			)
			(layer "F.Fab")
		)
		(fp_line
			(start -0.12065 0.2794)
			(end -0.12065 0.3048)
			(stroke
				(width 0.1)
				(type default)
			)
			(layer "F.Fab")
		)
		(fp_line
			(start -0.12065 0.3048)
			(end -0.67945 0.3048)
			(stroke
				(width 0.1)
				(type default)
			)
			(layer "F.Fab")
		)
		(fp_line
			(start 0.120396 0.2794)
			(end -0.12065 0.2794)
			(stroke
				(width 0.1)
				(type default)
			)
			(layer "F.Fab")
		)
		(fp_line
			(start 0.120396 0.3048)
			(end 0.120396 0.2794)
			(stroke
				(width 0.1)
				(type default)
			)
			(layer "F.Fab")
		)
		(fp_line
			(start 0.12065 -0.3048)
			(end 0.67945 -0.3048)
			(stroke
				(width 0.1)
				(type default)
			)
			(layer "F.Fab")
		)
		(fp_line
			(start 0.12065 -0.2794)
			(end 0.12065 -0.3048)
			(stroke
				(width 0.1)
				(type default)
			)
			(layer "F.Fab")
		)
		(fp_line
			(start 0.67945 -0.3048)
			(end 0.67945 0.3048)
			(stroke
				(width 0.1)
				(type default)
			)
			(layer "F.Fab")
		)
		(fp_line
			(start 0.67945 0.3048)
			(end 0.120396 0.3048)
			(stroke
				(width 0.1)
				(type default)
			)
			(layer "F.Fab")
		)
		(pad "1" smd circle
			(at -0.40005 0)
			(size 0 0)
			(layers "F.Cu" "F.Mask" "F.Paste")
			(net "P3V3_AUX")
		)
		(pad "2" smd circle
			(at 0.40005 0)
			(size 0 0)
			(layers "F.Cu" "F.Mask" "F.Paste")
			(net "PVDD11_S3_P1_VDDIO")
		)
	)
	(footprint ""
		(layer "F.Cu")
		(at 358.96169 -390.1694 180)
		(property "Reference" "R1395"
			(at 0 0 180)
			(layer "F.SilkS")
			(hide yes)
			(effects
				(font
					(size 1.27 1.27)
				)
			)
		)
		(property "Value" ""
			(at 0 0 180)
			(layer "F.Fab")
			(effects
				(font
					(size 1.27 1.27)
				)
			)
		)
		(duplicate_pad_numbers_are_jumpers no)
		(fp_line
			(start 0.32512 0.175006)
			(end -0.32512 0.175006)
			(stroke
				(width 0.1)
				(type default)
			)
			(layer "F.Fab")
		)
		(fp_line
			(start 0.32512 -0.175006)
			(end 0.32512 0.175006)
			(stroke
				(width 0.1)
				(type default)
			)
			(layer "F.Fab")
		)
		(fp_line
			(start -0.32512 0.175006)
			(end -0.32512 -0.175006)
			(stroke
				(width 0.1)
				(type default)
			)
			(layer "F.Fab")
		)
		(fp_line
			(start -0.32512 -0.175006)
			(end 0.32512 -0.175006)
			(stroke
				(width 0.1)
				(type default)
			)
			(layer "F.Fab")
		)
		(pad "1" smd rect
			(at -0.2667 0 180)
			(size 0.3048 0.381)
			(layers "F.Cu" "F.Mask" "F.Paste")
			(net "CLKREQ_RT_CPU0_P1_N")
		)
		(pad "2" smd rect
			(at 0.2667 0)
			(size 0.3048 0.381)
			(layers "F.Cu" "F.Mask" "F.Paste")
			(net "GND")
		)
	)
	(footprint ""
		(layer "F.Cu")
		(at 84.832952 -151.207216 -90)
		(property "Reference" "PC6002"
			(at 0 0 270)
			(layer "F.SilkS")
			(hide yes)
			(effects
				(font
					(size 1.27 1.27)
				)
			)
		)
		(property "Value" ""
			(at 0 0 270)
			(layer "F.Fab")
			(effects
				(font
					(size 1.27 1.27)
				)
			)
		)
		(duplicate_pad_numbers_are_jumpers no)
		(fp_line
			(start -0.7874 0.4064)
			(end -0.7874 -0.4064)
			(stroke
				(width 0.1524)
				(type default)
			)
			(layer "F.SilkS")
		)
		(fp_line
			(start 0.7874 0.4064)
			(end -0.7874 0.4064)
			(stroke
				(width 0.1524)
				(type default)
			)
			(layer "F.SilkS")
		)
		(fp_line
			(start -0.7874 -0.4064)
			(end 0.7874 -0.4064)
			(stroke
				(width 0.1524)
				(type default)
			)
			(layer "F.SilkS")
		)
		(fp_line
			(start 0.7874 -0.4064)
			(end 0.7874 0.4064)
			(stroke
				(width 0.1524)
				(type default)
			)
			(layer "F.SilkS")
		)
		(fp_line
			(start -0.67945 0.3048)
			(end -0.67945 -0.305054)
			(stroke
				(width 0.1)
				(type default)
			)
			(layer "F.Fab")
		)
		(fp_line
			(start -0.12065 0.3048)
			(end -0.67945 0.3048)
			(stroke
				(width 0.1)
				(type default)
			)
			(layer "F.Fab")
		)
		(fp_line
			(start 0.120396 0.3048)
			(end 0.120396 0.2794)
			(stroke
				(width 0.1)
				(type default)
			)
			(layer "F.Fab")
		)
		(fp_line
			(start 0.67945 0.3048)
			(end 0.120396 0.3048)
			(stroke
				(width 0.1)
				(type default)
			)
			(layer "F.Fab")
		)
		(fp_line
			(start -0.12065 0.2794)
			(end -0.12065 0.3048)
			(stroke
				(width 0.1)
				(type default)
			)
			(layer "F.Fab")
		)
		(fp_line
			(start 0.120396 0.2794)
			(end -0.12065 0.2794)
			(stroke
				(width 0.1)
				(type default)
			)
			(layer "F.Fab")
		)
		(fp_line
			(start -0.12065 -0.2794)
			(end 0.12065 -0.2794)
			(stroke
				(width 0.1)
				(type default)
			)
			(layer "F.Fab")
		)
		(fp_line
			(start 0.12065 -0.2794)
			(end 0.12065 -0.3048)
			(stroke
				(width 0.1)
				(type default)
			)
			(layer "F.Fab")
		)
		(fp_line
			(start 0.12065 -0.3048)
			(end 0.67945 -0.3048)
			(stroke
				(width 0.1)
				(type default)
			)
			(layer "F.Fab")
		)
		(fp_line
			(start 0.67945 -0.3048)
			(end 0.67945 0.3048)
			(stroke
				(width 0.1)
				(type default)
			)
			(layer "F.Fab")
		)
		(fp_line
			(start -0.67945 -0.305054)
			(end -0.12065 -0.305054)
			(stroke
				(width 0.1)
				(type default)
			)
			(layer "F.Fab")
		)
		(fp_line
			(start -0.12065 -0.305054)
			(end -0.12065 -0.2794)
			(stroke
				(width 0.1)
				(type default)
			)
			(layer "F.Fab")
		)
		(pad "1" smd circle
			(at -0.40005 0 270)
			(size 0 0)
			(layers "F.Cu" "F.Mask" "F.Paste")
			(net "P12V_AUX")
		)
		(pad "2" smd circle
			(at 0.40005 0 270)
			(size 0 0)
			(layers "F.Cu" "F.Mask" "F.Paste")
			(net "GND")
		)
	)
	(footprint ""
		(layer "F.Cu")
		(at 15.508478 -16.099536 90)
		(property "Reference" "C678"
			(at 0 0 90)
			(layer "F.SilkS")
			(hide yes)
			(effects
				(font
					(size 1.27 1.27)
				)
			)
		)
		(property "Value" ""
			(at 0 0 90)
			(layer "F.Fab")
			(effects
				(font
					(size 1.27 1.27)
				)
			)
		)
		(duplicate_pad_numbers_are_jumpers no)
		(fp_line
			(start 0.299974 -0.150114)
			(end 0.299974 0.150114)
			(stroke
				(width 0.1)
				(type default)
			)
			(layer "F.Fab")
		)
		(fp_line
			(start -0.299974 -0.150114)
			(end 0.299974 -0.150114)
			(stroke
				(width 0.1)
				(type default)
			)
			(layer "F.Fab")
		)
		(fp_line
			(start 0.299974 0.150114)
			(end -0.299974 0.150114)
			(stroke
				(width 0.1)
				(type default)
			)
			(layer "F.Fab")
		)
		(fp_line
			(start -0.299974 0.150114)
			(end -0.299974 -0.150114)
			(stroke
				(width 0.1)
				(type default)
			)
			(layer "F.Fab")
		)
		(pad "1" smd rect
			(at -0.2667 0 90)
			(size 0.3048 0.381)
			(layers "F.Cu" "F.Mask" "F.Paste")
			(net "P5E_CPU1_G1_TX_C_DN<15>")
		)
		(pad "2" smd rect
			(at 0.2667 0 90)
			(size 0.3048 0.381)
			(layers "F.Cu" "F.Mask" "F.Paste")
			(net "P5E_CPU1_G1_TX_DN<15>")
		)
	)
	(footprint ""
		(layer "F.Cu")
		(at 288.331148 -344.982038 90)
		(property "Reference" "PR223"
			(at 0 0 90)
			(layer "F.SilkS")
			(hide yes)
			(effects
				(font
					(size 1.27 1.27)
				)
			)
		)
		(property "Value" ""
			(at 0 0 90)
			(layer "F.Fab")
			(effects
				(font
					(size 1.27 1.27)
				)
			)
		)
		(duplicate_pad_numbers_are_jumpers no)
		(fp_line
			(start 0.7874 -0.4064)
			(end 0.7874 0.4064)
			(stroke
				(width 0.1524)
				(type default)
			)
			(layer "F.SilkS")
		)
		(fp_line
			(start -0.7874 -0.4064)
			(end 0.7874 -0.4064)
			(stroke
				(width 0.1524)
				(type default)
			)
			(layer "F.SilkS")
		)
		(fp_line
			(start 0.7874 0.4064)
			(end -0.7874 0.4064)
			(stroke
				(width 0.1524)
				(type default)
			)
			(layer "F.SilkS")
		)
		(fp_line
			(start -0.7874 0.4064)
			(end -0.7874 -0.4064)
			(stroke
				(width 0.1524)
				(type default)
			)
			(layer "F.SilkS")
		)
		(fp_line
			(start -0.12065 -0.305054)
			(end -0.12065 -0.2794)
			(stroke
				(width 0.1)
				(type default)
			)
			(layer "F.Fab")
		)
		(fp_line
			(start -0.67945 -0.305054)
			(end -0.12065 -0.305054)
			(stroke
				(width 0.1)
				(type default)
			)
			(layer "F.Fab")
		)
		(fp_line
			(start 0.67945 -0.3048)
			(end 0.67945 0.3048)
			(stroke
				(width 0.1)
				(type default)
			)
			(layer "F.Fab")
		)
		(fp_line
			(start 0.12065 -0.3048)
			(end 0.67945 -0.3048)
			(stroke
				(width 0.1)
				(type default)
			)
			(layer "F.Fab")
		)
		(fp_line
			(start 0.12065 -0.2794)
			(end 0.12065 -0.3048)
			(stroke
				(width 0.1)
				(type default)
			)
			(layer "F.Fab")
		)
		(fp_line
			(start -0.12065 -0.2794)
			(end 0.12065 -0.2794)
			(stroke
				(width 0.1)
				(type default)
			)
			(layer "F.Fab")
		)
		(fp_line
			(start 0.120396 0.2794)
			(end -0.12065 0.2794)
			(stroke
				(width 0.1)
				(type default)
			)
			(layer "F.Fab")
		)
		(fp_line
			(start -0.12065 0.2794)
			(end -0.12065 0.3048)
			(stroke
				(width 0.1)
				(type default)
			)
			(layer "F.Fab")
		)
		(fp_line
			(start 0.67945 0.3048)
			(end 0.120396 0.3048)
			(stroke
				(width 0.1)
				(type default)
			)
			(layer "F.Fab")
		)
		(fp_line
			(start 0.120396 0.3048)
			(end 0.120396 0.2794)
			(stroke
				(width 0.1)
				(type default)
			)
			(layer "F.Fab")
		)
		(fp_line
			(start -0.12065 0.3048)
			(end -0.67945 0.3048)
			(stroke
				(width 0.1)
				(type default)
			)
			(layer "F.Fab")
		)
		(fp_line
			(start -0.67945 0.3048)
			(end -0.67945 -0.305054)
			(stroke
				(width 0.1)
				(type default)
			)
			(layer "F.Fab")
		)
		(pad "1" smd circle
			(at -0.40005 0 90)
			(size 0 0)
			(layers "F.Cu" "F.Mask" "F.Paste")
			(net "SW_PVDDIO_P0_SW2_RC")
		)
		(pad "2" smd circle
			(at 0.40005 0 90)
			(size 0 0)
			(layers "F.Cu" "F.Mask" "F.Paste")
			(net "GND")
		)
	)
	(footprint ""
		(layer "F.Cu")
		(at 274.117562 -351.927922)
		(property "Reference" "PR105"
			(at 0 0 0)
			(layer "F.SilkS")
			(hide yes)
			(effects
				(font
					(size 1.27 1.27)
				)
			)
		)
		(property "Value" ""
			(at 0 0 0)
			(layer "F.Fab")
			(effects
				(font
					(size 1.27 1.27)
				)
			)
		)
		(duplicate_pad_numbers_are_jumpers no)
		(fp_line
			(start -0.7874 -0.4064)
			(end 0.7874 -0.4064)
			(stroke
				(width 0.1524)
				(type default)
			)
			(layer "F.SilkS")
		)
		(fp_line
			(start -0.7874 0.4064)
			(end -0.7874 -0.4064)
			(stroke
				(width 0.1524)
				(type default)
			)
			(layer "F.SilkS")
		)
		(fp_line
			(start 0.7874 -0.4064)
			(end 0.7874 0.4064)
			(stroke
				(width 0.1524)
				(type default)
			)
			(layer "F.SilkS")
		)
		(fp_line
			(start 0.7874 0.4064)
			(end -0.7874 0.4064)
			(stroke
				(width 0.1524)
				(type default)
			)
			(layer "F.SilkS")
		)
		(fp_line
			(start -0.67945 -0.305054)
			(end -0.12065 -0.305054)
			(stroke
				(width 0.1)
				(type default)
			)
			(layer "F.Fab")
		)
		(fp_line
			(start -0.67945 0.3048)
			(end -0.67945 -0.305054)
			(stroke
				(width 0.1)
				(type default)
			)
			(layer "F.Fab")
		)
		(fp_line
			(start -0.12065 -0.305054)
			(end -0.12065 -0.2794)
			(stroke
				(width 0.1)
				(type default)
			)
			(layer "F.Fab")
		)
		(fp_line
			(start -0.12065 -0.2794)
			(end 0.12065 -0.2794)
			(stroke
				(width 0.1)
				(type default)
			)
			(layer "F.Fab")
		)
		(fp_line
			(start -0.12065 0.2794)
			(end -0.12065 0.3048)
			(stroke
				(width 0.1)
				(type default)
			)
			(layer "F.Fab")
		)
		(fp_line
			(start -0.12065 0.3048)
			(end -0.67945 0.3048)
			(stroke
				(width 0.1)
				(type default)
			)
			(layer "F.Fab")
		)
		(fp_line
			(start 0.120396 0.2794)
			(end -0.12065 0.2794)
			(stroke
				(width 0.1)
				(type default)
			)
			(layer "F.Fab")
		)
		(fp_line
			(start 0.120396 0.3048)
			(end 0.120396 0.2794)
			(stroke
				(width 0.1)
				(type default)
			)
			(layer "F.Fab")
		)
		(fp_line
			(start 0.12065 -0.3048)
			(end 0.67945 -0.3048)
			(stroke
				(width 0.1)
				(type default)
			)
			(layer "F.Fab")
		)
		(fp_line
			(start 0.12065 -0.2794)
			(end 0.12065 -0.3048)
			(stroke
				(width 0.1)
				(type default)
			)
			(layer "F.Fab")
		)
		(fp_line
			(start 0.67945 -0.3048)
			(end 0.67945 0.3048)
			(stroke
				(width 0.1)
				(type default)
			)
			(layer "F.Fab")
		)
		(fp_line
			(start 0.67945 0.3048)
			(end 0.120396 0.3048)
			(stroke
				(width 0.1)
				(type default)
			)
			(layer "F.Fab")
		)
		(pad "1" smd circle
			(at -0.40005 0)
			(size 0 0)
			(layers "F.Cu" "F.Mask" "F.Paste")
			(net "PVDDIO_P0_LSET4")
		)
		(pad "2" smd circle
			(at 0.40005 0)
			(size 0 0)
			(layers "F.Cu" "F.Mask" "F.Paste")
			(net "GND")
		)
	)
	(footprint ""
		(layer "F.Cu")
		(at 98.314764 -178.0413 -90)
		(property "Reference" "PR197"
			(at 0 0 270)
			(layer "F.SilkS")
			(hide yes)
			(effects
				(font
					(size 1.27 1.27)
				)
			)
		)
		(property "Value" ""
			(at 0 0 270)
			(layer "F.Fab")
			(effects
				(font
					(size 1.27 1.27)
				)
			)
		)
		(duplicate_pad_numbers_are_jumpers no)
		(fp_line
			(start -0.7874 0.4064)
			(end -0.7874 -0.4064)
			(stroke
				(width 0.1524)
				(type default)
			)
			(layer "F.SilkS")
		)
		(fp_line
			(start 0.7874 0.4064)
			(end -0.7874 0.4064)
			(stroke
				(width 0.1524)
				(type default)
			)
			(layer "F.SilkS")
		)
		(fp_line
			(start -0.7874 -0.4064)
			(end 0.7874 -0.4064)
			(stroke
				(width 0.1524)
				(type default)
			)
			(layer "F.SilkS")
		)
		(fp_line
			(start 0.7874 -0.4064)
			(end 0.7874 0.4064)
			(stroke
				(width 0.1524)
				(type default)
			)
			(layer "F.SilkS")
		)
		(fp_line
			(start -0.67945 0.3048)
			(end -0.67945 -0.305054)
			(stroke
				(width 0.1)
				(type default)
			)
			(layer "F.Fab")
		)
		(fp_line
			(start -0.12065 0.3048)
			(end -0.67945 0.3048)
			(stroke
				(width 0.1)
				(type default)
			)
			(layer "F.Fab")
		)
		(fp_line
			(start 0.120396 0.3048)
			(end 0.120396 0.2794)
			(stroke
				(width 0.1)
				(type default)
			)
			(layer "F.Fab")
		)
		(fp_line
			(start 0.67945 0.3048)
			(end 0.120396 0.3048)
			(stroke
				(width 0.1)
				(type default)
			)
			(layer "F.Fab")
		)
		(fp_line
			(start -0.12065 0.2794)
			(end -0.12065 0.3048)
			(stroke
				(width 0.1)
				(type default)
			)
			(layer "F.Fab")
		)
		(fp_line
			(start 0.120396 0.2794)
			(end -0.12065 0.2794)
			(stroke
				(width 0.1)
				(type default)
			)
			(layer "F.Fab")
		)
		(fp_line
			(start -0.12065 -0.2794)
			(end 0.12065 -0.2794)
			(stroke
				(width 0.1)
				(type default)
			)
			(layer "F.Fab")
		)
		(fp_line
			(start 0.12065 -0.2794)
			(end 0.12065 -0.3048)
			(stroke
				(width 0.1)
				(type default)
			)
			(layer "F.Fab")
		)
		(fp_line
			(start 0.12065 -0.3048)
			(end 0.67945 -0.3048)
			(stroke
				(width 0.1)
				(type default)
			)
			(layer "F.Fab")
		)
		(fp_line
			(start 0.67945 -0.3048)
			(end 0.67945 0.3048)
			(stroke
				(width 0.1)
				(type default)
			)
			(layer "F.Fab")
		)
		(fp_line
			(start -0.67945 -0.305054)
			(end -0.12065 -0.305054)
			(stroke
				(width 0.1)
				(type default)
			)
			(layer "F.Fab")
		)
		(fp_line
			(start -0.12065 -0.305054)
			(end -0.12065 -0.2794)
			(stroke
				(width 0.1)
				(type default)
			)
			(layer "F.Fab")
		)
		(pad "1" smd circle
			(at -0.40005 0 270)
			(size 0 0)
			(layers "F.Cu" "F.Mask" "F.Paste")
			(net "SW_PVDDCR_CPU0_P1_BOOT3")
		)
		(pad "2" smd circle
			(at 0.40005 0 270)
			(size 0 0)
			(layers "F.Cu" "F.Mask" "F.Paste")
			(net "SW_PVDDCR_CPU0_P1_BOOT3_RC")
		)
	)
	(footprint ""
		(layer "F.Cu")
		(at 178.47183 -157.508194 -90)
		(property "Reference" "R495"
			(at 0 0 270)
			(layer "F.SilkS")
			(hide yes)
			(effects
				(font
					(size 1.27 1.27)
				)
			)
		)
		(property "Value" ""
			(at 0 0 270)
			(layer "F.Fab")
			(effects
				(font
					(size 1.27 1.27)
				)
			)
		)
		(duplicate_pad_numbers_are_jumpers no)
		(fp_line
			(start -0.7874 0.4064)
			(end -0.7874 -0.4064)
			(stroke
				(width 0.1524)
				(type default)
			)
			(layer "F.SilkS")
		)
		(fp_line
			(start 0.7874 0.4064)
			(end -0.7874 0.4064)
			(stroke
				(width 0.1524)
				(type default)
			)
			(layer "F.SilkS")
		)
		(fp_line
			(start -0.7874 -0.4064)
			(end 0.7874 -0.4064)
			(stroke
				(width 0.1524)
				(type default)
			)
			(layer "F.SilkS")
		)
		(fp_line
			(start 0.7874 -0.4064)
			(end 0.7874 0.4064)
			(stroke
				(width 0.1524)
				(type default)
			)
			(layer "F.SilkS")
		)
		(fp_line
			(start -0.67945 0.3048)
			(end -0.67945 -0.305054)
			(stroke
				(width 0.1)
				(type default)
			)
			(layer "F.Fab")
		)
		(fp_line
			(start -0.12065 0.3048)
			(end -0.67945 0.3048)
			(stroke
				(width 0.1)
				(type default)
			)
			(layer "F.Fab")
		)
		(fp_line
			(start 0.120396 0.3048)
			(end 0.120396 0.2794)
			(stroke
				(width 0.1)
				(type default)
			)
			(layer "F.Fab")
		)
		(fp_line
			(start 0.67945 0.3048)
			(end 0.120396 0.3048)
			(stroke
				(width 0.1)
				(type default)
			)
			(layer "F.Fab")
		)
		(fp_line
			(start -0.12065 0.2794)
			(end -0.12065 0.3048)
			(stroke
				(width 0.1)
				(type default)
			)
			(layer "F.Fab")
		)
		(fp_line
			(start 0.120396 0.2794)
			(end -0.12065 0.2794)
			(stroke
				(width 0.1)
				(type default)
			)
			(layer "F.Fab")
		)
		(fp_line
			(start -0.12065 -0.2794)
			(end 0.12065 -0.2794)
			(stroke
				(width 0.1)
				(type default)
			)
			(layer "F.Fab")
		)
		(fp_line
			(start 0.12065 -0.2794)
			(end 0.12065 -0.3048)
			(stroke
				(width 0.1)
				(type default)
			)
			(layer "F.Fab")
		)
		(fp_line
			(start 0.12065 -0.3048)
			(end 0.67945 -0.3048)
			(stroke
				(width 0.1)
				(type default)
			)
			(layer "F.Fab")
		)
		(fp_line
			(start 0.67945 -0.3048)
			(end 0.67945 0.3048)
			(stroke
				(width 0.1)
				(type default)
			)
			(layer "F.Fab")
		)
		(fp_line
			(start -0.67945 -0.305054)
			(end -0.12065 -0.305054)
			(stroke
				(width 0.1)
				(type default)
			)
			(layer "F.Fab")
		)
		(fp_line
			(start -0.12065 -0.305054)
			(end -0.12065 -0.2794)
			(stroke
				(width 0.1)
				(type default)
			)
			(layer "F.Fab")
		)
		(pad "1" smd circle
			(at -0.40005 0 270)
			(size 0 0)
			(layers "F.Cu" "F.Mask" "F.Paste")
			(net "PVDD18_S5_P0")
		)
		(pad "2" smd circle
			(at 0.40005 0 270)
			(size 0 0)
			(layers "F.Cu" "F.Mask" "F.Paste")
			(net "SMB_CPU0_4_SCL")
		)
	)
	(footprint ""
		(layer "F.Cu")
		(at 45.212 -171.831 180)
		(property "Reference" "R543"
			(at 0 0 180)
			(layer "F.SilkS")
			(hide yes)
			(effects
				(font
					(size 1.27 1.27)
				)
			)
		)
		(property "Value" ""
			(at 0 0 180)
			(layer "F.Fab")
			(effects
				(font
					(size 1.27 1.27)
				)
			)
		)
		(duplicate_pad_numbers_are_jumpers no)
		(fp_line
			(start 0.7874 0.4064)
			(end -0.7874 0.4064)
			(stroke
				(width 0.1524)
				(type default)
			)
			(layer "F.SilkS")
		)
		(fp_line
			(start 0.7874 -0.4064)
			(end 0.7874 0.4064)
			(stroke
				(width 0.1524)
				(type default)
			)
			(layer "F.SilkS")
		)
		(fp_line
			(start -0.7874 0.4064)
			(end -0.7874 -0.4064)
			(stroke
				(width 0.1524)
				(type default)
			)
			(layer "F.SilkS")
		)
		(fp_line
			(start -0.7874 -0.4064)
			(end 0.7874 -0.4064)
			(stroke
				(width 0.1524)
				(type default)
			)
			(layer "F.SilkS")
		)
		(fp_line
			(start 0.67945 0.3048)
			(end 0.120396 0.3048)
			(stroke
				(width 0.1)
				(type default)
			)
			(layer "F.Fab")
		)
		(fp_line
			(start 0.67945 -0.3048)
			(end 0.67945 0.3048)
			(stroke
				(width 0.1)
				(type default)
			)
			(layer "F.Fab")
		)
		(fp_line
			(start 0.12065 -0.2794)
			(end 0.12065 -0.3048)
			(stroke
				(width 0.1)
				(type default)
			)
			(layer "F.Fab")
		)
		(fp_line
			(start 0.12065 -0.3048)
			(end 0.67945 -0.3048)
			(stroke
				(width 0.1)
				(type default)
			)
			(layer "F.Fab")
		)
		(fp_line
			(start 0.120396 0.3048)
			(end 0.120396 0.2794)
			(stroke
				(width 0.1)
				(type default)
			)
			(layer "F.Fab")
		)
		(fp_line
			(start 0.120396 0.2794)
			(end -0.12065 0.2794)
			(stroke
				(width 0.1)
				(type default)
			)
			(layer "F.Fab")
		)
		(fp_line
			(start -0.12065 0.3048)
			(end -0.67945 0.3048)
			(stroke
				(width 0.1)
				(type default)
			)
			(layer "F.Fab")
		)
		(fp_line
			(start -0.12065 0.2794)
			(end -0.12065 0.3048)
			(stroke
				(width 0.1)
				(type default)
			)
			(layer "F.Fab")
		)
		(fp_line
			(start -0.12065 -0.2794)
			(end 0.12065 -0.2794)
			(stroke
				(width 0.1)
				(type default)
			)
			(layer "F.Fab")
		)
		(fp_line
			(start -0.12065 -0.305054)
			(end -0.12065 -0.2794)
			(stroke
				(width 0.1)
				(type default)
			)
			(layer "F.Fab")
		)
		(fp_line
			(start -0.67945 0.3048)
			(end -0.67945 -0.305054)
			(stroke
				(width 0.1)
				(type default)
			)
			(layer "F.Fab")
		)
		(fp_line
			(start -0.67945 -0.305054)
			(end -0.12065 -0.305054)
			(stroke
				(width 0.1)
				(type default)
			)
			(layer "F.Fab")
		)
		(pad "1" smd circle
			(at -0.40005 0 180)
			(size 0 0)
			(layers "F.Cu" "F.Mask" "F.Paste")
			(net "PVDD11_S3_P1")
		)
		(pad "2" smd circle
			(at 0.40005 0 180)
			(size 0 0)
			(layers "F.Cu" "F.Mask" "F.Paste")
			(net "I3C_0_SPD_DDRAF_CPU1_R_SDA")
		)
	)
	(footprint ""
		(layer "F.Cu")
		(at 89.898982 -53.697378)
		(property "Reference" "PR4523"
			(at 0 0 0)
			(layer "F.SilkS")
			(hide yes)
			(effects
				(font
					(size 1.27 1.27)
				)
			)
		)
		(property "Value" ""
			(at 0 0 0)
			(layer "F.Fab")
			(effects
				(font
					(size 1.27 1.27)
				)
			)
		)
		(duplicate_pad_numbers_are_jumpers no)
		(fp_line
			(start -0.7874 -0.4064)
			(end 0.7874 -0.4064)
			(stroke
				(width 0.1524)
				(type default)
			)
			(layer "F.SilkS")
		)
		(fp_line
			(start -0.7874 0.4064)
			(end -0.7874 -0.4064)
			(stroke
				(width 0.1524)
				(type default)
			)
			(layer "F.SilkS")
		)
		(fp_line
			(start 0.7874 -0.4064)
			(end 0.7874 0.4064)
			(stroke
				(width 0.1524)
				(type default)
			)
			(layer "F.SilkS")
		)
		(fp_line
			(start 0.7874 0.4064)
			(end -0.7874 0.4064)
			(stroke
				(width 0.1524)
				(type default)
			)
			(layer "F.SilkS")
		)
		(fp_line
			(start -0.67945 -0.305054)
			(end -0.12065 -0.305054)
			(stroke
				(width 0.1)
				(type default)
			)
			(layer "F.Fab")
		)
		(fp_line
			(start -0.67945 0.3048)
			(end -0.67945 -0.305054)
			(stroke
				(width 0.1)
				(type default)
			)
			(layer "F.Fab")
		)
		(fp_line
			(start -0.12065 -0.305054)
			(end -0.12065 -0.2794)
			(stroke
				(width 0.1)
				(type default)
			)
			(layer "F.Fab")
		)
		(fp_line
			(start -0.12065 -0.2794)
			(end 0.12065 -0.2794)
			(stroke
				(width 0.1)
				(type default)
			)
			(layer "F.Fab")
		)
		(fp_line
			(start -0.12065 0.2794)
			(end -0.12065 0.3048)
			(stroke
				(width 0.1)
				(type default)
			)
			(layer "F.Fab")
		)
		(fp_line
			(start -0.12065 0.3048)
			(end -0.67945 0.3048)
			(stroke
				(width 0.1)
				(type default)
			)
			(layer "F.Fab")
		)
		(fp_line
			(start 0.120396 0.2794)
			(end -0.12065 0.2794)
			(stroke
				(width 0.1)
				(type default)
			)
			(layer "F.Fab")
		)
		(fp_line
			(start 0.120396 0.3048)
			(end 0.120396 0.2794)
			(stroke
				(width 0.1)
				(type default)
			)
			(layer "F.Fab")
		)
		(fp_line
			(start 0.12065 -0.3048)
			(end 0.67945 -0.3048)
			(stroke
				(width 0.1)
				(type default)
			)
			(layer "F.Fab")
		)
		(fp_line
			(start 0.12065 -0.2794)
			(end 0.12065 -0.3048)
			(stroke
				(width 0.1)
				(type default)
			)
			(layer "F.Fab")
		)
		(fp_line
			(start 0.67945 -0.3048)
			(end 0.67945 0.3048)
			(stroke
				(width 0.1)
				(type default)
			)
			(layer "F.Fab")
		)
		(fp_line
			(start 0.67945 0.3048)
			(end 0.120396 0.3048)
			(stroke
				(width 0.1)
				(type default)
			)
			(layer "F.Fab")
		)
		(pad "1" smd circle
			(at -0.40005 0)
			(size 0 0)
			(layers "F.Cu" "F.Mask" "F.Paste")
			(net "P3V3_OCP_V3_2_R")
		)
		(pad "2" smd circle
			(at 0.40005 0)
			(size 0 0)
			(layers "F.Cu" "F.Mask" "F.Paste")
			(net "P3V3_OCP_GATE_2")
		)
	)
	(footprint ""
		(layer "F.Cu")
		(at 70.32117 -177.540666 90)
		(property "Reference" "PC310_5"
			(at 0 0 90)
			(layer "F.SilkS")
			(hide yes)
			(effects
				(font
					(size 1.27 1.27)
				)
			)
		)
		(property "Value" ""
			(at 0 0 90)
			(layer "F.Fab")
			(effects
				(font
					(size 1.27 1.27)
				)
			)
		)
		(duplicate_pad_numbers_are_jumpers no)
		(fp_line
			(start 0.7874 -0.4064)
			(end 0.7874 0.4064)
			(stroke
				(width 0.1524)
				(type default)
			)
			(layer "F.SilkS")
		)
		(fp_line
			(start -0.7874 -0.4064)
			(end 0.7874 -0.4064)
			(stroke
				(width 0.1524)
				(type default)
			)
			(layer "F.SilkS")
		)
		(fp_line
			(start 0.7874 0.4064)
			(end -0.7874 0.4064)
			(stroke
				(width 0.1524)
				(type default)
			)
			(layer "F.SilkS")
		)
		(fp_line
			(start -0.7874 0.4064)
			(end -0.7874 -0.4064)
			(stroke
				(width 0.1524)
				(type default)
			)
			(layer "F.SilkS")
		)
		(fp_line
			(start -0.12065 -0.305054)
			(end -0.12065 -0.2794)
			(stroke
				(width 0.1)
				(type default)
			)
			(layer "F.Fab")
		)
		(fp_line
			(start -0.67945 -0.305054)
			(end -0.12065 -0.305054)
			(stroke
				(width 0.1)
				(type default)
			)
			(layer "F.Fab")
		)
		(fp_line
			(start 0.67945 -0.3048)
			(end 0.67945 0.3048)
			(stroke
				(width 0.1)
				(type default)
			)
			(layer "F.Fab")
		)
		(fp_line
			(start 0.12065 -0.3048)
			(end 0.67945 -0.3048)
			(stroke
				(width 0.1)
				(type default)
			)
			(layer "F.Fab")
		)
		(fp_line
			(start 0.12065 -0.2794)
			(end 0.12065 -0.3048)
			(stroke
				(width 0.1)
				(type default)
			)
			(layer "F.Fab")
		)
		(fp_line
			(start -0.12065 -0.2794)
			(end 0.12065 -0.2794)
			(stroke
				(width 0.1)
				(type default)
			)
			(layer "F.Fab")
		)
		(fp_line
			(start 0.120396 0.2794)
			(end -0.12065 0.2794)
			(stroke
				(width 0.1)
				(type default)
			)
			(layer "F.Fab")
		)
		(fp_line
			(start -0.12065 0.2794)
			(end -0.12065 0.3048)
			(stroke
				(width 0.1)
				(type default)
			)
			(layer "F.Fab")
		)
		(fp_line
			(start 0.67945 0.3048)
			(end 0.120396 0.3048)
			(stroke
				(width 0.1)
				(type default)
			)
			(layer "F.Fab")
		)
		(fp_line
			(start 0.120396 0.3048)
			(end 0.120396 0.2794)
			(stroke
				(width 0.1)
				(type default)
			)
			(layer "F.Fab")
		)
		(fp_line
			(start -0.12065 0.3048)
			(end -0.67945 0.3048)
			(stroke
				(width 0.1)
				(type default)
			)
			(layer "F.Fab")
		)
		(fp_line
			(start -0.67945 0.3048)
			(end -0.67945 -0.305054)
			(stroke
				(width 0.1)
				(type default)
			)
			(layer "F.Fab")
		)
		(pad "1" smd circle
			(at -0.40005 0 90)
			(size 0 0)
			(layers "F.Cu" "F.Mask" "F.Paste")
			(net "SW_P12V_AUX_PVDDCR_CPU0_P1_FLT")
		)
		(pad "2" smd circle
			(at 0.40005 0 90)
			(size 0 0)
			(layers "F.Cu" "F.Mask" "F.Paste")
			(net "GND")
		)
	)
	(footprint ""
		(layer "F.Cu")
		(at 105.485946 -52.86248 -90)
		(property "Reference" "R6313"
			(at 0 0 270)
			(layer "F.SilkS")
			(hide yes)
			(effects
				(font
					(size 1.27 1.27)
				)
			)
		)
		(property "Value" ""
			(at 0 0 270)
			(layer "F.Fab")
			(effects
				(font
					(size 1.27 1.27)
				)
			)
		)
		(duplicate_pad_numbers_are_jumpers no)
		(fp_line
			(start -0.7874 0.4064)
			(end -0.7874 -0.4064)
			(stroke
				(width 0.1524)
				(type default)
			)
			(layer "F.SilkS")
		)
		(fp_line
			(start 0.7874 0.4064)
			(end -0.7874 0.4064)
			(stroke
				(width 0.1524)
				(type default)
			)
			(layer "F.SilkS")
		)
		(fp_line
			(start -0.7874 -0.4064)
			(end 0.7874 -0.4064)
			(stroke
				(width 0.1524)
				(type default)
			)
			(layer "F.SilkS")
		)
		(fp_line
			(start 0.7874 -0.4064)
			(end 0.7874 0.4064)
			(stroke
				(width 0.1524)
				(type default)
			)
			(layer "F.SilkS")
		)
		(fp_line
			(start -0.67945 0.3048)
			(end -0.67945 -0.305054)
			(stroke
				(width 0.1)
				(type default)
			)
			(layer "F.Fab")
		)
		(fp_line
			(start -0.12065 0.3048)
			(end -0.67945 0.3048)
			(stroke
				(width 0.1)
				(type default)
			)
			(layer "F.Fab")
		)
		(fp_line
			(start 0.120396 0.3048)
			(end 0.120396 0.2794)
			(stroke
				(width 0.1)
				(type default)
			)
			(layer "F.Fab")
		)
		(fp_line
			(start 0.67945 0.3048)
			(end 0.120396 0.3048)
			(stroke
				(width 0.1)
				(type default)
			)
			(layer "F.Fab")
		)
		(fp_line
			(start -0.12065 0.2794)
			(end -0.12065 0.3048)
			(stroke
				(width 0.1)
				(type default)
			)
			(layer "F.Fab")
		)
		(fp_line
			(start 0.120396 0.2794)
			(end -0.12065 0.2794)
			(stroke
				(width 0.1)
				(type default)
			)
			(layer "F.Fab")
		)
		(fp_line
			(start -0.12065 -0.2794)
			(end 0.12065 -0.2794)
			(stroke
				(width 0.1)
				(type default)
			)
			(layer "F.Fab")
		)
		(fp_line
			(start 0.12065 -0.2794)
			(end 0.12065 -0.3048)
			(stroke
				(width 0.1)
				(type default)
			)
			(layer "F.Fab")
		)
		(fp_line
			(start 0.12065 -0.3048)
			(end 0.67945 -0.3048)
			(stroke
				(width 0.1)
				(type default)
			)
			(layer "F.Fab")
		)
		(fp_line
			(start 0.67945 -0.3048)
			(end 0.67945 0.3048)
			(stroke
				(width 0.1)
				(type default)
			)
			(layer "F.Fab")
		)
		(fp_line
			(start -0.67945 -0.305054)
			(end -0.12065 -0.305054)
			(stroke
				(width 0.1)
				(type default)
			)
			(layer "F.Fab")
		)
		(fp_line
			(start -0.12065 -0.305054)
			(end -0.12065 -0.2794)
			(stroke
				(width 0.1)
				(type default)
			)
			(layer "F.Fab")
		)
		(pad "1" smd circle
			(at -0.40005 0 270)
			(size 0 0)
			(layers "F.Cu" "F.Mask" "F.Paste")
			(net "USB_HUB2_TI_OVERCUR2")
		)
		(pad "2" smd circle
			(at 0.40005 0 270)
			(size 0 0)
			(layers "F.Cu" "F.Mask" "F.Paste")
			(net "USB_HUB2_TI_OVERCUR2_MRP_PROG_FUNC5")
		)
	)
	(footprint ""
		(layer "F.Cu")
		(at 20.575524 -405.868378 90)
		(property "Reference" "R6861"
			(at 0 0 90)
			(layer "F.SilkS")
			(hide yes)
			(effects
				(font
					(size 1.27 1.27)
				)
			)
		)
		(property "Value" ""
			(at 0 0 90)
			(layer "F.Fab")
			(effects
				(font
					(size 1.27 1.27)
				)
			)
		)
		(duplicate_pad_numbers_are_jumpers no)
		(fp_line
			(start 0.7874 -0.4064)
			(end 0.7874 0.4064)
			(stroke
				(width 0.1524)
				(type default)
			)
			(layer "F.SilkS")
		)
		(fp_line
			(start -0.7874 -0.4064)
			(end 0.7874 -0.4064)
			(stroke
				(width 0.1524)
				(type default)
			)
			(layer "F.SilkS")
		)
		(fp_line
			(start 0.7874 0.4064)
			(end -0.7874 0.4064)
			(stroke
				(width 0.1524)
				(type default)
			)
			(layer "F.SilkS")
		)
		(fp_line
			(start -0.7874 0.4064)
			(end -0.7874 -0.4064)
			(stroke
				(width 0.1524)
				(type default)
			)
			(layer "F.SilkS")
		)
		(fp_line
			(start -0.12065 -0.305054)
			(end -0.12065 -0.2794)
			(stroke
				(width 0.1)
				(type default)
			)
			(layer "F.Fab")
		)
		(fp_line
			(start -0.67945 -0.305054)
			(end -0.12065 -0.305054)
			(stroke
				(width 0.1)
				(type default)
			)
			(layer "F.Fab")
		)
		(fp_line
			(start 0.67945 -0.3048)
			(end 0.67945 0.3048)
			(stroke
				(width 0.1)
				(type default)
			)
			(layer "F.Fab")
		)
		(fp_line
			(start 0.12065 -0.3048)
			(end 0.67945 -0.3048)
			(stroke
				(width 0.1)
				(type default)
			)
			(layer "F.Fab")
		)
		(fp_line
			(start 0.12065 -0.2794)
			(end 0.12065 -0.3048)
			(stroke
				(width 0.1)
				(type default)
			)
			(layer "F.Fab")
		)
		(fp_line
			(start -0.12065 -0.2794)
			(end 0.12065 -0.2794)
			(stroke
				(width 0.1)
				(type default)
			)
			(layer "F.Fab")
		)
		(fp_line
			(start 0.120396 0.2794)
			(end -0.12065 0.2794)
			(stroke
				(width 0.1)
				(type default)
			)
			(layer "F.Fab")
		)
		(fp_line
			(start -0.12065 0.2794)
			(end -0.12065 0.3048)
			(stroke
				(width 0.1)
				(type default)
			)
			(layer "F.Fab")
		)
		(fp_line
			(start 0.67945 0.3048)
			(end 0.120396 0.3048)
			(stroke
				(width 0.1)
				(type default)
			)
			(layer "F.Fab")
		)
		(fp_line
			(start 0.120396 0.3048)
			(end 0.120396 0.2794)
			(stroke
				(width 0.1)
				(type default)
			)
			(layer "F.Fab")
		)
		(fp_line
			(start -0.12065 0.3048)
			(end -0.67945 0.3048)
			(stroke
				(width 0.1)
				(type default)
			)
			(layer "F.Fab")
		)
		(fp_line
			(start -0.67945 0.3048)
			(end -0.67945 -0.305054)
			(stroke
				(width 0.1)
				(type default)
			)
			(layer "F.Fab")
		)
		(pad "1" smd circle
			(at -0.40005 0 90)
			(size 0 0)
			(layers "F.Cu" "F.Mask" "F.Paste")
			(net "P1V8_AUX")
		)
		(pad "2" smd circle
			(at 0.40005 0 90)
			(size 0 0)
			(layers "F.Cu" "F.Mask" "F.Paste")
			(net "PWRGD_P0V9_RETIMER_CPU1_R")
		)
	)
	(footprint ""
		(layer "F.Cu")
		(at 73.189084 -408.517344 -90)
		(property "Reference" "C6645"
			(at 0 0 270)
			(layer "F.SilkS")
			(hide yes)
			(effects
				(font
					(size 1.27 1.27)
				)
			)
		)
		(property "Value" ""
			(at 0 0 270)
			(layer "F.Fab")
			(effects
				(font
					(size 1.27 1.27)
				)
			)
		)
		(duplicate_pad_numbers_are_jumpers no)
		(fp_line
			(start -0.299974 0.150114)
			(end -0.299974 -0.150114)
			(stroke
				(width 0.1)
				(type default)
			)
			(layer "F.Fab")
		)
		(fp_line
			(start 0.299974 0.150114)
			(end -0.299974 0.150114)
			(stroke
				(width 0.1)
				(type default)
			)
			(layer "F.Fab")
		)
		(fp_line
			(start -0.299974 -0.150114)
			(end 0.299974 -0.150114)
			(stroke
				(width 0.1)
				(type default)
			)
			(layer "F.Fab")
		)
		(fp_line
			(start 0.299974 -0.150114)
			(end 0.299974 0.150114)
			(stroke
				(width 0.1)
				(type default)
			)
			(layer "F.Fab")
		)
		(pad "1" smd rect
			(at -0.2667 0 270)
			(size 0.3048 0.381)
			(layers "F.Cu" "F.Mask" "F.Paste")
			(net "P5E_CPU1_P0_TX_BUF_C_DP<8>")
		)
		(pad "2" smd rect
			(at 0.2667 0 270)
			(size 0.3048 0.381)
			(layers "F.Cu" "F.Mask" "F.Paste")
			(net "P5E_CPU1_P0_TX_BUF_DP<8>")
		)
	)
	(footprint ""
		(layer "F.Cu")
		(at 231.42702 -291.761926)
		(property "Reference" "PU6501"
			(at 1.014476 -3.50774 0)
			(unlocked yes)
			(layer "F.SilkS")
			(effects
				(font
					(size 0.7874 0.5842)
					(thickness 0.1524)
				)
				(justify left)
			)
		)
		(property "Value" ""
			(at 0 0 0)
			(layer "F.Fab")
			(effects
				(font
					(size 1.27 1.27)
				)
			)
		)
		(duplicate_pad_numbers_are_jumpers no)
		(fp_line
			(start -1.549908 -2.050034)
			(end -1.549908 -1.9812)
			(stroke
				(width 0.1524)
				(type default)
			)
			(layer "F.SilkS")
		)
		(fp_line
			(start -1.549908 1.9812)
			(end -1.549908 2.050034)
			(stroke
				(width 0.1524)
				(type default)
			)
			(layer "F.SilkS")
		)
		(fp_line
			(start -1.549908 2.050034)
			(end -0.5842 2.050034)
			(stroke
				(width 0.1524)
				(type default)
			)
			(layer "F.SilkS")
		)
		(fp_line
			(start -0.5842 -2.050034)
			(end -1.549908 -2.050034)
			(stroke
				(width 0.1524)
				(type default)
			)
			(layer "F.SilkS")
		)
		(fp_line
			(start 0 2.050034)
			(end 1.549908 2.050034)
			(stroke
				(width 0.1524)
				(type default)
			)
			(layer "F.SilkS")
		)
		(fp_line
			(start 1.549908 -2.050034)
			(end 0.5842 -2.050034)
			(stroke
				(width 0.1524)
				(type default)
			)
			(layer "F.SilkS")
		)
		(fp_line
			(start 1.549908 -1.9812)
			(end 1.549908 -2.050034)
			(stroke
				(width 0.1524)
				(type default)
			)
			(layer "F.SilkS")
		)
		(fp_line
			(start 1.549908 2.050034)
			(end 1.549908 1.9304)
			(stroke
				(width 0.1524)
				(type default)
			)
			(layer "F.SilkS")
		)
		(fp_poly
			(pts
				(xy -2.9464 -2.208022) (xy -2.9464 -1.192022) (xy -1.9304 -1.700022)
			)
			(stroke
				(width 0)
				(type default)
			)
			(fill yes)
			(layer "F.SilkS")
		)
		(fp_line
			(start -1.549908 -2.050034)
			(end -1.549908 2.050034)
			(stroke
				(width 0.1)
				(type default)
			)
			(layer "F.Fab")
		)
		(fp_line
			(start -1.549908 2.050034)
			(end 1.549908 2.050034)
			(stroke
				(width 0.1)
				(type default)
			)
			(layer "F.Fab")
		)
		(fp_line
			(start 1.549908 -2.050034)
			(end -1.549908 -2.050034)
			(stroke
				(width 0.1)
				(type default)
			)
			(layer "F.Fab")
		)
		(fp_line
			(start 1.549908 2.050034)
			(end 1.549908 -2.050034)
			(stroke
				(width 0.1)
				(type default)
			)
			(layer "F.Fab")
		)
		(fp_poly
			(pts
				(xy -2.9464 -2.208022) (xy -2.9464 -1.192022) (xy -1.9304 -1.700022)
			)
			(stroke
				(width 0)
				(type default)
			)
			(fill yes)
			(layer "F.Fab")
		)
		(pad "1" smd circle
			(at -1.35001 -1.700022)
			(size 0 0)
			(layers "F.Cu" "F.Mask" "F.Paste")
			(net "SW_P1V8_RETIMER_CPU1_BST")
		)
		(pad "2" smd rect
			(at -1.400048 -1.199896 90)
			(size 0.1778 0.8128)
			(layers "F.Cu" "F.Mask" "F.Paste")
			(net "GND")
		)
		(pad "3" smd rect
			(at -1.400048 -0.8001 90)
			(size 0.1778 0.8128)
			(layers "F.Cu" "F.Mask" "F.Paste")
			(net "P1V8_RETIMER_CPU1_CS")
		)
		(pad "4" smd rect
			(at -1.400048 -0.40005 90)
			(size 0.1778 0.8128)
			(layers "F.Cu" "F.Mask" "F.Paste")
			(net "P1V8_RETIMER_CPU1_MODE")
		)
		(pad "5" smd rect
			(at -1.400048 0 90)
			(size 0.1778 0.8128)
			(layers "F.Cu" "F.Mask" "F.Paste")
			(net "P1V8_RETIMER_CPU1_REF")
		)
		(pad "6" smd rect
			(at -1.400048 0.40005 90)
			(size 0.1778 0.8128)
			(layers "F.Cu" "F.Mask" "F.Paste")
			(net "GND")
		)
		(pad "7" smd rect
			(at -1.400048 0.8001 90)
			(size 0.1778 0.8128)
			(layers "F.Cu" "F.Mask" "F.Paste")
			(net "P1V8_RETIMER_CPU1_FB")
		)
		(pad "8" smd rect
			(at -1.400048 1.199896 90)
			(size 0.1778 0.8128)
			(layers "F.Cu" "F.Mask" "F.Paste")
			(net "P1V8_RETIMER_CPU1_EN")
		)
		(pad "9" smd rect
			(at -1.400048 1.700022 90)
			(size 0.3048 0.8128)
			(layers "F.Cu" "F.Mask" "F.Paste")
			(net "PWRGD_P1V8_RETIMER_CPU1")
		)
		(pad "10" smd rect
			(at -0.299974 1.299972)
			(size 0.3048 2.0066)
			(layers "F.Cu" "F.Mask" "F.Paste")
			(net "SW_P12V_AUX_P1V8_RETIMER_CPU1_FLT")
		)
		(pad "11_18" smd circle
			(at 1.175004 0.275082)
			(size 0 0)
			(layers "F.Cu" "F.Mask" "F.Paste")
			(net "GND")
		)
		(pad "19" smd rect
			(at 1.400048 -1.700022 270)
			(size 0.3048 0.8128)
			(layers "F.Cu" "F.Mask" "F.Paste")
			(net "P1V8_RETIMER_CPU1_VCC")
		)
		(pad "20" smd rect
			(at 0.299974 -1.299972)
			(size 0.3048 2.0066)
			(layers "F.Cu" "F.Mask" "F.Paste")
			(net "SW_P1V8_RETIMER_CPU1_SW")
		)
		(pad "21" smd rect
			(at -0.299974 -1.299972)
			(size 0.3048 2.0066)
			(layers "F.Cu" "F.Mask" "F.Paste")
			(net "SW_P12V_AUX_P1V8_RETIMER_CPU1_FLT")
		)
	)
	(footprint ""
		(layer "F.Cu")
		(at 303.999392 -346.866464 -90)
		(property "Reference" "PC150_1"
			(at 0 0 270)
			(layer "F.SilkS")
			(hide yes)
			(effects
				(font
					(size 1.27 1.27)
				)
			)
		)
		(property "Value" ""
			(at 0 0 270)
			(layer "F.Fab")
			(effects
				(font
					(size 1.27 1.27)
				)
			)
		)
		(duplicate_pad_numbers_are_jumpers no)
		(fp_line
			(start -0.7874 0.4064)
			(end -0.7874 -0.4064)
			(stroke
				(width 0.1524)
				(type default)
			)
			(layer "F.SilkS")
		)
		(fp_line
			(start 0.7874 0.4064)
			(end -0.7874 0.4064)
			(stroke
				(width 0.1524)
				(type default)
			)
			(layer "F.SilkS")
		)
		(fp_line
			(start -0.7874 -0.4064)
			(end 0.7874 -0.4064)
			(stroke
				(width 0.1524)
				(type default)
			)
			(layer "F.SilkS")
		)
		(fp_line
			(start 0.7874 -0.4064)
			(end 0.7874 0.4064)
			(stroke
				(width 0.1524)
				(type default)
			)
			(layer "F.SilkS")
		)
		(fp_line
			(start -0.67945 0.3048)
			(end -0.67945 -0.305054)
			(stroke
				(width 0.1)
				(type default)
			)
			(layer "F.Fab")
		)
		(fp_line
			(start -0.12065 0.3048)
			(end -0.67945 0.3048)
			(stroke
				(width 0.1)
				(type default)
			)
			(layer "F.Fab")
		)
		(fp_line
			(start 0.120396 0.3048)
			(end 0.120396 0.2794)
			(stroke
				(width 0.1)
				(type default)
			)
			(layer "F.Fab")
		)
		(fp_line
			(start 0.67945 0.3048)
			(end 0.120396 0.3048)
			(stroke
				(width 0.1)
				(type default)
			)
			(layer "F.Fab")
		)
		(fp_line
			(start -0.12065 0.2794)
			(end -0.12065 0.3048)
			(stroke
				(width 0.1)
				(type default)
			)
			(layer "F.Fab")
		)
		(fp_line
			(start 0.120396 0.2794)
			(end -0.12065 0.2794)
			(stroke
				(width 0.1)
				(type default)
			)
			(layer "F.Fab")
		)
		(fp_line
			(start -0.12065 -0.2794)
			(end 0.12065 -0.2794)
			(stroke
				(width 0.1)
				(type default)
			)
			(layer "F.Fab")
		)
		(fp_line
			(start 0.12065 -0.2794)
			(end 0.12065 -0.3048)
			(stroke
				(width 0.1)
				(type default)
			)
			(layer "F.Fab")
		)
		(fp_line
			(start 0.12065 -0.3048)
			(end 0.67945 -0.3048)
			(stroke
				(width 0.1)
				(type default)
			)
			(layer "F.Fab")
		)
		(fp_line
			(start 0.67945 -0.3048)
			(end 0.67945 0.3048)
			(stroke
				(width 0.1)
				(type default)
			)
			(layer "F.Fab")
		)
		(fp_line
			(start -0.67945 -0.305054)
			(end -0.12065 -0.305054)
			(stroke
				(width 0.1)
				(type default)
			)
			(layer "F.Fab")
		)
		(fp_line
			(start -0.12065 -0.305054)
			(end -0.12065 -0.2794)
			(stroke
				(width 0.1)
				(type default)
			)
			(layer "F.Fab")
		)
		(pad "1" smd circle
			(at -0.40005 0 270)
			(size 0 0)
			(layers "F.Cu" "F.Mask" "F.Paste")
			(net "SW_P12V_AUX_PVDDIO_P0_FLT")
		)
		(pad "2" smd circle
			(at 0.40005 0 270)
			(size 0 0)
			(layers "F.Cu" "F.Mask" "F.Paste")
			(net "GND")
		)
	)
	(footprint ""
		(layer "F.Cu")
		(at 418.2237 -166.772082)
		(property "Reference" "PC188"
			(at 0 0 0)
			(layer "F.SilkS")
			(hide yes)
			(effects
				(font
					(size 1.27 1.27)
				)
			)
		)
		(property "Value" ""
			(at 0 0 0)
			(layer "F.Fab")
			(effects
				(font
					(size 1.27 1.27)
				)
			)
		)
		(duplicate_pad_numbers_are_jumpers no)
		(fp_line
			(start -0.7874 -0.4064)
			(end 0.7874 -0.4064)
			(stroke
				(width 0.1524)
				(type default)
			)
			(layer "F.SilkS")
		)
		(fp_line
			(start -0.7874 0.4064)
			(end -0.7874 -0.4064)
			(stroke
				(width 0.1524)
				(type default)
			)
			(layer "F.SilkS")
		)
		(fp_line
			(start 0.7874 -0.4064)
			(end 0.7874 0.4064)
			(stroke
				(width 0.1524)
				(type default)
			)
			(layer "F.SilkS")
		)
		(fp_line
			(start 0.7874 0.4064)
			(end -0.7874 0.4064)
			(stroke
				(width 0.1524)
				(type default)
			)
			(layer "F.SilkS")
		)
		(fp_line
			(start -0.67945 -0.305054)
			(end -0.12065 -0.305054)
			(stroke
				(width 0.1)
				(type default)
			)
			(layer "F.Fab")
		)
		(fp_line
			(start -0.67945 0.3048)
			(end -0.67945 -0.305054)
			(stroke
				(width 0.1)
				(type default)
			)
			(layer "F.Fab")
		)
		(fp_line
			(start -0.12065 -0.305054)
			(end -0.12065 -0.2794)
			(stroke
				(width 0.1)
				(type default)
			)
			(layer "F.Fab")
		)
		(fp_line
			(start -0.12065 -0.2794)
			(end 0.12065 -0.2794)
			(stroke
				(width 0.1)
				(type default)
			)
			(layer "F.Fab")
		)
		(fp_line
			(start -0.12065 0.2794)
			(end -0.12065 0.3048)
			(stroke
				(width 0.1)
				(type default)
			)
			(layer "F.Fab")
		)
		(fp_line
			(start -0.12065 0.3048)
			(end -0.67945 0.3048)
			(stroke
				(width 0.1)
				(type default)
			)
			(layer "F.Fab")
		)
		(fp_line
			(start 0.120396 0.2794)
			(end -0.12065 0.2794)
			(stroke
				(width 0.1)
				(type default)
			)
			(layer "F.Fab")
		)
		(fp_line
			(start 0.120396 0.3048)
			(end 0.120396 0.2794)
			(stroke
				(width 0.1)
				(type default)
			)
			(layer "F.Fab")
		)
		(fp_line
			(start 0.12065 -0.3048)
			(end 0.67945 -0.3048)
			(stroke
				(width 0.1)
				(type default)
			)
			(layer "F.Fab")
		)
		(fp_line
			(start 0.12065 -0.2794)
			(end 0.12065 -0.3048)
			(stroke
				(width 0.1)
				(type default)
			)
			(layer "F.Fab")
		)
		(fp_line
			(start 0.67945 -0.3048)
			(end 0.67945 0.3048)
			(stroke
				(width 0.1)
				(type default)
			)
			(layer "F.Fab")
		)
		(fp_line
			(start 0.67945 0.3048)
			(end 0.120396 0.3048)
			(stroke
				(width 0.1)
				(type default)
			)
			(layer "F.Fab")
		)
		(pad "1" smd circle
			(at -0.40005 0)
			(size 0 0)
			(layers "F.Cu" "F.Mask" "F.Paste")
			(net "SW_PVDDCR_SOC_P0_SW3")
		)
		(pad "2" smd circle
			(at 0.40005 0)
			(size 0 0)
			(layers "F.Cu" "F.Mask" "F.Paste")
			(net "SW_PVDDCR_SOC_P0_SW3_RC")
		)
	)
	(footprint ""
		(layer "F.Cu")
		(at 103.453946 -52.86248 -90)
		(property "Reference" "R6316"
			(at 0 0 270)
			(layer "F.SilkS")
			(hide yes)
			(effects
				(font
					(size 1.27 1.27)
				)
			)
		)
		(property "Value" ""
			(at 0 0 270)
			(layer "F.Fab")
			(effects
				(font
					(size 1.27 1.27)
				)
			)
		)
		(duplicate_pad_numbers_are_jumpers no)
		(fp_line
			(start -0.7874 0.4064)
			(end -0.7874 -0.4064)
			(stroke
				(width 0.1524)
				(type default)
			)
			(layer "F.SilkS")
		)
		(fp_line
			(start 0.7874 0.4064)
			(end -0.7874 0.4064)
			(stroke
				(width 0.1524)
				(type default)
			)
			(layer "F.SilkS")
		)
		(fp_line
			(start -0.7874 -0.4064)
			(end 0.7874 -0.4064)
			(stroke
				(width 0.1524)
				(type default)
			)
			(layer "F.SilkS")
		)
		(fp_line
			(start 0.7874 -0.4064)
			(end 0.7874 0.4064)
			(stroke
				(width 0.1524)
				(type default)
			)
			(layer "F.SilkS")
		)
		(fp_line
			(start -0.67945 0.3048)
			(end -0.67945 -0.305054)
			(stroke
				(width 0.1)
				(type default)
			)
			(layer "F.Fab")
		)
		(fp_line
			(start -0.12065 0.3048)
			(end -0.67945 0.3048)
			(stroke
				(width 0.1)
				(type default)
			)
			(layer "F.Fab")
		)
		(fp_line
			(start 0.120396 0.3048)
			(end 0.120396 0.2794)
			(stroke
				(width 0.1)
				(type default)
			)
			(layer "F.Fab")
		)
		(fp_line
			(start 0.67945 0.3048)
			(end 0.120396 0.3048)
			(stroke
				(width 0.1)
				(type default)
			)
			(layer "F.Fab")
		)
		(fp_line
			(start -0.12065 0.2794)
			(end -0.12065 0.3048)
			(stroke
				(width 0.1)
				(type default)
			)
			(layer "F.Fab")
		)
		(fp_line
			(start 0.120396 0.2794)
			(end -0.12065 0.2794)
			(stroke
				(width 0.1)
				(type default)
			)
			(layer "F.Fab")
		)
		(fp_line
			(start -0.12065 -0.2794)
			(end 0.12065 -0.2794)
			(stroke
				(width 0.1)
				(type default)
			)
			(layer "F.Fab")
		)
		(fp_line
			(start 0.12065 -0.2794)
			(end 0.12065 -0.3048)
			(stroke
				(width 0.1)
				(type default)
			)
			(layer "F.Fab")
		)
		(fp_line
			(start 0.12065 -0.3048)
			(end 0.67945 -0.3048)
			(stroke
				(width 0.1)
				(type default)
			)
			(layer "F.Fab")
		)
		(fp_line
			(start 0.67945 -0.3048)
			(end 0.67945 0.3048)
			(stroke
				(width 0.1)
				(type default)
			)
			(layer "F.Fab")
		)
		(fp_line
			(start -0.67945 -0.305054)
			(end -0.12065 -0.305054)
			(stroke
				(width 0.1)
				(type default)
			)
			(layer "F.Fab")
		)
		(fp_line
			(start -0.12065 -0.305054)
			(end -0.12065 -0.2794)
			(stroke
				(width 0.1)
				(type default)
			)
			(layer "F.Fab")
		)
		(pad "1" smd circle
			(at -0.40005 0 270)
			(size 0 0)
			(layers "F.Cu" "F.Mask" "F.Paste")
			(net "USB_HUB2_TI_USB_VBUS")
		)
		(pad "2" smd circle
			(at 0.40005 0 270)
			(size 0 0)
			(layers "F.Cu" "F.Mask" "F.Paste")
			(net "USB_HUB2_TI_USB_VBUS_MRP_RESET_N")
		)
	)
	(footprint ""
		(layer "F.Cu")
		(at 165.2016 -437.423052)
		(property "Reference" "R3463"
			(at 0 0 0)
			(layer "F.SilkS")
			(hide yes)
			(effects
				(font
					(size 1.27 1.27)
				)
			)
		)
		(property "Value" ""
			(at 0 0 0)
			(layer "F.Fab")
			(effects
				(font
					(size 1.27 1.27)
				)
			)
		)
		(duplicate_pad_numbers_are_jumpers no)
		(fp_line
			(start -0.7874 -0.4064)
			(end 0.7874 -0.4064)
			(stroke
				(width 0.1524)
				(type default)
			)
			(layer "F.SilkS")
		)
		(fp_line
			(start -0.7874 0.4064)
			(end -0.7874 -0.4064)
			(stroke
				(width 0.1524)
				(type default)
			)
			(layer "F.SilkS")
		)
		(fp_line
			(start 0.7874 -0.4064)
			(end 0.7874 0.4064)
			(stroke
				(width 0.1524)
				(type default)
			)
			(layer "F.SilkS")
		)
		(fp_line
			(start 0.7874 0.4064)
			(end -0.7874 0.4064)
			(stroke
				(width 0.1524)
				(type default)
			)
			(layer "F.SilkS")
		)
		(fp_line
			(start -0.67945 -0.305054)
			(end -0.12065 -0.305054)
			(stroke
				(width 0.1)
				(type default)
			)
			(layer "F.Fab")
		)
		(fp_line
			(start -0.67945 0.3048)
			(end -0.67945 -0.305054)
			(stroke
				(width 0.1)
				(type default)
			)
			(layer "F.Fab")
		)
		(fp_line
			(start -0.12065 -0.305054)
			(end -0.12065 -0.2794)
			(stroke
				(width 0.1)
				(type default)
			)
			(layer "F.Fab")
		)
		(fp_line
			(start -0.12065 -0.2794)
			(end 0.12065 -0.2794)
			(stroke
				(width 0.1)
				(type default)
			)
			(layer "F.Fab")
		)
		(fp_line
			(start -0.12065 0.2794)
			(end -0.12065 0.3048)
			(stroke
				(width 0.1)
				(type default)
			)
			(layer "F.Fab")
		)
		(fp_line
			(start -0.12065 0.3048)
			(end -0.67945 0.3048)
			(stroke
				(width 0.1)
				(type default)
			)
			(layer "F.Fab")
		)
		(fp_line
			(start 0.120396 0.2794)
			(end -0.12065 0.2794)
			(stroke
				(width 0.1)
				(type default)
			)
			(layer "F.Fab")
		)
		(fp_line
			(start 0.120396 0.3048)
			(end 0.120396 0.2794)
			(stroke
				(width 0.1)
				(type default)
			)
			(layer "F.Fab")
		)
		(fp_line
			(start 0.12065 -0.3048)
			(end 0.67945 -0.3048)
			(stroke
				(width 0.1)
				(type default)
			)
			(layer "F.Fab")
		)
		(fp_line
			(start 0.12065 -0.2794)
			(end 0.12065 -0.3048)
			(stroke
				(width 0.1)
				(type default)
			)
			(layer "F.Fab")
		)
		(fp_line
			(start 0.67945 -0.3048)
			(end 0.67945 0.3048)
			(stroke
				(width 0.1)
				(type default)
			)
			(layer "F.Fab")
		)
		(fp_line
			(start 0.67945 0.3048)
			(end 0.120396 0.3048)
			(stroke
				(width 0.1)
				(type default)
			)
			(layer "F.Fab")
		)
		(pad "1" smd circle
			(at -0.40005 0)
			(size 0 0)
			(layers "F.Cu" "F.Mask" "F.Paste")
			(net "GPU_BASE_HMC_READY")
		)
		(pad "2" smd circle
			(at 0.40005 0)
			(size 0 0)
			(layers "F.Cu" "F.Mask" "F.Paste")
			(net "GND")
		)
	)
	(footprint ""
		(layer "F.Cu")
		(at 9.238488 -135.32993 90)
		(property "Reference" "R4501"
			(at 0 0 90)
			(layer "F.SilkS")
			(hide yes)
			(effects
				(font
					(size 1.27 1.27)
				)
			)
		)
		(property "Value" ""
			(at 0 0 90)
			(layer "F.Fab")
			(effects
				(font
					(size 1.27 1.27)
				)
			)
		)
		(duplicate_pad_numbers_are_jumpers no)
		(fp_line
			(start 0.7874 -0.4064)
			(end 0.7874 0.4064)
			(stroke
				(width 0.1524)
				(type default)
			)
			(layer "F.SilkS")
		)
		(fp_line
			(start -0.7874 -0.4064)
			(end 0.7874 -0.4064)
			(stroke
				(width 0.1524)
				(type default)
			)
			(layer "F.SilkS")
		)
		(fp_line
			(start 0.7874 0.4064)
			(end -0.7874 0.4064)
			(stroke
				(width 0.1524)
				(type default)
			)
			(layer "F.SilkS")
		)
		(fp_line
			(start -0.7874 0.4064)
			(end -0.7874 -0.4064)
			(stroke
				(width 0.1524)
				(type default)
			)
			(layer "F.SilkS")
		)
		(fp_line
			(start -0.12065 -0.305054)
			(end -0.12065 -0.2794)
			(stroke
				(width 0.1)
				(type default)
			)
			(layer "F.Fab")
		)
		(fp_line
			(start -0.67945 -0.305054)
			(end -0.12065 -0.305054)
			(stroke
				(width 0.1)
				(type default)
			)
			(layer "F.Fab")
		)
		(fp_line
			(start 0.67945 -0.3048)
			(end 0.67945 0.3048)
			(stroke
				(width 0.1)
				(type default)
			)
			(layer "F.Fab")
		)
		(fp_line
			(start 0.12065 -0.3048)
			(end 0.67945 -0.3048)
			(stroke
				(width 0.1)
				(type default)
			)
			(layer "F.Fab")
		)
		(fp_line
			(start 0.12065 -0.2794)
			(end 0.12065 -0.3048)
			(stroke
				(width 0.1)
				(type default)
			)
			(layer "F.Fab")
		)
		(fp_line
			(start -0.12065 -0.2794)
			(end 0.12065 -0.2794)
			(stroke
				(width 0.1)
				(type default)
			)
			(layer "F.Fab")
		)
		(fp_line
			(start 0.120396 0.2794)
			(end -0.12065 0.2794)
			(stroke
				(width 0.1)
				(type default)
			)
			(layer "F.Fab")
		)
		(fp_line
			(start -0.12065 0.2794)
			(end -0.12065 0.3048)
			(stroke
				(width 0.1)
				(type default)
			)
			(layer "F.Fab")
		)
		(fp_line
			(start 0.67945 0.3048)
			(end 0.120396 0.3048)
			(stroke
				(width 0.1)
				(type default)
			)
			(layer "F.Fab")
		)
		(fp_line
			(start 0.120396 0.3048)
			(end 0.120396 0.2794)
			(stroke
				(width 0.1)
				(type default)
			)
			(layer "F.Fab")
		)
		(fp_line
			(start -0.12065 0.3048)
			(end -0.67945 0.3048)
			(stroke
				(width 0.1)
				(type default)
			)
			(layer "F.Fab")
		)
		(fp_line
			(start -0.67945 0.3048)
			(end -0.67945 -0.305054)
			(stroke
				(width 0.1)
				(type default)
			)
			(layer "F.Fab")
		)
		(pad "1" smd circle
			(at -0.40005 0 90)
			(size 0 0)
			(layers "F.Cu" "F.Mask" "F.Paste")
			(net "CLK_GEN2_XTAL_IN_R")
		)
		(pad "2" smd circle
			(at 0.40005 0 90)
			(size 0 0)
			(layers "F.Cu" "F.Mask" "F.Paste")
			(net "CLK_GEN2_XTAL_IN")
		)
	)
	(footprint ""
		(layer "F.Cu")
		(at 261.468616 -72.976994 180)
		(property "Reference" "R2125"
			(at 0 0 180)
			(layer "F.SilkS")
			(hide yes)
			(effects
				(font
					(size 1.27 1.27)
				)
			)
		)
		(property "Value" ""
			(at 0 0 180)
			(layer "F.Fab")
			(effects
				(font
					(size 1.27 1.27)
				)
			)
		)
		(duplicate_pad_numbers_are_jumpers no)
		(fp_line
			(start 0.7874 0.4064)
			(end -0.7874 0.4064)
			(stroke
				(width 0.1524)
				(type default)
			)
			(layer "F.SilkS")
		)
		(fp_line
			(start 0.7874 -0.4064)
			(end 0.7874 0.4064)
			(stroke
				(width 0.1524)
				(type default)
			)
			(layer "F.SilkS")
		)
		(fp_line
			(start -0.7874 0.4064)
			(end -0.7874 -0.4064)
			(stroke
				(width 0.1524)
				(type default)
			)
			(layer "F.SilkS")
		)
		(fp_line
			(start -0.7874 -0.4064)
			(end 0.7874 -0.4064)
			(stroke
				(width 0.1524)
				(type default)
			)
			(layer "F.SilkS")
		)
		(fp_line
			(start 0.67945 0.3048)
			(end 0.120396 0.3048)
			(stroke
				(width 0.1)
				(type default)
			)
			(layer "F.Fab")
		)
		(fp_line
			(start 0.67945 -0.3048)
			(end 0.67945 0.3048)
			(stroke
				(width 0.1)
				(type default)
			)
			(layer "F.Fab")
		)
		(fp_line
			(start 0.12065 -0.2794)
			(end 0.12065 -0.3048)
			(stroke
				(width 0.1)
				(type default)
			)
			(layer "F.Fab")
		)
		(fp_line
			(start 0.12065 -0.3048)
			(end 0.67945 -0.3048)
			(stroke
				(width 0.1)
				(type default)
			)
			(layer "F.Fab")
		)
		(fp_line
			(start 0.120396 0.3048)
			(end 0.120396 0.2794)
			(stroke
				(width 0.1)
				(type default)
			)
			(layer "F.Fab")
		)
		(fp_line
			(start 0.120396 0.2794)
			(end -0.12065 0.2794)
			(stroke
				(width 0.1)
				(type default)
			)
			(layer "F.Fab")
		)
		(fp_line
			(start -0.12065 0.3048)
			(end -0.67945 0.3048)
			(stroke
				(width 0.1)
				(type default)
			)
			(layer "F.Fab")
		)
		(fp_line
			(start -0.12065 0.2794)
			(end -0.12065 0.3048)
			(stroke
				(width 0.1)
				(type default)
			)
			(layer "F.Fab")
		)
		(fp_line
			(start -0.12065 -0.2794)
			(end 0.12065 -0.2794)
			(stroke
				(width 0.1)
				(type default)
			)
			(layer "F.Fab")
		)
		(fp_line
			(start -0.12065 -0.305054)
			(end -0.12065 -0.2794)
			(stroke
				(width 0.1)
				(type default)
			)
			(layer "F.Fab")
		)
		(fp_line
			(start -0.67945 0.3048)
			(end -0.67945 -0.305054)
			(stroke
				(width 0.1)
				(type default)
			)
			(layer "F.Fab")
		)
		(fp_line
			(start -0.67945 -0.305054)
			(end -0.12065 -0.305054)
			(stroke
				(width 0.1)
				(type default)
			)
			(layer "F.Fab")
		)
		(pad "1" smd circle
			(at -0.40005 0 180)
			(size 0 0)
			(layers "F.Cu" "F.Mask" "F.Paste")
			(net "P3V3_AUX")
		)
		(pad "2" smd circle
			(at 0.40005 0 180)
			(size 0 0)
			(layers "F.Cu" "F.Mask" "F.Paste")
			(net "SMB_PCIE_E1S_ISO_EN")
		)
	)
	(footprint ""
		(layer "F.Cu")
		(at 106.675936 -127.768096 -90)
		(property "Reference" "R1440"
			(at 0 0 270)
			(layer "F.SilkS")
			(hide yes)
			(effects
				(font
					(size 1.27 1.27)
				)
			)
		)
		(property "Value" ""
			(at 0 0 270)
			(layer "F.Fab")
			(effects
				(font
					(size 1.27 1.27)
				)
			)
		)
		(duplicate_pad_numbers_are_jumpers no)
		(fp_line
			(start -0.7874 0.4064)
			(end -0.7874 -0.4064)
			(stroke
				(width 0.1524)
				(type default)
			)
			(layer "F.SilkS")
		)
		(fp_line
			(start 0.7874 0.4064)
			(end -0.7874 0.4064)
			(stroke
				(width 0.1524)
				(type default)
			)
			(layer "F.SilkS")
		)
		(fp_line
			(start -0.7874 -0.4064)
			(end 0.7874 -0.4064)
			(stroke
				(width 0.1524)
				(type default)
			)
			(layer "F.SilkS")
		)
		(fp_line
			(start 0.7874 -0.4064)
			(end 0.7874 0.4064)
			(stroke
				(width 0.1524)
				(type default)
			)
			(layer "F.SilkS")
		)
		(fp_line
			(start -0.67945 0.3048)
			(end -0.67945 -0.305054)
			(stroke
				(width 0.1)
				(type default)
			)
			(layer "F.Fab")
		)
		(fp_line
			(start -0.12065 0.3048)
			(end -0.67945 0.3048)
			(stroke
				(width 0.1)
				(type default)
			)
			(layer "F.Fab")
		)
		(fp_line
			(start 0.120396 0.3048)
			(end 0.120396 0.2794)
			(stroke
				(width 0.1)
				(type default)
			)
			(layer "F.Fab")
		)
		(fp_line
			(start 0.67945 0.3048)
			(end 0.120396 0.3048)
			(stroke
				(width 0.1)
				(type default)
			)
			(layer "F.Fab")
		)
		(fp_line
			(start -0.12065 0.2794)
			(end -0.12065 0.3048)
			(stroke
				(width 0.1)
				(type default)
			)
			(layer "F.Fab")
		)
		(fp_line
			(start 0.120396 0.2794)
			(end -0.12065 0.2794)
			(stroke
				(width 0.1)
				(type default)
			)
			(layer "F.Fab")
		)
		(fp_line
			(start -0.12065 -0.2794)
			(end 0.12065 -0.2794)
			(stroke
				(width 0.1)
				(type default)
			)
			(layer "F.Fab")
		)
		(fp_line
			(start 0.12065 -0.2794)
			(end 0.12065 -0.3048)
			(stroke
				(width 0.1)
				(type default)
			)
			(layer "F.Fab")
		)
		(fp_line
			(start 0.12065 -0.3048)
			(end 0.67945 -0.3048)
			(stroke
				(width 0.1)
				(type default)
			)
			(layer "F.Fab")
		)
		(fp_line
			(start 0.67945 -0.3048)
			(end 0.67945 0.3048)
			(stroke
				(width 0.1)
				(type default)
			)
			(layer "F.Fab")
		)
		(fp_line
			(start -0.67945 -0.305054)
			(end -0.12065 -0.305054)
			(stroke
				(width 0.1)
				(type default)
			)
			(layer "F.Fab")
		)
		(fp_line
			(start -0.12065 -0.305054)
			(end -0.12065 -0.2794)
			(stroke
				(width 0.1)
				(type default)
			)
			(layer "F.Fab")
		)
		(pad "1" smd circle
			(at -0.40005 0 270)
			(size 0 0)
			(layers "F.Cu" "F.Mask" "F.Paste")
			(net "P12V_MEM_CPU1")
		)
		(pad "2" smd circle
			(at 0.40005 0 270)
			(size 0 0)
			(layers "F.Cu" "F.Mask" "F.Paste")
			(net "PWRGD_P12V_MEM_CPU1_EN")
		)
	)
	(footprint ""
		(layer "F.Cu")
		(at 249.916696 -44.572682 180)
		(property "Reference" "PR3961"
			(at 0 0 180)
			(layer "F.SilkS")
			(hide yes)
			(effects
				(font
					(size 1.27 1.27)
				)
			)
		)
		(property "Value" ""
			(at 0 0 180)
			(layer "F.Fab")
			(effects
				(font
					(size 1.27 1.27)
				)
			)
		)
		(duplicate_pad_numbers_are_jumpers no)
		(fp_line
			(start 0.7874 0.4064)
			(end -0.7874 0.4064)
			(stroke
				(width 0.1524)
				(type default)
			)
			(layer "F.SilkS")
		)
		(fp_line
			(start 0.7874 -0.4064)
			(end 0.7874 0.4064)
			(stroke
				(width 0.1524)
				(type default)
			)
			(layer "F.SilkS")
		)
		(fp_line
			(start -0.7874 0.4064)
			(end -0.7874 -0.4064)
			(stroke
				(width 0.1524)
				(type default)
			)
			(layer "F.SilkS")
		)
		(fp_line
			(start -0.7874 -0.4064)
			(end 0.7874 -0.4064)
			(stroke
				(width 0.1524)
				(type default)
			)
			(layer "F.SilkS")
		)
		(fp_line
			(start 0.67945 0.3048)
			(end 0.120396 0.3048)
			(stroke
				(width 0.1)
				(type default)
			)
			(layer "F.Fab")
		)
		(fp_line
			(start 0.67945 -0.3048)
			(end 0.67945 0.3048)
			(stroke
				(width 0.1)
				(type default)
			)
			(layer "F.Fab")
		)
		(fp_line
			(start 0.12065 -0.2794)
			(end 0.12065 -0.3048)
			(stroke
				(width 0.1)
				(type default)
			)
			(layer "F.Fab")
		)
		(fp_line
			(start 0.12065 -0.3048)
			(end 0.67945 -0.3048)
			(stroke
				(width 0.1)
				(type default)
			)
			(layer "F.Fab")
		)
		(fp_line
			(start 0.120396 0.3048)
			(end 0.120396 0.2794)
			(stroke
				(width 0.1)
				(type default)
			)
			(layer "F.Fab")
		)
		(fp_line
			(start 0.120396 0.2794)
			(end -0.12065 0.2794)
			(stroke
				(width 0.1)
				(type default)
			)
			(layer "F.Fab")
		)
		(fp_line
			(start -0.12065 0.3048)
			(end -0.67945 0.3048)
			(stroke
				(width 0.1)
				(type default)
			)
			(layer "F.Fab")
		)
		(fp_line
			(start -0.12065 0.2794)
			(end -0.12065 0.3048)
			(stroke
				(width 0.1)
				(type default)
			)
			(layer "F.Fab")
		)
		(fp_line
			(start -0.12065 -0.2794)
			(end 0.12065 -0.2794)
			(stroke
				(width 0.1)
				(type default)
			)
			(layer "F.Fab")
		)
		(fp_line
			(start -0.12065 -0.305054)
			(end -0.12065 -0.2794)
			(stroke
				(width 0.1)
				(type default)
			)
			(layer "F.Fab")
		)
		(fp_line
			(start -0.67945 0.3048)
			(end -0.67945 -0.305054)
			(stroke
				(width 0.1)
				(type default)
			)
			(layer "F.Fab")
		)
		(fp_line
			(start -0.67945 -0.305054)
			(end -0.12065 -0.305054)
			(stroke
				(width 0.1)
				(type default)
			)
			(layer "F.Fab")
		)
		(pad "1" smd circle
			(at -0.40005 0 180)
			(size 0 0)
			(layers "F.Cu" "F.Mask" "F.Paste")
			(net "P12V_E1S_UV_0")
		)
		(pad "2" smd circle
			(at 0.40005 0 180)
			(size 0 0)
			(layers "F.Cu" "F.Mask" "F.Paste")
			(net "P12V_E1S_OV_0")
		)
	)
	(footprint ""
		(layer "F.Cu")
		(at 420.74084 -378.95403 -90)
		(property "Reference" "C845"
			(at 0 0 270)
			(layer "F.SilkS")
			(hide yes)
			(effects
				(font
					(size 1.27 1.27)
				)
			)
		)
		(property "Value" ""
			(at 0 0 270)
			(layer "F.Fab")
			(effects
				(font
					(size 1.27 1.27)
				)
			)
		)
		(duplicate_pad_numbers_are_jumpers no)
		(fp_line
			(start -0.299974 0.150114)
			(end -0.299974 -0.150114)
			(stroke
				(width 0.1)
				(type default)
			)
			(layer "F.Fab")
		)
		(fp_line
			(start 0.299974 0.150114)
			(end -0.299974 0.150114)
			(stroke
				(width 0.1)
				(type default)
			)
			(layer "F.Fab")
		)
		(fp_line
			(start -0.299974 -0.150114)
			(end 0.299974 -0.150114)
			(stroke
				(width 0.1)
				(type default)
			)
			(layer "F.Fab")
		)
		(fp_line
			(start 0.299974 -0.150114)
			(end 0.299974 0.150114)
			(stroke
				(width 0.1)
				(type default)
			)
			(layer "F.Fab")
		)
		(pad "1" smd rect
			(at -0.2667 0 270)
			(size 0.3048 0.381)
			(layers "F.Cu" "F.Mask" "F.Paste")
			(net "P5E_CPU0_P2_TX_C_DP<12>")
		)
		(pad "2" smd rect
			(at 0.2667 0 270)
			(size 0.3048 0.381)
			(layers "F.Cu" "F.Mask" "F.Paste")
			(net "P5E_CPU0_P2_TX_DP<12>")
		)
	)
	(footprint ""
		(layer "F.Cu")
		(at 100.03536 -336.935064 180)
		(property "Reference" "PC208"
			(at 0 0 180)
			(layer "F.SilkS")
			(hide yes)
			(effects
				(font
					(size 1.27 1.27)
				)
			)
		)
		(property "Value" ""
			(at 0 0 180)
			(layer "F.Fab")
			(effects
				(font
					(size 1.27 1.27)
				)
			)
		)
		(duplicate_pad_numbers_are_jumpers no)
		(fp_line
			(start 0.7874 0.4064)
			(end -0.7874 0.4064)
			(stroke
				(width 0.1524)
				(type default)
			)
			(layer "F.SilkS")
		)
		(fp_line
			(start 0.7874 -0.4064)
			(end 0.7874 0.4064)
			(stroke
				(width 0.1524)
				(type default)
			)
			(layer "F.SilkS")
		)
		(fp_line
			(start -0.7874 0.4064)
			(end -0.7874 -0.4064)
			(stroke
				(width 0.1524)
				(type default)
			)
			(layer "F.SilkS")
		)
		(fp_line
			(start -0.7874 -0.4064)
			(end 0.7874 -0.4064)
			(stroke
				(width 0.1524)
				(type default)
			)
			(layer "F.SilkS")
		)
		(fp_line
			(start 0.67945 0.3048)
			(end 0.120396 0.3048)
			(stroke
				(width 0.1)
				(type default)
			)
			(layer "F.Fab")
		)
		(fp_line
			(start 0.67945 -0.3048)
			(end 0.67945 0.3048)
			(stroke
				(width 0.1)
				(type default)
			)
			(layer "F.Fab")
		)
		(fp_line
			(start 0.12065 -0.2794)
			(end 0.12065 -0.3048)
			(stroke
				(width 0.1)
				(type default)
			)
			(layer "F.Fab")
		)
		(fp_line
			(start 0.12065 -0.3048)
			(end 0.67945 -0.3048)
			(stroke
				(width 0.1)
				(type default)
			)
			(layer "F.Fab")
		)
		(fp_line
			(start 0.120396 0.3048)
			(end 0.120396 0.2794)
			(stroke
				(width 0.1)
				(type default)
			)
			(layer "F.Fab")
		)
		(fp_line
			(start 0.120396 0.2794)
			(end -0.12065 0.2794)
			(stroke
				(width 0.1)
				(type default)
			)
			(layer "F.Fab")
		)
		(fp_line
			(start -0.12065 0.3048)
			(end -0.67945 0.3048)
			(stroke
				(width 0.1)
				(type default)
			)
			(layer "F.Fab")
		)
		(fp_line
			(start -0.12065 0.2794)
			(end -0.12065 0.3048)
			(stroke
				(width 0.1)
				(type default)
			)
			(layer "F.Fab")
		)
		(fp_line
			(start -0.12065 -0.2794)
			(end 0.12065 -0.2794)
			(stroke
				(width 0.1)
				(type default)
			)
			(layer "F.Fab")
		)
		(fp_line
			(start -0.12065 -0.305054)
			(end -0.12065 -0.2794)
			(stroke
				(width 0.1)
				(type default)
			)
			(layer "F.Fab")
		)
		(fp_line
			(start -0.67945 0.3048)
			(end -0.67945 -0.305054)
			(stroke
				(width 0.1)
				(type default)
			)
			(layer "F.Fab")
		)
		(fp_line
			(start -0.67945 -0.305054)
			(end -0.12065 -0.305054)
			(stroke
				(width 0.1)
				(type default)
			)
			(layer "F.Fab")
		)
		(pad "1" smd circle
			(at -0.40005 0 180)
			(size 0 0)
			(layers "F.Cu" "F.Mask" "F.Paste")
			(net "SW_PVDDCR_CPU1_P1_SW6")
		)
		(pad "2" smd circle
			(at 0.40005 0 180)
			(size 0 0)
			(layers "F.Cu" "F.Mask" "F.Paste")
			(net "SW_PVDDCR_CPU1_P1_SW6_RC")
		)
	)
	(footprint ""
		(layer "F.Cu")
		(at 124.633228 -51.185064 180)
		(property "Reference" "C2317"
			(at 0 0 180)
			(layer "F.SilkS")
			(hide yes)
			(effects
				(font
					(size 1.27 1.27)
				)
			)
		)
		(property "Value" ""
			(at 0 0 180)
			(layer "F.Fab")
			(effects
				(font
					(size 1.27 1.27)
				)
			)
		)
		(duplicate_pad_numbers_are_jumpers no)
		(fp_line
			(start 0.7874 0.4064)
			(end -0.7874 0.4064)
			(stroke
				(width 0.1524)
				(type default)
			)
			(layer "F.SilkS")
		)
		(fp_line
			(start 0.7874 -0.4064)
			(end 0.7874 0.4064)
			(stroke
				(width 0.1524)
				(type default)
			)
			(layer "F.SilkS")
		)
		(fp_line
			(start -0.7874 0.4064)
			(end -0.7874 -0.4064)
			(stroke
				(width 0.1524)
				(type default)
			)
			(layer "F.SilkS")
		)
		(fp_line
			(start -0.7874 -0.4064)
			(end 0.7874 -0.4064)
			(stroke
				(width 0.1524)
				(type default)
			)
			(layer "F.SilkS")
		)
		(fp_line
			(start 0.67945 0.3048)
			(end 0.120396 0.3048)
			(stroke
				(width 0.1)
				(type default)
			)
			(layer "F.Fab")
		)
		(fp_line
			(start 0.67945 -0.3048)
			(end 0.67945 0.3048)
			(stroke
				(width 0.1)
				(type default)
			)
			(layer "F.Fab")
		)
		(fp_line
			(start 0.12065 -0.2794)
			(end 0.12065 -0.3048)
			(stroke
				(width 0.1)
				(type default)
			)
			(layer "F.Fab")
		)
		(fp_line
			(start 0.12065 -0.3048)
			(end 0.67945 -0.3048)
			(stroke
				(width 0.1)
				(type default)
			)
			(layer "F.Fab")
		)
		(fp_line
			(start 0.120396 0.3048)
			(end 0.120396 0.2794)
			(stroke
				(width 0.1)
				(type default)
			)
			(layer "F.Fab")
		)
		(fp_line
			(start 0.120396 0.2794)
			(end -0.12065 0.2794)
			(stroke
				(width 0.1)
				(type default)
			)
			(layer "F.Fab")
		)
		(fp_line
			(start -0.12065 0.3048)
			(end -0.67945 0.3048)
			(stroke
				(width 0.1)
				(type default)
			)
			(layer "F.Fab")
		)
		(fp_line
			(start -0.12065 0.2794)
			(end -0.12065 0.3048)
			(stroke
				(width 0.1)
				(type default)
			)
			(layer "F.Fab")
		)
		(fp_line
			(start -0.12065 -0.2794)
			(end 0.12065 -0.2794)
			(stroke
				(width 0.1)
				(type default)
			)
			(layer "F.Fab")
		)
		(fp_line
			(start -0.12065 -0.305054)
			(end -0.12065 -0.2794)
			(stroke
				(width 0.1)
				(type default)
			)
			(layer "F.Fab")
		)
		(fp_line
			(start -0.67945 0.3048)
			(end -0.67945 -0.305054)
			(stroke
				(width 0.1)
				(type default)
			)
			(layer "F.Fab")
		)
		(fp_line
			(start -0.67945 -0.305054)
			(end -0.12065 -0.305054)
			(stroke
				(width 0.1)
				(type default)
			)
			(layer "F.Fab")
		)
		(pad "1" smd circle
			(at -0.40005 0 180)
			(size 0 0)
			(layers "F.Cu" "F.Mask" "F.Paste")
			(net "RST_USB_CPU0_HUB1_R_N")
		)
		(pad "2" smd circle
			(at 0.40005 0 180)
			(size 0 0)
			(layers "F.Cu" "F.Mask" "F.Paste")
			(net "GND")
		)
	)
	(footprint ""
		(layer "F.Cu")
		(at 41.509696 -344.986864 90)
		(property "Reference" "PR489"
			(at 0 0 90)
			(layer "F.SilkS")
			(hide yes)
			(effects
				(font
					(size 1.27 1.27)
				)
			)
		)
		(property "Value" ""
			(at 0 0 90)
			(layer "F.Fab")
			(effects
				(font
					(size 1.27 1.27)
				)
			)
		)
		(duplicate_pad_numbers_are_jumpers no)
		(fp_line
			(start 0.7874 -0.4064)
			(end 0.7874 0.4064)
			(stroke
				(width 0.1524)
				(type default)
			)
			(layer "F.SilkS")
		)
		(fp_line
			(start -0.7874 -0.4064)
			(end 0.7874 -0.4064)
			(stroke
				(width 0.1524)
				(type default)
			)
			(layer "F.SilkS")
		)
		(fp_line
			(start 0.7874 0.4064)
			(end -0.7874 0.4064)
			(stroke
				(width 0.1524)
				(type default)
			)
			(layer "F.SilkS")
		)
		(fp_line
			(start -0.7874 0.4064)
			(end -0.7874 -0.4064)
			(stroke
				(width 0.1524)
				(type default)
			)
			(layer "F.SilkS")
		)
		(fp_line
			(start -0.12065 -0.305054)
			(end -0.12065 -0.2794)
			(stroke
				(width 0.1)
				(type default)
			)
			(layer "F.Fab")
		)
		(fp_line
			(start -0.67945 -0.305054)
			(end -0.12065 -0.305054)
			(stroke
				(width 0.1)
				(type default)
			)
			(layer "F.Fab")
		)
		(fp_line
			(start 0.67945 -0.3048)
			(end 0.67945 0.3048)
			(stroke
				(width 0.1)
				(type default)
			)
			(layer "F.Fab")
		)
		(fp_line
			(start 0.12065 -0.3048)
			(end 0.67945 -0.3048)
			(stroke
				(width 0.1)
				(type default)
			)
			(layer "F.Fab")
		)
		(fp_line
			(start 0.12065 -0.2794)
			(end 0.12065 -0.3048)
			(stroke
				(width 0.1)
				(type default)
			)
			(layer "F.Fab")
		)
		(fp_line
			(start -0.12065 -0.2794)
			(end 0.12065 -0.2794)
			(stroke
				(width 0.1)
				(type default)
			)
			(layer "F.Fab")
		)
		(fp_line
			(start 0.120396 0.2794)
			(end -0.12065 0.2794)
			(stroke
				(width 0.1)
				(type default)
			)
			(layer "F.Fab")
		)
		(fp_line
			(start -0.12065 0.2794)
			(end -0.12065 0.3048)
			(stroke
				(width 0.1)
				(type default)
			)
			(layer "F.Fab")
		)
		(fp_line
			(start 0.67945 0.3048)
			(end 0.120396 0.3048)
			(stroke
				(width 0.1)
				(type default)
			)
			(layer "F.Fab")
		)
		(fp_line
			(start 0.120396 0.3048)
			(end 0.120396 0.2794)
			(stroke
				(width 0.1)
				(type default)
			)
			(layer "F.Fab")
		)
		(fp_line
			(start -0.12065 0.3048)
			(end -0.67945 0.3048)
			(stroke
				(width 0.1)
				(type default)
			)
			(layer "F.Fab")
		)
		(fp_line
			(start -0.67945 0.3048)
			(end -0.67945 -0.305054)
			(stroke
				(width 0.1)
				(type default)
			)
			(layer "F.Fab")
		)
		(pad "1" smd circle
			(at -0.40005 0 90)
			(size 0 0)
			(layers "F.Cu" "F.Mask" "F.Paste")
			(net "SW_PVDDIO_P1_SW2_RC")
		)
		(pad "2" smd circle
			(at 0.40005 0 90)
			(size 0 0)
			(layers "F.Cu" "F.Mask" "F.Paste")
			(net "GND")
		)
	)
	(footprint ""
		(layer "F.Cu")
		(at 212.993732 -110.630208 180)
		(property "Reference" "R126"
			(at 0 0 180)
			(layer "F.SilkS")
			(hide yes)
			(effects
				(font
					(size 1.27 1.27)
				)
			)
		)
		(property "Value" ""
			(at 0 0 180)
			(layer "F.Fab")
			(effects
				(font
					(size 1.27 1.27)
				)
			)
		)
		(duplicate_pad_numbers_are_jumpers no)
		(fp_line
			(start 0.7874 0.4064)
			(end -0.7874 0.4064)
			(stroke
				(width 0.1524)
				(type default)
			)
			(layer "F.SilkS")
		)
		(fp_line
			(start 0.7874 -0.4064)
			(end 0.7874 0.4064)
			(stroke
				(width 0.1524)
				(type default)
			)
			(layer "F.SilkS")
		)
		(fp_line
			(start -0.7874 0.4064)
			(end -0.7874 -0.4064)
			(stroke
				(width 0.1524)
				(type default)
			)
			(layer "F.SilkS")
		)
		(fp_line
			(start -0.7874 -0.4064)
			(end 0.7874 -0.4064)
			(stroke
				(width 0.1524)
				(type default)
			)
			(layer "F.SilkS")
		)
		(fp_line
			(start 0.67945 0.3048)
			(end 0.120396 0.3048)
			(stroke
				(width 0.1)
				(type default)
			)
			(layer "F.Fab")
		)
		(fp_line
			(start 0.67945 -0.3048)
			(end 0.67945 0.3048)
			(stroke
				(width 0.1)
				(type default)
			)
			(layer "F.Fab")
		)
		(fp_line
			(start 0.12065 -0.2794)
			(end 0.12065 -0.3048)
			(stroke
				(width 0.1)
				(type default)
			)
			(layer "F.Fab")
		)
		(fp_line
			(start 0.12065 -0.3048)
			(end 0.67945 -0.3048)
			(stroke
				(width 0.1)
				(type default)
			)
			(layer "F.Fab")
		)
		(fp_line
			(start 0.120396 0.3048)
			(end 0.120396 0.2794)
			(stroke
				(width 0.1)
				(type default)
			)
			(layer "F.Fab")
		)
		(fp_line
			(start 0.120396 0.2794)
			(end -0.12065 0.2794)
			(stroke
				(width 0.1)
				(type default)
			)
			(layer "F.Fab")
		)
		(fp_line
			(start -0.12065 0.3048)
			(end -0.67945 0.3048)
			(stroke
				(width 0.1)
				(type default)
			)
			(layer "F.Fab")
		)
		(fp_line
			(start -0.12065 0.2794)
			(end -0.12065 0.3048)
			(stroke
				(width 0.1)
				(type default)
			)
			(layer "F.Fab")
		)
		(fp_line
			(start -0.12065 -0.2794)
			(end 0.12065 -0.2794)
			(stroke
				(width 0.1)
				(type default)
			)
			(layer "F.Fab")
		)
		(fp_line
			(start -0.12065 -0.305054)
			(end -0.12065 -0.2794)
			(stroke
				(width 0.1)
				(type default)
			)
			(layer "F.Fab")
		)
		(fp_line
			(start -0.67945 0.3048)
			(end -0.67945 -0.305054)
			(stroke
				(width 0.1)
				(type default)
			)
			(layer "F.Fab")
		)
		(fp_line
			(start -0.67945 -0.305054)
			(end -0.12065 -0.305054)
			(stroke
				(width 0.1)
				(type default)
			)
			(layer "F.Fab")
		)
		(pad "1" smd circle
			(at -0.40005 0 180)
			(size 0 0)
			(layers "F.Cu" "F.Mask" "F.Paste")
			(net "FM_APML_MUX2_OE_N")
		)
		(pad "2" smd circle
			(at 0.40005 0 180)
			(size 0 0)
			(layers "F.Cu" "F.Mask" "F.Paste")
			(net "GND")
		)
	)
	(footprint ""
		(layer "F.Cu")
		(at 44.668694 -16.099536 90)
		(property "Reference" "C699"
			(at 0 0 90)
			(layer "F.SilkS")
			(hide yes)
			(effects
				(font
					(size 1.27 1.27)
				)
			)
		)
		(property "Value" ""
			(at 0 0 90)
			(layer "F.Fab")
			(effects
				(font
					(size 1.27 1.27)
				)
			)
		)
		(duplicate_pad_numbers_are_jumpers no)
		(fp_line
			(start 0.299974 -0.150114)
			(end 0.299974 0.150114)
			(stroke
				(width 0.1)
				(type default)
			)
			(layer "F.Fab")
		)
		(fp_line
			(start -0.299974 -0.150114)
			(end 0.299974 -0.150114)
			(stroke
				(width 0.1)
				(type default)
			)
			(layer "F.Fab")
		)
		(fp_line
			(start 0.299974 0.150114)
			(end -0.299974 0.150114)
			(stroke
				(width 0.1)
				(type default)
			)
			(layer "F.Fab")
		)
		(fp_line
			(start -0.299974 0.150114)
			(end -0.299974 -0.150114)
			(stroke
				(width 0.1)
				(type default)
			)
			(layer "F.Fab")
		)
		(pad "1" smd rect
			(at -0.2667 0 90)
			(size 0.3048 0.381)
			(layers "F.Cu" "F.Mask" "F.Paste")
			(net "P5E_CPU1_G1_TX_C_DP<5>")
		)
		(pad "2" smd rect
			(at 0.2667 0 90)
			(size 0.3048 0.381)
			(layers "F.Cu" "F.Mask" "F.Paste")
			(net "P5E_CPU1_G1_TX_DP<5>")
		)
	)
	(footprint ""
		(layer "F.Cu")
		(at 170.3324 -384.6068 180)
		(property "Reference" "L7"
			(at 0 0 180)
			(layer "F.SilkS")
			(hide yes)
			(effects
				(font
					(size 1.27 1.27)
				)
			)
		)
		(property "Value" ""
			(at 0 0 180)
			(layer "F.Fab")
			(effects
				(font
					(size 1.27 1.27)
				)
			)
		)
		(duplicate_pad_numbers_are_jumpers no)
		(fp_line
			(start 1.63576 0.8128)
			(end -1.63576 0.8128)
			(stroke
				(width 0.1524)
				(type default)
			)
			(layer "F.SilkS")
		)
		(fp_line
			(start 1.63576 -0.8128)
			(end 1.63576 0.8128)
			(stroke
				(width 0.1524)
				(type default)
			)
			(layer "F.SilkS")
		)
		(fp_line
			(start -1.63576 -0.8128)
			(end 1.63576 -0.8128)
			(stroke
				(width 0.1524)
				(type default)
			)
			(layer "F.SilkS")
		)
		(fp_line
			(start -1.63576 -0.8128)
			(end -1.63576 0.8128)
			(stroke
				(width 0.1524)
				(type default)
			)
			(layer "F.SilkS")
		)
		(fp_line
			(start 1.560576 0.7366)
			(end 1.560576 -0.738632)
			(stroke
				(width 0.1)
				(type default)
			)
			(layer "F.Fab")
		)
		(fp_line
			(start 1.560576 -0.738632)
			(end -1.56083 -0.738632)
			(stroke
				(width 0.1)
				(type default)
			)
			(layer "F.Fab")
		)
		(fp_line
			(start 1.524 0.7366)
			(end 1.560576 0.7366)
			(stroke
				(width 0.1)
				(type default)
			)
			(layer "F.Fab")
		)
		(fp_line
			(start -1.524 0.7366)
			(end 1.524 0.7366)
			(stroke
				(width 0.1)
				(type default)
			)
			(layer "F.Fab")
		)
		(fp_line
			(start -1.56083 0.7366)
			(end -1.524 0.7366)
			(stroke
				(width 0.1)
				(type default)
			)
			(layer "F.Fab")
		)
		(fp_line
			(start -1.56083 -0.738632)
			(end -1.56083 0.7366)
			(stroke
				(width 0.1)
				(type default)
			)
			(layer "F.Fab")
		)
		(pad "1" smd rect
			(at -0.94996 0)
			(size 1.1176 1.3716)
			(layers "F.Cu" "F.Mask" "F.Paste")
			(net "P1V8_CPU1_RT_1D")
		)
		(pad "2" smd rect
			(at 0.94996 0)
			(size 1.1176 1.3716)
			(layers "F.Cu" "F.Mask" "F.Paste")
			(net "P1V8_CPU1_RT2_1A")
		)
	)
	(footprint ""
		(layer "F.Cu")
		(at 214.43188 -50.637948 90)
		(property "Reference" "R3754"
			(at 0 0 90)
			(layer "F.SilkS")
			(hide yes)
			(effects
				(font
					(size 1.27 1.27)
				)
			)
		)
		(property "Value" ""
			(at 0 0 90)
			(layer "F.Fab")
			(effects
				(font
					(size 1.27 1.27)
				)
			)
		)
		(duplicate_pad_numbers_are_jumpers no)
		(fp_line
			(start 0.7874 -0.4064)
			(end 0.7874 0.4064)
			(stroke
				(width 0.1524)
				(type default)
			)
			(layer "F.SilkS")
		)
		(fp_line
			(start -0.7874 -0.4064)
			(end 0.7874 -0.4064)
			(stroke
				(width 0.1524)
				(type default)
			)
			(layer "F.SilkS")
		)
		(fp_line
			(start 0.7874 0.4064)
			(end -0.7874 0.4064)
			(stroke
				(width 0.1524)
				(type default)
			)
			(layer "F.SilkS")
		)
		(fp_line
			(start -0.7874 0.4064)
			(end -0.7874 -0.4064)
			(stroke
				(width 0.1524)
				(type default)
			)
			(layer "F.SilkS")
		)
		(fp_line
			(start -0.12065 -0.305054)
			(end -0.12065 -0.2794)
			(stroke
				(width 0.1)
				(type default)
			)
			(layer "F.Fab")
		)
		(fp_line
			(start -0.67945 -0.305054)
			(end -0.12065 -0.305054)
			(stroke
				(width 0.1)
				(type default)
			)
			(layer "F.Fab")
		)
		(fp_line
			(start 0.67945 -0.3048)
			(end 0.67945 0.3048)
			(stroke
				(width 0.1)
				(type default)
			)
			(layer "F.Fab")
		)
		(fp_line
			(start 0.12065 -0.3048)
			(end 0.67945 -0.3048)
			(stroke
				(width 0.1)
				(type default)
			)
			(layer "F.Fab")
		)
		(fp_line
			(start 0.12065 -0.2794)
			(end 0.12065 -0.3048)
			(stroke
				(width 0.1)
				(type default)
			)
			(layer "F.Fab")
		)
		(fp_line
			(start -0.12065 -0.2794)
			(end 0.12065 -0.2794)
			(stroke
				(width 0.1)
				(type default)
			)
			(layer "F.Fab")
		)
		(fp_line
			(start 0.120396 0.2794)
			(end -0.12065 0.2794)
			(stroke
				(width 0.1)
				(type default)
			)
			(layer "F.Fab")
		)
		(fp_line
			(start -0.12065 0.2794)
			(end -0.12065 0.3048)
			(stroke
				(width 0.1)
				(type default)
			)
			(layer "F.Fab")
		)
		(fp_line
			(start 0.67945 0.3048)
			(end 0.120396 0.3048)
			(stroke
				(width 0.1)
				(type default)
			)
			(layer "F.Fab")
		)
		(fp_line
			(start 0.120396 0.3048)
			(end 0.120396 0.2794)
			(stroke
				(width 0.1)
				(type default)
			)
			(layer "F.Fab")
		)
		(fp_line
			(start -0.12065 0.3048)
			(end -0.67945 0.3048)
			(stroke
				(width 0.1)
				(type default)
			)
			(layer "F.Fab")
		)
		(fp_line
			(start -0.67945 0.3048)
			(end -0.67945 -0.305054)
			(stroke
				(width 0.1)
				(type default)
			)
			(layer "F.Fab")
		)
		(pad "1" smd circle
			(at -0.40005 0 90)
			(size 0 0)
			(layers "F.Cu" "F.Mask" "F.Paste")
			(net "SMB_INA230_2_3V3AUX_SCL_R")
		)
		(pad "2" smd circle
			(at 0.40005 0 90)
			(size 0 0)
			(layers "F.Cu" "F.Mask" "F.Paste")
			(net "SMB_INA230_2_3V3AUX_SCL_R1")
		)
	)
	(footprint ""
		(layer "F.Cu")
		(at 135.118094 -151.67356 -90)
		(property "Reference" "PC345_9"
			(at 0 0 270)
			(layer "F.SilkS")
			(hide yes)
			(effects
				(font
					(size 1.27 1.27)
				)
			)
		)
		(property "Value" ""
			(at 0 0 270)
			(layer "F.Fab")
			(effects
				(font
					(size 1.27 1.27)
				)
			)
		)
		(duplicate_pad_numbers_are_jumpers no)
		(fp_line
			(start -0.7874 0.4064)
			(end -0.7874 -0.4064)
			(stroke
				(width 0.1524)
				(type default)
			)
			(layer "F.SilkS")
		)
		(fp_line
			(start 0.7874 0.4064)
			(end -0.7874 0.4064)
			(stroke
				(width 0.1524)
				(type default)
			)
			(layer "F.SilkS")
		)
		(fp_line
			(start -0.7874 -0.4064)
			(end 0.7874 -0.4064)
			(stroke
				(width 0.1524)
				(type default)
			)
			(layer "F.SilkS")
		)
		(fp_line
			(start 0.7874 -0.4064)
			(end 0.7874 0.4064)
			(stroke
				(width 0.1524)
				(type default)
			)
			(layer "F.SilkS")
		)
		(fp_line
			(start -0.67945 0.3048)
			(end -0.67945 -0.305054)
			(stroke
				(width 0.1)
				(type default)
			)
			(layer "F.Fab")
		)
		(fp_line
			(start -0.12065 0.3048)
			(end -0.67945 0.3048)
			(stroke
				(width 0.1)
				(type default)
			)
			(layer "F.Fab")
		)
		(fp_line
			(start 0.120396 0.3048)
			(end 0.120396 0.2794)
			(stroke
				(width 0.1)
				(type default)
			)
			(layer "F.Fab")
		)
		(fp_line
			(start 0.67945 0.3048)
			(end 0.120396 0.3048)
			(stroke
				(width 0.1)
				(type default)
			)
			(layer "F.Fab")
		)
		(fp_line
			(start -0.12065 0.2794)
			(end -0.12065 0.3048)
			(stroke
				(width 0.1)
				(type default)
			)
			(layer "F.Fab")
		)
		(fp_line
			(start 0.120396 0.2794)
			(end -0.12065 0.2794)
			(stroke
				(width 0.1)
				(type default)
			)
			(layer "F.Fab")
		)
		(fp_line
			(start -0.12065 -0.2794)
			(end 0.12065 -0.2794)
			(stroke
				(width 0.1)
				(type default)
			)
			(layer "F.Fab")
		)
		(fp_line
			(start 0.12065 -0.2794)
			(end 0.12065 -0.3048)
			(stroke
				(width 0.1)
				(type default)
			)
			(layer "F.Fab")
		)
		(fp_line
			(start 0.12065 -0.3048)
			(end 0.67945 -0.3048)
			(stroke
				(width 0.1)
				(type default)
			)
			(layer "F.Fab")
		)
		(fp_line
			(start 0.67945 -0.3048)
			(end 0.67945 0.3048)
			(stroke
				(width 0.1)
				(type default)
			)
			(layer "F.Fab")
		)
		(fp_line
			(start -0.67945 -0.305054)
			(end -0.12065 -0.305054)
			(stroke
				(width 0.1)
				(type default)
			)
			(layer "F.Fab")
		)
		(fp_line
			(start -0.12065 -0.305054)
			(end -0.12065 -0.2794)
			(stroke
				(width 0.1)
				(type default)
			)
			(layer "F.Fab")
		)
		(pad "1" smd circle
			(at -0.40005 0 270)
			(size 0 0)
			(layers "F.Cu" "F.Mask" "F.Paste")
			(net "PVDDCR_CPU0_P1_VCCS")
		)
		(pad "2" smd circle
			(at 0.40005 0 270)
			(size 0 0)
			(layers "F.Cu" "F.Mask" "F.Paste")
			(net "GND")
		)
	)
	(footprint ""
		(layer "F.Cu")
		(at 38.180772 -58.155332 90)
		(property "Reference" "D8001"
			(at -1.781556 1.402334 90)
			(unlocked yes)
			(layer "F.SilkS")
			(effects
				(font
					(size 0.7874 0.5842)
					(thickness 0.1524)
				)
				(justify left)
			)
		)
		(property "Value" ""
			(at 0 0 90)
			(layer "F.Fab")
			(effects
				(font
					(size 1.27 1.27)
				)
			)
		)
		(duplicate_pad_numbers_are_jumpers no)
		(fp_line
			(start 1.16078 -0.4826)
			(end 1.16078 0.4826)
			(stroke
				(width 0.1524)
				(type default)
			)
			(layer "F.SilkS")
		)
		(fp_line
			(start 1.03378 -0.4826)
			(end 1.03378 0.4826)
			(stroke
				(width 0.1524)
				(type default)
			)
			(layer "F.SilkS")
		)
		(fp_line
			(start 0.90678 -0.4826)
			(end 0.90678 0.4826)
			(stroke
				(width 0.1524)
				(type default)
			)
			(layer "F.SilkS")
		)
		(fp_line
			(start -0.64008 -0.4826)
			(end 1.16078 -0.4826)
			(stroke
				(width 0.1524)
				(type default)
			)
			(layer "F.SilkS")
		)
		(fp_line
			(start -0.79248 -0.4826)
			(end 1.03378 -0.4826)
			(stroke
				(width 0.1524)
				(type default)
			)
			(layer "F.SilkS")
		)
		(fp_line
			(start -0.89408 -0.4826)
			(end 0.90678 -0.4826)
			(stroke
				(width 0.1524)
				(type default)
			)
			(layer "F.SilkS")
		)
		(fp_line
			(start 1.16078 0.4826)
			(end -0.64008 0.4826)
			(stroke
				(width 0.1524)
				(type default)
			)
			(layer "F.SilkS")
		)
		(fp_line
			(start 1.03378 0.4826)
			(end -0.79248 0.4826)
			(stroke
				(width 0.1524)
				(type default)
			)
			(layer "F.SilkS")
		)
		(fp_line
			(start 0.90678 0.4826)
			(end -0.90678 0.4826)
			(stroke
				(width 0.1524)
				(type default)
			)
			(layer "F.SilkS")
		)
		(fp_line
			(start -0.90678 0.4826)
			(end -0.90678 -0.4699)
			(stroke
				(width 0.1524)
				(type default)
			)
			(layer "F.SilkS")
		)
		(fp_line
			(start 0.499872 -0.249936)
			(end 0.499872 0.249936)
			(stroke
				(width 0.1)
				(type default)
			)
			(layer "F.Fab")
		)
		(fp_line
			(start -0.499872 -0.249936)
			(end 0.499872 -0.249936)
			(stroke
				(width 0.1)
				(type default)
			)
			(layer "F.Fab")
		)
		(fp_line
			(start 0.499872 0.249936)
			(end -0.499872 0.249936)
			(stroke
				(width 0.1)
				(type default)
			)
			(layer "F.Fab")
		)
		(fp_line
			(start -0.499872 0.249936)
			(end -0.499872 -0.249936)
			(stroke
				(width 0.1)
				(type default)
			)
			(layer "F.Fab")
		)
		(pad "A" smd rect
			(at -0.47498 0 90)
			(size 0.6096 0.7112)
			(layers "F.Cu" "F.Mask" "F.Paste")
			(net "LED_P12V_PSU_R1")
		)
		(pad "C" smd rect
			(at 0.47498 0 90)
			(size 0.6096 0.7112)
			(layers "F.Cu" "F.Mask" "F.Paste")
			(net "GND")
		)
	)
	(footprint ""
		(layer "F.Cu")
		(at 34.103818 -436.433214 180)
		(property "Reference" "R2992"
			(at 0 0 180)
			(layer "F.SilkS")
			(hide yes)
			(effects
				(font
					(size 1.27 1.27)
				)
			)
		)
		(property "Value" ""
			(at 0 0 180)
			(layer "F.Fab")
			(effects
				(font
					(size 1.27 1.27)
				)
			)
		)
		(duplicate_pad_numbers_are_jumpers no)
		(fp_line
			(start 0.7874 0.4064)
			(end -0.7874 0.4064)
			(stroke
				(width 0.1524)
				(type default)
			)
			(layer "F.SilkS")
		)
		(fp_line
			(start 0.7874 -0.4064)
			(end 0.7874 0.4064)
			(stroke
				(width 0.1524)
				(type default)
			)
			(layer "F.SilkS")
		)
		(fp_line
			(start -0.7874 0.4064)
			(end -0.7874 -0.4064)
			(stroke
				(width 0.1524)
				(type default)
			)
			(layer "F.SilkS")
		)
		(fp_line
			(start -0.7874 -0.4064)
			(end 0.7874 -0.4064)
			(stroke
				(width 0.1524)
				(type default)
			)
			(layer "F.SilkS")
		)
		(fp_line
			(start 0.67945 0.3048)
			(end 0.120396 0.3048)
			(stroke
				(width 0.1)
				(type default)
			)
			(layer "F.Fab")
		)
		(fp_line
			(start 0.67945 -0.3048)
			(end 0.67945 0.3048)
			(stroke
				(width 0.1)
				(type default)
			)
			(layer "F.Fab")
		)
		(fp_line
			(start 0.12065 -0.2794)
			(end 0.12065 -0.3048)
			(stroke
				(width 0.1)
				(type default)
			)
			(layer "F.Fab")
		)
		(fp_line
			(start 0.12065 -0.3048)
			(end 0.67945 -0.3048)
			(stroke
				(width 0.1)
				(type default)
			)
			(layer "F.Fab")
		)
		(fp_line
			(start 0.120396 0.3048)
			(end 0.120396 0.2794)
			(stroke
				(width 0.1)
				(type default)
			)
			(layer "F.Fab")
		)
		(fp_line
			(start 0.120396 0.2794)
			(end -0.12065 0.2794)
			(stroke
				(width 0.1)
				(type default)
			)
			(layer "F.Fab")
		)
		(fp_line
			(start -0.12065 0.3048)
			(end -0.67945 0.3048)
			(stroke
				(width 0.1)
				(type default)
			)
			(layer "F.Fab")
		)
		(fp_line
			(start -0.12065 0.2794)
			(end -0.12065 0.3048)
			(stroke
				(width 0.1)
				(type default)
			)
			(layer "F.Fab")
		)
		(fp_line
			(start -0.12065 -0.2794)
			(end 0.12065 -0.2794)
			(stroke
				(width 0.1)
				(type default)
			)
			(layer "F.Fab")
		)
		(fp_line
			(start -0.12065 -0.305054)
			(end -0.12065 -0.2794)
			(stroke
				(width 0.1)
				(type default)
			)
			(layer "F.Fab")
		)
		(fp_line
			(start -0.67945 0.3048)
			(end -0.67945 -0.305054)
			(stroke
				(width 0.1)
				(type default)
			)
			(layer "F.Fab")
		)
		(fp_line
			(start -0.67945 -0.305054)
			(end -0.12065 -0.305054)
			(stroke
				(width 0.1)
				(type default)
			)
			(layer "F.Fab")
		)
		(pad "1" smd circle
			(at -0.40005 0 180)
			(size 0 0)
			(layers "F.Cu" "F.Mask" "F.Paste")
			(net "SMB_BMC_GPU_EN")
		)
		(pad "2" smd circle
			(at 0.40005 0 180)
			(size 0 0)
			(layers "F.Cu" "F.Mask" "F.Paste")
			(net "SMB_BMC_GPU_EN_R3")
		)
	)
	(footprint ""
		(layer "F.Cu")
		(at 176.391062 -32.935672 90)
		(property "Reference" "PC2232"
			(at 0 0 90)
			(layer "F.SilkS")
			(hide yes)
			(effects
				(font
					(size 1.27 1.27)
				)
			)
		)
		(property "Value" ""
			(at 0 0 90)
			(layer "F.Fab")
			(effects
				(font
					(size 1.27 1.27)
				)
			)
		)
		(duplicate_pad_numbers_are_jumpers no)
		(fp_line
			(start 0.7874 -0.4064)
			(end 0.7874 0.4064)
			(stroke
				(width 0.1524)
				(type default)
			)
			(layer "F.SilkS")
		)
		(fp_line
			(start -0.7874 -0.4064)
			(end 0.7874 -0.4064)
			(stroke
				(width 0.1524)
				(type default)
			)
			(layer "F.SilkS")
		)
		(fp_line
			(start 0.7874 0.4064)
			(end -0.7874 0.4064)
			(stroke
				(width 0.1524)
				(type default)
			)
			(layer "F.SilkS")
		)
		(fp_line
			(start -0.7874 0.4064)
			(end -0.7874 -0.4064)
			(stroke
				(width 0.1524)
				(type default)
			)
			(layer "F.SilkS")
		)
		(fp_line
			(start -0.12065 -0.305054)
			(end -0.12065 -0.2794)
			(stroke
				(width 0.1)
				(type default)
			)
			(layer "F.Fab")
		)
		(fp_line
			(start -0.67945 -0.305054)
			(end -0.12065 -0.305054)
			(stroke
				(width 0.1)
				(type default)
			)
			(layer "F.Fab")
		)
		(fp_line
			(start 0.67945 -0.3048)
			(end 0.67945 0.3048)
			(stroke
				(width 0.1)
				(type default)
			)
			(layer "F.Fab")
		)
		(fp_line
			(start 0.12065 -0.3048)
			(end 0.67945 -0.3048)
			(stroke
				(width 0.1)
				(type default)
			)
			(layer "F.Fab")
		)
		(fp_line
			(start 0.12065 -0.2794)
			(end 0.12065 -0.3048)
			(stroke
				(width 0.1)
				(type default)
			)
			(layer "F.Fab")
		)
		(fp_line
			(start -0.12065 -0.2794)
			(end 0.12065 -0.2794)
			(stroke
				(width 0.1)
				(type default)
			)
			(layer "F.Fab")
		)
		(fp_line
			(start 0.120396 0.2794)
			(end -0.12065 0.2794)
			(stroke
				(width 0.1)
				(type default)
			)
			(layer "F.Fab")
		)
		(fp_line
			(start -0.12065 0.2794)
			(end -0.12065 0.3048)
			(stroke
				(width 0.1)
				(type default)
			)
			(layer "F.Fab")
		)
		(fp_line
			(start 0.67945 0.3048)
			(end 0.120396 0.3048)
			(stroke
				(width 0.1)
				(type default)
			)
			(layer "F.Fab")
		)
		(fp_line
			(start 0.120396 0.3048)
			(end 0.120396 0.2794)
			(stroke
				(width 0.1)
				(type default)
			)
			(layer "F.Fab")
		)
		(fp_line
			(start -0.12065 0.3048)
			(end -0.67945 0.3048)
			(stroke
				(width 0.1)
				(type default)
			)
			(layer "F.Fab")
		)
		(fp_line
			(start -0.67945 0.3048)
			(end -0.67945 -0.305054)
			(stroke
				(width 0.1)
				(type default)
			)
			(layer "F.Fab")
		)
		(pad "1" smd circle
			(at -0.40005 0 90)
			(size 0 0)
			(layers "F.Cu" "F.Mask" "F.Paste")
			(net "P12V_SCM_SS")
		)
		(pad "2" smd circle
			(at 0.40005 0 90)
			(size 0 0)
			(layers "F.Cu" "F.Mask" "F.Paste")
			(net "GND")
		)
	)
	(footprint ""
		(layer "F.Cu")
		(at 124.090176 -74.555096 90)
		(property "Reference" "PR8004"
			(at 0 0 90)
			(layer "F.SilkS")
			(hide yes)
			(effects
				(font
					(size 1.27 1.27)
				)
			)
		)
		(property "Value" ""
			(at 0 0 90)
			(layer "F.Fab")
			(effects
				(font
					(size 1.27 1.27)
				)
			)
		)
		(duplicate_pad_numbers_are_jumpers no)
		(fp_line
			(start 0.7874 -0.4064)
			(end 0.7874 0.4064)
			(stroke
				(width 0.1524)
				(type default)
			)
			(layer "F.SilkS")
		)
		(fp_line
			(start -0.7874 -0.4064)
			(end 0.7874 -0.4064)
			(stroke
				(width 0.1524)
				(type default)
			)
			(layer "F.SilkS")
		)
		(fp_line
			(start 0.7874 0.4064)
			(end -0.7874 0.4064)
			(stroke
				(width 0.1524)
				(type default)
			)
			(layer "F.SilkS")
		)
		(fp_line
			(start -0.7874 0.4064)
			(end -0.7874 -0.4064)
			(stroke
				(width 0.1524)
				(type default)
			)
			(layer "F.SilkS")
		)
		(fp_line
			(start -0.12065 -0.305054)
			(end -0.12065 -0.2794)
			(stroke
				(width 0.1)
				(type default)
			)
			(layer "F.Fab")
		)
		(fp_line
			(start -0.67945 -0.305054)
			(end -0.12065 -0.305054)
			(stroke
				(width 0.1)
				(type default)
			)
			(layer "F.Fab")
		)
		(fp_line
			(start 0.67945 -0.3048)
			(end 0.67945 0.3048)
			(stroke
				(width 0.1)
				(type default)
			)
			(layer "F.Fab")
		)
		(fp_line
			(start 0.12065 -0.3048)
			(end 0.67945 -0.3048)
			(stroke
				(width 0.1)
				(type default)
			)
			(layer "F.Fab")
		)
		(fp_line
			(start 0.12065 -0.2794)
			(end 0.12065 -0.3048)
			(stroke
				(width 0.1)
				(type default)
			)
			(layer "F.Fab")
		)
		(fp_line
			(start -0.12065 -0.2794)
			(end 0.12065 -0.2794)
			(stroke
				(width 0.1)
				(type default)
			)
			(layer "F.Fab")
		)
		(fp_line
			(start 0.120396 0.2794)
			(end -0.12065 0.2794)
			(stroke
				(width 0.1)
				(type default)
			)
			(layer "F.Fab")
		)
		(fp_line
			(start -0.12065 0.2794)
			(end -0.12065 0.3048)
			(stroke
				(width 0.1)
				(type default)
			)
			(layer "F.Fab")
		)
		(fp_line
			(start 0.67945 0.3048)
			(end 0.120396 0.3048)
			(stroke
				(width 0.1)
				(type default)
			)
			(layer "F.Fab")
		)
		(fp_line
			(start 0.120396 0.3048)
			(end 0.120396 0.2794)
			(stroke
				(width 0.1)
				(type default)
			)
			(layer "F.Fab")
		)
		(fp_line
			(start -0.12065 0.3048)
			(end -0.67945 0.3048)
			(stroke
				(width 0.1)
				(type default)
			)
			(layer "F.Fab")
		)
		(fp_line
			(start -0.67945 0.3048)
			(end -0.67945 -0.305054)
			(stroke
				(width 0.1)
				(type default)
			)
			(layer "F.Fab")
		)
		(pad "1" smd circle
			(at -0.40005 0 90)
			(size 0 0)
			(layers "F.Cu" "F.Mask" "F.Paste")
			(net "SW_P1V2_AUX_BT")
		)
		(pad "2" smd circle
			(at 0.40005 0 90)
			(size 0 0)
			(layers "F.Cu" "F.Mask" "F.Paste")
			(net "SW_P1V2_AUX_BT_R")
		)
	)
	(footprint ""
		(layer "F.Cu")
		(at 257.85953 -57.511442)
		(property "Reference" "R3955"
			(at 0 0 0)
			(layer "F.SilkS")
			(hide yes)
			(effects
				(font
					(size 1.27 1.27)
				)
			)
		)
		(property "Value" ""
			(at 0 0 0)
			(layer "F.Fab")
			(effects
				(font
					(size 1.27 1.27)
				)
			)
		)
		(duplicate_pad_numbers_are_jumpers no)
		(fp_line
			(start -0.7874 -0.4064)
			(end 0.7874 -0.4064)
			(stroke
				(width 0.1524)
				(type default)
			)
			(layer "F.SilkS")
		)
		(fp_line
			(start -0.7874 0.4064)
			(end -0.7874 -0.4064)
			(stroke
				(width 0.1524)
				(type default)
			)
			(layer "F.SilkS")
		)
		(fp_line
			(start 0.7874 -0.4064)
			(end 0.7874 0.4064)
			(stroke
				(width 0.1524)
				(type default)
			)
			(layer "F.SilkS")
		)
		(fp_line
			(start 0.7874 0.4064)
			(end -0.7874 0.4064)
			(stroke
				(width 0.1524)
				(type default)
			)
			(layer "F.SilkS")
		)
		(fp_line
			(start -0.67945 -0.305054)
			(end -0.12065 -0.305054)
			(stroke
				(width 0.1)
				(type default)
			)
			(layer "F.Fab")
		)
		(fp_line
			(start -0.67945 0.3048)
			(end -0.67945 -0.305054)
			(stroke
				(width 0.1)
				(type default)
			)
			(layer "F.Fab")
		)
		(fp_line
			(start -0.12065 -0.305054)
			(end -0.12065 -0.2794)
			(stroke
				(width 0.1)
				(type default)
			)
			(layer "F.Fab")
		)
		(fp_line
			(start -0.12065 -0.2794)
			(end 0.12065 -0.2794)
			(stroke
				(width 0.1)
				(type default)
			)
			(layer "F.Fab")
		)
		(fp_line
			(start -0.12065 0.2794)
			(end -0.12065 0.3048)
			(stroke
				(width 0.1)
				(type default)
			)
			(layer "F.Fab")
		)
		(fp_line
			(start -0.12065 0.3048)
			(end -0.67945 0.3048)
			(stroke
				(width 0.1)
				(type default)
			)
			(layer "F.Fab")
		)
		(fp_line
			(start 0.120396 0.2794)
			(end -0.12065 0.2794)
			(stroke
				(width 0.1)
				(type default)
			)
			(layer "F.Fab")
		)
		(fp_line
			(start 0.120396 0.3048)
			(end 0.120396 0.2794)
			(stroke
				(width 0.1)
				(type default)
			)
			(layer "F.Fab")
		)
		(fp_line
			(start 0.12065 -0.3048)
			(end 0.67945 -0.3048)
			(stroke
				(width 0.1)
				(type default)
			)
			(layer "F.Fab")
		)
		(fp_line
			(start 0.12065 -0.2794)
			(end 0.12065 -0.3048)
			(stroke
				(width 0.1)
				(type default)
			)
			(layer "F.Fab")
		)
		(fp_line
			(start 0.67945 -0.3048)
			(end 0.67945 0.3048)
			(stroke
				(width 0.1)
				(type default)
			)
			(layer "F.Fab")
		)
		(fp_line
			(start 0.67945 0.3048)
			(end 0.120396 0.3048)
			(stroke
				(width 0.1)
				(type default)
			)
			(layer "F.Fab")
		)
		(pad "1" smd circle
			(at -0.40005 0)
			(size 0 0)
			(layers "F.Cu" "F.Mask" "F.Paste")
			(net "P12V_E1S_IMON_0")
		)
		(pad "2" smd circle
			(at 0.40005 0)
			(size 0 0)
			(layers "F.Cu" "F.Mask" "F.Paste")
			(net "P12V_E1S_0_ISENSE_MPS_MAM")
		)
	)
	(footprint ""
		(layer "F.Cu")
		(at 123.443238 -41.17975 90)
		(property "Reference" "R6276"
			(at 0 0 90)
			(layer "F.SilkS")
			(hide yes)
			(effects
				(font
					(size 1.27 1.27)
				)
			)
		)
		(property "Value" ""
			(at 0 0 90)
			(layer "F.Fab")
			(effects
				(font
					(size 1.27 1.27)
				)
			)
		)
		(duplicate_pad_numbers_are_jumpers no)
		(fp_line
			(start 0.7874 -0.4064)
			(end 0.7874 0.4064)
			(stroke
				(width 0.1524)
				(type default)
			)
			(layer "F.SilkS")
		)
		(fp_line
			(start -0.7874 -0.4064)
			(end 0.7874 -0.4064)
			(stroke
				(width 0.1524)
				(type default)
			)
			(layer "F.SilkS")
		)
		(fp_line
			(start 0.7874 0.4064)
			(end -0.7874 0.4064)
			(stroke
				(width 0.1524)
				(type default)
			)
			(layer "F.SilkS")
		)
		(fp_line
			(start -0.7874 0.4064)
			(end -0.7874 -0.4064)
			(stroke
				(width 0.1524)
				(type default)
			)
			(layer "F.SilkS")
		)
		(fp_line
			(start -0.12065 -0.305054)
			(end -0.12065 -0.2794)
			(stroke
				(width 0.1)
				(type default)
			)
			(layer "F.Fab")
		)
		(fp_line
			(start -0.67945 -0.305054)
			(end -0.12065 -0.305054)
			(stroke
				(width 0.1)
				(type default)
			)
			(layer "F.Fab")
		)
		(fp_line
			(start 0.67945 -0.3048)
			(end 0.67945 0.3048)
			(stroke
				(width 0.1)
				(type default)
			)
			(layer "F.Fab")
		)
		(fp_line
			(start 0.12065 -0.3048)
			(end 0.67945 -0.3048)
			(stroke
				(width 0.1)
				(type default)
			)
			(layer "F.Fab")
		)
		(fp_line
			(start 0.12065 -0.2794)
			(end 0.12065 -0.3048)
			(stroke
				(width 0.1)
				(type default)
			)
			(layer "F.Fab")
		)
		(fp_line
			(start -0.12065 -0.2794)
			(end 0.12065 -0.2794)
			(stroke
				(width 0.1)
				(type default)
			)
			(layer "F.Fab")
		)
		(fp_line
			(start 0.120396 0.2794)
			(end -0.12065 0.2794)
			(stroke
				(width 0.1)
				(type default)
			)
			(layer "F.Fab")
		)
		(fp_line
			(start -0.12065 0.2794)
			(end -0.12065 0.3048)
			(stroke
				(width 0.1)
				(type default)
			)
			(layer "F.Fab")
		)
		(fp_line
			(start 0.67945 0.3048)
			(end 0.120396 0.3048)
			(stroke
				(width 0.1)
				(type default)
			)
			(layer "F.Fab")
		)
		(fp_line
			(start 0.120396 0.3048)
			(end 0.120396 0.2794)
			(stroke
				(width 0.1)
				(type default)
			)
			(layer "F.Fab")
		)
		(fp_line
			(start -0.12065 0.3048)
			(end -0.67945 0.3048)
			(stroke
				(width 0.1)
				(type default)
			)
			(layer "F.Fab")
		)
		(fp_line
			(start -0.67945 0.3048)
			(end -0.67945 -0.305054)
			(stroke
				(width 0.1)
				(type default)
			)
			(layer "F.Fab")
		)
		(pad "1" smd circle
			(at -0.40005 0 90)
			(size 0 0)
			(layers "F.Cu" "F.Mask" "F.Paste")
			(net "USB_HUB2_TI_VDD33_MRP_PRT_CTL4_GANGPWR")
		)
		(pad "2" smd circle
			(at 0.40005 0 90)
			(size 0 0)
			(layers "F.Cu" "F.Mask" "F.Paste")
			(net "USB_HUB2_MRP_PRT_CTL4_GANGPWR")
		)
	)
	(footprint ""
		(layer "F.Cu")
		(at 133.248146 -408.517344 -90)
		(property "Reference" "C6706"
			(at 0 0 270)
			(layer "F.SilkS")
			(hide yes)
			(effects
				(font
					(size 1.27 1.27)
				)
			)
		)
		(property "Value" ""
			(at 0 0 270)
			(layer "F.Fab")
			(effects
				(font
					(size 1.27 1.27)
				)
			)
		)
		(duplicate_pad_numbers_are_jumpers no)
		(fp_line
			(start -0.299974 0.150114)
			(end -0.299974 -0.150114)
			(stroke
				(width 0.1)
				(type default)
			)
			(layer "F.Fab")
		)
		(fp_line
			(start 0.299974 0.150114)
			(end -0.299974 0.150114)
			(stroke
				(width 0.1)
				(type default)
			)
			(layer "F.Fab")
		)
		(fp_line
			(start -0.299974 -0.150114)
			(end 0.299974 -0.150114)
			(stroke
				(width 0.1)
				(type default)
			)
			(layer "F.Fab")
		)
		(fp_line
			(start 0.299974 -0.150114)
			(end 0.299974 0.150114)
			(stroke
				(width 0.1)
				(type default)
			)
			(layer "F.Fab")
		)
		(pad "1" smd rect
			(at -0.2667 0 270)
			(size 0.3048 0.381)
			(layers "F.Cu" "F.Mask" "F.Paste")
			(net "P5E_CPU1_P2_TX_BUF_C_DN<6>")
		)
		(pad "2" smd rect
			(at 0.2667 0 270)
			(size 0.3048 0.381)
			(layers "F.Cu" "F.Mask" "F.Paste")
			(net "P5E_CPU1_P2_TX_BUF_DN<6>")
		)
	)
	(footprint ""
		(layer "F.Cu")
		(at 364.366302 -28.2956 -90)
		(property "Reference" "C364"
			(at 0 0 270)
			(layer "F.SilkS")
			(hide yes)
			(effects
				(font
					(size 1.27 1.27)
				)
			)
		)
		(property "Value" ""
			(at 0 0 270)
			(layer "F.Fab")
			(effects
				(font
					(size 1.27 1.27)
				)
			)
		)
		(duplicate_pad_numbers_are_jumpers no)
		(fp_line
			(start -0.7874 0.4064)
			(end -0.7874 -0.4064)
			(stroke
				(width 0.1524)
				(type default)
			)
			(layer "F.SilkS")
		)
		(fp_line
			(start 0.7874 0.4064)
			(end -0.7874 0.4064)
			(stroke
				(width 0.1524)
				(type default)
			)
			(layer "F.SilkS")
		)
		(fp_line
			(start -0.7874 -0.4064)
			(end 0.7874 -0.4064)
			(stroke
				(width 0.1524)
				(type default)
			)
			(layer "F.SilkS")
		)
		(fp_line
			(start 0.7874 -0.4064)
			(end 0.7874 0.4064)
			(stroke
				(width 0.1524)
				(type default)
			)
			(layer "F.SilkS")
		)
		(fp_line
			(start -0.67945 0.3048)
			(end -0.67945 -0.305054)
			(stroke
				(width 0.1)
				(type default)
			)
			(layer "F.Fab")
		)
		(fp_line
			(start -0.12065 0.3048)
			(end -0.67945 0.3048)
			(stroke
				(width 0.1)
				(type default)
			)
			(layer "F.Fab")
		)
		(fp_line
			(start 0.120396 0.3048)
			(end 0.120396 0.2794)
			(stroke
				(width 0.1)
				(type default)
			)
			(layer "F.Fab")
		)
		(fp_line
			(start 0.67945 0.3048)
			(end 0.120396 0.3048)
			(stroke
				(width 0.1)
				(type default)
			)
			(layer "F.Fab")
		)
		(fp_line
			(start -0.12065 0.2794)
			(end -0.12065 0.3048)
			(stroke
				(width 0.1)
				(type default)
			)
			(layer "F.Fab")
		)
		(fp_line
			(start 0.120396 0.2794)
			(end -0.12065 0.2794)
			(stroke
				(width 0.1)
				(type default)
			)
			(layer "F.Fab")
		)
		(fp_line
			(start -0.12065 -0.2794)
			(end 0.12065 -0.2794)
			(stroke
				(width 0.1)
				(type default)
			)
			(layer "F.Fab")
		)
		(fp_line
			(start 0.12065 -0.2794)
			(end 0.12065 -0.3048)
			(stroke
				(width 0.1)
				(type default)
			)
			(layer "F.Fab")
		)
		(fp_line
			(start 0.12065 -0.3048)
			(end 0.67945 -0.3048)
			(stroke
				(width 0.1)
				(type default)
			)
			(layer "F.Fab")
		)
		(fp_line
			(start 0.67945 -0.3048)
			(end 0.67945 0.3048)
			(stroke
				(width 0.1)
				(type default)
			)
			(layer "F.Fab")
		)
		(fp_line
			(start -0.67945 -0.305054)
			(end -0.12065 -0.305054)
			(stroke
				(width 0.1)
				(type default)
			)
			(layer "F.Fab")
		)
		(fp_line
			(start -0.12065 -0.305054)
			(end -0.12065 -0.2794)
			(stroke
				(width 0.1)
				(type default)
			)
			(layer "F.Fab")
		)
		(pad "1" smd circle
			(at -0.40005 0 270)
			(size 0 0)
			(layers "F.Cu" "F.Mask" "F.Paste")
			(net "UART_CPU0_LVC3_UART0_RX")
		)
		(pad "2" smd circle
			(at 0.40005 0 270)
			(size 0 0)
			(layers "F.Cu" "F.Mask" "F.Paste")
			(net "GND")
		)
	)
	(footprint ""
		(layer "F.Cu")
		(at 161.571686 -57.65165 180)
		(property "Reference" "R3575"
			(at 0 0 180)
			(layer "F.SilkS")
			(hide yes)
			(effects
				(font
					(size 1.27 1.27)
				)
			)
		)
		(property "Value" ""
			(at 0 0 180)
			(layer "F.Fab")
			(effects
				(font
					(size 1.27 1.27)
				)
			)
		)
		(duplicate_pad_numbers_are_jumpers no)
		(fp_line
			(start 0.7874 0.4064)
			(end -0.7874 0.4064)
			(stroke
				(width 0.1524)
				(type default)
			)
			(layer "F.SilkS")
		)
		(fp_line
			(start 0.7874 -0.4064)
			(end 0.7874 0.4064)
			(stroke
				(width 0.1524)
				(type default)
			)
			(layer "F.SilkS")
		)
		(fp_line
			(start -0.7874 0.4064)
			(end -0.7874 -0.4064)
			(stroke
				(width 0.1524)
				(type default)
			)
			(layer "F.SilkS")
		)
		(fp_line
			(start -0.7874 -0.4064)
			(end 0.7874 -0.4064)
			(stroke
				(width 0.1524)
				(type default)
			)
			(layer "F.SilkS")
		)
		(fp_line
			(start 0.67945 0.3048)
			(end 0.120396 0.3048)
			(stroke
				(width 0.1)
				(type default)
			)
			(layer "F.Fab")
		)
		(fp_line
			(start 0.67945 -0.3048)
			(end 0.67945 0.3048)
			(stroke
				(width 0.1)
				(type default)
			)
			(layer "F.Fab")
		)
		(fp_line
			(start 0.12065 -0.2794)
			(end 0.12065 -0.3048)
			(stroke
				(width 0.1)
				(type default)
			)
			(layer "F.Fab")
		)
		(fp_line
			(start 0.12065 -0.3048)
			(end 0.67945 -0.3048)
			(stroke
				(width 0.1)
				(type default)
			)
			(layer "F.Fab")
		)
		(fp_line
			(start 0.120396 0.3048)
			(end 0.120396 0.2794)
			(stroke
				(width 0.1)
				(type default)
			)
			(layer "F.Fab")
		)
		(fp_line
			(start 0.120396 0.2794)
			(end -0.12065 0.2794)
			(stroke
				(width 0.1)
				(type default)
			)
			(layer "F.Fab")
		)
		(fp_line
			(start -0.12065 0.3048)
			(end -0.67945 0.3048)
			(stroke
				(width 0.1)
				(type default)
			)
			(layer "F.Fab")
		)
		(fp_line
			(start -0.12065 0.2794)
			(end -0.12065 0.3048)
			(stroke
				(width 0.1)
				(type default)
			)
			(layer "F.Fab")
		)
		(fp_line
			(start -0.12065 -0.2794)
			(end 0.12065 -0.2794)
			(stroke
				(width 0.1)
				(type default)
			)
			(layer "F.Fab")
		)
		(fp_line
			(start -0.12065 -0.305054)
			(end -0.12065 -0.2794)
			(stroke
				(width 0.1)
				(type default)
			)
			(layer "F.Fab")
		)
		(fp_line
			(start -0.67945 0.3048)
			(end -0.67945 -0.305054)
			(stroke
				(width 0.1)
				(type default)
			)
			(layer "F.Fab")
		)
		(fp_line
			(start -0.67945 -0.305054)
			(end -0.12065 -0.305054)
			(stroke
				(width 0.1)
				(type default)
			)
			(layer "F.Fab")
		)
		(pad "1" smd circle
			(at -0.40005 0 180)
			(size 0 0)
			(layers "F.Cu" "F.Mask" "F.Paste")
			(net "P3V3_M2_0")
		)
		(pad "2" smd circle
			(at 0.40005 0 180)
			(size 0 0)
			(layers "F.Cu" "F.Mask" "F.Paste")
			(net "VSENSE_P12V_INA230_4_INN")
		)
	)
	(footprint ""
		(layer "F.Cu")
		(at 331.37602 -334.971898 -90)
		(property "Reference" "PC81_C1P0_1"
			(at 0 0 270)
			(layer "F.SilkS")
			(hide yes)
			(effects
				(font
					(size 1.27 1.27)
				)
			)
		)
		(property "Value" ""
			(at 0 0 270)
			(layer "F.Fab")
			(effects
				(font
					(size 1.27 1.27)
				)
			)
		)
		(duplicate_pad_numbers_are_jumpers no)
		(fp_line
			(start -0.7874 0.4064)
			(end -0.7874 -0.4064)
			(stroke
				(width 0.1524)
				(type default)
			)
			(layer "F.SilkS")
		)
		(fp_line
			(start 0.7874 0.4064)
			(end -0.7874 0.4064)
			(stroke
				(width 0.1524)
				(type default)
			)
			(layer "F.SilkS")
		)
		(fp_line
			(start -0.7874 -0.4064)
			(end 0.7874 -0.4064)
			(stroke
				(width 0.1524)
				(type default)
			)
			(layer "F.SilkS")
		)
		(fp_line
			(start 0.7874 -0.4064)
			(end 0.7874 0.4064)
			(stroke
				(width 0.1524)
				(type default)
			)
			(layer "F.SilkS")
		)
		(fp_line
			(start -0.67945 0.3048)
			(end -0.67945 -0.305054)
			(stroke
				(width 0.1)
				(type default)
			)
			(layer "F.Fab")
		)
		(fp_line
			(start -0.12065 0.3048)
			(end -0.67945 0.3048)
			(stroke
				(width 0.1)
				(type default)
			)
			(layer "F.Fab")
		)
		(fp_line
			(start 0.120396 0.3048)
			(end 0.120396 0.2794)
			(stroke
				(width 0.1)
				(type default)
			)
			(layer "F.Fab")
		)
		(fp_line
			(start 0.67945 0.3048)
			(end 0.120396 0.3048)
			(stroke
				(width 0.1)
				(type default)
			)
			(layer "F.Fab")
		)
		(fp_line
			(start -0.12065 0.2794)
			(end -0.12065 0.3048)
			(stroke
				(width 0.1)
				(type default)
			)
			(layer "F.Fab")
		)
		(fp_line
			(start 0.120396 0.2794)
			(end -0.12065 0.2794)
			(stroke
				(width 0.1)
				(type default)
			)
			(layer "F.Fab")
		)
		(fp_line
			(start -0.12065 -0.2794)
			(end 0.12065 -0.2794)
			(stroke
				(width 0.1)
				(type default)
			)
			(layer "F.Fab")
		)
		(fp_line
			(start 0.12065 -0.2794)
			(end 0.12065 -0.3048)
			(stroke
				(width 0.1)
				(type default)
			)
			(layer "F.Fab")
		)
		(fp_line
			(start 0.12065 -0.3048)
			(end 0.67945 -0.3048)
			(stroke
				(width 0.1)
				(type default)
			)
			(layer "F.Fab")
		)
		(fp_line
			(start 0.67945 -0.3048)
			(end 0.67945 0.3048)
			(stroke
				(width 0.1)
				(type default)
			)
			(layer "F.Fab")
		)
		(fp_line
			(start -0.67945 -0.305054)
			(end -0.12065 -0.305054)
			(stroke
				(width 0.1)
				(type default)
			)
			(layer "F.Fab")
		)
		(fp_line
			(start -0.12065 -0.305054)
			(end -0.12065 -0.2794)
			(stroke
				(width 0.1)
				(type default)
			)
			(layer "F.Fab")
		)
		(pad "1" smd circle
			(at -0.40005 0 270)
			(size 0 0)
			(layers "F.Cu" "F.Mask" "F.Paste")
			(net "PVDDCR_CPU1_P0_PVCC")
		)
		(pad "2" smd circle
			(at 0.40005 0 270)
			(size 0 0)
			(layers "F.Cu" "F.Mask" "F.Paste")
			(net "GND")
		)
	)
	(footprint ""
		(layer "F.Cu")
		(at 316.15761 137.70356 90)
		(property "Reference" "ME5"
			(at 0.0254 -3.851148 90)
			(unlocked yes)
			(layer "F.SilkS")
			(effects
				(font
					(size 0.7874 0.5842)
					(thickness 0.1524)
				)
				(justify left)
			)
		)
		(property "Value" ""
			(at 0 0 90)
			(layer "F.Fab")
			(effects
				(font
					(size 1.27 1.27)
				)
			)
		)
		(duplicate_pad_numbers_are_jumpers no)
	)
	(footprint ""
		(layer "F.Cu")
		(at 498.693948 -142.844266 90)
		(property "Reference" "X8003"
			(at -1.975358 1.637792 0)
			(unlocked yes)
			(layer "F.SilkS")
			(effects
				(font
					(size 0.7874 0.5842)
					(thickness 0.1524)
				)
				(justify left)
			)
		)
		(property "Value" ""
			(at 0 0 90)
			(layer "F.Fab")
			(effects
				(font
					(size 1.27 1.27)
				)
			)
		)
		(property "Device Type" "TP_TDR_4P_FTS_TH-TP_TDR_4P_DIP,EMPTY,TP15"
			(at 1.30175 1.27 180)
			(unlocked yes)
			(layer "F.Fab")
			(hide yes)
			(effects
				(font
					(size 0.635 0.4064)
					(thickness 0.1524)
				)
			)
		)
		(property "User Part Number" "N_A"
			(at 1.30175 1.27 180)
			(unlocked yes)
			(layer "Cmts.User")
			(hide yes)
			(effects
				(font
					(size 0.635 0.4064)
					(thickness 0.1524)
				)
			)
		)
		(duplicate_pad_numbers_are_jumpers no)
		(fp_line
			(start 2.54 -1.27)
			(end 0 -1.27)
			(stroke
				(width 0.1524)
				(type default)
			)
			(layer "F.SilkS")
		)
		(fp_line
			(start 0 -1.27)
			(end 0 -0.635)
			(stroke
				(width 0.1524)
				(type default)
			)
			(layer "F.SilkS")
		)
		(fp_line
			(start 2.54 -1.1303)
			(end 2.54 -1.27)
			(stroke
				(width 0.1524)
				(type default)
			)
			(layer "F.SilkS")
		)
		(fp_line
			(start 0 0.635)
			(end 0 1.905)
			(stroke
				(width 0.1524)
				(type default)
			)
			(layer "F.SilkS")
		)
		(fp_line
			(start 2.54 1.4097)
			(end 2.54 1.1303)
			(stroke
				(width 0.1524)
				(type default)
			)
			(layer "F.SilkS")
		)
		(fp_line
			(start 0 3.175)
			(end 0 3.81)
			(stroke
				(width 0.1524)
				(type default)
			)
			(layer "F.SilkS")
		)
		(fp_line
			(start 2.54 3.81)
			(end 2.54 3.6703)
			(stroke
				(width 0.1524)
				(type default)
			)
			(layer "F.SilkS")
		)
		(fp_line
			(start 0 3.81)
			(end 2.54 3.81)
			(stroke
				(width 0.1524)
				(type default)
			)
			(layer "F.SilkS")
		)
		(fp_poly
			(pts
				(xy -2.285746 -0.762) (xy -0.761746 0) (xy -2.285746 0.762)
			)
			(stroke
				(width 0)
				(type default)
			)
			(fill yes)
			(layer "F.SilkS")
		)
		(fp_line
			(start 2.54 -1.27)
			(end 0 -1.27)
			(stroke
				(width 0.1)
				(type default)
			)
			(layer "F.Fab")
		)
		(fp_line
			(start 0 -1.27)
			(end 0 3.81)
			(stroke
				(width 0.1)
				(type default)
			)
			(layer "F.Fab")
		)
		(fp_line
			(start 2.54 3.81)
			(end 2.54 -1.27)
			(stroke
				(width 0.1)
				(type default)
			)
			(layer "F.Fab")
		)
		(fp_line
			(start 0 3.81)
			(end 2.54 3.81)
			(stroke
				(width 0.1)
				(type default)
			)
			(layer "F.Fab")
		)
		(fp_poly
			(pts
				(xy -0.761746 0) (xy -2.285746 -0.762) (xy -2.285746 0.762)
			)
			(stroke
				(width 0)
				(type default)
			)
			(fill yes)
			(layer "F.Fab")
		)
		(pad "1" thru_hole circle
			(at 0 0 90)
			(size 1.0033 1.0033)
			(drill 0.249936)
			(layers "*.Cu" "*.Mask")
			(remove_unused_layers no)
			(net "TDR_DIFF_85_IN2_DP")
			(clearance 0.10795)
			(thermal_gap 0.10795)
			(padstack
				(mode front_inner_back)
				(layer "Inner"
					(shape circle)
					(size 0.8001 0.8001)
					(clearance 0.1524)
				)
				(layer "B.Cu"
					(shape circle)
					(size 1.0033 1.0033)
					(clearance 0.10795)
				)
			)
		)
		(pad "2" thru_hole circle
			(at 2.54 0 90)
			(size 1.9939 1.9939)
			(drill 0.249936)
			(layers "*.Cu" "*.Mask")
			(remove_unused_layers no)
			(net "T1_GND")
			(clearance 0.10795)
			(thermal_gap 0.10795)
			(padstack
				(mode front_inner_back)
				(layer "Inner"
					(shape circle)
					(size 0.8001 0.8001)
					(clearance 0.1524)
				)
				(layer "B.Cu"
					(shape circle)
					(size 1.9939 1.9939)
					(clearance 0.10795)
				)
			)
		)
		(pad "3" thru_hole circle
			(at 2.54 2.54 90)
			(size 1.9939 1.9939)
			(drill 0.249936)
			(layers "*.Cu" "*.Mask")
			(remove_unused_layers no)
			(net "T1_GND")
			(clearance 0.10795)
			(thermal_gap 0.10795)
			(padstack
				(mode front_inner_back)
				(layer "Inner"
					(shape circle)
					(size 0.8001 0.8001)
					(clearance 0.1524)
				)
				(layer "B.Cu"
					(shape circle)
					(size 1.9939 1.9939)
					(clearance 0.10795)
				)
			)
		)
		(pad "4" thru_hole circle
			(at 0 2.54 90)
			(size 1.0033 1.0033)
			(drill 0.249936)
			(layers "*.Cu" "*.Mask")
			(remove_unused_layers no)
			(net "TDR_DIFF_85_IN2_DN")
			(clearance 0.10795)
			(thermal_gap 0.10795)
			(padstack
				(mode front_inner_back)
				(layer "Inner"
					(shape circle)
					(size 0.8001 0.8001)
					(clearance 0.1524)
				)
				(layer "B.Cu"
					(shape circle)
					(size 1.0033 1.0033)
					(clearance 0.10795)
				)
			)
		)
	)
	(footprint ""
		(layer "F.Cu")
		(at 330.63434 -16.178276 90)
		(property "Reference" "D7"
			(at -3.12166 0.79375 90)
			(unlocked yes)
			(layer "F.SilkS")
			(effects
				(font
					(size 0.7874 0.5842)
					(thickness 0.1524)
				)
				(justify left)
			)
		)
		(property "Value" ""
			(at 0 0 90)
			(layer "F.Fab")
			(effects
				(font
					(size 1.27 1.27)
				)
			)
		)
		(duplicate_pad_numbers_are_jumpers no)
		(fp_line
			(start 1.778 -0.5588)
			(end 1.3208 -0.5588)
			(stroke
				(width 0.1524)
				(type default)
			)
			(layer "F.SilkS")
		)
		(fp_line
			(start 1.778 -0.5588)
			(end 1.778 0.5588)
			(stroke
				(width 0.1524)
				(type default)
			)
			(layer "F.SilkS")
		)
		(fp_line
			(start 1.4732 -0.5588)
			(end 1.4732 0.5588)
			(stroke
				(width 0.1524)
				(type default)
			)
			(layer "F.SilkS")
		)
		(fp_line
			(start 1.3208 -0.5588)
			(end 1.3208 0.5588)
			(stroke
				(width 0.1524)
				(type default)
			)
			(layer "F.SilkS")
		)
		(fp_line
			(start -1.3208 -0.5588)
			(end 1.3208 -0.5588)
			(stroke
				(width 0.1524)
				(type default)
			)
			(layer "F.SilkS")
		)
		(fp_line
			(start 1.778 0.5588)
			(end 1.3208 0.5588)
			(stroke
				(width 0.1524)
				(type default)
			)
			(layer "F.SilkS")
		)
		(fp_line
			(start 1.6256 0.5588)
			(end 1.6256 -0.5588)
			(stroke
				(width 0.1524)
				(type default)
			)
			(layer "F.SilkS")
		)
		(fp_line
			(start 1.3208 0.5588)
			(end -1.3208 0.5588)
			(stroke
				(width 0.1524)
				(type default)
			)
			(layer "F.SilkS")
		)
		(fp_line
			(start -1.3208 0.5588)
			(end -1.3208 -0.5588)
			(stroke
				(width 0.1524)
				(type default)
			)
			(layer "F.SilkS")
		)
		(fp_line
			(start 0.899922 -0.40005)
			(end 0.899922 0.40005)
			(stroke
				(width 0.1)
				(type default)
			)
			(layer "F.Fab")
		)
		(fp_line
			(start -0.899922 -0.40005)
			(end 0.899922 -0.40005)
			(stroke
				(width 0.1)
				(type default)
			)
			(layer "F.Fab")
		)
		(fp_line
			(start 0.899922 0.40005)
			(end -0.899922 0.40005)
			(stroke
				(width 0.1)
				(type default)
			)
			(layer "F.Fab")
		)
		(fp_line
			(start -0.899922 0.40005)
			(end -0.899922 -0.40005)
			(stroke
				(width 0.1)
				(type default)
			)
			(layer "F.Fab")
		)
		(fp_text user "-"
			(at 1.651 -0.96901 90)
			(unlocked yes)
			(layer "F.SilkS")
			(effects
				(font
					(size 1.905 1.4224)
					(thickness 0.1524)
				)
				(justify left)
			)
		)
		(fp_text user "+"
			(at -2.57302 -0.59055 90)
			(unlocked yes)
			(layer "F.SilkS")
			(effects
				(font
					(size 1.905 1.4224)
					(thickness 0.1524)
				)
				(justify left)
			)
		)
		(fp_text user "-"
			(at 1.651 -0.22225 90)
			(unlocked yes)
			(layer "F.Fab")
			(effects
				(font
					(size 1.905 1.4224)
					(thickness 0.1524)
				)
				(justify left)
			)
		)
		(fp_text user "+"
			(at -2.6162 -0.22225 90)
			(unlocked yes)
			(layer "F.Fab")
			(effects
				(font
					(size 1.905 1.4224)
					(thickness 0.1524)
				)
				(justify left)
			)
		)
		(pad "A" smd rect
			(at -0.750062 0 90)
			(size 0.8128 0.8128)
			(layers "F.Cu" "F.Mask" "F.Paste")
			(net "BMC_FPGA_LED2_R_N")
		)
		(pad "C" smd rect
			(at 0.750062 0 90)
			(size 0.8128 0.8128)
			(layers "F.Cu" "F.Mask" "F.Paste")
			(net "BMC_FPGA_LED2_N")
		)
	)
	(footprint ""
		(layer "F.Cu")
		(at 330.932536 -387.350254)
		(property "Reference" "R676"
			(at 0 0 0)
			(layer "F.SilkS")
			(hide yes)
			(effects
				(font
					(size 1.27 1.27)
				)
			)
		)
		(property "Value" ""
			(at 0 0 0)
			(layer "F.Fab")
			(effects
				(font
					(size 1.27 1.27)
				)
			)
		)
		(duplicate_pad_numbers_are_jumpers no)
		(fp_line
			(start -0.32512 -0.175006)
			(end 0.32512 -0.175006)
			(stroke
				(width 0.1)
				(type default)
			)
			(layer "F.Fab")
		)
		(fp_line
			(start -0.32512 0.175006)
			(end -0.32512 -0.175006)
			(stroke
				(width 0.1)
				(type default)
			)
			(layer "F.Fab")
		)
		(fp_line
			(start 0.32512 -0.175006)
			(end 0.32512 0.175006)
			(stroke
				(width 0.1)
				(type default)
			)
			(layer "F.Fab")
		)
		(fp_line
			(start 0.32512 0.175006)
			(end -0.32512 0.175006)
			(stroke
				(width 0.1)
				(type default)
			)
			(layer "F.Fab")
		)
		(pad "1" smd rect
			(at -0.2667 0)
			(size 0.3048 0.381)
			(layers "F.Cu" "F.Mask" "F.Paste")
			(net "SMB_RT_CPU0_P1_ROM_MUX_1D_SCL")
		)
		(pad "2" smd rect
			(at 0.2667 0 180)
			(size 0.3048 0.381)
			(layers "F.Cu" "F.Mask" "F.Paste")
			(net "SMB_RT_CPU0_P1_ROM_MUX_1D_R_SCL")
		)
	)
	(footprint ""
		(layer "F.Cu")
		(at 367.004092 -381.41783 -90)
		(property "Reference" "C896"
			(at 0 0 270)
			(layer "F.SilkS")
			(hide yes)
			(effects
				(font
					(size 1.27 1.27)
				)
			)
		)
		(property "Value" ""
			(at 0 0 270)
			(layer "F.Fab")
			(effects
				(font
					(size 1.27 1.27)
				)
			)
		)
		(duplicate_pad_numbers_are_jumpers no)
		(fp_line
			(start -0.299974 0.150114)
			(end -0.299974 -0.150114)
			(stroke
				(width 0.1)
				(type default)
			)
			(layer "F.Fab")
		)
		(fp_line
			(start 0.299974 0.150114)
			(end -0.299974 0.150114)
			(stroke
				(width 0.1)
				(type default)
			)
			(layer "F.Fab")
		)
		(fp_line
			(start -0.299974 -0.150114)
			(end 0.299974 -0.150114)
			(stroke
				(width 0.1)
				(type default)
			)
			(layer "F.Fab")
		)
		(fp_line
			(start 0.299974 -0.150114)
			(end 0.299974 0.150114)
			(stroke
				(width 0.1)
				(type default)
			)
			(layer "F.Fab")
		)
		(pad "1" smd rect
			(at -0.2667 0 270)
			(size 0.3048 0.381)
			(layers "F.Cu" "F.Mask" "F.Paste")
			(net "P5E_CPU0_P3_TX_C_DN<2>")
		)
		(pad "2" smd rect
			(at 0.2667 0 270)
			(size 0.3048 0.381)
			(layers "F.Cu" "F.Mask" "F.Paste")
			(net "P5E_CPU0_P3_TX_DN<2>")
		)
	)
	(footprint ""
		(layer "F.Cu")
		(at 104.469946 -54.882034 90)
		(property "Reference" "R6319"
			(at 0 0 90)
			(layer "F.SilkS")
			(hide yes)
			(effects
				(font
					(size 1.27 1.27)
				)
			)
		)
		(property "Value" ""
			(at 0 0 90)
			(layer "F.Fab")
			(effects
				(font
					(size 1.27 1.27)
				)
			)
		)
		(duplicate_pad_numbers_are_jumpers no)
		(fp_line
			(start 0.7874 -0.4064)
			(end 0.7874 0.4064)
			(stroke
				(width 0.1524)
				(type default)
			)
			(layer "F.SilkS")
		)
		(fp_line
			(start -0.7874 -0.4064)
			(end 0.7874 -0.4064)
			(stroke
				(width 0.1524)
				(type default)
			)
			(layer "F.SilkS")
		)
		(fp_line
			(start 0.7874 0.4064)
			(end -0.7874 0.4064)
			(stroke
				(width 0.1524)
				(type default)
			)
			(layer "F.SilkS")
		)
		(fp_line
			(start -0.7874 0.4064)
			(end -0.7874 -0.4064)
			(stroke
				(width 0.1524)
				(type default)
			)
			(layer "F.SilkS")
		)
		(fp_line
			(start -0.12065 -0.305054)
			(end -0.12065 -0.2794)
			(stroke
				(width 0.1)
				(type default)
			)
			(layer "F.Fab")
		)
		(fp_line
			(start -0.67945 -0.305054)
			(end -0.12065 -0.305054)
			(stroke
				(width 0.1)
				(type default)
			)
			(layer "F.Fab")
		)
		(fp_line
			(start 0.67945 -0.3048)
			(end 0.67945 0.3048)
			(stroke
				(width 0.1)
				(type default)
			)
			(layer "F.Fab")
		)
		(fp_line
			(start 0.12065 -0.3048)
			(end 0.67945 -0.3048)
			(stroke
				(width 0.1)
				(type default)
			)
			(layer "F.Fab")
		)
		(fp_line
			(start 0.12065 -0.2794)
			(end 0.12065 -0.3048)
			(stroke
				(width 0.1)
				(type default)
			)
			(layer "F.Fab")
		)
		(fp_line
			(start -0.12065 -0.2794)
			(end 0.12065 -0.2794)
			(stroke
				(width 0.1)
				(type default)
			)
			(layer "F.Fab")
		)
		(fp_line
			(start 0.120396 0.2794)
			(end -0.12065 0.2794)
			(stroke
				(width 0.1)
				(type default)
			)
			(layer "F.Fab")
		)
		(fp_line
			(start -0.12065 0.2794)
			(end -0.12065 0.3048)
			(stroke
				(width 0.1)
				(type default)
			)
			(layer "F.Fab")
		)
		(fp_line
			(start 0.67945 0.3048)
			(end 0.120396 0.3048)
			(stroke
				(width 0.1)
				(type default)
			)
			(layer "F.Fab")
		)
		(fp_line
			(start 0.120396 0.3048)
			(end 0.120396 0.2794)
			(stroke
				(width 0.1)
				(type default)
			)
			(layer "F.Fab")
		)
		(fp_line
			(start -0.12065 0.3048)
			(end -0.67945 0.3048)
			(stroke
				(width 0.1)
				(type default)
			)
			(layer "F.Fab")
		)
		(fp_line
			(start -0.67945 0.3048)
			(end -0.67945 -0.305054)
			(stroke
				(width 0.1)
				(type default)
			)
			(layer "F.Fab")
		)
		(pad "1" smd circle
			(at -0.40005 0 90)
			(size 0 0)
			(layers "F.Cu" "F.Mask" "F.Paste")
			(net "USB_HUB2_TI_USB_VBUS")
		)
		(pad "2" smd circle
			(at 0.40005 0 90)
			(size 0 0)
			(layers "F.Cu" "F.Mask" "F.Paste")
			(net "GND")
		)
	)
	(footprint ""
		(layer "F.Cu")
		(at 141.29512 -31.62681 -90)
		(property "Reference" "C6015"
			(at 0 0 270)
			(layer "F.SilkS")
			(hide yes)
			(effects
				(font
					(size 1.27 1.27)
				)
			)
		)
		(property "Value" ""
			(at 0 0 270)
			(layer "F.Fab")
			(effects
				(font
					(size 1.27 1.27)
				)
			)
		)
		(duplicate_pad_numbers_are_jumpers no)
		(fp_line
			(start -0.40005 -0.4064)
			(end 0.40005 -0.4064)
			(stroke
				(width 0.1524)
				(type default)
			)
			(layer "F.SilkS")
		)
		(fp_line
			(start -0.6858 0.3048)
			(end -0.6858 -0.3048)
			(stroke
				(width 0.1)
				(type default)
			)
			(layer "F.Fab")
		)
		(fp_line
			(start -0.1016 0.3048)
			(end -0.6858 0.3048)
			(stroke
				(width 0.1)
				(type default)
			)
			(layer "F.Fab")
		)
		(fp_line
			(start 0.1016 0.3048)
			(end 0.1016 0.2794)
			(stroke
				(width 0.1)
				(type default)
			)
			(layer "F.Fab")
		)
		(fp_line
			(start 0.6858 0.3048)
			(end 0.1016 0.3048)
			(stroke
				(width 0.1)
				(type default)
			)
			(layer "F.Fab")
		)
		(fp_line
			(start -0.1016 0.2794)
			(end -0.1016 0.3048)
			(stroke
				(width 0.1)
				(type default)
			)
			(layer "F.Fab")
		)
		(fp_line
			(start 0.1016 0.2794)
			(end -0.1016 0.2794)
			(stroke
				(width 0.1)
				(type default)
			)
			(layer "F.Fab")
		)
		(fp_line
			(start -0.1016 -0.2794)
			(end 0.1016 -0.2794)
			(stroke
				(width 0.1)
				(type default)
			)
			(layer "F.Fab")
		)
		(fp_line
			(start 0.1016 -0.2794)
			(end 0.1016 -0.3048)
			(stroke
				(width 0.1)
				(type default)
			)
			(layer "F.Fab")
		)
		(fp_line
			(start -0.6858 -0.3048)
			(end -0.1016 -0.3048)
			(stroke
				(width 0.1)
				(type default)
			)
			(layer "F.Fab")
		)
		(fp_line
			(start -0.1016 -0.3048)
			(end -0.1016 -0.2794)
			(stroke
				(width 0.1)
				(type default)
			)
			(layer "F.Fab")
		)
		(fp_line
			(start 0.1016 -0.3048)
			(end 0.6858 -0.3048)
			(stroke
				(width 0.1)
				(type default)
			)
			(layer "F.Fab")
		)
		(fp_line
			(start 0.6858 -0.3048)
			(end 0.6858 0.3048)
			(stroke
				(width 0.1)
				(type default)
			)
			(layer "F.Fab")
		)
		(pad "1" smd rect
			(at -0.40005 0 90)
			(size 0.4572 0.508)
			(layers "F.Cu" "F.Mask" "F.Paste")
			(net "USB3_CPU0_BMC_RX_HUB1_DP")
		)
		(pad "2" smd rect
			(at 0.40005 0 90)
			(size 0.4572 0.508)
			(layers "F.Cu" "F.Mask" "F.Paste")
			(net "USB3_CPU0_BMC_RX_HUB_C_DP")
		)
	)
	(footprint ""
		(layer "F.Cu")
		(at 230.675688 -147.932648 180)
		(property "Reference" "C1519"
			(at 0 0 180)
			(layer "F.SilkS")
			(hide yes)
			(effects
				(font
					(size 1.27 1.27)
				)
			)
		)
		(property "Value" ""
			(at 0 0 180)
			(layer "F.Fab")
			(effects
				(font
					(size 1.27 1.27)
				)
			)
		)
		(duplicate_pad_numbers_are_jumpers no)
		(fp_line
			(start 0.7874 0.4064)
			(end -0.7874 0.4064)
			(stroke
				(width 0.1524)
				(type default)
			)
			(layer "F.SilkS")
		)
		(fp_line
			(start 0.7874 -0.4064)
			(end 0.7874 0.4064)
			(stroke
				(width 0.1524)
				(type default)
			)
			(layer "F.SilkS")
		)
		(fp_line
			(start -0.7874 0.4064)
			(end -0.7874 -0.4064)
			(stroke
				(width 0.1524)
				(type default)
			)
			(layer "F.SilkS")
		)
		(fp_line
			(start -0.7874 -0.4064)
			(end 0.7874 -0.4064)
			(stroke
				(width 0.1524)
				(type default)
			)
			(layer "F.SilkS")
		)
		(fp_line
			(start 0.67945 0.3048)
			(end 0.120396 0.3048)
			(stroke
				(width 0.1)
				(type default)
			)
			(layer "F.Fab")
		)
		(fp_line
			(start 0.67945 -0.3048)
			(end 0.67945 0.3048)
			(stroke
				(width 0.1)
				(type default)
			)
			(layer "F.Fab")
		)
		(fp_line
			(start 0.12065 -0.2794)
			(end 0.12065 -0.3048)
			(stroke
				(width 0.1)
				(type default)
			)
			(layer "F.Fab")
		)
		(fp_line
			(start 0.12065 -0.3048)
			(end 0.67945 -0.3048)
			(stroke
				(width 0.1)
				(type default)
			)
			(layer "F.Fab")
		)
		(fp_line
			(start 0.120396 0.3048)
			(end 0.120396 0.2794)
			(stroke
				(width 0.1)
				(type default)
			)
			(layer "F.Fab")
		)
		(fp_line
			(start 0.120396 0.2794)
			(end -0.12065 0.2794)
			(stroke
				(width 0.1)
				(type default)
			)
			(layer "F.Fab")
		)
		(fp_line
			(start -0.12065 0.3048)
			(end -0.67945 0.3048)
			(stroke
				(width 0.1)
				(type default)
			)
			(layer "F.Fab")
		)
		(fp_line
			(start -0.12065 0.2794)
			(end -0.12065 0.3048)
			(stroke
				(width 0.1)
				(type default)
			)
			(layer "F.Fab")
		)
		(fp_line
			(start -0.12065 -0.2794)
			(end 0.12065 -0.2794)
			(stroke
				(width 0.1)
				(type default)
			)
			(layer "F.Fab")
		)
		(fp_line
			(start -0.12065 -0.305054)
			(end -0.12065 -0.2794)
			(stroke
				(width 0.1)
				(type default)
			)
			(layer "F.Fab")
		)
		(fp_line
			(start -0.67945 0.3048)
			(end -0.67945 -0.305054)
			(stroke
				(width 0.1)
				(type default)
			)
			(layer "F.Fab")
		)
		(fp_line
			(start -0.67945 -0.305054)
			(end -0.12065 -0.305054)
			(stroke
				(width 0.1)
				(type default)
			)
			(layer "F.Fab")
		)
		(pad "1" smd circle
			(at -0.40005 0 180)
			(size 0 0)
			(layers "F.Cu" "F.Mask" "F.Paste")
			(net "PVDD18_S5_P0")
		)
		(pad "2" smd circle
			(at 0.40005 0 180)
			(size 0 0)
			(layers "F.Cu" "F.Mask" "F.Paste")
			(net "GND")
		)
	)
	(footprint ""
		(layer "F.Cu")
		(at 44.7294 -104.7369)
		(property "Reference" "R1052"
			(at 0 0 0)
			(layer "F.SilkS")
			(hide yes)
			(effects
				(font
					(size 1.27 1.27)
				)
			)
		)
		(property "Value" ""
			(at 0 0 0)
			(layer "F.Fab")
			(effects
				(font
					(size 1.27 1.27)
				)
			)
		)
		(duplicate_pad_numbers_are_jumpers no)
		(fp_line
			(start -0.7874 -0.4064)
			(end 0.7874 -0.4064)
			(stroke
				(width 0.1524)
				(type default)
			)
			(layer "F.SilkS")
		)
		(fp_line
			(start -0.7874 0.4064)
			(end -0.7874 -0.4064)
			(stroke
				(width 0.1524)
				(type default)
			)
			(layer "F.SilkS")
		)
		(fp_line
			(start 0.7874 -0.4064)
			(end 0.7874 0.4064)
			(stroke
				(width 0.1524)
				(type default)
			)
			(layer "F.SilkS")
		)
		(fp_line
			(start 0.7874 0.4064)
			(end -0.7874 0.4064)
			(stroke
				(width 0.1524)
				(type default)
			)
			(layer "F.SilkS")
		)
		(fp_line
			(start -0.67945 -0.305054)
			(end -0.12065 -0.305054)
			(stroke
				(width 0.1)
				(type default)
			)
			(layer "F.Fab")
		)
		(fp_line
			(start -0.67945 0.3048)
			(end -0.67945 -0.305054)
			(stroke
				(width 0.1)
				(type default)
			)
			(layer "F.Fab")
		)
		(fp_line
			(start -0.12065 -0.305054)
			(end -0.12065 -0.2794)
			(stroke
				(width 0.1)
				(type default)
			)
			(layer "F.Fab")
		)
		(fp_line
			(start -0.12065 -0.2794)
			(end 0.12065 -0.2794)
			(stroke
				(width 0.1)
				(type default)
			)
			(layer "F.Fab")
		)
		(fp_line
			(start -0.12065 0.2794)
			(end -0.12065 0.3048)
			(stroke
				(width 0.1)
				(type default)
			)
			(layer "F.Fab")
		)
		(fp_line
			(start -0.12065 0.3048)
			(end -0.67945 0.3048)
			(stroke
				(width 0.1)
				(type default)
			)
			(layer "F.Fab")
		)
		(fp_line
			(start 0.120396 0.2794)
			(end -0.12065 0.2794)
			(stroke
				(width 0.1)
				(type default)
			)
			(layer "F.Fab")
		)
		(fp_line
			(start 0.120396 0.3048)
			(end 0.120396 0.2794)
			(stroke
				(width 0.1)
				(type default)
			)
			(layer "F.Fab")
		)
		(fp_line
			(start 0.12065 -0.3048)
			(end 0.67945 -0.3048)
			(stroke
				(width 0.1)
				(type default)
			)
			(layer "F.Fab")
		)
		(fp_line
			(start 0.12065 -0.2794)
			(end 0.12065 -0.3048)
			(stroke
				(width 0.1)
				(type default)
			)
			(layer "F.Fab")
		)
		(fp_line
			(start 0.67945 -0.3048)
			(end 0.67945 0.3048)
			(stroke
				(width 0.1)
				(type default)
			)
			(layer "F.Fab")
		)
		(fp_line
			(start 0.67945 0.3048)
			(end 0.120396 0.3048)
			(stroke
				(width 0.1)
				(type default)
			)
			(layer "F.Fab")
		)
		(pad "1" smd circle
			(at -0.40005 0)
			(size 0 0)
			(layers "F.Cu" "F.Mask" "F.Paste")
			(net "P3V3_AUX")
		)
		(pad "2" smd circle
			(at 0.40005 0)
			(size 0 0)
			(layers "F.Cu" "F.Mask" "F.Paste")
			(net "P3V3_AUX_DSC_G1")
		)
	)
	(footprint ""
		(layer "F.Cu")
		(at 173.609 -100.294948 -90)
		(property "Reference" "R6008"
			(at 0 0 270)
			(layer "F.SilkS")
			(hide yes)
			(effects
				(font
					(size 1.27 1.27)
				)
			)
		)
		(property "Value" ""
			(at 0 0 270)
			(layer "F.Fab")
			(effects
				(font
					(size 1.27 1.27)
				)
			)
		)
		(duplicate_pad_numbers_are_jumpers no)
		(fp_line
			(start -0.7874 0.4064)
			(end -0.7874 -0.4064)
			(stroke
				(width 0.1524)
				(type default)
			)
			(layer "F.SilkS")
		)
		(fp_line
			(start 0.7874 0.4064)
			(end -0.7874 0.4064)
			(stroke
				(width 0.1524)
				(type default)
			)
			(layer "F.SilkS")
		)
		(fp_line
			(start -0.7874 -0.4064)
			(end 0.7874 -0.4064)
			(stroke
				(width 0.1524)
				(type default)
			)
			(layer "F.SilkS")
		)
		(fp_line
			(start 0.7874 -0.4064)
			(end 0.7874 0.4064)
			(stroke
				(width 0.1524)
				(type default)
			)
			(layer "F.SilkS")
		)
		(fp_line
			(start -0.67945 0.3048)
			(end -0.67945 -0.305054)
			(stroke
				(width 0.1)
				(type default)
			)
			(layer "F.Fab")
		)
		(fp_line
			(start -0.12065 0.3048)
			(end -0.67945 0.3048)
			(stroke
				(width 0.1)
				(type default)
			)
			(layer "F.Fab")
		)
		(fp_line
			(start 0.120396 0.3048)
			(end 0.120396 0.2794)
			(stroke
				(width 0.1)
				(type default)
			)
			(layer "F.Fab")
		)
		(fp_line
			(start 0.67945 0.3048)
			(end 0.120396 0.3048)
			(stroke
				(width 0.1)
				(type default)
			)
			(layer "F.Fab")
		)
		(fp_line
			(start -0.12065 0.2794)
			(end -0.12065 0.3048)
			(stroke
				(width 0.1)
				(type default)
			)
			(layer "F.Fab")
		)
		(fp_line
			(start 0.120396 0.2794)
			(end -0.12065 0.2794)
			(stroke
				(width 0.1)
				(type default)
			)
			(layer "F.Fab")
		)
		(fp_line
			(start -0.12065 -0.2794)
			(end 0.12065 -0.2794)
			(stroke
				(width 0.1)
				(type default)
			)
			(layer "F.Fab")
		)
		(fp_line
			(start 0.12065 -0.2794)
			(end 0.12065 -0.3048)
			(stroke
				(width 0.1)
				(type default)
			)
			(layer "F.Fab")
		)
		(fp_line
			(start 0.12065 -0.3048)
			(end 0.67945 -0.3048)
			(stroke
				(width 0.1)
				(type default)
			)
			(layer "F.Fab")
		)
		(fp_line
			(start 0.67945 -0.3048)
			(end 0.67945 0.3048)
			(stroke
				(width 0.1)
				(type default)
			)
			(layer "F.Fab")
		)
		(fp_line
			(start -0.67945 -0.305054)
			(end -0.12065 -0.305054)
			(stroke
				(width 0.1)
				(type default)
			)
			(layer "F.Fab")
		)
		(fp_line
			(start -0.12065 -0.305054)
			(end -0.12065 -0.2794)
			(stroke
				(width 0.1)
				(type default)
			)
			(layer "F.Fab")
		)
		(pad "1" smd circle
			(at -0.40005 0 270)
			(size 0 0)
			(layers "F.Cu" "F.Mask" "F.Paste")
			(net "SGPIO_SCM_DO_<0>")
		)
		(pad "2" smd circle
			(at 0.40005 0 270)
			(size 0 0)
			(layers "F.Cu" "F.Mask" "F.Paste")
			(net "SGPIO_SCM_DO_R_<0>")
		)
	)
	(footprint ""
		(layer "F.Cu")
		(at 422.339516 -356.32644 180)
		(property "Reference" "PR133"
			(at 0 0 180)
			(layer "F.SilkS")
			(hide yes)
			(effects
				(font
					(size 1.27 1.27)
				)
			)
		)
		(property "Value" ""
			(at 0 0 180)
			(layer "F.Fab")
			(effects
				(font
					(size 1.27 1.27)
				)
			)
		)
		(duplicate_pad_numbers_are_jumpers no)
		(fp_line
			(start 0.7874 0.4064)
			(end -0.7874 0.4064)
			(stroke
				(width 0.1524)
				(type default)
			)
			(layer "F.SilkS")
		)
		(fp_line
			(start 0.7874 -0.4064)
			(end 0.7874 0.4064)
			(stroke
				(width 0.1524)
				(type default)
			)
			(layer "F.SilkS")
		)
		(fp_line
			(start -0.7874 0.4064)
			(end -0.7874 -0.4064)
			(stroke
				(width 0.1524)
				(type default)
			)
			(layer "F.SilkS")
		)
		(fp_line
			(start -0.7874 -0.4064)
			(end 0.7874 -0.4064)
			(stroke
				(width 0.1524)
				(type default)
			)
			(layer "F.SilkS")
		)
		(fp_line
			(start 0.67945 0.3048)
			(end 0.120396 0.3048)
			(stroke
				(width 0.1)
				(type default)
			)
			(layer "F.Fab")
		)
		(fp_line
			(start 0.67945 -0.3048)
			(end 0.67945 0.3048)
			(stroke
				(width 0.1)
				(type default)
			)
			(layer "F.Fab")
		)
		(fp_line
			(start 0.12065 -0.2794)
			(end 0.12065 -0.3048)
			(stroke
				(width 0.1)
				(type default)
			)
			(layer "F.Fab")
		)
		(fp_line
			(start 0.12065 -0.3048)
			(end 0.67945 -0.3048)
			(stroke
				(width 0.1)
				(type default)
			)
			(layer "F.Fab")
		)
		(fp_line
			(start 0.120396 0.3048)
			(end 0.120396 0.2794)
			(stroke
				(width 0.1)
				(type default)
			)
			(layer "F.Fab")
		)
		(fp_line
			(start 0.120396 0.2794)
			(end -0.12065 0.2794)
			(stroke
				(width 0.1)
				(type default)
			)
			(layer "F.Fab")
		)
		(fp_line
			(start -0.12065 0.3048)
			(end -0.67945 0.3048)
			(stroke
				(width 0.1)
				(type default)
			)
			(layer "F.Fab")
		)
		(fp_line
			(start -0.12065 0.2794)
			(end -0.12065 0.3048)
			(stroke
				(width 0.1)
				(type default)
			)
			(layer "F.Fab")
		)
		(fp_line
			(start -0.12065 -0.2794)
			(end 0.12065 -0.2794)
			(stroke
				(width 0.1)
				(type default)
			)
			(layer "F.Fab")
		)
		(fp_line
			(start -0.12065 -0.305054)
			(end -0.12065 -0.2794)
			(stroke
				(width 0.1)
				(type default)
			)
			(layer "F.Fab")
		)
		(fp_line
			(start -0.67945 0.3048)
			(end -0.67945 -0.305054)
			(stroke
				(width 0.1)
				(type default)
			)
			(layer "F.Fab")
		)
		(fp_line
			(start -0.67945 -0.305054)
			(end -0.12065 -0.305054)
			(stroke
				(width 0.1)
				(type default)
			)
			(layer "F.Fab")
		)
		(pad "1" smd circle
			(at -0.40005 0 180)
			(size 0 0)
			(layers "F.Cu" "F.Mask" "F.Paste")
			(net "GND")
		)
		(pad "2" smd circle
			(at 0.40005 0 180)
			(size 0 0)
			(layers "F.Cu" "F.Mask" "F.Paste")
			(net "PVDD11_S3_P0_LSET1")
		)
	)
	(footprint ""
		(layer "F.Cu")
		(at 414.316418 -366.780064)
		(property "Reference" "R122"
			(at 0 0 0)
			(layer "F.SilkS")
			(hide yes)
			(effects
				(font
					(size 1.27 1.27)
				)
			)
		)
		(property "Value" ""
			(at 0 0 0)
			(layer "F.Fab")
			(effects
				(font
					(size 1.27 1.27)
				)
			)
		)
		(duplicate_pad_numbers_are_jumpers no)
		(fp_line
			(start -0.7874 -0.4064)
			(end 0.7874 -0.4064)
			(stroke
				(width 0.1524)
				(type default)
			)
			(layer "F.SilkS")
		)
		(fp_line
			(start -0.7874 0.4064)
			(end -0.7874 -0.4064)
			(stroke
				(width 0.1524)
				(type default)
			)
			(layer "F.SilkS")
		)
		(fp_line
			(start 0.7874 -0.4064)
			(end 0.7874 0.4064)
			(stroke
				(width 0.1524)
				(type default)
			)
			(layer "F.SilkS")
		)
		(fp_line
			(start 0.7874 0.4064)
			(end -0.7874 0.4064)
			(stroke
				(width 0.1524)
				(type default)
			)
			(layer "F.SilkS")
		)
		(fp_line
			(start -0.67945 -0.305054)
			(end -0.12065 -0.305054)
			(stroke
				(width 0.1)
				(type default)
			)
			(layer "F.Fab")
		)
		(fp_line
			(start -0.67945 0.3048)
			(end -0.67945 -0.305054)
			(stroke
				(width 0.1)
				(type default)
			)
			(layer "F.Fab")
		)
		(fp_line
			(start -0.12065 -0.305054)
			(end -0.12065 -0.2794)
			(stroke
				(width 0.1)
				(type default)
			)
			(layer "F.Fab")
		)
		(fp_line
			(start -0.12065 -0.2794)
			(end 0.12065 -0.2794)
			(stroke
				(width 0.1)
				(type default)
			)
			(layer "F.Fab")
		)
		(fp_line
			(start -0.12065 0.2794)
			(end -0.12065 0.3048)
			(stroke
				(width 0.1)
				(type default)
			)
			(layer "F.Fab")
		)
		(fp_line
			(start -0.12065 0.3048)
			(end -0.67945 0.3048)
			(stroke
				(width 0.1)
				(type default)
			)
			(layer "F.Fab")
		)
		(fp_line
			(start 0.120396 0.2794)
			(end -0.12065 0.2794)
			(stroke
				(width 0.1)
				(type default)
			)
			(layer "F.Fab")
		)
		(fp_line
			(start 0.120396 0.3048)
			(end 0.120396 0.2794)
			(stroke
				(width 0.1)
				(type default)
			)
			(layer "F.Fab")
		)
		(fp_line
			(start 0.12065 -0.3048)
			(end 0.67945 -0.3048)
			(stroke
				(width 0.1)
				(type default)
			)
			(layer "F.Fab")
		)
		(fp_line
			(start 0.12065 -0.2794)
			(end 0.12065 -0.3048)
			(stroke
				(width 0.1)
				(type default)
			)
			(layer "F.Fab")
		)
		(fp_line
			(start 0.67945 -0.3048)
			(end 0.67945 0.3048)
			(stroke
				(width 0.1)
				(type default)
			)
			(layer "F.Fab")
		)
		(fp_line
			(start 0.67945 0.3048)
			(end 0.120396 0.3048)
			(stroke
				(width 0.1)
				(type default)
			)
			(layer "F.Fab")
		)
		(pad "1" smd circle
			(at -0.40005 0)
			(size 0 0)
			(layers "F.Cu" "F.Mask" "F.Paste")
			(net "PWRGD_PVDD11_S3_P0")
		)
		(pad "2" smd circle
			(at 0.40005 0)
			(size 0 0)
			(layers "F.Cu" "F.Mask" "F.Paste")
			(net "PWRGD_PVDD11_S3_P0_R")
		)
	)
	(footprint ""
		(layer "F.Cu")
		(at 63.999364 -408.517344 -90)
		(property "Reference" "C6639"
			(at 0 0 270)
			(layer "F.SilkS")
			(hide yes)
			(effects
				(font
					(size 1.27 1.27)
				)
			)
		)
		(property "Value" ""
			(at 0 0 270)
			(layer "F.Fab")
			(effects
				(font
					(size 1.27 1.27)
				)
			)
		)
		(duplicate_pad_numbers_are_jumpers no)
		(fp_line
			(start -0.299974 0.150114)
			(end -0.299974 -0.150114)
			(stroke
				(width 0.1)
				(type default)
			)
			(layer "F.Fab")
		)
		(fp_line
			(start 0.299974 0.150114)
			(end -0.299974 0.150114)
			(stroke
				(width 0.1)
				(type default)
			)
			(layer "F.Fab")
		)
		(fp_line
			(start -0.299974 -0.150114)
			(end 0.299974 -0.150114)
			(stroke
				(width 0.1)
				(type default)
			)
			(layer "F.Fab")
		)
		(fp_line
			(start 0.299974 -0.150114)
			(end 0.299974 0.150114)
			(stroke
				(width 0.1)
				(type default)
			)
			(layer "F.Fab")
		)
		(pad "1" smd rect
			(at -0.2667 0 270)
			(size 0.3048 0.381)
			(layers "F.Cu" "F.Mask" "F.Paste")
			(net "P5E_CPU1_P0_TX_BUF_C_DP<5>")
		)
		(pad "2" smd rect
			(at 0.2667 0 270)
			(size 0.3048 0.381)
			(layers "F.Cu" "F.Mask" "F.Paste")
			(net "P5E_CPU1_P0_TX_BUF_DP<5>")
		)
	)
	(footprint ""
		(layer "F.Cu")
		(at 439.029602 -425.94911 180)
		(property "Reference" "R6786"
			(at 0 0 180)
			(layer "F.SilkS")
			(hide yes)
			(effects
				(font
					(size 1.27 1.27)
				)
			)
		)
		(property "Value" ""
			(at 0 0 180)
			(layer "F.Fab")
			(effects
				(font
					(size 1.27 1.27)
				)
			)
		)
		(duplicate_pad_numbers_are_jumpers no)
		(fp_line
			(start 0.7874 0.4064)
			(end -0.7874 0.4064)
			(stroke
				(width 0.1524)
				(type default)
			)
			(layer "F.SilkS")
		)
		(fp_line
			(start 0.7874 -0.4064)
			(end 0.7874 0.4064)
			(stroke
				(width 0.1524)
				(type default)
			)
			(layer "F.SilkS")
		)
		(fp_line
			(start -0.7874 0.4064)
			(end -0.7874 -0.4064)
			(stroke
				(width 0.1524)
				(type default)
			)
			(layer "F.SilkS")
		)
		(fp_line
			(start -0.7874 -0.4064)
			(end 0.7874 -0.4064)
			(stroke
				(width 0.1524)
				(type default)
			)
			(layer "F.SilkS")
		)
		(fp_line
			(start 0.67945 0.3048)
			(end 0.120396 0.3048)
			(stroke
				(width 0.1)
				(type default)
			)
			(layer "F.Fab")
		)
		(fp_line
			(start 0.67945 -0.3048)
			(end 0.67945 0.3048)
			(stroke
				(width 0.1)
				(type default)
			)
			(layer "F.Fab")
		)
		(fp_line
			(start 0.12065 -0.2794)
			(end 0.12065 -0.3048)
			(stroke
				(width 0.1)
				(type default)
			)
			(layer "F.Fab")
		)
		(fp_line
			(start 0.12065 -0.3048)
			(end 0.67945 -0.3048)
			(stroke
				(width 0.1)
				(type default)
			)
			(layer "F.Fab")
		)
		(fp_line
			(start 0.120396 0.3048)
			(end 0.120396 0.2794)
			(stroke
				(width 0.1)
				(type default)
			)
			(layer "F.Fab")
		)
		(fp_line
			(start 0.120396 0.2794)
			(end -0.12065 0.2794)
			(stroke
				(width 0.1)
				(type default)
			)
			(layer "F.Fab")
		)
		(fp_line
			(start -0.12065 0.3048)
			(end -0.67945 0.3048)
			(stroke
				(width 0.1)
				(type default)
			)
			(layer "F.Fab")
		)
		(fp_line
			(start -0.12065 0.2794)
			(end -0.12065 0.3048)
			(stroke
				(width 0.1)
				(type default)
			)
			(layer "F.Fab")
		)
		(fp_line
			(start -0.12065 -0.2794)
			(end 0.12065 -0.2794)
			(stroke
				(width 0.1)
				(type default)
			)
			(layer "F.Fab")
		)
		(fp_line
			(start -0.12065 -0.305054)
			(end -0.12065 -0.2794)
			(stroke
				(width 0.1)
				(type default)
			)
			(layer "F.Fab")
		)
		(fp_line
			(start -0.67945 0.3048)
			(end -0.67945 -0.305054)
			(stroke
				(width 0.1)
				(type default)
			)
			(layer "F.Fab")
		)
		(fp_line
			(start -0.67945 -0.305054)
			(end -0.12065 -0.305054)
			(stroke
				(width 0.1)
				(type default)
			)
			(layer "F.Fab")
		)
		(pad "1" smd circle
			(at -0.40005 0 180)
			(size 0 0)
			(layers "F.Cu" "F.Mask" "F.Paste")
			(net "P0V9_RETIMER_CPU0_EN0_R")
		)
		(pad "2" smd circle
			(at 0.40005 0 180)
			(size 0 0)
			(layers "F.Cu" "F.Mask" "F.Paste")
			(net "GND")
		)
	)
	(footprint ""
		(layer "F.Cu")
		(at 11.665458 -422.551098 180)
		(property "Reference" "R6174"
			(at 0 0 180)
			(layer "F.SilkS")
			(hide yes)
			(effects
				(font
					(size 1.27 1.27)
				)
			)
		)
		(property "Value" ""
			(at 0 0 180)
			(layer "F.Fab")
			(effects
				(font
					(size 1.27 1.27)
				)
			)
		)
		(duplicate_pad_numbers_are_jumpers no)
		(fp_line
			(start 0.7874 0.4064)
			(end -0.7874 0.4064)
			(stroke
				(width 0.1524)
				(type default)
			)
			(layer "F.SilkS")
		)
		(fp_line
			(start 0.7874 -0.4064)
			(end 0.7874 0.4064)
			(stroke
				(width 0.1524)
				(type default)
			)
			(layer "F.SilkS")
		)
		(fp_line
			(start -0.7874 0.4064)
			(end -0.7874 -0.4064)
			(stroke
				(width 0.1524)
				(type default)
			)
			(layer "F.SilkS")
		)
		(fp_line
			(start -0.7874 -0.4064)
			(end 0.7874 -0.4064)
			(stroke
				(width 0.1524)
				(type default)
			)
			(layer "F.SilkS")
		)
		(fp_line
			(start 0.67945 0.3048)
			(end 0.120396 0.3048)
			(stroke
				(width 0.1)
				(type default)
			)
			(layer "F.Fab")
		)
		(fp_line
			(start 0.67945 -0.3048)
			(end 0.67945 0.3048)
			(stroke
				(width 0.1)
				(type default)
			)
			(layer "F.Fab")
		)
		(fp_line
			(start 0.12065 -0.2794)
			(end 0.12065 -0.3048)
			(stroke
				(width 0.1)
				(type default)
			)
			(layer "F.Fab")
		)
		(fp_line
			(start 0.12065 -0.3048)
			(end 0.67945 -0.3048)
			(stroke
				(width 0.1)
				(type default)
			)
			(layer "F.Fab")
		)
		(fp_line
			(start 0.120396 0.3048)
			(end 0.120396 0.2794)
			(stroke
				(width 0.1)
				(type default)
			)
			(layer "F.Fab")
		)
		(fp_line
			(start 0.120396 0.2794)
			(end -0.12065 0.2794)
			(stroke
				(width 0.1)
				(type default)
			)
			(layer "F.Fab")
		)
		(fp_line
			(start -0.12065 0.3048)
			(end -0.67945 0.3048)
			(stroke
				(width 0.1)
				(type default)
			)
			(layer "F.Fab")
		)
		(fp_line
			(start -0.12065 0.2794)
			(end -0.12065 0.3048)
			(stroke
				(width 0.1)
				(type default)
			)
			(layer "F.Fab")
		)
		(fp_line
			(start -0.12065 -0.2794)
			(end 0.12065 -0.2794)
			(stroke
				(width 0.1)
				(type default)
			)
			(layer "F.Fab")
		)
		(fp_line
			(start -0.12065 -0.305054)
			(end -0.12065 -0.2794)
			(stroke
				(width 0.1)
				(type default)
			)
			(layer "F.Fab")
		)
		(fp_line
			(start -0.67945 0.3048)
			(end -0.67945 -0.305054)
			(stroke
				(width 0.1)
				(type default)
			)
			(layer "F.Fab")
		)
		(fp_line
			(start -0.67945 -0.305054)
			(end -0.12065 -0.305054)
			(stroke
				(width 0.1)
				(type default)
			)
			(layer "F.Fab")
		)
		(pad "1" smd circle
			(at -0.40005 0 180)
			(size 0 0)
			(layers "F.Cu" "F.Mask" "F.Paste")
			(net "FM_P2E_BUF2_EQA0")
		)
		(pad "2" smd circle
			(at 0.40005 0 180)
			(size 0 0)
			(layers "F.Cu" "F.Mask" "F.Paste")
			(net "GND")
		)
	)
	(footprint ""
		(layer "F.Cu")
		(at 193.929 -100.294948 -90)
		(property "Reference" "R223"
			(at 0 0 270)
			(layer "F.SilkS")
			(hide yes)
			(effects
				(font
					(size 1.27 1.27)
				)
			)
		)
		(property "Value" ""
			(at 0 0 270)
			(layer "F.Fab")
			(effects
				(font
					(size 1.27 1.27)
				)
			)
		)
		(duplicate_pad_numbers_are_jumpers no)
		(fp_line
			(start -0.7874 0.4064)
			(end -0.7874 -0.4064)
			(stroke
				(width 0.1524)
				(type default)
			)
			(layer "F.SilkS")
		)
		(fp_line
			(start 0.7874 0.4064)
			(end -0.7874 0.4064)
			(stroke
				(width 0.1524)
				(type default)
			)
			(layer "F.SilkS")
		)
		(fp_line
			(start -0.7874 -0.4064)
			(end 0.7874 -0.4064)
			(stroke
				(width 0.1524)
				(type default)
			)
			(layer "F.SilkS")
		)
		(fp_line
			(start 0.7874 -0.4064)
			(end 0.7874 0.4064)
			(stroke
				(width 0.1524)
				(type default)
			)
			(layer "F.SilkS")
		)
		(fp_line
			(start -0.67945 0.3048)
			(end -0.67945 -0.305054)
			(stroke
				(width 0.1)
				(type default)
			)
			(layer "F.Fab")
		)
		(fp_line
			(start -0.12065 0.3048)
			(end -0.67945 0.3048)
			(stroke
				(width 0.1)
				(type default)
			)
			(layer "F.Fab")
		)
		(fp_line
			(start 0.120396 0.3048)
			(end 0.120396 0.2794)
			(stroke
				(width 0.1)
				(type default)
			)
			(layer "F.Fab")
		)
		(fp_line
			(start 0.67945 0.3048)
			(end 0.120396 0.3048)
			(stroke
				(width 0.1)
				(type default)
			)
			(layer "F.Fab")
		)
		(fp_line
			(start -0.12065 0.2794)
			(end -0.12065 0.3048)
			(stroke
				(width 0.1)
				(type default)
			)
			(layer "F.Fab")
		)
		(fp_line
			(start 0.120396 0.2794)
			(end -0.12065 0.2794)
			(stroke
				(width 0.1)
				(type default)
			)
			(layer "F.Fab")
		)
		(fp_line
			(start -0.12065 -0.2794)
			(end 0.12065 -0.2794)
			(stroke
				(width 0.1)
				(type default)
			)
			(layer "F.Fab")
		)
		(fp_line
			(start 0.12065 -0.2794)
			(end 0.12065 -0.3048)
			(stroke
				(width 0.1)
				(type default)
			)
			(layer "F.Fab")
		)
		(fp_line
			(start 0.12065 -0.3048)
			(end 0.67945 -0.3048)
			(stroke
				(width 0.1)
				(type default)
			)
			(layer "F.Fab")
		)
		(fp_line
			(start 0.67945 -0.3048)
			(end 0.67945 0.3048)
			(stroke
				(width 0.1)
				(type default)
			)
			(layer "F.Fab")
		)
		(fp_line
			(start -0.67945 -0.305054)
			(end -0.12065 -0.305054)
			(stroke
				(width 0.1)
				(type default)
			)
			(layer "F.Fab")
		)
		(fp_line
			(start -0.12065 -0.305054)
			(end -0.12065 -0.2794)
			(stroke
				(width 0.1)
				(type default)
			)
			(layer "F.Fab")
		)
		(pad "1" smd circle
			(at -0.40005 0 270)
			(size 0 0)
			(layers "F.Cu" "F.Mask" "F.Paste")
			(net "FM_CPU0_SP5R4")
		)
		(pad "2" smd circle
			(at 0.40005 0 270)
			(size 0 0)
			(layers "F.Cu" "F.Mask" "F.Paste")
			(net "CPU0_SP5R4")
		)
	)
	(footprint ""
		(layer "F.Cu")
		(at 368.130836 -323.466968 90)
		(property "Reference" "R1204"
			(at 0 0 90)
			(layer "F.SilkS")
			(hide yes)
			(effects
				(font
					(size 1.27 1.27)
				)
			)
		)
		(property "Value" ""
			(at 0 0 90)
			(layer "F.Fab")
			(effects
				(font
					(size 1.27 1.27)
				)
			)
		)
		(duplicate_pad_numbers_are_jumpers no)
		(fp_line
			(start 0.7874 -0.4064)
			(end 0.7874 0.4064)
			(stroke
				(width 0.1524)
				(type default)
			)
			(layer "F.SilkS")
		)
		(fp_line
			(start -0.7874 -0.4064)
			(end 0.7874 -0.4064)
			(stroke
				(width 0.1524)
				(type default)
			)
			(layer "F.SilkS")
		)
		(fp_line
			(start 0.7874 0.4064)
			(end -0.7874 0.4064)
			(stroke
				(width 0.1524)
				(type default)
			)
			(layer "F.SilkS")
		)
		(fp_line
			(start -0.7874 0.4064)
			(end -0.7874 -0.4064)
			(stroke
				(width 0.1524)
				(type default)
			)
			(layer "F.SilkS")
		)
		(fp_line
			(start -0.12065 -0.305054)
			(end -0.12065 -0.2794)
			(stroke
				(width 0.1)
				(type default)
			)
			(layer "F.Fab")
		)
		(fp_line
			(start -0.67945 -0.305054)
			(end -0.12065 -0.305054)
			(stroke
				(width 0.1)
				(type default)
			)
			(layer "F.Fab")
		)
		(fp_line
			(start 0.67945 -0.3048)
			(end 0.67945 0.3048)
			(stroke
				(width 0.1)
				(type default)
			)
			(layer "F.Fab")
		)
		(fp_line
			(start 0.12065 -0.3048)
			(end 0.67945 -0.3048)
			(stroke
				(width 0.1)
				(type default)
			)
			(layer "F.Fab")
		)
		(fp_line
			(start 0.12065 -0.2794)
			(end 0.12065 -0.3048)
			(stroke
				(width 0.1)
				(type default)
			)
			(layer "F.Fab")
		)
		(fp_line
			(start -0.12065 -0.2794)
			(end 0.12065 -0.2794)
			(stroke
				(width 0.1)
				(type default)
			)
			(layer "F.Fab")
		)
		(fp_line
			(start 0.120396 0.2794)
			(end -0.12065 0.2794)
			(stroke
				(width 0.1)
				(type default)
			)
			(layer "F.Fab")
		)
		(fp_line
			(start -0.12065 0.2794)
			(end -0.12065 0.3048)
			(stroke
				(width 0.1)
				(type default)
			)
			(layer "F.Fab")
		)
		(fp_line
			(start 0.67945 0.3048)
			(end 0.120396 0.3048)
			(stroke
				(width 0.1)
				(type default)
			)
			(layer "F.Fab")
		)
		(fp_line
			(start 0.120396 0.3048)
			(end 0.120396 0.2794)
			(stroke
				(width 0.1)
				(type default)
			)
			(layer "F.Fab")
		)
		(fp_line
			(start -0.12065 0.3048)
			(end -0.67945 0.3048)
			(stroke
				(width 0.1)
				(type default)
			)
			(layer "F.Fab")
		)
		(fp_line
			(start -0.67945 0.3048)
			(end -0.67945 -0.305054)
			(stroke
				(width 0.1)
				(type default)
			)
			(layer "F.Fab")
		)
		(pad "1" smd circle
			(at -0.40005 0 90)
			(size 0 0)
			(layers "F.Cu" "F.Mask" "F.Paste")
			(net "FM_BIOS_USB_RECOVERY_R")
		)
		(pad "2" smd circle
			(at 0.40005 0 90)
			(size 0 0)
			(layers "F.Cu" "F.Mask" "F.Paste")
			(net "FM_BIOS_USB_RECOVERY")
		)
	)
	(footprint ""
		(layer "F.Cu")
		(at 63.861696 -164.276786 90)
		(property "Reference" "PC133"
			(at 0 0 90)
			(layer "F.SilkS")
			(hide yes)
			(effects
				(font
					(size 1.27 1.27)
				)
			)
		)
		(property "Value" ""
			(at 0 0 90)
			(layer "F.Fab")
			(effects
				(font
					(size 1.27 1.27)
				)
			)
		)
		(duplicate_pad_numbers_are_jumpers no)
		(fp_line
			(start 0.7874 -0.4064)
			(end 0.7874 0.4064)
			(stroke
				(width 0.1524)
				(type default)
			)
			(layer "F.SilkS")
		)
		(fp_line
			(start -0.7874 -0.4064)
			(end 0.7874 -0.4064)
			(stroke
				(width 0.1524)
				(type default)
			)
			(layer "F.SilkS")
		)
		(fp_line
			(start 0.7874 0.4064)
			(end -0.7874 0.4064)
			(stroke
				(width 0.1524)
				(type default)
			)
			(layer "F.SilkS")
		)
		(fp_line
			(start -0.7874 0.4064)
			(end -0.7874 -0.4064)
			(stroke
				(width 0.1524)
				(type default)
			)
			(layer "F.SilkS")
		)
		(fp_line
			(start -0.12065 -0.305054)
			(end -0.12065 -0.2794)
			(stroke
				(width 0.1)
				(type default)
			)
			(layer "F.Fab")
		)
		(fp_line
			(start -0.67945 -0.305054)
			(end -0.12065 -0.305054)
			(stroke
				(width 0.1)
				(type default)
			)
			(layer "F.Fab")
		)
		(fp_line
			(start 0.67945 -0.3048)
			(end 0.67945 0.3048)
			(stroke
				(width 0.1)
				(type default)
			)
			(layer "F.Fab")
		)
		(fp_line
			(start 0.12065 -0.3048)
			(end 0.67945 -0.3048)
			(stroke
				(width 0.1)
				(type default)
			)
			(layer "F.Fab")
		)
		(fp_line
			(start 0.12065 -0.2794)
			(end 0.12065 -0.3048)
			(stroke
				(width 0.1)
				(type default)
			)
			(layer "F.Fab")
		)
		(fp_line
			(start -0.12065 -0.2794)
			(end 0.12065 -0.2794)
			(stroke
				(width 0.1)
				(type default)
			)
			(layer "F.Fab")
		)
		(fp_line
			(start 0.120396 0.2794)
			(end -0.12065 0.2794)
			(stroke
				(width 0.1)
				(type default)
			)
			(layer "F.Fab")
		)
		(fp_line
			(start -0.12065 0.2794)
			(end -0.12065 0.3048)
			(stroke
				(width 0.1)
				(type default)
			)
			(layer "F.Fab")
		)
		(fp_line
			(start 0.67945 0.3048)
			(end 0.120396 0.3048)
			(stroke
				(width 0.1)
				(type default)
			)
			(layer "F.Fab")
		)
		(fp_line
			(start 0.120396 0.3048)
			(end 0.120396 0.2794)
			(stroke
				(width 0.1)
				(type default)
			)
			(layer "F.Fab")
		)
		(fp_line
			(start -0.12065 0.3048)
			(end -0.67945 0.3048)
			(stroke
				(width 0.1)
				(type default)
			)
			(layer "F.Fab")
		)
		(fp_line
			(start -0.67945 0.3048)
			(end -0.67945 -0.305054)
			(stroke
				(width 0.1)
				(type default)
			)
			(layer "F.Fab")
		)
		(pad "1" smd circle
			(at -0.40005 0 90)
			(size 0 0)
			(layers "F.Cu" "F.Mask" "F.Paste")
			(net "SW_PVDDCR_CPU0_P1_BOOT6_RC")
		)
		(pad "2" smd circle
			(at 0.40005 0 90)
			(size 0 0)
			(layers "F.Cu" "F.Mask" "F.Paste")
			(net "SW_PVDDCR_CPU0_P1_PH6")
		)
	)
	(footprint ""
		(layer "F.Cu")
		(at 12.860274 -390.822434 90)
		(property "Reference" "PC6610"
			(at 0 0 90)
			(layer "F.SilkS")
			(hide yes)
			(effects
				(font
					(size 1.27 1.27)
				)
			)
		)
		(property "Value" ""
			(at 0 0 90)
			(layer "F.Fab")
			(effects
				(font
					(size 1.27 1.27)
				)
			)
		)
		(duplicate_pad_numbers_are_jumpers no)
		(fp_line
			(start 0.7874 -0.4064)
			(end 0.7874 -0.185674)
			(stroke
				(width 0.1524)
				(type default)
			)
			(layer "F.SilkS")
		)
		(fp_line
			(start -0.7874 -0.4064)
			(end 0.7874 -0.4064)
			(stroke
				(width 0.1524)
				(type default)
			)
			(layer "F.SilkS")
		)
		(fp_line
			(start 0.540766 0.4064)
			(end -0.7874 0.4064)
			(stroke
				(width 0.1524)
				(type default)
			)
			(layer "F.SilkS")
		)
		(fp_line
			(start -0.7874 0.4064)
			(end -0.7874 -0.4064)
			(stroke
				(width 0.1524)
				(type default)
			)
			(layer "F.SilkS")
		)
		(fp_line
			(start -0.12065 -0.305054)
			(end -0.12065 -0.2794)
			(stroke
				(width 0.1)
				(type default)
			)
			(layer "F.Fab")
		)
		(fp_line
			(start -0.67945 -0.305054)
			(end -0.12065 -0.305054)
			(stroke
				(width 0.1)
				(type default)
			)
			(layer "F.Fab")
		)
		(fp_line
			(start 0.67945 -0.3048)
			(end 0.67945 0.3048)
			(stroke
				(width 0.1)
				(type default)
			)
			(layer "F.Fab")
		)
		(fp_line
			(start 0.12065 -0.3048)
			(end 0.67945 -0.3048)
			(stroke
				(width 0.1)
				(type default)
			)
			(layer "F.Fab")
		)
		(fp_line
			(start 0.12065 -0.2794)
			(end 0.12065 -0.3048)
			(stroke
				(width 0.1)
				(type default)
			)
			(layer "F.Fab")
		)
		(fp_line
			(start -0.12065 -0.2794)
			(end 0.12065 -0.2794)
			(stroke
				(width 0.1)
				(type default)
			)
			(layer "F.Fab")
		)
		(fp_line
			(start 0.120396 0.2794)
			(end -0.12065 0.2794)
			(stroke
				(width 0.1)
				(type default)
			)
			(layer "F.Fab")
		)
		(fp_line
			(start -0.12065 0.2794)
			(end -0.12065 0.3048)
			(stroke
				(width 0.1)
				(type default)
			)
			(layer "F.Fab")
		)
		(fp_line
			(start 0.67945 0.3048)
			(end 0.120396 0.3048)
			(stroke
				(width 0.1)
				(type default)
			)
			(layer "F.Fab")
		)
		(fp_line
			(start 0.120396 0.3048)
			(end 0.120396 0.2794)
			(stroke
				(width 0.1)
				(type default)
			)
			(layer "F.Fab")
		)
		(fp_line
			(start -0.12065 0.3048)
			(end -0.67945 0.3048)
			(stroke
				(width 0.1)
				(type default)
			)
			(layer "F.Fab")
		)
		(fp_line
			(start -0.67945 0.3048)
			(end -0.67945 -0.305054)
			(stroke
				(width 0.1)
				(type default)
			)
			(layer "F.Fab")
		)
		(pad "1" smd circle
			(at -0.40005 0 90)
			(size 0 0)
			(layers "F.Cu" "F.Mask" "F.Paste")
			(net "P0V9_RETIMER_CPU1_VCC1")
		)
		(pad "2" smd circle
			(at 0.40005 0 90)
			(size 0 0)
			(layers "F.Cu" "F.Mask" "F.Paste")
			(net "GND")
		)
	)
	(footprint ""
		(layer "F.Cu")
		(at 436.100474 -19.62277 -90)
		(property "Reference" "R40"
			(at 0 0 270)
			(layer "F.SilkS")
			(hide yes)
			(effects
				(font
					(size 1.27 1.27)
				)
			)
		)
		(property "Value" ""
			(at 0 0 270)
			(layer "F.Fab")
			(effects
				(font
					(size 1.27 1.27)
				)
			)
		)
		(duplicate_pad_numbers_are_jumpers no)
		(fp_line
			(start -0.7874 0.4064)
			(end -0.7874 -0.4064)
			(stroke
				(width 0.1524)
				(type default)
			)
			(layer "F.SilkS")
		)
		(fp_line
			(start 0.7874 0.4064)
			(end -0.7874 0.4064)
			(stroke
				(width 0.1524)
				(type default)
			)
			(layer "F.SilkS")
		)
		(fp_line
			(start -0.7874 -0.4064)
			(end 0.7874 -0.4064)
			(stroke
				(width 0.1524)
				(type default)
			)
			(layer "F.SilkS")
		)
		(fp_line
			(start 0.7874 -0.4064)
			(end 0.7874 0.4064)
			(stroke
				(width 0.1524)
				(type default)
			)
			(layer "F.SilkS")
		)
		(fp_line
			(start -0.67945 0.3048)
			(end -0.67945 -0.305054)
			(stroke
				(width 0.1)
				(type default)
			)
			(layer "F.Fab")
		)
		(fp_line
			(start -0.12065 0.3048)
			(end -0.67945 0.3048)
			(stroke
				(width 0.1)
				(type default)
			)
			(layer "F.Fab")
		)
		(fp_line
			(start 0.120396 0.3048)
			(end 0.120396 0.2794)
			(stroke
				(width 0.1)
				(type default)
			)
			(layer "F.Fab")
		)
		(fp_line
			(start 0.67945 0.3048)
			(end 0.120396 0.3048)
			(stroke
				(width 0.1)
				(type default)
			)
			(layer "F.Fab")
		)
		(fp_line
			(start -0.12065 0.2794)
			(end -0.12065 0.3048)
			(stroke
				(width 0.1)
				(type default)
			)
			(layer "F.Fab")
		)
		(fp_line
			(start 0.120396 0.2794)
			(end -0.12065 0.2794)
			(stroke
				(width 0.1)
				(type default)
			)
			(layer "F.Fab")
		)
		(fp_line
			(start -0.12065 -0.2794)
			(end 0.12065 -0.2794)
			(stroke
				(width 0.1)
				(type default)
			)
			(layer "F.Fab")
		)
		(fp_line
			(start 0.12065 -0.2794)
			(end 0.12065 -0.3048)
			(stroke
				(width 0.1)
				(type default)
			)
			(layer "F.Fab")
		)
		(fp_line
			(start 0.12065 -0.3048)
			(end 0.67945 -0.3048)
			(stroke
				(width 0.1)
				(type default)
			)
			(layer "F.Fab")
		)
		(fp_line
			(start 0.67945 -0.3048)
			(end 0.67945 0.3048)
			(stroke
				(width 0.1)
				(type default)
			)
			(layer "F.Fab")
		)
		(fp_line
			(start -0.67945 -0.305054)
			(end -0.12065 -0.305054)
			(stroke
				(width 0.1)
				(type default)
			)
			(layer "F.Fab")
		)
		(fp_line
			(start -0.12065 -0.305054)
			(end -0.12065 -0.2794)
			(stroke
				(width 0.1)
				(type default)
			)
			(layer "F.Fab")
		)
		(pad "1" smd circle
			(at -0.40005 0 270)
			(size 0 0)
			(layers "F.Cu" "F.Mask" "F.Paste")
			(net "OCP_SFF_ISO_BIF1_EN")
		)
		(pad "2" smd circle
			(at 0.40005 0 270)
			(size 0 0)
			(layers "F.Cu" "F.Mask" "F.Paste")
			(net "OCP_SFF_BIF1_R_N")
		)
	)
	(footprint ""
		(layer "F.Cu")
		(at 432.24704 -435.436772)
		(property "Reference" "Q70"
			(at -1.4224 -1.768348 0)
			(unlocked yes)
			(layer "F.SilkS")
			(effects
				(font
					(size 0.7874 0.5842)
					(thickness 0.1524)
				)
				(justify left)
			)
		)
		(property "Value" ""
			(at 0 0 0)
			(layer "F.Fab")
			(effects
				(font
					(size 1.27 1.27)
				)
			)
		)
		(duplicate_pad_numbers_are_jumpers no)
		(fp_line
			(start -1.332738 -1.100074)
			(end -0.4826 -1.100074)
			(stroke
				(width 0.1524)
				(type default)
			)
			(layer "F.SilkS")
		)
		(fp_line
			(start -1.332738 1.100074)
			(end -1.332738 -1.100074)
			(stroke
				(width 0.1524)
				(type default)
			)
			(layer "F.SilkS")
		)
		(fp_line
			(start -0.4826 -1.100074)
			(end 0 -0.541274)
			(stroke
				(width 0.1524)
				(type default)
			)
			(layer "F.SilkS")
		)
		(fp_line
			(start 0 -0.541274)
			(end 0.4826 -1.100074)
			(stroke
				(width 0.1524)
				(type default)
			)
			(layer "F.SilkS")
		)
		(fp_line
			(start 0.4826 -1.100074)
			(end 1.332738 -1.100074)
			(stroke
				(width 0.1524)
				(type default)
			)
			(layer "F.SilkS")
		)
		(fp_line
			(start 1.332738 -1.100074)
			(end 1.332738 1.100074)
			(stroke
				(width 0.1524)
				(type default)
			)
			(layer "F.SilkS")
		)
		(fp_line
			(start 1.332738 1.100074)
			(end -1.332738 1.100074)
			(stroke
				(width 0.1524)
				(type default)
			)
			(layer "F.SilkS")
		)
		(fp_poly
			(pts
				(xy -1.630934 -1.2446) (xy -2.356358 -1.544066) (xy -1.826514 -2.004568)
			)
			(stroke
				(width 0)
				(type default)
			)
			(fill yes)
			(layer "F.SilkS")
		)
		(fp_line
			(start -0.674878 -1.100074)
			(end 0.674878 -1.100074)
			(stroke
				(width 0.1)
				(type default)
			)
			(layer "F.Fab")
		)
		(fp_line
			(start -0.674878 1.100074)
			(end -0.674878 -1.100074)
			(stroke
				(width 0.1)
				(type default)
			)
			(layer "F.Fab")
		)
		(fp_line
			(start 0.674878 -1.100074)
			(end 0.674878 1.100074)
			(stroke
				(width 0.1)
				(type default)
			)
			(layer "F.Fab")
		)
		(fp_line
			(start 0.674878 1.100074)
			(end -0.674878 1.100074)
			(stroke
				(width 0.1)
				(type default)
			)
			(layer "F.Fab")
		)
		(fp_poly
			(pts
				(xy -2.2352 -0.298958) (xy -2.2352 -1.001014) (xy -1.533144 -0.649986)
			)
			(stroke
				(width 0)
				(type default)
			)
			(fill yes)
			(layer "F.Fab")
		)
		(pad "1" smd rect
			(at -0.94996 -0.649986 90)
			(size 0.4318 0.508)
			(layers "F.Cu" "F.Mask" "F.Paste")
			(net "GND")
		)
		(pad "2" smd rect
			(at -0.94996 0 90)
			(size 0.4318 0.508)
			(layers "F.Cu" "F.Mask" "F.Paste")
			(net "FM_SWB_BIC_READY_N")
		)
		(pad "3" smd rect
			(at -0.94996 0.649986 90)
			(size 0.4318 0.508)
			(layers "F.Cu" "F.Mask" "F.Paste")
			(net "FM_SWB_BIC_READY_ISO_N")
		)
		(pad "4" smd rect
			(at 0.94996 0.649986 90)
			(size 0.4318 0.508)
			(layers "F.Cu" "F.Mask" "F.Paste")
			(net "GND")
		)
		(pad "5" smd rect
			(at 0.94996 0 90)
			(size 0.4318 0.508)
			(layers "F.Cu" "F.Mask" "F.Paste")
			(net "FM_SWB_BIC_READY")
		)
		(pad "6" smd rect
			(at 0.94996 -0.649986 90)
			(size 0.4318 0.508)
			(layers "F.Cu" "F.Mask" "F.Paste")
			(net "FM_SWB_BIC_READY")
		)
	)
	(footprint ""
		(layer "F.Cu")
		(at 46.08068 -108.585 90)
		(property "Reference" "Q7002"
			(at -1.651 -2.25933 90)
			(unlocked yes)
			(layer "F.SilkS")
			(effects
				(font
					(size 0.7874 0.5842)
					(thickness 0.1524)
				)
				(justify left)
			)
		)
		(property "Value" ""
			(at 0 0 90)
			(layer "F.Fab")
			(effects
				(font
					(size 1.27 1.27)
				)
			)
		)
		(duplicate_pad_numbers_are_jumpers no)
		(fp_line
			(start 1.603248 -1.500124)
			(end 1.603248 1.500124)
			(stroke
				(width 0.1524)
				(type default)
			)
			(layer "F.SilkS")
		)
		(fp_line
			(start -1.603248 -1.500124)
			(end 1.603248 -1.500124)
			(stroke
				(width 0.1524)
				(type default)
			)
			(layer "F.SilkS")
		)
		(fp_line
			(start 1.603248 1.500124)
			(end -1.603248 1.500124)
			(stroke
				(width 0.1524)
				(type default)
			)
			(layer "F.SilkS")
		)
		(fp_line
			(start -1.603248 1.500124)
			(end -1.603248 -1.500124)
			(stroke
				(width 0.1524)
				(type default)
			)
			(layer "F.SilkS")
		)
		(fp_line
			(start 0.700024 -1.500124)
			(end -0.700024 -1.500124)
			(stroke
				(width 0.1)
				(type default)
			)
			(layer "F.Fab")
		)
		(fp_line
			(start -0.700024 -1.500124)
			(end -0.700024 -1.169924)
			(stroke
				(width 0.1)
				(type default)
			)
			(layer "F.Fab")
		)
		(fp_line
			(start -0.700024 -1.169924)
			(end -1.249934 -1.169924)
			(stroke
				(width 0.1)
				(type default)
			)
			(layer "F.Fab")
		)
		(fp_line
			(start -1.249934 -1.169924)
			(end -1.249934 -0.729996)
			(stroke
				(width 0.1)
				(type default)
			)
			(layer "F.Fab")
		)
		(fp_line
			(start -0.6985 -0.729996)
			(end -0.6985 0.729996)
			(stroke
				(width 0.1)
				(type default)
			)
			(layer "F.Fab")
		)
		(fp_line
			(start -1.249934 -0.729996)
			(end -0.6985 -0.729996)
			(stroke
				(width 0.1)
				(type default)
			)
			(layer "F.Fab")
		)
		(fp_line
			(start 1.249934 -0.219964)
			(end 0.700024 -0.219964)
			(stroke
				(width 0.1)
				(type default)
			)
			(layer "F.Fab")
		)
		(fp_line
			(start 0.700024 -0.219964)
			(end 0.700024 -1.500124)
			(stroke
				(width 0.1)
				(type default)
			)
			(layer "F.Fab")
		)
		(fp_line
			(start 1.249934 0.219964)
			(end 1.249934 -0.219964)
			(stroke
				(width 0.1)
				(type default)
			)
			(layer "F.Fab")
		)
		(fp_line
			(start 0.700024 0.219964)
			(end 1.249934 0.219964)
			(stroke
				(width 0.1)
				(type default)
			)
			(layer "F.Fab")
		)
		(fp_line
			(start -0.6985 0.729996)
			(end -1.249934 0.729996)
			(stroke
				(width 0.1)
				(type default)
			)
			(layer "F.Fab")
		)
		(fp_line
			(start -1.249934 0.729996)
			(end -1.249934 1.169924)
			(stroke
				(width 0.1)
				(type default)
			)
			(layer "F.Fab")
		)
		(fp_line
			(start -0.700024 1.169924)
			(end -0.700024 1.500124)
			(stroke
				(width 0.1)
				(type default)
			)
			(layer "F.Fab")
		)
		(fp_line
			(start -1.249934 1.169924)
			(end -0.700024 1.169924)
			(stroke
				(width 0.1)
				(type default)
			)
			(layer "F.Fab")
		)
		(fp_line
			(start 0.700024 1.500124)
			(end 0.700024 0.219964)
			(stroke
				(width 0.1)
				(type default)
			)
			(layer "F.Fab")
		)
		(fp_line
			(start -0.700024 1.500124)
			(end 0.700024 1.500124)
			(stroke
				(width 0.1)
				(type default)
			)
			(layer "F.Fab")
		)
		(fp_rect
			(start -0.700024 1.500124)
			(end 0.700024 -1.500124)
			(stroke
				(width 0)
				(type default)
			)
			(fill no)
			(layer "F.Fab")
		)
		(pad "D" smd rect
			(at 0.999998 0)
			(size 0.8128 0.9144)
			(layers "F.Cu" "F.Mask" "F.Paste")
			(net "P3V3_AUX_DSC_G2")
		)
		(pad "G" smd rect
			(at -0.999998 -0.94996)
			(size 0.8128 0.9144)
			(layers "F.Cu" "F.Mask" "F.Paste")
			(net "P3V3_AUX_DSC_G1")
		)
		(pad "S" smd rect
			(at -0.999998 0.94996)
			(size 0.8128 0.9144)
			(layers "F.Cu" "F.Mask" "F.Paste")
			(net "P3V3_AUX_DSC_S1")
		)
	)
	(footprint ""
		(layer "F.Cu")
		(at 136.962388 -385.09448 180)
		(property "Reference" "R894"
			(at 0 0 180)
			(layer "F.SilkS")
			(hide yes)
			(effects
				(font
					(size 1.27 1.27)
				)
			)
		)
		(property "Value" ""
			(at 0 0 180)
			(layer "F.Fab")
			(effects
				(font
					(size 1.27 1.27)
				)
			)
		)
		(duplicate_pad_numbers_are_jumpers no)
		(fp_line
			(start 0.7874 0.4064)
			(end -0.7874 0.4064)
			(stroke
				(width 0.1524)
				(type default)
			)
			(layer "F.SilkS")
		)
		(fp_line
			(start 0.7874 -0.4064)
			(end 0.7874 0.4064)
			(stroke
				(width 0.1524)
				(type default)
			)
			(layer "F.SilkS")
		)
		(fp_line
			(start -0.7874 0.4064)
			(end -0.7874 -0.4064)
			(stroke
				(width 0.1524)
				(type default)
			)
			(layer "F.SilkS")
		)
		(fp_line
			(start -0.7874 -0.4064)
			(end 0.7874 -0.4064)
			(stroke
				(width 0.1524)
				(type default)
			)
			(layer "F.SilkS")
		)
		(fp_line
			(start 0.67945 0.3048)
			(end 0.120396 0.3048)
			(stroke
				(width 0.1)
				(type default)
			)
			(layer "F.Fab")
		)
		(fp_line
			(start 0.67945 -0.3048)
			(end 0.67945 0.3048)
			(stroke
				(width 0.1)
				(type default)
			)
			(layer "F.Fab")
		)
		(fp_line
			(start 0.12065 -0.2794)
			(end 0.12065 -0.3048)
			(stroke
				(width 0.1)
				(type default)
			)
			(layer "F.Fab")
		)
		(fp_line
			(start 0.12065 -0.3048)
			(end 0.67945 -0.3048)
			(stroke
				(width 0.1)
				(type default)
			)
			(layer "F.Fab")
		)
		(fp_line
			(start 0.120396 0.3048)
			(end 0.120396 0.2794)
			(stroke
				(width 0.1)
				(type default)
			)
			(layer "F.Fab")
		)
		(fp_line
			(start 0.120396 0.2794)
			(end -0.12065 0.2794)
			(stroke
				(width 0.1)
				(type default)
			)
			(layer "F.Fab")
		)
		(fp_line
			(start -0.12065 0.3048)
			(end -0.67945 0.3048)
			(stroke
				(width 0.1)
				(type default)
			)
			(layer "F.Fab")
		)
		(fp_line
			(start -0.12065 0.2794)
			(end -0.12065 0.3048)
			(stroke
				(width 0.1)
				(type default)
			)
			(layer "F.Fab")
		)
		(fp_line
			(start -0.12065 -0.2794)
			(end 0.12065 -0.2794)
			(stroke
				(width 0.1)
				(type default)
			)
			(layer "F.Fab")
		)
		(fp_line
			(start -0.12065 -0.305054)
			(end -0.12065 -0.2794)
			(stroke
				(width 0.1)
				(type default)
			)
			(layer "F.Fab")
		)
		(fp_line
			(start -0.67945 0.3048)
			(end -0.67945 -0.305054)
			(stroke
				(width 0.1)
				(type default)
			)
			(layer "F.Fab")
		)
		(fp_line
			(start -0.67945 -0.305054)
			(end -0.12065 -0.305054)
			(stroke
				(width 0.1)
				(type default)
			)
			(layer "F.Fab")
		)
		(pad "1" smd rect
			(at -0.40005 0)
			(size 0.4572 0.508)
			(layers "F.Cu" "F.Mask" "F.Paste")
			(net "P1V8_CPU1_RT3_1A_1D")
		)
		(pad "2" smd rect
			(at 0.40005 0)
			(size 0.4572 0.508)
			(layers "F.Cu" "F.Mask" "F.Paste")
			(net "P1V8_CPU1_RT3_1A")
		)
	)
	(footprint ""
		(layer "F.Cu")
		(at 69.85 -56.642)
		(property "Reference" "U37"
			(at -3.023108 -2.564384 0)
			(unlocked yes)
			(layer "F.SilkS")
			(effects
				(font
					(size 0.7874 0.5842)
					(thickness 0.1524)
				)
				(justify left)
			)
		)
		(property "Value" ""
			(at 0 0 0)
			(layer "F.Fab")
			(effects
				(font
					(size 1.27 1.27)
				)
			)
		)
		(duplicate_pad_numbers_are_jumpers no)
		(fp_line
			(start -1.4986 -1.100074)
			(end 1.4986 -1.100074)
			(stroke
				(width 0.1524)
				(type default)
			)
			(layer "F.SilkS")
		)
		(fp_line
			(start -1.4986 1.100074)
			(end -1.4986 -1.100074)
			(stroke
				(width 0.1524)
				(type default)
			)
			(layer "F.SilkS")
		)
		(fp_line
			(start 1.4986 -1.100074)
			(end 1.4986 1.100074)
			(stroke
				(width 0.1524)
				(type default)
			)
			(layer "F.SilkS")
		)
		(fp_line
			(start 1.4986 1.100074)
			(end -1.4986 1.100074)
			(stroke
				(width 0.1524)
				(type default)
			)
			(layer "F.SilkS")
		)
		(fp_poly
			(pts
				(xy -2.20472 -0.338328) (xy -2.20472 -0.963168) (xy -1.651 -0.635)
			)
			(stroke
				(width 0)
				(type default)
			)
			(fill yes)
			(layer "F.SilkS")
		)
		(fp_line
			(start -0.67437 -1.100074)
			(end 0.67437 -1.100074)
			(stroke
				(width 0.1)
				(type default)
			)
			(layer "F.Fab")
		)
		(fp_line
			(start -0.67437 1.100074)
			(end -0.67437 -1.100074)
			(stroke
				(width 0.1)
				(type default)
			)
			(layer "F.Fab")
		)
		(fp_line
			(start 0.67437 -1.100074)
			(end 0.67437 1.100074)
			(stroke
				(width 0.1)
				(type default)
			)
			(layer "F.Fab")
		)
		(fp_line
			(start 0.67437 1.100074)
			(end -0.67437 1.100074)
			(stroke
				(width 0.1)
				(type default)
			)
			(layer "F.Fab")
		)
		(fp_poly
			(pts
				(xy -2.20472 -0.338328) (xy -2.20472 -0.963168) (xy -1.651 -0.635)
			)
			(stroke
				(width 0)
				(type default)
			)
			(fill yes)
			(layer "F.Fab")
		)
		(pad "1" smd rect
			(at -0.889 -0.649986)
			(size 1.016 0.381)
			(layers "F.Cu" "F.Mask" "F.Paste")
			(net "HP_LVC3_OCP_V3_2_PWRGD_R1")
		)
		(pad "2" smd rect
			(at -0.889 0)
			(size 1.016 0.381)
			(layers "F.Cu" "F.Mask" "F.Paste")
			(net "FM_OCP_V3_2_AUX_PWR_R_EN")
		)
		(pad "3" smd rect
			(at -0.889 0.649986)
			(size 1.016 0.381)
			(layers "F.Cu" "F.Mask" "F.Paste")
			(net "GND")
		)
		(pad "4" smd rect
			(at 0.889 0.649986)
			(size 1.016 0.381)
			(layers "F.Cu" "F.Mask" "F.Paste")
			(net "OCP_V3_2_AUX_PWR_EN_R2")
		)
		(pad "5" smd rect
			(at 0.889 -0.649986)
			(size 1.016 0.381)
			(layers "F.Cu" "F.Mask" "F.Paste")
			(net "P3V3_AUX")
		)
	)
	(footprint ""
		(layer "F.Cu")
		(at 244.327426 -283.853636)
		(property "Reference" "PC6502"
			(at 0 0 0)
			(layer "F.SilkS")
			(hide yes)
			(effects
				(font
					(size 1.27 1.27)
				)
			)
		)
		(property "Value" ""
			(at 0 0 0)
			(layer "F.Fab")
			(effects
				(font
					(size 1.27 1.27)
				)
			)
		)
		(duplicate_pad_numbers_are_jumpers no)
		(fp_line
			(start -1.524 -0.762)
			(end 1.524 -0.762)
			(stroke
				(width 0.1524)
				(type default)
			)
			(layer "F.SilkS")
		)
		(fp_line
			(start -1.524 0.762)
			(end -1.524 -0.762)
			(stroke
				(width 0.1524)
				(type default)
			)
			(layer "F.SilkS")
		)
		(fp_line
			(start 1.524 -0.762)
			(end 1.524 0.762)
			(stroke
				(width 0.1524)
				(type default)
			)
			(layer "F.SilkS")
		)
		(fp_line
			(start 1.524 0.762)
			(end -1.524 0.762)
			(stroke
				(width 0.1524)
				(type default)
			)
			(layer "F.SilkS")
		)
		(fp_line
			(start -1.1049 -0.724916)
			(end -1.1049 0.724916)
			(stroke
				(width 0.1)
				(type default)
			)
			(layer "F.Fab")
		)
		(fp_line
			(start -1.1049 0.724916)
			(end 1.1049 0.724916)
			(stroke
				(width 0.1)
				(type default)
			)
			(layer "F.Fab")
		)
		(fp_line
			(start 1.1049 -0.724916)
			(end -1.1049 -0.724916)
			(stroke
				(width 0.1)
				(type default)
			)
			(layer "F.Fab")
		)
		(fp_line
			(start 1.1049 0.724916)
			(end 1.1049 -0.724916)
			(stroke
				(width 0.1)
				(type default)
			)
			(layer "F.Fab")
		)
		(pad "1" smd rect
			(at -0.889 0 180)
			(size 1.016 1.27)
			(layers "F.Cu" "F.Mask" "F.Paste")
			(net "SW_P12V_AUX_P1V8_RETIMER_CPU0_FLT")
		)
		(pad "2" smd rect
			(at 0.889 0 180)
			(size 1.016 1.27)
			(layers "F.Cu" "F.Mask" "F.Paste")
			(net "GND")
		)
	)
	(footprint ""
		(layer "F.Cu")
		(at 384.113278 -140.202158 180)
		(property "Reference" "PR290"
			(at 0 0 180)
			(layer "F.SilkS")
			(hide yes)
			(effects
				(font
					(size 1.27 1.27)
				)
			)
		)
		(property "Value" ""
			(at 0 0 180)
			(layer "F.Fab")
			(effects
				(font
					(size 1.27 1.27)
				)
			)
		)
		(duplicate_pad_numbers_are_jumpers no)
		(fp_line
			(start 0.7874 0.4064)
			(end -0.7874 0.4064)
			(stroke
				(width 0.1524)
				(type default)
			)
			(layer "F.SilkS")
		)
		(fp_line
			(start 0.7874 -0.4064)
			(end 0.7874 0.4064)
			(stroke
				(width 0.1524)
				(type default)
			)
			(layer "F.SilkS")
		)
		(fp_line
			(start -0.7874 0.4064)
			(end -0.7874 -0.4064)
			(stroke
				(width 0.1524)
				(type default)
			)
			(layer "F.SilkS")
		)
		(fp_line
			(start -0.7874 -0.4064)
			(end 0.7874 -0.4064)
			(stroke
				(width 0.1524)
				(type default)
			)
			(layer "F.SilkS")
		)
		(fp_line
			(start 0.67945 0.3048)
			(end 0.120396 0.3048)
			(stroke
				(width 0.1)
				(type default)
			)
			(layer "F.Fab")
		)
		(fp_line
			(start 0.67945 -0.3048)
			(end 0.67945 0.3048)
			(stroke
				(width 0.1)
				(type default)
			)
			(layer "F.Fab")
		)
		(fp_line
			(start 0.12065 -0.2794)
			(end 0.12065 -0.3048)
			(stroke
				(width 0.1)
				(type default)
			)
			(layer "F.Fab")
		)
		(fp_line
			(start 0.12065 -0.3048)
			(end 0.67945 -0.3048)
			(stroke
				(width 0.1)
				(type default)
			)
			(layer "F.Fab")
		)
		(fp_line
			(start 0.120396 0.3048)
			(end 0.120396 0.2794)
			(stroke
				(width 0.1)
				(type default)
			)
			(layer "F.Fab")
		)
		(fp_line
			(start 0.120396 0.2794)
			(end -0.12065 0.2794)
			(stroke
				(width 0.1)
				(type default)
			)
			(layer "F.Fab")
		)
		(fp_line
			(start -0.12065 0.3048)
			(end -0.67945 0.3048)
			(stroke
				(width 0.1)
				(type default)
			)
			(layer "F.Fab")
		)
		(fp_line
			(start -0.12065 0.2794)
			(end -0.12065 0.3048)
			(stroke
				(width 0.1)
				(type default)
			)
			(layer "F.Fab")
		)
		(fp_line
			(start -0.12065 -0.2794)
			(end 0.12065 -0.2794)
			(stroke
				(width 0.1)
				(type default)
			)
			(layer "F.Fab")
		)
		(fp_line
			(start -0.12065 -0.305054)
			(end -0.12065 -0.2794)
			(stroke
				(width 0.1)
				(type default)
			)
			(layer "F.Fab")
		)
		(fp_line
			(start -0.67945 0.3048)
			(end -0.67945 -0.305054)
			(stroke
				(width 0.1)
				(type default)
			)
			(layer "F.Fab")
		)
		(fp_line
			(start -0.67945 -0.305054)
			(end -0.12065 -0.305054)
			(stroke
				(width 0.1)
				(type default)
			)
			(layer "F.Fab")
		)
		(pad "1" smd circle
			(at -0.40005 0 180)
			(size 0 0)
			(layers "F.Cu" "F.Mask" "F.Paste")
			(net "P5V_AUX")
		)
		(pad "2" smd circle
			(at 0.40005 0 180)
			(size 0 0)
			(layers "F.Cu" "F.Mask" "F.Paste")
			(net "PVDDCR_CPU0_P0_VMON")
		)
	)
	(footprint ""
		(layer "F.Cu")
		(at 22.987254 -35.8013 180)
		(property "Reference" "R1274"
			(at 0 0 180)
			(layer "F.SilkS")
			(hide yes)
			(effects
				(font
					(size 1.27 1.27)
				)
			)
		)
		(property "Value" ""
			(at 0 0 180)
			(layer "F.Fab")
			(effects
				(font
					(size 1.27 1.27)
				)
			)
		)
		(duplicate_pad_numbers_are_jumpers no)
		(fp_line
			(start 0.7874 0.4064)
			(end -0.7874 0.4064)
			(stroke
				(width 0.1524)
				(type default)
			)
			(layer "F.SilkS")
		)
		(fp_line
			(start 0.7874 -0.4064)
			(end 0.7874 0.4064)
			(stroke
				(width 0.1524)
				(type default)
			)
			(layer "F.SilkS")
		)
		(fp_line
			(start -0.7874 0.4064)
			(end -0.7874 -0.4064)
			(stroke
				(width 0.1524)
				(type default)
			)
			(layer "F.SilkS")
		)
		(fp_line
			(start -0.7874 -0.4064)
			(end 0.7874 -0.4064)
			(stroke
				(width 0.1524)
				(type default)
			)
			(layer "F.SilkS")
		)
		(fp_line
			(start 0.67945 0.3048)
			(end 0.120396 0.3048)
			(stroke
				(width 0.1)
				(type default)
			)
			(layer "F.Fab")
		)
		(fp_line
			(start 0.67945 -0.3048)
			(end 0.67945 0.3048)
			(stroke
				(width 0.1)
				(type default)
			)
			(layer "F.Fab")
		)
		(fp_line
			(start 0.12065 -0.2794)
			(end 0.12065 -0.3048)
			(stroke
				(width 0.1)
				(type default)
			)
			(layer "F.Fab")
		)
		(fp_line
			(start 0.12065 -0.3048)
			(end 0.67945 -0.3048)
			(stroke
				(width 0.1)
				(type default)
			)
			(layer "F.Fab")
		)
		(fp_line
			(start 0.120396 0.3048)
			(end 0.120396 0.2794)
			(stroke
				(width 0.1)
				(type default)
			)
			(layer "F.Fab")
		)
		(fp_line
			(start 0.120396 0.2794)
			(end -0.12065 0.2794)
			(stroke
				(width 0.1)
				(type default)
			)
			(layer "F.Fab")
		)
		(fp_line
			(start -0.12065 0.3048)
			(end -0.67945 0.3048)
			(stroke
				(width 0.1)
				(type default)
			)
			(layer "F.Fab")
		)
		(fp_line
			(start -0.12065 0.2794)
			(end -0.12065 0.3048)
			(stroke
				(width 0.1)
				(type default)
			)
			(layer "F.Fab")
		)
		(fp_line
			(start -0.12065 -0.2794)
			(end 0.12065 -0.2794)
			(stroke
				(width 0.1)
				(type default)
			)
			(layer "F.Fab")
		)
		(fp_line
			(start -0.12065 -0.305054)
			(end -0.12065 -0.2794)
			(stroke
				(width 0.1)
				(type default)
			)
			(layer "F.Fab")
		)
		(fp_line
			(start -0.67945 0.3048)
			(end -0.67945 -0.305054)
			(stroke
				(width 0.1)
				(type default)
			)
			(layer "F.Fab")
		)
		(fp_line
			(start -0.67945 -0.305054)
			(end -0.12065 -0.305054)
			(stroke
				(width 0.1)
				(type default)
			)
			(layer "F.Fab")
		)
		(pad "1" smd circle
			(at -0.40005 0 180)
			(size 0 0)
			(layers "F.Cu" "F.Mask" "F.Paste")
			(net "SMB_INA230_7_3V3AUX_SCL_R")
		)
		(pad "2" smd circle
			(at 0.40005 0 180)
			(size 0 0)
			(layers "F.Cu" "F.Mask" "F.Paste")
			(net "SMB_INA230_7_3V3AUX_SCL_R1")
		)
	)
	(footprint ""
		(layer "F.Cu")
		(at 53.53431 -337.403948)
		(property "Reference" "PL47"
			(at -3.115056 -15.887446 0)
			(unlocked yes)
			(layer "F.SilkS")
			(effects
				(font
					(size 0.7874 0.5842)
					(thickness 0.1524)
				)
				(justify left)
			)
		)
		(property "Value" ""
			(at 0 0 0)
			(layer "F.Fab")
			(effects
				(font
					(size 1.27 1.27)
				)
			)
		)
		(duplicate_pad_numbers_are_jumpers no)
		(fp_line
			(start -3.750056 -5.500116)
			(end -2.393442 -5.500116)
			(stroke
				(width 0.1524)
				(type default)
			)
			(layer "F.SilkS")
		)
		(fp_line
			(start -3.750056 5.500116)
			(end -3.750056 -5.500116)
			(stroke
				(width 0.1524)
				(type default)
			)
			(layer "F.SilkS")
		)
		(fp_line
			(start -2.393442 5.500116)
			(end -3.750056 5.500116)
			(stroke
				(width 0.1524)
				(type default)
			)
			(layer "F.SilkS")
		)
		(fp_line
			(start 2.393442 5.500116)
			(end 3.750056 5.500116)
			(stroke
				(width 0.1524)
				(type default)
			)
			(layer "F.SilkS")
		)
		(fp_line
			(start 3.750056 -5.500116)
			(end 2.393442 -5.500116)
			(stroke
				(width 0.1524)
				(type default)
			)
			(layer "F.SilkS")
		)
		(fp_line
			(start 3.750056 5.500116)
			(end 3.750056 -5.500116)
			(stroke
				(width 0.1524)
				(type default)
			)
			(layer "F.SilkS")
		)
		(fp_poly
			(pts
				(xy -3.9116 -4.249928) (xy -4.3434 -4.034028) (xy -4.3434 -4.465828)
			)
			(stroke
				(width 0)
				(type default)
			)
			(fill yes)
			(layer "F.SilkS")
		)
		(fp_line
			(start -3.750056 -5.500116)
			(end -3.750056 5.500116)
			(stroke
				(width 0.1)
				(type default)
			)
			(layer "F.Fab")
		)
		(fp_line
			(start -3.750056 5.500116)
			(end 3.750056 5.500116)
			(stroke
				(width 0.1)
				(type default)
			)
			(layer "F.Fab")
		)
		(fp_line
			(start 3.750056 -5.500116)
			(end -3.750056 -5.500116)
			(stroke
				(width 0.1)
				(type default)
			)
			(layer "F.Fab")
		)
		(fp_line
			(start 3.750056 5.500116)
			(end 3.750056 -5.500116)
			(stroke
				(width 0.1)
				(type default)
			)
			(layer "F.Fab")
		)
		(fp_poly
			(pts
				(xy -4.9276 -4.757928) (xy -4.9276 -3.741928) (xy -3.9116 -4.249928)
			)
			(stroke
				(width 0)
				(type default)
			)
			(fill yes)
			(layer "F.Fab")
		)
		(pad "1" smd rect
			(at 0 -4.249928 270)
			(size 2.413 4.5212)
			(layers "F.Cu" "F.Mask" "F.Paste")
			(net "SW_PVDDIO_P1_SW1")
		)
		(pad "2" smd rect
			(at 0 -1.175004 270)
			(size 1.3716 4.5212)
			(layers "F.Cu" "F.Mask" "F.Paste")
			(net "IND_PVDDIO_P1_CPL2")
		)
		(pad "3" smd rect
			(at 0 1.175004 270)
			(size 1.3716 4.5212)
			(layers "F.Cu" "F.Mask" "F.Paste")
			(net "GND")
		)
		(pad "4" smd rect
			(at 0 4.249928 270)
			(size 2.413 4.5212)
			(layers "F.Cu" "F.Mask" "F.Paste")
			(net "PVDDIO_P1")
		)
	)
	(footprint ""
		(layer "F.Cu")
		(at 177.45583 -157.508194 -90)
		(property "Reference" "R498"
			(at 0 0 270)
			(layer "F.SilkS")
			(hide yes)
			(effects
				(font
					(size 1.27 1.27)
				)
			)
		)
		(property "Value" ""
			(at 0 0 270)
			(layer "F.Fab")
			(effects
				(font
					(size 1.27 1.27)
				)
			)
		)
		(duplicate_pad_numbers_are_jumpers no)
		(fp_line
			(start -0.7874 0.4064)
			(end -0.7874 -0.4064)
			(stroke
				(width 0.1524)
				(type default)
			)
			(layer "F.SilkS")
		)
		(fp_line
			(start 0.7874 0.4064)
			(end -0.7874 0.4064)
			(stroke
				(width 0.1524)
				(type default)
			)
			(layer "F.SilkS")
		)
		(fp_line
			(start -0.7874 -0.4064)
			(end 0.7874 -0.4064)
			(stroke
				(width 0.1524)
				(type default)
			)
			(layer "F.SilkS")
		)
		(fp_line
			(start 0.7874 -0.4064)
			(end 0.7874 0.4064)
			(stroke
				(width 0.1524)
				(type default)
			)
			(layer "F.SilkS")
		)
		(fp_line
			(start -0.67945 0.3048)
			(end -0.67945 -0.305054)
			(stroke
				(width 0.1)
				(type default)
			)
			(layer "F.Fab")
		)
		(fp_line
			(start -0.12065 0.3048)
			(end -0.67945 0.3048)
			(stroke
				(width 0.1)
				(type default)
			)
			(layer "F.Fab")
		)
		(fp_line
			(start 0.120396 0.3048)
			(end 0.120396 0.2794)
			(stroke
				(width 0.1)
				(type default)
			)
			(layer "F.Fab")
		)
		(fp_line
			(start 0.67945 0.3048)
			(end 0.120396 0.3048)
			(stroke
				(width 0.1)
				(type default)
			)
			(layer "F.Fab")
		)
		(fp_line
			(start -0.12065 0.2794)
			(end -0.12065 0.3048)
			(stroke
				(width 0.1)
				(type default)
			)
			(layer "F.Fab")
		)
		(fp_line
			(start 0.120396 0.2794)
			(end -0.12065 0.2794)
			(stroke
				(width 0.1)
				(type default)
			)
			(layer "F.Fab")
		)
		(fp_line
			(start -0.12065 -0.2794)
			(end 0.12065 -0.2794)
			(stroke
				(width 0.1)
				(type default)
			)
			(layer "F.Fab")
		)
		(fp_line
			(start 0.12065 -0.2794)
			(end 0.12065 -0.3048)
			(stroke
				(width 0.1)
				(type default)
			)
			(layer "F.Fab")
		)
		(fp_line
			(start 0.12065 -0.3048)
			(end 0.67945 -0.3048)
			(stroke
				(width 0.1)
				(type default)
			)
			(layer "F.Fab")
		)
		(fp_line
			(start 0.67945 -0.3048)
			(end 0.67945 0.3048)
			(stroke
				(width 0.1)
				(type default)
			)
			(layer "F.Fab")
		)
		(fp_line
			(start -0.67945 -0.305054)
			(end -0.12065 -0.305054)
			(stroke
				(width 0.1)
				(type default)
			)
			(layer "F.Fab")
		)
		(fp_line
			(start -0.12065 -0.305054)
			(end -0.12065 -0.2794)
			(stroke
				(width 0.1)
				(type default)
			)
			(layer "F.Fab")
		)
		(pad "1" smd circle
			(at -0.40005 0 270)
			(size 0 0)
			(layers "F.Cu" "F.Mask" "F.Paste")
			(net "PVDD18_S5_P0")
		)
		(pad "2" smd circle
			(at 0.40005 0 270)
			(size 0 0)
			(layers "F.Cu" "F.Mask" "F.Paste")
			(net "SMB_CPU0_4_SDA")
		)
	)
	(footprint ""
		(layer "F.Cu")
		(at 276.181312 -351.368106 90)
		(property "Reference" "PR109"
			(at 0 0 90)
			(layer "F.SilkS")
			(hide yes)
			(effects
				(font
					(size 1.27 1.27)
				)
			)
		)
		(property "Value" ""
			(at 0 0 90)
			(layer "F.Fab")
			(effects
				(font
					(size 1.27 1.27)
				)
			)
		)
		(duplicate_pad_numbers_are_jumpers no)
		(fp_line
			(start 0.7874 -0.4064)
			(end 0.7874 0.4064)
			(stroke
				(width 0.1524)
				(type default)
			)
			(layer "F.SilkS")
		)
		(fp_line
			(start -0.7874 -0.4064)
			(end 0.7874 -0.4064)
			(stroke
				(width 0.1524)
				(type default)
			)
			(layer "F.SilkS")
		)
		(fp_line
			(start 0.7874 0.4064)
			(end -0.7874 0.4064)
			(stroke
				(width 0.1524)
				(type default)
			)
			(layer "F.SilkS")
		)
		(fp_line
			(start -0.7874 0.4064)
			(end -0.7874 -0.4064)
			(stroke
				(width 0.1524)
				(type default)
			)
			(layer "F.SilkS")
		)
		(fp_line
			(start -0.12065 -0.305054)
			(end -0.12065 -0.2794)
			(stroke
				(width 0.1)
				(type default)
			)
			(layer "F.Fab")
		)
		(fp_line
			(start -0.67945 -0.305054)
			(end -0.12065 -0.305054)
			(stroke
				(width 0.1)
				(type default)
			)
			(layer "F.Fab")
		)
		(fp_line
			(start 0.67945 -0.3048)
			(end 0.67945 0.3048)
			(stroke
				(width 0.1)
				(type default)
			)
			(layer "F.Fab")
		)
		(fp_line
			(start 0.12065 -0.3048)
			(end 0.67945 -0.3048)
			(stroke
				(width 0.1)
				(type default)
			)
			(layer "F.Fab")
		)
		(fp_line
			(start 0.12065 -0.2794)
			(end 0.12065 -0.3048)
			(stroke
				(width 0.1)
				(type default)
			)
			(layer "F.Fab")
		)
		(fp_line
			(start -0.12065 -0.2794)
			(end 0.12065 -0.2794)
			(stroke
				(width 0.1)
				(type default)
			)
			(layer "F.Fab")
		)
		(fp_line
			(start 0.120396 0.2794)
			(end -0.12065 0.2794)
			(stroke
				(width 0.1)
				(type default)
			)
			(layer "F.Fab")
		)
		(fp_line
			(start -0.12065 0.2794)
			(end -0.12065 0.3048)
			(stroke
				(width 0.1)
				(type default)
			)
			(layer "F.Fab")
		)
		(fp_line
			(start 0.67945 0.3048)
			(end 0.120396 0.3048)
			(stroke
				(width 0.1)
				(type default)
			)
			(layer "F.Fab")
		)
		(fp_line
			(start 0.120396 0.3048)
			(end 0.120396 0.2794)
			(stroke
				(width 0.1)
				(type default)
			)
			(layer "F.Fab")
		)
		(fp_line
			(start -0.12065 0.3048)
			(end -0.67945 0.3048)
			(stroke
				(width 0.1)
				(type default)
			)
			(layer "F.Fab")
		)
		(fp_line
			(start -0.67945 0.3048)
			(end -0.67945 -0.305054)
			(stroke
				(width 0.1)
				(type default)
			)
			(layer "F.Fab")
		)
		(pad "1" smd circle
			(at -0.40005 0 90)
			(size 0 0)
			(layers "F.Cu" "F.Mask" "F.Paste")
			(net "SW_PVDDIO_P0_BOOT4")
		)
		(pad "2" smd circle
			(at 0.40005 0 90)
			(size 0 0)
			(layers "F.Cu" "F.Mask" "F.Paste")
			(net "SW_PVDDIO_P0_BOOT4_R")
		)
	)
	(footprint ""
		(layer "F.Cu")
		(at 359.716578 -169.497756 90)
		(property "Reference" "PC568_C0P0_5"
			(at 0 0 90)
			(layer "F.SilkS")
			(hide yes)
			(effects
				(font
					(size 1.27 1.27)
				)
			)
		)
		(property "Value" ""
			(at 0 0 90)
			(layer "F.Fab")
			(effects
				(font
					(size 1.27 1.27)
				)
			)
		)
		(duplicate_pad_numbers_are_jumpers no)
		(fp_line
			(start 0.7874 -0.4064)
			(end 0.7874 0.4064)
			(stroke
				(width 0.1524)
				(type default)
			)
			(layer "F.SilkS")
		)
		(fp_line
			(start -0.7874 -0.4064)
			(end 0.7874 -0.4064)
			(stroke
				(width 0.1524)
				(type default)
			)
			(layer "F.SilkS")
		)
		(fp_line
			(start 0.7874 0.4064)
			(end -0.7874 0.4064)
			(stroke
				(width 0.1524)
				(type default)
			)
			(layer "F.SilkS")
		)
		(fp_line
			(start -0.7874 0.4064)
			(end -0.7874 -0.4064)
			(stroke
				(width 0.1524)
				(type default)
			)
			(layer "F.SilkS")
		)
		(fp_line
			(start -0.12065 -0.305054)
			(end -0.12065 -0.2794)
			(stroke
				(width 0.1)
				(type default)
			)
			(layer "F.Fab")
		)
		(fp_line
			(start -0.67945 -0.305054)
			(end -0.12065 -0.305054)
			(stroke
				(width 0.1)
				(type default)
			)
			(layer "F.Fab")
		)
		(fp_line
			(start 0.67945 -0.3048)
			(end 0.67945 0.3048)
			(stroke
				(width 0.1)
				(type default)
			)
			(layer "F.Fab")
		)
		(fp_line
			(start 0.12065 -0.3048)
			(end 0.67945 -0.3048)
			(stroke
				(width 0.1)
				(type default)
			)
			(layer "F.Fab")
		)
		(fp_line
			(start 0.12065 -0.2794)
			(end 0.12065 -0.3048)
			(stroke
				(width 0.1)
				(type default)
			)
			(layer "F.Fab")
		)
		(fp_line
			(start -0.12065 -0.2794)
			(end 0.12065 -0.2794)
			(stroke
				(width 0.1)
				(type default)
			)
			(layer "F.Fab")
		)
		(fp_line
			(start 0.120396 0.2794)
			(end -0.12065 0.2794)
			(stroke
				(width 0.1)
				(type default)
			)
			(layer "F.Fab")
		)
		(fp_line
			(start -0.12065 0.2794)
			(end -0.12065 0.3048)
			(stroke
				(width 0.1)
				(type default)
			)
			(layer "F.Fab")
		)
		(fp_line
			(start 0.67945 0.3048)
			(end 0.120396 0.3048)
			(stroke
				(width 0.1)
				(type default)
			)
			(layer "F.Fab")
		)
		(fp_line
			(start 0.120396 0.3048)
			(end 0.120396 0.2794)
			(stroke
				(width 0.1)
				(type default)
			)
			(layer "F.Fab")
		)
		(fp_line
			(start -0.12065 0.3048)
			(end -0.67945 0.3048)
			(stroke
				(width 0.1)
				(type default)
			)
			(layer "F.Fab")
		)
		(fp_line
			(start -0.67945 0.3048)
			(end -0.67945 -0.305054)
			(stroke
				(width 0.1)
				(type default)
			)
			(layer "F.Fab")
		)
		(pad "1" smd circle
			(at -0.40005 0 90)
			(size 0 0)
			(layers "F.Cu" "F.Mask" "F.Paste")
			(net "PVDDCR_CPU0_P0_PVCC")
		)
		(pad "2" smd circle
			(at 0.40005 0 90)
			(size 0 0)
			(layers "F.Cu" "F.Mask" "F.Paste")
			(net "GND")
		)
	)
	(footprint ""
		(layer "F.Cu")
		(at 421.169592 -175.851312 180)
		(property "Reference" "PR297"
			(at 0 0 180)
			(layer "F.SilkS")
			(hide yes)
			(effects
				(font
					(size 1.27 1.27)
				)
			)
		)
		(property "Value" ""
			(at 0 0 180)
			(layer "F.Fab")
			(effects
				(font
					(size 1.27 1.27)
				)
			)
		)
		(duplicate_pad_numbers_are_jumpers no)
		(fp_line
			(start 0.7874 0.4064)
			(end -0.7874 0.4064)
			(stroke
				(width 0.1524)
				(type default)
			)
			(layer "F.SilkS")
		)
		(fp_line
			(start 0.7874 -0.4064)
			(end 0.7874 0.4064)
			(stroke
				(width 0.1524)
				(type default)
			)
			(layer "F.SilkS")
		)
		(fp_line
			(start -0.7874 0.4064)
			(end -0.7874 -0.4064)
			(stroke
				(width 0.1524)
				(type default)
			)
			(layer "F.SilkS")
		)
		(fp_line
			(start -0.7874 -0.4064)
			(end 0.7874 -0.4064)
			(stroke
				(width 0.1524)
				(type default)
			)
			(layer "F.SilkS")
		)
		(fp_line
			(start 0.67945 0.3048)
			(end 0.120396 0.3048)
			(stroke
				(width 0.1)
				(type default)
			)
			(layer "F.Fab")
		)
		(fp_line
			(start 0.67945 -0.3048)
			(end 0.67945 0.3048)
			(stroke
				(width 0.1)
				(type default)
			)
			(layer "F.Fab")
		)
		(fp_line
			(start 0.12065 -0.2794)
			(end 0.12065 -0.3048)
			(stroke
				(width 0.1)
				(type default)
			)
			(layer "F.Fab")
		)
		(fp_line
			(start 0.12065 -0.3048)
			(end 0.67945 -0.3048)
			(stroke
				(width 0.1)
				(type default)
			)
			(layer "F.Fab")
		)
		(fp_line
			(start 0.120396 0.3048)
			(end 0.120396 0.2794)
			(stroke
				(width 0.1)
				(type default)
			)
			(layer "F.Fab")
		)
		(fp_line
			(start 0.120396 0.2794)
			(end -0.12065 0.2794)
			(stroke
				(width 0.1)
				(type default)
			)
			(layer "F.Fab")
		)
		(fp_line
			(start -0.12065 0.3048)
			(end -0.67945 0.3048)
			(stroke
				(width 0.1)
				(type default)
			)
			(layer "F.Fab")
		)
		(fp_line
			(start -0.12065 0.2794)
			(end -0.12065 0.3048)
			(stroke
				(width 0.1)
				(type default)
			)
			(layer "F.Fab")
		)
		(fp_line
			(start -0.12065 -0.2794)
			(end 0.12065 -0.2794)
			(stroke
				(width 0.1)
				(type default)
			)
			(layer "F.Fab")
		)
		(fp_line
			(start -0.12065 -0.305054)
			(end -0.12065 -0.2794)
			(stroke
				(width 0.1)
				(type default)
			)
			(layer "F.Fab")
		)
		(fp_line
			(start -0.67945 0.3048)
			(end -0.67945 -0.305054)
			(stroke
				(width 0.1)
				(type default)
			)
			(layer "F.Fab")
		)
		(fp_line
			(start -0.67945 -0.305054)
			(end -0.12065 -0.305054)
			(stroke
				(width 0.1)
				(type default)
			)
			(layer "F.Fab")
		)
		(pad "1" smd circle
			(at -0.40005 0 180)
			(size 0 0)
			(layers "F.Cu" "F.Mask" "F.Paste")
			(net "VSENSE_VSS_SENSE_A_P0")
		)
		(pad "2" smd circle
			(at 0.40005 0 180)
			(size 0 0)
			(layers "F.Cu" "F.Mask" "F.Paste")
			(net "GND")
		)
	)
	(footprint ""
		(layer "F.Cu")
		(at 190.754 -54.991 90)
		(property "Reference" "Q8001"
			(at -1.869186 3.81254 90)
			(unlocked yes)
			(layer "F.SilkS")
			(effects
				(font
					(size 0.7874 0.5842)
					(thickness 0.1524)
				)
				(justify left)
			)
		)
		(property "Value" ""
			(at 0 0 90)
			(layer "F.Fab")
			(effects
				(font
					(size 1.27 1.27)
				)
			)
		)
		(duplicate_pad_numbers_are_jumpers no)
		(fp_line
			(start 1.332738 -1.100074)
			(end 1.332738 1.100074)
			(stroke
				(width 0.1524)
				(type default)
			)
			(layer "F.SilkS")
		)
		(fp_line
			(start 0.4826 -1.100074)
			(end 1.332738 -1.100074)
			(stroke
				(width 0.1524)
				(type default)
			)
			(layer "F.SilkS")
		)
		(fp_line
			(start -0.4826 -1.100074)
			(end 0 -0.541274)
			(stroke
				(width 0.1524)
				(type default)
			)
			(layer "F.SilkS")
		)
		(fp_line
			(start -1.332738 -1.100074)
			(end -0.4826 -1.100074)
			(stroke
				(width 0.1524)
				(type default)
			)
			(layer "F.SilkS")
		)
		(fp_line
			(start 0 -0.541274)
			(end 0.4826 -1.100074)
			(stroke
				(width 0.1524)
				(type default)
			)
			(layer "F.SilkS")
		)
		(fp_line
			(start 1.332738 1.100074)
			(end -1.332738 1.100074)
			(stroke
				(width 0.1524)
				(type default)
			)
			(layer "F.SilkS")
		)
		(fp_line
			(start -1.332738 1.100074)
			(end -1.332738 -1.100074)
			(stroke
				(width 0.1524)
				(type default)
			)
			(layer "F.SilkS")
		)
		(fp_poly
			(pts
				(xy -2.323338 0.090932) (xy -2.490978 -0.590804) (xy -1.725422 -0.417576)
			)
			(stroke
				(width 0)
				(type default)
			)
			(fill yes)
			(layer "F.SilkS")
		)
		(fp_line
			(start 0.674878 -1.100074)
			(end 0.674878 1.100074)
			(stroke
				(width 0.1)
				(type default)
			)
			(layer "F.Fab")
		)
		(fp_line
			(start -0.674878 -1.100074)
			(end 0.674878 -1.100074)
			(stroke
				(width 0.1)
				(type default)
			)
			(layer "F.Fab")
		)
		(fp_line
			(start 0.674878 1.100074)
			(end -0.674878 1.100074)
			(stroke
				(width 0.1)
				(type default)
			)
			(layer "F.Fab")
		)
		(fp_line
			(start -0.674878 1.100074)
			(end -0.674878 -1.100074)
			(stroke
				(width 0.1)
				(type default)
			)
			(layer "F.Fab")
		)
		(fp_poly
			(pts
				(xy -2.2352 -0.298958) (xy -2.2352 -1.001014) (xy -1.533144 -0.649986)
			)
			(stroke
				(width 0)
				(type default)
			)
			(fill yes)
			(layer "F.Fab")
		)
		(pad "1" smd rect
			(at -0.94996 -0.649986 180)
			(size 0.4318 0.508)
			(layers "F.Cu" "F.Mask" "F.Paste")
			(net "GND")
		)
		(pad "2" smd rect
			(at -0.94996 0 180)
			(size 0.4318 0.508)
			(layers "F.Cu" "F.Mask" "F.Paste")
			(net "P12V_SCM_FAULT_R_N")
		)
		(pad "3" smd rect
			(at -0.94996 0.649986 180)
			(size 0.4318 0.508)
			(layers "F.Cu" "F.Mask" "F.Paste")
			(net "LED_P12V_SCM_FAULT_D2")
		)
		(pad "4" smd rect
			(at 0.94996 0.649986 180)
			(size 0.4318 0.508)
			(layers "F.Cu" "F.Mask" "F.Paste")
			(net "GND")
		)
		(pad "5" smd rect
			(at 0.94996 0 180)
			(size 0.4318 0.508)
			(layers "F.Cu" "F.Mask" "F.Paste")
			(net "LED_P12V_SCM_FAULT_D1")
		)
		(pad "6" smd rect
			(at 0.94996 -0.649986 180)
			(size 0.4318 0.508)
			(layers "F.Cu" "F.Mask" "F.Paste")
			(net "LED_P12V_SCM_FAULT_D1")
		)
	)
	(footprint ""
		(layer "F.Cu")
		(at 358.796082 -259.845048)
		(property "Reference" "C2132"
			(at 0 0 0)
			(layer "F.SilkS")
			(hide yes)
			(effects
				(font
					(size 1.27 1.27)
				)
			)
		)
		(property "Value" ""
			(at 0 0 0)
			(layer "F.Fab")
			(effects
				(font
					(size 1.27 1.27)
				)
			)
		)
		(duplicate_pad_numbers_are_jumpers no)
		(fp_line
			(start -0.7874 -0.4064)
			(end 0.7874 -0.4064)
			(stroke
				(width 0.1524)
				(type default)
			)
			(layer "F.SilkS")
		)
		(fp_line
			(start -0.7874 0.4064)
			(end -0.7874 -0.4064)
			(stroke
				(width 0.1524)
				(type default)
			)
			(layer "F.SilkS")
		)
		(fp_line
			(start 0.7874 -0.4064)
			(end 0.7874 0.4064)
			(stroke
				(width 0.1524)
				(type default)
			)
			(layer "F.SilkS")
		)
		(fp_line
			(start 0.7874 0.4064)
			(end -0.7874 0.4064)
			(stroke
				(width 0.1524)
				(type default)
			)
			(layer "F.SilkS")
		)
		(fp_line
			(start -0.67945 -0.305054)
			(end -0.12065 -0.305054)
			(stroke
				(width 0.1)
				(type default)
			)
			(layer "F.Fab")
		)
		(fp_line
			(start -0.67945 0.3048)
			(end -0.67945 -0.305054)
			(stroke
				(width 0.1)
				(type default)
			)
			(layer "F.Fab")
		)
		(fp_line
			(start -0.12065 -0.305054)
			(end -0.12065 -0.2794)
			(stroke
				(width 0.1)
				(type default)
			)
			(layer "F.Fab")
		)
		(fp_line
			(start -0.12065 -0.2794)
			(end 0.12065 -0.2794)
			(stroke
				(width 0.1)
				(type default)
			)
			(layer "F.Fab")
		)
		(fp_line
			(start -0.12065 0.2794)
			(end -0.12065 0.3048)
			(stroke
				(width 0.1)
				(type default)
			)
			(layer "F.Fab")
		)
		(fp_line
			(start -0.12065 0.3048)
			(end -0.67945 0.3048)
			(stroke
				(width 0.1)
				(type default)
			)
			(layer "F.Fab")
		)
		(fp_line
			(start 0.120396 0.2794)
			(end -0.12065 0.2794)
			(stroke
				(width 0.1)
				(type default)
			)
			(layer "F.Fab")
		)
		(fp_line
			(start 0.120396 0.3048)
			(end 0.120396 0.2794)
			(stroke
				(width 0.1)
				(type default)
			)
			(layer "F.Fab")
		)
		(fp_line
			(start 0.12065 -0.3048)
			(end 0.67945 -0.3048)
			(stroke
				(width 0.1)
				(type default)
			)
			(layer "F.Fab")
		)
		(fp_line
			(start 0.12065 -0.2794)
			(end 0.12065 -0.3048)
			(stroke
				(width 0.1)
				(type default)
			)
			(layer "F.Fab")
		)
		(fp_line
			(start 0.67945 -0.3048)
			(end 0.67945 0.3048)
			(stroke
				(width 0.1)
				(type default)
			)
			(layer "F.Fab")
		)
		(fp_line
			(start 0.67945 0.3048)
			(end 0.120396 0.3048)
			(stroke
				(width 0.1)
				(type default)
			)
			(layer "F.Fab")
		)
		(pad "1" smd circle
			(at -0.40005 0)
			(size 0 0)
			(layers "F.Cu" "F.Mask" "F.Paste")
			(net "PVDD11_S3_P0")
		)
		(pad "2" smd circle
			(at 0.40005 0)
			(size 0 0)
			(layers "F.Cu" "F.Mask" "F.Paste")
			(net "GND")
		)
	)
	(footprint ""
		(layer "F.Cu")
		(at 257.85953 -52.685442)
		(property "Reference" "PC2281"
			(at 0 0 0)
			(layer "F.SilkS")
			(hide yes)
			(effects
				(font
					(size 1.27 1.27)
				)
			)
		)
		(property "Value" ""
			(at 0 0 0)
			(layer "F.Fab")
			(effects
				(font
					(size 1.27 1.27)
				)
			)
		)
		(duplicate_pad_numbers_are_jumpers no)
		(fp_line
			(start -0.7874 -0.4064)
			(end 0.7874 -0.4064)
			(stroke
				(width 0.1524)
				(type default)
			)
			(layer "F.SilkS")
		)
		(fp_line
			(start -0.7874 0.4064)
			(end -0.7874 -0.4064)
			(stroke
				(width 0.1524)
				(type default)
			)
			(layer "F.SilkS")
		)
		(fp_line
			(start 0.7874 -0.4064)
			(end 0.7874 0.4064)
			(stroke
				(width 0.1524)
				(type default)
			)
			(layer "F.SilkS")
		)
		(fp_line
			(start 0.7874 0.4064)
			(end -0.7874 0.4064)
			(stroke
				(width 0.1524)
				(type default)
			)
			(layer "F.SilkS")
		)
		(fp_line
			(start -0.67945 -0.305054)
			(end -0.12065 -0.305054)
			(stroke
				(width 0.1)
				(type default)
			)
			(layer "F.Fab")
		)
		(fp_line
			(start -0.67945 0.3048)
			(end -0.67945 -0.305054)
			(stroke
				(width 0.1)
				(type default)
			)
			(layer "F.Fab")
		)
		(fp_line
			(start -0.12065 -0.305054)
			(end -0.12065 -0.2794)
			(stroke
				(width 0.1)
				(type default)
			)
			(layer "F.Fab")
		)
		(fp_line
			(start -0.12065 -0.2794)
			(end 0.12065 -0.2794)
			(stroke
				(width 0.1)
				(type default)
			)
			(layer "F.Fab")
		)
		(fp_line
			(start -0.12065 0.2794)
			(end -0.12065 0.3048)
			(stroke
				(width 0.1)
				(type default)
			)
			(layer "F.Fab")
		)
		(fp_line
			(start -0.12065 0.3048)
			(end -0.67945 0.3048)
			(stroke
				(width 0.1)
				(type default)
			)
			(layer "F.Fab")
		)
		(fp_line
			(start 0.120396 0.2794)
			(end -0.12065 0.2794)
			(stroke
				(width 0.1)
				(type default)
			)
			(layer "F.Fab")
		)
		(fp_line
			(start 0.120396 0.3048)
			(end 0.120396 0.2794)
			(stroke
				(width 0.1)
				(type default)
			)
			(layer "F.Fab")
		)
		(fp_line
			(start 0.12065 -0.3048)
			(end 0.67945 -0.3048)
			(stroke
				(width 0.1)
				(type default)
			)
			(layer "F.Fab")
		)
		(fp_line
			(start 0.12065 -0.2794)
			(end 0.12065 -0.3048)
			(stroke
				(width 0.1)
				(type default)
			)
			(layer "F.Fab")
		)
		(fp_line
			(start 0.67945 -0.3048)
			(end 0.67945 0.3048)
			(stroke
				(width 0.1)
				(type default)
			)
			(layer "F.Fab")
		)
		(fp_line
			(start 0.67945 0.3048)
			(end 0.120396 0.3048)
			(stroke
				(width 0.1)
				(type default)
			)
			(layer "F.Fab")
		)
		(pad "1" smd circle
			(at -0.40005 0)
			(size 0 0)
			(layers "F.Cu" "F.Mask" "F.Paste")
			(net "P12V_E1S_SS_0")
		)
		(pad "2" smd circle
			(at 0.40005 0)
			(size 0 0)
			(layers "F.Cu" "F.Mask" "F.Paste")
			(net "GND")
		)
	)
	(footprint ""
		(layer "F.Cu")
		(at 351.486216 -440.211972)
		(property "Reference" "R4547"
			(at 0 0 0)
			(layer "F.SilkS")
			(hide yes)
			(effects
				(font
					(size 1.27 1.27)
				)
			)
		)
		(property "Value" ""
			(at 0 0 0)
			(layer "F.Fab")
			(effects
				(font
					(size 1.27 1.27)
				)
			)
		)
		(duplicate_pad_numbers_are_jumpers no)
		(fp_line
			(start -0.7874 -0.4064)
			(end 0.7874 -0.4064)
			(stroke
				(width 0.1524)
				(type default)
			)
			(layer "F.SilkS")
		)
		(fp_line
			(start -0.7874 0.4064)
			(end -0.7874 -0.4064)
			(stroke
				(width 0.1524)
				(type default)
			)
			(layer "F.SilkS")
		)
		(fp_line
			(start 0.7874 -0.4064)
			(end 0.7874 0.4064)
			(stroke
				(width 0.1524)
				(type default)
			)
			(layer "F.SilkS")
		)
		(fp_line
			(start 0.7874 0.4064)
			(end -0.7874 0.4064)
			(stroke
				(width 0.1524)
				(type default)
			)
			(layer "F.SilkS")
		)
		(fp_line
			(start -0.67945 -0.305054)
			(end -0.12065 -0.305054)
			(stroke
				(width 0.1)
				(type default)
			)
			(layer "F.Fab")
		)
		(fp_line
			(start -0.67945 0.3048)
			(end -0.67945 -0.305054)
			(stroke
				(width 0.1)
				(type default)
			)
			(layer "F.Fab")
		)
		(fp_line
			(start -0.12065 -0.305054)
			(end -0.12065 -0.2794)
			(stroke
				(width 0.1)
				(type default)
			)
			(layer "F.Fab")
		)
		(fp_line
			(start -0.12065 -0.2794)
			(end 0.12065 -0.2794)
			(stroke
				(width 0.1)
				(type default)
			)
			(layer "F.Fab")
		)
		(fp_line
			(start -0.12065 0.2794)
			(end -0.12065 0.3048)
			(stroke
				(width 0.1)
				(type default)
			)
			(layer "F.Fab")
		)
		(fp_line
			(start -0.12065 0.3048)
			(end -0.67945 0.3048)
			(stroke
				(width 0.1)
				(type default)
			)
			(layer "F.Fab")
		)
		(fp_line
			(start 0.120396 0.2794)
			(end -0.12065 0.2794)
			(stroke
				(width 0.1)
				(type default)
			)
			(layer "F.Fab")
		)
		(fp_line
			(start 0.120396 0.3048)
			(end 0.120396 0.2794)
			(stroke
				(width 0.1)
				(type default)
			)
			(layer "F.Fab")
		)
		(fp_line
			(start 0.12065 -0.3048)
			(end 0.67945 -0.3048)
			(stroke
				(width 0.1)
				(type default)
			)
			(layer "F.Fab")
		)
		(fp_line
			(start 0.12065 -0.2794)
			(end 0.12065 -0.3048)
			(stroke
				(width 0.1)
				(type default)
			)
			(layer "F.Fab")
		)
		(fp_line
			(start 0.67945 -0.3048)
			(end 0.67945 0.3048)
			(stroke
				(width 0.1)
				(type default)
			)
			(layer "F.Fab")
		)
		(fp_line
			(start 0.67945 0.3048)
			(end 0.120396 0.3048)
			(stroke
				(width 0.1)
				(type default)
			)
			(layer "F.Fab")
		)
		(pad "1" smd circle
			(at -0.40005 0)
			(size 0 0)
			(layers "F.Cu" "F.Mask" "F.Paste")
			(net "P3V3_AUX")
		)
		(pad "2" smd circle
			(at 0.40005 0)
			(size 0 0)
			(layers "F.Cu" "F.Mask" "F.Paste")
			(net "SWB_HSC_EN")
		)
	)
	(footprint ""
		(layer "F.Cu")
		(at 340.527386 -416.899344 -90)
		(property "Reference" "C6526"
			(at 0 0 270)
			(layer "F.SilkS")
			(hide yes)
			(effects
				(font
					(size 1.27 1.27)
				)
			)
		)
		(property "Value" ""
			(at 0 0 270)
			(layer "F.Fab")
			(effects
				(font
					(size 1.27 1.27)
				)
			)
		)
		(duplicate_pad_numbers_are_jumpers no)
		(fp_line
			(start -0.299974 0.150114)
			(end -0.299974 -0.150114)
			(stroke
				(width 0.1)
				(type default)
			)
			(layer "F.Fab")
		)
		(fp_line
			(start 0.299974 0.150114)
			(end -0.299974 0.150114)
			(stroke
				(width 0.1)
				(type default)
			)
			(layer "F.Fab")
		)
		(fp_line
			(start -0.299974 -0.150114)
			(end 0.299974 -0.150114)
			(stroke
				(width 0.1)
				(type default)
			)
			(layer "F.Fab")
		)
		(fp_line
			(start 0.299974 -0.150114)
			(end 0.299974 0.150114)
			(stroke
				(width 0.1)
				(type default)
			)
			(layer "F.Fab")
		)
		(pad "1" smd rect
			(at -0.2667 0 270)
			(size 0.3048 0.381)
			(layers "F.Cu" "F.Mask" "F.Paste")
			(net "P5E_CPU0_P0_TX_BUF_C_DN<12>")
		)
		(pad "2" smd rect
			(at 0.2667 0 270)
			(size 0.3048 0.381)
			(layers "F.Cu" "F.Mask" "F.Paste")
			(net "P5E_CPU0_P0_TX_BUF_DN<12>")
		)
	)
	(footprint ""
		(layer "F.Cu")
		(at 463.18932 -37.549836)
		(property "Reference" "R1594"
			(at 0 0 0)
			(layer "F.SilkS")
			(hide yes)
			(effects
				(font
					(size 1.27 1.27)
				)
			)
		)
		(property "Value" ""
			(at 0 0 0)
			(layer "F.Fab")
			(effects
				(font
					(size 1.27 1.27)
				)
			)
		)
		(duplicate_pad_numbers_are_jumpers no)
		(fp_line
			(start -0.7874 -0.4064)
			(end 0.7874 -0.4064)
			(stroke
				(width 0.1524)
				(type default)
			)
			(layer "F.SilkS")
		)
		(fp_line
			(start -0.7874 0.4064)
			(end -0.7874 -0.4064)
			(stroke
				(width 0.1524)
				(type default)
			)
			(layer "F.SilkS")
		)
		(fp_line
			(start 0.7874 -0.4064)
			(end 0.7874 0.4064)
			(stroke
				(width 0.1524)
				(type default)
			)
			(layer "F.SilkS")
		)
		(fp_line
			(start 0.7874 0.4064)
			(end -0.7874 0.4064)
			(stroke
				(width 0.1524)
				(type default)
			)
			(layer "F.SilkS")
		)
		(fp_line
			(start -0.67945 -0.305054)
			(end -0.12065 -0.305054)
			(stroke
				(width 0.1)
				(type default)
			)
			(layer "F.Fab")
		)
		(fp_line
			(start -0.67945 0.3048)
			(end -0.67945 -0.305054)
			(stroke
				(width 0.1)
				(type default)
			)
			(layer "F.Fab")
		)
		(fp_line
			(start -0.12065 -0.305054)
			(end -0.12065 -0.2794)
			(stroke
				(width 0.1)
				(type default)
			)
			(layer "F.Fab")
		)
		(fp_line
			(start -0.12065 -0.2794)
			(end 0.12065 -0.2794)
			(stroke
				(width 0.1)
				(type default)
			)
			(layer "F.Fab")
		)
		(fp_line
			(start -0.12065 0.2794)
			(end -0.12065 0.3048)
			(stroke
				(width 0.1)
				(type default)
			)
			(layer "F.Fab")
		)
		(fp_line
			(start -0.12065 0.3048)
			(end -0.67945 0.3048)
			(stroke
				(width 0.1)
				(type default)
			)
			(layer "F.Fab")
		)
		(fp_line
			(start 0.120396 0.2794)
			(end -0.12065 0.2794)
			(stroke
				(width 0.1)
				(type default)
			)
			(layer "F.Fab")
		)
		(fp_line
			(start 0.120396 0.3048)
			(end 0.120396 0.2794)
			(stroke
				(width 0.1)
				(type default)
			)
			(layer "F.Fab")
		)
		(fp_line
			(start 0.12065 -0.3048)
			(end 0.67945 -0.3048)
			(stroke
				(width 0.1)
				(type default)
			)
			(layer "F.Fab")
		)
		(fp_line
			(start 0.12065 -0.2794)
			(end 0.12065 -0.3048)
			(stroke
				(width 0.1)
				(type default)
			)
			(layer "F.Fab")
		)
		(fp_line
			(start 0.67945 -0.3048)
			(end 0.67945 0.3048)
			(stroke
				(width 0.1)
				(type default)
			)
			(layer "F.Fab")
		)
		(fp_line
			(start 0.67945 0.3048)
			(end 0.120396 0.3048)
			(stroke
				(width 0.1)
				(type default)
			)
			(layer "F.Fab")
		)
		(pad "1" smd circle
			(at -0.40005 0)
			(size 0 0)
			(layers "F.Cu" "F.Mask" "F.Paste")
			(net "OCP_SFF_WAKE_BUFF_N")
		)
		(pad "2" smd circle
			(at 0.40005 0)
			(size 0 0)
			(layers "F.Cu" "F.Mask" "F.Paste")
			(net "OCP_SFF_WAKE_BUFF_R_N")
		)
	)
	(footprint ""
		(layer "F.Cu")
		(at 419.230302 -440.012836 90)
		(property "Reference" "R2829"
			(at 0 0 90)
			(layer "F.SilkS")
			(hide yes)
			(effects
				(font
					(size 1.27 1.27)
				)
			)
		)
		(property "Value" ""
			(at 0 0 90)
			(layer "F.Fab")
			(effects
				(font
					(size 1.27 1.27)
				)
			)
		)
		(duplicate_pad_numbers_are_jumpers no)
		(fp_line
			(start 0.7874 -0.4064)
			(end 0.7874 0.4064)
			(stroke
				(width 0.1524)
				(type default)
			)
			(layer "F.SilkS")
		)
		(fp_line
			(start -0.7874 -0.4064)
			(end 0.7874 -0.4064)
			(stroke
				(width 0.1524)
				(type default)
			)
			(layer "F.SilkS")
		)
		(fp_line
			(start 0.7874 0.4064)
			(end -0.7874 0.4064)
			(stroke
				(width 0.1524)
				(type default)
			)
			(layer "F.SilkS")
		)
		(fp_line
			(start -0.7874 0.4064)
			(end -0.7874 -0.4064)
			(stroke
				(width 0.1524)
				(type default)
			)
			(layer "F.SilkS")
		)
		(fp_line
			(start -0.12065 -0.305054)
			(end -0.12065 -0.2794)
			(stroke
				(width 0.1)
				(type default)
			)
			(layer "F.Fab")
		)
		(fp_line
			(start -0.67945 -0.305054)
			(end -0.12065 -0.305054)
			(stroke
				(width 0.1)
				(type default)
			)
			(layer "F.Fab")
		)
		(fp_line
			(start 0.67945 -0.3048)
			(end 0.67945 0.3048)
			(stroke
				(width 0.1)
				(type default)
			)
			(layer "F.Fab")
		)
		(fp_line
			(start 0.12065 -0.3048)
			(end 0.67945 -0.3048)
			(stroke
				(width 0.1)
				(type default)
			)
			(layer "F.Fab")
		)
		(fp_line
			(start 0.12065 -0.2794)
			(end 0.12065 -0.3048)
			(stroke
				(width 0.1)
				(type default)
			)
			(layer "F.Fab")
		)
		(fp_line
			(start -0.12065 -0.2794)
			(end 0.12065 -0.2794)
			(stroke
				(width 0.1)
				(type default)
			)
			(layer "F.Fab")
		)
		(fp_line
			(start 0.120396 0.2794)
			(end -0.12065 0.2794)
			(stroke
				(width 0.1)
				(type default)
			)
			(layer "F.Fab")
		)
		(fp_line
			(start -0.12065 0.2794)
			(end -0.12065 0.3048)
			(stroke
				(width 0.1)
				(type default)
			)
			(layer "F.Fab")
		)
		(fp_line
			(start 0.67945 0.3048)
			(end 0.120396 0.3048)
			(stroke
				(width 0.1)
				(type default)
			)
			(layer "F.Fab")
		)
		(fp_line
			(start 0.120396 0.3048)
			(end 0.120396 0.2794)
			(stroke
				(width 0.1)
				(type default)
			)
			(layer "F.Fab")
		)
		(fp_line
			(start -0.12065 0.3048)
			(end -0.67945 0.3048)
			(stroke
				(width 0.1)
				(type default)
			)
			(layer "F.Fab")
		)
		(fp_line
			(start -0.67945 0.3048)
			(end -0.67945 -0.305054)
			(stroke
				(width 0.1)
				(type default)
			)
			(layer "F.Fab")
		)
		(pad "1" smd circle
			(at -0.40005 0 90)
			(size 0 0)
			(layers "F.Cu" "F.Mask" "F.Paste")
			(net "RST_BMC_FROM_SWB_N")
		)
		(pad "2" smd circle
			(at 0.40005 0 90)
			(size 0 0)
			(layers "F.Cu" "F.Mask" "F.Paste")
			(net "GND")
		)
	)
	(footprint ""
		(layer "F.Cu")
		(at 421.01643 -109.231176 -90)
		(property "Reference" "R1137"
			(at 0 0 270)
			(layer "F.SilkS")
			(hide yes)
			(effects
				(font
					(size 1.27 1.27)
				)
			)
		)
		(property "Value" ""
			(at 0 0 270)
			(layer "F.Fab")
			(effects
				(font
					(size 1.27 1.27)
				)
			)
		)
		(duplicate_pad_numbers_are_jumpers no)
		(fp_line
			(start -0.7874 0.4064)
			(end -0.7874 -0.4064)
			(stroke
				(width 0.1524)
				(type default)
			)
			(layer "F.SilkS")
		)
		(fp_line
			(start 0.7874 0.4064)
			(end -0.7874 0.4064)
			(stroke
				(width 0.1524)
				(type default)
			)
			(layer "F.SilkS")
		)
		(fp_line
			(start -0.7874 -0.4064)
			(end 0.7874 -0.4064)
			(stroke
				(width 0.1524)
				(type default)
			)
			(layer "F.SilkS")
		)
		(fp_line
			(start 0.7874 -0.4064)
			(end 0.7874 0.4064)
			(stroke
				(width 0.1524)
				(type default)
			)
			(layer "F.SilkS")
		)
		(fp_line
			(start -0.67945 0.3048)
			(end -0.67945 -0.305054)
			(stroke
				(width 0.1)
				(type default)
			)
			(layer "F.Fab")
		)
		(fp_line
			(start -0.12065 0.3048)
			(end -0.67945 0.3048)
			(stroke
				(width 0.1)
				(type default)
			)
			(layer "F.Fab")
		)
		(fp_line
			(start 0.120396 0.3048)
			(end 0.120396 0.2794)
			(stroke
				(width 0.1)
				(type default)
			)
			(layer "F.Fab")
		)
		(fp_line
			(start 0.67945 0.3048)
			(end 0.120396 0.3048)
			(stroke
				(width 0.1)
				(type default)
			)
			(layer "F.Fab")
		)
		(fp_line
			(start -0.12065 0.2794)
			(end -0.12065 0.3048)
			(stroke
				(width 0.1)
				(type default)
			)
			(layer "F.Fab")
		)
		(fp_line
			(start 0.120396 0.2794)
			(end -0.12065 0.2794)
			(stroke
				(width 0.1)
				(type default)
			)
			(layer "F.Fab")
		)
		(fp_line
			(start -0.12065 -0.2794)
			(end 0.12065 -0.2794)
			(stroke
				(width 0.1)
				(type default)
			)
			(layer "F.Fab")
		)
		(fp_line
			(start 0.12065 -0.2794)
			(end 0.12065 -0.3048)
			(stroke
				(width 0.1)
				(type default)
			)
			(layer "F.Fab")
		)
		(fp_line
			(start 0.12065 -0.3048)
			(end 0.67945 -0.3048)
			(stroke
				(width 0.1)
				(type default)
			)
			(layer "F.Fab")
		)
		(fp_line
			(start 0.67945 -0.3048)
			(end 0.67945 0.3048)
			(stroke
				(width 0.1)
				(type default)
			)
			(layer "F.Fab")
		)
		(fp_line
			(start -0.67945 -0.305054)
			(end -0.12065 -0.305054)
			(stroke
				(width 0.1)
				(type default)
			)
			(layer "F.Fab")
		)
		(fp_line
			(start -0.12065 -0.305054)
			(end -0.12065 -0.2794)
			(stroke
				(width 0.1)
				(type default)
			)
			(layer "F.Fab")
		)
		(pad "1" smd circle
			(at -0.40005 0 270)
			(size 0 0)
			(layers "F.Cu" "F.Mask" "F.Paste")
			(net "HP_LVC3_OCP_V3_1_P12V_PWRGD")
		)
		(pad "2" smd circle
			(at 0.40005 0 270)
			(size 0 0)
			(layers "F.Cu" "F.Mask" "F.Paste")
			(net "P3V3_OCP_EN_1_R2")
		)
	)
	(footprint ""
		(layer "F.Cu")
		(at 308.198266 -430.240186 180)
		(property "Reference" "R4135"
			(at 0 0 180)
			(layer "F.SilkS")
			(hide yes)
			(effects
				(font
					(size 1.27 1.27)
				)
			)
		)
		(property "Value" ""
			(at 0 0 180)
			(layer "F.Fab")
			(effects
				(font
					(size 1.27 1.27)
				)
			)
		)
		(duplicate_pad_numbers_are_jumpers no)
		(fp_line
			(start 0.7874 0.4064)
			(end -0.7874 0.4064)
			(stroke
				(width 0.1524)
				(type default)
			)
			(layer "F.SilkS")
		)
		(fp_line
			(start 0.7874 -0.4064)
			(end 0.7874 0.4064)
			(stroke
				(width 0.1524)
				(type default)
			)
			(layer "F.SilkS")
		)
		(fp_line
			(start -0.7874 0.4064)
			(end -0.7874 -0.4064)
			(stroke
				(width 0.1524)
				(type default)
			)
			(layer "F.SilkS")
		)
		(fp_line
			(start -0.7874 -0.4064)
			(end 0.7874 -0.4064)
			(stroke
				(width 0.1524)
				(type default)
			)
			(layer "F.SilkS")
		)
		(fp_line
			(start 0.67945 0.3048)
			(end 0.120396 0.3048)
			(stroke
				(width 0.1)
				(type default)
			)
			(layer "F.Fab")
		)
		(fp_line
			(start 0.67945 -0.3048)
			(end 0.67945 0.3048)
			(stroke
				(width 0.1)
				(type default)
			)
			(layer "F.Fab")
		)
		(fp_line
			(start 0.12065 -0.2794)
			(end 0.12065 -0.3048)
			(stroke
				(width 0.1)
				(type default)
			)
			(layer "F.Fab")
		)
		(fp_line
			(start 0.12065 -0.3048)
			(end 0.67945 -0.3048)
			(stroke
				(width 0.1)
				(type default)
			)
			(layer "F.Fab")
		)
		(fp_line
			(start 0.120396 0.3048)
			(end 0.120396 0.2794)
			(stroke
				(width 0.1)
				(type default)
			)
			(layer "F.Fab")
		)
		(fp_line
			(start 0.120396 0.2794)
			(end -0.12065 0.2794)
			(stroke
				(width 0.1)
				(type default)
			)
			(layer "F.Fab")
		)
		(fp_line
			(start -0.12065 0.3048)
			(end -0.67945 0.3048)
			(stroke
				(width 0.1)
				(type default)
			)
			(layer "F.Fab")
		)
		(fp_line
			(start -0.12065 0.2794)
			(end -0.12065 0.3048)
			(stroke
				(width 0.1)
				(type default)
			)
			(layer "F.Fab")
		)
		(fp_line
			(start -0.12065 -0.2794)
			(end 0.12065 -0.2794)
			(stroke
				(width 0.1)
				(type default)
			)
			(layer "F.Fab")
		)
		(fp_line
			(start -0.12065 -0.305054)
			(end -0.12065 -0.2794)
			(stroke
				(width 0.1)
				(type default)
			)
			(layer "F.Fab")
		)
		(fp_line
			(start -0.67945 0.3048)
			(end -0.67945 -0.305054)
			(stroke
				(width 0.1)
				(type default)
			)
			(layer "F.Fab")
		)
		(fp_line
			(start -0.67945 -0.305054)
			(end -0.12065 -0.305054)
			(stroke
				(width 0.1)
				(type default)
			)
			(layer "F.Fab")
		)
		(pad "1" smd circle
			(at -0.40005 0 180)
			(size 0 0)
			(layers "F.Cu" "F.Mask" "F.Paste")
			(net "P3V3_AUX")
		)
		(pad "2" smd circle
			(at 0.40005 0 180)
			(size 0 0)
			(layers "F.Cu" "F.Mask" "F.Paste")
			(net "PRSNT_CABLE_GPU_A2_N")
		)
	)
	(footprint ""
		(layer "F.Cu")
		(at 144.74063 -98.355658)
		(property "Reference" "U246"
			(at 0.1651 -1.72847 0)
			(unlocked yes)
			(layer "F.SilkS")
			(effects
				(font
					(size 0.7874 0.5842)
					(thickness 0.1524)
				)
			)
		)
		(property "Value" ""
			(at 0 0 0)
			(layer "F.Fab")
			(effects
				(font
					(size 1.27 1.27)
				)
			)
		)
		(duplicate_pad_numbers_are_jumpers no)
		(fp_line
			(start -1.7272 1.1176)
			(end -1.7272 -1.1176)
			(stroke
				(width 0.1524)
				(type default)
			)
			(layer "F.SilkS")
		)
		(fp_line
			(start -0.254 -1.1176)
			(end -1.7272 -1.1176)
			(stroke
				(width 0.1524)
				(type default)
			)
			(layer "F.SilkS")
		)
		(fp_line
			(start 0 -0.7366)
			(end -0.254 -1.1176)
			(stroke
				(width 0.1524)
				(type default)
			)
			(layer "F.SilkS")
		)
		(fp_line
			(start 0.254 -1.1176)
			(end 0 -0.7366)
			(stroke
				(width 0.1524)
				(type default)
			)
			(layer "F.SilkS")
		)
		(fp_line
			(start 1.7272 -1.1176)
			(end 0.254 -1.1176)
			(stroke
				(width 0.1524)
				(type default)
			)
			(layer "F.SilkS")
		)
		(fp_line
			(start 1.7272 -1.1176)
			(end 1.7272 1.1176)
			(stroke
				(width 0.1524)
				(type default)
			)
			(layer "F.SilkS")
		)
		(fp_line
			(start 1.7272 1.1176)
			(end -1.7272 1.1176)
			(stroke
				(width 0.1524)
				(type default)
			)
			(layer "F.SilkS")
		)
		(fp_poly
			(pts
				(xy -2.7178 -1.030986) (xy -1.9558 -0.649986) (xy -2.7178 -0.268986)
			)
			(stroke
				(width 0)
				(type default)
			)
			(fill yes)
			(layer "F.SilkS")
		)
		(fp_line
			(start -1.5748 -1.1176)
			(end -1.5748 1.1176)
			(stroke
				(width 0.1)
				(type default)
			)
			(layer "F.Fab")
		)
		(fp_line
			(start -1.5748 1.1176)
			(end 1.5748 1.1176)
			(stroke
				(width 0.1)
				(type default)
			)
			(layer "F.Fab")
		)
		(fp_line
			(start 1.5748 -1.1176)
			(end -1.5748 -1.1176)
			(stroke
				(width 0.1)
				(type default)
			)
			(layer "F.Fab")
		)
		(fp_line
			(start 1.5748 1.1176)
			(end 1.5748 -1.1176)
			(stroke
				(width 0.1)
				(type default)
			)
			(layer "F.Fab")
		)
		(fp_poly
			(pts
				(xy -1.9558 -0.649986) (xy -2.7178 -0.268986) (xy -2.7178 -1.030986)
			)
			(stroke
				(width 0)
				(type default)
			)
			(fill yes)
			(layer "F.Fab")
		)
		(pad "1" smd rect
			(at -0.999998 -0.649986 270)
			(size 0.3556 1.1176)
			(layers "F.Cu" "F.Mask" "F.Paste")
			(net "OCP_V3_2_NOT_PRSNT_RBT_ARB_IN")
		)
		(pad "2" smd rect
			(at -0.999998 0 270)
			(size 0.3556 1.1176)
			(layers "F.Cu" "F.Mask" "F.Paste")
			(net "GND")
		)
		(pad "3" smd rect
			(at -0.999998 0.649986 270)
			(size 0.3556 1.1176)
			(layers "F.Cu" "F.Mask" "F.Paste")
			(net "OCP_V3_2_RBT_ARB_OUT")
		)
		(pad "4" smd rect
			(at 0.999998 0.649986 270)
			(size 0.3556 1.1176)
			(layers "F.Cu" "F.Mask" "F.Paste")
			(net "OCP_SFF_RBT_ARB_IN_MUX1")
		)
		(pad "5" smd rect
			(at 0.999998 0 270)
			(size 0.3556 1.1176)
			(layers "F.Cu" "F.Mask" "F.Paste")
			(net "P3V3_AUX")
		)
		(pad "6" smd rect
			(at 0.999998 -0.649986 270)
			(size 0.3556 1.1176)
			(layers "F.Cu" "F.Mask" "F.Paste")
			(net "OCP_V3_2_PRSNT_ALL_R1_N")
		)
	)
	(footprint ""
		(layer "F.Cu")
		(at 123.35637 -36.675568 180)
		(property "Reference" "C6023"
			(at 0 0 180)
			(layer "F.SilkS")
			(hide yes)
			(effects
				(font
					(size 1.27 1.27)
				)
			)
		)
		(property "Value" ""
			(at 0 0 180)
			(layer "F.Fab")
			(effects
				(font
					(size 1.27 1.27)
				)
			)
		)
		(duplicate_pad_numbers_are_jumpers no)
		(fp_line
			(start 0.7874 0.4064)
			(end -0.7874 0.4064)
			(stroke
				(width 0.1524)
				(type default)
			)
			(layer "F.SilkS")
		)
		(fp_line
			(start 0.7874 -0.4064)
			(end 0.7874 0.4064)
			(stroke
				(width 0.1524)
				(type default)
			)
			(layer "F.SilkS")
		)
		(fp_line
			(start -0.7874 0.4064)
			(end -0.7874 -0.4064)
			(stroke
				(width 0.1524)
				(type default)
			)
			(layer "F.SilkS")
		)
		(fp_line
			(start -0.7874 -0.4064)
			(end 0.7874 -0.4064)
			(stroke
				(width 0.1524)
				(type default)
			)
			(layer "F.SilkS")
		)
		(fp_line
			(start 0.6858 0.3048)
			(end 0.1016 0.3048)
			(stroke
				(width 0.1)
				(type default)
			)
			(layer "F.Fab")
		)
		(fp_line
			(start 0.6858 -0.3048)
			(end 0.6858 0.3048)
			(stroke
				(width 0.1)
				(type default)
			)
			(layer "F.Fab")
		)
		(fp_line
			(start 0.1016 0.3048)
			(end 0.1016 0.2794)
			(stroke
				(width 0.1)
				(type default)
			)
			(layer "F.Fab")
		)
		(fp_line
			(start 0.1016 0.2794)
			(end -0.1016 0.2794)
			(stroke
				(width 0.1)
				(type default)
			)
			(layer "F.Fab")
		)
		(fp_line
			(start 0.1016 -0.2794)
			(end 0.1016 -0.3048)
			(stroke
				(width 0.1)
				(type default)
			)
			(layer "F.Fab")
		)
		(fp_line
			(start 0.1016 -0.3048)
			(end 0.6858 -0.3048)
			(stroke
				(width 0.1)
				(type default)
			)
			(layer "F.Fab")
		)
		(fp_line
			(start -0.1016 0.3048)
			(end -0.6858 0.3048)
			(stroke
				(width 0.1)
				(type default)
			)
			(layer "F.Fab")
		)
		(fp_line
			(start -0.1016 0.2794)
			(end -0.1016 0.3048)
			(stroke
				(width 0.1)
				(type default)
			)
			(layer "F.Fab")
		)
		(fp_line
			(start -0.1016 -0.2794)
			(end 0.1016 -0.2794)
			(stroke
				(width 0.1)
				(type default)
			)
			(layer "F.Fab")
		)
		(fp_line
			(start -0.1016 -0.3048)
			(end -0.1016 -0.2794)
			(stroke
				(width 0.1)
				(type default)
			)
			(layer "F.Fab")
		)
		(fp_line
			(start -0.6858 0.3048)
			(end -0.6858 -0.3048)
			(stroke
				(width 0.1)
				(type default)
			)
			(layer "F.Fab")
		)
		(fp_line
			(start -0.6858 -0.3048)
			(end -0.1016 -0.3048)
			(stroke
				(width 0.1)
				(type default)
			)
			(layer "F.Fab")
		)
		(pad "1" smd rect
			(at -0.40005 0)
			(size 0.4572 0.508)
			(layers "F.Cu" "F.Mask" "F.Paste")
			(net "USB3_CPU0_BMC_HUB1_TX_DP")
		)
		(pad "2" smd rect
			(at 0.40005 0)
			(size 0.4572 0.508)
			(layers "F.Cu" "F.Mask" "F.Paste")
			(net "USB3_CPU0_BMC_TX_BUF_C_DP")
		)
	)
	(footprint ""
		(layer "F.Cu")
		(at 159.182562 -343.327736 90)
		(property "Reference" "PR384"
			(at 0 0 90)
			(layer "F.SilkS")
			(hide yes)
			(effects
				(font
					(size 1.27 1.27)
				)
			)
		)
		(property "Value" ""
			(at 0 0 90)
			(layer "F.Fab")
			(effects
				(font
					(size 1.27 1.27)
				)
			)
		)
		(duplicate_pad_numbers_are_jumpers no)
		(fp_line
			(start 0.7874 -0.4064)
			(end 0.7874 0.4064)
			(stroke
				(width 0.1524)
				(type default)
			)
			(layer "F.SilkS")
		)
		(fp_line
			(start -0.7874 -0.4064)
			(end 0.7874 -0.4064)
			(stroke
				(width 0.1524)
				(type default)
			)
			(layer "F.SilkS")
		)
		(fp_line
			(start 0.7874 0.4064)
			(end -0.7874 0.4064)
			(stroke
				(width 0.1524)
				(type default)
			)
			(layer "F.SilkS")
		)
		(fp_line
			(start -0.7874 0.4064)
			(end -0.7874 -0.4064)
			(stroke
				(width 0.1524)
				(type default)
			)
			(layer "F.SilkS")
		)
		(fp_line
			(start -0.12065 -0.305054)
			(end -0.12065 -0.2794)
			(stroke
				(width 0.1)
				(type default)
			)
			(layer "F.Fab")
		)
		(fp_line
			(start -0.67945 -0.305054)
			(end -0.12065 -0.305054)
			(stroke
				(width 0.1)
				(type default)
			)
			(layer "F.Fab")
		)
		(fp_line
			(start 0.67945 -0.3048)
			(end 0.67945 0.3048)
			(stroke
				(width 0.1)
				(type default)
			)
			(layer "F.Fab")
		)
		(fp_line
			(start 0.12065 -0.3048)
			(end 0.67945 -0.3048)
			(stroke
				(width 0.1)
				(type default)
			)
			(layer "F.Fab")
		)
		(fp_line
			(start 0.12065 -0.2794)
			(end 0.12065 -0.3048)
			(stroke
				(width 0.1)
				(type default)
			)
			(layer "F.Fab")
		)
		(fp_line
			(start -0.12065 -0.2794)
			(end 0.12065 -0.2794)
			(stroke
				(width 0.1)
				(type default)
			)
			(layer "F.Fab")
		)
		(fp_line
			(start 0.120396 0.2794)
			(end -0.12065 0.2794)
			(stroke
				(width 0.1)
				(type default)
			)
			(layer "F.Fab")
		)
		(fp_line
			(start -0.12065 0.2794)
			(end -0.12065 0.3048)
			(stroke
				(width 0.1)
				(type default)
			)
			(layer "F.Fab")
		)
		(fp_line
			(start 0.67945 0.3048)
			(end 0.120396 0.3048)
			(stroke
				(width 0.1)
				(type default)
			)
			(layer "F.Fab")
		)
		(fp_line
			(start 0.120396 0.3048)
			(end 0.120396 0.2794)
			(stroke
				(width 0.1)
				(type default)
			)
			(layer "F.Fab")
		)
		(fp_line
			(start -0.12065 0.3048)
			(end -0.67945 0.3048)
			(stroke
				(width 0.1)
				(type default)
			)
			(layer "F.Fab")
		)
		(fp_line
			(start -0.67945 0.3048)
			(end -0.67945 -0.305054)
			(stroke
				(width 0.1)
				(type default)
			)
			(layer "F.Fab")
		)
		(pad "1" smd circle
			(at -0.40005 0 90)
			(size 0 0)
			(layers "F.Cu" "F.Mask" "F.Paste")
			(net "VSENSE_PVDD11_S3_P1_DP")
		)
		(pad "2" smd circle
			(at 0.40005 0 90)
			(size 0 0)
			(layers "F.Cu" "F.Mask" "F.Paste")
			(net "VSENSE_PVDD11_S3_P1_R")
		)
	)
	(footprint ""
		(layer "F.Cu")
		(at 401.507198 -174.505874 -90)
		(property "Reference" "PC579"
			(at 0 0 270)
			(layer "F.SilkS")
			(hide yes)
			(effects
				(font
					(size 1.27 1.27)
				)
			)
		)
		(property "Value" ""
			(at 0 0 270)
			(layer "F.Fab")
			(effects
				(font
					(size 1.27 1.27)
				)
			)
		)
		(duplicate_pad_numbers_are_jumpers no)
		(fp_line
			(start -0.7874 0.4064)
			(end -0.7874 -0.4064)
			(stroke
				(width 0.1524)
				(type default)
			)
			(layer "F.SilkS")
		)
		(fp_line
			(start -0.322326 0.4064)
			(end -0.7874 0.4064)
			(stroke
				(width 0.1524)
				(type default)
			)
			(layer "F.SilkS")
		)
		(fp_line
			(start 0.7874 0.4064)
			(end 0.515874 0.4064)
			(stroke
				(width 0.1524)
				(type default)
			)
			(layer "F.SilkS")
		)
		(fp_line
			(start -0.7874 -0.4064)
			(end 0.7874 -0.4064)
			(stroke
				(width 0.1524)
				(type default)
			)
			(layer "F.SilkS")
		)
		(fp_line
			(start 0.7874 -0.4064)
			(end 0.7874 0.4064)
			(stroke
				(width 0.1524)
				(type default)
			)
			(layer "F.SilkS")
		)
		(fp_line
			(start -0.67945 0.3048)
			(end -0.67945 -0.305054)
			(stroke
				(width 0.1)
				(type default)
			)
			(layer "F.Fab")
		)
		(fp_line
			(start -0.12065 0.3048)
			(end -0.67945 0.3048)
			(stroke
				(width 0.1)
				(type default)
			)
			(layer "F.Fab")
		)
		(fp_line
			(start 0.120396 0.3048)
			(end 0.120396 0.2794)
			(stroke
				(width 0.1)
				(type default)
			)
			(layer "F.Fab")
		)
		(fp_line
			(start 0.67945 0.3048)
			(end 0.120396 0.3048)
			(stroke
				(width 0.1)
				(type default)
			)
			(layer "F.Fab")
		)
		(fp_line
			(start -0.12065 0.2794)
			(end -0.12065 0.3048)
			(stroke
				(width 0.1)
				(type default)
			)
			(layer "F.Fab")
		)
		(fp_line
			(start 0.120396 0.2794)
			(end -0.12065 0.2794)
			(stroke
				(width 0.1)
				(type default)
			)
			(layer "F.Fab")
		)
		(fp_line
			(start -0.12065 -0.2794)
			(end 0.12065 -0.2794)
			(stroke
				(width 0.1)
				(type default)
			)
			(layer "F.Fab")
		)
		(fp_line
			(start 0.12065 -0.2794)
			(end 0.12065 -0.3048)
			(stroke
				(width 0.1)
				(type default)
			)
			(layer "F.Fab")
		)
		(fp_line
			(start 0.12065 -0.3048)
			(end 0.67945 -0.3048)
			(stroke
				(width 0.1)
				(type default)
			)
			(layer "F.Fab")
		)
		(fp_line
			(start 0.67945 -0.3048)
			(end 0.67945 0.3048)
			(stroke
				(width 0.1)
				(type default)
			)
			(layer "F.Fab")
		)
		(fp_line
			(start -0.67945 -0.305054)
			(end -0.12065 -0.305054)
			(stroke
				(width 0.1)
				(type default)
			)
			(layer "F.Fab")
		)
		(fp_line
			(start -0.12065 -0.305054)
			(end -0.12065 -0.2794)
			(stroke
				(width 0.1)
				(type default)
			)
			(layer "F.Fab")
		)
		(pad "1" smd circle
			(at -0.40005 0 270)
			(size 0 0)
			(layers "F.Cu" "F.Mask" "F.Paste")
			(net "PVDDCR_SOC_P0_VCC1")
		)
		(pad "2" smd circle
			(at 0.40005 0 270)
			(size 0 0)
			(layers "F.Cu" "F.Mask" "F.Paste")
			(net "GND")
		)
	)
	(footprint ""
		(layer "F.Cu")
		(at 435.91226 -92.700348)
		(property "Reference" "C2027"
			(at 0 0 0)
			(layer "F.SilkS")
			(hide yes)
			(effects
				(font
					(size 1.27 1.27)
				)
			)
		)
		(property "Value" ""
			(at 0 0 0)
			(layer "F.Fab")
			(effects
				(font
					(size 1.27 1.27)
				)
			)
		)
		(duplicate_pad_numbers_are_jumpers no)
		(fp_line
			(start -0.7874 -0.4064)
			(end 0.7874 -0.4064)
			(stroke
				(width 0.1524)
				(type default)
			)
			(layer "F.SilkS")
		)
		(fp_line
			(start -0.7874 0.4064)
			(end -0.7874 -0.4064)
			(stroke
				(width 0.1524)
				(type default)
			)
			(layer "F.SilkS")
		)
		(fp_line
			(start 0.7874 -0.4064)
			(end 0.7874 0.4064)
			(stroke
				(width 0.1524)
				(type default)
			)
			(layer "F.SilkS")
		)
		(fp_line
			(start 0.7874 0.4064)
			(end -0.7874 0.4064)
			(stroke
				(width 0.1524)
				(type default)
			)
			(layer "F.SilkS")
		)
		(fp_line
			(start -0.67945 -0.305054)
			(end -0.12065 -0.305054)
			(stroke
				(width 0.1)
				(type default)
			)
			(layer "F.Fab")
		)
		(fp_line
			(start -0.67945 0.3048)
			(end -0.67945 -0.305054)
			(stroke
				(width 0.1)
				(type default)
			)
			(layer "F.Fab")
		)
		(fp_line
			(start -0.12065 -0.305054)
			(end -0.12065 -0.2794)
			(stroke
				(width 0.1)
				(type default)
			)
			(layer "F.Fab")
		)
		(fp_line
			(start -0.12065 -0.2794)
			(end 0.12065 -0.2794)
			(stroke
				(width 0.1)
				(type default)
			)
			(layer "F.Fab")
		)
		(fp_line
			(start -0.12065 0.2794)
			(end -0.12065 0.3048)
			(stroke
				(width 0.1)
				(type default)
			)
			(layer "F.Fab")
		)
		(fp_line
			(start -0.12065 0.3048)
			(end -0.67945 0.3048)
			(stroke
				(width 0.1)
				(type default)
			)
			(layer "F.Fab")
		)
		(fp_line
			(start 0.120396 0.2794)
			(end -0.12065 0.2794)
			(stroke
				(width 0.1)
				(type default)
			)
			(layer "F.Fab")
		)
		(fp_line
			(start 0.120396 0.3048)
			(end 0.120396 0.2794)
			(stroke
				(width 0.1)
				(type default)
			)
			(layer "F.Fab")
		)
		(fp_line
			(start 0.12065 -0.3048)
			(end 0.67945 -0.3048)
			(stroke
				(width 0.1)
				(type default)
			)
			(layer "F.Fab")
		)
		(fp_line
			(start 0.12065 -0.2794)
			(end 0.12065 -0.3048)
			(stroke
				(width 0.1)
				(type default)
			)
			(layer "F.Fab")
		)
		(fp_line
			(start 0.67945 -0.3048)
			(end 0.67945 0.3048)
			(stroke
				(width 0.1)
				(type default)
			)
			(layer "F.Fab")
		)
		(fp_line
			(start 0.67945 0.3048)
			(end 0.120396 0.3048)
			(stroke
				(width 0.1)
				(type default)
			)
			(layer "F.Fab")
		)
		(pad "1" smd circle
			(at -0.40005 0)
			(size 0 0)
			(layers "F.Cu" "F.Mask" "F.Paste")
			(net "VSENSE_P3V3_INA230_1_INP")
		)
		(pad "2" smd circle
			(at 0.40005 0)
			(size 0 0)
			(layers "F.Cu" "F.Mask" "F.Paste")
			(net "VSENSE_P3V3_INA230_1_INN")
		)
	)
	(footprint ""
		(layer "F.Cu")
		(at 41.503854 -346.719398 -90)
		(property "Reference" "PC434_IOP1_2"
			(at 0 0 270)
			(layer "F.SilkS")
			(hide yes)
			(effects
				(font
					(size 1.27 1.27)
				)
			)
		)
		(property "Value" ""
			(at 0 0 270)
			(layer "F.Fab")
			(effects
				(font
					(size 1.27 1.27)
				)
			)
		)
		(duplicate_pad_numbers_are_jumpers no)
		(fp_line
			(start -0.7874 0.4064)
			(end -0.7874 -0.4064)
			(stroke
				(width 0.1524)
				(type default)
			)
			(layer "F.SilkS")
		)
		(fp_line
			(start 0.7874 0.4064)
			(end -0.7874 0.4064)
			(stroke
				(width 0.1524)
				(type default)
			)
			(layer "F.SilkS")
		)
		(fp_line
			(start -0.7874 -0.4064)
			(end 0.7874 -0.4064)
			(stroke
				(width 0.1524)
				(type default)
			)
			(layer "F.SilkS")
		)
		(fp_line
			(start 0.7874 -0.4064)
			(end 0.7874 0.4064)
			(stroke
				(width 0.1524)
				(type default)
			)
			(layer "F.SilkS")
		)
		(fp_line
			(start -0.67945 0.3048)
			(end -0.67945 -0.305054)
			(stroke
				(width 0.1)
				(type default)
			)
			(layer "F.Fab")
		)
		(fp_line
			(start -0.12065 0.3048)
			(end -0.67945 0.3048)
			(stroke
				(width 0.1)
				(type default)
			)
			(layer "F.Fab")
		)
		(fp_line
			(start 0.120396 0.3048)
			(end 0.120396 0.2794)
			(stroke
				(width 0.1)
				(type default)
			)
			(layer "F.Fab")
		)
		(fp_line
			(start 0.67945 0.3048)
			(end 0.120396 0.3048)
			(stroke
				(width 0.1)
				(type default)
			)
			(layer "F.Fab")
		)
		(fp_line
			(start -0.12065 0.2794)
			(end -0.12065 0.3048)
			(stroke
				(width 0.1)
				(type default)
			)
			(layer "F.Fab")
		)
		(fp_line
			(start 0.120396 0.2794)
			(end -0.12065 0.2794)
			(stroke
				(width 0.1)
				(type default)
			)
			(layer "F.Fab")
		)
		(fp_line
			(start -0.12065 -0.2794)
			(end 0.12065 -0.2794)
			(stroke
				(width 0.1)
				(type default)
			)
			(layer "F.Fab")
		)
		(fp_line
			(start 0.12065 -0.2794)
			(end 0.12065 -0.3048)
			(stroke
				(width 0.1)
				(type default)
			)
			(layer "F.Fab")
		)
		(fp_line
			(start 0.12065 -0.3048)
			(end 0.67945 -0.3048)
			(stroke
				(width 0.1)
				(type default)
			)
			(layer "F.Fab")
		)
		(fp_line
			(start 0.67945 -0.3048)
			(end 0.67945 0.3048)
			(stroke
				(width 0.1)
				(type default)
			)
			(layer "F.Fab")
		)
		(fp_line
			(start -0.67945 -0.305054)
			(end -0.12065 -0.305054)
			(stroke
				(width 0.1)
				(type default)
			)
			(layer "F.Fab")
		)
		(fp_line
			(start -0.12065 -0.305054)
			(end -0.12065 -0.2794)
			(stroke
				(width 0.1)
				(type default)
			)
			(layer "F.Fab")
		)
		(pad "1" smd circle
			(at -0.40005 0 270)
			(size 0 0)
			(layers "F.Cu" "F.Mask" "F.Paste")
			(net "PVDDCR_CPU1_P1_PVCC")
		)
		(pad "2" smd circle
			(at 0.40005 0 270)
			(size 0 0)
			(layers "F.Cu" "F.Mask" "F.Paste")
			(net "GND")
		)
	)
	(footprint ""
		(layer "F.Cu")
		(at 122.80011 -146.957288)
		(property "Reference" "PC6007"
			(at 0 0 0)
			(layer "F.SilkS")
			(hide yes)
			(effects
				(font
					(size 1.27 1.27)
				)
			)
		)
		(property "Value" ""
			(at 0 0 0)
			(layer "F.Fab")
			(effects
				(font
					(size 1.27 1.27)
				)
			)
		)
		(duplicate_pad_numbers_are_jumpers no)
		(fp_line
			(start -0.7874 -0.4064)
			(end 0.7874 -0.4064)
			(stroke
				(width 0.1524)
				(type default)
			)
			(layer "F.SilkS")
		)
		(fp_line
			(start -0.7874 0.4064)
			(end -0.7874 -0.4064)
			(stroke
				(width 0.1524)
				(type default)
			)
			(layer "F.SilkS")
		)
		(fp_line
			(start 0.7874 -0.4064)
			(end 0.7874 0.4064)
			(stroke
				(width 0.1524)
				(type default)
			)
			(layer "F.SilkS")
		)
		(fp_line
			(start 0.7874 0.4064)
			(end -0.7874 0.4064)
			(stroke
				(width 0.1524)
				(type default)
			)
			(layer "F.SilkS")
		)
		(fp_line
			(start -0.67945 -0.305054)
			(end -0.12065 -0.305054)
			(stroke
				(width 0.1)
				(type default)
			)
			(layer "F.Fab")
		)
		(fp_line
			(start -0.67945 0.3048)
			(end -0.67945 -0.305054)
			(stroke
				(width 0.1)
				(type default)
			)
			(layer "F.Fab")
		)
		(fp_line
			(start -0.12065 -0.305054)
			(end -0.12065 -0.2794)
			(stroke
				(width 0.1)
				(type default)
			)
			(layer "F.Fab")
		)
		(fp_line
			(start -0.12065 -0.2794)
			(end 0.12065 -0.2794)
			(stroke
				(width 0.1)
				(type default)
			)
			(layer "F.Fab")
		)
		(fp_line
			(start -0.12065 0.2794)
			(end -0.12065 0.3048)
			(stroke
				(width 0.1)
				(type default)
			)
			(layer "F.Fab")
		)
		(fp_line
			(start -0.12065 0.3048)
			(end -0.67945 0.3048)
			(stroke
				(width 0.1)
				(type default)
			)
			(layer "F.Fab")
		)
		(fp_line
			(start 0.120396 0.2794)
			(end -0.12065 0.2794)
			(stroke
				(width 0.1)
				(type default)
			)
			(layer "F.Fab")
		)
		(fp_line
			(start 0.120396 0.3048)
			(end 0.120396 0.2794)
			(stroke
				(width 0.1)
				(type default)
			)
			(layer "F.Fab")
		)
		(fp_line
			(start 0.12065 -0.3048)
			(end 0.67945 -0.3048)
			(stroke
				(width 0.1)
				(type default)
			)
			(layer "F.Fab")
		)
		(fp_line
			(start 0.12065 -0.2794)
			(end 0.12065 -0.3048)
			(stroke
				(width 0.1)
				(type default)
			)
			(layer "F.Fab")
		)
		(fp_line
			(start 0.67945 -0.3048)
			(end 0.67945 0.3048)
			(stroke
				(width 0.1)
				(type default)
			)
			(layer "F.Fab")
		)
		(fp_line
			(start 0.67945 0.3048)
			(end 0.120396 0.3048)
			(stroke
				(width 0.1)
				(type default)
			)
			(layer "F.Fab")
		)
		(pad "1" smd circle
			(at -0.40005 0)
			(size 0 0)
			(layers "F.Cu" "F.Mask" "F.Paste")
			(net "P12V_AUX")
		)
		(pad "2" smd circle
			(at 0.40005 0)
			(size 0 0)
			(layers "F.Cu" "F.Mask" "F.Paste")
			(net "GND")
		)
	)
	(footprint ""
		(layer "F.Cu")
		(at 125.992636 -60.482226)
		(property "Reference" "R1727"
			(at 0 0 0)
			(layer "F.SilkS")
			(hide yes)
			(effects
				(font
					(size 1.27 1.27)
				)
			)
		)
		(property "Value" ""
			(at 0 0 0)
			(layer "F.Fab")
			(effects
				(font
					(size 1.27 1.27)
				)
			)
		)
		(duplicate_pad_numbers_are_jumpers no)
		(fp_line
			(start -0.7874 -0.4064)
			(end 0.7874 -0.4064)
			(stroke
				(width 0.1524)
				(type default)
			)
			(layer "F.SilkS")
		)
		(fp_line
			(start -0.7874 0.4064)
			(end -0.7874 -0.4064)
			(stroke
				(width 0.1524)
				(type default)
			)
			(layer "F.SilkS")
		)
		(fp_line
			(start 0.7874 -0.4064)
			(end 0.7874 0.4064)
			(stroke
				(width 0.1524)
				(type default)
			)
			(layer "F.SilkS")
		)
		(fp_line
			(start 0.7874 0.4064)
			(end -0.7874 0.4064)
			(stroke
				(width 0.1524)
				(type default)
			)
			(layer "F.SilkS")
		)
		(fp_line
			(start -0.67945 -0.305054)
			(end -0.12065 -0.305054)
			(stroke
				(width 0.1)
				(type default)
			)
			(layer "F.Fab")
		)
		(fp_line
			(start -0.67945 0.3048)
			(end -0.67945 -0.305054)
			(stroke
				(width 0.1)
				(type default)
			)
			(layer "F.Fab")
		)
		(fp_line
			(start -0.12065 -0.305054)
			(end -0.12065 -0.2794)
			(stroke
				(width 0.1)
				(type default)
			)
			(layer "F.Fab")
		)
		(fp_line
			(start -0.12065 -0.2794)
			(end 0.12065 -0.2794)
			(stroke
				(width 0.1)
				(type default)
			)
			(layer "F.Fab")
		)
		(fp_line
			(start -0.12065 0.2794)
			(end -0.12065 0.3048)
			(stroke
				(width 0.1)
				(type default)
			)
			(layer "F.Fab")
		)
		(fp_line
			(start -0.12065 0.3048)
			(end -0.67945 0.3048)
			(stroke
				(width 0.1)
				(type default)
			)
			(layer "F.Fab")
		)
		(fp_line
			(start 0.120396 0.2794)
			(end -0.12065 0.2794)
			(stroke
				(width 0.1)
				(type default)
			)
			(layer "F.Fab")
		)
		(fp_line
			(start 0.120396 0.3048)
			(end 0.120396 0.2794)
			(stroke
				(width 0.1)
				(type default)
			)
			(layer "F.Fab")
		)
		(fp_line
			(start 0.12065 -0.3048)
			(end 0.67945 -0.3048)
			(stroke
				(width 0.1)
				(type default)
			)
			(layer "F.Fab")
		)
		(fp_line
			(start 0.12065 -0.2794)
			(end 0.12065 -0.3048)
			(stroke
				(width 0.1)
				(type default)
			)
			(layer "F.Fab")
		)
		(fp_line
			(start 0.67945 -0.3048)
			(end 0.67945 0.3048)
			(stroke
				(width 0.1)
				(type default)
			)
			(layer "F.Fab")
		)
		(fp_line
			(start 0.67945 0.3048)
			(end 0.120396 0.3048)
			(stroke
				(width 0.1)
				(type default)
			)
			(layer "F.Fab")
		)
		(pad "1" smd circle
			(at -0.40005 0)
			(size 0 0)
			(layers "F.Cu" "F.Mask" "F.Paste")
			(net "P3V3_AUX")
		)
		(pad "2" smd circle
			(at 0.40005 0)
			(size 0 0)
			(layers "F.Cu" "F.Mask" "F.Paste")
			(net "JTAG_SCM_TDO")
		)
	)
	(footprint ""
		(layer "F.Cu")
		(at 86.868 -70.866 -90)
		(property "Reference" "R1171"
			(at 0 0 270)
			(layer "F.SilkS")
			(hide yes)
			(effects
				(font
					(size 1.27 1.27)
				)
			)
		)
		(property "Value" ""
			(at 0 0 270)
			(layer "F.Fab")
			(effects
				(font
					(size 1.27 1.27)
				)
			)
		)
		(duplicate_pad_numbers_are_jumpers no)
		(fp_line
			(start -0.7874 0.4064)
			(end -0.7874 -0.4064)
			(stroke
				(width 0.1524)
				(type default)
			)
			(layer "F.SilkS")
		)
		(fp_line
			(start 0.7874 0.4064)
			(end -0.7874 0.4064)
			(stroke
				(width 0.1524)
				(type default)
			)
			(layer "F.SilkS")
		)
		(fp_line
			(start -0.7874 -0.4064)
			(end 0.7874 -0.4064)
			(stroke
				(width 0.1524)
				(type default)
			)
			(layer "F.SilkS")
		)
		(fp_line
			(start 0.7874 -0.4064)
			(end 0.7874 0.4064)
			(stroke
				(width 0.1524)
				(type default)
			)
			(layer "F.SilkS")
		)
		(fp_line
			(start -0.67945 0.3048)
			(end -0.67945 -0.305054)
			(stroke
				(width 0.1)
				(type default)
			)
			(layer "F.Fab")
		)
		(fp_line
			(start -0.12065 0.3048)
			(end -0.67945 0.3048)
			(stroke
				(width 0.1)
				(type default)
			)
			(layer "F.Fab")
		)
		(fp_line
			(start 0.120396 0.3048)
			(end 0.120396 0.2794)
			(stroke
				(width 0.1)
				(type default)
			)
			(layer "F.Fab")
		)
		(fp_line
			(start 0.67945 0.3048)
			(end 0.120396 0.3048)
			(stroke
				(width 0.1)
				(type default)
			)
			(layer "F.Fab")
		)
		(fp_line
			(start -0.12065 0.2794)
			(end -0.12065 0.3048)
			(stroke
				(width 0.1)
				(type default)
			)
			(layer "F.Fab")
		)
		(fp_line
			(start 0.120396 0.2794)
			(end -0.12065 0.2794)
			(stroke
				(width 0.1)
				(type default)
			)
			(layer "F.Fab")
		)
		(fp_line
			(start -0.12065 -0.2794)
			(end 0.12065 -0.2794)
			(stroke
				(width 0.1)
				(type default)
			)
			(layer "F.Fab")
		)
		(fp_line
			(start 0.12065 -0.2794)
			(end 0.12065 -0.3048)
			(stroke
				(width 0.1)
				(type default)
			)
			(layer "F.Fab")
		)
		(fp_line
			(start 0.12065 -0.3048)
			(end 0.67945 -0.3048)
			(stroke
				(width 0.1)
				(type default)
			)
			(layer "F.Fab")
		)
		(fp_line
			(start 0.67945 -0.3048)
			(end 0.67945 0.3048)
			(stroke
				(width 0.1)
				(type default)
			)
			(layer "F.Fab")
		)
		(fp_line
			(start -0.67945 -0.305054)
			(end -0.12065 -0.305054)
			(stroke
				(width 0.1)
				(type default)
			)
			(layer "F.Fab")
		)
		(fp_line
			(start -0.12065 -0.305054)
			(end -0.12065 -0.2794)
			(stroke
				(width 0.1)
				(type default)
			)
			(layer "F.Fab")
		)
		(pad "1" smd circle
			(at -0.40005 0 270)
			(size 0 0)
			(layers "F.Cu" "F.Mask" "F.Paste")
			(net "P3V3_AUX")
		)
		(pad "2" smd circle
			(at 0.40005 0 270)
			(size 0 0)
			(layers "F.Cu" "F.Mask" "F.Paste")
			(net "OCP_V3_2_P3V3_PLD_R_PWRGD")
		)
	)
	(footprint ""
		(layer "F.Cu")
		(at 419.167564 -16.100298 90)
		(property "Reference" "C1569"
			(at 0 0 90)
			(layer "F.SilkS")
			(hide yes)
			(effects
				(font
					(size 1.27 1.27)
				)
			)
		)
		(property "Value" ""
			(at 0 0 90)
			(layer "F.Fab")
			(effects
				(font
					(size 1.27 1.27)
				)
			)
		)
		(duplicate_pad_numbers_are_jumpers no)
		(fp_line
			(start 0.299974 -0.150114)
			(end 0.299974 0.150114)
			(stroke
				(width 0.1)
				(type default)
			)
			(layer "F.Fab")
		)
		(fp_line
			(start -0.299974 -0.150114)
			(end 0.299974 -0.150114)
			(stroke
				(width 0.1)
				(type default)
			)
			(layer "F.Fab")
		)
		(fp_line
			(start 0.299974 0.150114)
			(end -0.299974 0.150114)
			(stroke
				(width 0.1)
				(type default)
			)
			(layer "F.Fab")
		)
		(fp_line
			(start -0.299974 0.150114)
			(end -0.299974 -0.150114)
			(stroke
				(width 0.1)
				(type default)
			)
			(layer "F.Fab")
		)
		(pad "1" smd rect
			(at -0.2667 0 90)
			(size 0.3048 0.381)
			(layers "F.Cu" "F.Mask" "F.Paste")
			(net "P5E_CPU0_G3_TX_C_DP<5>")
		)
		(pad "2" smd rect
			(at 0.2667 0 90)
			(size 0.3048 0.381)
			(layers "F.Cu" "F.Mask" "F.Paste")
			(net "P5E_CPU0_G3_TX_DP<5>")
		)
	)
	(footprint ""
		(layer "F.Cu")
		(at 398.155668 -395.333474)
		(property "Reference" "R614"
			(at 0 0 0)
			(layer "F.SilkS")
			(hide yes)
			(effects
				(font
					(size 1.27 1.27)
				)
			)
		)
		(property "Value" ""
			(at 0 0 0)
			(layer "F.Fab")
			(effects
				(font
					(size 1.27 1.27)
				)
			)
		)
		(duplicate_pad_numbers_are_jumpers no)
		(fp_line
			(start -0.32512 -0.175006)
			(end 0.32512 -0.175006)
			(stroke
				(width 0.1)
				(type default)
			)
			(layer "F.Fab")
		)
		(fp_line
			(start -0.32512 0.175006)
			(end -0.32512 -0.175006)
			(stroke
				(width 0.1)
				(type default)
			)
			(layer "F.Fab")
		)
		(fp_line
			(start 0.32512 -0.175006)
			(end 0.32512 0.175006)
			(stroke
				(width 0.1)
				(type default)
			)
			(layer "F.Fab")
		)
		(fp_line
			(start 0.32512 0.175006)
			(end -0.32512 0.175006)
			(stroke
				(width 0.1)
				(type default)
			)
			(layer "F.Fab")
		)
		(pad "1" smd rect
			(at -0.2667 0)
			(size 0.3048 0.381)
			(layers "F.Cu" "F.Mask" "F.Paste")
			(net "CLK_100M_RETIMER_CPU0_P2_R_DN")
		)
		(pad "2" smd rect
			(at 0.2667 0 180)
			(size 0.3048 0.381)
			(layers "F.Cu" "F.Mask" "F.Paste")
			(net "CLK_100M_RETIMER_CPU0_P2_DN")
		)
	)
	(footprint ""
		(layer "F.Cu")
		(at 164.544756 -43.193462)
		(property "Reference" "R153"
			(at 0 0 0)
			(layer "F.SilkS")
			(hide yes)
			(effects
				(font
					(size 1.27 1.27)
				)
			)
		)
		(property "Value" ""
			(at 0 0 0)
			(layer "F.Fab")
			(effects
				(font
					(size 1.27 1.27)
				)
			)
		)
		(duplicate_pad_numbers_are_jumpers no)
		(fp_line
			(start -0.7874 -0.4064)
			(end 0.7874 -0.4064)
			(stroke
				(width 0.1524)
				(type default)
			)
			(layer "F.SilkS")
		)
		(fp_line
			(start -0.7874 0.4064)
			(end -0.7874 -0.4064)
			(stroke
				(width 0.1524)
				(type default)
			)
			(layer "F.SilkS")
		)
		(fp_line
			(start 0.7874 -0.4064)
			(end 0.7874 0.4064)
			(stroke
				(width 0.1524)
				(type default)
			)
			(layer "F.SilkS")
		)
		(fp_line
			(start 0.7874 0.4064)
			(end -0.7874 0.4064)
			(stroke
				(width 0.1524)
				(type default)
			)
			(layer "F.SilkS")
		)
		(fp_line
			(start -0.67945 -0.305054)
			(end -0.12065 -0.305054)
			(stroke
				(width 0.1)
				(type default)
			)
			(layer "F.Fab")
		)
		(fp_line
			(start -0.67945 0.3048)
			(end -0.67945 -0.305054)
			(stroke
				(width 0.1)
				(type default)
			)
			(layer "F.Fab")
		)
		(fp_line
			(start -0.12065 -0.305054)
			(end -0.12065 -0.2794)
			(stroke
				(width 0.1)
				(type default)
			)
			(layer "F.Fab")
		)
		(fp_line
			(start -0.12065 -0.2794)
			(end 0.12065 -0.2794)
			(stroke
				(width 0.1)
				(type default)
			)
			(layer "F.Fab")
		)
		(fp_line
			(start -0.12065 0.2794)
			(end -0.12065 0.3048)
			(stroke
				(width 0.1)
				(type default)
			)
			(layer "F.Fab")
		)
		(fp_line
			(start -0.12065 0.3048)
			(end -0.67945 0.3048)
			(stroke
				(width 0.1)
				(type default)
			)
			(layer "F.Fab")
		)
		(fp_line
			(start 0.120396 0.2794)
			(end -0.12065 0.2794)
			(stroke
				(width 0.1)
				(type default)
			)
			(layer "F.Fab")
		)
		(fp_line
			(start 0.120396 0.3048)
			(end 0.120396 0.2794)
			(stroke
				(width 0.1)
				(type default)
			)
			(layer "F.Fab")
		)
		(fp_line
			(start 0.12065 -0.3048)
			(end 0.67945 -0.3048)
			(stroke
				(width 0.1)
				(type default)
			)
			(layer "F.Fab")
		)
		(fp_line
			(start 0.12065 -0.2794)
			(end 0.12065 -0.3048)
			(stroke
				(width 0.1)
				(type default)
			)
			(layer "F.Fab")
		)
		(fp_line
			(start 0.67945 -0.3048)
			(end 0.67945 0.3048)
			(stroke
				(width 0.1)
				(type default)
			)
			(layer "F.Fab")
		)
		(fp_line
			(start 0.67945 0.3048)
			(end 0.120396 0.3048)
			(stroke
				(width 0.1)
				(type default)
			)
			(layer "F.Fab")
		)
		(pad "1" smd circle
			(at -0.40005 0)
			(size 0 0)
			(layers "F.Cu" "F.Mask" "F.Paste")
			(net "M2_SSD0_CLKREQ_EN_N")
		)
		(pad "2" smd circle
			(at 0.40005 0)
			(size 0 0)
			(layers "F.Cu" "F.Mask" "F.Paste")
			(net "M2_SSD0_CLKREQ_EN_N_BUF")
		)
	)
	(footprint ""
		(layer "F.Cu")
		(at 193.167 -28.194 -90)
		(property "Reference" "R8030"
			(at 0 0 270)
			(layer "F.SilkS")
			(hide yes)
			(effects
				(font
					(size 1.27 1.27)
				)
			)
		)
		(property "Value" ""
			(at 0 0 270)
			(layer "F.Fab")
			(effects
				(font
					(size 1.27 1.27)
				)
			)
		)
		(duplicate_pad_numbers_are_jumpers no)
		(fp_line
			(start -0.7874 0.4064)
			(end -0.7874 -0.4064)
			(stroke
				(width 0.1524)
				(type default)
			)
			(layer "F.SilkS")
		)
		(fp_line
			(start 0.7874 0.4064)
			(end -0.7874 0.4064)
			(stroke
				(width 0.1524)
				(type default)
			)
			(layer "F.SilkS")
		)
		(fp_line
			(start -0.7874 -0.4064)
			(end 0.7874 -0.4064)
			(stroke
				(width 0.1524)
				(type default)
			)
			(layer "F.SilkS")
		)
		(fp_line
			(start 0.7874 -0.4064)
			(end 0.7874 0.4064)
			(stroke
				(width 0.1524)
				(type default)
			)
			(layer "F.SilkS")
		)
		(fp_line
			(start -0.67945 0.3048)
			(end -0.67945 -0.305054)
			(stroke
				(width 0.1)
				(type default)
			)
			(layer "F.Fab")
		)
		(fp_line
			(start -0.12065 0.3048)
			(end -0.67945 0.3048)
			(stroke
				(width 0.1)
				(type default)
			)
			(layer "F.Fab")
		)
		(fp_line
			(start 0.120396 0.3048)
			(end 0.120396 0.2794)
			(stroke
				(width 0.1)
				(type default)
			)
			(layer "F.Fab")
		)
		(fp_line
			(start 0.67945 0.3048)
			(end 0.120396 0.3048)
			(stroke
				(width 0.1)
				(type default)
			)
			(layer "F.Fab")
		)
		(fp_line
			(start -0.12065 0.2794)
			(end -0.12065 0.3048)
			(stroke
				(width 0.1)
				(type default)
			)
			(layer "F.Fab")
		)
		(fp_line
			(start 0.120396 0.2794)
			(end -0.12065 0.2794)
			(stroke
				(width 0.1)
				(type default)
			)
			(layer "F.Fab")
		)
		(fp_line
			(start -0.12065 -0.2794)
			(end 0.12065 -0.2794)
			(stroke
				(width 0.1)
				(type default)
			)
			(layer "F.Fab")
		)
		(fp_line
			(start 0.12065 -0.2794)
			(end 0.12065 -0.3048)
			(stroke
				(width 0.1)
				(type default)
			)
			(layer "F.Fab")
		)
		(fp_line
			(start 0.12065 -0.3048)
			(end 0.67945 -0.3048)
			(stroke
				(width 0.1)
				(type default)
			)
			(layer "F.Fab")
		)
		(fp_line
			(start 0.67945 -0.3048)
			(end 0.67945 0.3048)
			(stroke
				(width 0.1)
				(type default)
			)
			(layer "F.Fab")
		)
		(fp_line
			(start -0.67945 -0.305054)
			(end -0.12065 -0.305054)
			(stroke
				(width 0.1)
				(type default)
			)
			(layer "F.Fab")
		)
		(fp_line
			(start -0.12065 -0.305054)
			(end -0.12065 -0.2794)
			(stroke
				(width 0.1)
				(type default)
			)
			(layer "F.Fab")
		)
		(pad "1" smd circle
			(at -0.40005 0 270)
			(size 0 0)
			(layers "F.Cu" "F.Mask" "F.Paste")
			(net "P12V_SCM_FAULT_N")
		)
		(pad "2" smd circle
			(at 0.40005 0 270)
			(size 0 0)
			(layers "F.Cu" "F.Mask" "F.Paste")
			(net "P12V_SCM_FAULT_R_N")
		)
	)
	(footprint ""
		(layer "F.Cu")
		(at 291.706046 -368.230658)
		(property "Reference" "PQ14"
			(at 0.935482 -4.364482 0)
			(unlocked yes)
			(layer "F.SilkS")
			(effects
				(font
					(size 0.7874 0.5842)
					(thickness 0.1524)
				)
			)
		)
		(property "Value" ""
			(at 0 0 0)
			(layer "F.Fab")
			(effects
				(font
					(size 1.27 1.27)
				)
			)
		)
		(duplicate_pad_numbers_are_jumpers no)
		(fp_line
			(start -1.949958 -1.610106)
			(end 1.949958 -1.610106)
			(stroke
				(width 0.1524)
				(type default)
			)
			(layer "F.SilkS")
		)
		(fp_line
			(start -1.949958 1.610106)
			(end -1.949958 -1.610106)
			(stroke
				(width 0.1524)
				(type default)
			)
			(layer "F.SilkS")
		)
		(fp_line
			(start 1.949958 -1.560068)
			(end 1.949958 1.610106)
			(stroke
				(width 0.1524)
				(type default)
			)
			(layer "F.SilkS")
		)
		(fp_line
			(start 1.949958 1.610106)
			(end -1.949958 1.610106)
			(stroke
				(width 0.1524)
				(type default)
			)
			(layer "F.SilkS")
		)
		(fp_line
			(start -0.750062 -1.560068)
			(end 0.750062 -1.560068)
			(stroke
				(width 0.1)
				(type default)
			)
			(layer "F.Fab")
		)
		(fp_line
			(start -0.750062 1.560068)
			(end -0.750062 -1.560068)
			(stroke
				(width 0.1)
				(type default)
			)
			(layer "F.Fab")
		)
		(fp_line
			(start 0.750062 -1.560068)
			(end 0.750062 1.560068)
			(stroke
				(width 0.1)
				(type default)
			)
			(layer "F.Fab")
		)
		(fp_line
			(start 0.750062 1.560068)
			(end -0.750062 1.560068)
			(stroke
				(width 0.1)
				(type default)
			)
			(layer "F.Fab")
		)
		(pad "D" smd rect
			(at 1.100074 0 270)
			(size 1.016 1.4224)
			(layers "F.Cu" "F.Mask" "F.Paste")
			(net "PVDDIO_P0_EN_G")
		)
		(pad "G" smd rect
			(at -1.100074 -0.94996 270)
			(size 1.016 1.4224)
			(layers "F.Cu" "F.Mask" "F.Paste")
			(net "PVDDIO_P0_EN_R")
		)
		(pad "S" smd rect
			(at -1.100074 0.94996 270)
			(size 1.016 1.4224)
			(layers "F.Cu" "F.Mask" "F.Paste")
			(net "GND")
		)
	)
	(footprint ""
		(layer "F.Cu")
		(at 63.405258 -162.790886)
		(property "Reference" "PC127_6"
			(at 0 0 0)
			(layer "F.SilkS")
			(hide yes)
			(effects
				(font
					(size 1.27 1.27)
				)
			)
		)
		(property "Value" ""
			(at 0 0 0)
			(layer "F.Fab")
			(effects
				(font
					(size 1.27 1.27)
				)
			)
		)
		(duplicate_pad_numbers_are_jumpers no)
		(fp_line
			(start -0.7874 -0.4064)
			(end 0.7874 -0.4064)
			(stroke
				(width 0.1524)
				(type default)
			)
			(layer "F.SilkS")
		)
		(fp_line
			(start -0.7874 0.4064)
			(end -0.7874 -0.4064)
			(stroke
				(width 0.1524)
				(type default)
			)
			(layer "F.SilkS")
		)
		(fp_line
			(start 0.7874 -0.4064)
			(end 0.7874 0.4064)
			(stroke
				(width 0.1524)
				(type default)
			)
			(layer "F.SilkS")
		)
		(fp_line
			(start 0.7874 0.4064)
			(end -0.7874 0.4064)
			(stroke
				(width 0.1524)
				(type default)
			)
			(layer "F.SilkS")
		)
		(fp_line
			(start -0.67945 -0.305054)
			(end -0.12065 -0.305054)
			(stroke
				(width 0.1)
				(type default)
			)
			(layer "F.Fab")
		)
		(fp_line
			(start -0.67945 0.3048)
			(end -0.67945 -0.305054)
			(stroke
				(width 0.1)
				(type default)
			)
			(layer "F.Fab")
		)
		(fp_line
			(start -0.12065 -0.305054)
			(end -0.12065 -0.2794)
			(stroke
				(width 0.1)
				(type default)
			)
			(layer "F.Fab")
		)
		(fp_line
			(start -0.12065 -0.2794)
			(end 0.12065 -0.2794)
			(stroke
				(width 0.1)
				(type default)
			)
			(layer "F.Fab")
		)
		(fp_line
			(start -0.12065 0.2794)
			(end -0.12065 0.3048)
			(stroke
				(width 0.1)
				(type default)
			)
			(layer "F.Fab")
		)
		(fp_line
			(start -0.12065 0.3048)
			(end -0.67945 0.3048)
			(stroke
				(width 0.1)
				(type default)
			)
			(layer "F.Fab")
		)
		(fp_line
			(start 0.120396 0.2794)
			(end -0.12065 0.2794)
			(stroke
				(width 0.1)
				(type default)
			)
			(layer "F.Fab")
		)
		(fp_line
			(start 0.120396 0.3048)
			(end 0.120396 0.2794)
			(stroke
				(width 0.1)
				(type default)
			)
			(layer "F.Fab")
		)
		(fp_line
			(start 0.12065 -0.3048)
			(end 0.67945 -0.3048)
			(stroke
				(width 0.1)
				(type default)
			)
			(layer "F.Fab")
		)
		(fp_line
			(start 0.12065 -0.2794)
			(end 0.12065 -0.3048)
			(stroke
				(width 0.1)
				(type default)
			)
			(layer "F.Fab")
		)
		(fp_line
			(start 0.67945 -0.3048)
			(end 0.67945 0.3048)
			(stroke
				(width 0.1)
				(type default)
			)
			(layer "F.Fab")
		)
		(fp_line
			(start 0.67945 0.3048)
			(end 0.120396 0.3048)
			(stroke
				(width 0.1)
				(type default)
			)
			(layer "F.Fab")
		)
		(pad "1" smd circle
			(at -0.40005 0)
			(size 0 0)
			(layers "F.Cu" "F.Mask" "F.Paste")
			(net "SW_P12V_AUX_PVDDCR_CPU0_P1_FLT")
		)
		(pad "2" smd circle
			(at 0.40005 0)
			(size 0 0)
			(layers "F.Cu" "F.Mask" "F.Paste")
			(net "GND")
		)
	)
	(footprint ""
		(layer "F.Cu")
		(at 370.139468 -32.573468)
		(property "Reference" "C1354"
			(at 0 0 0)
			(layer "F.SilkS")
			(hide yes)
			(effects
				(font
					(size 1.27 1.27)
				)
			)
		)
		(property "Value" ""
			(at 0 0 0)
			(layer "F.Fab")
			(effects
				(font
					(size 1.27 1.27)
				)
			)
		)
		(duplicate_pad_numbers_are_jumpers no)
		(fp_line
			(start -0.7874 -0.4064)
			(end 0.7874 -0.4064)
			(stroke
				(width 0.1524)
				(type default)
			)
			(layer "F.SilkS")
		)
		(fp_line
			(start -0.7874 0.4064)
			(end -0.7874 -0.4064)
			(stroke
				(width 0.1524)
				(type default)
			)
			(layer "F.SilkS")
		)
		(fp_line
			(start 0.7874 -0.4064)
			(end 0.7874 0.4064)
			(stroke
				(width 0.1524)
				(type default)
			)
			(layer "F.SilkS")
		)
		(fp_line
			(start 0.7874 0.4064)
			(end -0.7874 0.4064)
			(stroke
				(width 0.1524)
				(type default)
			)
			(layer "F.SilkS")
		)
		(fp_line
			(start -0.67945 -0.305054)
			(end -0.12065 -0.305054)
			(stroke
				(width 0.1)
				(type default)
			)
			(layer "F.Fab")
		)
		(fp_line
			(start -0.67945 0.3048)
			(end -0.67945 -0.305054)
			(stroke
				(width 0.1)
				(type default)
			)
			(layer "F.Fab")
		)
		(fp_line
			(start -0.12065 -0.305054)
			(end -0.12065 -0.2794)
			(stroke
				(width 0.1)
				(type default)
			)
			(layer "F.Fab")
		)
		(fp_line
			(start -0.12065 -0.2794)
			(end 0.12065 -0.2794)
			(stroke
				(width 0.1)
				(type default)
			)
			(layer "F.Fab")
		)
		(fp_line
			(start -0.12065 0.2794)
			(end -0.12065 0.3048)
			(stroke
				(width 0.1)
				(type default)
			)
			(layer "F.Fab")
		)
		(fp_line
			(start -0.12065 0.3048)
			(end -0.67945 0.3048)
			(stroke
				(width 0.1)
				(type default)
			)
			(layer "F.Fab")
		)
		(fp_line
			(start 0.120396 0.2794)
			(end -0.12065 0.2794)
			(stroke
				(width 0.1)
				(type default)
			)
			(layer "F.Fab")
		)
		(fp_line
			(start 0.120396 0.3048)
			(end 0.120396 0.2794)
			(stroke
				(width 0.1)
				(type default)
			)
			(layer "F.Fab")
		)
		(fp_line
			(start 0.12065 -0.3048)
			(end 0.67945 -0.3048)
			(stroke
				(width 0.1)
				(type default)
			)
			(layer "F.Fab")
		)
		(fp_line
			(start 0.12065 -0.2794)
			(end 0.12065 -0.3048)
			(stroke
				(width 0.1)
				(type default)
			)
			(layer "F.Fab")
		)
		(fp_line
			(start 0.67945 -0.3048)
			(end 0.67945 0.3048)
			(stroke
				(width 0.1)
				(type default)
			)
			(layer "F.Fab")
		)
		(fp_line
			(start 0.67945 0.3048)
			(end 0.120396 0.3048)
			(stroke
				(width 0.1)
				(type default)
			)
			(layer "F.Fab")
		)
		(pad "1" smd circle
			(at -0.40005 0)
			(size 0 0)
			(layers "F.Cu" "F.Mask" "F.Paste")
			(net "P3V3_AUX")
		)
		(pad "2" smd circle
			(at 0.40005 0)
			(size 0 0)
			(layers "F.Cu" "F.Mask" "F.Paste")
			(net "GND")
		)
	)
	(footprint ""
		(layer "F.Cu")
		(at 409.853638 -163.684966 90)
		(property "Reference" "PC609_3"
			(at 0 0 90)
			(layer "F.SilkS")
			(hide yes)
			(effects
				(font
					(size 1.27 1.27)
				)
			)
		)
		(property "Value" ""
			(at 0 0 90)
			(layer "F.Fab")
			(effects
				(font
					(size 1.27 1.27)
				)
			)
		)
		(duplicate_pad_numbers_are_jumpers no)
		(fp_line
			(start 0.7874 -0.4064)
			(end 0.7874 0.4064)
			(stroke
				(width 0.1524)
				(type default)
			)
			(layer "F.SilkS")
		)
		(fp_line
			(start -0.7874 -0.4064)
			(end 0.7874 -0.4064)
			(stroke
				(width 0.1524)
				(type default)
			)
			(layer "F.SilkS")
		)
		(fp_line
			(start 0.7874 0.4064)
			(end -0.7874 0.4064)
			(stroke
				(width 0.1524)
				(type default)
			)
			(layer "F.SilkS")
		)
		(fp_line
			(start -0.7874 0.4064)
			(end -0.7874 -0.4064)
			(stroke
				(width 0.1524)
				(type default)
			)
			(layer "F.SilkS")
		)
		(fp_line
			(start -0.12065 -0.305054)
			(end -0.12065 -0.2794)
			(stroke
				(width 0.1)
				(type default)
			)
			(layer "F.Fab")
		)
		(fp_line
			(start -0.67945 -0.305054)
			(end -0.12065 -0.305054)
			(stroke
				(width 0.1)
				(type default)
			)
			(layer "F.Fab")
		)
		(fp_line
			(start 0.67945 -0.3048)
			(end 0.67945 0.3048)
			(stroke
				(width 0.1)
				(type default)
			)
			(layer "F.Fab")
		)
		(fp_line
			(start 0.12065 -0.3048)
			(end 0.67945 -0.3048)
			(stroke
				(width 0.1)
				(type default)
			)
			(layer "F.Fab")
		)
		(fp_line
			(start 0.12065 -0.2794)
			(end 0.12065 -0.3048)
			(stroke
				(width 0.1)
				(type default)
			)
			(layer "F.Fab")
		)
		(fp_line
			(start -0.12065 -0.2794)
			(end 0.12065 -0.2794)
			(stroke
				(width 0.1)
				(type default)
			)
			(layer "F.Fab")
		)
		(fp_line
			(start 0.120396 0.2794)
			(end -0.12065 0.2794)
			(stroke
				(width 0.1)
				(type default)
			)
			(layer "F.Fab")
		)
		(fp_line
			(start -0.12065 0.2794)
			(end -0.12065 0.3048)
			(stroke
				(width 0.1)
				(type default)
			)
			(layer "F.Fab")
		)
		(fp_line
			(start 0.67945 0.3048)
			(end 0.120396 0.3048)
			(stroke
				(width 0.1)
				(type default)
			)
			(layer "F.Fab")
		)
		(fp_line
			(start 0.120396 0.3048)
			(end 0.120396 0.2794)
			(stroke
				(width 0.1)
				(type default)
			)
			(layer "F.Fab")
		)
		(fp_line
			(start -0.12065 0.3048)
			(end -0.67945 0.3048)
			(stroke
				(width 0.1)
				(type default)
			)
			(layer "F.Fab")
		)
		(fp_line
			(start -0.67945 0.3048)
			(end -0.67945 -0.305054)
			(stroke
				(width 0.1)
				(type default)
			)
			(layer "F.Fab")
		)
		(pad "1" smd circle
			(at -0.40005 0 90)
			(size 0 0)
			(layers "F.Cu" "F.Mask" "F.Paste")
			(net "SW_P12V_AUX_PVDDCR_SOC_P0_FLT")
		)
		(pad "2" smd circle
			(at 0.40005 0 90)
			(size 0 0)
			(layers "F.Cu" "F.Mask" "F.Paste")
			(net "GND")
		)
	)
	(footprint ""
		(layer "F.Cu")
		(at 124.972826 -408.517344 -90)
		(property "Reference" "C6699"
			(at 0 0 270)
			(layer "F.SilkS")
			(hide yes)
			(effects
				(font
					(size 1.27 1.27)
				)
			)
		)
		(property "Value" ""
			(at 0 0 270)
			(layer "F.Fab")
			(effects
				(font
					(size 1.27 1.27)
				)
			)
		)
		(duplicate_pad_numbers_are_jumpers no)
		(fp_line
			(start -0.299974 0.150114)
			(end -0.299974 -0.150114)
			(stroke
				(width 0.1)
				(type default)
			)
			(layer "F.Fab")
		)
		(fp_line
			(start 0.299974 0.150114)
			(end -0.299974 0.150114)
			(stroke
				(width 0.1)
				(type default)
			)
			(layer "F.Fab")
		)
		(fp_line
			(start -0.299974 -0.150114)
			(end 0.299974 -0.150114)
			(stroke
				(width 0.1)
				(type default)
			)
			(layer "F.Fab")
		)
		(fp_line
			(start 0.299974 -0.150114)
			(end 0.299974 0.150114)
			(stroke
				(width 0.1)
				(type default)
			)
			(layer "F.Fab")
		)
		(pad "1" smd rect
			(at -0.2667 0 270)
			(size 0.3048 0.381)
			(layers "F.Cu" "F.Mask" "F.Paste")
			(net "P5E_CPU1_P2_TX_BUF_C_DP<3>")
		)
		(pad "2" smd rect
			(at 0.2667 0 270)
			(size 0.3048 0.381)
			(layers "F.Cu" "F.Mask" "F.Paste")
			(net "P5E_CPU1_P2_TX_BUF_DP<3>")
		)
	)
	(footprint ""
		(layer "F.Cu")
		(at 118.491 -420.497 180)
		(property "Reference" "C1975"
			(at 0 0 180)
			(layer "F.SilkS")
			(hide yes)
			(effects
				(font
					(size 1.27 1.27)
				)
			)
		)
		(property "Value" ""
			(at 0 0 180)
			(layer "F.Fab")
			(effects
				(font
					(size 1.27 1.27)
				)
			)
		)
		(duplicate_pad_numbers_are_jumpers no)
		(fp_line
			(start 0.7874 0.4064)
			(end -0.7874 0.4064)
			(stroke
				(width 0.1524)
				(type default)
			)
			(layer "F.SilkS")
		)
		(fp_line
			(start 0.7874 -0.4064)
			(end 0.7874 0.4064)
			(stroke
				(width 0.1524)
				(type default)
			)
			(layer "F.SilkS")
		)
		(fp_line
			(start -0.7874 0.4064)
			(end -0.7874 -0.4064)
			(stroke
				(width 0.1524)
				(type default)
			)
			(layer "F.SilkS")
		)
		(fp_line
			(start -0.7874 -0.4064)
			(end 0.7874 -0.4064)
			(stroke
				(width 0.1524)
				(type default)
			)
			(layer "F.SilkS")
		)
		(fp_line
			(start 0.67945 0.3048)
			(end 0.120396 0.3048)
			(stroke
				(width 0.1)
				(type default)
			)
			(layer "F.Fab")
		)
		(fp_line
			(start 0.67945 -0.3048)
			(end 0.67945 0.3048)
			(stroke
				(width 0.1)
				(type default)
			)
			(layer "F.Fab")
		)
		(fp_line
			(start 0.12065 -0.2794)
			(end 0.12065 -0.3048)
			(stroke
				(width 0.1)
				(type default)
			)
			(layer "F.Fab")
		)
		(fp_line
			(start 0.12065 -0.3048)
			(end 0.67945 -0.3048)
			(stroke
				(width 0.1)
				(type default)
			)
			(layer "F.Fab")
		)
		(fp_line
			(start 0.120396 0.3048)
			(end 0.120396 0.2794)
			(stroke
				(width 0.1)
				(type default)
			)
			(layer "F.Fab")
		)
		(fp_line
			(start 0.120396 0.2794)
			(end -0.12065 0.2794)
			(stroke
				(width 0.1)
				(type default)
			)
			(layer "F.Fab")
		)
		(fp_line
			(start -0.12065 0.3048)
			(end -0.67945 0.3048)
			(stroke
				(width 0.1)
				(type default)
			)
			(layer "F.Fab")
		)
		(fp_line
			(start -0.12065 0.2794)
			(end -0.12065 0.3048)
			(stroke
				(width 0.1)
				(type default)
			)
			(layer "F.Fab")
		)
		(fp_line
			(start -0.12065 -0.2794)
			(end 0.12065 -0.2794)
			(stroke
				(width 0.1)
				(type default)
			)
			(layer "F.Fab")
		)
		(fp_line
			(start -0.12065 -0.305054)
			(end -0.12065 -0.2794)
			(stroke
				(width 0.1)
				(type default)
			)
			(layer "F.Fab")
		)
		(fp_line
			(start -0.67945 0.3048)
			(end -0.67945 -0.305054)
			(stroke
				(width 0.1)
				(type default)
			)
			(layer "F.Fab")
		)
		(fp_line
			(start -0.67945 -0.305054)
			(end -0.12065 -0.305054)
			(stroke
				(width 0.1)
				(type default)
			)
			(layer "F.Fab")
		)
		(pad "1" smd circle
			(at -0.40005 0 180)
			(size 0 0)
			(layers "F.Cu" "F.Mask" "F.Paste")
			(net "GPU_HMC_PRSNT_ISO_N")
		)
		(pad "2" smd circle
			(at 0.40005 0 180)
			(size 0 0)
			(layers "F.Cu" "F.Mask" "F.Paste")
			(net "GND")
		)
	)
	(footprint ""
		(layer "F.Cu")
		(at 330.269342 -392.1252)
		(property "Reference" "R1034"
			(at 0 0 0)
			(layer "F.SilkS")
			(hide yes)
			(effects
				(font
					(size 1.27 1.27)
				)
			)
		)
		(property "Value" ""
			(at 0 0 0)
			(layer "F.Fab")
			(effects
				(font
					(size 1.27 1.27)
				)
			)
		)
		(duplicate_pad_numbers_are_jumpers no)
		(fp_line
			(start -0.32512 -0.175006)
			(end 0.32512 -0.175006)
			(stroke
				(width 0.1)
				(type default)
			)
			(layer "F.Fab")
		)
		(fp_line
			(start -0.32512 0.175006)
			(end -0.32512 -0.175006)
			(stroke
				(width 0.1)
				(type default)
			)
			(layer "F.Fab")
		)
		(fp_line
			(start 0.32512 -0.175006)
			(end 0.32512 0.175006)
			(stroke
				(width 0.1)
				(type default)
			)
			(layer "F.Fab")
		)
		(fp_line
			(start 0.32512 0.175006)
			(end -0.32512 0.175006)
			(stroke
				(width 0.1)
				(type default)
			)
			(layer "F.Fab")
		)
		(pad "1" smd rect
			(at -0.2667 0)
			(size 0.3048 0.381)
			(layers "F.Cu" "F.Mask" "F.Paste")
			(net "P1V8_CPU0_RT_1D")
		)
		(pad "2" smd rect
			(at 0.2667 0 180)
			(size 0.3048 0.381)
			(layers "F.Cu" "F.Mask" "F.Paste")
			(net "TEST2_RT_CPU0_P1")
		)
	)
	(footprint ""
		(layer "F.Cu")
		(at 110.235238 -41.17975 -90)
		(property "Reference" "R6292"
			(at 0 0 270)
			(layer "F.SilkS")
			(hide yes)
			(effects
				(font
					(size 1.27 1.27)
				)
			)
		)
		(property "Value" ""
			(at 0 0 270)
			(layer "F.Fab")
			(effects
				(font
					(size 1.27 1.27)
				)
			)
		)
		(duplicate_pad_numbers_are_jumpers no)
		(fp_line
			(start -0.7874 0.4064)
			(end -0.7874 -0.4064)
			(stroke
				(width 0.1524)
				(type default)
			)
			(layer "F.SilkS")
		)
		(fp_line
			(start 0.7874 0.4064)
			(end -0.7874 0.4064)
			(stroke
				(width 0.1524)
				(type default)
			)
			(layer "F.SilkS")
		)
		(fp_line
			(start -0.7874 -0.4064)
			(end 0.7874 -0.4064)
			(stroke
				(width 0.1524)
				(type default)
			)
			(layer "F.SilkS")
		)
		(fp_line
			(start 0.7874 -0.4064)
			(end 0.7874 0.4064)
			(stroke
				(width 0.1524)
				(type default)
			)
			(layer "F.SilkS")
		)
		(fp_line
			(start -0.67945 0.3048)
			(end -0.67945 -0.305054)
			(stroke
				(width 0.1)
				(type default)
			)
			(layer "F.Fab")
		)
		(fp_line
			(start -0.12065 0.3048)
			(end -0.67945 0.3048)
			(stroke
				(width 0.1)
				(type default)
			)
			(layer "F.Fab")
		)
		(fp_line
			(start 0.120396 0.3048)
			(end 0.120396 0.2794)
			(stroke
				(width 0.1)
				(type default)
			)
			(layer "F.Fab")
		)
		(fp_line
			(start 0.67945 0.3048)
			(end 0.120396 0.3048)
			(stroke
				(width 0.1)
				(type default)
			)
			(layer "F.Fab")
		)
		(fp_line
			(start -0.12065 0.2794)
			(end -0.12065 0.3048)
			(stroke
				(width 0.1)
				(type default)
			)
			(layer "F.Fab")
		)
		(fp_line
			(start 0.120396 0.2794)
			(end -0.12065 0.2794)
			(stroke
				(width 0.1)
				(type default)
			)
			(layer "F.Fab")
		)
		(fp_line
			(start -0.12065 -0.2794)
			(end 0.12065 -0.2794)
			(stroke
				(width 0.1)
				(type default)
			)
			(layer "F.Fab")
		)
		(fp_line
			(start 0.12065 -0.2794)
			(end 0.12065 -0.3048)
			(stroke
				(width 0.1)
				(type default)
			)
			(layer "F.Fab")
		)
		(fp_line
			(start 0.12065 -0.3048)
			(end 0.67945 -0.3048)
			(stroke
				(width 0.1)
				(type default)
			)
			(layer "F.Fab")
		)
		(fp_line
			(start 0.67945 -0.3048)
			(end 0.67945 0.3048)
			(stroke
				(width 0.1)
				(type default)
			)
			(layer "F.Fab")
		)
		(fp_line
			(start -0.67945 -0.305054)
			(end -0.12065 -0.305054)
			(stroke
				(width 0.1)
				(type default)
			)
			(layer "F.Fab")
		)
		(fp_line
			(start -0.12065 -0.305054)
			(end -0.12065 -0.2794)
			(stroke
				(width 0.1)
				(type default)
			)
			(layer "F.Fab")
		)
		(pad "1" smd circle
			(at -0.40005 0 270)
			(size 0 0)
			(layers "F.Cu" "F.Mask" "F.Paste")
			(net "P3V3_AUX")
		)
		(pad "2" smd circle
			(at 0.40005 0 270)
			(size 0 0)
			(layers "F.Cu" "F.Mask" "F.Paste")
			(net "USB_HUB2_TI_GANGED")
		)
	)
	(footprint ""
		(layer "F.Cu")
		(at 331.156564 -138.890502 89.946)
		(property "Reference" "PR470"
			(at 0 0 89.946)
			(layer "F.SilkS")
			(hide yes)
			(effects
				(font
					(size 1.27 1.27)
				)
			)
		)
		(property "Value" ""
			(at 0 0 89.946)
			(layer "F.Fab")
			(effects
				(font
					(size 1.27 1.27)
				)
			)
		)
		(duplicate_pad_numbers_are_jumpers no)
		(fp_line
			(start -0.787275 -0.40642)
			(end 0.787525 -0.40638)
			(stroke
				(width 0.1524)
				(type default)
			)
			(layer "F.SilkS")
		)
		(fp_line
			(start 0.787525 -0.40638)
			(end 0.787275 0.40642)
			(stroke
				(width 0.1524)
				(type default)
			)
			(layer "F.SilkS")
		)
		(fp_line
			(start -0.787525 0.40638)
			(end -0.787275 -0.40642)
			(stroke
				(width 0.1524)
				(type default)
			)
			(layer "F.SilkS")
		)
		(fp_line
			(start 0.787275 0.40642)
			(end -0.787525 0.40638)
			(stroke
				(width 0.1524)
				(type default)
			)
			(layer "F.SilkS")
		)
		(fp_line
			(start -0.679484 -0.305176)
			(end -0.120683 -0.30494)
			(stroke
				(width 0.1)
				(type default)
			)
			(layer "F.Fab")
		)
		(fp_line
			(start -0.120683 -0.30494)
			(end -0.120659 -0.279286)
			(stroke
				(width 0.1)
				(type default)
			)
			(layer "F.Fab")
		)
		(fp_line
			(start 0.120617 -0.304914)
			(end 0.679417 -0.304678)
			(stroke
				(width 0.1)
				(type default)
			)
			(layer "F.Fab")
		)
		(fp_line
			(start 0.679417 -0.304678)
			(end 0.679484 0.304922)
			(stroke
				(width 0.1)
				(type default)
			)
			(layer "F.Fab")
		)
		(fp_line
			(start 0.120641 -0.279514)
			(end 0.120617 -0.304914)
			(stroke
				(width 0.1)
				(type default)
			)
			(layer "F.Fab")
		)
		(fp_line
			(start -0.120659 -0.279286)
			(end 0.120641 -0.279514)
			(stroke
				(width 0.1)
				(type default)
			)
			(layer "F.Fab")
		)
		(fp_line
			(start 0.120405 0.279287)
			(end -0.120641 0.279514)
			(stroke
				(width 0.1)
				(type default)
			)
			(layer "F.Fab")
		)
		(fp_line
			(start -0.120641 0.279514)
			(end -0.120617 0.304914)
			(stroke
				(width 0.1)
				(type default)
			)
			(layer "F.Fab")
		)
		(fp_line
			(start -0.679417 0.304678)
			(end -0.679484 -0.305176)
			(stroke
				(width 0.1)
				(type default)
			)
			(layer "F.Fab")
		)
		(fp_line
			(start 0.120429 0.304687)
			(end 0.120405 0.279287)
			(stroke
				(width 0.1)
				(type default)
			)
			(layer "F.Fab")
		)
		(fp_line
			(start -0.120617 0.304914)
			(end -0.679417 0.304678)
			(stroke
				(width 0.1)
				(type default)
			)
			(layer "F.Fab")
		)
		(fp_line
			(start 0.679484 0.304922)
			(end 0.120429 0.304687)
			(stroke
				(width 0.1)
				(type default)
			)
			(layer "F.Fab")
		)
		(pad "1" smd circle
			(at -0.40005 0 89.946)
			(size 0 0)
			(layers "F.Cu" "F.Mask" "F.Paste")
			(net "PVDD18_S5_P0_FB")
		)
		(pad "2" smd circle
			(at 0.40005 0 89.946)
			(size 0 0)
			(layers "F.Cu" "F.Mask" "F.Paste")
			(net "PVDD18_S5_P0_RGND")
		)
	)
	(footprint ""
		(layer "F.Cu")
		(at 119.135652 -76.743052 90)
		(property "Reference" "PC6011"
			(at 0 0 90)
			(layer "F.SilkS")
			(hide yes)
			(effects
				(font
					(size 1.27 1.27)
				)
			)
		)
		(property "Value" ""
			(at 0 0 90)
			(layer "F.Fab")
			(effects
				(font
					(size 1.27 1.27)
				)
			)
		)
		(duplicate_pad_numbers_are_jumpers no)
		(fp_line
			(start 0.7874 -0.4064)
			(end 0.7874 0.4064)
			(stroke
				(width 0.1524)
				(type default)
			)
			(layer "F.SilkS")
		)
		(fp_line
			(start -0.7874 -0.4064)
			(end 0.7874 -0.4064)
			(stroke
				(width 0.1524)
				(type default)
			)
			(layer "F.SilkS")
		)
		(fp_line
			(start 0.7874 0.4064)
			(end -0.7874 0.4064)
			(stroke
				(width 0.1524)
				(type default)
			)
			(layer "F.SilkS")
		)
		(fp_line
			(start -0.7874 0.4064)
			(end -0.7874 -0.4064)
			(stroke
				(width 0.1524)
				(type default)
			)
			(layer "F.SilkS")
		)
		(fp_line
			(start -0.12065 -0.305054)
			(end -0.12065 -0.2794)
			(stroke
				(width 0.1)
				(type default)
			)
			(layer "F.Fab")
		)
		(fp_line
			(start -0.67945 -0.305054)
			(end -0.12065 -0.305054)
			(stroke
				(width 0.1)
				(type default)
			)
			(layer "F.Fab")
		)
		(fp_line
			(start 0.67945 -0.3048)
			(end 0.67945 0.3048)
			(stroke
				(width 0.1)
				(type default)
			)
			(layer "F.Fab")
		)
		(fp_line
			(start 0.12065 -0.3048)
			(end 0.67945 -0.3048)
			(stroke
				(width 0.1)
				(type default)
			)
			(layer "F.Fab")
		)
		(fp_line
			(start 0.12065 -0.2794)
			(end 0.12065 -0.3048)
			(stroke
				(width 0.1)
				(type default)
			)
			(layer "F.Fab")
		)
		(fp_line
			(start -0.12065 -0.2794)
			(end 0.12065 -0.2794)
			(stroke
				(width 0.1)
				(type default)
			)
			(layer "F.Fab")
		)
		(fp_line
			(start 0.120396 0.2794)
			(end -0.12065 0.2794)
			(stroke
				(width 0.1)
				(type default)
			)
			(layer "F.Fab")
		)
		(fp_line
			(start -0.12065 0.2794)
			(end -0.12065 0.3048)
			(stroke
				(width 0.1)
				(type default)
			)
			(layer "F.Fab")
		)
		(fp_line
			(start 0.67945 0.3048)
			(end 0.120396 0.3048)
			(stroke
				(width 0.1)
				(type default)
			)
			(layer "F.Fab")
		)
		(fp_line
			(start 0.120396 0.3048)
			(end 0.120396 0.2794)
			(stroke
				(width 0.1)
				(type default)
			)
			(layer "F.Fab")
		)
		(fp_line
			(start -0.12065 0.3048)
			(end -0.67945 0.3048)
			(stroke
				(width 0.1)
				(type default)
			)
			(layer "F.Fab")
		)
		(fp_line
			(start -0.67945 0.3048)
			(end -0.67945 -0.305054)
			(stroke
				(width 0.1)
				(type default)
			)
			(layer "F.Fab")
		)
		(pad "1" smd circle
			(at -0.40005 0 90)
			(size 0 0)
			(layers "F.Cu" "F.Mask" "F.Paste")
			(net "SW_P12V_AUX_P1V2_AUX_FLT")
		)
		(pad "2" smd circle
			(at 0.40005 0 90)
			(size 0 0)
			(layers "F.Cu" "F.Mask" "F.Paste")
			(net "GND")
		)
	)
	(footprint ""
		(layer "F.Cu")
		(at 204.7621 -398.940782 180)
		(property "Reference" "PC2348"
			(at 0 0 180)
			(layer "F.SilkS")
			(hide yes)
			(effects
				(font
					(size 1.27 1.27)
				)
			)
		)
		(property "Value" ""
			(at 0 0 180)
			(layer "F.Fab")
			(effects
				(font
					(size 1.27 1.27)
				)
			)
		)
		(duplicate_pad_numbers_are_jumpers no)
		(fp_line
			(start 0.7874 0.4064)
			(end -0.7874 0.4064)
			(stroke
				(width 0.1524)
				(type default)
			)
			(layer "F.SilkS")
		)
		(fp_line
			(start 0.7874 -0.4064)
			(end 0.7874 0.4064)
			(stroke
				(width 0.1524)
				(type default)
			)
			(layer "F.SilkS")
		)
		(fp_line
			(start -0.7874 0.4064)
			(end -0.7874 -0.4064)
			(stroke
				(width 0.1524)
				(type default)
			)
			(layer "F.SilkS")
		)
		(fp_line
			(start -0.7874 -0.4064)
			(end 0.7874 -0.4064)
			(stroke
				(width 0.1524)
				(type default)
			)
			(layer "F.SilkS")
		)
		(fp_line
			(start 0.67945 0.3048)
			(end 0.120396 0.3048)
			(stroke
				(width 0.1)
				(type default)
			)
			(layer "F.Fab")
		)
		(fp_line
			(start 0.67945 -0.3048)
			(end 0.67945 0.3048)
			(stroke
				(width 0.1)
				(type default)
			)
			(layer "F.Fab")
		)
		(fp_line
			(start 0.12065 -0.2794)
			(end 0.12065 -0.3048)
			(stroke
				(width 0.1)
				(type default)
			)
			(layer "F.Fab")
		)
		(fp_line
			(start 0.12065 -0.3048)
			(end 0.67945 -0.3048)
			(stroke
				(width 0.1)
				(type default)
			)
			(layer "F.Fab")
		)
		(fp_line
			(start 0.120396 0.3048)
			(end 0.120396 0.2794)
			(stroke
				(width 0.1)
				(type default)
			)
			(layer "F.Fab")
		)
		(fp_line
			(start 0.120396 0.2794)
			(end -0.12065 0.2794)
			(stroke
				(width 0.1)
				(type default)
			)
			(layer "F.Fab")
		)
		(fp_line
			(start -0.12065 0.3048)
			(end -0.67945 0.3048)
			(stroke
				(width 0.1)
				(type default)
			)
			(layer "F.Fab")
		)
		(fp_line
			(start -0.12065 0.2794)
			(end -0.12065 0.3048)
			(stroke
				(width 0.1)
				(type default)
			)
			(layer "F.Fab")
		)
		(fp_line
			(start -0.12065 -0.2794)
			(end 0.12065 -0.2794)
			(stroke
				(width 0.1)
				(type default)
			)
			(layer "F.Fab")
		)
		(fp_line
			(start -0.12065 -0.305054)
			(end -0.12065 -0.2794)
			(stroke
				(width 0.1)
				(type default)
			)
			(layer "F.Fab")
		)
		(fp_line
			(start -0.67945 0.3048)
			(end -0.67945 -0.305054)
			(stroke
				(width 0.1)
				(type default)
			)
			(layer "F.Fab")
		)
		(fp_line
			(start -0.67945 -0.305054)
			(end -0.12065 -0.305054)
			(stroke
				(width 0.1)
				(type default)
			)
			(layer "F.Fab")
		)
		(pad "1" smd circle
			(at -0.40005 0 180)
			(size 0 0)
			(layers "F.Cu" "F.Mask" "F.Paste")
			(net "HSC_OCREF")
		)
		(pad "2" smd circle
			(at 0.40005 0 180)
			(size 0 0)
			(layers "F.Cu" "F.Mask" "F.Paste")
			(net "AGND_HSC")
		)
	)
	(footprint ""
		(layer "F.Cu")
		(at 264.478516 -132.352796 180)
		(property "Reference" "R6098"
			(at 0 0 180)
			(layer "F.SilkS")
			(hide yes)
			(effects
				(font
					(size 1.27 1.27)
				)
			)
		)
		(property "Value" ""
			(at 0 0 180)
			(layer "F.Fab")
			(effects
				(font
					(size 1.27 1.27)
				)
			)
		)
		(duplicate_pad_numbers_are_jumpers no)
		(fp_line
			(start 0.7874 0.4064)
			(end -0.7874 0.4064)
			(stroke
				(width 0.1524)
				(type default)
			)
			(layer "F.SilkS")
		)
		(fp_line
			(start 0.7874 -0.4064)
			(end 0.7874 0.4064)
			(stroke
				(width 0.1524)
				(type default)
			)
			(layer "F.SilkS")
		)
		(fp_line
			(start -0.7874 0.4064)
			(end -0.7874 -0.4064)
			(stroke
				(width 0.1524)
				(type default)
			)
			(layer "F.SilkS")
		)
		(fp_line
			(start -0.7874 -0.4064)
			(end 0.7874 -0.4064)
			(stroke
				(width 0.1524)
				(type default)
			)
			(layer "F.SilkS")
		)
		(fp_line
			(start 0.67945 0.3048)
			(end 0.120396 0.3048)
			(stroke
				(width 0.1)
				(type default)
			)
			(layer "F.Fab")
		)
		(fp_line
			(start 0.67945 -0.3048)
			(end 0.67945 0.3048)
			(stroke
				(width 0.1)
				(type default)
			)
			(layer "F.Fab")
		)
		(fp_line
			(start 0.12065 -0.2794)
			(end 0.12065 -0.3048)
			(stroke
				(width 0.1)
				(type default)
			)
			(layer "F.Fab")
		)
		(fp_line
			(start 0.12065 -0.3048)
			(end 0.67945 -0.3048)
			(stroke
				(width 0.1)
				(type default)
			)
			(layer "F.Fab")
		)
		(fp_line
			(start 0.120396 0.3048)
			(end 0.120396 0.2794)
			(stroke
				(width 0.1)
				(type default)
			)
			(layer "F.Fab")
		)
		(fp_line
			(start 0.120396 0.2794)
			(end -0.12065 0.2794)
			(stroke
				(width 0.1)
				(type default)
			)
			(layer "F.Fab")
		)
		(fp_line
			(start -0.12065 0.3048)
			(end -0.67945 0.3048)
			(stroke
				(width 0.1)
				(type default)
			)
			(layer "F.Fab")
		)
		(fp_line
			(start -0.12065 0.2794)
			(end -0.12065 0.3048)
			(stroke
				(width 0.1)
				(type default)
			)
			(layer "F.Fab")
		)
		(fp_line
			(start -0.12065 -0.2794)
			(end 0.12065 -0.2794)
			(stroke
				(width 0.1)
				(type default)
			)
			(layer "F.Fab")
		)
		(fp_line
			(start -0.12065 -0.305054)
			(end -0.12065 -0.2794)
			(stroke
				(width 0.1)
				(type default)
			)
			(layer "F.Fab")
		)
		(fp_line
			(start -0.67945 0.3048)
			(end -0.67945 -0.305054)
			(stroke
				(width 0.1)
				(type default)
			)
			(layer "F.Fab")
		)
		(fp_line
			(start -0.67945 -0.305054)
			(end -0.12065 -0.305054)
			(stroke
				(width 0.1)
				(type default)
			)
			(layer "F.Fab")
		)
		(pad "1" smd circle
			(at -0.40005 0 180)
			(size 0 0)
			(layers "F.Cu" "F.Mask" "F.Paste")
			(net "GND")
		)
		(pad "2" smd circle
			(at 0.40005 0 180)
			(size 0 0)
			(layers "F.Cu" "F.Mask" "F.Paste")
			(net "SPI_CPU0_CLK")
		)
	)
	(footprint ""
		(layer "F.Cu")
		(at 215.330278 -128.804924)
		(property "Reference" "R214"
			(at 0 0 0)
			(layer "F.SilkS")
			(hide yes)
			(effects
				(font
					(size 1.27 1.27)
				)
			)
		)
		(property "Value" ""
			(at 0 0 0)
			(layer "F.Fab")
			(effects
				(font
					(size 1.27 1.27)
				)
			)
		)
		(duplicate_pad_numbers_are_jumpers no)
		(fp_line
			(start -0.7874 -0.4064)
			(end 0.7874 -0.4064)
			(stroke
				(width 0.1524)
				(type default)
			)
			(layer "F.SilkS")
		)
		(fp_line
			(start -0.7874 0.4064)
			(end -0.7874 -0.4064)
			(stroke
				(width 0.1524)
				(type default)
			)
			(layer "F.SilkS")
		)
		(fp_line
			(start 0.7874 -0.4064)
			(end 0.7874 0.4064)
			(stroke
				(width 0.1524)
				(type default)
			)
			(layer "F.SilkS")
		)
		(fp_line
			(start 0.7874 0.4064)
			(end -0.7874 0.4064)
			(stroke
				(width 0.1524)
				(type default)
			)
			(layer "F.SilkS")
		)
		(fp_line
			(start -0.67945 -0.305054)
			(end -0.12065 -0.305054)
			(stroke
				(width 0.1)
				(type default)
			)
			(layer "F.Fab")
		)
		(fp_line
			(start -0.67945 0.3048)
			(end -0.67945 -0.305054)
			(stroke
				(width 0.1)
				(type default)
			)
			(layer "F.Fab")
		)
		(fp_line
			(start -0.12065 -0.305054)
			(end -0.12065 -0.2794)
			(stroke
				(width 0.1)
				(type default)
			)
			(layer "F.Fab")
		)
		(fp_line
			(start -0.12065 -0.2794)
			(end 0.12065 -0.2794)
			(stroke
				(width 0.1)
				(type default)
			)
			(layer "F.Fab")
		)
		(fp_line
			(start -0.12065 0.2794)
			(end -0.12065 0.3048)
			(stroke
				(width 0.1)
				(type default)
			)
			(layer "F.Fab")
		)
		(fp_line
			(start -0.12065 0.3048)
			(end -0.67945 0.3048)
			(stroke
				(width 0.1)
				(type default)
			)
			(layer "F.Fab")
		)
		(fp_line
			(start 0.120396 0.2794)
			(end -0.12065 0.2794)
			(stroke
				(width 0.1)
				(type default)
			)
			(layer "F.Fab")
		)
		(fp_line
			(start 0.120396 0.3048)
			(end 0.120396 0.2794)
			(stroke
				(width 0.1)
				(type default)
			)
			(layer "F.Fab")
		)
		(fp_line
			(start 0.12065 -0.3048)
			(end 0.67945 -0.3048)
			(stroke
				(width 0.1)
				(type default)
			)
			(layer "F.Fab")
		)
		(fp_line
			(start 0.12065 -0.2794)
			(end 0.12065 -0.3048)
			(stroke
				(width 0.1)
				(type default)
			)
			(layer "F.Fab")
		)
		(fp_line
			(start 0.67945 -0.3048)
			(end 0.67945 0.3048)
			(stroke
				(width 0.1)
				(type default)
			)
			(layer "F.Fab")
		)
		(fp_line
			(start 0.67945 0.3048)
			(end 0.120396 0.3048)
			(stroke
				(width 0.1)
				(type default)
			)
			(layer "F.Fab")
		)
		(pad "1" smd circle
			(at -0.40005 0)
			(size 0 0)
			(layers "F.Cu" "F.Mask" "F.Paste")
			(net "PWRGD_P1V8_AUX")
		)
		(pad "2" smd circle
			(at 0.40005 0)
			(size 0 0)
			(layers "F.Cu" "F.Mask" "F.Paste")
			(net "PWRGD_P1V8_AUX_R")
		)
	)
	(footprint ""
		(layer "F.Cu")
		(at 73.303638 -55.122826 -90)
		(property "Reference" "R1177"
			(at 0 0 270)
			(layer "F.SilkS")
			(hide yes)
			(effects
				(font
					(size 1.27 1.27)
				)
			)
		)
		(property "Value" ""
			(at 0 0 270)
			(layer "F.Fab")
			(effects
				(font
					(size 1.27 1.27)
				)
			)
		)
		(duplicate_pad_numbers_are_jumpers no)
		(fp_line
			(start -0.7874 0.4064)
			(end -0.7874 -0.4064)
			(stroke
				(width 0.1524)
				(type default)
			)
			(layer "F.SilkS")
		)
		(fp_line
			(start 0.7874 0.4064)
			(end -0.7874 0.4064)
			(stroke
				(width 0.1524)
				(type default)
			)
			(layer "F.SilkS")
		)
		(fp_line
			(start -0.7874 -0.4064)
			(end 0.7874 -0.4064)
			(stroke
				(width 0.1524)
				(type default)
			)
			(layer "F.SilkS")
		)
		(fp_line
			(start 0.7874 -0.4064)
			(end 0.7874 0.4064)
			(stroke
				(width 0.1524)
				(type default)
			)
			(layer "F.SilkS")
		)
		(fp_line
			(start -0.67945 0.3048)
			(end -0.67945 -0.305054)
			(stroke
				(width 0.1)
				(type default)
			)
			(layer "F.Fab")
		)
		(fp_line
			(start -0.12065 0.3048)
			(end -0.67945 0.3048)
			(stroke
				(width 0.1)
				(type default)
			)
			(layer "F.Fab")
		)
		(fp_line
			(start 0.120396 0.3048)
			(end 0.120396 0.2794)
			(stroke
				(width 0.1)
				(type default)
			)
			(layer "F.Fab")
		)
		(fp_line
			(start 0.67945 0.3048)
			(end 0.120396 0.3048)
			(stroke
				(width 0.1)
				(type default)
			)
			(layer "F.Fab")
		)
		(fp_line
			(start -0.12065 0.2794)
			(end -0.12065 0.3048)
			(stroke
				(width 0.1)
				(type default)
			)
			(layer "F.Fab")
		)
		(fp_line
			(start 0.120396 0.2794)
			(end -0.12065 0.2794)
			(stroke
				(width 0.1)
				(type default)
			)
			(layer "F.Fab")
		)
		(fp_line
			(start -0.12065 -0.2794)
			(end 0.12065 -0.2794)
			(stroke
				(width 0.1)
				(type default)
			)
			(layer "F.Fab")
		)
		(fp_line
			(start 0.12065 -0.2794)
			(end 0.12065 -0.3048)
			(stroke
				(width 0.1)
				(type default)
			)
			(layer "F.Fab")
		)
		(fp_line
			(start 0.12065 -0.3048)
			(end 0.67945 -0.3048)
			(stroke
				(width 0.1)
				(type default)
			)
			(layer "F.Fab")
		)
		(fp_line
			(start 0.67945 -0.3048)
			(end 0.67945 0.3048)
			(stroke
				(width 0.1)
				(type default)
			)
			(layer "F.Fab")
		)
		(fp_line
			(start -0.67945 -0.305054)
			(end -0.12065 -0.305054)
			(stroke
				(width 0.1)
				(type default)
			)
			(layer "F.Fab")
		)
		(fp_line
			(start -0.12065 -0.305054)
			(end -0.12065 -0.2794)
			(stroke
				(width 0.1)
				(type default)
			)
			(layer "F.Fab")
		)
		(pad "1" smd circle
			(at -0.40005 0 270)
			(size 0 0)
			(layers "F.Cu" "F.Mask" "F.Paste")
			(net "RST_PERST_OCP_V3_2_BUF_R_N")
		)
		(pad "2" smd circle
			(at 0.40005 0 270)
			(size 0 0)
			(layers "F.Cu" "F.Mask" "F.Paste")
			(net "RST_PERST_OCP_V3_2_BUF_N")
		)
	)
	(footprint ""
		(layer "F.Cu")
		(at 187.071 -137.632948 90)
		(property "Reference" "R1552"
			(at 0 0 90)
			(layer "F.SilkS")
			(hide yes)
			(effects
				(font
					(size 1.27 1.27)
				)
			)
		)
		(property "Value" ""
			(at 0 0 90)
			(layer "F.Fab")
			(effects
				(font
					(size 1.27 1.27)
				)
			)
		)
		(duplicate_pad_numbers_are_jumpers no)
		(fp_line
			(start 0.7874 -0.4064)
			(end 0.7874 0.4064)
			(stroke
				(width 0.1524)
				(type default)
			)
			(layer "F.SilkS")
		)
		(fp_line
			(start -0.7874 -0.4064)
			(end 0.7874 -0.4064)
			(stroke
				(width 0.1524)
				(type default)
			)
			(layer "F.SilkS")
		)
		(fp_line
			(start 0.7874 0.4064)
			(end -0.7874 0.4064)
			(stroke
				(width 0.1524)
				(type default)
			)
			(layer "F.SilkS")
		)
		(fp_line
			(start -0.7874 0.4064)
			(end -0.7874 -0.4064)
			(stroke
				(width 0.1524)
				(type default)
			)
			(layer "F.SilkS")
		)
		(fp_line
			(start -0.12065 -0.305054)
			(end -0.12065 -0.2794)
			(stroke
				(width 0.1)
				(type default)
			)
			(layer "F.Fab")
		)
		(fp_line
			(start -0.67945 -0.305054)
			(end -0.12065 -0.305054)
			(stroke
				(width 0.1)
				(type default)
			)
			(layer "F.Fab")
		)
		(fp_line
			(start 0.67945 -0.3048)
			(end 0.67945 0.3048)
			(stroke
				(width 0.1)
				(type default)
			)
			(layer "F.Fab")
		)
		(fp_line
			(start 0.12065 -0.3048)
			(end 0.67945 -0.3048)
			(stroke
				(width 0.1)
				(type default)
			)
			(layer "F.Fab")
		)
		(fp_line
			(start 0.12065 -0.2794)
			(end 0.12065 -0.3048)
			(stroke
				(width 0.1)
				(type default)
			)
			(layer "F.Fab")
		)
		(fp_line
			(start -0.12065 -0.2794)
			(end 0.12065 -0.2794)
			(stroke
				(width 0.1)
				(type default)
			)
			(layer "F.Fab")
		)
		(fp_line
			(start 0.120396 0.2794)
			(end -0.12065 0.2794)
			(stroke
				(width 0.1)
				(type default)
			)
			(layer "F.Fab")
		)
		(fp_line
			(start -0.12065 0.2794)
			(end -0.12065 0.3048)
			(stroke
				(width 0.1)
				(type default)
			)
			(layer "F.Fab")
		)
		(fp_line
			(start 0.67945 0.3048)
			(end 0.120396 0.3048)
			(stroke
				(width 0.1)
				(type default)
			)
			(layer "F.Fab")
		)
		(fp_line
			(start 0.120396 0.3048)
			(end 0.120396 0.2794)
			(stroke
				(width 0.1)
				(type default)
			)
			(layer "F.Fab")
		)
		(fp_line
			(start -0.12065 0.3048)
			(end -0.67945 0.3048)
			(stroke
				(width 0.1)
				(type default)
			)
			(layer "F.Fab")
		)
		(fp_line
			(start -0.67945 0.3048)
			(end -0.67945 -0.305054)
			(stroke
				(width 0.1)
				(type default)
			)
			(layer "F.Fab")
		)
		(pad "1" smd circle
			(at -0.40005 0 90)
			(size 0 0)
			(layers "F.Cu" "F.Mask" "F.Paste")
			(net "ESPI_CPU0_R1_D3")
		)
		(pad "2" smd circle
			(at 0.40005 0 90)
			(size 0 0)
			(layers "F.Cu" "F.Mask" "F.Paste")
			(net "ESPI_CPU0_D3")
		)
	)
	(footprint ""
		(layer "F.Cu")
		(at 146.304762 -41.746424 180)
		(property "Reference" "R2410"
			(at 0 0 180)
			(layer "F.SilkS")
			(hide yes)
			(effects
				(font
					(size 1.27 1.27)
				)
			)
		)
		(property "Value" ""
			(at 0 0 180)
			(layer "F.Fab")
			(effects
				(font
					(size 1.27 1.27)
				)
			)
		)
		(duplicate_pad_numbers_are_jumpers no)
		(fp_line
			(start 0.7874 0.4064)
			(end -0.7874 0.4064)
			(stroke
				(width 0.1524)
				(type default)
			)
			(layer "F.SilkS")
		)
		(fp_line
			(start 0.7874 -0.4064)
			(end 0.7874 0.4064)
			(stroke
				(width 0.1524)
				(type default)
			)
			(layer "F.SilkS")
		)
		(fp_line
			(start -0.7874 0.4064)
			(end -0.7874 -0.4064)
			(stroke
				(width 0.1524)
				(type default)
			)
			(layer "F.SilkS")
		)
		(fp_line
			(start -0.7874 -0.4064)
			(end 0.7874 -0.4064)
			(stroke
				(width 0.1524)
				(type default)
			)
			(layer "F.SilkS")
		)
		(fp_line
			(start 0.67945 0.3048)
			(end 0.120396 0.3048)
			(stroke
				(width 0.1)
				(type default)
			)
			(layer "F.Fab")
		)
		(fp_line
			(start 0.67945 -0.3048)
			(end 0.67945 0.3048)
			(stroke
				(width 0.1)
				(type default)
			)
			(layer "F.Fab")
		)
		(fp_line
			(start 0.12065 -0.2794)
			(end 0.12065 -0.3048)
			(stroke
				(width 0.1)
				(type default)
			)
			(layer "F.Fab")
		)
		(fp_line
			(start 0.12065 -0.3048)
			(end 0.67945 -0.3048)
			(stroke
				(width 0.1)
				(type default)
			)
			(layer "F.Fab")
		)
		(fp_line
			(start 0.120396 0.3048)
			(end 0.120396 0.2794)
			(stroke
				(width 0.1)
				(type default)
			)
			(layer "F.Fab")
		)
		(fp_line
			(start 0.120396 0.2794)
			(end -0.12065 0.2794)
			(stroke
				(width 0.1)
				(type default)
			)
			(layer "F.Fab")
		)
		(fp_line
			(start -0.12065 0.3048)
			(end -0.67945 0.3048)
			(stroke
				(width 0.1)
				(type default)
			)
			(layer "F.Fab")
		)
		(fp_line
			(start -0.12065 0.2794)
			(end -0.12065 0.3048)
			(stroke
				(width 0.1)
				(type default)
			)
			(layer "F.Fab")
		)
		(fp_line
			(start -0.12065 -0.2794)
			(end 0.12065 -0.2794)
			(stroke
				(width 0.1)
				(type default)
			)
			(layer "F.Fab")
		)
		(fp_line
			(start -0.12065 -0.305054)
			(end -0.12065 -0.2794)
			(stroke
				(width 0.1)
				(type default)
			)
			(layer "F.Fab")
		)
		(fp_line
			(start -0.67945 0.3048)
			(end -0.67945 -0.305054)
			(stroke
				(width 0.1)
				(type default)
			)
			(layer "F.Fab")
		)
		(fp_line
			(start -0.67945 -0.305054)
			(end -0.12065 -0.305054)
			(stroke
				(width 0.1)
				(type default)
			)
			(layer "F.Fab")
		)
		(pad "1" smd circle
			(at -0.40005 0 180)
			(size 0 0)
			(layers "F.Cu" "F.Mask" "F.Paste")
			(net "SMB_M2_P1_1V8AUX_SDA_R")
		)
		(pad "2" smd circle
			(at 0.40005 0 180)
			(size 0 0)
			(layers "F.Cu" "F.Mask" "F.Paste")
			(net "SMB_M2_P1_1V8AUX_SDA")
		)
	)
	(footprint ""
		(layer "F.Cu")
		(at 271.330928 -385.27736 90)
		(property "Reference" "PPQ8"
			(at -7.52348 -2.129028 0)
			(unlocked yes)
			(layer "F.SilkS")
			(effects
				(font
					(size 0.7874 0.5842)
					(thickness 0.1524)
				)
				(justify left)
			)
		)
		(property "Value" ""
			(at 0 0 90)
			(layer "F.Fab")
			(effects
				(font
					(size 1.27 1.27)
				)
			)
		)
		(duplicate_pad_numbers_are_jumpers no)
		(fp_line
			(start 2.350008 -2.649982)
			(end 2.350008 -2.4892)
			(stroke
				(width 0.1524)
				(type default)
			)
			(layer "F.SilkS")
		)
		(fp_line
			(start -2.350008 -2.649982)
			(end 2.350008 -2.649982)
			(stroke
				(width 0.1524)
				(type default)
			)
			(layer "F.SilkS")
		)
		(fp_line
			(start -2.350008 -2.4384)
			(end -2.350008 -2.649982)
			(stroke
				(width 0.1524)
				(type default)
			)
			(layer "F.SilkS")
		)
		(fp_line
			(start 2.350008 2.4892)
			(end 2.350008 2.649982)
			(stroke
				(width 0.1524)
				(type default)
			)
			(layer "F.SilkS")
		)
		(fp_line
			(start 2.350008 2.649982)
			(end -2.350008 2.649982)
			(stroke
				(width 0.1524)
				(type default)
			)
			(layer "F.SilkS")
		)
		(fp_line
			(start -2.350008 2.649982)
			(end -2.350008 2.413)
			(stroke
				(width 0.1524)
				(type default)
			)
			(layer "F.SilkS")
		)
		(fp_poly
			(pts
				(xy -3.457448 -3.442462) (xy -2.657602 -3.424174) (xy -3.100324 -2.39268)
			)
			(stroke
				(width 0)
				(type default)
			)
			(fill yes)
			(layer "F.SilkS")
		)
		(fp_line
			(start 2.350008 -2.649982)
			(end 2.350008 2.649982)
			(stroke
				(width 0.1)
				(type default)
			)
			(layer "F.Fab")
		)
		(fp_line
			(start -2.350008 -2.649982)
			(end 2.350008 -2.649982)
			(stroke
				(width 0.1)
				(type default)
			)
			(layer "F.Fab")
		)
		(fp_line
			(start 2.350008 2.649982)
			(end -2.350008 2.649982)
			(stroke
				(width 0.1)
				(type default)
			)
			(layer "F.Fab")
		)
		(fp_line
			(start -2.350008 2.649982)
			(end -2.350008 -2.649982)
			(stroke
				(width 0.1)
				(type default)
			)
			(layer "F.Fab")
		)
		(fp_poly
			(pts
				(xy -3.717544 -1.905) (xy -4.758944 -2.3241) (xy -4.758944 -1.524)
			)
			(stroke
				(width 0)
				(type default)
			)
			(fill yes)
			(layer "F.Fab")
		)
		(pad "1" smd rect
			(at -2.999994 -1.905)
			(size 0.7112 1.1684)
			(layers "F.Cu" "F.Mask" "F.Paste")
			(net "P12V_AUX")
		)
		(pad "2" smd rect
			(at -2.999994 -0.635)
			(size 0.7112 1.1684)
			(layers "F.Cu" "F.Mask" "F.Paste")
			(net "P12V_AUX")
		)
		(pad "3" smd rect
			(at -2.999994 0.635)
			(size 0.7112 1.1684)
			(layers "F.Cu" "F.Mask" "F.Paste")
			(net "P12V_AUX")
		)
		(pad "4" smd rect
			(at -2.999994 1.905)
			(size 0.7112 1.1684)
			(layers "F.Cu" "F.Mask" "F.Paste")
			(net "P12V_HSC_GATE_G4")
		)
		(pad "5" smd circle
			(at 0.925068 0)
			(size 0 0)
			(layers "F.Cu" "F.Mask" "F.Paste")
			(net "P12V_MAIN_R")
		)
		(zone
			(layer "F.Cu")
			(hatch none 0.5)
			(connect_pads
				(clearance 0)
			)
			(min_thickness 0.25)
			(keepout
				(tracks not_allowed)
				(vias allowed)
				(pads allowed)
				(copperpour not_allowed)
				(footprints allowed)
			)
			(placement
				(enabled no)
				(sheetname "")
			)
			(fill
				(thermal_gap 0.5)
				(thermal_bridge_width 0.5)
				(island_removal_mode 0)
			)
			(polygon
				(pts
					(xy 268.689328 -383.7178) (xy 273.972528 -383.7178) (xy 273.972528 -382.92786) (xy 268.689328 -382.92786)
				)
			)
		)
	)
	(footprint ""
		(layer "F.Cu")
		(at 19.241516 -39.926514)
		(property "Reference" "R1310"
			(at 0 0 0)
			(layer "F.SilkS")
			(hide yes)
			(effects
				(font
					(size 1.27 1.27)
				)
			)
		)
		(property "Value" ""
			(at 0 0 0)
			(layer "F.Fab")
			(effects
				(font
					(size 1.27 1.27)
				)
			)
		)
		(duplicate_pad_numbers_are_jumpers no)
		(fp_line
			(start -0.7874 -0.4064)
			(end 0.7874 -0.4064)
			(stroke
				(width 0.1524)
				(type default)
			)
			(layer "F.SilkS")
		)
		(fp_line
			(start -0.7874 0.4064)
			(end -0.7874 -0.4064)
			(stroke
				(width 0.1524)
				(type default)
			)
			(layer "F.SilkS")
		)
		(fp_line
			(start 0.7874 -0.4064)
			(end 0.7874 0.4064)
			(stroke
				(width 0.1524)
				(type default)
			)
			(layer "F.SilkS")
		)
		(fp_line
			(start 0.7874 0.4064)
			(end -0.7874 0.4064)
			(stroke
				(width 0.1524)
				(type default)
			)
			(layer "F.SilkS")
		)
		(fp_line
			(start -0.67945 -0.305054)
			(end -0.12065 -0.305054)
			(stroke
				(width 0.1)
				(type default)
			)
			(layer "F.Fab")
		)
		(fp_line
			(start -0.67945 0.3048)
			(end -0.67945 -0.305054)
			(stroke
				(width 0.1)
				(type default)
			)
			(layer "F.Fab")
		)
		(fp_line
			(start -0.12065 -0.305054)
			(end -0.12065 -0.2794)
			(stroke
				(width 0.1)
				(type default)
			)
			(layer "F.Fab")
		)
		(fp_line
			(start -0.12065 -0.2794)
			(end 0.12065 -0.2794)
			(stroke
				(width 0.1)
				(type default)
			)
			(layer "F.Fab")
		)
		(fp_line
			(start -0.12065 0.2794)
			(end -0.12065 0.3048)
			(stroke
				(width 0.1)
				(type default)
			)
			(layer "F.Fab")
		)
		(fp_line
			(start -0.12065 0.3048)
			(end -0.67945 0.3048)
			(stroke
				(width 0.1)
				(type default)
			)
			(layer "F.Fab")
		)
		(fp_line
			(start 0.120396 0.2794)
			(end -0.12065 0.2794)
			(stroke
				(width 0.1)
				(type default)
			)
			(layer "F.Fab")
		)
		(fp_line
			(start 0.120396 0.3048)
			(end 0.120396 0.2794)
			(stroke
				(width 0.1)
				(type default)
			)
			(layer "F.Fab")
		)
		(fp_line
			(start 0.12065 -0.3048)
			(end 0.67945 -0.3048)
			(stroke
				(width 0.1)
				(type default)
			)
			(layer "F.Fab")
		)
		(fp_line
			(start 0.12065 -0.2794)
			(end 0.12065 -0.3048)
			(stroke
				(width 0.1)
				(type default)
			)
			(layer "F.Fab")
		)
		(fp_line
			(start 0.67945 -0.3048)
			(end 0.67945 0.3048)
			(stroke
				(width 0.1)
				(type default)
			)
			(layer "F.Fab")
		)
		(fp_line
			(start 0.67945 0.3048)
			(end 0.120396 0.3048)
			(stroke
				(width 0.1)
				(type default)
			)
			(layer "F.Fab")
		)
		(pad "1" smd circle
			(at -0.40005 0)
			(size 0 0)
			(layers "F.Cu" "F.Mask" "F.Paste")
			(net "GND")
		)
		(pad "2" smd circle
			(at 0.40005 0)
			(size 0 0)
			(layers "F.Cu" "F.Mask" "F.Paste")
			(net "INA230_7_A0")
		)
	)
	(footprint ""
		(layer "F.Cu")
		(at 21.702268 -423.450258)
		(property "Reference" "C6011"
			(at 0 0 0)
			(layer "F.SilkS")
			(hide yes)
			(effects
				(font
					(size 1.27 1.27)
				)
			)
		)
		(property "Value" ""
			(at 0 0 0)
			(layer "F.Fab")
			(effects
				(font
					(size 1.27 1.27)
				)
			)
		)
		(duplicate_pad_numbers_are_jumpers no)
		(fp_line
			(start -0.7874 -0.4064)
			(end 0.7874 -0.4064)
			(stroke
				(width 0.1524)
				(type default)
			)
			(layer "F.SilkS")
		)
		(fp_line
			(start -0.7874 0.4064)
			(end -0.7874 -0.4064)
			(stroke
				(width 0.1524)
				(type default)
			)
			(layer "F.SilkS")
		)
		(fp_line
			(start 0.7874 -0.4064)
			(end 0.7874 0.4064)
			(stroke
				(width 0.1524)
				(type default)
			)
			(layer "F.SilkS")
		)
		(fp_line
			(start 0.7874 0.4064)
			(end -0.7874 0.4064)
			(stroke
				(width 0.1524)
				(type default)
			)
			(layer "F.SilkS")
		)
		(fp_line
			(start -0.67945 -0.305054)
			(end -0.12065 -0.305054)
			(stroke
				(width 0.1)
				(type default)
			)
			(layer "F.Fab")
		)
		(fp_line
			(start -0.67945 0.3048)
			(end -0.67945 -0.305054)
			(stroke
				(width 0.1)
				(type default)
			)
			(layer "F.Fab")
		)
		(fp_line
			(start -0.12065 -0.305054)
			(end -0.12065 -0.2794)
			(stroke
				(width 0.1)
				(type default)
			)
			(layer "F.Fab")
		)
		(fp_line
			(start -0.12065 -0.2794)
			(end 0.12065 -0.2794)
			(stroke
				(width 0.1)
				(type default)
			)
			(layer "F.Fab")
		)
		(fp_line
			(start -0.12065 0.2794)
			(end -0.12065 0.3048)
			(stroke
				(width 0.1)
				(type default)
			)
			(layer "F.Fab")
		)
		(fp_line
			(start -0.12065 0.3048)
			(end -0.67945 0.3048)
			(stroke
				(width 0.1)
				(type default)
			)
			(layer "F.Fab")
		)
		(fp_line
			(start 0.120396 0.2794)
			(end -0.12065 0.2794)
			(stroke
				(width 0.1)
				(type default)
			)
			(layer "F.Fab")
		)
		(fp_line
			(start 0.120396 0.3048)
			(end 0.120396 0.2794)
			(stroke
				(width 0.1)
				(type default)
			)
			(layer "F.Fab")
		)
		(fp_line
			(start 0.12065 -0.3048)
			(end 0.67945 -0.3048)
			(stroke
				(width 0.1)
				(type default)
			)
			(layer "F.Fab")
		)
		(fp_line
			(start 0.12065 -0.2794)
			(end 0.12065 -0.3048)
			(stroke
				(width 0.1)
				(type default)
			)
			(layer "F.Fab")
		)
		(fp_line
			(start 0.67945 -0.3048)
			(end 0.67945 0.3048)
			(stroke
				(width 0.1)
				(type default)
			)
			(layer "F.Fab")
		)
		(fp_line
			(start 0.67945 0.3048)
			(end 0.120396 0.3048)
			(stroke
				(width 0.1)
				(type default)
			)
			(layer "F.Fab")
		)
		(pad "1" smd circle
			(at -0.40005 0)
			(size 0 0)
			(layers "F.Cu" "F.Mask" "F.Paste")
			(net "BUF2_VDD")
		)
		(pad "2" smd circle
			(at 0.40005 0)
			(size 0 0)
			(layers "F.Cu" "F.Mask" "F.Paste")
			(net "GND")
		)
	)
	(footprint ""
		(layer "F.Cu")
		(at 39.459662 -429.790098 90)
		(property "Reference" "R3292"
			(at 0 0 90)
			(layer "F.SilkS")
			(hide yes)
			(effects
				(font
					(size 1.27 1.27)
				)
			)
		)
		(property "Value" ""
			(at 0 0 90)
			(layer "F.Fab")
			(effects
				(font
					(size 1.27 1.27)
				)
			)
		)
		(duplicate_pad_numbers_are_jumpers no)
		(fp_line
			(start 0.7874 -0.4064)
			(end 0.7874 0.4064)
			(stroke
				(width 0.1524)
				(type default)
			)
			(layer "F.SilkS")
		)
		(fp_line
			(start -0.7874 -0.4064)
			(end 0.7874 -0.4064)
			(stroke
				(width 0.1524)
				(type default)
			)
			(layer "F.SilkS")
		)
		(fp_line
			(start 0.7874 0.4064)
			(end -0.7874 0.4064)
			(stroke
				(width 0.1524)
				(type default)
			)
			(layer "F.SilkS")
		)
		(fp_line
			(start -0.7874 0.4064)
			(end -0.7874 -0.4064)
			(stroke
				(width 0.1524)
				(type default)
			)
			(layer "F.SilkS")
		)
		(fp_line
			(start -0.12065 -0.305054)
			(end -0.12065 -0.2794)
			(stroke
				(width 0.1)
				(type default)
			)
			(layer "F.Fab")
		)
		(fp_line
			(start -0.67945 -0.305054)
			(end -0.12065 -0.305054)
			(stroke
				(width 0.1)
				(type default)
			)
			(layer "F.Fab")
		)
		(fp_line
			(start 0.67945 -0.3048)
			(end 0.67945 0.3048)
			(stroke
				(width 0.1)
				(type default)
			)
			(layer "F.Fab")
		)
		(fp_line
			(start 0.12065 -0.3048)
			(end 0.67945 -0.3048)
			(stroke
				(width 0.1)
				(type default)
			)
			(layer "F.Fab")
		)
		(fp_line
			(start 0.12065 -0.2794)
			(end 0.12065 -0.3048)
			(stroke
				(width 0.1)
				(type default)
			)
			(layer "F.Fab")
		)
		(fp_line
			(start -0.12065 -0.2794)
			(end 0.12065 -0.2794)
			(stroke
				(width 0.1)
				(type default)
			)
			(layer "F.Fab")
		)
		(fp_line
			(start 0.120396 0.2794)
			(end -0.12065 0.2794)
			(stroke
				(width 0.1)
				(type default)
			)
			(layer "F.Fab")
		)
		(fp_line
			(start -0.12065 0.2794)
			(end -0.12065 0.3048)
			(stroke
				(width 0.1)
				(type default)
			)
			(layer "F.Fab")
		)
		(fp_line
			(start 0.67945 0.3048)
			(end 0.120396 0.3048)
			(stroke
				(width 0.1)
				(type default)
			)
			(layer "F.Fab")
		)
		(fp_line
			(start 0.120396 0.3048)
			(end 0.120396 0.2794)
			(stroke
				(width 0.1)
				(type default)
			)
			(layer "F.Fab")
		)
		(fp_line
			(start -0.12065 0.3048)
			(end -0.67945 0.3048)
			(stroke
				(width 0.1)
				(type default)
			)
			(layer "F.Fab")
		)
		(fp_line
			(start -0.67945 0.3048)
			(end -0.67945 -0.305054)
			(stroke
				(width 0.1)
				(type default)
			)
			(layer "F.Fab")
		)
		(pad "1" smd circle
			(at -0.40005 0 90)
			(size 0 0)
			(layers "F.Cu" "F.Mask" "F.Paste")
			(net "P3V3_AUX")
		)
		(pad "2" smd circle
			(at 0.40005 0 90)
			(size 0 0)
			(layers "F.Cu" "F.Mask" "F.Paste")
			(net "CLK_GEN2_GPU_FPGA_OE_OR_N")
		)
	)
	(footprint ""
		(layer "F.Cu")
		(at 320.900044 -61.999876)
		(property "Reference" "J48"
			(at 5.08 1.965452 0)
			(unlocked yes)
			(layer "F.SilkS")
			(effects
				(font
					(size 0.7874 0.5842)
					(thickness 0.1524)
				)
			)
		)
		(property "Value" ""
			(at 0 0 0)
			(layer "F.Fab")
			(effects
				(font
					(size 1.27 1.27)
				)
			)
		)
		(duplicate_pad_numbers_are_jumpers no)
		(fp_line
			(start -1.700022 -2.739898)
			(end 1.700022 -2.739898)
			(stroke
				(width 0.1524)
				(type default)
			)
			(layer "F.SilkS")
		)
		(fp_line
			(start -1.700022 -2.4257)
			(end -1.700022 -2.739898)
			(stroke
				(width 0.1524)
				(type default)
			)
			(layer "F.SilkS")
		)
		(fp_line
			(start -1.700022 -1.1557)
			(end -1.700022 -1.3843)
			(stroke
				(width 0.1524)
				(type default)
			)
			(layer "F.SilkS")
		)
		(fp_line
			(start -1.700022 0.1143)
			(end -1.700022 -0.1143)
			(stroke
				(width 0.1524)
				(type default)
			)
			(layer "F.SilkS")
		)
		(fp_line
			(start -1.700022 1.3843)
			(end -1.700022 1.1557)
			(stroke
				(width 0.1524)
				(type default)
			)
			(layer "F.SilkS")
		)
		(fp_line
			(start -1.700022 2.739898)
			(end -1.700022 2.4257)
			(stroke
				(width 0.1524)
				(type default)
			)
			(layer "F.SilkS")
		)
		(fp_line
			(start 1.700022 -2.739898)
			(end 1.700022 -2.4257)
			(stroke
				(width 0.1524)
				(type default)
			)
			(layer "F.SilkS")
		)
		(fp_line
			(start 1.700022 -1.3843)
			(end 1.700022 -1.1557)
			(stroke
				(width 0.1524)
				(type default)
			)
			(layer "F.SilkS")
		)
		(fp_line
			(start 1.700022 -0.1143)
			(end 1.700022 0.1143)
			(stroke
				(width 0.1524)
				(type default)
			)
			(layer "F.SilkS")
		)
		(fp_line
			(start 1.700022 1.1557)
			(end 1.700022 1.3843)
			(stroke
				(width 0.1524)
				(type default)
			)
			(layer "F.SilkS")
		)
		(fp_line
			(start 1.700022 2.4257)
			(end 1.700022 2.739898)
			(stroke
				(width 0.1524)
				(type default)
			)
			(layer "F.SilkS")
		)
		(fp_line
			(start 1.700022 2.739898)
			(end -1.700022 2.739898)
			(stroke
				(width 0.1524)
				(type default)
			)
			(layer "F.SilkS")
		)
		(fp_poly
			(pts
				(xy -3.383534 -1.905) (xy -4.399534 -1.397) (xy -4.399534 -2.413)
			)
			(stroke
				(width 0)
				(type default)
			)
			(fill yes)
			(layer "F.SilkS")
		)
		(fp_line
			(start -1.700022 -2.739898)
			(end 1.700022 -2.739898)
			(stroke
				(width 0.1)
				(type default)
			)
			(layer "F.Fab")
		)
		(fp_line
			(start -1.700022 2.739898)
			(end -1.700022 -2.739898)
			(stroke
				(width 0.1)
				(type default)
			)
			(layer "F.Fab")
		)
		(fp_line
			(start 1.700022 -2.739898)
			(end 1.700022 2.739898)
			(stroke
				(width 0.1)
				(type default)
			)
			(layer "F.Fab")
		)
		(fp_line
			(start 1.700022 2.739898)
			(end -1.700022 2.739898)
			(stroke
				(width 0.1)
				(type default)
			)
			(layer "F.Fab")
		)
		(fp_poly
			(pts
				(xy -4.399534 -2.413) (xy -4.399534 -1.397) (xy -3.383534 -1.905)
			)
			(stroke
				(width 0)
				(type default)
			)
			(fill yes)
			(layer "F.Fab")
		)
		(pad "1" smd rect
			(at -2.050034 -1.905 270)
			(size 0.762 2.413)
			(layers "F.Cu" "F.Mask" "F.Paste")
			(net "CPU0_BP0")
		)
		(pad "2" smd rect
			(at 2.050034 -1.905 270)
			(size 0.762 2.413)
			(layers "F.Cu" "F.Mask" "F.Paste")
			(net "GND")
		)
		(pad "3" smd rect
			(at -2.050034 -0.635 270)
			(size 0.762 2.413)
			(layers "F.Cu" "F.Mask" "F.Paste")
			(net "CPU0_BP1")
		)
		(pad "4" smd rect
			(at 2.050034 -0.635 270)
			(size 0.762 2.413)
			(layers "F.Cu" "F.Mask" "F.Paste")
			(net "GND")
		)
		(pad "5" smd rect
			(at -2.050034 0.635 270)
			(size 0.762 2.413)
			(layers "F.Cu" "F.Mask" "F.Paste")
			(net "CPU0_BP2")
		)
		(pad "6" smd rect
			(at 2.050034 0.635 270)
			(size 0.762 2.413)
			(layers "F.Cu" "F.Mask" "F.Paste")
			(net "GND")
		)
		(pad "7" smd rect
			(at -2.050034 1.905 270)
			(size 0.762 2.413)
			(layers "F.Cu" "F.Mask" "F.Paste")
			(net "CPU0_BP3")
		)
		(pad "8" smd rect
			(at 2.050034 1.905 270)
			(size 0.762 2.413)
			(layers "F.Cu" "F.Mask" "F.Paste")
			(net "GND")
		)
	)
	(footprint ""
		(layer "F.Cu")
		(at 448.61988 -94.602808 180)
		(property "Reference" "R4094"
			(at 0 0 180)
			(layer "F.SilkS")
			(hide yes)
			(effects
				(font
					(size 1.27 1.27)
				)
			)
		)
		(property "Value" ""
			(at 0 0 180)
			(layer "F.Fab")
			(effects
				(font
					(size 1.27 1.27)
				)
			)
		)
		(duplicate_pad_numbers_are_jumpers no)
		(fp_line
			(start 0.7874 0.4064)
			(end -0.7874 0.4064)
			(stroke
				(width 0.1524)
				(type default)
			)
			(layer "F.SilkS")
		)
		(fp_line
			(start 0.7874 -0.4064)
			(end 0.7874 0.4064)
			(stroke
				(width 0.1524)
				(type default)
			)
			(layer "F.SilkS")
		)
		(fp_line
			(start -0.7874 0.4064)
			(end -0.7874 -0.4064)
			(stroke
				(width 0.1524)
				(type default)
			)
			(layer "F.SilkS")
		)
		(fp_line
			(start -0.7874 -0.4064)
			(end 0.7874 -0.4064)
			(stroke
				(width 0.1524)
				(type default)
			)
			(layer "F.SilkS")
		)
		(fp_line
			(start 0.67945 0.3048)
			(end 0.120396 0.3048)
			(stroke
				(width 0.1)
				(type default)
			)
			(layer "F.Fab")
		)
		(fp_line
			(start 0.67945 -0.3048)
			(end 0.67945 0.3048)
			(stroke
				(width 0.1)
				(type default)
			)
			(layer "F.Fab")
		)
		(fp_line
			(start 0.12065 -0.2794)
			(end 0.12065 -0.3048)
			(stroke
				(width 0.1)
				(type default)
			)
			(layer "F.Fab")
		)
		(fp_line
			(start 0.12065 -0.3048)
			(end 0.67945 -0.3048)
			(stroke
				(width 0.1)
				(type default)
			)
			(layer "F.Fab")
		)
		(fp_line
			(start 0.120396 0.3048)
			(end 0.120396 0.2794)
			(stroke
				(width 0.1)
				(type default)
			)
			(layer "F.Fab")
		)
		(fp_line
			(start 0.120396 0.2794)
			(end -0.12065 0.2794)
			(stroke
				(width 0.1)
				(type default)
			)
			(layer "F.Fab")
		)
		(fp_line
			(start -0.12065 0.3048)
			(end -0.67945 0.3048)
			(stroke
				(width 0.1)
				(type default)
			)
			(layer "F.Fab")
		)
		(fp_line
			(start -0.12065 0.2794)
			(end -0.12065 0.3048)
			(stroke
				(width 0.1)
				(type default)
			)
			(layer "F.Fab")
		)
		(fp_line
			(start -0.12065 -0.2794)
			(end 0.12065 -0.2794)
			(stroke
				(width 0.1)
				(type default)
			)
			(layer "F.Fab")
		)
		(fp_line
			(start -0.12065 -0.305054)
			(end -0.12065 -0.2794)
			(stroke
				(width 0.1)
				(type default)
			)
			(layer "F.Fab")
		)
		(fp_line
			(start -0.67945 0.3048)
			(end -0.67945 -0.305054)
			(stroke
				(width 0.1)
				(type default)
			)
			(layer "F.Fab")
		)
		(fp_line
			(start -0.67945 -0.305054)
			(end -0.12065 -0.305054)
			(stroke
				(width 0.1)
				(type default)
			)
			(layer "F.Fab")
		)
		(pad "1" smd circle
			(at -0.40005 0 180)
			(size 0 0)
			(layers "F.Cu" "F.Mask" "F.Paste")
			(net "P3V3_AUX")
		)
		(pad "2" smd circle
			(at 0.40005 0 180)
			(size 0 0)
			(layers "F.Cu" "F.Mask" "F.Paste")
			(net "OCP_SFF_P3V3_ADC_ALERT_R")
		)
	)
	(footprint ""
		(layer "F.Cu")
		(at 105.659936 -127.768096 90)
		(property "Reference" "R1441"
			(at 0 0 90)
			(layer "F.SilkS")
			(hide yes)
			(effects
				(font
					(size 1.27 1.27)
				)
			)
		)
		(property "Value" ""
			(at 0 0 90)
			(layer "F.Fab")
			(effects
				(font
					(size 1.27 1.27)
				)
			)
		)
		(duplicate_pad_numbers_are_jumpers no)
		(fp_line
			(start 0.7874 -0.4064)
			(end 0.7874 0.4064)
			(stroke
				(width 0.1524)
				(type default)
			)
			(layer "F.SilkS")
		)
		(fp_line
			(start -0.7874 -0.4064)
			(end 0.7874 -0.4064)
			(stroke
				(width 0.1524)
				(type default)
			)
			(layer "F.SilkS")
		)
		(fp_line
			(start 0.7874 0.4064)
			(end -0.7874 0.4064)
			(stroke
				(width 0.1524)
				(type default)
			)
			(layer "F.SilkS")
		)
		(fp_line
			(start -0.7874 0.4064)
			(end -0.7874 -0.4064)
			(stroke
				(width 0.1524)
				(type default)
			)
			(layer "F.SilkS")
		)
		(fp_line
			(start -0.12065 -0.305054)
			(end -0.12065 -0.2794)
			(stroke
				(width 0.1)
				(type default)
			)
			(layer "F.Fab")
		)
		(fp_line
			(start -0.67945 -0.305054)
			(end -0.12065 -0.305054)
			(stroke
				(width 0.1)
				(type default)
			)
			(layer "F.Fab")
		)
		(fp_line
			(start 0.67945 -0.3048)
			(end 0.67945 0.3048)
			(stroke
				(width 0.1)
				(type default)
			)
			(layer "F.Fab")
		)
		(fp_line
			(start 0.12065 -0.3048)
			(end 0.67945 -0.3048)
			(stroke
				(width 0.1)
				(type default)
			)
			(layer "F.Fab")
		)
		(fp_line
			(start 0.12065 -0.2794)
			(end 0.12065 -0.3048)
			(stroke
				(width 0.1)
				(type default)
			)
			(layer "F.Fab")
		)
		(fp_line
			(start -0.12065 -0.2794)
			(end 0.12065 -0.2794)
			(stroke
				(width 0.1)
				(type default)
			)
			(layer "F.Fab")
		)
		(fp_line
			(start 0.120396 0.2794)
			(end -0.12065 0.2794)
			(stroke
				(width 0.1)
				(type default)
			)
			(layer "F.Fab")
		)
		(fp_line
			(start -0.12065 0.2794)
			(end -0.12065 0.3048)
			(stroke
				(width 0.1)
				(type default)
			)
			(layer "F.Fab")
		)
		(fp_line
			(start 0.67945 0.3048)
			(end 0.120396 0.3048)
			(stroke
				(width 0.1)
				(type default)
			)
			(layer "F.Fab")
		)
		(fp_line
			(start 0.120396 0.3048)
			(end 0.120396 0.2794)
			(stroke
				(width 0.1)
				(type default)
			)
			(layer "F.Fab")
		)
		(fp_line
			(start -0.12065 0.3048)
			(end -0.67945 0.3048)
			(stroke
				(width 0.1)
				(type default)
			)
			(layer "F.Fab")
		)
		(fp_line
			(start -0.67945 0.3048)
			(end -0.67945 -0.305054)
			(stroke
				(width 0.1)
				(type default)
			)
			(layer "F.Fab")
		)
		(pad "1" smd circle
			(at -0.40005 0 90)
			(size 0 0)
			(layers "F.Cu" "F.Mask" "F.Paste")
			(net "PWRGD_P12V_MEM_CPU1_EN")
		)
		(pad "2" smd circle
			(at 0.40005 0 90)
			(size 0 0)
			(layers "F.Cu" "F.Mask" "F.Paste")
			(net "GND")
		)
	)
	(footprint ""
		(layer "F.Cu")
		(at 22.479 -365.76)
		(property "Reference" "R8250"
			(at 0 0 0)
			(layer "F.SilkS")
			(hide yes)
			(effects
				(font
					(size 1.27 1.27)
				)
			)
		)
		(property "Value" ""
			(at 0 0 0)
			(layer "F.Fab")
			(effects
				(font
					(size 1.27 1.27)
				)
			)
		)
		(duplicate_pad_numbers_are_jumpers no)
		(fp_line
			(start -0.7874 -0.4064)
			(end 0.7874 -0.4064)
			(stroke
				(width 0.1524)
				(type default)
			)
			(layer "F.SilkS")
		)
		(fp_line
			(start -0.7874 0.4064)
			(end -0.7874 -0.4064)
			(stroke
				(width 0.1524)
				(type default)
			)
			(layer "F.SilkS")
		)
		(fp_line
			(start 0.7874 -0.4064)
			(end 0.7874 0.4064)
			(stroke
				(width 0.1524)
				(type default)
			)
			(layer "F.SilkS")
		)
		(fp_line
			(start 0.7874 0.4064)
			(end -0.7874 0.4064)
			(stroke
				(width 0.1524)
				(type default)
			)
			(layer "F.SilkS")
		)
		(fp_line
			(start -0.67945 -0.305054)
			(end -0.12065 -0.305054)
			(stroke
				(width 0.1)
				(type default)
			)
			(layer "F.Fab")
		)
		(fp_line
			(start -0.67945 0.3048)
			(end -0.67945 -0.305054)
			(stroke
				(width 0.1)
				(type default)
			)
			(layer "F.Fab")
		)
		(fp_line
			(start -0.12065 -0.305054)
			(end -0.12065 -0.2794)
			(stroke
				(width 0.1)
				(type default)
			)
			(layer "F.Fab")
		)
		(fp_line
			(start -0.12065 -0.2794)
			(end 0.12065 -0.2794)
			(stroke
				(width 0.1)
				(type default)
			)
			(layer "F.Fab")
		)
		(fp_line
			(start -0.12065 0.2794)
			(end -0.12065 0.3048)
			(stroke
				(width 0.1)
				(type default)
			)
			(layer "F.Fab")
		)
		(fp_line
			(start -0.12065 0.3048)
			(end -0.67945 0.3048)
			(stroke
				(width 0.1)
				(type default)
			)
			(layer "F.Fab")
		)
		(fp_line
			(start 0.120396 0.2794)
			(end -0.12065 0.2794)
			(stroke
				(width 0.1)
				(type default)
			)
			(layer "F.Fab")
		)
		(fp_line
			(start 0.120396 0.3048)
			(end 0.120396 0.2794)
			(stroke
				(width 0.1)
				(type default)
			)
			(layer "F.Fab")
		)
		(fp_line
			(start 0.12065 -0.3048)
			(end 0.67945 -0.3048)
			(stroke
				(width 0.1)
				(type default)
			)
			(layer "F.Fab")
		)
		(fp_line
			(start 0.12065 -0.2794)
			(end 0.12065 -0.3048)
			(stroke
				(width 0.1)
				(type default)
			)
			(layer "F.Fab")
		)
		(fp_line
			(start 0.67945 -0.3048)
			(end 0.67945 0.3048)
			(stroke
				(width 0.1)
				(type default)
			)
			(layer "F.Fab")
		)
		(fp_line
			(start 0.67945 0.3048)
			(end 0.120396 0.3048)
			(stroke
				(width 0.1)
				(type default)
			)
			(layer "F.Fab")
		)
		(pad "1" smd circle
			(at -0.40005 0)
			(size 0 0)
			(layers "F.Cu" "F.Mask" "F.Paste")
			(net "PVDDCR_CPU1_P1_SMB_ALERT")
		)
		(pad "2" smd circle
			(at 0.40005 0)
			(size 0 0)
			(layers "F.Cu" "F.Mask" "F.Paste")
			(net "PVDDCR_CPU1_P1_SMB_ALERT_R")
		)
	)
	(footprint ""
		(layer "F.Cu")
		(at 396.58163 -146.354292 -90)
		(property "Reference" "C1227"
			(at 0 0 270)
			(layer "F.SilkS")
			(hide yes)
			(effects
				(font
					(size 1.27 1.27)
				)
			)
		)
		(property "Value" ""
			(at 0 0 270)
			(layer "F.Fab")
			(effects
				(font
					(size 1.27 1.27)
				)
			)
		)
		(duplicate_pad_numbers_are_jumpers no)
		(fp_line
			(start -0.7874 0.4064)
			(end -0.7874 -0.4064)
			(stroke
				(width 0.1524)
				(type default)
			)
			(layer "F.SilkS")
		)
		(fp_line
			(start 0.7874 0.4064)
			(end -0.7874 0.4064)
			(stroke
				(width 0.1524)
				(type default)
			)
			(layer "F.SilkS")
		)
		(fp_line
			(start -0.7874 -0.4064)
			(end 0.7874 -0.4064)
			(stroke
				(width 0.1524)
				(type default)
			)
			(layer "F.SilkS")
		)
		(fp_line
			(start 0.7874 -0.4064)
			(end 0.7874 0.4064)
			(stroke
				(width 0.1524)
				(type default)
			)
			(layer "F.SilkS")
		)
		(fp_line
			(start -0.67945 0.3048)
			(end -0.67945 -0.305054)
			(stroke
				(width 0.1)
				(type default)
			)
			(layer "F.Fab")
		)
		(fp_line
			(start -0.12065 0.3048)
			(end -0.67945 0.3048)
			(stroke
				(width 0.1)
				(type default)
			)
			(layer "F.Fab")
		)
		(fp_line
			(start 0.120396 0.3048)
			(end 0.120396 0.2794)
			(stroke
				(width 0.1)
				(type default)
			)
			(layer "F.Fab")
		)
		(fp_line
			(start 0.67945 0.3048)
			(end 0.120396 0.3048)
			(stroke
				(width 0.1)
				(type default)
			)
			(layer "F.Fab")
		)
		(fp_line
			(start -0.12065 0.2794)
			(end -0.12065 0.3048)
			(stroke
				(width 0.1)
				(type default)
			)
			(layer "F.Fab")
		)
		(fp_line
			(start 0.120396 0.2794)
			(end -0.12065 0.2794)
			(stroke
				(width 0.1)
				(type default)
			)
			(layer "F.Fab")
		)
		(fp_line
			(start -0.12065 -0.2794)
			(end 0.12065 -0.2794)
			(stroke
				(width 0.1)
				(type default)
			)
			(layer "F.Fab")
		)
		(fp_line
			(start 0.12065 -0.2794)
			(end 0.12065 -0.3048)
			(stroke
				(width 0.1)
				(type default)
			)
			(layer "F.Fab")
		)
		(fp_line
			(start 0.12065 -0.3048)
			(end 0.67945 -0.3048)
			(stroke
				(width 0.1)
				(type default)
			)
			(layer "F.Fab")
		)
		(fp_line
			(start 0.67945 -0.3048)
			(end 0.67945 0.3048)
			(stroke
				(width 0.1)
				(type default)
			)
			(layer "F.Fab")
		)
		(fp_line
			(start -0.67945 -0.305054)
			(end -0.12065 -0.305054)
			(stroke
				(width 0.1)
				(type default)
			)
			(layer "F.Fab")
		)
		(fp_line
			(start -0.12065 -0.305054)
			(end -0.12065 -0.2794)
			(stroke
				(width 0.1)
				(type default)
			)
			(layer "F.Fab")
		)
		(pad "1" smd circle
			(at -0.40005 0 270)
			(size 0 0)
			(layers "F.Cu" "F.Mask" "F.Paste")
			(net "P5V")
		)
		(pad "2" smd circle
			(at 0.40005 0 270)
			(size 0 0)
			(layers "F.Cu" "F.Mask" "F.Paste")
			(net "GND")
		)
	)
	(footprint ""
		(layer "F.Cu")
		(at 450.008752 -395.699234 90)
		(property "Reference" "PR6563"
			(at 0 0 90)
			(layer "F.SilkS")
			(hide yes)
			(effects
				(font
					(size 1.27 1.27)
				)
			)
		)
		(property "Value" ""
			(at 0 0 90)
			(layer "F.Fab")
			(effects
				(font
					(size 1.27 1.27)
				)
			)
		)
		(duplicate_pad_numbers_are_jumpers no)
		(fp_line
			(start 0.7874 -0.4064)
			(end 0.7874 0.4064)
			(stroke
				(width 0.1524)
				(type default)
			)
			(layer "F.SilkS")
		)
		(fp_line
			(start -0.7874 -0.4064)
			(end 0.7874 -0.4064)
			(stroke
				(width 0.1524)
				(type default)
			)
			(layer "F.SilkS")
		)
		(fp_line
			(start 0.7874 0.4064)
			(end -0.7874 0.4064)
			(stroke
				(width 0.1524)
				(type default)
			)
			(layer "F.SilkS")
		)
		(fp_line
			(start -0.7874 0.4064)
			(end -0.7874 -0.4064)
			(stroke
				(width 0.1524)
				(type default)
			)
			(layer "F.SilkS")
		)
		(fp_line
			(start -0.12065 -0.305054)
			(end -0.12065 -0.2794)
			(stroke
				(width 0.1)
				(type default)
			)
			(layer "F.Fab")
		)
		(fp_line
			(start -0.67945 -0.305054)
			(end -0.12065 -0.305054)
			(stroke
				(width 0.1)
				(type default)
			)
			(layer "F.Fab")
		)
		(fp_line
			(start 0.67945 -0.3048)
			(end 0.67945 0.3048)
			(stroke
				(width 0.1)
				(type default)
			)
			(layer "F.Fab")
		)
		(fp_line
			(start 0.12065 -0.3048)
			(end 0.67945 -0.3048)
			(stroke
				(width 0.1)
				(type default)
			)
			(layer "F.Fab")
		)
		(fp_line
			(start 0.12065 -0.2794)
			(end 0.12065 -0.3048)
			(stroke
				(width 0.1)
				(type default)
			)
			(layer "F.Fab")
		)
		(fp_line
			(start -0.12065 -0.2794)
			(end 0.12065 -0.2794)
			(stroke
				(width 0.1)
				(type default)
			)
			(layer "F.Fab")
		)
		(fp_line
			(start 0.120396 0.2794)
			(end -0.12065 0.2794)
			(stroke
				(width 0.1)
				(type default)
			)
			(layer "F.Fab")
		)
		(fp_line
			(start -0.12065 0.2794)
			(end -0.12065 0.3048)
			(stroke
				(width 0.1)
				(type default)
			)
			(layer "F.Fab")
		)
		(fp_line
			(start 0.67945 0.3048)
			(end 0.120396 0.3048)
			(stroke
				(width 0.1)
				(type default)
			)
			(layer "F.Fab")
		)
		(fp_line
			(start 0.120396 0.3048)
			(end 0.120396 0.2794)
			(stroke
				(width 0.1)
				(type default)
			)
			(layer "F.Fab")
		)
		(fp_line
			(start -0.12065 0.3048)
			(end -0.67945 0.3048)
			(stroke
				(width 0.1)
				(type default)
			)
			(layer "F.Fab")
		)
		(fp_line
			(start -0.67945 0.3048)
			(end -0.67945 -0.305054)
			(stroke
				(width 0.1)
				(type default)
			)
			(layer "F.Fab")
		)
		(pad "1" smd circle
			(at -0.40005 0 90)
			(size 0 0)
			(layers "F.Cu" "F.Mask" "F.Paste")
			(net "SW_P0V9_RETIMER_CPU0_SW2_RC")
		)
		(pad "2" smd circle
			(at 0.40005 0 90)
			(size 0 0)
			(layers "F.Cu" "F.Mask" "F.Paste")
			(net "GND")
		)
	)
	(footprint ""
		(layer "F.Cu")
		(at 163.4236 -436.153052)
		(property "Reference" "R3438"
			(at 0 0 0)
			(layer "F.SilkS")
			(hide yes)
			(effects
				(font
					(size 1.27 1.27)
				)
			)
		)
		(property "Value" ""
			(at 0 0 0)
			(layer "F.Fab")
			(effects
				(font
					(size 1.27 1.27)
				)
			)
		)
		(duplicate_pad_numbers_are_jumpers no)
		(fp_line
			(start -0.7874 -0.4064)
			(end 0.7874 -0.4064)
			(stroke
				(width 0.1524)
				(type default)
			)
			(layer "F.SilkS")
		)
		(fp_line
			(start -0.7874 0.4064)
			(end -0.7874 -0.4064)
			(stroke
				(width 0.1524)
				(type default)
			)
			(layer "F.SilkS")
		)
		(fp_line
			(start 0.7874 -0.4064)
			(end 0.7874 0.4064)
			(stroke
				(width 0.1524)
				(type default)
			)
			(layer "F.SilkS")
		)
		(fp_line
			(start 0.7874 0.4064)
			(end -0.7874 0.4064)
			(stroke
				(width 0.1524)
				(type default)
			)
			(layer "F.SilkS")
		)
		(fp_line
			(start -0.67945 -0.305054)
			(end -0.12065 -0.305054)
			(stroke
				(width 0.1)
				(type default)
			)
			(layer "F.Fab")
		)
		(fp_line
			(start -0.67945 0.3048)
			(end -0.67945 -0.305054)
			(stroke
				(width 0.1)
				(type default)
			)
			(layer "F.Fab")
		)
		(fp_line
			(start -0.12065 -0.305054)
			(end -0.12065 -0.2794)
			(stroke
				(width 0.1)
				(type default)
			)
			(layer "F.Fab")
		)
		(fp_line
			(start -0.12065 -0.2794)
			(end 0.12065 -0.2794)
			(stroke
				(width 0.1)
				(type default)
			)
			(layer "F.Fab")
		)
		(fp_line
			(start -0.12065 0.2794)
			(end -0.12065 0.3048)
			(stroke
				(width 0.1)
				(type default)
			)
			(layer "F.Fab")
		)
		(fp_line
			(start -0.12065 0.3048)
			(end -0.67945 0.3048)
			(stroke
				(width 0.1)
				(type default)
			)
			(layer "F.Fab")
		)
		(fp_line
			(start 0.120396 0.2794)
			(end -0.12065 0.2794)
			(stroke
				(width 0.1)
				(type default)
			)
			(layer "F.Fab")
		)
		(fp_line
			(start 0.120396 0.3048)
			(end 0.120396 0.2794)
			(stroke
				(width 0.1)
				(type default)
			)
			(layer "F.Fab")
		)
		(fp_line
			(start 0.12065 -0.3048)
			(end 0.67945 -0.3048)
			(stroke
				(width 0.1)
				(type default)
			)
			(layer "F.Fab")
		)
		(fp_line
			(start 0.12065 -0.2794)
			(end 0.12065 -0.3048)
			(stroke
				(width 0.1)
				(type default)
			)
			(layer "F.Fab")
		)
		(fp_line
			(start 0.67945 -0.3048)
			(end 0.67945 0.3048)
			(stroke
				(width 0.1)
				(type default)
			)
			(layer "F.Fab")
		)
		(fp_line
			(start 0.67945 0.3048)
			(end 0.120396 0.3048)
			(stroke
				(width 0.1)
				(type default)
			)
			(layer "F.Fab")
		)
		(pad "1" smd circle
			(at -0.40005 0)
			(size 0 0)
			(layers "F.Cu" "F.Mask" "F.Paste")
			(net "P3V3_AUX")
		)
		(pad "2" smd circle
			(at 0.40005 0)
			(size 0 0)
			(layers "F.Cu" "F.Mask" "F.Paste")
			(net "GPU_BASE_HMC_READY_ISO")
		)
	)
	(footprint ""
		(layer "F.Cu")
		(at 197.269608 -117.689376)
		(property "Reference" "R685"
			(at 0 0 0)
			(layer "F.SilkS")
			(hide yes)
			(effects
				(font
					(size 1.27 1.27)
				)
			)
		)
		(property "Value" ""
			(at 0 0 0)
			(layer "F.Fab")
			(effects
				(font
					(size 1.27 1.27)
				)
			)
		)
		(duplicate_pad_numbers_are_jumpers no)
		(fp_line
			(start -0.7874 -0.4064)
			(end 0.7874 -0.4064)
			(stroke
				(width 0.1524)
				(type default)
			)
			(layer "F.SilkS")
		)
		(fp_line
			(start -0.7874 0.4064)
			(end -0.7874 -0.4064)
			(stroke
				(width 0.1524)
				(type default)
			)
			(layer "F.SilkS")
		)
		(fp_line
			(start 0.7874 -0.4064)
			(end 0.7874 0.4064)
			(stroke
				(width 0.1524)
				(type default)
			)
			(layer "F.SilkS")
		)
		(fp_line
			(start 0.7874 0.4064)
			(end -0.7874 0.4064)
			(stroke
				(width 0.1524)
				(type default)
			)
			(layer "F.SilkS")
		)
		(fp_line
			(start -0.67945 -0.305054)
			(end -0.12065 -0.305054)
			(stroke
				(width 0.1)
				(type default)
			)
			(layer "F.Fab")
		)
		(fp_line
			(start -0.67945 0.3048)
			(end -0.67945 -0.305054)
			(stroke
				(width 0.1)
				(type default)
			)
			(layer "F.Fab")
		)
		(fp_line
			(start -0.12065 -0.305054)
			(end -0.12065 -0.2794)
			(stroke
				(width 0.1)
				(type default)
			)
			(layer "F.Fab")
		)
		(fp_line
			(start -0.12065 -0.2794)
			(end 0.12065 -0.2794)
			(stroke
				(width 0.1)
				(type default)
			)
			(layer "F.Fab")
		)
		(fp_line
			(start -0.12065 0.2794)
			(end -0.12065 0.3048)
			(stroke
				(width 0.1)
				(type default)
			)
			(layer "F.Fab")
		)
		(fp_line
			(start -0.12065 0.3048)
			(end -0.67945 0.3048)
			(stroke
				(width 0.1)
				(type default)
			)
			(layer "F.Fab")
		)
		(fp_line
			(start 0.120396 0.2794)
			(end -0.12065 0.2794)
			(stroke
				(width 0.1)
				(type default)
			)
			(layer "F.Fab")
		)
		(fp_line
			(start 0.120396 0.3048)
			(end 0.120396 0.2794)
			(stroke
				(width 0.1)
				(type default)
			)
			(layer "F.Fab")
		)
		(fp_line
			(start 0.12065 -0.3048)
			(end 0.67945 -0.3048)
			(stroke
				(width 0.1)
				(type default)
			)
			(layer "F.Fab")
		)
		(fp_line
			(start 0.12065 -0.2794)
			(end 0.12065 -0.3048)
			(stroke
				(width 0.1)
				(type default)
			)
			(layer "F.Fab")
		)
		(fp_line
			(start 0.67945 -0.3048)
			(end 0.67945 0.3048)
			(stroke
				(width 0.1)
				(type default)
			)
			(layer "F.Fab")
		)
		(fp_line
			(start 0.67945 0.3048)
			(end 0.120396 0.3048)
			(stroke
				(width 0.1)
				(type default)
			)
			(layer "F.Fab")
		)
		(pad "1" smd circle
			(at -0.40005 0)
			(size 0 0)
			(layers "F.Cu" "F.Mask" "F.Paste")
			(net "RST_PERST_E1S_0_R_N")
		)
		(pad "2" smd circle
			(at 0.40005 0)
			(size 0 0)
			(layers "F.Cu" "F.Mask" "F.Paste")
			(net "RST_PERST_E1S_0_N")
		)
	)
	(footprint ""
		(layer "F.Cu")
		(at 126.111 -321.655948 90)
		(property "Reference" "R3352"
			(at 0 0 90)
			(layer "F.SilkS")
			(hide yes)
			(effects
				(font
					(size 1.27 1.27)
				)
			)
		)
		(property "Value" ""
			(at 0 0 90)
			(layer "F.Fab")
			(effects
				(font
					(size 1.27 1.27)
				)
			)
		)
		(duplicate_pad_numbers_are_jumpers no)
		(fp_line
			(start -0.371348 -0.4064)
			(end 0.390652 -0.4064)
			(stroke
				(width 0.1524)
				(type default)
			)
			(layer "F.SilkS")
		)
		(fp_line
			(start 0.7874 0)
			(end 0.7874 0.4064)
			(stroke
				(width 0.1524)
				(type default)
			)
			(layer "F.SilkS")
		)
		(fp_line
			(start 0.7874 0.4064)
			(end -0.7874 0.4064)
			(stroke
				(width 0.1524)
				(type default)
			)
			(layer "F.SilkS")
		)
		(fp_line
			(start -0.7874 0.4064)
			(end -0.7874 0.0254)
			(stroke
				(width 0.1524)
				(type default)
			)
			(layer "F.SilkS")
		)
		(fp_line
			(start -0.12065 -0.305054)
			(end -0.12065 -0.2794)
			(stroke
				(width 0.1)
				(type default)
			)
			(layer "F.Fab")
		)
		(fp_line
			(start -0.67945 -0.305054)
			(end -0.12065 -0.305054)
			(stroke
				(width 0.1)
				(type default)
			)
			(layer "F.Fab")
		)
		(fp_line
			(start 0.67945 -0.3048)
			(end 0.67945 0.3048)
			(stroke
				(width 0.1)
				(type default)
			)
			(layer "F.Fab")
		)
		(fp_line
			(start 0.12065 -0.3048)
			(end 0.67945 -0.3048)
			(stroke
				(width 0.1)
				(type default)
			)
			(layer "F.Fab")
		)
		(fp_line
			(start 0.12065 -0.2794)
			(end 0.12065 -0.3048)
			(stroke
				(width 0.1)
				(type default)
			)
			(layer "F.Fab")
		)
		(fp_line
			(start -0.12065 -0.2794)
			(end 0.12065 -0.2794)
			(stroke
				(width 0.1)
				(type default)
			)
			(layer "F.Fab")
		)
		(fp_line
			(start 0.120396 0.2794)
			(end -0.12065 0.2794)
			(stroke
				(width 0.1)
				(type default)
			)
			(layer "F.Fab")
		)
		(fp_line
			(start -0.12065 0.2794)
			(end -0.12065 0.3048)
			(stroke
				(width 0.1)
				(type default)
			)
			(layer "F.Fab")
		)
		(fp_line
			(start 0.67945 0.3048)
			(end 0.120396 0.3048)
			(stroke
				(width 0.1)
				(type default)
			)
			(layer "F.Fab")
		)
		(fp_line
			(start 0.120396 0.3048)
			(end 0.120396 0.2794)
			(stroke
				(width 0.1)
				(type default)
			)
			(layer "F.Fab")
		)
		(fp_line
			(start -0.12065 0.3048)
			(end -0.67945 0.3048)
			(stroke
				(width 0.1)
				(type default)
			)
			(layer "F.Fab")
		)
		(fp_line
			(start -0.67945 0.3048)
			(end -0.67945 -0.305054)
			(stroke
				(width 0.1)
				(type default)
			)
			(layer "F.Fab")
		)
		(pad "1" smd circle
			(at -0.40005 0 90)
			(size 0 0)
			(layers "F.Cu" "F.Mask" "F.Paste")
			(net "CLK_100M_CPU1_CLK11_R_DP")
		)
		(pad "2" smd circle
			(at 0.40005 0 90)
			(size 0 0)
			(layers "F.Cu" "F.Mask" "F.Paste")
			(net "CLK_100M_CPU1_CLK11_DP")
		)
	)
	(footprint ""
		(layer "F.Cu")
		(at 167.132 -109.184948 180)
		(property "Reference" "R6096"
			(at 0 0 180)
			(layer "F.SilkS")
			(hide yes)
			(effects
				(font
					(size 1.27 1.27)
				)
			)
		)
		(property "Value" ""
			(at 0 0 180)
			(layer "F.Fab")
			(effects
				(font
					(size 1.27 1.27)
				)
			)
		)
		(duplicate_pad_numbers_are_jumpers no)
		(fp_line
			(start 0.7874 0.4064)
			(end -0.7874 0.4064)
			(stroke
				(width 0.1524)
				(type default)
			)
			(layer "F.SilkS")
		)
		(fp_line
			(start 0.7874 -0.4064)
			(end 0.7874 0.4064)
			(stroke
				(width 0.1524)
				(type default)
			)
			(layer "F.SilkS")
		)
		(fp_line
			(start -0.7874 0.4064)
			(end -0.7874 -0.4064)
			(stroke
				(width 0.1524)
				(type default)
			)
			(layer "F.SilkS")
		)
		(fp_line
			(start -0.7874 -0.4064)
			(end 0.7874 -0.4064)
			(stroke
				(width 0.1524)
				(type default)
			)
			(layer "F.SilkS")
		)
		(fp_line
			(start 0.67945 0.3048)
			(end 0.120396 0.3048)
			(stroke
				(width 0.1)
				(type default)
			)
			(layer "F.Fab")
		)
		(fp_line
			(start 0.67945 -0.3048)
			(end 0.67945 0.3048)
			(stroke
				(width 0.1)
				(type default)
			)
			(layer "F.Fab")
		)
		(fp_line
			(start 0.12065 -0.2794)
			(end 0.12065 -0.3048)
			(stroke
				(width 0.1)
				(type default)
			)
			(layer "F.Fab")
		)
		(fp_line
			(start 0.12065 -0.3048)
			(end 0.67945 -0.3048)
			(stroke
				(width 0.1)
				(type default)
			)
			(layer "F.Fab")
		)
		(fp_line
			(start 0.120396 0.3048)
			(end 0.120396 0.2794)
			(stroke
				(width 0.1)
				(type default)
			)
			(layer "F.Fab")
		)
		(fp_line
			(start 0.120396 0.2794)
			(end -0.12065 0.2794)
			(stroke
				(width 0.1)
				(type default)
			)
			(layer "F.Fab")
		)
		(fp_line
			(start -0.12065 0.3048)
			(end -0.67945 0.3048)
			(stroke
				(width 0.1)
				(type default)
			)
			(layer "F.Fab")
		)
		(fp_line
			(start -0.12065 0.2794)
			(end -0.12065 0.3048)
			(stroke
				(width 0.1)
				(type default)
			)
			(layer "F.Fab")
		)
		(fp_line
			(start -0.12065 -0.2794)
			(end 0.12065 -0.2794)
			(stroke
				(width 0.1)
				(type default)
			)
			(layer "F.Fab")
		)
		(fp_line
			(start -0.12065 -0.305054)
			(end -0.12065 -0.2794)
			(stroke
				(width 0.1)
				(type default)
			)
			(layer "F.Fab")
		)
		(fp_line
			(start -0.67945 0.3048)
			(end -0.67945 -0.305054)
			(stroke
				(width 0.1)
				(type default)
			)
			(layer "F.Fab")
		)
		(fp_line
			(start -0.67945 -0.305054)
			(end -0.12065 -0.305054)
			(stroke
				(width 0.1)
				(type default)
			)
			(layer "F.Fab")
		)
		(pad "1" smd circle
			(at -0.40005 0 180)
			(size 0 0)
			(layers "F.Cu" "F.Mask" "F.Paste")
			(net "FM_UV_ADR_TRIGGER_R_N")
		)
		(pad "2" smd circle
			(at 0.40005 0 180)
			(size 0 0)
			(layers "F.Cu" "F.Mask" "F.Paste")
			(net "FM_UV_ADR_TRIGGER_N")
		)
	)
	(footprint ""
		(layer "F.Cu")
		(at 69.862446 -385.09448 180)
		(property "Reference" "R6702"
			(at 0 0 180)
			(layer "F.SilkS")
			(hide yes)
			(effects
				(font
					(size 1.27 1.27)
				)
			)
		)
		(property "Value" ""
			(at 0 0 180)
			(layer "F.Fab")
			(effects
				(font
					(size 1.27 1.27)
				)
			)
		)
		(duplicate_pad_numbers_are_jumpers no)
		(fp_line
			(start 0.7874 0.4064)
			(end -0.7874 0.4064)
			(stroke
				(width 0.1524)
				(type default)
			)
			(layer "F.SilkS")
		)
		(fp_line
			(start 0.7874 -0.4064)
			(end 0.7874 0.4064)
			(stroke
				(width 0.1524)
				(type default)
			)
			(layer "F.SilkS")
		)
		(fp_line
			(start -0.7874 0.4064)
			(end -0.7874 -0.4064)
			(stroke
				(width 0.1524)
				(type default)
			)
			(layer "F.SilkS")
		)
		(fp_line
			(start -0.7874 -0.4064)
			(end 0.7874 -0.4064)
			(stroke
				(width 0.1524)
				(type default)
			)
			(layer "F.SilkS")
		)
		(fp_line
			(start 0.67945 0.3048)
			(end 0.120396 0.3048)
			(stroke
				(width 0.1)
				(type default)
			)
			(layer "F.Fab")
		)
		(fp_line
			(start 0.67945 -0.3048)
			(end 0.67945 0.3048)
			(stroke
				(width 0.1)
				(type default)
			)
			(layer "F.Fab")
		)
		(fp_line
			(start 0.12065 -0.2794)
			(end 0.12065 -0.3048)
			(stroke
				(width 0.1)
				(type default)
			)
			(layer "F.Fab")
		)
		(fp_line
			(start 0.12065 -0.3048)
			(end 0.67945 -0.3048)
			(stroke
				(width 0.1)
				(type default)
			)
			(layer "F.Fab")
		)
		(fp_line
			(start 0.120396 0.3048)
			(end 0.120396 0.2794)
			(stroke
				(width 0.1)
				(type default)
			)
			(layer "F.Fab")
		)
		(fp_line
			(start 0.120396 0.2794)
			(end -0.12065 0.2794)
			(stroke
				(width 0.1)
				(type default)
			)
			(layer "F.Fab")
		)
		(fp_line
			(start -0.12065 0.3048)
			(end -0.67945 0.3048)
			(stroke
				(width 0.1)
				(type default)
			)
			(layer "F.Fab")
		)
		(fp_line
			(start -0.12065 0.2794)
			(end -0.12065 0.3048)
			(stroke
				(width 0.1)
				(type default)
			)
			(layer "F.Fab")
		)
		(fp_line
			(start -0.12065 -0.2794)
			(end 0.12065 -0.2794)
			(stroke
				(width 0.1)
				(type default)
			)
			(layer "F.Fab")
		)
		(fp_line
			(start -0.12065 -0.305054)
			(end -0.12065 -0.2794)
			(stroke
				(width 0.1)
				(type default)
			)
			(layer "F.Fab")
		)
		(fp_line
			(start -0.67945 0.3048)
			(end -0.67945 -0.305054)
			(stroke
				(width 0.1)
				(type default)
			)
			(layer "F.Fab")
		)
		(fp_line
			(start -0.67945 -0.305054)
			(end -0.12065 -0.305054)
			(stroke
				(width 0.1)
				(type default)
			)
			(layer "F.Fab")
		)
		(pad "1" smd rect
			(at -0.40005 0)
			(size 0.4572 0.508)
			(layers "F.Cu" "F.Mask" "F.Paste")
			(net "P1V8_CPU1_RT0_1A_1D")
		)
		(pad "2" smd rect
			(at 0.40005 0)
			(size 0.4572 0.508)
			(layers "F.Cu" "F.Mask" "F.Paste")
			(net "P1V8_CPU1_RT0_1A")
		)
	)
	(footprint ""
		(layer "F.Cu")
		(at 290.230052 -255.560068 180)
		(property "Reference" "J17"
			(at -2.2098 -81.984088 0)
			(unlocked yes)
			(layer "F.SilkS")
			(effects
				(font
					(size 0.7874 0.5842)
					(thickness 0.1524)
				)
			)
		)
		(property "Value" ""
			(at 0 0 180)
			(layer "F.Fab")
			(effects
				(font
					(size 1.27 1.27)
				)
			)
		)
		(duplicate_pad_numbers_are_jumpers no)
		(fp_line
			(start 3.24993 -81.000092)
			(end 3.24993 75.625452)
			(stroke
				(width 0.1524)
				(type default)
			)
			(layer "F.SilkS")
		)
		(fp_line
			(start -3.24993 75.617832)
			(end -3.24993 -81.000092)
			(stroke
				(width 0.1524)
				(type default)
			)
			(layer "F.SilkS")
		)
		(fp_line
			(start -3.24993 72.499982)
			(end 3.24993 72.499982)
			(stroke
				(width 0.1524)
				(type default)
			)
			(layer "F.SilkS")
		)
		(fp_line
			(start -3.24993 -72.499982)
			(end 3.24993 -72.499982)
			(stroke
				(width 0.1524)
				(type default)
			)
			(layer "F.SilkS")
		)
		(fp_line
			(start -3.24993 -81.000092)
			(end 3.24993 -81.000092)
			(stroke
				(width 0.1524)
				(type default)
			)
			(layer "F.SilkS")
		)
		(fp_poly
			(pts
				(xy -3.836924 -64.477138) (xy -3.382518 -63.9318) (xy -4.091432 -63.895478)
			)
			(stroke
				(width 0)
				(type default)
			)
			(fill yes)
			(layer "F.SilkS")
		)
		(fp_line
			(start 3.24993 81.000092)
			(end -3.24993 81.000092)
			(stroke
				(width 0.1)
				(type default)
			)
			(layer "F.Fab")
		)
		(fp_line
			(start 3.24993 -81.000092)
			(end 3.24993 81.000092)
			(stroke
				(width 0.1)
				(type default)
			)
			(layer "F.Fab")
		)
		(fp_line
			(start -3.24993 81.000092)
			(end -3.24993 -81.000092)
			(stroke
				(width 0.1)
				(type default)
			)
			(layer "F.Fab")
		)
		(fp_line
			(start -3.24993 72.499982)
			(end 3.24993 72.499982)
			(stroke
				(width 0.1)
				(type default)
			)
			(layer "F.Fab")
		)
		(fp_line
			(start -3.24993 71.000112)
			(end 3.24993 71.000112)
			(stroke
				(width 0.1)
				(type default)
			)
			(layer "F.Fab")
		)
		(fp_line
			(start -3.24993 -71.000112)
			(end 3.24993 -71.000112)
			(stroke
				(width 0.1)
				(type default)
			)
			(layer "F.Fab")
		)
		(fp_line
			(start -3.24993 -72.499982)
			(end 3.24993 -72.499982)
			(stroke
				(width 0.1)
				(type default)
			)
			(layer "F.Fab")
		)
		(fp_line
			(start -3.24993 -81.000092)
			(end 3.24993 -81.000092)
			(stroke
				(width 0.1)
				(type default)
			)
			(layer "F.Fab")
		)
		(fp_poly
			(pts
				(xy -3.41503 -63.324994) (xy -4.43103 -62.816994) (xy -4.43103 -63.832994)
			)
			(stroke
				(width 0)
				(type default)
			)
			(fill yes)
			(layer "F.Fab")
		)
		(pad "1" smd rect
			(at -2.050034 -63.324994 90)
			(size 0.519938 1.4986)
			(layers "F.Cu" "F.Mask" "F.Paste")
			(net "P12V_MEM_CPU0")
		)
		(pad "2" smd rect
			(at -2.050034 -62.47511 90)
			(size 0.519938 1.4986)
			(layers "F.Cu" "F.Mask" "F.Paste")
			(net "Net_2277")
		)
		(pad "3" smd rect
			(at -2.050034 -61.624972 90)
			(size 0.519938 1.4986)
			(layers "F.Cu" "F.Mask" "F.Paste")
			(net "P3V3_AUX")
		)
		(pad "4" smd rect
			(at -2.050034 -60.775088 90)
			(size 0.519938 1.4986)
			(layers "F.Cu" "F.Mask" "F.Paste")
			(net "I3C_SPD_DDRC_CPU0_SCL")
		)
		(pad "5" smd rect
			(at -2.050034 -59.92495 90)
			(size 0.519938 1.4986)
			(layers "F.Cu" "F.Mask" "F.Paste")
			(net "I3C_SPD_DDRC_CPU0_SDA")
		)
		(pad "6" smd rect
			(at -2.050034 -59.075066 90)
			(size 0.519938 1.4986)
			(layers "F.Cu" "F.Mask" "F.Paste")
			(net "GND")
		)
		(pad "7" smd rect
			(at -2.050034 -58.224928 90)
			(size 0.519938 1.4986)
			(layers "F.Cu" "F.Mask" "F.Paste")
			(net "M_C_CPU0_SA_DQ<0>")
		)
		(pad "8" smd rect
			(at -2.050034 -57.375044 90)
			(size 0.519938 1.4986)
			(layers "F.Cu" "F.Mask" "F.Paste")
			(net "GND")
		)
		(pad "9" smd rect
			(at -2.050034 -56.524906 90)
			(size 0.519938 1.4986)
			(layers "F.Cu" "F.Mask" "F.Paste")
			(net "M_C_CPU0_SA_DQ<1>")
		)
		(pad "10" smd rect
			(at -2.050034 -55.675022 90)
			(size 0.519938 1.4986)
			(layers "F.Cu" "F.Mask" "F.Paste")
			(net "GND")
		)
		(pad "11" smd rect
			(at -2.050034 -54.824884 90)
			(size 0.519938 1.4986)
			(layers "F.Cu" "F.Mask" "F.Paste")
			(net "M_C_CPU0_SA_DQS_DP<0>")
		)
		(pad "12" smd rect
			(at -2.050034 -53.975 90)
			(size 0.519938 1.4986)
			(layers "F.Cu" "F.Mask" "F.Paste")
			(net "M_C_CPU0_SA_DQS_DN<0>")
		)
		(pad "13" smd rect
			(at -2.050034 -53.125116 90)
			(size 0.519938 1.4986)
			(layers "F.Cu" "F.Mask" "F.Paste")
			(net "GND")
		)
		(pad "14" smd rect
			(at -2.050034 -52.274978 90)
			(size 0.519938 1.4986)
			(layers "F.Cu" "F.Mask" "F.Paste")
			(net "M_C_CPU0_SA_DQ<4>")
		)
		(pad "15" smd rect
			(at -2.050034 -51.425094 90)
			(size 0.519938 1.4986)
			(layers "F.Cu" "F.Mask" "F.Paste")
			(net "GND")
		)
		(pad "16" smd rect
			(at -2.050034 -50.574956 90)
			(size 0.519938 1.4986)
			(layers "F.Cu" "F.Mask" "F.Paste")
			(net "M_C_CPU0_SA_DQ<5>")
		)
		(pad "17" smd rect
			(at -2.050034 -49.725072 90)
			(size 0.519938 1.4986)
			(layers "F.Cu" "F.Mask" "F.Paste")
			(net "GND")
		)
		(pad "18" smd rect
			(at -2.050034 -48.874934 90)
			(size 0.519938 1.4986)
			(layers "F.Cu" "F.Mask" "F.Paste")
			(net "M_C_CPU0_SA_DQ<8>")
		)
		(pad "19" smd rect
			(at -2.050034 -48.02505 90)
			(size 0.519938 1.4986)
			(layers "F.Cu" "F.Mask" "F.Paste")
			(net "GND")
		)
		(pad "20" smd rect
			(at -2.050034 -47.174912 90)
			(size 0.519938 1.4986)
			(layers "F.Cu" "F.Mask" "F.Paste")
			(net "M_C_CPU0_SA_DQ<9>")
		)
		(pad "21" smd rect
			(at -2.050034 -46.325028 90)
			(size 0.519938 1.4986)
			(layers "F.Cu" "F.Mask" "F.Paste")
			(net "GND")
		)
		(pad "22" smd rect
			(at -2.050034 -45.47489 90)
			(size 0.519938 1.4986)
			(layers "F.Cu" "F.Mask" "F.Paste")
			(net "M_C_CPU0_SA_DQS_DP<1>")
		)
		(pad "23" smd rect
			(at -2.050034 -44.625006 90)
			(size 0.519938 1.4986)
			(layers "F.Cu" "F.Mask" "F.Paste")
			(net "M_C_CPU0_SA_DQS_DN<1>")
		)
		(pad "24" smd rect
			(at -2.050034 -43.775122 90)
			(size 0.519938 1.4986)
			(layers "F.Cu" "F.Mask" "F.Paste")
			(net "GND")
		)
		(pad "25" smd rect
			(at -2.050034 -42.924984 90)
			(size 0.519938 1.4986)
			(layers "F.Cu" "F.Mask" "F.Paste")
			(net "M_C_CPU0_SA_DQ<12>")
		)
		(pad "26" smd rect
			(at -2.050034 -42.0751 90)
			(size 0.519938 1.4986)
			(layers "F.Cu" "F.Mask" "F.Paste")
			(net "GND")
		)
		(pad "27" smd rect
			(at -2.050034 -41.224962 90)
			(size 0.519938 1.4986)
			(layers "F.Cu" "F.Mask" "F.Paste")
			(net "M_C_CPU0_SA_DQ<13>")
		)
		(pad "28" smd rect
			(at -2.050034 -40.375078 90)
			(size 0.519938 1.4986)
			(layers "F.Cu" "F.Mask" "F.Paste")
			(net "GND")
		)
		(pad "29" smd rect
			(at -2.050034 -39.52494 90)
			(size 0.519938 1.4986)
			(layers "F.Cu" "F.Mask" "F.Paste")
			(net "M_C_CPU0_SA_DQ<16>")
		)
		(pad "30" smd rect
			(at -2.050034 -38.675056 90)
			(size 0.519938 1.4986)
			(layers "F.Cu" "F.Mask" "F.Paste")
			(net "GND")
		)
		(pad "31" smd rect
			(at -2.050034 -37.824918 90)
			(size 0.519938 1.4986)
			(layers "F.Cu" "F.Mask" "F.Paste")
			(net "M_C_CPU0_SA_DQ<17>")
		)
		(pad "32" smd rect
			(at -2.050034 -36.975034 90)
			(size 0.519938 1.4986)
			(layers "F.Cu" "F.Mask" "F.Paste")
			(net "GND")
		)
		(pad "33" smd rect
			(at -2.050034 -36.124896 90)
			(size 0.519938 1.4986)
			(layers "F.Cu" "F.Mask" "F.Paste")
			(net "M_C_CPU0_SA_DQS_DP<2>")
		)
		(pad "34" smd rect
			(at -2.050034 -35.275012 90)
			(size 0.519938 1.4986)
			(layers "F.Cu" "F.Mask" "F.Paste")
			(net "M_C_CPU0_SA_DQS_DN<2>")
		)
		(pad "35" smd rect
			(at -2.050034 -34.425128 90)
			(size 0.519938 1.4986)
			(layers "F.Cu" "F.Mask" "F.Paste")
			(net "GND")
		)
		(pad "36" smd rect
			(at -2.050034 -33.57499 90)
			(size 0.519938 1.4986)
			(layers "F.Cu" "F.Mask" "F.Paste")
			(net "M_C_CPU0_SA_DQ<20>")
		)
		(pad "37" smd rect
			(at -2.050034 -32.725106 90)
			(size 0.519938 1.4986)
			(layers "F.Cu" "F.Mask" "F.Paste")
			(net "GND")
		)
		(pad "38" smd rect
			(at -2.050034 -31.874968 90)
			(size 0.519938 1.4986)
			(layers "F.Cu" "F.Mask" "F.Paste")
			(net "M_C_CPU0_SA_DQ<21>")
		)
		(pad "39" smd rect
			(at -2.050034 -31.025084 90)
			(size 0.519938 1.4986)
			(layers "F.Cu" "F.Mask" "F.Paste")
			(net "GND")
		)
		(pad "40" smd rect
			(at -2.050034 -30.174946 90)
			(size 0.519938 1.4986)
			(layers "F.Cu" "F.Mask" "F.Paste")
			(net "M_C_CPU0_SA_DQ<24>")
		)
		(pad "41" smd rect
			(at -2.050034 -29.325062 90)
			(size 0.519938 1.4986)
			(layers "F.Cu" "F.Mask" "F.Paste")
			(net "GND")
		)
		(pad "42" smd rect
			(at -2.050034 -28.474924 90)
			(size 0.519938 1.4986)
			(layers "F.Cu" "F.Mask" "F.Paste")
			(net "M_C_CPU0_SA_DQ<25>")
		)
		(pad "43" smd rect
			(at -2.050034 -27.62504 90)
			(size 0.519938 1.4986)
			(layers "F.Cu" "F.Mask" "F.Paste")
			(net "GND")
		)
		(pad "44" smd rect
			(at -2.050034 -26.774902 90)
			(size 0.519938 1.4986)
			(layers "F.Cu" "F.Mask" "F.Paste")
			(net "M_C_CPU0_SA_DQS_DP<3>")
		)
		(pad "45" smd rect
			(at -2.050034 -25.925018 90)
			(size 0.519938 1.4986)
			(layers "F.Cu" "F.Mask" "F.Paste")
			(net "M_C_CPU0_SA_DQS_DN<3>")
		)
		(pad "46" smd rect
			(at -2.050034 -25.07488 90)
			(size 0.519938 1.4986)
			(layers "F.Cu" "F.Mask" "F.Paste")
			(net "GND")
		)
		(pad "47" smd rect
			(at -2.050034 -24.224996 90)
			(size 0.519938 1.4986)
			(layers "F.Cu" "F.Mask" "F.Paste")
			(net "M_C_CPU0_SA_DQ<28>")
		)
		(pad "48" smd rect
			(at -2.050034 -23.375112 90)
			(size 0.519938 1.4986)
			(layers "F.Cu" "F.Mask" "F.Paste")
			(net "GND")
		)
		(pad "49" smd rect
			(at -2.050034 -22.524974 90)
			(size 0.519938 1.4986)
			(layers "F.Cu" "F.Mask" "F.Paste")
			(net "M_C_CPU0_SA_DQ<29>")
		)
		(pad "50" smd rect
			(at -2.050034 -21.67509 90)
			(size 0.519938 1.4986)
			(layers "F.Cu" "F.Mask" "F.Paste")
			(net "GND")
		)
		(pad "51" smd rect
			(at -2.050034 -20.824952 90)
			(size 0.519938 1.4986)
			(layers "F.Cu" "F.Mask" "F.Paste")
			(net "M_C_CPU0_SA_CB<0>")
		)
		(pad "52" smd rect
			(at -2.050034 -19.975068 90)
			(size 0.519938 1.4986)
			(layers "F.Cu" "F.Mask" "F.Paste")
			(net "GND")
		)
		(pad "53" smd rect
			(at -2.050034 -19.12493 90)
			(size 0.519938 1.4986)
			(layers "F.Cu" "F.Mask" "F.Paste")
			(net "M_C_CPU0_SA_CB<1>")
		)
		(pad "54" smd rect
			(at -2.050034 -18.275046 90)
			(size 0.519938 1.4986)
			(layers "F.Cu" "F.Mask" "F.Paste")
			(net "GND")
		)
		(pad "55" smd rect
			(at -2.050034 -17.424908 90)
			(size 0.519938 1.4986)
			(layers "F.Cu" "F.Mask" "F.Paste")
			(net "M_C_CPU0_SA_DQS_DP<4>")
		)
		(pad "56" smd rect
			(at -2.050034 -16.575024 90)
			(size 0.519938 1.4986)
			(layers "F.Cu" "F.Mask" "F.Paste")
			(net "M_C_CPU0_SA_DQS_DN<4>")
		)
		(pad "57" smd rect
			(at -2.050034 -15.724886 90)
			(size 0.519938 1.4986)
			(layers "F.Cu" "F.Mask" "F.Paste")
			(net "GND")
		)
		(pad "58" smd rect
			(at -2.050034 -14.875002 90)
			(size 0.519938 1.4986)
			(layers "F.Cu" "F.Mask" "F.Paste")
			(net "M_C_CPU0_SA_CB<4>")
		)
		(pad "59" smd rect
			(at -2.050034 -14.025118 90)
			(size 0.519938 1.4986)
			(layers "F.Cu" "F.Mask" "F.Paste")
			(net "GND")
		)
		(pad "60" smd rect
			(at -2.050034 -13.17498 90)
			(size 0.519938 1.4986)
			(layers "F.Cu" "F.Mask" "F.Paste")
			(net "M_C_CPU0_SA_CB<5>")
		)
		(pad "61" smd rect
			(at -2.050034 -12.325096 90)
			(size 0.519938 1.4986)
			(layers "F.Cu" "F.Mask" "F.Paste")
			(net "GND")
		)
		(pad "62" smd rect
			(at -2.050034 -11.474958 90)
			(size 0.519938 1.4986)
			(layers "F.Cu" "F.Mask" "F.Paste")
			(net "M_C_CPU0_ALERT_N")
		)
		(pad "63" smd rect
			(at -2.050034 -10.625074 90)
			(size 0.519938 1.4986)
			(layers "F.Cu" "F.Mask" "F.Paste")
			(net "GND")
		)
		(pad "64" smd rect
			(at -2.050034 -9.774936 90)
			(size 0.519938 1.4986)
			(layers "F.Cu" "F.Mask" "F.Paste")
			(net "M_C_CPU0_SA_CS_N<0>")
		)
		(pad "65" smd rect
			(at -2.050034 -8.925052 90)
			(size 0.519938 1.4986)
			(layers "F.Cu" "F.Mask" "F.Paste")
			(net "GND")
		)
		(pad "66" smd rect
			(at -2.050034 -8.074914 90)
			(size 0.519938 1.4986)
			(layers "F.Cu" "F.Mask" "F.Paste")
			(net "M_C_CPU0_SA_CA<0>")
		)
		(pad "67" smd rect
			(at -2.050034 -7.22503 90)
			(size 0.519938 1.4986)
			(layers "F.Cu" "F.Mask" "F.Paste")
			(net "GND")
		)
		(pad "68" smd rect
			(at -2.050034 -6.374892 90)
			(size 0.519938 1.4986)
			(layers "F.Cu" "F.Mask" "F.Paste")
			(net "M_C_CPU0_SA_CA<2>")
		)
		(pad "69" smd rect
			(at -2.050034 -5.525008 90)
			(size 0.519938 1.4986)
			(layers "F.Cu" "F.Mask" "F.Paste")
			(net "GND")
		)
		(pad "70" smd rect
			(at -2.050034 -4.675124 90)
			(size 0.519938 1.4986)
			(layers "F.Cu" "F.Mask" "F.Paste")
			(net "M_C_CPU0_SA_CA<4>")
		)
		(pad "71" smd rect
			(at -2.050034 -3.824986 90)
			(size 0.519938 1.4986)
			(layers "F.Cu" "F.Mask" "F.Paste")
			(net "GND")
		)
		(pad "72" smd rect
			(at -2.050034 -2.975102 90)
			(size 0.519938 1.4986)
			(layers "F.Cu" "F.Mask" "F.Paste")
			(net "M_C_CPU0_SA_CA<6>")
		)
		(pad "73" smd rect
			(at -2.050034 -2.124964 90)
			(size 0.519938 1.4986)
			(layers "F.Cu" "F.Mask" "F.Paste")
			(net "GND")
		)
		(pad "74" smd rect
			(at -2.050034 -1.27508 90)
			(size 0.519938 1.4986)
			(layers "F.Cu" "F.Mask" "F.Paste")
			(net "M_C_CPU0_SA_PAR")
		)
		(pad "75" smd rect
			(at -2.050034 -0.424942 90)
			(size 0.519938 1.4986)
			(layers "F.Cu" "F.Mask" "F.Paste")
			(net "GND")
		)
		(pad "76" smd rect
			(at -2.050034 5.525008 90)
			(size 0.519938 1.4986)
			(layers "F.Cu" "F.Mask" "F.Paste")
			(net "M_C_CPU0_SB_CA<0>")
		)
		(pad "77" smd rect
			(at -2.050034 6.374892 90)
			(size 0.519938 1.4986)
			(layers "F.Cu" "F.Mask" "F.Paste")
			(net "GND")
		)
		(pad "78" smd rect
			(at -2.050034 7.22503 90)
			(size 0.519938 1.4986)
			(layers "F.Cu" "F.Mask" "F.Paste")
			(net "M_C_CPU0_SB_CA<2>")
		)
		(pad "79" smd rect
			(at -2.050034 8.074914 90)
			(size 0.519938 1.4986)
			(layers "F.Cu" "F.Mask" "F.Paste")
			(net "GND")
		)
		(pad "80" smd rect
			(at -2.050034 8.925052 90)
			(size 0.519938 1.4986)
			(layers "F.Cu" "F.Mask" "F.Paste")
			(net "M_C_CPU0_SB_CA<4>")
		)
		(pad "81" smd rect
			(at -2.050034 9.774936 90)
			(size 0.519938 1.4986)
			(layers "F.Cu" "F.Mask" "F.Paste")
			(net "GND")
		)
		(pad "82" smd rect
			(at -2.050034 10.625074 90)
			(size 0.519938 1.4986)
			(layers "F.Cu" "F.Mask" "F.Paste")
			(net "M_C_CPU0_SB_CA<6>")
		)
		(pad "83" smd rect
			(at -2.050034 11.474958 90)
			(size 0.519938 1.4986)
			(layers "F.Cu" "F.Mask" "F.Paste")
			(net "GND")
		)
		(pad "84" smd rect
			(at -2.050034 12.325096 90)
			(size 0.519938 1.4986)
			(layers "F.Cu" "F.Mask" "F.Paste")
			(net "M_C_CPU0_SB_CS_N<0>")
		)
		(pad "85" smd rect
			(at -2.050034 13.17498 90)
			(size 0.519938 1.4986)
			(layers "F.Cu" "F.Mask" "F.Paste")
			(net "GND")
		)
		(pad "86" smd rect
			(at -2.050034 14.025118 90)
			(size 0.519938 1.4986)
			(layers "F.Cu" "F.Mask" "F.Paste")
			(net "M_C_CPU0_SA_RSP<0>")
		)
		(pad "87" smd rect
			(at -2.050034 14.875002 90)
			(size 0.519938 1.4986)
			(layers "F.Cu" "F.Mask" "F.Paste")
			(net "M_C_CPU0_SB_RSP<0>")
		)
		(pad "88" smd rect
			(at -2.050034 15.724886 90)
			(size 0.519938 1.4986)
			(layers "F.Cu" "F.Mask" "F.Paste")
			(net "GND")
		)
		(pad "89" smd rect
			(at -2.050034 16.575024 90)
			(size 0.519938 1.4986)
			(layers "F.Cu" "F.Mask" "F.Paste")
			(net "M_C_CPU0_SB_CB<4>")
		)
		(pad "90" smd rect
			(at -2.050034 17.424908 90)
			(size 0.519938 1.4986)
			(layers "F.Cu" "F.Mask" "F.Paste")
			(net "GND")
		)
		(pad "91" smd rect
			(at -2.050034 18.275046 90)
			(size 0.519938 1.4986)
			(layers "F.Cu" "F.Mask" "F.Paste")
			(net "M_C_CPU0_SB_CB<5>")
		)
		(pad "92" smd rect
			(at -2.050034 19.12493 90)
			(size 0.519938 1.4986)
			(layers "F.Cu" "F.Mask" "F.Paste")
			(net "GND")
		)
		(pad "93" smd rect
			(at -2.050034 19.975068 90)
			(size 0.519938 1.4986)
			(layers "F.Cu" "F.Mask" "F.Paste")
			(net "M_C_CPU0_SB_DQS_DP<9>")
		)
		(pad "94" smd rect
			(at -2.050034 20.824952 90)
			(size 0.519938 1.4986)
			(layers "F.Cu" "F.Mask" "F.Paste")
			(net "M_C_CPU0_SB_DQS_DN<9>")
		)
		(pad "95" smd rect
			(at -2.050034 21.67509 90)
			(size 0.519938 1.4986)
			(layers "F.Cu" "F.Mask" "F.Paste")
			(net "GND")
		)
		(pad "96" smd rect
			(at -2.050034 22.524974 90)
			(size 0.519938 1.4986)
			(layers "F.Cu" "F.Mask" "F.Paste")
			(net "M_C_CPU0_SB_CB<0>")
		)
		(pad "97" smd rect
			(at -2.050034 23.375112 90)
			(size 0.519938 1.4986)
			(layers "F.Cu" "F.Mask" "F.Paste")
			(net "GND")
		)
		(pad "98" smd rect
			(at -2.050034 24.224996 90)
			(size 0.519938 1.4986)
			(layers "F.Cu" "F.Mask" "F.Paste")
			(net "M_C_CPU0_SB_CB<1>")
		)
		(pad "99" smd rect
			(at -2.050034 25.07488 90)
			(size 0.519938 1.4986)
			(layers "F.Cu" "F.Mask" "F.Paste")
			(net "GND")
		)
		(pad "100" smd rect
			(at -2.050034 25.925018 90)
			(size 0.519938 1.4986)
			(layers "F.Cu" "F.Mask" "F.Paste")
			(net "M_C_CPU0_SB_DQ<0>")
		)
		(pad "101" smd rect
			(at -2.050034 26.774902 90)
			(size 0.519938 1.4986)
			(layers "F.Cu" "F.Mask" "F.Paste")
			(net "GND")
		)
		(pad "102" smd rect
			(at -2.050034 27.62504 90)
			(size 0.519938 1.4986)
			(layers "F.Cu" "F.Mask" "F.Paste")
			(net "M_C_CPU0_SB_DQ<1>")
		)
		(pad "103" smd rect
			(at -2.050034 28.474924 90)
			(size 0.519938 1.4986)
			(layers "F.Cu" "F.Mask" "F.Paste")
			(net "GND")
		)
		(pad "104" smd rect
			(at -2.050034 29.325062 90)
			(size 0.519938 1.4986)
			(layers "F.Cu" "F.Mask" "F.Paste")
			(net "M_C_CPU0_SB_DQS_DP<0>")
		)
		(pad "105" smd rect
			(at -2.050034 30.174946 90)
			(size 0.519938 1.4986)
			(layers "F.Cu" "F.Mask" "F.Paste")
			(net "M_C_CPU0_SB_DQS_DN<0>")
		)
		(pad "106" smd rect
			(at -2.050034 31.025084 90)
			(size 0.519938 1.4986)
			(layers "F.Cu" "F.Mask" "F.Paste")
			(net "GND")
		)
		(pad "107" smd rect
			(at -2.050034 31.874968 90)
			(size 0.519938 1.4986)
			(layers "F.Cu" "F.Mask" "F.Paste")
			(net "M_C_CPU0_SB_DQ<4>")
		)
		(pad "108" smd rect
			(at -2.050034 32.725106 90)
			(size 0.519938 1.4986)
			(layers "F.Cu" "F.Mask" "F.Paste")
			(net "GND")
		)
		(pad "109" smd rect
			(at -2.050034 33.57499 90)
			(size 0.519938 1.4986)
			(layers "F.Cu" "F.Mask" "F.Paste")
			(net "M_C_CPU0_SB_DQ<5>")
		)
		(pad "110" smd rect
			(at -2.050034 34.425128 90)
			(size 0.519938 1.4986)
			(layers "F.Cu" "F.Mask" "F.Paste")
			(net "GND")
		)
		(pad "111" smd rect
			(at -2.050034 35.275012 90)
			(size 0.519938 1.4986)
			(layers "F.Cu" "F.Mask" "F.Paste")
			(net "M_C_CPU0_SB_DQ<8>")
		)
		(pad "112" smd rect
			(at -2.050034 36.124896 90)
			(size 0.519938 1.4986)
			(layers "F.Cu" "F.Mask" "F.Paste")
			(net "GND")
		)
		(pad "113" smd rect
			(at -2.050034 36.975034 90)
			(size 0.519938 1.4986)
			(layers "F.Cu" "F.Mask" "F.Paste")
			(net "M_C_CPU0_SB_DQ<9>")
		)
		(pad "114" smd rect
			(at -2.050034 37.824918 90)
			(size 0.519938 1.4986)
			(layers "F.Cu" "F.Mask" "F.Paste")
			(net "GND")
		)
		(pad "115" smd rect
			(at -2.050034 38.675056 90)
			(size 0.519938 1.4986)
			(layers "F.Cu" "F.Mask" "F.Paste")
			(net "M_C_CPU0_SB_DQS_DP<1>")
		)
		(pad "116" smd rect
			(at -2.050034 39.52494 90)
			(size 0.519938 1.4986)
			(layers "F.Cu" "F.Mask" "F.Paste")
			(net "M_C_CPU0_SB_DQS_DN<1>")
		)
		(pad "117" smd rect
			(at -2.050034 40.375078 90)
			(size 0.519938 1.4986)
			(layers "F.Cu" "F.Mask" "F.Paste")
			(net "GND")
		)
		(pad "118" smd rect
			(at -2.050034 41.224962 90)
			(size 0.519938 1.4986)
			(layers "F.Cu" "F.Mask" "F.Paste")
			(net "M_C_CPU0_SB_DQ<12>")
		)
		(pad "119" smd rect
			(at -2.050034 42.0751 90)
			(size 0.519938 1.4986)
			(layers "F.Cu" "F.Mask" "F.Paste")
			(net "GND")
		)
		(pad "120" smd rect
			(at -2.050034 42.924984 90)
			(size 0.519938 1.4986)
			(layers "F.Cu" "F.Mask" "F.Paste")
			(net "M_C_CPU0_SB_DQ<13>")
		)
		(pad "121" smd rect
			(at -2.050034 43.775122 90)
			(size 0.519938 1.4986)
			(layers "F.Cu" "F.Mask" "F.Paste")
			(net "GND")
		)
		(pad "122" smd rect
			(at -2.050034 44.625006 90)
			(size 0.519938 1.4986)
			(layers "F.Cu" "F.Mask" "F.Paste")
			(net "M_C_CPU0_SB_DQ<16>")
		)
		(pad "123" smd rect
			(at -2.050034 45.47489 90)
			(size 0.519938 1.4986)
			(layers "F.Cu" "F.Mask" "F.Paste")
			(net "GND")
		)
		(pad "124" smd rect
			(at -2.050034 46.325028 90)
			(size 0.519938 1.4986)
			(layers "F.Cu" "F.Mask" "F.Paste")
			(net "M_C_CPU0_SB_DQ<17>")
		)
		(pad "125" smd rect
			(at -2.050034 47.174912 90)
			(size 0.519938 1.4986)
			(layers "F.Cu" "F.Mask" "F.Paste")
			(net "GND")
		)
		(pad "126" smd rect
			(at -2.050034 48.02505 90)
			(size 0.519938 1.4986)
			(layers "F.Cu" "F.Mask" "F.Paste")
			(net "M_C_CPU0_SB_DQS_DP<2>")
		)
		(pad "127" smd rect
			(at -2.050034 48.874934 90)
			(size 0.519938 1.4986)
			(layers "F.Cu" "F.Mask" "F.Paste")
			(net "M_C_CPU0_SB_DQS_DN<2>")
		)
		(pad "128" smd rect
			(at -2.050034 49.725072 90)
			(size 0.519938 1.4986)
			(layers "F.Cu" "F.Mask" "F.Paste")
			(net "GND")
		)
		(pad "129" smd rect
			(at -2.050034 50.574956 90)
			(size 0.519938 1.4986)
			(layers "F.Cu" "F.Mask" "F.Paste")
			(net "M_C_CPU0_SB_DQ<20>")
		)
		(pad "130" smd rect
			(at -2.050034 51.425094 90)
			(size 0.519938 1.4986)
			(layers "F.Cu" "F.Mask" "F.Paste")
			(net "GND")
		)
		(pad "131" smd rect
			(at -2.050034 52.274978 90)
			(size 0.519938 1.4986)
			(layers "F.Cu" "F.Mask" "F.Paste")
			(net "M_C_CPU0_SB_DQ<21>")
		)
		(pad "132" smd rect
			(at -2.050034 53.125116 90)
			(size 0.519938 1.4986)
			(layers "F.Cu" "F.Mask" "F.Paste")
			(net "GND")
		)
		(pad "133" smd rect
			(at -2.050034 53.975 90)
			(size 0.519938 1.4986)
			(layers "F.Cu" "F.Mask" "F.Paste")
			(net "M_C_CPU0_SB_DQ<24>")
		)
		(pad "134" smd rect
			(at -2.050034 54.824884 90)
			(size 0.519938 1.4986)
			(layers "F.Cu" "F.Mask" "F.Paste")
			(net "GND")
		)
		(pad "135" smd rect
			(at -2.050034 55.675022 90)
			(size 0.519938 1.4986)
			(layers "F.Cu" "F.Mask" "F.Paste")
			(net "M_C_CPU0_SB_DQ<25>")
		)
		(pad "136" smd rect
			(at -2.050034 56.524906 90)
			(size 0.519938 1.4986)
			(layers "F.Cu" "F.Mask" "F.Paste")
			(net "GND")
		)
		(pad "137" smd rect
			(at -2.050034 57.375044 90)
			(size 0.519938 1.4986)
			(layers "F.Cu" "F.Mask" "F.Paste")
			(net "M_C_CPU0_SB_DQS_DP<3>")
		)
		(pad "138" smd rect
			(at -2.050034 58.224928 90)
			(size 0.519938 1.4986)
			(layers "F.Cu" "F.Mask" "F.Paste")
			(net "M_C_CPU0_SB_DQS_DN<3>")
		)
		(pad "139" smd rect
			(at -2.050034 59.075066 90)
			(size 0.519938 1.4986)
			(layers "F.Cu" "F.Mask" "F.Paste")
			(net "GND")
		)
		(pad "140" smd rect
			(at -2.050034 59.92495 90)
			(size 0.519938 1.4986)
			(layers "F.Cu" "F.Mask" "F.Paste")
			(net "M_C_CPU0_SB_DQ<28>")
		)
		(pad "141" smd rect
			(at -2.050034 60.775088 90)
			(size 0.519938 1.4986)
			(layers "F.Cu" "F.Mask" "F.Paste")
			(net "GND")
		)
		(pad "142" smd rect
			(at -2.050034 61.624972 90)
			(size 0.519938 1.4986)
			(layers "F.Cu" "F.Mask" "F.Paste")
			(net "M_C_CPU0_SB_DQ<29>")
		)
		(pad "143" smd rect
			(at -2.050034 62.47511 90)
			(size 0.519938 1.4986)
			(layers "F.Cu" "F.Mask" "F.Paste")
			(net "GND")
		)
		(pad "144" smd rect
			(at -2.050034 63.324994 90)
			(size 0.519938 1.4986)
			(layers "F.Cu" "F.Mask" "F.Paste")
			(net "Net_2278")
		)
		(pad "145" smd rect
			(at 2.050034 -63.324994 90)
			(size 0.519938 1.4986)
			(layers "F.Cu" "F.Mask" "F.Paste")
			(net "P12V_MEM_CPU0")
		)
		(pad "146" smd rect
			(at 2.050034 -62.47511 90)
			(size 0.519938 1.4986)
			(layers "F.Cu" "F.Mask" "F.Paste")
			(net "P12V_MEM_CPU0")
		)
		(pad "147" smd rect
			(at 2.050034 -61.624972 90)
			(size 0.519938 1.4986)
			(layers "F.Cu" "F.Mask" "F.Paste")
			(net "PWRGD_CHC_CPU0_DIMM")
		)
		(pad "148" smd rect
			(at 2.050034 -60.775088 90)
			(size 0.519938 1.4986)
			(layers "F.Cu" "F.Mask" "F.Paste")
			(net "PD_CHC_CPU0_DIMM_SAA")
		)
		(pad "149" smd rect
			(at 2.050034 -59.92495 90)
			(size 0.519938 1.4986)
			(layers "F.Cu" "F.Mask" "F.Paste")
			(net "Net_2279")
		)
		(pad "150" smd rect
			(at 2.050034 -59.075066 90)
			(size 0.519938 1.4986)
			(layers "F.Cu" "F.Mask" "F.Paste")
			(net "Net_2280")
		)
		(pad "151" smd rect
			(at 2.050034 -58.224928 90)
			(size 0.519938 1.4986)
			(layers "F.Cu" "F.Mask" "F.Paste")
			(net "GND")
		)
		(pad "152" smd rect
			(at 2.050034 -57.375044 90)
			(size 0.519938 1.4986)
			(layers "F.Cu" "F.Mask" "F.Paste")
			(net "M_C_CPU0_SA_DQ<2>")
		)
		(pad "153" smd rect
			(at 2.050034 -56.524906 90)
			(size 0.519938 1.4986)
			(layers "F.Cu" "F.Mask" "F.Paste")
			(net "GND")
		)
		(pad "154" smd rect
			(at 2.050034 -55.675022 90)
			(size 0.519938 1.4986)
			(layers "F.Cu" "F.Mask" "F.Paste")
			(net "M_C_CPU0_SA_DQ<3>")
		)
		(pad "155" smd rect
			(at 2.050034 -54.824884 90)
			(size 0.519938 1.4986)
			(layers "F.Cu" "F.Mask" "F.Paste")
			(net "GND")
		)
		(pad "156" smd rect
			(at 2.050034 -53.975 90)
			(size 0.519938 1.4986)
			(layers "F.Cu" "F.Mask" "F.Paste")
			(net "M_C_CPU0_SA_DQS_DN<5>")
		)
		(pad "157" smd rect
			(at 2.050034 -53.125116 90)
			(size 0.519938 1.4986)
			(layers "F.Cu" "F.Mask" "F.Paste")
			(net "M_C_CPU0_SA_DQS_DP<5>")
		)
		(pad "158" smd rect
			(at 2.050034 -52.274978 90)
			(size 0.519938 1.4986)
			(layers "F.Cu" "F.Mask" "F.Paste")
			(net "GND")
		)
		(pad "159" smd rect
			(at 2.050034 -51.425094 90)
			(size 0.519938 1.4986)
			(layers "F.Cu" "F.Mask" "F.Paste")
			(net "M_C_CPU0_SA_DQ<6>")
		)
		(pad "160" smd rect
			(at 2.050034 -50.574956 90)
			(size 0.519938 1.4986)
			(layers "F.Cu" "F.Mask" "F.Paste")
			(net "GND")
		)
		(pad "161" smd rect
			(at 2.050034 -49.725072 90)
			(size 0.519938 1.4986)
			(layers "F.Cu" "F.Mask" "F.Paste")
			(net "M_C_CPU0_SA_DQ<7>")
		)
		(pad "162" smd rect
			(at 2.050034 -48.874934 90)
			(size 0.519938 1.4986)
			(layers "F.Cu" "F.Mask" "F.Paste")
			(net "GND")
		)
		(pad "163" smd rect
			(at 2.050034 -48.02505 90)
			(size 0.519938 1.4986)
			(layers "F.Cu" "F.Mask" "F.Paste")
			(net "M_C_CPU0_SA_DQ<10>")
		)
		(pad "164" smd rect
			(at 2.050034 -47.174912 90)
			(size 0.519938 1.4986)
			(layers "F.Cu" "F.Mask" "F.Paste")
			(net "GND")
		)
		(pad "165" smd rect
			(at 2.050034 -46.325028 90)
			(size 0.519938 1.4986)
			(layers "F.Cu" "F.Mask" "F.Paste")
			(net "M_C_CPU0_SA_DQ<11>")
		)
		(pad "166" smd rect
			(at 2.050034 -45.47489 90)
			(size 0.519938 1.4986)
			(layers "F.Cu" "F.Mask" "F.Paste")
			(net "GND")
		)
		(pad "167" smd rect
			(at 2.050034 -44.625006 90)
			(size 0.519938 1.4986)
			(layers "F.Cu" "F.Mask" "F.Paste")
			(net "M_C_CPU0_SA_DQS_DN<6>")
		)
		(pad "168" smd rect
			(at 2.050034 -43.775122 90)
			(size 0.519938 1.4986)
			(layers "F.Cu" "F.Mask" "F.Paste")
			(net "M_C_CPU0_SA_DQS_DP<6>")
		)
		(pad "169" smd rect
			(at 2.050034 -42.924984 90)
			(size 0.519938 1.4986)
			(layers "F.Cu" "F.Mask" "F.Paste")
			(net "GND")
		)
		(pad "170" smd rect
			(at 2.050034 -42.0751 90)
			(size 0.519938 1.4986)
			(layers "F.Cu" "F.Mask" "F.Paste")
			(net "M_C_CPU0_SA_DQ<14>")
		)
		(pad "171" smd rect
			(at 2.050034 -41.224962 90)
			(size 0.519938 1.4986)
			(layers "F.Cu" "F.Mask" "F.Paste")
			(net "GND")
		)
		(pad "172" smd rect
			(at 2.050034 -40.375078 90)
			(size 0.519938 1.4986)
			(layers "F.Cu" "F.Mask" "F.Paste")
			(net "M_C_CPU0_SA_DQ<15>")
		)
		(pad "173" smd rect
			(at 2.050034 -39.52494 90)
			(size 0.519938 1.4986)
			(layers "F.Cu" "F.Mask" "F.Paste")
			(net "GND")
		)
		(pad "174" smd rect
			(at 2.050034 -38.675056 90)
			(size 0.519938 1.4986)
			(layers "F.Cu" "F.Mask" "F.Paste")
			(net "M_C_CPU0_SA_DQ<18>")
		)
		(pad "175" smd rect
			(at 2.050034 -37.824918 90)
			(size 0.519938 1.4986)
			(layers "F.Cu" "F.Mask" "F.Paste")
			(net "GND")
		)
		(pad "176" smd rect
			(at 2.050034 -36.975034 90)
			(size 0.519938 1.4986)
			(layers "F.Cu" "F.Mask" "F.Paste")
			(net "M_C_CPU0_SA_DQ<19>")
		)
		(pad "177" smd rect
			(at 2.050034 -36.124896 90)
			(size 0.519938 1.4986)
			(layers "F.Cu" "F.Mask" "F.Paste")
			(net "GND")
		)
		(pad "178" smd rect
			(at 2.050034 -35.275012 90)
			(size 0.519938 1.4986)
			(layers "F.Cu" "F.Mask" "F.Paste")
			(net "M_C_CPU0_SA_DQS_DN<7>")
		)
		(pad "179" smd rect
			(at 2.050034 -34.425128 90)
			(size 0.519938 1.4986)
			(layers "F.Cu" "F.Mask" "F.Paste")
			(net "M_C_CPU0_SA_DQS_DP<7>")
		)
		(pad "180" smd rect
			(at 2.050034 -33.57499 90)
			(size 0.519938 1.4986)
			(layers "F.Cu" "F.Mask" "F.Paste")
			(net "GND")
		)
		(pad "181" smd rect
			(at 2.050034 -32.725106 90)
			(size 0.519938 1.4986)
			(layers "F.Cu" "F.Mask" "F.Paste")
			(net "M_C_CPU0_SA_DQ<22>")
		)
		(pad "182" smd rect
			(at 2.050034 -31.874968 90)
			(size 0.519938 1.4986)
			(layers "F.Cu" "F.Mask" "F.Paste")
			(net "GND")
		)
		(pad "183" smd rect
			(at 2.050034 -31.025084 90)
			(size 0.519938 1.4986)
			(layers "F.Cu" "F.Mask" "F.Paste")
			(net "M_C_CPU0_SA_DQ<23>")
		)
		(pad "184" smd rect
			(at 2.050034 -30.174946 90)
			(size 0.519938 1.4986)
			(layers "F.Cu" "F.Mask" "F.Paste")
			(net "GND")
		)
		(pad "185" smd rect
			(at 2.050034 -29.325062 90)
			(size 0.519938 1.4986)
			(layers "F.Cu" "F.Mask" "F.Paste")
			(net "M_C_CPU0_SA_DQ<26>")
		)
		(pad "186" smd rect
			(at 2.050034 -28.474924 90)
			(size 0.519938 1.4986)
			(layers "F.Cu" "F.Mask" "F.Paste")
			(net "GND")
		)
		(pad "187" smd rect
			(at 2.050034 -27.62504 90)
			(size 0.519938 1.4986)
			(layers "F.Cu" "F.Mask" "F.Paste")
			(net "M_C_CPU0_SA_DQ<27>")
		)
		(pad "188" smd rect
			(at 2.050034 -26.774902 90)
			(size 0.519938 1.4986)
			(layers "F.Cu" "F.Mask" "F.Paste")
			(net "GND")
		)
		(pad "189" smd rect
			(at 2.050034 -25.925018 90)
			(size 0.519938 1.4986)
			(layers "F.Cu" "F.Mask" "F.Paste")
			(net "M_C_CPU0_SA_DQS_DN<8>")
		)
		(pad "190" smd rect
			(at 2.050034 -25.07488 90)
			(size 0.519938 1.4986)
			(layers "F.Cu" "F.Mask" "F.Paste")
			(net "M_C_CPU0_SA_DQS_DP<8>")
		)
		(pad "191" smd rect
			(at 2.050034 -24.224996 90)
			(size 0.519938 1.4986)
			(layers "F.Cu" "F.Mask" "F.Paste")
			(net "GND")
		)
		(pad "192" smd rect
			(at 2.050034 -23.375112 90)
			(size 0.519938 1.4986)
			(layers "F.Cu" "F.Mask" "F.Paste")
			(net "M_C_CPU0_SA_DQ<30>")
		)
		(pad "193" smd rect
			(at 2.050034 -22.524974 90)
			(size 0.519938 1.4986)
			(layers "F.Cu" "F.Mask" "F.Paste")
			(net "GND")
		)
		(pad "194" smd rect
			(at 2.050034 -21.67509 90)
			(size 0.519938 1.4986)
			(layers "F.Cu" "F.Mask" "F.Paste")
			(net "M_C_CPU0_SA_DQ<31>")
		)
		(pad "195" smd rect
			(at 2.050034 -20.824952 90)
			(size 0.519938 1.4986)
			(layers "F.Cu" "F.Mask" "F.Paste")
			(net "GND")
		)
		(pad "196" smd rect
			(at 2.050034 -19.975068 90)
			(size 0.519938 1.4986)
			(layers "F.Cu" "F.Mask" "F.Paste")
			(net "M_C_CPU0_SA_CB<2>")
		)
		(pad "197" smd rect
			(at 2.050034 -19.12493 90)
			(size 0.519938 1.4986)
			(layers "F.Cu" "F.Mask" "F.Paste")
			(net "GND")
		)
		(pad "198" smd rect
			(at 2.050034 -18.275046 90)
			(size 0.519938 1.4986)
			(layers "F.Cu" "F.Mask" "F.Paste")
			(net "M_C_CPU0_SA_CB<3>")
		)
		(pad "199" smd rect
			(at 2.050034 -17.424908 90)
			(size 0.519938 1.4986)
			(layers "F.Cu" "F.Mask" "F.Paste")
			(net "GND")
		)
		(pad "200" smd rect
			(at 2.050034 -16.575024 90)
			(size 0.519938 1.4986)
			(layers "F.Cu" "F.Mask" "F.Paste")
			(net "M_C_CPU0_SA_DQS_DN<9>")
		)
		(pad "201" smd rect
			(at 2.050034 -15.724886 90)
			(size 0.519938 1.4986)
			(layers "F.Cu" "F.Mask" "F.Paste")
			(net "M_C_CPU0_SA_DQS_DP<9>")
		)
		(pad "202" smd rect
			(at 2.050034 -14.875002 90)
			(size 0.519938 1.4986)
			(layers "F.Cu" "F.Mask" "F.Paste")
			(net "GND")
		)
		(pad "203" smd rect
			(at 2.050034 -14.025118 90)
			(size 0.519938 1.4986)
			(layers "F.Cu" "F.Mask" "F.Paste")
			(net "M_C_CPU0_SA_CB<6>")
		)
		(pad "204" smd rect
			(at 2.050034 -13.17498 90)
			(size 0.519938 1.4986)
			(layers "F.Cu" "F.Mask" "F.Paste")
			(net "GND")
		)
		(pad "205" smd rect
			(at 2.050034 -12.325096 90)
			(size 0.519938 1.4986)
			(layers "F.Cu" "F.Mask" "F.Paste")
			(net "M_C_CPU0_SA_CB<7>")
		)
		(pad "206" smd rect
			(at 2.050034 -11.474958 90)
			(size 0.519938 1.4986)
			(layers "F.Cu" "F.Mask" "F.Paste")
			(net "GND")
		)
		(pad "207" smd rect
			(at 2.050034 -10.625074 90)
			(size 0.519938 1.4986)
			(layers "F.Cu" "F.Mask" "F.Paste")
			(net "M_C_CPU0_RESET_N")
		)
		(pad "208" smd rect
			(at 2.050034 -9.774936 90)
			(size 0.519938 1.4986)
			(layers "F.Cu" "F.Mask" "F.Paste")
			(net "GND")
		)
		(pad "209" smd rect
			(at 2.050034 -8.925052 90)
			(size 0.519938 1.4986)
			(layers "F.Cu" "F.Mask" "F.Paste")
			(net "M_C_CPU0_SA_CS_N<1>")
		)
		(pad "210" smd rect
			(at 2.050034 -8.074914 90)
			(size 0.519938 1.4986)
			(layers "F.Cu" "F.Mask" "F.Paste")
			(net "GND")
		)
		(pad "211" smd rect
			(at 2.050034 -7.22503 90)
			(size 0.519938 1.4986)
			(layers "F.Cu" "F.Mask" "F.Paste")
			(net "M_C_CPU0_SA_CA<1>")
		)
		(pad "212" smd rect
			(at 2.050034 -6.374892 90)
			(size 0.519938 1.4986)
			(layers "F.Cu" "F.Mask" "F.Paste")
			(net "GND")
		)
		(pad "213" smd rect
			(at 2.050034 -5.525008 90)
			(size 0.519938 1.4986)
			(layers "F.Cu" "F.Mask" "F.Paste")
			(net "M_C_CPU0_SA_CA<3>")
		)
		(pad "214" smd rect
			(at 2.050034 -4.675124 90)
			(size 0.519938 1.4986)
			(layers "F.Cu" "F.Mask" "F.Paste")
			(net "GND")
		)
		(pad "215" smd rect
			(at 2.050034 -3.824986 90)
			(size 0.519938 1.4986)
			(layers "F.Cu" "F.Mask" "F.Paste")
			(net "M_C_CPU0_SA_CA<5>")
		)
		(pad "216" smd rect
			(at 2.050034 -2.975102 90)
			(size 0.519938 1.4986)
			(layers "F.Cu" "F.Mask" "F.Paste")
			(net "GND")
		)
		(pad "217" smd rect
			(at 2.050034 -2.124964 90)
			(size 0.519938 1.4986)
			(layers "F.Cu" "F.Mask" "F.Paste")
			(net "M_C_CPU0_CLK_DP<0>")
		)
		(pad "218" smd rect
			(at 2.050034 -1.27508 90)
			(size 0.519938 1.4986)
			(layers "F.Cu" "F.Mask" "F.Paste")
			(net "M_C_CPU0_CLK_DN<0>")
		)
		(pad "219" smd rect
			(at 2.050034 -0.424942 90)
			(size 0.519938 1.4986)
			(layers "F.Cu" "F.Mask" "F.Paste")
			(net "GND")
		)
		(pad "220" smd rect
			(at 2.050034 5.525008 90)
			(size 0.519938 1.4986)
			(layers "F.Cu" "F.Mask" "F.Paste")
			(net "Net_2281")
		)
		(pad "221" smd rect
			(at 2.050034 6.374892 90)
			(size 0.519938 1.4986)
			(layers "F.Cu" "F.Mask" "F.Paste")
			(net "M_C_CPU0_SB_CA<1>")
		)
		(pad "222" smd rect
			(at 2.050034 7.22503 90)
			(size 0.519938 1.4986)
			(layers "F.Cu" "F.Mask" "F.Paste")
			(net "GND")
		)
		(pad "223" smd rect
			(at 2.050034 8.074914 90)
			(size 0.519938 1.4986)
			(layers "F.Cu" "F.Mask" "F.Paste")
			(net "M_C_CPU0_SB_CA<3>")
		)
		(pad "224" smd rect
			(at 2.050034 8.925052 90)
			(size 0.519938 1.4986)
			(layers "F.Cu" "F.Mask" "F.Paste")
			(net "GND")
		)
		(pad "225" smd rect
			(at 2.050034 9.774936 90)
			(size 0.519938 1.4986)
			(layers "F.Cu" "F.Mask" "F.Paste")
			(net "M_C_CPU0_SB_CA<5>")
		)
		(pad "226" smd rect
			(at 2.050034 10.625074 90)
			(size 0.519938 1.4986)
			(layers "F.Cu" "F.Mask" "F.Paste")
			(net "GND")
		)
		(pad "227" smd rect
			(at 2.050034 11.474958 90)
			(size 0.519938 1.4986)
			(layers "F.Cu" "F.Mask" "F.Paste")
			(net "M_C_CPU0_SB_PAR")
		)
		(pad "228" smd rect
			(at 2.050034 12.325096 90)
			(size 0.519938 1.4986)
			(layers "F.Cu" "F.Mask" "F.Paste")
			(net "GND")
		)
		(pad "229" smd rect
			(at 2.050034 13.17498 90)
			(size 0.519938 1.4986)
			(layers "F.Cu" "F.Mask" "F.Paste")
			(net "M_C_CPU0_SB_CS_N<1>")
		)
		(pad "230" smd rect
			(at 2.050034 14.025118 90)
			(size 0.519938 1.4986)
			(layers "F.Cu" "F.Mask" "F.Paste")
			(net "GND")
		)
		(pad "231" smd rect
			(at 2.050034 14.875002 90)
			(size 0.519938 1.4986)
			(layers "F.Cu" "F.Mask" "F.Paste")
			(net "Net_2282")
		)
		(pad "232" smd rect
			(at 2.050034 15.724886 90)
			(size 0.519938 1.4986)
			(layers "F.Cu" "F.Mask" "F.Paste")
			(net "Net_2283")
		)
		(pad "233" smd rect
			(at 2.050034 16.575024 90)
			(size 0.519938 1.4986)
			(layers "F.Cu" "F.Mask" "F.Paste")
			(net "GND")
		)
		(pad "234" smd rect
			(at 2.050034 17.424908 90)
			(size 0.519938 1.4986)
			(layers "F.Cu" "F.Mask" "F.Paste")
			(net "M_C_CPU0_SB_CB<6>")
		)
		(pad "235" smd rect
			(at 2.050034 18.275046 90)
			(size 0.519938 1.4986)
			(layers "F.Cu" "F.Mask" "F.Paste")
			(net "GND")
		)
		(pad "236" smd rect
			(at 2.050034 19.12493 90)
			(size 0.519938 1.4986)
			(layers "F.Cu" "F.Mask" "F.Paste")
			(net "M_C_CPU0_SB_CB<7>")
		)
		(pad "237" smd rect
			(at 2.050034 19.975068 90)
			(size 0.519938 1.4986)
			(layers "F.Cu" "F.Mask" "F.Paste")
			(net "GND")
		)
		(pad "238" smd rect
			(at 2.050034 20.824952 90)
			(size 0.519938 1.4986)
			(layers "F.Cu" "F.Mask" "F.Paste")
			(net "M_C_CPU0_SB_DQS_DN<4>")
		)
		(pad "239" smd rect
			(at 2.050034 21.67509 90)
			(size 0.519938 1.4986)
			(layers "F.Cu" "F.Mask" "F.Paste")
			(net "M_C_CPU0_SB_DQS_DP<4>")
		)
		(pad "240" smd rect
			(at 2.050034 22.524974 90)
			(size 0.519938 1.4986)
			(layers "F.Cu" "F.Mask" "F.Paste")
			(net "GND")
		)
		(pad "241" smd rect
			(at 2.050034 23.375112 90)
			(size 0.519938 1.4986)
			(layers "F.Cu" "F.Mask" "F.Paste")
			(net "M_C_CPU0_SB_CB<2>")
		)
		(pad "242" smd rect
			(at 2.050034 24.224996 90)
			(size 0.519938 1.4986)
			(layers "F.Cu" "F.Mask" "F.Paste")
			(net "GND")
		)
		(pad "243" smd rect
			(at 2.050034 25.07488 90)
			(size 0.519938 1.4986)
			(layers "F.Cu" "F.Mask" "F.Paste")
			(net "M_C_CPU0_SB_CB<3>")
		)
		(pad "244" smd rect
			(at 2.050034 25.925018 90)
			(size 0.519938 1.4986)
			(layers "F.Cu" "F.Mask" "F.Paste")
			(net "GND")
		)
		(pad "245" smd rect
			(at 2.050034 26.774902 90)
			(size 0.519938 1.4986)
			(layers "F.Cu" "F.Mask" "F.Paste")
			(net "M_C_CPU0_SB_DQ<2>")
		)
		(pad "246" smd rect
			(at 2.050034 27.62504 90)
			(size 0.519938 1.4986)
			(layers "F.Cu" "F.Mask" "F.Paste")
			(net "GND")
		)
		(pad "247" smd rect
			(at 2.050034 28.474924 90)
			(size 0.519938 1.4986)
			(layers "F.Cu" "F.Mask" "F.Paste")
			(net "M_C_CPU0_SB_DQ<3>")
		)
		(pad "248" smd rect
			(at 2.050034 29.325062 90)
			(size 0.519938 1.4986)
			(layers "F.Cu" "F.Mask" "F.Paste")
			(net "GND")
		)
		(pad "249" smd rect
			(at 2.050034 30.174946 90)
			(size 0.519938 1.4986)
			(layers "F.Cu" "F.Mask" "F.Paste")
			(net "M_C_CPU0_SB_DQS_DN<5>")
		)
		(pad "250" smd rect
			(at 2.050034 31.025084 90)
			(size 0.519938 1.4986)
			(layers "F.Cu" "F.Mask" "F.Paste")
			(net "M_C_CPU0_SB_DQS_DP<5>")
		)
		(pad "251" smd rect
			(at 2.050034 31.874968 90)
			(size 0.519938 1.4986)
			(layers "F.Cu" "F.Mask" "F.Paste")
			(net "GND")
		)
		(pad "252" smd rect
			(at 2.050034 32.725106 90)
			(size 0.519938 1.4986)
			(layers "F.Cu" "F.Mask" "F.Paste")
			(net "M_C_CPU0_SB_DQ<6>")
		)
		(pad "253" smd rect
			(at 2.050034 33.57499 90)
			(size 0.519938 1.4986)
			(layers "F.Cu" "F.Mask" "F.Paste")
			(net "GND")
		)
		(pad "254" smd rect
			(at 2.050034 34.425128 90)
			(size 0.519938 1.4986)
			(layers "F.Cu" "F.Mask" "F.Paste")
			(net "M_C_CPU0_SB_DQ<7>")
		)
		(pad "255" smd rect
			(at 2.050034 35.275012 90)
			(size 0.519938 1.4986)
			(layers "F.Cu" "F.Mask" "F.Paste")
			(net "GND")
		)
		(pad "256" smd rect
			(at 2.050034 36.124896 90)
			(size 0.519938 1.4986)
			(layers "F.Cu" "F.Mask" "F.Paste")
			(net "M_C_CPU0_SB_DQ<10>")
		)
		(pad "257" smd rect
			(at 2.050034 36.975034 90)
			(size 0.519938 1.4986)
			(layers "F.Cu" "F.Mask" "F.Paste")
			(net "GND")
		)
		(pad "258" smd rect
			(at 2.050034 37.824918 90)
			(size 0.519938 1.4986)
			(layers "F.Cu" "F.Mask" "F.Paste")
			(net "M_C_CPU0_SB_DQ<11>")
		)
		(pad "259" smd rect
			(at 2.050034 38.675056 90)
			(size 0.519938 1.4986)
			(layers "F.Cu" "F.Mask" "F.Paste")
			(net "GND")
		)
		(pad "260" smd rect
			(at 2.050034 39.52494 90)
			(size 0.519938 1.4986)
			(layers "F.Cu" "F.Mask" "F.Paste")
			(net "M_C_CPU0_SB_DQS_DN<6>")
		)
		(pad "261" smd rect
			(at 2.050034 40.375078 90)
			(size 0.519938 1.4986)
			(layers "F.Cu" "F.Mask" "F.Paste")
			(net "M_C_CPU0_SB_DQS_DP<6>")
		)
		(pad "262" smd rect
			(at 2.050034 41.224962 90)
			(size 0.519938 1.4986)
			(layers "F.Cu" "F.Mask" "F.Paste")
			(net "GND")
		)
		(pad "263" smd rect
			(at 2.050034 42.0751 90)
			(size 0.519938 1.4986)
			(layers "F.Cu" "F.Mask" "F.Paste")
			(net "M_C_CPU0_SB_DQ<14>")
		)
		(pad "264" smd rect
			(at 2.050034 42.924984 90)
			(size 0.519938 1.4986)
			(layers "F.Cu" "F.Mask" "F.Paste")
			(net "GND")
		)
		(pad "265" smd rect
			(at 2.050034 43.775122 90)
			(size 0.519938 1.4986)
			(layers "F.Cu" "F.Mask" "F.Paste")
			(net "M_C_CPU0_SB_DQ<15>")
		)
		(pad "266" smd rect
			(at 2.050034 44.625006 90)
			(size 0.519938 1.4986)
			(layers "F.Cu" "F.Mask" "F.Paste")
			(net "GND")
		)
		(pad "267" smd rect
			(at 2.050034 45.47489 90)
			(size 0.519938 1.4986)
			(layers "F.Cu" "F.Mask" "F.Paste")
			(net "M_C_CPU0_SB_DQ<18>")
		)
		(pad "268" smd rect
			(at 2.050034 46.325028 90)
			(size 0.519938 1.4986)
			(layers "F.Cu" "F.Mask" "F.Paste")
			(net "GND")
		)
		(pad "269" smd rect
			(at 2.050034 47.174912 90)
			(size 0.519938 1.4986)
			(layers "F.Cu" "F.Mask" "F.Paste")
			(net "M_C_CPU0_SB_DQ<19>")
		)
		(pad "270" smd rect
			(at 2.050034 48.02505 90)
			(size 0.519938 1.4986)
			(layers "F.Cu" "F.Mask" "F.Paste")
			(net "GND")
		)
		(pad "271" smd rect
			(at 2.050034 48.874934 90)
			(size 0.519938 1.4986)
			(layers "F.Cu" "F.Mask" "F.Paste")
			(net "M_C_CPU0_SB_DQS_DN<7>")
		)
		(pad "272" smd rect
			(at 2.050034 49.725072 90)
			(size 0.519938 1.4986)
			(layers "F.Cu" "F.Mask" "F.Paste")
			(net "M_C_CPU0_SB_DQS_DP<7>")
		)
		(pad "273" smd rect
			(at 2.050034 50.574956 90)
			(size 0.519938 1.4986)
			(layers "F.Cu" "F.Mask" "F.Paste")
			(net "GND")
		)
		(pad "274" smd rect
			(at 2.050034 51.425094 90)
			(size 0.519938 1.4986)
			(layers "F.Cu" "F.Mask" "F.Paste")
			(net "M_C_CPU0_SB_DQ<22>")
		)
		(pad "275" smd rect
			(at 2.050034 52.274978 90)
			(size 0.519938 1.4986)
			(layers "F.Cu" "F.Mask" "F.Paste")
			(net "GND")
		)
		(pad "276" smd rect
			(at 2.050034 53.125116 90)
			(size 0.519938 1.4986)
			(layers "F.Cu" "F.Mask" "F.Paste")
			(net "M_C_CPU0_SB_DQ<23>")
		)
		(pad "277" smd rect
			(at 2.050034 53.975 90)
			(size 0.519938 1.4986)
			(layers "F.Cu" "F.Mask" "F.Paste")
			(net "GND")
		)
		(pad "278" smd rect
			(at 2.050034 54.824884 90)
			(size 0.519938 1.4986)
			(layers "F.Cu" "F.Mask" "F.Paste")
			(net "M_C_CPU0_SB_DQ<26>")
		)
		(pad "279" smd rect
			(at 2.050034 55.675022 90)
			(size 0.519938 1.4986)
			(layers "F.Cu" "F.Mask" "F.Paste")
			(net "GND")
		)
		(pad "280" smd rect
			(at 2.050034 56.524906 90)
			(size 0.519938 1.4986)
			(layers "F.Cu" "F.Mask" "F.Paste")
			(net "M_C_CPU0_SB_DQ<27>")
		)
		(pad "281" smd rect
			(at 2.050034 57.375044 90)
			(size 0.519938 1.4986)
			(layers "F.Cu" "F.Mask" "F.Paste")
			(net "GND")
		)
		(pad "282" smd rect
			(at 2.050034 58.224928 90)
			(size 0.519938 1.4986)
			(layers "F.Cu" "F.Mask" "F.Paste")
			(net "M_C_CPU0_SB_DQS_DN<8>")
		)
		(pad "283" smd rect
			(at 2.050034 59.075066 90)
			(size 0.519938 1.4986)
			(layers "F.Cu" "F.Mask" "F.Paste")
			(net "M_C_CPU0_SB_DQS_DP<8>")
		)
		(pad "284" smd rect
			(at 2.050034 59.92495 90)
			(size 0.519938 1.4986)
			(layers "F.Cu" "F.Mask" "F.Paste")
			(net "GND")
		)
		(pad "285" smd rect
			(at 2.050034 60.775088 90)
			(size 0.519938 1.4986)
			(layers "F.Cu" "F.Mask" "F.Paste")
			(net "M_C_CPU0_SB_DQ<30>")
		)
		(pad "286" smd rect
			(at 2.050034 61.624972 90)
			(size 0.519938 1.4986)
			(layers "F.Cu" "F.Mask" "F.Paste")
			(net "GND")
		)
		(pad "287" smd rect
			(at 2.050034 62.47511 90)
			(size 0.519938 1.4986)
			(layers "F.Cu" "F.Mask" "F.Paste")
			(net "M_C_CPU0_SB_DQ<31>")
		)
		(pad "288" smd rect
			(at 2.050034 63.324994 90)
			(size 0.519938 1.4986)
			(layers "F.Cu" "F.Mask" "F.Paste")
			(net "GND")
		)
		(pad "G1" thru_hole oval
			(at 0 -68.97497 90)
			(size 1.7272 3.4798)
			(drill oval 1.2192 2.4638)
			(layers "*.Cu" "*.Mask")
			(remove_unused_layers no)
			(net "GND")
			(clearance 0.127)
			(thermal_gap 0.127)
		)
		(pad "G2" thru_hole oval
			(at 0 3.875024 90)
			(size 1.7272 3.4798)
			(drill oval 1.2192 2.4638)
			(layers "*.Cu" "*.Mask")
			(remove_unused_layers no)
			(net "GND")
			(clearance 0.127)
			(thermal_gap 0.127)
		)
		(pad "G3" thru_hole oval
			(at 0 68.97497 90)
			(size 1.7272 3.4798)
			(drill oval 1.2192 2.4638)
			(layers "*.Cu" "*.Mask")
			(remove_unused_layers no)
			(net "GND")
			(clearance 0.127)
			(thermal_gap 0.127)
		)
	)
	(footprint ""
		(layer "F.Cu")
		(at 111.581946 -52.86248 -90)
		(property "Reference" "R6305"
			(at 0 0 270)
			(layer "F.SilkS")
			(hide yes)
			(effects
				(font
					(size 1.27 1.27)
				)
			)
		)
		(property "Value" ""
			(at 0 0 270)
			(layer "F.Fab")
			(effects
				(font
					(size 1.27 1.27)
				)
			)
		)
		(duplicate_pad_numbers_are_jumpers no)
		(fp_line
			(start -0.7874 0.4064)
			(end -0.7874 -0.4064)
			(stroke
				(width 0.1524)
				(type default)
			)
			(layer "F.SilkS")
		)
		(fp_line
			(start 0.7874 0.4064)
			(end -0.7874 0.4064)
			(stroke
				(width 0.1524)
				(type default)
			)
			(layer "F.SilkS")
		)
		(fp_line
			(start -0.7874 -0.4064)
			(end 0.7874 -0.4064)
			(stroke
				(width 0.1524)
				(type default)
			)
			(layer "F.SilkS")
		)
		(fp_line
			(start 0.7874 -0.4064)
			(end 0.7874 0.4064)
			(stroke
				(width 0.1524)
				(type default)
			)
			(layer "F.SilkS")
		)
		(fp_line
			(start -0.67945 0.3048)
			(end -0.67945 -0.305054)
			(stroke
				(width 0.1)
				(type default)
			)
			(layer "F.Fab")
		)
		(fp_line
			(start -0.12065 0.3048)
			(end -0.67945 0.3048)
			(stroke
				(width 0.1)
				(type default)
			)
			(layer "F.Fab")
		)
		(fp_line
			(start 0.120396 0.3048)
			(end 0.120396 0.2794)
			(stroke
				(width 0.1)
				(type default)
			)
			(layer "F.Fab")
		)
		(fp_line
			(start 0.67945 0.3048)
			(end 0.120396 0.3048)
			(stroke
				(width 0.1)
				(type default)
			)
			(layer "F.Fab")
		)
		(fp_line
			(start -0.12065 0.2794)
			(end -0.12065 0.3048)
			(stroke
				(width 0.1)
				(type default)
			)
			(layer "F.Fab")
		)
		(fp_line
			(start 0.120396 0.2794)
			(end -0.12065 0.2794)
			(stroke
				(width 0.1)
				(type default)
			)
			(layer "F.Fab")
		)
		(fp_line
			(start -0.12065 -0.2794)
			(end 0.12065 -0.2794)
			(stroke
				(width 0.1)
				(type default)
			)
			(layer "F.Fab")
		)
		(fp_line
			(start 0.12065 -0.2794)
			(end 0.12065 -0.3048)
			(stroke
				(width 0.1)
				(type default)
			)
			(layer "F.Fab")
		)
		(fp_line
			(start 0.12065 -0.3048)
			(end 0.67945 -0.3048)
			(stroke
				(width 0.1)
				(type default)
			)
			(layer "F.Fab")
		)
		(fp_line
			(start 0.67945 -0.3048)
			(end 0.67945 0.3048)
			(stroke
				(width 0.1)
				(type default)
			)
			(layer "F.Fab")
		)
		(fp_line
			(start -0.67945 -0.305054)
			(end -0.12065 -0.305054)
			(stroke
				(width 0.1)
				(type default)
			)
			(layer "F.Fab")
		)
		(fp_line
			(start -0.12065 -0.305054)
			(end -0.12065 -0.2794)
			(stroke
				(width 0.1)
				(type default)
			)
			(layer "F.Fab")
		)
		(pad "1" smd circle
			(at -0.40005 0 270)
			(size 0 0)
			(layers "F.Cu" "F.Mask" "F.Paste")
			(net "USB_HUB2_MRP_CFG_NON_REM")
		)
		(pad "2" smd circle
			(at 0.40005 0 270)
			(size 0 0)
			(layers "F.Cu" "F.Mask" "F.Paste")
			(net "USB_HUB2_TI_HS_SUSPEND_MRP_CFG_NON_REM")
		)
	)
	(footprint ""
		(layer "F.Cu")
		(at 60.57011 -351.932748)
		(property "Reference" "PR262"
			(at 0 0 0)
			(layer "F.SilkS")
			(hide yes)
			(effects
				(font
					(size 1.27 1.27)
				)
			)
		)
		(property "Value" ""
			(at 0 0 0)
			(layer "F.Fab")
			(effects
				(font
					(size 1.27 1.27)
				)
			)
		)
		(duplicate_pad_numbers_are_jumpers no)
		(fp_line
			(start -0.7874 -0.4064)
			(end 0.7874 -0.4064)
			(stroke
				(width 0.1524)
				(type default)
			)
			(layer "F.SilkS")
		)
		(fp_line
			(start -0.7874 0.4064)
			(end -0.7874 -0.4064)
			(stroke
				(width 0.1524)
				(type default)
			)
			(layer "F.SilkS")
		)
		(fp_line
			(start 0.7874 -0.4064)
			(end 0.7874 0.4064)
			(stroke
				(width 0.1524)
				(type default)
			)
			(layer "F.SilkS")
		)
		(fp_line
			(start 0.7874 0.4064)
			(end -0.7874 0.4064)
			(stroke
				(width 0.1524)
				(type default)
			)
			(layer "F.SilkS")
		)
		(fp_line
			(start -0.67945 -0.305054)
			(end -0.12065 -0.305054)
			(stroke
				(width 0.1)
				(type default)
			)
			(layer "F.Fab")
		)
		(fp_line
			(start -0.67945 0.3048)
			(end -0.67945 -0.305054)
			(stroke
				(width 0.1)
				(type default)
			)
			(layer "F.Fab")
		)
		(fp_line
			(start -0.12065 -0.305054)
			(end -0.12065 -0.2794)
			(stroke
				(width 0.1)
				(type default)
			)
			(layer "F.Fab")
		)
		(fp_line
			(start -0.12065 -0.2794)
			(end 0.12065 -0.2794)
			(stroke
				(width 0.1)
				(type default)
			)
			(layer "F.Fab")
		)
		(fp_line
			(start -0.12065 0.2794)
			(end -0.12065 0.3048)
			(stroke
				(width 0.1)
				(type default)
			)
			(layer "F.Fab")
		)
		(fp_line
			(start -0.12065 0.3048)
			(end -0.67945 0.3048)
			(stroke
				(width 0.1)
				(type default)
			)
			(layer "F.Fab")
		)
		(fp_line
			(start 0.120396 0.2794)
			(end -0.12065 0.2794)
			(stroke
				(width 0.1)
				(type default)
			)
			(layer "F.Fab")
		)
		(fp_line
			(start 0.120396 0.3048)
			(end 0.120396 0.2794)
			(stroke
				(width 0.1)
				(type default)
			)
			(layer "F.Fab")
		)
		(fp_line
			(start 0.12065 -0.3048)
			(end 0.67945 -0.3048)
			(stroke
				(width 0.1)
				(type default)
			)
			(layer "F.Fab")
		)
		(fp_line
			(start 0.12065 -0.2794)
			(end 0.12065 -0.3048)
			(stroke
				(width 0.1)
				(type default)
			)
			(layer "F.Fab")
		)
		(fp_line
			(start 0.67945 -0.3048)
			(end 0.67945 0.3048)
			(stroke
				(width 0.1)
				(type default)
			)
			(layer "F.Fab")
		)
		(fp_line
			(start 0.67945 0.3048)
			(end 0.120396 0.3048)
			(stroke
				(width 0.1)
				(type default)
			)
			(layer "F.Fab")
		)
		(pad "1" smd circle
			(at -0.40005 0)
			(size 0 0)
			(layers "F.Cu" "F.Mask" "F.Paste")
			(net "PVDDCR_CPU1_P1_LSET4")
		)
		(pad "2" smd circle
			(at 0.40005 0)
			(size 0 0)
			(layers "F.Cu" "F.Mask" "F.Paste")
			(net "GND")
		)
	)
	(footprint ""
		(layer "F.Cu")
		(at 104.47528 -394.7668 -90)
		(property "Reference" "R671"
			(at 0 0 270)
			(layer "F.SilkS")
			(hide yes)
			(effects
				(font
					(size 1.27 1.27)
				)
			)
		)
		(property "Value" ""
			(at 0 0 270)
			(layer "F.Fab")
			(effects
				(font
					(size 1.27 1.27)
				)
			)
		)
		(duplicate_pad_numbers_are_jumpers no)
		(fp_line
			(start -0.32512 0.175006)
			(end -0.32512 -0.175006)
			(stroke
				(width 0.1)
				(type default)
			)
			(layer "F.Fab")
		)
		(fp_line
			(start 0.32512 0.175006)
			(end -0.32512 0.175006)
			(stroke
				(width 0.1)
				(type default)
			)
			(layer "F.Fab")
		)
		(fp_line
			(start -0.32512 -0.175006)
			(end 0.32512 -0.175006)
			(stroke
				(width 0.1)
				(type default)
			)
			(layer "F.Fab")
		)
		(fp_line
			(start 0.32512 -0.175006)
			(end 0.32512 0.175006)
			(stroke
				(width 0.1)
				(type default)
			)
			(layer "F.Fab")
		)
		(pad "1" smd rect
			(at -0.2667 0 270)
			(size 0.3048 0.381)
			(layers "F.Cu" "F.Mask" "F.Paste")
			(net "SMB_RT_CPU1_P1_ROM_MUX_1D_SDA")
		)
		(pad "2" smd rect
			(at 0.2667 0 90)
			(size 0.3048 0.381)
			(layers "F.Cu" "F.Mask" "F.Paste")
			(net "SMB_RT_CPU1_P1_ROM_MUX_1D_R_SDA")
		)
	)
	(footprint ""
		(layer "F.Cu")
		(at 191.29629 -30.269688 180)
		(property "Reference" "PR4526"
			(at 0 0 180)
			(layer "F.SilkS")
			(hide yes)
			(effects
				(font
					(size 1.27 1.27)
				)
			)
		)
		(property "Value" ""
			(at 0 0 180)
			(layer "F.Fab")
			(effects
				(font
					(size 1.27 1.27)
				)
			)
		)
		(duplicate_pad_numbers_are_jumpers no)
		(fp_line
			(start 0.7874 0.4064)
			(end -0.7874 0.4064)
			(stroke
				(width 0.1524)
				(type default)
			)
			(layer "F.SilkS")
		)
		(fp_line
			(start 0.7874 -0.4064)
			(end 0.7874 0.4064)
			(stroke
				(width 0.1524)
				(type default)
			)
			(layer "F.SilkS")
		)
		(fp_line
			(start -0.7874 0.4064)
			(end -0.7874 -0.4064)
			(stroke
				(width 0.1524)
				(type default)
			)
			(layer "F.SilkS")
		)
		(fp_line
			(start -0.7874 -0.4064)
			(end 0.7874 -0.4064)
			(stroke
				(width 0.1524)
				(type default)
			)
			(layer "F.SilkS")
		)
		(fp_line
			(start 0.67945 0.3048)
			(end 0.120396 0.3048)
			(stroke
				(width 0.1)
				(type default)
			)
			(layer "F.Fab")
		)
		(fp_line
			(start 0.67945 -0.3048)
			(end 0.67945 0.3048)
			(stroke
				(width 0.1)
				(type default)
			)
			(layer "F.Fab")
		)
		(fp_line
			(start 0.12065 -0.2794)
			(end 0.12065 -0.3048)
			(stroke
				(width 0.1)
				(type default)
			)
			(layer "F.Fab")
		)
		(fp_line
			(start 0.12065 -0.3048)
			(end 0.67945 -0.3048)
			(stroke
				(width 0.1)
				(type default)
			)
			(layer "F.Fab")
		)
		(fp_line
			(start 0.120396 0.3048)
			(end 0.120396 0.2794)
			(stroke
				(width 0.1)
				(type default)
			)
			(layer "F.Fab")
		)
		(fp_line
			(start 0.120396 0.2794)
			(end -0.12065 0.2794)
			(stroke
				(width 0.1)
				(type default)
			)
			(layer "F.Fab")
		)
		(fp_line
			(start -0.12065 0.3048)
			(end -0.67945 0.3048)
			(stroke
				(width 0.1)
				(type default)
			)
			(layer "F.Fab")
		)
		(fp_line
			(start -0.12065 0.2794)
			(end -0.12065 0.3048)
			(stroke
				(width 0.1)
				(type default)
			)
			(layer "F.Fab")
		)
		(fp_line
			(start -0.12065 -0.2794)
			(end 0.12065 -0.2794)
			(stroke
				(width 0.1)
				(type default)
			)
			(layer "F.Fab")
		)
		(fp_line
			(start -0.12065 -0.305054)
			(end -0.12065 -0.2794)
			(stroke
				(width 0.1)
				(type default)
			)
			(layer "F.Fab")
		)
		(fp_line
			(start -0.67945 0.3048)
			(end -0.67945 -0.305054)
			(stroke
				(width 0.1)
				(type default)
			)
			(layer "F.Fab")
		)
		(fp_line
			(start -0.67945 -0.305054)
			(end -0.12065 -0.305054)
			(stroke
				(width 0.1)
				(type default)
			)
			(layer "F.Fab")
		)
		(pad "1" smd circle
			(at -0.40005 0 180)
			(size 0 0)
			(layers "F.Cu" "F.Mask" "F.Paste")
			(net "P12V_SCM_R")
		)
		(pad "2" smd circle
			(at 0.40005 0 180)
			(size 0 0)
			(layers "F.Cu" "F.Mask" "F.Paste")
			(net "P12V_SCM_GATE")
		)
	)
	(footprint ""
		(layer "F.Cu")
		(at 165.109144 -344.153998 -90)
		(property "Reference" "PR14"
			(at 0 0 270)
			(layer "F.SilkS")
			(hide yes)
			(effects
				(font
					(size 1.27 1.27)
				)
			)
		)
		(property "Value" ""
			(at 0 0 270)
			(layer "F.Fab")
			(effects
				(font
					(size 1.27 1.27)
				)
			)
		)
		(duplicate_pad_numbers_are_jumpers no)
		(fp_line
			(start -0.7874 0.4064)
			(end -0.7874 -0.4064)
			(stroke
				(width 0.1524)
				(type default)
			)
			(layer "F.SilkS")
		)
		(fp_line
			(start 0.7874 0.4064)
			(end -0.7874 0.4064)
			(stroke
				(width 0.1524)
				(type default)
			)
			(layer "F.SilkS")
		)
		(fp_line
			(start -0.7874 -0.4064)
			(end 0.7874 -0.4064)
			(stroke
				(width 0.1524)
				(type default)
			)
			(layer "F.SilkS")
		)
		(fp_line
			(start 0.7874 -0.4064)
			(end 0.7874 0.4064)
			(stroke
				(width 0.1524)
				(type default)
			)
			(layer "F.SilkS")
		)
		(fp_line
			(start -0.67945 0.3048)
			(end -0.67945 -0.305054)
			(stroke
				(width 0.1)
				(type default)
			)
			(layer "F.Fab")
		)
		(fp_line
			(start -0.12065 0.3048)
			(end -0.67945 0.3048)
			(stroke
				(width 0.1)
				(type default)
			)
			(layer "F.Fab")
		)
		(fp_line
			(start 0.120396 0.3048)
			(end 0.120396 0.2794)
			(stroke
				(width 0.1)
				(type default)
			)
			(layer "F.Fab")
		)
		(fp_line
			(start 0.67945 0.3048)
			(end 0.120396 0.3048)
			(stroke
				(width 0.1)
				(type default)
			)
			(layer "F.Fab")
		)
		(fp_line
			(start -0.12065 0.2794)
			(end -0.12065 0.3048)
			(stroke
				(width 0.1)
				(type default)
			)
			(layer "F.Fab")
		)
		(fp_line
			(start 0.120396 0.2794)
			(end -0.12065 0.2794)
			(stroke
				(width 0.1)
				(type default)
			)
			(layer "F.Fab")
		)
		(fp_line
			(start -0.12065 -0.2794)
			(end 0.12065 -0.2794)
			(stroke
				(width 0.1)
				(type default)
			)
			(layer "F.Fab")
		)
		(fp_line
			(start 0.12065 -0.2794)
			(end 0.12065 -0.3048)
			(stroke
				(width 0.1)
				(type default)
			)
			(layer "F.Fab")
		)
		(fp_line
			(start 0.12065 -0.3048)
			(end 0.67945 -0.3048)
			(stroke
				(width 0.1)
				(type default)
			)
			(layer "F.Fab")
		)
		(fp_line
			(start 0.67945 -0.3048)
			(end 0.67945 0.3048)
			(stroke
				(width 0.1)
				(type default)
			)
			(layer "F.Fab")
		)
		(fp_line
			(start -0.67945 -0.305054)
			(end -0.12065 -0.305054)
			(stroke
				(width 0.1)
				(type default)
			)
			(layer "F.Fab")
		)
		(fp_line
			(start -0.12065 -0.305054)
			(end -0.12065 -0.2794)
			(stroke
				(width 0.1)
				(type default)
			)
			(layer "F.Fab")
		)
		(pad "1" smd circle
			(at -0.40005 0 270)
			(size 0 0)
			(layers "F.Cu" "F.Mask" "F.Paste")
			(net "NC_PVDD11_S3_P1_IMON6")
		)
		(pad "2" smd circle
			(at 0.40005 0 270)
			(size 0 0)
			(layers "F.Cu" "F.Mask" "F.Paste")
			(net "GND")
		)
	)
	(footprint ""
		(layer "F.Cu")
		(at 332.8924 -131.755642)
		(property "Reference" "PL77"
			(at 0 0 0)
			(layer "F.SilkS")
			(hide yes)
			(effects
				(font
					(size 1.27 1.27)
				)
			)
		)
		(property "Value" ""
			(at 0 0 0)
			(layer "F.Fab")
			(effects
				(font
					(size 1.27 1.27)
				)
			)
		)
		(duplicate_pad_numbers_are_jumpers no)
		(fp_line
			(start -1.27 -0.5842)
			(end 1.27 -0.5842)
			(stroke
				(width 0.1524)
				(type default)
			)
			(layer "F.SilkS")
		)
		(fp_line
			(start -1.27 -0.5588)
			(end -1.27 -0.5842)
			(stroke
				(width 0.1524)
				(type default)
			)
			(layer "F.SilkS")
		)
		(fp_line
			(start -1.27 0.5842)
			(end -1.27 -0.5842)
			(stroke
				(width 0.1524)
				(type default)
			)
			(layer "F.SilkS")
		)
		(fp_line
			(start 1.27 0.5842)
			(end -1.27 0.5842)
			(stroke
				(width 0.1524)
				(type default)
			)
			(layer "F.SilkS")
		)
		(fp_line
			(start 1.27 0.5842)
			(end 1.27 -0.5842)
			(stroke
				(width 0.1524)
				(type default)
			)
			(layer "F.SilkS")
		)
		(fp_line
			(start -1.194308 -0.406654)
			(end -0.9144 -0.406654)
			(stroke
				(width 0.1)
				(type default)
			)
			(layer "F.Fab")
		)
		(fp_line
			(start -1.194308 0.406654)
			(end -1.194308 -0.406654)
			(stroke
				(width 0.1)
				(type default)
			)
			(layer "F.Fab")
		)
		(fp_line
			(start -0.9144 -0.508)
			(end 0.9144 -0.508)
			(stroke
				(width 0.1)
				(type default)
			)
			(layer "F.Fab")
		)
		(fp_line
			(start -0.9144 -0.406654)
			(end -0.9144 -0.508)
			(stroke
				(width 0.1)
				(type default)
			)
			(layer "F.Fab")
		)
		(fp_line
			(start -0.9144 0.406654)
			(end -1.194308 0.406654)
			(stroke
				(width 0.1)
				(type default)
			)
			(layer "F.Fab")
		)
		(fp_line
			(start -0.9144 0.508)
			(end -0.9144 0.406654)
			(stroke
				(width 0.1)
				(type default)
			)
			(layer "F.Fab")
		)
		(fp_line
			(start 0.9144 -0.508)
			(end 0.9144 -0.406654)
			(stroke
				(width 0.1)
				(type default)
			)
			(layer "F.Fab")
		)
		(fp_line
			(start 0.9144 -0.406654)
			(end 1.1938 -0.406654)
			(stroke
				(width 0.1)
				(type default)
			)
			(layer "F.Fab")
		)
		(fp_line
			(start 0.9144 0.4064)
			(end 0.9144 0.508)
			(stroke
				(width 0.1)
				(type default)
			)
			(layer "F.Fab")
		)
		(fp_line
			(start 0.9144 0.508)
			(end -0.9144 0.508)
			(stroke
				(width 0.1)
				(type default)
			)
			(layer "F.Fab")
		)
		(fp_line
			(start 1.1938 -0.406654)
			(end 1.1938 0.4064)
			(stroke
				(width 0.1)
				(type default)
			)
			(layer "F.Fab")
		)
		(fp_line
			(start 1.1938 0.4064)
			(end 0.9144 0.4064)
			(stroke
				(width 0.1)
				(type default)
			)
			(layer "F.Fab")
		)
		(pad "1" smd rect
			(at -0.7366 0 270)
			(size 0.7112 0.8128)
			(layers "F.Cu" "F.Mask" "F.Paste")
			(net "P12V_AUX")
		)
		(pad "2" smd rect
			(at 0.7366 0 270)
			(size 0.7112 0.8128)
			(layers "F.Cu" "F.Mask" "F.Paste")
			(net "SW_P12V_AUX_PVDD18_S5_P0_FLT")
		)
	)
	(footprint ""
		(layer "F.Cu")
		(at 415.586418 -365.881412 -90)
		(property "Reference" "R120"
			(at 0 0 270)
			(layer "F.SilkS")
			(hide yes)
			(effects
				(font
					(size 1.27 1.27)
				)
			)
		)
		(property "Value" ""
			(at 0 0 270)
			(layer "F.Fab")
			(effects
				(font
					(size 1.27 1.27)
				)
			)
		)
		(duplicate_pad_numbers_are_jumpers no)
		(fp_line
			(start -0.7874 0.4064)
			(end -0.7874 -0.4064)
			(stroke
				(width 0.1524)
				(type default)
			)
			(layer "F.SilkS")
		)
		(fp_line
			(start 0.7874 0.4064)
			(end -0.7874 0.4064)
			(stroke
				(width 0.1524)
				(type default)
			)
			(layer "F.SilkS")
		)
		(fp_line
			(start -0.7874 -0.4064)
			(end 0.7874 -0.4064)
			(stroke
				(width 0.1524)
				(type default)
			)
			(layer "F.SilkS")
		)
		(fp_line
			(start 0.7874 -0.4064)
			(end 0.7874 0.4064)
			(stroke
				(width 0.1524)
				(type default)
			)
			(layer "F.SilkS")
		)
		(fp_line
			(start -0.67945 0.3048)
			(end -0.67945 -0.305054)
			(stroke
				(width 0.1)
				(type default)
			)
			(layer "F.Fab")
		)
		(fp_line
			(start -0.12065 0.3048)
			(end -0.67945 0.3048)
			(stroke
				(width 0.1)
				(type default)
			)
			(layer "F.Fab")
		)
		(fp_line
			(start 0.120396 0.3048)
			(end 0.120396 0.2794)
			(stroke
				(width 0.1)
				(type default)
			)
			(layer "F.Fab")
		)
		(fp_line
			(start 0.67945 0.3048)
			(end 0.120396 0.3048)
			(stroke
				(width 0.1)
				(type default)
			)
			(layer "F.Fab")
		)
		(fp_line
			(start -0.12065 0.2794)
			(end -0.12065 0.3048)
			(stroke
				(width 0.1)
				(type default)
			)
			(layer "F.Fab")
		)
		(fp_line
			(start 0.120396 0.2794)
			(end -0.12065 0.2794)
			(stroke
				(width 0.1)
				(type default)
			)
			(layer "F.Fab")
		)
		(fp_line
			(start -0.12065 -0.2794)
			(end 0.12065 -0.2794)
			(stroke
				(width 0.1)
				(type default)
			)
			(layer "F.Fab")
		)
		(fp_line
			(start 0.12065 -0.2794)
			(end 0.12065 -0.3048)
			(stroke
				(width 0.1)
				(type default)
			)
			(layer "F.Fab")
		)
		(fp_line
			(start 0.12065 -0.3048)
			(end 0.67945 -0.3048)
			(stroke
				(width 0.1)
				(type default)
			)
			(layer "F.Fab")
		)
		(fp_line
			(start 0.67945 -0.3048)
			(end 0.67945 0.3048)
			(stroke
				(width 0.1)
				(type default)
			)
			(layer "F.Fab")
		)
		(fp_line
			(start -0.67945 -0.305054)
			(end -0.12065 -0.305054)
			(stroke
				(width 0.1)
				(type default)
			)
			(layer "F.Fab")
		)
		(fp_line
			(start -0.12065 -0.305054)
			(end -0.12065 -0.2794)
			(stroke
				(width 0.1)
				(type default)
			)
			(layer "F.Fab")
		)
		(pad "1" smd circle
			(at -0.40005 0 270)
			(size 0 0)
			(layers "F.Cu" "F.Mask" "F.Paste")
			(net "PVDD11_S3_P0_PMALERT")
		)
		(pad "2" smd circle
			(at 0.40005 0 270)
			(size 0 0)
			(layers "F.Cu" "F.Mask" "F.Paste")
			(net "PVDD11_S3_P0_PMALERT_R")
		)
	)
	(footprint ""
		(layer "F.Cu")
		(at 251.35967 -45.987462 -90)
		(property "Reference" "PC2211"
			(at 0 0 270)
			(layer "F.SilkS")
			(hide yes)
			(effects
				(font
					(size 1.27 1.27)
				)
			)
		)
		(property "Value" ""
			(at 0 0 270)
			(layer "F.Fab")
			(effects
				(font
					(size 1.27 1.27)
				)
			)
		)
		(duplicate_pad_numbers_are_jumpers no)
		(fp_line
			(start -0.7874 0.4064)
			(end -0.7874 -0.4064)
			(stroke
				(width 0.1524)
				(type default)
			)
			(layer "F.SilkS")
		)
		(fp_line
			(start 0.7874 0.4064)
			(end -0.7874 0.4064)
			(stroke
				(width 0.1524)
				(type default)
			)
			(layer "F.SilkS")
		)
		(fp_line
			(start -0.7874 -0.4064)
			(end 0.7874 -0.4064)
			(stroke
				(width 0.1524)
				(type default)
			)
			(layer "F.SilkS")
		)
		(fp_line
			(start 0.7874 -0.4064)
			(end 0.7874 0.4064)
			(stroke
				(width 0.1524)
				(type default)
			)
			(layer "F.SilkS")
		)
		(fp_line
			(start -0.67945 0.3048)
			(end -0.67945 -0.305054)
			(stroke
				(width 0.1)
				(type default)
			)
			(layer "F.Fab")
		)
		(fp_line
			(start -0.12065 0.3048)
			(end -0.67945 0.3048)
			(stroke
				(width 0.1)
				(type default)
			)
			(layer "F.Fab")
		)
		(fp_line
			(start 0.120396 0.3048)
			(end 0.120396 0.2794)
			(stroke
				(width 0.1)
				(type default)
			)
			(layer "F.Fab")
		)
		(fp_line
			(start 0.67945 0.3048)
			(end 0.120396 0.3048)
			(stroke
				(width 0.1)
				(type default)
			)
			(layer "F.Fab")
		)
		(fp_line
			(start -0.12065 0.2794)
			(end -0.12065 0.3048)
			(stroke
				(width 0.1)
				(type default)
			)
			(layer "F.Fab")
		)
		(fp_line
			(start 0.120396 0.2794)
			(end -0.12065 0.2794)
			(stroke
				(width 0.1)
				(type default)
			)
			(layer "F.Fab")
		)
		(fp_line
			(start -0.12065 -0.2794)
			(end 0.12065 -0.2794)
			(stroke
				(width 0.1)
				(type default)
			)
			(layer "F.Fab")
		)
		(fp_line
			(start 0.12065 -0.2794)
			(end 0.12065 -0.3048)
			(stroke
				(width 0.1)
				(type default)
			)
			(layer "F.Fab")
		)
		(fp_line
			(start 0.12065 -0.3048)
			(end 0.67945 -0.3048)
			(stroke
				(width 0.1)
				(type default)
			)
			(layer "F.Fab")
		)
		(fp_line
			(start 0.67945 -0.3048)
			(end 0.67945 0.3048)
			(stroke
				(width 0.1)
				(type default)
			)
			(layer "F.Fab")
		)
		(fp_line
			(start -0.67945 -0.305054)
			(end -0.12065 -0.305054)
			(stroke
				(width 0.1)
				(type default)
			)
			(layer "F.Fab")
		)
		(fp_line
			(start -0.12065 -0.305054)
			(end -0.12065 -0.2794)
			(stroke
				(width 0.1)
				(type default)
			)
			(layer "F.Fab")
		)
		(pad "1" smd circle
			(at -0.40005 0 270)
			(size 0 0)
			(layers "F.Cu" "F.Mask" "F.Paste")
			(net "GND")
		)
		(pad "2" smd circle
			(at 0.40005 0 270)
			(size 0 0)
			(layers "F.Cu" "F.Mask" "F.Paste")
			(net "P12V_E1S_REG_0")
		)
	)
	(footprint ""
		(layer "F.Cu")
		(at 413.928306 -133.66242)
		(property "Reference" "PC1850"
			(at 0 0 0)
			(layer "F.SilkS")
			(hide yes)
			(effects
				(font
					(size 1.27 1.27)
				)
			)
		)
		(property "Value" ""
			(at 0 0 0)
			(layer "F.Fab")
			(effects
				(font
					(size 1.27 1.27)
				)
			)
		)
		(duplicate_pad_numbers_are_jumpers no)
		(fp_line
			(start -1.524 -0.762)
			(end 1.524 -0.762)
			(stroke
				(width 0.1524)
				(type default)
			)
			(layer "F.SilkS")
		)
		(fp_line
			(start -1.524 0.762)
			(end -1.524 -0.762)
			(stroke
				(width 0.1524)
				(type default)
			)
			(layer "F.SilkS")
		)
		(fp_line
			(start 1.524 -0.762)
			(end 1.524 0.762)
			(stroke
				(width 0.1524)
				(type default)
			)
			(layer "F.SilkS")
		)
		(fp_line
			(start 1.524 0.762)
			(end -1.524 0.762)
			(stroke
				(width 0.1524)
				(type default)
			)
			(layer "F.SilkS")
		)
		(fp_line
			(start -1.1049 -0.724916)
			(end -1.1049 0.724916)
			(stroke
				(width 0.1)
				(type default)
			)
			(layer "F.Fab")
		)
		(fp_line
			(start -1.1049 0.724916)
			(end 1.1049 0.724916)
			(stroke
				(width 0.1)
				(type default)
			)
			(layer "F.Fab")
		)
		(fp_line
			(start 1.1049 -0.724916)
			(end -1.1049 -0.724916)
			(stroke
				(width 0.1)
				(type default)
			)
			(layer "F.Fab")
		)
		(fp_line
			(start 1.1049 0.724916)
			(end 1.1049 -0.724916)
			(stroke
				(width 0.1)
				(type default)
			)
			(layer "F.Fab")
		)
		(pad "1" smd rect
			(at -0.889 0 180)
			(size 1.016 1.27)
			(layers "F.Cu" "F.Mask" "F.Paste")
			(net "SW_P5V_AUX_FLT")
		)
		(pad "2" smd rect
			(at 0.889 0 180)
			(size 1.016 1.27)
			(layers "F.Cu" "F.Mask" "F.Paste")
			(net "GND")
		)
	)
	(footprint ""
		(layer "F.Cu")
		(at 403.142958 -321.002152 90)
		(property "Reference" "R449"
			(at 0 0 90)
			(layer "F.SilkS")
			(hide yes)
			(effects
				(font
					(size 1.27 1.27)
				)
			)
		)
		(property "Value" ""
			(at 0 0 90)
			(layer "F.Fab")
			(effects
				(font
					(size 1.27 1.27)
				)
			)
		)
		(duplicate_pad_numbers_are_jumpers no)
		(fp_line
			(start 0.7874 -0.4064)
			(end 0.7874 0.4064)
			(stroke
				(width 0.1524)
				(type default)
			)
			(layer "F.SilkS")
		)
		(fp_line
			(start -0.7874 -0.4064)
			(end 0.7874 -0.4064)
			(stroke
				(width 0.1524)
				(type default)
			)
			(layer "F.SilkS")
		)
		(fp_line
			(start 0.7874 0.4064)
			(end -0.7874 0.4064)
			(stroke
				(width 0.1524)
				(type default)
			)
			(layer "F.SilkS")
		)
		(fp_line
			(start -0.7874 0.4064)
			(end -0.7874 -0.4064)
			(stroke
				(width 0.1524)
				(type default)
			)
			(layer "F.SilkS")
		)
		(fp_line
			(start -0.12065 -0.305054)
			(end -0.12065 -0.2794)
			(stroke
				(width 0.1)
				(type default)
			)
			(layer "F.Fab")
		)
		(fp_line
			(start -0.67945 -0.305054)
			(end -0.12065 -0.305054)
			(stroke
				(width 0.1)
				(type default)
			)
			(layer "F.Fab")
		)
		(fp_line
			(start 0.67945 -0.3048)
			(end 0.67945 0.3048)
			(stroke
				(width 0.1)
				(type default)
			)
			(layer "F.Fab")
		)
		(fp_line
			(start 0.12065 -0.3048)
			(end 0.67945 -0.3048)
			(stroke
				(width 0.1)
				(type default)
			)
			(layer "F.Fab")
		)
		(fp_line
			(start 0.12065 -0.2794)
			(end 0.12065 -0.3048)
			(stroke
				(width 0.1)
				(type default)
			)
			(layer "F.Fab")
		)
		(fp_line
			(start -0.12065 -0.2794)
			(end 0.12065 -0.2794)
			(stroke
				(width 0.1)
				(type default)
			)
			(layer "F.Fab")
		)
		(fp_line
			(start 0.120396 0.2794)
			(end -0.12065 0.2794)
			(stroke
				(width 0.1)
				(type default)
			)
			(layer "F.Fab")
		)
		(fp_line
			(start -0.12065 0.2794)
			(end -0.12065 0.3048)
			(stroke
				(width 0.1)
				(type default)
			)
			(layer "F.Fab")
		)
		(fp_line
			(start 0.67945 0.3048)
			(end 0.120396 0.3048)
			(stroke
				(width 0.1)
				(type default)
			)
			(layer "F.Fab")
		)
		(fp_line
			(start 0.120396 0.3048)
			(end 0.120396 0.2794)
			(stroke
				(width 0.1)
				(type default)
			)
			(layer "F.Fab")
		)
		(fp_line
			(start -0.12065 0.3048)
			(end -0.67945 0.3048)
			(stroke
				(width 0.1)
				(type default)
			)
			(layer "F.Fab")
		)
		(fp_line
			(start -0.67945 0.3048)
			(end -0.67945 -0.305054)
			(stroke
				(width 0.1)
				(type default)
			)
			(layer "F.Fab")
		)
		(pad "1" smd circle
			(at -0.40005 0 90)
			(size 0 0)
			(layers "F.Cu" "F.Mask" "F.Paste")
			(net "CPU0_SLP_S3_N")
		)
		(pad "2" smd circle
			(at 0.40005 0 90)
			(size 0 0)
			(layers "F.Cu" "F.Mask" "F.Paste")
			(net "PVDD18_S5_P0")
		)
	)
	(footprint ""
		(layer "F.Cu")
		(at 212.0265 -144.201388 -90)
		(property "Reference" "R2530"
			(at 0 0 270)
			(layer "F.SilkS")
			(hide yes)
			(effects
				(font
					(size 1.27 1.27)
				)
			)
		)
		(property "Value" ""
			(at 0 0 270)
			(layer "F.Fab")
			(effects
				(font
					(size 1.27 1.27)
				)
			)
		)
		(duplicate_pad_numbers_are_jumpers no)
		(fp_line
			(start -0.7874 0.4064)
			(end -0.7874 -0.4064)
			(stroke
				(width 0.1524)
				(type default)
			)
			(layer "F.SilkS")
		)
		(fp_line
			(start 0.7874 0.4064)
			(end -0.7874 0.4064)
			(stroke
				(width 0.1524)
				(type default)
			)
			(layer "F.SilkS")
		)
		(fp_line
			(start -0.7874 -0.4064)
			(end 0.7874 -0.4064)
			(stroke
				(width 0.1524)
				(type default)
			)
			(layer "F.SilkS")
		)
		(fp_line
			(start 0.7874 -0.4064)
			(end 0.7874 0.4064)
			(stroke
				(width 0.1524)
				(type default)
			)
			(layer "F.SilkS")
		)
		(fp_line
			(start -0.67945 0.3048)
			(end -0.67945 -0.305054)
			(stroke
				(width 0.1)
				(type default)
			)
			(layer "F.Fab")
		)
		(fp_line
			(start -0.12065 0.3048)
			(end -0.67945 0.3048)
			(stroke
				(width 0.1)
				(type default)
			)
			(layer "F.Fab")
		)
		(fp_line
			(start 0.120396 0.3048)
			(end 0.120396 0.2794)
			(stroke
				(width 0.1)
				(type default)
			)
			(layer "F.Fab")
		)
		(fp_line
			(start 0.67945 0.3048)
			(end 0.120396 0.3048)
			(stroke
				(width 0.1)
				(type default)
			)
			(layer "F.Fab")
		)
		(fp_line
			(start -0.12065 0.2794)
			(end -0.12065 0.3048)
			(stroke
				(width 0.1)
				(type default)
			)
			(layer "F.Fab")
		)
		(fp_line
			(start 0.120396 0.2794)
			(end -0.12065 0.2794)
			(stroke
				(width 0.1)
				(type default)
			)
			(layer "F.Fab")
		)
		(fp_line
			(start -0.12065 -0.2794)
			(end 0.12065 -0.2794)
			(stroke
				(width 0.1)
				(type default)
			)
			(layer "F.Fab")
		)
		(fp_line
			(start 0.12065 -0.2794)
			(end 0.12065 -0.3048)
			(stroke
				(width 0.1)
				(type default)
			)
			(layer "F.Fab")
		)
		(fp_line
			(start 0.12065 -0.3048)
			(end 0.67945 -0.3048)
			(stroke
				(width 0.1)
				(type default)
			)
			(layer "F.Fab")
		)
		(fp_line
			(start 0.67945 -0.3048)
			(end 0.67945 0.3048)
			(stroke
				(width 0.1)
				(type default)
			)
			(layer "F.Fab")
		)
		(fp_line
			(start -0.67945 -0.305054)
			(end -0.12065 -0.305054)
			(stroke
				(width 0.1)
				(type default)
			)
			(layer "F.Fab")
		)
		(fp_line
			(start -0.12065 -0.305054)
			(end -0.12065 -0.2794)
			(stroke
				(width 0.1)
				(type default)
			)
			(layer "F.Fab")
		)
		(pad "1" smd circle
			(at -0.40005 0 270)
			(size 0 0)
			(layers "F.Cu" "F.Mask" "F.Paste")
			(net "P12V_AUX")
		)
		(pad "2" smd circle
			(at 0.40005 0 270)
			(size 0 0)
			(layers "F.Cu" "F.Mask" "F.Paste")
			(net "P12V_AUX_BLEEDING")
		)
	)
	(footprint ""
		(layer "F.Cu")
		(at 200.995534 -118.782084)
		(property "Reference" "R4157"
			(at 0 0 0)
			(layer "F.SilkS")
			(hide yes)
			(effects
				(font
					(size 1.27 1.27)
				)
			)
		)
		(property "Value" ""
			(at 0 0 0)
			(layer "F.Fab")
			(effects
				(font
					(size 1.27 1.27)
				)
			)
		)
		(duplicate_pad_numbers_are_jumpers no)
		(fp_line
			(start -0.7874 -0.4064)
			(end 0.7874 -0.4064)
			(stroke
				(width 0.1524)
				(type default)
			)
			(layer "F.SilkS")
		)
		(fp_line
			(start -0.7874 0.4064)
			(end -0.7874 -0.4064)
			(stroke
				(width 0.1524)
				(type default)
			)
			(layer "F.SilkS")
		)
		(fp_line
			(start 0.7874 -0.4064)
			(end 0.7874 0.4064)
			(stroke
				(width 0.1524)
				(type default)
			)
			(layer "F.SilkS")
		)
		(fp_line
			(start 0.7874 0.4064)
			(end -0.7874 0.4064)
			(stroke
				(width 0.1524)
				(type default)
			)
			(layer "F.SilkS")
		)
		(fp_line
			(start -0.67945 -0.305054)
			(end -0.12065 -0.305054)
			(stroke
				(width 0.1)
				(type default)
			)
			(layer "F.Fab")
		)
		(fp_line
			(start -0.67945 0.3048)
			(end -0.67945 -0.305054)
			(stroke
				(width 0.1)
				(type default)
			)
			(layer "F.Fab")
		)
		(fp_line
			(start -0.12065 -0.305054)
			(end -0.12065 -0.2794)
			(stroke
				(width 0.1)
				(type default)
			)
			(layer "F.Fab")
		)
		(fp_line
			(start -0.12065 -0.2794)
			(end 0.12065 -0.2794)
			(stroke
				(width 0.1)
				(type default)
			)
			(layer "F.Fab")
		)
		(fp_line
			(start -0.12065 0.2794)
			(end -0.12065 0.3048)
			(stroke
				(width 0.1)
				(type default)
			)
			(layer "F.Fab")
		)
		(fp_line
			(start -0.12065 0.3048)
			(end -0.67945 0.3048)
			(stroke
				(width 0.1)
				(type default)
			)
			(layer "F.Fab")
		)
		(fp_line
			(start 0.120396 0.2794)
			(end -0.12065 0.2794)
			(stroke
				(width 0.1)
				(type default)
			)
			(layer "F.Fab")
		)
		(fp_line
			(start 0.120396 0.3048)
			(end 0.120396 0.2794)
			(stroke
				(width 0.1)
				(type default)
			)
			(layer "F.Fab")
		)
		(fp_line
			(start 0.12065 -0.3048)
			(end 0.67945 -0.3048)
			(stroke
				(width 0.1)
				(type default)
			)
			(layer "F.Fab")
		)
		(fp_line
			(start 0.12065 -0.2794)
			(end 0.12065 -0.3048)
			(stroke
				(width 0.1)
				(type default)
			)
			(layer "F.Fab")
		)
		(fp_line
			(start 0.67945 -0.3048)
			(end 0.67945 0.3048)
			(stroke
				(width 0.1)
				(type default)
			)
			(layer "F.Fab")
		)
		(fp_line
			(start 0.67945 0.3048)
			(end 0.120396 0.3048)
			(stroke
				(width 0.1)
				(type default)
			)
			(layer "F.Fab")
		)
		(pad "1" smd circle
			(at -0.40005 0)
			(size 0 0)
			(layers "F.Cu" "F.Mask" "F.Paste")
			(net "PRSNT_CABLE_GPU_A1_ISO_R_N")
		)
		(pad "2" smd circle
			(at 0.40005 0)
			(size 0 0)
			(layers "F.Cu" "F.Mask" "F.Paste")
			(net "PRSNT_CABLE_GPU_A1_ISO_N")
		)
	)
	(footprint ""
		(layer "F.Cu")
		(at 146.03349 -31.18739)
		(property "Reference" "R341"
			(at 0 0 0)
			(layer "F.SilkS")
			(hide yes)
			(effects
				(font
					(size 1.27 1.27)
				)
			)
		)
		(property "Value" ""
			(at 0 0 0)
			(layer "F.Fab")
			(effects
				(font
					(size 1.27 1.27)
				)
			)
		)
		(duplicate_pad_numbers_are_jumpers no)
		(fp_line
			(start -0.7874 -0.4064)
			(end 0.7874 -0.4064)
			(stroke
				(width 0.1524)
				(type default)
			)
			(layer "F.SilkS")
		)
		(fp_line
			(start -0.7874 0.4064)
			(end -0.7874 -0.4064)
			(stroke
				(width 0.1524)
				(type default)
			)
			(layer "F.SilkS")
		)
		(fp_line
			(start 0.7874 -0.4064)
			(end 0.7874 0.4064)
			(stroke
				(width 0.1524)
				(type default)
			)
			(layer "F.SilkS")
		)
		(fp_line
			(start 0.7874 0.4064)
			(end -0.7874 0.4064)
			(stroke
				(width 0.1524)
				(type default)
			)
			(layer "F.SilkS")
		)
		(fp_line
			(start -0.67945 -0.305054)
			(end -0.12065 -0.305054)
			(stroke
				(width 0.1)
				(type default)
			)
			(layer "F.Fab")
		)
		(fp_line
			(start -0.67945 0.3048)
			(end -0.67945 -0.305054)
			(stroke
				(width 0.1)
				(type default)
			)
			(layer "F.Fab")
		)
		(fp_line
			(start -0.12065 -0.305054)
			(end -0.12065 -0.2794)
			(stroke
				(width 0.1)
				(type default)
			)
			(layer "F.Fab")
		)
		(fp_line
			(start -0.12065 -0.2794)
			(end 0.12065 -0.2794)
			(stroke
				(width 0.1)
				(type default)
			)
			(layer "F.Fab")
		)
		(fp_line
			(start -0.12065 0.2794)
			(end -0.12065 0.3048)
			(stroke
				(width 0.1)
				(type default)
			)
			(layer "F.Fab")
		)
		(fp_line
			(start -0.12065 0.3048)
			(end -0.67945 0.3048)
			(stroke
				(width 0.1)
				(type default)
			)
			(layer "F.Fab")
		)
		(fp_line
			(start 0.120396 0.2794)
			(end -0.12065 0.2794)
			(stroke
				(width 0.1)
				(type default)
			)
			(layer "F.Fab")
		)
		(fp_line
			(start 0.120396 0.3048)
			(end 0.120396 0.2794)
			(stroke
				(width 0.1)
				(type default)
			)
			(layer "F.Fab")
		)
		(fp_line
			(start 0.12065 -0.3048)
			(end 0.67945 -0.3048)
			(stroke
				(width 0.1)
				(type default)
			)
			(layer "F.Fab")
		)
		(fp_line
			(start 0.12065 -0.2794)
			(end 0.12065 -0.3048)
			(stroke
				(width 0.1)
				(type default)
			)
			(layer "F.Fab")
		)
		(fp_line
			(start 0.67945 -0.3048)
			(end 0.67945 0.3048)
			(stroke
				(width 0.1)
				(type default)
			)
			(layer "F.Fab")
		)
		(fp_line
			(start 0.67945 0.3048)
			(end 0.120396 0.3048)
			(stroke
				(width 0.1)
				(type default)
			)
			(layer "F.Fab")
		)
		(pad "1" smd rect
			(at -0.40005 0 180)
			(size 0.4572 0.508)
			(layers "F.Cu" "F.Mask" "F.Paste")
			(net "USB3_CPU0_BMC_TX_DP")
		)
		(pad "2" smd rect
			(at 0.40005 0 180)
			(size 0.4572 0.508)
			(layers "F.Cu" "F.Mask" "F.Paste")
			(net "GND")
		)
	)
	(footprint ""
		(layer "F.Cu")
		(at 281.621738 -390.49452 -90)
		(property "Reference" "R2627"
			(at 0 0 270)
			(layer "F.SilkS")
			(hide yes)
			(effects
				(font
					(size 1.27 1.27)
				)
			)
		)
		(property "Value" ""
			(at 0 0 270)
			(layer "F.Fab")
			(effects
				(font
					(size 1.27 1.27)
				)
			)
		)
		(duplicate_pad_numbers_are_jumpers no)
		(fp_line
			(start -0.7874 0.4064)
			(end -0.7874 -0.4064)
			(stroke
				(width 0.1524)
				(type default)
			)
			(layer "F.SilkS")
		)
		(fp_line
			(start 0.7874 0.4064)
			(end -0.7874 0.4064)
			(stroke
				(width 0.1524)
				(type default)
			)
			(layer "F.SilkS")
		)
		(fp_line
			(start -0.7874 -0.4064)
			(end 0.7874 -0.4064)
			(stroke
				(width 0.1524)
				(type default)
			)
			(layer "F.SilkS")
		)
		(fp_line
			(start 0.7874 -0.4064)
			(end 0.7874 0.4064)
			(stroke
				(width 0.1524)
				(type default)
			)
			(layer "F.SilkS")
		)
		(fp_line
			(start -0.67945 0.3048)
			(end -0.67945 -0.305054)
			(stroke
				(width 0.1)
				(type default)
			)
			(layer "F.Fab")
		)
		(fp_line
			(start -0.12065 0.3048)
			(end -0.67945 0.3048)
			(stroke
				(width 0.1)
				(type default)
			)
			(layer "F.Fab")
		)
		(fp_line
			(start 0.120396 0.3048)
			(end 0.120396 0.2794)
			(stroke
				(width 0.1)
				(type default)
			)
			(layer "F.Fab")
		)
		(fp_line
			(start 0.67945 0.3048)
			(end 0.120396 0.3048)
			(stroke
				(width 0.1)
				(type default)
			)
			(layer "F.Fab")
		)
		(fp_line
			(start -0.12065 0.2794)
			(end -0.12065 0.3048)
			(stroke
				(width 0.1)
				(type default)
			)
			(layer "F.Fab")
		)
		(fp_line
			(start 0.120396 0.2794)
			(end -0.12065 0.2794)
			(stroke
				(width 0.1)
				(type default)
			)
			(layer "F.Fab")
		)
		(fp_line
			(start -0.12065 -0.2794)
			(end 0.12065 -0.2794)
			(stroke
				(width 0.1)
				(type default)
			)
			(layer "F.Fab")
		)
		(fp_line
			(start 0.12065 -0.2794)
			(end 0.12065 -0.3048)
			(stroke
				(width 0.1)
				(type default)
			)
			(layer "F.Fab")
		)
		(fp_line
			(start 0.12065 -0.3048)
			(end 0.67945 -0.3048)
			(stroke
				(width 0.1)
				(type default)
			)
			(layer "F.Fab")
		)
		(fp_line
			(start 0.67945 -0.3048)
			(end 0.67945 0.3048)
			(stroke
				(width 0.1)
				(type default)
			)
			(layer "F.Fab")
		)
		(fp_line
			(start -0.67945 -0.305054)
			(end -0.12065 -0.305054)
			(stroke
				(width 0.1)
				(type default)
			)
			(layer "F.Fab")
		)
		(fp_line
			(start -0.12065 -0.305054)
			(end -0.12065 -0.2794)
			(stroke
				(width 0.1)
				(type default)
			)
			(layer "F.Fab")
		)
		(pad "1" smd circle
			(at -0.40005 0 270)
			(size 0 0)
			(layers "F.Cu" "F.Mask" "F.Paste")
			(net "SMB_P12V_HSC_TEMP_SDA")
		)
		(pad "2" smd circle
			(at 0.40005 0 270)
			(size 0 0)
			(layers "F.Cu" "F.Mask" "F.Paste")
			(net "SMB_P12V_HSC_SDA")
		)
	)
	(footprint ""
		(layer "F.Cu")
		(at 404.63724 -383.88163 -90)
		(property "Reference" "C860"
			(at 0 0 270)
			(layer "F.SilkS")
			(hide yes)
			(effects
				(font
					(size 1.27 1.27)
				)
			)
		)
		(property "Value" ""
			(at 0 0 270)
			(layer "F.Fab")
			(effects
				(font
					(size 1.27 1.27)
				)
			)
		)
		(duplicate_pad_numbers_are_jumpers no)
		(fp_line
			(start -0.299974 0.150114)
			(end -0.299974 -0.150114)
			(stroke
				(width 0.1)
				(type default)
			)
			(layer "F.Fab")
		)
		(fp_line
			(start 0.299974 0.150114)
			(end -0.299974 0.150114)
			(stroke
				(width 0.1)
				(type default)
			)
			(layer "F.Fab")
		)
		(fp_line
			(start -0.299974 -0.150114)
			(end 0.299974 -0.150114)
			(stroke
				(width 0.1)
				(type default)
			)
			(layer "F.Fab")
		)
		(fp_line
			(start 0.299974 -0.150114)
			(end 0.299974 0.150114)
			(stroke
				(width 0.1)
				(type default)
			)
			(layer "F.Fab")
		)
		(pad "1" smd rect
			(at -0.2667 0 270)
			(size 0.3048 0.381)
			(layers "F.Cu" "F.Mask" "F.Paste")
			(net "P5E_CPU0_P2_TX_C_DN<4>")
		)
		(pad "2" smd rect
			(at 0.2667 0 270)
			(size 0.3048 0.381)
			(layers "F.Cu" "F.Mask" "F.Paste")
			(net "P5E_CPU0_P2_TX_DN<4>")
		)
	)
	(footprint ""
		(layer "F.Cu")
		(at 158.848044 -370.57203 -90)
		(property "Reference" "C754"
			(at 0 0 270)
			(layer "F.SilkS")
			(hide yes)
			(effects
				(font
					(size 1.27 1.27)
				)
			)
		)
		(property "Value" ""
			(at 0 0 270)
			(layer "F.Fab")
			(effects
				(font
					(size 1.27 1.27)
				)
			)
		)
		(duplicate_pad_numbers_are_jumpers no)
		(fp_line
			(start -0.299974 0.150114)
			(end -0.299974 -0.150114)
			(stroke
				(width 0.1)
				(type default)
			)
			(layer "F.Fab")
		)
		(fp_line
			(start 0.299974 0.150114)
			(end -0.299974 0.150114)
			(stroke
				(width 0.1)
				(type default)
			)
			(layer "F.Fab")
		)
		(fp_line
			(start -0.299974 -0.150114)
			(end 0.299974 -0.150114)
			(stroke
				(width 0.1)
				(type default)
			)
			(layer "F.Fab")
		)
		(fp_line
			(start 0.299974 -0.150114)
			(end 0.299974 0.150114)
			(stroke
				(width 0.1)
				(type default)
			)
			(layer "F.Fab")
		)
		(pad "1" smd rect
			(at -0.2667 0 270)
			(size 0.3048 0.381)
			(layers "F.Cu" "F.Mask" "F.Paste")
			(net "P5E_CPU1_P2_TX_C_DN<9>")
		)
		(pad "2" smd rect
			(at 0.2667 0 270)
			(size 0.3048 0.381)
			(layers "F.Cu" "F.Mask" "F.Paste")
			(net "P5E_CPU1_P2_TX_DN<9>")
		)
	)
	(footprint ""
		(layer "F.Cu")
		(at 371.915944 -178.0921 -90)
		(property "Reference" "PR323"
			(at 0 0 270)
			(layer "F.SilkS")
			(hide yes)
			(effects
				(font
					(size 1.27 1.27)
				)
			)
		)
		(property "Value" ""
			(at 0 0 270)
			(layer "F.Fab")
			(effects
				(font
					(size 1.27 1.27)
				)
			)
		)
		(duplicate_pad_numbers_are_jumpers no)
		(fp_line
			(start -0.7874 0.4064)
			(end -0.7874 -0.4064)
			(stroke
				(width 0.1524)
				(type default)
			)
			(layer "F.SilkS")
		)
		(fp_line
			(start 0.7874 0.4064)
			(end -0.7874 0.4064)
			(stroke
				(width 0.1524)
				(type default)
			)
			(layer "F.SilkS")
		)
		(fp_line
			(start -0.7874 -0.4064)
			(end 0.7874 -0.4064)
			(stroke
				(width 0.1524)
				(type default)
			)
			(layer "F.SilkS")
		)
		(fp_line
			(start 0.7874 -0.4064)
			(end 0.7874 0.4064)
			(stroke
				(width 0.1524)
				(type default)
			)
			(layer "F.SilkS")
		)
		(fp_line
			(start -0.67945 0.3048)
			(end -0.67945 -0.305054)
			(stroke
				(width 0.1)
				(type default)
			)
			(layer "F.Fab")
		)
		(fp_line
			(start -0.12065 0.3048)
			(end -0.67945 0.3048)
			(stroke
				(width 0.1)
				(type default)
			)
			(layer "F.Fab")
		)
		(fp_line
			(start 0.120396 0.3048)
			(end 0.120396 0.2794)
			(stroke
				(width 0.1)
				(type default)
			)
			(layer "F.Fab")
		)
		(fp_line
			(start 0.67945 0.3048)
			(end 0.120396 0.3048)
			(stroke
				(width 0.1)
				(type default)
			)
			(layer "F.Fab")
		)
		(fp_line
			(start -0.12065 0.2794)
			(end -0.12065 0.3048)
			(stroke
				(width 0.1)
				(type default)
			)
			(layer "F.Fab")
		)
		(fp_line
			(start 0.120396 0.2794)
			(end -0.12065 0.2794)
			(stroke
				(width 0.1)
				(type default)
			)
			(layer "F.Fab")
		)
		(fp_line
			(start -0.12065 -0.2794)
			(end 0.12065 -0.2794)
			(stroke
				(width 0.1)
				(type default)
			)
			(layer "F.Fab")
		)
		(fp_line
			(start 0.12065 -0.2794)
			(end 0.12065 -0.3048)
			(stroke
				(width 0.1)
				(type default)
			)
			(layer "F.Fab")
		)
		(fp_line
			(start 0.12065 -0.3048)
			(end 0.67945 -0.3048)
			(stroke
				(width 0.1)
				(type default)
			)
			(layer "F.Fab")
		)
		(fp_line
			(start 0.67945 -0.3048)
			(end 0.67945 0.3048)
			(stroke
				(width 0.1)
				(type default)
			)
			(layer "F.Fab")
		)
		(fp_line
			(start -0.67945 -0.305054)
			(end -0.12065 -0.305054)
			(stroke
				(width 0.1)
				(type default)
			)
			(layer "F.Fab")
		)
		(fp_line
			(start -0.12065 -0.305054)
			(end -0.12065 -0.2794)
			(stroke
				(width 0.1)
				(type default)
			)
			(layer "F.Fab")
		)
		(pad "1" smd circle
			(at -0.40005 0 270)
			(size 0 0)
			(layers "F.Cu" "F.Mask" "F.Paste")
			(net "SW_PVDDCR_CPU0_P0_BOOT2")
		)
		(pad "2" smd circle
			(at 0.40005 0 270)
			(size 0 0)
			(layers "F.Cu" "F.Mask" "F.Paste")
			(net "SW_PVDDCR_CPU0_P0_BOOT2_RC")
		)
	)
	(footprint ""
		(layer "F.Cu")
		(at 409.792424 -139.362942 89.946)
		(property "Reference" "PR8091"
			(at 0 0 89.946)
			(layer "F.SilkS")
			(hide yes)
			(effects
				(font
					(size 1.27 1.27)
				)
			)
		)
		(property "Value" ""
			(at 0 0 89.946)
			(layer "F.Fab")
			(effects
				(font
					(size 1.27 1.27)
				)
			)
		)
		(duplicate_pad_numbers_are_jumpers no)
		(fp_line
			(start -0.787275 -0.40642)
			(end 0.787525 -0.40638)
			(stroke
				(width 0.1524)
				(type default)
			)
			(layer "F.SilkS")
		)
		(fp_line
			(start 0.787525 -0.40638)
			(end 0.787275 0.40642)
			(stroke
				(width 0.1524)
				(type default)
			)
			(layer "F.SilkS")
		)
		(fp_line
			(start -0.787525 0.40638)
			(end -0.787275 -0.40642)
			(stroke
				(width 0.1524)
				(type default)
			)
			(layer "F.SilkS")
		)
		(fp_line
			(start 0.787275 0.40642)
			(end -0.787525 0.40638)
			(stroke
				(width 0.1524)
				(type default)
			)
			(layer "F.SilkS")
		)
		(fp_line
			(start -0.679484 -0.305176)
			(end -0.120683 -0.30494)
			(stroke
				(width 0.1)
				(type default)
			)
			(layer "F.Fab")
		)
		(fp_line
			(start -0.120683 -0.30494)
			(end -0.120659 -0.279286)
			(stroke
				(width 0.1)
				(type default)
			)
			(layer "F.Fab")
		)
		(fp_line
			(start 0.120617 -0.304914)
			(end 0.679417 -0.304678)
			(stroke
				(width 0.1)
				(type default)
			)
			(layer "F.Fab")
		)
		(fp_line
			(start 0.679417 -0.304678)
			(end 0.679484 0.304922)
			(stroke
				(width 0.1)
				(type default)
			)
			(layer "F.Fab")
		)
		(fp_line
			(start 0.120641 -0.279514)
			(end 0.120617 -0.304914)
			(stroke
				(width 0.1)
				(type default)
			)
			(layer "F.Fab")
		)
		(fp_line
			(start -0.120659 -0.279286)
			(end 0.120641 -0.279514)
			(stroke
				(width 0.1)
				(type default)
			)
			(layer "F.Fab")
		)
		(fp_line
			(start 0.120405 0.279287)
			(end -0.120641 0.279514)
			(stroke
				(width 0.1)
				(type default)
			)
			(layer "F.Fab")
		)
		(fp_line
			(start -0.120641 0.279514)
			(end -0.120617 0.304914)
			(stroke
				(width 0.1)
				(type default)
			)
			(layer "F.Fab")
		)
		(fp_line
			(start -0.679417 0.304678)
			(end -0.679484 -0.305176)
			(stroke
				(width 0.1)
				(type default)
			)
			(layer "F.Fab")
		)
		(fp_line
			(start 0.120429 0.304687)
			(end 0.120405 0.279287)
			(stroke
				(width 0.1)
				(type default)
			)
			(layer "F.Fab")
		)
		(fp_line
			(start -0.120617 0.304914)
			(end -0.679417 0.304678)
			(stroke
				(width 0.1)
				(type default)
			)
			(layer "F.Fab")
		)
		(fp_line
			(start 0.679484 0.304922)
			(end 0.120429 0.304687)
			(stroke
				(width 0.1)
				(type default)
			)
			(layer "F.Fab")
		)
		(pad "1" smd circle
			(at -0.40005 0 89.946)
			(size 0 0)
			(layers "F.Cu" "F.Mask" "F.Paste")
			(net "P5V_AUX_FB")
		)
		(pad "2" smd circle
			(at 0.40005 0 89.946)
			(size 0 0)
			(layers "F.Cu" "F.Mask" "F.Paste")
			(net "GND")
		)
	)
	(footprint ""
		(layer "F.Cu")
		(at 29.299662 -429.759364 90)
		(property "Reference" "R3279"
			(at 0 0 90)
			(layer "F.SilkS")
			(hide yes)
			(effects
				(font
					(size 1.27 1.27)
				)
			)
		)
		(property "Value" ""
			(at 0 0 90)
			(layer "F.Fab")
			(effects
				(font
					(size 1.27 1.27)
				)
			)
		)
		(duplicate_pad_numbers_are_jumpers no)
		(fp_line
			(start 0.7874 -0.4064)
			(end 0.7874 0.4064)
			(stroke
				(width 0.1524)
				(type default)
			)
			(layer "F.SilkS")
		)
		(fp_line
			(start -0.7874 -0.4064)
			(end 0.7874 -0.4064)
			(stroke
				(width 0.1524)
				(type default)
			)
			(layer "F.SilkS")
		)
		(fp_line
			(start 0.7874 0.4064)
			(end -0.7874 0.4064)
			(stroke
				(width 0.1524)
				(type default)
			)
			(layer "F.SilkS")
		)
		(fp_line
			(start -0.7874 0.4064)
			(end -0.7874 -0.4064)
			(stroke
				(width 0.1524)
				(type default)
			)
			(layer "F.SilkS")
		)
		(fp_line
			(start -0.12065 -0.305054)
			(end -0.12065 -0.2794)
			(stroke
				(width 0.1)
				(type default)
			)
			(layer "F.Fab")
		)
		(fp_line
			(start -0.67945 -0.305054)
			(end -0.12065 -0.305054)
			(stroke
				(width 0.1)
				(type default)
			)
			(layer "F.Fab")
		)
		(fp_line
			(start 0.67945 -0.3048)
			(end 0.67945 0.3048)
			(stroke
				(width 0.1)
				(type default)
			)
			(layer "F.Fab")
		)
		(fp_line
			(start 0.12065 -0.3048)
			(end 0.67945 -0.3048)
			(stroke
				(width 0.1)
				(type default)
			)
			(layer "F.Fab")
		)
		(fp_line
			(start 0.12065 -0.2794)
			(end 0.12065 -0.3048)
			(stroke
				(width 0.1)
				(type default)
			)
			(layer "F.Fab")
		)
		(fp_line
			(start -0.12065 -0.2794)
			(end 0.12065 -0.2794)
			(stroke
				(width 0.1)
				(type default)
			)
			(layer "F.Fab")
		)
		(fp_line
			(start 0.120396 0.2794)
			(end -0.12065 0.2794)
			(stroke
				(width 0.1)
				(type default)
			)
			(layer "F.Fab")
		)
		(fp_line
			(start -0.12065 0.2794)
			(end -0.12065 0.3048)
			(stroke
				(width 0.1)
				(type default)
			)
			(layer "F.Fab")
		)
		(fp_line
			(start 0.67945 0.3048)
			(end 0.120396 0.3048)
			(stroke
				(width 0.1)
				(type default)
			)
			(layer "F.Fab")
		)
		(fp_line
			(start 0.120396 0.3048)
			(end 0.120396 0.2794)
			(stroke
				(width 0.1)
				(type default)
			)
			(layer "F.Fab")
		)
		(fp_line
			(start -0.12065 0.3048)
			(end -0.67945 0.3048)
			(stroke
				(width 0.1)
				(type default)
			)
			(layer "F.Fab")
		)
		(fp_line
			(start -0.67945 0.3048)
			(end -0.67945 -0.305054)
			(stroke
				(width 0.1)
				(type default)
			)
			(layer "F.Fab")
		)
		(pad "1" smd circle
			(at -0.40005 0 90)
			(size 0 0)
			(layers "F.Cu" "F.Mask" "F.Paste")
			(net "FM_P2E_EQB1")
		)
		(pad "2" smd circle
			(at 0.40005 0 90)
			(size 0 0)
			(layers "F.Cu" "F.Mask" "F.Paste")
			(net "GND")
		)
	)
	(footprint ""
		(layer "F.Cu")
		(at 419.230302 -436.164736 90)
		(property "Reference" "R4159"
			(at 0 0 90)
			(layer "F.SilkS")
			(hide yes)
			(effects
				(font
					(size 1.27 1.27)
				)
			)
		)
		(property "Value" ""
			(at 0 0 90)
			(layer "F.Fab")
			(effects
				(font
					(size 1.27 1.27)
				)
			)
		)
		(duplicate_pad_numbers_are_jumpers no)
		(fp_line
			(start 0.7874 -0.4064)
			(end 0.7874 0.4064)
			(stroke
				(width 0.1524)
				(type default)
			)
			(layer "F.SilkS")
		)
		(fp_line
			(start -0.7874 -0.4064)
			(end 0.7874 -0.4064)
			(stroke
				(width 0.1524)
				(type default)
			)
			(layer "F.SilkS")
		)
		(fp_line
			(start 0.7874 0.4064)
			(end -0.7874 0.4064)
			(stroke
				(width 0.1524)
				(type default)
			)
			(layer "F.SilkS")
		)
		(fp_line
			(start -0.7874 0.4064)
			(end -0.7874 -0.4064)
			(stroke
				(width 0.1524)
				(type default)
			)
			(layer "F.SilkS")
		)
		(fp_line
			(start -0.12065 -0.305054)
			(end -0.12065 -0.2794)
			(stroke
				(width 0.1)
				(type default)
			)
			(layer "F.Fab")
		)
		(fp_line
			(start -0.67945 -0.305054)
			(end -0.12065 -0.305054)
			(stroke
				(width 0.1)
				(type default)
			)
			(layer "F.Fab")
		)
		(fp_line
			(start 0.67945 -0.3048)
			(end 0.67945 0.3048)
			(stroke
				(width 0.1)
				(type default)
			)
			(layer "F.Fab")
		)
		(fp_line
			(start 0.12065 -0.3048)
			(end 0.67945 -0.3048)
			(stroke
				(width 0.1)
				(type default)
			)
			(layer "F.Fab")
		)
		(fp_line
			(start 0.12065 -0.2794)
			(end 0.12065 -0.3048)
			(stroke
				(width 0.1)
				(type default)
			)
			(layer "F.Fab")
		)
		(fp_line
			(start -0.12065 -0.2794)
			(end 0.12065 -0.2794)
			(stroke
				(width 0.1)
				(type default)
			)
			(layer "F.Fab")
		)
		(fp_line
			(start 0.120396 0.2794)
			(end -0.12065 0.2794)
			(stroke
				(width 0.1)
				(type default)
			)
			(layer "F.Fab")
		)
		(fp_line
			(start -0.12065 0.2794)
			(end -0.12065 0.3048)
			(stroke
				(width 0.1)
				(type default)
			)
			(layer "F.Fab")
		)
		(fp_line
			(start 0.67945 0.3048)
			(end 0.120396 0.3048)
			(stroke
				(width 0.1)
				(type default)
			)
			(layer "F.Fab")
		)
		(fp_line
			(start 0.120396 0.3048)
			(end 0.120396 0.2794)
			(stroke
				(width 0.1)
				(type default)
			)
			(layer "F.Fab")
		)
		(fp_line
			(start -0.12065 0.3048)
			(end -0.67945 0.3048)
			(stroke
				(width 0.1)
				(type default)
			)
			(layer "F.Fab")
		)
		(fp_line
			(start -0.67945 0.3048)
			(end -0.67945 -0.305054)
			(stroke
				(width 0.1)
				(type default)
			)
			(layer "F.Fab")
		)
		(pad "1" smd circle
			(at -0.40005 0 90)
			(size 0 0)
			(layers "F.Cu" "F.Mask" "F.Paste")
			(net "GPU_3V3IO_RSVD1")
		)
		(pad "2" smd circle
			(at 0.40005 0 90)
			(size 0 0)
			(layers "F.Cu" "F.Mask" "F.Paste")
			(net "GND")
		)
	)
	(footprint ""
		(layer "F.Cu")
		(at 42.289984 -255.560322 180)
		(property "Reference" "J28"
			(at -2.876296 -82.230976 0)
			(unlocked yes)
			(layer "F.SilkS")
			(effects
				(font
					(size 0.7874 0.5842)
					(thickness 0.1524)
				)
			)
		)
		(property "Value" ""
			(at 0 0 180)
			(layer "F.Fab")
			(effects
				(font
					(size 1.27 1.27)
				)
			)
		)
		(duplicate_pad_numbers_are_jumpers no)
		(fp_line
			(start 3.24993 -81.000092)
			(end 3.24993 75.401678)
			(stroke
				(width 0.1524)
				(type default)
			)
			(layer "F.SilkS")
		)
		(fp_line
			(start -3.24993 75.401678)
			(end -3.24993 -81.000092)
			(stroke
				(width 0.1524)
				(type default)
			)
			(layer "F.SilkS")
		)
		(fp_line
			(start -3.24993 72.499982)
			(end 3.24993 72.499982)
			(stroke
				(width 0.1524)
				(type default)
			)
			(layer "F.SilkS")
		)
		(fp_line
			(start -3.24993 -72.499982)
			(end 3.24993 -72.499982)
			(stroke
				(width 0.1524)
				(type default)
			)
			(layer "F.SilkS")
		)
		(fp_line
			(start -3.24993 -81.000092)
			(end 3.24993 -81.000092)
			(stroke
				(width 0.1524)
				(type default)
			)
			(layer "F.SilkS")
		)
		(fp_poly
			(pts
				(xy -3.784346 -64.725042) (xy -3.07467 -63.838074) (xy -4.21005 -63.802514)
			)
			(stroke
				(width 0)
				(type default)
			)
			(fill yes)
			(layer "F.SilkS")
		)
		(fp_line
			(start 3.24993 81.000092)
			(end -3.24993 81.000092)
			(stroke
				(width 0.1)
				(type default)
			)
			(layer "F.Fab")
		)
		(fp_line
			(start 3.24993 -81.000092)
			(end 3.24993 81.000092)
			(stroke
				(width 0.1)
				(type default)
			)
			(layer "F.Fab")
		)
		(fp_line
			(start -3.24993 81.000092)
			(end -3.24993 -81.000092)
			(stroke
				(width 0.1)
				(type default)
			)
			(layer "F.Fab")
		)
		(fp_line
			(start -3.24993 72.499982)
			(end 3.24993 72.499982)
			(stroke
				(width 0.1)
				(type default)
			)
			(layer "F.Fab")
		)
		(fp_line
			(start -3.24993 71.000112)
			(end 3.24993 71.000112)
			(stroke
				(width 0.1)
				(type default)
			)
			(layer "F.Fab")
		)
		(fp_line
			(start -3.24993 -71.000112)
			(end 3.24993 -71.000112)
			(stroke
				(width 0.1)
				(type default)
			)
			(layer "F.Fab")
		)
		(fp_line
			(start -3.24993 -72.499982)
			(end 3.24993 -72.499982)
			(stroke
				(width 0.1)
				(type default)
			)
			(layer "F.Fab")
		)
		(fp_line
			(start -3.24993 -81.000092)
			(end 3.24993 -81.000092)
			(stroke
				(width 0.1)
				(type default)
			)
			(layer "F.Fab")
		)
		(fp_poly
			(pts
				(xy -3.41503 -63.324994) (xy -4.43103 -62.816994) (xy -4.43103 -63.832994)
			)
			(stroke
				(width 0)
				(type default)
			)
			(fill yes)
			(layer "F.Fab")
		)
		(pad "1" smd rect
			(at -2.050034 -63.324994 90)
			(size 0.519938 1.4986)
			(layers "F.Cu" "F.Mask" "F.Paste")
			(net "P12V_MEM_CPU1")
		)
		(pad "2" smd rect
			(at -2.050034 -62.47511 90)
			(size 0.519938 1.4986)
			(layers "F.Cu" "F.Mask" "F.Paste")
			(net "Net_2284")
		)
		(pad "3" smd rect
			(at -2.050034 -61.624972 90)
			(size 0.519938 1.4986)
			(layers "F.Cu" "F.Mask" "F.Paste")
			(net "P3V3_AUX")
		)
		(pad "4" smd rect
			(at -2.050034 -60.775088 90)
			(size 0.519938 1.4986)
			(layers "F.Cu" "F.Mask" "F.Paste")
			(net "I3C_SPD_DDRC_CPU1_SCL")
		)
		(pad "5" smd rect
			(at -2.050034 -59.92495 90)
			(size 0.519938 1.4986)
			(layers "F.Cu" "F.Mask" "F.Paste")
			(net "I3C_SPD_DDRC_CPU1_SDA")
		)
		(pad "6" smd rect
			(at -2.050034 -59.075066 90)
			(size 0.519938 1.4986)
			(layers "F.Cu" "F.Mask" "F.Paste")
			(net "GND")
		)
		(pad "7" smd rect
			(at -2.050034 -58.224928 90)
			(size 0.519938 1.4986)
			(layers "F.Cu" "F.Mask" "F.Paste")
			(net "M_C_CPU1_SA_DQ<0>")
		)
		(pad "8" smd rect
			(at -2.050034 -57.375044 90)
			(size 0.519938 1.4986)
			(layers "F.Cu" "F.Mask" "F.Paste")
			(net "GND")
		)
		(pad "9" smd rect
			(at -2.050034 -56.524906 90)
			(size 0.519938 1.4986)
			(layers "F.Cu" "F.Mask" "F.Paste")
			(net "M_C_CPU1_SA_DQ<1>")
		)
		(pad "10" smd rect
			(at -2.050034 -55.675022 90)
			(size 0.519938 1.4986)
			(layers "F.Cu" "F.Mask" "F.Paste")
			(net "GND")
		)
		(pad "11" smd rect
			(at -2.050034 -54.824884 90)
			(size 0.519938 1.4986)
			(layers "F.Cu" "F.Mask" "F.Paste")
			(net "M_C_CPU1_SA_DQS_DP<0>")
		)
		(pad "12" smd rect
			(at -2.050034 -53.975 90)
			(size 0.519938 1.4986)
			(layers "F.Cu" "F.Mask" "F.Paste")
			(net "M_C_CPU1_SA_DQS_DN<0>")
		)
		(pad "13" smd rect
			(at -2.050034 -53.125116 90)
			(size 0.519938 1.4986)
			(layers "F.Cu" "F.Mask" "F.Paste")
			(net "GND")
		)
		(pad "14" smd rect
			(at -2.050034 -52.274978 90)
			(size 0.519938 1.4986)
			(layers "F.Cu" "F.Mask" "F.Paste")
			(net "M_C_CPU1_SA_DQ<4>")
		)
		(pad "15" smd rect
			(at -2.050034 -51.425094 90)
			(size 0.519938 1.4986)
			(layers "F.Cu" "F.Mask" "F.Paste")
			(net "GND")
		)
		(pad "16" smd rect
			(at -2.050034 -50.574956 90)
			(size 0.519938 1.4986)
			(layers "F.Cu" "F.Mask" "F.Paste")
			(net "M_C_CPU1_SA_DQ<5>")
		)
		(pad "17" smd rect
			(at -2.050034 -49.725072 90)
			(size 0.519938 1.4986)
			(layers "F.Cu" "F.Mask" "F.Paste")
			(net "GND")
		)
		(pad "18" smd rect
			(at -2.050034 -48.874934 90)
			(size 0.519938 1.4986)
			(layers "F.Cu" "F.Mask" "F.Paste")
			(net "M_C_CPU1_SA_DQ<8>")
		)
		(pad "19" smd rect
			(at -2.050034 -48.02505 90)
			(size 0.519938 1.4986)
			(layers "F.Cu" "F.Mask" "F.Paste")
			(net "GND")
		)
		(pad "20" smd rect
			(at -2.050034 -47.174912 90)
			(size 0.519938 1.4986)
			(layers "F.Cu" "F.Mask" "F.Paste")
			(net "M_C_CPU1_SA_DQ<9>")
		)
		(pad "21" smd rect
			(at -2.050034 -46.325028 90)
			(size 0.519938 1.4986)
			(layers "F.Cu" "F.Mask" "F.Paste")
			(net "GND")
		)
		(pad "22" smd rect
			(at -2.050034 -45.47489 90)
			(size 0.519938 1.4986)
			(layers "F.Cu" "F.Mask" "F.Paste")
			(net "M_C_CPU1_SA_DQS_DP<1>")
		)
		(pad "23" smd rect
			(at -2.050034 -44.625006 90)
			(size 0.519938 1.4986)
			(layers "F.Cu" "F.Mask" "F.Paste")
			(net "M_C_CPU1_SA_DQS_DN<1>")
		)
		(pad "24" smd rect
			(at -2.050034 -43.775122 90)
			(size 0.519938 1.4986)
			(layers "F.Cu" "F.Mask" "F.Paste")
			(net "GND")
		)
		(pad "25" smd rect
			(at -2.050034 -42.924984 90)
			(size 0.519938 1.4986)
			(layers "F.Cu" "F.Mask" "F.Paste")
			(net "M_C_CPU1_SA_DQ<12>")
		)
		(pad "26" smd rect
			(at -2.050034 -42.0751 90)
			(size 0.519938 1.4986)
			(layers "F.Cu" "F.Mask" "F.Paste")
			(net "GND")
		)
		(pad "27" smd rect
			(at -2.050034 -41.224962 90)
			(size 0.519938 1.4986)
			(layers "F.Cu" "F.Mask" "F.Paste")
			(net "M_C_CPU1_SA_DQ<13>")
		)
		(pad "28" smd rect
			(at -2.050034 -40.375078 90)
			(size 0.519938 1.4986)
			(layers "F.Cu" "F.Mask" "F.Paste")
			(net "GND")
		)
		(pad "29" smd rect
			(at -2.050034 -39.52494 90)
			(size 0.519938 1.4986)
			(layers "F.Cu" "F.Mask" "F.Paste")
			(net "M_C_CPU1_SA_DQ<16>")
		)
		(pad "30" smd rect
			(at -2.050034 -38.675056 90)
			(size 0.519938 1.4986)
			(layers "F.Cu" "F.Mask" "F.Paste")
			(net "GND")
		)
		(pad "31" smd rect
			(at -2.050034 -37.824918 90)
			(size 0.519938 1.4986)
			(layers "F.Cu" "F.Mask" "F.Paste")
			(net "M_C_CPU1_SA_DQ<17>")
		)
		(pad "32" smd rect
			(at -2.050034 -36.975034 90)
			(size 0.519938 1.4986)
			(layers "F.Cu" "F.Mask" "F.Paste")
			(net "GND")
		)
		(pad "33" smd rect
			(at -2.050034 -36.124896 90)
			(size 0.519938 1.4986)
			(layers "F.Cu" "F.Mask" "F.Paste")
			(net "M_C_CPU1_SA_DQS_DP<2>")
		)
		(pad "34" smd rect
			(at -2.050034 -35.275012 90)
			(size 0.519938 1.4986)
			(layers "F.Cu" "F.Mask" "F.Paste")
			(net "M_C_CPU1_SA_DQS_DN<2>")
		)
		(pad "35" smd rect
			(at -2.050034 -34.425128 90)
			(size 0.519938 1.4986)
			(layers "F.Cu" "F.Mask" "F.Paste")
			(net "GND")
		)
		(pad "36" smd rect
			(at -2.050034 -33.57499 90)
			(size 0.519938 1.4986)
			(layers "F.Cu" "F.Mask" "F.Paste")
			(net "M_C_CPU1_SA_DQ<20>")
		)
		(pad "37" smd rect
			(at -2.050034 -32.725106 90)
			(size 0.519938 1.4986)
			(layers "F.Cu" "F.Mask" "F.Paste")
			(net "GND")
		)
		(pad "38" smd rect
			(at -2.050034 -31.874968 90)
			(size 0.519938 1.4986)
			(layers "F.Cu" "F.Mask" "F.Paste")
			(net "M_C_CPU1_SA_DQ<21>")
		)
		(pad "39" smd rect
			(at -2.050034 -31.025084 90)
			(size 0.519938 1.4986)
			(layers "F.Cu" "F.Mask" "F.Paste")
			(net "GND")
		)
		(pad "40" smd rect
			(at -2.050034 -30.174946 90)
			(size 0.519938 1.4986)
			(layers "F.Cu" "F.Mask" "F.Paste")
			(net "M_C_CPU1_SA_DQ<24>")
		)
		(pad "41" smd rect
			(at -2.050034 -29.325062 90)
			(size 0.519938 1.4986)
			(layers "F.Cu" "F.Mask" "F.Paste")
			(net "GND")
		)
		(pad "42" smd rect
			(at -2.050034 -28.474924 90)
			(size 0.519938 1.4986)
			(layers "F.Cu" "F.Mask" "F.Paste")
			(net "M_C_CPU1_SA_DQ<25>")
		)
		(pad "43" smd rect
			(at -2.050034 -27.62504 90)
			(size 0.519938 1.4986)
			(layers "F.Cu" "F.Mask" "F.Paste")
			(net "GND")
		)
		(pad "44" smd rect
			(at -2.050034 -26.774902 90)
			(size 0.519938 1.4986)
			(layers "F.Cu" "F.Mask" "F.Paste")
			(net "M_C_CPU1_SA_DQS_DP<3>")
		)
		(pad "45" smd rect
			(at -2.050034 -25.925018 90)
			(size 0.519938 1.4986)
			(layers "F.Cu" "F.Mask" "F.Paste")
			(net "M_C_CPU1_SA_DQS_DN<3>")
		)
		(pad "46" smd rect
			(at -2.050034 -25.07488 90)
			(size 0.519938 1.4986)
			(layers "F.Cu" "F.Mask" "F.Paste")
			(net "GND")
		)
		(pad "47" smd rect
			(at -2.050034 -24.224996 90)
			(size 0.519938 1.4986)
			(layers "F.Cu" "F.Mask" "F.Paste")
			(net "M_C_CPU1_SA_DQ<28>")
		)
		(pad "48" smd rect
			(at -2.050034 -23.375112 90)
			(size 0.519938 1.4986)
			(layers "F.Cu" "F.Mask" "F.Paste")
			(net "GND")
		)
		(pad "49" smd rect
			(at -2.050034 -22.524974 90)
			(size 0.519938 1.4986)
			(layers "F.Cu" "F.Mask" "F.Paste")
			(net "M_C_CPU1_SA_DQ<29>")
		)
		(pad "50" smd rect
			(at -2.050034 -21.67509 90)
			(size 0.519938 1.4986)
			(layers "F.Cu" "F.Mask" "F.Paste")
			(net "GND")
		)
		(pad "51" smd rect
			(at -2.050034 -20.824952 90)
			(size 0.519938 1.4986)
			(layers "F.Cu" "F.Mask" "F.Paste")
			(net "M_C_CPU1_SA_CB<0>")
		)
		(pad "52" smd rect
			(at -2.050034 -19.975068 90)
			(size 0.519938 1.4986)
			(layers "F.Cu" "F.Mask" "F.Paste")
			(net "GND")
		)
		(pad "53" smd rect
			(at -2.050034 -19.12493 90)
			(size 0.519938 1.4986)
			(layers "F.Cu" "F.Mask" "F.Paste")
			(net "M_C_CPU1_SA_CB<1>")
		)
		(pad "54" smd rect
			(at -2.050034 -18.275046 90)
			(size 0.519938 1.4986)
			(layers "F.Cu" "F.Mask" "F.Paste")
			(net "GND")
		)
		(pad "55" smd rect
			(at -2.050034 -17.424908 90)
			(size 0.519938 1.4986)
			(layers "F.Cu" "F.Mask" "F.Paste")
			(net "M_C_CPU1_SA_DQS_DP<4>")
		)
		(pad "56" smd rect
			(at -2.050034 -16.575024 90)
			(size 0.519938 1.4986)
			(layers "F.Cu" "F.Mask" "F.Paste")
			(net "M_C_CPU1_SA_DQS_DN<4>")
		)
		(pad "57" smd rect
			(at -2.050034 -15.724886 90)
			(size 0.519938 1.4986)
			(layers "F.Cu" "F.Mask" "F.Paste")
			(net "GND")
		)
		(pad "58" smd rect
			(at -2.050034 -14.875002 90)
			(size 0.519938 1.4986)
			(layers "F.Cu" "F.Mask" "F.Paste")
			(net "M_C_CPU1_SA_CB<4>")
		)
		(pad "59" smd rect
			(at -2.050034 -14.025118 90)
			(size 0.519938 1.4986)
			(layers "F.Cu" "F.Mask" "F.Paste")
			(net "GND")
		)
		(pad "60" smd rect
			(at -2.050034 -13.17498 90)
			(size 0.519938 1.4986)
			(layers "F.Cu" "F.Mask" "F.Paste")
			(net "M_C_CPU1_SA_CB<5>")
		)
		(pad "61" smd rect
			(at -2.050034 -12.325096 90)
			(size 0.519938 1.4986)
			(layers "F.Cu" "F.Mask" "F.Paste")
			(net "GND")
		)
		(pad "62" smd rect
			(at -2.050034 -11.474958 90)
			(size 0.519938 1.4986)
			(layers "F.Cu" "F.Mask" "F.Paste")
			(net "M_C_CPU1_ALERT_N")
		)
		(pad "63" smd rect
			(at -2.050034 -10.625074 90)
			(size 0.519938 1.4986)
			(layers "F.Cu" "F.Mask" "F.Paste")
			(net "GND")
		)
		(pad "64" smd rect
			(at -2.050034 -9.774936 90)
			(size 0.519938 1.4986)
			(layers "F.Cu" "F.Mask" "F.Paste")
			(net "M_C_CPU1_SA_CS_N<0>")
		)
		(pad "65" smd rect
			(at -2.050034 -8.925052 90)
			(size 0.519938 1.4986)
			(layers "F.Cu" "F.Mask" "F.Paste")
			(net "GND")
		)
		(pad "66" smd rect
			(at -2.050034 -8.074914 90)
			(size 0.519938 1.4986)
			(layers "F.Cu" "F.Mask" "F.Paste")
			(net "M_C_CPU1_SA_CA<0>")
		)
		(pad "67" smd rect
			(at -2.050034 -7.22503 90)
			(size 0.519938 1.4986)
			(layers "F.Cu" "F.Mask" "F.Paste")
			(net "GND")
		)
		(pad "68" smd rect
			(at -2.050034 -6.374892 90)
			(size 0.519938 1.4986)
			(layers "F.Cu" "F.Mask" "F.Paste")
			(net "M_C_CPU1_SA_CA<2>")
		)
		(pad "69" smd rect
			(at -2.050034 -5.525008 90)
			(size 0.519938 1.4986)
			(layers "F.Cu" "F.Mask" "F.Paste")
			(net "GND")
		)
		(pad "70" smd rect
			(at -2.050034 -4.675124 90)
			(size 0.519938 1.4986)
			(layers "F.Cu" "F.Mask" "F.Paste")
			(net "M_C_CPU1_SA_CA<4>")
		)
		(pad "71" smd rect
			(at -2.050034 -3.824986 90)
			(size 0.519938 1.4986)
			(layers "F.Cu" "F.Mask" "F.Paste")
			(net "GND")
		)
		(pad "72" smd rect
			(at -2.050034 -2.975102 90)
			(size 0.519938 1.4986)
			(layers "F.Cu" "F.Mask" "F.Paste")
			(net "M_C_CPU1_SA_CA<6>")
		)
		(pad "73" smd rect
			(at -2.050034 -2.124964 90)
			(size 0.519938 1.4986)
			(layers "F.Cu" "F.Mask" "F.Paste")
			(net "GND")
		)
		(pad "74" smd rect
			(at -2.050034 -1.27508 90)
			(size 0.519938 1.4986)
			(layers "F.Cu" "F.Mask" "F.Paste")
			(net "M_C_CPU1_SA_PAR")
		)
		(pad "75" smd rect
			(at -2.050034 -0.424942 90)
			(size 0.519938 1.4986)
			(layers "F.Cu" "F.Mask" "F.Paste")
			(net "GND")
		)
		(pad "76" smd rect
			(at -2.050034 5.525008 90)
			(size 0.519938 1.4986)
			(layers "F.Cu" "F.Mask" "F.Paste")
			(net "M_C_CPU1_SB_CA<0>")
		)
		(pad "77" smd rect
			(at -2.050034 6.374892 90)
			(size 0.519938 1.4986)
			(layers "F.Cu" "F.Mask" "F.Paste")
			(net "GND")
		)
		(pad "78" smd rect
			(at -2.050034 7.22503 90)
			(size 0.519938 1.4986)
			(layers "F.Cu" "F.Mask" "F.Paste")
			(net "M_C_CPU1_SB_CA<2>")
		)
		(pad "79" smd rect
			(at -2.050034 8.074914 90)
			(size 0.519938 1.4986)
			(layers "F.Cu" "F.Mask" "F.Paste")
			(net "GND")
		)
		(pad "80" smd rect
			(at -2.050034 8.925052 90)
			(size 0.519938 1.4986)
			(layers "F.Cu" "F.Mask" "F.Paste")
			(net "M_C_CPU1_SB_CA<4>")
		)
		(pad "81" smd rect
			(at -2.050034 9.774936 90)
			(size 0.519938 1.4986)
			(layers "F.Cu" "F.Mask" "F.Paste")
			(net "GND")
		)
		(pad "82" smd rect
			(at -2.050034 10.625074 90)
			(size 0.519938 1.4986)
			(layers "F.Cu" "F.Mask" "F.Paste")
			(net "M_C_CPU1_SB_CA<6>")
		)
		(pad "83" smd rect
			(at -2.050034 11.474958 90)
			(size 0.519938 1.4986)
			(layers "F.Cu" "F.Mask" "F.Paste")
			(net "GND")
		)
		(pad "84" smd rect
			(at -2.050034 12.325096 90)
			(size 0.519938 1.4986)
			(layers "F.Cu" "F.Mask" "F.Paste")
			(net "M_C_CPU1_SB_CS_N<0>")
		)
		(pad "85" smd rect
			(at -2.050034 13.17498 90)
			(size 0.519938 1.4986)
			(layers "F.Cu" "F.Mask" "F.Paste")
			(net "GND")
		)
		(pad "86" smd rect
			(at -2.050034 14.025118 90)
			(size 0.519938 1.4986)
			(layers "F.Cu" "F.Mask" "F.Paste")
			(net "M_C_CPU1_SA_RSP<0>")
		)
		(pad "87" smd rect
			(at -2.050034 14.875002 90)
			(size 0.519938 1.4986)
			(layers "F.Cu" "F.Mask" "F.Paste")
			(net "M_C_CPU1_SB_RSP<0>")
		)
		(pad "88" smd rect
			(at -2.050034 15.724886 90)
			(size 0.519938 1.4986)
			(layers "F.Cu" "F.Mask" "F.Paste")
			(net "GND")
		)
		(pad "89" smd rect
			(at -2.050034 16.575024 90)
			(size 0.519938 1.4986)
			(layers "F.Cu" "F.Mask" "F.Paste")
			(net "M_C_CPU1_SB_CB<4>")
		)
		(pad "90" smd rect
			(at -2.050034 17.424908 90)
			(size 0.519938 1.4986)
			(layers "F.Cu" "F.Mask" "F.Paste")
			(net "GND")
		)
		(pad "91" smd rect
			(at -2.050034 18.275046 90)
			(size 0.519938 1.4986)
			(layers "F.Cu" "F.Mask" "F.Paste")
			(net "M_C_CPU1_SB_CB<5>")
		)
		(pad "92" smd rect
			(at -2.050034 19.12493 90)
			(size 0.519938 1.4986)
			(layers "F.Cu" "F.Mask" "F.Paste")
			(net "GND")
		)
		(pad "93" smd rect
			(at -2.050034 19.975068 90)
			(size 0.519938 1.4986)
			(layers "F.Cu" "F.Mask" "F.Paste")
			(net "M_C_CPU1_SB_DQS_DP<9>")
		)
		(pad "94" smd rect
			(at -2.050034 20.824952 90)
			(size 0.519938 1.4986)
			(layers "F.Cu" "F.Mask" "F.Paste")
			(net "M_C_CPU1_SB_DQS_DN<9>")
		)
		(pad "95" smd rect
			(at -2.050034 21.67509 90)
			(size 0.519938 1.4986)
			(layers "F.Cu" "F.Mask" "F.Paste")
			(net "GND")
		)
		(pad "96" smd rect
			(at -2.050034 22.524974 90)
			(size 0.519938 1.4986)
			(layers "F.Cu" "F.Mask" "F.Paste")
			(net "M_C_CPU1_SB_CB<0>")
		)
		(pad "97" smd rect
			(at -2.050034 23.375112 90)
			(size 0.519938 1.4986)
			(layers "F.Cu" "F.Mask" "F.Paste")
			(net "GND")
		)
		(pad "98" smd rect
			(at -2.050034 24.224996 90)
			(size 0.519938 1.4986)
			(layers "F.Cu" "F.Mask" "F.Paste")
			(net "M_C_CPU1_SB_CB<1>")
		)
		(pad "99" smd rect
			(at -2.050034 25.07488 90)
			(size 0.519938 1.4986)
			(layers "F.Cu" "F.Mask" "F.Paste")
			(net "GND")
		)
		(pad "100" smd rect
			(at -2.050034 25.925018 90)
			(size 0.519938 1.4986)
			(layers "F.Cu" "F.Mask" "F.Paste")
			(net "M_C_CPU1_SB_DQ<0>")
		)
		(pad "101" smd rect
			(at -2.050034 26.774902 90)
			(size 0.519938 1.4986)
			(layers "F.Cu" "F.Mask" "F.Paste")
			(net "GND")
		)
		(pad "102" smd rect
			(at -2.050034 27.62504 90)
			(size 0.519938 1.4986)
			(layers "F.Cu" "F.Mask" "F.Paste")
			(net "M_C_CPU1_SB_DQ<1>")
		)
		(pad "103" smd rect
			(at -2.050034 28.474924 90)
			(size 0.519938 1.4986)
			(layers "F.Cu" "F.Mask" "F.Paste")
			(net "GND")
		)
		(pad "104" smd rect
			(at -2.050034 29.325062 90)
			(size 0.519938 1.4986)
			(layers "F.Cu" "F.Mask" "F.Paste")
			(net "M_C_CPU1_SB_DQS_DP<0>")
		)
		(pad "105" smd rect
			(at -2.050034 30.174946 90)
			(size 0.519938 1.4986)
			(layers "F.Cu" "F.Mask" "F.Paste")
			(net "M_C_CPU1_SB_DQS_DN<0>")
		)
		(pad "106" smd rect
			(at -2.050034 31.025084 90)
			(size 0.519938 1.4986)
			(layers "F.Cu" "F.Mask" "F.Paste")
			(net "GND")
		)
		(pad "107" smd rect
			(at -2.050034 31.874968 90)
			(size 0.519938 1.4986)
			(layers "F.Cu" "F.Mask" "F.Paste")
			(net "M_C_CPU1_SB_DQ<4>")
		)
		(pad "108" smd rect
			(at -2.050034 32.725106 90)
			(size 0.519938 1.4986)
			(layers "F.Cu" "F.Mask" "F.Paste")
			(net "GND")
		)
		(pad "109" smd rect
			(at -2.050034 33.57499 90)
			(size 0.519938 1.4986)
			(layers "F.Cu" "F.Mask" "F.Paste")
			(net "M_C_CPU1_SB_DQ<5>")
		)
		(pad "110" smd rect
			(at -2.050034 34.425128 90)
			(size 0.519938 1.4986)
			(layers "F.Cu" "F.Mask" "F.Paste")
			(net "GND")
		)
		(pad "111" smd rect
			(at -2.050034 35.275012 90)
			(size 0.519938 1.4986)
			(layers "F.Cu" "F.Mask" "F.Paste")
			(net "M_C_CPU1_SB_DQ<8>")
		)
		(pad "112" smd rect
			(at -2.050034 36.124896 90)
			(size 0.519938 1.4986)
			(layers "F.Cu" "F.Mask" "F.Paste")
			(net "GND")
		)
		(pad "113" smd rect
			(at -2.050034 36.975034 90)
			(size 0.519938 1.4986)
			(layers "F.Cu" "F.Mask" "F.Paste")
			(net "M_C_CPU1_SB_DQ<9>")
		)
		(pad "114" smd rect
			(at -2.050034 37.824918 90)
			(size 0.519938 1.4986)
			(layers "F.Cu" "F.Mask" "F.Paste")
			(net "GND")
		)
		(pad "115" smd rect
			(at -2.050034 38.675056 90)
			(size 0.519938 1.4986)
			(layers "F.Cu" "F.Mask" "F.Paste")
			(net "M_C_CPU1_SB_DQS_DP<1>")
		)
		(pad "116" smd rect
			(at -2.050034 39.52494 90)
			(size 0.519938 1.4986)
			(layers "F.Cu" "F.Mask" "F.Paste")
			(net "M_C_CPU1_SB_DQS_DN<1>")
		)
		(pad "117" smd rect
			(at -2.050034 40.375078 90)
			(size 0.519938 1.4986)
			(layers "F.Cu" "F.Mask" "F.Paste")
			(net "GND")
		)
		(pad "118" smd rect
			(at -2.050034 41.224962 90)
			(size 0.519938 1.4986)
			(layers "F.Cu" "F.Mask" "F.Paste")
			(net "M_C_CPU1_SB_DQ<12>")
		)
		(pad "119" smd rect
			(at -2.050034 42.0751 90)
			(size 0.519938 1.4986)
			(layers "F.Cu" "F.Mask" "F.Paste")
			(net "GND")
		)
		(pad "120" smd rect
			(at -2.050034 42.924984 90)
			(size 0.519938 1.4986)
			(layers "F.Cu" "F.Mask" "F.Paste")
			(net "M_C_CPU1_SB_DQ<13>")
		)
		(pad "121" smd rect
			(at -2.050034 43.775122 90)
			(size 0.519938 1.4986)
			(layers "F.Cu" "F.Mask" "F.Paste")
			(net "GND")
		)
		(pad "122" smd rect
			(at -2.050034 44.625006 90)
			(size 0.519938 1.4986)
			(layers "F.Cu" "F.Mask" "F.Paste")
			(net "M_C_CPU1_SB_DQ<16>")
		)
		(pad "123" smd rect
			(at -2.050034 45.47489 90)
			(size 0.519938 1.4986)
			(layers "F.Cu" "F.Mask" "F.Paste")
			(net "GND")
		)
		(pad "124" smd rect
			(at -2.050034 46.325028 90)
			(size 0.519938 1.4986)
			(layers "F.Cu" "F.Mask" "F.Paste")
			(net "M_C_CPU1_SB_DQ<17>")
		)
		(pad "125" smd rect
			(at -2.050034 47.174912 90)
			(size 0.519938 1.4986)
			(layers "F.Cu" "F.Mask" "F.Paste")
			(net "GND")
		)
		(pad "126" smd rect
			(at -2.050034 48.02505 90)
			(size 0.519938 1.4986)
			(layers "F.Cu" "F.Mask" "F.Paste")
			(net "M_C_CPU1_SB_DQS_DP<2>")
		)
		(pad "127" smd rect
			(at -2.050034 48.874934 90)
			(size 0.519938 1.4986)
			(layers "F.Cu" "F.Mask" "F.Paste")
			(net "M_C_CPU1_SB_DQS_DN<2>")
		)
		(pad "128" smd rect
			(at -2.050034 49.725072 90)
			(size 0.519938 1.4986)
			(layers "F.Cu" "F.Mask" "F.Paste")
			(net "GND")
		)
		(pad "129" smd rect
			(at -2.050034 50.574956 90)
			(size 0.519938 1.4986)
			(layers "F.Cu" "F.Mask" "F.Paste")
			(net "M_C_CPU1_SB_DQ<20>")
		)
		(pad "130" smd rect
			(at -2.050034 51.425094 90)
			(size 0.519938 1.4986)
			(layers "F.Cu" "F.Mask" "F.Paste")
			(net "GND")
		)
		(pad "131" smd rect
			(at -2.050034 52.274978 90)
			(size 0.519938 1.4986)
			(layers "F.Cu" "F.Mask" "F.Paste")
			(net "M_C_CPU1_SB_DQ<21>")
		)
		(pad "132" smd rect
			(at -2.050034 53.125116 90)
			(size 0.519938 1.4986)
			(layers "F.Cu" "F.Mask" "F.Paste")
			(net "GND")
		)
		(pad "133" smd rect
			(at -2.050034 53.975 90)
			(size 0.519938 1.4986)
			(layers "F.Cu" "F.Mask" "F.Paste")
			(net "M_C_CPU1_SB_DQ<24>")
		)
		(pad "134" smd rect
			(at -2.050034 54.824884 90)
			(size 0.519938 1.4986)
			(layers "F.Cu" "F.Mask" "F.Paste")
			(net "GND")
		)
		(pad "135" smd rect
			(at -2.050034 55.675022 90)
			(size 0.519938 1.4986)
			(layers "F.Cu" "F.Mask" "F.Paste")
			(net "M_C_CPU1_SB_DQ<25>")
		)
		(pad "136" smd rect
			(at -2.050034 56.524906 90)
			(size 0.519938 1.4986)
			(layers "F.Cu" "F.Mask" "F.Paste")
			(net "GND")
		)
		(pad "137" smd rect
			(at -2.050034 57.375044 90)
			(size 0.519938 1.4986)
			(layers "F.Cu" "F.Mask" "F.Paste")
			(net "M_C_CPU1_SB_DQS_DP<3>")
		)
		(pad "138" smd rect
			(at -2.050034 58.224928 90)
			(size 0.519938 1.4986)
			(layers "F.Cu" "F.Mask" "F.Paste")
			(net "M_C_CPU1_SB_DQS_DN<3>")
		)
		(pad "139" smd rect
			(at -2.050034 59.075066 90)
			(size 0.519938 1.4986)
			(layers "F.Cu" "F.Mask" "F.Paste")
			(net "GND")
		)
		(pad "140" smd rect
			(at -2.050034 59.92495 90)
			(size 0.519938 1.4986)
			(layers "F.Cu" "F.Mask" "F.Paste")
			(net "M_C_CPU1_SB_DQ<28>")
		)
		(pad "141" smd rect
			(at -2.050034 60.775088 90)
			(size 0.519938 1.4986)
			(layers "F.Cu" "F.Mask" "F.Paste")
			(net "GND")
		)
		(pad "142" smd rect
			(at -2.050034 61.624972 90)
			(size 0.519938 1.4986)
			(layers "F.Cu" "F.Mask" "F.Paste")
			(net "M_C_CPU1_SB_DQ<29>")
		)
		(pad "143" smd rect
			(at -2.050034 62.47511 90)
			(size 0.519938 1.4986)
			(layers "F.Cu" "F.Mask" "F.Paste")
			(net "GND")
		)
		(pad "144" smd rect
			(at -2.050034 63.324994 90)
			(size 0.519938 1.4986)
			(layers "F.Cu" "F.Mask" "F.Paste")
			(net "Net_2285")
		)
		(pad "145" smd rect
			(at 2.050034 -63.324994 90)
			(size 0.519938 1.4986)
			(layers "F.Cu" "F.Mask" "F.Paste")
			(net "P12V_MEM_CPU1")
		)
		(pad "146" smd rect
			(at 2.050034 -62.47511 90)
			(size 0.519938 1.4986)
			(layers "F.Cu" "F.Mask" "F.Paste")
			(net "P12V_MEM_CPU1")
		)
		(pad "147" smd rect
			(at 2.050034 -61.624972 90)
			(size 0.519938 1.4986)
			(layers "F.Cu" "F.Mask" "F.Paste")
			(net "PWRGD_CHC_CPU1_DIMM")
		)
		(pad "148" smd rect
			(at 2.050034 -60.775088 90)
			(size 0.519938 1.4986)
			(layers "F.Cu" "F.Mask" "F.Paste")
			(net "PD_CHC_CPU1_DIMM_SAA")
		)
		(pad "149" smd rect
			(at 2.050034 -59.92495 90)
			(size 0.519938 1.4986)
			(layers "F.Cu" "F.Mask" "F.Paste")
			(net "Net_2286")
		)
		(pad "150" smd rect
			(at 2.050034 -59.075066 90)
			(size 0.519938 1.4986)
			(layers "F.Cu" "F.Mask" "F.Paste")
			(net "Net_2287")
		)
		(pad "151" smd rect
			(at 2.050034 -58.224928 90)
			(size 0.519938 1.4986)
			(layers "F.Cu" "F.Mask" "F.Paste")
			(net "GND")
		)
		(pad "152" smd rect
			(at 2.050034 -57.375044 90)
			(size 0.519938 1.4986)
			(layers "F.Cu" "F.Mask" "F.Paste")
			(net "M_C_CPU1_SA_DQ<2>")
		)
		(pad "153" smd rect
			(at 2.050034 -56.524906 90)
			(size 0.519938 1.4986)
			(layers "F.Cu" "F.Mask" "F.Paste")
			(net "GND")
		)
		(pad "154" smd rect
			(at 2.050034 -55.675022 90)
			(size 0.519938 1.4986)
			(layers "F.Cu" "F.Mask" "F.Paste")
			(net "M_C_CPU1_SA_DQ<3>")
		)
		(pad "155" smd rect
			(at 2.050034 -54.824884 90)
			(size 0.519938 1.4986)
			(layers "F.Cu" "F.Mask" "F.Paste")
			(net "GND")
		)
		(pad "156" smd rect
			(at 2.050034 -53.975 90)
			(size 0.519938 1.4986)
			(layers "F.Cu" "F.Mask" "F.Paste")
			(net "M_C_CPU1_SA_DQS_DN<5>")
		)
		(pad "157" smd rect
			(at 2.050034 -53.125116 90)
			(size 0.519938 1.4986)
			(layers "F.Cu" "F.Mask" "F.Paste")
			(net "M_C_CPU1_SA_DQS_DP<5>")
		)
		(pad "158" smd rect
			(at 2.050034 -52.274978 90)
			(size 0.519938 1.4986)
			(layers "F.Cu" "F.Mask" "F.Paste")
			(net "GND")
		)
		(pad "159" smd rect
			(at 2.050034 -51.425094 90)
			(size 0.519938 1.4986)
			(layers "F.Cu" "F.Mask" "F.Paste")
			(net "M_C_CPU1_SA_DQ<6>")
		)
		(pad "160" smd rect
			(at 2.050034 -50.574956 90)
			(size 0.519938 1.4986)
			(layers "F.Cu" "F.Mask" "F.Paste")
			(net "GND")
		)
		(pad "161" smd rect
			(at 2.050034 -49.725072 90)
			(size 0.519938 1.4986)
			(layers "F.Cu" "F.Mask" "F.Paste")
			(net "M_C_CPU1_SA_DQ<7>")
		)
		(pad "162" smd rect
			(at 2.050034 -48.874934 90)
			(size 0.519938 1.4986)
			(layers "F.Cu" "F.Mask" "F.Paste")
			(net "GND")
		)
		(pad "163" smd rect
			(at 2.050034 -48.02505 90)
			(size 0.519938 1.4986)
			(layers "F.Cu" "F.Mask" "F.Paste")
			(net "M_C_CPU1_SA_DQ<10>")
		)
		(pad "164" smd rect
			(at 2.050034 -47.174912 90)
			(size 0.519938 1.4986)
			(layers "F.Cu" "F.Mask" "F.Paste")
			(net "GND")
		)
		(pad "165" smd rect
			(at 2.050034 -46.325028 90)
			(size 0.519938 1.4986)
			(layers "F.Cu" "F.Mask" "F.Paste")
			(net "M_C_CPU1_SA_DQ<11>")
		)
		(pad "166" smd rect
			(at 2.050034 -45.47489 90)
			(size 0.519938 1.4986)
			(layers "F.Cu" "F.Mask" "F.Paste")
			(net "GND")
		)
		(pad "167" smd rect
			(at 2.050034 -44.625006 90)
			(size 0.519938 1.4986)
			(layers "F.Cu" "F.Mask" "F.Paste")
			(net "M_C_CPU1_SA_DQS_DN<6>")
		)
		(pad "168" smd rect
			(at 2.050034 -43.775122 90)
			(size 0.519938 1.4986)
			(layers "F.Cu" "F.Mask" "F.Paste")
			(net "M_C_CPU1_SA_DQS_DP<6>")
		)
		(pad "169" smd rect
			(at 2.050034 -42.924984 90)
			(size 0.519938 1.4986)
			(layers "F.Cu" "F.Mask" "F.Paste")
			(net "GND")
		)
		(pad "170" smd rect
			(at 2.050034 -42.0751 90)
			(size 0.519938 1.4986)
			(layers "F.Cu" "F.Mask" "F.Paste")
			(net "M_C_CPU1_SA_DQ<14>")
		)
		(pad "171" smd rect
			(at 2.050034 -41.224962 90)
			(size 0.519938 1.4986)
			(layers "F.Cu" "F.Mask" "F.Paste")
			(net "GND")
		)
		(pad "172" smd rect
			(at 2.050034 -40.375078 90)
			(size 0.519938 1.4986)
			(layers "F.Cu" "F.Mask" "F.Paste")
			(net "M_C_CPU1_SA_DQ<15>")
		)
		(pad "173" smd rect
			(at 2.050034 -39.52494 90)
			(size 0.519938 1.4986)
			(layers "F.Cu" "F.Mask" "F.Paste")
			(net "GND")
		)
		(pad "174" smd rect
			(at 2.050034 -38.675056 90)
			(size 0.519938 1.4986)
			(layers "F.Cu" "F.Mask" "F.Paste")
			(net "M_C_CPU1_SA_DQ<18>")
		)
		(pad "175" smd rect
			(at 2.050034 -37.824918 90)
			(size 0.519938 1.4986)
			(layers "F.Cu" "F.Mask" "F.Paste")
			(net "GND")
		)
		(pad "176" smd rect
			(at 2.050034 -36.975034 90)
			(size 0.519938 1.4986)
			(layers "F.Cu" "F.Mask" "F.Paste")
			(net "M_C_CPU1_SA_DQ<19>")
		)
		(pad "177" smd rect
			(at 2.050034 -36.124896 90)
			(size 0.519938 1.4986)
			(layers "F.Cu" "F.Mask" "F.Paste")
			(net "GND")
		)
		(pad "178" smd rect
			(at 2.050034 -35.275012 90)
			(size 0.519938 1.4986)
			(layers "F.Cu" "F.Mask" "F.Paste")
			(net "M_C_CPU1_SA_DQS_DN<7>")
		)
		(pad "179" smd rect
			(at 2.050034 -34.425128 90)
			(size 0.519938 1.4986)
			(layers "F.Cu" "F.Mask" "F.Paste")
			(net "M_C_CPU1_SA_DQS_DP<7>")
		)
		(pad "180" smd rect
			(at 2.050034 -33.57499 90)
			(size 0.519938 1.4986)
			(layers "F.Cu" "F.Mask" "F.Paste")
			(net "GND")
		)
		(pad "181" smd rect
			(at 2.050034 -32.725106 90)
			(size 0.519938 1.4986)
			(layers "F.Cu" "F.Mask" "F.Paste")
			(net "M_C_CPU1_SA_DQ<22>")
		)
		(pad "182" smd rect
			(at 2.050034 -31.874968 90)
			(size 0.519938 1.4986)
			(layers "F.Cu" "F.Mask" "F.Paste")
			(net "GND")
		)
		(pad "183" smd rect
			(at 2.050034 -31.025084 90)
			(size 0.519938 1.4986)
			(layers "F.Cu" "F.Mask" "F.Paste")
			(net "M_C_CPU1_SA_DQ<23>")
		)
		(pad "184" smd rect
			(at 2.050034 -30.174946 90)
			(size 0.519938 1.4986)
			(layers "F.Cu" "F.Mask" "F.Paste")
			(net "GND")
		)
		(pad "185" smd rect
			(at 2.050034 -29.325062 90)
			(size 0.519938 1.4986)
			(layers "F.Cu" "F.Mask" "F.Paste")
			(net "M_C_CPU1_SA_DQ<26>")
		)
		(pad "186" smd rect
			(at 2.050034 -28.474924 90)
			(size 0.519938 1.4986)
			(layers "F.Cu" "F.Mask" "F.Paste")
			(net "GND")
		)
		(pad "187" smd rect
			(at 2.050034 -27.62504 90)
			(size 0.519938 1.4986)
			(layers "F.Cu" "F.Mask" "F.Paste")
			(net "M_C_CPU1_SA_DQ<27>")
		)
		(pad "188" smd rect
			(at 2.050034 -26.774902 90)
			(size 0.519938 1.4986)
			(layers "F.Cu" "F.Mask" "F.Paste")
			(net "GND")
		)
		(pad "189" smd rect
			(at 2.050034 -25.925018 90)
			(size 0.519938 1.4986)
			(layers "F.Cu" "F.Mask" "F.Paste")
			(net "M_C_CPU1_SA_DQS_DN<8>")
		)
		(pad "190" smd rect
			(at 2.050034 -25.07488 90)
			(size 0.519938 1.4986)
			(layers "F.Cu" "F.Mask" "F.Paste")
			(net "M_C_CPU1_SA_DQS_DP<8>")
		)
		(pad "191" smd rect
			(at 2.050034 -24.224996 90)
			(size 0.519938 1.4986)
			(layers "F.Cu" "F.Mask" "F.Paste")
			(net "GND")
		)
		(pad "192" smd rect
			(at 2.050034 -23.375112 90)
			(size 0.519938 1.4986)
			(layers "F.Cu" "F.Mask" "F.Paste")
			(net "M_C_CPU1_SA_DQ<30>")
		)
		(pad "193" smd rect
			(at 2.050034 -22.524974 90)
			(size 0.519938 1.4986)
			(layers "F.Cu" "F.Mask" "F.Paste")
			(net "GND")
		)
		(pad "194" smd rect
			(at 2.050034 -21.67509 90)
			(size 0.519938 1.4986)
			(layers "F.Cu" "F.Mask" "F.Paste")
			(net "M_C_CPU1_SA_DQ<31>")
		)
		(pad "195" smd rect
			(at 2.050034 -20.824952 90)
			(size 0.519938 1.4986)
			(layers "F.Cu" "F.Mask" "F.Paste")
			(net "GND")
		)
		(pad "196" smd rect
			(at 2.050034 -19.975068 90)
			(size 0.519938 1.4986)
			(layers "F.Cu" "F.Mask" "F.Paste")
			(net "M_C_CPU1_SA_CB<2>")
		)
		(pad "197" smd rect
			(at 2.050034 -19.12493 90)
			(size 0.519938 1.4986)
			(layers "F.Cu" "F.Mask" "F.Paste")
			(net "GND")
		)
		(pad "198" smd rect
			(at 2.050034 -18.275046 90)
			(size 0.519938 1.4986)
			(layers "F.Cu" "F.Mask" "F.Paste")
			(net "M_C_CPU1_SA_CB<3>")
		)
		(pad "199" smd rect
			(at 2.050034 -17.424908 90)
			(size 0.519938 1.4986)
			(layers "F.Cu" "F.Mask" "F.Paste")
			(net "GND")
		)
		(pad "200" smd rect
			(at 2.050034 -16.575024 90)
			(size 0.519938 1.4986)
			(layers "F.Cu" "F.Mask" "F.Paste")
			(net "M_C_CPU1_SA_DQS_DN<9>")
		)
		(pad "201" smd rect
			(at 2.050034 -15.724886 90)
			(size 0.519938 1.4986)
			(layers "F.Cu" "F.Mask" "F.Paste")
			(net "M_C_CPU1_SA_DQS_DP<9>")
		)
		(pad "202" smd rect
			(at 2.050034 -14.875002 90)
			(size 0.519938 1.4986)
			(layers "F.Cu" "F.Mask" "F.Paste")
			(net "GND")
		)
		(pad "203" smd rect
			(at 2.050034 -14.025118 90)
			(size 0.519938 1.4986)
			(layers "F.Cu" "F.Mask" "F.Paste")
			(net "M_C_CPU1_SA_CB<6>")
		)
		(pad "204" smd rect
			(at 2.050034 -13.17498 90)
			(size 0.519938 1.4986)
			(layers "F.Cu" "F.Mask" "F.Paste")
			(net "GND")
		)
		(pad "205" smd rect
			(at 2.050034 -12.325096 90)
			(size 0.519938 1.4986)
			(layers "F.Cu" "F.Mask" "F.Paste")
			(net "M_C_CPU1_SA_CB<7>")
		)
		(pad "206" smd rect
			(at 2.050034 -11.474958 90)
			(size 0.519938 1.4986)
			(layers "F.Cu" "F.Mask" "F.Paste")
			(net "GND")
		)
		(pad "207" smd rect
			(at 2.050034 -10.625074 90)
			(size 0.519938 1.4986)
			(layers "F.Cu" "F.Mask" "F.Paste")
			(net "M_C_CPU1_RESET_N")
		)
		(pad "208" smd rect
			(at 2.050034 -9.774936 90)
			(size 0.519938 1.4986)
			(layers "F.Cu" "F.Mask" "F.Paste")
			(net "GND")
		)
		(pad "209" smd rect
			(at 2.050034 -8.925052 90)
			(size 0.519938 1.4986)
			(layers "F.Cu" "F.Mask" "F.Paste")
			(net "M_C_CPU1_SA_CS_N<1>")
		)
		(pad "210" smd rect
			(at 2.050034 -8.074914 90)
			(size 0.519938 1.4986)
			(layers "F.Cu" "F.Mask" "F.Paste")
			(net "GND")
		)
		(pad "211" smd rect
			(at 2.050034 -7.22503 90)
			(size 0.519938 1.4986)
			(layers "F.Cu" "F.Mask" "F.Paste")
			(net "M_C_CPU1_SA_CA<1>")
		)
		(pad "212" smd rect
			(at 2.050034 -6.374892 90)
			(size 0.519938 1.4986)
			(layers "F.Cu" "F.Mask" "F.Paste")
			(net "GND")
		)
		(pad "213" smd rect
			(at 2.050034 -5.525008 90)
			(size 0.519938 1.4986)
			(layers "F.Cu" "F.Mask" "F.Paste")
			(net "M_C_CPU1_SA_CA<3>")
		)
		(pad "214" smd rect
			(at 2.050034 -4.675124 90)
			(size 0.519938 1.4986)
			(layers "F.Cu" "F.Mask" "F.Paste")
			(net "GND")
		)
		(pad "215" smd rect
			(at 2.050034 -3.824986 90)
			(size 0.519938 1.4986)
			(layers "F.Cu" "F.Mask" "F.Paste")
			(net "M_C_CPU1_SA_CA<5>")
		)
		(pad "216" smd rect
			(at 2.050034 -2.975102 90)
			(size 0.519938 1.4986)
			(layers "F.Cu" "F.Mask" "F.Paste")
			(net "GND")
		)
		(pad "217" smd rect
			(at 2.050034 -2.124964 90)
			(size 0.519938 1.4986)
			(layers "F.Cu" "F.Mask" "F.Paste")
			(net "M_C_CPU1_CLK_DP<0>")
		)
		(pad "218" smd rect
			(at 2.050034 -1.27508 90)
			(size 0.519938 1.4986)
			(layers "F.Cu" "F.Mask" "F.Paste")
			(net "M_C_CPU1_CLK_DN<0>")
		)
		(pad "219" smd rect
			(at 2.050034 -0.424942 90)
			(size 0.519938 1.4986)
			(layers "F.Cu" "F.Mask" "F.Paste")
			(net "GND")
		)
		(pad "220" smd rect
			(at 2.050034 5.525008 90)
			(size 0.519938 1.4986)
			(layers "F.Cu" "F.Mask" "F.Paste")
			(net "Net_2288")
		)
		(pad "221" smd rect
			(at 2.050034 6.374892 90)
			(size 0.519938 1.4986)
			(layers "F.Cu" "F.Mask" "F.Paste")
			(net "M_C_CPU1_SB_CA<1>")
		)
		(pad "222" smd rect
			(at 2.050034 7.22503 90)
			(size 0.519938 1.4986)
			(layers "F.Cu" "F.Mask" "F.Paste")
			(net "GND")
		)
		(pad "223" smd rect
			(at 2.050034 8.074914 90)
			(size 0.519938 1.4986)
			(layers "F.Cu" "F.Mask" "F.Paste")
			(net "M_C_CPU1_SB_CA<3>")
		)
		(pad "224" smd rect
			(at 2.050034 8.925052 90)
			(size 0.519938 1.4986)
			(layers "F.Cu" "F.Mask" "F.Paste")
			(net "GND")
		)
		(pad "225" smd rect
			(at 2.050034 9.774936 90)
			(size 0.519938 1.4986)
			(layers "F.Cu" "F.Mask" "F.Paste")
			(net "M_C_CPU1_SB_CA<5>")
		)
		(pad "226" smd rect
			(at 2.050034 10.625074 90)
			(size 0.519938 1.4986)
			(layers "F.Cu" "F.Mask" "F.Paste")
			(net "GND")
		)
		(pad "227" smd rect
			(at 2.050034 11.474958 90)
			(size 0.519938 1.4986)
			(layers "F.Cu" "F.Mask" "F.Paste")
			(net "M_C_CPU1_SB_PAR")
		)
		(pad "228" smd rect
			(at 2.050034 12.325096 90)
			(size 0.519938 1.4986)
			(layers "F.Cu" "F.Mask" "F.Paste")
			(net "GND")
		)
		(pad "229" smd rect
			(at 2.050034 13.17498 90)
			(size 0.519938 1.4986)
			(layers "F.Cu" "F.Mask" "F.Paste")
			(net "M_C_CPU1_SB_CS_N<1>")
		)
		(pad "230" smd rect
			(at 2.050034 14.025118 90)
			(size 0.519938 1.4986)
			(layers "F.Cu" "F.Mask" "F.Paste")
			(net "GND")
		)
		(pad "231" smd rect
			(at 2.050034 14.875002 90)
			(size 0.519938 1.4986)
			(layers "F.Cu" "F.Mask" "F.Paste")
			(net "Net_2289")
		)
		(pad "232" smd rect
			(at 2.050034 15.724886 90)
			(size 0.519938 1.4986)
			(layers "F.Cu" "F.Mask" "F.Paste")
			(net "Net_2290")
		)
		(pad "233" smd rect
			(at 2.050034 16.575024 90)
			(size 0.519938 1.4986)
			(layers "F.Cu" "F.Mask" "F.Paste")
			(net "GND")
		)
		(pad "234" smd rect
			(at 2.050034 17.424908 90)
			(size 0.519938 1.4986)
			(layers "F.Cu" "F.Mask" "F.Paste")
			(net "M_C_CPU1_SB_CB<6>")
		)
		(pad "235" smd rect
			(at 2.050034 18.275046 90)
			(size 0.519938 1.4986)
			(layers "F.Cu" "F.Mask" "F.Paste")
			(net "GND")
		)
		(pad "236" smd rect
			(at 2.050034 19.12493 90)
			(size 0.519938 1.4986)
			(layers "F.Cu" "F.Mask" "F.Paste")
			(net "M_C_CPU1_SB_CB<7>")
		)
		(pad "237" smd rect
			(at 2.050034 19.975068 90)
			(size 0.519938 1.4986)
			(layers "F.Cu" "F.Mask" "F.Paste")
			(net "GND")
		)
		(pad "238" smd rect
			(at 2.050034 20.824952 90)
			(size 0.519938 1.4986)
			(layers "F.Cu" "F.Mask" "F.Paste")
			(net "M_C_CPU1_SB_DQS_DN<4>")
		)
		(pad "239" smd rect
			(at 2.050034 21.67509 90)
			(size 0.519938 1.4986)
			(layers "F.Cu" "F.Mask" "F.Paste")
			(net "M_C_CPU1_SB_DQS_DP<4>")
		)
		(pad "240" smd rect
			(at 2.050034 22.524974 90)
			(size 0.519938 1.4986)
			(layers "F.Cu" "F.Mask" "F.Paste")
			(net "GND")
		)
		(pad "241" smd rect
			(at 2.050034 23.375112 90)
			(size 0.519938 1.4986)
			(layers "F.Cu" "F.Mask" "F.Paste")
			(net "M_C_CPU1_SB_CB<2>")
		)
		(pad "242" smd rect
			(at 2.050034 24.224996 90)
			(size 0.519938 1.4986)
			(layers "F.Cu" "F.Mask" "F.Paste")
			(net "GND")
		)
		(pad "243" smd rect
			(at 2.050034 25.07488 90)
			(size 0.519938 1.4986)
			(layers "F.Cu" "F.Mask" "F.Paste")
			(net "M_C_CPU1_SB_CB<3>")
		)
		(pad "244" smd rect
			(at 2.050034 25.925018 90)
			(size 0.519938 1.4986)
			(layers "F.Cu" "F.Mask" "F.Paste")
			(net "GND")
		)
		(pad "245" smd rect
			(at 2.050034 26.774902 90)
			(size 0.519938 1.4986)
			(layers "F.Cu" "F.Mask" "F.Paste")
			(net "M_C_CPU1_SB_DQ<2>")
		)
		(pad "246" smd rect
			(at 2.050034 27.62504 90)
			(size 0.519938 1.4986)
			(layers "F.Cu" "F.Mask" "F.Paste")
			(net "GND")
		)
		(pad "247" smd rect
			(at 2.050034 28.474924 90)
			(size 0.519938 1.4986)
			(layers "F.Cu" "F.Mask" "F.Paste")
			(net "M_C_CPU1_SB_DQ<3>")
		)
		(pad "248" smd rect
			(at 2.050034 29.325062 90)
			(size 0.519938 1.4986)
			(layers "F.Cu" "F.Mask" "F.Paste")
			(net "GND")
		)
		(pad "249" smd rect
			(at 2.050034 30.174946 90)
			(size 0.519938 1.4986)
			(layers "F.Cu" "F.Mask" "F.Paste")
			(net "M_C_CPU1_SB_DQS_DN<5>")
		)
		(pad "250" smd rect
			(at 2.050034 31.025084 90)
			(size 0.519938 1.4986)
			(layers "F.Cu" "F.Mask" "F.Paste")
			(net "M_C_CPU1_SB_DQS_DP<5>")
		)
		(pad "251" smd rect
			(at 2.050034 31.874968 90)
			(size 0.519938 1.4986)
			(layers "F.Cu" "F.Mask" "F.Paste")
			(net "GND")
		)
		(pad "252" smd rect
			(at 2.050034 32.725106 90)
			(size 0.519938 1.4986)
			(layers "F.Cu" "F.Mask" "F.Paste")
			(net "M_C_CPU1_SB_DQ<6>")
		)
		(pad "253" smd rect
			(at 2.050034 33.57499 90)
			(size 0.519938 1.4986)
			(layers "F.Cu" "F.Mask" "F.Paste")
			(net "GND")
		)
		(pad "254" smd rect
			(at 2.050034 34.425128 90)
			(size 0.519938 1.4986)
			(layers "F.Cu" "F.Mask" "F.Paste")
			(net "M_C_CPU1_SB_DQ<7>")
		)
		(pad "255" smd rect
			(at 2.050034 35.275012 90)
			(size 0.519938 1.4986)
			(layers "F.Cu" "F.Mask" "F.Paste")
			(net "GND")
		)
		(pad "256" smd rect
			(at 2.050034 36.124896 90)
			(size 0.519938 1.4986)
			(layers "F.Cu" "F.Mask" "F.Paste")
			(net "M_C_CPU1_SB_DQ<10>")
		)
		(pad "257" smd rect
			(at 2.050034 36.975034 90)
			(size 0.519938 1.4986)
			(layers "F.Cu" "F.Mask" "F.Paste")
			(net "GND")
		)
		(pad "258" smd rect
			(at 2.050034 37.824918 90)
			(size 0.519938 1.4986)
			(layers "F.Cu" "F.Mask" "F.Paste")
			(net "M_C_CPU1_SB_DQ<11>")
		)
		(pad "259" smd rect
			(at 2.050034 38.675056 90)
			(size 0.519938 1.4986)
			(layers "F.Cu" "F.Mask" "F.Paste")
			(net "GND")
		)
		(pad "260" smd rect
			(at 2.050034 39.52494 90)
			(size 0.519938 1.4986)
			(layers "F.Cu" "F.Mask" "F.Paste")
			(net "M_C_CPU1_SB_DQS_DN<6>")
		)
		(pad "261" smd rect
			(at 2.050034 40.375078 90)
			(size 0.519938 1.4986)
			(layers "F.Cu" "F.Mask" "F.Paste")
			(net "M_C_CPU1_SB_DQS_DP<6>")
		)
		(pad "262" smd rect
			(at 2.050034 41.224962 90)
			(size 0.519938 1.4986)
			(layers "F.Cu" "F.Mask" "F.Paste")
			(net "GND")
		)
		(pad "263" smd rect
			(at 2.050034 42.0751 90)
			(size 0.519938 1.4986)
			(layers "F.Cu" "F.Mask" "F.Paste")
			(net "M_C_CPU1_SB_DQ<14>")
		)
		(pad "264" smd rect
			(at 2.050034 42.924984 90)
			(size 0.519938 1.4986)
			(layers "F.Cu" "F.Mask" "F.Paste")
			(net "GND")
		)
		(pad "265" smd rect
			(at 2.050034 43.775122 90)
			(size 0.519938 1.4986)
			(layers "F.Cu" "F.Mask" "F.Paste")
			(net "M_C_CPU1_SB_DQ<15>")
		)
		(pad "266" smd rect
			(at 2.050034 44.625006 90)
			(size 0.519938 1.4986)
			(layers "F.Cu" "F.Mask" "F.Paste")
			(net "GND")
		)
		(pad "267" smd rect
			(at 2.050034 45.47489 90)
			(size 0.519938 1.4986)
			(layers "F.Cu" "F.Mask" "F.Paste")
			(net "M_C_CPU1_SB_DQ<18>")
		)
		(pad "268" smd rect
			(at 2.050034 46.325028 90)
			(size 0.519938 1.4986)
			(layers "F.Cu" "F.Mask" "F.Paste")
			(net "GND")
		)
		(pad "269" smd rect
			(at 2.050034 47.174912 90)
			(size 0.519938 1.4986)
			(layers "F.Cu" "F.Mask" "F.Paste")
			(net "M_C_CPU1_SB_DQ<19>")
		)
		(pad "270" smd rect
			(at 2.050034 48.02505 90)
			(size 0.519938 1.4986)
			(layers "F.Cu" "F.Mask" "F.Paste")
			(net "GND")
		)
		(pad "271" smd rect
			(at 2.050034 48.874934 90)
			(size 0.519938 1.4986)
			(layers "F.Cu" "F.Mask" "F.Paste")
			(net "M_C_CPU1_SB_DQS_DN<7>")
		)
		(pad "272" smd rect
			(at 2.050034 49.725072 90)
			(size 0.519938 1.4986)
			(layers "F.Cu" "F.Mask" "F.Paste")
			(net "M_C_CPU1_SB_DQS_DP<7>")
		)
		(pad "273" smd rect
			(at 2.050034 50.574956 90)
			(size 0.519938 1.4986)
			(layers "F.Cu" "F.Mask" "F.Paste")
			(net "GND")
		)
		(pad "274" smd rect
			(at 2.050034 51.425094 90)
			(size 0.519938 1.4986)
			(layers "F.Cu" "F.Mask" "F.Paste")
			(net "M_C_CPU1_SB_DQ<22>")
		)
		(pad "275" smd rect
			(at 2.050034 52.274978 90)
			(size 0.519938 1.4986)
			(layers "F.Cu" "F.Mask" "F.Paste")
			(net "GND")
		)
		(pad "276" smd rect
			(at 2.050034 53.125116 90)
			(size 0.519938 1.4986)
			(layers "F.Cu" "F.Mask" "F.Paste")
			(net "M_C_CPU1_SB_DQ<23>")
		)
		(pad "277" smd rect
			(at 2.050034 53.975 90)
			(size 0.519938 1.4986)
			(layers "F.Cu" "F.Mask" "F.Paste")
			(net "GND")
		)
		(pad "278" smd rect
			(at 2.050034 54.824884 90)
			(size 0.519938 1.4986)
			(layers "F.Cu" "F.Mask" "F.Paste")
			(net "M_C_CPU1_SB_DQ<26>")
		)
		(pad "279" smd rect
			(at 2.050034 55.675022 90)
			(size 0.519938 1.4986)
			(layers "F.Cu" "F.Mask" "F.Paste")
			(net "GND")
		)
		(pad "280" smd rect
			(at 2.050034 56.524906 90)
			(size 0.519938 1.4986)
			(layers "F.Cu" "F.Mask" "F.Paste")
			(net "M_C_CPU1_SB_DQ<27>")
		)
		(pad "281" smd rect
			(at 2.050034 57.375044 90)
			(size 0.519938 1.4986)
			(layers "F.Cu" "F.Mask" "F.Paste")
			(net "GND")
		)
		(pad "282" smd rect
			(at 2.050034 58.224928 90)
			(size 0.519938 1.4986)
			(layers "F.Cu" "F.Mask" "F.Paste")
			(net "M_C_CPU1_SB_DQS_DN<8>")
		)
		(pad "283" smd rect
			(at 2.050034 59.075066 90)
			(size 0.519938 1.4986)
			(layers "F.Cu" "F.Mask" "F.Paste")
			(net "M_C_CPU1_SB_DQS_DP<8>")
		)
		(pad "284" smd rect
			(at 2.050034 59.92495 90)
			(size 0.519938 1.4986)
			(layers "F.Cu" "F.Mask" "F.Paste")
			(net "GND")
		)
		(pad "285" smd rect
			(at 2.050034 60.775088 90)
			(size 0.519938 1.4986)
			(layers "F.Cu" "F.Mask" "F.Paste")
			(net "M_C_CPU1_SB_DQ<30>")
		)
		(pad "286" smd rect
			(at 2.050034 61.624972 90)
			(size 0.519938 1.4986)
			(layers "F.Cu" "F.Mask" "F.Paste")
			(net "GND")
		)
		(pad "287" smd rect
			(at 2.050034 62.47511 90)
			(size 0.519938 1.4986)
			(layers "F.Cu" "F.Mask" "F.Paste")
			(net "M_C_CPU1_SB_DQ<31>")
		)
		(pad "288" smd rect
			(at 2.050034 63.324994 90)
			(size 0.519938 1.4986)
			(layers "F.Cu" "F.Mask" "F.Paste")
			(net "GND")
		)
		(pad "G1" thru_hole oval
			(at 0 -68.97497 90)
			(size 1.7272 3.4798)
			(drill oval 1.2192 2.4638)
			(layers "*.Cu" "*.Mask")
			(remove_unused_layers no)
			(net "GND")
			(clearance 0.127)
			(thermal_gap 0.127)
		)
		(pad "G2" thru_hole oval
			(at 0 3.875024 90)
			(size 1.7272 3.4798)
			(drill oval 1.2192 2.4638)
			(layers "*.Cu" "*.Mask")
			(remove_unused_layers no)
			(net "GND")
			(clearance 0.127)
			(thermal_gap 0.127)
		)
		(pad "G3" thru_hole oval
			(at 0 68.97497 90)
			(size 1.7272 3.4798)
			(drill oval 1.2192 2.4638)
			(layers "*.Cu" "*.Mask")
			(remove_unused_layers no)
			(net "GND")
			(clearance 0.127)
			(thermal_gap 0.127)
		)
	)
	(footprint ""
		(layer "F.Cu")
		(at 201.082148 -122.798332)
		(property "Reference" "R3324"
			(at 0 0 0)
			(layer "F.SilkS")
			(hide yes)
			(effects
				(font
					(size 1.27 1.27)
				)
			)
		)
		(property "Value" ""
			(at 0 0 0)
			(layer "F.Fab")
			(effects
				(font
					(size 1.27 1.27)
				)
			)
		)
		(duplicate_pad_numbers_are_jumpers no)
		(fp_line
			(start -0.7874 -0.4064)
			(end 0.7874 -0.4064)
			(stroke
				(width 0.1524)
				(type default)
			)
			(layer "F.SilkS")
		)
		(fp_line
			(start -0.7874 0.4064)
			(end -0.7874 -0.4064)
			(stroke
				(width 0.1524)
				(type default)
			)
			(layer "F.SilkS")
		)
		(fp_line
			(start 0.7874 -0.4064)
			(end 0.7874 0.4064)
			(stroke
				(width 0.1524)
				(type default)
			)
			(layer "F.SilkS")
		)
		(fp_line
			(start 0.7874 0.4064)
			(end -0.7874 0.4064)
			(stroke
				(width 0.1524)
				(type default)
			)
			(layer "F.SilkS")
		)
		(fp_line
			(start -0.67945 -0.305054)
			(end -0.12065 -0.305054)
			(stroke
				(width 0.1)
				(type default)
			)
			(layer "F.Fab")
		)
		(fp_line
			(start -0.67945 0.3048)
			(end -0.67945 -0.305054)
			(stroke
				(width 0.1)
				(type default)
			)
			(layer "F.Fab")
		)
		(fp_line
			(start -0.12065 -0.305054)
			(end -0.12065 -0.2794)
			(stroke
				(width 0.1)
				(type default)
			)
			(layer "F.Fab")
		)
		(fp_line
			(start -0.12065 -0.2794)
			(end 0.12065 -0.2794)
			(stroke
				(width 0.1)
				(type default)
			)
			(layer "F.Fab")
		)
		(fp_line
			(start -0.12065 0.2794)
			(end -0.12065 0.3048)
			(stroke
				(width 0.1)
				(type default)
			)
			(layer "F.Fab")
		)
		(fp_line
			(start -0.12065 0.3048)
			(end -0.67945 0.3048)
			(stroke
				(width 0.1)
				(type default)
			)
			(layer "F.Fab")
		)
		(fp_line
			(start 0.120396 0.2794)
			(end -0.12065 0.2794)
			(stroke
				(width 0.1)
				(type default)
			)
			(layer "F.Fab")
		)
		(fp_line
			(start 0.120396 0.3048)
			(end 0.120396 0.2794)
			(stroke
				(width 0.1)
				(type default)
			)
			(layer "F.Fab")
		)
		(fp_line
			(start 0.12065 -0.3048)
			(end 0.67945 -0.3048)
			(stroke
				(width 0.1)
				(type default)
			)
			(layer "F.Fab")
		)
		(fp_line
			(start 0.12065 -0.2794)
			(end 0.12065 -0.3048)
			(stroke
				(width 0.1)
				(type default)
			)
			(layer "F.Fab")
		)
		(fp_line
			(start 0.67945 -0.3048)
			(end 0.67945 0.3048)
			(stroke
				(width 0.1)
				(type default)
			)
			(layer "F.Fab")
		)
		(fp_line
			(start 0.67945 0.3048)
			(end 0.120396 0.3048)
			(stroke
				(width 0.1)
				(type default)
			)
			(layer "F.Fab")
		)
		(pad "1" smd circle
			(at -0.40005 0)
			(size 0 0)
			(layers "F.Cu" "F.Mask" "F.Paste")
			(net "GPU_FPGA_READY_ISO_R")
		)
		(pad "2" smd circle
			(at 0.40005 0)
			(size 0 0)
			(layers "F.Cu" "F.Mask" "F.Paste")
			(net "GPU_FPGA_READY_ISO")
		)
	)
	(footprint ""
		(layer "F.Cu")
		(at 81.525364 -178.0921 -90)
		(property "Reference" "PR189"
			(at 0 0 270)
			(layer "F.SilkS")
			(hide yes)
			(effects
				(font
					(size 1.27 1.27)
				)
			)
		)
		(property "Value" ""
			(at 0 0 270)
			(layer "F.Fab")
			(effects
				(font
					(size 1.27 1.27)
				)
			)
		)
		(duplicate_pad_numbers_are_jumpers no)
		(fp_line
			(start -0.7874 0.4064)
			(end -0.7874 -0.4064)
			(stroke
				(width 0.1524)
				(type default)
			)
			(layer "F.SilkS")
		)
		(fp_line
			(start 0.7874 0.4064)
			(end -0.7874 0.4064)
			(stroke
				(width 0.1524)
				(type default)
			)
			(layer "F.SilkS")
		)
		(fp_line
			(start -0.7874 -0.4064)
			(end 0.7874 -0.4064)
			(stroke
				(width 0.1524)
				(type default)
			)
			(layer "F.SilkS")
		)
		(fp_line
			(start 0.7874 -0.4064)
			(end 0.7874 0.4064)
			(stroke
				(width 0.1524)
				(type default)
			)
			(layer "F.SilkS")
		)
		(fp_line
			(start -0.67945 0.3048)
			(end -0.67945 -0.305054)
			(stroke
				(width 0.1)
				(type default)
			)
			(layer "F.Fab")
		)
		(fp_line
			(start -0.12065 0.3048)
			(end -0.67945 0.3048)
			(stroke
				(width 0.1)
				(type default)
			)
			(layer "F.Fab")
		)
		(fp_line
			(start 0.120396 0.3048)
			(end 0.120396 0.2794)
			(stroke
				(width 0.1)
				(type default)
			)
			(layer "F.Fab")
		)
		(fp_line
			(start 0.67945 0.3048)
			(end 0.120396 0.3048)
			(stroke
				(width 0.1)
				(type default)
			)
			(layer "F.Fab")
		)
		(fp_line
			(start -0.12065 0.2794)
			(end -0.12065 0.3048)
			(stroke
				(width 0.1)
				(type default)
			)
			(layer "F.Fab")
		)
		(fp_line
			(start 0.120396 0.2794)
			(end -0.12065 0.2794)
			(stroke
				(width 0.1)
				(type default)
			)
			(layer "F.Fab")
		)
		(fp_line
			(start -0.12065 -0.2794)
			(end 0.12065 -0.2794)
			(stroke
				(width 0.1)
				(type default)
			)
			(layer "F.Fab")
		)
		(fp_line
			(start 0.12065 -0.2794)
			(end 0.12065 -0.3048)
			(stroke
				(width 0.1)
				(type default)
			)
			(layer "F.Fab")
		)
		(fp_line
			(start 0.12065 -0.3048)
			(end 0.67945 -0.3048)
			(stroke
				(width 0.1)
				(type default)
			)
			(layer "F.Fab")
		)
		(fp_line
			(start 0.67945 -0.3048)
			(end 0.67945 0.3048)
			(stroke
				(width 0.1)
				(type default)
			)
			(layer "F.Fab")
		)
		(fp_line
			(start -0.67945 -0.305054)
			(end -0.12065 -0.305054)
			(stroke
				(width 0.1)
				(type default)
			)
			(layer "F.Fab")
		)
		(fp_line
			(start -0.12065 -0.305054)
			(end -0.12065 -0.2794)
			(stroke
				(width 0.1)
				(type default)
			)
			(layer "F.Fab")
		)
		(pad "1" smd circle
			(at -0.40005 0 270)
			(size 0 0)
			(layers "F.Cu" "F.Mask" "F.Paste")
			(net "SW_PVDDCR_CPU0_P1_BOOT1")
		)
		(pad "2" smd circle
			(at 0.40005 0 270)
			(size 0 0)
			(layers "F.Cu" "F.Mask" "F.Paste")
			(net "SW_PVDDCR_CPU0_P1_BOOT1_RC")
		)
	)
	(footprint ""
		(layer "F.Cu")
		(at 110.067344 -376.85726 180)
		(property "Reference" "C1544"
			(at 0 0 180)
			(layer "F.SilkS")
			(hide yes)
			(effects
				(font
					(size 1.27 1.27)
				)
			)
		)
		(property "Value" ""
			(at 0 0 180)
			(layer "F.Fab")
			(effects
				(font
					(size 1.27 1.27)
				)
			)
		)
		(duplicate_pad_numbers_are_jumpers no)
		(fp_line
			(start 0.299974 0.150114)
			(end -0.299974 0.150114)
			(stroke
				(width 0.1)
				(type default)
			)
			(layer "F.Fab")
		)
		(fp_line
			(start 0.299974 -0.150114)
			(end 0.299974 0.150114)
			(stroke
				(width 0.1)
				(type default)
			)
			(layer "F.Fab")
		)
		(fp_line
			(start -0.299974 0.150114)
			(end -0.299974 -0.150114)
			(stroke
				(width 0.1)
				(type default)
			)
			(layer "F.Fab")
		)
		(fp_line
			(start -0.299974 -0.150114)
			(end 0.299974 -0.150114)
			(stroke
				(width 0.1)
				(type default)
			)
			(layer "F.Fab")
		)
		(pad "1" smd rect
			(at -0.2667 0 180)
			(size 0.3048 0.381)
			(layers "F.Cu" "F.Mask" "F.Paste")
			(net "P5E_CPU1_P3_TX_C_DN<1>")
		)
		(pad "2" smd rect
			(at 0.2667 0 180)
			(size 0.3048 0.381)
			(layers "F.Cu" "F.Mask" "F.Paste")
			(net "P5E_CPU1_P3_TX_DN<1>")
		)
	)
	(footprint ""
		(layer "F.Cu")
		(at 215.4301 -407.068782 180)
		(property "Reference" "PR3912"
			(at 0 0 180)
			(layer "F.SilkS")
			(hide yes)
			(effects
				(font
					(size 1.27 1.27)
				)
			)
		)
		(property "Value" ""
			(at 0 0 180)
			(layer "F.Fab")
			(effects
				(font
					(size 1.27 1.27)
				)
			)
		)
		(duplicate_pad_numbers_are_jumpers no)
		(fp_line
			(start 0.7874 0.4064)
			(end -0.7874 0.4064)
			(stroke
				(width 0.1524)
				(type default)
			)
			(layer "F.SilkS")
		)
		(fp_line
			(start 0.7874 -0.4064)
			(end 0.7874 0.4064)
			(stroke
				(width 0.1524)
				(type default)
			)
			(layer "F.SilkS")
		)
		(fp_line
			(start -0.7874 0.4064)
			(end -0.7874 -0.4064)
			(stroke
				(width 0.1524)
				(type default)
			)
			(layer "F.SilkS")
		)
		(fp_line
			(start -0.7874 -0.4064)
			(end 0.7874 -0.4064)
			(stroke
				(width 0.1524)
				(type default)
			)
			(layer "F.SilkS")
		)
		(fp_line
			(start 0.67945 0.3048)
			(end 0.120396 0.3048)
			(stroke
				(width 0.1)
				(type default)
			)
			(layer "F.Fab")
		)
		(fp_line
			(start 0.67945 -0.3048)
			(end 0.67945 0.3048)
			(stroke
				(width 0.1)
				(type default)
			)
			(layer "F.Fab")
		)
		(fp_line
			(start 0.12065 -0.2794)
			(end 0.12065 -0.3048)
			(stroke
				(width 0.1)
				(type default)
			)
			(layer "F.Fab")
		)
		(fp_line
			(start 0.12065 -0.3048)
			(end 0.67945 -0.3048)
			(stroke
				(width 0.1)
				(type default)
			)
			(layer "F.Fab")
		)
		(fp_line
			(start 0.120396 0.3048)
			(end 0.120396 0.2794)
			(stroke
				(width 0.1)
				(type default)
			)
			(layer "F.Fab")
		)
		(fp_line
			(start 0.120396 0.2794)
			(end -0.12065 0.2794)
			(stroke
				(width 0.1)
				(type default)
			)
			(layer "F.Fab")
		)
		(fp_line
			(start -0.12065 0.3048)
			(end -0.67945 0.3048)
			(stroke
				(width 0.1)
				(type default)
			)
			(layer "F.Fab")
		)
		(fp_line
			(start -0.12065 0.2794)
			(end -0.12065 0.3048)
			(stroke
				(width 0.1)
				(type default)
			)
			(layer "F.Fab")
		)
		(fp_line
			(start -0.12065 -0.2794)
			(end 0.12065 -0.2794)
			(stroke
				(width 0.1)
				(type default)
			)
			(layer "F.Fab")
		)
		(fp_line
			(start -0.12065 -0.305054)
			(end -0.12065 -0.2794)
			(stroke
				(width 0.1)
				(type default)
			)
			(layer "F.Fab")
		)
		(fp_line
			(start -0.67945 0.3048)
			(end -0.67945 -0.305054)
			(stroke
				(width 0.1)
				(type default)
			)
			(layer "F.Fab")
		)
		(fp_line
			(start -0.67945 -0.305054)
			(end -0.12065 -0.305054)
			(stroke
				(width 0.1)
				(type default)
			)
			(layer "F.Fab")
		)
		(pad "1" smd circle
			(at -0.40005 0 180)
			(size 0 0)
			(layers "F.Cu" "F.Mask" "F.Paste")
			(net "AGND_HSC")
		)
		(pad "2" smd circle
			(at 0.40005 0 180)
			(size 0 0)
			(layers "F.Cu" "F.Mask" "F.Paste")
			(net "HSC_MODE_2")
		)
	)
	(footprint ""
		(layer "F.Cu")
		(at 297.486324 -112.354614 180)
		(property "Reference" "R2985"
			(at 0 0 180)
			(layer "F.SilkS")
			(hide yes)
			(effects
				(font
					(size 1.27 1.27)
				)
			)
		)
		(property "Value" ""
			(at 0 0 180)
			(layer "F.Fab")
			(effects
				(font
					(size 1.27 1.27)
				)
			)
		)
		(duplicate_pad_numbers_are_jumpers no)
		(fp_line
			(start 0.7874 0.4064)
			(end -0.7874 0.4064)
			(stroke
				(width 0.1524)
				(type default)
			)
			(layer "F.SilkS")
		)
		(fp_line
			(start 0.7874 -0.4064)
			(end 0.7874 0.4064)
			(stroke
				(width 0.1524)
				(type default)
			)
			(layer "F.SilkS")
		)
		(fp_line
			(start -0.7874 0.4064)
			(end -0.7874 -0.4064)
			(stroke
				(width 0.1524)
				(type default)
			)
			(layer "F.SilkS")
		)
		(fp_line
			(start -0.7874 -0.4064)
			(end 0.7874 -0.4064)
			(stroke
				(width 0.1524)
				(type default)
			)
			(layer "F.SilkS")
		)
		(fp_line
			(start 0.67945 0.3048)
			(end 0.120396 0.3048)
			(stroke
				(width 0.1)
				(type default)
			)
			(layer "F.Fab")
		)
		(fp_line
			(start 0.67945 -0.3048)
			(end 0.67945 0.3048)
			(stroke
				(width 0.1)
				(type default)
			)
			(layer "F.Fab")
		)
		(fp_line
			(start 0.12065 -0.2794)
			(end 0.12065 -0.3048)
			(stroke
				(width 0.1)
				(type default)
			)
			(layer "F.Fab")
		)
		(fp_line
			(start 0.12065 -0.3048)
			(end 0.67945 -0.3048)
			(stroke
				(width 0.1)
				(type default)
			)
			(layer "F.Fab")
		)
		(fp_line
			(start 0.120396 0.3048)
			(end 0.120396 0.2794)
			(stroke
				(width 0.1)
				(type default)
			)
			(layer "F.Fab")
		)
		(fp_line
			(start 0.120396 0.2794)
			(end -0.12065 0.2794)
			(stroke
				(width 0.1)
				(type default)
			)
			(layer "F.Fab")
		)
		(fp_line
			(start -0.12065 0.3048)
			(end -0.67945 0.3048)
			(stroke
				(width 0.1)
				(type default)
			)
			(layer "F.Fab")
		)
		(fp_line
			(start -0.12065 0.2794)
			(end -0.12065 0.3048)
			(stroke
				(width 0.1)
				(type default)
			)
			(layer "F.Fab")
		)
		(fp_line
			(start -0.12065 -0.2794)
			(end 0.12065 -0.2794)
			(stroke
				(width 0.1)
				(type default)
			)
			(layer "F.Fab")
		)
		(fp_line
			(start -0.12065 -0.305054)
			(end -0.12065 -0.2794)
			(stroke
				(width 0.1)
				(type default)
			)
			(layer "F.Fab")
		)
		(fp_line
			(start -0.67945 0.3048)
			(end -0.67945 -0.305054)
			(stroke
				(width 0.1)
				(type default)
			)
			(layer "F.Fab")
		)
		(fp_line
			(start -0.67945 -0.305054)
			(end -0.12065 -0.305054)
			(stroke
				(width 0.1)
				(type default)
			)
			(layer "F.Fab")
		)
		(pad "1" smd circle
			(at -0.40005 0 180)
			(size 0 0)
			(layers "F.Cu" "F.Mask" "F.Paste")
			(net "P3V3_AUX")
		)
		(pad "2" smd circle
			(at 0.40005 0 180)
			(size 0 0)
			(layers "F.Cu" "F.Mask" "F.Paste")
			(net "SMB_BMC_SWB_SDA")
		)
	)
	(footprint ""
		(layer "F.Cu")
		(at 16.162782 -404.341584 90)
		(property "Reference" "R657"
			(at 0 0 90)
			(layer "F.SilkS")
			(hide yes)
			(effects
				(font
					(size 1.27 1.27)
				)
			)
		)
		(property "Value" ""
			(at 0 0 90)
			(layer "F.Fab")
			(effects
				(font
					(size 1.27 1.27)
				)
			)
		)
		(duplicate_pad_numbers_are_jumpers no)
		(fp_line
			(start 0.7874 -0.4064)
			(end 0.7874 0.4064)
			(stroke
				(width 0.1524)
				(type default)
			)
			(layer "F.SilkS")
		)
		(fp_line
			(start -0.7874 -0.4064)
			(end 0.7874 -0.4064)
			(stroke
				(width 0.1524)
				(type default)
			)
			(layer "F.SilkS")
		)
		(fp_line
			(start 0.7874 0.4064)
			(end -0.7874 0.4064)
			(stroke
				(width 0.1524)
				(type default)
			)
			(layer "F.SilkS")
		)
		(fp_line
			(start -0.7874 0.4064)
			(end -0.7874 -0.4064)
			(stroke
				(width 0.1524)
				(type default)
			)
			(layer "F.SilkS")
		)
		(fp_line
			(start -0.12065 -0.305054)
			(end -0.12065 -0.2794)
			(stroke
				(width 0.1)
				(type default)
			)
			(layer "F.Fab")
		)
		(fp_line
			(start -0.67945 -0.305054)
			(end -0.12065 -0.305054)
			(stroke
				(width 0.1)
				(type default)
			)
			(layer "F.Fab")
		)
		(fp_line
			(start 0.67945 -0.3048)
			(end 0.67945 0.3048)
			(stroke
				(width 0.1)
				(type default)
			)
			(layer "F.Fab")
		)
		(fp_line
			(start 0.12065 -0.3048)
			(end 0.67945 -0.3048)
			(stroke
				(width 0.1)
				(type default)
			)
			(layer "F.Fab")
		)
		(fp_line
			(start 0.12065 -0.2794)
			(end 0.12065 -0.3048)
			(stroke
				(width 0.1)
				(type default)
			)
			(layer "F.Fab")
		)
		(fp_line
			(start -0.12065 -0.2794)
			(end 0.12065 -0.2794)
			(stroke
				(width 0.1)
				(type default)
			)
			(layer "F.Fab")
		)
		(fp_line
			(start 0.120396 0.2794)
			(end -0.12065 0.2794)
			(stroke
				(width 0.1)
				(type default)
			)
			(layer "F.Fab")
		)
		(fp_line
			(start -0.12065 0.2794)
			(end -0.12065 0.3048)
			(stroke
				(width 0.1)
				(type default)
			)
			(layer "F.Fab")
		)
		(fp_line
			(start 0.67945 0.3048)
			(end 0.120396 0.3048)
			(stroke
				(width 0.1)
				(type default)
			)
			(layer "F.Fab")
		)
		(fp_line
			(start 0.120396 0.3048)
			(end 0.120396 0.2794)
			(stroke
				(width 0.1)
				(type default)
			)
			(layer "F.Fab")
		)
		(fp_line
			(start -0.12065 0.3048)
			(end -0.67945 0.3048)
			(stroke
				(width 0.1)
				(type default)
			)
			(layer "F.Fab")
		)
		(fp_line
			(start -0.67945 0.3048)
			(end -0.67945 -0.305054)
			(stroke
				(width 0.1)
				(type default)
			)
			(layer "F.Fab")
		)
		(pad "1" smd circle
			(at -0.40005 0 90)
			(size 0 0)
			(layers "F.Cu" "F.Mask" "F.Paste")
			(net "P0V9_RETIMER_CPU1_PMSCL")
		)
		(pad "2" smd circle
			(at 0.40005 0 90)
			(size 0 0)
			(layers "F.Cu" "F.Mask" "F.Paste")
			(net "P0V9_RETIMER_CPU1_PMSCL_R")
		)
	)
	(footprint ""
		(layer "F.Cu")
		(at 350.237044 -383.88163 -90)
		(property "Reference" "C945"
			(at 0 0 270)
			(layer "F.SilkS")
			(hide yes)
			(effects
				(font
					(size 1.27 1.27)
				)
			)
		)
		(property "Value" ""
			(at 0 0 270)
			(layer "F.Fab")
			(effects
				(font
					(size 1.27 1.27)
				)
			)
		)
		(duplicate_pad_numbers_are_jumpers no)
		(fp_line
			(start -0.299974 0.150114)
			(end -0.299974 -0.150114)
			(stroke
				(width 0.1)
				(type default)
			)
			(layer "F.Fab")
		)
		(fp_line
			(start 0.299974 0.150114)
			(end -0.299974 0.150114)
			(stroke
				(width 0.1)
				(type default)
			)
			(layer "F.Fab")
		)
		(fp_line
			(start -0.299974 -0.150114)
			(end 0.299974 -0.150114)
			(stroke
				(width 0.1)
				(type default)
			)
			(layer "F.Fab")
		)
		(fp_line
			(start 0.299974 -0.150114)
			(end 0.299974 0.150114)
			(stroke
				(width 0.1)
				(type default)
			)
			(layer "F.Fab")
		)
		(pad "1" smd rect
			(at -0.2667 0 270)
			(size 0.3048 0.381)
			(layers "F.Cu" "F.Mask" "F.Paste")
			(net "P5E_CPU0_P1_TX_C_DP<10>")
		)
		(pad "2" smd rect
			(at 0.2667 0 270)
			(size 0.3048 0.381)
			(layers "F.Cu" "F.Mask" "F.Paste")
			(net "P5E_CPU0_P1_TX_DP<10>")
		)
	)
	(footprint ""
		(layer "F.Cu")
		(at 98.380296 -425.82973 -90)
		(property "Reference" "R4202"
			(at 0 0 270)
			(layer "F.SilkS")
			(hide yes)
			(effects
				(font
					(size 1.27 1.27)
				)
			)
		)
		(property "Value" ""
			(at 0 0 270)
			(layer "F.Fab")
			(effects
				(font
					(size 1.27 1.27)
				)
			)
		)
		(duplicate_pad_numbers_are_jumpers no)
		(fp_line
			(start -0.7874 0.4064)
			(end -0.7874 -0.4064)
			(stroke
				(width 0.1524)
				(type default)
			)
			(layer "F.SilkS")
		)
		(fp_line
			(start 0.7874 0.4064)
			(end -0.7874 0.4064)
			(stroke
				(width 0.1524)
				(type default)
			)
			(layer "F.SilkS")
		)
		(fp_line
			(start -0.7874 -0.4064)
			(end 0.7874 -0.4064)
			(stroke
				(width 0.1524)
				(type default)
			)
			(layer "F.SilkS")
		)
		(fp_line
			(start 0.7874 -0.4064)
			(end 0.7874 0.4064)
			(stroke
				(width 0.1524)
				(type default)
			)
			(layer "F.SilkS")
		)
		(fp_line
			(start -0.67945 0.3048)
			(end -0.67945 -0.305054)
			(stroke
				(width 0.1)
				(type default)
			)
			(layer "F.Fab")
		)
		(fp_line
			(start -0.12065 0.3048)
			(end -0.67945 0.3048)
			(stroke
				(width 0.1)
				(type default)
			)
			(layer "F.Fab")
		)
		(fp_line
			(start 0.120396 0.3048)
			(end 0.120396 0.2794)
			(stroke
				(width 0.1)
				(type default)
			)
			(layer "F.Fab")
		)
		(fp_line
			(start 0.67945 0.3048)
			(end 0.120396 0.3048)
			(stroke
				(width 0.1)
				(type default)
			)
			(layer "F.Fab")
		)
		(fp_line
			(start -0.12065 0.2794)
			(end -0.12065 0.3048)
			(stroke
				(width 0.1)
				(type default)
			)
			(layer "F.Fab")
		)
		(fp_line
			(start 0.120396 0.2794)
			(end -0.12065 0.2794)
			(stroke
				(width 0.1)
				(type default)
			)
			(layer "F.Fab")
		)
		(fp_line
			(start -0.12065 -0.2794)
			(end 0.12065 -0.2794)
			(stroke
				(width 0.1)
				(type default)
			)
			(layer "F.Fab")
		)
		(fp_line
			(start 0.12065 -0.2794)
			(end 0.12065 -0.3048)
			(stroke
				(width 0.1)
				(type default)
			)
			(layer "F.Fab")
		)
		(fp_line
			(start 0.12065 -0.3048)
			(end 0.67945 -0.3048)
			(stroke
				(width 0.1)
				(type default)
			)
			(layer "F.Fab")
		)
		(fp_line
			(start 0.67945 -0.3048)
			(end 0.67945 0.3048)
			(stroke
				(width 0.1)
				(type default)
			)
			(layer "F.Fab")
		)
		(fp_line
			(start -0.67945 -0.305054)
			(end -0.12065 -0.305054)
			(stroke
				(width 0.1)
				(type default)
			)
			(layer "F.Fab")
		)
		(fp_line
			(start -0.12065 -0.305054)
			(end -0.12065 -0.2794)
			(stroke
				(width 0.1)
				(type default)
			)
			(layer "F.Fab")
		)
		(pad "1" smd circle
			(at -0.40005 0 270)
			(size 0 0)
			(layers "F.Cu" "F.Mask" "F.Paste")
			(net "P3V3_AUX")
		)
		(pad "2" smd circle
			(at 0.40005 0 270)
			(size 0 0)
			(layers "F.Cu" "F.Mask" "F.Paste")
			(net "U272_2_ADD0")
		)
	)
	(footprint ""
		(layer "F.Cu")
		(at 182.919878 -342.462358 -90)
		(property "Reference" "PL54"
			(at -15.116048 5.983986 0)
			(unlocked yes)
			(layer "F.SilkS")
			(effects
				(font
					(size 0.7874 0.5842)
					(thickness 0.1524)
				)
				(justify left)
			)
		)
		(property "Value" ""
			(at 0 0 270)
			(layer "F.Fab")
			(effects
				(font
					(size 1.27 1.27)
				)
			)
		)
		(duplicate_pad_numbers_are_jumpers no)
		(fp_line
			(start -4.99999 3.849878)
			(end -4.99999 2.23901)
			(stroke
				(width 0.1524)
				(type default)
			)
			(layer "F.SilkS")
		)
		(fp_line
			(start 4.99999 3.849878)
			(end -4.99999 3.849878)
			(stroke
				(width 0.1524)
				(type default)
			)
			(layer "F.SilkS")
		)
		(fp_line
			(start 4.99999 2.23901)
			(end 4.99999 3.849878)
			(stroke
				(width 0.1524)
				(type default)
			)
			(layer "F.SilkS")
		)
		(fp_line
			(start -4.99999 -2.23901)
			(end -4.99999 -3.849878)
			(stroke
				(width 0.1524)
				(type default)
			)
			(layer "F.SilkS")
		)
		(fp_line
			(start -4.99999 -3.849878)
			(end 4.99999 -3.849878)
			(stroke
				(width 0.1524)
				(type default)
			)
			(layer "F.SilkS")
		)
		(fp_line
			(start 4.99999 -3.849878)
			(end 4.99999 -2.23901)
			(stroke
				(width 0.1524)
				(type default)
			)
			(layer "F.SilkS")
		)
		(fp_line
			(start -4.99999 3.849878)
			(end -4.99999 -3.849878)
			(stroke
				(width 0.1)
				(type default)
			)
			(layer "F.Fab")
		)
		(fp_line
			(start 4.99999 3.849878)
			(end -4.99999 3.849878)
			(stroke
				(width 0.1)
				(type default)
			)
			(layer "F.Fab")
		)
		(fp_line
			(start -4.99999 -3.849878)
			(end 4.99999 -3.849878)
			(stroke
				(width 0.1)
				(type default)
			)
			(layer "F.Fab")
		)
		(fp_line
			(start 4.99999 -3.849878)
			(end 4.99999 3.849878)
			(stroke
				(width 0.1)
				(type default)
			)
			(layer "F.Fab")
		)
		(pad "1" smd rect
			(at -3.299968 0 270)
			(size 3.302 4.2164)
			(layers "F.Cu" "F.Mask" "F.Paste")
			(net "SW_PVDD11_S3_P1_SW1")
		)
		(pad "2" smd rect
			(at 3.299968 0 270)
			(size 3.302 4.2164)
			(layers "F.Cu" "F.Mask" "F.Paste")
			(net "PVDD11_S3_P1")
		)
	)
	(footprint ""
		(layer "F.Cu")
		(at 142.595092 -375.94286 180)
		(property "Reference" "C771"
			(at 0 0 180)
			(layer "F.SilkS")
			(hide yes)
			(effects
				(font
					(size 1.27 1.27)
				)
			)
		)
		(property "Value" ""
			(at 0 0 180)
			(layer "F.Fab")
			(effects
				(font
					(size 1.27 1.27)
				)
			)
		)
		(duplicate_pad_numbers_are_jumpers no)
		(fp_line
			(start 0.299974 0.150114)
			(end -0.299974 0.150114)
			(stroke
				(width 0.1)
				(type default)
			)
			(layer "F.Fab")
		)
		(fp_line
			(start 0.299974 -0.150114)
			(end 0.299974 0.150114)
			(stroke
				(width 0.1)
				(type default)
			)
			(layer "F.Fab")
		)
		(fp_line
			(start -0.299974 0.150114)
			(end -0.299974 -0.150114)
			(stroke
				(width 0.1)
				(type default)
			)
			(layer "F.Fab")
		)
		(fp_line
			(start -0.299974 -0.150114)
			(end 0.299974 -0.150114)
			(stroke
				(width 0.1)
				(type default)
			)
			(layer "F.Fab")
		)
		(pad "1" smd rect
			(at -0.2667 0 180)
			(size 0.3048 0.381)
			(layers "F.Cu" "F.Mask" "F.Paste")
			(net "P5E_CPU1_P2_TX_C_DP<1>")
		)
		(pad "2" smd rect
			(at 0.2667 0 180)
			(size 0.3048 0.381)
			(layers "F.Cu" "F.Mask" "F.Paste")
			(net "P5E_CPU1_P2_TX_DP<1>")
		)
	)
	(footprint ""
		(layer "F.Cu")
		(at 455.617834 -99.164394)
		(property "Reference" "R1719"
			(at 0 0 0)
			(layer "F.SilkS")
			(hide yes)
			(effects
				(font
					(size 1.27 1.27)
				)
			)
		)
		(property "Value" ""
			(at 0 0 0)
			(layer "F.Fab")
			(effects
				(font
					(size 1.27 1.27)
				)
			)
		)
		(duplicate_pad_numbers_are_jumpers no)
		(fp_line
			(start -0.7874 -0.4064)
			(end 0.7874 -0.4064)
			(stroke
				(width 0.1524)
				(type default)
			)
			(layer "F.SilkS")
		)
		(fp_line
			(start -0.7874 0.4064)
			(end -0.7874 -0.4064)
			(stroke
				(width 0.1524)
				(type default)
			)
			(layer "F.SilkS")
		)
		(fp_line
			(start 0.7874 -0.4064)
			(end 0.7874 0.4064)
			(stroke
				(width 0.1524)
				(type default)
			)
			(layer "F.SilkS")
		)
		(fp_line
			(start 0.7874 0.4064)
			(end -0.7874 0.4064)
			(stroke
				(width 0.1524)
				(type default)
			)
			(layer "F.SilkS")
		)
		(fp_line
			(start -0.67945 -0.305054)
			(end -0.12065 -0.305054)
			(stroke
				(width 0.1)
				(type default)
			)
			(layer "F.Fab")
		)
		(fp_line
			(start -0.67945 0.3048)
			(end -0.67945 -0.305054)
			(stroke
				(width 0.1)
				(type default)
			)
			(layer "F.Fab")
		)
		(fp_line
			(start -0.12065 -0.305054)
			(end -0.12065 -0.2794)
			(stroke
				(width 0.1)
				(type default)
			)
			(layer "F.Fab")
		)
		(fp_line
			(start -0.12065 -0.2794)
			(end 0.12065 -0.2794)
			(stroke
				(width 0.1)
				(type default)
			)
			(layer "F.Fab")
		)
		(fp_line
			(start -0.12065 0.2794)
			(end -0.12065 0.3048)
			(stroke
				(width 0.1)
				(type default)
			)
			(layer "F.Fab")
		)
		(fp_line
			(start -0.12065 0.3048)
			(end -0.67945 0.3048)
			(stroke
				(width 0.1)
				(type default)
			)
			(layer "F.Fab")
		)
		(fp_line
			(start 0.120396 0.2794)
			(end -0.12065 0.2794)
			(stroke
				(width 0.1)
				(type default)
			)
			(layer "F.Fab")
		)
		(fp_line
			(start 0.120396 0.3048)
			(end 0.120396 0.2794)
			(stroke
				(width 0.1)
				(type default)
			)
			(layer "F.Fab")
		)
		(fp_line
			(start 0.12065 -0.3048)
			(end 0.67945 -0.3048)
			(stroke
				(width 0.1)
				(type default)
			)
			(layer "F.Fab")
		)
		(fp_line
			(start 0.12065 -0.2794)
			(end 0.12065 -0.3048)
			(stroke
				(width 0.1)
				(type default)
			)
			(layer "F.Fab")
		)
		(fp_line
			(start 0.67945 -0.3048)
			(end 0.67945 0.3048)
			(stroke
				(width 0.1)
				(type default)
			)
			(layer "F.Fab")
		)
		(fp_line
			(start 0.67945 0.3048)
			(end 0.120396 0.3048)
			(stroke
				(width 0.1)
				(type default)
			)
			(layer "F.Fab")
		)
		(pad "1" smd circle
			(at -0.40005 0)
			(size 0 0)
			(layers "F.Cu" "F.Mask" "F.Paste")
			(net "OCP_SFF_AUX_PWR_EN")
		)
		(pad "2" smd circle
			(at 0.40005 0)
			(size 0 0)
			(layers "F.Cu" "F.Mask" "F.Paste")
			(net "OCP_SFF_AUX_PWR_EN_R1")
		)
	)
	(footprint ""
		(layer "F.Cu")
		(at 98.956114 -192.010284 180)
		(property "Reference" "PL31"
			(at -7.476744 3.583686 90)
			(unlocked yes)
			(layer "F.SilkS")
			(effects
				(font
					(size 0.7874 0.5842)
					(thickness 0.1524)
				)
				(justify left)
			)
		)
		(property "Value" ""
			(at 0 0 180)
			(layer "F.Fab")
			(effects
				(font
					(size 1.27 1.27)
				)
			)
		)
		(duplicate_pad_numbers_are_jumpers no)
		(fp_line
			(start 3.750056 5.500116)
			(end 3.750056 -5.500116)
			(stroke
				(width 0.1524)
				(type default)
			)
			(layer "F.SilkS")
		)
		(fp_line
			(start 3.750056 -5.500116)
			(end 2.393442 -5.500116)
			(stroke
				(width 0.1524)
				(type default)
			)
			(layer "F.SilkS")
		)
		(fp_line
			(start 2.393442 5.500116)
			(end 3.750056 5.500116)
			(stroke
				(width 0.1524)
				(type default)
			)
			(layer "F.SilkS")
		)
		(fp_line
			(start -2.393442 5.500116)
			(end -3.750056 5.500116)
			(stroke
				(width 0.1524)
				(type default)
			)
			(layer "F.SilkS")
		)
		(fp_line
			(start -3.750056 5.500116)
			(end -3.750056 -5.500116)
			(stroke
				(width 0.1524)
				(type default)
			)
			(layer "F.SilkS")
		)
		(fp_line
			(start -3.750056 -5.500116)
			(end -2.393442 -5.500116)
			(stroke
				(width 0.1524)
				(type default)
			)
			(layer "F.SilkS")
		)
		(fp_poly
			(pts
				(xy -3.9116 -4.249928) (xy -4.9276 -3.741928) (xy -4.9276 -4.757928)
			)
			(stroke
				(width 0)
				(type default)
			)
			(fill yes)
			(layer "F.SilkS")
		)
		(fp_line
			(start 3.750056 5.500116)
			(end 3.750056 -5.500116)
			(stroke
				(width 0.1)
				(type default)
			)
			(layer "F.Fab")
		)
		(fp_line
			(start 3.750056 -5.500116)
			(end -3.750056 -5.500116)
			(stroke
				(width 0.1)
				(type default)
			)
			(layer "F.Fab")
		)
		(fp_line
			(start -3.750056 5.500116)
			(end 3.750056 5.500116)
			(stroke
				(width 0.1)
				(type default)
			)
			(layer "F.Fab")
		)
		(fp_line
			(start -3.750056 -5.500116)
			(end -3.750056 5.500116)
			(stroke
				(width 0.1)
				(type default)
			)
			(layer "F.Fab")
		)
		(fp_poly
			(pts
				(xy -4.9276 -4.757928) (xy -4.9276 -3.741928) (xy -3.9116 -4.249928)
			)
			(stroke
				(width 0)
				(type default)
			)
			(fill yes)
			(layer "F.Fab")
		)
		(pad "1" smd rect
			(at 0 -4.249928 90)
			(size 2.413 4.5212)
			(layers "F.Cu" "F.Mask" "F.Paste")
			(net "SW_PVDDCR_CPU0_P1_SW3")
		)
		(pad "2" smd rect
			(at 0 -1.175004 90)
			(size 1.3716 4.5212)
			(layers "F.Cu" "F.Mask" "F.Paste")
			(net "IND_CPU0_P1_CPL2")
		)
		(pad "3" smd rect
			(at 0 1.175004 90)
			(size 1.3716 4.5212)
			(layers "F.Cu" "F.Mask" "F.Paste")
			(net "IND_CPU0_P1_CPL3")
		)
		(pad "4" smd rect
			(at 0 4.249928 90)
			(size 2.413 4.5212)
			(layers "F.Cu" "F.Mask" "F.Paste")
			(net "PVDDCR_CPU0_P1")
		)
	)
	(footprint ""
		(layer "F.Cu")
		(at 436.052722 -408.01036)
		(property "Reference" "R1400"
			(at 0 0 0)
			(layer "F.SilkS")
			(hide yes)
			(effects
				(font
					(size 1.27 1.27)
				)
			)
		)
		(property "Value" ""
			(at 0 0 0)
			(layer "F.Fab")
			(effects
				(font
					(size 1.27 1.27)
				)
			)
		)
		(duplicate_pad_numbers_are_jumpers no)
		(fp_line
			(start -0.32512 -0.175006)
			(end 0.32512 -0.175006)
			(stroke
				(width 0.1)
				(type default)
			)
			(layer "F.Fab")
		)
		(fp_line
			(start -0.32512 0.175006)
			(end -0.32512 -0.175006)
			(stroke
				(width 0.1)
				(type default)
			)
			(layer "F.Fab")
		)
		(fp_line
			(start 0.32512 -0.175006)
			(end 0.32512 0.175006)
			(stroke
				(width 0.1)
				(type default)
			)
			(layer "F.Fab")
		)
		(fp_line
			(start 0.32512 0.175006)
			(end -0.32512 0.175006)
			(stroke
				(width 0.1)
				(type default)
			)
			(layer "F.Fab")
		)
		(pad "1" smd rect
			(at -0.2667 0)
			(size 0.3048 0.381)
			(layers "F.Cu" "F.Mask" "F.Paste")
			(net "JTAG_TRST_RT_CPU0_P2_N")
		)
		(pad "2" smd rect
			(at 0.2667 0 180)
			(size 0.3048 0.381)
			(layers "F.Cu" "F.Mask" "F.Paste")
			(net "GND")
		)
	)
	(footprint ""
		(layer "F.Cu")
		(at 11.421618 -105.48239 90)
		(property "Reference" "R2786"
			(at 0 0 90)
			(layer "F.SilkS")
			(hide yes)
			(effects
				(font
					(size 1.27 1.27)
				)
			)
		)
		(property "Value" ""
			(at 0 0 90)
			(layer "F.Fab")
			(effects
				(font
					(size 1.27 1.27)
				)
			)
		)
		(duplicate_pad_numbers_are_jumpers no)
		(fp_line
			(start 0.7874 -0.4064)
			(end 0.7874 0.4064)
			(stroke
				(width 0.1524)
				(type default)
			)
			(layer "F.SilkS")
		)
		(fp_line
			(start -0.7874 -0.4064)
			(end 0.7874 -0.4064)
			(stroke
				(width 0.1524)
				(type default)
			)
			(layer "F.SilkS")
		)
		(fp_line
			(start 0.7874 0.4064)
			(end -0.7874 0.4064)
			(stroke
				(width 0.1524)
				(type default)
			)
			(layer "F.SilkS")
		)
		(fp_line
			(start -0.7874 0.4064)
			(end -0.7874 -0.4064)
			(stroke
				(width 0.1524)
				(type default)
			)
			(layer "F.SilkS")
		)
		(fp_line
			(start -0.12065 -0.305054)
			(end -0.12065 -0.2794)
			(stroke
				(width 0.1)
				(type default)
			)
			(layer "F.Fab")
		)
		(fp_line
			(start -0.67945 -0.305054)
			(end -0.12065 -0.305054)
			(stroke
				(width 0.1)
				(type default)
			)
			(layer "F.Fab")
		)
		(fp_line
			(start 0.67945 -0.3048)
			(end 0.67945 0.3048)
			(stroke
				(width 0.1)
				(type default)
			)
			(layer "F.Fab")
		)
		(fp_line
			(start 0.12065 -0.3048)
			(end 0.67945 -0.3048)
			(stroke
				(width 0.1)
				(type default)
			)
			(layer "F.Fab")
		)
		(fp_line
			(start 0.12065 -0.2794)
			(end 0.12065 -0.3048)
			(stroke
				(width 0.1)
				(type default)
			)
			(layer "F.Fab")
		)
		(fp_line
			(start -0.12065 -0.2794)
			(end 0.12065 -0.2794)
			(stroke
				(width 0.1)
				(type default)
			)
			(layer "F.Fab")
		)
		(fp_line
			(start 0.120396 0.2794)
			(end -0.12065 0.2794)
			(stroke
				(width 0.1)
				(type default)
			)
			(layer "F.Fab")
		)
		(fp_line
			(start -0.12065 0.2794)
			(end -0.12065 0.3048)
			(stroke
				(width 0.1)
				(type default)
			)
			(layer "F.Fab")
		)
		(fp_line
			(start 0.67945 0.3048)
			(end 0.120396 0.3048)
			(stroke
				(width 0.1)
				(type default)
			)
			(layer "F.Fab")
		)
		(fp_line
			(start 0.120396 0.3048)
			(end 0.120396 0.2794)
			(stroke
				(width 0.1)
				(type default)
			)
			(layer "F.Fab")
		)
		(fp_line
			(start -0.12065 0.3048)
			(end -0.67945 0.3048)
			(stroke
				(width 0.1)
				(type default)
			)
			(layer "F.Fab")
		)
		(fp_line
			(start -0.67945 0.3048)
			(end -0.67945 -0.305054)
			(stroke
				(width 0.1)
				(type default)
			)
			(layer "F.Fab")
		)
		(pad "1" smd rect
			(at -0.40005 0 270)
			(size 0.4572 0.508)
			(layers "F.Cu" "F.Mask" "F.Paste")
			(net "USB2_HUB_SWB_DP")
		)
		(pad "2" smd rect
			(at 0.40005 0 270)
			(size 0.4572 0.508)
			(layers "F.Cu" "F.Mask" "F.Paste")
			(net "USB2_HUB_BUF_SWB_R_DP")
		)
	)
	(footprint ""
		(layer "F.Cu")
		(at 116.332 -125.349)
		(property "Reference" "U6006"
			(at -1.979676 -2.710942 0)
			(unlocked yes)
			(layer "F.SilkS")
			(effects
				(font
					(size 0.7874 0.5842)
					(thickness 0.1524)
				)
				(justify left)
			)
		)
		(property "Value" ""
			(at 0 0 0)
			(layer "F.Fab")
			(effects
				(font
					(size 1.27 1.27)
				)
			)
		)
		(duplicate_pad_numbers_are_jumpers no)
		(fp_line
			(start -1.759712 -1.500124)
			(end 1.759712 -1.500124)
			(stroke
				(width 0.1524)
				(type default)
			)
			(layer "F.SilkS")
		)
		(fp_line
			(start -1.759712 1.500124)
			(end -1.759712 -1.500124)
			(stroke
				(width 0.1524)
				(type default)
			)
			(layer "F.SilkS")
		)
		(fp_line
			(start 1.759712 -1.500124)
			(end 1.759712 1.500124)
			(stroke
				(width 0.1524)
				(type default)
			)
			(layer "F.SilkS")
		)
		(fp_line
			(start 1.759712 1.500124)
			(end -1.759712 1.500124)
			(stroke
				(width 0.1524)
				(type default)
			)
			(layer "F.SilkS")
		)
		(fp_line
			(start -0.700024 -1.500124)
			(end 0.700024 -1.500124)
			(stroke
				(width 0.1)
				(type default)
			)
			(layer "F.Fab")
		)
		(fp_line
			(start -0.700024 1.500124)
			(end -0.700024 -1.500124)
			(stroke
				(width 0.1)
				(type default)
			)
			(layer "F.Fab")
		)
		(fp_line
			(start 0.700024 -1.500124)
			(end 0.700024 1.500124)
			(stroke
				(width 0.1)
				(type default)
			)
			(layer "F.Fab")
		)
		(fp_line
			(start 0.700024 1.500124)
			(end -0.700024 1.500124)
			(stroke
				(width 0.1)
				(type default)
			)
			(layer "F.Fab")
		)
		(pad "1" smd rect
			(at -1.150112 -0.94996 270)
			(size 0.6604 0.9652)
			(layers "F.Cu" "F.Mask" "F.Paste")
			(net "GND")
		)
		(pad "2" smd rect
			(at -1.150112 0.94996 270)
			(size 0.6604 0.9652)
			(layers "F.Cu" "F.Mask" "F.Paste")
			(net "PWRGD_P3V3_EN_R")
		)
		(pad "3" smd rect
			(at 1.150112 0 270)
			(size 0.6604 0.9652)
			(layers "F.Cu" "F.Mask" "F.Paste")
			(net "P3V3")
		)
	)
	(footprint ""
		(layer "F.Cu")
		(at 208.894426 -109.561376 180)
		(property "Reference" "R6055"
			(at 0 0 180)
			(layer "F.SilkS")
			(hide yes)
			(effects
				(font
					(size 1.27 1.27)
				)
			)
		)
		(property "Value" ""
			(at 0 0 180)
			(layer "F.Fab")
			(effects
				(font
					(size 1.27 1.27)
				)
			)
		)
		(duplicate_pad_numbers_are_jumpers no)
		(fp_line
			(start 0.7874 0.4064)
			(end -0.7874 0.4064)
			(stroke
				(width 0.1524)
				(type default)
			)
			(layer "F.SilkS")
		)
		(fp_line
			(start 0.7874 -0.4064)
			(end 0.7874 0.4064)
			(stroke
				(width 0.1524)
				(type default)
			)
			(layer "F.SilkS")
		)
		(fp_line
			(start -0.7874 0.4064)
			(end -0.7874 -0.4064)
			(stroke
				(width 0.1524)
				(type default)
			)
			(layer "F.SilkS")
		)
		(fp_line
			(start -0.7874 -0.4064)
			(end 0.7874 -0.4064)
			(stroke
				(width 0.1524)
				(type default)
			)
			(layer "F.SilkS")
		)
		(fp_line
			(start 0.67945 0.3048)
			(end 0.120396 0.3048)
			(stroke
				(width 0.1)
				(type default)
			)
			(layer "F.Fab")
		)
		(fp_line
			(start 0.67945 -0.3048)
			(end 0.67945 0.3048)
			(stroke
				(width 0.1)
				(type default)
			)
			(layer "F.Fab")
		)
		(fp_line
			(start 0.12065 -0.2794)
			(end 0.12065 -0.3048)
			(stroke
				(width 0.1)
				(type default)
			)
			(layer "F.Fab")
		)
		(fp_line
			(start 0.12065 -0.3048)
			(end 0.67945 -0.3048)
			(stroke
				(width 0.1)
				(type default)
			)
			(layer "F.Fab")
		)
		(fp_line
			(start 0.120396 0.3048)
			(end 0.120396 0.2794)
			(stroke
				(width 0.1)
				(type default)
			)
			(layer "F.Fab")
		)
		(fp_line
			(start 0.120396 0.2794)
			(end -0.12065 0.2794)
			(stroke
				(width 0.1)
				(type default)
			)
			(layer "F.Fab")
		)
		(fp_line
			(start -0.12065 0.3048)
			(end -0.67945 0.3048)
			(stroke
				(width 0.1)
				(type default)
			)
			(layer "F.Fab")
		)
		(fp_line
			(start -0.12065 0.2794)
			(end -0.12065 0.3048)
			(stroke
				(width 0.1)
				(type default)
			)
			(layer "F.Fab")
		)
		(fp_line
			(start -0.12065 -0.2794)
			(end 0.12065 -0.2794)
			(stroke
				(width 0.1)
				(type default)
			)
			(layer "F.Fab")
		)
		(fp_line
			(start -0.12065 -0.305054)
			(end -0.12065 -0.2794)
			(stroke
				(width 0.1)
				(type default)
			)
			(layer "F.Fab")
		)
		(fp_line
			(start -0.67945 0.3048)
			(end -0.67945 -0.305054)
			(stroke
				(width 0.1)
				(type default)
			)
			(layer "F.Fab")
		)
		(fp_line
			(start -0.67945 -0.305054)
			(end -0.12065 -0.305054)
			(stroke
				(width 0.1)
				(type default)
			)
			(layer "F.Fab")
		)
		(pad "1" smd circle
			(at -0.40005 0 180)
			(size 0 0)
			(layers "F.Cu" "F.Mask" "F.Paste")
			(net "HP_LVC3_SCM_HSC_PWRGD")
		)
		(pad "2" smd circle
			(at 0.40005 0 180)
			(size 0 0)
			(layers "F.Cu" "F.Mask" "F.Paste")
			(net "P12V_SCM_PWRGD_R")
		)
	)
	(footprint ""
		(layer "F.Cu")
		(at 108.839 -415.417 -90)
		(property "Reference" "R560"
			(at 0 0 270)
			(layer "F.SilkS")
			(hide yes)
			(effects
				(font
					(size 1.27 1.27)
				)
			)
		)
		(property "Value" ""
			(at 0 0 270)
			(layer "F.Fab")
			(effects
				(font
					(size 1.27 1.27)
				)
			)
		)
		(duplicate_pad_numbers_are_jumpers no)
		(fp_line
			(start -0.7874 0.4064)
			(end -0.7874 -0.4064)
			(stroke
				(width 0.1524)
				(type default)
			)
			(layer "F.SilkS")
		)
		(fp_line
			(start 0.7874 0.4064)
			(end -0.7874 0.4064)
			(stroke
				(width 0.1524)
				(type default)
			)
			(layer "F.SilkS")
		)
		(fp_line
			(start -0.7874 -0.4064)
			(end 0.7874 -0.4064)
			(stroke
				(width 0.1524)
				(type default)
			)
			(layer "F.SilkS")
		)
		(fp_line
			(start 0.7874 -0.4064)
			(end 0.7874 0.4064)
			(stroke
				(width 0.1524)
				(type default)
			)
			(layer "F.SilkS")
		)
		(fp_line
			(start -0.67945 0.3048)
			(end -0.67945 -0.305054)
			(stroke
				(width 0.1)
				(type default)
			)
			(layer "F.Fab")
		)
		(fp_line
			(start -0.12065 0.3048)
			(end -0.67945 0.3048)
			(stroke
				(width 0.1)
				(type default)
			)
			(layer "F.Fab")
		)
		(fp_line
			(start 0.120396 0.3048)
			(end 0.120396 0.2794)
			(stroke
				(width 0.1)
				(type default)
			)
			(layer "F.Fab")
		)
		(fp_line
			(start 0.67945 0.3048)
			(end 0.120396 0.3048)
			(stroke
				(width 0.1)
				(type default)
			)
			(layer "F.Fab")
		)
		(fp_line
			(start -0.12065 0.2794)
			(end -0.12065 0.3048)
			(stroke
				(width 0.1)
				(type default)
			)
			(layer "F.Fab")
		)
		(fp_line
			(start 0.120396 0.2794)
			(end -0.12065 0.2794)
			(stroke
				(width 0.1)
				(type default)
			)
			(layer "F.Fab")
		)
		(fp_line
			(start -0.12065 -0.2794)
			(end 0.12065 -0.2794)
			(stroke
				(width 0.1)
				(type default)
			)
			(layer "F.Fab")
		)
		(fp_line
			(start 0.12065 -0.2794)
			(end 0.12065 -0.3048)
			(stroke
				(width 0.1)
				(type default)
			)
			(layer "F.Fab")
		)
		(fp_line
			(start 0.12065 -0.3048)
			(end 0.67945 -0.3048)
			(stroke
				(width 0.1)
				(type default)
			)
			(layer "F.Fab")
		)
		(fp_line
			(start 0.67945 -0.3048)
			(end 0.67945 0.3048)
			(stroke
				(width 0.1)
				(type default)
			)
			(layer "F.Fab")
		)
		(fp_line
			(start -0.67945 -0.305054)
			(end -0.12065 -0.305054)
			(stroke
				(width 0.1)
				(type default)
			)
			(layer "F.Fab")
		)
		(fp_line
			(start -0.12065 -0.305054)
			(end -0.12065 -0.2794)
			(stroke
				(width 0.1)
				(type default)
			)
			(layer "F.Fab")
		)
		(pad "1" smd circle
			(at -0.40005 0 270)
			(size 0 0)
			(layers "F.Cu" "F.Mask" "F.Paste")
			(net "P3V3_AUX")
		)
		(pad "2" smd circle
			(at 0.40005 0 270)
			(size 0 0)
			(layers "F.Cu" "F.Mask" "F.Paste")
			(net "FM_9ZXL045_P1_DEV_EN")
		)
	)
	(footprint ""
		(layer "F.Cu")
		(at 129.483104 -51.410616)
		(property "Reference" "R6109"
			(at 0 0 0)
			(layer "F.SilkS")
			(hide yes)
			(effects
				(font
					(size 1.27 1.27)
				)
			)
		)
		(property "Value" ""
			(at 0 0 0)
			(layer "F.Fab")
			(effects
				(font
					(size 1.27 1.27)
				)
			)
		)
		(duplicate_pad_numbers_are_jumpers no)
		(fp_line
			(start -0.7874 -0.4064)
			(end 0.7874 -0.4064)
			(stroke
				(width 0.1524)
				(type default)
			)
			(layer "F.SilkS")
		)
		(fp_line
			(start -0.7874 0.4064)
			(end -0.7874 -0.4064)
			(stroke
				(width 0.1524)
				(type default)
			)
			(layer "F.SilkS")
		)
		(fp_line
			(start 0.7874 -0.4064)
			(end 0.7874 0.4064)
			(stroke
				(width 0.1524)
				(type default)
			)
			(layer "F.SilkS")
		)
		(fp_line
			(start 0.7874 0.4064)
			(end -0.7874 0.4064)
			(stroke
				(width 0.1524)
				(type default)
			)
			(layer "F.SilkS")
		)
		(fp_line
			(start -0.67945 -0.305054)
			(end -0.12065 -0.305054)
			(stroke
				(width 0.1)
				(type default)
			)
			(layer "F.Fab")
		)
		(fp_line
			(start -0.67945 0.3048)
			(end -0.67945 -0.305054)
			(stroke
				(width 0.1)
				(type default)
			)
			(layer "F.Fab")
		)
		(fp_line
			(start -0.12065 -0.305054)
			(end -0.12065 -0.2794)
			(stroke
				(width 0.1)
				(type default)
			)
			(layer "F.Fab")
		)
		(fp_line
			(start -0.12065 -0.2794)
			(end 0.12065 -0.2794)
			(stroke
				(width 0.1)
				(type default)
			)
			(layer "F.Fab")
		)
		(fp_line
			(start -0.12065 0.2794)
			(end -0.12065 0.3048)
			(stroke
				(width 0.1)
				(type default)
			)
			(layer "F.Fab")
		)
		(fp_line
			(start -0.12065 0.3048)
			(end -0.67945 0.3048)
			(stroke
				(width 0.1)
				(type default)
			)
			(layer "F.Fab")
		)
		(fp_line
			(start 0.120396 0.2794)
			(end -0.12065 0.2794)
			(stroke
				(width 0.1)
				(type default)
			)
			(layer "F.Fab")
		)
		(fp_line
			(start 0.120396 0.3048)
			(end 0.120396 0.2794)
			(stroke
				(width 0.1)
				(type default)
			)
			(layer "F.Fab")
		)
		(fp_line
			(start 0.12065 -0.3048)
			(end 0.67945 -0.3048)
			(stroke
				(width 0.1)
				(type default)
			)
			(layer "F.Fab")
		)
		(fp_line
			(start 0.12065 -0.2794)
			(end 0.12065 -0.3048)
			(stroke
				(width 0.1)
				(type default)
			)
			(layer "F.Fab")
		)
		(fp_line
			(start 0.67945 -0.3048)
			(end 0.67945 0.3048)
			(stroke
				(width 0.1)
				(type default)
			)
			(layer "F.Fab")
		)
		(fp_line
			(start 0.67945 0.3048)
			(end 0.120396 0.3048)
			(stroke
				(width 0.1)
				(type default)
			)
			(layer "F.Fab")
		)
		(pad "1" smd circle
			(at -0.40005 0)
			(size 0 0)
			(layers "F.Cu" "F.Mask" "F.Paste")
			(net "JTAG_TDO")
		)
		(pad "2" smd circle
			(at 0.40005 0)
			(size 0 0)
			(layers "F.Cu" "F.Mask" "F.Paste")
			(net "JTAG_TDO_R")
		)
	)
	(footprint ""
		(layer "F.Cu")
		(at 132.603748 -165.848284 180)
		(property "Reference" "PL38"
			(at -0.737108 7.266178 0)
			(unlocked yes)
			(layer "F.SilkS")
			(effects
				(font
					(size 0.7874 0.5842)
					(thickness 0.1524)
				)
				(justify left)
			)
		)
		(property "Value" ""
			(at 0 0 180)
			(layer "F.Fab")
			(effects
				(font
					(size 1.27 1.27)
				)
			)
		)
		(duplicate_pad_numbers_are_jumpers no)
		(fp_line
			(start 3.750056 5.500116)
			(end 3.750056 -5.500116)
			(stroke
				(width 0.1524)
				(type default)
			)
			(layer "F.SilkS")
		)
		(fp_line
			(start 3.750056 -5.500116)
			(end 2.393442 -5.500116)
			(stroke
				(width 0.1524)
				(type default)
			)
			(layer "F.SilkS")
		)
		(fp_line
			(start 2.393442 5.500116)
			(end 3.750056 5.500116)
			(stroke
				(width 0.1524)
				(type default)
			)
			(layer "F.SilkS")
		)
		(fp_line
			(start -2.393442 5.500116)
			(end -3.750056 5.500116)
			(stroke
				(width 0.1524)
				(type default)
			)
			(layer "F.SilkS")
		)
		(fp_line
			(start -3.750056 5.500116)
			(end -3.750056 -5.500116)
			(stroke
				(width 0.1524)
				(type default)
			)
			(layer "F.SilkS")
		)
		(fp_line
			(start -3.750056 -5.500116)
			(end -2.393442 -5.500116)
			(stroke
				(width 0.1524)
				(type default)
			)
			(layer "F.SilkS")
		)
		(fp_poly
			(pts
				(xy -3.9116 -4.249928) (xy -4.556252 -3.927602) (xy -4.556252 -4.572254)
			)
			(stroke
				(width 0)
				(type default)
			)
			(fill yes)
			(layer "F.SilkS")
		)
		(fp_line
			(start 3.750056 5.500116)
			(end 3.750056 -5.500116)
			(stroke
				(width 0.1)
				(type default)
			)
			(layer "F.Fab")
		)
		(fp_line
			(start 3.750056 -5.500116)
			(end -3.750056 -5.500116)
			(stroke
				(width 0.1)
				(type default)
			)
			(layer "F.Fab")
		)
		(fp_line
			(start -3.750056 5.500116)
			(end 3.750056 5.500116)
			(stroke
				(width 0.1)
				(type default)
			)
			(layer "F.Fab")
		)
		(fp_line
			(start -3.750056 -5.500116)
			(end -3.750056 5.500116)
			(stroke
				(width 0.1)
				(type default)
			)
			(layer "F.Fab")
		)
		(fp_poly
			(pts
				(xy -4.9276 -4.757928) (xy -4.9276 -3.741928) (xy -3.9116 -4.249928)
			)
			(stroke
				(width 0)
				(type default)
			)
			(fill yes)
			(layer "F.Fab")
		)
		(pad "1" smd rect
			(at 0 -4.249928 90)
			(size 2.413 4.5212)
			(layers "F.Cu" "F.Mask" "F.Paste")
			(net "SW_PVDDCR_SOC_P1_SW3")
		)
		(pad "2" smd rect
			(at 0 -1.175004 90)
			(size 1.3716 4.5212)
			(layers "F.Cu" "F.Mask" "F.Paste")
			(net "IND_SOC_P1_CPL0")
		)
		(pad "3" smd rect
			(at 0 1.175004 90)
			(size 1.3716 4.5212)
			(layers "F.Cu" "F.Mask" "F.Paste")
			(net "IND_SOC_P1_CPL3")
		)
		(pad "4" smd rect
			(at 0 4.249928 90)
			(size 2.413 4.5212)
			(layers "F.Cu" "F.Mask" "F.Paste")
			(net "PVDDCR_SOC_P1")
		)
	)
	(footprint ""
		(layer "F.Cu")
		(at 72.2884 -382.27)
		(property "Reference" "R6717"
			(at 0 0 0)
			(layer "F.SilkS")
			(hide yes)
			(effects
				(font
					(size 1.27 1.27)
				)
			)
		)
		(property "Value" ""
			(at 0 0 0)
			(layer "F.Fab")
			(effects
				(font
					(size 1.27 1.27)
				)
			)
		)
		(duplicate_pad_numbers_are_jumpers no)
		(fp_line
			(start -0.32512 -0.175006)
			(end 0.32512 -0.175006)
			(stroke
				(width 0.1)
				(type default)
			)
			(layer "F.Fab")
		)
		(fp_line
			(start -0.32512 0.175006)
			(end -0.32512 -0.175006)
			(stroke
				(width 0.1)
				(type default)
			)
			(layer "F.Fab")
		)
		(fp_line
			(start 0.32512 -0.175006)
			(end 0.32512 0.175006)
			(stroke
				(width 0.1)
				(type default)
			)
			(layer "F.Fab")
		)
		(fp_line
			(start 0.32512 0.175006)
			(end -0.32512 0.175006)
			(stroke
				(width 0.1)
				(type default)
			)
			(layer "F.Fab")
		)
		(pad "1" smd rect
			(at -0.2667 0)
			(size 0.3048 0.381)
			(layers "F.Cu" "F.Mask" "F.Paste")
			(net "RT_CPU1_P0_ADDR1")
		)
		(pad "2" smd rect
			(at 0.2667 0 180)
			(size 0.3048 0.381)
			(layers "F.Cu" "F.Mask" "F.Paste")
			(net "GND")
		)
	)
	(footprint ""
		(layer "F.Cu")
		(at 120.995186 -408.517344 -90)
		(property "Reference" "C6698"
			(at 0 0 270)
			(layer "F.SilkS")
			(hide yes)
			(effects
				(font
					(size 1.27 1.27)
				)
			)
		)
		(property "Value" ""
			(at 0 0 270)
			(layer "F.Fab")
			(effects
				(font
					(size 1.27 1.27)
				)
			)
		)
		(duplicate_pad_numbers_are_jumpers no)
		(fp_line
			(start -0.299974 0.150114)
			(end -0.299974 -0.150114)
			(stroke
				(width 0.1)
				(type default)
			)
			(layer "F.Fab")
		)
		(fp_line
			(start 0.299974 0.150114)
			(end -0.299974 0.150114)
			(stroke
				(width 0.1)
				(type default)
			)
			(layer "F.Fab")
		)
		(fp_line
			(start -0.299974 -0.150114)
			(end 0.299974 -0.150114)
			(stroke
				(width 0.1)
				(type default)
			)
			(layer "F.Fab")
		)
		(fp_line
			(start 0.299974 -0.150114)
			(end 0.299974 0.150114)
			(stroke
				(width 0.1)
				(type default)
			)
			(layer "F.Fab")
		)
		(pad "1" smd rect
			(at -0.2667 0 270)
			(size 0.3048 0.381)
			(layers "F.Cu" "F.Mask" "F.Paste")
			(net "P5E_CPU1_P2_TX_BUF_C_DN<2>")
		)
		(pad "2" smd rect
			(at 0.2667 0 270)
			(size 0.3048 0.381)
			(layers "F.Cu" "F.Mask" "F.Paste")
			(net "P5E_CPU1_P2_TX_BUF_DN<2>")
		)
	)
	(footprint ""
		(layer "F.Cu")
		(at 178.985164 -129.366518 -90)
		(property "Reference" "R6710"
			(at 0 0 270)
			(layer "F.SilkS")
			(hide yes)
			(effects
				(font
					(size 1.27 1.27)
				)
			)
		)
		(property "Value" ""
			(at 0 0 270)
			(layer "F.Fab")
			(effects
				(font
					(size 1.27 1.27)
				)
			)
		)
		(duplicate_pad_numbers_are_jumpers no)
		(fp_line
			(start -0.7874 0.4064)
			(end -0.7874 -0.4064)
			(stroke
				(width 0.1524)
				(type default)
			)
			(layer "F.SilkS")
		)
		(fp_line
			(start 0.7874 0.4064)
			(end -0.7874 0.4064)
			(stroke
				(width 0.1524)
				(type default)
			)
			(layer "F.SilkS")
		)
		(fp_line
			(start -0.7874 -0.4064)
			(end 0.7874 -0.4064)
			(stroke
				(width 0.1524)
				(type default)
			)
			(layer "F.SilkS")
		)
		(fp_line
			(start 0.7874 -0.4064)
			(end 0.7874 0.4064)
			(stroke
				(width 0.1524)
				(type default)
			)
			(layer "F.SilkS")
		)
		(fp_line
			(start -0.67945 0.3048)
			(end -0.67945 -0.305054)
			(stroke
				(width 0.1)
				(type default)
			)
			(layer "F.Fab")
		)
		(fp_line
			(start -0.12065 0.3048)
			(end -0.67945 0.3048)
			(stroke
				(width 0.1)
				(type default)
			)
			(layer "F.Fab")
		)
		(fp_line
			(start 0.120396 0.3048)
			(end 0.120396 0.2794)
			(stroke
				(width 0.1)
				(type default)
			)
			(layer "F.Fab")
		)
		(fp_line
			(start 0.67945 0.3048)
			(end 0.120396 0.3048)
			(stroke
				(width 0.1)
				(type default)
			)
			(layer "F.Fab")
		)
		(fp_line
			(start -0.12065 0.2794)
			(end -0.12065 0.3048)
			(stroke
				(width 0.1)
				(type default)
			)
			(layer "F.Fab")
		)
		(fp_line
			(start 0.120396 0.2794)
			(end -0.12065 0.2794)
			(stroke
				(width 0.1)
				(type default)
			)
			(layer "F.Fab")
		)
		(fp_line
			(start -0.12065 -0.2794)
			(end 0.12065 -0.2794)
			(stroke
				(width 0.1)
				(type default)
			)
			(layer "F.Fab")
		)
		(fp_line
			(start 0.12065 -0.2794)
			(end 0.12065 -0.3048)
			(stroke
				(width 0.1)
				(type default)
			)
			(layer "F.Fab")
		)
		(fp_line
			(start 0.12065 -0.3048)
			(end 0.67945 -0.3048)
			(stroke
				(width 0.1)
				(type default)
			)
			(layer "F.Fab")
		)
		(fp_line
			(start 0.67945 -0.3048)
			(end 0.67945 0.3048)
			(stroke
				(width 0.1)
				(type default)
			)
			(layer "F.Fab")
		)
		(fp_line
			(start -0.67945 -0.305054)
			(end -0.12065 -0.305054)
			(stroke
				(width 0.1)
				(type default)
			)
			(layer "F.Fab")
		)
		(fp_line
			(start -0.12065 -0.305054)
			(end -0.12065 -0.2794)
			(stroke
				(width 0.1)
				(type default)
			)
			(layer "F.Fab")
		)
		(pad "1" smd circle
			(at -0.40005 0 270)
			(size 0 0)
			(layers "F.Cu" "F.Mask" "F.Paste")
			(net "RST_RT_CPU1_P0_PERST_R_N")
		)
		(pad "2" smd circle
			(at 0.40005 0 270)
			(size 0 0)
			(layers "F.Cu" "F.Mask" "F.Paste")
			(net "RST_RT_CPU1_P0_PERST_R2_N")
		)
	)
	(footprint ""
		(layer "F.Cu")
		(at 178.689 -395.351 180)
		(property "Reference" "PR3929"
			(at 0 0 180)
			(layer "F.SilkS")
			(hide yes)
			(effects
				(font
					(size 1.27 1.27)
				)
			)
		)
		(property "Value" ""
			(at 0 0 180)
			(layer "F.Fab")
			(effects
				(font
					(size 1.27 1.27)
				)
			)
		)
		(duplicate_pad_numbers_are_jumpers no)
		(fp_line
			(start 0.7874 0.4064)
			(end -0.7874 0.4064)
			(stroke
				(width 0.1524)
				(type default)
			)
			(layer "F.SilkS")
		)
		(fp_line
			(start 0.7874 -0.4064)
			(end 0.7874 0.4064)
			(stroke
				(width 0.1524)
				(type default)
			)
			(layer "F.SilkS")
		)
		(fp_line
			(start -0.7874 0.4064)
			(end -0.7874 -0.4064)
			(stroke
				(width 0.1524)
				(type default)
			)
			(layer "F.SilkS")
		)
		(fp_line
			(start -0.7874 -0.4064)
			(end 0.7874 -0.4064)
			(stroke
				(width 0.1524)
				(type default)
			)
			(layer "F.SilkS")
		)
		(fp_line
			(start 0.67945 0.3048)
			(end 0.120396 0.3048)
			(stroke
				(width 0.1)
				(type default)
			)
			(layer "F.Fab")
		)
		(fp_line
			(start 0.67945 -0.3048)
			(end 0.67945 0.3048)
			(stroke
				(width 0.1)
				(type default)
			)
			(layer "F.Fab")
		)
		(fp_line
			(start 0.12065 -0.2794)
			(end 0.12065 -0.3048)
			(stroke
				(width 0.1)
				(type default)
			)
			(layer "F.Fab")
		)
		(fp_line
			(start 0.12065 -0.3048)
			(end 0.67945 -0.3048)
			(stroke
				(width 0.1)
				(type default)
			)
			(layer "F.Fab")
		)
		(fp_line
			(start 0.120396 0.3048)
			(end 0.120396 0.2794)
			(stroke
				(width 0.1)
				(type default)
			)
			(layer "F.Fab")
		)
		(fp_line
			(start 0.120396 0.2794)
			(end -0.12065 0.2794)
			(stroke
				(width 0.1)
				(type default)
			)
			(layer "F.Fab")
		)
		(fp_line
			(start -0.12065 0.3048)
			(end -0.67945 0.3048)
			(stroke
				(width 0.1)
				(type default)
			)
			(layer "F.Fab")
		)
		(fp_line
			(start -0.12065 0.2794)
			(end -0.12065 0.3048)
			(stroke
				(width 0.1)
				(type default)
			)
			(layer "F.Fab")
		)
		(fp_line
			(start -0.12065 -0.2794)
			(end 0.12065 -0.2794)
			(stroke
				(width 0.1)
				(type default)
			)
			(layer "F.Fab")
		)
		(fp_line
			(start -0.12065 -0.305054)
			(end -0.12065 -0.2794)
			(stroke
				(width 0.1)
				(type default)
			)
			(layer "F.Fab")
		)
		(fp_line
			(start -0.67945 0.3048)
			(end -0.67945 -0.305054)
			(stroke
				(width 0.1)
				(type default)
			)
			(layer "F.Fab")
		)
		(fp_line
			(start -0.67945 -0.305054)
			(end -0.12065 -0.305054)
			(stroke
				(width 0.1)
				(type default)
			)
			(layer "F.Fab")
		)
		(pad "1" smd circle
			(at -0.40005 0 180)
			(size 0 0)
			(layers "F.Cu" "F.Mask" "F.Paste")
			(net "HSC_ADDR")
		)
		(pad "2" smd circle
			(at 0.40005 0 180)
			(size 0 0)
			(layers "F.Cu" "F.Mask" "F.Paste")
			(net "HSC_VDD18")
		)
	)
	(footprint ""
		(layer "F.Cu")
		(at 126.320296 -370.57203 -90)
		(property "Reference" "C1528"
			(at 0 0 270)
			(layer "F.SilkS")
			(hide yes)
			(effects
				(font
					(size 1.27 1.27)
				)
			)
		)
		(property "Value" ""
			(at 0 0 270)
			(layer "F.Fab")
			(effects
				(font
					(size 1.27 1.27)
				)
			)
		)
		(duplicate_pad_numbers_are_jumpers no)
		(fp_line
			(start -0.299974 0.150114)
			(end -0.299974 -0.150114)
			(stroke
				(width 0.1)
				(type default)
			)
			(layer "F.Fab")
		)
		(fp_line
			(start 0.299974 0.150114)
			(end -0.299974 0.150114)
			(stroke
				(width 0.1)
				(type default)
			)
			(layer "F.Fab")
		)
		(fp_line
			(start -0.299974 -0.150114)
			(end 0.299974 -0.150114)
			(stroke
				(width 0.1)
				(type default)
			)
			(layer "F.Fab")
		)
		(fp_line
			(start 0.299974 -0.150114)
			(end 0.299974 0.150114)
			(stroke
				(width 0.1)
				(type default)
			)
			(layer "F.Fab")
		)
		(pad "1" smd rect
			(at -0.2667 0 270)
			(size 0.3048 0.381)
			(layers "F.Cu" "F.Mask" "F.Paste")
			(net "P5E_CPU1_P3_TX_C_DN<9>")
		)
		(pad "2" smd rect
			(at 0.2667 0 270)
			(size 0.3048 0.381)
			(layers "F.Cu" "F.Mask" "F.Paste")
			(net "P5E_CPU1_P3_TX_DN<9>")
		)
	)
	(footprint ""
		(layer "F.Cu")
		(at 45.932344 -421.326564)
		(property "Reference" "R1467"
			(at 0 0 0)
			(layer "F.SilkS")
			(hide yes)
			(effects
				(font
					(size 1.27 1.27)
				)
			)
		)
		(property "Value" ""
			(at 0 0 0)
			(layer "F.Fab")
			(effects
				(font
					(size 1.27 1.27)
				)
			)
		)
		(duplicate_pad_numbers_are_jumpers no)
		(fp_line
			(start -0.32512 -0.175006)
			(end 0.32512 -0.175006)
			(stroke
				(width 0.1)
				(type default)
			)
			(layer "F.Fab")
		)
		(fp_line
			(start -0.32512 0.175006)
			(end -0.32512 -0.175006)
			(stroke
				(width 0.1)
				(type default)
			)
			(layer "F.Fab")
		)
		(fp_line
			(start 0.32512 -0.175006)
			(end 0.32512 0.175006)
			(stroke
				(width 0.1)
				(type default)
			)
			(layer "F.Fab")
		)
		(fp_line
			(start 0.32512 0.175006)
			(end -0.32512 0.175006)
			(stroke
				(width 0.1)
				(type default)
			)
			(layer "F.Fab")
		)
		(pad "1" smd rect
			(at -0.2667 0)
			(size 0.3048 0.381)
			(layers "F.Cu" "F.Mask" "F.Paste")
			(net "P1V8_CPU1_RT_1D")
		)
		(pad "2" smd rect
			(at 0.2667 0 180)
			(size 0.3048 0.381)
			(layers "F.Cu" "F.Mask" "F.Paste")
			(net "JTAG_TCK_RT_CPU1_P0")
		)
	)
	(footprint ""
		(layer "F.Cu")
		(at 173.216062 -30.446472 180)
		(property "Reference" "PR4007"
			(at 0 0 180)
			(layer "F.SilkS")
			(hide yes)
			(effects
				(font
					(size 1.27 1.27)
				)
			)
		)
		(property "Value" ""
			(at 0 0 180)
			(layer "F.Fab")
			(effects
				(font
					(size 1.27 1.27)
				)
			)
		)
		(duplicate_pad_numbers_are_jumpers no)
		(fp_line
			(start 0.7874 0.4064)
			(end -0.7874 0.4064)
			(stroke
				(width 0.1524)
				(type default)
			)
			(layer "F.SilkS")
		)
		(fp_line
			(start 0.7874 -0.4064)
			(end 0.7874 0.4064)
			(stroke
				(width 0.1524)
				(type default)
			)
			(layer "F.SilkS")
		)
		(fp_line
			(start -0.7874 0.4064)
			(end -0.7874 -0.4064)
			(stroke
				(width 0.1524)
				(type default)
			)
			(layer "F.SilkS")
		)
		(fp_line
			(start -0.7874 -0.4064)
			(end 0.7874 -0.4064)
			(stroke
				(width 0.1524)
				(type default)
			)
			(layer "F.SilkS")
		)
		(fp_line
			(start 0.67945 0.3048)
			(end 0.120396 0.3048)
			(stroke
				(width 0.1)
				(type default)
			)
			(layer "F.Fab")
		)
		(fp_line
			(start 0.67945 -0.3048)
			(end 0.67945 0.3048)
			(stroke
				(width 0.1)
				(type default)
			)
			(layer "F.Fab")
		)
		(fp_line
			(start 0.12065 -0.2794)
			(end 0.12065 -0.3048)
			(stroke
				(width 0.1)
				(type default)
			)
			(layer "F.Fab")
		)
		(fp_line
			(start 0.12065 -0.3048)
			(end 0.67945 -0.3048)
			(stroke
				(width 0.1)
				(type default)
			)
			(layer "F.Fab")
		)
		(fp_line
			(start 0.120396 0.3048)
			(end 0.120396 0.2794)
			(stroke
				(width 0.1)
				(type default)
			)
			(layer "F.Fab")
		)
		(fp_line
			(start 0.120396 0.2794)
			(end -0.12065 0.2794)
			(stroke
				(width 0.1)
				(type default)
			)
			(layer "F.Fab")
		)
		(fp_line
			(start -0.12065 0.3048)
			(end -0.67945 0.3048)
			(stroke
				(width 0.1)
				(type default)
			)
			(layer "F.Fab")
		)
		(fp_line
			(start -0.12065 0.2794)
			(end -0.12065 0.3048)
			(stroke
				(width 0.1)
				(type default)
			)
			(layer "F.Fab")
		)
		(fp_line
			(start -0.12065 -0.2794)
			(end 0.12065 -0.2794)
			(stroke
				(width 0.1)
				(type default)
			)
			(layer "F.Fab")
		)
		(fp_line
			(start -0.12065 -0.305054)
			(end -0.12065 -0.2794)
			(stroke
				(width 0.1)
				(type default)
			)
			(layer "F.Fab")
		)
		(fp_line
			(start -0.67945 0.3048)
			(end -0.67945 -0.305054)
			(stroke
				(width 0.1)
				(type default)
			)
			(layer "F.Fab")
		)
		(fp_line
			(start -0.67945 -0.305054)
			(end -0.12065 -0.305054)
			(stroke
				(width 0.1)
				(type default)
			)
			(layer "F.Fab")
		)
		(pad "1" smd circle
			(at -0.40005 0 180)
			(size 0 0)
			(layers "F.Cu" "F.Mask" "F.Paste")
			(net "P12V_SCM_FLTB_N")
		)
		(pad "2" smd circle
			(at 0.40005 0 180)
			(size 0 0)
			(layers "F.Cu" "F.Mask" "F.Paste")
			(net "P3V3_AUX")
		)
	)
	(footprint ""
		(layer "F.Cu")
		(at 448.671442 -415.464244 180)
		(property "Reference" "PC6562"
			(at 0 0 180)
			(layer "F.SilkS")
			(hide yes)
			(effects
				(font
					(size 1.27 1.27)
				)
			)
		)
		(property "Value" ""
			(at 0 0 180)
			(layer "F.Fab")
			(effects
				(font
					(size 1.27 1.27)
				)
			)
		)
		(duplicate_pad_numbers_are_jumpers no)
		(fp_line
			(start 0.7874 0.4064)
			(end -0.7874 0.4064)
			(stroke
				(width 0.1524)
				(type default)
			)
			(layer "F.SilkS")
		)
		(fp_line
			(start 0.7874 -0.4064)
			(end 0.7874 0.4064)
			(stroke
				(width 0.1524)
				(type default)
			)
			(layer "F.SilkS")
		)
		(fp_line
			(start -0.7874 0.4064)
			(end -0.7874 -0.4064)
			(stroke
				(width 0.1524)
				(type default)
			)
			(layer "F.SilkS")
		)
		(fp_line
			(start -0.7874 -0.4064)
			(end 0.7874 -0.4064)
			(stroke
				(width 0.1524)
				(type default)
			)
			(layer "F.SilkS")
		)
		(fp_line
			(start 0.67945 0.3048)
			(end 0.120396 0.3048)
			(stroke
				(width 0.1)
				(type default)
			)
			(layer "F.Fab")
		)
		(fp_line
			(start 0.67945 -0.3048)
			(end 0.67945 0.3048)
			(stroke
				(width 0.1)
				(type default)
			)
			(layer "F.Fab")
		)
		(fp_line
			(start 0.12065 -0.2794)
			(end 0.12065 -0.3048)
			(stroke
				(width 0.1)
				(type default)
			)
			(layer "F.Fab")
		)
		(fp_line
			(start 0.12065 -0.3048)
			(end 0.67945 -0.3048)
			(stroke
				(width 0.1)
				(type default)
			)
			(layer "F.Fab")
		)
		(fp_line
			(start 0.120396 0.3048)
			(end 0.120396 0.2794)
			(stroke
				(width 0.1)
				(type default)
			)
			(layer "F.Fab")
		)
		(fp_line
			(start 0.120396 0.2794)
			(end -0.12065 0.2794)
			(stroke
				(width 0.1)
				(type default)
			)
			(layer "F.Fab")
		)
		(fp_line
			(start -0.12065 0.3048)
			(end -0.67945 0.3048)
			(stroke
				(width 0.1)
				(type default)
			)
			(layer "F.Fab")
		)
		(fp_line
			(start -0.12065 0.2794)
			(end -0.12065 0.3048)
			(stroke
				(width 0.1)
				(type default)
			)
			(layer "F.Fab")
		)
		(fp_line
			(start -0.12065 -0.2794)
			(end 0.12065 -0.2794)
			(stroke
				(width 0.1)
				(type default)
			)
			(layer "F.Fab")
		)
		(fp_line
			(start -0.12065 -0.305054)
			(end -0.12065 -0.2794)
			(stroke
				(width 0.1)
				(type default)
			)
			(layer "F.Fab")
		)
		(fp_line
			(start -0.67945 0.3048)
			(end -0.67945 -0.305054)
			(stroke
				(width 0.1)
				(type default)
			)
			(layer "F.Fab")
		)
		(fp_line
			(start -0.67945 -0.305054)
			(end -0.12065 -0.305054)
			(stroke
				(width 0.1)
				(type default)
			)
			(layer "F.Fab")
		)
		(pad "1" smd circle
			(at -0.40005 0 180)
			(size 0 0)
			(layers "F.Cu" "F.Mask" "F.Paste")
			(net "P12V_AUX")
		)
		(pad "2" smd circle
			(at 0.40005 0 180)
			(size 0 0)
			(layers "F.Cu" "F.Mask" "F.Paste")
			(net "GND")
		)
	)
	(footprint ""
		(layer "F.Cu")
		(at 172.230034 -332.788006 -90)
		(property "Reference" "PC524"
			(at 0 0 270)
			(layer "F.SilkS")
			(hide yes)
			(effects
				(font
					(size 1.27 1.27)
				)
			)
		)
		(property "Value" ""
			(at 0 0 270)
			(layer "F.Fab")
			(effects
				(font
					(size 1.27 1.27)
				)
			)
		)
		(duplicate_pad_numbers_are_jumpers no)
		(fp_line
			(start -0.7874 0.4064)
			(end -0.7874 -0.4064)
			(stroke
				(width 0.1524)
				(type default)
			)
			(layer "F.SilkS")
		)
		(fp_line
			(start 0.7874 0.4064)
			(end -0.7874 0.4064)
			(stroke
				(width 0.1524)
				(type default)
			)
			(layer "F.SilkS")
		)
		(fp_line
			(start -0.7874 -0.4064)
			(end 0.7874 -0.4064)
			(stroke
				(width 0.1524)
				(type default)
			)
			(layer "F.SilkS")
		)
		(fp_line
			(start 0.7874 -0.4064)
			(end 0.7874 0.4064)
			(stroke
				(width 0.1524)
				(type default)
			)
			(layer "F.SilkS")
		)
		(fp_line
			(start -0.67945 0.3048)
			(end -0.67945 -0.305054)
			(stroke
				(width 0.1)
				(type default)
			)
			(layer "F.Fab")
		)
		(fp_line
			(start -0.12065 0.3048)
			(end -0.67945 0.3048)
			(stroke
				(width 0.1)
				(type default)
			)
			(layer "F.Fab")
		)
		(fp_line
			(start 0.120396 0.3048)
			(end 0.120396 0.2794)
			(stroke
				(width 0.1)
				(type default)
			)
			(layer "F.Fab")
		)
		(fp_line
			(start 0.67945 0.3048)
			(end 0.120396 0.3048)
			(stroke
				(width 0.1)
				(type default)
			)
			(layer "F.Fab")
		)
		(fp_line
			(start -0.12065 0.2794)
			(end -0.12065 0.3048)
			(stroke
				(width 0.1)
				(type default)
			)
			(layer "F.Fab")
		)
		(fp_line
			(start 0.120396 0.2794)
			(end -0.12065 0.2794)
			(stroke
				(width 0.1)
				(type default)
			)
			(layer "F.Fab")
		)
		(fp_line
			(start -0.12065 -0.2794)
			(end 0.12065 -0.2794)
			(stroke
				(width 0.1)
				(type default)
			)
			(layer "F.Fab")
		)
		(fp_line
			(start 0.12065 -0.2794)
			(end 0.12065 -0.3048)
			(stroke
				(width 0.1)
				(type default)
			)
			(layer "F.Fab")
		)
		(fp_line
			(start 0.12065 -0.3048)
			(end 0.67945 -0.3048)
			(stroke
				(width 0.1)
				(type default)
			)
			(layer "F.Fab")
		)
		(fp_line
			(start 0.67945 -0.3048)
			(end 0.67945 0.3048)
			(stroke
				(width 0.1)
				(type default)
			)
			(layer "F.Fab")
		)
		(fp_line
			(start -0.67945 -0.305054)
			(end -0.12065 -0.305054)
			(stroke
				(width 0.1)
				(type default)
			)
			(layer "F.Fab")
		)
		(fp_line
			(start -0.12065 -0.305054)
			(end -0.12065 -0.2794)
			(stroke
				(width 0.1)
				(type default)
			)
			(layer "F.Fab")
		)
		(pad "1" smd circle
			(at -0.40005 0 270)
			(size 0 0)
			(layers "F.Cu" "F.Mask" "F.Paste")
			(net "PVDD11_S3_P1")
		)
		(pad "2" smd circle
			(at 0.40005 0 270)
			(size 0 0)
			(layers "F.Cu" "F.Mask" "F.Paste")
			(net "GND")
		)
	)
	(footprint ""
		(layer "F.Cu")
		(at 168.60901 -394.3604 -90)
		(property "Reference" "R6796"
			(at 0 0 270)
			(layer "F.SilkS")
			(hide yes)
			(effects
				(font
					(size 1.27 1.27)
				)
			)
		)
		(property "Value" ""
			(at 0 0 270)
			(layer "F.Fab")
			(effects
				(font
					(size 1.27 1.27)
				)
			)
		)
		(duplicate_pad_numbers_are_jumpers no)
		(fp_line
			(start -0.32512 0.175006)
			(end -0.32512 -0.175006)
			(stroke
				(width 0.1)
				(type default)
			)
			(layer "F.Fab")
		)
		(fp_line
			(start 0.32512 0.175006)
			(end -0.32512 0.175006)
			(stroke
				(width 0.1)
				(type default)
			)
			(layer "F.Fab")
		)
		(fp_line
			(start -0.32512 -0.175006)
			(end 0.32512 -0.175006)
			(stroke
				(width 0.1)
				(type default)
			)
			(layer "F.Fab")
		)
		(fp_line
			(start 0.32512 -0.175006)
			(end 0.32512 0.175006)
			(stroke
				(width 0.1)
				(type default)
			)
			(layer "F.Fab")
		)
		(pad "1" smd rect
			(at -0.2667 0 270)
			(size 0.3048 0.381)
			(layers "F.Cu" "F.Mask" "F.Paste")
			(net "NCF_A1_CPU1_P2_GND")
		)
		(pad "2" smd rect
			(at 0.2667 0 90)
			(size 0.3048 0.381)
			(layers "F.Cu" "F.Mask" "F.Paste")
			(net "GND")
		)
	)
	(footprint ""
		(layer "F.Cu")
		(at 256.889504 -43.504612 180)
		(property "Reference" "PR3966"
			(at 0 0 180)
			(layer "F.SilkS")
			(hide yes)
			(effects
				(font
					(size 1.27 1.27)
				)
			)
		)
		(property "Value" ""
			(at 0 0 180)
			(layer "F.Fab")
			(effects
				(font
					(size 1.27 1.27)
				)
			)
		)
		(duplicate_pad_numbers_are_jumpers no)
		(fp_line
			(start 0.7874 0.4064)
			(end -0.7874 0.4064)
			(stroke
				(width 0.1524)
				(type default)
			)
			(layer "F.SilkS")
		)
		(fp_line
			(start 0.7874 -0.4064)
			(end 0.7874 0.4064)
			(stroke
				(width 0.1524)
				(type default)
			)
			(layer "F.SilkS")
		)
		(fp_line
			(start -0.7874 0.4064)
			(end -0.7874 -0.4064)
			(stroke
				(width 0.1524)
				(type default)
			)
			(layer "F.SilkS")
		)
		(fp_line
			(start -0.7874 -0.4064)
			(end 0.7874 -0.4064)
			(stroke
				(width 0.1524)
				(type default)
			)
			(layer "F.SilkS")
		)
		(fp_line
			(start 0.67945 0.3048)
			(end 0.120396 0.3048)
			(stroke
				(width 0.1)
				(type default)
			)
			(layer "F.Fab")
		)
		(fp_line
			(start 0.67945 -0.3048)
			(end 0.67945 0.3048)
			(stroke
				(width 0.1)
				(type default)
			)
			(layer "F.Fab")
		)
		(fp_line
			(start 0.12065 -0.2794)
			(end 0.12065 -0.3048)
			(stroke
				(width 0.1)
				(type default)
			)
			(layer "F.Fab")
		)
		(fp_line
			(start 0.12065 -0.3048)
			(end 0.67945 -0.3048)
			(stroke
				(width 0.1)
				(type default)
			)
			(layer "F.Fab")
		)
		(fp_line
			(start 0.120396 0.3048)
			(end 0.120396 0.2794)
			(stroke
				(width 0.1)
				(type default)
			)
			(layer "F.Fab")
		)
		(fp_line
			(start 0.120396 0.2794)
			(end -0.12065 0.2794)
			(stroke
				(width 0.1)
				(type default)
			)
			(layer "F.Fab")
		)
		(fp_line
			(start -0.12065 0.3048)
			(end -0.67945 0.3048)
			(stroke
				(width 0.1)
				(type default)
			)
			(layer "F.Fab")
		)
		(fp_line
			(start -0.12065 0.2794)
			(end -0.12065 0.3048)
			(stroke
				(width 0.1)
				(type default)
			)
			(layer "F.Fab")
		)
		(fp_line
			(start -0.12065 -0.2794)
			(end 0.12065 -0.2794)
			(stroke
				(width 0.1)
				(type default)
			)
			(layer "F.Fab")
		)
		(fp_line
			(start -0.12065 -0.305054)
			(end -0.12065 -0.2794)
			(stroke
				(width 0.1)
				(type default)
			)
			(layer "F.Fab")
		)
		(fp_line
			(start -0.67945 0.3048)
			(end -0.67945 -0.305054)
			(stroke
				(width 0.1)
				(type default)
			)
			(layer "F.Fab")
		)
		(fp_line
			(start -0.67945 -0.305054)
			(end -0.12065 -0.305054)
			(stroke
				(width 0.1)
				(type default)
			)
			(layer "F.Fab")
		)
		(pad "1" smd circle
			(at -0.40005 0 180)
			(size 0 0)
			(layers "F.Cu" "F.Mask" "F.Paste")
			(net "P12V_AUX")
		)
		(pad "2" smd circle
			(at 0.40005 0 180)
			(size 0 0)
			(layers "F.Cu" "F.Mask" "F.Paste")
			(net "P12V_E1S_VCC_0")
		)
	)
	(footprint ""
		(layer "F.Cu")
		(at 306.832 -354.457 90)
		(property "Reference" "PR68"
			(at 0 0 90)
			(layer "F.SilkS")
			(hide yes)
			(effects
				(font
					(size 1.27 1.27)
				)
			)
		)
		(property "Value" ""
			(at 0 0 90)
			(layer "F.Fab")
			(effects
				(font
					(size 1.27 1.27)
				)
			)
		)
		(duplicate_pad_numbers_are_jumpers no)
		(fp_line
			(start 0.7874 -0.4064)
			(end 0.7874 0.4064)
			(stroke
				(width 0.1524)
				(type default)
			)
			(layer "F.SilkS")
		)
		(fp_line
			(start -0.7874 -0.4064)
			(end 0.7874 -0.4064)
			(stroke
				(width 0.1524)
				(type default)
			)
			(layer "F.SilkS")
		)
		(fp_line
			(start 0.7874 0.4064)
			(end -0.7874 0.4064)
			(stroke
				(width 0.1524)
				(type default)
			)
			(layer "F.SilkS")
		)
		(fp_line
			(start -0.7874 0.4064)
			(end -0.7874 -0.4064)
			(stroke
				(width 0.1524)
				(type default)
			)
			(layer "F.SilkS")
		)
		(fp_line
			(start -0.12065 -0.305054)
			(end -0.12065 -0.2794)
			(stroke
				(width 0.1)
				(type default)
			)
			(layer "F.Fab")
		)
		(fp_line
			(start -0.67945 -0.305054)
			(end -0.12065 -0.305054)
			(stroke
				(width 0.1)
				(type default)
			)
			(layer "F.Fab")
		)
		(fp_line
			(start 0.67945 -0.3048)
			(end 0.67945 0.3048)
			(stroke
				(width 0.1)
				(type default)
			)
			(layer "F.Fab")
		)
		(fp_line
			(start 0.12065 -0.3048)
			(end 0.67945 -0.3048)
			(stroke
				(width 0.1)
				(type default)
			)
			(layer "F.Fab")
		)
		(fp_line
			(start 0.12065 -0.2794)
			(end 0.12065 -0.3048)
			(stroke
				(width 0.1)
				(type default)
			)
			(layer "F.Fab")
		)
		(fp_line
			(start -0.12065 -0.2794)
			(end 0.12065 -0.2794)
			(stroke
				(width 0.1)
				(type default)
			)
			(layer "F.Fab")
		)
		(fp_line
			(start 0.120396 0.2794)
			(end -0.12065 0.2794)
			(stroke
				(width 0.1)
				(type default)
			)
			(layer "F.Fab")
		)
		(fp_line
			(start -0.12065 0.2794)
			(end -0.12065 0.3048)
			(stroke
				(width 0.1)
				(type default)
			)
			(layer "F.Fab")
		)
		(fp_line
			(start 0.67945 0.3048)
			(end 0.120396 0.3048)
			(stroke
				(width 0.1)
				(type default)
			)
			(layer "F.Fab")
		)
		(fp_line
			(start 0.120396 0.3048)
			(end 0.120396 0.2794)
			(stroke
				(width 0.1)
				(type default)
			)
			(layer "F.Fab")
		)
		(fp_line
			(start -0.12065 0.3048)
			(end -0.67945 0.3048)
			(stroke
				(width 0.1)
				(type default)
			)
			(layer "F.Fab")
		)
		(fp_line
			(start -0.67945 0.3048)
			(end -0.67945 -0.305054)
			(stroke
				(width 0.1)
				(type default)
			)
			(layer "F.Fab")
		)
		(pad "1" smd circle
			(at -0.40005 0 90)
			(size 0 0)
			(layers "F.Cu" "F.Mask" "F.Paste")
			(net "VSENSE_PVDDCR_CPU1_P0_DP")
		)
		(pad "2" smd circle
			(at 0.40005 0 90)
			(size 0 0)
			(layers "F.Cu" "F.Mask" "F.Paste")
			(net "VSENSE_PVDDCR_CPU1_P0_VSEN0")
		)
	)
	(footprint ""
		(layer "F.Cu")
		(at 426.974 -421.64 90)
		(property "Reference" "R1483"
			(at 0 0 90)
			(layer "F.SilkS")
			(hide yes)
			(effects
				(font
					(size 1.27 1.27)
				)
			)
		)
		(property "Value" ""
			(at 0 0 90)
			(layer "F.Fab")
			(effects
				(font
					(size 1.27 1.27)
				)
			)
		)
		(duplicate_pad_numbers_are_jumpers no)
		(fp_line
			(start 0.32512 -0.175006)
			(end 0.32512 0.175006)
			(stroke
				(width 0.1)
				(type default)
			)
			(layer "F.Fab")
		)
		(fp_line
			(start -0.32512 -0.175006)
			(end 0.32512 -0.175006)
			(stroke
				(width 0.1)
				(type default)
			)
			(layer "F.Fab")
		)
		(fp_line
			(start 0.32512 0.175006)
			(end -0.32512 0.175006)
			(stroke
				(width 0.1)
				(type default)
			)
			(layer "F.Fab")
		)
		(fp_line
			(start -0.32512 0.175006)
			(end -0.32512 -0.175006)
			(stroke
				(width 0.1)
				(type default)
			)
			(layer "F.Fab")
		)
		(pad "1" smd rect
			(at -0.2667 0 90)
			(size 0.3048 0.381)
			(layers "F.Cu" "F.Mask" "F.Paste")
			(net "P1V8_CPU0_RT_1D")
		)
		(pad "2" smd rect
			(at 0.2667 0 270)
			(size 0.3048 0.381)
			(layers "F.Cu" "F.Mask" "F.Paste")
			(net "JTAG_TMS_RT_CPU0_P3")
		)
	)
	(footprint ""
		(layer "F.Cu")
		(at 162.052 -105.918 -90)
		(property "Reference" "R9025"
			(at 0 0 270)
			(layer "F.SilkS")
			(hide yes)
			(effects
				(font
					(size 1.27 1.27)
				)
			)
		)
		(property "Value" ""
			(at 0 0 270)
			(layer "F.Fab")
			(effects
				(font
					(size 1.27 1.27)
				)
			)
		)
		(duplicate_pad_numbers_are_jumpers no)
		(fp_line
			(start -0.7874 0.4064)
			(end -0.7874 -0.4064)
			(stroke
				(width 0.1524)
				(type default)
			)
			(layer "F.SilkS")
		)
		(fp_line
			(start 0.7874 0.4064)
			(end -0.7874 0.4064)
			(stroke
				(width 0.1524)
				(type default)
			)
			(layer "F.SilkS")
		)
		(fp_line
			(start -0.7874 -0.4064)
			(end 0.7874 -0.4064)
			(stroke
				(width 0.1524)
				(type default)
			)
			(layer "F.SilkS")
		)
		(fp_line
			(start 0.7874 -0.4064)
			(end 0.7874 0.4064)
			(stroke
				(width 0.1524)
				(type default)
			)
			(layer "F.SilkS")
		)
		(fp_line
			(start -0.67945 0.3048)
			(end -0.67945 -0.305054)
			(stroke
				(width 0.1)
				(type default)
			)
			(layer "F.Fab")
		)
		(fp_line
			(start -0.12065 0.3048)
			(end -0.67945 0.3048)
			(stroke
				(width 0.1)
				(type default)
			)
			(layer "F.Fab")
		)
		(fp_line
			(start 0.120396 0.3048)
			(end 0.120396 0.2794)
			(stroke
				(width 0.1)
				(type default)
			)
			(layer "F.Fab")
		)
		(fp_line
			(start 0.67945 0.3048)
			(end 0.120396 0.3048)
			(stroke
				(width 0.1)
				(type default)
			)
			(layer "F.Fab")
		)
		(fp_line
			(start -0.12065 0.2794)
			(end -0.12065 0.3048)
			(stroke
				(width 0.1)
				(type default)
			)
			(layer "F.Fab")
		)
		(fp_line
			(start 0.120396 0.2794)
			(end -0.12065 0.2794)
			(stroke
				(width 0.1)
				(type default)
			)
			(layer "F.Fab")
		)
		(fp_line
			(start -0.12065 -0.2794)
			(end 0.12065 -0.2794)
			(stroke
				(width 0.1)
				(type default)
			)
			(layer "F.Fab")
		)
		(fp_line
			(start 0.12065 -0.2794)
			(end 0.12065 -0.3048)
			(stroke
				(width 0.1)
				(type default)
			)
			(layer "F.Fab")
		)
		(fp_line
			(start 0.12065 -0.3048)
			(end 0.67945 -0.3048)
			(stroke
				(width 0.1)
				(type default)
			)
			(layer "F.Fab")
		)
		(fp_line
			(start 0.67945 -0.3048)
			(end 0.67945 0.3048)
			(stroke
				(width 0.1)
				(type default)
			)
			(layer "F.Fab")
		)
		(fp_line
			(start -0.67945 -0.305054)
			(end -0.12065 -0.305054)
			(stroke
				(width 0.1)
				(type default)
			)
			(layer "F.Fab")
		)
		(fp_line
			(start -0.12065 -0.305054)
			(end -0.12065 -0.2794)
			(stroke
				(width 0.1)
				(type default)
			)
			(layer "F.Fab")
		)
		(pad "1" smd circle
			(at -0.40005 0 270)
			(size 0 0)
			(layers "F.Cu" "F.Mask" "F.Paste")
			(net "IRQ_HSC_FAULT_N")
		)
		(pad "2" smd circle
			(at 0.40005 0 270)
			(size 0 0)
			(layers "F.Cu" "F.Mask" "F.Paste")
			(net "GND")
		)
	)
	(footprint ""
		(layer "F.Cu")
		(at 148.494242 -107.683046)
		(property "Reference" "R334"
			(at 0 0 0)
			(layer "F.SilkS")
			(hide yes)
			(effects
				(font
					(size 1.27 1.27)
				)
			)
		)
		(property "Value" ""
			(at 0 0 0)
			(layer "F.Fab")
			(effects
				(font
					(size 1.27 1.27)
				)
			)
		)
		(duplicate_pad_numbers_are_jumpers no)
		(fp_line
			(start -0.7874 -0.4064)
			(end 0.7874 -0.4064)
			(stroke
				(width 0.1524)
				(type default)
			)
			(layer "F.SilkS")
		)
		(fp_line
			(start -0.7874 0.4064)
			(end -0.7874 -0.4064)
			(stroke
				(width 0.1524)
				(type default)
			)
			(layer "F.SilkS")
		)
		(fp_line
			(start 0.7874 -0.4064)
			(end 0.7874 0.4064)
			(stroke
				(width 0.1524)
				(type default)
			)
			(layer "F.SilkS")
		)
		(fp_line
			(start 0.7874 0.4064)
			(end -0.7874 0.4064)
			(stroke
				(width 0.1524)
				(type default)
			)
			(layer "F.SilkS")
		)
		(fp_line
			(start -0.67945 -0.305054)
			(end -0.12065 -0.305054)
			(stroke
				(width 0.1)
				(type default)
			)
			(layer "F.Fab")
		)
		(fp_line
			(start -0.67945 0.3048)
			(end -0.67945 -0.305054)
			(stroke
				(width 0.1)
				(type default)
			)
			(layer "F.Fab")
		)
		(fp_line
			(start -0.12065 -0.305054)
			(end -0.12065 -0.2794)
			(stroke
				(width 0.1)
				(type default)
			)
			(layer "F.Fab")
		)
		(fp_line
			(start -0.12065 -0.2794)
			(end 0.12065 -0.2794)
			(stroke
				(width 0.1)
				(type default)
			)
			(layer "F.Fab")
		)
		(fp_line
			(start -0.12065 0.2794)
			(end -0.12065 0.3048)
			(stroke
				(width 0.1)
				(type default)
			)
			(layer "F.Fab")
		)
		(fp_line
			(start -0.12065 0.3048)
			(end -0.67945 0.3048)
			(stroke
				(width 0.1)
				(type default)
			)
			(layer "F.Fab")
		)
		(fp_line
			(start 0.120396 0.2794)
			(end -0.12065 0.2794)
			(stroke
				(width 0.1)
				(type default)
			)
			(layer "F.Fab")
		)
		(fp_line
			(start 0.120396 0.3048)
			(end 0.120396 0.2794)
			(stroke
				(width 0.1)
				(type default)
			)
			(layer "F.Fab")
		)
		(fp_line
			(start 0.12065 -0.3048)
			(end 0.67945 -0.3048)
			(stroke
				(width 0.1)
				(type default)
			)
			(layer "F.Fab")
		)
		(fp_line
			(start 0.12065 -0.2794)
			(end 0.12065 -0.3048)
			(stroke
				(width 0.1)
				(type default)
			)
			(layer "F.Fab")
		)
		(fp_line
			(start 0.67945 -0.3048)
			(end 0.67945 0.3048)
			(stroke
				(width 0.1)
				(type default)
			)
			(layer "F.Fab")
		)
		(fp_line
			(start 0.67945 0.3048)
			(end 0.120396 0.3048)
			(stroke
				(width 0.1)
				(type default)
			)
			(layer "F.Fab")
		)
		(pad "1" smd circle
			(at -0.40005 0)
			(size 0 0)
			(layers "F.Cu" "F.Mask" "F.Paste")
			(net "VR_P5V_EN")
		)
		(pad "2" smd circle
			(at 0.40005 0)
			(size 0 0)
			(layers "F.Cu" "F.Mask" "F.Paste")
			(net "GND")
		)
	)
	(footprint ""
		(layer "F.Cu")
		(at 160.856422 -20.068794 -90)
		(property "Reference" "C2078"
			(at 0 0 270)
			(layer "F.SilkS")
			(hide yes)
			(effects
				(font
					(size 1.27 1.27)
				)
			)
		)
		(property "Value" ""
			(at 0 0 270)
			(layer "F.Fab")
			(effects
				(font
					(size 1.27 1.27)
				)
			)
		)
		(duplicate_pad_numbers_are_jumpers no)
		(fp_line
			(start -0.299974 0.150114)
			(end -0.299974 -0.150114)
			(stroke
				(width 0.1)
				(type default)
			)
			(layer "F.Fab")
		)
		(fp_line
			(start 0.299974 0.150114)
			(end -0.299974 0.150114)
			(stroke
				(width 0.1)
				(type default)
			)
			(layer "F.Fab")
		)
		(fp_line
			(start -0.299974 -0.150114)
			(end 0.299974 -0.150114)
			(stroke
				(width 0.1)
				(type default)
			)
			(layer "F.Fab")
		)
		(fp_line
			(start 0.299974 -0.150114)
			(end 0.299974 0.150114)
			(stroke
				(width 0.1)
				(type default)
			)
			(layer "F.Fab")
		)
		(pad "1" smd rect
			(at -0.2667 0 270)
			(size 0.3048 0.381)
			(layers "F.Cu" "F.Mask" "F.Paste")
			(net "P2E_CPU0_P5_TX_DN")
		)
		(pad "2" smd rect
			(at 0.2667 0 270)
			(size 0.3048 0.381)
			(layers "F.Cu" "F.Mask" "F.Paste")
			(net "P2E_CPU0_P5_TX_C_DN")
		)
	)
	(footprint ""
		(layer "F.Cu")
		(at 37.41166 -125.38202 -90)
		(property "Reference" "R1480"
			(at -0.17526 -2.686812 90)
			(unlocked yes)
			(layer "F.SilkS")
			(effects
				(font
					(size 0.7874 0.5842)
					(thickness 0.1524)
				)
				(justify left)
			)
		)
		(property "Value" ""
			(at 0 0 270)
			(layer "F.Fab")
			(effects
				(font
					(size 1.27 1.27)
				)
			)
		)
		(duplicate_pad_numbers_are_jumpers no)
		(fp_line
			(start -4.18973 1.700022)
			(end 4.18973 1.700022)
			(stroke
				(width 0.1524)
				(type default)
			)
			(layer "F.SilkS")
		)
		(fp_line
			(start 4.18973 1.700022)
			(end 4.18973 -1.700022)
			(stroke
				(width 0.1524)
				(type default)
			)
			(layer "F.SilkS")
		)
		(fp_line
			(start -4.18973 -1.700022)
			(end -4.18973 1.700022)
			(stroke
				(width 0.1524)
				(type default)
			)
			(layer "F.SilkS")
		)
		(fp_line
			(start 4.18973 -1.700022)
			(end -4.18973 -1.700022)
			(stroke
				(width 0.1524)
				(type default)
			)
			(layer "F.SilkS")
		)
		(fp_line
			(start -3.24993 1.700022)
			(end 3.24993 1.700022)
			(stroke
				(width 0.1)
				(type default)
			)
			(layer "F.Fab")
		)
		(fp_line
			(start 3.24993 1.700022)
			(end 3.24993 -1.700022)
			(stroke
				(width 0.1)
				(type default)
			)
			(layer "F.Fab")
		)
		(fp_line
			(start -3.24993 -1.700022)
			(end -3.24993 1.700022)
			(stroke
				(width 0.1)
				(type default)
			)
			(layer "F.Fab")
		)
		(fp_line
			(start 3.24993 -1.700022)
			(end -3.24993 -1.700022)
			(stroke
				(width 0.1)
				(type default)
			)
			(layer "F.Fab")
		)
		(pad "1" smd rect
			(at -2.975102 0 270)
			(size 2.159 2.921)
			(layers "F.Cu" "F.Mask" "F.Paste")
			(net "P12V_AUX")
		)
		(pad "2" smd rect
			(at 2.975102 0 270)
			(size 2.159 2.921)
			(layers "F.Cu" "F.Mask" "F.Paste")
			(net "P12V_AUX_DSC")
		)
	)
	(footprint ""
		(layer "F.Cu")
		(at 29.045662 -425.275502)
		(property "Reference" "R3283"
			(at 0 0 0)
			(layer "F.SilkS")
			(hide yes)
			(effects
				(font
					(size 1.27 1.27)
				)
			)
		)
		(property "Value" ""
			(at 0 0 0)
			(layer "F.Fab")
			(effects
				(font
					(size 1.27 1.27)
				)
			)
		)
		(duplicate_pad_numbers_are_jumpers no)
		(fp_line
			(start -0.7874 -0.4064)
			(end 0.7874 -0.4064)
			(stroke
				(width 0.1524)
				(type default)
			)
			(layer "F.SilkS")
		)
		(fp_line
			(start -0.7874 0.4064)
			(end -0.7874 -0.4064)
			(stroke
				(width 0.1524)
				(type default)
			)
			(layer "F.SilkS")
		)
		(fp_line
			(start 0.7874 -0.4064)
			(end 0.7874 0.4064)
			(stroke
				(width 0.1524)
				(type default)
			)
			(layer "F.SilkS")
		)
		(fp_line
			(start 0.7874 0.4064)
			(end -0.7874 0.4064)
			(stroke
				(width 0.1524)
				(type default)
			)
			(layer "F.SilkS")
		)
		(fp_line
			(start -0.67945 -0.305054)
			(end -0.12065 -0.305054)
			(stroke
				(width 0.1)
				(type default)
			)
			(layer "F.Fab")
		)
		(fp_line
			(start -0.67945 0.3048)
			(end -0.67945 -0.305054)
			(stroke
				(width 0.1)
				(type default)
			)
			(layer "F.Fab")
		)
		(fp_line
			(start -0.12065 -0.305054)
			(end -0.12065 -0.2794)
			(stroke
				(width 0.1)
				(type default)
			)
			(layer "F.Fab")
		)
		(fp_line
			(start -0.12065 -0.2794)
			(end 0.12065 -0.2794)
			(stroke
				(width 0.1)
				(type default)
			)
			(layer "F.Fab")
		)
		(fp_line
			(start -0.12065 0.2794)
			(end -0.12065 0.3048)
			(stroke
				(width 0.1)
				(type default)
			)
			(layer "F.Fab")
		)
		(fp_line
			(start -0.12065 0.3048)
			(end -0.67945 0.3048)
			(stroke
				(width 0.1)
				(type default)
			)
			(layer "F.Fab")
		)
		(fp_line
			(start 0.120396 0.2794)
			(end -0.12065 0.2794)
			(stroke
				(width 0.1)
				(type default)
			)
			(layer "F.Fab")
		)
		(fp_line
			(start 0.120396 0.3048)
			(end 0.120396 0.2794)
			(stroke
				(width 0.1)
				(type default)
			)
			(layer "F.Fab")
		)
		(fp_line
			(start 0.12065 -0.3048)
			(end 0.67945 -0.3048)
			(stroke
				(width 0.1)
				(type default)
			)
			(layer "F.Fab")
		)
		(fp_line
			(start 0.12065 -0.2794)
			(end 0.12065 -0.3048)
			(stroke
				(width 0.1)
				(type default)
			)
			(layer "F.Fab")
		)
		(fp_line
			(start 0.67945 -0.3048)
			(end 0.67945 0.3048)
			(stroke
				(width 0.1)
				(type default)
			)
			(layer "F.Fab")
		)
		(fp_line
			(start 0.67945 0.3048)
			(end 0.120396 0.3048)
			(stroke
				(width 0.1)
				(type default)
			)
			(layer "F.Fab")
		)
		(pad "1" smd circle
			(at -0.40005 0)
			(size 0 0)
			(layers "F.Cu" "F.Mask" "F.Paste")
			(net "P3V3_AUX")
		)
		(pad "2" smd circle
			(at 0.40005 0)
			(size 0 0)
			(layers "F.Cu" "F.Mask" "F.Paste")
			(net "FM_P2E_EQB0")
		)
	)
	(footprint ""
		(layer "F.Cu")
		(at 70.346824 -19.929094 180)
		(property "Reference" "C1112"
			(at 0 0 180)
			(layer "F.SilkS")
			(hide yes)
			(effects
				(font
					(size 1.27 1.27)
				)
			)
		)
		(property "Value" ""
			(at 0 0 180)
			(layer "F.Fab")
			(effects
				(font
					(size 1.27 1.27)
				)
			)
		)
		(duplicate_pad_numbers_are_jumpers no)
		(fp_line
			(start 0.7874 0.4064)
			(end -0.7874 0.4064)
			(stroke
				(width 0.1524)
				(type default)
			)
			(layer "F.SilkS")
		)
		(fp_line
			(start 0.7874 -0.4064)
			(end 0.7874 0.4064)
			(stroke
				(width 0.1524)
				(type default)
			)
			(layer "F.SilkS")
		)
		(fp_line
			(start -0.7874 0.4064)
			(end -0.7874 -0.4064)
			(stroke
				(width 0.1524)
				(type default)
			)
			(layer "F.SilkS")
		)
		(fp_line
			(start -0.7874 -0.4064)
			(end 0.7874 -0.4064)
			(stroke
				(width 0.1524)
				(type default)
			)
			(layer "F.SilkS")
		)
		(fp_line
			(start 0.67945 0.3048)
			(end 0.120396 0.3048)
			(stroke
				(width 0.1)
				(type default)
			)
			(layer "F.Fab")
		)
		(fp_line
			(start 0.67945 -0.3048)
			(end 0.67945 0.3048)
			(stroke
				(width 0.1)
				(type default)
			)
			(layer "F.Fab")
		)
		(fp_line
			(start 0.12065 -0.2794)
			(end 0.12065 -0.3048)
			(stroke
				(width 0.1)
				(type default)
			)
			(layer "F.Fab")
		)
		(fp_line
			(start 0.12065 -0.3048)
			(end 0.67945 -0.3048)
			(stroke
				(width 0.1)
				(type default)
			)
			(layer "F.Fab")
		)
		(fp_line
			(start 0.120396 0.3048)
			(end 0.120396 0.2794)
			(stroke
				(width 0.1)
				(type default)
			)
			(layer "F.Fab")
		)
		(fp_line
			(start 0.120396 0.2794)
			(end -0.12065 0.2794)
			(stroke
				(width 0.1)
				(type default)
			)
			(layer "F.Fab")
		)
		(fp_line
			(start -0.12065 0.3048)
			(end -0.67945 0.3048)
			(stroke
				(width 0.1)
				(type default)
			)
			(layer "F.Fab")
		)
		(fp_line
			(start -0.12065 0.2794)
			(end -0.12065 0.3048)
			(stroke
				(width 0.1)
				(type default)
			)
			(layer "F.Fab")
		)
		(fp_line
			(start -0.12065 -0.2794)
			(end 0.12065 -0.2794)
			(stroke
				(width 0.1)
				(type default)
			)
			(layer "F.Fab")
		)
		(fp_line
			(start -0.12065 -0.305054)
			(end -0.12065 -0.2794)
			(stroke
				(width 0.1)
				(type default)
			)
			(layer "F.Fab")
		)
		(fp_line
			(start -0.67945 0.3048)
			(end -0.67945 -0.305054)
			(stroke
				(width 0.1)
				(type default)
			)
			(layer "F.Fab")
		)
		(fp_line
			(start -0.67945 -0.305054)
			(end -0.12065 -0.305054)
			(stroke
				(width 0.1)
				(type default)
			)
			(layer "F.Fab")
		)
		(pad "1" smd circle
			(at -0.40005 0 180)
			(size 0 0)
			(layers "F.Cu" "F.Mask" "F.Paste")
			(net "VSENSE_P12V_INA230_7_INP")
		)
		(pad "2" smd circle
			(at 0.40005 0 180)
			(size 0 0)
			(layers "F.Cu" "F.Mask" "F.Paste")
			(net "VSENSE_P12V_INA230_7_INN")
		)
	)
	(footprint ""
		(layer "F.Cu")
		(at 99.822 -79.121)
		(property "Reference" "C1061"
			(at 0 0 0)
			(layer "F.SilkS")
			(hide yes)
			(effects
				(font
					(size 1.27 1.27)
				)
			)
		)
		(property "Value" ""
			(at 0 0 0)
			(layer "F.Fab")
			(effects
				(font
					(size 1.27 1.27)
				)
			)
		)
		(duplicate_pad_numbers_are_jumpers no)
		(fp_line
			(start -0.7874 -0.4064)
			(end 0.7874 -0.4064)
			(stroke
				(width 0.1524)
				(type default)
			)
			(layer "F.SilkS")
		)
		(fp_line
			(start -0.7874 0.4064)
			(end -0.7874 -0.4064)
			(stroke
				(width 0.1524)
				(type default)
			)
			(layer "F.SilkS")
		)
		(fp_line
			(start 0.7874 -0.4064)
			(end 0.7874 0.4064)
			(stroke
				(width 0.1524)
				(type default)
			)
			(layer "F.SilkS")
		)
		(fp_line
			(start 0.7874 0.4064)
			(end -0.7874 0.4064)
			(stroke
				(width 0.1524)
				(type default)
			)
			(layer "F.SilkS")
		)
		(fp_line
			(start -0.67945 -0.305054)
			(end -0.12065 -0.305054)
			(stroke
				(width 0.1)
				(type default)
			)
			(layer "F.Fab")
		)
		(fp_line
			(start -0.67945 0.3048)
			(end -0.67945 -0.305054)
			(stroke
				(width 0.1)
				(type default)
			)
			(layer "F.Fab")
		)
		(fp_line
			(start -0.12065 -0.305054)
			(end -0.12065 -0.2794)
			(stroke
				(width 0.1)
				(type default)
			)
			(layer "F.Fab")
		)
		(fp_line
			(start -0.12065 -0.2794)
			(end 0.12065 -0.2794)
			(stroke
				(width 0.1)
				(type default)
			)
			(layer "F.Fab")
		)
		(fp_line
			(start -0.12065 0.2794)
			(end -0.12065 0.3048)
			(stroke
				(width 0.1)
				(type default)
			)
			(layer "F.Fab")
		)
		(fp_line
			(start -0.12065 0.3048)
			(end -0.67945 0.3048)
			(stroke
				(width 0.1)
				(type default)
			)
			(layer "F.Fab")
		)
		(fp_line
			(start 0.120396 0.2794)
			(end -0.12065 0.2794)
			(stroke
				(width 0.1)
				(type default)
			)
			(layer "F.Fab")
		)
		(fp_line
			(start 0.120396 0.3048)
			(end 0.120396 0.2794)
			(stroke
				(width 0.1)
				(type default)
			)
			(layer "F.Fab")
		)
		(fp_line
			(start 0.12065 -0.3048)
			(end 0.67945 -0.3048)
			(stroke
				(width 0.1)
				(type default)
			)
			(layer "F.Fab")
		)
		(fp_line
			(start 0.12065 -0.2794)
			(end 0.12065 -0.3048)
			(stroke
				(width 0.1)
				(type default)
			)
			(layer "F.Fab")
		)
		(fp_line
			(start 0.67945 -0.3048)
			(end 0.67945 0.3048)
			(stroke
				(width 0.1)
				(type default)
			)
			(layer "F.Fab")
		)
		(fp_line
			(start 0.67945 0.3048)
			(end 0.120396 0.3048)
			(stroke
				(width 0.1)
				(type default)
			)
			(layer "F.Fab")
		)
		(pad "1" smd circle
			(at -0.40005 0)
			(size 0 0)
			(layers "F.Cu" "F.Mask" "F.Paste")
			(net "P3V3_AUX")
		)
		(pad "2" smd circle
			(at 0.40005 0)
			(size 0 0)
			(layers "F.Cu" "F.Mask" "F.Paste")
			(net "GND")
		)
	)
	(footprint ""
		(layer "F.Cu")
		(at 41.5544 -389.8392 180)
		(property "Reference" "R6709"
			(at 0 0 180)
			(layer "F.SilkS")
			(hide yes)
			(effects
				(font
					(size 1.27 1.27)
				)
			)
		)
		(property "Value" ""
			(at 0 0 180)
			(layer "F.Fab")
			(effects
				(font
					(size 1.27 1.27)
				)
			)
		)
		(duplicate_pad_numbers_are_jumpers no)
		(fp_line
			(start 0.32512 0.175006)
			(end -0.32512 0.175006)
			(stroke
				(width 0.1)
				(type default)
			)
			(layer "F.Fab")
		)
		(fp_line
			(start 0.32512 -0.175006)
			(end 0.32512 0.175006)
			(stroke
				(width 0.1)
				(type default)
			)
			(layer "F.Fab")
		)
		(fp_line
			(start -0.32512 0.175006)
			(end -0.32512 -0.175006)
			(stroke
				(width 0.1)
				(type default)
			)
			(layer "F.Fab")
		)
		(fp_line
			(start -0.32512 -0.175006)
			(end 0.32512 -0.175006)
			(stroke
				(width 0.1)
				(type default)
			)
			(layer "F.Fab")
		)
		(pad "1" smd rect
			(at -0.2667 0 180)
			(size 0.3048 0.381)
			(layers "F.Cu" "F.Mask" "F.Paste")
			(net "RST_RT_CPU1_P0_RESET_N")
		)
		(pad "2" smd rect
			(at 0.2667 0)
			(size 0.3048 0.381)
			(layers "F.Cu" "F.Mask" "F.Paste")
			(net "RST_RT_CPU1_P0_RESET_R_N")
		)
	)
	(footprint ""
		(layer "F.Cu")
		(at 449.561712 -423.413936)
		(property "Reference" "PC6607"
			(at 0 0 0)
			(layer "F.SilkS")
			(hide yes)
			(effects
				(font
					(size 1.27 1.27)
				)
			)
		)
		(property "Value" ""
			(at 0 0 0)
			(layer "F.Fab")
			(effects
				(font
					(size 1.27 1.27)
				)
			)
		)
		(duplicate_pad_numbers_are_jumpers no)
		(fp_line
			(start -0.7874 -0.4064)
			(end 0.7874 -0.4064)
			(stroke
				(width 0.1524)
				(type default)
			)
			(layer "F.SilkS")
		)
		(fp_line
			(start -0.7874 0.4064)
			(end -0.7874 -0.4064)
			(stroke
				(width 0.1524)
				(type default)
			)
			(layer "F.SilkS")
		)
		(fp_line
			(start 0.7874 -0.4064)
			(end 0.7874 0.4064)
			(stroke
				(width 0.1524)
				(type default)
			)
			(layer "F.SilkS")
		)
		(fp_line
			(start 0.7874 0.4064)
			(end -0.7874 0.4064)
			(stroke
				(width 0.1524)
				(type default)
			)
			(layer "F.SilkS")
		)
		(fp_line
			(start -0.67945 -0.305054)
			(end -0.12065 -0.305054)
			(stroke
				(width 0.1)
				(type default)
			)
			(layer "F.Fab")
		)
		(fp_line
			(start -0.67945 0.3048)
			(end -0.67945 -0.305054)
			(stroke
				(width 0.1)
				(type default)
			)
			(layer "F.Fab")
		)
		(fp_line
			(start -0.12065 -0.305054)
			(end -0.12065 -0.2794)
			(stroke
				(width 0.1)
				(type default)
			)
			(layer "F.Fab")
		)
		(fp_line
			(start -0.12065 -0.2794)
			(end 0.12065 -0.2794)
			(stroke
				(width 0.1)
				(type default)
			)
			(layer "F.Fab")
		)
		(fp_line
			(start -0.12065 0.2794)
			(end -0.12065 0.3048)
			(stroke
				(width 0.1)
				(type default)
			)
			(layer "F.Fab")
		)
		(fp_line
			(start -0.12065 0.3048)
			(end -0.67945 0.3048)
			(stroke
				(width 0.1)
				(type default)
			)
			(layer "F.Fab")
		)
		(fp_line
			(start 0.120396 0.2794)
			(end -0.12065 0.2794)
			(stroke
				(width 0.1)
				(type default)
			)
			(layer "F.Fab")
		)
		(fp_line
			(start 0.120396 0.3048)
			(end 0.120396 0.2794)
			(stroke
				(width 0.1)
				(type default)
			)
			(layer "F.Fab")
		)
		(fp_line
			(start 0.12065 -0.3048)
			(end 0.67945 -0.3048)
			(stroke
				(width 0.1)
				(type default)
			)
			(layer "F.Fab")
		)
		(fp_line
			(start 0.12065 -0.2794)
			(end 0.12065 -0.3048)
			(stroke
				(width 0.1)
				(type default)
			)
			(layer "F.Fab")
		)
		(fp_line
			(start 0.67945 -0.3048)
			(end 0.67945 0.3048)
			(stroke
				(width 0.1)
				(type default)
			)
			(layer "F.Fab")
		)
		(fp_line
			(start 0.67945 0.3048)
			(end 0.120396 0.3048)
			(stroke
				(width 0.1)
				(type default)
			)
			(layer "F.Fab")
		)
		(pad "1" smd circle
			(at -0.40005 0)
			(size 0 0)
			(layers "F.Cu" "F.Mask" "F.Paste")
			(net "P0V9_RETIMER_CPU0_TEMP0")
		)
		(pad "2" smd circle
			(at 0.40005 0)
			(size 0 0)
			(layers "F.Cu" "F.Mask" "F.Paste")
			(net "GND")
		)
	)
	(footprint ""
		(layer "F.Cu")
		(at 94.36481 -182.677562 90)
		(property "Reference" "PC259_C0P1_2"
			(at 0 0 90)
			(layer "F.SilkS")
			(hide yes)
			(effects
				(font
					(size 1.27 1.27)
				)
			)
		)
		(property "Value" ""
			(at 0 0 90)
			(layer "F.Fab")
			(effects
				(font
					(size 1.27 1.27)
				)
			)
		)
		(duplicate_pad_numbers_are_jumpers no)
		(fp_line
			(start 0.7874 -0.4064)
			(end 0.7874 0.4064)
			(stroke
				(width 0.1524)
				(type default)
			)
			(layer "F.SilkS")
		)
		(fp_line
			(start -0.7874 -0.4064)
			(end 0.7874 -0.4064)
			(stroke
				(width 0.1524)
				(type default)
			)
			(layer "F.SilkS")
		)
		(fp_line
			(start 0.7874 0.4064)
			(end -0.7874 0.4064)
			(stroke
				(width 0.1524)
				(type default)
			)
			(layer "F.SilkS")
		)
		(fp_line
			(start -0.7874 0.4064)
			(end -0.7874 -0.4064)
			(stroke
				(width 0.1524)
				(type default)
			)
			(layer "F.SilkS")
		)
		(fp_line
			(start -0.12065 -0.305054)
			(end -0.12065 -0.2794)
			(stroke
				(width 0.1)
				(type default)
			)
			(layer "F.Fab")
		)
		(fp_line
			(start -0.67945 -0.305054)
			(end -0.12065 -0.305054)
			(stroke
				(width 0.1)
				(type default)
			)
			(layer "F.Fab")
		)
		(fp_line
			(start 0.67945 -0.3048)
			(end 0.67945 0.3048)
			(stroke
				(width 0.1)
				(type default)
			)
			(layer "F.Fab")
		)
		(fp_line
			(start 0.12065 -0.3048)
			(end 0.67945 -0.3048)
			(stroke
				(width 0.1)
				(type default)
			)
			(layer "F.Fab")
		)
		(fp_line
			(start 0.12065 -0.2794)
			(end 0.12065 -0.3048)
			(stroke
				(width 0.1)
				(type default)
			)
			(layer "F.Fab")
		)
		(fp_line
			(start -0.12065 -0.2794)
			(end 0.12065 -0.2794)
			(stroke
				(width 0.1)
				(type default)
			)
			(layer "F.Fab")
		)
		(fp_line
			(start 0.120396 0.2794)
			(end -0.12065 0.2794)
			(stroke
				(width 0.1)
				(type default)
			)
			(layer "F.Fab")
		)
		(fp_line
			(start -0.12065 0.2794)
			(end -0.12065 0.3048)
			(stroke
				(width 0.1)
				(type default)
			)
			(layer "F.Fab")
		)
		(fp_line
			(start 0.67945 0.3048)
			(end 0.120396 0.3048)
			(stroke
				(width 0.1)
				(type default)
			)
			(layer "F.Fab")
		)
		(fp_line
			(start 0.120396 0.3048)
			(end 0.120396 0.2794)
			(stroke
				(width 0.1)
				(type default)
			)
			(layer "F.Fab")
		)
		(fp_line
			(start -0.12065 0.3048)
			(end -0.67945 0.3048)
			(stroke
				(width 0.1)
				(type default)
			)
			(layer "F.Fab")
		)
		(fp_line
			(start -0.67945 0.3048)
			(end -0.67945 -0.305054)
			(stroke
				(width 0.1)
				(type default)
			)
			(layer "F.Fab")
		)
		(pad "1" smd circle
			(at -0.40005 0 90)
			(size 0 0)
			(layers "F.Cu" "F.Mask" "F.Paste")
			(net "PVDDCR_CPU0_P1_PVCC")
		)
		(pad "2" smd circle
			(at 0.40005 0 90)
			(size 0 0)
			(layers "F.Cu" "F.Mask" "F.Paste")
			(net "GND")
		)
	)
	(footprint ""
		(layer "F.Cu")
		(at 113.376964 -261.748016 -90)
		(property "Reference" "C2282"
			(at 0 0 270)
			(layer "F.SilkS")
			(hide yes)
			(effects
				(font
					(size 1.27 1.27)
				)
			)
		)
		(property "Value" ""
			(at 0 0 270)
			(layer "F.Fab")
			(effects
				(font
					(size 1.27 1.27)
				)
			)
		)
		(duplicate_pad_numbers_are_jumpers no)
		(fp_line
			(start -0.7874 0.4064)
			(end -0.7874 -0.4064)
			(stroke
				(width 0.1524)
				(type default)
			)
			(layer "F.SilkS")
		)
		(fp_line
			(start 0.7874 0.4064)
			(end -0.7874 0.4064)
			(stroke
				(width 0.1524)
				(type default)
			)
			(layer "F.SilkS")
		)
		(fp_line
			(start -0.7874 -0.4064)
			(end 0.7874 -0.4064)
			(stroke
				(width 0.1524)
				(type default)
			)
			(layer "F.SilkS")
		)
		(fp_line
			(start 0.7874 -0.4064)
			(end 0.7874 0.4064)
			(stroke
				(width 0.1524)
				(type default)
			)
			(layer "F.SilkS")
		)
		(fp_line
			(start -0.67945 0.3048)
			(end -0.67945 -0.305054)
			(stroke
				(width 0.1)
				(type default)
			)
			(layer "F.Fab")
		)
		(fp_line
			(start -0.12065 0.3048)
			(end -0.67945 0.3048)
			(stroke
				(width 0.1)
				(type default)
			)
			(layer "F.Fab")
		)
		(fp_line
			(start 0.120396 0.3048)
			(end 0.120396 0.2794)
			(stroke
				(width 0.1)
				(type default)
			)
			(layer "F.Fab")
		)
		(fp_line
			(start 0.67945 0.3048)
			(end 0.120396 0.3048)
			(stroke
				(width 0.1)
				(type default)
			)
			(layer "F.Fab")
		)
		(fp_line
			(start -0.12065 0.2794)
			(end -0.12065 0.3048)
			(stroke
				(width 0.1)
				(type default)
			)
			(layer "F.Fab")
		)
		(fp_line
			(start 0.120396 0.2794)
			(end -0.12065 0.2794)
			(stroke
				(width 0.1)
				(type default)
			)
			(layer "F.Fab")
		)
		(fp_line
			(start -0.12065 -0.2794)
			(end 0.12065 -0.2794)
			(stroke
				(width 0.1)
				(type default)
			)
			(layer "F.Fab")
		)
		(fp_line
			(start 0.12065 -0.2794)
			(end 0.12065 -0.3048)
			(stroke
				(width 0.1)
				(type default)
			)
			(layer "F.Fab")
		)
		(fp_line
			(start 0.12065 -0.3048)
			(end 0.67945 -0.3048)
			(stroke
				(width 0.1)
				(type default)
			)
			(layer "F.Fab")
		)
		(fp_line
			(start 0.67945 -0.3048)
			(end 0.67945 0.3048)
			(stroke
				(width 0.1)
				(type default)
			)
			(layer "F.Fab")
		)
		(fp_line
			(start -0.67945 -0.305054)
			(end -0.12065 -0.305054)
			(stroke
				(width 0.1)
				(type default)
			)
			(layer "F.Fab")
		)
		(fp_line
			(start -0.12065 -0.305054)
			(end -0.12065 -0.2794)
			(stroke
				(width 0.1)
				(type default)
			)
			(layer "F.Fab")
		)
		(pad "1" smd circle
			(at -0.40005 0 270)
			(size 0 0)
			(layers "F.Cu" "F.Mask" "F.Paste")
			(net "PVDD11_S3_P1")
		)
		(pad "2" smd circle
			(at 0.40005 0 270)
			(size 0 0)
			(layers "F.Cu" "F.Mask" "F.Paste")
			(net "GND")
		)
	)
	(footprint ""
		(layer "F.Cu")
		(at 178.71694 -397.388842 180)
		(property "Reference" "PC2193"
			(at 0 0 180)
			(layer "F.SilkS")
			(hide yes)
			(effects
				(font
					(size 1.27 1.27)
				)
			)
		)
		(property "Value" ""
			(at 0 0 180)
			(layer "F.Fab")
			(effects
				(font
					(size 1.27 1.27)
				)
			)
		)
		(duplicate_pad_numbers_are_jumpers no)
		(fp_line
			(start 0.7874 0.4064)
			(end -0.7874 0.4064)
			(stroke
				(width 0.1524)
				(type default)
			)
			(layer "F.SilkS")
		)
		(fp_line
			(start 0.7874 -0.4064)
			(end 0.7874 0.4064)
			(stroke
				(width 0.1524)
				(type default)
			)
			(layer "F.SilkS")
		)
		(fp_line
			(start -0.7874 0.4064)
			(end -0.7874 -0.4064)
			(stroke
				(width 0.1524)
				(type default)
			)
			(layer "F.SilkS")
		)
		(fp_line
			(start -0.7874 -0.4064)
			(end 0.7874 -0.4064)
			(stroke
				(width 0.1524)
				(type default)
			)
			(layer "F.SilkS")
		)
		(fp_line
			(start 0.67945 0.3048)
			(end 0.120396 0.3048)
			(stroke
				(width 0.1)
				(type default)
			)
			(layer "F.Fab")
		)
		(fp_line
			(start 0.67945 -0.3048)
			(end 0.67945 0.3048)
			(stroke
				(width 0.1)
				(type default)
			)
			(layer "F.Fab")
		)
		(fp_line
			(start 0.12065 -0.2794)
			(end 0.12065 -0.3048)
			(stroke
				(width 0.1)
				(type default)
			)
			(layer "F.Fab")
		)
		(fp_line
			(start 0.12065 -0.3048)
			(end 0.67945 -0.3048)
			(stroke
				(width 0.1)
				(type default)
			)
			(layer "F.Fab")
		)
		(fp_line
			(start 0.120396 0.3048)
			(end 0.120396 0.2794)
			(stroke
				(width 0.1)
				(type default)
			)
			(layer "F.Fab")
		)
		(fp_line
			(start 0.120396 0.2794)
			(end -0.12065 0.2794)
			(stroke
				(width 0.1)
				(type default)
			)
			(layer "F.Fab")
		)
		(fp_line
			(start -0.12065 0.3048)
			(end -0.67945 0.3048)
			(stroke
				(width 0.1)
				(type default)
			)
			(layer "F.Fab")
		)
		(fp_line
			(start -0.12065 0.2794)
			(end -0.12065 0.3048)
			(stroke
				(width 0.1)
				(type default)
			)
			(layer "F.Fab")
		)
		(fp_line
			(start -0.12065 -0.2794)
			(end 0.12065 -0.2794)
			(stroke
				(width 0.1)
				(type default)
			)
			(layer "F.Fab")
		)
		(fp_line
			(start -0.12065 -0.305054)
			(end -0.12065 -0.2794)
			(stroke
				(width 0.1)
				(type default)
			)
			(layer "F.Fab")
		)
		(fp_line
			(start -0.67945 0.3048)
			(end -0.67945 -0.305054)
			(stroke
				(width 0.1)
				(type default)
			)
			(layer "F.Fab")
		)
		(fp_line
			(start -0.67945 -0.305054)
			(end -0.12065 -0.305054)
			(stroke
				(width 0.1)
				(type default)
			)
			(layer "F.Fab")
		)
		(pad "1" smd circle
			(at -0.40005 0 180)
			(size 0 0)
			(layers "F.Cu" "F.Mask" "F.Paste")
			(net "HSC_IMON")
		)
		(pad "2" smd circle
			(at 0.40005 0 180)
			(size 0 0)
			(layers "F.Cu" "F.Mask" "F.Paste")
			(net "AGND_HSC")
		)
	)
	(footprint ""
		(layer "F.Cu")
		(at 286.571182 -13.373354)
		(property "Reference" "R4209"
			(at 0 0 0)
			(layer "F.SilkS")
			(hide yes)
			(effects
				(font
					(size 1.27 1.27)
				)
			)
		)
		(property "Value" ""
			(at 0 0 0)
			(layer "F.Fab")
			(effects
				(font
					(size 1.27 1.27)
				)
			)
		)
		(duplicate_pad_numbers_are_jumpers no)
		(fp_line
			(start -0.7874 -0.4064)
			(end 0.7874 -0.4064)
			(stroke
				(width 0.1524)
				(type default)
			)
			(layer "F.SilkS")
		)
		(fp_line
			(start -0.7874 0.4064)
			(end -0.7874 -0.4064)
			(stroke
				(width 0.1524)
				(type default)
			)
			(layer "F.SilkS")
		)
		(fp_line
			(start 0.7874 -0.4064)
			(end 0.7874 0.4064)
			(stroke
				(width 0.1524)
				(type default)
			)
			(layer "F.SilkS")
		)
		(fp_line
			(start 0.7874 0.4064)
			(end -0.7874 0.4064)
			(stroke
				(width 0.1524)
				(type default)
			)
			(layer "F.SilkS")
		)
		(fp_line
			(start -0.67945 -0.305054)
			(end -0.12065 -0.305054)
			(stroke
				(width 0.1)
				(type default)
			)
			(layer "F.Fab")
		)
		(fp_line
			(start -0.67945 0.3048)
			(end -0.67945 -0.305054)
			(stroke
				(width 0.1)
				(type default)
			)
			(layer "F.Fab")
		)
		(fp_line
			(start -0.12065 -0.305054)
			(end -0.12065 -0.2794)
			(stroke
				(width 0.1)
				(type default)
			)
			(layer "F.Fab")
		)
		(fp_line
			(start -0.12065 -0.2794)
			(end 0.12065 -0.2794)
			(stroke
				(width 0.1)
				(type default)
			)
			(layer "F.Fab")
		)
		(fp_line
			(start -0.12065 0.2794)
			(end -0.12065 0.3048)
			(stroke
				(width 0.1)
				(type default)
			)
			(layer "F.Fab")
		)
		(fp_line
			(start -0.12065 0.3048)
			(end -0.67945 0.3048)
			(stroke
				(width 0.1)
				(type default)
			)
			(layer "F.Fab")
		)
		(fp_line
			(start 0.120396 0.2794)
			(end -0.12065 0.2794)
			(stroke
				(width 0.1)
				(type default)
			)
			(layer "F.Fab")
		)
		(fp_line
			(start 0.120396 0.3048)
			(end 0.120396 0.2794)
			(stroke
				(width 0.1)
				(type default)
			)
			(layer "F.Fab")
		)
		(fp_line
			(start 0.12065 -0.3048)
			(end 0.67945 -0.3048)
			(stroke
				(width 0.1)
				(type default)
			)
			(layer "F.Fab")
		)
		(fp_line
			(start 0.12065 -0.2794)
			(end 0.12065 -0.3048)
			(stroke
				(width 0.1)
				(type default)
			)
			(layer "F.Fab")
		)
		(fp_line
			(start 0.67945 -0.3048)
			(end 0.67945 0.3048)
			(stroke
				(width 0.1)
				(type default)
			)
			(layer "F.Fab")
		)
		(fp_line
			(start 0.67945 0.3048)
			(end 0.120396 0.3048)
			(stroke
				(width 0.1)
				(type default)
			)
			(layer "F.Fab")
		)
		(pad "1" smd circle
			(at -0.40005 0)
			(size 0 0)
			(layers "F.Cu" "F.Mask" "F.Paste")
			(net "P3V3_AUX")
		)
		(pad "2" smd circle
			(at 0.40005 0)
			(size 0 0)
			(layers "F.Cu" "F.Mask" "F.Paste")
			(net "FM_THERMAL_ALERT_N")
		)
	)
	(footprint ""
		(layer "F.Cu")
		(at 413.303466 -150.858982 90)
		(property "Reference" "PL8065"
			(at 1.033018 -5.987796 90)
			(unlocked yes)
			(layer "F.SilkS")
			(effects
				(font
					(size 0.7874 0.5842)
					(thickness 0.1524)
				)
				(justify left)
			)
		)
		(property "Value" ""
			(at 0 0 90)
			(layer "F.Fab")
			(effects
				(font
					(size 1.27 1.27)
				)
			)
		)
		(duplicate_pad_numbers_are_jumpers no)
		(fp_line
			(start 5.588 -5.150104)
			(end -5.588 -5.150104)
			(stroke
				(width 0.1524)
				(type default)
			)
			(layer "F.SilkS")
		)
		(fp_line
			(start -5.588 -5.150104)
			(end -5.588 -1.8542)
			(stroke
				(width 0.1524)
				(type default)
			)
			(layer "F.SilkS")
		)
		(fp_line
			(start 5.588 -1.8288)
			(end 5.588 -5.150104)
			(stroke
				(width 0.1524)
				(type default)
			)
			(layer "F.SilkS")
		)
		(fp_line
			(start -5.588 1.8288)
			(end -5.588 5.150104)
			(stroke
				(width 0.1524)
				(type default)
			)
			(layer "F.SilkS")
		)
		(fp_line
			(start 5.588 5.150104)
			(end 5.588 1.8034)
			(stroke
				(width 0.1524)
				(type default)
			)
			(layer "F.SilkS")
		)
		(fp_line
			(start -5.588 5.150104)
			(end 5.588 5.150104)
			(stroke
				(width 0.1524)
				(type default)
			)
			(layer "F.SilkS")
		)
		(fp_line
			(start 5.599938 -5.150104)
			(end 5.599938 5.150104)
			(stroke
				(width 0.1)
				(type default)
			)
			(layer "F.Fab")
		)
		(fp_line
			(start -5.599938 -5.150104)
			(end 5.599938 -5.150104)
			(stroke
				(width 0.1)
				(type default)
			)
			(layer "F.Fab")
		)
		(fp_line
			(start 5.599938 5.150104)
			(end -5.599938 5.150104)
			(stroke
				(width 0.1)
				(type default)
			)
			(layer "F.Fab")
		)
		(fp_line
			(start -5.599938 5.150104)
			(end -5.599938 -5.150104)
			(stroke
				(width 0.1)
				(type default)
			)
			(layer "F.Fab")
		)
		(pad "1" smd rect
			(at -4.338828 0 90)
			(size 3.302 3.302)
			(layers "F.Cu" "F.Mask" "F.Paste")
			(net "SW_P5V_AUX_SW")
		)
		(pad "2" smd rect
			(at 4.338828 0 90)
			(size 3.302 3.302)
			(layers "F.Cu" "F.Mask" "F.Paste")
			(net "P5V_AUX")
		)
	)
	(footprint ""
		(layer "F.Cu")
		(at 315.802518 -360.289348)
		(property "Reference" "PC77"
			(at 0 0 0)
			(layer "F.SilkS")
			(hide yes)
			(effects
				(font
					(size 1.27 1.27)
				)
			)
		)
		(property "Value" ""
			(at 0 0 0)
			(layer "F.Fab")
			(effects
				(font
					(size 1.27 1.27)
				)
			)
		)
		(duplicate_pad_numbers_are_jumpers no)
		(fp_line
			(start -0.7874 -0.4064)
			(end 0.7874 -0.4064)
			(stroke
				(width 0.1524)
				(type default)
			)
			(layer "F.SilkS")
		)
		(fp_line
			(start -0.7874 0.4064)
			(end -0.7874 -0.4064)
			(stroke
				(width 0.1524)
				(type default)
			)
			(layer "F.SilkS")
		)
		(fp_line
			(start 0.7874 -0.4064)
			(end 0.7874 0.4064)
			(stroke
				(width 0.1524)
				(type default)
			)
			(layer "F.SilkS")
		)
		(fp_line
			(start 0.7874 0.4064)
			(end -0.7874 0.4064)
			(stroke
				(width 0.1524)
				(type default)
			)
			(layer "F.SilkS")
		)
		(fp_line
			(start -0.67945 -0.305054)
			(end -0.12065 -0.305054)
			(stroke
				(width 0.1)
				(type default)
			)
			(layer "F.Fab")
		)
		(fp_line
			(start -0.67945 0.3048)
			(end -0.67945 -0.305054)
			(stroke
				(width 0.1)
				(type default)
			)
			(layer "F.Fab")
		)
		(fp_line
			(start -0.12065 -0.305054)
			(end -0.12065 -0.2794)
			(stroke
				(width 0.1)
				(type default)
			)
			(layer "F.Fab")
		)
		(fp_line
			(start -0.12065 -0.2794)
			(end 0.12065 -0.2794)
			(stroke
				(width 0.1)
				(type default)
			)
			(layer "F.Fab")
		)
		(fp_line
			(start -0.12065 0.2794)
			(end -0.12065 0.3048)
			(stroke
				(width 0.1)
				(type default)
			)
			(layer "F.Fab")
		)
		(fp_line
			(start -0.12065 0.3048)
			(end -0.67945 0.3048)
			(stroke
				(width 0.1)
				(type default)
			)
			(layer "F.Fab")
		)
		(fp_line
			(start 0.120396 0.2794)
			(end -0.12065 0.2794)
			(stroke
				(width 0.1)
				(type default)
			)
			(layer "F.Fab")
		)
		(fp_line
			(start 0.120396 0.3048)
			(end 0.120396 0.2794)
			(stroke
				(width 0.1)
				(type default)
			)
			(layer "F.Fab")
		)
		(fp_line
			(start 0.12065 -0.3048)
			(end 0.67945 -0.3048)
			(stroke
				(width 0.1)
				(type default)
			)
			(layer "F.Fab")
		)
		(fp_line
			(start 0.12065 -0.2794)
			(end 0.12065 -0.3048)
			(stroke
				(width 0.1)
				(type default)
			)
			(layer "F.Fab")
		)
		(fp_line
			(start 0.67945 -0.3048)
			(end 0.67945 0.3048)
			(stroke
				(width 0.1)
				(type default)
			)
			(layer "F.Fab")
		)
		(fp_line
			(start 0.67945 0.3048)
			(end 0.120396 0.3048)
			(stroke
				(width 0.1)
				(type default)
			)
			(layer "F.Fab")
		)
		(pad "1" smd circle
			(at -0.40005 0)
			(size 0 0)
			(layers "F.Cu" "F.Mask" "F.Paste")
			(net "PVDDIO_P0_TEMP1")
		)
		(pad "2" smd circle
			(at 0.40005 0)
			(size 0 0)
			(layers "F.Cu" "F.Mask" "F.Paste")
			(net "GND")
		)
	)
	(footprint ""
		(layer "F.Cu")
		(at 185.039 -137.632948 90)
		(property "Reference" "R1557"
			(at 0 0 90)
			(layer "F.SilkS")
			(hide yes)
			(effects
				(font
					(size 1.27 1.27)
				)
			)
		)
		(property "Value" ""
			(at 0 0 90)
			(layer "F.Fab")
			(effects
				(font
					(size 1.27 1.27)
				)
			)
		)
		(duplicate_pad_numbers_are_jumpers no)
		(fp_line
			(start 0.7874 -0.4064)
			(end 0.7874 0.4064)
			(stroke
				(width 0.1524)
				(type default)
			)
			(layer "F.SilkS")
		)
		(fp_line
			(start -0.7874 -0.4064)
			(end 0.7874 -0.4064)
			(stroke
				(width 0.1524)
				(type default)
			)
			(layer "F.SilkS")
		)
		(fp_line
			(start 0.7874 0.4064)
			(end -0.7874 0.4064)
			(stroke
				(width 0.1524)
				(type default)
			)
			(layer "F.SilkS")
		)
		(fp_line
			(start -0.7874 0.4064)
			(end -0.7874 -0.4064)
			(stroke
				(width 0.1524)
				(type default)
			)
			(layer "F.SilkS")
		)
		(fp_line
			(start -0.12065 -0.305054)
			(end -0.12065 -0.2794)
			(stroke
				(width 0.1)
				(type default)
			)
			(layer "F.Fab")
		)
		(fp_line
			(start -0.67945 -0.305054)
			(end -0.12065 -0.305054)
			(stroke
				(width 0.1)
				(type default)
			)
			(layer "F.Fab")
		)
		(fp_line
			(start 0.67945 -0.3048)
			(end 0.67945 0.3048)
			(stroke
				(width 0.1)
				(type default)
			)
			(layer "F.Fab")
		)
		(fp_line
			(start 0.12065 -0.3048)
			(end 0.67945 -0.3048)
			(stroke
				(width 0.1)
				(type default)
			)
			(layer "F.Fab")
		)
		(fp_line
			(start 0.12065 -0.2794)
			(end 0.12065 -0.3048)
			(stroke
				(width 0.1)
				(type default)
			)
			(layer "F.Fab")
		)
		(fp_line
			(start -0.12065 -0.2794)
			(end 0.12065 -0.2794)
			(stroke
				(width 0.1)
				(type default)
			)
			(layer "F.Fab")
		)
		(fp_line
			(start 0.120396 0.2794)
			(end -0.12065 0.2794)
			(stroke
				(width 0.1)
				(type default)
			)
			(layer "F.Fab")
		)
		(fp_line
			(start -0.12065 0.2794)
			(end -0.12065 0.3048)
			(stroke
				(width 0.1)
				(type default)
			)
			(layer "F.Fab")
		)
		(fp_line
			(start 0.67945 0.3048)
			(end 0.120396 0.3048)
			(stroke
				(width 0.1)
				(type default)
			)
			(layer "F.Fab")
		)
		(fp_line
			(start 0.120396 0.3048)
			(end 0.120396 0.2794)
			(stroke
				(width 0.1)
				(type default)
			)
			(layer "F.Fab")
		)
		(fp_line
			(start -0.12065 0.3048)
			(end -0.67945 0.3048)
			(stroke
				(width 0.1)
				(type default)
			)
			(layer "F.Fab")
		)
		(fp_line
			(start -0.67945 0.3048)
			(end -0.67945 -0.305054)
			(stroke
				(width 0.1)
				(type default)
			)
			(layer "F.Fab")
		)
		(pad "1" smd circle
			(at -0.40005 0 90)
			(size 0 0)
			(layers "F.Cu" "F.Mask" "F.Paste")
			(net "ESPI_CPU0_ALERT_R_N")
		)
		(pad "2" smd circle
			(at 0.40005 0 90)
			(size 0 0)
			(layers "F.Cu" "F.Mask" "F.Paste")
			(net "ESPI_CPU0_ALERT_PLD_N")
		)
	)
	(footprint ""
		(layer "F.Cu")
		(at 109.577124 -261.748016 -90)
		(property "Reference" "C2121"
			(at 0 0 270)
			(layer "F.SilkS")
			(hide yes)
			(effects
				(font
					(size 1.27 1.27)
				)
			)
		)
		(property "Value" ""
			(at 0 0 270)
			(layer "F.Fab")
			(effects
				(font
					(size 1.27 1.27)
				)
			)
		)
		(duplicate_pad_numbers_are_jumpers no)
		(fp_line
			(start -0.7874 0.4064)
			(end -0.7874 -0.4064)
			(stroke
				(width 0.1524)
				(type default)
			)
			(layer "F.SilkS")
		)
		(fp_line
			(start 0.7874 0.4064)
			(end -0.7874 0.4064)
			(stroke
				(width 0.1524)
				(type default)
			)
			(layer "F.SilkS")
		)
		(fp_line
			(start -0.7874 -0.4064)
			(end 0.7874 -0.4064)
			(stroke
				(width 0.1524)
				(type default)
			)
			(layer "F.SilkS")
		)
		(fp_line
			(start 0.7874 -0.4064)
			(end 0.7874 0.4064)
			(stroke
				(width 0.1524)
				(type default)
			)
			(layer "F.SilkS")
		)
		(fp_line
			(start -0.67945 0.3048)
			(end -0.67945 -0.305054)
			(stroke
				(width 0.1)
				(type default)
			)
			(layer "F.Fab")
		)
		(fp_line
			(start -0.12065 0.3048)
			(end -0.67945 0.3048)
			(stroke
				(width 0.1)
				(type default)
			)
			(layer "F.Fab")
		)
		(fp_line
			(start 0.120396 0.3048)
			(end 0.120396 0.2794)
			(stroke
				(width 0.1)
				(type default)
			)
			(layer "F.Fab")
		)
		(fp_line
			(start 0.67945 0.3048)
			(end 0.120396 0.3048)
			(stroke
				(width 0.1)
				(type default)
			)
			(layer "F.Fab")
		)
		(fp_line
			(start -0.12065 0.2794)
			(end -0.12065 0.3048)
			(stroke
				(width 0.1)
				(type default)
			)
			(layer "F.Fab")
		)
		(fp_line
			(start 0.120396 0.2794)
			(end -0.12065 0.2794)
			(stroke
				(width 0.1)
				(type default)
			)
			(layer "F.Fab")
		)
		(fp_line
			(start -0.12065 -0.2794)
			(end 0.12065 -0.2794)
			(stroke
				(width 0.1)
				(type default)
			)
			(layer "F.Fab")
		)
		(fp_line
			(start 0.12065 -0.2794)
			(end 0.12065 -0.3048)
			(stroke
				(width 0.1)
				(type default)
			)
			(layer "F.Fab")
		)
		(fp_line
			(start 0.12065 -0.3048)
			(end 0.67945 -0.3048)
			(stroke
				(width 0.1)
				(type default)
			)
			(layer "F.Fab")
		)
		(fp_line
			(start 0.67945 -0.3048)
			(end 0.67945 0.3048)
			(stroke
				(width 0.1)
				(type default)
			)
			(layer "F.Fab")
		)
		(fp_line
			(start -0.67945 -0.305054)
			(end -0.12065 -0.305054)
			(stroke
				(width 0.1)
				(type default)
			)
			(layer "F.Fab")
		)
		(fp_line
			(start -0.12065 -0.305054)
			(end -0.12065 -0.2794)
			(stroke
				(width 0.1)
				(type default)
			)
			(layer "F.Fab")
		)
		(pad "1" smd circle
			(at -0.40005 0 270)
			(size 0 0)
			(layers "F.Cu" "F.Mask" "F.Paste")
			(net "PVDD11_S3_P1")
		)
		(pad "2" smd circle
			(at 0.40005 0 270)
			(size 0 0)
			(layers "F.Cu" "F.Mask" "F.Paste")
			(net "GND")
		)
	)
	(footprint ""
		(layer "F.Cu")
		(at 255.13284 -92.719144 -90)
		(property "Reference" "C1516"
			(at 0 0 270)
			(layer "F.SilkS")
			(hide yes)
			(effects
				(font
					(size 1.27 1.27)
				)
			)
		)
		(property "Value" ""
			(at 0 0 270)
			(layer "F.Fab")
			(effects
				(font
					(size 1.27 1.27)
				)
			)
		)
		(duplicate_pad_numbers_are_jumpers no)
		(fp_line
			(start -0.7874 0.4064)
			(end -0.7874 -0.4064)
			(stroke
				(width 0.1524)
				(type default)
			)
			(layer "F.SilkS")
		)
		(fp_line
			(start 0.7874 0.4064)
			(end -0.7874 0.4064)
			(stroke
				(width 0.1524)
				(type default)
			)
			(layer "F.SilkS")
		)
		(fp_line
			(start -0.7874 -0.4064)
			(end 0.7874 -0.4064)
			(stroke
				(width 0.1524)
				(type default)
			)
			(layer "F.SilkS")
		)
		(fp_line
			(start 0.7874 -0.4064)
			(end 0.7874 0.4064)
			(stroke
				(width 0.1524)
				(type default)
			)
			(layer "F.SilkS")
		)
		(fp_line
			(start -0.67945 0.3048)
			(end -0.67945 -0.305054)
			(stroke
				(width 0.1)
				(type default)
			)
			(layer "F.Fab")
		)
		(fp_line
			(start -0.12065 0.3048)
			(end -0.67945 0.3048)
			(stroke
				(width 0.1)
				(type default)
			)
			(layer "F.Fab")
		)
		(fp_line
			(start 0.120396 0.3048)
			(end 0.120396 0.2794)
			(stroke
				(width 0.1)
				(type default)
			)
			(layer "F.Fab")
		)
		(fp_line
			(start 0.67945 0.3048)
			(end 0.120396 0.3048)
			(stroke
				(width 0.1)
				(type default)
			)
			(layer "F.Fab")
		)
		(fp_line
			(start -0.12065 0.2794)
			(end -0.12065 0.3048)
			(stroke
				(width 0.1)
				(type default)
			)
			(layer "F.Fab")
		)
		(fp_line
			(start 0.120396 0.2794)
			(end -0.12065 0.2794)
			(stroke
				(width 0.1)
				(type default)
			)
			(layer "F.Fab")
		)
		(fp_line
			(start -0.12065 -0.2794)
			(end 0.12065 -0.2794)
			(stroke
				(width 0.1)
				(type default)
			)
			(layer "F.Fab")
		)
		(fp_line
			(start 0.12065 -0.2794)
			(end 0.12065 -0.3048)
			(stroke
				(width 0.1)
				(type default)
			)
			(layer "F.Fab")
		)
		(fp_line
			(start 0.12065 -0.3048)
			(end 0.67945 -0.3048)
			(stroke
				(width 0.1)
				(type default)
			)
			(layer "F.Fab")
		)
		(fp_line
			(start 0.67945 -0.3048)
			(end 0.67945 0.3048)
			(stroke
				(width 0.1)
				(type default)
			)
			(layer "F.Fab")
		)
		(fp_line
			(start -0.67945 -0.305054)
			(end -0.12065 -0.305054)
			(stroke
				(width 0.1)
				(type default)
			)
			(layer "F.Fab")
		)
		(fp_line
			(start -0.12065 -0.305054)
			(end -0.12065 -0.2794)
			(stroke
				(width 0.1)
				(type default)
			)
			(layer "F.Fab")
		)
		(pad "1" smd circle
			(at -0.40005 0 270)
			(size 0 0)
			(layers "F.Cu" "F.Mask" "F.Paste")
			(net "PVDD18_S5_P0")
		)
		(pad "2" smd circle
			(at 0.40005 0 270)
			(size 0 0)
			(layers "F.Cu" "F.Mask" "F.Paste")
			(net "GND")
		)
	)
	(footprint ""
		(layer "F.Cu")
		(at 326.967342 -391.0584 180)
		(property "Reference" "R968"
			(at 0 0 180)
			(layer "F.SilkS")
			(hide yes)
			(effects
				(font
					(size 1.27 1.27)
				)
			)
		)
		(property "Value" ""
			(at 0 0 180)
			(layer "F.Fab")
			(effects
				(font
					(size 1.27 1.27)
				)
			)
		)
		(duplicate_pad_numbers_are_jumpers no)
		(fp_line
			(start 0.32512 0.175006)
			(end -0.32512 0.175006)
			(stroke
				(width 0.1)
				(type default)
			)
			(layer "F.Fab")
		)
		(fp_line
			(start 0.32512 -0.175006)
			(end 0.32512 0.175006)
			(stroke
				(width 0.1)
				(type default)
			)
			(layer "F.Fab")
		)
		(fp_line
			(start -0.32512 0.175006)
			(end -0.32512 -0.175006)
			(stroke
				(width 0.1)
				(type default)
			)
			(layer "F.Fab")
		)
		(fp_line
			(start -0.32512 -0.175006)
			(end 0.32512 -0.175006)
			(stroke
				(width 0.1)
				(type default)
			)
			(layer "F.Fab")
		)
		(pad "1" smd rect
			(at -0.2667 0 180)
			(size 0.3048 0.381)
			(layers "F.Cu" "F.Mask" "F.Paste")
			(net "P1V8_CPU0_RT_1D")
		)
		(pad "2" smd rect
			(at 0.2667 0)
			(size 0.3048 0.381)
			(layers "F.Cu" "F.Mask" "F.Paste")
			(net "RT_CPU0_P0_ADDR1")
		)
	)
	(footprint ""
		(layer "F.Cu")
		(at 157.146244 -373.03583 -90)
		(property "Reference" "C756"
			(at 0 0 270)
			(layer "F.SilkS")
			(hide yes)
			(effects
				(font
					(size 1.27 1.27)
				)
			)
		)
		(property "Value" ""
			(at 0 0 270)
			(layer "F.Fab")
			(effects
				(font
					(size 1.27 1.27)
				)
			)
		)
		(duplicate_pad_numbers_are_jumpers no)
		(fp_line
			(start -0.299974 0.150114)
			(end -0.299974 -0.150114)
			(stroke
				(width 0.1)
				(type default)
			)
			(layer "F.Fab")
		)
		(fp_line
			(start 0.299974 0.150114)
			(end -0.299974 0.150114)
			(stroke
				(width 0.1)
				(type default)
			)
			(layer "F.Fab")
		)
		(fp_line
			(start -0.299974 -0.150114)
			(end 0.299974 -0.150114)
			(stroke
				(width 0.1)
				(type default)
			)
			(layer "F.Fab")
		)
		(fp_line
			(start 0.299974 -0.150114)
			(end 0.299974 0.150114)
			(stroke
				(width 0.1)
				(type default)
			)
			(layer "F.Fab")
		)
		(pad "1" smd rect
			(at -0.2667 0 270)
			(size 0.3048 0.381)
			(layers "F.Cu" "F.Mask" "F.Paste")
			(net "P5E_CPU1_P2_TX_C_DN<8>")
		)
		(pad "2" smd rect
			(at 0.2667 0 270)
			(size 0.3048 0.381)
			(layers "F.Cu" "F.Mask" "F.Paste")
			(net "P5E_CPU1_P2_TX_DN<8>")
		)
	)
	(footprint ""
		(layer "F.Cu")
		(at 375.369074 -177.88636 -90)
		(property "Reference" "PC474_2"
			(at 0 0 270)
			(layer "F.SilkS")
			(hide yes)
			(effects
				(font
					(size 1.27 1.27)
				)
			)
		)
		(property "Value" ""
			(at 0 0 270)
			(layer "F.Fab")
			(effects
				(font
					(size 1.27 1.27)
				)
			)
		)
		(duplicate_pad_numbers_are_jumpers no)
		(fp_line
			(start -0.7874 0.4064)
			(end -0.7874 -0.4064)
			(stroke
				(width 0.1524)
				(type default)
			)
			(layer "F.SilkS")
		)
		(fp_line
			(start 0.7874 0.4064)
			(end -0.7874 0.4064)
			(stroke
				(width 0.1524)
				(type default)
			)
			(layer "F.SilkS")
		)
		(fp_line
			(start -0.7874 -0.4064)
			(end 0.7874 -0.4064)
			(stroke
				(width 0.1524)
				(type default)
			)
			(layer "F.SilkS")
		)
		(fp_line
			(start 0.7874 -0.4064)
			(end 0.7874 0.4064)
			(stroke
				(width 0.1524)
				(type default)
			)
			(layer "F.SilkS")
		)
		(fp_line
			(start -0.67945 0.3048)
			(end -0.67945 -0.305054)
			(stroke
				(width 0.1)
				(type default)
			)
			(layer "F.Fab")
		)
		(fp_line
			(start -0.12065 0.3048)
			(end -0.67945 0.3048)
			(stroke
				(width 0.1)
				(type default)
			)
			(layer "F.Fab")
		)
		(fp_line
			(start 0.120396 0.3048)
			(end 0.120396 0.2794)
			(stroke
				(width 0.1)
				(type default)
			)
			(layer "F.Fab")
		)
		(fp_line
			(start 0.67945 0.3048)
			(end 0.120396 0.3048)
			(stroke
				(width 0.1)
				(type default)
			)
			(layer "F.Fab")
		)
		(fp_line
			(start -0.12065 0.2794)
			(end -0.12065 0.3048)
			(stroke
				(width 0.1)
				(type default)
			)
			(layer "F.Fab")
		)
		(fp_line
			(start 0.120396 0.2794)
			(end -0.12065 0.2794)
			(stroke
				(width 0.1)
				(type default)
			)
			(layer "F.Fab")
		)
		(fp_line
			(start -0.12065 -0.2794)
			(end 0.12065 -0.2794)
			(stroke
				(width 0.1)
				(type default)
			)
			(layer "F.Fab")
		)
		(fp_line
			(start 0.12065 -0.2794)
			(end 0.12065 -0.3048)
			(stroke
				(width 0.1)
				(type default)
			)
			(layer "F.Fab")
		)
		(fp_line
			(start 0.12065 -0.3048)
			(end 0.67945 -0.3048)
			(stroke
				(width 0.1)
				(type default)
			)
			(layer "F.Fab")
		)
		(fp_line
			(start 0.67945 -0.3048)
			(end 0.67945 0.3048)
			(stroke
				(width 0.1)
				(type default)
			)
			(layer "F.Fab")
		)
		(fp_line
			(start -0.67945 -0.305054)
			(end -0.12065 -0.305054)
			(stroke
				(width 0.1)
				(type default)
			)
			(layer "F.Fab")
		)
		(fp_line
			(start -0.12065 -0.305054)
			(end -0.12065 -0.2794)
			(stroke
				(width 0.1)
				(type default)
			)
			(layer "F.Fab")
		)
		(pad "1" smd circle
			(at -0.40005 0 270)
			(size 0 0)
			(layers "F.Cu" "F.Mask" "F.Paste")
			(net "PVDDCR_CPU0_P0_VCCS")
		)
		(pad "2" smd circle
			(at 0.40005 0 270)
			(size 0 0)
			(layers "F.Cu" "F.Mask" "F.Paste")
			(net "GND")
		)
	)
	(footprint ""
		(layer "F.Cu")
		(at 336.195416 -24.617172 -90)
		(property "Reference" "Q30"
			(at -2.829052 -0.126492 0)
			(unlocked yes)
			(layer "F.SilkS")
			(effects
				(font
					(size 0.7874 0.5842)
					(thickness 0.1524)
				)
			)
		)
		(property "Value" ""
			(at 0 0 270)
			(layer "F.Fab")
			(effects
				(font
					(size 1.27 1.27)
				)
			)
		)
		(duplicate_pad_numbers_are_jumpers no)
		(fp_line
			(start -1.8796 1.651)
			(end -1.8796 -1.651)
			(stroke
				(width 0.1524)
				(type default)
			)
			(layer "F.SilkS")
		)
		(fp_line
			(start 1.8796 1.651)
			(end -1.8796 1.651)
			(stroke
				(width 0.1524)
				(type default)
			)
			(layer "F.SilkS")
		)
		(fp_line
			(start -1.8796 -1.651)
			(end 1.8796 -1.651)
			(stroke
				(width 0.1524)
				(type default)
			)
			(layer "F.SilkS")
		)
		(fp_line
			(start 1.8796 -1.651)
			(end 1.8796 1.651)
			(stroke
				(width 0.1524)
				(type default)
			)
			(layer "F.SilkS")
		)
		(fp_line
			(start -0.700024 1.500124)
			(end -0.700024 -1.500124)
			(stroke
				(width 0.1)
				(type default)
			)
			(layer "F.Fab")
		)
		(fp_line
			(start 0.700024 1.500124)
			(end -0.700024 1.500124)
			(stroke
				(width 0.1)
				(type default)
			)
			(layer "F.Fab")
		)
		(fp_line
			(start -0.700024 -1.500124)
			(end 0.700024 -1.500124)
			(stroke
				(width 0.1)
				(type default)
			)
			(layer "F.Fab")
		)
		(fp_line
			(start 0.700024 -1.500124)
			(end 0.700024 1.500124)
			(stroke
				(width 0.1)
				(type default)
			)
			(layer "F.Fab")
		)
		(pad "D" smd rect
			(at 1.119886 0 180)
			(size 1.016 1.2192)
			(layers "F.Cu" "F.Mask" "F.Paste")
			(net "LED_BIOS_DBG_MODE_N")
		)
		(pad "G" smd rect
			(at -1.119886 -0.999998 180)
			(size 1.016 1.2192)
			(layers "F.Cu" "F.Mask" "F.Paste")
			(net "BIOS_DEBUG_MODE")
		)
		(pad "S" smd rect
			(at -1.119886 0.999998 180)
			(size 1.016 1.2192)
			(layers "F.Cu" "F.Mask" "F.Paste")
			(net "GND")
		)
	)
	(footprint ""
		(layer "F.Cu")
		(at 109.575854 -256.012442 90)
		(property "Reference" "C2410"
			(at 0 0 90)
			(layer "F.SilkS")
			(hide yes)
			(effects
				(font
					(size 1.27 1.27)
				)
			)
		)
		(property "Value" ""
			(at 0 0 90)
			(layer "F.Fab")
			(effects
				(font
					(size 1.27 1.27)
				)
			)
		)
		(duplicate_pad_numbers_are_jumpers no)
		(fp_line
			(start 0.7874 -0.4064)
			(end 0.7874 0.4064)
			(stroke
				(width 0.1524)
				(type default)
			)
			(layer "F.SilkS")
		)
		(fp_line
			(start -0.7874 -0.4064)
			(end 0.7874 -0.4064)
			(stroke
				(width 0.1524)
				(type default)
			)
			(layer "F.SilkS")
		)
		(fp_line
			(start 0.7874 0.4064)
			(end -0.7874 0.4064)
			(stroke
				(width 0.1524)
				(type default)
			)
			(layer "F.SilkS")
		)
		(fp_line
			(start -0.7874 0.4064)
			(end -0.7874 -0.4064)
			(stroke
				(width 0.1524)
				(type default)
			)
			(layer "F.SilkS")
		)
		(fp_line
			(start -0.12065 -0.305054)
			(end -0.12065 -0.2794)
			(stroke
				(width 0.1)
				(type default)
			)
			(layer "F.Fab")
		)
		(fp_line
			(start -0.67945 -0.305054)
			(end -0.12065 -0.305054)
			(stroke
				(width 0.1)
				(type default)
			)
			(layer "F.Fab")
		)
		(fp_line
			(start 0.67945 -0.3048)
			(end 0.67945 0.3048)
			(stroke
				(width 0.1)
				(type default)
			)
			(layer "F.Fab")
		)
		(fp_line
			(start 0.12065 -0.3048)
			(end 0.67945 -0.3048)
			(stroke
				(width 0.1)
				(type default)
			)
			(layer "F.Fab")
		)
		(fp_line
			(start 0.12065 -0.2794)
			(end 0.12065 -0.3048)
			(stroke
				(width 0.1)
				(type default)
			)
			(layer "F.Fab")
		)
		(fp_line
			(start -0.12065 -0.2794)
			(end 0.12065 -0.2794)
			(stroke
				(width 0.1)
				(type default)
			)
			(layer "F.Fab")
		)
		(fp_line
			(start 0.120396 0.2794)
			(end -0.12065 0.2794)
			(stroke
				(width 0.1)
				(type default)
			)
			(layer "F.Fab")
		)
		(fp_line
			(start -0.12065 0.2794)
			(end -0.12065 0.3048)
			(stroke
				(width 0.1)
				(type default)
			)
			(layer "F.Fab")
		)
		(fp_line
			(start 0.67945 0.3048)
			(end 0.120396 0.3048)
			(stroke
				(width 0.1)
				(type default)
			)
			(layer "F.Fab")
		)
		(fp_line
			(start 0.120396 0.3048)
			(end 0.120396 0.2794)
			(stroke
				(width 0.1)
				(type default)
			)
			(layer "F.Fab")
		)
		(fp_line
			(start -0.12065 0.3048)
			(end -0.67945 0.3048)
			(stroke
				(width 0.1)
				(type default)
			)
			(layer "F.Fab")
		)
		(fp_line
			(start -0.67945 0.3048)
			(end -0.67945 -0.305054)
			(stroke
				(width 0.1)
				(type default)
			)
			(layer "F.Fab")
		)
		(pad "1" smd circle
			(at -0.40005 0 90)
			(size 0 0)
			(layers "F.Cu" "F.Mask" "F.Paste")
			(net "PVDDCR_SOC_P1")
		)
		(pad "2" smd circle
			(at 0.40005 0 90)
			(size 0 0)
			(layers "F.Cu" "F.Mask" "F.Paste")
			(net "GND")
		)
	)
	(footprint ""
		(layer "F.Cu")
		(at 434.678836 -169.224452)
		(property "Reference" "R5009"
			(at 0 0 0)
			(layer "F.SilkS")
			(hide yes)
			(effects
				(font
					(size 1.27 1.27)
				)
			)
		)
		(property "Value" ""
			(at 0 0 0)
			(layer "F.Fab")
			(effects
				(font
					(size 1.27 1.27)
				)
			)
		)
		(duplicate_pad_numbers_are_jumpers no)
		(fp_line
			(start -0.7874 -0.4064)
			(end 0.7874 -0.4064)
			(stroke
				(width 0.1524)
				(type default)
			)
			(layer "F.SilkS")
		)
		(fp_line
			(start -0.7874 0.4064)
			(end -0.7874 -0.4064)
			(stroke
				(width 0.1524)
				(type default)
			)
			(layer "F.SilkS")
		)
		(fp_line
			(start 0.7874 -0.4064)
			(end 0.7874 0.4064)
			(stroke
				(width 0.1524)
				(type default)
			)
			(layer "F.SilkS")
		)
		(fp_line
			(start 0.7874 0.4064)
			(end -0.7874 0.4064)
			(stroke
				(width 0.1524)
				(type default)
			)
			(layer "F.SilkS")
		)
		(fp_line
			(start -0.67945 -0.305054)
			(end -0.12065 -0.305054)
			(stroke
				(width 0.1)
				(type default)
			)
			(layer "F.Fab")
		)
		(fp_line
			(start -0.67945 0.3048)
			(end -0.67945 -0.305054)
			(stroke
				(width 0.1)
				(type default)
			)
			(layer "F.Fab")
		)
		(fp_line
			(start -0.12065 -0.305054)
			(end -0.12065 -0.2794)
			(stroke
				(width 0.1)
				(type default)
			)
			(layer "F.Fab")
		)
		(fp_line
			(start -0.12065 -0.2794)
			(end 0.12065 -0.2794)
			(stroke
				(width 0.1)
				(type default)
			)
			(layer "F.Fab")
		)
		(fp_line
			(start -0.12065 0.2794)
			(end -0.12065 0.3048)
			(stroke
				(width 0.1)
				(type default)
			)
			(layer "F.Fab")
		)
		(fp_line
			(start -0.12065 0.3048)
			(end -0.67945 0.3048)
			(stroke
				(width 0.1)
				(type default)
			)
			(layer "F.Fab")
		)
		(fp_line
			(start 0.120396 0.2794)
			(end -0.12065 0.2794)
			(stroke
				(width 0.1)
				(type default)
			)
			(layer "F.Fab")
		)
		(fp_line
			(start 0.120396 0.3048)
			(end 0.120396 0.2794)
			(stroke
				(width 0.1)
				(type default)
			)
			(layer "F.Fab")
		)
		(fp_line
			(start 0.12065 -0.3048)
			(end 0.67945 -0.3048)
			(stroke
				(width 0.1)
				(type default)
			)
			(layer "F.Fab")
		)
		(fp_line
			(start 0.12065 -0.2794)
			(end 0.12065 -0.3048)
			(stroke
				(width 0.1)
				(type default)
			)
			(layer "F.Fab")
		)
		(fp_line
			(start 0.67945 -0.3048)
			(end 0.67945 0.3048)
			(stroke
				(width 0.1)
				(type default)
			)
			(layer "F.Fab")
		)
		(fp_line
			(start 0.67945 0.3048)
			(end 0.120396 0.3048)
			(stroke
				(width 0.1)
				(type default)
			)
			(layer "F.Fab")
		)
		(pad "1" smd circle
			(at -0.40005 0)
			(size 0 0)
			(layers "F.Cu" "F.Mask" "F.Paste")
			(net "PVDD11_S3_P0")
		)
		(pad "2" smd circle
			(at 0.40005 0)
			(size 0 0)
			(layers "F.Cu" "F.Mask" "F.Paste")
			(net "I3C_SPD_DDRGL_CPU0_LVC1_SDA")
		)
	)
	(footprint ""
		(layer "F.Cu")
		(at 103.505 -417.957)
		(property "Reference" "R3496"
			(at 0 0 0)
			(layer "F.SilkS")
			(hide yes)
			(effects
				(font
					(size 1.27 1.27)
				)
			)
		)
		(property "Value" ""
			(at 0 0 0)
			(layer "F.Fab")
			(effects
				(font
					(size 1.27 1.27)
				)
			)
		)
		(duplicate_pad_numbers_are_jumpers no)
		(fp_line
			(start -0.7874 -0.4064)
			(end 0.7874 -0.4064)
			(stroke
				(width 0.1524)
				(type default)
			)
			(layer "F.SilkS")
		)
		(fp_line
			(start -0.7874 0.4064)
			(end -0.7874 -0.4064)
			(stroke
				(width 0.1524)
				(type default)
			)
			(layer "F.SilkS")
		)
		(fp_line
			(start 0.7874 -0.4064)
			(end 0.7874 0.4064)
			(stroke
				(width 0.1524)
				(type default)
			)
			(layer "F.SilkS")
		)
		(fp_line
			(start 0.7874 0.4064)
			(end -0.7874 0.4064)
			(stroke
				(width 0.1524)
				(type default)
			)
			(layer "F.SilkS")
		)
		(fp_line
			(start -0.67945 -0.305054)
			(end -0.12065 -0.305054)
			(stroke
				(width 0.1)
				(type default)
			)
			(layer "F.Fab")
		)
		(fp_line
			(start -0.67945 0.3048)
			(end -0.67945 -0.305054)
			(stroke
				(width 0.1)
				(type default)
			)
			(layer "F.Fab")
		)
		(fp_line
			(start -0.12065 -0.305054)
			(end -0.12065 -0.2794)
			(stroke
				(width 0.1)
				(type default)
			)
			(layer "F.Fab")
		)
		(fp_line
			(start -0.12065 -0.2794)
			(end 0.12065 -0.2794)
			(stroke
				(width 0.1)
				(type default)
			)
			(layer "F.Fab")
		)
		(fp_line
			(start -0.12065 0.2794)
			(end -0.12065 0.3048)
			(stroke
				(width 0.1)
				(type default)
			)
			(layer "F.Fab")
		)
		(fp_line
			(start -0.12065 0.3048)
			(end -0.67945 0.3048)
			(stroke
				(width 0.1)
				(type default)
			)
			(layer "F.Fab")
		)
		(fp_line
			(start 0.120396 0.2794)
			(end -0.12065 0.2794)
			(stroke
				(width 0.1)
				(type default)
			)
			(layer "F.Fab")
		)
		(fp_line
			(start 0.120396 0.3048)
			(end 0.120396 0.2794)
			(stroke
				(width 0.1)
				(type default)
			)
			(layer "F.Fab")
		)
		(fp_line
			(start 0.12065 -0.3048)
			(end 0.67945 -0.3048)
			(stroke
				(width 0.1)
				(type default)
			)
			(layer "F.Fab")
		)
		(fp_line
			(start 0.12065 -0.2794)
			(end 0.12065 -0.3048)
			(stroke
				(width 0.1)
				(type default)
			)
			(layer "F.Fab")
		)
		(fp_line
			(start 0.67945 -0.3048)
			(end 0.67945 0.3048)
			(stroke
				(width 0.1)
				(type default)
			)
			(layer "F.Fab")
		)
		(fp_line
			(start 0.67945 0.3048)
			(end 0.120396 0.3048)
			(stroke
				(width 0.1)
				(type default)
			)
			(layer "F.Fab")
		)
		(pad "1" smd circle
			(at -0.40005 0)
			(size 0 0)
			(layers "F.Cu" "F.Mask" "F.Paste")
			(net "GPU_FPGA_EROT_RST_BUF_R_N")
		)
		(pad "2" smd circle
			(at 0.40005 0)
			(size 0 0)
			(layers "F.Cu" "F.Mask" "F.Paste")
			(net "GPU_FPGA_EROT_RST_BUF_N")
		)
	)
	(footprint ""
		(layer "F.Cu")
		(at 175.883062 -23.283672 180)
		(property "Reference" "PR4006"
			(at 0 0 180)
			(layer "F.SilkS")
			(hide yes)
			(effects
				(font
					(size 1.27 1.27)
				)
			)
		)
		(property "Value" ""
			(at 0 0 180)
			(layer "F.Fab")
			(effects
				(font
					(size 1.27 1.27)
				)
			)
		)
		(duplicate_pad_numbers_are_jumpers no)
		(fp_line
			(start 0.7874 0.4064)
			(end -0.7874 0.4064)
			(stroke
				(width 0.1524)
				(type default)
			)
			(layer "F.SilkS")
		)
		(fp_line
			(start 0.7874 -0.4064)
			(end 0.7874 0.4064)
			(stroke
				(width 0.1524)
				(type default)
			)
			(layer "F.SilkS")
		)
		(fp_line
			(start -0.7874 0.4064)
			(end -0.7874 -0.4064)
			(stroke
				(width 0.1524)
				(type default)
			)
			(layer "F.SilkS")
		)
		(fp_line
			(start -0.7874 -0.4064)
			(end 0.7874 -0.4064)
			(stroke
				(width 0.1524)
				(type default)
			)
			(layer "F.SilkS")
		)
		(fp_line
			(start 0.67945 0.3048)
			(end 0.120396 0.3048)
			(stroke
				(width 0.1)
				(type default)
			)
			(layer "F.Fab")
		)
		(fp_line
			(start 0.67945 -0.3048)
			(end 0.67945 0.3048)
			(stroke
				(width 0.1)
				(type default)
			)
			(layer "F.Fab")
		)
		(fp_line
			(start 0.12065 -0.2794)
			(end 0.12065 -0.3048)
			(stroke
				(width 0.1)
				(type default)
			)
			(layer "F.Fab")
		)
		(fp_line
			(start 0.12065 -0.3048)
			(end 0.67945 -0.3048)
			(stroke
				(width 0.1)
				(type default)
			)
			(layer "F.Fab")
		)
		(fp_line
			(start 0.120396 0.3048)
			(end 0.120396 0.2794)
			(stroke
				(width 0.1)
				(type default)
			)
			(layer "F.Fab")
		)
		(fp_line
			(start 0.120396 0.2794)
			(end -0.12065 0.2794)
			(stroke
				(width 0.1)
				(type default)
			)
			(layer "F.Fab")
		)
		(fp_line
			(start -0.12065 0.3048)
			(end -0.67945 0.3048)
			(stroke
				(width 0.1)
				(type default)
			)
			(layer "F.Fab")
		)
		(fp_line
			(start -0.12065 0.2794)
			(end -0.12065 0.3048)
			(stroke
				(width 0.1)
				(type default)
			)
			(layer "F.Fab")
		)
		(fp_line
			(start -0.12065 -0.2794)
			(end 0.12065 -0.2794)
			(stroke
				(width 0.1)
				(type default)
			)
			(layer "F.Fab")
		)
		(fp_line
			(start -0.12065 -0.305054)
			(end -0.12065 -0.2794)
			(stroke
				(width 0.1)
				(type default)
			)
			(layer "F.Fab")
		)
		(fp_line
			(start -0.67945 0.3048)
			(end -0.67945 -0.305054)
			(stroke
				(width 0.1)
				(type default)
			)
			(layer "F.Fab")
		)
		(fp_line
			(start -0.67945 -0.305054)
			(end -0.12065 -0.305054)
			(stroke
				(width 0.1)
				(type default)
			)
			(layer "F.Fab")
		)
		(pad "1" smd circle
			(at -0.40005 0 180)
			(size 0 0)
			(layers "F.Cu" "F.Mask" "F.Paste")
			(net "P12V_SCM_R")
		)
		(pad "2" smd circle
			(at 0.40005 0 180)
			(size 0 0)
			(layers "F.Cu" "F.Mask" "F.Paste")
			(net "P12V_SCM_AVIN_PD")
		)
	)
	(footprint ""
		(layer "F.Cu")
		(at 258.275836 -75.770994)
		(property "Reference" "R3772"
			(at 0 0 0)
			(layer "F.SilkS")
			(hide yes)
			(effects
				(font
					(size 1.27 1.27)
				)
			)
		)
		(property "Value" ""
			(at 0 0 0)
			(layer "F.Fab")
			(effects
				(font
					(size 1.27 1.27)
				)
			)
		)
		(duplicate_pad_numbers_are_jumpers no)
		(fp_line
			(start -0.7874 -0.4064)
			(end 0.7874 -0.4064)
			(stroke
				(width 0.1524)
				(type default)
			)
			(layer "F.SilkS")
		)
		(fp_line
			(start -0.7874 0.4064)
			(end -0.7874 -0.4064)
			(stroke
				(width 0.1524)
				(type default)
			)
			(layer "F.SilkS")
		)
		(fp_line
			(start 0.7874 -0.4064)
			(end 0.7874 0.4064)
			(stroke
				(width 0.1524)
				(type default)
			)
			(layer "F.SilkS")
		)
		(fp_line
			(start 0.7874 0.4064)
			(end -0.7874 0.4064)
			(stroke
				(width 0.1524)
				(type default)
			)
			(layer "F.SilkS")
		)
		(fp_line
			(start -0.67945 -0.305054)
			(end -0.12065 -0.305054)
			(stroke
				(width 0.1)
				(type default)
			)
			(layer "F.Fab")
		)
		(fp_line
			(start -0.67945 0.3048)
			(end -0.67945 -0.305054)
			(stroke
				(width 0.1)
				(type default)
			)
			(layer "F.Fab")
		)
		(fp_line
			(start -0.12065 -0.305054)
			(end -0.12065 -0.2794)
			(stroke
				(width 0.1)
				(type default)
			)
			(layer "F.Fab")
		)
		(fp_line
			(start -0.12065 -0.2794)
			(end 0.12065 -0.2794)
			(stroke
				(width 0.1)
				(type default)
			)
			(layer "F.Fab")
		)
		(fp_line
			(start -0.12065 0.2794)
			(end -0.12065 0.3048)
			(stroke
				(width 0.1)
				(type default)
			)
			(layer "F.Fab")
		)
		(fp_line
			(start -0.12065 0.3048)
			(end -0.67945 0.3048)
			(stroke
				(width 0.1)
				(type default)
			)
			(layer "F.Fab")
		)
		(fp_line
			(start 0.120396 0.2794)
			(end -0.12065 0.2794)
			(stroke
				(width 0.1)
				(type default)
			)
			(layer "F.Fab")
		)
		(fp_line
			(start 0.120396 0.3048)
			(end 0.120396 0.2794)
			(stroke
				(width 0.1)
				(type default)
			)
			(layer "F.Fab")
		)
		(fp_line
			(start 0.12065 -0.3048)
			(end 0.67945 -0.3048)
			(stroke
				(width 0.1)
				(type default)
			)
			(layer "F.Fab")
		)
		(fp_line
			(start 0.12065 -0.2794)
			(end 0.12065 -0.3048)
			(stroke
				(width 0.1)
				(type default)
			)
			(layer "F.Fab")
		)
		(fp_line
			(start 0.67945 -0.3048)
			(end 0.67945 0.3048)
			(stroke
				(width 0.1)
				(type default)
			)
			(layer "F.Fab")
		)
		(fp_line
			(start 0.67945 0.3048)
			(end 0.120396 0.3048)
			(stroke
				(width 0.1)
				(type default)
			)
			(layer "F.Fab")
		)
		(pad "1" smd circle
			(at -0.40005 0)
			(size 0 0)
			(layers "F.Cu" "F.Mask" "F.Paste")
			(net "RST_SMB_BUF_E1S_0_N")
		)
		(pad "2" smd circle
			(at 0.40005 0)
			(size 0 0)
			(layers "F.Cu" "F.Mask" "F.Paste")
			(net "RST_SMB_E1S_0_N")
		)
	)
	(footprint ""
		(layer "F.Cu")
		(at 19.658076 -255.560322 180)
		(property "Reference" "J33"
			(at -1.25984 -82.079846 0)
			(unlocked yes)
			(layer "F.SilkS")
			(effects
				(font
					(size 0.7874 0.5842)
					(thickness 0.1524)
				)
			)
		)
		(property "Value" ""
			(at 0 0 180)
			(layer "F.Fab")
			(effects
				(font
					(size 1.27 1.27)
				)
			)
		)
		(duplicate_pad_numbers_are_jumpers no)
		(fp_line
			(start 3.24993 -81.000092)
			(end 3.24993 75.401678)
			(stroke
				(width 0.1524)
				(type default)
			)
			(layer "F.SilkS")
		)
		(fp_line
			(start -3.24993 75.401678)
			(end -3.24993 -81.000092)
			(stroke
				(width 0.1524)
				(type default)
			)
			(layer "F.SilkS")
		)
		(fp_line
			(start -3.24993 72.499982)
			(end 3.24993 72.499982)
			(stroke
				(width 0.1524)
				(type default)
			)
			(layer "F.SilkS")
		)
		(fp_line
			(start -3.24993 -72.499982)
			(end 3.24993 -72.499982)
			(stroke
				(width 0.1524)
				(type default)
			)
			(layer "F.SilkS")
		)
		(fp_line
			(start -3.24993 -81.000092)
			(end 3.24993 -81.000092)
			(stroke
				(width 0.1524)
				(type default)
			)
			(layer "F.SilkS")
		)
		(fp_poly
			(pts
				(xy -4.012184 -64.807846) (xy -3.306572 -63.91783) (xy -4.441952 -63.88735)
			)
			(stroke
				(width 0)
				(type default)
			)
			(fill yes)
			(layer "F.SilkS")
		)
		(fp_line
			(start 3.24993 81.000092)
			(end -3.24993 81.000092)
			(stroke
				(width 0.1)
				(type default)
			)
			(layer "F.Fab")
		)
		(fp_line
			(start 3.24993 -81.000092)
			(end 3.24993 81.000092)
			(stroke
				(width 0.1)
				(type default)
			)
			(layer "F.Fab")
		)
		(fp_line
			(start -3.24993 81.000092)
			(end -3.24993 -81.000092)
			(stroke
				(width 0.1)
				(type default)
			)
			(layer "F.Fab")
		)
		(fp_line
			(start -3.24993 72.499982)
			(end 3.24993 72.499982)
			(stroke
				(width 0.1)
				(type default)
			)
			(layer "F.Fab")
		)
		(fp_line
			(start -3.24993 71.000112)
			(end 3.24993 71.000112)
			(stroke
				(width 0.1)
				(type default)
			)
			(layer "F.Fab")
		)
		(fp_line
			(start -3.24993 -71.000112)
			(end 3.24993 -71.000112)
			(stroke
				(width 0.1)
				(type default)
			)
			(layer "F.Fab")
		)
		(fp_line
			(start -3.24993 -72.499982)
			(end 3.24993 -72.499982)
			(stroke
				(width 0.1)
				(type default)
			)
			(layer "F.Fab")
		)
		(fp_line
			(start -3.24993 -81.000092)
			(end 3.24993 -81.000092)
			(stroke
				(width 0.1)
				(type default)
			)
			(layer "F.Fab")
		)
		(fp_poly
			(pts
				(xy -3.41503 -63.324994) (xy -4.43103 -62.816994) (xy -4.43103 -63.832994)
			)
			(stroke
				(width 0)
				(type default)
			)
			(fill yes)
			(layer "F.Fab")
		)
		(pad "1" smd rect
			(at -2.050034 -63.324994 90)
			(size 0.519938 1.4986)
			(layers "F.Cu" "F.Mask" "F.Paste")
			(net "P12V_MEM_CPU1")
		)
		(pad "2" smd rect
			(at -2.050034 -62.47511 90)
			(size 0.519938 1.4986)
			(layers "F.Cu" "F.Mask" "F.Paste")
			(net "Net_2326")
		)
		(pad "3" smd rect
			(at -2.050034 -61.624972 90)
			(size 0.519938 1.4986)
			(layers "F.Cu" "F.Mask" "F.Paste")
			(net "P3V3_AUX")
		)
		(pad "4" smd rect
			(at -2.050034 -60.775088 90)
			(size 0.519938 1.4986)
			(layers "F.Cu" "F.Mask" "F.Paste")
			(net "I3C_SPD_DDRF_CPU1_SCL")
		)
		(pad "5" smd rect
			(at -2.050034 -59.92495 90)
			(size 0.519938 1.4986)
			(layers "F.Cu" "F.Mask" "F.Paste")
			(net "I3C_SPD_DDRF_CPU1_SDA")
		)
		(pad "6" smd rect
			(at -2.050034 -59.075066 90)
			(size 0.519938 1.4986)
			(layers "F.Cu" "F.Mask" "F.Paste")
			(net "GND")
		)
		(pad "7" smd rect
			(at -2.050034 -58.224928 90)
			(size 0.519938 1.4986)
			(layers "F.Cu" "F.Mask" "F.Paste")
			(net "M_F_CPU1_SA_DQ<0>")
		)
		(pad "8" smd rect
			(at -2.050034 -57.375044 90)
			(size 0.519938 1.4986)
			(layers "F.Cu" "F.Mask" "F.Paste")
			(net "GND")
		)
		(pad "9" smd rect
			(at -2.050034 -56.524906 90)
			(size 0.519938 1.4986)
			(layers "F.Cu" "F.Mask" "F.Paste")
			(net "M_F_CPU1_SA_DQ<1>")
		)
		(pad "10" smd rect
			(at -2.050034 -55.675022 90)
			(size 0.519938 1.4986)
			(layers "F.Cu" "F.Mask" "F.Paste")
			(net "GND")
		)
		(pad "11" smd rect
			(at -2.050034 -54.824884 90)
			(size 0.519938 1.4986)
			(layers "F.Cu" "F.Mask" "F.Paste")
			(net "M_F_CPU1_SA_DQS_DP<0>")
		)
		(pad "12" smd rect
			(at -2.050034 -53.975 90)
			(size 0.519938 1.4986)
			(layers "F.Cu" "F.Mask" "F.Paste")
			(net "M_F_CPU1_SA_DQS_DN<0>")
		)
		(pad "13" smd rect
			(at -2.050034 -53.125116 90)
			(size 0.519938 1.4986)
			(layers "F.Cu" "F.Mask" "F.Paste")
			(net "GND")
		)
		(pad "14" smd rect
			(at -2.050034 -52.274978 90)
			(size 0.519938 1.4986)
			(layers "F.Cu" "F.Mask" "F.Paste")
			(net "M_F_CPU1_SA_DQ<4>")
		)
		(pad "15" smd rect
			(at -2.050034 -51.425094 90)
			(size 0.519938 1.4986)
			(layers "F.Cu" "F.Mask" "F.Paste")
			(net "GND")
		)
		(pad "16" smd rect
			(at -2.050034 -50.574956 90)
			(size 0.519938 1.4986)
			(layers "F.Cu" "F.Mask" "F.Paste")
			(net "M_F_CPU1_SA_DQ<5>")
		)
		(pad "17" smd rect
			(at -2.050034 -49.725072 90)
			(size 0.519938 1.4986)
			(layers "F.Cu" "F.Mask" "F.Paste")
			(net "GND")
		)
		(pad "18" smd rect
			(at -2.050034 -48.874934 90)
			(size 0.519938 1.4986)
			(layers "F.Cu" "F.Mask" "F.Paste")
			(net "M_F_CPU1_SA_DQ<8>")
		)
		(pad "19" smd rect
			(at -2.050034 -48.02505 90)
			(size 0.519938 1.4986)
			(layers "F.Cu" "F.Mask" "F.Paste")
			(net "GND")
		)
		(pad "20" smd rect
			(at -2.050034 -47.174912 90)
			(size 0.519938 1.4986)
			(layers "F.Cu" "F.Mask" "F.Paste")
			(net "M_F_CPU1_SA_DQ<9>")
		)
		(pad "21" smd rect
			(at -2.050034 -46.325028 90)
			(size 0.519938 1.4986)
			(layers "F.Cu" "F.Mask" "F.Paste")
			(net "GND")
		)
		(pad "22" smd rect
			(at -2.050034 -45.47489 90)
			(size 0.519938 1.4986)
			(layers "F.Cu" "F.Mask" "F.Paste")
			(net "M_F_CPU1_SA_DQS_DP<1>")
		)
		(pad "23" smd rect
			(at -2.050034 -44.625006 90)
			(size 0.519938 1.4986)
			(layers "F.Cu" "F.Mask" "F.Paste")
			(net "M_F_CPU1_SA_DQS_DN<1>")
		)
		(pad "24" smd rect
			(at -2.050034 -43.775122 90)
			(size 0.519938 1.4986)
			(layers "F.Cu" "F.Mask" "F.Paste")
			(net "GND")
		)
		(pad "25" smd rect
			(at -2.050034 -42.924984 90)
			(size 0.519938 1.4986)
			(layers "F.Cu" "F.Mask" "F.Paste")
			(net "M_F_CPU1_SA_DQ<12>")
		)
		(pad "26" smd rect
			(at -2.050034 -42.0751 90)
			(size 0.519938 1.4986)
			(layers "F.Cu" "F.Mask" "F.Paste")
			(net "GND")
		)
		(pad "27" smd rect
			(at -2.050034 -41.224962 90)
			(size 0.519938 1.4986)
			(layers "F.Cu" "F.Mask" "F.Paste")
			(net "M_F_CPU1_SA_DQ<13>")
		)
		(pad "28" smd rect
			(at -2.050034 -40.375078 90)
			(size 0.519938 1.4986)
			(layers "F.Cu" "F.Mask" "F.Paste")
			(net "GND")
		)
		(pad "29" smd rect
			(at -2.050034 -39.52494 90)
			(size 0.519938 1.4986)
			(layers "F.Cu" "F.Mask" "F.Paste")
			(net "M_F_CPU1_SA_DQ<16>")
		)
		(pad "30" smd rect
			(at -2.050034 -38.675056 90)
			(size 0.519938 1.4986)
			(layers "F.Cu" "F.Mask" "F.Paste")
			(net "GND")
		)
		(pad "31" smd rect
			(at -2.050034 -37.824918 90)
			(size 0.519938 1.4986)
			(layers "F.Cu" "F.Mask" "F.Paste")
			(net "M_F_CPU1_SA_DQ<17>")
		)
		(pad "32" smd rect
			(at -2.050034 -36.975034 90)
			(size 0.519938 1.4986)
			(layers "F.Cu" "F.Mask" "F.Paste")
			(net "GND")
		)
		(pad "33" smd rect
			(at -2.050034 -36.124896 90)
			(size 0.519938 1.4986)
			(layers "F.Cu" "F.Mask" "F.Paste")
			(net "M_F_CPU1_SA_DQS_DP<2>")
		)
		(pad "34" smd rect
			(at -2.050034 -35.275012 90)
			(size 0.519938 1.4986)
			(layers "F.Cu" "F.Mask" "F.Paste")
			(net "M_F_CPU1_SA_DQS_DN<2>")
		)
		(pad "35" smd rect
			(at -2.050034 -34.425128 90)
			(size 0.519938 1.4986)
			(layers "F.Cu" "F.Mask" "F.Paste")
			(net "GND")
		)
		(pad "36" smd rect
			(at -2.050034 -33.57499 90)
			(size 0.519938 1.4986)
			(layers "F.Cu" "F.Mask" "F.Paste")
			(net "M_F_CPU1_SA_DQ<20>")
		)
		(pad "37" smd rect
			(at -2.050034 -32.725106 90)
			(size 0.519938 1.4986)
			(layers "F.Cu" "F.Mask" "F.Paste")
			(net "GND")
		)
		(pad "38" smd rect
			(at -2.050034 -31.874968 90)
			(size 0.519938 1.4986)
			(layers "F.Cu" "F.Mask" "F.Paste")
			(net "M_F_CPU1_SA_DQ<21>")
		)
		(pad "39" smd rect
			(at -2.050034 -31.025084 90)
			(size 0.519938 1.4986)
			(layers "F.Cu" "F.Mask" "F.Paste")
			(net "GND")
		)
		(pad "40" smd rect
			(at -2.050034 -30.174946 90)
			(size 0.519938 1.4986)
			(layers "F.Cu" "F.Mask" "F.Paste")
			(net "M_F_CPU1_SA_DQ<24>")
		)
		(pad "41" smd rect
			(at -2.050034 -29.325062 90)
			(size 0.519938 1.4986)
			(layers "F.Cu" "F.Mask" "F.Paste")
			(net "GND")
		)
		(pad "42" smd rect
			(at -2.050034 -28.474924 90)
			(size 0.519938 1.4986)
			(layers "F.Cu" "F.Mask" "F.Paste")
			(net "M_F_CPU1_SA_DQ<25>")
		)
		(pad "43" smd rect
			(at -2.050034 -27.62504 90)
			(size 0.519938 1.4986)
			(layers "F.Cu" "F.Mask" "F.Paste")
			(net "GND")
		)
		(pad "44" smd rect
			(at -2.050034 -26.774902 90)
			(size 0.519938 1.4986)
			(layers "F.Cu" "F.Mask" "F.Paste")
			(net "M_F_CPU1_SA_DQS_DP<3>")
		)
		(pad "45" smd rect
			(at -2.050034 -25.925018 90)
			(size 0.519938 1.4986)
			(layers "F.Cu" "F.Mask" "F.Paste")
			(net "M_F_CPU1_SA_DQS_DN<3>")
		)
		(pad "46" smd rect
			(at -2.050034 -25.07488 90)
			(size 0.519938 1.4986)
			(layers "F.Cu" "F.Mask" "F.Paste")
			(net "GND")
		)
		(pad "47" smd rect
			(at -2.050034 -24.224996 90)
			(size 0.519938 1.4986)
			(layers "F.Cu" "F.Mask" "F.Paste")
			(net "M_F_CPU1_SA_DQ<28>")
		)
		(pad "48" smd rect
			(at -2.050034 -23.375112 90)
			(size 0.519938 1.4986)
			(layers "F.Cu" "F.Mask" "F.Paste")
			(net "GND")
		)
		(pad "49" smd rect
			(at -2.050034 -22.524974 90)
			(size 0.519938 1.4986)
			(layers "F.Cu" "F.Mask" "F.Paste")
			(net "M_F_CPU1_SA_DQ<29>")
		)
		(pad "50" smd rect
			(at -2.050034 -21.67509 90)
			(size 0.519938 1.4986)
			(layers "F.Cu" "F.Mask" "F.Paste")
			(net "GND")
		)
		(pad "51" smd rect
			(at -2.050034 -20.824952 90)
			(size 0.519938 1.4986)
			(layers "F.Cu" "F.Mask" "F.Paste")
			(net "M_F_CPU1_SA_CB<0>")
		)
		(pad "52" smd rect
			(at -2.050034 -19.975068 90)
			(size 0.519938 1.4986)
			(layers "F.Cu" "F.Mask" "F.Paste")
			(net "GND")
		)
		(pad "53" smd rect
			(at -2.050034 -19.12493 90)
			(size 0.519938 1.4986)
			(layers "F.Cu" "F.Mask" "F.Paste")
			(net "M_F_CPU1_SA_CB<1>")
		)
		(pad "54" smd rect
			(at -2.050034 -18.275046 90)
			(size 0.519938 1.4986)
			(layers "F.Cu" "F.Mask" "F.Paste")
			(net "GND")
		)
		(pad "55" smd rect
			(at -2.050034 -17.424908 90)
			(size 0.519938 1.4986)
			(layers "F.Cu" "F.Mask" "F.Paste")
			(net "M_F_CPU1_SA_DQS_DP<4>")
		)
		(pad "56" smd rect
			(at -2.050034 -16.575024 90)
			(size 0.519938 1.4986)
			(layers "F.Cu" "F.Mask" "F.Paste")
			(net "M_F_CPU1_SA_DQS_DN<4>")
		)
		(pad "57" smd rect
			(at -2.050034 -15.724886 90)
			(size 0.519938 1.4986)
			(layers "F.Cu" "F.Mask" "F.Paste")
			(net "GND")
		)
		(pad "58" smd rect
			(at -2.050034 -14.875002 90)
			(size 0.519938 1.4986)
			(layers "F.Cu" "F.Mask" "F.Paste")
			(net "M_F_CPU1_SA_CB<4>")
		)
		(pad "59" smd rect
			(at -2.050034 -14.025118 90)
			(size 0.519938 1.4986)
			(layers "F.Cu" "F.Mask" "F.Paste")
			(net "GND")
		)
		(pad "60" smd rect
			(at -2.050034 -13.17498 90)
			(size 0.519938 1.4986)
			(layers "F.Cu" "F.Mask" "F.Paste")
			(net "M_F_CPU1_SA_CB<5>")
		)
		(pad "61" smd rect
			(at -2.050034 -12.325096 90)
			(size 0.519938 1.4986)
			(layers "F.Cu" "F.Mask" "F.Paste")
			(net "GND")
		)
		(pad "62" smd rect
			(at -2.050034 -11.474958 90)
			(size 0.519938 1.4986)
			(layers "F.Cu" "F.Mask" "F.Paste")
			(net "M_F_CPU1_ALERT_N")
		)
		(pad "63" smd rect
			(at -2.050034 -10.625074 90)
			(size 0.519938 1.4986)
			(layers "F.Cu" "F.Mask" "F.Paste")
			(net "GND")
		)
		(pad "64" smd rect
			(at -2.050034 -9.774936 90)
			(size 0.519938 1.4986)
			(layers "F.Cu" "F.Mask" "F.Paste")
			(net "M_F_CPU1_SA_CS_N<0>")
		)
		(pad "65" smd rect
			(at -2.050034 -8.925052 90)
			(size 0.519938 1.4986)
			(layers "F.Cu" "F.Mask" "F.Paste")
			(net "GND")
		)
		(pad "66" smd rect
			(at -2.050034 -8.074914 90)
			(size 0.519938 1.4986)
			(layers "F.Cu" "F.Mask" "F.Paste")
			(net "M_F_CPU1_SA_CA<0>")
		)
		(pad "67" smd rect
			(at -2.050034 -7.22503 90)
			(size 0.519938 1.4986)
			(layers "F.Cu" "F.Mask" "F.Paste")
			(net "GND")
		)
		(pad "68" smd rect
			(at -2.050034 -6.374892 90)
			(size 0.519938 1.4986)
			(layers "F.Cu" "F.Mask" "F.Paste")
			(net "M_F_CPU1_SA_CA<2>")
		)
		(pad "69" smd rect
			(at -2.050034 -5.525008 90)
			(size 0.519938 1.4986)
			(layers "F.Cu" "F.Mask" "F.Paste")
			(net "GND")
		)
		(pad "70" smd rect
			(at -2.050034 -4.675124 90)
			(size 0.519938 1.4986)
			(layers "F.Cu" "F.Mask" "F.Paste")
			(net "M_F_CPU1_SA_CA<4>")
		)
		(pad "71" smd rect
			(at -2.050034 -3.824986 90)
			(size 0.519938 1.4986)
			(layers "F.Cu" "F.Mask" "F.Paste")
			(net "GND")
		)
		(pad "72" smd rect
			(at -2.050034 -2.975102 90)
			(size 0.519938 1.4986)
			(layers "F.Cu" "F.Mask" "F.Paste")
			(net "M_F_CPU1_SA_CA<6>")
		)
		(pad "73" smd rect
			(at -2.050034 -2.124964 90)
			(size 0.519938 1.4986)
			(layers "F.Cu" "F.Mask" "F.Paste")
			(net "GND")
		)
		(pad "74" smd rect
			(at -2.050034 -1.27508 90)
			(size 0.519938 1.4986)
			(layers "F.Cu" "F.Mask" "F.Paste")
			(net "M_F_CPU1_SA_PAR")
		)
		(pad "75" smd rect
			(at -2.050034 -0.424942 90)
			(size 0.519938 1.4986)
			(layers "F.Cu" "F.Mask" "F.Paste")
			(net "GND")
		)
		(pad "76" smd rect
			(at -2.050034 5.525008 90)
			(size 0.519938 1.4986)
			(layers "F.Cu" "F.Mask" "F.Paste")
			(net "M_F_CPU1_SB_CA<0>")
		)
		(pad "77" smd rect
			(at -2.050034 6.374892 90)
			(size 0.519938 1.4986)
			(layers "F.Cu" "F.Mask" "F.Paste")
			(net "GND")
		)
		(pad "78" smd rect
			(at -2.050034 7.22503 90)
			(size 0.519938 1.4986)
			(layers "F.Cu" "F.Mask" "F.Paste")
			(net "M_F_CPU1_SB_CA<2>")
		)
		(pad "79" smd rect
			(at -2.050034 8.074914 90)
			(size 0.519938 1.4986)
			(layers "F.Cu" "F.Mask" "F.Paste")
			(net "GND")
		)
		(pad "80" smd rect
			(at -2.050034 8.925052 90)
			(size 0.519938 1.4986)
			(layers "F.Cu" "F.Mask" "F.Paste")
			(net "M_F_CPU1_SB_CA<4>")
		)
		(pad "81" smd rect
			(at -2.050034 9.774936 90)
			(size 0.519938 1.4986)
			(layers "F.Cu" "F.Mask" "F.Paste")
			(net "GND")
		)
		(pad "82" smd rect
			(at -2.050034 10.625074 90)
			(size 0.519938 1.4986)
			(layers "F.Cu" "F.Mask" "F.Paste")
			(net "M_F_CPU1_SB_CA<6>")
		)
		(pad "83" smd rect
			(at -2.050034 11.474958 90)
			(size 0.519938 1.4986)
			(layers "F.Cu" "F.Mask" "F.Paste")
			(net "GND")
		)
		(pad "84" smd rect
			(at -2.050034 12.325096 90)
			(size 0.519938 1.4986)
			(layers "F.Cu" "F.Mask" "F.Paste")
			(net "M_F_CPU1_SB_CS_N<0>")
		)
		(pad "85" smd rect
			(at -2.050034 13.17498 90)
			(size 0.519938 1.4986)
			(layers "F.Cu" "F.Mask" "F.Paste")
			(net "GND")
		)
		(pad "86" smd rect
			(at -2.050034 14.025118 90)
			(size 0.519938 1.4986)
			(layers "F.Cu" "F.Mask" "F.Paste")
			(net "M_F_CPU1_SA_RSP<0>")
		)
		(pad "87" smd rect
			(at -2.050034 14.875002 90)
			(size 0.519938 1.4986)
			(layers "F.Cu" "F.Mask" "F.Paste")
			(net "M_F_CPU1_SB_RSP<0>")
		)
		(pad "88" smd rect
			(at -2.050034 15.724886 90)
			(size 0.519938 1.4986)
			(layers "F.Cu" "F.Mask" "F.Paste")
			(net "GND")
		)
		(pad "89" smd rect
			(at -2.050034 16.575024 90)
			(size 0.519938 1.4986)
			(layers "F.Cu" "F.Mask" "F.Paste")
			(net "M_F_CPU1_SB_CB<4>")
		)
		(pad "90" smd rect
			(at -2.050034 17.424908 90)
			(size 0.519938 1.4986)
			(layers "F.Cu" "F.Mask" "F.Paste")
			(net "GND")
		)
		(pad "91" smd rect
			(at -2.050034 18.275046 90)
			(size 0.519938 1.4986)
			(layers "F.Cu" "F.Mask" "F.Paste")
			(net "M_F_CPU1_SB_CB<5>")
		)
		(pad "92" smd rect
			(at -2.050034 19.12493 90)
			(size 0.519938 1.4986)
			(layers "F.Cu" "F.Mask" "F.Paste")
			(net "GND")
		)
		(pad "93" smd rect
			(at -2.050034 19.975068 90)
			(size 0.519938 1.4986)
			(layers "F.Cu" "F.Mask" "F.Paste")
			(net "M_F_CPU1_SB_DQS_DP<9>")
		)
		(pad "94" smd rect
			(at -2.050034 20.824952 90)
			(size 0.519938 1.4986)
			(layers "F.Cu" "F.Mask" "F.Paste")
			(net "M_F_CPU1_SB_DQS_DN<9>")
		)
		(pad "95" smd rect
			(at -2.050034 21.67509 90)
			(size 0.519938 1.4986)
			(layers "F.Cu" "F.Mask" "F.Paste")
			(net "GND")
		)
		(pad "96" smd rect
			(at -2.050034 22.524974 90)
			(size 0.519938 1.4986)
			(layers "F.Cu" "F.Mask" "F.Paste")
			(net "M_F_CPU1_SB_CB<0>")
		)
		(pad "97" smd rect
			(at -2.050034 23.375112 90)
			(size 0.519938 1.4986)
			(layers "F.Cu" "F.Mask" "F.Paste")
			(net "GND")
		)
		(pad "98" smd rect
			(at -2.050034 24.224996 90)
			(size 0.519938 1.4986)
			(layers "F.Cu" "F.Mask" "F.Paste")
			(net "M_F_CPU1_SB_CB<1>")
		)
		(pad "99" smd rect
			(at -2.050034 25.07488 90)
			(size 0.519938 1.4986)
			(layers "F.Cu" "F.Mask" "F.Paste")
			(net "GND")
		)
		(pad "100" smd rect
			(at -2.050034 25.925018 90)
			(size 0.519938 1.4986)
			(layers "F.Cu" "F.Mask" "F.Paste")
			(net "M_F_CPU1_SB_DQ<0>")
		)
		(pad "101" smd rect
			(at -2.050034 26.774902 90)
			(size 0.519938 1.4986)
			(layers "F.Cu" "F.Mask" "F.Paste")
			(net "GND")
		)
		(pad "102" smd rect
			(at -2.050034 27.62504 90)
			(size 0.519938 1.4986)
			(layers "F.Cu" "F.Mask" "F.Paste")
			(net "M_F_CPU1_SB_DQ<1>")
		)
		(pad "103" smd rect
			(at -2.050034 28.474924 90)
			(size 0.519938 1.4986)
			(layers "F.Cu" "F.Mask" "F.Paste")
			(net "GND")
		)
		(pad "104" smd rect
			(at -2.050034 29.325062 90)
			(size 0.519938 1.4986)
			(layers "F.Cu" "F.Mask" "F.Paste")
			(net "M_F_CPU1_SB_DQS_DP<0>")
		)
		(pad "105" smd rect
			(at -2.050034 30.174946 90)
			(size 0.519938 1.4986)
			(layers "F.Cu" "F.Mask" "F.Paste")
			(net "M_F_CPU1_SB_DQS_DN<0>")
		)
		(pad "106" smd rect
			(at -2.050034 31.025084 90)
			(size 0.519938 1.4986)
			(layers "F.Cu" "F.Mask" "F.Paste")
			(net "GND")
		)
		(pad "107" smd rect
			(at -2.050034 31.874968 90)
			(size 0.519938 1.4986)
			(layers "F.Cu" "F.Mask" "F.Paste")
			(net "M_F_CPU1_SB_DQ<4>")
		)
		(pad "108" smd rect
			(at -2.050034 32.725106 90)
			(size 0.519938 1.4986)
			(layers "F.Cu" "F.Mask" "F.Paste")
			(net "GND")
		)
		(pad "109" smd rect
			(at -2.050034 33.57499 90)
			(size 0.519938 1.4986)
			(layers "F.Cu" "F.Mask" "F.Paste")
			(net "M_F_CPU1_SB_DQ<5>")
		)
		(pad "110" smd rect
			(at -2.050034 34.425128 90)
			(size 0.519938 1.4986)
			(layers "F.Cu" "F.Mask" "F.Paste")
			(net "GND")
		)
		(pad "111" smd rect
			(at -2.050034 35.275012 90)
			(size 0.519938 1.4986)
			(layers "F.Cu" "F.Mask" "F.Paste")
			(net "M_F_CPU1_SB_DQ<8>")
		)
		(pad "112" smd rect
			(at -2.050034 36.124896 90)
			(size 0.519938 1.4986)
			(layers "F.Cu" "F.Mask" "F.Paste")
			(net "GND")
		)
		(pad "113" smd rect
			(at -2.050034 36.975034 90)
			(size 0.519938 1.4986)
			(layers "F.Cu" "F.Mask" "F.Paste")
			(net "M_F_CPU1_SB_DQ<9>")
		)
		(pad "114" smd rect
			(at -2.050034 37.824918 90)
			(size 0.519938 1.4986)
			(layers "F.Cu" "F.Mask" "F.Paste")
			(net "GND")
		)
		(pad "115" smd rect
			(at -2.050034 38.675056 90)
			(size 0.519938 1.4986)
			(layers "F.Cu" "F.Mask" "F.Paste")
			(net "M_F_CPU1_SB_DQS_DP<1>")
		)
		(pad "116" smd rect
			(at -2.050034 39.52494 90)
			(size 0.519938 1.4986)
			(layers "F.Cu" "F.Mask" "F.Paste")
			(net "M_F_CPU1_SB_DQS_DN<1>")
		)
		(pad "117" smd rect
			(at -2.050034 40.375078 90)
			(size 0.519938 1.4986)
			(layers "F.Cu" "F.Mask" "F.Paste")
			(net "GND")
		)
		(pad "118" smd rect
			(at -2.050034 41.224962 90)
			(size 0.519938 1.4986)
			(layers "F.Cu" "F.Mask" "F.Paste")
			(net "M_F_CPU1_SB_DQ<12>")
		)
		(pad "119" smd rect
			(at -2.050034 42.0751 90)
			(size 0.519938 1.4986)
			(layers "F.Cu" "F.Mask" "F.Paste")
			(net "GND")
		)
		(pad "120" smd rect
			(at -2.050034 42.924984 90)
			(size 0.519938 1.4986)
			(layers "F.Cu" "F.Mask" "F.Paste")
			(net "M_F_CPU1_SB_DQ<13>")
		)
		(pad "121" smd rect
			(at -2.050034 43.775122 90)
			(size 0.519938 1.4986)
			(layers "F.Cu" "F.Mask" "F.Paste")
			(net "GND")
		)
		(pad "122" smd rect
			(at -2.050034 44.625006 90)
			(size 0.519938 1.4986)
			(layers "F.Cu" "F.Mask" "F.Paste")
			(net "M_F_CPU1_SB_DQ<16>")
		)
		(pad "123" smd rect
			(at -2.050034 45.47489 90)
			(size 0.519938 1.4986)
			(layers "F.Cu" "F.Mask" "F.Paste")
			(net "GND")
		)
		(pad "124" smd rect
			(at -2.050034 46.325028 90)
			(size 0.519938 1.4986)
			(layers "F.Cu" "F.Mask" "F.Paste")
			(net "M_F_CPU1_SB_DQ<17>")
		)
		(pad "125" smd rect
			(at -2.050034 47.174912 90)
			(size 0.519938 1.4986)
			(layers "F.Cu" "F.Mask" "F.Paste")
			(net "GND")
		)
		(pad "126" smd rect
			(at -2.050034 48.02505 90)
			(size 0.519938 1.4986)
			(layers "F.Cu" "F.Mask" "F.Paste")
			(net "M_F_CPU1_SB_DQS_DP<2>")
		)
		(pad "127" smd rect
			(at -2.050034 48.874934 90)
			(size 0.519938 1.4986)
			(layers "F.Cu" "F.Mask" "F.Paste")
			(net "M_F_CPU1_SB_DQS_DN<2>")
		)
		(pad "128" smd rect
			(at -2.050034 49.725072 90)
			(size 0.519938 1.4986)
			(layers "F.Cu" "F.Mask" "F.Paste")
			(net "GND")
		)
		(pad "129" smd rect
			(at -2.050034 50.574956 90)
			(size 0.519938 1.4986)
			(layers "F.Cu" "F.Mask" "F.Paste")
			(net "M_F_CPU1_SB_DQ<20>")
		)
		(pad "130" smd rect
			(at -2.050034 51.425094 90)
			(size 0.519938 1.4986)
			(layers "F.Cu" "F.Mask" "F.Paste")
			(net "GND")
		)
		(pad "131" smd rect
			(at -2.050034 52.274978 90)
			(size 0.519938 1.4986)
			(layers "F.Cu" "F.Mask" "F.Paste")
			(net "M_F_CPU1_SB_DQ<21>")
		)
		(pad "132" smd rect
			(at -2.050034 53.125116 90)
			(size 0.519938 1.4986)
			(layers "F.Cu" "F.Mask" "F.Paste")
			(net "GND")
		)
		(pad "133" smd rect
			(at -2.050034 53.975 90)
			(size 0.519938 1.4986)
			(layers "F.Cu" "F.Mask" "F.Paste")
			(net "M_F_CPU1_SB_DQ<24>")
		)
		(pad "134" smd rect
			(at -2.050034 54.824884 90)
			(size 0.519938 1.4986)
			(layers "F.Cu" "F.Mask" "F.Paste")
			(net "GND")
		)
		(pad "135" smd rect
			(at -2.050034 55.675022 90)
			(size 0.519938 1.4986)
			(layers "F.Cu" "F.Mask" "F.Paste")
			(net "M_F_CPU1_SB_DQ<25>")
		)
		(pad "136" smd rect
			(at -2.050034 56.524906 90)
			(size 0.519938 1.4986)
			(layers "F.Cu" "F.Mask" "F.Paste")
			(net "GND")
		)
		(pad "137" smd rect
			(at -2.050034 57.375044 90)
			(size 0.519938 1.4986)
			(layers "F.Cu" "F.Mask" "F.Paste")
			(net "M_F_CPU1_SB_DQS_DP<3>")
		)
		(pad "138" smd rect
			(at -2.050034 58.224928 90)
			(size 0.519938 1.4986)
			(layers "F.Cu" "F.Mask" "F.Paste")
			(net "M_F_CPU1_SB_DQS_DN<3>")
		)
		(pad "139" smd rect
			(at -2.050034 59.075066 90)
			(size 0.519938 1.4986)
			(layers "F.Cu" "F.Mask" "F.Paste")
			(net "GND")
		)
		(pad "140" smd rect
			(at -2.050034 59.92495 90)
			(size 0.519938 1.4986)
			(layers "F.Cu" "F.Mask" "F.Paste")
			(net "M_F_CPU1_SB_DQ<28>")
		)
		(pad "141" smd rect
			(at -2.050034 60.775088 90)
			(size 0.519938 1.4986)
			(layers "F.Cu" "F.Mask" "F.Paste")
			(net "GND")
		)
		(pad "142" smd rect
			(at -2.050034 61.624972 90)
			(size 0.519938 1.4986)
			(layers "F.Cu" "F.Mask" "F.Paste")
			(net "M_F_CPU1_SB_DQ<29>")
		)
		(pad "143" smd rect
			(at -2.050034 62.47511 90)
			(size 0.519938 1.4986)
			(layers "F.Cu" "F.Mask" "F.Paste")
			(net "GND")
		)
		(pad "144" smd rect
			(at -2.050034 63.324994 90)
			(size 0.519938 1.4986)
			(layers "F.Cu" "F.Mask" "F.Paste")
			(net "Net_2327")
		)
		(pad "145" smd rect
			(at 2.050034 -63.324994 90)
			(size 0.519938 1.4986)
			(layers "F.Cu" "F.Mask" "F.Paste")
			(net "P12V_MEM_CPU1")
		)
		(pad "146" smd rect
			(at 2.050034 -62.47511 90)
			(size 0.519938 1.4986)
			(layers "F.Cu" "F.Mask" "F.Paste")
			(net "P12V_MEM_CPU1")
		)
		(pad "147" smd rect
			(at 2.050034 -61.624972 90)
			(size 0.519938 1.4986)
			(layers "F.Cu" "F.Mask" "F.Paste")
			(net "PWRGD_CHF_CPU1_DIMM")
		)
		(pad "148" smd rect
			(at 2.050034 -60.775088 90)
			(size 0.519938 1.4986)
			(layers "F.Cu" "F.Mask" "F.Paste")
			(net "PD_CHF_CPU1_DIMM_SAA")
		)
		(pad "149" smd rect
			(at 2.050034 -59.92495 90)
			(size 0.519938 1.4986)
			(layers "F.Cu" "F.Mask" "F.Paste")
			(net "Net_2328")
		)
		(pad "150" smd rect
			(at 2.050034 -59.075066 90)
			(size 0.519938 1.4986)
			(layers "F.Cu" "F.Mask" "F.Paste")
			(net "Net_2329")
		)
		(pad "151" smd rect
			(at 2.050034 -58.224928 90)
			(size 0.519938 1.4986)
			(layers "F.Cu" "F.Mask" "F.Paste")
			(net "GND")
		)
		(pad "152" smd rect
			(at 2.050034 -57.375044 90)
			(size 0.519938 1.4986)
			(layers "F.Cu" "F.Mask" "F.Paste")
			(net "M_F_CPU1_SA_DQ<2>")
		)
		(pad "153" smd rect
			(at 2.050034 -56.524906 90)
			(size 0.519938 1.4986)
			(layers "F.Cu" "F.Mask" "F.Paste")
			(net "GND")
		)
		(pad "154" smd rect
			(at 2.050034 -55.675022 90)
			(size 0.519938 1.4986)
			(layers "F.Cu" "F.Mask" "F.Paste")
			(net "M_F_CPU1_SA_DQ<3>")
		)
		(pad "155" smd rect
			(at 2.050034 -54.824884 90)
			(size 0.519938 1.4986)
			(layers "F.Cu" "F.Mask" "F.Paste")
			(net "GND")
		)
		(pad "156" smd rect
			(at 2.050034 -53.975 90)
			(size 0.519938 1.4986)
			(layers "F.Cu" "F.Mask" "F.Paste")
			(net "M_F_CPU1_SA_DQS_DN<5>")
		)
		(pad "157" smd rect
			(at 2.050034 -53.125116 90)
			(size 0.519938 1.4986)
			(layers "F.Cu" "F.Mask" "F.Paste")
			(net "M_F_CPU1_SA_DQS_DP<5>")
		)
		(pad "158" smd rect
			(at 2.050034 -52.274978 90)
			(size 0.519938 1.4986)
			(layers "F.Cu" "F.Mask" "F.Paste")
			(net "GND")
		)
		(pad "159" smd rect
			(at 2.050034 -51.425094 90)
			(size 0.519938 1.4986)
			(layers "F.Cu" "F.Mask" "F.Paste")
			(net "M_F_CPU1_SA_DQ<6>")
		)
		(pad "160" smd rect
			(at 2.050034 -50.574956 90)
			(size 0.519938 1.4986)
			(layers "F.Cu" "F.Mask" "F.Paste")
			(net "GND")
		)
		(pad "161" smd rect
			(at 2.050034 -49.725072 90)
			(size 0.519938 1.4986)
			(layers "F.Cu" "F.Mask" "F.Paste")
			(net "M_F_CPU1_SA_DQ<7>")
		)
		(pad "162" smd rect
			(at 2.050034 -48.874934 90)
			(size 0.519938 1.4986)
			(layers "F.Cu" "F.Mask" "F.Paste")
			(net "GND")
		)
		(pad "163" smd rect
			(at 2.050034 -48.02505 90)
			(size 0.519938 1.4986)
			(layers "F.Cu" "F.Mask" "F.Paste")
			(net "M_F_CPU1_SA_DQ<10>")
		)
		(pad "164" smd rect
			(at 2.050034 -47.174912 90)
			(size 0.519938 1.4986)
			(layers "F.Cu" "F.Mask" "F.Paste")
			(net "GND")
		)
		(pad "165" smd rect
			(at 2.050034 -46.325028 90)
			(size 0.519938 1.4986)
			(layers "F.Cu" "F.Mask" "F.Paste")
			(net "M_F_CPU1_SA_DQ<11>")
		)
		(pad "166" smd rect
			(at 2.050034 -45.47489 90)
			(size 0.519938 1.4986)
			(layers "F.Cu" "F.Mask" "F.Paste")
			(net "GND")
		)
		(pad "167" smd rect
			(at 2.050034 -44.625006 90)
			(size 0.519938 1.4986)
			(layers "F.Cu" "F.Mask" "F.Paste")
			(net "M_F_CPU1_SA_DQS_DN<6>")
		)
		(pad "168" smd rect
			(at 2.050034 -43.775122 90)
			(size 0.519938 1.4986)
			(layers "F.Cu" "F.Mask" "F.Paste")
			(net "M_F_CPU1_SA_DQS_DP<6>")
		)
		(pad "169" smd rect
			(at 2.050034 -42.924984 90)
			(size 0.519938 1.4986)
			(layers "F.Cu" "F.Mask" "F.Paste")
			(net "GND")
		)
		(pad "170" smd rect
			(at 2.050034 -42.0751 90)
			(size 0.519938 1.4986)
			(layers "F.Cu" "F.Mask" "F.Paste")
			(net "M_F_CPU1_SA_DQ<14>")
		)
		(pad "171" smd rect
			(at 2.050034 -41.224962 90)
			(size 0.519938 1.4986)
			(layers "F.Cu" "F.Mask" "F.Paste")
			(net "GND")
		)
		(pad "172" smd rect
			(at 2.050034 -40.375078 90)
			(size 0.519938 1.4986)
			(layers "F.Cu" "F.Mask" "F.Paste")
			(net "M_F_CPU1_SA_DQ<15>")
		)
		(pad "173" smd rect
			(at 2.050034 -39.52494 90)
			(size 0.519938 1.4986)
			(layers "F.Cu" "F.Mask" "F.Paste")
			(net "GND")
		)
		(pad "174" smd rect
			(at 2.050034 -38.675056 90)
			(size 0.519938 1.4986)
			(layers "F.Cu" "F.Mask" "F.Paste")
			(net "M_F_CPU1_SA_DQ<18>")
		)
		(pad "175" smd rect
			(at 2.050034 -37.824918 90)
			(size 0.519938 1.4986)
			(layers "F.Cu" "F.Mask" "F.Paste")
			(net "GND")
		)
		(pad "176" smd rect
			(at 2.050034 -36.975034 90)
			(size 0.519938 1.4986)
			(layers "F.Cu" "F.Mask" "F.Paste")
			(net "M_F_CPU1_SA_DQ<19>")
		)
		(pad "177" smd rect
			(at 2.050034 -36.124896 90)
			(size 0.519938 1.4986)
			(layers "F.Cu" "F.Mask" "F.Paste")
			(net "GND")
		)
		(pad "178" smd rect
			(at 2.050034 -35.275012 90)
			(size 0.519938 1.4986)
			(layers "F.Cu" "F.Mask" "F.Paste")
			(net "M_F_CPU1_SA_DQS_DN<7>")
		)
		(pad "179" smd rect
			(at 2.050034 -34.425128 90)
			(size 0.519938 1.4986)
			(layers "F.Cu" "F.Mask" "F.Paste")
			(net "M_F_CPU1_SA_DQS_DP<7>")
		)
		(pad "180" smd rect
			(at 2.050034 -33.57499 90)
			(size 0.519938 1.4986)
			(layers "F.Cu" "F.Mask" "F.Paste")
			(net "GND")
		)
		(pad "181" smd rect
			(at 2.050034 -32.725106 90)
			(size 0.519938 1.4986)
			(layers "F.Cu" "F.Mask" "F.Paste")
			(net "M_F_CPU1_SA_DQ<22>")
		)
		(pad "182" smd rect
			(at 2.050034 -31.874968 90)
			(size 0.519938 1.4986)
			(layers "F.Cu" "F.Mask" "F.Paste")
			(net "GND")
		)
		(pad "183" smd rect
			(at 2.050034 -31.025084 90)
			(size 0.519938 1.4986)
			(layers "F.Cu" "F.Mask" "F.Paste")
			(net "M_F_CPU1_SA_DQ<23>")
		)
		(pad "184" smd rect
			(at 2.050034 -30.174946 90)
			(size 0.519938 1.4986)
			(layers "F.Cu" "F.Mask" "F.Paste")
			(net "GND")
		)
		(pad "185" smd rect
			(at 2.050034 -29.325062 90)
			(size 0.519938 1.4986)
			(layers "F.Cu" "F.Mask" "F.Paste")
			(net "M_F_CPU1_SA_DQ<26>")
		)
		(pad "186" smd rect
			(at 2.050034 -28.474924 90)
			(size 0.519938 1.4986)
			(layers "F.Cu" "F.Mask" "F.Paste")
			(net "GND")
		)
		(pad "187" smd rect
			(at 2.050034 -27.62504 90)
			(size 0.519938 1.4986)
			(layers "F.Cu" "F.Mask" "F.Paste")
			(net "M_F_CPU1_SA_DQ<27>")
		)
		(pad "188" smd rect
			(at 2.050034 -26.774902 90)
			(size 0.519938 1.4986)
			(layers "F.Cu" "F.Mask" "F.Paste")
			(net "GND")
		)
		(pad "189" smd rect
			(at 2.050034 -25.925018 90)
			(size 0.519938 1.4986)
			(layers "F.Cu" "F.Mask" "F.Paste")
			(net "M_F_CPU1_SA_DQS_DN<8>")
		)
		(pad "190" smd rect
			(at 2.050034 -25.07488 90)
			(size 0.519938 1.4986)
			(layers "F.Cu" "F.Mask" "F.Paste")
			(net "M_F_CPU1_SA_DQS_DP<8>")
		)
		(pad "191" smd rect
			(at 2.050034 -24.224996 90)
			(size 0.519938 1.4986)
			(layers "F.Cu" "F.Mask" "F.Paste")
			(net "GND")
		)
		(pad "192" smd rect
			(at 2.050034 -23.375112 90)
			(size 0.519938 1.4986)
			(layers "F.Cu" "F.Mask" "F.Paste")
			(net "M_F_CPU1_SA_DQ<30>")
		)
		(pad "193" smd rect
			(at 2.050034 -22.524974 90)
			(size 0.519938 1.4986)
			(layers "F.Cu" "F.Mask" "F.Paste")
			(net "GND")
		)
		(pad "194" smd rect
			(at 2.050034 -21.67509 90)
			(size 0.519938 1.4986)
			(layers "F.Cu" "F.Mask" "F.Paste")
			(net "M_F_CPU1_SA_DQ<31>")
		)
		(pad "195" smd rect
			(at 2.050034 -20.824952 90)
			(size 0.519938 1.4986)
			(layers "F.Cu" "F.Mask" "F.Paste")
			(net "GND")
		)
		(pad "196" smd rect
			(at 2.050034 -19.975068 90)
			(size 0.519938 1.4986)
			(layers "F.Cu" "F.Mask" "F.Paste")
			(net "M_F_CPU1_SA_CB<2>")
		)
		(pad "197" smd rect
			(at 2.050034 -19.12493 90)
			(size 0.519938 1.4986)
			(layers "F.Cu" "F.Mask" "F.Paste")
			(net "GND")
		)
		(pad "198" smd rect
			(at 2.050034 -18.275046 90)
			(size 0.519938 1.4986)
			(layers "F.Cu" "F.Mask" "F.Paste")
			(net "M_F_CPU1_SA_CB<3>")
		)
		(pad "199" smd rect
			(at 2.050034 -17.424908 90)
			(size 0.519938 1.4986)
			(layers "F.Cu" "F.Mask" "F.Paste")
			(net "GND")
		)
		(pad "200" smd rect
			(at 2.050034 -16.575024 90)
			(size 0.519938 1.4986)
			(layers "F.Cu" "F.Mask" "F.Paste")
			(net "M_F_CPU1_SA_DQS_DN<9>")
		)
		(pad "201" smd rect
			(at 2.050034 -15.724886 90)
			(size 0.519938 1.4986)
			(layers "F.Cu" "F.Mask" "F.Paste")
			(net "M_F_CPU1_SA_DQS_DP<9>")
		)
		(pad "202" smd rect
			(at 2.050034 -14.875002 90)
			(size 0.519938 1.4986)
			(layers "F.Cu" "F.Mask" "F.Paste")
			(net "GND")
		)
		(pad "203" smd rect
			(at 2.050034 -14.025118 90)
			(size 0.519938 1.4986)
			(layers "F.Cu" "F.Mask" "F.Paste")
			(net "M_F_CPU1_SA_CB<6>")
		)
		(pad "204" smd rect
			(at 2.050034 -13.17498 90)
			(size 0.519938 1.4986)
			(layers "F.Cu" "F.Mask" "F.Paste")
			(net "GND")
		)
		(pad "205" smd rect
			(at 2.050034 -12.325096 90)
			(size 0.519938 1.4986)
			(layers "F.Cu" "F.Mask" "F.Paste")
			(net "M_F_CPU1_SA_CB<7>")
		)
		(pad "206" smd rect
			(at 2.050034 -11.474958 90)
			(size 0.519938 1.4986)
			(layers "F.Cu" "F.Mask" "F.Paste")
			(net "GND")
		)
		(pad "207" smd rect
			(at 2.050034 -10.625074 90)
			(size 0.519938 1.4986)
			(layers "F.Cu" "F.Mask" "F.Paste")
			(net "M_F_CPU1_RESET_N")
		)
		(pad "208" smd rect
			(at 2.050034 -9.774936 90)
			(size 0.519938 1.4986)
			(layers "F.Cu" "F.Mask" "F.Paste")
			(net "GND")
		)
		(pad "209" smd rect
			(at 2.050034 -8.925052 90)
			(size 0.519938 1.4986)
			(layers "F.Cu" "F.Mask" "F.Paste")
			(net "M_F_CPU1_SA_CS_N<1>")
		)
		(pad "210" smd rect
			(at 2.050034 -8.074914 90)
			(size 0.519938 1.4986)
			(layers "F.Cu" "F.Mask" "F.Paste")
			(net "GND")
		)
		(pad "211" smd rect
			(at 2.050034 -7.22503 90)
			(size 0.519938 1.4986)
			(layers "F.Cu" "F.Mask" "F.Paste")
			(net "M_F_CPU1_SA_CA<1>")
		)
		(pad "212" smd rect
			(at 2.050034 -6.374892 90)
			(size 0.519938 1.4986)
			(layers "F.Cu" "F.Mask" "F.Paste")
			(net "GND")
		)
		(pad "213" smd rect
			(at 2.050034 -5.525008 90)
			(size 0.519938 1.4986)
			(layers "F.Cu" "F.Mask" "F.Paste")
			(net "M_F_CPU1_SA_CA<3>")
		)
		(pad "214" smd rect
			(at 2.050034 -4.675124 90)
			(size 0.519938 1.4986)
			(layers "F.Cu" "F.Mask" "F.Paste")
			(net "GND")
		)
		(pad "215" smd rect
			(at 2.050034 -3.824986 90)
			(size 0.519938 1.4986)
			(layers "F.Cu" "F.Mask" "F.Paste")
			(net "M_F_CPU1_SA_CA<5>")
		)
		(pad "216" smd rect
			(at 2.050034 -2.975102 90)
			(size 0.519938 1.4986)
			(layers "F.Cu" "F.Mask" "F.Paste")
			(net "GND")
		)
		(pad "217" smd rect
			(at 2.050034 -2.124964 90)
			(size 0.519938 1.4986)
			(layers "F.Cu" "F.Mask" "F.Paste")
			(net "M_F_CPU1_CLK_DP<0>")
		)
		(pad "218" smd rect
			(at 2.050034 -1.27508 90)
			(size 0.519938 1.4986)
			(layers "F.Cu" "F.Mask" "F.Paste")
			(net "M_F_CPU1_CLK_DN<0>")
		)
		(pad "219" smd rect
			(at 2.050034 -0.424942 90)
			(size 0.519938 1.4986)
			(layers "F.Cu" "F.Mask" "F.Paste")
			(net "GND")
		)
		(pad "220" smd rect
			(at 2.050034 5.525008 90)
			(size 0.519938 1.4986)
			(layers "F.Cu" "F.Mask" "F.Paste")
			(net "Net_2330")
		)
		(pad "221" smd rect
			(at 2.050034 6.374892 90)
			(size 0.519938 1.4986)
			(layers "F.Cu" "F.Mask" "F.Paste")
			(net "M_F_CPU1_SB_CA<1>")
		)
		(pad "222" smd rect
			(at 2.050034 7.22503 90)
			(size 0.519938 1.4986)
			(layers "F.Cu" "F.Mask" "F.Paste")
			(net "GND")
		)
		(pad "223" smd rect
			(at 2.050034 8.074914 90)
			(size 0.519938 1.4986)
			(layers "F.Cu" "F.Mask" "F.Paste")
			(net "M_F_CPU1_SB_CA<3>")
		)
		(pad "224" smd rect
			(at 2.050034 8.925052 90)
			(size 0.519938 1.4986)
			(layers "F.Cu" "F.Mask" "F.Paste")
			(net "GND")
		)
		(pad "225" smd rect
			(at 2.050034 9.774936 90)
			(size 0.519938 1.4986)
			(layers "F.Cu" "F.Mask" "F.Paste")
			(net "M_F_CPU1_SB_CA<5>")
		)
		(pad "226" smd rect
			(at 2.050034 10.625074 90)
			(size 0.519938 1.4986)
			(layers "F.Cu" "F.Mask" "F.Paste")
			(net "GND")
		)
		(pad "227" smd rect
			(at 2.050034 11.474958 90)
			(size 0.519938 1.4986)
			(layers "F.Cu" "F.Mask" "F.Paste")
			(net "M_F_CPU1_SB_PAR")
		)
		(pad "228" smd rect
			(at 2.050034 12.325096 90)
			(size 0.519938 1.4986)
			(layers "F.Cu" "F.Mask" "F.Paste")
			(net "GND")
		)
		(pad "229" smd rect
			(at 2.050034 13.17498 90)
			(size 0.519938 1.4986)
			(layers "F.Cu" "F.Mask" "F.Paste")
			(net "M_F_CPU1_SB_CS_N<1>")
		)
		(pad "230" smd rect
			(at 2.050034 14.025118 90)
			(size 0.519938 1.4986)
			(layers "F.Cu" "F.Mask" "F.Paste")
			(net "GND")
		)
		(pad "231" smd rect
			(at 2.050034 14.875002 90)
			(size 0.519938 1.4986)
			(layers "F.Cu" "F.Mask" "F.Paste")
			(net "Net_2331")
		)
		(pad "232" smd rect
			(at 2.050034 15.724886 90)
			(size 0.519938 1.4986)
			(layers "F.Cu" "F.Mask" "F.Paste")
			(net "Net_2332")
		)
		(pad "233" smd rect
			(at 2.050034 16.575024 90)
			(size 0.519938 1.4986)
			(layers "F.Cu" "F.Mask" "F.Paste")
			(net "GND")
		)
		(pad "234" smd rect
			(at 2.050034 17.424908 90)
			(size 0.519938 1.4986)
			(layers "F.Cu" "F.Mask" "F.Paste")
			(net "M_F_CPU1_SB_CB<6>")
		)
		(pad "235" smd rect
			(at 2.050034 18.275046 90)
			(size 0.519938 1.4986)
			(layers "F.Cu" "F.Mask" "F.Paste")
			(net "GND")
		)
		(pad "236" smd rect
			(at 2.050034 19.12493 90)
			(size 0.519938 1.4986)
			(layers "F.Cu" "F.Mask" "F.Paste")
			(net "M_F_CPU1_SB_CB<7>")
		)
		(pad "237" smd rect
			(at 2.050034 19.975068 90)
			(size 0.519938 1.4986)
			(layers "F.Cu" "F.Mask" "F.Paste")
			(net "GND")
		)
		(pad "238" smd rect
			(at 2.050034 20.824952 90)
			(size 0.519938 1.4986)
			(layers "F.Cu" "F.Mask" "F.Paste")
			(net "M_F_CPU1_SB_DQS_DN<4>")
		)
		(pad "239" smd rect
			(at 2.050034 21.67509 90)
			(size 0.519938 1.4986)
			(layers "F.Cu" "F.Mask" "F.Paste")
			(net "M_F_CPU1_SB_DQS_DP<4>")
		)
		(pad "240" smd rect
			(at 2.050034 22.524974 90)
			(size 0.519938 1.4986)
			(layers "F.Cu" "F.Mask" "F.Paste")
			(net "GND")
		)
		(pad "241" smd rect
			(at 2.050034 23.375112 90)
			(size 0.519938 1.4986)
			(layers "F.Cu" "F.Mask" "F.Paste")
			(net "M_F_CPU1_SB_CB<2>")
		)
		(pad "242" smd rect
			(at 2.050034 24.224996 90)
			(size 0.519938 1.4986)
			(layers "F.Cu" "F.Mask" "F.Paste")
			(net "GND")
		)
		(pad "243" smd rect
			(at 2.050034 25.07488 90)
			(size 0.519938 1.4986)
			(layers "F.Cu" "F.Mask" "F.Paste")
			(net "M_F_CPU1_SB_CB<3>")
		)
		(pad "244" smd rect
			(at 2.050034 25.925018 90)
			(size 0.519938 1.4986)
			(layers "F.Cu" "F.Mask" "F.Paste")
			(net "GND")
		)
		(pad "245" smd rect
			(at 2.050034 26.774902 90)
			(size 0.519938 1.4986)
			(layers "F.Cu" "F.Mask" "F.Paste")
			(net "M_F_CPU1_SB_DQ<2>")
		)
		(pad "246" smd rect
			(at 2.050034 27.62504 90)
			(size 0.519938 1.4986)
			(layers "F.Cu" "F.Mask" "F.Paste")
			(net "GND")
		)
		(pad "247" smd rect
			(at 2.050034 28.474924 90)
			(size 0.519938 1.4986)
			(layers "F.Cu" "F.Mask" "F.Paste")
			(net "M_F_CPU1_SB_DQ<3>")
		)
		(pad "248" smd rect
			(at 2.050034 29.325062 90)
			(size 0.519938 1.4986)
			(layers "F.Cu" "F.Mask" "F.Paste")
			(net "GND")
		)
		(pad "249" smd rect
			(at 2.050034 30.174946 90)
			(size 0.519938 1.4986)
			(layers "F.Cu" "F.Mask" "F.Paste")
			(net "M_F_CPU1_SB_DQS_DN<5>")
		)
		(pad "250" smd rect
			(at 2.050034 31.025084 90)
			(size 0.519938 1.4986)
			(layers "F.Cu" "F.Mask" "F.Paste")
			(net "M_F_CPU1_SB_DQS_DP<5>")
		)
		(pad "251" smd rect
			(at 2.050034 31.874968 90)
			(size 0.519938 1.4986)
			(layers "F.Cu" "F.Mask" "F.Paste")
			(net "GND")
		)
		(pad "252" smd rect
			(at 2.050034 32.725106 90)
			(size 0.519938 1.4986)
			(layers "F.Cu" "F.Mask" "F.Paste")
			(net "M_F_CPU1_SB_DQ<6>")
		)
		(pad "253" smd rect
			(at 2.050034 33.57499 90)
			(size 0.519938 1.4986)
			(layers "F.Cu" "F.Mask" "F.Paste")
			(net "GND")
		)
		(pad "254" smd rect
			(at 2.050034 34.425128 90)
			(size 0.519938 1.4986)
			(layers "F.Cu" "F.Mask" "F.Paste")
			(net "M_F_CPU1_SB_DQ<7>")
		)
		(pad "255" smd rect
			(at 2.050034 35.275012 90)
			(size 0.519938 1.4986)
			(layers "F.Cu" "F.Mask" "F.Paste")
			(net "GND")
		)
		(pad "256" smd rect
			(at 2.050034 36.124896 90)
			(size 0.519938 1.4986)
			(layers "F.Cu" "F.Mask" "F.Paste")
			(net "M_F_CPU1_SB_DQ<10>")
		)
		(pad "257" smd rect
			(at 2.050034 36.975034 90)
			(size 0.519938 1.4986)
			(layers "F.Cu" "F.Mask" "F.Paste")
			(net "GND")
		)
		(pad "258" smd rect
			(at 2.050034 37.824918 90)
			(size 0.519938 1.4986)
			(layers "F.Cu" "F.Mask" "F.Paste")
			(net "M_F_CPU1_SB_DQ<11>")
		)
		(pad "259" smd rect
			(at 2.050034 38.675056 90)
			(size 0.519938 1.4986)
			(layers "F.Cu" "F.Mask" "F.Paste")
			(net "GND")
		)
		(pad "260" smd rect
			(at 2.050034 39.52494 90)
			(size 0.519938 1.4986)
			(layers "F.Cu" "F.Mask" "F.Paste")
			(net "M_F_CPU1_SB_DQS_DN<6>")
		)
		(pad "261" smd rect
			(at 2.050034 40.375078 90)
			(size 0.519938 1.4986)
			(layers "F.Cu" "F.Mask" "F.Paste")
			(net "M_F_CPU1_SB_DQS_DP<6>")
		)
		(pad "262" smd rect
			(at 2.050034 41.224962 90)
			(size 0.519938 1.4986)
			(layers "F.Cu" "F.Mask" "F.Paste")
			(net "GND")
		)
		(pad "263" smd rect
			(at 2.050034 42.0751 90)
			(size 0.519938 1.4986)
			(layers "F.Cu" "F.Mask" "F.Paste")
			(net "M_F_CPU1_SB_DQ<14>")
		)
		(pad "264" smd rect
			(at 2.050034 42.924984 90)
			(size 0.519938 1.4986)
			(layers "F.Cu" "F.Mask" "F.Paste")
			(net "GND")
		)
		(pad "265" smd rect
			(at 2.050034 43.775122 90)
			(size 0.519938 1.4986)
			(layers "F.Cu" "F.Mask" "F.Paste")
			(net "M_F_CPU1_SB_DQ<15>")
		)
		(pad "266" smd rect
			(at 2.050034 44.625006 90)
			(size 0.519938 1.4986)
			(layers "F.Cu" "F.Mask" "F.Paste")
			(net "GND")
		)
		(pad "267" smd rect
			(at 2.050034 45.47489 90)
			(size 0.519938 1.4986)
			(layers "F.Cu" "F.Mask" "F.Paste")
			(net "M_F_CPU1_SB_DQ<18>")
		)
		(pad "268" smd rect
			(at 2.050034 46.325028 90)
			(size 0.519938 1.4986)
			(layers "F.Cu" "F.Mask" "F.Paste")
			(net "GND")
		)
		(pad "269" smd rect
			(at 2.050034 47.174912 90)
			(size 0.519938 1.4986)
			(layers "F.Cu" "F.Mask" "F.Paste")
			(net "M_F_CPU1_SB_DQ<19>")
		)
		(pad "270" smd rect
			(at 2.050034 48.02505 90)
			(size 0.519938 1.4986)
			(layers "F.Cu" "F.Mask" "F.Paste")
			(net "GND")
		)
		(pad "271" smd rect
			(at 2.050034 48.874934 90)
			(size 0.519938 1.4986)
			(layers "F.Cu" "F.Mask" "F.Paste")
			(net "M_F_CPU1_SB_DQS_DN<7>")
		)
		(pad "272" smd rect
			(at 2.050034 49.725072 90)
			(size 0.519938 1.4986)
			(layers "F.Cu" "F.Mask" "F.Paste")
			(net "M_F_CPU1_SB_DQS_DP<7>")
		)
		(pad "273" smd rect
			(at 2.050034 50.574956 90)
			(size 0.519938 1.4986)
			(layers "F.Cu" "F.Mask" "F.Paste")
			(net "GND")
		)
		(pad "274" smd rect
			(at 2.050034 51.425094 90)
			(size 0.519938 1.4986)
			(layers "F.Cu" "F.Mask" "F.Paste")
			(net "M_F_CPU1_SB_DQ<22>")
		)
		(pad "275" smd rect
			(at 2.050034 52.274978 90)
			(size 0.519938 1.4986)
			(layers "F.Cu" "F.Mask" "F.Paste")
			(net "GND")
		)
		(pad "276" smd rect
			(at 2.050034 53.125116 90)
			(size 0.519938 1.4986)
			(layers "F.Cu" "F.Mask" "F.Paste")
			(net "M_F_CPU1_SB_DQ<23>")
		)
		(pad "277" smd rect
			(at 2.050034 53.975 90)
			(size 0.519938 1.4986)
			(layers "F.Cu" "F.Mask" "F.Paste")
			(net "GND")
		)
		(pad "278" smd rect
			(at 2.050034 54.824884 90)
			(size 0.519938 1.4986)
			(layers "F.Cu" "F.Mask" "F.Paste")
			(net "M_F_CPU1_SB_DQ<26>")
		)
		(pad "279" smd rect
			(at 2.050034 55.675022 90)
			(size 0.519938 1.4986)
			(layers "F.Cu" "F.Mask" "F.Paste")
			(net "GND")
		)
		(pad "280" smd rect
			(at 2.050034 56.524906 90)
			(size 0.519938 1.4986)
			(layers "F.Cu" "F.Mask" "F.Paste")
			(net "M_F_CPU1_SB_DQ<27>")
		)
		(pad "281" smd rect
			(at 2.050034 57.375044 90)
			(size 0.519938 1.4986)
			(layers "F.Cu" "F.Mask" "F.Paste")
			(net "GND")
		)
		(pad "282" smd rect
			(at 2.050034 58.224928 90)
			(size 0.519938 1.4986)
			(layers "F.Cu" "F.Mask" "F.Paste")
			(net "M_F_CPU1_SB_DQS_DN<8>")
		)
		(pad "283" smd rect
			(at 2.050034 59.075066 90)
			(size 0.519938 1.4986)
			(layers "F.Cu" "F.Mask" "F.Paste")
			(net "M_F_CPU1_SB_DQS_DP<8>")
		)
		(pad "284" smd rect
			(at 2.050034 59.92495 90)
			(size 0.519938 1.4986)
			(layers "F.Cu" "F.Mask" "F.Paste")
			(net "GND")
		)
		(pad "285" smd rect
			(at 2.050034 60.775088 90)
			(size 0.519938 1.4986)
			(layers "F.Cu" "F.Mask" "F.Paste")
			(net "M_F_CPU1_SB_DQ<30>")
		)
		(pad "286" smd rect
			(at 2.050034 61.624972 90)
			(size 0.519938 1.4986)
			(layers "F.Cu" "F.Mask" "F.Paste")
			(net "GND")
		)
		(pad "287" smd rect
			(at 2.050034 62.47511 90)
			(size 0.519938 1.4986)
			(layers "F.Cu" "F.Mask" "F.Paste")
			(net "M_F_CPU1_SB_DQ<31>")
		)
		(pad "288" smd rect
			(at 2.050034 63.324994 90)
			(size 0.519938 1.4986)
			(layers "F.Cu" "F.Mask" "F.Paste")
			(net "GND")
		)
		(pad "G1" thru_hole oval
			(at 0 -68.97497 90)
			(size 1.7272 3.4798)
			(drill oval 1.2192 2.4638)
			(layers "*.Cu" "*.Mask")
			(remove_unused_layers no)
			(net "GND")
			(clearance 0.127)
			(thermal_gap 0.127)
		)
		(pad "G2" thru_hole oval
			(at 0 3.875024 90)
			(size 1.7272 3.4798)
			(drill oval 1.2192 2.4638)
			(layers "*.Cu" "*.Mask")
			(remove_unused_layers no)
			(net "GND")
			(clearance 0.127)
			(thermal_gap 0.127)
		)
		(pad "G3" thru_hole oval
			(at 0 68.97497 90)
			(size 1.7272 3.4798)
			(drill oval 1.2192 2.4638)
			(layers "*.Cu" "*.Mask")
			(remove_unused_layers no)
			(net "GND")
			(clearance 0.127)
			(thermal_gap 0.127)
		)
	)
	(footprint ""
		(layer "F.Cu")
		(at 454.210674 -397.245332)
		(property "Reference" "PU6504"
			(at -2.411984 -7.177024 0)
			(unlocked yes)
			(layer "F.SilkS")
			(effects
				(font
					(size 0.7874 0.5842)
					(thickness 0.1524)
				)
				(justify left)
			)
		)
		(property "Value" ""
			(at 0 0 0)
			(layer "F.Fab")
			(effects
				(font
					(size 1.27 1.27)
				)
			)
		)
		(duplicate_pad_numbers_are_jumpers no)
		(fp_line
			(start -2.500122 -2.999994)
			(end -2.24409 -2.999994)
			(stroke
				(width 0.1524)
				(type default)
			)
			(layer "F.SilkS")
		)
		(fp_line
			(start -2.500122 -2.529078)
			(end -2.500122 -2.999994)
			(stroke
				(width 0.1524)
				(type default)
			)
			(layer "F.SilkS")
		)
		(fp_line
			(start -2.500122 0.6604)
			(end -2.500122 0.229108)
			(stroke
				(width 0.1524)
				(type default)
			)
			(layer "F.SilkS")
		)
		(fp_line
			(start -2.500122 2.999994)
			(end -2.500122 2.339594)
			(stroke
				(width 0.1524)
				(type default)
			)
			(layer "F.SilkS")
		)
		(fp_line
			(start -2.2987 2.999994)
			(end -2.500122 2.999994)
			(stroke
				(width 0.1524)
				(type default)
			)
			(layer "F.SilkS")
		)
		(fp_line
			(start 2.31394 -2.999994)
			(end 2.500122 -2.999994)
			(stroke
				(width 0.1524)
				(type default)
			)
			(layer "F.SilkS")
		)
		(fp_line
			(start 2.500122 -2.999994)
			(end 2.500122 -2.44348)
			(stroke
				(width 0.1524)
				(type default)
			)
			(layer "F.SilkS")
		)
		(fp_line
			(start 2.500122 2.339594)
			(end 2.500122 2.999994)
			(stroke
				(width 0.1524)
				(type default)
			)
			(layer "F.SilkS")
		)
		(fp_line
			(start 2.500122 2.999994)
			(end 2.2987 2.999994)
			(stroke
				(width 0.1524)
				(type default)
			)
			(layer "F.SilkS")
		)
		(fp_poly
			(pts
				(xy -3.10769 -3.61823) (xy -3.812794 -2.886964) (xy -2.728722 -2.54762)
			)
			(stroke
				(width 0)
				(type default)
			)
			(fill yes)
			(layer "F.SilkS")
		)
		(fp_line
			(start -2.500122 -2.999994)
			(end 2.500122 -2.999994)
			(stroke
				(width 0.1)
				(type default)
			)
			(layer "F.Fab")
		)
		(fp_line
			(start -2.500122 2.999994)
			(end -2.500122 -2.999994)
			(stroke
				(width 0.1)
				(type default)
			)
			(layer "F.Fab")
		)
		(fp_line
			(start 2.500122 -2.999994)
			(end 2.500122 2.999994)
			(stroke
				(width 0.1)
				(type default)
			)
			(layer "F.Fab")
		)
		(fp_line
			(start 2.500122 2.999994)
			(end -2.500122 2.999994)
			(stroke
				(width 0.1)
				(type default)
			)
			(layer "F.Fab")
		)
		(fp_poly
			(pts
				(xy -4.218432 -2.783078) (xy -4.218432 -1.767078) (xy -3.202432 -2.275078)
			)
			(stroke
				(width 0)
				(type default)
			)
			(fill yes)
			(layer "F.Fab")
		)
		(pad "1" smd rect
			(at -2.400046 -2.275078 90)
			(size 0.2286 0.6096)
			(layers "F.Cu" "F.Mask" "F.Paste")
			(net "P0V9_RETIMER_CPU0_VOS2")
		)
		(pad "2" smd rect
			(at -2.400046 -1.82499 90)
			(size 0.2286 0.6096)
			(layers "F.Cu" "F.Mask" "F.Paste")
			(net "GND")
		)
		(pad "3" smd rect
			(at -2.400046 -1.374902 90)
			(size 0.2286 0.6096)
			(layers "F.Cu" "F.Mask" "F.Paste")
			(net "P0V9_RETIMER_CPU0_VCC2")
		)
		(pad "4" smd rect
			(at -2.400046 -0.925068 90)
			(size 0.2286 0.6096)
			(layers "F.Cu" "F.Mask" "F.Paste")
			(net "P0V9_RETIMER_CPU0_PVCC")
		)
		(pad "5" smd rect
			(at -2.400046 -0.47498 90)
			(size 0.2286 0.6096)
			(layers "F.Cu" "F.Mask" "F.Paste")
			(net "GND")
		)
		(pad "6" smd rect
			(at -2.400046 -0.024892 90)
			(size 0.2286 0.6096)
			(layers "F.Cu" "F.Mask" "F.Paste")
			(net "NC_PV09_RETIMER_CPU0_GL1_2")
		)
		(pad "7_9-20_24" smd circle
			(at 0 1.150112 90)
			(size 0 0)
			(layers "F.Cu" "F.Mask" "F.Paste")
			(net "GND")
		)
		(pad "10_19" smd rect
			(at 0 2.899918 90)
			(size 0.6096 4.318)
			(layers "F.Cu" "F.Mask" "F.Paste")
			(net "SW_P0V9_RETIMER_CPU0_SW2")
		)
		(pad "25_29" smd rect
			(at 1.549908 -1.279906 270)
			(size 2.0574 2.3114)
			(layers "F.Cu" "F.Mask" "F.Paste")
			(net "SW_P12V_AUX_P0V9_RETIMER_CPU0_FLT")
		)
		(pad "30" smd rect
			(at 2.05994 -2.899918)
			(size 0.2286 0.6096)
			(layers "F.Cu" "F.Mask" "F.Paste")
			(net "SW_P12V_AUX_P0V9_RETIMER_CPU0_FLT")
		)
		(pad "31" smd rect
			(at 1.610106 -2.899918)
			(size 0.2286 0.6096)
			(layers "F.Cu" "F.Mask" "F.Paste")
			(net "NC_PV09_RETIMER_CPU0_DNC2")
		)
		(pad "32" smd rect
			(at 1.160018 -2.899918)
			(size 0.2286 0.6096)
			(layers "F.Cu" "F.Mask" "F.Paste")
			(net "SW_P0V9_RETIMER_CPU0_PH2")
		)
		(pad "33" smd rect
			(at 0.70993 -2.899918)
			(size 0.2286 0.6096)
			(layers "F.Cu" "F.Mask" "F.Paste")
			(net "SW_P0V9_RETIMER_CPU0_BOOT2")
		)
		(pad "34" smd rect
			(at 0.260096 -2.899918)
			(size 0.2286 0.6096)
			(layers "F.Cu" "F.Mask" "F.Paste")
			(net "P0V9_RETIMER_CPU0_PWM2")
		)
		(pad "35" smd rect
			(at -0.189992 -2.899918)
			(size 0.2286 0.6096)
			(layers "F.Cu" "F.Mask" "F.Paste")
			(net "P0V9_RETIMER_CPU0_VCC2")
		)
		(pad "36" smd rect
			(at -0.64008 -2.899918)
			(size 0.2286 0.6096)
			(layers "F.Cu" "F.Mask" "F.Paste")
			(net "P0V9_RETIMER_CPU0_TEMP0")
		)
		(pad "37" smd rect
			(at -1.089914 -2.899918)
			(size 0.2286 0.6096)
			(layers "F.Cu" "F.Mask" "F.Paste")
			(net "P0V9_RETIMER_CPU0_LSET2")
		)
		(pad "38" smd rect
			(at -1.540002 -2.899918)
			(size 0.2286 0.6096)
			(layers "F.Cu" "F.Mask" "F.Paste")
			(net "P0V9_RETIMER_CPU0_IMON2")
		)
		(pad "39" smd rect
			(at -1.99009 -2.899918)
			(size 0.2286 0.6096)
			(layers "F.Cu" "F.Mask" "F.Paste")
			(net "PV09_RETIMER_CPU0_VCCS")
		)
		(pad "40" smd rect
			(at -0.87503 -1.27508)
			(size 1.7526 1.9558)
			(layers "F.Cu" "F.Mask" "F.Paste")
			(net "GND")
		)
		(pad "41" smd rect
			(at -1.525016 0.249936 270)
			(size 0.3048 0.4572)
			(layers "F.Cu" "F.Mask" "F.Paste")
			(net "NC_PV09_RETIMER_CPU0_GL2_2")
		)
		(zone
			(layer "F.Cu")
			(hatch none 0.5)
			(connect_pads
				(clearance 0)
			)
			(min_thickness 0.25)
			(keepout
				(tracks not_allowed)
				(vias allowed)
				(pads allowed)
				(copperpour not_allowed)
				(footprints allowed)
			)
			(placement
				(enabled no)
				(sheetname "")
			)
			(fill
				(thermal_gap 0.5)
				(thermal_bridge_width 0.5)
				(island_removal_mode 0)
			)
			(polygon
				(pts
					(xy 451.710552 -394.245338) (xy 451.710552 -394.994638) (xy 456.710796 -394.994638) (xy 456.710796 -394.245338)
					(xy 456.420474 -394.245338) (xy 456.420474 -394.701014) (xy 452.000874 -394.701014) (xy 452.000874 -394.245338)
				)
			)
		)
		(zone
			(layer "F.Cu")
			(hatch none 0.5)
			(connect_pads
				(clearance 0)
			)
			(min_thickness 0.25)
			(keepout
				(tracks not_allowed)
				(vias allowed)
				(pads allowed)
				(copperpour not_allowed)
				(footprints allowed)
			)
			(placement
				(enabled no)
				(sheetname "")
			)
			(fill
				(thermal_gap 0.5)
				(thermal_bridge_width 0.5)
				(island_removal_mode 0)
			)
			(polygon
				(pts
					(xy 451.710552 -396.496032) (xy 451.710552 -396.952724) (xy 452.406258 -396.952724) (xy 452.406258 -396.792196)
					(xy 452.965058 -396.792196) (xy 452.965058 -397.198596) (xy 452.406258 -397.198596) (xy 452.406258 -396.978124)
					(xy 451.710552 -396.978124) (xy 451.710552 -397.105124) (xy 452.166228 -397.105124) (xy 452.166228 -399.282666)
					(xy 452.408544 -399.282666) (xy 452.408544 -397.491712) (xy 454.262744 -397.491712) (xy 454.262744 -399.549112)
					(xy 452.408544 -399.549112) (xy 452.408544 -399.308066) (xy 452.166228 -399.308066) (xy 452.166228 -399.78965)
					(xy 456.710796 -399.78965) (xy 456.710796 -399.604738) (xy 454.554082 -399.604738) (xy 454.554082 -397.445738)
					(xy 456.710796 -397.445738) (xy 456.710796 -397.196056) (xy 453.259952 -397.196056) (xy 453.259952 -396.496032)
				)
			)
		)
	)
	(footprint ""
		(layer "F.Cu")
		(at 126.659894 -160.33496 -90)
		(property "Reference" "PC318_8"
			(at 0 0 270)
			(layer "F.SilkS")
			(hide yes)
			(effects
				(font
					(size 1.27 1.27)
				)
			)
		)
		(property "Value" ""
			(at 0 0 270)
			(layer "F.Fab")
			(effects
				(font
					(size 1.27 1.27)
				)
			)
		)
		(duplicate_pad_numbers_are_jumpers no)
		(fp_line
			(start -0.7874 0.4064)
			(end -0.7874 -0.4064)
			(stroke
				(width 0.1524)
				(type default)
			)
			(layer "F.SilkS")
		)
		(fp_line
			(start 0.7874 0.4064)
			(end -0.7874 0.4064)
			(stroke
				(width 0.1524)
				(type default)
			)
			(layer "F.SilkS")
		)
		(fp_line
			(start -0.7874 -0.4064)
			(end 0.7874 -0.4064)
			(stroke
				(width 0.1524)
				(type default)
			)
			(layer "F.SilkS")
		)
		(fp_line
			(start 0.7874 -0.4064)
			(end 0.7874 0.4064)
			(stroke
				(width 0.1524)
				(type default)
			)
			(layer "F.SilkS")
		)
		(fp_line
			(start -0.67945 0.3048)
			(end -0.67945 -0.305054)
			(stroke
				(width 0.1)
				(type default)
			)
			(layer "F.Fab")
		)
		(fp_line
			(start -0.12065 0.3048)
			(end -0.67945 0.3048)
			(stroke
				(width 0.1)
				(type default)
			)
			(layer "F.Fab")
		)
		(fp_line
			(start 0.120396 0.3048)
			(end 0.120396 0.2794)
			(stroke
				(width 0.1)
				(type default)
			)
			(layer "F.Fab")
		)
		(fp_line
			(start 0.67945 0.3048)
			(end 0.120396 0.3048)
			(stroke
				(width 0.1)
				(type default)
			)
			(layer "F.Fab")
		)
		(fp_line
			(start -0.12065 0.2794)
			(end -0.12065 0.3048)
			(stroke
				(width 0.1)
				(type default)
			)
			(layer "F.Fab")
		)
		(fp_line
			(start 0.120396 0.2794)
			(end -0.12065 0.2794)
			(stroke
				(width 0.1)
				(type default)
			)
			(layer "F.Fab")
		)
		(fp_line
			(start -0.12065 -0.2794)
			(end 0.12065 -0.2794)
			(stroke
				(width 0.1)
				(type default)
			)
			(layer "F.Fab")
		)
		(fp_line
			(start 0.12065 -0.2794)
			(end 0.12065 -0.3048)
			(stroke
				(width 0.1)
				(type default)
			)
			(layer "F.Fab")
		)
		(fp_line
			(start 0.12065 -0.3048)
			(end 0.67945 -0.3048)
			(stroke
				(width 0.1)
				(type default)
			)
			(layer "F.Fab")
		)
		(fp_line
			(start 0.67945 -0.3048)
			(end 0.67945 0.3048)
			(stroke
				(width 0.1)
				(type default)
			)
			(layer "F.Fab")
		)
		(fp_line
			(start -0.67945 -0.305054)
			(end -0.12065 -0.305054)
			(stroke
				(width 0.1)
				(type default)
			)
			(layer "F.Fab")
		)
		(fp_line
			(start -0.12065 -0.305054)
			(end -0.12065 -0.2794)
			(stroke
				(width 0.1)
				(type default)
			)
			(layer "F.Fab")
		)
		(pad "1" smd circle
			(at -0.40005 0 270)
			(size 0 0)
			(layers "F.Cu" "F.Mask" "F.Paste")
			(net "PVDDCR_CPU0_P1_VCCS")
		)
		(pad "2" smd circle
			(at 0.40005 0 270)
			(size 0 0)
			(layers "F.Cu" "F.Mask" "F.Paste")
			(net "GND")
		)
	)
	(footprint ""
		(layer "F.Cu")
		(at 239.53597 -292.988238 180)
		(property "Reference" "PR6502"
			(at 0 0 180)
			(layer "F.SilkS")
			(hide yes)
			(effects
				(font
					(size 1.27 1.27)
				)
			)
		)
		(property "Value" ""
			(at 0 0 180)
			(layer "F.Fab")
			(effects
				(font
					(size 1.27 1.27)
				)
			)
		)
		(duplicate_pad_numbers_are_jumpers no)
		(fp_line
			(start 0.7874 0.4064)
			(end -0.7874 0.4064)
			(stroke
				(width 0.1524)
				(type default)
			)
			(layer "F.SilkS")
		)
		(fp_line
			(start 0.7874 -0.4064)
			(end 0.7874 0.4064)
			(stroke
				(width 0.1524)
				(type default)
			)
			(layer "F.SilkS")
		)
		(fp_line
			(start -0.7874 0.4064)
			(end -0.7874 -0.4064)
			(stroke
				(width 0.1524)
				(type default)
			)
			(layer "F.SilkS")
		)
		(fp_line
			(start -0.7874 -0.4064)
			(end 0.7874 -0.4064)
			(stroke
				(width 0.1524)
				(type default)
			)
			(layer "F.SilkS")
		)
		(fp_line
			(start 0.67945 0.3048)
			(end 0.120396 0.3048)
			(stroke
				(width 0.1)
				(type default)
			)
			(layer "F.Fab")
		)
		(fp_line
			(start 0.67945 -0.3048)
			(end 0.67945 0.3048)
			(stroke
				(width 0.1)
				(type default)
			)
			(layer "F.Fab")
		)
		(fp_line
			(start 0.12065 -0.2794)
			(end 0.12065 -0.3048)
			(stroke
				(width 0.1)
				(type default)
			)
			(layer "F.Fab")
		)
		(fp_line
			(start 0.12065 -0.3048)
			(end 0.67945 -0.3048)
			(stroke
				(width 0.1)
				(type default)
			)
			(layer "F.Fab")
		)
		(fp_line
			(start 0.120396 0.3048)
			(end 0.120396 0.2794)
			(stroke
				(width 0.1)
				(type default)
			)
			(layer "F.Fab")
		)
		(fp_line
			(start 0.120396 0.2794)
			(end -0.12065 0.2794)
			(stroke
				(width 0.1)
				(type default)
			)
			(layer "F.Fab")
		)
		(fp_line
			(start -0.12065 0.3048)
			(end -0.67945 0.3048)
			(stroke
				(width 0.1)
				(type default)
			)
			(layer "F.Fab")
		)
		(fp_line
			(start -0.12065 0.2794)
			(end -0.12065 0.3048)
			(stroke
				(width 0.1)
				(type default)
			)
			(layer "F.Fab")
		)
		(fp_line
			(start -0.12065 -0.2794)
			(end 0.12065 -0.2794)
			(stroke
				(width 0.1)
				(type default)
			)
			(layer "F.Fab")
		)
		(fp_line
			(start -0.12065 -0.305054)
			(end -0.12065 -0.2794)
			(stroke
				(width 0.1)
				(type default)
			)
			(layer "F.Fab")
		)
		(fp_line
			(start -0.67945 0.3048)
			(end -0.67945 -0.305054)
			(stroke
				(width 0.1)
				(type default)
			)
			(layer "F.Fab")
		)
		(fp_line
			(start -0.67945 -0.305054)
			(end -0.12065 -0.305054)
			(stroke
				(width 0.1)
				(type default)
			)
			(layer "F.Fab")
		)
		(pad "1" smd circle
			(at -0.40005 0 180)
			(size 0 0)
			(layers "F.Cu" "F.Mask" "F.Paste")
			(net "P1V8_RETIMER_CPU0_CS")
		)
		(pad "2" smd circle
			(at 0.40005 0 180)
			(size 0 0)
			(layers "F.Cu" "F.Mask" "F.Paste")
			(net "GND")
		)
	)
	(footprint ""
		(layer "F.Cu")
		(at 339.663278 -172.40631)
		(property "Reference" "TP7"
			(at -3.053842 0 0)
			(unlocked yes)
			(layer "F.SilkS")
			(effects
				(font
					(size 0.7874 0.5842)
					(thickness 0.1524)
				)
				(justify left)
			)
		)
		(property "Value" ""
			(at 0 0 0)
			(layer "F.Fab")
			(effects
				(font
					(size 1.27 1.27)
				)
			)
		)
		(duplicate_pad_numbers_are_jumpers no)
		(pad "1" smd circle
			(at 0 0)
			(size 0.762 0.762)
			(layers "F.Cu" "F.Mask" "F.Paste")
			(net "VSENSE_PVDDCR_CPU0_P0_DP")
		)
	)
	(footprint ""
		(layer "F.Cu")
		(at 148.73859 -95.517208 90)
		(property "Reference" "R3306"
			(at 0 0 90)
			(layer "F.SilkS")
			(hide yes)
			(effects
				(font
					(size 1.27 1.27)
				)
			)
		)
		(property "Value" ""
			(at 0 0 90)
			(layer "F.Fab")
			(effects
				(font
					(size 1.27 1.27)
				)
			)
		)
		(duplicate_pad_numbers_are_jumpers no)
		(fp_line
			(start 0.7874 -0.4064)
			(end 0.7874 0.4064)
			(stroke
				(width 0.1524)
				(type default)
			)
			(layer "F.SilkS")
		)
		(fp_line
			(start -0.7874 -0.4064)
			(end 0.7874 -0.4064)
			(stroke
				(width 0.1524)
				(type default)
			)
			(layer "F.SilkS")
		)
		(fp_line
			(start 0.7874 0.4064)
			(end -0.7874 0.4064)
			(stroke
				(width 0.1524)
				(type default)
			)
			(layer "F.SilkS")
		)
		(fp_line
			(start -0.7874 0.4064)
			(end -0.7874 -0.4064)
			(stroke
				(width 0.1524)
				(type default)
			)
			(layer "F.SilkS")
		)
		(fp_line
			(start -0.12065 -0.305054)
			(end -0.12065 -0.2794)
			(stroke
				(width 0.1)
				(type default)
			)
			(layer "F.Fab")
		)
		(fp_line
			(start -0.67945 -0.305054)
			(end -0.12065 -0.305054)
			(stroke
				(width 0.1)
				(type default)
			)
			(layer "F.Fab")
		)
		(fp_line
			(start 0.67945 -0.3048)
			(end 0.67945 0.3048)
			(stroke
				(width 0.1)
				(type default)
			)
			(layer "F.Fab")
		)
		(fp_line
			(start 0.12065 -0.3048)
			(end 0.67945 -0.3048)
			(stroke
				(width 0.1)
				(type default)
			)
			(layer "F.Fab")
		)
		(fp_line
			(start 0.12065 -0.2794)
			(end 0.12065 -0.3048)
			(stroke
				(width 0.1)
				(type default)
			)
			(layer "F.Fab")
		)
		(fp_line
			(start -0.12065 -0.2794)
			(end 0.12065 -0.2794)
			(stroke
				(width 0.1)
				(type default)
			)
			(layer "F.Fab")
		)
		(fp_line
			(start 0.120396 0.2794)
			(end -0.12065 0.2794)
			(stroke
				(width 0.1)
				(type default)
			)
			(layer "F.Fab")
		)
		(fp_line
			(start -0.12065 0.2794)
			(end -0.12065 0.3048)
			(stroke
				(width 0.1)
				(type default)
			)
			(layer "F.Fab")
		)
		(fp_line
			(start 0.67945 0.3048)
			(end 0.120396 0.3048)
			(stroke
				(width 0.1)
				(type default)
			)
			(layer "F.Fab")
		)
		(fp_line
			(start 0.120396 0.3048)
			(end 0.120396 0.2794)
			(stroke
				(width 0.1)
				(type default)
			)
			(layer "F.Fab")
		)
		(fp_line
			(start -0.12065 0.3048)
			(end -0.67945 0.3048)
			(stroke
				(width 0.1)
				(type default)
			)
			(layer "F.Fab")
		)
		(fp_line
			(start -0.67945 0.3048)
			(end -0.67945 -0.305054)
			(stroke
				(width 0.1)
				(type default)
			)
			(layer "F.Fab")
		)
		(pad "1" smd circle
			(at -0.40005 0 90)
			(size 0 0)
			(layers "F.Cu" "F.Mask" "F.Paste")
			(net "OCP_V3_2_PRSNT_ALL_R_N")
		)
		(pad "2" smd circle
			(at 0.40005 0 90)
			(size 0 0)
			(layers "F.Cu" "F.Mask" "F.Paste")
			(net "OCP_V3_2_PRSNT_ALL_R3_N")
		)
	)
	(footprint ""
		(layer "F.Cu")
		(at 180.528468 -47.139098)
		(property "Reference" "C9102"
			(at 0 0 0)
			(layer "F.SilkS")
			(hide yes)
			(effects
				(font
					(size 1.27 1.27)
				)
			)
		)
		(property "Value" ""
			(at 0 0 0)
			(layer "F.Fab")
			(effects
				(font
					(size 1.27 1.27)
				)
			)
		)
		(duplicate_pad_numbers_are_jumpers no)
		(fp_line
			(start -0.299974 -0.150114)
			(end 0.299974 -0.150114)
			(stroke
				(width 0.1)
				(type default)
			)
			(layer "F.Fab")
		)
		(fp_line
			(start -0.299974 0.150114)
			(end -0.299974 -0.150114)
			(stroke
				(width 0.1)
				(type default)
			)
			(layer "F.Fab")
		)
		(fp_line
			(start 0.299974 -0.150114)
			(end 0.299974 0.150114)
			(stroke
				(width 0.1)
				(type default)
			)
			(layer "F.Fab")
		)
		(fp_line
			(start 0.299974 0.150114)
			(end -0.299974 0.150114)
			(stroke
				(width 0.1)
				(type default)
			)
			(layer "F.Fab")
		)
		(pad "1" smd rect
			(at -0.2667 0)
			(size 0.3048 0.381)
			(layers "F.Cu" "F.Mask" "F.Paste")
			(net "P3E_CPU1_P4_TX_C_DP<1>")
		)
		(pad "2" smd rect
			(at 0.2667 0)
			(size 0.3048 0.381)
			(layers "F.Cu" "F.Mask" "F.Paste")
			(net "P3E_CPU1_P4_TX_DP<1>")
		)
	)
	(footprint ""
		(layer "F.Cu")
		(at 102.357682 -394.697966 90)
		(property "Reference" "R6707"
			(at 0 0 90)
			(layer "F.SilkS")
			(hide yes)
			(effects
				(font
					(size 1.27 1.27)
				)
			)
		)
		(property "Value" ""
			(at 0 0 90)
			(layer "F.Fab")
			(effects
				(font
					(size 1.27 1.27)
				)
			)
		)
		(duplicate_pad_numbers_are_jumpers no)
		(fp_line
			(start 0.32512 -0.175006)
			(end 0.32512 0.175006)
			(stroke
				(width 0.1)
				(type default)
			)
			(layer "F.Fab")
		)
		(fp_line
			(start -0.32512 -0.175006)
			(end 0.32512 -0.175006)
			(stroke
				(width 0.1)
				(type default)
			)
			(layer "F.Fab")
		)
		(fp_line
			(start 0.32512 0.175006)
			(end -0.32512 0.175006)
			(stroke
				(width 0.1)
				(type default)
			)
			(layer "F.Fab")
		)
		(fp_line
			(start -0.32512 0.175006)
			(end -0.32512 -0.175006)
			(stroke
				(width 0.1)
				(type default)
			)
			(layer "F.Fab")
		)
		(pad "1" smd rect
			(at -0.2667 0 90)
			(size 0.3048 0.381)
			(layers "F.Cu" "F.Mask" "F.Paste")
			(net "P1V8_CPU1_RT_1D")
		)
		(pad "2" smd rect
			(at 0.2667 0 270)
			(size 0.3048 0.381)
			(layers "F.Cu" "F.Mask" "F.Paste")
			(net "SMB_RT_CPU1_P0_ROM_R_SDA")
		)
	)
	(footprint ""
		(layer "F.Cu")
		(at 102.563422 -38.678612 180)
		(property "Reference" "R3183"
			(at 0 0 180)
			(layer "F.SilkS")
			(hide yes)
			(effects
				(font
					(size 1.27 1.27)
				)
			)
		)
		(property "Value" ""
			(at 0 0 180)
			(layer "F.Fab")
			(effects
				(font
					(size 1.27 1.27)
				)
			)
		)
		(duplicate_pad_numbers_are_jumpers no)
		(fp_line
			(start 0.7874 0.4064)
			(end -0.7874 0.4064)
			(stroke
				(width 0.1524)
				(type default)
			)
			(layer "F.SilkS")
		)
		(fp_line
			(start 0.7874 -0.4064)
			(end 0.7874 0.4064)
			(stroke
				(width 0.1524)
				(type default)
			)
			(layer "F.SilkS")
		)
		(fp_line
			(start -0.7874 0.4064)
			(end -0.7874 -0.4064)
			(stroke
				(width 0.1524)
				(type default)
			)
			(layer "F.SilkS")
		)
		(fp_line
			(start -0.7874 -0.4064)
			(end 0.7874 -0.4064)
			(stroke
				(width 0.1524)
				(type default)
			)
			(layer "F.SilkS")
		)
		(fp_line
			(start 0.67945 0.3048)
			(end 0.120396 0.3048)
			(stroke
				(width 0.1)
				(type default)
			)
			(layer "F.Fab")
		)
		(fp_line
			(start 0.67945 -0.3048)
			(end 0.67945 0.3048)
			(stroke
				(width 0.1)
				(type default)
			)
			(layer "F.Fab")
		)
		(fp_line
			(start 0.12065 -0.2794)
			(end 0.12065 -0.3048)
			(stroke
				(width 0.1)
				(type default)
			)
			(layer "F.Fab")
		)
		(fp_line
			(start 0.12065 -0.3048)
			(end 0.67945 -0.3048)
			(stroke
				(width 0.1)
				(type default)
			)
			(layer "F.Fab")
		)
		(fp_line
			(start 0.120396 0.3048)
			(end 0.120396 0.2794)
			(stroke
				(width 0.1)
				(type default)
			)
			(layer "F.Fab")
		)
		(fp_line
			(start 0.120396 0.2794)
			(end -0.12065 0.2794)
			(stroke
				(width 0.1)
				(type default)
			)
			(layer "F.Fab")
		)
		(fp_line
			(start -0.12065 0.3048)
			(end -0.67945 0.3048)
			(stroke
				(width 0.1)
				(type default)
			)
			(layer "F.Fab")
		)
		(fp_line
			(start -0.12065 0.2794)
			(end -0.12065 0.3048)
			(stroke
				(width 0.1)
				(type default)
			)
			(layer "F.Fab")
		)
		(fp_line
			(start -0.12065 -0.2794)
			(end 0.12065 -0.2794)
			(stroke
				(width 0.1)
				(type default)
			)
			(layer "F.Fab")
		)
		(fp_line
			(start -0.12065 -0.305054)
			(end -0.12065 -0.2794)
			(stroke
				(width 0.1)
				(type default)
			)
			(layer "F.Fab")
		)
		(fp_line
			(start -0.67945 0.3048)
			(end -0.67945 -0.305054)
			(stroke
				(width 0.1)
				(type default)
			)
			(layer "F.Fab")
		)
		(fp_line
			(start -0.67945 -0.305054)
			(end -0.12065 -0.305054)
			(stroke
				(width 0.1)
				(type default)
			)
			(layer "F.Fab")
		)
		(pad "1" smd circle
			(at -0.40005 0 180)
			(size 0 0)
			(layers "F.Cu" "F.Mask" "F.Paste")
			(net "P3V3_OCP_V3_2")
		)
		(pad "2" smd circle
			(at 0.40005 0 180)
			(size 0 0)
			(layers "F.Cu" "F.Mask" "F.Paste")
			(net "PU_OCP_V3_2_WAKE_OE")
		)
	)
	(footprint ""
		(layer "F.Cu")
		(at 138.426952 -60.849764)
		(property "Reference" "R1738"
			(at 0 0 0)
			(layer "F.SilkS")
			(hide yes)
			(effects
				(font
					(size 1.27 1.27)
				)
			)
		)
		(property "Value" ""
			(at 0 0 0)
			(layer "F.Fab")
			(effects
				(font
					(size 1.27 1.27)
				)
			)
		)
		(duplicate_pad_numbers_are_jumpers no)
		(fp_line
			(start -0.7874 -0.4064)
			(end 0.7874 -0.4064)
			(stroke
				(width 0.1524)
				(type default)
			)
			(layer "F.SilkS")
		)
		(fp_line
			(start -0.7874 0.4064)
			(end -0.7874 -0.4064)
			(stroke
				(width 0.1524)
				(type default)
			)
			(layer "F.SilkS")
		)
		(fp_line
			(start 0.7874 -0.4064)
			(end 0.7874 0.4064)
			(stroke
				(width 0.1524)
				(type default)
			)
			(layer "F.SilkS")
		)
		(fp_line
			(start 0.7874 0.4064)
			(end -0.7874 0.4064)
			(stroke
				(width 0.1524)
				(type default)
			)
			(layer "F.SilkS")
		)
		(fp_line
			(start -0.67945 -0.305054)
			(end -0.12065 -0.305054)
			(stroke
				(width 0.1)
				(type default)
			)
			(layer "F.Fab")
		)
		(fp_line
			(start -0.67945 0.3048)
			(end -0.67945 -0.305054)
			(stroke
				(width 0.1)
				(type default)
			)
			(layer "F.Fab")
		)
		(fp_line
			(start -0.12065 -0.305054)
			(end -0.12065 -0.2794)
			(stroke
				(width 0.1)
				(type default)
			)
			(layer "F.Fab")
		)
		(fp_line
			(start -0.12065 -0.2794)
			(end 0.12065 -0.2794)
			(stroke
				(width 0.1)
				(type default)
			)
			(layer "F.Fab")
		)
		(fp_line
			(start -0.12065 0.2794)
			(end -0.12065 0.3048)
			(stroke
				(width 0.1)
				(type default)
			)
			(layer "F.Fab")
		)
		(fp_line
			(start -0.12065 0.3048)
			(end -0.67945 0.3048)
			(stroke
				(width 0.1)
				(type default)
			)
			(layer "F.Fab")
		)
		(fp_line
			(start 0.120396 0.2794)
			(end -0.12065 0.2794)
			(stroke
				(width 0.1)
				(type default)
			)
			(layer "F.Fab")
		)
		(fp_line
			(start 0.120396 0.3048)
			(end 0.120396 0.2794)
			(stroke
				(width 0.1)
				(type default)
			)
			(layer "F.Fab")
		)
		(fp_line
			(start 0.12065 -0.3048)
			(end 0.67945 -0.3048)
			(stroke
				(width 0.1)
				(type default)
			)
			(layer "F.Fab")
		)
		(fp_line
			(start 0.12065 -0.2794)
			(end 0.12065 -0.3048)
			(stroke
				(width 0.1)
				(type default)
			)
			(layer "F.Fab")
		)
		(fp_line
			(start 0.67945 -0.3048)
			(end 0.67945 0.3048)
			(stroke
				(width 0.1)
				(type default)
			)
			(layer "F.Fab")
		)
		(fp_line
			(start 0.67945 0.3048)
			(end 0.120396 0.3048)
			(stroke
				(width 0.1)
				(type default)
			)
			(layer "F.Fab")
		)
		(pad "1" smd circle
			(at -0.40005 0)
			(size 0 0)
			(layers "F.Cu" "F.Mask" "F.Paste")
			(net "JTAG_SCM_MUX_R_TDI")
		)
		(pad "2" smd circle
			(at 0.40005 0)
			(size 0 0)
			(layers "F.Cu" "F.Mask" "F.Paste")
			(net "JTAG_SCM_MUX_TDI")
		)
	)
	(footprint ""
		(layer "F.Cu")
		(at 156.718 -106.172 180)
		(property "Reference" "R1131"
			(at 0 0 180)
			(layer "F.SilkS")
			(hide yes)
			(effects
				(font
					(size 1.27 1.27)
				)
			)
		)
		(property "Value" ""
			(at 0 0 180)
			(layer "F.Fab")
			(effects
				(font
					(size 1.27 1.27)
				)
			)
		)
		(duplicate_pad_numbers_are_jumpers no)
		(fp_line
			(start 0.7874 0.4064)
			(end -0.7874 0.4064)
			(stroke
				(width 0.1524)
				(type default)
			)
			(layer "F.SilkS")
		)
		(fp_line
			(start 0.7874 -0.4064)
			(end 0.7874 0.4064)
			(stroke
				(width 0.1524)
				(type default)
			)
			(layer "F.SilkS")
		)
		(fp_line
			(start -0.7874 0.4064)
			(end -0.7874 -0.4064)
			(stroke
				(width 0.1524)
				(type default)
			)
			(layer "F.SilkS")
		)
		(fp_line
			(start -0.7874 -0.4064)
			(end 0.7874 -0.4064)
			(stroke
				(width 0.1524)
				(type default)
			)
			(layer "F.SilkS")
		)
		(fp_line
			(start 0.67945 0.3048)
			(end 0.120396 0.3048)
			(stroke
				(width 0.1)
				(type default)
			)
			(layer "F.Fab")
		)
		(fp_line
			(start 0.67945 -0.3048)
			(end 0.67945 0.3048)
			(stroke
				(width 0.1)
				(type default)
			)
			(layer "F.Fab")
		)
		(fp_line
			(start 0.12065 -0.2794)
			(end 0.12065 -0.3048)
			(stroke
				(width 0.1)
				(type default)
			)
			(layer "F.Fab")
		)
		(fp_line
			(start 0.12065 -0.3048)
			(end 0.67945 -0.3048)
			(stroke
				(width 0.1)
				(type default)
			)
			(layer "F.Fab")
		)
		(fp_line
			(start 0.120396 0.3048)
			(end 0.120396 0.2794)
			(stroke
				(width 0.1)
				(type default)
			)
			(layer "F.Fab")
		)
		(fp_line
			(start 0.120396 0.2794)
			(end -0.12065 0.2794)
			(stroke
				(width 0.1)
				(type default)
			)
			(layer "F.Fab")
		)
		(fp_line
			(start -0.12065 0.3048)
			(end -0.67945 0.3048)
			(stroke
				(width 0.1)
				(type default)
			)
			(layer "F.Fab")
		)
		(fp_line
			(start -0.12065 0.2794)
			(end -0.12065 0.3048)
			(stroke
				(width 0.1)
				(type default)
			)
			(layer "F.Fab")
		)
		(fp_line
			(start -0.12065 -0.2794)
			(end 0.12065 -0.2794)
			(stroke
				(width 0.1)
				(type default)
			)
			(layer "F.Fab")
		)
		(fp_line
			(start -0.12065 -0.305054)
			(end -0.12065 -0.2794)
			(stroke
				(width 0.1)
				(type default)
			)
			(layer "F.Fab")
		)
		(fp_line
			(start -0.67945 0.3048)
			(end -0.67945 -0.305054)
			(stroke
				(width 0.1)
				(type default)
			)
			(layer "F.Fab")
		)
		(fp_line
			(start -0.67945 -0.305054)
			(end -0.12065 -0.305054)
			(stroke
				(width 0.1)
				(type default)
			)
			(layer "F.Fab")
		)
		(pad "1" smd circle
			(at -0.40005 0 180)
			(size 0 0)
			(layers "F.Cu" "F.Mask" "F.Paste")
			(net "P3V3_AUX")
		)
		(pad "2" smd circle
			(at 0.40005 0 180)
			(size 0 0)
			(layers "F.Cu" "F.Mask" "F.Paste")
			(net "P12V_OCP_SFF_EN_R3")
		)
	)
	(footprint ""
		(layer "F.Cu")
		(at 55.753 -39.751)
		(property "Reference" "C1065"
			(at 0 0 0)
			(layer "F.SilkS")
			(hide yes)
			(effects
				(font
					(size 1.27 1.27)
				)
			)
		)
		(property "Value" ""
			(at 0 0 0)
			(layer "F.Fab")
			(effects
				(font
					(size 1.27 1.27)
				)
			)
		)
		(duplicate_pad_numbers_are_jumpers no)
		(fp_line
			(start -0.7874 -0.4064)
			(end 0.7874 -0.4064)
			(stroke
				(width 0.1524)
				(type default)
			)
			(layer "F.SilkS")
		)
		(fp_line
			(start -0.7874 0.4064)
			(end -0.7874 -0.4064)
			(stroke
				(width 0.1524)
				(type default)
			)
			(layer "F.SilkS")
		)
		(fp_line
			(start 0.7874 -0.4064)
			(end 0.7874 0.4064)
			(stroke
				(width 0.1524)
				(type default)
			)
			(layer "F.SilkS")
		)
		(fp_line
			(start 0.7874 0.4064)
			(end -0.7874 0.4064)
			(stroke
				(width 0.1524)
				(type default)
			)
			(layer "F.SilkS")
		)
		(fp_line
			(start -0.67945 -0.305054)
			(end -0.12065 -0.305054)
			(stroke
				(width 0.1)
				(type default)
			)
			(layer "F.Fab")
		)
		(fp_line
			(start -0.67945 0.3048)
			(end -0.67945 -0.305054)
			(stroke
				(width 0.1)
				(type default)
			)
			(layer "F.Fab")
		)
		(fp_line
			(start -0.12065 -0.305054)
			(end -0.12065 -0.2794)
			(stroke
				(width 0.1)
				(type default)
			)
			(layer "F.Fab")
		)
		(fp_line
			(start -0.12065 -0.2794)
			(end 0.12065 -0.2794)
			(stroke
				(width 0.1)
				(type default)
			)
			(layer "F.Fab")
		)
		(fp_line
			(start -0.12065 0.2794)
			(end -0.12065 0.3048)
			(stroke
				(width 0.1)
				(type default)
			)
			(layer "F.Fab")
		)
		(fp_line
			(start -0.12065 0.3048)
			(end -0.67945 0.3048)
			(stroke
				(width 0.1)
				(type default)
			)
			(layer "F.Fab")
		)
		(fp_line
			(start 0.120396 0.2794)
			(end -0.12065 0.2794)
			(stroke
				(width 0.1)
				(type default)
			)
			(layer "F.Fab")
		)
		(fp_line
			(start 0.120396 0.3048)
			(end 0.120396 0.2794)
			(stroke
				(width 0.1)
				(type default)
			)
			(layer "F.Fab")
		)
		(fp_line
			(start 0.12065 -0.3048)
			(end 0.67945 -0.3048)
			(stroke
				(width 0.1)
				(type default)
			)
			(layer "F.Fab")
		)
		(fp_line
			(start 0.12065 -0.2794)
			(end 0.12065 -0.3048)
			(stroke
				(width 0.1)
				(type default)
			)
			(layer "F.Fab")
		)
		(fp_line
			(start 0.67945 -0.3048)
			(end 0.67945 0.3048)
			(stroke
				(width 0.1)
				(type default)
			)
			(layer "F.Fab")
		)
		(fp_line
			(start 0.67945 0.3048)
			(end 0.120396 0.3048)
			(stroke
				(width 0.1)
				(type default)
			)
			(layer "F.Fab")
		)
		(pad "1" smd circle
			(at -0.40005 0)
			(size 0 0)
			(layers "F.Cu" "F.Mask" "F.Paste")
			(net "P3V3_AUX")
		)
		(pad "2" smd circle
			(at 0.40005 0)
			(size 0 0)
			(layers "F.Cu" "F.Mask" "F.Paste")
			(net "GND")
		)
	)
	(footprint ""
		(layer "F.Cu")
		(at 14.01826 -92.687648 -90)
		(property "Reference" "R3666"
			(at 0 0 270)
			(layer "F.SilkS")
			(hide yes)
			(effects
				(font
					(size 1.27 1.27)
				)
			)
		)
		(property "Value" ""
			(at 0 0 270)
			(layer "F.Fab")
			(effects
				(font
					(size 1.27 1.27)
				)
			)
		)
		(duplicate_pad_numbers_are_jumpers no)
		(fp_line
			(start -0.7874 0.4064)
			(end -0.7874 -0.4064)
			(stroke
				(width 0.1524)
				(type default)
			)
			(layer "F.SilkS")
		)
		(fp_line
			(start 0.7874 0.4064)
			(end -0.7874 0.4064)
			(stroke
				(width 0.1524)
				(type default)
			)
			(layer "F.SilkS")
		)
		(fp_line
			(start -0.7874 -0.4064)
			(end 0.7874 -0.4064)
			(stroke
				(width 0.1524)
				(type default)
			)
			(layer "F.SilkS")
		)
		(fp_line
			(start 0.7874 -0.4064)
			(end 0.7874 0.4064)
			(stroke
				(width 0.1524)
				(type default)
			)
			(layer "F.SilkS")
		)
		(fp_line
			(start -0.67945 0.3048)
			(end -0.67945 -0.305054)
			(stroke
				(width 0.1)
				(type default)
			)
			(layer "F.Fab")
		)
		(fp_line
			(start -0.12065 0.3048)
			(end -0.67945 0.3048)
			(stroke
				(width 0.1)
				(type default)
			)
			(layer "F.Fab")
		)
		(fp_line
			(start 0.120396 0.3048)
			(end 0.120396 0.2794)
			(stroke
				(width 0.1)
				(type default)
			)
			(layer "F.Fab")
		)
		(fp_line
			(start 0.67945 0.3048)
			(end 0.120396 0.3048)
			(stroke
				(width 0.1)
				(type default)
			)
			(layer "F.Fab")
		)
		(fp_line
			(start -0.12065 0.2794)
			(end -0.12065 0.3048)
			(stroke
				(width 0.1)
				(type default)
			)
			(layer "F.Fab")
		)
		(fp_line
			(start 0.120396 0.2794)
			(end -0.12065 0.2794)
			(stroke
				(width 0.1)
				(type default)
			)
			(layer "F.Fab")
		)
		(fp_line
			(start -0.12065 -0.2794)
			(end 0.12065 -0.2794)
			(stroke
				(width 0.1)
				(type default)
			)
			(layer "F.Fab")
		)
		(fp_line
			(start 0.12065 -0.2794)
			(end 0.12065 -0.3048)
			(stroke
				(width 0.1)
				(type default)
			)
			(layer "F.Fab")
		)
		(fp_line
			(start 0.12065 -0.3048)
			(end 0.67945 -0.3048)
			(stroke
				(width 0.1)
				(type default)
			)
			(layer "F.Fab")
		)
		(fp_line
			(start 0.67945 -0.3048)
			(end 0.67945 0.3048)
			(stroke
				(width 0.1)
				(type default)
			)
			(layer "F.Fab")
		)
		(fp_line
			(start -0.67945 -0.305054)
			(end -0.12065 -0.305054)
			(stroke
				(width 0.1)
				(type default)
			)
			(layer "F.Fab")
		)
		(fp_line
			(start -0.12065 -0.305054)
			(end -0.12065 -0.2794)
			(stroke
				(width 0.1)
				(type default)
			)
			(layer "F.Fab")
		)
		(pad "1" smd circle
			(at -0.40005 0 270)
			(size 0 0)
			(layers "F.Cu" "F.Mask" "F.Paste")
			(net "USB_HUB_TEST")
		)
		(pad "2" smd circle
			(at 0.40005 0 270)
			(size 0 0)
			(layers "F.Cu" "F.Mask" "F.Paste")
			(net "GND")
		)
	)
	(footprint ""
		(layer "F.Cu")
		(at 419.094666 -157.618684 -90)
		(property "Reference" "PR446"
			(at 0 0 270)
			(layer "F.SilkS")
			(hide yes)
			(effects
				(font
					(size 1.27 1.27)
				)
			)
		)
		(property "Value" ""
			(at 0 0 270)
			(layer "F.Fab")
			(effects
				(font
					(size 1.27 1.27)
				)
			)
		)
		(duplicate_pad_numbers_are_jumpers no)
		(fp_line
			(start -0.7874 0.4064)
			(end -0.7874 -0.4064)
			(stroke
				(width 0.1524)
				(type default)
			)
			(layer "F.SilkS")
		)
		(fp_line
			(start 0.7874 0.4064)
			(end -0.7874 0.4064)
			(stroke
				(width 0.1524)
				(type default)
			)
			(layer "F.SilkS")
		)
		(fp_line
			(start -0.7874 -0.4064)
			(end 0.7874 -0.4064)
			(stroke
				(width 0.1524)
				(type default)
			)
			(layer "F.SilkS")
		)
		(fp_line
			(start 0.7874 -0.4064)
			(end 0.7874 0.4064)
			(stroke
				(width 0.1524)
				(type default)
			)
			(layer "F.SilkS")
		)
		(fp_line
			(start -0.67945 0.3048)
			(end -0.67945 -0.305054)
			(stroke
				(width 0.1)
				(type default)
			)
			(layer "F.Fab")
		)
		(fp_line
			(start -0.12065 0.3048)
			(end -0.67945 0.3048)
			(stroke
				(width 0.1)
				(type default)
			)
			(layer "F.Fab")
		)
		(fp_line
			(start 0.120396 0.3048)
			(end 0.120396 0.2794)
			(stroke
				(width 0.1)
				(type default)
			)
			(layer "F.Fab")
		)
		(fp_line
			(start 0.67945 0.3048)
			(end 0.120396 0.3048)
			(stroke
				(width 0.1)
				(type default)
			)
			(layer "F.Fab")
		)
		(fp_line
			(start -0.12065 0.2794)
			(end -0.12065 0.3048)
			(stroke
				(width 0.1)
				(type default)
			)
			(layer "F.Fab")
		)
		(fp_line
			(start 0.120396 0.2794)
			(end -0.12065 0.2794)
			(stroke
				(width 0.1)
				(type default)
			)
			(layer "F.Fab")
		)
		(fp_line
			(start -0.12065 -0.2794)
			(end 0.12065 -0.2794)
			(stroke
				(width 0.1)
				(type default)
			)
			(layer "F.Fab")
		)
		(fp_line
			(start 0.12065 -0.2794)
			(end 0.12065 -0.3048)
			(stroke
				(width 0.1)
				(type default)
			)
			(layer "F.Fab")
		)
		(fp_line
			(start 0.12065 -0.3048)
			(end 0.67945 -0.3048)
			(stroke
				(width 0.1)
				(type default)
			)
			(layer "F.Fab")
		)
		(fp_line
			(start 0.67945 -0.3048)
			(end 0.67945 0.3048)
			(stroke
				(width 0.1)
				(type default)
			)
			(layer "F.Fab")
		)
		(fp_line
			(start -0.67945 -0.305054)
			(end -0.12065 -0.305054)
			(stroke
				(width 0.1)
				(type default)
			)
			(layer "F.Fab")
		)
		(fp_line
			(start -0.12065 -0.305054)
			(end -0.12065 -0.2794)
			(stroke
				(width 0.1)
				(type default)
			)
			(layer "F.Fab")
		)
		(pad "1" smd circle
			(at -0.40005 0 270)
			(size 0 0)
			(layers "F.Cu" "F.Mask" "F.Paste")
			(net "PVDDCR_CPU0_P0_PVCC")
		)
		(pad "2" smd circle
			(at 0.40005 0 270)
			(size 0 0)
			(layers "F.Cu" "F.Mask" "F.Paste")
			(net "P3V3_AUX")
		)
	)
	(footprint ""
		(layer "F.Cu")
		(at 146.927316 -21.498306 -90)
		(property "Reference" "R8101"
			(at 0 0 270)
			(layer "F.SilkS")
			(hide yes)
			(effects
				(font
					(size 1.27 1.27)
				)
			)
		)
		(property "Value" ""
			(at 0 0 270)
			(layer "F.Fab")
			(effects
				(font
					(size 1.27 1.27)
				)
			)
		)
		(duplicate_pad_numbers_are_jumpers no)
		(fp_line
			(start -0.7874 0.4064)
			(end -0.7874 -0.4064)
			(stroke
				(width 0.1524)
				(type default)
			)
			(layer "F.SilkS")
		)
		(fp_line
			(start 0.7874 0.4064)
			(end -0.7874 0.4064)
			(stroke
				(width 0.1524)
				(type default)
			)
			(layer "F.SilkS")
		)
		(fp_line
			(start -0.7874 -0.4064)
			(end 0.7874 -0.4064)
			(stroke
				(width 0.1524)
				(type default)
			)
			(layer "F.SilkS")
		)
		(fp_line
			(start 0.7874 -0.4064)
			(end 0.7874 0.4064)
			(stroke
				(width 0.1524)
				(type default)
			)
			(layer "F.SilkS")
		)
		(fp_line
			(start -0.67945 0.3048)
			(end -0.67945 -0.305054)
			(stroke
				(width 0.1)
				(type default)
			)
			(layer "F.Fab")
		)
		(fp_line
			(start -0.12065 0.3048)
			(end -0.67945 0.3048)
			(stroke
				(width 0.1)
				(type default)
			)
			(layer "F.Fab")
		)
		(fp_line
			(start 0.120396 0.3048)
			(end 0.120396 0.2794)
			(stroke
				(width 0.1)
				(type default)
			)
			(layer "F.Fab")
		)
		(fp_line
			(start 0.67945 0.3048)
			(end 0.120396 0.3048)
			(stroke
				(width 0.1)
				(type default)
			)
			(layer "F.Fab")
		)
		(fp_line
			(start -0.12065 0.2794)
			(end -0.12065 0.3048)
			(stroke
				(width 0.1)
				(type default)
			)
			(layer "F.Fab")
		)
		(fp_line
			(start 0.120396 0.2794)
			(end -0.12065 0.2794)
			(stroke
				(width 0.1)
				(type default)
			)
			(layer "F.Fab")
		)
		(fp_line
			(start -0.12065 -0.2794)
			(end 0.12065 -0.2794)
			(stroke
				(width 0.1)
				(type default)
			)
			(layer "F.Fab")
		)
		(fp_line
			(start 0.12065 -0.2794)
			(end 0.12065 -0.3048)
			(stroke
				(width 0.1)
				(type default)
			)
			(layer "F.Fab")
		)
		(fp_line
			(start 0.12065 -0.3048)
			(end 0.67945 -0.3048)
			(stroke
				(width 0.1)
				(type default)
			)
			(layer "F.Fab")
		)
		(fp_line
			(start 0.67945 -0.3048)
			(end 0.67945 0.3048)
			(stroke
				(width 0.1)
				(type default)
			)
			(layer "F.Fab")
		)
		(fp_line
			(start -0.67945 -0.305054)
			(end -0.12065 -0.305054)
			(stroke
				(width 0.1)
				(type default)
			)
			(layer "F.Fab")
		)
		(fp_line
			(start -0.12065 -0.305054)
			(end -0.12065 -0.2794)
			(stroke
				(width 0.1)
				(type default)
			)
			(layer "F.Fab")
		)
		(pad "1" smd circle
			(at -0.40005 0 270)
			(size 0 0)
			(layers "F.Cu" "F.Mask" "F.Paste")
			(net "FM_AC_PWR_BTN_R_N")
		)
		(pad "2" smd circle
			(at 0.40005 0 270)
			(size 0 0)
			(layers "F.Cu" "F.Mask" "F.Paste")
			(net "FM_AC_PWR_BTN_N")
		)
	)
	(footprint ""
		(layer "F.Cu")
		(at 422.688258 -171.231306 90)
		(property "Reference" "PL62"
			(at -3.10134 4.124452 90)
			(unlocked yes)
			(layer "F.SilkS")
			(effects
				(font
					(size 0.7874 0.5842)
					(thickness 0.1524)
				)
				(justify left)
			)
		)
		(property "Value" ""
			(at 0 0 90)
			(layer "F.Fab")
			(effects
				(font
					(size 1.27 1.27)
				)
			)
		)
		(duplicate_pad_numbers_are_jumpers no)
		(fp_line
			(start 3.24993 -3.24993)
			(end 3.24993 -2.2352)
			(stroke
				(width 0.1524)
				(type default)
			)
			(layer "F.SilkS")
		)
		(fp_line
			(start -3.24993 -3.24993)
			(end 3.24993 -3.24993)
			(stroke
				(width 0.1524)
				(type default)
			)
			(layer "F.SilkS")
		)
		(fp_line
			(start -3.24993 -2.2352)
			(end -3.24993 -3.24993)
			(stroke
				(width 0.1524)
				(type default)
			)
			(layer "F.SilkS")
		)
		(fp_line
			(start 3.24993 2.761742)
			(end 3.24993 3.24993)
			(stroke
				(width 0.1524)
				(type default)
			)
			(layer "F.SilkS")
		)
		(fp_line
			(start 3.24993 3.24993)
			(end -3.24993 3.24993)
			(stroke
				(width 0.1524)
				(type default)
			)
			(layer "F.SilkS")
		)
		(fp_line
			(start -3.24993 3.24993)
			(end -3.24993 2.2352)
			(stroke
				(width 0.1524)
				(type default)
			)
			(layer "F.SilkS")
		)
		(fp_line
			(start 3.24993 -3.24993)
			(end 3.24993 3.24993)
			(stroke
				(width 0.1)
				(type default)
			)
			(layer "F.Fab")
		)
		(fp_line
			(start -3.24993 -3.24993)
			(end 3.24993 -3.24993)
			(stroke
				(width 0.1)
				(type default)
			)
			(layer "F.Fab")
		)
		(fp_line
			(start 3.24993 3.24993)
			(end -3.24993 3.24993)
			(stroke
				(width 0.1)
				(type default)
			)
			(layer "F.Fab")
		)
		(fp_line
			(start -3.24993 3.24993)
			(end -3.24993 -3.24993)
			(stroke
				(width 0.1)
				(type default)
			)
			(layer "F.Fab")
		)
		(pad "1" smd rect
			(at -2.29997 0 90)
			(size 2.0066 4.2164)
			(layers "F.Cu" "F.Mask" "F.Paste")
			(net "GND")
		)
		(pad "2" smd rect
			(at 2.29997 0 90)
			(size 2.0066 4.2164)
			(layers "F.Cu" "F.Mask" "F.Paste")
			(net "IND_SOC_P0_CPL0")
		)
	)
	(footprint ""
		(layer "F.Cu")
		(at 214.432134 -47.335948 90)
		(property "Reference" "R3588"
			(at 0 0 90)
			(layer "F.SilkS")
			(hide yes)
			(effects
				(font
					(size 1.27 1.27)
				)
			)
		)
		(property "Value" ""
			(at 0 0 90)
			(layer "F.Fab")
			(effects
				(font
					(size 1.27 1.27)
				)
			)
		)
		(duplicate_pad_numbers_are_jumpers no)
		(fp_line
			(start 0.7874 -0.4064)
			(end 0.7874 0.4064)
			(stroke
				(width 0.1524)
				(type default)
			)
			(layer "F.SilkS")
		)
		(fp_line
			(start -0.7874 -0.4064)
			(end 0.7874 -0.4064)
			(stroke
				(width 0.1524)
				(type default)
			)
			(layer "F.SilkS")
		)
		(fp_line
			(start 0.7874 0.4064)
			(end -0.7874 0.4064)
			(stroke
				(width 0.1524)
				(type default)
			)
			(layer "F.SilkS")
		)
		(fp_line
			(start -0.7874 0.4064)
			(end -0.7874 -0.4064)
			(stroke
				(width 0.1524)
				(type default)
			)
			(layer "F.SilkS")
		)
		(fp_line
			(start -0.12065 -0.305054)
			(end -0.12065 -0.2794)
			(stroke
				(width 0.1)
				(type default)
			)
			(layer "F.Fab")
		)
		(fp_line
			(start -0.67945 -0.305054)
			(end -0.12065 -0.305054)
			(stroke
				(width 0.1)
				(type default)
			)
			(layer "F.Fab")
		)
		(fp_line
			(start 0.67945 -0.3048)
			(end 0.67945 0.3048)
			(stroke
				(width 0.1)
				(type default)
			)
			(layer "F.Fab")
		)
		(fp_line
			(start 0.12065 -0.3048)
			(end 0.67945 -0.3048)
			(stroke
				(width 0.1)
				(type default)
			)
			(layer "F.Fab")
		)
		(fp_line
			(start 0.12065 -0.2794)
			(end 0.12065 -0.3048)
			(stroke
				(width 0.1)
				(type default)
			)
			(layer "F.Fab")
		)
		(fp_line
			(start -0.12065 -0.2794)
			(end 0.12065 -0.2794)
			(stroke
				(width 0.1)
				(type default)
			)
			(layer "F.Fab")
		)
		(fp_line
			(start 0.120396 0.2794)
			(end -0.12065 0.2794)
			(stroke
				(width 0.1)
				(type default)
			)
			(layer "F.Fab")
		)
		(fp_line
			(start -0.12065 0.2794)
			(end -0.12065 0.3048)
			(stroke
				(width 0.1)
				(type default)
			)
			(layer "F.Fab")
		)
		(fp_line
			(start 0.67945 0.3048)
			(end 0.120396 0.3048)
			(stroke
				(width 0.1)
				(type default)
			)
			(layer "F.Fab")
		)
		(fp_line
			(start 0.120396 0.3048)
			(end 0.120396 0.2794)
			(stroke
				(width 0.1)
				(type default)
			)
			(layer "F.Fab")
		)
		(fp_line
			(start -0.12065 0.3048)
			(end -0.67945 0.3048)
			(stroke
				(width 0.1)
				(type default)
			)
			(layer "F.Fab")
		)
		(fp_line
			(start -0.67945 0.3048)
			(end -0.67945 -0.305054)
			(stroke
				(width 0.1)
				(type default)
			)
			(layer "F.Fab")
		)
		(pad "1" smd circle
			(at -0.40005 0 90)
			(size 0 0)
			(layers "F.Cu" "F.Mask" "F.Paste")
			(net "SMB_INA230_3V3AUX_SCL")
		)
		(pad "2" smd circle
			(at 0.40005 0 90)
			(size 0 0)
			(layers "F.Cu" "F.Mask" "F.Paste")
			(net "SMB_INA230_2_3V3AUX_SCL_R")
		)
	)
	(footprint ""
		(layer "F.Cu")
		(at 386.511292 -381.41783 -90)
		(property "Reference" "C879"
			(at 0 0 270)
			(layer "F.SilkS")
			(hide yes)
			(effects
				(font
					(size 1.27 1.27)
				)
			)
		)
		(property "Value" ""
			(at 0 0 270)
			(layer "F.Fab")
			(effects
				(font
					(size 1.27 1.27)
				)
			)
		)
		(duplicate_pad_numbers_are_jumpers no)
		(fp_line
			(start -0.299974 0.150114)
			(end -0.299974 -0.150114)
			(stroke
				(width 0.1)
				(type default)
			)
			(layer "F.Fab")
		)
		(fp_line
			(start 0.299974 0.150114)
			(end -0.299974 0.150114)
			(stroke
				(width 0.1)
				(type default)
			)
			(layer "F.Fab")
		)
		(fp_line
			(start -0.299974 -0.150114)
			(end 0.299974 -0.150114)
			(stroke
				(width 0.1)
				(type default)
			)
			(layer "F.Fab")
		)
		(fp_line
			(start 0.299974 -0.150114)
			(end 0.299974 0.150114)
			(stroke
				(width 0.1)
				(type default)
			)
			(layer "F.Fab")
		)
		(pad "1" smd rect
			(at -0.2667 0 270)
			(size 0.3048 0.381)
			(layers "F.Cu" "F.Mask" "F.Paste")
			(net "P5E_CPU0_P3_TX_C_DP<11>")
		)
		(pad "2" smd rect
			(at 0.2667 0 270)
			(size 0.3048 0.381)
			(layers "F.Cu" "F.Mask" "F.Paste")
			(net "P5E_CPU0_P3_TX_DP<11>")
		)
	)
	(footprint ""
		(layer "F.Cu")
		(at 101.413056 -31.786576 90)
		(property "Reference" "R6328"
			(at 0 0 90)
			(layer "F.SilkS")
			(hide yes)
			(effects
				(font
					(size 1.27 1.27)
				)
			)
		)
		(property "Value" ""
			(at 0 0 90)
			(layer "F.Fab")
			(effects
				(font
					(size 1.27 1.27)
				)
			)
		)
		(duplicate_pad_numbers_are_jumpers no)
		(fp_line
			(start 0.7874 -0.4064)
			(end 0.7874 0.4064)
			(stroke
				(width 0.1524)
				(type default)
			)
			(layer "F.SilkS")
		)
		(fp_line
			(start -0.7874 -0.4064)
			(end 0.7874 -0.4064)
			(stroke
				(width 0.1524)
				(type default)
			)
			(layer "F.SilkS")
		)
		(fp_line
			(start 0.7874 0.4064)
			(end -0.7874 0.4064)
			(stroke
				(width 0.1524)
				(type default)
			)
			(layer "F.SilkS")
		)
		(fp_line
			(start -0.7874 0.4064)
			(end -0.7874 -0.4064)
			(stroke
				(width 0.1524)
				(type default)
			)
			(layer "F.SilkS")
		)
		(fp_line
			(start -0.12065 -0.305054)
			(end -0.12065 -0.2794)
			(stroke
				(width 0.1)
				(type default)
			)
			(layer "F.Fab")
		)
		(fp_line
			(start -0.67945 -0.305054)
			(end -0.12065 -0.305054)
			(stroke
				(width 0.1)
				(type default)
			)
			(layer "F.Fab")
		)
		(fp_line
			(start 0.67945 -0.3048)
			(end 0.67945 0.3048)
			(stroke
				(width 0.1)
				(type default)
			)
			(layer "F.Fab")
		)
		(fp_line
			(start 0.12065 -0.3048)
			(end 0.67945 -0.3048)
			(stroke
				(width 0.1)
				(type default)
			)
			(layer "F.Fab")
		)
		(fp_line
			(start 0.12065 -0.2794)
			(end 0.12065 -0.3048)
			(stroke
				(width 0.1)
				(type default)
			)
			(layer "F.Fab")
		)
		(fp_line
			(start -0.12065 -0.2794)
			(end 0.12065 -0.2794)
			(stroke
				(width 0.1)
				(type default)
			)
			(layer "F.Fab")
		)
		(fp_line
			(start 0.120396 0.2794)
			(end -0.12065 0.2794)
			(stroke
				(width 0.1)
				(type default)
			)
			(layer "F.Fab")
		)
		(fp_line
			(start -0.12065 0.2794)
			(end -0.12065 0.3048)
			(stroke
				(width 0.1)
				(type default)
			)
			(layer "F.Fab")
		)
		(fp_line
			(start 0.67945 0.3048)
			(end 0.120396 0.3048)
			(stroke
				(width 0.1)
				(type default)
			)
			(layer "F.Fab")
		)
		(fp_line
			(start 0.120396 0.3048)
			(end 0.120396 0.2794)
			(stroke
				(width 0.1)
				(type default)
			)
			(layer "F.Fab")
		)
		(fp_line
			(start -0.12065 0.3048)
			(end -0.67945 0.3048)
			(stroke
				(width 0.1)
				(type default)
			)
			(layer "F.Fab")
		)
		(fp_line
			(start -0.67945 0.3048)
			(end -0.67945 -0.305054)
			(stroke
				(width 0.1)
				(type default)
			)
			(layer "F.Fab")
		)
		(pad "1" smd circle
			(at -0.40005 0 90)
			(size 0 0)
			(layers "F.Cu" "F.Mask" "F.Paste")
			(net "RST_USB_HUB_N")
		)
		(pad "2" smd circle
			(at 0.40005 0 90)
			(size 0 0)
			(layers "F.Cu" "F.Mask" "F.Paste")
			(net "USB_HUB2_TI_GRSTZ_MRP_PROG_FUNC1")
		)
	)
	(footprint ""
		(layer "F.Cu")
		(at 102.268782 -376.067828)
		(property "Reference" "C712"
			(at 0 0 0)
			(layer "F.SilkS")
			(hide yes)
			(effects
				(font
					(size 1.27 1.27)
				)
			)
		)
		(property "Value" ""
			(at 0 0 0)
			(layer "F.Fab")
			(effects
				(font
					(size 1.27 1.27)
				)
			)
		)
		(duplicate_pad_numbers_are_jumpers no)
		(fp_line
			(start -0.299974 -0.150114)
			(end 0.299974 -0.150114)
			(stroke
				(width 0.1)
				(type default)
			)
			(layer "F.Fab")
		)
		(fp_line
			(start -0.299974 0.150114)
			(end -0.299974 -0.150114)
			(stroke
				(width 0.1)
				(type default)
			)
			(layer "F.Fab")
		)
		(fp_line
			(start 0.299974 -0.150114)
			(end 0.299974 0.150114)
			(stroke
				(width 0.1)
				(type default)
			)
			(layer "F.Fab")
		)
		(fp_line
			(start 0.299974 0.150114)
			(end -0.299974 0.150114)
			(stroke
				(width 0.1)
				(type default)
			)
			(layer "F.Fab")
		)
		(pad "1" smd rect
			(at -0.2667 0)
			(size 0.3048 0.381)
			(layers "F.Cu" "F.Mask" "F.Paste")
			(net "P5E_CPU1_P1_TX_C_DN<14>")
		)
		(pad "2" smd rect
			(at 0.2667 0)
			(size 0.3048 0.381)
			(layers "F.Cu" "F.Mask" "F.Paste")
			(net "P5E_CPU1_P1_TX_DN<14>")
		)
	)
	(footprint ""
		(layer "F.Cu")
		(at 398.389348 -17.624298 90)
		(property "Reference" "C41"
			(at 0 0 90)
			(layer "F.SilkS")
			(hide yes)
			(effects
				(font
					(size 1.27 1.27)
				)
			)
		)
		(property "Value" ""
			(at 0 0 90)
			(layer "F.Fab")
			(effects
				(font
					(size 1.27 1.27)
				)
			)
		)
		(duplicate_pad_numbers_are_jumpers no)
		(fp_line
			(start 0.299974 -0.150114)
			(end 0.299974 0.150114)
			(stroke
				(width 0.1)
				(type default)
			)
			(layer "F.Fab")
		)
		(fp_line
			(start -0.299974 -0.150114)
			(end 0.299974 -0.150114)
			(stroke
				(width 0.1)
				(type default)
			)
			(layer "F.Fab")
		)
		(fp_line
			(start 0.299974 0.150114)
			(end -0.299974 0.150114)
			(stroke
				(width 0.1)
				(type default)
			)
			(layer "F.Fab")
		)
		(fp_line
			(start -0.299974 0.150114)
			(end -0.299974 -0.150114)
			(stroke
				(width 0.1)
				(type default)
			)
			(layer "F.Fab")
		)
		(pad "1" smd rect
			(at -0.2667 0 90)
			(size 0.3048 0.381)
			(layers "F.Cu" "F.Mask" "F.Paste")
			(net "P5E_CPU0_G3_TX_C_DN<12>")
		)
		(pad "2" smd rect
			(at 0.2667 0 90)
			(size 0.3048 0.381)
			(layers "F.Cu" "F.Mask" "F.Paste")
			(net "P5E_CPU0_G3_TX_DN<12>")
		)
	)
	(footprint ""
		(layer "F.Cu")
		(at 174.613062 -32.935672 90)
		(property "Reference" "PC2235"
			(at 0 0 90)
			(layer "F.SilkS")
			(hide yes)
			(effects
				(font
					(size 1.27 1.27)
				)
			)
		)
		(property "Value" ""
			(at 0 0 90)
			(layer "F.Fab")
			(effects
				(font
					(size 1.27 1.27)
				)
			)
		)
		(duplicate_pad_numbers_are_jumpers no)
		(fp_line
			(start 0.7874 -0.4064)
			(end 0.7874 0.4064)
			(stroke
				(width 0.1524)
				(type default)
			)
			(layer "F.SilkS")
		)
		(fp_line
			(start -0.7874 -0.4064)
			(end 0.7874 -0.4064)
			(stroke
				(width 0.1524)
				(type default)
			)
			(layer "F.SilkS")
		)
		(fp_line
			(start 0.7874 0.4064)
			(end -0.7874 0.4064)
			(stroke
				(width 0.1524)
				(type default)
			)
			(layer "F.SilkS")
		)
		(fp_line
			(start -0.7874 0.4064)
			(end -0.7874 -0.4064)
			(stroke
				(width 0.1524)
				(type default)
			)
			(layer "F.SilkS")
		)
		(fp_line
			(start -0.12065 -0.305054)
			(end -0.12065 -0.2794)
			(stroke
				(width 0.1)
				(type default)
			)
			(layer "F.Fab")
		)
		(fp_line
			(start -0.67945 -0.305054)
			(end -0.12065 -0.305054)
			(stroke
				(width 0.1)
				(type default)
			)
			(layer "F.Fab")
		)
		(fp_line
			(start 0.67945 -0.3048)
			(end 0.67945 0.3048)
			(stroke
				(width 0.1)
				(type default)
			)
			(layer "F.Fab")
		)
		(fp_line
			(start 0.12065 -0.3048)
			(end 0.67945 -0.3048)
			(stroke
				(width 0.1)
				(type default)
			)
			(layer "F.Fab")
		)
		(fp_line
			(start 0.12065 -0.2794)
			(end 0.12065 -0.3048)
			(stroke
				(width 0.1)
				(type default)
			)
			(layer "F.Fab")
		)
		(fp_line
			(start -0.12065 -0.2794)
			(end 0.12065 -0.2794)
			(stroke
				(width 0.1)
				(type default)
			)
			(layer "F.Fab")
		)
		(fp_line
			(start 0.120396 0.2794)
			(end -0.12065 0.2794)
			(stroke
				(width 0.1)
				(type default)
			)
			(layer "F.Fab")
		)
		(fp_line
			(start -0.12065 0.2794)
			(end -0.12065 0.3048)
			(stroke
				(width 0.1)
				(type default)
			)
			(layer "F.Fab")
		)
		(fp_line
			(start 0.67945 0.3048)
			(end 0.120396 0.3048)
			(stroke
				(width 0.1)
				(type default)
			)
			(layer "F.Fab")
		)
		(fp_line
			(start 0.120396 0.3048)
			(end 0.120396 0.2794)
			(stroke
				(width 0.1)
				(type default)
			)
			(layer "F.Fab")
		)
		(fp_line
			(start -0.12065 0.3048)
			(end -0.67945 0.3048)
			(stroke
				(width 0.1)
				(type default)
			)
			(layer "F.Fab")
		)
		(fp_line
			(start -0.67945 0.3048)
			(end -0.67945 -0.305054)
			(stroke
				(width 0.1)
				(type default)
			)
			(layer "F.Fab")
		)
		(pad "1" smd circle
			(at -0.40005 0 90)
			(size 0 0)
			(layers "F.Cu" "F.Mask" "F.Paste")
			(net "P12V_SCM_IMON")
		)
		(pad "2" smd circle
			(at 0.40005 0 90)
			(size 0 0)
			(layers "F.Cu" "F.Mask" "F.Paste")
			(net "GND")
		)
	)
	(footprint ""
		(layer "F.Cu")
		(at 302.523398 -431.2539)
		(property "Reference" "R4140"
			(at 0 0 0)
			(layer "F.SilkS")
			(hide yes)
			(effects
				(font
					(size 1.27 1.27)
				)
			)
		)
		(property "Value" ""
			(at 0 0 0)
			(layer "F.Fab")
			(effects
				(font
					(size 1.27 1.27)
				)
			)
		)
		(duplicate_pad_numbers_are_jumpers no)
		(fp_line
			(start -0.7874 -0.4064)
			(end 0.7874 -0.4064)
			(stroke
				(width 0.1524)
				(type default)
			)
			(layer "F.SilkS")
		)
		(fp_line
			(start -0.7874 0.4064)
			(end -0.7874 -0.4064)
			(stroke
				(width 0.1524)
				(type default)
			)
			(layer "F.SilkS")
		)
		(fp_line
			(start 0.7874 -0.4064)
			(end 0.7874 0.4064)
			(stroke
				(width 0.1524)
				(type default)
			)
			(layer "F.SilkS")
		)
		(fp_line
			(start 0.7874 0.4064)
			(end -0.7874 0.4064)
			(stroke
				(width 0.1524)
				(type default)
			)
			(layer "F.SilkS")
		)
		(fp_line
			(start -0.67945 -0.305054)
			(end -0.12065 -0.305054)
			(stroke
				(width 0.1)
				(type default)
			)
			(layer "F.Fab")
		)
		(fp_line
			(start -0.67945 0.3048)
			(end -0.67945 -0.305054)
			(stroke
				(width 0.1)
				(type default)
			)
			(layer "F.Fab")
		)
		(fp_line
			(start -0.12065 -0.305054)
			(end -0.12065 -0.2794)
			(stroke
				(width 0.1)
				(type default)
			)
			(layer "F.Fab")
		)
		(fp_line
			(start -0.12065 -0.2794)
			(end 0.12065 -0.2794)
			(stroke
				(width 0.1)
				(type default)
			)
			(layer "F.Fab")
		)
		(fp_line
			(start -0.12065 0.2794)
			(end -0.12065 0.3048)
			(stroke
				(width 0.1)
				(type default)
			)
			(layer "F.Fab")
		)
		(fp_line
			(start -0.12065 0.3048)
			(end -0.67945 0.3048)
			(stroke
				(width 0.1)
				(type default)
			)
			(layer "F.Fab")
		)
		(fp_line
			(start 0.120396 0.2794)
			(end -0.12065 0.2794)
			(stroke
				(width 0.1)
				(type default)
			)
			(layer "F.Fab")
		)
		(fp_line
			(start 0.120396 0.3048)
			(end 0.120396 0.2794)
			(stroke
				(width 0.1)
				(type default)
			)
			(layer "F.Fab")
		)
		(fp_line
			(start 0.12065 -0.3048)
			(end 0.67945 -0.3048)
			(stroke
				(width 0.1)
				(type default)
			)
			(layer "F.Fab")
		)
		(fp_line
			(start 0.12065 -0.2794)
			(end 0.12065 -0.3048)
			(stroke
				(width 0.1)
				(type default)
			)
			(layer "F.Fab")
		)
		(fp_line
			(start 0.67945 -0.3048)
			(end 0.67945 0.3048)
			(stroke
				(width 0.1)
				(type default)
			)
			(layer "F.Fab")
		)
		(fp_line
			(start 0.67945 0.3048)
			(end 0.120396 0.3048)
			(stroke
				(width 0.1)
				(type default)
			)
			(layer "F.Fab")
		)
		(pad "1" smd circle
			(at -0.40005 0)
			(size 0 0)
			(layers "F.Cu" "F.Mask" "F.Paste")
			(net "P3V3_AUX")
		)
		(pad "2" smd circle
			(at 0.40005 0)
			(size 0 0)
			(layers "F.Cu" "F.Mask" "F.Paste")
			(net "GPU_3V3IO_RSVD3_FFU_ISO")
		)
	)
	(footprint ""
		(layer "F.Cu")
		(at 240.421922 -148.6408)
		(property "Reference" "R1648"
			(at 0 0 0)
			(layer "F.SilkS")
			(hide yes)
			(effects
				(font
					(size 1.27 1.27)
				)
			)
		)
		(property "Value" ""
			(at 0 0 0)
			(layer "F.Fab")
			(effects
				(font
					(size 1.27 1.27)
				)
			)
		)
		(duplicate_pad_numbers_are_jumpers no)
		(fp_line
			(start -0.7874 -0.4064)
			(end 0.7874 -0.4064)
			(stroke
				(width 0.1524)
				(type default)
			)
			(layer "F.SilkS")
		)
		(fp_line
			(start -0.7874 0.4064)
			(end -0.7874 -0.4064)
			(stroke
				(width 0.1524)
				(type default)
			)
			(layer "F.SilkS")
		)
		(fp_line
			(start 0.7874 -0.4064)
			(end 0.7874 0.4064)
			(stroke
				(width 0.1524)
				(type default)
			)
			(layer "F.SilkS")
		)
		(fp_line
			(start 0.7874 0.4064)
			(end -0.7874 0.4064)
			(stroke
				(width 0.1524)
				(type default)
			)
			(layer "F.SilkS")
		)
		(fp_line
			(start -0.67945 -0.305054)
			(end -0.12065 -0.305054)
			(stroke
				(width 0.1)
				(type default)
			)
			(layer "F.Fab")
		)
		(fp_line
			(start -0.67945 0.3048)
			(end -0.67945 -0.305054)
			(stroke
				(width 0.1)
				(type default)
			)
			(layer "F.Fab")
		)
		(fp_line
			(start -0.12065 -0.305054)
			(end -0.12065 -0.2794)
			(stroke
				(width 0.1)
				(type default)
			)
			(layer "F.Fab")
		)
		(fp_line
			(start -0.12065 -0.2794)
			(end 0.12065 -0.2794)
			(stroke
				(width 0.1)
				(type default)
			)
			(layer "F.Fab")
		)
		(fp_line
			(start -0.12065 0.2794)
			(end -0.12065 0.3048)
			(stroke
				(width 0.1)
				(type default)
			)
			(layer "F.Fab")
		)
		(fp_line
			(start -0.12065 0.3048)
			(end -0.67945 0.3048)
			(stroke
				(width 0.1)
				(type default)
			)
			(layer "F.Fab")
		)
		(fp_line
			(start 0.120396 0.2794)
			(end -0.12065 0.2794)
			(stroke
				(width 0.1)
				(type default)
			)
			(layer "F.Fab")
		)
		(fp_line
			(start 0.120396 0.3048)
			(end 0.120396 0.2794)
			(stroke
				(width 0.1)
				(type default)
			)
			(layer "F.Fab")
		)
		(fp_line
			(start 0.12065 -0.3048)
			(end 0.67945 -0.3048)
			(stroke
				(width 0.1)
				(type default)
			)
			(layer "F.Fab")
		)
		(fp_line
			(start 0.12065 -0.2794)
			(end 0.12065 -0.3048)
			(stroke
				(width 0.1)
				(type default)
			)
			(layer "F.Fab")
		)
		(fp_line
			(start 0.67945 -0.3048)
			(end 0.67945 0.3048)
			(stroke
				(width 0.1)
				(type default)
			)
			(layer "F.Fab")
		)
		(fp_line
			(start 0.67945 0.3048)
			(end 0.120396 0.3048)
			(stroke
				(width 0.1)
				(type default)
			)
			(layer "F.Fab")
		)
		(pad "1" smd circle
			(at -0.40005 0)
			(size 0 0)
			(layers "F.Cu" "F.Mask" "F.Paste")
			(net "JTAG_CPU0_R_TDI")
		)
		(pad "2" smd circle
			(at 0.40005 0)
			(size 0 0)
			(layers "F.Cu" "F.Mask" "F.Paste")
			(net "JTAG_CPU0_TDI")
		)
	)
	(footprint ""
		(layer "F.Cu")
		(at 152.849834 -324.763892 180)
		(property "Reference" "R736"
			(at 0 0 180)
			(layer "F.SilkS")
			(hide yes)
			(effects
				(font
					(size 1.27 1.27)
				)
			)
		)
		(property "Value" ""
			(at 0 0 180)
			(layer "F.Fab")
			(effects
				(font
					(size 1.27 1.27)
				)
			)
		)
		(duplicate_pad_numbers_are_jumpers no)
		(fp_line
			(start 0.7874 0.4064)
			(end -0.7874 0.4064)
			(stroke
				(width 0.1524)
				(type default)
			)
			(layer "F.SilkS")
		)
		(fp_line
			(start 0.7874 -0.4064)
			(end 0.7874 0.4064)
			(stroke
				(width 0.1524)
				(type default)
			)
			(layer "F.SilkS")
		)
		(fp_line
			(start -0.7874 0.4064)
			(end -0.7874 -0.4064)
			(stroke
				(width 0.1524)
				(type default)
			)
			(layer "F.SilkS")
		)
		(fp_line
			(start -0.7874 -0.4064)
			(end 0.7874 -0.4064)
			(stroke
				(width 0.1524)
				(type default)
			)
			(layer "F.SilkS")
		)
		(fp_line
			(start 0.67945 0.3048)
			(end 0.120396 0.3048)
			(stroke
				(width 0.1)
				(type default)
			)
			(layer "F.Fab")
		)
		(fp_line
			(start 0.67945 -0.3048)
			(end 0.67945 0.3048)
			(stroke
				(width 0.1)
				(type default)
			)
			(layer "F.Fab")
		)
		(fp_line
			(start 0.12065 -0.2794)
			(end 0.12065 -0.3048)
			(stroke
				(width 0.1)
				(type default)
			)
			(layer "F.Fab")
		)
		(fp_line
			(start 0.12065 -0.3048)
			(end 0.67945 -0.3048)
			(stroke
				(width 0.1)
				(type default)
			)
			(layer "F.Fab")
		)
		(fp_line
			(start 0.120396 0.3048)
			(end 0.120396 0.2794)
			(stroke
				(width 0.1)
				(type default)
			)
			(layer "F.Fab")
		)
		(fp_line
			(start 0.120396 0.2794)
			(end -0.12065 0.2794)
			(stroke
				(width 0.1)
				(type default)
			)
			(layer "F.Fab")
		)
		(fp_line
			(start -0.12065 0.3048)
			(end -0.67945 0.3048)
			(stroke
				(width 0.1)
				(type default)
			)
			(layer "F.Fab")
		)
		(fp_line
			(start -0.12065 0.2794)
			(end -0.12065 0.3048)
			(stroke
				(width 0.1)
				(type default)
			)
			(layer "F.Fab")
		)
		(fp_line
			(start -0.12065 -0.2794)
			(end 0.12065 -0.2794)
			(stroke
				(width 0.1)
				(type default)
			)
			(layer "F.Fab")
		)
		(fp_line
			(start -0.12065 -0.305054)
			(end -0.12065 -0.2794)
			(stroke
				(width 0.1)
				(type default)
			)
			(layer "F.Fab")
		)
		(fp_line
			(start -0.67945 0.3048)
			(end -0.67945 -0.305054)
			(stroke
				(width 0.1)
				(type default)
			)
			(layer "F.Fab")
		)
		(fp_line
			(start -0.67945 -0.305054)
			(end -0.12065 -0.305054)
			(stroke
				(width 0.1)
				(type default)
			)
			(layer "F.Fab")
		)
		(pad "1" smd circle
			(at -0.40005 0 180)
			(size 0 0)
			(layers "F.Cu" "F.Mask" "F.Paste")
			(net "PVDD18_S5_P1")
		)
		(pad "2" smd circle
			(at 0.40005 0 180)
			(size 0 0)
			(layers "F.Cu" "F.Mask" "F.Paste")
			(net "PD_ESPI_CPU1_CLK2")
		)
	)
	(footprint ""
		(layer "F.Cu")
		(at 525.408906 -298.384214 90)
		(property "Reference" "X1"
			(at -1.830578 2.823718 0)
			(unlocked yes)
			(layer "F.SilkS")
			(effects
				(font
					(size 0.7874 0.5842)
					(thickness 0.1524)
				)
				(justify left)
			)
		)
		(property "Value" ""
			(at 0 0 90)
			(layer "F.Fab")
			(effects
				(font
					(size 1.27 1.27)
				)
			)
		)
		(property "User Part Number" "N_A"
			(at 1.30175 1.27 180)
			(unlocked yes)
			(layer "Cmts.User")
			(hide yes)
			(effects
				(font
					(size 0.635 0.4064)
					(thickness 0.1524)
				)
			)
		)
		(property "Device Type" "TP_TDR_4P_FTS_TH-TP_TDR_4P_DIP,EMPTY,TP15"
			(at 1.30175 1.27 180)
			(unlocked yes)
			(layer "F.Fab")
			(hide yes)
			(effects
				(font
					(size 0.635 0.4064)
					(thickness 0.1524)
				)
			)
		)
		(duplicate_pad_numbers_are_jumpers no)
		(fp_line
			(start 2.54 -1.27)
			(end 0 -1.27)
			(stroke
				(width 0.1524)
				(type default)
			)
			(layer "F.SilkS")
		)
		(fp_line
			(start 0 -1.27)
			(end 0 -0.635)
			(stroke
				(width 0.1524)
				(type default)
			)
			(layer "F.SilkS")
		)
		(fp_line
			(start 2.54 -1.1303)
			(end 2.54 -1.27)
			(stroke
				(width 0.1524)
				(type default)
			)
			(layer "F.SilkS")
		)
		(fp_line
			(start 0 0.635)
			(end 0 1.905)
			(stroke
				(width 0.1524)
				(type default)
			)
			(layer "F.SilkS")
		)
		(fp_line
			(start 2.54 1.4097)
			(end 2.54 1.1303)
			(stroke
				(width 0.1524)
				(type default)
			)
			(layer "F.SilkS")
		)
		(fp_line
			(start 0 3.175)
			(end 0 3.81)
			(stroke
				(width 0.1524)
				(type default)
			)
			(layer "F.SilkS")
		)
		(fp_line
			(start 2.54 3.81)
			(end 2.54 3.6703)
			(stroke
				(width 0.1524)
				(type default)
			)
			(layer "F.SilkS")
		)
		(fp_line
			(start 0 3.81)
			(end 2.54 3.81)
			(stroke
				(width 0.1524)
				(type default)
			)
			(layer "F.SilkS")
		)
		(fp_poly
			(pts
				(xy -0.761746 0) (xy -2.285746 0.762) (xy -2.285746 -0.762)
			)
			(stroke
				(width 0)
				(type default)
			)
			(fill yes)
			(layer "F.SilkS")
		)
		(fp_line
			(start 2.54 -1.27)
			(end 0 -1.27)
			(stroke
				(width 0.1)
				(type default)
			)
			(layer "F.Fab")
		)
		(fp_line
			(start 0 -1.27)
			(end 0 3.81)
			(stroke
				(width 0.1)
				(type default)
			)
			(layer "F.Fab")
		)
		(fp_line
			(start 2.54 3.81)
			(end 2.54 -1.27)
			(stroke
				(width 0.1)
				(type default)
			)
			(layer "F.Fab")
		)
		(fp_line
			(start 0 3.81)
			(end 2.54 3.81)
			(stroke
				(width 0.1)
				(type default)
			)
			(layer "F.Fab")
		)
		(fp_poly
			(pts
				(xy -0.761746 0) (xy -2.285746 -0.762) (xy -2.285746 0.762)
			)
			(stroke
				(width 0)
				(type default)
			)
			(fill yes)
			(layer "F.Fab")
		)
		(pad "1" thru_hole circle
			(at 0 0 90)
			(size 1.0033 1.0033)
			(drill 0.249936)
			(layers "*.Cu" "*.Mask")
			(remove_unused_layers no)
			(net "TDR_DIFF_80_TOP_DP")
			(clearance 0.10795)
			(thermal_gap 0.10795)
			(padstack
				(mode front_inner_back)
				(layer "Inner"
					(shape circle)
					(size 0.8001 0.8001)
					(clearance 0.1524)
				)
				(layer "B.Cu"
					(shape circle)
					(size 1.0033 1.0033)
					(clearance 0.10795)
				)
			)
		)
		(pad "2" thru_hole circle
			(at 2.54 0 90)
			(size 1.9939 1.9939)
			(drill 0.249936)
			(layers "*.Cu" "*.Mask")
			(remove_unused_layers no)
			(net "T1_GND")
			(clearance 0.10795)
			(thermal_gap 0.10795)
			(padstack
				(mode front_inner_back)
				(layer "Inner"
					(shape circle)
					(size 0.8001 0.8001)
					(clearance 0.1524)
				)
				(layer "B.Cu"
					(shape circle)
					(size 1.9939 1.9939)
					(clearance 0.10795)
				)
			)
		)
		(pad "3" thru_hole circle
			(at 2.54 2.54 90)
			(size 1.9939 1.9939)
			(drill 0.249936)
			(layers "*.Cu" "*.Mask")
			(remove_unused_layers no)
			(net "T1_GND")
			(clearance 0.10795)
			(thermal_gap 0.10795)
			(padstack
				(mode front_inner_back)
				(layer "Inner"
					(shape circle)
					(size 0.8001 0.8001)
					(clearance 0.1524)
				)
				(layer "B.Cu"
					(shape circle)
					(size 1.9939 1.9939)
					(clearance 0.10795)
				)
			)
		)
		(pad "4" thru_hole circle
			(at 0 2.54 90)
			(size 1.0033 1.0033)
			(drill 0.249936)
			(layers "*.Cu" "*.Mask")
			(remove_unused_layers no)
			(net "TDR_DIFF_80_TOP_DN")
			(clearance 0.10795)
			(thermal_gap 0.10795)
			(padstack
				(mode front_inner_back)
				(layer "Inner"
					(shape circle)
					(size 0.8001 0.8001)
					(clearance 0.1524)
				)
				(layer "B.Cu"
					(shape circle)
					(size 1.0033 1.0033)
					(clearance 0.10795)
				)
			)
		)
	)
	(footprint ""
		(layer "F.Cu")
		(at 195.2498 -137.668 90)
		(property "Reference" "R6855"
			(at 0 0 90)
			(layer "F.SilkS")
			(hide yes)
			(effects
				(font
					(size 1.27 1.27)
				)
			)
		)
		(property "Value" ""
			(at 0 0 90)
			(layer "F.Fab")
			(effects
				(font
					(size 1.27 1.27)
				)
			)
		)
		(duplicate_pad_numbers_are_jumpers no)
		(fp_line
			(start 0.7874 -0.4064)
			(end 0.7874 0.4064)
			(stroke
				(width 0.1524)
				(type default)
			)
			(layer "F.SilkS")
		)
		(fp_line
			(start -0.7874 -0.4064)
			(end 0.7874 -0.4064)
			(stroke
				(width 0.1524)
				(type default)
			)
			(layer "F.SilkS")
		)
		(fp_line
			(start 0.7874 0.4064)
			(end -0.7874 0.4064)
			(stroke
				(width 0.1524)
				(type default)
			)
			(layer "F.SilkS")
		)
		(fp_line
			(start -0.7874 0.4064)
			(end -0.7874 -0.4064)
			(stroke
				(width 0.1524)
				(type default)
			)
			(layer "F.SilkS")
		)
		(fp_line
			(start -0.12065 -0.305054)
			(end -0.12065 -0.2794)
			(stroke
				(width 0.1)
				(type default)
			)
			(layer "F.Fab")
		)
		(fp_line
			(start -0.67945 -0.305054)
			(end -0.12065 -0.305054)
			(stroke
				(width 0.1)
				(type default)
			)
			(layer "F.Fab")
		)
		(fp_line
			(start 0.67945 -0.3048)
			(end 0.67945 0.3048)
			(stroke
				(width 0.1)
				(type default)
			)
			(layer "F.Fab")
		)
		(fp_line
			(start 0.12065 -0.3048)
			(end 0.67945 -0.3048)
			(stroke
				(width 0.1)
				(type default)
			)
			(layer "F.Fab")
		)
		(fp_line
			(start 0.12065 -0.2794)
			(end 0.12065 -0.3048)
			(stroke
				(width 0.1)
				(type default)
			)
			(layer "F.Fab")
		)
		(fp_line
			(start -0.12065 -0.2794)
			(end 0.12065 -0.2794)
			(stroke
				(width 0.1)
				(type default)
			)
			(layer "F.Fab")
		)
		(fp_line
			(start 0.120396 0.2794)
			(end -0.12065 0.2794)
			(stroke
				(width 0.1)
				(type default)
			)
			(layer "F.Fab")
		)
		(fp_line
			(start -0.12065 0.2794)
			(end -0.12065 0.3048)
			(stroke
				(width 0.1)
				(type default)
			)
			(layer "F.Fab")
		)
		(fp_line
			(start 0.67945 0.3048)
			(end 0.120396 0.3048)
			(stroke
				(width 0.1)
				(type default)
			)
			(layer "F.Fab")
		)
		(fp_line
			(start 0.120396 0.3048)
			(end 0.120396 0.2794)
			(stroke
				(width 0.1)
				(type default)
			)
			(layer "F.Fab")
		)
		(fp_line
			(start -0.12065 0.3048)
			(end -0.67945 0.3048)
			(stroke
				(width 0.1)
				(type default)
			)
			(layer "F.Fab")
		)
		(fp_line
			(start -0.67945 0.3048)
			(end -0.67945 -0.305054)
			(stroke
				(width 0.1)
				(type default)
			)
			(layer "F.Fab")
		)
		(pad "1" smd circle
			(at -0.40005 0 90)
			(size 0 0)
			(layers "F.Cu" "F.Mask" "F.Paste")
			(net "P0V9_RETIMER_CPU1_EN_R2")
		)
		(pad "2" smd circle
			(at 0.40005 0 90)
			(size 0 0)
			(layers "F.Cu" "F.Mask" "F.Paste")
			(net "P0V9_RETIMER_CPU1_EN")
		)
	)
	(footprint ""
		(layer "F.Cu")
		(at 457.796646 -397.322802 -90)
		(property "Reference" "PC6577_2"
			(at 0 0 270)
			(layer "F.SilkS")
			(hide yes)
			(effects
				(font
					(size 1.27 1.27)
				)
			)
		)
		(property "Value" ""
			(at 0 0 270)
			(layer "F.Fab")
			(effects
				(font
					(size 1.27 1.27)
				)
			)
		)
		(duplicate_pad_numbers_are_jumpers no)
		(fp_line
			(start -0.7874 0.4064)
			(end -0.7874 -0.4064)
			(stroke
				(width 0.1524)
				(type default)
			)
			(layer "F.SilkS")
		)
		(fp_line
			(start 0.7874 0.4064)
			(end -0.7874 0.4064)
			(stroke
				(width 0.1524)
				(type default)
			)
			(layer "F.SilkS")
		)
		(fp_line
			(start -0.7874 -0.4064)
			(end 0.7874 -0.4064)
			(stroke
				(width 0.1524)
				(type default)
			)
			(layer "F.SilkS")
		)
		(fp_line
			(start 0.7874 -0.4064)
			(end 0.7874 0.4064)
			(stroke
				(width 0.1524)
				(type default)
			)
			(layer "F.SilkS")
		)
		(fp_line
			(start -0.67945 0.3048)
			(end -0.67945 -0.305054)
			(stroke
				(width 0.1)
				(type default)
			)
			(layer "F.Fab")
		)
		(fp_line
			(start -0.12065 0.3048)
			(end -0.67945 0.3048)
			(stroke
				(width 0.1)
				(type default)
			)
			(layer "F.Fab")
		)
		(fp_line
			(start 0.120396 0.3048)
			(end 0.120396 0.2794)
			(stroke
				(width 0.1)
				(type default)
			)
			(layer "F.Fab")
		)
		(fp_line
			(start 0.67945 0.3048)
			(end 0.120396 0.3048)
			(stroke
				(width 0.1)
				(type default)
			)
			(layer "F.Fab")
		)
		(fp_line
			(start -0.12065 0.2794)
			(end -0.12065 0.3048)
			(stroke
				(width 0.1)
				(type default)
			)
			(layer "F.Fab")
		)
		(fp_line
			(start 0.120396 0.2794)
			(end -0.12065 0.2794)
			(stroke
				(width 0.1)
				(type default)
			)
			(layer "F.Fab")
		)
		(fp_line
			(start -0.12065 -0.2794)
			(end 0.12065 -0.2794)
			(stroke
				(width 0.1)
				(type default)
			)
			(layer "F.Fab")
		)
		(fp_line
			(start 0.12065 -0.2794)
			(end 0.12065 -0.3048)
			(stroke
				(width 0.1)
				(type default)
			)
			(layer "F.Fab")
		)
		(fp_line
			(start 0.12065 -0.3048)
			(end 0.67945 -0.3048)
			(stroke
				(width 0.1)
				(type default)
			)
			(layer "F.Fab")
		)
		(fp_line
			(start 0.67945 -0.3048)
			(end 0.67945 0.3048)
			(stroke
				(width 0.1)
				(type default)
			)
			(layer "F.Fab")
		)
		(fp_line
			(start -0.67945 -0.305054)
			(end -0.12065 -0.305054)
			(stroke
				(width 0.1)
				(type default)
			)
			(layer "F.Fab")
		)
		(fp_line
			(start -0.12065 -0.305054)
			(end -0.12065 -0.2794)
			(stroke
				(width 0.1)
				(type default)
			)
			(layer "F.Fab")
		)
		(pad "1" smd circle
			(at -0.40005 0 270)
			(size 0 0)
			(layers "F.Cu" "F.Mask" "F.Paste")
			(net "SW_P12V_AUX_P0V9_RETIMER_CPU0_FLT")
		)
		(pad "2" smd circle
			(at 0.40005 0 270)
			(size 0 0)
			(layers "F.Cu" "F.Mask" "F.Paste")
			(net "GND")
		)
	)
	(footprint ""
		(layer "F.Cu")
		(at 250.317 -39.064946 -90)
		(property "Reference" "R3972"
			(at 0 0 270)
			(layer "F.SilkS")
			(hide yes)
			(effects
				(font
					(size 1.27 1.27)
				)
			)
		)
		(property "Value" ""
			(at 0 0 270)
			(layer "F.Fab")
			(effects
				(font
					(size 1.27 1.27)
				)
			)
		)
		(duplicate_pad_numbers_are_jumpers no)
		(fp_line
			(start -0.7874 0.4064)
			(end -0.7874 -0.4064)
			(stroke
				(width 0.1524)
				(type default)
			)
			(layer "F.SilkS")
		)
		(fp_line
			(start 0.7874 0.4064)
			(end -0.7874 0.4064)
			(stroke
				(width 0.1524)
				(type default)
			)
			(layer "F.SilkS")
		)
		(fp_line
			(start -0.7874 -0.4064)
			(end 0.7874 -0.4064)
			(stroke
				(width 0.1524)
				(type default)
			)
			(layer "F.SilkS")
		)
		(fp_line
			(start 0.7874 -0.4064)
			(end 0.7874 0.4064)
			(stroke
				(width 0.1524)
				(type default)
			)
			(layer "F.SilkS")
		)
		(fp_line
			(start -0.67945 0.3048)
			(end -0.67945 -0.305054)
			(stroke
				(width 0.1)
				(type default)
			)
			(layer "F.Fab")
		)
		(fp_line
			(start -0.12065 0.3048)
			(end -0.67945 0.3048)
			(stroke
				(width 0.1)
				(type default)
			)
			(layer "F.Fab")
		)
		(fp_line
			(start 0.120396 0.3048)
			(end 0.120396 0.2794)
			(stroke
				(width 0.1)
				(type default)
			)
			(layer "F.Fab")
		)
		(fp_line
			(start 0.67945 0.3048)
			(end 0.120396 0.3048)
			(stroke
				(width 0.1)
				(type default)
			)
			(layer "F.Fab")
		)
		(fp_line
			(start -0.12065 0.2794)
			(end -0.12065 0.3048)
			(stroke
				(width 0.1)
				(type default)
			)
			(layer "F.Fab")
		)
		(fp_line
			(start 0.120396 0.2794)
			(end -0.12065 0.2794)
			(stroke
				(width 0.1)
				(type default)
			)
			(layer "F.Fab")
		)
		(fp_line
			(start -0.12065 -0.2794)
			(end 0.12065 -0.2794)
			(stroke
				(width 0.1)
				(type default)
			)
			(layer "F.Fab")
		)
		(fp_line
			(start 0.12065 -0.2794)
			(end 0.12065 -0.3048)
			(stroke
				(width 0.1)
				(type default)
			)
			(layer "F.Fab")
		)
		(fp_line
			(start 0.12065 -0.3048)
			(end 0.67945 -0.3048)
			(stroke
				(width 0.1)
				(type default)
			)
			(layer "F.Fab")
		)
		(fp_line
			(start 0.67945 -0.3048)
			(end 0.67945 0.3048)
			(stroke
				(width 0.1)
				(type default)
			)
			(layer "F.Fab")
		)
		(fp_line
			(start -0.67945 -0.305054)
			(end -0.12065 -0.305054)
			(stroke
				(width 0.1)
				(type default)
			)
			(layer "F.Fab")
		)
		(fp_line
			(start -0.12065 -0.305054)
			(end -0.12065 -0.2794)
			(stroke
				(width 0.1)
				(type default)
			)
			(layer "F.Fab")
		)
		(pad "1" smd circle
			(at -0.40005 0 270)
			(size 0 0)
			(layers "F.Cu" "F.Mask" "F.Paste")
			(net "P12V_E1S_PWRGD_0")
		)
		(pad "2" smd circle
			(at 0.40005 0 270)
			(size 0 0)
			(layers "F.Cu" "F.Mask" "F.Paste")
			(net "HP_LVC3_E1S_0_HSC_PWRGD")
		)
	)
	(footprint ""
		(layer "F.Cu")
		(at 418.917882 -362.087414 -90)
		(property "Reference" "PU21"
			(at -5.639816 -0.501904 0)
			(unlocked yes)
			(layer "F.SilkS")
			(effects
				(font
					(size 0.7874 0.5842)
					(thickness 0.1524)
				)
				(justify left)
			)
		)
		(property "Value" ""
			(at 0 0 270)
			(layer "F.Fab")
			(effects
				(font
					(size 1.27 1.27)
				)
			)
		)
		(duplicate_pad_numbers_are_jumpers no)
		(fp_line
			(start 1.778 3.6322)
			(end 1.778 2.8702)
			(stroke
				(width 0.1524)
				(type default)
			)
			(layer "F.SilkS")
		)
		(fp_line
			(start -0.2032 2.8829)
			(end -0.2032 3.2639)
			(stroke
				(width 0.1524)
				(type default)
			)
			(layer "F.SilkS")
		)
		(fp_line
			(start -2.500122 2.500122)
			(end -2.500122 2.018538)
			(stroke
				(width 0.1524)
				(type default)
			)
			(layer "F.SilkS")
		)
		(fp_line
			(start -2.015998 2.500122)
			(end -2.500122 2.500122)
			(stroke
				(width 0.1524)
				(type default)
			)
			(layer "F.SilkS")
		)
		(fp_line
			(start 2.500122 2.500122)
			(end 2.015998 2.500122)
			(stroke
				(width 0.1524)
				(type default)
			)
			(layer "F.SilkS")
		)
		(fp_line
			(start 2.500122 2.015998)
			(end 2.500122 2.500122)
			(stroke
				(width 0.1524)
				(type default)
			)
			(layer "F.SilkS")
		)
		(fp_line
			(start -3.103626 1.8034)
			(end -2.8956 1.8034)
			(stroke
				(width 0.1524)
				(type default)
			)
			(layer "F.SilkS")
		)
		(fp_line
			(start 2.8829 0.2032)
			(end 3.2639 0.2032)
			(stroke
				(width 0.1524)
				(type default)
			)
			(layer "F.SilkS")
		)
		(fp_line
			(start -3.2639 -0.1778)
			(end -2.8829 -0.1778)
			(stroke
				(width 0.1524)
				(type default)
			)
			(layer "F.SilkS")
		)
		(fp_line
			(start 2.8702 -1.778)
			(end 3.6322 -1.778)
			(stroke
				(width 0.1524)
				(type default)
			)
			(layer "F.SilkS")
		)
		(fp_line
			(start -2.500122 -2.015998)
			(end -2.500122 -2.500122)
			(stroke
				(width 0.1524)
				(type default)
			)
			(layer "F.SilkS")
		)
		(fp_line
			(start -2.500122 -2.500122)
			(end -2.015998 -2.500122)
			(stroke
				(width 0.1524)
				(type default)
			)
			(layer "F.SilkS")
		)
		(fp_line
			(start 2.015998 -2.500122)
			(end 2.500122 -2.500122)
			(stroke
				(width 0.1524)
				(type default)
			)
			(layer "F.SilkS")
		)
		(fp_line
			(start 2.500122 -2.500122)
			(end 2.500122 -2.015998)
			(stroke
				(width 0.1524)
				(type default)
			)
			(layer "F.SilkS")
		)
		(fp_line
			(start -1.8034 -2.8702)
			(end -1.8034 -3.6322)
			(stroke
				(width 0.1524)
				(type default)
			)
			(layer "F.SilkS")
		)
		(fp_line
			(start 0.1778 -3.2385)
			(end 0.1778 -2.8575)
			(stroke
				(width 0.1524)
				(type default)
			)
			(layer "F.SilkS")
		)
		(fp_poly
			(pts
				(xy -2.391918 -2.826512) (xy -2.622296 -2.366264) (xy -2.852674 -2.826766)
			)
			(stroke
				(width 0)
				(type default)
			)
			(fill yes)
			(layer "F.SilkS")
		)
		(fp_line
			(start 1.778 3.6322)
			(end 1.778 2.8702)
			(stroke
				(width 0.1)
				(type default)
			)
			(layer "F.Fab")
		)
		(fp_line
			(start -0.2032 2.8829)
			(end -0.2032 3.2639)
			(stroke
				(width 0.1)
				(type default)
			)
			(layer "F.Fab")
		)
		(fp_line
			(start -2.500122 2.500122)
			(end -2.500122 -2.500122)
			(stroke
				(width 0.1)
				(type default)
			)
			(layer "F.Fab")
		)
		(fp_line
			(start 2.500122 2.500122)
			(end -2.500122 2.500122)
			(stroke
				(width 0.1)
				(type default)
			)
			(layer "F.Fab")
		)
		(fp_line
			(start -3.6576 1.8034)
			(end -2.8956 1.8034)
			(stroke
				(width 0.1)
				(type default)
			)
			(layer "F.Fab")
		)
		(fp_line
			(start 2.8829 0.2032)
			(end 3.2639 0.2032)
			(stroke
				(width 0.1)
				(type default)
			)
			(layer "F.Fab")
		)
		(fp_line
			(start -3.2639 -0.1778)
			(end -2.8829 -0.1778)
			(stroke
				(width 0.1)
				(type default)
			)
			(layer "F.Fab")
		)
		(fp_line
			(start 2.8702 -1.778)
			(end 3.6322 -1.778)
			(stroke
				(width 0.1)
				(type default)
			)
			(layer "F.Fab")
		)
		(fp_line
			(start -2.500122 -2.500122)
			(end 2.500122 -2.500122)
			(stroke
				(width 0.1)
				(type default)
			)
			(layer "F.Fab")
		)
		(fp_line
			(start 2.500122 -2.500122)
			(end 2.500122 2.500122)
			(stroke
				(width 0.1)
				(type default)
			)
			(layer "F.Fab")
		)
		(fp_line
			(start -1.8034 -2.8702)
			(end -1.8034 -3.6322)
			(stroke
				(width 0.1)
				(type default)
			)
			(layer "F.Fab")
		)
		(fp_line
			(start 0.1778 -3.2385)
			(end 0.1778 -2.8575)
			(stroke
				(width 0.1)
				(type default)
			)
			(layer "F.Fab")
		)
		(fp_poly
			(pts
				(xy -2.921 -1.800098) (xy -3.504184 -1.508506) (xy -3.504184 -2.09169)
			)
			(stroke
				(width 0)
				(type default)
			)
			(fill yes)
			(layer "F.Fab")
		)
		(fp_text user "20"
			(at 1.8288 5.031232 270)
			(unlocked yes)
			(layer "F.SilkS")
			(effects
				(font
					(size 0.635 0.4064)
					(thickness 0.1524)
				)
				(justify left)
			)
		)
		(fp_text user "21"
			(at 4.1021 4.501642 180)
			(unlocked yes)
			(layer "F.SilkS")
			(effects
				(font
					(size 0.635 0.4064)
					(thickness 0.1524)
				)
				(justify left)
			)
		)
		(fp_text user "11"
			(at -2.8702 3.278632 270)
			(unlocked yes)
			(layer "F.SilkS")
			(effects
				(font
					(size 0.635 0.4064)
					(thickness 0.1524)
				)
				(justify left)
			)
		)
		(fp_text user "10"
			(at -3.395726 1.796288 180)
			(unlocked yes)
			(layer "F.SilkS")
			(effects
				(font
					(size 0.635 0.4064)
					(thickness 0.1524)
				)
				(justify left)
			)
		)
		(fp_text user "30"
			(at 3.096768 -2.9718 180)
			(unlocked yes)
			(layer "F.SilkS")
			(effects
				(font
					(size 0.635 0.4064)
					(thickness 0.1524)
				)
				(justify left)
			)
		)
		(fp_text user "31"
			(at 0.98298 -3.172968 270)
			(unlocked yes)
			(layer "F.SilkS")
			(effects
				(font
					(size 0.635 0.4064)
					(thickness 0.1524)
				)
				(justify left)
			)
		)
		(fp_text user "40"
			(at -2.6924 -6.017768 270)
			(unlocked yes)
			(layer "F.SilkS")
			(effects
				(font
					(size 0.635 0.4064)
					(thickness 0.1524)
				)
				(justify left)
			)
		)
		(fp_text user "11"
			(at -2.8702 3.278632 270)
			(unlocked yes)
			(layer "F.Fab")
			(effects
				(font
					(size 0.635 0.4064)
					(thickness 0.1524)
				)
				(justify left)
			)
		)
		(fp_text user "20"
			(at 2.0828 3.253232 270)
			(unlocked yes)
			(layer "F.Fab")
			(effects
				(font
					(size 0.635 0.4064)
					(thickness 0.1524)
				)
				(justify left)
			)
		)
		(fp_text user "10"
			(at -3.253232 2.1336 180)
			(unlocked yes)
			(layer "F.Fab")
			(effects
				(font
					(size 0.635 0.4064)
					(thickness 0.1524)
				)
				(justify left)
			)
		)
		(fp_text user "21"
			(at 3.274568 1.8796 180)
			(unlocked yes)
			(layer "F.Fab")
			(effects
				(font
					(size 0.635 0.4064)
					(thickness 0.1524)
				)
				(justify left)
			)
		)
		(fp_text user "40"
			(at -3.2004 -3.096768 270)
			(unlocked yes)
			(layer "F.Fab")
			(effects
				(font
					(size 0.635 0.4064)
					(thickness 0.1524)
				)
				(justify left)
			)
		)
		(fp_text user "30"
			(at 3.223768 -3.0988 180)
			(unlocked yes)
			(layer "F.Fab")
			(effects
				(font
					(size 0.635 0.4064)
					(thickness 0.1524)
				)
				(justify left)
			)
		)
		(fp_text user "31"
			(at 1.8542 -3.172968 270)
			(unlocked yes)
			(layer "F.Fab")
			(effects
				(font
					(size 0.635 0.4064)
					(thickness 0.1524)
				)
				(justify left)
			)
		)
		(pad "1" smd rect
			(at -2.400046 -1.800098 180)
			(size 0.1778 0.6096)
			(layers "F.Cu" "F.Mask" "F.Paste")
			(net "NC_PVDD11_S3_P0_PWM8")
		)
		(pad "2" smd rect
			(at -2.400046 -1.400048 180)
			(size 0.1778 0.6096)
			(layers "F.Cu" "F.Mask" "F.Paste")
			(net "NC_PVDD11_S3_P0_PWM7")
		)
		(pad "3" smd rect
			(at -2.400046 -0.999998 180)
			(size 0.1778 0.6096)
			(layers "F.Cu" "F.Mask" "F.Paste")
			(net "NC_PVDD11_S3_P0_PWM6")
		)
		(pad "4" smd rect
			(at -2.400046 -0.599948 180)
			(size 0.1778 0.6096)
			(layers "F.Cu" "F.Mask" "F.Paste")
			(net "NC_PVDD11_S3_P0_PWM5")
		)
		(pad "5" smd rect
			(at -2.400046 -0.199898 180)
			(size 0.1778 0.6096)
			(layers "F.Cu" "F.Mask" "F.Paste")
			(net "NC_PVDD11_S3_P0_PWM4")
		)
		(pad "6" smd rect
			(at -2.400046 0.199898 180)
			(size 0.1778 0.6096)
			(layers "F.Cu" "F.Mask" "F.Paste")
			(net "NC_PVDD11_S3_P0_PWM3")
		)
		(pad "7" smd rect
			(at -2.400046 0.599948 180)
			(size 0.1778 0.6096)
			(layers "F.Cu" "F.Mask" "F.Paste")
			(net "PVDD11_S3_P0_PWM2")
		)
		(pad "8" smd rect
			(at -2.400046 0.999998 180)
			(size 0.1778 0.6096)
			(layers "F.Cu" "F.Mask" "F.Paste")
			(net "PVDD11_S3_P0_PWM1")
		)
		(pad "9" smd rect
			(at -2.400046 1.400048 180)
			(size 0.1778 0.6096)
			(layers "F.Cu" "F.Mask" "F.Paste")
			(net "PVDD11_S3_P0_PMSDA_R")
		)
		(pad "10" smd rect
			(at -2.400046 1.800098 180)
			(size 0.1778 0.6096)
			(layers "F.Cu" "F.Mask" "F.Paste")
			(net "PVDD11_S3_P0_PMSCL_R")
		)
		(pad "11" smd rect
			(at -1.800098 2.400046 270)
			(size 0.1778 0.6096)
			(layers "F.Cu" "F.Mask" "F.Paste")
			(net "PVDD11_S3_P0_PMALERT_R")
		)
		(pad "12" smd rect
			(at -1.400048 2.400046 270)
			(size 0.1778 0.6096)
			(layers "F.Cu" "F.Mask" "F.Paste")
			(net "PWRGD_PVDD11_S3_P0_R")
		)
		(pad "13" smd rect
			(at -0.999998 2.400046 270)
			(size 0.1778 0.6096)
			(layers "F.Cu" "F.Mask" "F.Paste")
			(net "PVDD11_S3_P0_EN_R")
		)
		(pad "14" smd rect
			(at -0.599948 2.400046 270)
			(size 0.1778 0.6096)
			(layers "F.Cu" "F.Mask" "F.Paste")
			(net "PVDD11_S3_P0_RESET_N_R")
		)
		(pad "15" smd rect
			(at -0.199898 2.400046 270)
			(size 0.1778 0.6096)
			(layers "F.Cu" "F.Mask" "F.Paste")
			(net "PVDD11_S3_P0_VDDIO")
		)
		(pad "16" smd rect
			(at 0.199898 2.400046 270)
			(size 0.1778 0.6096)
			(layers "F.Cu" "F.Mask" "F.Paste")
			(net "NC_PVDD11_S3_P0_PG1")
		)
		(pad "17" smd rect
			(at 0.599948 2.400046 270)
			(size 0.1778 0.6096)
			(layers "F.Cu" "F.Mask" "F.Paste")
			(net "GND")
		)
		(pad "18" smd rect
			(at 0.999998 2.400046 270)
			(size 0.1778 0.6096)
			(layers "F.Cu" "F.Mask" "F.Paste")
			(net "GND")
		)
		(pad "19" smd rect
			(at 1.400048 2.400046 270)
			(size 0.1778 0.6096)
			(layers "F.Cu" "F.Mask" "F.Paste")
			(net "NC_PVDD11_S3_P0_SVTO")
		)
		(pad "20" smd rect
			(at 1.800098 2.400046 270)
			(size 0.1778 0.6096)
			(layers "F.Cu" "F.Mask" "F.Paste")
			(net "GND")
		)
		(pad "21" smd rect
			(at 2.400046 1.800098 180)
			(size 0.1778 0.6096)
			(layers "F.Cu" "F.Mask" "F.Paste")
			(net "VSENSE_PVDD11_S3_P0_R")
		)
		(pad "22" smd rect
			(at 2.400046 1.400048 180)
			(size 0.1778 0.6096)
			(layers "F.Cu" "F.Mask" "F.Paste")
			(net "VSENSE_VSS_SENSE_C_P0")
		)
		(pad "23" smd rect
			(at 2.400046 0.999998 180)
			(size 0.1778 0.6096)
			(layers "F.Cu" "F.Mask" "F.Paste")
			(net "PVDD11_S3_P0_IMON1")
		)
		(pad "24" smd rect
			(at 2.400046 0.599948 180)
			(size 0.1778 0.6096)
			(layers "F.Cu" "F.Mask" "F.Paste")
			(net "PVDD11_S3_P0_IMON2")
		)
		(pad "25" smd rect
			(at 2.400046 0.199898 180)
			(size 0.1778 0.6096)
			(layers "F.Cu" "F.Mask" "F.Paste")
			(net "NC_PVDD11_S3_P0_IMON3")
		)
		(pad "26" smd rect
			(at 2.400046 -0.199898 180)
			(size 0.1778 0.6096)
			(layers "F.Cu" "F.Mask" "F.Paste")
			(net "NC_PVDD11_S3_P0_IMON4")
		)
		(pad "27" smd rect
			(at 2.400046 -0.599948 180)
			(size 0.1778 0.6096)
			(layers "F.Cu" "F.Mask" "F.Paste")
			(net "NC_PVDD11_S3_P0_IMON5")
		)
		(pad "28" smd rect
			(at 2.400046 -0.999998 180)
			(size 0.1778 0.6096)
			(layers "F.Cu" "F.Mask" "F.Paste")
			(net "NC_PVDD11_S3_P0_IMON6")
		)
		(pad "29" smd rect
			(at 2.400046 -1.400048 180)
			(size 0.1778 0.6096)
			(layers "F.Cu" "F.Mask" "F.Paste")
			(net "NC_PVDD11_S3_P0_IMON7")
		)
		(pad "30" smd rect
			(at 2.400046 -1.800098 180)
			(size 0.1778 0.6096)
			(layers "F.Cu" "F.Mask" "F.Paste")
			(net "NC_PVDD11_S3_P0_IMON8")
		)
		(pad "31" smd rect
			(at 1.800098 -2.400046 270)
			(size 0.1778 0.6096)
			(layers "F.Cu" "F.Mask" "F.Paste")
			(net "GND")
		)
		(pad "32" smd rect
			(at 1.400048 -2.400046 270)
			(size 0.1778 0.6096)
			(layers "F.Cu" "F.Mask" "F.Paste")
			(net "GND")
		)
		(pad "33" smd rect
			(at 0.999998 -2.400046 270)
			(size 0.1778 0.6096)
			(layers "F.Cu" "F.Mask" "F.Paste")
			(net "PVDD11_S3_P0_OCP_N_R")
		)
		(pad "34" smd rect
			(at 0.599948 -2.400046 270)
			(size 0.1778 0.6096)
			(layers "F.Cu" "F.Mask" "F.Paste")
			(net "PVDD11_S3_P0_ADDR_CFG")
		)
		(pad "35" smd rect
			(at 0.199898 -2.400046 270)
			(size 0.1778 0.6096)
			(layers "F.Cu" "F.Mask" "F.Paste")
			(net "PVDD11_S3_P0_TEMP1")
		)
		(pad "36" smd rect
			(at -0.199898 -2.400046 270)
			(size 0.1778 0.6096)
			(layers "F.Cu" "F.Mask" "F.Paste")
			(net "PVDD11_S3_P0_TEMP0")
		)
		(pad "37" smd rect
			(at -0.599948 -2.400046 270)
			(size 0.1778 0.6096)
			(layers "F.Cu" "F.Mask" "F.Paste")
			(net "PVDD11_S3_P0_VMON")
		)
		(pad "38" smd rect
			(at -0.999998 -2.400046 270)
			(size 0.1778 0.6096)
			(layers "F.Cu" "F.Mask" "F.Paste")
			(net "PVDD11_S3_P0_VINSEN")
		)
		(pad "39" smd rect
			(at -1.400048 -2.400046 270)
			(size 0.1778 0.6096)
			(layers "F.Cu" "F.Mask" "F.Paste")
			(net "PVDD11_S3_P0_VCC")
		)
		(pad "40" smd rect
			(at -1.800098 -2.400046 270)
			(size 0.1778 0.6096)
			(layers "F.Cu" "F.Mask" "F.Paste")
			(net "PVDD11_S3_P0_VCCS")
		)
		(pad "TH" smd rect
			(at 0 0 270)
			(size 3.6576 3.6576)
			(layers "F.Cu" "F.Mask" "F.Paste")
			(net "GND")
		)
		(zone
			(layer "F.Cu")
			(hatch none 0.5)
			(connect_pads
				(clearance 0)
			)
			(min_thickness 0.25)
			(keepout
				(tracks not_allowed)
				(vias allowed)
				(pads allowed)
				(copperpour not_allowed)
				(footprints allowed)
			)
			(placement
				(enabled no)
				(sheetname "")
			)
			(fill
				(thermal_gap 0.5)
				(thermal_bridge_width 0.5)
				(island_removal_mode 0)
			)
			(polygon
				(pts
					(xy 416.885882 -361.70362) (xy 416.885882 -364.119414) (xy 420.772082 -364.119414) (xy 420.772082 -363.967014)
					(xy 417.038282 -363.967014) (xy 417.038282 -361.70362)
				)
			)
		)
	)
	(footprint ""
		(layer "F.Cu")
		(at 402.151088 -330.778612)
		(property "Reference" "R940"
			(at 0 0 0)
			(layer "F.SilkS")
			(hide yes)
			(effects
				(font
					(size 1.27 1.27)
				)
			)
		)
		(property "Value" ""
			(at 0 0 0)
			(layer "F.Fab")
			(effects
				(font
					(size 1.27 1.27)
				)
			)
		)
		(duplicate_pad_numbers_are_jumpers no)
		(fp_line
			(start -0.7874 -0.4064)
			(end 0.7874 -0.4064)
			(stroke
				(width 0.1524)
				(type default)
			)
			(layer "F.SilkS")
		)
		(fp_line
			(start -0.7874 0.4064)
			(end -0.7874 -0.4064)
			(stroke
				(width 0.1524)
				(type default)
			)
			(layer "F.SilkS")
		)
		(fp_line
			(start 0.7874 -0.4064)
			(end 0.7874 0.4064)
			(stroke
				(width 0.1524)
				(type default)
			)
			(layer "F.SilkS")
		)
		(fp_line
			(start 0.7874 0.4064)
			(end -0.7874 0.4064)
			(stroke
				(width 0.1524)
				(type default)
			)
			(layer "F.SilkS")
		)
		(fp_line
			(start -0.67945 -0.305054)
			(end -0.12065 -0.305054)
			(stroke
				(width 0.1)
				(type default)
			)
			(layer "F.Fab")
		)
		(fp_line
			(start -0.67945 0.3048)
			(end -0.67945 -0.305054)
			(stroke
				(width 0.1)
				(type default)
			)
			(layer "F.Fab")
		)
		(fp_line
			(start -0.12065 -0.305054)
			(end -0.12065 -0.2794)
			(stroke
				(width 0.1)
				(type default)
			)
			(layer "F.Fab")
		)
		(fp_line
			(start -0.12065 -0.2794)
			(end 0.12065 -0.2794)
			(stroke
				(width 0.1)
				(type default)
			)
			(layer "F.Fab")
		)
		(fp_line
			(start -0.12065 0.2794)
			(end -0.12065 0.3048)
			(stroke
				(width 0.1)
				(type default)
			)
			(layer "F.Fab")
		)
		(fp_line
			(start -0.12065 0.3048)
			(end -0.67945 0.3048)
			(stroke
				(width 0.1)
				(type default)
			)
			(layer "F.Fab")
		)
		(fp_line
			(start 0.120396 0.2794)
			(end -0.12065 0.2794)
			(stroke
				(width 0.1)
				(type default)
			)
			(layer "F.Fab")
		)
		(fp_line
			(start 0.120396 0.3048)
			(end 0.120396 0.2794)
			(stroke
				(width 0.1)
				(type default)
			)
			(layer "F.Fab")
		)
		(fp_line
			(start 0.12065 -0.3048)
			(end 0.67945 -0.3048)
			(stroke
				(width 0.1)
				(type default)
			)
			(layer "F.Fab")
		)
		(fp_line
			(start 0.12065 -0.2794)
			(end 0.12065 -0.3048)
			(stroke
				(width 0.1)
				(type default)
			)
			(layer "F.Fab")
		)
		(fp_line
			(start 0.67945 -0.3048)
			(end 0.67945 0.3048)
			(stroke
				(width 0.1)
				(type default)
			)
			(layer "F.Fab")
		)
		(fp_line
			(start 0.67945 0.3048)
			(end 0.120396 0.3048)
			(stroke
				(width 0.1)
				(type default)
			)
			(layer "F.Fab")
		)
		(pad "1" smd circle
			(at -0.40005 0)
			(size 0 0)
			(layers "F.Cu" "F.Mask" "F.Paste")
			(net "BOOT_RDY_R_H")
		)
		(pad "2" smd circle
			(at 0.40005 0)
			(size 0 0)
			(layers "F.Cu" "F.Mask" "F.Paste")
			(net "BOOT_RDY_H")
		)
	)
	(footprint ""
		(layer "F.Cu")
		(at 323.624194 -38.10762)
		(property "Reference" "R4568"
			(at 0 0 0)
			(layer "F.SilkS")
			(hide yes)
			(effects
				(font
					(size 1.27 1.27)
				)
			)
		)
		(property "Value" ""
			(at 0 0 0)
			(layer "F.Fab")
			(effects
				(font
					(size 1.27 1.27)
				)
			)
		)
		(duplicate_pad_numbers_are_jumpers no)
		(fp_line
			(start -0.7874 -0.4064)
			(end 0.7874 -0.4064)
			(stroke
				(width 0.1524)
				(type default)
			)
			(layer "F.SilkS")
		)
		(fp_line
			(start -0.7874 0.4064)
			(end -0.7874 -0.4064)
			(stroke
				(width 0.1524)
				(type default)
			)
			(layer "F.SilkS")
		)
		(fp_line
			(start 0.7874 -0.4064)
			(end 0.7874 0.4064)
			(stroke
				(width 0.1524)
				(type default)
			)
			(layer "F.SilkS")
		)
		(fp_line
			(start 0.7874 0.4064)
			(end -0.7874 0.4064)
			(stroke
				(width 0.1524)
				(type default)
			)
			(layer "F.SilkS")
		)
		(fp_line
			(start -0.67945 -0.305054)
			(end -0.12065 -0.305054)
			(stroke
				(width 0.1)
				(type default)
			)
			(layer "F.Fab")
		)
		(fp_line
			(start -0.67945 0.3048)
			(end -0.67945 -0.305054)
			(stroke
				(width 0.1)
				(type default)
			)
			(layer "F.Fab")
		)
		(fp_line
			(start -0.12065 -0.305054)
			(end -0.12065 -0.2794)
			(stroke
				(width 0.1)
				(type default)
			)
			(layer "F.Fab")
		)
		(fp_line
			(start -0.12065 -0.2794)
			(end 0.12065 -0.2794)
			(stroke
				(width 0.1)
				(type default)
			)
			(layer "F.Fab")
		)
		(fp_line
			(start -0.12065 0.2794)
			(end -0.12065 0.3048)
			(stroke
				(width 0.1)
				(type default)
			)
			(layer "F.Fab")
		)
		(fp_line
			(start -0.12065 0.3048)
			(end -0.67945 0.3048)
			(stroke
				(width 0.1)
				(type default)
			)
			(layer "F.Fab")
		)
		(fp_line
			(start 0.120396 0.2794)
			(end -0.12065 0.2794)
			(stroke
				(width 0.1)
				(type default)
			)
			(layer "F.Fab")
		)
		(fp_line
			(start 0.120396 0.3048)
			(end 0.120396 0.2794)
			(stroke
				(width 0.1)
				(type default)
			)
			(layer "F.Fab")
		)
		(fp_line
			(start 0.12065 -0.3048)
			(end 0.67945 -0.3048)
			(stroke
				(width 0.1)
				(type default)
			)
			(layer "F.Fab")
		)
		(fp_line
			(start 0.12065 -0.2794)
			(end 0.12065 -0.3048)
			(stroke
				(width 0.1)
				(type default)
			)
			(layer "F.Fab")
		)
		(fp_line
			(start 0.67945 -0.3048)
			(end 0.67945 0.3048)
			(stroke
				(width 0.1)
				(type default)
			)
			(layer "F.Fab")
		)
		(fp_line
			(start 0.67945 0.3048)
			(end 0.120396 0.3048)
			(stroke
				(width 0.1)
				(type default)
			)
			(layer "F.Fab")
		)
		(pad "1" smd circle
			(at -0.40005 0)
			(size 0 0)
			(layers "F.Cu" "F.Mask" "F.Paste")
			(net "P1V581_PDB_ADC")
		)
		(pad "2" smd circle
			(at 0.40005 0)
			(size 0 0)
			(layers "F.Cu" "F.Mask" "F.Paste")
			(net "GND")
		)
	)
	(footprint ""
		(layer "F.Cu")
		(at 192.151 -129.377948 90)
		(property "Reference" "R277"
			(at 0 0 90)
			(layer "F.SilkS")
			(hide yes)
			(effects
				(font
					(size 1.27 1.27)
				)
			)
		)
		(property "Value" ""
			(at 0 0 90)
			(layer "F.Fab")
			(effects
				(font
					(size 1.27 1.27)
				)
			)
		)
		(duplicate_pad_numbers_are_jumpers no)
		(fp_line
			(start 0.7874 -0.4064)
			(end 0.7874 0.4064)
			(stroke
				(width 0.1524)
				(type default)
			)
			(layer "F.SilkS")
		)
		(fp_line
			(start -0.7874 -0.4064)
			(end 0.7874 -0.4064)
			(stroke
				(width 0.1524)
				(type default)
			)
			(layer "F.SilkS")
		)
		(fp_line
			(start 0.7874 0.4064)
			(end -0.7874 0.4064)
			(stroke
				(width 0.1524)
				(type default)
			)
			(layer "F.SilkS")
		)
		(fp_line
			(start -0.7874 0.4064)
			(end -0.7874 -0.4064)
			(stroke
				(width 0.1524)
				(type default)
			)
			(layer "F.SilkS")
		)
		(fp_line
			(start -0.12065 -0.305054)
			(end -0.12065 -0.2794)
			(stroke
				(width 0.1)
				(type default)
			)
			(layer "F.Fab")
		)
		(fp_line
			(start -0.67945 -0.305054)
			(end -0.12065 -0.305054)
			(stroke
				(width 0.1)
				(type default)
			)
			(layer "F.Fab")
		)
		(fp_line
			(start 0.67945 -0.3048)
			(end 0.67945 0.3048)
			(stroke
				(width 0.1)
				(type default)
			)
			(layer "F.Fab")
		)
		(fp_line
			(start 0.12065 -0.3048)
			(end 0.67945 -0.3048)
			(stroke
				(width 0.1)
				(type default)
			)
			(layer "F.Fab")
		)
		(fp_line
			(start 0.12065 -0.2794)
			(end 0.12065 -0.3048)
			(stroke
				(width 0.1)
				(type default)
			)
			(layer "F.Fab")
		)
		(fp_line
			(start -0.12065 -0.2794)
			(end 0.12065 -0.2794)
			(stroke
				(width 0.1)
				(type default)
			)
			(layer "F.Fab")
		)
		(fp_line
			(start 0.120396 0.2794)
			(end -0.12065 0.2794)
			(stroke
				(width 0.1)
				(type default)
			)
			(layer "F.Fab")
		)
		(fp_line
			(start -0.12065 0.2794)
			(end -0.12065 0.3048)
			(stroke
				(width 0.1)
				(type default)
			)
			(layer "F.Fab")
		)
		(fp_line
			(start 0.67945 0.3048)
			(end 0.120396 0.3048)
			(stroke
				(width 0.1)
				(type default)
			)
			(layer "F.Fab")
		)
		(fp_line
			(start 0.120396 0.3048)
			(end 0.120396 0.2794)
			(stroke
				(width 0.1)
				(type default)
			)
			(layer "F.Fab")
		)
		(fp_line
			(start -0.12065 0.3048)
			(end -0.67945 0.3048)
			(stroke
				(width 0.1)
				(type default)
			)
			(layer "F.Fab")
		)
		(fp_line
			(start -0.67945 0.3048)
			(end -0.67945 -0.305054)
			(stroke
				(width 0.1)
				(type default)
			)
			(layer "F.Fab")
		)
		(pad "1" smd circle
			(at -0.40005 0 90)
			(size 0 0)
			(layers "F.Cu" "F.Mask" "F.Paste")
			(net "FM_CPU1_NMI_SYNC_FLOOD_N")
		)
		(pad "2" smd circle
			(at 0.40005 0 90)
			(size 0 0)
			(layers "F.Cu" "F.Mask" "F.Paste")
			(net "CPU1_NMI_SYNC_FLOOD_N")
		)
	)
	(footprint ""
		(layer "F.Cu")
		(at 200.057258 -77.06614 180)
		(property "Reference" "R72"
			(at 0 0 180)
			(layer "F.SilkS")
			(hide yes)
			(effects
				(font
					(size 1.27 1.27)
				)
			)
		)
		(property "Value" ""
			(at 0 0 180)
			(layer "F.Fab")
			(effects
				(font
					(size 1.27 1.27)
				)
			)
		)
		(duplicate_pad_numbers_are_jumpers no)
		(fp_line
			(start 0.7874 0.4064)
			(end -0.7874 0.4064)
			(stroke
				(width 0.1524)
				(type default)
			)
			(layer "F.SilkS")
		)
		(fp_line
			(start 0.7874 -0.4064)
			(end 0.7874 0.4064)
			(stroke
				(width 0.1524)
				(type default)
			)
			(layer "F.SilkS")
		)
		(fp_line
			(start -0.7874 0.4064)
			(end -0.7874 -0.4064)
			(stroke
				(width 0.1524)
				(type default)
			)
			(layer "F.SilkS")
		)
		(fp_line
			(start -0.7874 -0.4064)
			(end 0.7874 -0.4064)
			(stroke
				(width 0.1524)
				(type default)
			)
			(layer "F.SilkS")
		)
		(fp_line
			(start 0.67945 0.3048)
			(end 0.120396 0.3048)
			(stroke
				(width 0.1)
				(type default)
			)
			(layer "F.Fab")
		)
		(fp_line
			(start 0.67945 -0.3048)
			(end 0.67945 0.3048)
			(stroke
				(width 0.1)
				(type default)
			)
			(layer "F.Fab")
		)
		(fp_line
			(start 0.12065 -0.2794)
			(end 0.12065 -0.3048)
			(stroke
				(width 0.1)
				(type default)
			)
			(layer "F.Fab")
		)
		(fp_line
			(start 0.12065 -0.3048)
			(end 0.67945 -0.3048)
			(stroke
				(width 0.1)
				(type default)
			)
			(layer "F.Fab")
		)
		(fp_line
			(start 0.120396 0.3048)
			(end 0.120396 0.2794)
			(stroke
				(width 0.1)
				(type default)
			)
			(layer "F.Fab")
		)
		(fp_line
			(start 0.120396 0.2794)
			(end -0.12065 0.2794)
			(stroke
				(width 0.1)
				(type default)
			)
			(layer "F.Fab")
		)
		(fp_line
			(start -0.12065 0.3048)
			(end -0.67945 0.3048)
			(stroke
				(width 0.1)
				(type default)
			)
			(layer "F.Fab")
		)
		(fp_line
			(start -0.12065 0.2794)
			(end -0.12065 0.3048)
			(stroke
				(width 0.1)
				(type default)
			)
			(layer "F.Fab")
		)
		(fp_line
			(start -0.12065 -0.2794)
			(end 0.12065 -0.2794)
			(stroke
				(width 0.1)
				(type default)
			)
			(layer "F.Fab")
		)
		(fp_line
			(start -0.12065 -0.305054)
			(end -0.12065 -0.2794)
			(stroke
				(width 0.1)
				(type default)
			)
			(layer "F.Fab")
		)
		(fp_line
			(start -0.67945 0.3048)
			(end -0.67945 -0.305054)
			(stroke
				(width 0.1)
				(type default)
			)
			(layer "F.Fab")
		)
		(fp_line
			(start -0.67945 -0.305054)
			(end -0.12065 -0.305054)
			(stroke
				(width 0.1)
				(type default)
			)
			(layer "F.Fab")
		)
		(pad "1" smd circle
			(at -0.40005 0 180)
			(size 0 0)
			(layers "F.Cu" "F.Mask" "F.Paste")
			(net "NCSI_BMC_RXD0_R")
		)
		(pad "2" smd circle
			(at 0.40005 0 180)
			(size 0 0)
			(layers "F.Cu" "F.Mask" "F.Paste")
			(net "RMII_OCP_BMC_RXD_0")
		)
	)
	(footprint ""
		(layer "F.Cu")
		(at 41.5544 -389.0264)
		(property "Reference" "R6721"
			(at 0 0 0)
			(layer "F.SilkS")
			(hide yes)
			(effects
				(font
					(size 1.27 1.27)
				)
			)
		)
		(property "Value" ""
			(at 0 0 0)
			(layer "F.Fab")
			(effects
				(font
					(size 1.27 1.27)
				)
			)
		)
		(duplicate_pad_numbers_are_jumpers no)
		(fp_line
			(start -0.32512 -0.175006)
			(end 0.32512 -0.175006)
			(stroke
				(width 0.1)
				(type default)
			)
			(layer "F.Fab")
		)
		(fp_line
			(start -0.32512 0.175006)
			(end -0.32512 -0.175006)
			(stroke
				(width 0.1)
				(type default)
			)
			(layer "F.Fab")
		)
		(fp_line
			(start 0.32512 -0.175006)
			(end 0.32512 0.175006)
			(stroke
				(width 0.1)
				(type default)
			)
			(layer "F.Fab")
		)
		(fp_line
			(start 0.32512 0.175006)
			(end -0.32512 0.175006)
			(stroke
				(width 0.1)
				(type default)
			)
			(layer "F.Fab")
		)
		(pad "1" smd rect
			(at -0.2667 0)
			(size 0.3048 0.381)
			(layers "F.Cu" "F.Mask" "F.Paste")
			(net "RST_RT_CPU1_P0_RESET_R_N")
		)
		(pad "2" smd rect
			(at 0.2667 0 180)
			(size 0.3048 0.381)
			(layers "F.Cu" "F.Mask" "F.Paste")
			(net "GND")
		)
	)
	(footprint ""
		(layer "F.Cu")
		(at 255.780794 -140.118846 -90)
		(property "Reference" "R128"
			(at 0 0 270)
			(layer "F.SilkS")
			(hide yes)
			(effects
				(font
					(size 1.27 1.27)
				)
			)
		)
		(property "Value" ""
			(at 0 0 270)
			(layer "F.Fab")
			(effects
				(font
					(size 1.27 1.27)
				)
			)
		)
		(duplicate_pad_numbers_are_jumpers no)
		(fp_line
			(start -0.7874 0.4064)
			(end -0.7874 -0.4064)
			(stroke
				(width 0.1524)
				(type default)
			)
			(layer "F.SilkS")
		)
		(fp_line
			(start 0.7874 0.4064)
			(end -0.7874 0.4064)
			(stroke
				(width 0.1524)
				(type default)
			)
			(layer "F.SilkS")
		)
		(fp_line
			(start -0.7874 -0.4064)
			(end 0.7874 -0.4064)
			(stroke
				(width 0.1524)
				(type default)
			)
			(layer "F.SilkS")
		)
		(fp_line
			(start 0.7874 -0.4064)
			(end 0.7874 0.4064)
			(stroke
				(width 0.1524)
				(type default)
			)
			(layer "F.SilkS")
		)
		(fp_line
			(start -0.67945 0.3048)
			(end -0.67945 -0.305054)
			(stroke
				(width 0.1)
				(type default)
			)
			(layer "F.Fab")
		)
		(fp_line
			(start -0.12065 0.3048)
			(end -0.67945 0.3048)
			(stroke
				(width 0.1)
				(type default)
			)
			(layer "F.Fab")
		)
		(fp_line
			(start 0.120396 0.3048)
			(end 0.120396 0.2794)
			(stroke
				(width 0.1)
				(type default)
			)
			(layer "F.Fab")
		)
		(fp_line
			(start 0.67945 0.3048)
			(end 0.120396 0.3048)
			(stroke
				(width 0.1)
				(type default)
			)
			(layer "F.Fab")
		)
		(fp_line
			(start -0.12065 0.2794)
			(end -0.12065 0.3048)
			(stroke
				(width 0.1)
				(type default)
			)
			(layer "F.Fab")
		)
		(fp_line
			(start 0.120396 0.2794)
			(end -0.12065 0.2794)
			(stroke
				(width 0.1)
				(type default)
			)
			(layer "F.Fab")
		)
		(fp_line
			(start -0.12065 -0.2794)
			(end 0.12065 -0.2794)
			(stroke
				(width 0.1)
				(type default)
			)
			(layer "F.Fab")
		)
		(fp_line
			(start 0.12065 -0.2794)
			(end 0.12065 -0.3048)
			(stroke
				(width 0.1)
				(type default)
			)
			(layer "F.Fab")
		)
		(fp_line
			(start 0.12065 -0.3048)
			(end 0.67945 -0.3048)
			(stroke
				(width 0.1)
				(type default)
			)
			(layer "F.Fab")
		)
		(fp_line
			(start 0.67945 -0.3048)
			(end 0.67945 0.3048)
			(stroke
				(width 0.1)
				(type default)
			)
			(layer "F.Fab")
		)
		(fp_line
			(start -0.67945 -0.305054)
			(end -0.12065 -0.305054)
			(stroke
				(width 0.1)
				(type default)
			)
			(layer "F.Fab")
		)
		(fp_line
			(start -0.12065 -0.305054)
			(end -0.12065 -0.2794)
			(stroke
				(width 0.1)
				(type default)
			)
			(layer "F.Fab")
		)
		(pad "1" smd circle
			(at -0.40005 0 270)
			(size 0 0)
			(layers "F.Cu" "F.Mask" "F.Paste")
			(net "P3V3_AUX")
		)
		(pad "2" smd circle
			(at 0.40005 0 270)
			(size 0 0)
			(layers "F.Cu" "F.Mask" "F.Paste")
			(net "SPI_CPU0_LVC3_SCM_D2")
		)
	)
	(footprint ""
		(layer "F.Cu")
		(at 163.715446 -419.0492 90)
		(property "Reference" "R693"
			(at 0 0 90)
			(layer "F.SilkS")
			(hide yes)
			(effects
				(font
					(size 1.27 1.27)
				)
			)
		)
		(property "Value" ""
			(at 0 0 90)
			(layer "F.Fab")
			(effects
				(font
					(size 1.27 1.27)
				)
			)
		)
		(duplicate_pad_numbers_are_jumpers no)
		(fp_line
			(start 0.32512 -0.175006)
			(end 0.32512 0.175006)
			(stroke
				(width 0.1)
				(type default)
			)
			(layer "F.Fab")
		)
		(fp_line
			(start -0.32512 -0.175006)
			(end 0.32512 -0.175006)
			(stroke
				(width 0.1)
				(type default)
			)
			(layer "F.Fab")
		)
		(fp_line
			(start 0.32512 0.175006)
			(end -0.32512 0.175006)
			(stroke
				(width 0.1)
				(type default)
			)
			(layer "F.Fab")
		)
		(fp_line
			(start -0.32512 0.175006)
			(end -0.32512 -0.175006)
			(stroke
				(width 0.1)
				(type default)
			)
			(layer "F.Fab")
		)
		(pad "1" smd rect
			(at -0.2667 0 90)
			(size 0.3048 0.381)
			(layers "F.Cu" "F.Mask" "F.Paste")
			(net "SMB_RT_CPU1_P2_ROM_R_SCL")
		)
		(pad "2" smd rect
			(at 0.2667 0 270)
			(size 0.3048 0.381)
			(layers "F.Cu" "F.Mask" "F.Paste")
			(net "SMB_RT_CPU1_P2_ROM_SCL")
		)
	)
	(footprint ""
		(layer "F.Cu")
		(at 438.256172 -32.173418 90)
		(property "Reference" "PR3837"
			(at 0 0 90)
			(layer "F.SilkS")
			(hide yes)
			(effects
				(font
					(size 1.27 1.27)
				)
			)
		)
		(property "Value" ""
			(at 0 0 90)
			(layer "F.Fab")
			(effects
				(font
					(size 1.27 1.27)
				)
			)
		)
		(duplicate_pad_numbers_are_jumpers no)
		(fp_line
			(start 0.7874 -0.4064)
			(end 0.7874 0.4064)
			(stroke
				(width 0.1524)
				(type default)
			)
			(layer "F.SilkS")
		)
		(fp_line
			(start -0.7874 -0.4064)
			(end 0.7874 -0.4064)
			(stroke
				(width 0.1524)
				(type default)
			)
			(layer "F.SilkS")
		)
		(fp_line
			(start 0.7874 0.4064)
			(end -0.7874 0.4064)
			(stroke
				(width 0.1524)
				(type default)
			)
			(layer "F.SilkS")
		)
		(fp_line
			(start -0.7874 0.4064)
			(end -0.7874 -0.4064)
			(stroke
				(width 0.1524)
				(type default)
			)
			(layer "F.SilkS")
		)
		(fp_line
			(start -0.12065 -0.305054)
			(end -0.12065 -0.2794)
			(stroke
				(width 0.1)
				(type default)
			)
			(layer "F.Fab")
		)
		(fp_line
			(start -0.67945 -0.305054)
			(end -0.12065 -0.305054)
			(stroke
				(width 0.1)
				(type default)
			)
			(layer "F.Fab")
		)
		(fp_line
			(start 0.67945 -0.3048)
			(end 0.67945 0.3048)
			(stroke
				(width 0.1)
				(type default)
			)
			(layer "F.Fab")
		)
		(fp_line
			(start 0.12065 -0.3048)
			(end 0.67945 -0.3048)
			(stroke
				(width 0.1)
				(type default)
			)
			(layer "F.Fab")
		)
		(fp_line
			(start 0.12065 -0.2794)
			(end 0.12065 -0.3048)
			(stroke
				(width 0.1)
				(type default)
			)
			(layer "F.Fab")
		)
		(fp_line
			(start -0.12065 -0.2794)
			(end 0.12065 -0.2794)
			(stroke
				(width 0.1)
				(type default)
			)
			(layer "F.Fab")
		)
		(fp_line
			(start 0.120396 0.2794)
			(end -0.12065 0.2794)
			(stroke
				(width 0.1)
				(type default)
			)
			(layer "F.Fab")
		)
		(fp_line
			(start -0.12065 0.2794)
			(end -0.12065 0.3048)
			(stroke
				(width 0.1)
				(type default)
			)
			(layer "F.Fab")
		)
		(fp_line
			(start 0.67945 0.3048)
			(end 0.120396 0.3048)
			(stroke
				(width 0.1)
				(type default)
			)
			(layer "F.Fab")
		)
		(fp_line
			(start 0.120396 0.3048)
			(end 0.120396 0.2794)
			(stroke
				(width 0.1)
				(type default)
			)
			(layer "F.Fab")
		)
		(fp_line
			(start -0.12065 0.3048)
			(end -0.67945 0.3048)
			(stroke
				(width 0.1)
				(type default)
			)
			(layer "F.Fab")
		)
		(fp_line
			(start -0.67945 0.3048)
			(end -0.67945 -0.305054)
			(stroke
				(width 0.1)
				(type default)
			)
			(layer "F.Fab")
		)
		(pad "1" smd circle
			(at -0.40005 0 90)
			(size 0 0)
			(layers "F.Cu" "F.Mask" "F.Paste")
			(net "P12V_OCP_IMON_1")
		)
		(pad "2" smd circle
			(at 0.40005 0 90)
			(size 0 0)
			(layers "F.Cu" "F.Mask" "F.Paste")
			(net "GND")
		)
	)
	(footprint ""
		(layer "F.Cu")
		(at 379.292104 -178.0921 90)
		(property "Reference" "PC560"
			(at 0 0 90)
			(layer "F.SilkS")
			(hide yes)
			(effects
				(font
					(size 1.27 1.27)
				)
			)
		)
		(property "Value" ""
			(at 0 0 90)
			(layer "F.Fab")
			(effects
				(font
					(size 1.27 1.27)
				)
			)
		)
		(duplicate_pad_numbers_are_jumpers no)
		(fp_line
			(start 0.7874 -0.4064)
			(end 0.7874 0.4064)
			(stroke
				(width 0.1524)
				(type default)
			)
			(layer "F.SilkS")
		)
		(fp_line
			(start -0.7874 -0.4064)
			(end 0.7874 -0.4064)
			(stroke
				(width 0.1524)
				(type default)
			)
			(layer "F.SilkS")
		)
		(fp_line
			(start 0.7874 0.4064)
			(end -0.7874 0.4064)
			(stroke
				(width 0.1524)
				(type default)
			)
			(layer "F.SilkS")
		)
		(fp_line
			(start -0.7874 0.4064)
			(end -0.7874 -0.4064)
			(stroke
				(width 0.1524)
				(type default)
			)
			(layer "F.SilkS")
		)
		(fp_line
			(start -0.12065 -0.305054)
			(end -0.12065 -0.2794)
			(stroke
				(width 0.1)
				(type default)
			)
			(layer "F.Fab")
		)
		(fp_line
			(start -0.67945 -0.305054)
			(end -0.12065 -0.305054)
			(stroke
				(width 0.1)
				(type default)
			)
			(layer "F.Fab")
		)
		(fp_line
			(start 0.67945 -0.3048)
			(end 0.67945 0.3048)
			(stroke
				(width 0.1)
				(type default)
			)
			(layer "F.Fab")
		)
		(fp_line
			(start 0.12065 -0.3048)
			(end 0.67945 -0.3048)
			(stroke
				(width 0.1)
				(type default)
			)
			(layer "F.Fab")
		)
		(fp_line
			(start 0.12065 -0.2794)
			(end 0.12065 -0.3048)
			(stroke
				(width 0.1)
				(type default)
			)
			(layer "F.Fab")
		)
		(fp_line
			(start -0.12065 -0.2794)
			(end 0.12065 -0.2794)
			(stroke
				(width 0.1)
				(type default)
			)
			(layer "F.Fab")
		)
		(fp_line
			(start 0.120396 0.2794)
			(end -0.12065 0.2794)
			(stroke
				(width 0.1)
				(type default)
			)
			(layer "F.Fab")
		)
		(fp_line
			(start -0.12065 0.2794)
			(end -0.12065 0.3048)
			(stroke
				(width 0.1)
				(type default)
			)
			(layer "F.Fab")
		)
		(fp_line
			(start 0.67945 0.3048)
			(end 0.120396 0.3048)
			(stroke
				(width 0.1)
				(type default)
			)
			(layer "F.Fab")
		)
		(fp_line
			(start 0.120396 0.3048)
			(end 0.120396 0.2794)
			(stroke
				(width 0.1)
				(type default)
			)
			(layer "F.Fab")
		)
		(fp_line
			(start -0.12065 0.3048)
			(end -0.67945 0.3048)
			(stroke
				(width 0.1)
				(type default)
			)
			(layer "F.Fab")
		)
		(fp_line
			(start -0.67945 0.3048)
			(end -0.67945 -0.305054)
			(stroke
				(width 0.1)
				(type default)
			)
			(layer "F.Fab")
		)
		(pad "1" smd circle
			(at -0.40005 0 90)
			(size 0 0)
			(layers "F.Cu" "F.Mask" "F.Paste")
			(net "SW_PVDDCR_CPU0_P0_BOOT3_RC")
		)
		(pad "2" smd circle
			(at 0.40005 0 90)
			(size 0 0)
			(layers "F.Cu" "F.Mask" "F.Paste")
			(net "SW_PVDDCR_CPU0_P0_PH3")
		)
	)
	(footprint ""
		(layer "F.Cu")
		(at 454.611994 -46.264576 -90)
		(property "Reference" "PR833"
			(at 0 0 270)
			(layer "F.SilkS")
			(hide yes)
			(effects
				(font
					(size 1.27 1.27)
				)
			)
		)
		(property "Value" ""
			(at 0 0 270)
			(layer "F.Fab")
			(effects
				(font
					(size 1.27 1.27)
				)
			)
		)
		(duplicate_pad_numbers_are_jumpers no)
		(fp_line
			(start -0.7874 0.4064)
			(end -0.7874 -0.4064)
			(stroke
				(width 0.1524)
				(type default)
			)
			(layer "F.SilkS")
		)
		(fp_line
			(start 0.7874 0.4064)
			(end -0.7874 0.4064)
			(stroke
				(width 0.1524)
				(type default)
			)
			(layer "F.SilkS")
		)
		(fp_line
			(start -0.7874 -0.4064)
			(end 0.7874 -0.4064)
			(stroke
				(width 0.1524)
				(type default)
			)
			(layer "F.SilkS")
		)
		(fp_line
			(start 0.7874 -0.4064)
			(end 0.7874 0.4064)
			(stroke
				(width 0.1524)
				(type default)
			)
			(layer "F.SilkS")
		)
		(fp_line
			(start -0.67945 0.3048)
			(end -0.67945 -0.305054)
			(stroke
				(width 0.1)
				(type default)
			)
			(layer "F.Fab")
		)
		(fp_line
			(start -0.12065 0.3048)
			(end -0.67945 0.3048)
			(stroke
				(width 0.1)
				(type default)
			)
			(layer "F.Fab")
		)
		(fp_line
			(start 0.120396 0.3048)
			(end 0.120396 0.2794)
			(stroke
				(width 0.1)
				(type default)
			)
			(layer "F.Fab")
		)
		(fp_line
			(start 0.67945 0.3048)
			(end 0.120396 0.3048)
			(stroke
				(width 0.1)
				(type default)
			)
			(layer "F.Fab")
		)
		(fp_line
			(start -0.12065 0.2794)
			(end -0.12065 0.3048)
			(stroke
				(width 0.1)
				(type default)
			)
			(layer "F.Fab")
		)
		(fp_line
			(start 0.120396 0.2794)
			(end -0.12065 0.2794)
			(stroke
				(width 0.1)
				(type default)
			)
			(layer "F.Fab")
		)
		(fp_line
			(start -0.12065 -0.2794)
			(end 0.12065 -0.2794)
			(stroke
				(width 0.1)
				(type default)
			)
			(layer "F.Fab")
		)
		(fp_line
			(start 0.12065 -0.2794)
			(end 0.12065 -0.3048)
			(stroke
				(width 0.1)
				(type default)
			)
			(layer "F.Fab")
		)
		(fp_line
			(start 0.12065 -0.3048)
			(end 0.67945 -0.3048)
			(stroke
				(width 0.1)
				(type default)
			)
			(layer "F.Fab")
		)
		(fp_line
			(start 0.67945 -0.3048)
			(end 0.67945 0.3048)
			(stroke
				(width 0.1)
				(type default)
			)
			(layer "F.Fab")
		)
		(fp_line
			(start -0.67945 -0.305054)
			(end -0.12065 -0.305054)
			(stroke
				(width 0.1)
				(type default)
			)
			(layer "F.Fab")
		)
		(fp_line
			(start -0.12065 -0.305054)
			(end -0.12065 -0.2794)
			(stroke
				(width 0.1)
				(type default)
			)
			(layer "F.Fab")
		)
		(pad "1" smd circle
			(at -0.40005 0 270)
			(size 0 0)
			(layers "F.Cu" "F.Mask" "F.Paste")
			(net "P3V3_AUX_SS")
		)
		(pad "2" smd circle
			(at 0.40005 0 270)
			(size 0 0)
			(layers "F.Cu" "F.Mask" "F.Paste")
			(net "GND")
		)
	)
	(footprint ""
		(layer "F.Cu")
		(at 459.437486 -93.627448)
		(property "Reference" "U224"
			(at -1.651 -1.793748 0)
			(unlocked yes)
			(layer "F.SilkS")
			(effects
				(font
					(size 0.7874 0.5842)
					(thickness 0.1524)
				)
				(justify left)
			)
		)
		(property "Value" ""
			(at 0 0 0)
			(layer "F.Fab")
			(effects
				(font
					(size 1.27 1.27)
				)
			)
		)
		(duplicate_pad_numbers_are_jumpers no)
		(fp_line
			(start -1.400048 1.100074)
			(end -1.400048 -1.100074)
			(stroke
				(width 0.1524)
				(type default)
			)
			(layer "F.SilkS")
		)
		(fp_line
			(start 1.400048 -1.100074)
			(end -1.400048 -1.100074)
			(stroke
				(width 0.1524)
				(type default)
			)
			(layer "F.SilkS")
		)
		(fp_line
			(start 1.400048 -1.100074)
			(end 1.400048 1.100074)
			(stroke
				(width 0.1524)
				(type default)
			)
			(layer "F.SilkS")
		)
		(fp_line
			(start 1.400048 1.100074)
			(end -1.400048 1.100074)
			(stroke
				(width 0.1524)
				(type default)
			)
			(layer "F.SilkS")
		)
		(fp_poly
			(pts
				(xy -2.606548 -0.141986) (xy -2.606548 -1.157986) (xy -1.590548 -0.649986)
			)
			(stroke
				(width 0)
				(type default)
			)
			(fill yes)
			(layer "F.SilkS")
		)
		(fp_line
			(start -0.674878 -1.100074)
			(end 0.674878 -1.100074)
			(stroke
				(width 0.1)
				(type default)
			)
			(layer "F.Fab")
		)
		(fp_line
			(start -0.674878 1.100074)
			(end -0.674878 -1.100074)
			(stroke
				(width 0.1)
				(type default)
			)
			(layer "F.Fab")
		)
		(fp_line
			(start 0.674878 -1.100074)
			(end 0.674878 1.100074)
			(stroke
				(width 0.1)
				(type default)
			)
			(layer "F.Fab")
		)
		(fp_line
			(start 0.674878 1.100074)
			(end -0.674878 1.100074)
			(stroke
				(width 0.1)
				(type default)
			)
			(layer "F.Fab")
		)
		(fp_poly
			(pts
				(xy -1.590548 -0.649986) (xy -2.606548 -1.157986) (xy -2.606548 -0.141986)
			)
			(stroke
				(width 0)
				(type default)
			)
			(fill yes)
			(layer "F.Fab")
		)
		(pad "1" smd rect
			(at -0.94996 -0.649986 270)
			(size 0.4318 0.6096)
			(layers "F.Cu" "F.Mask" "F.Paste")
			(net "OCP_SFF_AUX_PWR_EN_R2")
		)
		(pad "2" smd rect
			(at -0.94996 0 270)
			(size 0.4318 0.6096)
			(layers "F.Cu" "F.Mask" "F.Paste")
			(net "RST_SMB_SWITCH_N")
		)
		(pad "3" smd rect
			(at -0.94996 0.649986 270)
			(size 0.4318 0.6096)
			(layers "F.Cu" "F.Mask" "F.Paste")
			(net "GND")
		)
		(pad "4" smd rect
			(at 0.94996 0.649986 270)
			(size 0.4318 0.6096)
			(layers "F.Cu" "F.Mask" "F.Paste")
			(net "RST_HP_OCP_SFF_R_N")
		)
		(pad "5" smd rect
			(at 0.94996 -0.649986 270)
			(size 0.4318 0.6096)
			(layers "F.Cu" "F.Mask" "F.Paste")
			(net "P3V3_AUX")
		)
	)
	(footprint ""
		(layer "F.Cu")
		(at 61.709554 -375.49963 -90)
		(property "Reference" "C817"
			(at 0 0 270)
			(layer "F.SilkS")
			(hide yes)
			(effects
				(font
					(size 1.27 1.27)
				)
			)
		)
		(property "Value" ""
			(at 0 0 270)
			(layer "F.Fab")
			(effects
				(font
					(size 1.27 1.27)
				)
			)
		)
		(duplicate_pad_numbers_are_jumpers no)
		(fp_line
			(start -0.299974 0.150114)
			(end -0.299974 -0.150114)
			(stroke
				(width 0.1)
				(type default)
			)
			(layer "F.Fab")
		)
		(fp_line
			(start 0.299974 0.150114)
			(end -0.299974 0.150114)
			(stroke
				(width 0.1)
				(type default)
			)
			(layer "F.Fab")
		)
		(fp_line
			(start -0.299974 -0.150114)
			(end 0.299974 -0.150114)
			(stroke
				(width 0.1)
				(type default)
			)
			(layer "F.Fab")
		)
		(fp_line
			(start 0.299974 -0.150114)
			(end 0.299974 0.150114)
			(stroke
				(width 0.1)
				(type default)
			)
			(layer "F.Fab")
		)
		(pad "1" smd rect
			(at -0.2667 0 270)
			(size 0.3048 0.381)
			(layers "F.Cu" "F.Mask" "F.Paste")
			(net "P5E_CPU1_P0_TX_C_DP<10>")
		)
		(pad "2" smd rect
			(at 0.2667 0 270)
			(size 0.3048 0.381)
			(layers "F.Cu" "F.Mask" "F.Paste")
			(net "P5E_CPU1_P0_TX_DP<10>")
		)
	)
	(footprint ""
		(layer "F.Cu")
		(at 189.103 -133.568948 90)
		(property "Reference" "R856"
			(at 0 0 90)
			(layer "F.SilkS")
			(hide yes)
			(effects
				(font
					(size 1.27 1.27)
				)
			)
		)
		(property "Value" ""
			(at 0 0 90)
			(layer "F.Fab")
			(effects
				(font
					(size 1.27 1.27)
				)
			)
		)
		(duplicate_pad_numbers_are_jumpers no)
		(fp_line
			(start 0.7874 -0.4064)
			(end 0.7874 0.4064)
			(stroke
				(width 0.1524)
				(type default)
			)
			(layer "F.SilkS")
		)
		(fp_line
			(start -0.7874 -0.4064)
			(end 0.7874 -0.4064)
			(stroke
				(width 0.1524)
				(type default)
			)
			(layer "F.SilkS")
		)
		(fp_line
			(start 0.7874 0.4064)
			(end -0.7874 0.4064)
			(stroke
				(width 0.1524)
				(type default)
			)
			(layer "F.SilkS")
		)
		(fp_line
			(start -0.7874 0.4064)
			(end -0.7874 -0.4064)
			(stroke
				(width 0.1524)
				(type default)
			)
			(layer "F.SilkS")
		)
		(fp_line
			(start -0.12065 -0.305054)
			(end -0.12065 -0.2794)
			(stroke
				(width 0.1)
				(type default)
			)
			(layer "F.Fab")
		)
		(fp_line
			(start -0.67945 -0.305054)
			(end -0.12065 -0.305054)
			(stroke
				(width 0.1)
				(type default)
			)
			(layer "F.Fab")
		)
		(fp_line
			(start 0.67945 -0.3048)
			(end 0.67945 0.3048)
			(stroke
				(width 0.1)
				(type default)
			)
			(layer "F.Fab")
		)
		(fp_line
			(start 0.12065 -0.3048)
			(end 0.67945 -0.3048)
			(stroke
				(width 0.1)
				(type default)
			)
			(layer "F.Fab")
		)
		(fp_line
			(start 0.12065 -0.2794)
			(end 0.12065 -0.3048)
			(stroke
				(width 0.1)
				(type default)
			)
			(layer "F.Fab")
		)
		(fp_line
			(start -0.12065 -0.2794)
			(end 0.12065 -0.2794)
			(stroke
				(width 0.1)
				(type default)
			)
			(layer "F.Fab")
		)
		(fp_line
			(start 0.120396 0.2794)
			(end -0.12065 0.2794)
			(stroke
				(width 0.1)
				(type default)
			)
			(layer "F.Fab")
		)
		(fp_line
			(start -0.12065 0.2794)
			(end -0.12065 0.3048)
			(stroke
				(width 0.1)
				(type default)
			)
			(layer "F.Fab")
		)
		(fp_line
			(start 0.67945 0.3048)
			(end 0.120396 0.3048)
			(stroke
				(width 0.1)
				(type default)
			)
			(layer "F.Fab")
		)
		(fp_line
			(start 0.120396 0.3048)
			(end 0.120396 0.2794)
			(stroke
				(width 0.1)
				(type default)
			)
			(layer "F.Fab")
		)
		(fp_line
			(start -0.12065 0.3048)
			(end -0.67945 0.3048)
			(stroke
				(width 0.1)
				(type default)
			)
			(layer "F.Fab")
		)
		(fp_line
			(start -0.67945 0.3048)
			(end -0.67945 -0.305054)
			(stroke
				(width 0.1)
				(type default)
			)
			(layer "F.Fab")
		)
		(pad "1" smd circle
			(at -0.40005 0 90)
			(size 0 0)
			(layers "F.Cu" "F.Mask" "F.Paste")
			(net "FM_HDT_HDR_RESET_N")
		)
		(pad "2" smd circle
			(at 0.40005 0 90)
			(size 0 0)
			(layers "F.Cu" "F.Mask" "F.Paste")
			(net "HDT_HDR_RESET_N")
		)
	)
	(footprint ""
		(layer "F.Cu")
		(at 168.39057 -123.683014)
		(property "Reference" "R6138"
			(at 0 0 0)
			(layer "F.SilkS")
			(hide yes)
			(effects
				(font
					(size 1.27 1.27)
				)
			)
		)
		(property "Value" ""
			(at 0 0 0)
			(layer "F.Fab")
			(effects
				(font
					(size 1.27 1.27)
				)
			)
		)
		(duplicate_pad_numbers_are_jumpers no)
		(fp_line
			(start -0.7874 -0.4064)
			(end 0.7874 -0.4064)
			(stroke
				(width 0.1524)
				(type default)
			)
			(layer "F.SilkS")
		)
		(fp_line
			(start -0.7874 0.4064)
			(end -0.7874 -0.4064)
			(stroke
				(width 0.1524)
				(type default)
			)
			(layer "F.SilkS")
		)
		(fp_line
			(start 0.7874 -0.4064)
			(end 0.7874 0.4064)
			(stroke
				(width 0.1524)
				(type default)
			)
			(layer "F.SilkS")
		)
		(fp_line
			(start 0.7874 0.4064)
			(end -0.7874 0.4064)
			(stroke
				(width 0.1524)
				(type default)
			)
			(layer "F.SilkS")
		)
		(fp_line
			(start -0.67945 -0.305054)
			(end -0.12065 -0.305054)
			(stroke
				(width 0.1)
				(type default)
			)
			(layer "F.Fab")
		)
		(fp_line
			(start -0.67945 0.3048)
			(end -0.67945 -0.305054)
			(stroke
				(width 0.1)
				(type default)
			)
			(layer "F.Fab")
		)
		(fp_line
			(start -0.12065 -0.305054)
			(end -0.12065 -0.2794)
			(stroke
				(width 0.1)
				(type default)
			)
			(layer "F.Fab")
		)
		(fp_line
			(start -0.12065 -0.2794)
			(end 0.12065 -0.2794)
			(stroke
				(width 0.1)
				(type default)
			)
			(layer "F.Fab")
		)
		(fp_line
			(start -0.12065 0.2794)
			(end -0.12065 0.3048)
			(stroke
				(width 0.1)
				(type default)
			)
			(layer "F.Fab")
		)
		(fp_line
			(start -0.12065 0.3048)
			(end -0.67945 0.3048)
			(stroke
				(width 0.1)
				(type default)
			)
			(layer "F.Fab")
		)
		(fp_line
			(start 0.120396 0.2794)
			(end -0.12065 0.2794)
			(stroke
				(width 0.1)
				(type default)
			)
			(layer "F.Fab")
		)
		(fp_line
			(start 0.120396 0.3048)
			(end 0.120396 0.2794)
			(stroke
				(width 0.1)
				(type default)
			)
			(layer "F.Fab")
		)
		(fp_line
			(start 0.12065 -0.3048)
			(end 0.67945 -0.3048)
			(stroke
				(width 0.1)
				(type default)
			)
			(layer "F.Fab")
		)
		(fp_line
			(start 0.12065 -0.2794)
			(end 0.12065 -0.3048)
			(stroke
				(width 0.1)
				(type default)
			)
			(layer "F.Fab")
		)
		(fp_line
			(start 0.67945 -0.3048)
			(end 0.67945 0.3048)
			(stroke
				(width 0.1)
				(type default)
			)
			(layer "F.Fab")
		)
		(fp_line
			(start 0.67945 0.3048)
			(end 0.120396 0.3048)
			(stroke
				(width 0.1)
				(type default)
			)
			(layer "F.Fab")
		)
		(pad "1" smd circle
			(at -0.40005 0)
			(size 0 0)
			(layers "F.Cu" "F.Mask" "F.Paste")
			(net "P3V3_AUX")
		)
		(pad "2" smd circle
			(at 0.40005 0)
			(size 0 0)
			(layers "F.Cu" "F.Mask" "F.Paste")
			(net "FM_BOARD_BMC_SKU_ID2")
		)
	)
	(footprint ""
		(layer "F.Cu")
		(at 9.74471 -71.860664)
		(property "Reference" "R3134"
			(at 0 0 0)
			(layer "F.SilkS")
			(hide yes)
			(effects
				(font
					(size 1.27 1.27)
				)
			)
		)
		(property "Value" ""
			(at 0 0 0)
			(layer "F.Fab")
			(effects
				(font
					(size 1.27 1.27)
				)
			)
		)
		(duplicate_pad_numbers_are_jumpers no)
		(fp_line
			(start -0.7874 -0.4064)
			(end 0.7874 -0.4064)
			(stroke
				(width 0.1524)
				(type default)
			)
			(layer "F.SilkS")
		)
		(fp_line
			(start -0.7874 0.4064)
			(end -0.7874 -0.4064)
			(stroke
				(width 0.1524)
				(type default)
			)
			(layer "F.SilkS")
		)
		(fp_line
			(start 0.7874 -0.4064)
			(end 0.7874 0.4064)
			(stroke
				(width 0.1524)
				(type default)
			)
			(layer "F.SilkS")
		)
		(fp_line
			(start 0.7874 0.4064)
			(end -0.7874 0.4064)
			(stroke
				(width 0.1524)
				(type default)
			)
			(layer "F.SilkS")
		)
		(fp_line
			(start -0.67945 -0.305054)
			(end -0.12065 -0.305054)
			(stroke
				(width 0.1)
				(type default)
			)
			(layer "F.Fab")
		)
		(fp_line
			(start -0.67945 0.3048)
			(end -0.67945 -0.305054)
			(stroke
				(width 0.1)
				(type default)
			)
			(layer "F.Fab")
		)
		(fp_line
			(start -0.12065 -0.305054)
			(end -0.12065 -0.2794)
			(stroke
				(width 0.1)
				(type default)
			)
			(layer "F.Fab")
		)
		(fp_line
			(start -0.12065 -0.2794)
			(end 0.12065 -0.2794)
			(stroke
				(width 0.1)
				(type default)
			)
			(layer "F.Fab")
		)
		(fp_line
			(start -0.12065 0.2794)
			(end -0.12065 0.3048)
			(stroke
				(width 0.1)
				(type default)
			)
			(layer "F.Fab")
		)
		(fp_line
			(start -0.12065 0.3048)
			(end -0.67945 0.3048)
			(stroke
				(width 0.1)
				(type default)
			)
			(layer "F.Fab")
		)
		(fp_line
			(start 0.120396 0.2794)
			(end -0.12065 0.2794)
			(stroke
				(width 0.1)
				(type default)
			)
			(layer "F.Fab")
		)
		(fp_line
			(start 0.120396 0.3048)
			(end 0.120396 0.2794)
			(stroke
				(width 0.1)
				(type default)
			)
			(layer "F.Fab")
		)
		(fp_line
			(start 0.12065 -0.3048)
			(end 0.67945 -0.3048)
			(stroke
				(width 0.1)
				(type default)
			)
			(layer "F.Fab")
		)
		(fp_line
			(start 0.12065 -0.2794)
			(end 0.12065 -0.3048)
			(stroke
				(width 0.1)
				(type default)
			)
			(layer "F.Fab")
		)
		(fp_line
			(start 0.67945 -0.3048)
			(end 0.67945 0.3048)
			(stroke
				(width 0.1)
				(type default)
			)
			(layer "F.Fab")
		)
		(fp_line
			(start 0.67945 0.3048)
			(end 0.120396 0.3048)
			(stroke
				(width 0.1)
				(type default)
			)
			(layer "F.Fab")
		)
		(pad "1" smd circle
			(at -0.40005 0)
			(size 0 0)
			(layers "F.Cu" "F.Mask" "F.Paste")
			(net "P3V3_AUX")
		)
		(pad "2" smd circle
			(at 0.40005 0)
			(size 0 0)
			(layers "F.Cu" "F.Mask" "F.Paste")
			(net "OCP_V3_2_PRSNT2_R_N")
		)
	)
	(footprint ""
		(layer "F.Cu")
		(at 33.187132 -343.716864 180)
		(property "Reference" "PC177"
			(at 0 0 180)
			(layer "F.SilkS")
			(hide yes)
			(effects
				(font
					(size 1.27 1.27)
				)
			)
		)
		(property "Value" ""
			(at 0 0 180)
			(layer "F.Fab")
			(effects
				(font
					(size 1.27 1.27)
				)
			)
		)
		(duplicate_pad_numbers_are_jumpers no)
		(fp_line
			(start 0.7874 0.4064)
			(end -0.7874 0.4064)
			(stroke
				(width 0.1524)
				(type default)
			)
			(layer "F.SilkS")
		)
		(fp_line
			(start 0.7874 -0.4064)
			(end 0.7874 0.4064)
			(stroke
				(width 0.1524)
				(type default)
			)
			(layer "F.SilkS")
		)
		(fp_line
			(start -0.7874 0.4064)
			(end -0.7874 -0.4064)
			(stroke
				(width 0.1524)
				(type default)
			)
			(layer "F.SilkS")
		)
		(fp_line
			(start -0.7874 -0.4064)
			(end 0.7874 -0.4064)
			(stroke
				(width 0.1524)
				(type default)
			)
			(layer "F.SilkS")
		)
		(fp_line
			(start 0.67945 0.3048)
			(end 0.120396 0.3048)
			(stroke
				(width 0.1)
				(type default)
			)
			(layer "F.Fab")
		)
		(fp_line
			(start 0.67945 -0.3048)
			(end 0.67945 0.3048)
			(stroke
				(width 0.1)
				(type default)
			)
			(layer "F.Fab")
		)
		(fp_line
			(start 0.12065 -0.2794)
			(end 0.12065 -0.3048)
			(stroke
				(width 0.1)
				(type default)
			)
			(layer "F.Fab")
		)
		(fp_line
			(start 0.12065 -0.3048)
			(end 0.67945 -0.3048)
			(stroke
				(width 0.1)
				(type default)
			)
			(layer "F.Fab")
		)
		(fp_line
			(start 0.120396 0.3048)
			(end 0.120396 0.2794)
			(stroke
				(width 0.1)
				(type default)
			)
			(layer "F.Fab")
		)
		(fp_line
			(start 0.120396 0.2794)
			(end -0.12065 0.2794)
			(stroke
				(width 0.1)
				(type default)
			)
			(layer "F.Fab")
		)
		(fp_line
			(start -0.12065 0.3048)
			(end -0.67945 0.3048)
			(stroke
				(width 0.1)
				(type default)
			)
			(layer "F.Fab")
		)
		(fp_line
			(start -0.12065 0.2794)
			(end -0.12065 0.3048)
			(stroke
				(width 0.1)
				(type default)
			)
			(layer "F.Fab")
		)
		(fp_line
			(start -0.12065 -0.2794)
			(end 0.12065 -0.2794)
			(stroke
				(width 0.1)
				(type default)
			)
			(layer "F.Fab")
		)
		(fp_line
			(start -0.12065 -0.305054)
			(end -0.12065 -0.2794)
			(stroke
				(width 0.1)
				(type default)
			)
			(layer "F.Fab")
		)
		(fp_line
			(start -0.67945 0.3048)
			(end -0.67945 -0.305054)
			(stroke
				(width 0.1)
				(type default)
			)
			(layer "F.Fab")
		)
		(fp_line
			(start -0.67945 -0.305054)
			(end -0.12065 -0.305054)
			(stroke
				(width 0.1)
				(type default)
			)
			(layer "F.Fab")
		)
		(pad "1" smd circle
			(at -0.40005 0 180)
			(size 0 0)
			(layers "F.Cu" "F.Mask" "F.Paste")
			(net "SW_PVDDIO_P1_SW3")
		)
		(pad "2" smd circle
			(at 0.40005 0 180)
			(size 0 0)
			(layers "F.Cu" "F.Mask" "F.Paste")
			(net "SW_PVDDIO_P1_SW3_RC")
		)
	)
	(footprint ""
		(layer "F.Cu")
		(at 135.36168 -29.01442 -90)
		(property "Reference" "R6195"
			(at 0 0 270)
			(layer "F.SilkS")
			(hide yes)
			(effects
				(font
					(size 1.27 1.27)
				)
			)
		)
		(property "Value" ""
			(at 0 0 270)
			(layer "F.Fab")
			(effects
				(font
					(size 1.27 1.27)
				)
			)
		)
		(duplicate_pad_numbers_are_jumpers no)
		(fp_line
			(start -0.32512 0.175006)
			(end -0.32512 -0.175006)
			(stroke
				(width 0.1)
				(type default)
			)
			(layer "F.Fab")
		)
		(fp_line
			(start 0.32512 0.175006)
			(end -0.32512 0.175006)
			(stroke
				(width 0.1)
				(type default)
			)
			(layer "F.Fab")
		)
		(fp_line
			(start -0.32512 -0.175006)
			(end 0.32512 -0.175006)
			(stroke
				(width 0.1)
				(type default)
			)
			(layer "F.Fab")
		)
		(fp_line
			(start 0.32512 -0.175006)
			(end 0.32512 0.175006)
			(stroke
				(width 0.1)
				(type default)
			)
			(layer "F.Fab")
		)
		(pad "1" smd rect
			(at -0.2667 0 270)
			(size 0.3048 0.381)
			(layers "F.Cu" "F.Mask" "F.Paste")
			(net "USB2_CPU0_P0_HUB1_R_DN")
		)
		(pad "2" smd rect
			(at 0.2667 0 90)
			(size 0.3048 0.381)
			(layers "F.Cu" "F.Mask" "F.Paste")
			(net "USB2_HUB_EXT_DN")
		)
	)
	(footprint ""
		(layer "F.Cu")
		(at 10.339832 -160.499806)
		(property "Reference" "H88"
			(at -4.6863 -5.71119 0)
			(unlocked yes)
			(layer "F.SilkS")
			(effects
				(font
					(size 0.7874 0.5842)
					(thickness 0.1524)
				)
				(justify left)
			)
		)
		(property "Value" ""
			(at 0 0 0)
			(layer "F.Fab")
			(effects
				(font
					(size 1.27 1.27)
				)
			)
		)
		(duplicate_pad_numbers_are_jumpers no)
		(pad "1" thru_hole circle
			(at 0 0)
			(size 10.0076 10.0076)
			(drill 5.6134)
			(layers "*.Cu" "*.Mask")
			(remove_unused_layers no)
			(net "GND")
			(clearance -1.9431)
		)
	)
	(footprint ""
		(layer "F.Cu")
		(at 138.016234 -151.619712 -90)
		(property "Reference" "PR335"
			(at 0 0 270)
			(layer "F.SilkS")
			(hide yes)
			(effects
				(font
					(size 1.27 1.27)
				)
			)
		)
		(property "Value" ""
			(at 0 0 270)
			(layer "F.Fab")
			(effects
				(font
					(size 1.27 1.27)
				)
			)
		)
		(duplicate_pad_numbers_are_jumpers no)
		(fp_line
			(start -0.7874 0.4064)
			(end -0.7874 -0.4064)
			(stroke
				(width 0.1524)
				(type default)
			)
			(layer "F.SilkS")
		)
		(fp_line
			(start 0.7874 0.4064)
			(end -0.7874 0.4064)
			(stroke
				(width 0.1524)
				(type default)
			)
			(layer "F.SilkS")
		)
		(fp_line
			(start -0.7874 -0.4064)
			(end 0.7874 -0.4064)
			(stroke
				(width 0.1524)
				(type default)
			)
			(layer "F.SilkS")
		)
		(fp_line
			(start 0.7874 -0.4064)
			(end 0.7874 0.4064)
			(stroke
				(width 0.1524)
				(type default)
			)
			(layer "F.SilkS")
		)
		(fp_line
			(start -0.67945 0.3048)
			(end -0.67945 -0.305054)
			(stroke
				(width 0.1)
				(type default)
			)
			(layer "F.Fab")
		)
		(fp_line
			(start -0.12065 0.3048)
			(end -0.67945 0.3048)
			(stroke
				(width 0.1)
				(type default)
			)
			(layer "F.Fab")
		)
		(fp_line
			(start 0.120396 0.3048)
			(end 0.120396 0.2794)
			(stroke
				(width 0.1)
				(type default)
			)
			(layer "F.Fab")
		)
		(fp_line
			(start 0.67945 0.3048)
			(end 0.120396 0.3048)
			(stroke
				(width 0.1)
				(type default)
			)
			(layer "F.Fab")
		)
		(fp_line
			(start -0.12065 0.2794)
			(end -0.12065 0.3048)
			(stroke
				(width 0.1)
				(type default)
			)
			(layer "F.Fab")
		)
		(fp_line
			(start 0.120396 0.2794)
			(end -0.12065 0.2794)
			(stroke
				(width 0.1)
				(type default)
			)
			(layer "F.Fab")
		)
		(fp_line
			(start -0.12065 -0.2794)
			(end 0.12065 -0.2794)
			(stroke
				(width 0.1)
				(type default)
			)
			(layer "F.Fab")
		)
		(fp_line
			(start 0.12065 -0.2794)
			(end 0.12065 -0.3048)
			(stroke
				(width 0.1)
				(type default)
			)
			(layer "F.Fab")
		)
		(fp_line
			(start 0.12065 -0.3048)
			(end 0.67945 -0.3048)
			(stroke
				(width 0.1)
				(type default)
			)
			(layer "F.Fab")
		)
		(fp_line
			(start 0.67945 -0.3048)
			(end 0.67945 0.3048)
			(stroke
				(width 0.1)
				(type default)
			)
			(layer "F.Fab")
		)
		(fp_line
			(start -0.67945 -0.305054)
			(end -0.12065 -0.305054)
			(stroke
				(width 0.1)
				(type default)
			)
			(layer "F.Fab")
		)
		(fp_line
			(start -0.12065 -0.305054)
			(end -0.12065 -0.2794)
			(stroke
				(width 0.1)
				(type default)
			)
			(layer "F.Fab")
		)
		(pad "1" smd circle
			(at -0.40005 0 270)
			(size 0 0)
			(layers "F.Cu" "F.Mask" "F.Paste")
			(net "PVDDCR_CPU0_P1_PVCC")
		)
		(pad "2" smd circle
			(at 0.40005 0 270)
			(size 0 0)
			(layers "F.Cu" "F.Mask" "F.Paste")
			(net "P5V_AUX")
		)
	)
	(footprint ""
		(layer "F.Cu")
		(at 353.451922 -344.586306 -90)
		(property "Reference" "PC117"
			(at 0 0 270)
			(layer "F.SilkS")
			(hide yes)
			(effects
				(font
					(size 1.27 1.27)
				)
			)
		)
		(property "Value" ""
			(at 0 0 270)
			(layer "F.Fab")
			(effects
				(font
					(size 1.27 1.27)
				)
			)
		)
		(duplicate_pad_numbers_are_jumpers no)
		(fp_line
			(start -0.7874 0.4064)
			(end -0.7874 -0.4064)
			(stroke
				(width 0.1524)
				(type default)
			)
			(layer "F.SilkS")
		)
		(fp_line
			(start 0.7874 0.4064)
			(end -0.7874 0.4064)
			(stroke
				(width 0.1524)
				(type default)
			)
			(layer "F.SilkS")
		)
		(fp_line
			(start -0.7874 -0.4064)
			(end 0.7874 -0.4064)
			(stroke
				(width 0.1524)
				(type default)
			)
			(layer "F.SilkS")
		)
		(fp_line
			(start 0.7874 -0.4064)
			(end 0.7874 0.4064)
			(stroke
				(width 0.1524)
				(type default)
			)
			(layer "F.SilkS")
		)
		(fp_line
			(start -0.67945 0.3048)
			(end -0.67945 -0.305054)
			(stroke
				(width 0.1)
				(type default)
			)
			(layer "F.Fab")
		)
		(fp_line
			(start -0.12065 0.3048)
			(end -0.67945 0.3048)
			(stroke
				(width 0.1)
				(type default)
			)
			(layer "F.Fab")
		)
		(fp_line
			(start 0.120396 0.3048)
			(end 0.120396 0.2794)
			(stroke
				(width 0.1)
				(type default)
			)
			(layer "F.Fab")
		)
		(fp_line
			(start 0.67945 0.3048)
			(end 0.120396 0.3048)
			(stroke
				(width 0.1)
				(type default)
			)
			(layer "F.Fab")
		)
		(fp_line
			(start -0.12065 0.2794)
			(end -0.12065 0.3048)
			(stroke
				(width 0.1)
				(type default)
			)
			(layer "F.Fab")
		)
		(fp_line
			(start 0.120396 0.2794)
			(end -0.12065 0.2794)
			(stroke
				(width 0.1)
				(type default)
			)
			(layer "F.Fab")
		)
		(fp_line
			(start -0.12065 -0.2794)
			(end 0.12065 -0.2794)
			(stroke
				(width 0.1)
				(type default)
			)
			(layer "F.Fab")
		)
		(fp_line
			(start 0.12065 -0.2794)
			(end 0.12065 -0.3048)
			(stroke
				(width 0.1)
				(type default)
			)
			(layer "F.Fab")
		)
		(fp_line
			(start 0.12065 -0.3048)
			(end 0.67945 -0.3048)
			(stroke
				(width 0.1)
				(type default)
			)
			(layer "F.Fab")
		)
		(fp_line
			(start 0.67945 -0.3048)
			(end 0.67945 0.3048)
			(stroke
				(width 0.1)
				(type default)
			)
			(layer "F.Fab")
		)
		(fp_line
			(start -0.67945 -0.305054)
			(end -0.12065 -0.305054)
			(stroke
				(width 0.1)
				(type default)
			)
			(layer "F.Fab")
		)
		(fp_line
			(start -0.12065 -0.305054)
			(end -0.12065 -0.2794)
			(stroke
				(width 0.1)
				(type default)
			)
			(layer "F.Fab")
		)
		(pad "1" smd circle
			(at -0.40005 0 270)
			(size 0 0)
			(layers "F.Cu" "F.Mask" "F.Paste")
			(net "SW_PVDDCR_CPU1_P0_BOOT6_R")
		)
		(pad "2" smd circle
			(at 0.40005 0 270)
			(size 0 0)
			(layers "F.Cu" "F.Mask" "F.Paste")
			(net "SW_PVDDCR_CPU1_P0_BOOTR6")
		)
	)
	(footprint ""
		(layer "F.Cu")
		(at 115.783106 -408.517344 -90)
		(property "Reference" "C6693"
			(at 0 0 270)
			(layer "F.SilkS")
			(hide yes)
			(effects
				(font
					(size 1.27 1.27)
				)
			)
		)
		(property "Value" ""
			(at 0 0 270)
			(layer "F.Fab")
			(effects
				(font
					(size 1.27 1.27)
				)
			)
		)
		(duplicate_pad_numbers_are_jumpers no)
		(fp_line
			(start -0.299974 0.150114)
			(end -0.299974 -0.150114)
			(stroke
				(width 0.1)
				(type default)
			)
			(layer "F.Fab")
		)
		(fp_line
			(start 0.299974 0.150114)
			(end -0.299974 0.150114)
			(stroke
				(width 0.1)
				(type default)
			)
			(layer "F.Fab")
		)
		(fp_line
			(start -0.299974 -0.150114)
			(end 0.299974 -0.150114)
			(stroke
				(width 0.1)
				(type default)
			)
			(layer "F.Fab")
		)
		(fp_line
			(start 0.299974 -0.150114)
			(end 0.299974 0.150114)
			(stroke
				(width 0.1)
				(type default)
			)
			(layer "F.Fab")
		)
		(pad "1" smd rect
			(at -0.2667 0 270)
			(size 0.3048 0.381)
			(layers "F.Cu" "F.Mask" "F.Paste")
			(net "P5E_CPU1_P2_TX_BUF_C_DP<0>")
		)
		(pad "2" smd rect
			(at 0.2667 0 270)
			(size 0.3048 0.381)
			(layers "F.Cu" "F.Mask" "F.Paste")
			(net "P5E_CPU1_P2_TX_BUF_DP<0>")
		)
	)
	(footprint ""
		(layer "F.Cu")
		(at 437.875172 -29.684218 180)
		(property "Reference" "PR3839"
			(at 0 0 180)
			(layer "F.SilkS")
			(hide yes)
			(effects
				(font
					(size 1.27 1.27)
				)
			)
		)
		(property "Value" ""
			(at 0 0 180)
			(layer "F.Fab")
			(effects
				(font
					(size 1.27 1.27)
				)
			)
		)
		(duplicate_pad_numbers_are_jumpers no)
		(fp_line
			(start 0.7874 0.4064)
			(end -0.7874 0.4064)
			(stroke
				(width 0.1524)
				(type default)
			)
			(layer "F.SilkS")
		)
		(fp_line
			(start 0.7874 -0.4064)
			(end 0.7874 0.4064)
			(stroke
				(width 0.1524)
				(type default)
			)
			(layer "F.SilkS")
		)
		(fp_line
			(start -0.7874 0.4064)
			(end -0.7874 -0.4064)
			(stroke
				(width 0.1524)
				(type default)
			)
			(layer "F.SilkS")
		)
		(fp_line
			(start -0.7874 -0.4064)
			(end 0.7874 -0.4064)
			(stroke
				(width 0.1524)
				(type default)
			)
			(layer "F.SilkS")
		)
		(fp_line
			(start 0.67945 0.3048)
			(end 0.120396 0.3048)
			(stroke
				(width 0.1)
				(type default)
			)
			(layer "F.Fab")
		)
		(fp_line
			(start 0.67945 -0.3048)
			(end 0.67945 0.3048)
			(stroke
				(width 0.1)
				(type default)
			)
			(layer "F.Fab")
		)
		(fp_line
			(start 0.12065 -0.2794)
			(end 0.12065 -0.3048)
			(stroke
				(width 0.1)
				(type default)
			)
			(layer "F.Fab")
		)
		(fp_line
			(start 0.12065 -0.3048)
			(end 0.67945 -0.3048)
			(stroke
				(width 0.1)
				(type default)
			)
			(layer "F.Fab")
		)
		(fp_line
			(start 0.120396 0.3048)
			(end 0.120396 0.2794)
			(stroke
				(width 0.1)
				(type default)
			)
			(layer "F.Fab")
		)
		(fp_line
			(start 0.120396 0.2794)
			(end -0.12065 0.2794)
			(stroke
				(width 0.1)
				(type default)
			)
			(layer "F.Fab")
		)
		(fp_line
			(start -0.12065 0.3048)
			(end -0.67945 0.3048)
			(stroke
				(width 0.1)
				(type default)
			)
			(layer "F.Fab")
		)
		(fp_line
			(start -0.12065 0.2794)
			(end -0.12065 0.3048)
			(stroke
				(width 0.1)
				(type default)
			)
			(layer "F.Fab")
		)
		(fp_line
			(start -0.12065 -0.2794)
			(end 0.12065 -0.2794)
			(stroke
				(width 0.1)
				(type default)
			)
			(layer "F.Fab")
		)
		(fp_line
			(start -0.12065 -0.305054)
			(end -0.12065 -0.2794)
			(stroke
				(width 0.1)
				(type default)
			)
			(layer "F.Fab")
		)
		(fp_line
			(start -0.67945 0.3048)
			(end -0.67945 -0.305054)
			(stroke
				(width 0.1)
				(type default)
			)
			(layer "F.Fab")
		)
		(fp_line
			(start -0.67945 -0.305054)
			(end -0.12065 -0.305054)
			(stroke
				(width 0.1)
				(type default)
			)
			(layer "F.Fab")
		)
		(pad "1" smd circle
			(at -0.40005 0 180)
			(size 0 0)
			(layers "F.Cu" "F.Mask" "F.Paste")
			(net "P12V_OCP_FLTB_1")
		)
		(pad "2" smd circle
			(at 0.40005 0 180)
			(size 0 0)
			(layers "F.Cu" "F.Mask" "F.Paste")
			(net "P3V3_AUX")
		)
	)
	(footprint ""
		(layer "F.Cu")
		(at 331.793342 -392.1252)
		(property "Reference" "R1035"
			(at 0 0 0)
			(layer "F.SilkS")
			(hide yes)
			(effects
				(font
					(size 1.27 1.27)
				)
			)
		)
		(property "Value" ""
			(at 0 0 0)
			(layer "F.Fab")
			(effects
				(font
					(size 1.27 1.27)
				)
			)
		)
		(duplicate_pad_numbers_are_jumpers no)
		(fp_line
			(start -0.32512 -0.175006)
			(end 0.32512 -0.175006)
			(stroke
				(width 0.1)
				(type default)
			)
			(layer "F.Fab")
		)
		(fp_line
			(start -0.32512 0.175006)
			(end -0.32512 -0.175006)
			(stroke
				(width 0.1)
				(type default)
			)
			(layer "F.Fab")
		)
		(fp_line
			(start 0.32512 -0.175006)
			(end 0.32512 0.175006)
			(stroke
				(width 0.1)
				(type default)
			)
			(layer "F.Fab")
		)
		(fp_line
			(start 0.32512 0.175006)
			(end -0.32512 0.175006)
			(stroke
				(width 0.1)
				(type default)
			)
			(layer "F.Fab")
		)
		(pad "1" smd rect
			(at -0.2667 0)
			(size 0.3048 0.381)
			(layers "F.Cu" "F.Mask" "F.Paste")
			(net "TEST2_RT_CPU0_P1")
		)
		(pad "2" smd rect
			(at 0.2667 0 180)
			(size 0.3048 0.381)
			(layers "F.Cu" "F.Mask" "F.Paste")
			(net "GND")
		)
	)
	(footprint ""
		(layer "F.Cu")
		(at 98.344736 -120.52173 -90)
		(property "Reference" "C347"
			(at 0 0 270)
			(layer "F.SilkS")
			(hide yes)
			(effects
				(font
					(size 1.27 1.27)
				)
			)
		)
		(property "Value" ""
			(at 0 0 270)
			(layer "F.Fab")
			(effects
				(font
					(size 1.27 1.27)
				)
			)
		)
		(duplicate_pad_numbers_are_jumpers no)
		(fp_line
			(start -0.7874 0.4064)
			(end -0.7874 -0.4064)
			(stroke
				(width 0.1524)
				(type default)
			)
			(layer "F.SilkS")
		)
		(fp_line
			(start 0.7874 0.4064)
			(end -0.7874 0.4064)
			(stroke
				(width 0.1524)
				(type default)
			)
			(layer "F.SilkS")
		)
		(fp_line
			(start -0.7874 -0.4064)
			(end 0.7874 -0.4064)
			(stroke
				(width 0.1524)
				(type default)
			)
			(layer "F.SilkS")
		)
		(fp_line
			(start 0.7874 -0.4064)
			(end 0.7874 0.4064)
			(stroke
				(width 0.1524)
				(type default)
			)
			(layer "F.SilkS")
		)
		(fp_line
			(start -0.67945 0.3048)
			(end -0.67945 -0.305054)
			(stroke
				(width 0.1)
				(type default)
			)
			(layer "F.Fab")
		)
		(fp_line
			(start -0.12065 0.3048)
			(end -0.67945 0.3048)
			(stroke
				(width 0.1)
				(type default)
			)
			(layer "F.Fab")
		)
		(fp_line
			(start 0.120396 0.3048)
			(end 0.120396 0.2794)
			(stroke
				(width 0.1)
				(type default)
			)
			(layer "F.Fab")
		)
		(fp_line
			(start 0.67945 0.3048)
			(end 0.120396 0.3048)
			(stroke
				(width 0.1)
				(type default)
			)
			(layer "F.Fab")
		)
		(fp_line
			(start -0.12065 0.2794)
			(end -0.12065 0.3048)
			(stroke
				(width 0.1)
				(type default)
			)
			(layer "F.Fab")
		)
		(fp_line
			(start 0.120396 0.2794)
			(end -0.12065 0.2794)
			(stroke
				(width 0.1)
				(type default)
			)
			(layer "F.Fab")
		)
		(fp_line
			(start -0.12065 -0.2794)
			(end 0.12065 -0.2794)
			(stroke
				(width 0.1)
				(type default)
			)
			(layer "F.Fab")
		)
		(fp_line
			(start 0.12065 -0.2794)
			(end 0.12065 -0.3048)
			(stroke
				(width 0.1)
				(type default)
			)
			(layer "F.Fab")
		)
		(fp_line
			(start 0.12065 -0.3048)
			(end 0.67945 -0.3048)
			(stroke
				(width 0.1)
				(type default)
			)
			(layer "F.Fab")
		)
		(fp_line
			(start 0.67945 -0.3048)
			(end 0.67945 0.3048)
			(stroke
				(width 0.1)
				(type default)
			)
			(layer "F.Fab")
		)
		(fp_line
			(start -0.67945 -0.305054)
			(end -0.12065 -0.305054)
			(stroke
				(width 0.1)
				(type default)
			)
			(layer "F.Fab")
		)
		(fp_line
			(start -0.12065 -0.305054)
			(end -0.12065 -0.2794)
			(stroke
				(width 0.1)
				(type default)
			)
			(layer "F.Fab")
		)
		(pad "1" smd circle
			(at -0.40005 0 270)
			(size 0 0)
			(layers "F.Cu" "F.Mask" "F.Paste")
			(net "P1V8_AUX")
		)
		(pad "2" smd circle
			(at 0.40005 0 270)
			(size 0 0)
			(layers "F.Cu" "F.Mask" "F.Paste")
			(net "GND")
		)
	)
	(footprint ""
		(layer "F.Cu")
		(at 221.899988 -290.89985)
		(property "Reference" "H8"
			(at -1.960118 -4.20751 0)
			(unlocked yes)
			(layer "F.SilkS")
			(effects
				(font
					(size 0.7874 0.5842)
					(thickness 0.1524)
				)
				(justify left)
			)
		)
		(property "Value" ""
			(at 0 0 0)
			(layer "F.Fab")
			(effects
				(font
					(size 1.27 1.27)
				)
			)
		)
		(duplicate_pad_numbers_are_jumpers no)
		(pad "1" thru_hole circle
			(at 0 0)
			(size 6.1976 6.1976)
			(drill 3.7338)
			(layers "*.Cu" "*.Mask")
			(remove_unused_layers no)
			(net "GND")
			(clearance -0.9779)
			(padstack
				(mode front_inner_back)
				(layer "Inner"
					(shape circle)
					(size 5.5372 5.5372)
					(clearance -0.6477)
				)
				(layer "B.Cu"
					(shape circle)
					(size 6.1976 6.1976)
					(clearance -0.9779)
				)
			)
		)
	)
	(footprint ""
		(layer "F.Cu")
		(at 29.553662 -419.249098 -90)
		(property "Reference" "R3268"
			(at 0 0 270)
			(layer "F.SilkS")
			(hide yes)
			(effects
				(font
					(size 1.27 1.27)
				)
			)
		)
		(property "Value" ""
			(at 0 0 270)
			(layer "F.Fab")
			(effects
				(font
					(size 1.27 1.27)
				)
			)
		)
		(duplicate_pad_numbers_are_jumpers no)
		(fp_line
			(start -0.7874 0.4064)
			(end -0.7874 -0.4064)
			(stroke
				(width 0.1524)
				(type default)
			)
			(layer "F.SilkS")
		)
		(fp_line
			(start 0.7874 0.4064)
			(end -0.7874 0.4064)
			(stroke
				(width 0.1524)
				(type default)
			)
			(layer "F.SilkS")
		)
		(fp_line
			(start -0.7874 -0.4064)
			(end 0.7874 -0.4064)
			(stroke
				(width 0.1524)
				(type default)
			)
			(layer "F.SilkS")
		)
		(fp_line
			(start 0.7874 -0.4064)
			(end 0.7874 0.4064)
			(stroke
				(width 0.1524)
				(type default)
			)
			(layer "F.SilkS")
		)
		(fp_line
			(start -0.67945 0.3048)
			(end -0.67945 -0.305054)
			(stroke
				(width 0.1)
				(type default)
			)
			(layer "F.Fab")
		)
		(fp_line
			(start -0.12065 0.3048)
			(end -0.67945 0.3048)
			(stroke
				(width 0.1)
				(type default)
			)
			(layer "F.Fab")
		)
		(fp_line
			(start 0.120396 0.3048)
			(end 0.120396 0.2794)
			(stroke
				(width 0.1)
				(type default)
			)
			(layer "F.Fab")
		)
		(fp_line
			(start 0.67945 0.3048)
			(end 0.120396 0.3048)
			(stroke
				(width 0.1)
				(type default)
			)
			(layer "F.Fab")
		)
		(fp_line
			(start -0.12065 0.2794)
			(end -0.12065 0.3048)
			(stroke
				(width 0.1)
				(type default)
			)
			(layer "F.Fab")
		)
		(fp_line
			(start 0.120396 0.2794)
			(end -0.12065 0.2794)
			(stroke
				(width 0.1)
				(type default)
			)
			(layer "F.Fab")
		)
		(fp_line
			(start -0.12065 -0.2794)
			(end 0.12065 -0.2794)
			(stroke
				(width 0.1)
				(type default)
			)
			(layer "F.Fab")
		)
		(fp_line
			(start 0.12065 -0.2794)
			(end 0.12065 -0.3048)
			(stroke
				(width 0.1)
				(type default)
			)
			(layer "F.Fab")
		)
		(fp_line
			(start 0.12065 -0.3048)
			(end 0.67945 -0.3048)
			(stroke
				(width 0.1)
				(type default)
			)
			(layer "F.Fab")
		)
		(fp_line
			(start 0.67945 -0.3048)
			(end 0.67945 0.3048)
			(stroke
				(width 0.1)
				(type default)
			)
			(layer "F.Fab")
		)
		(fp_line
			(start -0.67945 -0.305054)
			(end -0.12065 -0.305054)
			(stroke
				(width 0.1)
				(type default)
			)
			(layer "F.Fab")
		)
		(fp_line
			(start -0.12065 -0.305054)
			(end -0.12065 -0.2794)
			(stroke
				(width 0.1)
				(type default)
			)
			(layer "F.Fab")
		)
		(pad "1" smd circle
			(at -0.40005 0 270)
			(size 0 0)
			(layers "F.Cu" "F.Mask" "F.Paste")
			(net "FM_P2E_EQA1")
		)
		(pad "2" smd circle
			(at 0.40005 0 270)
			(size 0 0)
			(layers "F.Cu" "F.Mask" "F.Paste")
			(net "GND")
		)
	)
	(footprint ""
		(layer "F.Cu")
		(at 20.480782 -412.850584 180)
		(property "Reference" "PR6818"
			(at 0 0 180)
			(layer "F.SilkS")
			(hide yes)
			(effects
				(font
					(size 1.27 1.27)
				)
			)
		)
		(property "Value" ""
			(at 0 0 180)
			(layer "F.Fab")
			(effects
				(font
					(size 1.27 1.27)
				)
			)
		)
		(duplicate_pad_numbers_are_jumpers no)
		(fp_line
			(start 0.7874 0.4064)
			(end -0.7874 0.4064)
			(stroke
				(width 0.1524)
				(type default)
			)
			(layer "F.SilkS")
		)
		(fp_line
			(start 0.7874 -0.4064)
			(end 0.7874 0.4064)
			(stroke
				(width 0.1524)
				(type default)
			)
			(layer "F.SilkS")
		)
		(fp_line
			(start -0.7874 0.4064)
			(end -0.7874 -0.4064)
			(stroke
				(width 0.1524)
				(type default)
			)
			(layer "F.SilkS")
		)
		(fp_line
			(start -0.7874 -0.4064)
			(end 0.7874 -0.4064)
			(stroke
				(width 0.1524)
				(type default)
			)
			(layer "F.SilkS")
		)
		(fp_line
			(start 0.67945 0.3048)
			(end 0.120396 0.3048)
			(stroke
				(width 0.1)
				(type default)
			)
			(layer "F.Fab")
		)
		(fp_line
			(start 0.67945 -0.3048)
			(end 0.67945 0.3048)
			(stroke
				(width 0.1)
				(type default)
			)
			(layer "F.Fab")
		)
		(fp_line
			(start 0.12065 -0.2794)
			(end 0.12065 -0.3048)
			(stroke
				(width 0.1)
				(type default)
			)
			(layer "F.Fab")
		)
		(fp_line
			(start 0.12065 -0.3048)
			(end 0.67945 -0.3048)
			(stroke
				(width 0.1)
				(type default)
			)
			(layer "F.Fab")
		)
		(fp_line
			(start 0.120396 0.3048)
			(end 0.120396 0.2794)
			(stroke
				(width 0.1)
				(type default)
			)
			(layer "F.Fab")
		)
		(fp_line
			(start 0.120396 0.2794)
			(end -0.12065 0.2794)
			(stroke
				(width 0.1)
				(type default)
			)
			(layer "F.Fab")
		)
		(fp_line
			(start -0.12065 0.3048)
			(end -0.67945 0.3048)
			(stroke
				(width 0.1)
				(type default)
			)
			(layer "F.Fab")
		)
		(fp_line
			(start -0.12065 0.2794)
			(end -0.12065 0.3048)
			(stroke
				(width 0.1)
				(type default)
			)
			(layer "F.Fab")
		)
		(fp_line
			(start -0.12065 -0.2794)
			(end 0.12065 -0.2794)
			(stroke
				(width 0.1)
				(type default)
			)
			(layer "F.Fab")
		)
		(fp_line
			(start -0.12065 -0.305054)
			(end -0.12065 -0.2794)
			(stroke
				(width 0.1)
				(type default)
			)
			(layer "F.Fab")
		)
		(fp_line
			(start -0.67945 0.3048)
			(end -0.67945 -0.305054)
			(stroke
				(width 0.1)
				(type default)
			)
			(layer "F.Fab")
		)
		(fp_line
			(start -0.67945 -0.305054)
			(end -0.12065 -0.305054)
			(stroke
				(width 0.1)
				(type default)
			)
			(layer "F.Fab")
		)
		(pad "1" smd circle
			(at -0.40005 0 180)
			(size 0 0)
			(layers "F.Cu" "F.Mask" "F.Paste")
			(net "P3V3_AUX")
		)
		(pad "2" smd circle
			(at 0.40005 0 180)
			(size 0 0)
			(layers "F.Cu" "F.Mask" "F.Paste")
			(net "TP_P0V9_RETIMER_CPU1_SVID_ALERT_N")
		)
	)
	(footprint ""
		(layer "F.Cu")
		(at 123.795282 -15.26667 180)
		(property "Reference" "R4192"
			(at 0 0 180)
			(layer "F.SilkS")
			(hide yes)
			(effects
				(font
					(size 1.27 1.27)
				)
			)
		)
		(property "Value" ""
			(at 0 0 180)
			(layer "F.Fab")
			(effects
				(font
					(size 1.27 1.27)
				)
			)
		)
		(duplicate_pad_numbers_are_jumpers no)
		(fp_line
			(start 0.7874 0.4064)
			(end -0.7874 0.4064)
			(stroke
				(width 0.1524)
				(type default)
			)
			(layer "F.SilkS")
		)
		(fp_line
			(start 0.7874 -0.4064)
			(end 0.7874 0.4064)
			(stroke
				(width 0.1524)
				(type default)
			)
			(layer "F.SilkS")
		)
		(fp_line
			(start -0.7874 0.4064)
			(end -0.7874 -0.4064)
			(stroke
				(width 0.1524)
				(type default)
			)
			(layer "F.SilkS")
		)
		(fp_line
			(start -0.7874 -0.4064)
			(end 0.7874 -0.4064)
			(stroke
				(width 0.1524)
				(type default)
			)
			(layer "F.SilkS")
		)
		(fp_line
			(start 0.67945 0.3048)
			(end 0.120396 0.3048)
			(stroke
				(width 0.1)
				(type default)
			)
			(layer "F.Fab")
		)
		(fp_line
			(start 0.67945 -0.3048)
			(end 0.67945 0.3048)
			(stroke
				(width 0.1)
				(type default)
			)
			(layer "F.Fab")
		)
		(fp_line
			(start 0.12065 -0.2794)
			(end 0.12065 -0.3048)
			(stroke
				(width 0.1)
				(type default)
			)
			(layer "F.Fab")
		)
		(fp_line
			(start 0.12065 -0.3048)
			(end 0.67945 -0.3048)
			(stroke
				(width 0.1)
				(type default)
			)
			(layer "F.Fab")
		)
		(fp_line
			(start 0.120396 0.3048)
			(end 0.120396 0.2794)
			(stroke
				(width 0.1)
				(type default)
			)
			(layer "F.Fab")
		)
		(fp_line
			(start 0.120396 0.2794)
			(end -0.12065 0.2794)
			(stroke
				(width 0.1)
				(type default)
			)
			(layer "F.Fab")
		)
		(fp_line
			(start -0.12065 0.3048)
			(end -0.67945 0.3048)
			(stroke
				(width 0.1)
				(type default)
			)
			(layer "F.Fab")
		)
		(fp_line
			(start -0.12065 0.2794)
			(end -0.12065 0.3048)
			(stroke
				(width 0.1)
				(type default)
			)
			(layer "F.Fab")
		)
		(fp_line
			(start -0.12065 -0.2794)
			(end 0.12065 -0.2794)
			(stroke
				(width 0.1)
				(type default)
			)
			(layer "F.Fab")
		)
		(fp_line
			(start -0.12065 -0.305054)
			(end -0.12065 -0.2794)
			(stroke
				(width 0.1)
				(type default)
			)
			(layer "F.Fab")
		)
		(fp_line
			(start -0.67945 0.3048)
			(end -0.67945 -0.305054)
			(stroke
				(width 0.1)
				(type default)
			)
			(layer "F.Fab")
		)
		(fp_line
			(start -0.67945 -0.305054)
			(end -0.12065 -0.305054)
			(stroke
				(width 0.1)
				(type default)
			)
			(layer "F.Fab")
		)
		(pad "1" smd circle
			(at -0.40005 0 180)
			(size 0 0)
			(layers "F.Cu" "F.Mask" "F.Paste")
			(net "P3V3_AUX")
		)
		(pad "2" smd circle
			(at 0.40005 0 180)
			(size 0 0)
			(layers "F.Cu" "F.Mask" "F.Paste")
			(net "U273_3_ADD1")
		)
	)
	(footprint ""
		(layer "F.Cu")
		(at 138.426952 -55.484014)
		(property "Reference" "R1659"
			(at 0 0 0)
			(layer "F.SilkS")
			(hide yes)
			(effects
				(font
					(size 1.27 1.27)
				)
			)
		)
		(property "Value" ""
			(at 0 0 0)
			(layer "F.Fab")
			(effects
				(font
					(size 1.27 1.27)
				)
			)
		)
		(duplicate_pad_numbers_are_jumpers no)
		(fp_line
			(start -0.7874 -0.4064)
			(end 0.7874 -0.4064)
			(stroke
				(width 0.1524)
				(type default)
			)
			(layer "F.SilkS")
		)
		(fp_line
			(start -0.7874 0.4064)
			(end -0.7874 -0.4064)
			(stroke
				(width 0.1524)
				(type default)
			)
			(layer "F.SilkS")
		)
		(fp_line
			(start 0.7874 -0.4064)
			(end 0.7874 0.4064)
			(stroke
				(width 0.1524)
				(type default)
			)
			(layer "F.SilkS")
		)
		(fp_line
			(start 0.7874 0.4064)
			(end -0.7874 0.4064)
			(stroke
				(width 0.1524)
				(type default)
			)
			(layer "F.SilkS")
		)
		(fp_line
			(start -0.67945 -0.305054)
			(end -0.12065 -0.305054)
			(stroke
				(width 0.1)
				(type default)
			)
			(layer "F.Fab")
		)
		(fp_line
			(start -0.67945 0.3048)
			(end -0.67945 -0.305054)
			(stroke
				(width 0.1)
				(type default)
			)
			(layer "F.Fab")
		)
		(fp_line
			(start -0.12065 -0.305054)
			(end -0.12065 -0.2794)
			(stroke
				(width 0.1)
				(type default)
			)
			(layer "F.Fab")
		)
		(fp_line
			(start -0.12065 -0.2794)
			(end 0.12065 -0.2794)
			(stroke
				(width 0.1)
				(type default)
			)
			(layer "F.Fab")
		)
		(fp_line
			(start -0.12065 0.2794)
			(end -0.12065 0.3048)
			(stroke
				(width 0.1)
				(type default)
			)
			(layer "F.Fab")
		)
		(fp_line
			(start -0.12065 0.3048)
			(end -0.67945 0.3048)
			(stroke
				(width 0.1)
				(type default)
			)
			(layer "F.Fab")
		)
		(fp_line
			(start 0.120396 0.2794)
			(end -0.12065 0.2794)
			(stroke
				(width 0.1)
				(type default)
			)
			(layer "F.Fab")
		)
		(fp_line
			(start 0.120396 0.3048)
			(end 0.120396 0.2794)
			(stroke
				(width 0.1)
				(type default)
			)
			(layer "F.Fab")
		)
		(fp_line
			(start 0.12065 -0.3048)
			(end 0.67945 -0.3048)
			(stroke
				(width 0.1)
				(type default)
			)
			(layer "F.Fab")
		)
		(fp_line
			(start 0.12065 -0.2794)
			(end 0.12065 -0.3048)
			(stroke
				(width 0.1)
				(type default)
			)
			(layer "F.Fab")
		)
		(fp_line
			(start 0.67945 -0.3048)
			(end 0.67945 0.3048)
			(stroke
				(width 0.1)
				(type default)
			)
			(layer "F.Fab")
		)
		(fp_line
			(start 0.67945 0.3048)
			(end 0.120396 0.3048)
			(stroke
				(width 0.1)
				(type default)
			)
			(layer "F.Fab")
		)
		(pad "1" smd circle
			(at -0.40005 0)
			(size 0 0)
			(layers "F.Cu" "F.Mask" "F.Paste")
			(net "P3V3_AUX")
		)
		(pad "2" smd circle
			(at 0.40005 0)
			(size 0 0)
			(layers "F.Cu" "F.Mask" "F.Paste")
			(net "SCM_JTAG_MUX_S0")
		)
	)
	(footprint ""
		(layer "F.Cu")
		(at 97.074736 -127.787654 -90)
		(property "Reference" "R1459"
			(at 0 0 270)
			(layer "F.SilkS")
			(hide yes)
			(effects
				(font
					(size 1.27 1.27)
				)
			)
		)
		(property "Value" ""
			(at 0 0 270)
			(layer "F.Fab")
			(effects
				(font
					(size 1.27 1.27)
				)
			)
		)
		(duplicate_pad_numbers_are_jumpers no)
		(fp_line
			(start -0.7874 0.4064)
			(end -0.7874 -0.4064)
			(stroke
				(width 0.1524)
				(type default)
			)
			(layer "F.SilkS")
		)
		(fp_line
			(start 0.7874 0.4064)
			(end -0.7874 0.4064)
			(stroke
				(width 0.1524)
				(type default)
			)
			(layer "F.SilkS")
		)
		(fp_line
			(start -0.7874 -0.4064)
			(end 0.7874 -0.4064)
			(stroke
				(width 0.1524)
				(type default)
			)
			(layer "F.SilkS")
		)
		(fp_line
			(start 0.7874 -0.4064)
			(end 0.7874 0.4064)
			(stroke
				(width 0.1524)
				(type default)
			)
			(layer "F.SilkS")
		)
		(fp_line
			(start -0.67945 0.3048)
			(end -0.67945 -0.305054)
			(stroke
				(width 0.1)
				(type default)
			)
			(layer "F.Fab")
		)
		(fp_line
			(start -0.12065 0.3048)
			(end -0.67945 0.3048)
			(stroke
				(width 0.1)
				(type default)
			)
			(layer "F.Fab")
		)
		(fp_line
			(start 0.120396 0.3048)
			(end 0.120396 0.2794)
			(stroke
				(width 0.1)
				(type default)
			)
			(layer "F.Fab")
		)
		(fp_line
			(start 0.67945 0.3048)
			(end 0.120396 0.3048)
			(stroke
				(width 0.1)
				(type default)
			)
			(layer "F.Fab")
		)
		(fp_line
			(start -0.12065 0.2794)
			(end -0.12065 0.3048)
			(stroke
				(width 0.1)
				(type default)
			)
			(layer "F.Fab")
		)
		(fp_line
			(start 0.120396 0.2794)
			(end -0.12065 0.2794)
			(stroke
				(width 0.1)
				(type default)
			)
			(layer "F.Fab")
		)
		(fp_line
			(start -0.12065 -0.2794)
			(end 0.12065 -0.2794)
			(stroke
				(width 0.1)
				(type default)
			)
			(layer "F.Fab")
		)
		(fp_line
			(start 0.12065 -0.2794)
			(end 0.12065 -0.3048)
			(stroke
				(width 0.1)
				(type default)
			)
			(layer "F.Fab")
		)
		(fp_line
			(start 0.12065 -0.3048)
			(end 0.67945 -0.3048)
			(stroke
				(width 0.1)
				(type default)
			)
			(layer "F.Fab")
		)
		(fp_line
			(start 0.67945 -0.3048)
			(end 0.67945 0.3048)
			(stroke
				(width 0.1)
				(type default)
			)
			(layer "F.Fab")
		)
		(fp_line
			(start -0.67945 -0.305054)
			(end -0.12065 -0.305054)
			(stroke
				(width 0.1)
				(type default)
			)
			(layer "F.Fab")
		)
		(fp_line
			(start -0.12065 -0.305054)
			(end -0.12065 -0.2794)
			(stroke
				(width 0.1)
				(type default)
			)
			(layer "F.Fab")
		)
		(pad "1" smd circle
			(at -0.40005 0 270)
			(size 0 0)
			(layers "F.Cu" "F.Mask" "F.Paste")
			(net "PWRGD_P12V_MEM_CPU1")
		)
		(pad "2" smd circle
			(at 0.40005 0 270)
			(size 0 0)
			(layers "F.Cu" "F.Mask" "F.Paste")
			(net "PWRGD_P12V_MEM_CPU1_R")
		)
	)
	(footprint ""
		(layer "F.Cu")
		(at 339.696298 -332.020164 180)
		(property "Reference" "PC157"
			(at 0 0 180)
			(layer "F.SilkS")
			(hide yes)
			(effects
				(font
					(size 1.27 1.27)
				)
			)
		)
		(property "Value" ""
			(at 0 0 180)
			(layer "F.Fab")
			(effects
				(font
					(size 1.27 1.27)
				)
			)
		)
		(duplicate_pad_numbers_are_jumpers no)
		(fp_line
			(start 0.7874 0.4064)
			(end -0.7874 0.4064)
			(stroke
				(width 0.1524)
				(type default)
			)
			(layer "F.SilkS")
		)
		(fp_line
			(start 0.7874 -0.4064)
			(end 0.7874 0.4064)
			(stroke
				(width 0.1524)
				(type default)
			)
			(layer "F.SilkS")
		)
		(fp_line
			(start -0.7874 0.4064)
			(end -0.7874 -0.4064)
			(stroke
				(width 0.1524)
				(type default)
			)
			(layer "F.SilkS")
		)
		(fp_line
			(start -0.7874 -0.4064)
			(end 0.7874 -0.4064)
			(stroke
				(width 0.1524)
				(type default)
			)
			(layer "F.SilkS")
		)
		(fp_line
			(start 0.67945 0.3048)
			(end 0.120396 0.3048)
			(stroke
				(width 0.1)
				(type default)
			)
			(layer "F.Fab")
		)
		(fp_line
			(start 0.67945 -0.3048)
			(end 0.67945 0.3048)
			(stroke
				(width 0.1)
				(type default)
			)
			(layer "F.Fab")
		)
		(fp_line
			(start 0.12065 -0.2794)
			(end 0.12065 -0.3048)
			(stroke
				(width 0.1)
				(type default)
			)
			(layer "F.Fab")
		)
		(fp_line
			(start 0.12065 -0.3048)
			(end 0.67945 -0.3048)
			(stroke
				(width 0.1)
				(type default)
			)
			(layer "F.Fab")
		)
		(fp_line
			(start 0.120396 0.3048)
			(end 0.120396 0.2794)
			(stroke
				(width 0.1)
				(type default)
			)
			(layer "F.Fab")
		)
		(fp_line
			(start 0.120396 0.2794)
			(end -0.12065 0.2794)
			(stroke
				(width 0.1)
				(type default)
			)
			(layer "F.Fab")
		)
		(fp_line
			(start -0.12065 0.3048)
			(end -0.67945 0.3048)
			(stroke
				(width 0.1)
				(type default)
			)
			(layer "F.Fab")
		)
		(fp_line
			(start -0.12065 0.2794)
			(end -0.12065 0.3048)
			(stroke
				(width 0.1)
				(type default)
			)
			(layer "F.Fab")
		)
		(fp_line
			(start -0.12065 -0.2794)
			(end 0.12065 -0.2794)
			(stroke
				(width 0.1)
				(type default)
			)
			(layer "F.Fab")
		)
		(fp_line
			(start -0.12065 -0.305054)
			(end -0.12065 -0.2794)
			(stroke
				(width 0.1)
				(type default)
			)
			(layer "F.Fab")
		)
		(fp_line
			(start -0.67945 0.3048)
			(end -0.67945 -0.305054)
			(stroke
				(width 0.1)
				(type default)
			)
			(layer "F.Fab")
		)
		(fp_line
			(start -0.67945 -0.305054)
			(end -0.12065 -0.305054)
			(stroke
				(width 0.1)
				(type default)
			)
			(layer "F.Fab")
		)
		(pad "1" smd circle
			(at -0.40005 0 180)
			(size 0 0)
			(layers "F.Cu" "F.Mask" "F.Paste")
			(net "SW_PVDDCR_CPU1_P0_SW5")
		)
		(pad "2" smd circle
			(at 0.40005 0 180)
			(size 0 0)
			(layers "F.Cu" "F.Mask" "F.Paste")
			(net "SW_PVDDCR_CPU1_P0_SW5_RC")
		)
	)
	(footprint ""
		(layer "F.Cu")
		(at 380.618492 -381.41783 -90)
		(property "Reference" "C884"
			(at 0 0 270)
			(layer "F.SilkS")
			(hide yes)
			(effects
				(font
					(size 1.27 1.27)
				)
			)
		)
		(property "Value" ""
			(at 0 0 270)
			(layer "F.Fab")
			(effects
				(font
					(size 1.27 1.27)
				)
			)
		)
		(duplicate_pad_numbers_are_jumpers no)
		(fp_line
			(start -0.299974 0.150114)
			(end -0.299974 -0.150114)
			(stroke
				(width 0.1)
				(type default)
			)
			(layer "F.Fab")
		)
		(fp_line
			(start 0.299974 0.150114)
			(end -0.299974 0.150114)
			(stroke
				(width 0.1)
				(type default)
			)
			(layer "F.Fab")
		)
		(fp_line
			(start -0.299974 -0.150114)
			(end 0.299974 -0.150114)
			(stroke
				(width 0.1)
				(type default)
			)
			(layer "F.Fab")
		)
		(fp_line
			(start 0.299974 -0.150114)
			(end 0.299974 0.150114)
			(stroke
				(width 0.1)
				(type default)
			)
			(layer "F.Fab")
		)
		(pad "1" smd rect
			(at -0.2667 0 270)
			(size 0.3048 0.381)
			(layers "F.Cu" "F.Mask" "F.Paste")
			(net "P5E_CPU0_P3_TX_C_DN<8>")
		)
		(pad "2" smd rect
			(at 0.2667 0 270)
			(size 0.3048 0.381)
			(layers "F.Cu" "F.Mask" "F.Paste")
			(net "P5E_CPU0_P3_TX_DN<8>")
		)
	)
	(footprint ""
		(layer "F.Cu")
		(at 318.539876 -70.098412 90)
		(property "Reference" "D91"
			(at -3.934714 -0.691642 90)
			(unlocked yes)
			(layer "F.SilkS")
			(effects
				(font
					(size 0.7874 0.5842)
					(thickness 0.1524)
				)
				(justify left)
			)
		)
		(property "Value" ""
			(at 0 0 90)
			(layer "F.Fab")
			(effects
				(font
					(size 1.27 1.27)
				)
			)
		)
		(duplicate_pad_numbers_are_jumpers no)
		(fp_line
			(start 1.16078 -0.4826)
			(end 1.16078 0.4826)
			(stroke
				(width 0.1524)
				(type default)
			)
			(layer "F.SilkS")
		)
		(fp_line
			(start 1.03378 -0.4826)
			(end 1.03378 0.4826)
			(stroke
				(width 0.1524)
				(type default)
			)
			(layer "F.SilkS")
		)
		(fp_line
			(start 0.90678 -0.4826)
			(end 0.90678 0.4826)
			(stroke
				(width 0.1524)
				(type default)
			)
			(layer "F.SilkS")
		)
		(fp_line
			(start -0.64008 -0.4826)
			(end 1.16078 -0.4826)
			(stroke
				(width 0.1524)
				(type default)
			)
			(layer "F.SilkS")
		)
		(fp_line
			(start -0.79248 -0.4826)
			(end 1.03378 -0.4826)
			(stroke
				(width 0.1524)
				(type default)
			)
			(layer "F.SilkS")
		)
		(fp_line
			(start -0.89408 -0.4826)
			(end 0.90678 -0.4826)
			(stroke
				(width 0.1524)
				(type default)
			)
			(layer "F.SilkS")
		)
		(fp_line
			(start 1.16078 0.4826)
			(end -0.64008 0.4826)
			(stroke
				(width 0.1524)
				(type default)
			)
			(layer "F.SilkS")
		)
		(fp_line
			(start 1.03378 0.4826)
			(end -0.79248 0.4826)
			(stroke
				(width 0.1524)
				(type default)
			)
			(layer "F.SilkS")
		)
		(fp_line
			(start 0.90678 0.4826)
			(end -0.90678 0.4826)
			(stroke
				(width 0.1524)
				(type default)
			)
			(layer "F.SilkS")
		)
		(fp_line
			(start -0.90678 0.4826)
			(end -0.90678 -0.4699)
			(stroke
				(width 0.1524)
				(type default)
			)
			(layer "F.SilkS")
		)
		(fp_line
			(start 0.499872 -0.249936)
			(end 0.499872 0.249936)
			(stroke
				(width 0.1)
				(type default)
			)
			(layer "F.Fab")
		)
		(fp_line
			(start -0.499872 -0.249936)
			(end 0.499872 -0.249936)
			(stroke
				(width 0.1)
				(type default)
			)
			(layer "F.Fab")
		)
		(fp_line
			(start 0.499872 0.249936)
			(end -0.499872 0.249936)
			(stroke
				(width 0.1)
				(type default)
			)
			(layer "F.Fab")
		)
		(fp_line
			(start -0.499872 0.249936)
			(end -0.499872 -0.249936)
			(stroke
				(width 0.1)
				(type default)
			)
			(layer "F.Fab")
		)
		(pad "A" smd rect
			(at -0.47498 0 90)
			(size 0.6096 0.7112)
			(layers "F.Cu" "F.Mask" "F.Paste")
			(net "LED_PWRGD_P1V8_AUX")
		)
		(pad "C" smd rect
			(at 0.47498 0 90)
			(size 0.6096 0.7112)
			(layers "F.Cu" "F.Mask" "F.Paste")
			(net "LED_PWRGD_P1V8_AUX_D")
		)
	)
	(footprint ""
		(layer "F.Cu")
		(at 192.037716 -57.963054 180)
		(property "Reference" "R8028"
			(at 0 0 180)
			(layer "F.SilkS")
			(hide yes)
			(effects
				(font
					(size 1.27 1.27)
				)
			)
		)
		(property "Value" ""
			(at 0 0 180)
			(layer "F.Fab")
			(effects
				(font
					(size 1.27 1.27)
				)
			)
		)
		(duplicate_pad_numbers_are_jumpers no)
		(fp_line
			(start 0.7874 0.4064)
			(end -0.7874 0.4064)
			(stroke
				(width 0.1524)
				(type default)
			)
			(layer "F.SilkS")
		)
		(fp_line
			(start 0.7874 -0.4064)
			(end 0.7874 0.4064)
			(stroke
				(width 0.1524)
				(type default)
			)
			(layer "F.SilkS")
		)
		(fp_line
			(start -0.7874 0.4064)
			(end -0.7874 -0.4064)
			(stroke
				(width 0.1524)
				(type default)
			)
			(layer "F.SilkS")
		)
		(fp_line
			(start -0.7874 -0.4064)
			(end 0.7874 -0.4064)
			(stroke
				(width 0.1524)
				(type default)
			)
			(layer "F.SilkS")
		)
		(fp_line
			(start 0.67945 0.3048)
			(end 0.120396 0.3048)
			(stroke
				(width 0.1)
				(type default)
			)
			(layer "F.Fab")
		)
		(fp_line
			(start 0.67945 -0.3048)
			(end 0.67945 0.3048)
			(stroke
				(width 0.1)
				(type default)
			)
			(layer "F.Fab")
		)
		(fp_line
			(start 0.12065 -0.2794)
			(end 0.12065 -0.3048)
			(stroke
				(width 0.1)
				(type default)
			)
			(layer "F.Fab")
		)
		(fp_line
			(start 0.12065 -0.3048)
			(end 0.67945 -0.3048)
			(stroke
				(width 0.1)
				(type default)
			)
			(layer "F.Fab")
		)
		(fp_line
			(start 0.120396 0.3048)
			(end 0.120396 0.2794)
			(stroke
				(width 0.1)
				(type default)
			)
			(layer "F.Fab")
		)
		(fp_line
			(start 0.120396 0.2794)
			(end -0.12065 0.2794)
			(stroke
				(width 0.1)
				(type default)
			)
			(layer "F.Fab")
		)
		(fp_line
			(start -0.12065 0.3048)
			(end -0.67945 0.3048)
			(stroke
				(width 0.1)
				(type default)
			)
			(layer "F.Fab")
		)
		(fp_line
			(start -0.12065 0.2794)
			(end -0.12065 0.3048)
			(stroke
				(width 0.1)
				(type default)
			)
			(layer "F.Fab")
		)
		(fp_line
			(start -0.12065 -0.2794)
			(end 0.12065 -0.2794)
			(stroke
				(width 0.1)
				(type default)
			)
			(layer "F.Fab")
		)
		(fp_line
			(start -0.12065 -0.305054)
			(end -0.12065 -0.2794)
			(stroke
				(width 0.1)
				(type default)
			)
			(layer "F.Fab")
		)
		(fp_line
			(start -0.67945 0.3048)
			(end -0.67945 -0.305054)
			(stroke
				(width 0.1)
				(type default)
			)
			(layer "F.Fab")
		)
		(fp_line
			(start -0.67945 -0.305054)
			(end -0.12065 -0.305054)
			(stroke
				(width 0.1)
				(type default)
			)
			(layer "F.Fab")
		)
		(pad "1" smd circle
			(at -0.40005 0 180)
			(size 0 0)
			(layers "F.Cu" "F.Mask" "F.Paste")
			(net "P3V3_AUX")
		)
		(pad "2" smd circle
			(at 0.40005 0 180)
			(size 0 0)
			(layers "F.Cu" "F.Mask" "F.Paste")
			(net "LED_P12V_SCM_FAULT_D1")
		)
	)
	(footprint ""
		(layer "F.Cu")
		(at 391.082022 -137.061702 -90)
		(property "Reference" "R702"
			(at 0 0 270)
			(layer "F.SilkS")
			(hide yes)
			(effects
				(font
					(size 1.27 1.27)
				)
			)
		)
		(property "Value" ""
			(at 0 0 270)
			(layer "F.Fab")
			(effects
				(font
					(size 1.27 1.27)
				)
			)
		)
		(duplicate_pad_numbers_are_jumpers no)
		(fp_line
			(start -0.7874 0.4064)
			(end -0.7874 -0.4064)
			(stroke
				(width 0.1524)
				(type default)
			)
			(layer "F.SilkS")
		)
		(fp_line
			(start 0.7874 0.4064)
			(end -0.7874 0.4064)
			(stroke
				(width 0.1524)
				(type default)
			)
			(layer "F.SilkS")
		)
		(fp_line
			(start -0.7874 -0.4064)
			(end 0.7874 -0.4064)
			(stroke
				(width 0.1524)
				(type default)
			)
			(layer "F.SilkS")
		)
		(fp_line
			(start 0.7874 -0.4064)
			(end 0.7874 0.4064)
			(stroke
				(width 0.1524)
				(type default)
			)
			(layer "F.SilkS")
		)
		(fp_line
			(start -0.67945 0.3048)
			(end -0.67945 -0.305054)
			(stroke
				(width 0.1)
				(type default)
			)
			(layer "F.Fab")
		)
		(fp_line
			(start -0.12065 0.3048)
			(end -0.67945 0.3048)
			(stroke
				(width 0.1)
				(type default)
			)
			(layer "F.Fab")
		)
		(fp_line
			(start 0.120396 0.3048)
			(end 0.120396 0.2794)
			(stroke
				(width 0.1)
				(type default)
			)
			(layer "F.Fab")
		)
		(fp_line
			(start 0.67945 0.3048)
			(end 0.120396 0.3048)
			(stroke
				(width 0.1)
				(type default)
			)
			(layer "F.Fab")
		)
		(fp_line
			(start -0.12065 0.2794)
			(end -0.12065 0.3048)
			(stroke
				(width 0.1)
				(type default)
			)
			(layer "F.Fab")
		)
		(fp_line
			(start 0.120396 0.2794)
			(end -0.12065 0.2794)
			(stroke
				(width 0.1)
				(type default)
			)
			(layer "F.Fab")
		)
		(fp_line
			(start -0.12065 -0.2794)
			(end 0.12065 -0.2794)
			(stroke
				(width 0.1)
				(type default)
			)
			(layer "F.Fab")
		)
		(fp_line
			(start 0.12065 -0.2794)
			(end 0.12065 -0.3048)
			(stroke
				(width 0.1)
				(type default)
			)
			(layer "F.Fab")
		)
		(fp_line
			(start 0.12065 -0.3048)
			(end 0.67945 -0.3048)
			(stroke
				(width 0.1)
				(type default)
			)
			(layer "F.Fab")
		)
		(fp_line
			(start 0.67945 -0.3048)
			(end 0.67945 0.3048)
			(stroke
				(width 0.1)
				(type default)
			)
			(layer "F.Fab")
		)
		(fp_line
			(start -0.67945 -0.305054)
			(end -0.12065 -0.305054)
			(stroke
				(width 0.1)
				(type default)
			)
			(layer "F.Fab")
		)
		(fp_line
			(start -0.12065 -0.305054)
			(end -0.12065 -0.2794)
			(stroke
				(width 0.1)
				(type default)
			)
			(layer "F.Fab")
		)
		(pad "1" smd circle
			(at -0.40005 0 270)
			(size 0 0)
			(layers "F.Cu" "F.Mask" "F.Paste")
			(net "PWRGD_CPU0_PWROK")
		)
		(pad "2" smd circle
			(at 0.40005 0 270)
			(size 0 0)
			(layers "F.Cu" "F.Mask" "F.Paste")
			(net "GND")
		)
	)
	(footprint ""
		(layer "F.Cu")
		(at 405.764746 -142.871952 -90)
		(property "Reference" "C1170"
			(at 0 0 270)
			(layer "F.SilkS")
			(hide yes)
			(effects
				(font
					(size 1.27 1.27)
				)
			)
		)
		(property "Value" ""
			(at 0 0 270)
			(layer "F.Fab")
			(effects
				(font
					(size 1.27 1.27)
				)
			)
		)
		(duplicate_pad_numbers_are_jumpers no)
		(fp_line
			(start -1.524 0.762)
			(end -1.524 -0.762)
			(stroke
				(width 0.1524)
				(type default)
			)
			(layer "F.SilkS")
		)
		(fp_line
			(start 1.524 0.762)
			(end -1.524 0.762)
			(stroke
				(width 0.1524)
				(type default)
			)
			(layer "F.SilkS")
		)
		(fp_line
			(start -1.524 -0.762)
			(end 1.524 -0.762)
			(stroke
				(width 0.1524)
				(type default)
			)
			(layer "F.SilkS")
		)
		(fp_line
			(start 1.524 -0.762)
			(end 1.524 0.762)
			(stroke
				(width 0.1524)
				(type default)
			)
			(layer "F.SilkS")
		)
		(fp_line
			(start -1.1049 0.724916)
			(end 1.1049 0.724916)
			(stroke
				(width 0.1)
				(type default)
			)
			(layer "F.Fab")
		)
		(fp_line
			(start 1.1049 0.724916)
			(end 1.1049 -0.724916)
			(stroke
				(width 0.1)
				(type default)
			)
			(layer "F.Fab")
		)
		(fp_line
			(start -1.1049 -0.724916)
			(end -1.1049 0.724916)
			(stroke
				(width 0.1)
				(type default)
			)
			(layer "F.Fab")
		)
		(fp_line
			(start 1.1049 -0.724916)
			(end -1.1049 -0.724916)
			(stroke
				(width 0.1)
				(type default)
			)
			(layer "F.Fab")
		)
		(pad "1" smd rect
			(at -0.889 0 90)
			(size 1.016 1.27)
			(layers "F.Cu" "F.Mask" "F.Paste")
			(net "P5V_AUX")
		)
		(pad "2" smd rect
			(at 0.889 0 90)
			(size 1.016 1.27)
			(layers "F.Cu" "F.Mask" "F.Paste")
			(net "GND")
		)
	)
	(footprint ""
		(layer "F.Cu")
		(at 115.010946 -53.49748 180)
		(property "Reference" "R6296"
			(at 0 0 180)
			(layer "F.SilkS")
			(hide yes)
			(effects
				(font
					(size 1.27 1.27)
				)
			)
		)
		(property "Value" ""
			(at 0 0 180)
			(layer "F.Fab")
			(effects
				(font
					(size 1.27 1.27)
				)
			)
		)
		(duplicate_pad_numbers_are_jumpers no)
		(fp_line
			(start 0.7874 0.4064)
			(end -0.7874 0.4064)
			(stroke
				(width 0.1524)
				(type default)
			)
			(layer "F.SilkS")
		)
		(fp_line
			(start 0.7874 -0.4064)
			(end 0.7874 0.4064)
			(stroke
				(width 0.1524)
				(type default)
			)
			(layer "F.SilkS")
		)
		(fp_line
			(start -0.7874 0.4064)
			(end -0.7874 -0.4064)
			(stroke
				(width 0.1524)
				(type default)
			)
			(layer "F.SilkS")
		)
		(fp_line
			(start -0.7874 -0.4064)
			(end 0.7874 -0.4064)
			(stroke
				(width 0.1524)
				(type default)
			)
			(layer "F.SilkS")
		)
		(fp_line
			(start 0.67945 0.3048)
			(end 0.120396 0.3048)
			(stroke
				(width 0.1)
				(type default)
			)
			(layer "F.Fab")
		)
		(fp_line
			(start 0.67945 -0.3048)
			(end 0.67945 0.3048)
			(stroke
				(width 0.1)
				(type default)
			)
			(layer "F.Fab")
		)
		(fp_line
			(start 0.12065 -0.2794)
			(end 0.12065 -0.3048)
			(stroke
				(width 0.1)
				(type default)
			)
			(layer "F.Fab")
		)
		(fp_line
			(start 0.12065 -0.3048)
			(end 0.67945 -0.3048)
			(stroke
				(width 0.1)
				(type default)
			)
			(layer "F.Fab")
		)
		(fp_line
			(start 0.120396 0.3048)
			(end 0.120396 0.2794)
			(stroke
				(width 0.1)
				(type default)
			)
			(layer "F.Fab")
		)
		(fp_line
			(start 0.120396 0.2794)
			(end -0.12065 0.2794)
			(stroke
				(width 0.1)
				(type default)
			)
			(layer "F.Fab")
		)
		(fp_line
			(start -0.12065 0.3048)
			(end -0.67945 0.3048)
			(stroke
				(width 0.1)
				(type default)
			)
			(layer "F.Fab")
		)
		(fp_line
			(start -0.12065 0.2794)
			(end -0.12065 0.3048)
			(stroke
				(width 0.1)
				(type default)
			)
			(layer "F.Fab")
		)
		(fp_line
			(start -0.12065 -0.2794)
			(end 0.12065 -0.2794)
			(stroke
				(width 0.1)
				(type default)
			)
			(layer "F.Fab")
		)
		(fp_line
			(start -0.12065 -0.305054)
			(end -0.12065 -0.2794)
			(stroke
				(width 0.1)
				(type default)
			)
			(layer "F.Fab")
		)
		(fp_line
			(start -0.67945 0.3048)
			(end -0.67945 -0.305054)
			(stroke
				(width 0.1)
				(type default)
			)
			(layer "F.Fab")
		)
		(fp_line
			(start -0.67945 -0.305054)
			(end -0.12065 -0.305054)
			(stroke
				(width 0.1)
				(type default)
			)
			(layer "F.Fab")
		)
		(pad "1" smd circle
			(at -0.40005 0 180)
			(size 0 0)
			(layers "F.Cu" "F.Mask" "F.Paste")
			(net "USB_HUB2_MRP_I2C_SLV_CFG1")
		)
		(pad "2" smd circle
			(at 0.40005 0 180)
			(size 0 0)
			(layers "F.Cu" "F.Mask" "F.Paste")
			(net "USB_HUB2_TI_OVERCUR4_MRP_I2C_SLV_CFG1")
		)
	)
	(footprint ""
		(layer "F.Cu")
		(at 200.939908 -108.545376 180)
		(property "Reference" "R209"
			(at 0 0 180)
			(layer "F.SilkS")
			(hide yes)
			(effects
				(font
					(size 1.27 1.27)
				)
			)
		)
		(property "Value" ""
			(at 0 0 180)
			(layer "F.Fab")
			(effects
				(font
					(size 1.27 1.27)
				)
			)
		)
		(duplicate_pad_numbers_are_jumpers no)
		(fp_line
			(start 0.7874 0.4064)
			(end -0.7874 0.4064)
			(stroke
				(width 0.1524)
				(type default)
			)
			(layer "F.SilkS")
		)
		(fp_line
			(start 0.7874 -0.4064)
			(end 0.7874 0.4064)
			(stroke
				(width 0.1524)
				(type default)
			)
			(layer "F.SilkS")
		)
		(fp_line
			(start -0.7874 0.4064)
			(end -0.7874 -0.4064)
			(stroke
				(width 0.1524)
				(type default)
			)
			(layer "F.SilkS")
		)
		(fp_line
			(start -0.7874 -0.4064)
			(end 0.7874 -0.4064)
			(stroke
				(width 0.1524)
				(type default)
			)
			(layer "F.SilkS")
		)
		(fp_line
			(start 0.67945 0.3048)
			(end 0.120396 0.3048)
			(stroke
				(width 0.1)
				(type default)
			)
			(layer "F.Fab")
		)
		(fp_line
			(start 0.67945 -0.3048)
			(end 0.67945 0.3048)
			(stroke
				(width 0.1)
				(type default)
			)
			(layer "F.Fab")
		)
		(fp_line
			(start 0.12065 -0.2794)
			(end 0.12065 -0.3048)
			(stroke
				(width 0.1)
				(type default)
			)
			(layer "F.Fab")
		)
		(fp_line
			(start 0.12065 -0.3048)
			(end 0.67945 -0.3048)
			(stroke
				(width 0.1)
				(type default)
			)
			(layer "F.Fab")
		)
		(fp_line
			(start 0.120396 0.3048)
			(end 0.120396 0.2794)
			(stroke
				(width 0.1)
				(type default)
			)
			(layer "F.Fab")
		)
		(fp_line
			(start 0.120396 0.2794)
			(end -0.12065 0.2794)
			(stroke
				(width 0.1)
				(type default)
			)
			(layer "F.Fab")
		)
		(fp_line
			(start -0.12065 0.3048)
			(end -0.67945 0.3048)
			(stroke
				(width 0.1)
				(type default)
			)
			(layer "F.Fab")
		)
		(fp_line
			(start -0.12065 0.2794)
			(end -0.12065 0.3048)
			(stroke
				(width 0.1)
				(type default)
			)
			(layer "F.Fab")
		)
		(fp_line
			(start -0.12065 -0.2794)
			(end 0.12065 -0.2794)
			(stroke
				(width 0.1)
				(type default)
			)
			(layer "F.Fab")
		)
		(fp_line
			(start -0.12065 -0.305054)
			(end -0.12065 -0.2794)
			(stroke
				(width 0.1)
				(type default)
			)
			(layer "F.Fab")
		)
		(fp_line
			(start -0.67945 0.3048)
			(end -0.67945 -0.305054)
			(stroke
				(width 0.1)
				(type default)
			)
			(layer "F.Fab")
		)
		(fp_line
			(start -0.67945 -0.305054)
			(end -0.12065 -0.305054)
			(stroke
				(width 0.1)
				(type default)
			)
			(layer "F.Fab")
		)
		(pad "1" smd circle
			(at -0.40005 0 180)
			(size 0 0)
			(layers "F.Cu" "F.Mask" "F.Paste")
			(net "PWRGD_PVDDCR_CPU0_P1")
		)
		(pad "2" smd circle
			(at 0.40005 0 180)
			(size 0 0)
			(layers "F.Cu" "F.Mask" "F.Paste")
			(net "FM_PWRGD_PVDDCR_CPU0_P1")
		)
	)
	(footprint ""
		(layer "F.Cu")
		(at 49.38268 -36.820348)
		(property "Reference" "R3207"
			(at 0 0 0)
			(layer "F.SilkS")
			(hide yes)
			(effects
				(font
					(size 1.27 1.27)
				)
			)
		)
		(property "Value" ""
			(at 0 0 0)
			(layer "F.Fab")
			(effects
				(font
					(size 1.27 1.27)
				)
			)
		)
		(duplicate_pad_numbers_are_jumpers no)
		(fp_line
			(start -0.7874 -0.4064)
			(end 0.7874 -0.4064)
			(stroke
				(width 0.1524)
				(type default)
			)
			(layer "F.SilkS")
		)
		(fp_line
			(start -0.7874 0.4064)
			(end -0.7874 -0.4064)
			(stroke
				(width 0.1524)
				(type default)
			)
			(layer "F.SilkS")
		)
		(fp_line
			(start 0.7874 -0.4064)
			(end 0.7874 0.4064)
			(stroke
				(width 0.1524)
				(type default)
			)
			(layer "F.SilkS")
		)
		(fp_line
			(start 0.7874 0.4064)
			(end -0.7874 0.4064)
			(stroke
				(width 0.1524)
				(type default)
			)
			(layer "F.SilkS")
		)
		(fp_line
			(start -0.67945 -0.305054)
			(end -0.12065 -0.305054)
			(stroke
				(width 0.1)
				(type default)
			)
			(layer "F.Fab")
		)
		(fp_line
			(start -0.67945 0.3048)
			(end -0.67945 -0.305054)
			(stroke
				(width 0.1)
				(type default)
			)
			(layer "F.Fab")
		)
		(fp_line
			(start -0.12065 -0.305054)
			(end -0.12065 -0.2794)
			(stroke
				(width 0.1)
				(type default)
			)
			(layer "F.Fab")
		)
		(fp_line
			(start -0.12065 -0.2794)
			(end 0.12065 -0.2794)
			(stroke
				(width 0.1)
				(type default)
			)
			(layer "F.Fab")
		)
		(fp_line
			(start -0.12065 0.2794)
			(end -0.12065 0.3048)
			(stroke
				(width 0.1)
				(type default)
			)
			(layer "F.Fab")
		)
		(fp_line
			(start -0.12065 0.3048)
			(end -0.67945 0.3048)
			(stroke
				(width 0.1)
				(type default)
			)
			(layer "F.Fab")
		)
		(fp_line
			(start 0.120396 0.2794)
			(end -0.12065 0.2794)
			(stroke
				(width 0.1)
				(type default)
			)
			(layer "F.Fab")
		)
		(fp_line
			(start 0.120396 0.3048)
			(end 0.120396 0.2794)
			(stroke
				(width 0.1)
				(type default)
			)
			(layer "F.Fab")
		)
		(fp_line
			(start 0.12065 -0.3048)
			(end 0.67945 -0.3048)
			(stroke
				(width 0.1)
				(type default)
			)
			(layer "F.Fab")
		)
		(fp_line
			(start 0.12065 -0.2794)
			(end 0.12065 -0.3048)
			(stroke
				(width 0.1)
				(type default)
			)
			(layer "F.Fab")
		)
		(fp_line
			(start 0.67945 -0.3048)
			(end 0.67945 0.3048)
			(stroke
				(width 0.1)
				(type default)
			)
			(layer "F.Fab")
		)
		(fp_line
			(start 0.67945 0.3048)
			(end 0.120396 0.3048)
			(stroke
				(width 0.1)
				(type default)
			)
			(layer "F.Fab")
		)
		(pad "1" smd circle
			(at -0.40005 0)
			(size 0 0)
			(layers "F.Cu" "F.Mask" "F.Paste")
			(net "FB_BMC_ISOLATE1")
		)
		(pad "2" smd circle
			(at 0.40005 0)
			(size 0 0)
			(layers "F.Cu" "F.Mask" "F.Paste")
			(net "GND")
		)
	)
	(footprint ""
		(layer "F.Cu")
		(at 423.23766 -365.812578 90)
		(property "Reference" "PC4"
			(at 0 0 90)
			(layer "F.SilkS")
			(hide yes)
			(effects
				(font
					(size 1.27 1.27)
				)
			)
		)
		(property "Value" ""
			(at 0 0 90)
			(layer "F.Fab")
			(effects
				(font
					(size 1.27 1.27)
				)
			)
		)
		(duplicate_pad_numbers_are_jumpers no)
		(fp_line
			(start 0.7874 -0.4064)
			(end 0.7874 0.4064)
			(stroke
				(width 0.1524)
				(type default)
			)
			(layer "F.SilkS")
		)
		(fp_line
			(start -0.7874 -0.4064)
			(end 0.7874 -0.4064)
			(stroke
				(width 0.1524)
				(type default)
			)
			(layer "F.SilkS")
		)
		(fp_line
			(start 0.7874 0.4064)
			(end -0.7874 0.4064)
			(stroke
				(width 0.1524)
				(type default)
			)
			(layer "F.SilkS")
		)
		(fp_line
			(start -0.7874 0.4064)
			(end -0.7874 -0.4064)
			(stroke
				(width 0.1524)
				(type default)
			)
			(layer "F.SilkS")
		)
		(fp_line
			(start -0.12065 -0.305054)
			(end -0.12065 -0.2794)
			(stroke
				(width 0.1)
				(type default)
			)
			(layer "F.Fab")
		)
		(fp_line
			(start -0.67945 -0.305054)
			(end -0.12065 -0.305054)
			(stroke
				(width 0.1)
				(type default)
			)
			(layer "F.Fab")
		)
		(fp_line
			(start 0.67945 -0.3048)
			(end 0.67945 0.3048)
			(stroke
				(width 0.1)
				(type default)
			)
			(layer "F.Fab")
		)
		(fp_line
			(start 0.12065 -0.3048)
			(end 0.67945 -0.3048)
			(stroke
				(width 0.1)
				(type default)
			)
			(layer "F.Fab")
		)
		(fp_line
			(start 0.12065 -0.2794)
			(end 0.12065 -0.3048)
			(stroke
				(width 0.1)
				(type default)
			)
			(layer "F.Fab")
		)
		(fp_line
			(start -0.12065 -0.2794)
			(end 0.12065 -0.2794)
			(stroke
				(width 0.1)
				(type default)
			)
			(layer "F.Fab")
		)
		(fp_line
			(start 0.120396 0.2794)
			(end -0.12065 0.2794)
			(stroke
				(width 0.1)
				(type default)
			)
			(layer "F.Fab")
		)
		(fp_line
			(start -0.12065 0.2794)
			(end -0.12065 0.3048)
			(stroke
				(width 0.1)
				(type default)
			)
			(layer "F.Fab")
		)
		(fp_line
			(start 0.67945 0.3048)
			(end 0.120396 0.3048)
			(stroke
				(width 0.1)
				(type default)
			)
			(layer "F.Fab")
		)
		(fp_line
			(start 0.120396 0.3048)
			(end 0.120396 0.2794)
			(stroke
				(width 0.1)
				(type default)
			)
			(layer "F.Fab")
		)
		(fp_line
			(start -0.12065 0.3048)
			(end -0.67945 0.3048)
			(stroke
				(width 0.1)
				(type default)
			)
			(layer "F.Fab")
		)
		(fp_line
			(start -0.67945 0.3048)
			(end -0.67945 -0.305054)
			(stroke
				(width 0.1)
				(type default)
			)
			(layer "F.Fab")
		)
		(pad "1" smd circle
			(at -0.40005 0 90)
			(size 0 0)
			(layers "F.Cu" "F.Mask" "F.Paste")
			(net "PVDD11_S3_P0_VCC")
		)
		(pad "2" smd circle
			(at 0.40005 0 90)
			(size 0 0)
			(layers "F.Cu" "F.Mask" "F.Paste")
			(net "GND")
		)
	)
	(footprint ""
		(layer "F.Cu")
		(at 425.05249 -57.047638)
		(property "Reference" "U124"
			(at -2.032 -2.377948 0)
			(unlocked yes)
			(layer "F.SilkS")
			(effects
				(font
					(size 0.7874 0.5842)
					(thickness 0.1524)
				)
				(justify left)
			)
		)
		(property "Value" ""
			(at 0 0 0)
			(layer "F.Fab")
			(effects
				(font
					(size 1.27 1.27)
				)
			)
		)
		(duplicate_pad_numbers_are_jumpers no)
		(fp_line
			(start -2.0574 -1.651)
			(end -0.381 -1.651)
			(stroke
				(width 0.1524)
				(type default)
			)
			(layer "F.SilkS")
		)
		(fp_line
			(start -2.0574 1.651)
			(end -2.0574 -1.651)
			(stroke
				(width 0.1524)
				(type default)
			)
			(layer "F.SilkS")
		)
		(fp_line
			(start -0.381 -1.651)
			(end 0 -1.016)
			(stroke
				(width 0.1524)
				(type default)
			)
			(layer "F.SilkS")
		)
		(fp_line
			(start 0 -1.016)
			(end 0.381 -1.651)
			(stroke
				(width 0.1524)
				(type default)
			)
			(layer "F.SilkS")
		)
		(fp_line
			(start 0.381 -1.651)
			(end 2.0574 -1.651)
			(stroke
				(width 0.1524)
				(type default)
			)
			(layer "F.SilkS")
		)
		(fp_line
			(start 2.0574 -1.651)
			(end 2.0574 1.651)
			(stroke
				(width 0.1524)
				(type default)
			)
			(layer "F.SilkS")
		)
		(fp_line
			(start 2.0574 1.651)
			(end -2.0574 1.651)
			(stroke
				(width 0.1524)
				(type default)
			)
			(layer "F.SilkS")
		)
		(fp_poly
			(pts
				(xy -2.511806 -1.813052) (xy -3.113278 -1.994662) (xy -2.671318 -2.436622)
			)
			(stroke
				(width 0)
				(type default)
			)
			(fill yes)
			(layer "F.SilkS")
		)
		(fp_line
			(start -1.599946 -1.199896)
			(end -0.899922 -1.199896)
			(stroke
				(width 0.1)
				(type default)
			)
			(layer "F.Fab")
		)
		(fp_line
			(start -1.599946 1.199896)
			(end -1.599946 -1.199896)
			(stroke
				(width 0.1)
				(type default)
			)
			(layer "F.Fab")
		)
		(fp_line
			(start -0.899922 -1.549908)
			(end 0.899922 -1.549908)
			(stroke
				(width 0.1)
				(type default)
			)
			(layer "F.Fab")
		)
		(fp_line
			(start -0.899922 -1.199896)
			(end -0.899922 -1.549908)
			(stroke
				(width 0.1)
				(type default)
			)
			(layer "F.Fab")
		)
		(fp_line
			(start -0.899922 1.199896)
			(end -1.599946 1.199896)
			(stroke
				(width 0.1)
				(type default)
			)
			(layer "F.Fab")
		)
		(fp_line
			(start -0.899922 1.549908)
			(end -0.899922 1.199896)
			(stroke
				(width 0.1)
				(type default)
			)
			(layer "F.Fab")
		)
		(fp_line
			(start 0.899922 -1.549908)
			(end 0.899922 -1.199896)
			(stroke
				(width 0.1)
				(type default)
			)
			(layer "F.Fab")
		)
		(fp_line
			(start 0.899922 -1.199896)
			(end 1.599946 -1.199896)
			(stroke
				(width 0.1)
				(type default)
			)
			(layer "F.Fab")
		)
		(fp_line
			(start 0.899922 1.199896)
			(end 0.899922 1.549908)
			(stroke
				(width 0.1)
				(type default)
			)
			(layer "F.Fab")
		)
		(fp_line
			(start 0.899922 1.549908)
			(end -0.899922 1.549908)
			(stroke
				(width 0.1)
				(type default)
			)
			(layer "F.Fab")
		)
		(fp_line
			(start 1.599946 -1.199896)
			(end 1.599946 1.199896)
			(stroke
				(width 0.1)
				(type default)
			)
			(layer "F.Fab")
		)
		(fp_line
			(start 1.599946 1.199896)
			(end 0.899922 1.199896)
			(stroke
				(width 0.1)
				(type default)
			)
			(layer "F.Fab")
		)
		(fp_poly
			(pts
				(xy -2.71272 -0.719328) (xy -2.71272 -1.344168) (xy -2.159 -1.016)
			)
			(stroke
				(width 0)
				(type default)
			)
			(fill yes)
			(layer "F.Fab")
		)
		(pad "1" smd rect
			(at -1.225042 -0.94996 270)
			(size 0.5588 1.3462)
			(layers "F.Cu" "F.Mask" "F.Paste")
			(net "Net_10728")
		)
		(pad "2" smd rect
			(at -1.225042 0 270)
			(size 0.5588 1.3462)
			(layers "F.Cu" "F.Mask" "F.Paste")
			(net "FM_JTAG_BMC_R_OE")
		)
		(pad "3" smd rect
			(at -1.225042 0.94996 270)
			(size 0.5588 1.3462)
			(layers "F.Cu" "F.Mask" "F.Paste")
			(net "GND")
		)
		(pad "4" smd rect
			(at 1.225042 0.94996 270)
			(size 0.5588 1.3462)
			(layers "F.Cu" "F.Mask" "F.Paste")
			(net "JTAG_BMC_OE")
		)
		(pad "5" smd rect
			(at 1.225042 -0.94996 270)
			(size 0.5588 1.3462)
			(layers "F.Cu" "F.Mask" "F.Paste")
			(net "U124_VCC")
		)
	)
	(footprint ""
		(layer "F.Cu")
		(at 115.315238 -41.17975 -90)
		(property "Reference" "R6283"
			(at 0 0 270)
			(layer "F.SilkS")
			(hide yes)
			(effects
				(font
					(size 1.27 1.27)
				)
			)
		)
		(property "Value" ""
			(at 0 0 270)
			(layer "F.Fab")
			(effects
				(font
					(size 1.27 1.27)
				)
			)
		)
		(duplicate_pad_numbers_are_jumpers no)
		(fp_line
			(start -0.7874 0.4064)
			(end -0.7874 -0.4064)
			(stroke
				(width 0.1524)
				(type default)
			)
			(layer "F.SilkS")
		)
		(fp_line
			(start 0.7874 0.4064)
			(end -0.7874 0.4064)
			(stroke
				(width 0.1524)
				(type default)
			)
			(layer "F.SilkS")
		)
		(fp_line
			(start -0.7874 -0.4064)
			(end 0.7874 -0.4064)
			(stroke
				(width 0.1524)
				(type default)
			)
			(layer "F.SilkS")
		)
		(fp_line
			(start 0.7874 -0.4064)
			(end 0.7874 0.4064)
			(stroke
				(width 0.1524)
				(type default)
			)
			(layer "F.SilkS")
		)
		(fp_line
			(start -0.67945 0.3048)
			(end -0.67945 -0.305054)
			(stroke
				(width 0.1)
				(type default)
			)
			(layer "F.Fab")
		)
		(fp_line
			(start -0.12065 0.3048)
			(end -0.67945 0.3048)
			(stroke
				(width 0.1)
				(type default)
			)
			(layer "F.Fab")
		)
		(fp_line
			(start 0.120396 0.3048)
			(end 0.120396 0.2794)
			(stroke
				(width 0.1)
				(type default)
			)
			(layer "F.Fab")
		)
		(fp_line
			(start 0.67945 0.3048)
			(end 0.120396 0.3048)
			(stroke
				(width 0.1)
				(type default)
			)
			(layer "F.Fab")
		)
		(fp_line
			(start -0.12065 0.2794)
			(end -0.12065 0.3048)
			(stroke
				(width 0.1)
				(type default)
			)
			(layer "F.Fab")
		)
		(fp_line
			(start 0.120396 0.2794)
			(end -0.12065 0.2794)
			(stroke
				(width 0.1)
				(type default)
			)
			(layer "F.Fab")
		)
		(fp_line
			(start -0.12065 -0.2794)
			(end 0.12065 -0.2794)
			(stroke
				(width 0.1)
				(type default)
			)
			(layer "F.Fab")
		)
		(fp_line
			(start 0.12065 -0.2794)
			(end 0.12065 -0.3048)
			(stroke
				(width 0.1)
				(type default)
			)
			(layer "F.Fab")
		)
		(fp_line
			(start 0.12065 -0.3048)
			(end 0.67945 -0.3048)
			(stroke
				(width 0.1)
				(type default)
			)
			(layer "F.Fab")
		)
		(fp_line
			(start 0.67945 -0.3048)
			(end 0.67945 0.3048)
			(stroke
				(width 0.1)
				(type default)
			)
			(layer "F.Fab")
		)
		(fp_line
			(start -0.67945 -0.305054)
			(end -0.12065 -0.305054)
			(stroke
				(width 0.1)
				(type default)
			)
			(layer "F.Fab")
		)
		(fp_line
			(start -0.12065 -0.305054)
			(end -0.12065 -0.2794)
			(stroke
				(width 0.1)
				(type default)
			)
			(layer "F.Fab")
		)
		(pad "1" smd circle
			(at -0.40005 0 270)
			(size 0 0)
			(layers "F.Cu" "F.Mask" "F.Paste")
			(net "P3V3_AUX")
		)
		(pad "2" smd circle
			(at 0.40005 0 270)
			(size 0 0)
			(layers "F.Cu" "F.Mask" "F.Paste")
			(net "USB_HUB2_TI_FULLPWRMGMTZ_MRP_PROG_FUNC3")
		)
	)
	(footprint ""
		(layer "F.Cu")
		(at 157.677358 -352.229928)
		(property "Reference" "R8380"
			(at 0 0 0)
			(layer "F.SilkS")
			(hide yes)
			(effects
				(font
					(size 1.27 1.27)
				)
			)
		)
		(property "Value" ""
			(at 0 0 0)
			(layer "F.Fab")
			(effects
				(font
					(size 1.27 1.27)
				)
			)
		)
		(duplicate_pad_numbers_are_jumpers no)
		(fp_line
			(start -0.7874 -0.4064)
			(end 0.7874 -0.4064)
			(stroke
				(width 0.1524)
				(type default)
			)
			(layer "F.SilkS")
		)
		(fp_line
			(start -0.7874 0.4064)
			(end -0.7874 -0.4064)
			(stroke
				(width 0.1524)
				(type default)
			)
			(layer "F.SilkS")
		)
		(fp_line
			(start 0.7874 -0.4064)
			(end 0.7874 0.4064)
			(stroke
				(width 0.1524)
				(type default)
			)
			(layer "F.SilkS")
		)
		(fp_line
			(start 0.7874 0.4064)
			(end -0.7874 0.4064)
			(stroke
				(width 0.1524)
				(type default)
			)
			(layer "F.SilkS")
		)
		(fp_line
			(start -0.67945 -0.305054)
			(end -0.12065 -0.305054)
			(stroke
				(width 0.1)
				(type default)
			)
			(layer "F.Fab")
		)
		(fp_line
			(start -0.67945 0.3048)
			(end -0.67945 -0.305054)
			(stroke
				(width 0.1)
				(type default)
			)
			(layer "F.Fab")
		)
		(fp_line
			(start -0.12065 -0.305054)
			(end -0.12065 -0.2794)
			(stroke
				(width 0.1)
				(type default)
			)
			(layer "F.Fab")
		)
		(fp_line
			(start -0.12065 -0.2794)
			(end 0.12065 -0.2794)
			(stroke
				(width 0.1)
				(type default)
			)
			(layer "F.Fab")
		)
		(fp_line
			(start -0.12065 0.2794)
			(end -0.12065 0.3048)
			(stroke
				(width 0.1)
				(type default)
			)
			(layer "F.Fab")
		)
		(fp_line
			(start -0.12065 0.3048)
			(end -0.67945 0.3048)
			(stroke
				(width 0.1)
				(type default)
			)
			(layer "F.Fab")
		)
		(fp_line
			(start 0.120396 0.2794)
			(end -0.12065 0.2794)
			(stroke
				(width 0.1)
				(type default)
			)
			(layer "F.Fab")
		)
		(fp_line
			(start 0.120396 0.3048)
			(end 0.120396 0.2794)
			(stroke
				(width 0.1)
				(type default)
			)
			(layer "F.Fab")
		)
		(fp_line
			(start 0.12065 -0.3048)
			(end 0.67945 -0.3048)
			(stroke
				(width 0.1)
				(type default)
			)
			(layer "F.Fab")
		)
		(fp_line
			(start 0.12065 -0.2794)
			(end 0.12065 -0.3048)
			(stroke
				(width 0.1)
				(type default)
			)
			(layer "F.Fab")
		)
		(fp_line
			(start 0.67945 -0.3048)
			(end 0.67945 0.3048)
			(stroke
				(width 0.1)
				(type default)
			)
			(layer "F.Fab")
		)
		(fp_line
			(start 0.67945 0.3048)
			(end 0.120396 0.3048)
			(stroke
				(width 0.1)
				(type default)
			)
			(layer "F.Fab")
		)
		(pad "1" smd circle
			(at -0.40005 0)
			(size 0 0)
			(layers "F.Cu" "F.Mask" "F.Paste")
			(net "P3V3_AUX")
		)
		(pad "2" smd circle
			(at 0.40005 0)
			(size 0 0)
			(layers "F.Cu" "F.Mask" "F.Paste")
			(net "PWRGD_PVDD11_S3_P1_R")
		)
	)
	(footprint ""
		(layer "F.Cu")
		(at 111.76 -406.4508)
		(property "Reference" "R592"
			(at 0 0 0)
			(layer "F.SilkS")
			(hide yes)
			(effects
				(font
					(size 1.27 1.27)
				)
			)
		)
		(property "Value" ""
			(at 0 0 0)
			(layer "F.Fab")
			(effects
				(font
					(size 1.27 1.27)
				)
			)
		)
		(duplicate_pad_numbers_are_jumpers no)
		(fp_line
			(start -0.7874 -0.4064)
			(end 0.7874 -0.4064)
			(stroke
				(width 0.1524)
				(type default)
			)
			(layer "F.SilkS")
		)
		(fp_line
			(start -0.7874 0.4064)
			(end -0.7874 -0.4064)
			(stroke
				(width 0.1524)
				(type default)
			)
			(layer "F.SilkS")
		)
		(fp_line
			(start 0.7874 -0.4064)
			(end 0.7874 0.4064)
			(stroke
				(width 0.1524)
				(type default)
			)
			(layer "F.SilkS")
		)
		(fp_line
			(start 0.7874 0.4064)
			(end -0.7874 0.4064)
			(stroke
				(width 0.1524)
				(type default)
			)
			(layer "F.SilkS")
		)
		(fp_line
			(start -0.67945 -0.305054)
			(end -0.12065 -0.305054)
			(stroke
				(width 0.1)
				(type default)
			)
			(layer "F.Fab")
		)
		(fp_line
			(start -0.67945 0.3048)
			(end -0.67945 -0.305054)
			(stroke
				(width 0.1)
				(type default)
			)
			(layer "F.Fab")
		)
		(fp_line
			(start -0.12065 -0.305054)
			(end -0.12065 -0.2794)
			(stroke
				(width 0.1)
				(type default)
			)
			(layer "F.Fab")
		)
		(fp_line
			(start -0.12065 -0.2794)
			(end 0.12065 -0.2794)
			(stroke
				(width 0.1)
				(type default)
			)
			(layer "F.Fab")
		)
		(fp_line
			(start -0.12065 0.2794)
			(end -0.12065 0.3048)
			(stroke
				(width 0.1)
				(type default)
			)
			(layer "F.Fab")
		)
		(fp_line
			(start -0.12065 0.3048)
			(end -0.67945 0.3048)
			(stroke
				(width 0.1)
				(type default)
			)
			(layer "F.Fab")
		)
		(fp_line
			(start 0.120396 0.2794)
			(end -0.12065 0.2794)
			(stroke
				(width 0.1)
				(type default)
			)
			(layer "F.Fab")
		)
		(fp_line
			(start 0.120396 0.3048)
			(end 0.120396 0.2794)
			(stroke
				(width 0.1)
				(type default)
			)
			(layer "F.Fab")
		)
		(fp_line
			(start 0.12065 -0.3048)
			(end 0.67945 -0.3048)
			(stroke
				(width 0.1)
				(type default)
			)
			(layer "F.Fab")
		)
		(fp_line
			(start 0.12065 -0.2794)
			(end 0.12065 -0.3048)
			(stroke
				(width 0.1)
				(type default)
			)
			(layer "F.Fab")
		)
		(fp_line
			(start 0.67945 -0.3048)
			(end 0.67945 0.3048)
			(stroke
				(width 0.1)
				(type default)
			)
			(layer "F.Fab")
		)
		(fp_line
			(start 0.67945 0.3048)
			(end 0.120396 0.3048)
			(stroke
				(width 0.1)
				(type default)
			)
			(layer "F.Fab")
		)
		(pad "1" smd circle
			(at -0.40005 0)
			(size 0 0)
			(layers "F.Cu" "F.Mask" "F.Paste")
			(net "FM_9ZXL045_P1_2_OE_N")
		)
		(pad "2" smd circle
			(at 0.40005 0)
			(size 0 0)
			(layers "F.Cu" "F.Mask" "F.Paste")
			(net "GND")
		)
	)
	(footprint ""
		(layer "F.Cu")
		(at 322.837048 -42.176954 180)
		(property "Reference" "R3684"
			(at 0 0 180)
			(layer "F.SilkS")
			(hide yes)
			(effects
				(font
					(size 1.27 1.27)
				)
			)
		)
		(property "Value" ""
			(at 0 0 180)
			(layer "F.Fab")
			(effects
				(font
					(size 1.27 1.27)
				)
			)
		)
		(duplicate_pad_numbers_are_jumpers no)
		(fp_line
			(start 0.7874 0.4064)
			(end -0.7874 0.4064)
			(stroke
				(width 0.1524)
				(type default)
			)
			(layer "F.SilkS")
		)
		(fp_line
			(start 0.7874 -0.4064)
			(end 0.7874 0.4064)
			(stroke
				(width 0.1524)
				(type default)
			)
			(layer "F.SilkS")
		)
		(fp_line
			(start -0.7874 0.4064)
			(end -0.7874 -0.4064)
			(stroke
				(width 0.1524)
				(type default)
			)
			(layer "F.SilkS")
		)
		(fp_line
			(start -0.7874 -0.4064)
			(end 0.7874 -0.4064)
			(stroke
				(width 0.1524)
				(type default)
			)
			(layer "F.SilkS")
		)
		(fp_line
			(start 0.67945 0.3048)
			(end 0.120396 0.3048)
			(stroke
				(width 0.1)
				(type default)
			)
			(layer "F.Fab")
		)
		(fp_line
			(start 0.67945 -0.3048)
			(end 0.67945 0.3048)
			(stroke
				(width 0.1)
				(type default)
			)
			(layer "F.Fab")
		)
		(fp_line
			(start 0.12065 -0.2794)
			(end 0.12065 -0.3048)
			(stroke
				(width 0.1)
				(type default)
			)
			(layer "F.Fab")
		)
		(fp_line
			(start 0.12065 -0.3048)
			(end 0.67945 -0.3048)
			(stroke
				(width 0.1)
				(type default)
			)
			(layer "F.Fab")
		)
		(fp_line
			(start 0.120396 0.3048)
			(end 0.120396 0.2794)
			(stroke
				(width 0.1)
				(type default)
			)
			(layer "F.Fab")
		)
		(fp_line
			(start 0.120396 0.2794)
			(end -0.12065 0.2794)
			(stroke
				(width 0.1)
				(type default)
			)
			(layer "F.Fab")
		)
		(fp_line
			(start -0.12065 0.3048)
			(end -0.67945 0.3048)
			(stroke
				(width 0.1)
				(type default)
			)
			(layer "F.Fab")
		)
		(fp_line
			(start -0.12065 0.2794)
			(end -0.12065 0.3048)
			(stroke
				(width 0.1)
				(type default)
			)
			(layer "F.Fab")
		)
		(fp_line
			(start -0.12065 -0.2794)
			(end 0.12065 -0.2794)
			(stroke
				(width 0.1)
				(type default)
			)
			(layer "F.Fab")
		)
		(fp_line
			(start -0.12065 -0.305054)
			(end -0.12065 -0.2794)
			(stroke
				(width 0.1)
				(type default)
			)
			(layer "F.Fab")
		)
		(fp_line
			(start -0.67945 0.3048)
			(end -0.67945 -0.305054)
			(stroke
				(width 0.1)
				(type default)
			)
			(layer "F.Fab")
		)
		(fp_line
			(start -0.67945 -0.305054)
			(end -0.12065 -0.305054)
			(stroke
				(width 0.1)
				(type default)
			)
			(layer "F.Fab")
		)
		(pad "1" smd rect
			(at -0.40005 0)
			(size 0.4572 0.508)
			(layers "F.Cu" "F.Mask" "F.Paste")
			(net "P3V3_ADC")
		)
		(pad "2" smd rect
			(at 0.40005 0)
			(size 0.4572 0.508)
			(layers "F.Cu" "F.Mask" "F.Paste")
			(net "P3V3_ADC_TIC")
		)
	)
	(footprint ""
		(layer "F.Cu")
		(at 24.765 -357.632)
		(property "Reference" "PR239"
			(at 0 0 0)
			(layer "F.SilkS")
			(hide yes)
			(effects
				(font
					(size 1.27 1.27)
				)
			)
		)
		(property "Value" ""
			(at 0 0 0)
			(layer "F.Fab")
			(effects
				(font
					(size 1.27 1.27)
				)
			)
		)
		(duplicate_pad_numbers_are_jumpers no)
		(fp_line
			(start -0.7874 -0.4064)
			(end 0.7874 -0.4064)
			(stroke
				(width 0.1524)
				(type default)
			)
			(layer "F.SilkS")
		)
		(fp_line
			(start -0.7874 0.4064)
			(end -0.7874 -0.4064)
			(stroke
				(width 0.1524)
				(type default)
			)
			(layer "F.SilkS")
		)
		(fp_line
			(start 0.7874 -0.4064)
			(end 0.7874 0.4064)
			(stroke
				(width 0.1524)
				(type default)
			)
			(layer "F.SilkS")
		)
		(fp_line
			(start 0.7874 0.4064)
			(end -0.7874 0.4064)
			(stroke
				(width 0.1524)
				(type default)
			)
			(layer "F.SilkS")
		)
		(fp_line
			(start -0.67945 -0.305054)
			(end -0.12065 -0.305054)
			(stroke
				(width 0.1)
				(type default)
			)
			(layer "F.Fab")
		)
		(fp_line
			(start -0.67945 0.3048)
			(end -0.67945 -0.305054)
			(stroke
				(width 0.1)
				(type default)
			)
			(layer "F.Fab")
		)
		(fp_line
			(start -0.12065 -0.305054)
			(end -0.12065 -0.2794)
			(stroke
				(width 0.1)
				(type default)
			)
			(layer "F.Fab")
		)
		(fp_line
			(start -0.12065 -0.2794)
			(end 0.12065 -0.2794)
			(stroke
				(width 0.1)
				(type default)
			)
			(layer "F.Fab")
		)
		(fp_line
			(start -0.12065 0.2794)
			(end -0.12065 0.3048)
			(stroke
				(width 0.1)
				(type default)
			)
			(layer "F.Fab")
		)
		(fp_line
			(start -0.12065 0.3048)
			(end -0.67945 0.3048)
			(stroke
				(width 0.1)
				(type default)
			)
			(layer "F.Fab")
		)
		(fp_line
			(start 0.120396 0.2794)
			(end -0.12065 0.2794)
			(stroke
				(width 0.1)
				(type default)
			)
			(layer "F.Fab")
		)
		(fp_line
			(start 0.120396 0.3048)
			(end 0.120396 0.2794)
			(stroke
				(width 0.1)
				(type default)
			)
			(layer "F.Fab")
		)
		(fp_line
			(start 0.12065 -0.3048)
			(end 0.67945 -0.3048)
			(stroke
				(width 0.1)
				(type default)
			)
			(layer "F.Fab")
		)
		(fp_line
			(start 0.12065 -0.2794)
			(end 0.12065 -0.3048)
			(stroke
				(width 0.1)
				(type default)
			)
			(layer "F.Fab")
		)
		(fp_line
			(start 0.67945 -0.3048)
			(end 0.67945 0.3048)
			(stroke
				(width 0.1)
				(type default)
			)
			(layer "F.Fab")
		)
		(fp_line
			(start 0.67945 0.3048)
			(end 0.120396 0.3048)
			(stroke
				(width 0.1)
				(type default)
			)
			(layer "F.Fab")
		)
		(pad "1" smd circle
			(at -0.40005 0)
			(size 0 0)
			(layers "F.Cu" "F.Mask" "F.Paste")
			(net "SVID_PVDDCR_CPU1_P1_SVTI")
		)
		(pad "2" smd circle
			(at 0.40005 0)
			(size 0 0)
			(layers "F.Cu" "F.Mask" "F.Paste")
			(net "SVID_PVDDCR_CPU1_P1_SVTI_R")
		)
	)
	(footprint ""
		(layer "F.Cu")
		(at 384.809492 -383.88163 -90)
		(property "Reference" "C881"
			(at 0 0 270)
			(layer "F.SilkS")
			(hide yes)
			(effects
				(font
					(size 1.27 1.27)
				)
			)
		)
		(property "Value" ""
			(at 0 0 270)
			(layer "F.Fab")
			(effects
				(font
					(size 1.27 1.27)
				)
			)
		)
		(duplicate_pad_numbers_are_jumpers no)
		(fp_line
			(start -0.299974 0.150114)
			(end -0.299974 -0.150114)
			(stroke
				(width 0.1)
				(type default)
			)
			(layer "F.Fab")
		)
		(fp_line
			(start 0.299974 0.150114)
			(end -0.299974 0.150114)
			(stroke
				(width 0.1)
				(type default)
			)
			(layer "F.Fab")
		)
		(fp_line
			(start -0.299974 -0.150114)
			(end 0.299974 -0.150114)
			(stroke
				(width 0.1)
				(type default)
			)
			(layer "F.Fab")
		)
		(fp_line
			(start 0.299974 -0.150114)
			(end 0.299974 0.150114)
			(stroke
				(width 0.1)
				(type default)
			)
			(layer "F.Fab")
		)
		(pad "1" smd rect
			(at -0.2667 0 270)
			(size 0.3048 0.381)
			(layers "F.Cu" "F.Mask" "F.Paste")
			(net "P5E_CPU0_P3_TX_C_DP<10>")
		)
		(pad "2" smd rect
			(at 0.2667 0 270)
			(size 0.3048 0.381)
			(layers "F.Cu" "F.Mask" "F.Paste")
			(net "P5E_CPU0_P3_TX_DP<10>")
		)
	)
	(footprint ""
		(layer "F.Cu")
		(at 479.262948 -23.903178)
		(property "Reference" "DB9"
			(at 1.276096 2.670556 0)
			(unlocked yes)
			(layer "F.SilkS")
			(effects
				(font
					(size 0.7874 0.5842)
					(thickness 0.1524)
				)
				(justify left)
			)
		)
		(property "Value" ""
			(at 0 0 0)
			(layer "F.Fab")
			(effects
				(font
					(size 1.27 1.27)
				)
			)
		)
		(duplicate_pad_numbers_are_jumpers no)
		(fp_line
			(start -3.330702 -4.771136)
			(end 3.330702 -4.771136)
			(stroke
				(width 0.1524)
				(type default)
			)
			(layer "F.SilkS")
		)
		(fp_line
			(start 0 4.011168)
			(end -3.330702 -4.771136)
			(stroke
				(width 0.1524)
				(type default)
			)
			(layer "F.SilkS")
		)
		(fp_line
			(start 3.330702 -4.771136)
			(end 0 4.011168)
			(stroke
				(width 0.1524)
				(type default)
			)
			(layer "F.SilkS")
		)
		(fp_line
			(start -3.330702 -4.771136)
			(end 3.330702 -4.771136)
			(stroke
				(width 0.1)
				(type default)
			)
			(layer "F.Fab")
		)
		(fp_line
			(start 0 4.011168)
			(end -3.330702 -4.771136)
			(stroke
				(width 0.1)
				(type default)
			)
			(layer "F.Fab")
		)
		(fp_line
			(start 3.330702 -4.771136)
			(end 0 4.011168)
			(stroke
				(width 0.1)
				(type default)
			)
			(layer "F.Fab")
		)
		(pad "1" thru_hole circle
			(at 0 0)
			(size 2.159 2.159)
			(drill 1.7018)
			(layers "*.Cu" "*.Mask")
			(remove_unused_layers no)
			(net "T1_GND")
			(clearance 0.0254)
			(thermal_gap 0.0254)
		)
		(pad "2" thru_hole circle
			(at -1.27 -3.348736)
			(size 2.159 2.159)
			(drill 1.7018)
			(layers "*.Cu" "*.Mask")
			(remove_unused_layers no)
			(net "TDR_SE_50_OHM_IN2")
			(clearance 0.0254)
			(thermal_gap 0.0254)
		)
		(pad "3" thru_hole circle
			(at 1.27 -3.348736)
			(size 2.159 2.159)
			(drill 1.7018)
			(layers "*.Cu" "*.Mask")
			(remove_unused_layers no)
			(net "TDR_SE_50_OHM_IN2")
			(clearance 0.0254)
			(thermal_gap 0.0254)
		)
	)
	(footprint ""
		(layer "F.Cu")
		(at 184.455054 -169.118026 -90)
		(property "Reference" "R1337"
			(at 0 0 270)
			(layer "F.SilkS")
			(hide yes)
			(effects
				(font
					(size 1.27 1.27)
				)
			)
		)
		(property "Value" ""
			(at 0 0 270)
			(layer "F.Fab")
			(effects
				(font
					(size 1.27 1.27)
				)
			)
		)
		(duplicate_pad_numbers_are_jumpers no)
		(fp_line
			(start -0.7874 0.4064)
			(end -0.7874 -0.4064)
			(stroke
				(width 0.1524)
				(type default)
			)
			(layer "F.SilkS")
		)
		(fp_line
			(start 0.7874 0.4064)
			(end -0.7874 0.4064)
			(stroke
				(width 0.1524)
				(type default)
			)
			(layer "F.SilkS")
		)
		(fp_line
			(start -0.7874 -0.4064)
			(end 0.7874 -0.4064)
			(stroke
				(width 0.1524)
				(type default)
			)
			(layer "F.SilkS")
		)
		(fp_line
			(start 0.7874 -0.4064)
			(end 0.7874 0.4064)
			(stroke
				(width 0.1524)
				(type default)
			)
			(layer "F.SilkS")
		)
		(fp_line
			(start -0.67945 0.3048)
			(end -0.67945 -0.305054)
			(stroke
				(width 0.1)
				(type default)
			)
			(layer "F.Fab")
		)
		(fp_line
			(start -0.12065 0.3048)
			(end -0.67945 0.3048)
			(stroke
				(width 0.1)
				(type default)
			)
			(layer "F.Fab")
		)
		(fp_line
			(start 0.120396 0.3048)
			(end 0.120396 0.2794)
			(stroke
				(width 0.1)
				(type default)
			)
			(layer "F.Fab")
		)
		(fp_line
			(start 0.67945 0.3048)
			(end 0.120396 0.3048)
			(stroke
				(width 0.1)
				(type default)
			)
			(layer "F.Fab")
		)
		(fp_line
			(start -0.12065 0.2794)
			(end -0.12065 0.3048)
			(stroke
				(width 0.1)
				(type default)
			)
			(layer "F.Fab")
		)
		(fp_line
			(start 0.120396 0.2794)
			(end -0.12065 0.2794)
			(stroke
				(width 0.1)
				(type default)
			)
			(layer "F.Fab")
		)
		(fp_line
			(start -0.12065 -0.2794)
			(end 0.12065 -0.2794)
			(stroke
				(width 0.1)
				(type default)
			)
			(layer "F.Fab")
		)
		(fp_line
			(start 0.12065 -0.2794)
			(end 0.12065 -0.3048)
			(stroke
				(width 0.1)
				(type default)
			)
			(layer "F.Fab")
		)
		(fp_line
			(start 0.12065 -0.3048)
			(end 0.67945 -0.3048)
			(stroke
				(width 0.1)
				(type default)
			)
			(layer "F.Fab")
		)
		(fp_line
			(start 0.67945 -0.3048)
			(end 0.67945 0.3048)
			(stroke
				(width 0.1)
				(type default)
			)
			(layer "F.Fab")
		)
		(fp_line
			(start -0.67945 -0.305054)
			(end -0.12065 -0.305054)
			(stroke
				(width 0.1)
				(type default)
			)
			(layer "F.Fab")
		)
		(fp_line
			(start -0.12065 -0.305054)
			(end -0.12065 -0.2794)
			(stroke
				(width 0.1)
				(type default)
			)
			(layer "F.Fab")
		)
		(pad "1" smd rect
			(at -0.40005 0 90)
			(size 0.4572 0.508)
			(layers "F.Cu" "F.Mask" "F.Paste")
			(net "I3C_SPD_DDRGL_CPU1_BYPASS_SDA")
		)
		(pad "2" smd rect
			(at 0.40005 0 90)
			(size 0.4572 0.508)
			(layers "F.Cu" "F.Mask" "F.Paste")
			(net "I3C_SPD_DDRGL_CPU1_SDA")
		)
	)
	(footprint ""
		(layer "F.Cu")
		(at 169.368724 -376.982228)
		(property "Reference" "C744"
			(at 0 0 0)
			(layer "F.SilkS")
			(hide yes)
			(effects
				(font
					(size 1.27 1.27)
				)
			)
		)
		(property "Value" ""
			(at 0 0 0)
			(layer "F.Fab")
			(effects
				(font
					(size 1.27 1.27)
				)
			)
		)
		(duplicate_pad_numbers_are_jumpers no)
		(fp_line
			(start -0.299974 -0.150114)
			(end 0.299974 -0.150114)
			(stroke
				(width 0.1)
				(type default)
			)
			(layer "F.Fab")
		)
		(fp_line
			(start -0.299974 0.150114)
			(end -0.299974 -0.150114)
			(stroke
				(width 0.1)
				(type default)
			)
			(layer "F.Fab")
		)
		(fp_line
			(start 0.299974 -0.150114)
			(end 0.299974 0.150114)
			(stroke
				(width 0.1)
				(type default)
			)
			(layer "F.Fab")
		)
		(fp_line
			(start 0.299974 0.150114)
			(end -0.299974 0.150114)
			(stroke
				(width 0.1)
				(type default)
			)
			(layer "F.Fab")
		)
		(pad "1" smd rect
			(at -0.2667 0)
			(size 0.3048 0.381)
			(layers "F.Cu" "F.Mask" "F.Paste")
			(net "P5E_CPU1_P2_TX_C_DN<14>")
		)
		(pad "2" smd rect
			(at 0.2667 0)
			(size 0.3048 0.381)
			(layers "F.Cu" "F.Mask" "F.Paste")
			(net "P5E_CPU1_P2_TX_DN<14>")
		)
	)
	(footprint ""
		(layer "F.Cu")
		(at 229.560374 -154.15641)
		(property "Reference" "R6104"
			(at 0 0 0)
			(layer "F.SilkS")
			(hide yes)
			(effects
				(font
					(size 1.27 1.27)
				)
			)
		)
		(property "Value" ""
			(at 0 0 0)
			(layer "F.Fab")
			(effects
				(font
					(size 1.27 1.27)
				)
			)
		)
		(duplicate_pad_numbers_are_jumpers no)
		(fp_line
			(start -0.7874 -0.4064)
			(end 0.7874 -0.4064)
			(stroke
				(width 0.1524)
				(type default)
			)
			(layer "F.SilkS")
		)
		(fp_line
			(start -0.7874 0.4064)
			(end -0.7874 -0.4064)
			(stroke
				(width 0.1524)
				(type default)
			)
			(layer "F.SilkS")
		)
		(fp_line
			(start 0.7874 -0.4064)
			(end 0.7874 0.4064)
			(stroke
				(width 0.1524)
				(type default)
			)
			(layer "F.SilkS")
		)
		(fp_line
			(start 0.7874 0.4064)
			(end -0.7874 0.4064)
			(stroke
				(width 0.1524)
				(type default)
			)
			(layer "F.SilkS")
		)
		(fp_line
			(start -0.67945 -0.305054)
			(end -0.12065 -0.305054)
			(stroke
				(width 0.1)
				(type default)
			)
			(layer "F.Fab")
		)
		(fp_line
			(start -0.67945 0.3048)
			(end -0.67945 -0.305054)
			(stroke
				(width 0.1)
				(type default)
			)
			(layer "F.Fab")
		)
		(fp_line
			(start -0.12065 -0.305054)
			(end -0.12065 -0.2794)
			(stroke
				(width 0.1)
				(type default)
			)
			(layer "F.Fab")
		)
		(fp_line
			(start -0.12065 -0.2794)
			(end 0.12065 -0.2794)
			(stroke
				(width 0.1)
				(type default)
			)
			(layer "F.Fab")
		)
		(fp_line
			(start -0.12065 0.2794)
			(end -0.12065 0.3048)
			(stroke
				(width 0.1)
				(type default)
			)
			(layer "F.Fab")
		)
		(fp_line
			(start -0.12065 0.3048)
			(end -0.67945 0.3048)
			(stroke
				(width 0.1)
				(type default)
			)
			(layer "F.Fab")
		)
		(fp_line
			(start 0.120396 0.2794)
			(end -0.12065 0.2794)
			(stroke
				(width 0.1)
				(type default)
			)
			(layer "F.Fab")
		)
		(fp_line
			(start 0.120396 0.3048)
			(end 0.120396 0.2794)
			(stroke
				(width 0.1)
				(type default)
			)
			(layer "F.Fab")
		)
		(fp_line
			(start 0.12065 -0.3048)
			(end 0.67945 -0.3048)
			(stroke
				(width 0.1)
				(type default)
			)
			(layer "F.Fab")
		)
		(fp_line
			(start 0.12065 -0.2794)
			(end 0.12065 -0.3048)
			(stroke
				(width 0.1)
				(type default)
			)
			(layer "F.Fab")
		)
		(fp_line
			(start 0.67945 -0.3048)
			(end 0.67945 0.3048)
			(stroke
				(width 0.1)
				(type default)
			)
			(layer "F.Fab")
		)
		(fp_line
			(start 0.67945 0.3048)
			(end 0.120396 0.3048)
			(stroke
				(width 0.1)
				(type default)
			)
			(layer "F.Fab")
		)
		(pad "1" smd circle
			(at -0.40005 0)
			(size 0 0)
			(layers "F.Cu" "F.Mask" "F.Paste")
			(net "JTAG_CPU0_BYPASS")
		)
		(pad "2" smd circle
			(at 0.40005 0)
			(size 0 0)
			(layers "F.Cu" "F.Mask" "F.Paste")
			(net "JTAG_CPU0_BYPASS_R1")
		)
	)
	(footprint ""
		(layer "F.Cu")
		(at 316.821058 -118.910608)
		(property "Reference" "C629"
			(at 0 0 0)
			(layer "F.SilkS")
			(hide yes)
			(effects
				(font
					(size 1.27 1.27)
				)
			)
		)
		(property "Value" ""
			(at 0 0 0)
			(layer "F.Fab")
			(effects
				(font
					(size 1.27 1.27)
				)
			)
		)
		(duplicate_pad_numbers_are_jumpers no)
		(fp_line
			(start -0.7874 -0.4064)
			(end 0.7874 -0.4064)
			(stroke
				(width 0.1524)
				(type default)
			)
			(layer "F.SilkS")
		)
		(fp_line
			(start -0.7874 0.4064)
			(end -0.7874 -0.4064)
			(stroke
				(width 0.1524)
				(type default)
			)
			(layer "F.SilkS")
		)
		(fp_line
			(start 0.7874 -0.4064)
			(end 0.7874 0.4064)
			(stroke
				(width 0.1524)
				(type default)
			)
			(layer "F.SilkS")
		)
		(fp_line
			(start 0.7874 0.4064)
			(end -0.7874 0.4064)
			(stroke
				(width 0.1524)
				(type default)
			)
			(layer "F.SilkS")
		)
		(fp_line
			(start -0.67945 -0.305054)
			(end -0.12065 -0.305054)
			(stroke
				(width 0.1)
				(type default)
			)
			(layer "F.Fab")
		)
		(fp_line
			(start -0.67945 0.3048)
			(end -0.67945 -0.305054)
			(stroke
				(width 0.1)
				(type default)
			)
			(layer "F.Fab")
		)
		(fp_line
			(start -0.12065 -0.305054)
			(end -0.12065 -0.2794)
			(stroke
				(width 0.1)
				(type default)
			)
			(layer "F.Fab")
		)
		(fp_line
			(start -0.12065 -0.2794)
			(end 0.12065 -0.2794)
			(stroke
				(width 0.1)
				(type default)
			)
			(layer "F.Fab")
		)
		(fp_line
			(start -0.12065 0.2794)
			(end -0.12065 0.3048)
			(stroke
				(width 0.1)
				(type default)
			)
			(layer "F.Fab")
		)
		(fp_line
			(start -0.12065 0.3048)
			(end -0.67945 0.3048)
			(stroke
				(width 0.1)
				(type default)
			)
			(layer "F.Fab")
		)
		(fp_line
			(start 0.120396 0.2794)
			(end -0.12065 0.2794)
			(stroke
				(width 0.1)
				(type default)
			)
			(layer "F.Fab")
		)
		(fp_line
			(start 0.120396 0.3048)
			(end 0.120396 0.2794)
			(stroke
				(width 0.1)
				(type default)
			)
			(layer "F.Fab")
		)
		(fp_line
			(start 0.12065 -0.3048)
			(end 0.67945 -0.3048)
			(stroke
				(width 0.1)
				(type default)
			)
			(layer "F.Fab")
		)
		(fp_line
			(start 0.12065 -0.2794)
			(end 0.12065 -0.3048)
			(stroke
				(width 0.1)
				(type default)
			)
			(layer "F.Fab")
		)
		(fp_line
			(start 0.67945 -0.3048)
			(end 0.67945 0.3048)
			(stroke
				(width 0.1)
				(type default)
			)
			(layer "F.Fab")
		)
		(fp_line
			(start 0.67945 0.3048)
			(end 0.120396 0.3048)
			(stroke
				(width 0.1)
				(type default)
			)
			(layer "F.Fab")
		)
		(pad "1" smd circle
			(at -0.40005 0)
			(size 0 0)
			(layers "F.Cu" "F.Mask" "F.Paste")
			(net "P3V3_AUX")
		)
		(pad "2" smd circle
			(at 0.40005 0)
			(size 0 0)
			(layers "F.Cu" "F.Mask" "F.Paste")
			(net "GND")
		)
	)
	(footprint ""
		(layer "F.Cu")
		(at 325.095108 -103.30815)
		(property "Reference" "U52"
			(at -1.63449 -4.200144 0)
			(unlocked yes)
			(layer "F.SilkS")
			(effects
				(font
					(size 0.7874 0.5842)
					(thickness 0.1524)
				)
			)
		)
		(property "Value" ""
			(at 0 0 0)
			(layer "F.Fab")
			(effects
				(font
					(size 1.27 1.27)
				)
			)
		)
		(duplicate_pad_numbers_are_jumpers no)
		(fp_line
			(start -1.500124 -1.500124)
			(end -1.004062 -1.500124)
			(stroke
				(width 0.1524)
				(type default)
			)
			(layer "F.SilkS")
		)
		(fp_line
			(start -1.500124 -1.004062)
			(end -1.500124 -1.500124)
			(stroke
				(width 0.1524)
				(type default)
			)
			(layer "F.SilkS")
		)
		(fp_line
			(start -1.500124 1.500124)
			(end -1.500124 1.004062)
			(stroke
				(width 0.1524)
				(type default)
			)
			(layer "F.SilkS")
		)
		(fp_line
			(start -1.004062 1.500124)
			(end -1.500124 1.500124)
			(stroke
				(width 0.1524)
				(type default)
			)
			(layer "F.SilkS")
		)
		(fp_line
			(start 1.004062 -1.500124)
			(end 1.500124 -1.500124)
			(stroke
				(width 0.1524)
				(type default)
			)
			(layer "F.SilkS")
		)
		(fp_line
			(start 1.500124 -1.500124)
			(end 1.500124 -1.004062)
			(stroke
				(width 0.1524)
				(type default)
			)
			(layer "F.SilkS")
		)
		(fp_line
			(start 1.500124 1.004062)
			(end 1.500124 1.500124)
			(stroke
				(width 0.1524)
				(type default)
			)
			(layer "F.SilkS")
		)
		(fp_line
			(start 1.500124 1.500124)
			(end 1.004062 1.500124)
			(stroke
				(width 0.1524)
				(type default)
			)
			(layer "F.SilkS")
		)
		(fp_poly
			(pts
				(xy -2.413 -2.50698) (xy -3.089402 -1.74879) (xy -1.992884 -1.45161)
			)
			(stroke
				(width 0)
				(type default)
			)
			(fill yes)
			(layer "F.SilkS")
		)
		(fp_line
			(start -1.500124 -1.500124)
			(end 1.500124 -1.500124)
			(stroke
				(width 0.1)
				(type default)
			)
			(layer "F.Fab")
		)
		(fp_line
			(start -1.500124 1.500124)
			(end -1.500124 -1.500124)
			(stroke
				(width 0.1)
				(type default)
			)
			(layer "F.Fab")
		)
		(fp_line
			(start 1.500124 -1.500124)
			(end 1.500124 1.500124)
			(stroke
				(width 0.1)
				(type default)
			)
			(layer "F.Fab")
		)
		(fp_line
			(start 1.500124 1.500124)
			(end -1.500124 1.500124)
			(stroke
				(width 0.1)
				(type default)
			)
			(layer "F.Fab")
		)
		(fp_poly
			(pts
				(xy -2.847848 -1.258062) (xy -2.847848 -0.242062) (xy -1.831848 -0.750062)
			)
			(stroke
				(width 0)
				(type default)
			)
			(fill yes)
			(layer "F.Fab")
		)
		(pad "1" smd rect
			(at -1.400048 -0.750062 270)
			(size 0.2286 0.6096)
			(layers "F.Cu" "F.Mask" "F.Paste")
			(net "INA230_8_A1")
		)
		(pad "2" smd rect
			(at -1.400048 -0.249936 270)
			(size 0.2286 0.6096)
			(layers "F.Cu" "F.Mask" "F.Paste")
			(net "INA230_8_A0")
		)
		(pad "3" smd rect
			(at -1.400048 0.249936 270)
			(size 0.2286 0.6096)
			(layers "F.Cu" "F.Mask" "F.Paste")
			(net "P12V_E1S_0_ADC_ALERT_R")
		)
		(pad "4" smd rect
			(at -1.400048 0.750062 270)
			(size 0.2286 0.6096)
			(layers "F.Cu" "F.Mask" "F.Paste")
			(net "SMB_INA230_8_3V3AUX_SDA_R1")
		)
		(pad "5" smd rect
			(at -0.750062 1.400048)
			(size 0.2286 0.6096)
			(layers "F.Cu" "F.Mask" "F.Paste")
			(net "SMB_INA230_8_3V3AUX_SCL_R1")
		)
		(pad "6" smd rect
			(at -0.249936 1.400048)
			(size 0.2286 0.6096)
			(layers "F.Cu" "F.Mask" "F.Paste")
			(net "NC_INA230_8_NC0")
		)
		(pad "7" smd rect
			(at 0.249936 1.400048)
			(size 0.2286 0.6096)
			(layers "F.Cu" "F.Mask" "F.Paste")
			(net "NC_INA230_8_NC1")
		)
		(pad "8" smd rect
			(at 0.750062 1.400048)
			(size 0.2286 0.6096)
			(layers "F.Cu" "F.Mask" "F.Paste")
			(net "NC_INA230_8_NC2")
		)
		(pad "9" smd rect
			(at 1.400048 0.750062 270)
			(size 0.2286 0.6096)
			(layers "F.Cu" "F.Mask" "F.Paste")
			(net "P3V3_AUX")
		)
		(pad "10" smd rect
			(at 1.400048 0.249936 270)
			(size 0.2286 0.6096)
			(layers "F.Cu" "F.Mask" "F.Paste")
			(net "GND")
		)
		(pad "11" smd rect
			(at 1.400048 -0.249936 270)
			(size 0.2286 0.6096)
			(layers "F.Cu" "F.Mask" "F.Paste")
			(net "P12V_E1S_0")
		)
		(pad "12" smd rect
			(at 1.400048 -0.750062 270)
			(size 0.2286 0.6096)
			(layers "F.Cu" "F.Mask" "F.Paste")
			(net "VSENSE_P12V_INA230_8_INN")
		)
		(pad "13" smd rect
			(at 0.750062 -1.400048)
			(size 0.2286 0.6096)
			(layers "F.Cu" "F.Mask" "F.Paste")
			(net "VSENSE_P12V_INA230_8_INP")
		)
		(pad "14" smd rect
			(at 0.249936 -1.400048)
			(size 0.2286 0.6096)
			(layers "F.Cu" "F.Mask" "F.Paste")
			(net "NC_INA230_8_NC3")
		)
		(pad "15" smd rect
			(at -0.249936 -1.400048)
			(size 0.2286 0.6096)
			(layers "F.Cu" "F.Mask" "F.Paste")
			(net "NC_INA230_8_NC4")
		)
		(pad "16" smd rect
			(at -0.750062 -1.400048)
			(size 0.2286 0.6096)
			(layers "F.Cu" "F.Mask" "F.Paste")
			(net "NC_INA230_8_NC5")
		)
		(pad "TH" smd rect
			(at 0 0)
			(size 1.7018 1.7018)
			(layers "F.Cu" "F.Mask" "F.Paste")
			(net "GND")
		)
		(zone
			(layer "F.Cu")
			(hatch none 0.5)
			(connect_pads
				(clearance 0)
			)
			(min_thickness 0.25)
			(keepout
				(tracks not_allowed)
				(vias allowed)
				(pads allowed)
				(copperpour not_allowed)
				(footprints allowed)
			)
			(placement
				(enabled no)
				(sheetname "")
			)
			(fill
				(thermal_gap 0.5)
				(thermal_bridge_width 0.5)
				(island_removal_mode 0)
			)
			(polygon
				(pts
					(xy 324.05066 -103.33355) (xy 324.05066 -104.352598) (xy 326.139556 -104.352598) (xy 326.139556 -102.263702)
					(xy 324.05066 -102.263702) (xy 324.05066 -103.30815) (xy 324.193408 -103.30815) (xy 324.193408 -102.40645)
					(xy 325.996808 -102.40645) (xy 325.996808 -104.20985) (xy 324.193408 -104.20985) (xy 324.193408 -103.33355)
				)
			)
		)
	)
	(footprint ""
		(layer "F.Cu")
		(at 28.53563 -422.330626 180)
		(property "Reference" "C1871"
			(at 0 0 180)
			(layer "F.SilkS")
			(hide yes)
			(effects
				(font
					(size 1.27 1.27)
				)
			)
		)
		(property "Value" ""
			(at 0 0 180)
			(layer "F.Fab")
			(effects
				(font
					(size 1.27 1.27)
				)
			)
		)
		(duplicate_pad_numbers_are_jumpers no)
		(fp_line
			(start 0.7874 0.4064)
			(end -0.7874 0.4064)
			(stroke
				(width 0.1524)
				(type default)
			)
			(layer "F.SilkS")
		)
		(fp_line
			(start 0.7874 -0.284226)
			(end 0.7874 0.4064)
			(stroke
				(width 0.1524)
				(type default)
			)
			(layer "F.SilkS")
		)
		(fp_line
			(start -0.7874 -0.4064)
			(end -0.34417 -0.4064)
			(stroke
				(width 0.1524)
				(type default)
			)
			(layer "F.SilkS")
		)
		(fp_line
			(start 0.6858 0.3048)
			(end 0.1016 0.3048)
			(stroke
				(width 0.1)
				(type default)
			)
			(layer "F.Fab")
		)
		(fp_line
			(start 0.6858 -0.3048)
			(end 0.6858 0.3048)
			(stroke
				(width 0.1)
				(type default)
			)
			(layer "F.Fab")
		)
		(fp_line
			(start 0.1016 0.3048)
			(end 0.1016 0.2794)
			(stroke
				(width 0.1)
				(type default)
			)
			(layer "F.Fab")
		)
		(fp_line
			(start 0.1016 0.2794)
			(end -0.1016 0.2794)
			(stroke
				(width 0.1)
				(type default)
			)
			(layer "F.Fab")
		)
		(fp_line
			(start 0.1016 -0.2794)
			(end 0.1016 -0.3048)
			(stroke
				(width 0.1)
				(type default)
			)
			(layer "F.Fab")
		)
		(fp_line
			(start 0.1016 -0.3048)
			(end 0.6858 -0.3048)
			(stroke
				(width 0.1)
				(type default)
			)
			(layer "F.Fab")
		)
		(fp_line
			(start -0.1016 0.3048)
			(end -0.6858 0.3048)
			(stroke
				(width 0.1)
				(type default)
			)
			(layer "F.Fab")
		)
		(fp_line
			(start -0.1016 0.2794)
			(end -0.1016 0.3048)
			(stroke
				(width 0.1)
				(type default)
			)
			(layer "F.Fab")
		)
		(fp_line
			(start -0.1016 -0.2794)
			(end 0.1016 -0.2794)
			(stroke
				(width 0.1)
				(type default)
			)
			(layer "F.Fab")
		)
		(fp_line
			(start -0.1016 -0.3048)
			(end -0.1016 -0.2794)
			(stroke
				(width 0.1)
				(type default)
			)
			(layer "F.Fab")
		)
		(fp_line
			(start -0.6858 0.3048)
			(end -0.6858 -0.3048)
			(stroke
				(width 0.1)
				(type default)
			)
			(layer "F.Fab")
		)
		(fp_line
			(start -0.6858 -0.3048)
			(end -0.1016 -0.3048)
			(stroke
				(width 0.1)
				(type default)
			)
			(layer "F.Fab")
		)
		(pad "1" smd rect
			(at -0.40005 0)
			(size 0.4572 0.508)
			(layers "F.Cu" "F.Mask" "F.Paste")
			(net "P2E_MB_BMC_TX_BUF_DN<0>")
		)
		(pad "2" smd rect
			(at 0.40005 0)
			(size 0.4572 0.508)
			(layers "F.Cu" "F.Mask" "F.Paste")
			(net "P2E_MB_BMC_TX_BUF_C_DN<0>")
		)
	)
	(footprint ""
		(layer "F.Cu")
		(at 177.81016 -393.2936)
		(property "Reference" "R1488"
			(at 0 0 0)
			(layer "F.SilkS")
			(hide yes)
			(effects
				(font
					(size 1.27 1.27)
				)
			)
		)
		(property "Value" ""
			(at 0 0 0)
			(layer "F.Fab")
			(effects
				(font
					(size 1.27 1.27)
				)
			)
		)
		(duplicate_pad_numbers_are_jumpers no)
		(fp_line
			(start -0.32512 -0.175006)
			(end 0.32512 -0.175006)
			(stroke
				(width 0.1)
				(type default)
			)
			(layer "F.Fab")
		)
		(fp_line
			(start -0.32512 0.175006)
			(end -0.32512 -0.175006)
			(stroke
				(width 0.1)
				(type default)
			)
			(layer "F.Fab")
		)
		(fp_line
			(start 0.32512 -0.175006)
			(end 0.32512 0.175006)
			(stroke
				(width 0.1)
				(type default)
			)
			(layer "F.Fab")
		)
		(fp_line
			(start 0.32512 0.175006)
			(end -0.32512 0.175006)
			(stroke
				(width 0.1)
				(type default)
			)
			(layer "F.Fab")
		)
		(pad "1" smd rect
			(at -0.2667 0)
			(size 0.3048 0.381)
			(layers "F.Cu" "F.Mask" "F.Paste")
			(net "P1V8_CPU1_RT_1D")
		)
		(pad "2" smd rect
			(at 0.2667 0 180)
			(size 0.3048 0.381)
			(layers "F.Cu" "F.Mask" "F.Paste")
			(net "JTAG_TDI_RT_CPU1_P2")
		)
	)
	(footprint ""
		(layer "F.Cu")
		(at 89.562432 -70.69582 -90)
		(property "Reference" "PR3855"
			(at 0 0 270)
			(layer "F.SilkS")
			(hide yes)
			(effects
				(font
					(size 1.27 1.27)
				)
			)
		)
		(property "Value" ""
			(at 0 0 270)
			(layer "F.Fab")
			(effects
				(font
					(size 1.27 1.27)
				)
			)
		)
		(duplicate_pad_numbers_are_jumpers no)
		(fp_line
			(start -0.7874 0.4064)
			(end -0.7874 -0.4064)
			(stroke
				(width 0.1524)
				(type default)
			)
			(layer "F.SilkS")
		)
		(fp_line
			(start 0.7874 0.4064)
			(end -0.7874 0.4064)
			(stroke
				(width 0.1524)
				(type default)
			)
			(layer "F.SilkS")
		)
		(fp_line
			(start -0.7874 -0.4064)
			(end 0.7874 -0.4064)
			(stroke
				(width 0.1524)
				(type default)
			)
			(layer "F.SilkS")
		)
		(fp_line
			(start 0.7874 -0.4064)
			(end 0.7874 0.4064)
			(stroke
				(width 0.1524)
				(type default)
			)
			(layer "F.SilkS")
		)
		(fp_line
			(start -0.67945 0.3048)
			(end -0.67945 -0.305054)
			(stroke
				(width 0.1)
				(type default)
			)
			(layer "F.Fab")
		)
		(fp_line
			(start -0.12065 0.3048)
			(end -0.67945 0.3048)
			(stroke
				(width 0.1)
				(type default)
			)
			(layer "F.Fab")
		)
		(fp_line
			(start 0.120396 0.3048)
			(end 0.120396 0.2794)
			(stroke
				(width 0.1)
				(type default)
			)
			(layer "F.Fab")
		)
		(fp_line
			(start 0.67945 0.3048)
			(end 0.120396 0.3048)
			(stroke
				(width 0.1)
				(type default)
			)
			(layer "F.Fab")
		)
		(fp_line
			(start -0.12065 0.2794)
			(end -0.12065 0.3048)
			(stroke
				(width 0.1)
				(type default)
			)
			(layer "F.Fab")
		)
		(fp_line
			(start 0.120396 0.2794)
			(end -0.12065 0.2794)
			(stroke
				(width 0.1)
				(type default)
			)
			(layer "F.Fab")
		)
		(fp_line
			(start -0.12065 -0.2794)
			(end 0.12065 -0.2794)
			(stroke
				(width 0.1)
				(type default)
			)
			(layer "F.Fab")
		)
		(fp_line
			(start 0.12065 -0.2794)
			(end 0.12065 -0.3048)
			(stroke
				(width 0.1)
				(type default)
			)
			(layer "F.Fab")
		)
		(fp_line
			(start 0.12065 -0.3048)
			(end 0.67945 -0.3048)
			(stroke
				(width 0.1)
				(type default)
			)
			(layer "F.Fab")
		)
		(fp_line
			(start 0.67945 -0.3048)
			(end 0.67945 0.3048)
			(stroke
				(width 0.1)
				(type default)
			)
			(layer "F.Fab")
		)
		(fp_line
			(start -0.67945 -0.305054)
			(end -0.12065 -0.305054)
			(stroke
				(width 0.1)
				(type default)
			)
			(layer "F.Fab")
		)
		(fp_line
			(start -0.12065 -0.305054)
			(end -0.12065 -0.2794)
			(stroke
				(width 0.1)
				(type default)
			)
			(layer "F.Fab")
		)
		(pad "1" smd circle
			(at -0.40005 0 270)
			(size 0 0)
			(layers "F.Cu" "F.Mask" "F.Paste")
			(net "P3V3_OCP_MODE_2")
		)
		(pad "2" smd circle
			(at 0.40005 0 270)
			(size 0 0)
			(layers "F.Cu" "F.Mask" "F.Paste")
			(net "GND")
		)
	)
	(footprint ""
		(layer "F.Cu")
		(at 226.0981 -400.972782 180)
		(property "Reference" "PR3987"
			(at 0 0 180)
			(layer "F.SilkS")
			(hide yes)
			(effects
				(font
					(size 1.27 1.27)
				)
			)
		)
		(property "Value" ""
			(at 0 0 180)
			(layer "F.Fab")
			(effects
				(font
					(size 1.27 1.27)
				)
			)
		)
		(duplicate_pad_numbers_are_jumpers no)
		(fp_line
			(start 0.7874 0.4064)
			(end -0.7874 0.4064)
			(stroke
				(width 0.1524)
				(type default)
			)
			(layer "F.SilkS")
		)
		(fp_line
			(start 0.7874 -0.4064)
			(end 0.7874 0.4064)
			(stroke
				(width 0.1524)
				(type default)
			)
			(layer "F.SilkS")
		)
		(fp_line
			(start -0.7874 0.4064)
			(end -0.7874 -0.4064)
			(stroke
				(width 0.1524)
				(type default)
			)
			(layer "F.SilkS")
		)
		(fp_line
			(start -0.7874 -0.4064)
			(end 0.7874 -0.4064)
			(stroke
				(width 0.1524)
				(type default)
			)
			(layer "F.SilkS")
		)
		(fp_line
			(start 0.67945 0.3048)
			(end 0.120396 0.3048)
			(stroke
				(width 0.1)
				(type default)
			)
			(layer "F.Fab")
		)
		(fp_line
			(start 0.67945 -0.3048)
			(end 0.67945 0.3048)
			(stroke
				(width 0.1)
				(type default)
			)
			(layer "F.Fab")
		)
		(fp_line
			(start 0.12065 -0.2794)
			(end 0.12065 -0.3048)
			(stroke
				(width 0.1)
				(type default)
			)
			(layer "F.Fab")
		)
		(fp_line
			(start 0.12065 -0.3048)
			(end 0.67945 -0.3048)
			(stroke
				(width 0.1)
				(type default)
			)
			(layer "F.Fab")
		)
		(fp_line
			(start 0.120396 0.3048)
			(end 0.120396 0.2794)
			(stroke
				(width 0.1)
				(type default)
			)
			(layer "F.Fab")
		)
		(fp_line
			(start 0.120396 0.2794)
			(end -0.12065 0.2794)
			(stroke
				(width 0.1)
				(type default)
			)
			(layer "F.Fab")
		)
		(fp_line
			(start -0.12065 0.3048)
			(end -0.67945 0.3048)
			(stroke
				(width 0.1)
				(type default)
			)
			(layer "F.Fab")
		)
		(fp_line
			(start -0.12065 0.2794)
			(end -0.12065 0.3048)
			(stroke
				(width 0.1)
				(type default)
			)
			(layer "F.Fab")
		)
		(fp_line
			(start -0.12065 -0.2794)
			(end 0.12065 -0.2794)
			(stroke
				(width 0.1)
				(type default)
			)
			(layer "F.Fab")
		)
		(fp_line
			(start -0.12065 -0.305054)
			(end -0.12065 -0.2794)
			(stroke
				(width 0.1)
				(type default)
			)
			(layer "F.Fab")
		)
		(fp_line
			(start -0.67945 0.3048)
			(end -0.67945 -0.305054)
			(stroke
				(width 0.1)
				(type default)
			)
			(layer "F.Fab")
		)
		(fp_line
			(start -0.67945 -0.305054)
			(end -0.12065 -0.305054)
			(stroke
				(width 0.1)
				(type default)
			)
			(layer "F.Fab")
		)
		(pad "1" smd circle
			(at -0.40005 0 180)
			(size 0 0)
			(layers "F.Cu" "F.Mask" "F.Paste")
			(net "HSC_CS_4")
		)
		(pad "2" smd circle
			(at 0.40005 0 180)
			(size 0 0)
			(layers "F.Cu" "F.Mask" "F.Paste")
			(net "AGND_HSC")
		)
	)
	(footprint ""
		(layer "F.Cu")
		(at 170.8404 -333.375508 180)
		(property "Reference" "PR229"
			(at 0 0 180)
			(layer "F.SilkS")
			(hide yes)
			(effects
				(font
					(size 1.27 1.27)
				)
			)
		)
		(property "Value" ""
			(at 0 0 180)
			(layer "F.Fab")
			(effects
				(font
					(size 1.27 1.27)
				)
			)
		)
		(duplicate_pad_numbers_are_jumpers no)
		(fp_line
			(start 0.7874 0.4064)
			(end -0.7874 0.4064)
			(stroke
				(width 0.1524)
				(type default)
			)
			(layer "F.SilkS")
		)
		(fp_line
			(start 0.7874 -0.4064)
			(end 0.7874 0.4064)
			(stroke
				(width 0.1524)
				(type default)
			)
			(layer "F.SilkS")
		)
		(fp_line
			(start -0.7874 0.4064)
			(end -0.7874 -0.4064)
			(stroke
				(width 0.1524)
				(type default)
			)
			(layer "F.SilkS")
		)
		(fp_line
			(start -0.7874 -0.4064)
			(end 0.7874 -0.4064)
			(stroke
				(width 0.1524)
				(type default)
			)
			(layer "F.SilkS")
		)
		(fp_line
			(start 0.67945 0.3048)
			(end 0.120396 0.3048)
			(stroke
				(width 0.1)
				(type default)
			)
			(layer "F.Fab")
		)
		(fp_line
			(start 0.67945 -0.3048)
			(end 0.67945 0.3048)
			(stroke
				(width 0.1)
				(type default)
			)
			(layer "F.Fab")
		)
		(fp_line
			(start 0.12065 -0.2794)
			(end 0.12065 -0.3048)
			(stroke
				(width 0.1)
				(type default)
			)
			(layer "F.Fab")
		)
		(fp_line
			(start 0.12065 -0.3048)
			(end 0.67945 -0.3048)
			(stroke
				(width 0.1)
				(type default)
			)
			(layer "F.Fab")
		)
		(fp_line
			(start 0.120396 0.3048)
			(end 0.120396 0.2794)
			(stroke
				(width 0.1)
				(type default)
			)
			(layer "F.Fab")
		)
		(fp_line
			(start 0.120396 0.2794)
			(end -0.12065 0.2794)
			(stroke
				(width 0.1)
				(type default)
			)
			(layer "F.Fab")
		)
		(fp_line
			(start -0.12065 0.3048)
			(end -0.67945 0.3048)
			(stroke
				(width 0.1)
				(type default)
			)
			(layer "F.Fab")
		)
		(fp_line
			(start -0.12065 0.2794)
			(end -0.12065 0.3048)
			(stroke
				(width 0.1)
				(type default)
			)
			(layer "F.Fab")
		)
		(fp_line
			(start -0.12065 -0.2794)
			(end 0.12065 -0.2794)
			(stroke
				(width 0.1)
				(type default)
			)
			(layer "F.Fab")
		)
		(fp_line
			(start -0.12065 -0.305054)
			(end -0.12065 -0.2794)
			(stroke
				(width 0.1)
				(type default)
			)
			(layer "F.Fab")
		)
		(fp_line
			(start -0.67945 0.3048)
			(end -0.67945 -0.305054)
			(stroke
				(width 0.1)
				(type default)
			)
			(layer "F.Fab")
		)
		(fp_line
			(start -0.67945 -0.305054)
			(end -0.12065 -0.305054)
			(stroke
				(width 0.1)
				(type default)
			)
			(layer "F.Fab")
		)
		(pad "1" smd circle
			(at -0.40005 0 180)
			(size 0 0)
			(layers "F.Cu" "F.Mask" "F.Paste")
			(net "PVDD11_S3_P1")
		)
		(pad "2" smd circle
			(at 0.40005 0 180)
			(size 0 0)
			(layers "F.Cu" "F.Mask" "F.Paste")
			(net "VSENSE_PVDD11_S3_P1_DP")
		)
	)
	(footprint ""
		(layer "F.Cu")
		(at 197.269608 -113.625376 180)
		(property "Reference" "R283"
			(at 0 0 180)
			(layer "F.SilkS")
			(hide yes)
			(effects
				(font
					(size 1.27 1.27)
				)
			)
		)
		(property "Value" ""
			(at 0 0 180)
			(layer "F.Fab")
			(effects
				(font
					(size 1.27 1.27)
				)
			)
		)
		(duplicate_pad_numbers_are_jumpers no)
		(fp_line
			(start 0.7874 0.4064)
			(end -0.7874 0.4064)
			(stroke
				(width 0.1524)
				(type default)
			)
			(layer "F.SilkS")
		)
		(fp_line
			(start 0.7874 -0.4064)
			(end 0.7874 0.4064)
			(stroke
				(width 0.1524)
				(type default)
			)
			(layer "F.SilkS")
		)
		(fp_line
			(start -0.7874 0.4064)
			(end -0.7874 -0.4064)
			(stroke
				(width 0.1524)
				(type default)
			)
			(layer "F.SilkS")
		)
		(fp_line
			(start -0.7874 -0.4064)
			(end 0.7874 -0.4064)
			(stroke
				(width 0.1524)
				(type default)
			)
			(layer "F.SilkS")
		)
		(fp_line
			(start 0.67945 0.3048)
			(end 0.120396 0.3048)
			(stroke
				(width 0.1)
				(type default)
			)
			(layer "F.Fab")
		)
		(fp_line
			(start 0.67945 -0.3048)
			(end 0.67945 0.3048)
			(stroke
				(width 0.1)
				(type default)
			)
			(layer "F.Fab")
		)
		(fp_line
			(start 0.12065 -0.2794)
			(end 0.12065 -0.3048)
			(stroke
				(width 0.1)
				(type default)
			)
			(layer "F.Fab")
		)
		(fp_line
			(start 0.12065 -0.3048)
			(end 0.67945 -0.3048)
			(stroke
				(width 0.1)
				(type default)
			)
			(layer "F.Fab")
		)
		(fp_line
			(start 0.120396 0.3048)
			(end 0.120396 0.2794)
			(stroke
				(width 0.1)
				(type default)
			)
			(layer "F.Fab")
		)
		(fp_line
			(start 0.120396 0.2794)
			(end -0.12065 0.2794)
			(stroke
				(width 0.1)
				(type default)
			)
			(layer "F.Fab")
		)
		(fp_line
			(start -0.12065 0.3048)
			(end -0.67945 0.3048)
			(stroke
				(width 0.1)
				(type default)
			)
			(layer "F.Fab")
		)
		(fp_line
			(start -0.12065 0.2794)
			(end -0.12065 0.3048)
			(stroke
				(width 0.1)
				(type default)
			)
			(layer "F.Fab")
		)
		(fp_line
			(start -0.12065 -0.2794)
			(end 0.12065 -0.2794)
			(stroke
				(width 0.1)
				(type default)
			)
			(layer "F.Fab")
		)
		(fp_line
			(start -0.12065 -0.305054)
			(end -0.12065 -0.2794)
			(stroke
				(width 0.1)
				(type default)
			)
			(layer "F.Fab")
		)
		(fp_line
			(start -0.67945 0.3048)
			(end -0.67945 -0.305054)
			(stroke
				(width 0.1)
				(type default)
			)
			(layer "F.Fab")
		)
		(fp_line
			(start -0.67945 -0.305054)
			(end -0.12065 -0.305054)
			(stroke
				(width 0.1)
				(type default)
			)
			(layer "F.Fab")
		)
		(pad "1" smd circle
			(at -0.40005 0 180)
			(size 0 0)
			(layers "F.Cu" "F.Mask" "F.Paste")
			(net "PWRGD_PVDDIO_P1")
		)
		(pad "2" smd circle
			(at 0.40005 0 180)
			(size 0 0)
			(layers "F.Cu" "F.Mask" "F.Paste")
			(net "FM_PWRGD_PVDDIO_P1")
		)
	)
	(footprint ""
		(layer "F.Cu")
		(at 327.46061 -339.63991 90)
		(property "Reference" "PR81"
			(at 0 0 90)
			(layer "F.SilkS")
			(hide yes)
			(effects
				(font
					(size 1.27 1.27)
				)
			)
		)
		(property "Value" ""
			(at 0 0 90)
			(layer "F.Fab")
			(effects
				(font
					(size 1.27 1.27)
				)
			)
		)
		(duplicate_pad_numbers_are_jumpers no)
		(fp_line
			(start 0.7874 -0.4064)
			(end 0.7874 0.4064)
			(stroke
				(width 0.1524)
				(type default)
			)
			(layer "F.SilkS")
		)
		(fp_line
			(start -0.7874 -0.4064)
			(end 0.7874 -0.4064)
			(stroke
				(width 0.1524)
				(type default)
			)
			(layer "F.SilkS")
		)
		(fp_line
			(start 0.7874 0.4064)
			(end -0.7874 0.4064)
			(stroke
				(width 0.1524)
				(type default)
			)
			(layer "F.SilkS")
		)
		(fp_line
			(start -0.7874 0.4064)
			(end -0.7874 -0.4064)
			(stroke
				(width 0.1524)
				(type default)
			)
			(layer "F.SilkS")
		)
		(fp_line
			(start -0.12065 -0.305054)
			(end -0.12065 -0.2794)
			(stroke
				(width 0.1)
				(type default)
			)
			(layer "F.Fab")
		)
		(fp_line
			(start -0.67945 -0.305054)
			(end -0.12065 -0.305054)
			(stroke
				(width 0.1)
				(type default)
			)
			(layer "F.Fab")
		)
		(fp_line
			(start 0.67945 -0.3048)
			(end 0.67945 0.3048)
			(stroke
				(width 0.1)
				(type default)
			)
			(layer "F.Fab")
		)
		(fp_line
			(start 0.12065 -0.3048)
			(end 0.67945 -0.3048)
			(stroke
				(width 0.1)
				(type default)
			)
			(layer "F.Fab")
		)
		(fp_line
			(start 0.12065 -0.2794)
			(end 0.12065 -0.3048)
			(stroke
				(width 0.1)
				(type default)
			)
			(layer "F.Fab")
		)
		(fp_line
			(start -0.12065 -0.2794)
			(end 0.12065 -0.2794)
			(stroke
				(width 0.1)
				(type default)
			)
			(layer "F.Fab")
		)
		(fp_line
			(start 0.120396 0.2794)
			(end -0.12065 0.2794)
			(stroke
				(width 0.1)
				(type default)
			)
			(layer "F.Fab")
		)
		(fp_line
			(start -0.12065 0.2794)
			(end -0.12065 0.3048)
			(stroke
				(width 0.1)
				(type default)
			)
			(layer "F.Fab")
		)
		(fp_line
			(start 0.67945 0.3048)
			(end 0.120396 0.3048)
			(stroke
				(width 0.1)
				(type default)
			)
			(layer "F.Fab")
		)
		(fp_line
			(start 0.120396 0.3048)
			(end 0.120396 0.2794)
			(stroke
				(width 0.1)
				(type default)
			)
			(layer "F.Fab")
		)
		(fp_line
			(start -0.12065 0.3048)
			(end -0.67945 0.3048)
			(stroke
				(width 0.1)
				(type default)
			)
			(layer "F.Fab")
		)
		(fp_line
			(start -0.67945 0.3048)
			(end -0.67945 -0.305054)
			(stroke
				(width 0.1)
				(type default)
			)
			(layer "F.Fab")
		)
		(pad "1" smd circle
			(at -0.40005 0 90)
			(size 0 0)
			(layers "F.Cu" "F.Mask" "F.Paste")
			(net "SW_PVDDCR_CPU1_P0_BOOT2")
		)
		(pad "2" smd circle
			(at 0.40005 0 90)
			(size 0 0)
			(layers "F.Cu" "F.Mask" "F.Paste")
			(net "SW_PVDDCR_CPU1_P0_BOOT2_R")
		)
	)
	(footprint ""
		(layer "F.Cu")
		(at 152.849834 -322.731892 180)
		(property "Reference" "R584"
			(at 0 0 180)
			(layer "F.SilkS")
			(hide yes)
			(effects
				(font
					(size 1.27 1.27)
				)
			)
		)
		(property "Value" ""
			(at 0 0 180)
			(layer "F.Fab")
			(effects
				(font
					(size 1.27 1.27)
				)
			)
		)
		(duplicate_pad_numbers_are_jumpers no)
		(fp_line
			(start 0.7874 0.4064)
			(end -0.7874 0.4064)
			(stroke
				(width 0.1524)
				(type default)
			)
			(layer "F.SilkS")
		)
		(fp_line
			(start 0.7874 -0.4064)
			(end 0.7874 0.4064)
			(stroke
				(width 0.1524)
				(type default)
			)
			(layer "F.SilkS")
		)
		(fp_line
			(start -0.7874 0.4064)
			(end -0.7874 -0.4064)
			(stroke
				(width 0.1524)
				(type default)
			)
			(layer "F.SilkS")
		)
		(fp_line
			(start -0.7874 -0.4064)
			(end 0.7874 -0.4064)
			(stroke
				(width 0.1524)
				(type default)
			)
			(layer "F.SilkS")
		)
		(fp_line
			(start 0.67945 0.3048)
			(end 0.120396 0.3048)
			(stroke
				(width 0.1)
				(type default)
			)
			(layer "F.Fab")
		)
		(fp_line
			(start 0.67945 -0.3048)
			(end 0.67945 0.3048)
			(stroke
				(width 0.1)
				(type default)
			)
			(layer "F.Fab")
		)
		(fp_line
			(start 0.12065 -0.2794)
			(end 0.12065 -0.3048)
			(stroke
				(width 0.1)
				(type default)
			)
			(layer "F.Fab")
		)
		(fp_line
			(start 0.12065 -0.3048)
			(end 0.67945 -0.3048)
			(stroke
				(width 0.1)
				(type default)
			)
			(layer "F.Fab")
		)
		(fp_line
			(start 0.120396 0.3048)
			(end 0.120396 0.2794)
			(stroke
				(width 0.1)
				(type default)
			)
			(layer "F.Fab")
		)
		(fp_line
			(start 0.120396 0.2794)
			(end -0.12065 0.2794)
			(stroke
				(width 0.1)
				(type default)
			)
			(layer "F.Fab")
		)
		(fp_line
			(start -0.12065 0.3048)
			(end -0.67945 0.3048)
			(stroke
				(width 0.1)
				(type default)
			)
			(layer "F.Fab")
		)
		(fp_line
			(start -0.12065 0.2794)
			(end -0.12065 0.3048)
			(stroke
				(width 0.1)
				(type default)
			)
			(layer "F.Fab")
		)
		(fp_line
			(start -0.12065 -0.2794)
			(end 0.12065 -0.2794)
			(stroke
				(width 0.1)
				(type default)
			)
			(layer "F.Fab")
		)
		(fp_line
			(start -0.12065 -0.305054)
			(end -0.12065 -0.2794)
			(stroke
				(width 0.1)
				(type default)
			)
			(layer "F.Fab")
		)
		(fp_line
			(start -0.67945 0.3048)
			(end -0.67945 -0.305054)
			(stroke
				(width 0.1)
				(type default)
			)
			(layer "F.Fab")
		)
		(fp_line
			(start -0.67945 -0.305054)
			(end -0.12065 -0.305054)
			(stroke
				(width 0.1)
				(type default)
			)
			(layer "F.Fab")
		)
		(pad "1" smd circle
			(at -0.40005 0 180)
			(size 0 0)
			(layers "F.Cu" "F.Mask" "F.Paste")
			(net "GND")
		)
		(pad "2" smd circle
			(at 0.40005 0 180)
			(size 0 0)
			(layers "F.Cu" "F.Mask" "F.Paste")
			(net "RST_CPU1_RSMRST_N")
		)
	)
	(footprint ""
		(layer "F.Cu")
		(at 387.425692 -381.41783 -90)
		(property "Reference" "C878"
			(at 0 0 270)
			(layer "F.SilkS")
			(hide yes)
			(effects
				(font
					(size 1.27 1.27)
				)
			)
		)
		(property "Value" ""
			(at 0 0 270)
			(layer "F.Fab")
			(effects
				(font
					(size 1.27 1.27)
				)
			)
		)
		(duplicate_pad_numbers_are_jumpers no)
		(fp_line
			(start -0.299974 0.150114)
			(end -0.299974 -0.150114)
			(stroke
				(width 0.1)
				(type default)
			)
			(layer "F.Fab")
		)
		(fp_line
			(start 0.299974 0.150114)
			(end -0.299974 0.150114)
			(stroke
				(width 0.1)
				(type default)
			)
			(layer "F.Fab")
		)
		(fp_line
			(start -0.299974 -0.150114)
			(end 0.299974 -0.150114)
			(stroke
				(width 0.1)
				(type default)
			)
			(layer "F.Fab")
		)
		(fp_line
			(start 0.299974 -0.150114)
			(end 0.299974 0.150114)
			(stroke
				(width 0.1)
				(type default)
			)
			(layer "F.Fab")
		)
		(pad "1" smd rect
			(at -0.2667 0 270)
			(size 0.3048 0.381)
			(layers "F.Cu" "F.Mask" "F.Paste")
			(net "P5E_CPU0_P3_TX_C_DN<11>")
		)
		(pad "2" smd rect
			(at 0.2667 0 270)
			(size 0.3048 0.381)
			(layers "F.Cu" "F.Mask" "F.Paste")
			(net "P5E_CPU0_P3_TX_DN<11>")
		)
	)
	(footprint ""
		(layer "F.Cu")
		(at 85.96757 -180.078634 -90)
		(property "Reference" "PC256"
			(at 0 0 270)
			(layer "F.SilkS")
			(hide yes)
			(effects
				(font
					(size 1.27 1.27)
				)
			)
		)
		(property "Value" ""
			(at 0 0 270)
			(layer "F.Fab")
			(effects
				(font
					(size 1.27 1.27)
				)
			)
		)
		(duplicate_pad_numbers_are_jumpers no)
		(fp_line
			(start -0.7874 0.4064)
			(end -0.7874 -0.4064)
			(stroke
				(width 0.1524)
				(type default)
			)
			(layer "F.SilkS")
		)
		(fp_line
			(start -0.134366 0.4064)
			(end -0.7874 0.4064)
			(stroke
				(width 0.1524)
				(type default)
			)
			(layer "F.SilkS")
		)
		(fp_line
			(start 0.7874 0.4064)
			(end 0.500634 0.4064)
			(stroke
				(width 0.1524)
				(type default)
			)
			(layer "F.SilkS")
		)
		(fp_line
			(start -0.7874 -0.4064)
			(end 0.7874 -0.4064)
			(stroke
				(width 0.1524)
				(type default)
			)
			(layer "F.SilkS")
		)
		(fp_line
			(start 0.7874 -0.4064)
			(end 0.7874 0.4064)
			(stroke
				(width 0.1524)
				(type default)
			)
			(layer "F.SilkS")
		)
		(fp_line
			(start -0.67945 0.3048)
			(end -0.67945 -0.305054)
			(stroke
				(width 0.1)
				(type default)
			)
			(layer "F.Fab")
		)
		(fp_line
			(start -0.12065 0.3048)
			(end -0.67945 0.3048)
			(stroke
				(width 0.1)
				(type default)
			)
			(layer "F.Fab")
		)
		(fp_line
			(start 0.120396 0.3048)
			(end 0.120396 0.2794)
			(stroke
				(width 0.1)
				(type default)
			)
			(layer "F.Fab")
		)
		(fp_line
			(start 0.67945 0.3048)
			(end 0.120396 0.3048)
			(stroke
				(width 0.1)
				(type default)
			)
			(layer "F.Fab")
		)
		(fp_line
			(start -0.12065 0.2794)
			(end -0.12065 0.3048)
			(stroke
				(width 0.1)
				(type default)
			)
			(layer "F.Fab")
		)
		(fp_line
			(start 0.120396 0.2794)
			(end -0.12065 0.2794)
			(stroke
				(width 0.1)
				(type default)
			)
			(layer "F.Fab")
		)
		(fp_line
			(start -0.12065 -0.2794)
			(end 0.12065 -0.2794)
			(stroke
				(width 0.1)
				(type default)
			)
			(layer "F.Fab")
		)
		(fp_line
			(start 0.12065 -0.2794)
			(end 0.12065 -0.3048)
			(stroke
				(width 0.1)
				(type default)
			)
			(layer "F.Fab")
		)
		(fp_line
			(start 0.12065 -0.3048)
			(end 0.67945 -0.3048)
			(stroke
				(width 0.1)
				(type default)
			)
			(layer "F.Fab")
		)
		(fp_line
			(start 0.67945 -0.3048)
			(end 0.67945 0.3048)
			(stroke
				(width 0.1)
				(type default)
			)
			(layer "F.Fab")
		)
		(fp_line
			(start -0.67945 -0.305054)
			(end -0.12065 -0.305054)
			(stroke
				(width 0.1)
				(type default)
			)
			(layer "F.Fab")
		)
		(fp_line
			(start -0.12065 -0.305054)
			(end -0.12065 -0.2794)
			(stroke
				(width 0.1)
				(type default)
			)
			(layer "F.Fab")
		)
		(pad "1" smd circle
			(at -0.40005 0 270)
			(size 0 0)
			(layers "F.Cu" "F.Mask" "F.Paste")
			(net "PVDDCR_CPU0_P1_VCC1")
		)
		(pad "2" smd circle
			(at 0.40005 0 270)
			(size 0 0)
			(layers "F.Cu" "F.Mask" "F.Paste")
			(net "GND")
		)
	)
	(footprint ""
		(layer "F.Cu")
		(at 106.932222 -15.22349)
		(property "Reference" "R4212"
			(at 0 0 0)
			(layer "F.SilkS")
			(hide yes)
			(effects
				(font
					(size 1.27 1.27)
				)
			)
		)
		(property "Value" ""
			(at 0 0 0)
			(layer "F.Fab")
			(effects
				(font
					(size 1.27 1.27)
				)
			)
		)
		(duplicate_pad_numbers_are_jumpers no)
		(fp_line
			(start -0.7874 -0.4064)
			(end 0.7874 -0.4064)
			(stroke
				(width 0.1524)
				(type default)
			)
			(layer "F.SilkS")
		)
		(fp_line
			(start -0.7874 0.4064)
			(end -0.7874 -0.4064)
			(stroke
				(width 0.1524)
				(type default)
			)
			(layer "F.SilkS")
		)
		(fp_line
			(start 0.7874 -0.4064)
			(end 0.7874 0.4064)
			(stroke
				(width 0.1524)
				(type default)
			)
			(layer "F.SilkS")
		)
		(fp_line
			(start 0.7874 0.4064)
			(end -0.7874 0.4064)
			(stroke
				(width 0.1524)
				(type default)
			)
			(layer "F.SilkS")
		)
		(fp_line
			(start -0.67945 -0.305054)
			(end -0.12065 -0.305054)
			(stroke
				(width 0.1)
				(type default)
			)
			(layer "F.Fab")
		)
		(fp_line
			(start -0.67945 0.3048)
			(end -0.67945 -0.305054)
			(stroke
				(width 0.1)
				(type default)
			)
			(layer "F.Fab")
		)
		(fp_line
			(start -0.12065 -0.305054)
			(end -0.12065 -0.2794)
			(stroke
				(width 0.1)
				(type default)
			)
			(layer "F.Fab")
		)
		(fp_line
			(start -0.12065 -0.2794)
			(end 0.12065 -0.2794)
			(stroke
				(width 0.1)
				(type default)
			)
			(layer "F.Fab")
		)
		(fp_line
			(start -0.12065 0.2794)
			(end -0.12065 0.3048)
			(stroke
				(width 0.1)
				(type default)
			)
			(layer "F.Fab")
		)
		(fp_line
			(start -0.12065 0.3048)
			(end -0.67945 0.3048)
			(stroke
				(width 0.1)
				(type default)
			)
			(layer "F.Fab")
		)
		(fp_line
			(start 0.120396 0.2794)
			(end -0.12065 0.2794)
			(stroke
				(width 0.1)
				(type default)
			)
			(layer "F.Fab")
		)
		(fp_line
			(start 0.120396 0.3048)
			(end 0.120396 0.2794)
			(stroke
				(width 0.1)
				(type default)
			)
			(layer "F.Fab")
		)
		(fp_line
			(start 0.12065 -0.3048)
			(end 0.67945 -0.3048)
			(stroke
				(width 0.1)
				(type default)
			)
			(layer "F.Fab")
		)
		(fp_line
			(start 0.12065 -0.2794)
			(end 0.12065 -0.3048)
			(stroke
				(width 0.1)
				(type default)
			)
			(layer "F.Fab")
		)
		(fp_line
			(start 0.67945 -0.3048)
			(end 0.67945 0.3048)
			(stroke
				(width 0.1)
				(type default)
			)
			(layer "F.Fab")
		)
		(fp_line
			(start 0.67945 0.3048)
			(end 0.120396 0.3048)
			(stroke
				(width 0.1)
				(type default)
			)
			(layer "F.Fab")
		)
		(pad "1" smd circle
			(at -0.40005 0)
			(size 0 0)
			(layers "F.Cu" "F.Mask" "F.Paste")
			(net "FM_THERMAL_ALERT_N")
		)
		(pad "2" smd circle
			(at 0.40005 0)
			(size 0 0)
			(layers "F.Cu" "F.Mask" "F.Paste")
			(net "FM_LM75_3_ALERT_N")
		)
	)
	(footprint ""
		(layer "F.Cu")
		(at 275.14169 -98.355404 180)
		(property "Reference" "R1644"
			(at 0 0 180)
			(layer "F.SilkS")
			(hide yes)
			(effects
				(font
					(size 1.27 1.27)
				)
			)
		)
		(property "Value" ""
			(at 0 0 180)
			(layer "F.Fab")
			(effects
				(font
					(size 1.27 1.27)
				)
			)
		)
		(duplicate_pad_numbers_are_jumpers no)
		(fp_line
			(start 0.7874 0.4064)
			(end -0.7874 0.4064)
			(stroke
				(width 0.1524)
				(type default)
			)
			(layer "F.SilkS")
		)
		(fp_line
			(start 0.7874 -0.4064)
			(end 0.7874 0.4064)
			(stroke
				(width 0.1524)
				(type default)
			)
			(layer "F.SilkS")
		)
		(fp_line
			(start -0.7874 0.4064)
			(end -0.7874 -0.4064)
			(stroke
				(width 0.1524)
				(type default)
			)
			(layer "F.SilkS")
		)
		(fp_line
			(start -0.7874 -0.4064)
			(end 0.7874 -0.4064)
			(stroke
				(width 0.1524)
				(type default)
			)
			(layer "F.SilkS")
		)
		(fp_line
			(start 0.67945 0.3048)
			(end 0.120396 0.3048)
			(stroke
				(width 0.1)
				(type default)
			)
			(layer "F.Fab")
		)
		(fp_line
			(start 0.67945 -0.3048)
			(end 0.67945 0.3048)
			(stroke
				(width 0.1)
				(type default)
			)
			(layer "F.Fab")
		)
		(fp_line
			(start 0.12065 -0.2794)
			(end 0.12065 -0.3048)
			(stroke
				(width 0.1)
				(type default)
			)
			(layer "F.Fab")
		)
		(fp_line
			(start 0.12065 -0.3048)
			(end 0.67945 -0.3048)
			(stroke
				(width 0.1)
				(type default)
			)
			(layer "F.Fab")
		)
		(fp_line
			(start 0.120396 0.3048)
			(end 0.120396 0.2794)
			(stroke
				(width 0.1)
				(type default)
			)
			(layer "F.Fab")
		)
		(fp_line
			(start 0.120396 0.2794)
			(end -0.12065 0.2794)
			(stroke
				(width 0.1)
				(type default)
			)
			(layer "F.Fab")
		)
		(fp_line
			(start -0.12065 0.3048)
			(end -0.67945 0.3048)
			(stroke
				(width 0.1)
				(type default)
			)
			(layer "F.Fab")
		)
		(fp_line
			(start -0.12065 0.2794)
			(end -0.12065 0.3048)
			(stroke
				(width 0.1)
				(type default)
			)
			(layer "F.Fab")
		)
		(fp_line
			(start -0.12065 -0.2794)
			(end 0.12065 -0.2794)
			(stroke
				(width 0.1)
				(type default)
			)
			(layer "F.Fab")
		)
		(fp_line
			(start -0.12065 -0.305054)
			(end -0.12065 -0.2794)
			(stroke
				(width 0.1)
				(type default)
			)
			(layer "F.Fab")
		)
		(fp_line
			(start -0.67945 0.3048)
			(end -0.67945 -0.305054)
			(stroke
				(width 0.1)
				(type default)
			)
			(layer "F.Fab")
		)
		(fp_line
			(start -0.67945 -0.305054)
			(end -0.12065 -0.305054)
			(stroke
				(width 0.1)
				(type default)
			)
			(layer "F.Fab")
		)
		(pad "1" smd circle
			(at -0.40005 0 180)
			(size 0 0)
			(layers "F.Cu" "F.Mask" "F.Paste")
			(net "JTAG_P1_R_TRST_N")
		)
		(pad "2" smd circle
			(at 0.40005 0 180)
			(size 0 0)
			(layers "F.Cu" "F.Mask" "F.Paste")
			(net "JTAG_CPU1_TRST_N")
		)
	)
	(footprint ""
		(layer "F.Cu")
		(at 70.662546 -384.10388 180)
		(property "Reference" "R6701"
			(at 0 0 180)
			(layer "F.SilkS")
			(hide yes)
			(effects
				(font
					(size 1.27 1.27)
				)
			)
		)
		(property "Value" ""
			(at 0 0 180)
			(layer "F.Fab")
			(effects
				(font
					(size 1.27 1.27)
				)
			)
		)
		(duplicate_pad_numbers_are_jumpers no)
		(fp_line
			(start 0.7874 0.4064)
			(end -0.7874 0.4064)
			(stroke
				(width 0.1524)
				(type default)
			)
			(layer "F.SilkS")
		)
		(fp_line
			(start 0.7874 -0.4064)
			(end 0.7874 0.4064)
			(stroke
				(width 0.1524)
				(type default)
			)
			(layer "F.SilkS")
		)
		(fp_line
			(start -0.7874 0.4064)
			(end -0.7874 -0.4064)
			(stroke
				(width 0.1524)
				(type default)
			)
			(layer "F.SilkS")
		)
		(fp_line
			(start -0.7874 -0.4064)
			(end 0.7874 -0.4064)
			(stroke
				(width 0.1524)
				(type default)
			)
			(layer "F.SilkS")
		)
		(fp_line
			(start 0.67945 0.3048)
			(end 0.120396 0.3048)
			(stroke
				(width 0.1)
				(type default)
			)
			(layer "F.Fab")
		)
		(fp_line
			(start 0.67945 -0.3048)
			(end 0.67945 0.3048)
			(stroke
				(width 0.1)
				(type default)
			)
			(layer "F.Fab")
		)
		(fp_line
			(start 0.12065 -0.2794)
			(end 0.12065 -0.3048)
			(stroke
				(width 0.1)
				(type default)
			)
			(layer "F.Fab")
		)
		(fp_line
			(start 0.12065 -0.3048)
			(end 0.67945 -0.3048)
			(stroke
				(width 0.1)
				(type default)
			)
			(layer "F.Fab")
		)
		(fp_line
			(start 0.120396 0.3048)
			(end 0.120396 0.2794)
			(stroke
				(width 0.1)
				(type default)
			)
			(layer "F.Fab")
		)
		(fp_line
			(start 0.120396 0.2794)
			(end -0.12065 0.2794)
			(stroke
				(width 0.1)
				(type default)
			)
			(layer "F.Fab")
		)
		(fp_line
			(start -0.12065 0.3048)
			(end -0.67945 0.3048)
			(stroke
				(width 0.1)
				(type default)
			)
			(layer "F.Fab")
		)
		(fp_line
			(start -0.12065 0.2794)
			(end -0.12065 0.3048)
			(stroke
				(width 0.1)
				(type default)
			)
			(layer "F.Fab")
		)
		(fp_line
			(start -0.12065 -0.2794)
			(end 0.12065 -0.2794)
			(stroke
				(width 0.1)
				(type default)
			)
			(layer "F.Fab")
		)
		(fp_line
			(start -0.12065 -0.305054)
			(end -0.12065 -0.2794)
			(stroke
				(width 0.1)
				(type default)
			)
			(layer "F.Fab")
		)
		(fp_line
			(start -0.67945 0.3048)
			(end -0.67945 -0.305054)
			(stroke
				(width 0.1)
				(type default)
			)
			(layer "F.Fab")
		)
		(fp_line
			(start -0.67945 -0.305054)
			(end -0.12065 -0.305054)
			(stroke
				(width 0.1)
				(type default)
			)
			(layer "F.Fab")
		)
		(pad "1" smd rect
			(at -0.40005 0)
			(size 0.4572 0.508)
			(layers "F.Cu" "F.Mask" "F.Paste")
			(net "P1V8_CPU1_RT_1D")
		)
		(pad "2" smd rect
			(at 0.40005 0)
			(size 0.4572 0.508)
			(layers "F.Cu" "F.Mask" "F.Paste")
			(net "P1V8_CPU1_RT0_1A_1D")
		)
	)
	(footprint ""
		(layer "F.Cu")
		(at 446.036954 -401.785328 90)
		(property "Reference" "PR6554"
			(at 0 0 90)
			(layer "F.SilkS")
			(hide yes)
			(effects
				(font
					(size 1.27 1.27)
				)
			)
		)
		(property "Value" ""
			(at 0 0 90)
			(layer "F.Fab")
			(effects
				(font
					(size 1.27 1.27)
				)
			)
		)
		(duplicate_pad_numbers_are_jumpers no)
		(fp_line
			(start 0.7874 -0.4064)
			(end 0.7874 0.4064)
			(stroke
				(width 0.1524)
				(type default)
			)
			(layer "F.SilkS")
		)
		(fp_line
			(start -0.7874 -0.4064)
			(end 0.7874 -0.4064)
			(stroke
				(width 0.1524)
				(type default)
			)
			(layer "F.SilkS")
		)
		(fp_line
			(start 0.7874 0.4064)
			(end -0.7874 0.4064)
			(stroke
				(width 0.1524)
				(type default)
			)
			(layer "F.SilkS")
		)
		(fp_line
			(start -0.7874 0.4064)
			(end -0.7874 -0.4064)
			(stroke
				(width 0.1524)
				(type default)
			)
			(layer "F.SilkS")
		)
		(fp_line
			(start -0.12065 -0.305054)
			(end -0.12065 -0.2794)
			(stroke
				(width 0.1)
				(type default)
			)
			(layer "F.Fab")
		)
		(fp_line
			(start -0.67945 -0.305054)
			(end -0.12065 -0.305054)
			(stroke
				(width 0.1)
				(type default)
			)
			(layer "F.Fab")
		)
		(fp_line
			(start 0.67945 -0.3048)
			(end 0.67945 0.3048)
			(stroke
				(width 0.1)
				(type default)
			)
			(layer "F.Fab")
		)
		(fp_line
			(start 0.12065 -0.3048)
			(end 0.67945 -0.3048)
			(stroke
				(width 0.1)
				(type default)
			)
			(layer "F.Fab")
		)
		(fp_line
			(start 0.12065 -0.2794)
			(end 0.12065 -0.3048)
			(stroke
				(width 0.1)
				(type default)
			)
			(layer "F.Fab")
		)
		(fp_line
			(start -0.12065 -0.2794)
			(end 0.12065 -0.2794)
			(stroke
				(width 0.1)
				(type default)
			)
			(layer "F.Fab")
		)
		(fp_line
			(start 0.120396 0.2794)
			(end -0.12065 0.2794)
			(stroke
				(width 0.1)
				(type default)
			)
			(layer "F.Fab")
		)
		(fp_line
			(start -0.12065 0.2794)
			(end -0.12065 0.3048)
			(stroke
				(width 0.1)
				(type default)
			)
			(layer "F.Fab")
		)
		(fp_line
			(start 0.67945 0.3048)
			(end 0.120396 0.3048)
			(stroke
				(width 0.1)
				(type default)
			)
			(layer "F.Fab")
		)
		(fp_line
			(start 0.120396 0.3048)
			(end 0.120396 0.2794)
			(stroke
				(width 0.1)
				(type default)
			)
			(layer "F.Fab")
		)
		(fp_line
			(start -0.12065 0.3048)
			(end -0.67945 0.3048)
			(stroke
				(width 0.1)
				(type default)
			)
			(layer "F.Fab")
		)
		(fp_line
			(start -0.67945 0.3048)
			(end -0.67945 -0.305054)
			(stroke
				(width 0.1)
				(type default)
			)
			(layer "F.Fab")
		)
		(pad "1" smd circle
			(at -0.40005 0 90)
			(size 0 0)
			(layers "F.Cu" "F.Mask" "F.Paste")
			(net "SW_P0V9_RETIMER_CPU0_BOOT1")
		)
		(pad "2" smd circle
			(at 0.40005 0 90)
			(size 0 0)
			(layers "F.Cu" "F.Mask" "F.Paste")
			(net "SW_P0V9_RETIMER_CPU0_BOOT1_RC")
		)
	)
	(footprint ""
		(layer "F.Cu")
		(at 133.127496 -370.57203 -90)
		(property "Reference" "C54"
			(at 0 0 270)
			(layer "F.SilkS")
			(hide yes)
			(effects
				(font
					(size 1.27 1.27)
				)
			)
		)
		(property "Value" ""
			(at 0 0 270)
			(layer "F.Fab")
			(effects
				(font
					(size 1.27 1.27)
				)
			)
		)
		(duplicate_pad_numbers_are_jumpers no)
		(fp_line
			(start -0.299974 0.150114)
			(end -0.299974 -0.150114)
			(stroke
				(width 0.1)
				(type default)
			)
			(layer "F.Fab")
		)
		(fp_line
			(start 0.299974 0.150114)
			(end -0.299974 0.150114)
			(stroke
				(width 0.1)
				(type default)
			)
			(layer "F.Fab")
		)
		(fp_line
			(start -0.299974 -0.150114)
			(end 0.299974 -0.150114)
			(stroke
				(width 0.1)
				(type default)
			)
			(layer "F.Fab")
		)
		(fp_line
			(start 0.299974 -0.150114)
			(end 0.299974 0.150114)
			(stroke
				(width 0.1)
				(type default)
			)
			(layer "F.Fab")
		)
		(pad "1" smd rect
			(at -0.2667 0 270)
			(size 0.3048 0.381)
			(layers "F.Cu" "F.Mask" "F.Paste")
			(net "P5E_CPU1_P3_TX_C_DN<12>")
		)
		(pad "2" smd rect
			(at 0.2667 0 270)
			(size 0.3048 0.381)
			(layers "F.Cu" "F.Mask" "F.Paste")
			(net "P5E_CPU1_P3_TX_DN<12>")
		)
	)
	(footprint ""
		(layer "F.Cu")
		(at 312.467752 -395.724634)
		(property "Reference" "U6010"
			(at -6.426454 -7.380224 0)
			(unlocked yes)
			(layer "F.SilkS")
			(effects
				(font
					(size 0.7874 0.5842)
					(thickness 0.1524)
				)
				(justify left)
			)
		)
		(property "Value" ""
			(at 0 0 0)
			(layer "F.Fab")
			(effects
				(font
					(size 1.27 1.27)
				)
			)
		)
		(duplicate_pad_numbers_are_jumpers no)
		(fp_line
			(start -11.400028 -4.45008)
			(end -9.852152 -4.45008)
			(stroke
				(width 0.1524)
				(type default)
			)
			(layer "F.SilkS")
		)
		(fp_line
			(start -11.400028 -0.794766)
			(end -11.400028 -4.45008)
			(stroke
				(width 0.1524)
				(type default)
			)
			(layer "F.SilkS")
		)
		(fp_line
			(start -11.400028 4.45008)
			(end -11.400028 0.145034)
			(stroke
				(width 0.1524)
				(type default)
			)
			(layer "F.SilkS")
		)
		(fp_line
			(start -9.725152 4.45008)
			(end -11.400028 4.45008)
			(stroke
				(width 0.1524)
				(type default)
			)
			(layer "F.SilkS")
		)
		(fp_line
			(start 9.553448 -4.45008)
			(end 11.400028 -4.45008)
			(stroke
				(width 0.1524)
				(type default)
			)
			(layer "F.SilkS")
		)
		(fp_line
			(start 11.400028 -4.45008)
			(end 11.400028 4.45008)
			(stroke
				(width 0.1524)
				(type default)
			)
			(layer "F.SilkS")
		)
		(fp_line
			(start 11.400028 4.45008)
			(end 9.528048 4.45008)
			(stroke
				(width 0.1524)
				(type default)
			)
			(layer "F.SilkS")
		)
		(fp_poly
			(pts
				(xy 10.450068 -4.45008) (xy 10.450068 -5.21208) (xy 12.162028 -5.21208) (xy 12.162028 -3.41884)
				(xy 11.400028 -3.41884) (xy 11.400028 -4.45008)
			)
			(stroke
				(width 0)
				(type default)
			)
			(fill yes)
			(layer "F.SilkS")
		)
		(fp_line
			(start -11.400028 -4.45008)
			(end -11.400028 4.45008)
			(stroke
				(width 0.1)
				(type default)
			)
			(layer "F.Fab")
		)
		(fp_line
			(start -11.400028 4.45008)
			(end 11.400028 4.45008)
			(stroke
				(width 0.1)
				(type default)
			)
			(layer "F.Fab")
		)
		(fp_line
			(start 11.400028 -4.45008)
			(end -11.400028 -4.45008)
			(stroke
				(width 0.1)
				(type default)
			)
			(layer "F.Fab")
		)
		(fp_line
			(start 11.400028 4.45008)
			(end 11.400028 -4.45008)
			(stroke
				(width 0.1)
				(type default)
			)
			(layer "F.Fab")
		)
		(fp_poly
			(pts
				(xy 10.450068 -4.45008) (xy 10.450068 -5.21208) (xy 12.162028 -5.21208) (xy 12.162028 -3.41884)
				(xy 11.400028 -3.41884) (xy 11.400028 -4.45008)
			)
			(stroke
				(width 0)
				(type default)
			)
			(fill yes)
			(layer "F.Fab")
		)
		(pad "A1" smd oval
			(at 11.050016 -3.938524)
			(size 0.254 0.3302)
			(layers "F.Cu" "F.Mask" "F.Paste")
			(net "NCF_A1_CPU0_P0_GND")
		)
		(pad "A35" smd oval
			(at 11.050016 3.940048)
			(size 0.254 0.3302)
			(layers "F.Cu" "F.Mask" "F.Paste")
			(net "NCF_CPU0_P0_GND")
		)
		(pad "AA10" smd circle
			(at 7.602728 -1.431798)
			(size 0.381 0.381)
			(layers "F.Cu" "F.Mask" "F.Paste")
			(net "P5E_CPU0_P0_TX_BUF_DN<14>")
		)
		(pad "AA29" smd circle
			(at 7.602728 2.032254)
			(size 0.381 0.381)
			(layers "F.Cu" "F.Mask" "F.Paste")
			(net "P5E_CPU0_P0_RX_DN<14>")
		)
		(pad "AB1" smd oval
			(at 7.450074 -3.938524)
			(size 0.254 0.3302)
			(layers "F.Cu" "F.Mask" "F.Paste")
			(net "P5E_CPU0_P0_RX_BUF_DP<14>")
		)
		(pad "AB35" smd oval
			(at 7.450074 3.940048)
			(size 0.254 0.3302)
			(layers "F.Cu" "F.Mask" "F.Paste")
			(net "P5E_CPU0_P0_TX_C_DP<14>")
		)
		(pad "AC4" smd circle
			(at 7.202678 -2.817368)
			(size 0.381 0.381)
			(layers "F.Cu" "F.Mask" "F.Paste")
			(net "GND")
		)
		(pad "AC13" smd circle
			(at 7.202678 -0.79629)
			(size 0.3048 0.3048)
			(layers "F.Cu" "F.Mask" "F.Paste")
			(net "GND")
		)
		(pad "AC17" smd circle
			(at 7.202678 -0.296164)
			(size 0.3048 0.3048)
			(layers "F.Cu" "F.Mask" "F.Paste")
			(net "P0V9_CPU0_RT0_2A")
		)
		(pad "AC20" smd circle
			(at 7.202678 0.203708)
			(size 0.3048 0.3048)
			(layers "F.Cu" "F.Mask" "F.Paste")
			(net "P0V9_CPU0_RT0_2A")
		)
		(pad "AC22" smd circle
			(at 7.202678 0.703834)
			(size 0.3048 0.3048)
			(layers "F.Cu" "F.Mask" "F.Paste")
			(net "GND")
		)
		(pad "AC32" smd circle
			(at 7.202678 2.724912)
			(size 0.381 0.381)
			(layers "F.Cu" "F.Mask" "F.Paste")
			(net "GND")
		)
		(pad "AD2" smd circle
			(at 7.1501 -3.41884)
			(size 0.3048 0.3048)
			(layers "F.Cu" "F.Mask" "F.Paste")
			(net "GND")
		)
		(pad "AD34" smd circle
			(at 7.1501 3.420364)
			(size 0.3048 0.3048)
			(layers "F.Cu" "F.Mask" "F.Paste")
			(net "GND")
		)
		(pad "AE1" smd oval
			(at 6.849872 -3.938524)
			(size 0.254 0.3302)
			(layers "F.Cu" "F.Mask" "F.Paste")
			(net "GND")
		)
		(pad "AE35" smd oval
			(at 6.849872 3.940048)
			(size 0.254 0.3302)
			(layers "F.Cu" "F.Mask" "F.Paste")
			(net "GND")
		)
		(pad "AF7" smd circle
			(at 6.802628 -2.12471)
			(size 0.381 0.381)
			(layers "F.Cu" "F.Mask" "F.Paste")
			(net "P5E_CPU0_P0_TX_BUF_DP<13>")
		)
		(pad "AF26" smd circle
			(at 6.802628 1.339342)
			(size 0.381 0.381)
			(layers "F.Cu" "F.Mask" "F.Paste")
			(net "P5E_CPU0_P0_RX_DP<13>")
		)
		(pad "AG2" smd circle
			(at 6.549898 -3.41884)
			(size 0.3048 0.3048)
			(layers "F.Cu" "F.Mask" "F.Paste")
			(net "P5E_CPU0_P0_RX_BUF_DN<13>")
		)
		(pad "AG34" smd circle
			(at 6.549898 3.420364)
			(size 0.3048 0.3048)
			(layers "F.Cu" "F.Mask" "F.Paste")
			(net "P5E_CPU0_P0_TX_C_DP<13>")
		)
		(pad "AH10" smd circle
			(at 6.402578 -1.431798)
			(size 0.381 0.381)
			(layers "F.Cu" "F.Mask" "F.Paste")
			(net "P5E_CPU0_P0_TX_BUF_DN<13>")
		)
		(pad "AH29" smd circle
			(at 6.402578 2.032254)
			(size 0.381 0.381)
			(layers "F.Cu" "F.Mask" "F.Paste")
			(net "P5E_CPU0_P0_RX_DN<13>")
		)
		(pad "AJ1" smd oval
			(at 6.249924 -3.938524)
			(size 0.254 0.3302)
			(layers "F.Cu" "F.Mask" "F.Paste")
			(net "P5E_CPU0_P0_RX_BUF_DP<13>")
		)
		(pad "AJ35" smd oval
			(at 6.249924 3.940048)
			(size 0.254 0.3302)
			(layers "F.Cu" "F.Mask" "F.Paste")
			(net "P5E_CPU0_P0_TX_C_DN<13>")
		)
		(pad "AK4" smd circle
			(at 6.002528 -2.817368)
			(size 0.381 0.381)
			(layers "F.Cu" "F.Mask" "F.Paste")
			(net "GND")
		)
		(pad "AK13" smd circle
			(at 6.002528 -0.79629)
			(size 0.3048 0.3048)
			(layers "F.Cu" "F.Mask" "F.Paste")
			(net "GND")
		)
		(pad "AK17" smd circle
			(at 6.002528 -0.296164)
			(size 0.3048 0.3048)
			(layers "F.Cu" "F.Mask" "F.Paste")
			(net "P0V9_CPU0_RT0_2A")
		)
		(pad "AK20" smd circle
			(at 6.002528 0.203708)
			(size 0.3048 0.3048)
			(layers "F.Cu" "F.Mask" "F.Paste")
			(net "P0V9_CPU0_RT0_2A")
		)
		(pad "AK22" smd circle
			(at 6.002528 0.703834)
			(size 0.3048 0.3048)
			(layers "F.Cu" "F.Mask" "F.Paste")
			(net "GND")
		)
		(pad "AK32" smd circle
			(at 6.002528 2.724912)
			(size 0.381 0.381)
			(layers "F.Cu" "F.Mask" "F.Paste")
			(net "GND")
		)
		(pad "AL2" smd circle
			(at 5.94995 -3.41884)
			(size 0.3048 0.3048)
			(layers "F.Cu" "F.Mask" "F.Paste")
			(net "GND")
		)
		(pad "AL34" smd circle
			(at 5.94995 3.420364)
			(size 0.3048 0.3048)
			(layers "F.Cu" "F.Mask" "F.Paste")
			(net "GND")
		)
		(pad "AM1" smd oval
			(at 5.649976 -3.938524)
			(size 0.254 0.3302)
			(layers "F.Cu" "F.Mask" "F.Paste")
			(net "GND")
		)
		(pad "AM35" smd oval
			(at 5.649976 3.940048)
			(size 0.254 0.3302)
			(layers "F.Cu" "F.Mask" "F.Paste")
			(net "GND")
		)
		(pad "AN7" smd circle
			(at 5.602478 -2.12471)
			(size 0.381 0.381)
			(layers "F.Cu" "F.Mask" "F.Paste")
			(net "P5E_CPU0_P0_TX_BUF_DP<12>")
		)
		(pad "AN26" smd circle
			(at 5.602478 1.339342)
			(size 0.381 0.381)
			(layers "F.Cu" "F.Mask" "F.Paste")
			(net "P5E_CPU0_P0_RX_DP<12>")
		)
		(pad "AP2" smd circle
			(at 5.350002 -3.41884)
			(size 0.3048 0.3048)
			(layers "F.Cu" "F.Mask" "F.Paste")
			(net "P5E_CPU0_P0_RX_BUF_DN<12>")
		)
		(pad "AP34" smd circle
			(at 5.350002 3.420364)
			(size 0.3048 0.3048)
			(layers "F.Cu" "F.Mask" "F.Paste")
			(net "P5E_CPU0_P0_TX_C_DN<12>")
		)
		(pad "AR10" smd circle
			(at 5.202682 -1.431798)
			(size 0.381 0.381)
			(layers "F.Cu" "F.Mask" "F.Paste")
			(net "P5E_CPU0_P0_TX_BUF_DN<12>")
		)
		(pad "AR29" smd circle
			(at 5.202682 2.032254)
			(size 0.381 0.381)
			(layers "F.Cu" "F.Mask" "F.Paste")
			(net "P5E_CPU0_P0_RX_DN<12>")
		)
		(pad "AT1" smd oval
			(at 5.050028 -3.938524)
			(size 0.254 0.3302)
			(layers "F.Cu" "F.Mask" "F.Paste")
			(net "P5E_CPU0_P0_RX_BUF_DP<12>")
		)
		(pad "AT35" smd oval
			(at 5.050028 3.940048)
			(size 0.254 0.3302)
			(layers "F.Cu" "F.Mask" "F.Paste")
			(net "P5E_CPU0_P0_TX_C_DP<12>")
		)
		(pad "AU4" smd circle
			(at 4.802632 -2.817368)
			(size 0.381 0.381)
			(layers "F.Cu" "F.Mask" "F.Paste")
			(net "GND")
		)
		(pad "AU13" smd circle
			(at 4.802632 -0.79629)
			(size 0.3048 0.3048)
			(layers "F.Cu" "F.Mask" "F.Paste")
			(net "GND")
		)
		(pad "AU17" smd circle
			(at 4.802632 -0.296164)
			(size 0.3048 0.3048)
			(layers "F.Cu" "F.Mask" "F.Paste")
			(net "P0V9_CPU0_RT0_2A")
		)
		(pad "AU20" smd circle
			(at 4.802632 0.203708)
			(size 0.3048 0.3048)
			(layers "F.Cu" "F.Mask" "F.Paste")
			(net "P0V9_CPU0_RT0_2A")
		)
		(pad "AU22" smd circle
			(at 4.802632 0.703834)
			(size 0.3048 0.3048)
			(layers "F.Cu" "F.Mask" "F.Paste")
			(net "GND")
		)
		(pad "AU32" smd circle
			(at 4.802632 2.724912)
			(size 0.381 0.381)
			(layers "F.Cu" "F.Mask" "F.Paste")
			(net "GND")
		)
		(pad "AV2" smd circle
			(at 4.750054 -3.41884)
			(size 0.3048 0.3048)
			(layers "F.Cu" "F.Mask" "F.Paste")
			(net "GND")
		)
		(pad "AV34" smd circle
			(at 4.750054 3.420364)
			(size 0.3048 0.3048)
			(layers "F.Cu" "F.Mask" "F.Paste")
			(net "GND")
		)
		(pad "AW1" smd oval
			(at 4.45008 -3.938524)
			(size 0.254 0.3302)
			(layers "F.Cu" "F.Mask" "F.Paste")
			(net "GND")
		)
		(pad "AW35" smd oval
			(at 4.45008 3.940048)
			(size 0.254 0.3302)
			(layers "F.Cu" "F.Mask" "F.Paste")
			(net "GND")
		)
		(pad "AY7" smd circle
			(at 4.402582 -2.12471)
			(size 0.381 0.381)
			(layers "F.Cu" "F.Mask" "F.Paste")
			(net "P5E_CPU0_P0_TX_BUF_DP<11>")
		)
		(pad "AY26" smd circle
			(at 4.402582 1.339342)
			(size 0.381 0.381)
			(layers "F.Cu" "F.Mask" "F.Paste")
			(net "P5E_CPU0_P0_RX_DP<11>")
		)
		(pad "B3" smd oval
			(at 10.885932 -2.888488 90)
			(size 0.254 0.3302)
			(layers "F.Cu" "F.Mask" "F.Paste")
			(net "JTAG_TCK_RT_CPU0_P0")
		)
		(pad "B6" smd oval
			(at 10.885932 -2.288286 90)
			(size 0.254 0.3302)
			(layers "F.Cu" "F.Mask" "F.Paste")
			(net "JTAG_TDI_RT_CPU0_P0")
		)
		(pad "B9" smd oval
			(at 10.885932 -1.688338 90)
			(size 0.254 0.3302)
			(layers "F.Cu" "F.Mask" "F.Paste")
			(net "JTAG_TDO_RT_CPU0_P0")
		)
		(pad "B12" smd oval
			(at 10.885932 -1.08839 90)
			(size 0.254 0.3302)
			(layers "F.Cu" "F.Mask" "F.Paste")
			(net "JTAG_TMS_RT_CPU0_P0")
		)
		(pad "B16" smd oval
			(at 10.885932 -0.488442 90)
			(size 0.254 0.3302)
			(layers "F.Cu" "F.Mask" "F.Paste")
			(net "Net_2203")
		)
		(pad "B19" smd oval
			(at 10.885932 0.111506 90)
			(size 0.254 0.3302)
			(layers "F.Cu" "F.Mask" "F.Paste")
			(net "GND")
		)
		(pad "B23" smd oval
			(at 10.885932 0.711708 90)
			(size 0.254 0.3302)
			(layers "F.Cu" "F.Mask" "F.Paste")
			(net "RT_CPU0_P0_ADDR2")
		)
		(pad "B25" smd oval
			(at 10.885932 1.311656 90)
			(size 0.254 0.3302)
			(layers "F.Cu" "F.Mask" "F.Paste")
			(net "RT_CPU0_P0_ADDR3")
		)
		(pad "B28" smd oval
			(at 10.885932 1.911604 90)
			(size 0.254 0.3302)
			(layers "F.Cu" "F.Mask" "F.Paste")
			(net "SMB_RT_CPU0_P0_R2_SDA")
		)
		(pad "B31" smd oval
			(at 10.885932 2.511552 90)
			(size 0.254 0.3302)
			(layers "F.Cu" "F.Mask" "F.Paste")
			(net "SMB_RT_CPU0_P0_R2_SCL")
		)
		(pad "BA2" smd circle
			(at 4.150106 -3.41884)
			(size 0.3048 0.3048)
			(layers "F.Cu" "F.Mask" "F.Paste")
			(net "P5E_CPU0_P0_RX_BUF_DN<11>")
		)
		(pad "BA34" smd circle
			(at 4.150106 3.420364)
			(size 0.3048 0.3048)
			(layers "F.Cu" "F.Mask" "F.Paste")
			(net "P5E_CPU0_P0_TX_C_DN<11>")
		)
		(pad "BB10" smd circle
			(at 4.002532 -1.431798)
			(size 0.381 0.381)
			(layers "F.Cu" "F.Mask" "F.Paste")
			(net "P5E_CPU0_P0_TX_BUF_DN<11>")
		)
		(pad "BB29" smd circle
			(at 4.002532 2.032254)
			(size 0.381 0.381)
			(layers "F.Cu" "F.Mask" "F.Paste")
			(net "P5E_CPU0_P0_RX_DN<11>")
		)
		(pad "BC1" smd oval
			(at 3.849878 -3.938524)
			(size 0.254 0.3302)
			(layers "F.Cu" "F.Mask" "F.Paste")
			(net "P5E_CPU0_P0_RX_BUF_DP<11>")
		)
		(pad "BC35" smd oval
			(at 3.849878 3.940048)
			(size 0.254 0.3302)
			(layers "F.Cu" "F.Mask" "F.Paste")
			(net "P5E_CPU0_P0_TX_C_DP<11>")
		)
		(pad "BD4" smd circle
			(at 3.602482 -2.817368)
			(size 0.381 0.381)
			(layers "F.Cu" "F.Mask" "F.Paste")
			(net "GND")
		)
		(pad "BD13" smd circle
			(at 3.602482 -0.79629)
			(size 0.3048 0.3048)
			(layers "F.Cu" "F.Mask" "F.Paste")
			(net "GND")
		)
		(pad "BD17" smd circle
			(at 3.602482 -0.296164)
			(size 0.3048 0.3048)
			(layers "F.Cu" "F.Mask" "F.Paste")
			(net "P0V9_CPU0_RT0_2A_2D")
		)
		(pad "BD20" smd circle
			(at 3.602482 0.203708)
			(size 0.3048 0.3048)
			(layers "F.Cu" "F.Mask" "F.Paste")
			(net "P0V9_CPU0_RT0_2A_2D")
		)
		(pad "BD22" smd circle
			(at 3.602482 0.703834)
			(size 0.3048 0.3048)
			(layers "F.Cu" "F.Mask" "F.Paste")
			(net "GND")
		)
		(pad "BD32" smd circle
			(at 3.602482 2.724912)
			(size 0.381 0.381)
			(layers "F.Cu" "F.Mask" "F.Paste")
			(net "GND")
		)
		(pad "BE2" smd circle
			(at 3.549904 -3.41884)
			(size 0.3048 0.3048)
			(layers "F.Cu" "F.Mask" "F.Paste")
			(net "GND")
		)
		(pad "BE34" smd circle
			(at 3.549904 3.420364)
			(size 0.3048 0.3048)
			(layers "F.Cu" "F.Mask" "F.Paste")
			(net "GND")
		)
		(pad "BF1" smd oval
			(at 3.24993 -3.938524)
			(size 0.254 0.3302)
			(layers "F.Cu" "F.Mask" "F.Paste")
			(net "GND")
		)
		(pad "BF35" smd oval
			(at 3.24993 3.940048)
			(size 0.254 0.3302)
			(layers "F.Cu" "F.Mask" "F.Paste")
			(net "GND")
		)
		(pad "BG7" smd circle
			(at 3.202686 -2.12471)
			(size 0.381 0.381)
			(layers "F.Cu" "F.Mask" "F.Paste")
			(net "P5E_CPU0_P0_TX_BUF_DP<10>")
		)
		(pad "BG26" smd circle
			(at 3.202686 1.339342)
			(size 0.381 0.381)
			(layers "F.Cu" "F.Mask" "F.Paste")
			(net "P5E_CPU0_P0_RX_DP<10>")
		)
		(pad "BH2" smd circle
			(at 2.949956 -3.41884)
			(size 0.3048 0.3048)
			(layers "F.Cu" "F.Mask" "F.Paste")
			(net "P5E_CPU0_P0_RX_BUF_DN<10>")
		)
		(pad "BH34" smd circle
			(at 2.949956 3.420364)
			(size 0.3048 0.3048)
			(layers "F.Cu" "F.Mask" "F.Paste")
			(net "P5E_CPU0_P0_TX_C_DN<10>")
		)
		(pad "BJ10" smd circle
			(at 2.802636 -1.431798)
			(size 0.381 0.381)
			(layers "F.Cu" "F.Mask" "F.Paste")
			(net "P5E_CPU0_P0_TX_BUF_DN<10>")
		)
		(pad "BJ29" smd circle
			(at 2.802636 2.032254)
			(size 0.381 0.381)
			(layers "F.Cu" "F.Mask" "F.Paste")
			(net "P5E_CPU0_P0_RX_DN<10>")
		)
		(pad "BK1" smd oval
			(at 2.649982 -3.938524)
			(size 0.254 0.3302)
			(layers "F.Cu" "F.Mask" "F.Paste")
			(net "P5E_CPU0_P0_RX_BUF_DP<10>")
		)
		(pad "BK35" smd oval
			(at 2.649982 3.940048)
			(size 0.254 0.3302)
			(layers "F.Cu" "F.Mask" "F.Paste")
			(net "P5E_CPU0_P0_TX_C_DP<10>")
		)
		(pad "BL4" smd circle
			(at 2.402586 -2.817368)
			(size 0.381 0.381)
			(layers "F.Cu" "F.Mask" "F.Paste")
			(net "GND")
		)
		(pad "BL13" smd circle
			(at 2.402586 -0.79629)
			(size 0.3048 0.3048)
			(layers "F.Cu" "F.Mask" "F.Paste")
			(net "GND")
		)
		(pad "BL17" smd circle
			(at 2.402586 -0.296164)
			(size 0.3048 0.3048)
			(layers "F.Cu" "F.Mask" "F.Paste")
			(net "P0V9_CPU0_RT_2D")
		)
		(pad "BL20" smd circle
			(at 2.402586 0.203708)
			(size 0.3048 0.3048)
			(layers "F.Cu" "F.Mask" "F.Paste")
			(net "P0V9_CPU0_RT_2D")
		)
		(pad "BL22" smd circle
			(at 2.402586 0.703834)
			(size 0.3048 0.3048)
			(layers "F.Cu" "F.Mask" "F.Paste")
			(net "GND")
		)
		(pad "BL32" smd circle
			(at 2.402586 2.724912)
			(size 0.381 0.381)
			(layers "F.Cu" "F.Mask" "F.Paste")
			(net "GND")
		)
		(pad "BM2" smd circle
			(at 2.350008 -3.41884)
			(size 0.3048 0.3048)
			(layers "F.Cu" "F.Mask" "F.Paste")
			(net "GND")
		)
		(pad "BM34" smd circle
			(at 2.350008 3.420364)
			(size 0.3048 0.3048)
			(layers "F.Cu" "F.Mask" "F.Paste")
			(net "GND")
		)
		(pad "BN1" smd oval
			(at 2.050034 -3.938524)
			(size 0.254 0.3302)
			(layers "F.Cu" "F.Mask" "F.Paste")
			(net "GND")
		)
		(pad "BN35" smd oval
			(at 2.050034 3.940048)
			(size 0.254 0.3302)
			(layers "F.Cu" "F.Mask" "F.Paste")
			(net "GND")
		)
		(pad "BP7" smd circle
			(at 2.002536 -2.12471)
			(size 0.381 0.381)
			(layers "F.Cu" "F.Mask" "F.Paste")
			(net "P5E_CPU0_P0_TX_BUF_DP<9>")
		)
		(pad "BP26" smd circle
			(at 2.002536 1.339342)
			(size 0.381 0.381)
			(layers "F.Cu" "F.Mask" "F.Paste")
			(net "P5E_CPU0_P0_RX_DP<9>")
		)
		(pad "BR2" smd circle
			(at 1.75006 -3.41884)
			(size 0.3048 0.3048)
			(layers "F.Cu" "F.Mask" "F.Paste")
			(net "P5E_CPU0_P0_RX_BUF_DN<9>")
		)
		(pad "BR34" smd circle
			(at 1.75006 3.420364)
			(size 0.3048 0.3048)
			(layers "F.Cu" "F.Mask" "F.Paste")
			(net "P5E_CPU0_P0_TX_C_DN<9>")
		)
		(pad "BT10" smd circle
			(at 1.602486 -1.431798)
			(size 0.381 0.381)
			(layers "F.Cu" "F.Mask" "F.Paste")
			(net "P5E_CPU0_P0_TX_BUF_DN<9>")
		)
		(pad "BT29" smd circle
			(at 1.602486 2.032254)
			(size 0.381 0.381)
			(layers "F.Cu" "F.Mask" "F.Paste")
			(net "P5E_CPU0_P0_RX_DN<9>")
		)
		(pad "BU1" smd oval
			(at 1.450086 -3.938524)
			(size 0.254 0.3302)
			(layers "F.Cu" "F.Mask" "F.Paste")
			(net "P5E_CPU0_P0_RX_BUF_DP<9>")
		)
		(pad "BU35" smd oval
			(at 1.450086 3.940048)
			(size 0.254 0.3302)
			(layers "F.Cu" "F.Mask" "F.Paste")
			(net "P5E_CPU0_P0_TX_C_DP<9>")
		)
		(pad "BV4" smd circle
			(at 1.20269 -2.817368)
			(size 0.381 0.381)
			(layers "F.Cu" "F.Mask" "F.Paste")
			(net "GND")
		)
		(pad "BV13" smd circle
			(at 1.20269 -0.79629)
			(size 0.3048 0.3048)
			(layers "F.Cu" "F.Mask" "F.Paste")
			(net "GND")
		)
		(pad "BV17" smd circle
			(at 1.20269 -0.296164)
			(size 0.3048 0.3048)
			(layers "F.Cu" "F.Mask" "F.Paste")
			(net "P1V8_CPU0_RT0_1A_1D")
		)
		(pad "BV20" smd circle
			(at 1.20269 0.203708)
			(size 0.3048 0.3048)
			(layers "F.Cu" "F.Mask" "F.Paste")
			(net "P1V8_CPU0_RT0_1A")
		)
		(pad "BV22" smd circle
			(at 1.20269 0.703834)
			(size 0.3048 0.3048)
			(layers "F.Cu" "F.Mask" "F.Paste")
			(net "GND")
		)
		(pad "BV32" smd circle
			(at 1.20269 2.724912)
			(size 0.381 0.381)
			(layers "F.Cu" "F.Mask" "F.Paste")
			(net "GND")
		)
		(pad "BW2" smd circle
			(at 1.150112 -3.41884)
			(size 0.3048 0.3048)
			(layers "F.Cu" "F.Mask" "F.Paste")
			(net "GND")
		)
		(pad "BW34" smd circle
			(at 1.150112 3.420364)
			(size 0.3048 0.3048)
			(layers "F.Cu" "F.Mask" "F.Paste")
			(net "GND")
		)
		(pad "BY1" smd oval
			(at 0.849884 -3.938524)
			(size 0.254 0.3302)
			(layers "F.Cu" "F.Mask" "F.Paste")
			(net "GND")
		)
		(pad "BY35" smd oval
			(at 0.849884 3.940048)
			(size 0.254 0.3302)
			(layers "F.Cu" "F.Mask" "F.Paste")
			(net "GND")
		)
		(pad "C2" smd circle
			(at 10.750042 -3.41884)
			(size 0.3048 0.3048)
			(layers "F.Cu" "F.Mask" "F.Paste")
			(net "NCF_CPU0_P0_GND")
		)
		(pad "C34" smd circle
			(at 10.750042 3.420364)
			(size 0.3048 0.3048)
			(layers "F.Cu" "F.Mask" "F.Paste")
			(net "NCF_CPU0_P0_GND")
		)
		(pad "CA7" smd circle
			(at 0.80264 -2.12471)
			(size 0.381 0.381)
			(layers "F.Cu" "F.Mask" "F.Paste")
			(net "P5E_CPU0_P0_TX_BUF_DP<8>")
		)
		(pad "CA26" smd circle
			(at 0.80264 1.339342)
			(size 0.381 0.381)
			(layers "F.Cu" "F.Mask" "F.Paste")
			(net "P5E_CPU0_P0_RX_DP<8>")
		)
		(pad "CB2" smd circle
			(at 0.54991 -3.41884)
			(size 0.3048 0.3048)
			(layers "F.Cu" "F.Mask" "F.Paste")
			(net "P5E_CPU0_P0_RX_BUF_DN<8>")
		)
		(pad "CB34" smd circle
			(at 0.54991 3.420364)
			(size 0.3048 0.3048)
			(layers "F.Cu" "F.Mask" "F.Paste")
			(net "P5E_CPU0_P0_TX_C_DN<8>")
		)
		(pad "CC10" smd circle
			(at 0.40259 -1.431798)
			(size 0.381 0.381)
			(layers "F.Cu" "F.Mask" "F.Paste")
			(net "P5E_CPU0_P0_TX_BUF_DN<8>")
		)
		(pad "CC29" smd circle
			(at 0.40259 2.032254)
			(size 0.381 0.381)
			(layers "F.Cu" "F.Mask" "F.Paste")
			(net "P5E_CPU0_P0_RX_DN<8>")
		)
		(pad "CD1" smd oval
			(at 0.249936 -3.938524)
			(size 0.254 0.3302)
			(layers "F.Cu" "F.Mask" "F.Paste")
			(net "P5E_CPU0_P0_RX_BUF_DP<8>")
		)
		(pad "CD35" smd oval
			(at 0.249936 3.940048)
			(size 0.254 0.3302)
			(layers "F.Cu" "F.Mask" "F.Paste")
			(net "P5E_CPU0_P0_TX_C_DP<8>")
		)
		(pad "CE4" smd circle
			(at 0.00254 -2.817368)
			(size 0.381 0.381)
			(layers "F.Cu" "F.Mask" "F.Paste")
			(net "GND")
		)
		(pad "CE13" smd circle
			(at 0.00254 -0.79629)
			(size 0.3048 0.3048)
			(layers "F.Cu" "F.Mask" "F.Paste")
			(net "GND")
		)
		(pad "CE17" smd circle
			(at 0.00254 -0.296164)
			(size 0.3048 0.3048)
			(layers "F.Cu" "F.Mask" "F.Paste")
			(net "P1V8_CPU0_RT0_1A")
		)
		(pad "CE20" smd circle
			(at 0.00254 0.203708)
			(size 0.3048 0.3048)
			(layers "F.Cu" "F.Mask" "F.Paste")
			(net "P1V8_CPU0_RT0_1A")
		)
		(pad "CE22" smd circle
			(at 0.00254 0.703834)
			(size 0.3048 0.3048)
			(layers "F.Cu" "F.Mask" "F.Paste")
			(net "GND")
		)
		(pad "CE32" smd circle
			(at 0.00254 2.724912)
			(size 0.381 0.381)
			(layers "F.Cu" "F.Mask" "F.Paste")
			(net "GND")
		)
		(pad "CF2" smd circle
			(at -0.050038 -3.41884)
			(size 0.3048 0.3048)
			(layers "F.Cu" "F.Mask" "F.Paste")
			(net "GND")
		)
		(pad "CF34" smd circle
			(at -0.050038 3.420364)
			(size 0.3048 0.3048)
			(layers "F.Cu" "F.Mask" "F.Paste")
			(net "GND")
		)
		(pad "CG1" smd oval
			(at -0.350012 -3.938524)
			(size 0.254 0.3302)
			(layers "F.Cu" "F.Mask" "F.Paste")
			(net "GND")
		)
		(pad "CG35" smd oval
			(at -0.350012 3.940048)
			(size 0.254 0.3302)
			(layers "F.Cu" "F.Mask" "F.Paste")
			(net "GND")
		)
		(pad "CH7" smd circle
			(at -0.39751 -2.12471)
			(size 0.381 0.381)
			(layers "F.Cu" "F.Mask" "F.Paste")
			(net "P5E_CPU0_P0_TX_BUF_DP<7>")
		)
		(pad "CH26" smd circle
			(at -0.39751 1.339342)
			(size 0.381 0.381)
			(layers "F.Cu" "F.Mask" "F.Paste")
			(net "P5E_CPU0_P0_RX_DP<7>")
		)
		(pad "CJ2" smd circle
			(at -0.649986 -3.41884)
			(size 0.3048 0.3048)
			(layers "F.Cu" "F.Mask" "F.Paste")
			(net "P5E_CPU0_P0_RX_BUF_DN<7>")
		)
		(pad "CJ34" smd circle
			(at -0.649986 3.420364)
			(size 0.3048 0.3048)
			(layers "F.Cu" "F.Mask" "F.Paste")
			(net "P5E_CPU0_P0_TX_C_DN<7>")
		)
		(pad "CK10" smd circle
			(at -0.797306 -1.431798)
			(size 0.381 0.381)
			(layers "F.Cu" "F.Mask" "F.Paste")
			(net "P5E_CPU0_P0_TX_BUF_DN<7>")
		)
		(pad "CK29" smd circle
			(at -0.797306 2.032254)
			(size 0.381 0.381)
			(layers "F.Cu" "F.Mask" "F.Paste")
			(net "P5E_CPU0_P0_RX_DN<7>")
		)
		(pad "CL1" smd oval
			(at -0.94996 -3.938524)
			(size 0.254 0.3302)
			(layers "F.Cu" "F.Mask" "F.Paste")
			(net "P5E_CPU0_P0_RX_BUF_DP<7>")
		)
		(pad "CL35" smd oval
			(at -0.94996 3.940048)
			(size 0.254 0.3302)
			(layers "F.Cu" "F.Mask" "F.Paste")
			(net "P5E_CPU0_P0_TX_C_DP<7>")
		)
		(pad "CM4" smd circle
			(at -1.197356 -2.817368)
			(size 0.381 0.381)
			(layers "F.Cu" "F.Mask" "F.Paste")
			(net "GND")
		)
		(pad "CM13" smd circle
			(at -1.197356 -0.79629)
			(size 0.3048 0.3048)
			(layers "F.Cu" "F.Mask" "F.Paste")
			(net "GND")
		)
		(pad "CM17" smd circle
			(at -1.197356 -0.296164)
			(size 0.3048 0.3048)
			(layers "F.Cu" "F.Mask" "F.Paste")
			(net "P1V8_CPU0_RT0_1A")
		)
		(pad "CM20" smd circle
			(at -1.197356 0.203708)
			(size 0.3048 0.3048)
			(layers "F.Cu" "F.Mask" "F.Paste")
			(net "P1V8_CPU0_RT0_1A")
		)
		(pad "CM22" smd circle
			(at -1.197356 0.703834)
			(size 0.3048 0.3048)
			(layers "F.Cu" "F.Mask" "F.Paste")
			(net "GND")
		)
		(pad "CM32" smd circle
			(at -1.197356 2.724912)
			(size 0.381 0.381)
			(layers "F.Cu" "F.Mask" "F.Paste")
			(net "GND")
		)
		(pad "CN2" smd circle
			(at -1.249934 -3.41884)
			(size 0.3048 0.3048)
			(layers "F.Cu" "F.Mask" "F.Paste")
			(net "GND")
		)
		(pad "CN34" smd circle
			(at -1.249934 3.420364)
			(size 0.3048 0.3048)
			(layers "F.Cu" "F.Mask" "F.Paste")
			(net "GND")
		)
		(pad "CP1" smd oval
			(at -1.549908 -3.938524)
			(size 0.254 0.3302)
			(layers "F.Cu" "F.Mask" "F.Paste")
			(net "GND")
		)
		(pad "CP35" smd oval
			(at -1.549908 3.940048)
			(size 0.254 0.3302)
			(layers "F.Cu" "F.Mask" "F.Paste")
			(net "GND")
		)
		(pad "CR7" smd circle
			(at -1.597406 -2.12471)
			(size 0.381 0.381)
			(layers "F.Cu" "F.Mask" "F.Paste")
			(net "P5E_CPU0_P0_TX_BUF_DP<6>")
		)
		(pad "CR26" smd circle
			(at -1.597406 1.339342)
			(size 0.381 0.381)
			(layers "F.Cu" "F.Mask" "F.Paste")
			(net "P5E_CPU0_P0_RX_DP<6>")
		)
		(pad "CT2" smd circle
			(at -1.849882 -3.41884)
			(size 0.3048 0.3048)
			(layers "F.Cu" "F.Mask" "F.Paste")
			(net "P5E_CPU0_P0_RX_BUF_DN<6>")
		)
		(pad "CT34" smd circle
			(at -1.849882 3.420364)
			(size 0.3048 0.3048)
			(layers "F.Cu" "F.Mask" "F.Paste")
			(net "P5E_CPU0_P0_TX_C_DN<6>")
		)
		(pad "CU10" smd circle
			(at -1.997456 -1.431798)
			(size 0.381 0.381)
			(layers "F.Cu" "F.Mask" "F.Paste")
			(net "P5E_CPU0_P0_TX_BUF_DN<6>")
		)
		(pad "CU29" smd circle
			(at -1.997456 2.032254)
			(size 0.381 0.381)
			(layers "F.Cu" "F.Mask" "F.Paste")
			(net "P5E_CPU0_P0_RX_DN<6>")
		)
		(pad "CV1" smd oval
			(at -2.15011 -3.938524)
			(size 0.254 0.3302)
			(layers "F.Cu" "F.Mask" "F.Paste")
			(net "P5E_CPU0_P0_RX_BUF_DP<6>")
		)
		(pad "CV35" smd oval
			(at -2.15011 3.940048)
			(size 0.254 0.3302)
			(layers "F.Cu" "F.Mask" "F.Paste")
			(net "P5E_CPU0_P0_TX_C_DP<6>")
		)
		(pad "CW4" smd circle
			(at -2.397506 -2.817368)
			(size 0.381 0.381)
			(layers "F.Cu" "F.Mask" "F.Paste")
			(net "GND")
		)
		(pad "CW13" smd circle
			(at -2.397506 -0.79629)
			(size 0.3048 0.3048)
			(layers "F.Cu" "F.Mask" "F.Paste")
			(net "GND")
		)
		(pad "CW17" smd circle
			(at -2.397506 -0.296164)
			(size 0.3048 0.3048)
			(layers "F.Cu" "F.Mask" "F.Paste")
			(net "P0V9_CPU0_RT_2D")
		)
		(pad "CW20" smd circle
			(at -2.397506 0.203708)
			(size 0.3048 0.3048)
			(layers "F.Cu" "F.Mask" "F.Paste")
			(net "P0V9_CPU0_RT_2D")
		)
		(pad "CW22" smd circle
			(at -2.397506 0.703834)
			(size 0.3048 0.3048)
			(layers "F.Cu" "F.Mask" "F.Paste")
			(net "GND")
		)
		(pad "CW32" smd circle
			(at -2.397506 2.724912)
			(size 0.381 0.381)
			(layers "F.Cu" "F.Mask" "F.Paste")
			(net "GND")
		)
		(pad "CY2" smd circle
			(at -2.450084 -3.41884)
			(size 0.3048 0.3048)
			(layers "F.Cu" "F.Mask" "F.Paste")
			(net "GND")
		)
		(pad "CY34" smd circle
			(at -2.450084 3.420364)
			(size 0.3048 0.3048)
			(layers "F.Cu" "F.Mask" "F.Paste")
			(net "GND")
		)
		(pad "D1" smd oval
			(at 10.450068 -3.938524)
			(size 0.254 0.3302)
			(layers "F.Cu" "F.Mask" "F.Paste")
			(net "NCF_CPU0_P0_GND")
		)
		(pad "D35" smd oval
			(at 10.450068 3.940048)
			(size 0.254 0.3302)
			(layers "F.Cu" "F.Mask" "F.Paste")
			(net "NCF_CPU0_P0_GND")
		)
		(pad "DA1" smd oval
			(at -2.750058 -3.938524)
			(size 0.254 0.3302)
			(layers "F.Cu" "F.Mask" "F.Paste")
			(net "GND")
		)
		(pad "DA35" smd oval
			(at -2.750058 3.940048)
			(size 0.254 0.3302)
			(layers "F.Cu" "F.Mask" "F.Paste")
			(net "GND")
		)
		(pad "DB7" smd circle
			(at -2.797302 -2.12471)
			(size 0.381 0.381)
			(layers "F.Cu" "F.Mask" "F.Paste")
			(net "P5E_CPU0_P0_TX_BUF_DP<5>")
		)
		(pad "DB26" smd circle
			(at -2.797302 1.339342)
			(size 0.381 0.381)
			(layers "F.Cu" "F.Mask" "F.Paste")
			(net "P5E_CPU0_P0_RX_DP<5>")
		)
		(pad "DC2" smd circle
			(at -3.050032 -3.41884)
			(size 0.3048 0.3048)
			(layers "F.Cu" "F.Mask" "F.Paste")
			(net "P5E_CPU0_P0_RX_BUF_DN<5>")
		)
		(pad "DC34" smd circle
			(at -3.050032 3.420364)
			(size 0.3048 0.3048)
			(layers "F.Cu" "F.Mask" "F.Paste")
			(net "P5E_CPU0_P0_TX_C_DN<5>")
		)
		(pad "DD10" smd circle
			(at -3.197352 -1.431798)
			(size 0.381 0.381)
			(layers "F.Cu" "F.Mask" "F.Paste")
			(net "P5E_CPU0_P0_TX_BUF_DN<5>")
		)
		(pad "DD29" smd circle
			(at -3.197352 2.032254)
			(size 0.381 0.381)
			(layers "F.Cu" "F.Mask" "F.Paste")
			(net "P5E_CPU0_P0_RX_DN<5>")
		)
		(pad "DE1" smd oval
			(at -3.350006 -3.938524)
			(size 0.254 0.3302)
			(layers "F.Cu" "F.Mask" "F.Paste")
			(net "P5E_CPU0_P0_RX_BUF_DP<5>")
		)
		(pad "DE35" smd oval
			(at -3.350006 3.940048)
			(size 0.254 0.3302)
			(layers "F.Cu" "F.Mask" "F.Paste")
			(net "P5E_CPU0_P0_TX_C_DP<5>")
		)
		(pad "DF4" smd circle
			(at -3.597402 -2.817368)
			(size 0.381 0.381)
			(layers "F.Cu" "F.Mask" "F.Paste")
			(net "GND")
		)
		(pad "DF13" smd circle
			(at -3.597402 -0.79629)
			(size 0.3048 0.3048)
			(layers "F.Cu" "F.Mask" "F.Paste")
			(net "GND")
		)
		(pad "DF17" smd circle
			(at -3.597402 -0.296164)
			(size 0.3048 0.3048)
			(layers "F.Cu" "F.Mask" "F.Paste")
			(net "P0V9_CPU0_RT0_2A_2D")
		)
		(pad "DF20" smd circle
			(at -3.597402 0.203708)
			(size 0.3048 0.3048)
			(layers "F.Cu" "F.Mask" "F.Paste")
			(net "P0V9_CPU0_RT0_2A_2D")
		)
		(pad "DF22" smd circle
			(at -3.597402 0.703834)
			(size 0.3048 0.3048)
			(layers "F.Cu" "F.Mask" "F.Paste")
			(net "GND")
		)
		(pad "DF32" smd circle
			(at -3.597402 2.724912)
			(size 0.381 0.381)
			(layers "F.Cu" "F.Mask" "F.Paste")
			(net "GND")
		)
		(pad "DG2" smd circle
			(at -3.64998 -3.41884)
			(size 0.3048 0.3048)
			(layers "F.Cu" "F.Mask" "F.Paste")
			(net "GND")
		)
		(pad "DG34" smd circle
			(at -3.64998 3.420364)
			(size 0.3048 0.3048)
			(layers "F.Cu" "F.Mask" "F.Paste")
			(net "GND")
		)
		(pad "DH1" smd oval
			(at -3.949954 -3.938524)
			(size 0.254 0.3302)
			(layers "F.Cu" "F.Mask" "F.Paste")
			(net "GND")
		)
		(pad "DH35" smd oval
			(at -3.949954 3.940048)
			(size 0.254 0.3302)
			(layers "F.Cu" "F.Mask" "F.Paste")
			(net "GND")
		)
		(pad "DJ7" smd circle
			(at -3.997452 -2.12471)
			(size 0.381 0.381)
			(layers "F.Cu" "F.Mask" "F.Paste")
			(net "P5E_CPU0_P0_TX_BUF_DP<4>")
		)
		(pad "DJ26" smd circle
			(at -3.997452 1.339342)
			(size 0.381 0.381)
			(layers "F.Cu" "F.Mask" "F.Paste")
			(net "P5E_CPU0_P0_RX_DP<4>")
		)
		(pad "DK2" smd circle
			(at -4.249928 -3.41884)
			(size 0.3048 0.3048)
			(layers "F.Cu" "F.Mask" "F.Paste")
			(net "P5E_CPU0_P0_RX_BUF_DN<4>")
		)
		(pad "DK34" smd circle
			(at -4.249928 3.420364)
			(size 0.3048 0.3048)
			(layers "F.Cu" "F.Mask" "F.Paste")
			(net "P5E_CPU0_P0_TX_C_DN<4>")
		)
		(pad "DL10" smd circle
			(at -4.397502 -1.431798)
			(size 0.381 0.381)
			(layers "F.Cu" "F.Mask" "F.Paste")
			(net "P5E_CPU0_P0_TX_BUF_DN<4>")
		)
		(pad "DL29" smd circle
			(at -4.397502 2.032254)
			(size 0.381 0.381)
			(layers "F.Cu" "F.Mask" "F.Paste")
			(net "P5E_CPU0_P0_RX_DN<4>")
		)
		(pad "DM1" smd oval
			(at -4.549902 -3.938524)
			(size 0.254 0.3302)
			(layers "F.Cu" "F.Mask" "F.Paste")
			(net "P5E_CPU0_P0_RX_BUF_DP<4>")
		)
		(pad "DM35" smd oval
			(at -4.549902 3.940048)
			(size 0.254 0.3302)
			(layers "F.Cu" "F.Mask" "F.Paste")
			(net "P5E_CPU0_P0_TX_C_DP<4>")
		)
		(pad "DN4" smd circle
			(at -4.797298 -2.817368)
			(size 0.381 0.381)
			(layers "F.Cu" "F.Mask" "F.Paste")
			(net "GND")
		)
		(pad "DN13" smd circle
			(at -4.797298 -0.79629)
			(size 0.3048 0.3048)
			(layers "F.Cu" "F.Mask" "F.Paste")
			(net "GND")
		)
		(pad "DN17" smd circle
			(at -4.797298 -0.296164)
			(size 0.3048 0.3048)
			(layers "F.Cu" "F.Mask" "F.Paste")
			(net "P0V9_CPU0_RT0_2A")
		)
		(pad "DN20" smd circle
			(at -4.797298 0.203708)
			(size 0.3048 0.3048)
			(layers "F.Cu" "F.Mask" "F.Paste")
			(net "P0V9_CPU0_RT0_2A")
		)
		(pad "DN22" smd circle
			(at -4.797298 0.703834)
			(size 0.3048 0.3048)
			(layers "F.Cu" "F.Mask" "F.Paste")
			(net "GND")
		)
		(pad "DN32" smd circle
			(at -4.797298 2.724912)
			(size 0.381 0.381)
			(layers "F.Cu" "F.Mask" "F.Paste")
			(net "GND")
		)
		(pad "DP2" smd circle
			(at -4.849876 -3.41884)
			(size 0.3048 0.3048)
			(layers "F.Cu" "F.Mask" "F.Paste")
			(net "GND")
		)
		(pad "DP34" smd circle
			(at -4.849876 3.420364)
			(size 0.3048 0.3048)
			(layers "F.Cu" "F.Mask" "F.Paste")
			(net "GND")
		)
		(pad "DR1" smd oval
			(at -5.150104 -3.938524)
			(size 0.254 0.3302)
			(layers "F.Cu" "F.Mask" "F.Paste")
			(net "GND")
		)
		(pad "DR35" smd oval
			(at -5.150104 3.940048)
			(size 0.254 0.3302)
			(layers "F.Cu" "F.Mask" "F.Paste")
			(net "GND")
		)
		(pad "DT7" smd circle
			(at -5.197348 -2.12471)
			(size 0.381 0.381)
			(layers "F.Cu" "F.Mask" "F.Paste")
			(net "P5E_CPU0_P0_TX_BUF_DP<3>")
		)
		(pad "DT26" smd circle
			(at -5.197348 1.339342)
			(size 0.381 0.381)
			(layers "F.Cu" "F.Mask" "F.Paste")
			(net "P5E_CPU0_P0_RX_DP<3>")
		)
		(pad "DU2" smd circle
			(at -5.450078 -3.41884)
			(size 0.3048 0.3048)
			(layers "F.Cu" "F.Mask" "F.Paste")
			(net "P5E_CPU0_P0_RX_BUF_DN<3>")
		)
		(pad "DU34" smd circle
			(at -5.450078 3.420364)
			(size 0.3048 0.3048)
			(layers "F.Cu" "F.Mask" "F.Paste")
			(net "P5E_CPU0_P0_TX_C_DN<3>")
		)
		(pad "DV10" smd circle
			(at -5.597398 -1.431798)
			(size 0.381 0.381)
			(layers "F.Cu" "F.Mask" "F.Paste")
			(net "P5E_CPU0_P0_TX_BUF_DN<3>")
		)
		(pad "DV29" smd circle
			(at -5.597398 2.032254)
			(size 0.381 0.381)
			(layers "F.Cu" "F.Mask" "F.Paste")
			(net "P5E_CPU0_P0_RX_DN<3>")
		)
		(pad "DW1" smd oval
			(at -5.750052 -3.938524)
			(size 0.254 0.3302)
			(layers "F.Cu" "F.Mask" "F.Paste")
			(net "P5E_CPU0_P0_RX_BUF_DP<3>")
		)
		(pad "DW35" smd oval
			(at -5.750052 3.940048)
			(size 0.254 0.3302)
			(layers "F.Cu" "F.Mask" "F.Paste")
			(net "P5E_CPU0_P0_TX_C_DP<3>")
		)
		(pad "DY4" smd circle
			(at -5.997448 -2.817368)
			(size 0.381 0.381)
			(layers "F.Cu" "F.Mask" "F.Paste")
			(net "GND")
		)
		(pad "DY13" smd circle
			(at -5.997448 -0.79629)
			(size 0.3048 0.3048)
			(layers "F.Cu" "F.Mask" "F.Paste")
			(net "GND")
		)
		(pad "DY17" smd circle
			(at -5.997448 -0.296164)
			(size 0.3048 0.3048)
			(layers "F.Cu" "F.Mask" "F.Paste")
			(net "P0V9_CPU0_RT0_2A")
		)
		(pad "DY20" smd circle
			(at -5.997448 0.203708)
			(size 0.3048 0.3048)
			(layers "F.Cu" "F.Mask" "F.Paste")
			(net "P0V9_CPU0_RT0_2A")
		)
		(pad "DY22" smd circle
			(at -5.997448 0.703834)
			(size 0.3048 0.3048)
			(layers "F.Cu" "F.Mask" "F.Paste")
			(net "GND")
		)
		(pad "DY32" smd circle
			(at -5.997448 2.724912)
			(size 0.381 0.381)
			(layers "F.Cu" "F.Mask" "F.Paste")
			(net "GND")
		)
		(pad "E8" smd circle
			(at 10.366502 -1.988312)
			(size 0.3048 0.3048)
			(layers "F.Cu" "F.Mask" "F.Paste")
			(net "JTAG_TRST_RT_CPU0_P0_N")
		)
		(pad "E11" smd circle
			(at 10.366502 -1.388364)
			(size 0.3048 0.3048)
			(layers "F.Cu" "F.Mask" "F.Paste")
			(net "RXDET_BYP_RT_CPU0_P0")
		)
		(pad "E14" smd circle
			(at 10.366502 -0.788416)
			(size 0.3048 0.3048)
			(layers "F.Cu" "F.Mask" "F.Paste")
			(net "GND")
		)
		(pad "E18" smd circle
			(at 10.366502 -0.188468)
			(size 0.3048 0.3048)
			(layers "F.Cu" "F.Mask" "F.Paste")
			(net "Net_2202")
		)
		(pad "E27" smd circle
			(at 10.366502 1.61163)
			(size 0.3048 0.3048)
			(layers "F.Cu" "F.Mask" "F.Paste")
			(net "GND")
		)
		(pad "E30" smd circle
			(at 10.366502 2.211578)
			(size 0.3048 0.3048)
			(layers "F.Cu" "F.Mask" "F.Paste")
			(net "GND")
		)
		(pad "E33" smd circle
			(at 10.366502 2.811526)
			(size 0.3048 0.3048)
			(layers "F.Cu" "F.Mask" "F.Paste")
			(net "GND")
		)
		(pad "EA2" smd circle
			(at -6.050026 -3.41884)
			(size 0.3048 0.3048)
			(layers "F.Cu" "F.Mask" "F.Paste")
			(net "GND")
		)
		(pad "EA34" smd circle
			(at -6.050026 3.420364)
			(size 0.3048 0.3048)
			(layers "F.Cu" "F.Mask" "F.Paste")
			(net "GND")
		)
		(pad "EB1" smd oval
			(at -6.35 -3.938524)
			(size 0.254 0.3302)
			(layers "F.Cu" "F.Mask" "F.Paste")
			(net "GND")
		)
		(pad "EB35" smd oval
			(at -6.35 3.940048)
			(size 0.254 0.3302)
			(layers "F.Cu" "F.Mask" "F.Paste")
			(net "GND")
		)
		(pad "EC7" smd circle
			(at -6.397498 -2.12471)
			(size 0.381 0.381)
			(layers "F.Cu" "F.Mask" "F.Paste")
			(net "P5E_CPU0_P0_TX_BUF_DP<2>")
		)
		(pad "EC26" smd circle
			(at -6.397498 1.339342)
			(size 0.381 0.381)
			(layers "F.Cu" "F.Mask" "F.Paste")
			(net "P5E_CPU0_P0_RX_DP<2>")
		)
		(pad "ED2" smd circle
			(at -6.649974 -3.41884)
			(size 0.3048 0.3048)
			(layers "F.Cu" "F.Mask" "F.Paste")
			(net "P5E_CPU0_P0_RX_BUF_DN<2>")
		)
		(pad "ED34" smd circle
			(at -6.649974 3.420364)
			(size 0.3048 0.3048)
			(layers "F.Cu" "F.Mask" "F.Paste")
			(net "P5E_CPU0_P0_TX_C_DN<2>")
		)
		(pad "EE10" smd circle
			(at -6.797294 -1.431798)
			(size 0.381 0.381)
			(layers "F.Cu" "F.Mask" "F.Paste")
			(net "P5E_CPU0_P0_TX_BUF_DN<2>")
		)
		(pad "EE29" smd circle
			(at -6.797294 2.032254)
			(size 0.381 0.381)
			(layers "F.Cu" "F.Mask" "F.Paste")
			(net "P5E_CPU0_P0_RX_DN<2>")
		)
		(pad "EF1" smd oval
			(at -6.949948 -3.938524)
			(size 0.254 0.3302)
			(layers "F.Cu" "F.Mask" "F.Paste")
			(net "P5E_CPU0_P0_RX_BUF_DP<2>")
		)
		(pad "EF35" smd oval
			(at -6.949948 3.940048)
			(size 0.254 0.3302)
			(layers "F.Cu" "F.Mask" "F.Paste")
			(net "P5E_CPU0_P0_TX_C_DP<2>")
		)
		(pad "EG4" smd circle
			(at -7.197344 -2.817368)
			(size 0.381 0.381)
			(layers "F.Cu" "F.Mask" "F.Paste")
			(net "GND")
		)
		(pad "EG13" smd circle
			(at -7.197344 -0.79629)
			(size 0.3048 0.3048)
			(layers "F.Cu" "F.Mask" "F.Paste")
			(net "GND")
		)
		(pad "EG17" smd circle
			(at -7.197344 -0.296164)
			(size 0.3048 0.3048)
			(layers "F.Cu" "F.Mask" "F.Paste")
			(net "P0V9_CPU0_RT0_2A")
		)
		(pad "EG20" smd circle
			(at -7.197344 0.203708)
			(size 0.3048 0.3048)
			(layers "F.Cu" "F.Mask" "F.Paste")
			(net "P0V9_CPU0_RT0_2A")
		)
		(pad "EG22" smd circle
			(at -7.197344 0.703834)
			(size 0.3048 0.3048)
			(layers "F.Cu" "F.Mask" "F.Paste")
			(net "GND")
		)
		(pad "EG32" smd circle
			(at -7.197344 2.724912)
			(size 0.381 0.381)
			(layers "F.Cu" "F.Mask" "F.Paste")
			(net "GND")
		)
		(pad "EH2" smd circle
			(at -7.249922 -3.41884)
			(size 0.3048 0.3048)
			(layers "F.Cu" "F.Mask" "F.Paste")
			(net "GND")
		)
		(pad "EH34" smd circle
			(at -7.249922 3.420364)
			(size 0.3048 0.3048)
			(layers "F.Cu" "F.Mask" "F.Paste")
			(net "GND")
		)
		(pad "EJ1" smd oval
			(at -7.549896 -3.938524)
			(size 0.254 0.3302)
			(layers "F.Cu" "F.Mask" "F.Paste")
			(net "GND")
		)
		(pad "EJ35" smd oval
			(at -7.549896 3.940048)
			(size 0.254 0.3302)
			(layers "F.Cu" "F.Mask" "F.Paste")
			(net "GND")
		)
		(pad "EK7" smd circle
			(at -7.597394 -2.12471)
			(size 0.381 0.381)
			(layers "F.Cu" "F.Mask" "F.Paste")
			(net "P5E_CPU0_P0_TX_BUF_DP<1>")
		)
		(pad "EK26" smd circle
			(at -7.597394 1.339342)
			(size 0.381 0.381)
			(layers "F.Cu" "F.Mask" "F.Paste")
			(net "P5E_CPU0_P0_RX_DP<1>")
		)
		(pad "EL2" smd circle
			(at -7.850124 -3.41884)
			(size 0.3048 0.3048)
			(layers "F.Cu" "F.Mask" "F.Paste")
			(net "P5E_CPU0_P0_RX_BUF_DN<1>")
		)
		(pad "EL34" smd circle
			(at -7.850124 3.420364)
			(size 0.3048 0.3048)
			(layers "F.Cu" "F.Mask" "F.Paste")
			(net "P5E_CPU0_P0_TX_C_DP<1>")
		)
		(pad "EM10" smd circle
			(at -7.997444 -1.431798)
			(size 0.381 0.381)
			(layers "F.Cu" "F.Mask" "F.Paste")
			(net "P5E_CPU0_P0_TX_BUF_DN<1>")
		)
		(pad "EM29" smd circle
			(at -7.997444 2.032254)
			(size 0.381 0.381)
			(layers "F.Cu" "F.Mask" "F.Paste")
			(net "P5E_CPU0_P0_RX_DN<1>")
		)
		(pad "EN1" smd oval
			(at -8.150098 -3.938524)
			(size 0.254 0.3302)
			(layers "F.Cu" "F.Mask" "F.Paste")
			(net "P5E_CPU0_P0_RX_BUF_DP<1>")
		)
		(pad "EN35" smd oval
			(at -8.150098 3.940048)
			(size 0.254 0.3302)
			(layers "F.Cu" "F.Mask" "F.Paste")
			(net "P5E_CPU0_P0_TX_C_DN<1>")
		)
		(pad "EP4" smd circle
			(at -8.397494 -2.817368)
			(size 0.381 0.381)
			(layers "F.Cu" "F.Mask" "F.Paste")
			(net "GND")
		)
		(pad "EP13" smd circle
			(at -8.397494 -0.79629)
			(size 0.3048 0.3048)
			(layers "F.Cu" "F.Mask" "F.Paste")
			(net "GND")
		)
		(pad "EP17" smd circle
			(at -8.397494 -0.296164)
			(size 0.3048 0.3048)
			(layers "F.Cu" "F.Mask" "F.Paste")
			(net "P0V9_CPU0_RT0_2A")
		)
		(pad "EP20" smd circle
			(at -8.397494 0.203708)
			(size 0.3048 0.3048)
			(layers "F.Cu" "F.Mask" "F.Paste")
			(net "P0V9_CPU0_RT0_2A")
		)
		(pad "EP22" smd circle
			(at -8.397494 0.703834)
			(size 0.3048 0.3048)
			(layers "F.Cu" "F.Mask" "F.Paste")
			(net "GND")
		)
		(pad "EP32" smd circle
			(at -8.397494 2.724912)
			(size 0.381 0.381)
			(layers "F.Cu" "F.Mask" "F.Paste")
			(net "GND")
		)
		(pad "ER2" smd circle
			(at -8.450072 -3.41884)
			(size 0.3048 0.3048)
			(layers "F.Cu" "F.Mask" "F.Paste")
			(net "GND")
		)
		(pad "ER34" smd circle
			(at -8.450072 3.420364)
			(size 0.3048 0.3048)
			(layers "F.Cu" "F.Mask" "F.Paste")
			(net "GND")
		)
		(pad "ET1" smd oval
			(at -8.750046 -3.938524)
			(size 0.254 0.3302)
			(layers "F.Cu" "F.Mask" "F.Paste")
			(net "GND")
		)
		(pad "ET35" smd oval
			(at -8.750046 3.940048)
			(size 0.254 0.3302)
			(layers "F.Cu" "F.Mask" "F.Paste")
			(net "GND")
		)
		(pad "EU7" smd circle
			(at -8.79729 -2.12471)
			(size 0.381 0.381)
			(layers "F.Cu" "F.Mask" "F.Paste")
			(net "P5E_CPU0_P0_TX_BUF_DP<0>")
		)
		(pad "EU26" smd circle
			(at -8.79729 1.339342)
			(size 0.381 0.381)
			(layers "F.Cu" "F.Mask" "F.Paste")
			(net "P5E_CPU0_P0_RX_DP<0>")
		)
		(pad "EV2" smd circle
			(at -9.05002 -3.41884)
			(size 0.3048 0.3048)
			(layers "F.Cu" "F.Mask" "F.Paste")
			(net "P5E_CPU0_P0_RX_BUF_DN<0>")
		)
		(pad "EV34" smd circle
			(at -9.05002 3.420364)
			(size 0.3048 0.3048)
			(layers "F.Cu" "F.Mask" "F.Paste")
			(net "P5E_CPU0_P0_TX_C_DN<0>")
		)
		(pad "EW10" smd circle
			(at -9.19734 -1.431798)
			(size 0.381 0.381)
			(layers "F.Cu" "F.Mask" "F.Paste")
			(net "P5E_CPU0_P0_TX_BUF_DN<0>")
		)
		(pad "EW29" smd circle
			(at -9.19734 2.032254)
			(size 0.381 0.381)
			(layers "F.Cu" "F.Mask" "F.Paste")
			(net "P5E_CPU0_P0_RX_DN<0>")
		)
		(pad "EY1" smd oval
			(at -9.349994 -3.938524)
			(size 0.254 0.3302)
			(layers "F.Cu" "F.Mask" "F.Paste")
			(net "P5E_CPU0_P0_RX_BUF_DP<0>")
		)
		(pad "EY35" smd oval
			(at -9.349994 3.940048)
			(size 0.254 0.3302)
			(layers "F.Cu" "F.Mask" "F.Paste")
			(net "P5E_CPU0_P0_TX_C_DP<0>")
		)
		(pad "F2" smd circle
			(at 10.150094 -3.41884)
			(size 0.3048 0.3048)
			(layers "F.Cu" "F.Mask" "F.Paste")
			(net "RST_RT_CPU0_P0_PERST_N")
		)
		(pad "F34" smd circle
			(at 10.150094 3.420364)
			(size 0.3048 0.3048)
			(layers "F.Cu" "F.Mask" "F.Paste")
			(net "RT_CPU0_P0_ADDR1")
		)
		(pad "FA15" smd circle
			(at -9.59739 -0.738886)
			(size 0.381 0.381)
			(layers "F.Cu" "F.Mask" "F.Paste")
			(net "GND")
		)
		(pad "FA32" smd circle
			(at -9.59739 2.724912)
			(size 0.381 0.381)
			(layers "F.Cu" "F.Mask" "F.Paste")
			(net "GND")
		)
		(pad "FB2" smd circle
			(at -9.649968 -3.41884)
			(size 0.3048 0.3048)
			(layers "F.Cu" "F.Mask" "F.Paste")
			(net "GND")
		)
		(pad "FB34" smd circle
			(at -9.649968 3.420364)
			(size 0.3048 0.3048)
			(layers "F.Cu" "F.Mask" "F.Paste")
			(net "GND")
		)
		(pad "FC3" smd circle
			(at -9.846818 -2.888488)
			(size 0.3048 0.3048)
			(layers "F.Cu" "F.Mask" "F.Paste")
			(net "GND")
		)
		(pad "FC6" smd circle
			(at -9.846818 -2.288286)
			(size 0.3048 0.3048)
			(layers "F.Cu" "F.Mask" "F.Paste")
			(net "GND")
		)
		(pad "FC9" smd circle
			(at -9.846818 -1.688338)
			(size 0.3048 0.3048)
			(layers "F.Cu" "F.Mask" "F.Paste")
			(net "GND")
		)
		(pad "FC19" smd circle
			(at -9.846818 0.111506)
			(size 0.3048 0.3048)
			(layers "F.Cu" "F.Mask" "F.Paste")
			(net "GND")
		)
		(pad "FC23" smd circle
			(at -9.846818 0.711708)
			(size 0.3048 0.3048)
			(layers "F.Cu" "F.Mask" "F.Paste")
			(net "GND")
		)
		(pad "FC25" smd circle
			(at -9.846818 1.311656)
			(size 0.3048 0.3048)
			(layers "F.Cu" "F.Mask" "F.Paste")
			(net "GND")
		)
		(pad "FC28" smd circle
			(at -9.846818 1.911604)
			(size 0.3048 0.3048)
			(layers "F.Cu" "F.Mask" "F.Paste")
			(net "GND")
		)
		(pad "FD1" smd oval
			(at -9.949942 -3.938524)
			(size 0.254 0.3302)
			(layers "F.Cu" "F.Mask" "F.Paste")
			(net "GND")
		)
		(pad "FD35" smd oval
			(at -9.949942 3.940048)
			(size 0.254 0.3302)
			(layers "F.Cu" "F.Mask" "F.Paste")
			(net "GND")
		)
		(pad "FE2" smd circle
			(at -10.249916 -3.41884)
			(size 0.3048 0.3048)
			(layers "F.Cu" "F.Mask" "F.Paste")
			(net "NCF_CPU0_P0_GND")
		)
		(pad "FE34" smd circle
			(at -10.249916 3.420364)
			(size 0.3048 0.3048)
			(layers "F.Cu" "F.Mask" "F.Paste")
			(net "NCF_CPU0_P0_GND")
		)
		(pad "FF5" smd circle
			(at -10.366248 -2.588514)
			(size 0.3048 0.3048)
			(layers "F.Cu" "F.Mask" "F.Paste")
			(net "SMB_RT_CPU0_P0_ROM_MUX_1D_R_SCL")
		)
		(pad "FF8" smd circle
			(at -10.366248 -1.988312)
			(size 0.3048 0.3048)
			(layers "F.Cu" "F.Mask" "F.Paste")
			(net "JTAG_TEST_MODE_RT_CPU0_P0")
		)
		(pad "FF11" smd circle
			(at -10.366248 -1.388364)
			(size 0.3048 0.3048)
			(layers "F.Cu" "F.Mask" "F.Paste")
			(net "RST_RT_CPU0_P0_RESET_N")
		)
		(pad "FF14" smd circle
			(at -10.366248 -0.788416)
			(size 0.3048 0.3048)
			(layers "F.Cu" "F.Mask" "F.Paste")
			(net "GND")
		)
		(pad "FF18" smd circle
			(at -10.366248 -0.188468)
			(size 0.3048 0.3048)
			(layers "F.Cu" "F.Mask" "F.Paste")
			(net "CLK_100M_RETIMER_CPU0_P0_DN")
		)
		(pad "FF21" smd circle
			(at -10.366248 0.41148)
			(size 0.3048 0.3048)
			(layers "F.Cu" "F.Mask" "F.Paste")
			(net "GND")
		)
		(pad "FF24" smd circle
			(at -10.366248 1.011682)
			(size 0.3048 0.3048)
			(layers "F.Cu" "F.Mask" "F.Paste")
			(net "TEST0_RT_CPU0_P0")
		)
		(pad "FF27" smd circle
			(at -10.366248 1.61163)
			(size 0.3048 0.3048)
			(layers "F.Cu" "F.Mask" "F.Paste")
			(net "TEST1_RT_CPU0_P0")
		)
		(pad "FF30" smd circle
			(at -10.366248 2.211578)
			(size 0.3048 0.3048)
			(layers "F.Cu" "F.Mask" "F.Paste")
			(net "TEST2_RT_CPU0_P0")
		)
		(pad "FF33" smd circle
			(at -10.366248 2.811526)
			(size 0.3048 0.3048)
			(layers "F.Cu" "F.Mask" "F.Paste")
			(net "RT_CPU0_P0_SCAN_MODE")
		)
		(pad "FG1" smd oval
			(at -10.54989 -3.938524)
			(size 0.254 0.3302)
			(layers "F.Cu" "F.Mask" "F.Paste")
			(net "NCF_CPU0_P0_GND")
		)
		(pad "FG35" smd oval
			(at -10.54989 3.940048)
			(size 0.254 0.3302)
			(layers "F.Cu" "F.Mask" "F.Paste")
			(net "NCF_CPU0_P0_GND")
		)
		(pad "FH2" smd circle
			(at -10.850118 -3.41884)
			(size 0.3048 0.3048)
			(layers "F.Cu" "F.Mask" "F.Paste")
			(net "NCF_CPU0_P0_GND")
		)
		(pad "FH34" smd circle
			(at -10.850118 3.420364)
			(size 0.3048 0.3048)
			(layers "F.Cu" "F.Mask" "F.Paste")
			(net "NCF_CPU0_P0_GND")
		)
		(pad "FJ3" smd oval
			(at -10.885932 -2.888488 90)
			(size 0.254 0.3302)
			(layers "F.Cu" "F.Mask" "F.Paste")
			(net "SMB_RT_CPU0_P0_ROM_MUX_1D_R_SDA")
		)
		(pad "FJ6" smd oval
			(at -10.885932 -2.288286 90)
			(size 0.254 0.3302)
			(layers "F.Cu" "F.Mask" "F.Paste")
			(net "Net_2200")
		)
		(pad "FJ9" smd oval
			(at -10.885932 -1.688338 90)
			(size 0.254 0.3302)
			(layers "F.Cu" "F.Mask" "F.Paste")
			(net "MODE_RT_CPU0_P0")
		)
		(pad "FJ12" smd oval
			(at -10.885932 -1.08839 90)
			(size 0.254 0.3302)
			(layers "F.Cu" "F.Mask" "F.Paste")
			(net "GND")
		)
		(pad "FJ16" smd oval
			(at -10.885932 -0.488442 90)
			(size 0.254 0.3302)
			(layers "F.Cu" "F.Mask" "F.Paste")
			(net "CLK_100M_RETIMER_CPU0_P0_DP")
		)
		(pad "FJ19" smd oval
			(at -10.885932 0.111506 90)
			(size 0.254 0.3302)
			(layers "F.Cu" "F.Mask" "F.Paste")
			(net "GND")
		)
		(pad "FJ23" smd oval
			(at -10.885932 0.711708 90)
			(size 0.254 0.3302)
			(layers "F.Cu" "F.Mask" "F.Paste")
			(net "Net_2201")
		)
		(pad "FJ25" smd oval
			(at -10.885932 1.311656 90)
			(size 0.254 0.3302)
			(layers "F.Cu" "F.Mask" "F.Paste")
			(net "GPIO2_RT_CPU0_P0")
		)
		(pad "FJ28" smd oval
			(at -10.885932 1.911604 90)
			(size 0.254 0.3302)
			(layers "F.Cu" "F.Mask" "F.Paste")
			(net "GPIO3_RT_CPU0_P0")
		)
		(pad "FJ31" smd oval
			(at -10.885932 2.511552 90)
			(size 0.254 0.3302)
			(layers "F.Cu" "F.Mask" "F.Paste")
			(net "Net_50")
		)
		(pad "G1" smd oval
			(at 9.85012 -3.938524)
			(size 0.254 0.3302)
			(layers "F.Cu" "F.Mask" "F.Paste")
			(net "RT_CPU0_P0_VQPS")
		)
		(pad "G35" smd oval
			(at 9.85012 3.940048)
			(size 0.254 0.3302)
			(layers "F.Cu" "F.Mask" "F.Paste")
			(net "CLKREQ_RT_CPU0_P0_N")
		)
		(pad "H12" smd circle
			(at 9.846818 -1.08839)
			(size 0.3048 0.3048)
			(layers "F.Cu" "F.Mask" "F.Paste")
			(net "GND")
		)
		(pad "H16" smd circle
			(at 9.846818 -0.488442)
			(size 0.3048 0.3048)
			(layers "F.Cu" "F.Mask" "F.Paste")
			(net "GND")
		)
		(pad "H19" smd circle
			(at 9.846818 0.111506)
			(size 0.3048 0.3048)
			(layers "F.Cu" "F.Mask" "F.Paste")
			(net "GND")
		)
		(pad "H31" smd circle
			(at 9.846818 2.511552)
			(size 0.3048 0.3048)
			(layers "F.Cu" "F.Mask" "F.Paste")
			(net "GND")
		)
		(pad "J4" smd circle
			(at 9.602724 -2.817368)
			(size 0.381 0.381)
			(layers "F.Cu" "F.Mask" "F.Paste")
			(net "GND")
		)
		(pad "J22" smd circle
			(at 9.602724 0.703834)
			(size 0.3048 0.3048)
			(layers "F.Cu" "F.Mask" "F.Paste")
			(net "GND")
		)
		(pad "K2" smd circle
			(at 9.549892 -3.41884)
			(size 0.3048 0.3048)
			(layers "F.Cu" "F.Mask" "F.Paste")
			(net "GND")
		)
		(pad "K34" smd circle
			(at 9.549892 3.420364)
			(size 0.3048 0.3048)
			(layers "F.Cu" "F.Mask" "F.Paste")
			(net "GND")
		)
		(pad "L1" smd oval
			(at 9.249918 -3.938524)
			(size 0.254 0.3302)
			(layers "F.Cu" "F.Mask" "F.Paste")
			(net "GND")
		)
		(pad "L35" smd oval
			(at 9.249918 3.940048)
			(size 0.254 0.3302)
			(layers "F.Cu" "F.Mask" "F.Paste")
			(net "GND")
		)
		(pad "M7" smd circle
			(at 9.202674 -2.12471)
			(size 0.381 0.381)
			(layers "F.Cu" "F.Mask" "F.Paste")
			(net "P5E_CPU0_P0_TX_BUF_DP<15>")
		)
		(pad "M26" smd circle
			(at 9.202674 1.339342)
			(size 0.381 0.381)
			(layers "F.Cu" "F.Mask" "F.Paste")
			(net "P5E_CPU0_P0_RX_DP<15>")
		)
		(pad "N2" smd circle
			(at 8.949944 -3.41884)
			(size 0.3048 0.3048)
			(layers "F.Cu" "F.Mask" "F.Paste")
			(net "P5E_CPU0_P0_RX_BUF_DN<15>")
		)
		(pad "N34" smd circle
			(at 8.949944 3.420364)
			(size 0.3048 0.3048)
			(layers "F.Cu" "F.Mask" "F.Paste")
			(net "P5E_CPU0_P0_TX_C_DN<15>")
		)
		(pad "P10" smd circle
			(at 8.802624 -1.431798)
			(size 0.381 0.381)
			(layers "F.Cu" "F.Mask" "F.Paste")
			(net "P5E_CPU0_P0_TX_BUF_DN<15>")
		)
		(pad "P29" smd circle
			(at 8.802624 2.032254)
			(size 0.381 0.381)
			(layers "F.Cu" "F.Mask" "F.Paste")
			(net "P5E_CPU0_P0_RX_DN<15>")
		)
		(pad "R1" smd oval
			(at 8.64997 -3.938524)
			(size 0.254 0.3302)
			(layers "F.Cu" "F.Mask" "F.Paste")
			(net "P5E_CPU0_P0_RX_BUF_DP<15>")
		)
		(pad "R35" smd oval
			(at 8.64997 3.940048)
			(size 0.254 0.3302)
			(layers "F.Cu" "F.Mask" "F.Paste")
			(net "P5E_CPU0_P0_TX_C_DP<15>")
		)
		(pad "T4" smd circle
			(at 8.402574 -2.817368)
			(size 0.381 0.381)
			(layers "F.Cu" "F.Mask" "F.Paste")
			(net "GND")
		)
		(pad "T13" smd circle
			(at 8.402574 -0.79629)
			(size 0.3048 0.3048)
			(layers "F.Cu" "F.Mask" "F.Paste")
			(net "GND")
		)
		(pad "T17" smd circle
			(at 8.402574 -0.296164)
			(size 0.3048 0.3048)
			(layers "F.Cu" "F.Mask" "F.Paste")
			(net "P0V9_CPU0_RT0_2A")
		)
		(pad "T20" smd circle
			(at 8.402574 0.203708)
			(size 0.3048 0.3048)
			(layers "F.Cu" "F.Mask" "F.Paste")
			(net "P0V9_CPU0_RT0_2A")
		)
		(pad "T22" smd circle
			(at 8.402574 0.703834)
			(size 0.3048 0.3048)
			(layers "F.Cu" "F.Mask" "F.Paste")
			(net "GND")
		)
		(pad "T32" smd circle
			(at 8.402574 2.724912)
			(size 0.381 0.381)
			(layers "F.Cu" "F.Mask" "F.Paste")
			(net "GND")
		)
		(pad "U2" smd circle
			(at 8.349996 -3.41884)
			(size 0.3048 0.3048)
			(layers "F.Cu" "F.Mask" "F.Paste")
			(net "GND")
		)
		(pad "U34" smd circle
			(at 8.349996 3.420364)
			(size 0.3048 0.3048)
			(layers "F.Cu" "F.Mask" "F.Paste")
			(net "GND")
		)
		(pad "V1" smd oval
			(at 8.050022 -3.938524)
			(size 0.254 0.3302)
			(layers "F.Cu" "F.Mask" "F.Paste")
			(net "GND")
		)
		(pad "V35" smd oval
			(at 8.050022 3.940048)
			(size 0.254 0.3302)
			(layers "F.Cu" "F.Mask" "F.Paste")
			(net "GND")
		)
		(pad "W7" smd circle
			(at 8.002524 -2.12471)
			(size 0.381 0.381)
			(layers "F.Cu" "F.Mask" "F.Paste")
			(net "P5E_CPU0_P0_TX_BUF_DP<14>")
		)
		(pad "W26" smd circle
			(at 8.002524 1.339342)
			(size 0.381 0.381)
			(layers "F.Cu" "F.Mask" "F.Paste")
			(net "P5E_CPU0_P0_RX_DP<14>")
		)
		(pad "Y2" smd circle
			(at 7.750048 -3.41884)
			(size 0.3048 0.3048)
			(layers "F.Cu" "F.Mask" "F.Paste")
			(net "P5E_CPU0_P0_RX_BUF_DN<14>")
		)
		(pad "Y34" smd circle
			(at 7.750048 3.420364)
			(size 0.3048 0.3048)
			(layers "F.Cu" "F.Mask" "F.Paste")
			(net "P5E_CPU0_P0_TX_C_DN<14>")
		)
	)
	(footprint ""
		(layer "F.Cu")
		(at 426.469556 -396.145004 180)
		(property "Reference" "R1045"
			(at 0 0 180)
			(layer "F.SilkS")
			(hide yes)
			(effects
				(font
					(size 1.27 1.27)
				)
			)
		)
		(property "Value" ""
			(at 0 0 180)
			(layer "F.Fab")
			(effects
				(font
					(size 1.27 1.27)
				)
			)
		)
		(duplicate_pad_numbers_are_jumpers no)
		(fp_line
			(start 0.7874 0.4064)
			(end -0.7874 0.4064)
			(stroke
				(width 0.1524)
				(type default)
			)
			(layer "F.SilkS")
		)
		(fp_line
			(start 0.7874 -0.4064)
			(end 0.7874 0.4064)
			(stroke
				(width 0.1524)
				(type default)
			)
			(layer "F.SilkS")
		)
		(fp_line
			(start -0.7874 0.4064)
			(end -0.7874 -0.4064)
			(stroke
				(width 0.1524)
				(type default)
			)
			(layer "F.SilkS")
		)
		(fp_line
			(start -0.7874 -0.4064)
			(end 0.7874 -0.4064)
			(stroke
				(width 0.1524)
				(type default)
			)
			(layer "F.SilkS")
		)
		(fp_line
			(start 0.67945 0.3048)
			(end 0.120396 0.3048)
			(stroke
				(width 0.1)
				(type default)
			)
			(layer "F.Fab")
		)
		(fp_line
			(start 0.67945 -0.3048)
			(end 0.67945 0.3048)
			(stroke
				(width 0.1)
				(type default)
			)
			(layer "F.Fab")
		)
		(fp_line
			(start 0.12065 -0.2794)
			(end 0.12065 -0.3048)
			(stroke
				(width 0.1)
				(type default)
			)
			(layer "F.Fab")
		)
		(fp_line
			(start 0.12065 -0.3048)
			(end 0.67945 -0.3048)
			(stroke
				(width 0.1)
				(type default)
			)
			(layer "F.Fab")
		)
		(fp_line
			(start 0.120396 0.3048)
			(end 0.120396 0.2794)
			(stroke
				(width 0.1)
				(type default)
			)
			(layer "F.Fab")
		)
		(fp_line
			(start 0.120396 0.2794)
			(end -0.12065 0.2794)
			(stroke
				(width 0.1)
				(type default)
			)
			(layer "F.Fab")
		)
		(fp_line
			(start -0.12065 0.3048)
			(end -0.67945 0.3048)
			(stroke
				(width 0.1)
				(type default)
			)
			(layer "F.Fab")
		)
		(fp_line
			(start -0.12065 0.2794)
			(end -0.12065 0.3048)
			(stroke
				(width 0.1)
				(type default)
			)
			(layer "F.Fab")
		)
		(fp_line
			(start -0.12065 -0.2794)
			(end 0.12065 -0.2794)
			(stroke
				(width 0.1)
				(type default)
			)
			(layer "F.Fab")
		)
		(fp_line
			(start -0.12065 -0.305054)
			(end -0.12065 -0.2794)
			(stroke
				(width 0.1)
				(type default)
			)
			(layer "F.Fab")
		)
		(fp_line
			(start -0.67945 0.3048)
			(end -0.67945 -0.305054)
			(stroke
				(width 0.1)
				(type default)
			)
			(layer "F.Fab")
		)
		(fp_line
			(start -0.67945 -0.305054)
			(end -0.12065 -0.305054)
			(stroke
				(width 0.1)
				(type default)
			)
			(layer "F.Fab")
		)
		(pad "1" smd rect
			(at -0.40005 0)
			(size 0.4572 0.508)
			(layers "F.Cu" "F.Mask" "F.Paste")
			(net "P1V8_CPU0_RT2_1A_1D")
		)
		(pad "2" smd rect
			(at 0.40005 0)
			(size 0.4572 0.508)
			(layers "F.Cu" "F.Mask" "F.Paste")
			(net "P1V8_CPU0_RT2_1A")
		)
	)
	(footprint ""
		(layer "F.Cu")
		(at 418.212778 -163.769548 90)
		(property "Reference" "PC607_SOP0_3"
			(at 0 0 90)
			(layer "F.SilkS")
			(hide yes)
			(effects
				(font
					(size 1.27 1.27)
				)
			)
		)
		(property "Value" ""
			(at 0 0 90)
			(layer "F.Fab")
			(effects
				(font
					(size 1.27 1.27)
				)
			)
		)
		(duplicate_pad_numbers_are_jumpers no)
		(fp_line
			(start 0.7874 -0.4064)
			(end 0.7874 0.4064)
			(stroke
				(width 0.1524)
				(type default)
			)
			(layer "F.SilkS")
		)
		(fp_line
			(start -0.7874 -0.4064)
			(end 0.7874 -0.4064)
			(stroke
				(width 0.1524)
				(type default)
			)
			(layer "F.SilkS")
		)
		(fp_line
			(start 0.7874 0.4064)
			(end -0.7874 0.4064)
			(stroke
				(width 0.1524)
				(type default)
			)
			(layer "F.SilkS")
		)
		(fp_line
			(start -0.7874 0.4064)
			(end -0.7874 -0.4064)
			(stroke
				(width 0.1524)
				(type default)
			)
			(layer "F.SilkS")
		)
		(fp_line
			(start -0.12065 -0.305054)
			(end -0.12065 -0.2794)
			(stroke
				(width 0.1)
				(type default)
			)
			(layer "F.Fab")
		)
		(fp_line
			(start -0.67945 -0.305054)
			(end -0.12065 -0.305054)
			(stroke
				(width 0.1)
				(type default)
			)
			(layer "F.Fab")
		)
		(fp_line
			(start 0.67945 -0.3048)
			(end 0.67945 0.3048)
			(stroke
				(width 0.1)
				(type default)
			)
			(layer "F.Fab")
		)
		(fp_line
			(start 0.12065 -0.3048)
			(end 0.67945 -0.3048)
			(stroke
				(width 0.1)
				(type default)
			)
			(layer "F.Fab")
		)
		(fp_line
			(start 0.12065 -0.2794)
			(end 0.12065 -0.3048)
			(stroke
				(width 0.1)
				(type default)
			)
			(layer "F.Fab")
		)
		(fp_line
			(start -0.12065 -0.2794)
			(end 0.12065 -0.2794)
			(stroke
				(width 0.1)
				(type default)
			)
			(layer "F.Fab")
		)
		(fp_line
			(start 0.120396 0.2794)
			(end -0.12065 0.2794)
			(stroke
				(width 0.1)
				(type default)
			)
			(layer "F.Fab")
		)
		(fp_line
			(start -0.12065 0.2794)
			(end -0.12065 0.3048)
			(stroke
				(width 0.1)
				(type default)
			)
			(layer "F.Fab")
		)
		(fp_line
			(start 0.67945 0.3048)
			(end 0.120396 0.3048)
			(stroke
				(width 0.1)
				(type default)
			)
			(layer "F.Fab")
		)
		(fp_line
			(start 0.120396 0.3048)
			(end 0.120396 0.2794)
			(stroke
				(width 0.1)
				(type default)
			)
			(layer "F.Fab")
		)
		(fp_line
			(start -0.12065 0.3048)
			(end -0.67945 0.3048)
			(stroke
				(width 0.1)
				(type default)
			)
			(layer "F.Fab")
		)
		(fp_line
			(start -0.67945 0.3048)
			(end -0.67945 -0.305054)
			(stroke
				(width 0.1)
				(type default)
			)
			(layer "F.Fab")
		)
		(pad "1" smd circle
			(at -0.40005 0 90)
			(size 0 0)
			(layers "F.Cu" "F.Mask" "F.Paste")
			(net "PVDDCR_CPU0_P0_PVCC")
		)
		(pad "2" smd circle
			(at 0.40005 0 90)
			(size 0 0)
			(layers "F.Cu" "F.Mask" "F.Paste")
			(net "GND")
		)
	)
	(footprint ""
		(layer "F.Cu")
		(at 110.15599 -23.534878 -90)
		(property "Reference" "R6332"
			(at 0 0 270)
			(layer "F.SilkS")
			(hide yes)
			(effects
				(font
					(size 1.27 1.27)
				)
			)
		)
		(property "Value" ""
			(at 0 0 270)
			(layer "F.Fab")
			(effects
				(font
					(size 1.27 1.27)
				)
			)
		)
		(duplicate_pad_numbers_are_jumpers no)
		(fp_line
			(start -0.7874 0.4064)
			(end -0.7874 -0.4064)
			(stroke
				(width 0.1524)
				(type default)
			)
			(layer "F.SilkS")
		)
		(fp_line
			(start 0.7874 0.4064)
			(end -0.7874 0.4064)
			(stroke
				(width 0.1524)
				(type default)
			)
			(layer "F.SilkS")
		)
		(fp_line
			(start -0.7874 -0.4064)
			(end 0.7874 -0.4064)
			(stroke
				(width 0.1524)
				(type default)
			)
			(layer "F.SilkS")
		)
		(fp_line
			(start 0.7874 -0.4064)
			(end 0.7874 0.4064)
			(stroke
				(width 0.1524)
				(type default)
			)
			(layer "F.SilkS")
		)
		(fp_line
			(start -0.67945 0.3048)
			(end -0.67945 -0.305054)
			(stroke
				(width 0.1)
				(type default)
			)
			(layer "F.Fab")
		)
		(fp_line
			(start -0.12065 0.3048)
			(end -0.67945 0.3048)
			(stroke
				(width 0.1)
				(type default)
			)
			(layer "F.Fab")
		)
		(fp_line
			(start 0.120396 0.3048)
			(end 0.120396 0.2794)
			(stroke
				(width 0.1)
				(type default)
			)
			(layer "F.Fab")
		)
		(fp_line
			(start 0.67945 0.3048)
			(end 0.120396 0.3048)
			(stroke
				(width 0.1)
				(type default)
			)
			(layer "F.Fab")
		)
		(fp_line
			(start -0.12065 0.2794)
			(end -0.12065 0.3048)
			(stroke
				(width 0.1)
				(type default)
			)
			(layer "F.Fab")
		)
		(fp_line
			(start 0.120396 0.2794)
			(end -0.12065 0.2794)
			(stroke
				(width 0.1)
				(type default)
			)
			(layer "F.Fab")
		)
		(fp_line
			(start -0.12065 -0.2794)
			(end 0.12065 -0.2794)
			(stroke
				(width 0.1)
				(type default)
			)
			(layer "F.Fab")
		)
		(fp_line
			(start 0.12065 -0.2794)
			(end 0.12065 -0.3048)
			(stroke
				(width 0.1)
				(type default)
			)
			(layer "F.Fab")
		)
		(fp_line
			(start 0.12065 -0.3048)
			(end 0.67945 -0.3048)
			(stroke
				(width 0.1)
				(type default)
			)
			(layer "F.Fab")
		)
		(fp_line
			(start 0.67945 -0.3048)
			(end 0.67945 0.3048)
			(stroke
				(width 0.1)
				(type default)
			)
			(layer "F.Fab")
		)
		(fp_line
			(start -0.67945 -0.305054)
			(end -0.12065 -0.305054)
			(stroke
				(width 0.1)
				(type default)
			)
			(layer "F.Fab")
		)
		(fp_line
			(start -0.12065 -0.305054)
			(end -0.12065 -0.2794)
			(stroke
				(width 0.1)
				(type default)
			)
			(layer "F.Fab")
		)
		(pad "1" smd circle
			(at -0.40005 0 270)
			(size 0 0)
			(layers "F.Cu" "F.Mask" "F.Paste")
			(net "USB_HUB2_TI_USB_R1_MRP_RBIAS")
		)
		(pad "2" smd circle
			(at 0.40005 0 270)
			(size 0 0)
			(layers "F.Cu" "F.Mask" "F.Paste")
			(net "GND")
		)
	)
	(footprint ""
		(layer "F.Cu")
		(at 66.929 -56.261)
		(property "Reference" "R1176"
			(at 0 0 0)
			(layer "F.SilkS")
			(hide yes)
			(effects
				(font
					(size 1.27 1.27)
				)
			)
		)
		(property "Value" ""
			(at 0 0 0)
			(layer "F.Fab")
			(effects
				(font
					(size 1.27 1.27)
				)
			)
		)
		(duplicate_pad_numbers_are_jumpers no)
		(fp_line
			(start -0.7874 -0.4064)
			(end 0.7874 -0.4064)
			(stroke
				(width 0.1524)
				(type default)
			)
			(layer "F.SilkS")
		)
		(fp_line
			(start -0.7874 0.4064)
			(end -0.7874 -0.4064)
			(stroke
				(width 0.1524)
				(type default)
			)
			(layer "F.SilkS")
		)
		(fp_line
			(start 0.7874 -0.4064)
			(end 0.7874 0.4064)
			(stroke
				(width 0.1524)
				(type default)
			)
			(layer "F.SilkS")
		)
		(fp_line
			(start 0.7874 0.4064)
			(end -0.7874 0.4064)
			(stroke
				(width 0.1524)
				(type default)
			)
			(layer "F.SilkS")
		)
		(fp_line
			(start -0.67945 -0.305054)
			(end -0.12065 -0.305054)
			(stroke
				(width 0.1)
				(type default)
			)
			(layer "F.Fab")
		)
		(fp_line
			(start -0.67945 0.3048)
			(end -0.67945 -0.305054)
			(stroke
				(width 0.1)
				(type default)
			)
			(layer "F.Fab")
		)
		(fp_line
			(start -0.12065 -0.305054)
			(end -0.12065 -0.2794)
			(stroke
				(width 0.1)
				(type default)
			)
			(layer "F.Fab")
		)
		(fp_line
			(start -0.12065 -0.2794)
			(end 0.12065 -0.2794)
			(stroke
				(width 0.1)
				(type default)
			)
			(layer "F.Fab")
		)
		(fp_line
			(start -0.12065 0.2794)
			(end -0.12065 0.3048)
			(stroke
				(width 0.1)
				(type default)
			)
			(layer "F.Fab")
		)
		(fp_line
			(start -0.12065 0.3048)
			(end -0.67945 0.3048)
			(stroke
				(width 0.1)
				(type default)
			)
			(layer "F.Fab")
		)
		(fp_line
			(start 0.120396 0.2794)
			(end -0.12065 0.2794)
			(stroke
				(width 0.1)
				(type default)
			)
			(layer "F.Fab")
		)
		(fp_line
			(start 0.120396 0.3048)
			(end 0.120396 0.2794)
			(stroke
				(width 0.1)
				(type default)
			)
			(layer "F.Fab")
		)
		(fp_line
			(start 0.12065 -0.3048)
			(end 0.67945 -0.3048)
			(stroke
				(width 0.1)
				(type default)
			)
			(layer "F.Fab")
		)
		(fp_line
			(start 0.12065 -0.2794)
			(end 0.12065 -0.3048)
			(stroke
				(width 0.1)
				(type default)
			)
			(layer "F.Fab")
		)
		(fp_line
			(start 0.67945 -0.3048)
			(end 0.67945 0.3048)
			(stroke
				(width 0.1)
				(type default)
			)
			(layer "F.Fab")
		)
		(fp_line
			(start 0.67945 0.3048)
			(end 0.120396 0.3048)
			(stroke
				(width 0.1)
				(type default)
			)
			(layer "F.Fab")
		)
		(pad "1" smd circle
			(at -0.40005 0)
			(size 0 0)
			(layers "F.Cu" "F.Mask" "F.Paste")
			(net "P3V3_AUX")
		)
		(pad "2" smd circle
			(at 0.40005 0)
			(size 0 0)
			(layers "F.Cu" "F.Mask" "F.Paste")
			(net "FM_OCP_V3_2_AUX_PWR_R_EN")
		)
	)
	(footprint ""
		(layer "F.Cu")
		(at 423.473372 -424.217846)
		(property "Reference" "C989"
			(at 0 0 0)
			(layer "F.SilkS")
			(hide yes)
			(effects
				(font
					(size 1.27 1.27)
				)
			)
		)
		(property "Value" ""
			(at 0 0 0)
			(layer "F.Fab")
			(effects
				(font
					(size 1.27 1.27)
				)
			)
		)
		(duplicate_pad_numbers_are_jumpers no)
		(fp_line
			(start -0.299974 -0.150114)
			(end 0.299974 -0.150114)
			(stroke
				(width 0.1)
				(type default)
			)
			(layer "F.Fab")
		)
		(fp_line
			(start -0.299974 0.150114)
			(end -0.299974 -0.150114)
			(stroke
				(width 0.1)
				(type default)
			)
			(layer "F.Fab")
		)
		(fp_line
			(start 0.299974 -0.150114)
			(end 0.299974 0.150114)
			(stroke
				(width 0.1)
				(type default)
			)
			(layer "F.Fab")
		)
		(fp_line
			(start 0.299974 0.150114)
			(end -0.299974 0.150114)
			(stroke
				(width 0.1)
				(type default)
			)
			(layer "F.Fab")
		)
		(pad "1" smd rect
			(at -0.2667 0)
			(size 0.3048 0.381)
			(layers "F.Cu" "F.Mask" "F.Paste")
			(net "P1V8_CPU0_RT_1D")
		)
		(pad "2" smd rect
			(at 0.2667 0)
			(size 0.3048 0.381)
			(layers "F.Cu" "F.Mask" "F.Paste")
			(net "GND")
		)
	)
	(footprint ""
		(layer "F.Cu")
		(at 49.796954 -373.03583 -90)
		(property "Reference" "C827"
			(at 0 0 270)
			(layer "F.SilkS")
			(hide yes)
			(effects
				(font
					(size 1.27 1.27)
				)
			)
		)
		(property "Value" ""
			(at 0 0 270)
			(layer "F.Fab")
			(effects
				(font
					(size 1.27 1.27)
				)
			)
		)
		(duplicate_pad_numbers_are_jumpers no)
		(fp_line
			(start -0.299974 0.150114)
			(end -0.299974 -0.150114)
			(stroke
				(width 0.1)
				(type default)
			)
			(layer "F.Fab")
		)
		(fp_line
			(start 0.299974 0.150114)
			(end -0.299974 0.150114)
			(stroke
				(width 0.1)
				(type default)
			)
			(layer "F.Fab")
		)
		(fp_line
			(start -0.299974 -0.150114)
			(end 0.299974 -0.150114)
			(stroke
				(width 0.1)
				(type default)
			)
			(layer "F.Fab")
		)
		(fp_line
			(start 0.299974 -0.150114)
			(end 0.299974 0.150114)
			(stroke
				(width 0.1)
				(type default)
			)
			(layer "F.Fab")
		)
		(pad "1" smd rect
			(at -0.2667 0 270)
			(size 0.3048 0.381)
			(layers "F.Cu" "F.Mask" "F.Paste")
			(net "P5E_CPU1_P0_TX_C_DP<5>")
		)
		(pad "2" smd rect
			(at 0.2667 0 270)
			(size 0.3048 0.381)
			(layers "F.Cu" "F.Mask" "F.Paste")
			(net "P5E_CPU1_P0_TX_DP<5>")
		)
	)
	(footprint ""
		(layer "F.Cu")
		(at 15.180818 -410.31287 90)
		(property "Reference" "PU6510"
			(at -3.06324 -7.03707 90)
			(unlocked yes)
			(layer "F.SilkS")
			(effects
				(font
					(size 0.7874 0.5842)
					(thickness 0.1524)
				)
				(justify left)
			)
		)
		(property "Value" ""
			(at 0 0 90)
			(layer "F.Fab")
			(effects
				(font
					(size 1.27 1.27)
				)
			)
		)
		(duplicate_pad_numbers_are_jumpers no)
		(fp_line
			(start 0.1778 -3.2385)
			(end 0.1778 -2.8575)
			(stroke
				(width 0.1524)
				(type default)
			)
			(layer "F.SilkS")
		)
		(fp_line
			(start -1.8034 -2.8702)
			(end -1.8034 -3.6322)
			(stroke
				(width 0.1524)
				(type default)
			)
			(layer "F.SilkS")
		)
		(fp_line
			(start 2.500122 -2.500122)
			(end 2.500122 -2.015998)
			(stroke
				(width 0.1524)
				(type default)
			)
			(layer "F.SilkS")
		)
		(fp_line
			(start 2.015998 -2.500122)
			(end 2.500122 -2.500122)
			(stroke
				(width 0.1524)
				(type default)
			)
			(layer "F.SilkS")
		)
		(fp_line
			(start -2.500122 -2.500122)
			(end -2.015998 -2.500122)
			(stroke
				(width 0.1524)
				(type default)
			)
			(layer "F.SilkS")
		)
		(fp_line
			(start -2.500122 -2.015998)
			(end -2.500122 -2.500122)
			(stroke
				(width 0.1524)
				(type default)
			)
			(layer "F.SilkS")
		)
		(fp_line
			(start 2.8702 -1.778)
			(end 3.6322 -1.778)
			(stroke
				(width 0.1524)
				(type default)
			)
			(layer "F.SilkS")
		)
		(fp_line
			(start -3.2639 -0.1778)
			(end -2.8829 -0.1778)
			(stroke
				(width 0.1524)
				(type default)
			)
			(layer "F.SilkS")
		)
		(fp_line
			(start 2.8829 0.2032)
			(end 3.2639 0.2032)
			(stroke
				(width 0.1524)
				(type default)
			)
			(layer "F.SilkS")
		)
		(fp_line
			(start -3.6576 1.8034)
			(end -2.8956 1.8034)
			(stroke
				(width 0.1524)
				(type default)
			)
			(layer "F.SilkS")
		)
		(fp_line
			(start 2.500122 2.015998)
			(end 2.500122 2.500122)
			(stroke
				(width 0.1524)
				(type default)
			)
			(layer "F.SilkS")
		)
		(fp_line
			(start 2.500122 2.500122)
			(end 2.015998 2.500122)
			(stroke
				(width 0.1524)
				(type default)
			)
			(layer "F.SilkS")
		)
		(fp_line
			(start -2.015998 2.500122)
			(end -2.500122 2.500122)
			(stroke
				(width 0.1524)
				(type default)
			)
			(layer "F.SilkS")
		)
		(fp_line
			(start -2.500122 2.500122)
			(end -2.500122 2.018538)
			(stroke
				(width 0.1524)
				(type default)
			)
			(layer "F.SilkS")
		)
		(fp_line
			(start -0.2032 2.8829)
			(end -0.2032 3.2639)
			(stroke
				(width 0.1524)
				(type default)
			)
			(layer "F.SilkS")
		)
		(fp_line
			(start 1.778 3.6322)
			(end 1.778 2.8702)
			(stroke
				(width 0.1524)
				(type default)
			)
			(layer "F.SilkS")
		)
		(fp_poly
			(pts
				(xy -2.921 -1.800098) (xy -3.504184 -1.508506) (xy -3.504184 -2.09169)
			)
			(stroke
				(width 0)
				(type default)
			)
			(fill yes)
			(layer "F.SilkS")
		)
		(fp_line
			(start 0.1778 -3.2385)
			(end 0.1778 -2.8575)
			(stroke
				(width 0.1)
				(type default)
			)
			(layer "F.Fab")
		)
		(fp_line
			(start -1.8034 -2.8702)
			(end -1.8034 -3.6322)
			(stroke
				(width 0.1)
				(type default)
			)
			(layer "F.Fab")
		)
		(fp_line
			(start 2.500122 -2.500122)
			(end 2.500122 2.500122)
			(stroke
				(width 0.1)
				(type default)
			)
			(layer "F.Fab")
		)
		(fp_line
			(start -2.500122 -2.500122)
			(end 2.500122 -2.500122)
			(stroke
				(width 0.1)
				(type default)
			)
			(layer "F.Fab")
		)
		(fp_line
			(start 2.8702 -1.778)
			(end 3.6322 -1.778)
			(stroke
				(width 0.1)
				(type default)
			)
			(layer "F.Fab")
		)
		(fp_line
			(start -3.2639 -0.1778)
			(end -2.8829 -0.1778)
			(stroke
				(width 0.1)
				(type default)
			)
			(layer "F.Fab")
		)
		(fp_line
			(start 2.8829 0.2032)
			(end 3.2639 0.2032)
			(stroke
				(width 0.1)
				(type default)
			)
			(layer "F.Fab")
		)
		(fp_line
			(start -3.6576 1.8034)
			(end -2.8956 1.8034)
			(stroke
				(width 0.1)
				(type default)
			)
			(layer "F.Fab")
		)
		(fp_line
			(start 2.500122 2.500122)
			(end -2.500122 2.500122)
			(stroke
				(width 0.1)
				(type default)
			)
			(layer "F.Fab")
		)
		(fp_line
			(start -2.500122 2.500122)
			(end -2.500122 -2.500122)
			(stroke
				(width 0.1)
				(type default)
			)
			(layer "F.Fab")
		)
		(fp_line
			(start -0.2032 2.8829)
			(end -0.2032 3.2639)
			(stroke
				(width 0.1)
				(type default)
			)
			(layer "F.Fab")
		)
		(fp_line
			(start 1.778 3.6322)
			(end 1.778 2.8702)
			(stroke
				(width 0.1)
				(type default)
			)
			(layer "F.Fab")
		)
		(fp_poly
			(pts
				(xy -2.921 -1.800098) (xy -3.504184 -1.508506) (xy -3.504184 -2.09169)
			)
			(stroke
				(width 0)
				(type default)
			)
			(fill yes)
			(layer "F.Fab")
		)
		(fp_text user "40"
			(at -1.705356 -3.810762 90)
			(unlocked yes)
			(layer "F.SilkS")
			(effects
				(font
					(size 0.635 0.4064)
					(thickness 0.1524)
				)
				(justify left)
			)
		)
		(fp_text user "31"
			(at 1.29413 -3.732276 90)
			(unlocked yes)
			(layer "F.SilkS")
			(effects
				(font
					(size 0.635 0.4064)
					(thickness 0.1524)
				)
				(justify left)
			)
		)
		(fp_text user "30"
			(at 3.54203 -3.011932 0)
			(unlocked yes)
			(layer "F.SilkS")
			(effects
				(font
					(size 0.635 0.4064)
					(thickness 0.1524)
				)
				(justify left)
			)
		)
		(fp_text user "10"
			(at -2.959608 1.924558 0)
			(unlocked yes)
			(layer "F.SilkS")
			(effects
				(font
					(size 0.635 0.4064)
					(thickness 0.1524)
				)
				(justify left)
			)
		)
		(fp_text user "21"
			(at 2.948178 2.247392 0)
			(unlocked yes)
			(layer "F.SilkS")
			(effects
				(font
					(size 0.635 0.4064)
					(thickness 0.1524)
				)
				(justify left)
			)
		)
		(fp_text user "20"
			(at 1.851406 3.561842 90)
			(unlocked yes)
			(layer "F.SilkS")
			(effects
				(font
					(size 0.635 0.4064)
					(thickness 0.1524)
				)
				(justify left)
			)
		)
		(fp_text user "11"
			(at -3.35407 3.809492 90)
			(unlocked yes)
			(layer "F.SilkS")
			(effects
				(font
					(size 0.635 0.4064)
					(thickness 0.1524)
				)
				(justify left)
			)
		)
		(fp_text user "31"
			(at 1.8542 -3.172968 90)
			(unlocked yes)
			(layer "F.Fab")
			(effects
				(font
					(size 0.635 0.4064)
					(thickness 0.1524)
				)
				(justify left)
			)
		)
		(fp_text user "30"
			(at 3.223768 -3.0988 0)
			(unlocked yes)
			(layer "F.Fab")
			(effects
				(font
					(size 0.635 0.4064)
					(thickness 0.1524)
				)
				(justify left)
			)
		)
		(fp_text user "40"
			(at -3.2004 -3.096768 90)
			(unlocked yes)
			(layer "F.Fab")
			(effects
				(font
					(size 0.635 0.4064)
					(thickness 0.1524)
				)
				(justify left)
			)
		)
		(fp_text user "21"
			(at 3.274568 1.8796 0)
			(unlocked yes)
			(layer "F.Fab")
			(effects
				(font
					(size 0.635 0.4064)
					(thickness 0.1524)
				)
				(justify left)
			)
		)
		(fp_text user "10"
			(at -3.253232 2.1336 0)
			(unlocked yes)
			(layer "F.Fab")
			(effects
				(font
					(size 0.635 0.4064)
					(thickness 0.1524)
				)
				(justify left)
			)
		)
		(fp_text user "20"
			(at 2.0828 3.253232 90)
			(unlocked yes)
			(layer "F.Fab")
			(effects
				(font
					(size 0.635 0.4064)
					(thickness 0.1524)
				)
				(justify left)
			)
		)
		(fp_text user "11"
			(at -2.8702 3.278632 90)
			(unlocked yes)
			(layer "F.Fab")
			(effects
				(font
					(size 0.635 0.4064)
					(thickness 0.1524)
				)
				(justify left)
			)
		)
		(pad "1" smd rect
			(at -2.400046 -1.800098)
			(size 0.1778 0.6096)
			(layers "F.Cu" "F.Mask" "F.Paste")
			(net "NC_P0V9_RETIMER_CPU1_PWM8")
		)
		(pad "2" smd rect
			(at -2.400046 -1.400048)
			(size 0.1778 0.6096)
			(layers "F.Cu" "F.Mask" "F.Paste")
			(net "NC_P0V9_RETIMER_CPU1_PWM7")
		)
		(pad "3" smd rect
			(at -2.400046 -0.999998)
			(size 0.1778 0.6096)
			(layers "F.Cu" "F.Mask" "F.Paste")
			(net "NC_P0V9_RETIMER_CPU1_PWM6")
		)
		(pad "4" smd rect
			(at -2.400046 -0.599948)
			(size 0.1778 0.6096)
			(layers "F.Cu" "F.Mask" "F.Paste")
			(net "NC_P0V9_RETIMER_CPU1_PWM5")
		)
		(pad "5" smd rect
			(at -2.400046 -0.199898)
			(size 0.1778 0.6096)
			(layers "F.Cu" "F.Mask" "F.Paste")
			(net "NC_P0V9_RETIMER_CPU1_PWM4")
		)
		(pad "6" smd rect
			(at -2.400046 0.199898)
			(size 0.1778 0.6096)
			(layers "F.Cu" "F.Mask" "F.Paste")
			(net "NC_P0V9_RETIMER_CPU1_PWM3")
		)
		(pad "7" smd rect
			(at -2.400046 0.599948)
			(size 0.1778 0.6096)
			(layers "F.Cu" "F.Mask" "F.Paste")
			(net "P0V9_RETIMER_CPU1_PWM2")
		)
		(pad "8" smd rect
			(at -2.400046 0.999998)
			(size 0.1778 0.6096)
			(layers "F.Cu" "F.Mask" "F.Paste")
			(net "P0V9_RETIMER_CPU1_PWM1")
		)
		(pad "9" smd rect
			(at -2.400046 1.400048)
			(size 0.1778 0.6096)
			(layers "F.Cu" "F.Mask" "F.Paste")
			(net "P0V9_RETIMER_CPU1_PMSDA_R")
		)
		(pad "10" smd rect
			(at -2.400046 1.800098)
			(size 0.1778 0.6096)
			(layers "F.Cu" "F.Mask" "F.Paste")
			(net "P0V9_RETIMER_CPU1_PMSCL_R")
		)
		(pad "11" smd rect
			(at -1.800098 2.400046 90)
			(size 0.1778 0.6096)
			(layers "F.Cu" "F.Mask" "F.Paste")
			(net "TP_P0V9_RETIMER_CPU1_PMALERT")
		)
		(pad "12" smd rect
			(at -1.400048 2.400046 90)
			(size 0.1778 0.6096)
			(layers "F.Cu" "F.Mask" "F.Paste")
			(net "PWRGD_P0V9_RETIMER_CPU1_R")
		)
		(pad "13" smd rect
			(at -0.999998 2.400046 90)
			(size 0.1778 0.6096)
			(layers "F.Cu" "F.Mask" "F.Paste")
			(net "P0V9_RETIMER_CPU1_EN0_R")
		)
		(pad "14" smd rect
			(at -0.599948 2.400046 90)
			(size 0.1778 0.6096)
			(layers "F.Cu" "F.Mask" "F.Paste")
			(net "P0V9_RETIMER_CPU1_VRHOT")
		)
		(pad "15" smd rect
			(at -0.199898 2.400046 90)
			(size 0.1778 0.6096)
			(layers "F.Cu" "F.Mask" "F.Paste")
			(net "P0V9_RETIMER_CPU1_INALERT")
		)
		(pad "16" smd rect
			(at 0.199898 2.400046 90)
			(size 0.1778 0.6096)
			(layers "F.Cu" "F.Mask" "F.Paste")
			(net "NC_P0V9_RETIMER_CPU1_PG1")
		)
		(pad "17" smd rect
			(at 0.599948 2.400046 90)
			(size 0.1778 0.6096)
			(layers "F.Cu" "F.Mask" "F.Paste")
			(net "P0V9_RETIMER_CPU1_SVID_CLK")
		)
		(pad "18" smd rect
			(at 0.999998 2.400046 90)
			(size 0.1778 0.6096)
			(layers "F.Cu" "F.Mask" "F.Paste")
			(net "P0V9_RETIMER_CPU1_SVID_SDA")
		)
		(pad "19" smd rect
			(at 1.400048 2.400046 90)
			(size 0.1778 0.6096)
			(layers "F.Cu" "F.Mask" "F.Paste")
			(net "TP_P0V9_RETIMER_CPU1_SVID_ALERT_N")
		)
		(pad "20" smd rect
			(at 1.800098 2.400046 90)
			(size 0.1778 0.6096)
			(layers "F.Cu" "F.Mask" "F.Paste")
			(net "P0V9_RETIMER_CPU1_EN1_R")
		)
		(pad "21" smd rect
			(at 2.400046 1.800098)
			(size 0.1778 0.6096)
			(layers "F.Cu" "F.Mask" "F.Paste")
			(net "P0V9_RETIMER_CPU1_SENSE_R_P")
		)
		(pad "22" smd rect
			(at 2.400046 1.400048)
			(size 0.1778 0.6096)
			(layers "F.Cu" "F.Mask" "F.Paste")
			(net "P0V9_RETIMER_CPU1_SENSE_SH_N")
		)
		(pad "23" smd rect
			(at 2.400046 0.999998)
			(size 0.1778 0.6096)
			(layers "F.Cu" "F.Mask" "F.Paste")
			(net "P0V9_RETIMER_CPU1_IMON1")
		)
		(pad "24" smd rect
			(at 2.400046 0.599948)
			(size 0.1778 0.6096)
			(layers "F.Cu" "F.Mask" "F.Paste")
			(net "P0V9_RETIMER_CPU1_IMON2")
		)
		(pad "25" smd rect
			(at 2.400046 0.199898)
			(size 0.1778 0.6096)
			(layers "F.Cu" "F.Mask" "F.Paste")
			(net "NC_P0V9_RETIMER_CPU1_IMON3")
		)
		(pad "26" smd rect
			(at 2.400046 -0.199898)
			(size 0.1778 0.6096)
			(layers "F.Cu" "F.Mask" "F.Paste")
			(net "NC_P0V9_RETIMER_CPU1_IMON4")
		)
		(pad "27" smd rect
			(at 2.400046 -0.599948)
			(size 0.1778 0.6096)
			(layers "F.Cu" "F.Mask" "F.Paste")
			(net "NC_P0V9_RETIMER_CPU1_IMON5")
		)
		(pad "28" smd rect
			(at 2.400046 -0.999998)
			(size 0.1778 0.6096)
			(layers "F.Cu" "F.Mask" "F.Paste")
			(net "NC_P0V9_RETIMER_CPU1_IMON6")
		)
		(pad "29" smd rect
			(at 2.400046 -1.400048)
			(size 0.1778 0.6096)
			(layers "F.Cu" "F.Mask" "F.Paste")
			(net "NC_P0V9_RETIMER_CPU1_IMON7")
		)
		(pad "30" smd rect
			(at 2.400046 -1.800098)
			(size 0.1778 0.6096)
			(layers "F.Cu" "F.Mask" "F.Paste")
			(net "NC_P0V9_RETIMER_CPU1_IMON8")
		)
		(pad "31" smd rect
			(at 1.800098 -2.400046 90)
			(size 0.1778 0.6096)
			(layers "F.Cu" "F.Mask" "F.Paste")
			(net "GND")
		)
		(pad "32" smd rect
			(at 1.400048 -2.400046 90)
			(size 0.1778 0.6096)
			(layers "F.Cu" "F.Mask" "F.Paste")
			(net "GND")
		)
		(pad "33" smd rect
			(at 0.999998 -2.400046 90)
			(size 0.1778 0.6096)
			(layers "F.Cu" "F.Mask" "F.Paste")
			(net "P0V9_RETIMER_CPU1_CFP")
		)
		(pad "34" smd rect
			(at 0.599948 -2.400046 90)
			(size 0.1778 0.6096)
			(layers "F.Cu" "F.Mask" "F.Paste")
			(net "P0V9_RETIMER_CPU1_ADDR")
		)
		(pad "35" smd rect
			(at 0.199898 -2.400046 90)
			(size 0.1778 0.6096)
			(layers "F.Cu" "F.Mask" "F.Paste")
			(net "P0V9_RETIMER_CPU1_TEMP0")
		)
		(pad "36" smd rect
			(at -0.199898 -2.400046 90)
			(size 0.1778 0.6096)
			(layers "F.Cu" "F.Mask" "F.Paste")
			(net "P0V9_RETIMER_CPU1_TEMP1_R")
		)
		(pad "37" smd rect
			(at -0.599948 -2.400046 90)
			(size 0.1778 0.6096)
			(layers "F.Cu" "F.Mask" "F.Paste")
			(net "P0V9_RETIMER_CPU1_VMON")
		)
		(pad "38" smd rect
			(at -0.999998 -2.400046 90)
			(size 0.1778 0.6096)
			(layers "F.Cu" "F.Mask" "F.Paste")
			(net "P0V9_RETIMER_CPU1_VINSEN")
		)
		(pad "39" smd rect
			(at -1.400048 -2.400046 90)
			(size 0.1778 0.6096)
			(layers "F.Cu" "F.Mask" "F.Paste")
			(net "P0V9_RETIMER_CPU1_VCC")
		)
		(pad "40" smd rect
			(at -1.800098 -2.400046 90)
			(size 0.1778 0.6096)
			(layers "F.Cu" "F.Mask" "F.Paste")
			(net "PV09_RETIMER_CPU1_VCCS")
		)
		(pad "TH" smd rect
			(at 0 0 90)
			(size 3.6576 3.6576)
			(layers "F.Cu" "F.Mask" "F.Paste")
			(net "GND")
		)
		(zone
			(layer "F.Cu")
			(hatch none 0.5)
			(connect_pads
				(clearance 0)
			)
			(min_thickness 0.25)
			(keepout
				(tracks not_allowed)
				(vias allowed)
				(pads allowed)
				(copperpour not_allowed)
				(footprints allowed)
			)
			(placement
				(enabled no)
				(sheetname "")
			)
			(fill
				(thermal_gap 0.5)
				(thermal_bridge_width 0.5)
				(island_removal_mode 0)
			)
			(polygon
				(pts
					(xy 13.148818 -408.28087) (xy 13.148818 -412.34487) (xy 17.212818 -412.34487) (xy 17.212818 -408.28087)
					(xy 13.326618 -408.28087) (xy 13.326618 -408.43327) (xy 17.060418 -408.43327) (xy 17.060418 -412.19247)
					(xy 13.301218 -412.19247) (xy 13.301218 -408.28087)
				)
			)
		)
	)
	(footprint ""
		(layer "F.Cu")
		(at 324.529958 -193.925952 -90)
		(property "Reference" "R418"
			(at 0 0 270)
			(layer "F.SilkS")
			(hide yes)
			(effects
				(font
					(size 1.27 1.27)
				)
			)
		)
		(property "Value" ""
			(at 0 0 270)
			(layer "F.Fab")
			(effects
				(font
					(size 1.27 1.27)
				)
			)
		)
		(duplicate_pad_numbers_are_jumpers no)
		(fp_line
			(start -0.7874 0.4064)
			(end -0.7874 -0.4064)
			(stroke
				(width 0.1524)
				(type default)
			)
			(layer "F.SilkS")
		)
		(fp_line
			(start 0.7874 0.4064)
			(end -0.7874 0.4064)
			(stroke
				(width 0.1524)
				(type default)
			)
			(layer "F.SilkS")
		)
		(fp_line
			(start -0.7874 -0.4064)
			(end 0.7874 -0.4064)
			(stroke
				(width 0.1524)
				(type default)
			)
			(layer "F.SilkS")
		)
		(fp_line
			(start 0.7874 -0.4064)
			(end 0.7874 0.4064)
			(stroke
				(width 0.1524)
				(type default)
			)
			(layer "F.SilkS")
		)
		(fp_line
			(start -0.67945 0.3048)
			(end -0.67945 -0.305054)
			(stroke
				(width 0.1)
				(type default)
			)
			(layer "F.Fab")
		)
		(fp_line
			(start -0.12065 0.3048)
			(end -0.67945 0.3048)
			(stroke
				(width 0.1)
				(type default)
			)
			(layer "F.Fab")
		)
		(fp_line
			(start 0.120396 0.3048)
			(end 0.120396 0.2794)
			(stroke
				(width 0.1)
				(type default)
			)
			(layer "F.Fab")
		)
		(fp_line
			(start 0.67945 0.3048)
			(end 0.120396 0.3048)
			(stroke
				(width 0.1)
				(type default)
			)
			(layer "F.Fab")
		)
		(fp_line
			(start -0.12065 0.2794)
			(end -0.12065 0.3048)
			(stroke
				(width 0.1)
				(type default)
			)
			(layer "F.Fab")
		)
		(fp_line
			(start 0.120396 0.2794)
			(end -0.12065 0.2794)
			(stroke
				(width 0.1)
				(type default)
			)
			(layer "F.Fab")
		)
		(fp_line
			(start -0.12065 -0.2794)
			(end 0.12065 -0.2794)
			(stroke
				(width 0.1)
				(type default)
			)
			(layer "F.Fab")
		)
		(fp_line
			(start 0.12065 -0.2794)
			(end 0.12065 -0.3048)
			(stroke
				(width 0.1)
				(type default)
			)
			(layer "F.Fab")
		)
		(fp_line
			(start 0.12065 -0.3048)
			(end 0.67945 -0.3048)
			(stroke
				(width 0.1)
				(type default)
			)
			(layer "F.Fab")
		)
		(fp_line
			(start 0.67945 -0.3048)
			(end 0.67945 0.3048)
			(stroke
				(width 0.1)
				(type default)
			)
			(layer "F.Fab")
		)
		(fp_line
			(start -0.67945 -0.305054)
			(end -0.12065 -0.305054)
			(stroke
				(width 0.1)
				(type default)
			)
			(layer "F.Fab")
		)
		(fp_line
			(start -0.12065 -0.305054)
			(end -0.12065 -0.2794)
			(stroke
				(width 0.1)
				(type default)
			)
			(layer "F.Fab")
		)
		(pad "1" smd circle
			(at -0.40005 0 270)
			(size 0 0)
			(layers "F.Cu" "F.Mask" "F.Paste")
			(net "APML_CPU0_ALERT_N")
		)
		(pad "2" smd circle
			(at 0.40005 0 270)
			(size 0 0)
			(layers "F.Cu" "F.Mask" "F.Paste")
			(net "PVDD18_S5_P0")
		)
	)
	(footprint ""
		(layer "F.Cu")
		(at 197.269608 -126.833376)
		(property "Reference" "R2847"
			(at 0 0 0)
			(layer "F.SilkS")
			(hide yes)
			(effects
				(font
					(size 1.27 1.27)
				)
			)
		)
		(property "Value" ""
			(at 0 0 0)
			(layer "F.Fab")
			(effects
				(font
					(size 1.27 1.27)
				)
			)
		)
		(duplicate_pad_numbers_are_jumpers no)
		(fp_line
			(start -0.7874 -0.4064)
			(end 0.7874 -0.4064)
			(stroke
				(width 0.1524)
				(type default)
			)
			(layer "F.SilkS")
		)
		(fp_line
			(start -0.7874 0.4064)
			(end -0.7874 -0.4064)
			(stroke
				(width 0.1524)
				(type default)
			)
			(layer "F.SilkS")
		)
		(fp_line
			(start 0.7874 -0.4064)
			(end 0.7874 0.4064)
			(stroke
				(width 0.1524)
				(type default)
			)
			(layer "F.SilkS")
		)
		(fp_line
			(start 0.7874 0.4064)
			(end -0.7874 0.4064)
			(stroke
				(width 0.1524)
				(type default)
			)
			(layer "F.SilkS")
		)
		(fp_line
			(start -0.67945 -0.305054)
			(end -0.12065 -0.305054)
			(stroke
				(width 0.1)
				(type default)
			)
			(layer "F.Fab")
		)
		(fp_line
			(start -0.67945 0.3048)
			(end -0.67945 -0.305054)
			(stroke
				(width 0.1)
				(type default)
			)
			(layer "F.Fab")
		)
		(fp_line
			(start -0.12065 -0.305054)
			(end -0.12065 -0.2794)
			(stroke
				(width 0.1)
				(type default)
			)
			(layer "F.Fab")
		)
		(fp_line
			(start -0.12065 -0.2794)
			(end 0.12065 -0.2794)
			(stroke
				(width 0.1)
				(type default)
			)
			(layer "F.Fab")
		)
		(fp_line
			(start -0.12065 0.2794)
			(end -0.12065 0.3048)
			(stroke
				(width 0.1)
				(type default)
			)
			(layer "F.Fab")
		)
		(fp_line
			(start -0.12065 0.3048)
			(end -0.67945 0.3048)
			(stroke
				(width 0.1)
				(type default)
			)
			(layer "F.Fab")
		)
		(fp_line
			(start 0.120396 0.2794)
			(end -0.12065 0.2794)
			(stroke
				(width 0.1)
				(type default)
			)
			(layer "F.Fab")
		)
		(fp_line
			(start 0.120396 0.3048)
			(end 0.120396 0.2794)
			(stroke
				(width 0.1)
				(type default)
			)
			(layer "F.Fab")
		)
		(fp_line
			(start 0.12065 -0.3048)
			(end 0.67945 -0.3048)
			(stroke
				(width 0.1)
				(type default)
			)
			(layer "F.Fab")
		)
		(fp_line
			(start 0.12065 -0.2794)
			(end 0.12065 -0.3048)
			(stroke
				(width 0.1)
				(type default)
			)
			(layer "F.Fab")
		)
		(fp_line
			(start 0.67945 -0.3048)
			(end 0.67945 0.3048)
			(stroke
				(width 0.1)
				(type default)
			)
			(layer "F.Fab")
		)
		(fp_line
			(start 0.67945 0.3048)
			(end 0.120396 0.3048)
			(stroke
				(width 0.1)
				(type default)
			)
			(layer "F.Fab")
		)
		(pad "1" smd circle
			(at -0.40005 0)
			(size 0 0)
			(layers "F.Cu" "F.Mask" "F.Paste")
			(net "RST_BMC_FROM_SWB_ISO_R_N")
		)
		(pad "2" smd circle
			(at 0.40005 0)
			(size 0 0)
			(layers "F.Cu" "F.Mask" "F.Paste")
			(net "RST_BMC_FROM_SWB_ISO_N")
		)
	)
	(footprint ""
		(layer "F.Cu")
		(at 355.274372 -164.844222 -90)
		(property "Reference" "PR354"
			(at 0 0 270)
			(layer "F.SilkS")
			(hide yes)
			(effects
				(font
					(size 1.27 1.27)
				)
			)
		)
		(property "Value" ""
			(at 0 0 270)
			(layer "F.Fab")
			(effects
				(font
					(size 1.27 1.27)
				)
			)
		)
		(duplicate_pad_numbers_are_jumpers no)
		(fp_line
			(start -0.7874 0.4064)
			(end -0.7874 -0.4064)
			(stroke
				(width 0.1524)
				(type default)
			)
			(layer "F.SilkS")
		)
		(fp_line
			(start 0.7874 0.4064)
			(end -0.7874 0.4064)
			(stroke
				(width 0.1524)
				(type default)
			)
			(layer "F.SilkS")
		)
		(fp_line
			(start -0.7874 -0.4064)
			(end 0.7874 -0.4064)
			(stroke
				(width 0.1524)
				(type default)
			)
			(layer "F.SilkS")
		)
		(fp_line
			(start 0.7874 -0.4064)
			(end 0.7874 0.4064)
			(stroke
				(width 0.1524)
				(type default)
			)
			(layer "F.SilkS")
		)
		(fp_line
			(start -0.67945 0.3048)
			(end -0.67945 -0.305054)
			(stroke
				(width 0.1)
				(type default)
			)
			(layer "F.Fab")
		)
		(fp_line
			(start -0.12065 0.3048)
			(end -0.67945 0.3048)
			(stroke
				(width 0.1)
				(type default)
			)
			(layer "F.Fab")
		)
		(fp_line
			(start 0.120396 0.3048)
			(end 0.120396 0.2794)
			(stroke
				(width 0.1)
				(type default)
			)
			(layer "F.Fab")
		)
		(fp_line
			(start 0.67945 0.3048)
			(end 0.120396 0.3048)
			(stroke
				(width 0.1)
				(type default)
			)
			(layer "F.Fab")
		)
		(fp_line
			(start -0.12065 0.2794)
			(end -0.12065 0.3048)
			(stroke
				(width 0.1)
				(type default)
			)
			(layer "F.Fab")
		)
		(fp_line
			(start 0.120396 0.2794)
			(end -0.12065 0.2794)
			(stroke
				(width 0.1)
				(type default)
			)
			(layer "F.Fab")
		)
		(fp_line
			(start -0.12065 -0.2794)
			(end 0.12065 -0.2794)
			(stroke
				(width 0.1)
				(type default)
			)
			(layer "F.Fab")
		)
		(fp_line
			(start 0.12065 -0.2794)
			(end 0.12065 -0.3048)
			(stroke
				(width 0.1)
				(type default)
			)
			(layer "F.Fab")
		)
		(fp_line
			(start 0.12065 -0.3048)
			(end 0.67945 -0.3048)
			(stroke
				(width 0.1)
				(type default)
			)
			(layer "F.Fab")
		)
		(fp_line
			(start 0.67945 -0.3048)
			(end 0.67945 0.3048)
			(stroke
				(width 0.1)
				(type default)
			)
			(layer "F.Fab")
		)
		(fp_line
			(start -0.67945 -0.305054)
			(end -0.12065 -0.305054)
			(stroke
				(width 0.1)
				(type default)
			)
			(layer "F.Fab")
		)
		(fp_line
			(start -0.12065 -0.305054)
			(end -0.12065 -0.2794)
			(stroke
				(width 0.1)
				(type default)
			)
			(layer "F.Fab")
		)
		(pad "1" smd circle
			(at -0.40005 0 270)
			(size 0 0)
			(layers "F.Cu" "F.Mask" "F.Paste")
			(net "SW_PVDDCR_CPU0_P0_BOOT5")
		)
		(pad "2" smd circle
			(at 0.40005 0 270)
			(size 0 0)
			(layers "F.Cu" "F.Mask" "F.Paste")
			(net "SW_PVDDCR_CPU0_P0_BOOT5_RC")
		)
	)
	(footprint ""
		(layer "F.Cu")
		(at 118.491 -425.704)
		(property "Reference" "R3457"
			(at 0 0 0)
			(layer "F.SilkS")
			(hide yes)
			(effects
				(font
					(size 1.27 1.27)
				)
			)
		)
		(property "Value" ""
			(at 0 0 0)
			(layer "F.Fab")
			(effects
				(font
					(size 1.27 1.27)
				)
			)
		)
		(duplicate_pad_numbers_are_jumpers no)
		(fp_line
			(start -0.7874 -0.4064)
			(end 0.7874 -0.4064)
			(stroke
				(width 0.1524)
				(type default)
			)
			(layer "F.SilkS")
		)
		(fp_line
			(start -0.7874 0.4064)
			(end -0.7874 -0.4064)
			(stroke
				(width 0.1524)
				(type default)
			)
			(layer "F.SilkS")
		)
		(fp_line
			(start 0.7874 -0.4064)
			(end 0.7874 0.4064)
			(stroke
				(width 0.1524)
				(type default)
			)
			(layer "F.SilkS")
		)
		(fp_line
			(start 0.7874 0.4064)
			(end -0.7874 0.4064)
			(stroke
				(width 0.1524)
				(type default)
			)
			(layer "F.SilkS")
		)
		(fp_line
			(start -0.67945 -0.305054)
			(end -0.12065 -0.305054)
			(stroke
				(width 0.1)
				(type default)
			)
			(layer "F.Fab")
		)
		(fp_line
			(start -0.67945 0.3048)
			(end -0.67945 -0.305054)
			(stroke
				(width 0.1)
				(type default)
			)
			(layer "F.Fab")
		)
		(fp_line
			(start -0.12065 -0.305054)
			(end -0.12065 -0.2794)
			(stroke
				(width 0.1)
				(type default)
			)
			(layer "F.Fab")
		)
		(fp_line
			(start -0.12065 -0.2794)
			(end 0.12065 -0.2794)
			(stroke
				(width 0.1)
				(type default)
			)
			(layer "F.Fab")
		)
		(fp_line
			(start -0.12065 0.2794)
			(end -0.12065 0.3048)
			(stroke
				(width 0.1)
				(type default)
			)
			(layer "F.Fab")
		)
		(fp_line
			(start -0.12065 0.3048)
			(end -0.67945 0.3048)
			(stroke
				(width 0.1)
				(type default)
			)
			(layer "F.Fab")
		)
		(fp_line
			(start 0.120396 0.2794)
			(end -0.12065 0.2794)
			(stroke
				(width 0.1)
				(type default)
			)
			(layer "F.Fab")
		)
		(fp_line
			(start 0.120396 0.3048)
			(end 0.120396 0.2794)
			(stroke
				(width 0.1)
				(type default)
			)
			(layer "F.Fab")
		)
		(fp_line
			(start 0.12065 -0.3048)
			(end 0.67945 -0.3048)
			(stroke
				(width 0.1)
				(type default)
			)
			(layer "F.Fab")
		)
		(fp_line
			(start 0.12065 -0.2794)
			(end 0.12065 -0.3048)
			(stroke
				(width 0.1)
				(type default)
			)
			(layer "F.Fab")
		)
		(fp_line
			(start 0.67945 -0.3048)
			(end 0.67945 0.3048)
			(stroke
				(width 0.1)
				(type default)
			)
			(layer "F.Fab")
		)
		(fp_line
			(start 0.67945 0.3048)
			(end 0.120396 0.3048)
			(stroke
				(width 0.1)
				(type default)
			)
			(layer "F.Fab")
		)
		(pad "1" smd circle
			(at -0.40005 0)
			(size 0 0)
			(layers "F.Cu" "F.Mask" "F.Paste")
			(net "GPU_BASE_STBY_EN_BUF_R")
		)
		(pad "2" smd circle
			(at 0.40005 0)
			(size 0 0)
			(layers "F.Cu" "F.Mask" "F.Paste")
			(net "GND")
		)
	)
	(footprint ""
		(layer "F.Cu")
		(at 113.105946 -259.845302)
		(property "Reference" "C2279"
			(at 0 0 0)
			(layer "F.SilkS")
			(hide yes)
			(effects
				(font
					(size 1.27 1.27)
				)
			)
		)
		(property "Value" ""
			(at 0 0 0)
			(layer "F.Fab")
			(effects
				(font
					(size 1.27 1.27)
				)
			)
		)
		(duplicate_pad_numbers_are_jumpers no)
		(fp_line
			(start -0.7874 -0.4064)
			(end 0.7874 -0.4064)
			(stroke
				(width 0.1524)
				(type default)
			)
			(layer "F.SilkS")
		)
		(fp_line
			(start -0.7874 0.4064)
			(end -0.7874 -0.4064)
			(stroke
				(width 0.1524)
				(type default)
			)
			(layer "F.SilkS")
		)
		(fp_line
			(start 0.7874 -0.4064)
			(end 0.7874 0.4064)
			(stroke
				(width 0.1524)
				(type default)
			)
			(layer "F.SilkS")
		)
		(fp_line
			(start 0.7874 0.4064)
			(end -0.7874 0.4064)
			(stroke
				(width 0.1524)
				(type default)
			)
			(layer "F.SilkS")
		)
		(fp_line
			(start -0.67945 -0.305054)
			(end -0.12065 -0.305054)
			(stroke
				(width 0.1)
				(type default)
			)
			(layer "F.Fab")
		)
		(fp_line
			(start -0.67945 0.3048)
			(end -0.67945 -0.305054)
			(stroke
				(width 0.1)
				(type default)
			)
			(layer "F.Fab")
		)
		(fp_line
			(start -0.12065 -0.305054)
			(end -0.12065 -0.2794)
			(stroke
				(width 0.1)
				(type default)
			)
			(layer "F.Fab")
		)
		(fp_line
			(start -0.12065 -0.2794)
			(end 0.12065 -0.2794)
			(stroke
				(width 0.1)
				(type default)
			)
			(layer "F.Fab")
		)
		(fp_line
			(start -0.12065 0.2794)
			(end -0.12065 0.3048)
			(stroke
				(width 0.1)
				(type default)
			)
			(layer "F.Fab")
		)
		(fp_line
			(start -0.12065 0.3048)
			(end -0.67945 0.3048)
			(stroke
				(width 0.1)
				(type default)
			)
			(layer "F.Fab")
		)
		(fp_line
			(start 0.120396 0.2794)
			(end -0.12065 0.2794)
			(stroke
				(width 0.1)
				(type default)
			)
			(layer "F.Fab")
		)
		(fp_line
			(start 0.120396 0.3048)
			(end 0.120396 0.2794)
			(stroke
				(width 0.1)
				(type default)
			)
			(layer "F.Fab")
		)
		(fp_line
			(start 0.12065 -0.3048)
			(end 0.67945 -0.3048)
			(stroke
				(width 0.1)
				(type default)
			)
			(layer "F.Fab")
		)
		(fp_line
			(start 0.12065 -0.2794)
			(end 0.12065 -0.3048)
			(stroke
				(width 0.1)
				(type default)
			)
			(layer "F.Fab")
		)
		(fp_line
			(start 0.67945 -0.3048)
			(end 0.67945 0.3048)
			(stroke
				(width 0.1)
				(type default)
			)
			(layer "F.Fab")
		)
		(fp_line
			(start 0.67945 0.3048)
			(end 0.120396 0.3048)
			(stroke
				(width 0.1)
				(type default)
			)
			(layer "F.Fab")
		)
		(pad "1" smd circle
			(at -0.40005 0)
			(size 0 0)
			(layers "F.Cu" "F.Mask" "F.Paste")
			(net "PVDD11_S3_P1")
		)
		(pad "2" smd circle
			(at 0.40005 0)
			(size 0 0)
			(layers "F.Cu" "F.Mask" "F.Paste")
			(net "GND")
		)
	)
	(footprint ""
		(layer "F.Cu")
		(at 94.681548 -352.475038)
		(property "Reference" "PC375"
			(at 0 0 0)
			(layer "F.SilkS")
			(hide yes)
			(effects
				(font
					(size 1.27 1.27)
				)
			)
		)
		(property "Value" ""
			(at 0 0 0)
			(layer "F.Fab")
			(effects
				(font
					(size 1.27 1.27)
				)
			)
		)
		(duplicate_pad_numbers_are_jumpers no)
		(fp_line
			(start -0.7874 -0.4064)
			(end 0.7874 -0.4064)
			(stroke
				(width 0.1524)
				(type default)
			)
			(layer "F.SilkS")
		)
		(fp_line
			(start -0.7874 0.4064)
			(end -0.7874 -0.4064)
			(stroke
				(width 0.1524)
				(type default)
			)
			(layer "F.SilkS")
		)
		(fp_line
			(start 0.7874 -0.4064)
			(end 0.7874 0.4064)
			(stroke
				(width 0.1524)
				(type default)
			)
			(layer "F.SilkS")
		)
		(fp_line
			(start 0.7874 0.4064)
			(end -0.7874 0.4064)
			(stroke
				(width 0.1524)
				(type default)
			)
			(layer "F.SilkS")
		)
		(fp_line
			(start -0.67945 -0.305054)
			(end -0.12065 -0.305054)
			(stroke
				(width 0.1)
				(type default)
			)
			(layer "F.Fab")
		)
		(fp_line
			(start -0.67945 0.3048)
			(end -0.67945 -0.305054)
			(stroke
				(width 0.1)
				(type default)
			)
			(layer "F.Fab")
		)
		(fp_line
			(start -0.12065 -0.305054)
			(end -0.12065 -0.2794)
			(stroke
				(width 0.1)
				(type default)
			)
			(layer "F.Fab")
		)
		(fp_line
			(start -0.12065 -0.2794)
			(end 0.12065 -0.2794)
			(stroke
				(width 0.1)
				(type default)
			)
			(layer "F.Fab")
		)
		(fp_line
			(start -0.12065 0.2794)
			(end -0.12065 0.3048)
			(stroke
				(width 0.1)
				(type default)
			)
			(layer "F.Fab")
		)
		(fp_line
			(start -0.12065 0.3048)
			(end -0.67945 0.3048)
			(stroke
				(width 0.1)
				(type default)
			)
			(layer "F.Fab")
		)
		(fp_line
			(start 0.120396 0.2794)
			(end -0.12065 0.2794)
			(stroke
				(width 0.1)
				(type default)
			)
			(layer "F.Fab")
		)
		(fp_line
			(start 0.120396 0.3048)
			(end 0.120396 0.2794)
			(stroke
				(width 0.1)
				(type default)
			)
			(layer "F.Fab")
		)
		(fp_line
			(start 0.12065 -0.3048)
			(end 0.67945 -0.3048)
			(stroke
				(width 0.1)
				(type default)
			)
			(layer "F.Fab")
		)
		(fp_line
			(start 0.12065 -0.2794)
			(end 0.12065 -0.3048)
			(stroke
				(width 0.1)
				(type default)
			)
			(layer "F.Fab")
		)
		(fp_line
			(start 0.67945 -0.3048)
			(end 0.67945 0.3048)
			(stroke
				(width 0.1)
				(type default)
			)
			(layer "F.Fab")
		)
		(fp_line
			(start 0.67945 0.3048)
			(end 0.120396 0.3048)
			(stroke
				(width 0.1)
				(type default)
			)
			(layer "F.Fab")
		)
		(pad "1" smd circle
			(at -0.40005 0)
			(size 0 0)
			(layers "F.Cu" "F.Mask" "F.Paste")
			(net "P12V_AUX")
		)
		(pad "2" smd circle
			(at 0.40005 0)
			(size 0 0)
			(layers "F.Cu" "F.Mask" "F.Paste")
			(net "GND")
		)
	)
	(footprint ""
		(layer "F.Cu")
		(at 234.739688 -156.314648 180)
		(property "Reference" "U14"
			(at -3.930904 -1.816608 0)
			(unlocked yes)
			(layer "F.SilkS")
			(effects
				(font
					(size 0.7874 0.5842)
					(thickness 0.1524)
				)
				(justify left)
			)
		)
		(property "Value" ""
			(at 0 0 180)
			(layer "F.Fab")
			(effects
				(font
					(size 1.27 1.27)
				)
			)
		)
		(duplicate_pad_numbers_are_jumpers no)
		(fp_line
			(start 1.0414 1.575054)
			(end -1.0414 1.575054)
			(stroke
				(width 0.1524)
				(type default)
			)
			(layer "F.SilkS")
		)
		(fp_line
			(start 1.0414 -1.575054)
			(end 1.0414 1.575054)
			(stroke
				(width 0.1524)
				(type default)
			)
			(layer "F.SilkS")
		)
		(fp_line
			(start 0.254 -1.575054)
			(end 1.0414 -1.575054)
			(stroke
				(width 0.1524)
				(type default)
			)
			(layer "F.SilkS")
		)
		(fp_line
			(start 0.2286 -1.575054)
			(end 0 -1.272032)
			(stroke
				(width 0.1524)
				(type default)
			)
			(layer "F.SilkS")
		)
		(fp_line
			(start 0 -1.272032)
			(end -0.254 -1.575054)
			(stroke
				(width 0.1524)
				(type default)
			)
			(layer "F.SilkS")
		)
		(fp_line
			(start -1.0414 1.575054)
			(end -1.0414 -1.575054)
			(stroke
				(width 0.1524)
				(type default)
			)
			(layer "F.SilkS")
		)
		(fp_line
			(start -1.0414 -1.575054)
			(end -0.254 -1.575054)
			(stroke
				(width 0.1524)
				(type default)
			)
			(layer "F.SilkS")
		)
		(fp_poly
			(pts
				(xy -3.916172 -1.656588) (xy -3.32105 -2.479802) (xy -2.79527 -1.472946)
			)
			(stroke
				(width 0)
				(type default)
			)
			(fill yes)
			(layer "F.SilkS")
		)
		(fp_line
			(start 2.5654 1.2192)
			(end 1.4478 1.2192)
			(stroke
				(width 0.1)
				(type default)
			)
			(layer "F.Fab")
		)
		(fp_line
			(start 2.5654 -1.2192)
			(end 2.5654 1.2192)
			(stroke
				(width 0.1)
				(type default)
			)
			(layer "F.Fab")
		)
		(fp_line
			(start 1.4478 1.5748)
			(end -1.4478 1.5748)
			(stroke
				(width 0.1)
				(type default)
			)
			(layer "F.Fab")
		)
		(fp_line
			(start 1.4478 1.2192)
			(end 1.4478 1.5748)
			(stroke
				(width 0.1)
				(type default)
			)
			(layer "F.Fab")
		)
		(fp_line
			(start 1.4478 -1.2192)
			(end 2.5654 -1.2192)
			(stroke
				(width 0.1)
				(type default)
			)
			(layer "F.Fab")
		)
		(fp_line
			(start 1.4478 -1.5748)
			(end 1.4478 -1.2192)
			(stroke
				(width 0.1)
				(type default)
			)
			(layer "F.Fab")
		)
		(fp_line
			(start -1.4478 1.5748)
			(end -1.4478 1.2192)
			(stroke
				(width 0.1)
				(type default)
			)
			(layer "F.Fab")
		)
		(fp_line
			(start -1.4478 1.2192)
			(end -2.5654 1.2192)
			(stroke
				(width 0.1)
				(type default)
			)
			(layer "F.Fab")
		)
		(fp_line
			(start -1.4478 -1.2192)
			(end -1.4478 -1.5748)
			(stroke
				(width 0.1)
				(type default)
			)
			(layer "F.Fab")
		)
		(fp_line
			(start -1.4478 -1.5748)
			(end 1.4478 -1.5748)
			(stroke
				(width 0.1)
				(type default)
			)
			(layer "F.Fab")
		)
		(fp_line
			(start -2.5654 1.2192)
			(end -2.5654 -1.2192)
			(stroke
				(width 0.1)
				(type default)
			)
			(layer "F.Fab")
		)
		(fp_line
			(start -2.5654 -1.2192)
			(end -1.4478 -1.2192)
			(stroke
				(width 0.1)
				(type default)
			)
			(layer "F.Fab")
		)
		(fp_poly
			(pts
				(xy -2.710688 -0.975106) (xy -3.726688 -1.483106) (xy -3.726688 -0.467106)
			)
			(stroke
				(width 0)
				(type default)
			)
			(fill yes)
			(layer "F.Fab")
		)
		(pad "1" smd rect
			(at -1.849882 -0.975106 90)
			(size 0.3556 1.3208)
			(layers "F.Cu" "F.Mask" "F.Paste")
			(net "JTAG_CPU0_TDO_CPU1_TDI")
		)
		(pad "2" smd rect
			(at -1.849882 -0.32512 90)
			(size 0.3556 1.3208)
			(layers "F.Cu" "F.Mask" "F.Paste")
			(net "JTAG_CPU1_R_TDI")
		)
		(pad "3" smd rect
			(at -1.849882 0.32512 90)
			(size 0.3556 1.3208)
			(layers "F.Cu" "F.Mask" "F.Paste")
			(net "FM_PLD_CPU1_PRSNT_HDT_N")
		)
		(pad "4" smd rect
			(at -1.849882 0.975106 90)
			(size 0.3556 1.3208)
			(layers "F.Cu" "F.Mask" "F.Paste")
			(net "GND")
		)
		(pad "5" smd rect
			(at 1.849882 0.975106 90)
			(size 0.3556 1.3208)
			(layers "F.Cu" "F.Mask" "F.Paste")
			(net "JTAG_CPU0_TDO_CPU1_TDI")
		)
		(pad "6" smd rect
			(at 1.849882 0.32512 90)
			(size 0.3556 1.3208)
			(layers "F.Cu" "F.Mask" "F.Paste")
			(net "JTAG_CPU1_BYPASS")
		)
		(pad "7" smd rect
			(at 1.849882 -0.32512 90)
			(size 0.3556 1.3208)
			(layers "F.Cu" "F.Mask" "F.Paste")
			(net "CPU1_HDT_BYPASS_SEL")
		)
		(pad "8" smd rect
			(at 1.849882 -0.975106 90)
			(size 0.3556 1.3208)
			(layers "F.Cu" "F.Mask" "F.Paste")
			(net "PVDD18_S5_P0")
		)
	)
	(footprint ""
		(layer "F.Cu")
		(at 194.30619 -43.199558 180)
		(property "Reference" "Q125"
			(at 1.7526 1.856232 0)
			(unlocked yes)
			(layer "F.SilkS")
			(effects
				(font
					(size 0.7874 0.5842)
					(thickness 0.1524)
				)
				(justify left)
			)
		)
		(property "Value" ""
			(at 0 0 180)
			(layer "F.Fab")
			(effects
				(font
					(size 1.27 1.27)
				)
			)
		)
		(duplicate_pad_numbers_are_jumpers no)
		(fp_line
			(start 1.332738 1.100074)
			(end -1.332738 1.100074)
			(stroke
				(width 0.1524)
				(type default)
			)
			(layer "F.SilkS")
		)
		(fp_line
			(start 1.332738 -1.100074)
			(end 1.332738 1.100074)
			(stroke
				(width 0.1524)
				(type default)
			)
			(layer "F.SilkS")
		)
		(fp_line
			(start 0.4826 -1.100074)
			(end 1.332738 -1.100074)
			(stroke
				(width 0.1524)
				(type default)
			)
			(layer "F.SilkS")
		)
		(fp_line
			(start 0 -0.541274)
			(end 0.4826 -1.100074)
			(stroke
				(width 0.1524)
				(type default)
			)
			(layer "F.SilkS")
		)
		(fp_line
			(start -0.4826 -1.100074)
			(end 0 -0.541274)
			(stroke
				(width 0.1524)
				(type default)
			)
			(layer "F.SilkS")
		)
		(fp_line
			(start -1.332738 1.100074)
			(end -1.332738 -1.100074)
			(stroke
				(width 0.1524)
				(type default)
			)
			(layer "F.SilkS")
		)
		(fp_line
			(start -1.332738 -1.100074)
			(end -0.4826 -1.100074)
			(stroke
				(width 0.1524)
				(type default)
			)
			(layer "F.SilkS")
		)
		(fp_poly
			(pts
				(xy -1.980438 -0.69215) (xy -2.682494 -0.341122) (xy -2.682494 -1.043178)
			)
			(stroke
				(width 0)
				(type default)
			)
			(fill yes)
			(layer "F.SilkS")
		)
		(fp_line
			(start 0.674878 1.100074)
			(end -0.674878 1.100074)
			(stroke
				(width 0.1)
				(type default)
			)
			(layer "F.Fab")
		)
		(fp_line
			(start 0.674878 -1.100074)
			(end 0.674878 1.100074)
			(stroke
				(width 0.1)
				(type default)
			)
			(layer "F.Fab")
		)
		(fp_line
			(start -0.674878 1.100074)
			(end -0.674878 -1.100074)
			(stroke
				(width 0.1)
				(type default)
			)
			(layer "F.Fab")
		)
		(fp_line
			(start -0.674878 -1.100074)
			(end 0.674878 -1.100074)
			(stroke
				(width 0.1)
				(type default)
			)
			(layer "F.Fab")
		)
		(fp_poly
			(pts
				(xy -2.2352 -0.298958) (xy -2.2352 -1.001014) (xy -1.533144 -0.649986)
			)
			(stroke
				(width 0)
				(type default)
			)
			(fill yes)
			(layer "F.Fab")
		)
		(pad "1" smd rect
			(at -0.94996 -0.649986 270)
			(size 0.4318 0.508)
			(layers "F.Cu" "F.Mask" "F.Paste")
			(net "GND")
		)
		(pad "2" smd rect
			(at -0.94996 0 270)
			(size 0.4318 0.508)
			(layers "F.Cu" "F.Mask" "F.Paste")
			(net "P12V_SCM_EN_R")
		)
		(pad "3" smd rect
			(at -0.94996 0.649986 270)
			(size 0.4318 0.508)
			(layers "F.Cu" "F.Mask" "F.Paste")
			(net "P12V_SCM_UV_R")
		)
		(pad "4" smd rect
			(at 0.94996 0.649986 270)
			(size 0.4318 0.508)
			(layers "F.Cu" "F.Mask" "F.Paste")
			(net "GND")
		)
		(pad "5" smd rect
			(at 0.94996 0 270)
			(size 0.4318 0.508)
			(layers "F.Cu" "F.Mask" "F.Paste")
			(net "P12V_SCM_EN_G")
		)
		(pad "6" smd rect
			(at 0.94996 -0.649986 270)
			(size 0.4318 0.508)
			(layers "F.Cu" "F.Mask" "F.Paste")
			(net "P12V_SCM_EN_G")
		)
	)
	(footprint ""
		(layer "F.Cu")
		(at 420.75735 -41.087548)
		(property "Reference" "R5071"
			(at 0 0 0)
			(layer "F.SilkS")
			(hide yes)
			(effects
				(font
					(size 1.27 1.27)
				)
			)
		)
		(property "Value" ""
			(at 0 0 0)
			(layer "F.Fab")
			(effects
				(font
					(size 1.27 1.27)
				)
			)
		)
		(duplicate_pad_numbers_are_jumpers no)
		(fp_line
			(start -0.7874 -0.4064)
			(end 0.7874 -0.4064)
			(stroke
				(width 0.1524)
				(type default)
			)
			(layer "F.SilkS")
		)
		(fp_line
			(start -0.7874 0.4064)
			(end -0.7874 -0.4064)
			(stroke
				(width 0.1524)
				(type default)
			)
			(layer "F.SilkS")
		)
		(fp_line
			(start 0.7874 -0.4064)
			(end 0.7874 0.4064)
			(stroke
				(width 0.1524)
				(type default)
			)
			(layer "F.SilkS")
		)
		(fp_line
			(start 0.7874 0.4064)
			(end -0.7874 0.4064)
			(stroke
				(width 0.1524)
				(type default)
			)
			(layer "F.SilkS")
		)
		(fp_line
			(start -0.67945 -0.305054)
			(end -0.12065 -0.305054)
			(stroke
				(width 0.1)
				(type default)
			)
			(layer "F.Fab")
		)
		(fp_line
			(start -0.67945 0.3048)
			(end -0.67945 -0.305054)
			(stroke
				(width 0.1)
				(type default)
			)
			(layer "F.Fab")
		)
		(fp_line
			(start -0.12065 -0.305054)
			(end -0.12065 -0.2794)
			(stroke
				(width 0.1)
				(type default)
			)
			(layer "F.Fab")
		)
		(fp_line
			(start -0.12065 -0.2794)
			(end 0.12065 -0.2794)
			(stroke
				(width 0.1)
				(type default)
			)
			(layer "F.Fab")
		)
		(fp_line
			(start -0.12065 0.2794)
			(end -0.12065 0.3048)
			(stroke
				(width 0.1)
				(type default)
			)
			(layer "F.Fab")
		)
		(fp_line
			(start -0.12065 0.3048)
			(end -0.67945 0.3048)
			(stroke
				(width 0.1)
				(type default)
			)
			(layer "F.Fab")
		)
		(fp_line
			(start 0.120396 0.2794)
			(end -0.12065 0.2794)
			(stroke
				(width 0.1)
				(type default)
			)
			(layer "F.Fab")
		)
		(fp_line
			(start 0.120396 0.3048)
			(end 0.120396 0.2794)
			(stroke
				(width 0.1)
				(type default)
			)
			(layer "F.Fab")
		)
		(fp_line
			(start 0.12065 -0.3048)
			(end 0.67945 -0.3048)
			(stroke
				(width 0.1)
				(type default)
			)
			(layer "F.Fab")
		)
		(fp_line
			(start 0.12065 -0.2794)
			(end 0.12065 -0.3048)
			(stroke
				(width 0.1)
				(type default)
			)
			(layer "F.Fab")
		)
		(fp_line
			(start 0.67945 -0.3048)
			(end 0.67945 0.3048)
			(stroke
				(width 0.1)
				(type default)
			)
			(layer "F.Fab")
		)
		(fp_line
			(start 0.67945 0.3048)
			(end 0.120396 0.3048)
			(stroke
				(width 0.1)
				(type default)
			)
			(layer "F.Fab")
		)
		(pad "1" smd circle
			(at -0.40005 0)
			(size 0 0)
			(layers "F.Cu" "F.Mask" "F.Paste")
			(net "P1V8_AUX")
		)
		(pad "2" smd circle
			(at 0.40005 0)
			(size 0 0)
			(layers "F.Cu" "F.Mask" "F.Paste")
			(net "FM_FORCE_ALL_PWRON_ON")
		)
	)
	(footprint ""
		(layer "F.Cu")
		(at 257.501644 -138.448796 180)
		(property "Reference" "R607"
			(at 0 0 180)
			(layer "F.SilkS")
			(hide yes)
			(effects
				(font
					(size 1.27 1.27)
				)
			)
		)
		(property "Value" ""
			(at 0 0 180)
			(layer "F.Fab")
			(effects
				(font
					(size 1.27 1.27)
				)
			)
		)
		(duplicate_pad_numbers_are_jumpers no)
		(fp_line
			(start 0.7874 0.4064)
			(end -0.7874 0.4064)
			(stroke
				(width 0.1524)
				(type default)
			)
			(layer "F.SilkS")
		)
		(fp_line
			(start 0.7874 -0.4064)
			(end 0.7874 0.4064)
			(stroke
				(width 0.1524)
				(type default)
			)
			(layer "F.SilkS")
		)
		(fp_line
			(start -0.7874 0.4064)
			(end -0.7874 -0.4064)
			(stroke
				(width 0.1524)
				(type default)
			)
			(layer "F.SilkS")
		)
		(fp_line
			(start -0.7874 -0.4064)
			(end 0.7874 -0.4064)
			(stroke
				(width 0.1524)
				(type default)
			)
			(layer "F.SilkS")
		)
		(fp_line
			(start 0.67945 0.3048)
			(end 0.120396 0.3048)
			(stroke
				(width 0.1)
				(type default)
			)
			(layer "F.Fab")
		)
		(fp_line
			(start 0.67945 -0.3048)
			(end 0.67945 0.3048)
			(stroke
				(width 0.1)
				(type default)
			)
			(layer "F.Fab")
		)
		(fp_line
			(start 0.12065 -0.2794)
			(end 0.12065 -0.3048)
			(stroke
				(width 0.1)
				(type default)
			)
			(layer "F.Fab")
		)
		(fp_line
			(start 0.12065 -0.3048)
			(end 0.67945 -0.3048)
			(stroke
				(width 0.1)
				(type default)
			)
			(layer "F.Fab")
		)
		(fp_line
			(start 0.120396 0.3048)
			(end 0.120396 0.2794)
			(stroke
				(width 0.1)
				(type default)
			)
			(layer "F.Fab")
		)
		(fp_line
			(start 0.120396 0.2794)
			(end -0.12065 0.2794)
			(stroke
				(width 0.1)
				(type default)
			)
			(layer "F.Fab")
		)
		(fp_line
			(start -0.12065 0.3048)
			(end -0.67945 0.3048)
			(stroke
				(width 0.1)
				(type default)
			)
			(layer "F.Fab")
		)
		(fp_line
			(start -0.12065 0.2794)
			(end -0.12065 0.3048)
			(stroke
				(width 0.1)
				(type default)
			)
			(layer "F.Fab")
		)
		(fp_line
			(start -0.12065 -0.2794)
			(end 0.12065 -0.2794)
			(stroke
				(width 0.1)
				(type default)
			)
			(layer "F.Fab")
		)
		(fp_line
			(start -0.12065 -0.305054)
			(end -0.12065 -0.2794)
			(stroke
				(width 0.1)
				(type default)
			)
			(layer "F.Fab")
		)
		(fp_line
			(start -0.67945 0.3048)
			(end -0.67945 -0.305054)
			(stroke
				(width 0.1)
				(type default)
			)
			(layer "F.Fab")
		)
		(fp_line
			(start -0.67945 -0.305054)
			(end -0.12065 -0.305054)
			(stroke
				(width 0.1)
				(type default)
			)
			(layer "F.Fab")
		)
		(pad "1" smd circle
			(at -0.40005 0 180)
			(size 0 0)
			(layers "F.Cu" "F.Mask" "F.Paste")
			(net "SPI_CPU0_LVC3_D3")
		)
		(pad "2" smd circle
			(at 0.40005 0 180)
			(size 0 0)
			(layers "F.Cu" "F.Mask" "F.Paste")
			(net "SPI_CPU0_LVC3_SCM_D3")
		)
	)
	(footprint ""
		(layer "F.Cu")
		(at 291.816282 -364.891066)
		(property "Reference" "PC148"
			(at 0 0 0)
			(layer "F.SilkS")
			(hide yes)
			(effects
				(font
					(size 1.27 1.27)
				)
			)
		)
		(property "Value" ""
			(at 0 0 0)
			(layer "F.Fab")
			(effects
				(font
					(size 1.27 1.27)
				)
			)
		)
		(duplicate_pad_numbers_are_jumpers no)
		(fp_line
			(start -0.7874 -0.4064)
			(end 0.7874 -0.4064)
			(stroke
				(width 0.1524)
				(type default)
			)
			(layer "F.SilkS")
		)
		(fp_line
			(start -0.7874 0.4064)
			(end -0.7874 -0.4064)
			(stroke
				(width 0.1524)
				(type default)
			)
			(layer "F.SilkS")
		)
		(fp_line
			(start 0.7874 -0.4064)
			(end 0.7874 0.4064)
			(stroke
				(width 0.1524)
				(type default)
			)
			(layer "F.SilkS")
		)
		(fp_line
			(start 0.7874 0.4064)
			(end -0.7874 0.4064)
			(stroke
				(width 0.1524)
				(type default)
			)
			(layer "F.SilkS")
		)
		(fp_line
			(start -0.67945 -0.305054)
			(end -0.12065 -0.305054)
			(stroke
				(width 0.1)
				(type default)
			)
			(layer "F.Fab")
		)
		(fp_line
			(start -0.67945 0.3048)
			(end -0.67945 -0.305054)
			(stroke
				(width 0.1)
				(type default)
			)
			(layer "F.Fab")
		)
		(fp_line
			(start -0.12065 -0.305054)
			(end -0.12065 -0.2794)
			(stroke
				(width 0.1)
				(type default)
			)
			(layer "F.Fab")
		)
		(fp_line
			(start -0.12065 -0.2794)
			(end 0.12065 -0.2794)
			(stroke
				(width 0.1)
				(type default)
			)
			(layer "F.Fab")
		)
		(fp_line
			(start -0.12065 0.2794)
			(end -0.12065 0.3048)
			(stroke
				(width 0.1)
				(type default)
			)
			(layer "F.Fab")
		)
		(fp_line
			(start -0.12065 0.3048)
			(end -0.67945 0.3048)
			(stroke
				(width 0.1)
				(type default)
			)
			(layer "F.Fab")
		)
		(fp_line
			(start 0.120396 0.2794)
			(end -0.12065 0.2794)
			(stroke
				(width 0.1)
				(type default)
			)
			(layer "F.Fab")
		)
		(fp_line
			(start 0.120396 0.3048)
			(end 0.120396 0.2794)
			(stroke
				(width 0.1)
				(type default)
			)
			(layer "F.Fab")
		)
		(fp_line
			(start 0.12065 -0.3048)
			(end 0.67945 -0.3048)
			(stroke
				(width 0.1)
				(type default)
			)
			(layer "F.Fab")
		)
		(fp_line
			(start 0.12065 -0.2794)
			(end 0.12065 -0.3048)
			(stroke
				(width 0.1)
				(type default)
			)
			(layer "F.Fab")
		)
		(fp_line
			(start 0.67945 -0.3048)
			(end 0.67945 0.3048)
			(stroke
				(width 0.1)
				(type default)
			)
			(layer "F.Fab")
		)
		(fp_line
			(start 0.67945 0.3048)
			(end 0.120396 0.3048)
			(stroke
				(width 0.1)
				(type default)
			)
			(layer "F.Fab")
		)
		(pad "1" smd circle
			(at -0.40005 0)
			(size 0 0)
			(layers "F.Cu" "F.Mask" "F.Paste")
			(net "P12V_AUX")
		)
		(pad "2" smd circle
			(at 0.40005 0)
			(size 0 0)
			(layers "F.Cu" "F.Mask" "F.Paste")
			(net "GND")
		)
	)
	(footprint ""
		(layer "F.Cu")
		(at 157.037024 -26.68778 -90)
		(property "Reference" "R6018"
			(at 0 0 270)
			(layer "F.SilkS")
			(hide yes)
			(effects
				(font
					(size 1.27 1.27)
				)
			)
		)
		(property "Value" ""
			(at 0 0 270)
			(layer "F.Fab")
			(effects
				(font
					(size 1.27 1.27)
				)
			)
		)
		(duplicate_pad_numbers_are_jumpers no)
		(fp_line
			(start -0.7874 0.4064)
			(end -0.7874 -0.4064)
			(stroke
				(width 0.1524)
				(type default)
			)
			(layer "F.SilkS")
		)
		(fp_line
			(start 0.7874 0.4064)
			(end -0.7874 0.4064)
			(stroke
				(width 0.1524)
				(type default)
			)
			(layer "F.SilkS")
		)
		(fp_line
			(start -0.7874 -0.4064)
			(end 0.7874 -0.4064)
			(stroke
				(width 0.1524)
				(type default)
			)
			(layer "F.SilkS")
		)
		(fp_line
			(start 0.7874 -0.4064)
			(end 0.7874 0.4064)
			(stroke
				(width 0.1524)
				(type default)
			)
			(layer "F.SilkS")
		)
		(fp_line
			(start -0.67945 0.3048)
			(end -0.67945 -0.305054)
			(stroke
				(width 0.1)
				(type default)
			)
			(layer "F.Fab")
		)
		(fp_line
			(start -0.12065 0.3048)
			(end -0.67945 0.3048)
			(stroke
				(width 0.1)
				(type default)
			)
			(layer "F.Fab")
		)
		(fp_line
			(start 0.120396 0.3048)
			(end 0.120396 0.2794)
			(stroke
				(width 0.1)
				(type default)
			)
			(layer "F.Fab")
		)
		(fp_line
			(start 0.67945 0.3048)
			(end 0.120396 0.3048)
			(stroke
				(width 0.1)
				(type default)
			)
			(layer "F.Fab")
		)
		(fp_line
			(start -0.12065 0.2794)
			(end -0.12065 0.3048)
			(stroke
				(width 0.1)
				(type default)
			)
			(layer "F.Fab")
		)
		(fp_line
			(start 0.120396 0.2794)
			(end -0.12065 0.2794)
			(stroke
				(width 0.1)
				(type default)
			)
			(layer "F.Fab")
		)
		(fp_line
			(start -0.12065 -0.2794)
			(end 0.12065 -0.2794)
			(stroke
				(width 0.1)
				(type default)
			)
			(layer "F.Fab")
		)
		(fp_line
			(start 0.12065 -0.2794)
			(end 0.12065 -0.3048)
			(stroke
				(width 0.1)
				(type default)
			)
			(layer "F.Fab")
		)
		(fp_line
			(start 0.12065 -0.3048)
			(end 0.67945 -0.3048)
			(stroke
				(width 0.1)
				(type default)
			)
			(layer "F.Fab")
		)
		(fp_line
			(start 0.67945 -0.3048)
			(end 0.67945 0.3048)
			(stroke
				(width 0.1)
				(type default)
			)
			(layer "F.Fab")
		)
		(fp_line
			(start -0.67945 -0.305054)
			(end -0.12065 -0.305054)
			(stroke
				(width 0.1)
				(type default)
			)
			(layer "F.Fab")
		)
		(fp_line
			(start -0.12065 -0.305054)
			(end -0.12065 -0.2794)
			(stroke
				(width 0.1)
				(type default)
			)
			(layer "F.Fab")
		)
		(pad "1" smd circle
			(at -0.40005 0 270)
			(size 0 0)
			(layers "F.Cu" "F.Mask" "F.Paste")
			(net "P3V3_AUX")
		)
		(pad "2" smd circle
			(at 0.40005 0 270)
			(size 0 0)
			(layers "F.Cu" "F.Mask" "F.Paste")
			(net "SGPIO_SCM_DI_<0>")
		)
	)
	(footprint ""
		(layer "F.Cu")
		(at 398.893538 -393.04468)
		(property "Reference" "R1072"
			(at 0 0 0)
			(layer "F.SilkS")
			(hide yes)
			(effects
				(font
					(size 1.27 1.27)
				)
			)
		)
		(property "Value" ""
			(at 0 0 0)
			(layer "F.Fab")
			(effects
				(font
					(size 1.27 1.27)
				)
			)
		)
		(duplicate_pad_numbers_are_jumpers no)
		(fp_line
			(start -0.32512 -0.175006)
			(end 0.32512 -0.175006)
			(stroke
				(width 0.1)
				(type default)
			)
			(layer "F.Fab")
		)
		(fp_line
			(start -0.32512 0.175006)
			(end -0.32512 -0.175006)
			(stroke
				(width 0.1)
				(type default)
			)
			(layer "F.Fab")
		)
		(fp_line
			(start 0.32512 -0.175006)
			(end 0.32512 0.175006)
			(stroke
				(width 0.1)
				(type default)
			)
			(layer "F.Fab")
		)
		(fp_line
			(start 0.32512 0.175006)
			(end -0.32512 0.175006)
			(stroke
				(width 0.1)
				(type default)
			)
			(layer "F.Fab")
		)
		(pad "1" smd rect
			(at -0.2667 0)
			(size 0.3048 0.381)
			(layers "F.Cu" "F.Mask" "F.Paste")
			(net "GPIO3_RT_CPU0_P2")
		)
		(pad "2" smd rect
			(at 0.2667 0 180)
			(size 0.3048 0.381)
			(layers "F.Cu" "F.Mask" "F.Paste")
			(net "GND")
		)
	)
	(footprint ""
		(layer "F.Cu")
		(at 97.177352 -72.99198 180)
		(property "Reference" "R3631"
			(at 0 0 180)
			(layer "F.SilkS")
			(hide yes)
			(effects
				(font
					(size 1.27 1.27)
				)
			)
		)
		(property "Value" ""
			(at 0 0 180)
			(layer "F.Fab")
			(effects
				(font
					(size 1.27 1.27)
				)
			)
		)
		(duplicate_pad_numbers_are_jumpers no)
		(fp_line
			(start 0.7874 0.4064)
			(end -0.7874 0.4064)
			(stroke
				(width 0.1524)
				(type default)
			)
			(layer "F.SilkS")
		)
		(fp_line
			(start 0.7874 -0.4064)
			(end 0.7874 0.4064)
			(stroke
				(width 0.1524)
				(type default)
			)
			(layer "F.SilkS")
		)
		(fp_line
			(start -0.7874 0.4064)
			(end -0.7874 -0.4064)
			(stroke
				(width 0.1524)
				(type default)
			)
			(layer "F.SilkS")
		)
		(fp_line
			(start -0.7874 -0.4064)
			(end 0.7874 -0.4064)
			(stroke
				(width 0.1524)
				(type default)
			)
			(layer "F.SilkS")
		)
		(fp_line
			(start 0.67945 0.3048)
			(end 0.120396 0.3048)
			(stroke
				(width 0.1)
				(type default)
			)
			(layer "F.Fab")
		)
		(fp_line
			(start 0.67945 -0.3048)
			(end 0.67945 0.3048)
			(stroke
				(width 0.1)
				(type default)
			)
			(layer "F.Fab")
		)
		(fp_line
			(start 0.12065 -0.2794)
			(end 0.12065 -0.3048)
			(stroke
				(width 0.1)
				(type default)
			)
			(layer "F.Fab")
		)
		(fp_line
			(start 0.12065 -0.3048)
			(end 0.67945 -0.3048)
			(stroke
				(width 0.1)
				(type default)
			)
			(layer "F.Fab")
		)
		(fp_line
			(start 0.120396 0.3048)
			(end 0.120396 0.2794)
			(stroke
				(width 0.1)
				(type default)
			)
			(layer "F.Fab")
		)
		(fp_line
			(start 0.120396 0.2794)
			(end -0.12065 0.2794)
			(stroke
				(width 0.1)
				(type default)
			)
			(layer "F.Fab")
		)
		(fp_line
			(start -0.12065 0.3048)
			(end -0.67945 0.3048)
			(stroke
				(width 0.1)
				(type default)
			)
			(layer "F.Fab")
		)
		(fp_line
			(start -0.12065 0.2794)
			(end -0.12065 0.3048)
			(stroke
				(width 0.1)
				(type default)
			)
			(layer "F.Fab")
		)
		(fp_line
			(start -0.12065 -0.2794)
			(end 0.12065 -0.2794)
			(stroke
				(width 0.1)
				(type default)
			)
			(layer "F.Fab")
		)
		(fp_line
			(start -0.12065 -0.305054)
			(end -0.12065 -0.2794)
			(stroke
				(width 0.1)
				(type default)
			)
			(layer "F.Fab")
		)
		(fp_line
			(start -0.67945 0.3048)
			(end -0.67945 -0.305054)
			(stroke
				(width 0.1)
				(type default)
			)
			(layer "F.Fab")
		)
		(fp_line
			(start -0.67945 -0.305054)
			(end -0.12065 -0.305054)
			(stroke
				(width 0.1)
				(type default)
			)
			(layer "F.Fab")
		)
		(pad "1" smd circle
			(at -0.40005 0 180)
			(size 0 0)
			(layers "F.Cu" "F.Mask" "F.Paste")
			(net "P3V3_OCP_V3_2_EN_R")
		)
		(pad "2" smd circle
			(at 0.40005 0 180)
			(size 0 0)
			(layers "F.Cu" "F.Mask" "F.Paste")
			(net "P3V3_OCP_EN_2")
		)
	)
	(footprint ""
		(layer "F.Cu")
		(at 179.236878 -353.960684 90)
		(property "Reference" "PC505"
			(at 0 0 90)
			(layer "F.SilkS")
			(hide yes)
			(effects
				(font
					(size 1.27 1.27)
				)
			)
		)
		(property "Value" ""
			(at 0 0 90)
			(layer "F.Fab")
			(effects
				(font
					(size 1.27 1.27)
				)
			)
		)
		(duplicate_pad_numbers_are_jumpers no)
		(fp_line
			(start 0.7874 -0.4064)
			(end 0.7874 0.4064)
			(stroke
				(width 0.1524)
				(type default)
			)
			(layer "F.SilkS")
		)
		(fp_line
			(start -0.7874 -0.4064)
			(end 0.7874 -0.4064)
			(stroke
				(width 0.1524)
				(type default)
			)
			(layer "F.SilkS")
		)
		(fp_line
			(start 0.7874 0.4064)
			(end 0.420116 0.4064)
			(stroke
				(width 0.1524)
				(type default)
			)
			(layer "F.SilkS")
		)
		(fp_line
			(start -0.265684 0.4064)
			(end -0.7874 0.4064)
			(stroke
				(width 0.1524)
				(type default)
			)
			(layer "F.SilkS")
		)
		(fp_line
			(start -0.7874 0.4064)
			(end -0.7874 -0.4064)
			(stroke
				(width 0.1524)
				(type default)
			)
			(layer "F.SilkS")
		)
		(fp_line
			(start -0.12065 -0.305054)
			(end -0.12065 -0.2794)
			(stroke
				(width 0.1)
				(type default)
			)
			(layer "F.Fab")
		)
		(fp_line
			(start -0.67945 -0.305054)
			(end -0.12065 -0.305054)
			(stroke
				(width 0.1)
				(type default)
			)
			(layer "F.Fab")
		)
		(fp_line
			(start 0.67945 -0.3048)
			(end 0.67945 0.3048)
			(stroke
				(width 0.1)
				(type default)
			)
			(layer "F.Fab")
		)
		(fp_line
			(start 0.12065 -0.3048)
			(end 0.67945 -0.3048)
			(stroke
				(width 0.1)
				(type default)
			)
			(layer "F.Fab")
		)
		(fp_line
			(start 0.12065 -0.2794)
			(end 0.12065 -0.3048)
			(stroke
				(width 0.1)
				(type default)
			)
			(layer "F.Fab")
		)
		(fp_line
			(start -0.12065 -0.2794)
			(end 0.12065 -0.2794)
			(stroke
				(width 0.1)
				(type default)
			)
			(layer "F.Fab")
		)
		(fp_line
			(start 0.120396 0.2794)
			(end -0.12065 0.2794)
			(stroke
				(width 0.1)
				(type default)
			)
			(layer "F.Fab")
		)
		(fp_line
			(start -0.12065 0.2794)
			(end -0.12065 0.3048)
			(stroke
				(width 0.1)
				(type default)
			)
			(layer "F.Fab")
		)
		(fp_line
			(start 0.67945 0.3048)
			(end 0.120396 0.3048)
			(stroke
				(width 0.1)
				(type default)
			)
			(layer "F.Fab")
		)
		(fp_line
			(start 0.120396 0.3048)
			(end 0.120396 0.2794)
			(stroke
				(width 0.1)
				(type default)
			)
			(layer "F.Fab")
		)
		(fp_line
			(start -0.12065 0.3048)
			(end -0.67945 0.3048)
			(stroke
				(width 0.1)
				(type default)
			)
			(layer "F.Fab")
		)
		(fp_line
			(start -0.67945 0.3048)
			(end -0.67945 -0.305054)
			(stroke
				(width 0.1)
				(type default)
			)
			(layer "F.Fab")
		)
		(pad "1" smd circle
			(at -0.40005 0 90)
			(size 0 0)
			(layers "F.Cu" "F.Mask" "F.Paste")
			(net "PVDD11_S3_P1_VCC1")
		)
		(pad "2" smd circle
			(at 0.40005 0 90)
			(size 0 0)
			(layers "F.Cu" "F.Mask" "F.Paste")
			(net "GND")
		)
	)
	(footprint ""
		(layer "F.Cu")
		(at 21.075396 -339.223604 90)
		(property "Reference" "PL46"
			(at 0 -3.978148 90)
			(unlocked yes)
			(layer "F.SilkS")
			(effects
				(font
					(size 0.7874 0.5842)
					(thickness 0.1524)
				)
				(justify left)
			)
		)
		(property "Value" ""
			(at 0 0 90)
			(layer "F.Fab")
			(effects
				(font
					(size 1.27 1.27)
				)
			)
		)
		(duplicate_pad_numbers_are_jumpers no)
		(fp_line
			(start 3.24993 -3.24993)
			(end 3.24993 -2.2352)
			(stroke
				(width 0.1524)
				(type default)
			)
			(layer "F.SilkS")
		)
		(fp_line
			(start -3.24993 -3.24993)
			(end 3.24993 -3.24993)
			(stroke
				(width 0.1524)
				(type default)
			)
			(layer "F.SilkS")
		)
		(fp_line
			(start -3.24993 -2.2352)
			(end -3.24993 -3.24993)
			(stroke
				(width 0.1524)
				(type default)
			)
			(layer "F.SilkS")
		)
		(fp_line
			(start 3.24993 2.2352)
			(end 3.24993 3.24993)
			(stroke
				(width 0.1524)
				(type default)
			)
			(layer "F.SilkS")
		)
		(fp_line
			(start 3.24993 3.24993)
			(end -3.24993 3.24993)
			(stroke
				(width 0.1524)
				(type default)
			)
			(layer "F.SilkS")
		)
		(fp_line
			(start -3.24993 3.24993)
			(end -3.24993 2.2352)
			(stroke
				(width 0.1524)
				(type default)
			)
			(layer "F.SilkS")
		)
		(fp_line
			(start 3.24993 -3.24993)
			(end 3.24993 3.24993)
			(stroke
				(width 0.1)
				(type default)
			)
			(layer "F.Fab")
		)
		(fp_line
			(start -3.24993 -3.24993)
			(end 3.24993 -3.24993)
			(stroke
				(width 0.1)
				(type default)
			)
			(layer "F.Fab")
		)
		(fp_line
			(start 3.24993 3.24993)
			(end -3.24993 3.24993)
			(stroke
				(width 0.1)
				(type default)
			)
			(layer "F.Fab")
		)
		(fp_line
			(start -3.24993 3.24993)
			(end -3.24993 -3.24993)
			(stroke
				(width 0.1)
				(type default)
			)
			(layer "F.Fab")
		)
		(pad "1" smd rect
			(at -2.29997 0 90)
			(size 2.0066 4.2164)
			(layers "F.Cu" "F.Mask" "F.Paste")
			(net "IND_PVDDIO_P1_CPL0")
		)
		(pad "2" smd rect
			(at 2.29997 0 90)
			(size 2.0066 4.2164)
			(layers "F.Cu" "F.Mask" "F.Paste")
			(net "GND")
		)
	)
	(footprint ""
		(layer "F.Cu")
		(at 166.3192 -434.869336)
		(property "Reference" "R2724"
			(at 0 0 0)
			(layer "F.SilkS")
			(hide yes)
			(effects
				(font
					(size 1.27 1.27)
				)
			)
		)
		(property "Value" ""
			(at 0 0 0)
			(layer "F.Fab")
			(effects
				(font
					(size 1.27 1.27)
				)
			)
		)
		(duplicate_pad_numbers_are_jumpers no)
		(fp_line
			(start -0.7874 -0.4064)
			(end 0.7874 -0.4064)
			(stroke
				(width 0.1524)
				(type default)
			)
			(layer "F.SilkS")
		)
		(fp_line
			(start -0.7874 0.4064)
			(end -0.7874 -0.4064)
			(stroke
				(width 0.1524)
				(type default)
			)
			(layer "F.SilkS")
		)
		(fp_line
			(start 0.7874 -0.4064)
			(end 0.7874 0.4064)
			(stroke
				(width 0.1524)
				(type default)
			)
			(layer "F.SilkS")
		)
		(fp_line
			(start 0.7874 0.4064)
			(end -0.7874 0.4064)
			(stroke
				(width 0.1524)
				(type default)
			)
			(layer "F.SilkS")
		)
		(fp_line
			(start -0.67945 -0.305054)
			(end -0.12065 -0.305054)
			(stroke
				(width 0.1)
				(type default)
			)
			(layer "F.Fab")
		)
		(fp_line
			(start -0.67945 0.3048)
			(end -0.67945 -0.305054)
			(stroke
				(width 0.1)
				(type default)
			)
			(layer "F.Fab")
		)
		(fp_line
			(start -0.12065 -0.305054)
			(end -0.12065 -0.2794)
			(stroke
				(width 0.1)
				(type default)
			)
			(layer "F.Fab")
		)
		(fp_line
			(start -0.12065 -0.2794)
			(end 0.12065 -0.2794)
			(stroke
				(width 0.1)
				(type default)
			)
			(layer "F.Fab")
		)
		(fp_line
			(start -0.12065 0.2794)
			(end -0.12065 0.3048)
			(stroke
				(width 0.1)
				(type default)
			)
			(layer "F.Fab")
		)
		(fp_line
			(start -0.12065 0.3048)
			(end -0.67945 0.3048)
			(stroke
				(width 0.1)
				(type default)
			)
			(layer "F.Fab")
		)
		(fp_line
			(start 0.120396 0.2794)
			(end -0.12065 0.2794)
			(stroke
				(width 0.1)
				(type default)
			)
			(layer "F.Fab")
		)
		(fp_line
			(start 0.120396 0.3048)
			(end 0.120396 0.2794)
			(stroke
				(width 0.1)
				(type default)
			)
			(layer "F.Fab")
		)
		(fp_line
			(start 0.12065 -0.3048)
			(end 0.67945 -0.3048)
			(stroke
				(width 0.1)
				(type default)
			)
			(layer "F.Fab")
		)
		(fp_line
			(start 0.12065 -0.2794)
			(end 0.12065 -0.3048)
			(stroke
				(width 0.1)
				(type default)
			)
			(layer "F.Fab")
		)
		(fp_line
			(start 0.67945 -0.3048)
			(end 0.67945 0.3048)
			(stroke
				(width 0.1)
				(type default)
			)
			(layer "F.Fab")
		)
		(fp_line
			(start 0.67945 0.3048)
			(end 0.120396 0.3048)
			(stroke
				(width 0.1)
				(type default)
			)
			(layer "F.Fab")
		)
		(pad "1" smd circle
			(at -0.40005 0)
			(size 0 0)
			(layers "F.Cu" "F.Mask" "F.Paste")
			(net "SMB_BMC_SWB_R_SDA")
		)
		(pad "2" smd circle
			(at 0.40005 0)
			(size 0 0)
			(layers "F.Cu" "F.Mask" "F.Paste")
			(net "SMB_BMC_SWB_BUF_R_SDA")
		)
	)
	(footprint ""
		(layer "F.Cu")
		(at 49.834038 -255.560322 180)
		(property "Reference" "J26"
			(at -0.703326 -82.357722 0)
			(unlocked yes)
			(layer "F.SilkS")
			(effects
				(font
					(size 0.7874 0.5842)
					(thickness 0.1524)
				)
			)
		)
		(property "Value" ""
			(at 0 0 180)
			(layer "F.Fab")
			(effects
				(font
					(size 1.27 1.27)
				)
			)
		)
		(duplicate_pad_numbers_are_jumpers no)
		(fp_line
			(start 3.24993 -81.000092)
			(end 3.24993 75.401678)
			(stroke
				(width 0.1524)
				(type default)
			)
			(layer "F.SilkS")
		)
		(fp_line
			(start -3.24993 75.401678)
			(end -3.24993 -81.000092)
			(stroke
				(width 0.1524)
				(type default)
			)
			(layer "F.SilkS")
		)
		(fp_line
			(start -3.24993 72.499982)
			(end 3.24993 72.499982)
			(stroke
				(width 0.1524)
				(type default)
			)
			(layer "F.SilkS")
		)
		(fp_line
			(start -3.24993 -72.499982)
			(end 3.24993 -72.499982)
			(stroke
				(width 0.1524)
				(type default)
			)
			(layer "F.SilkS")
		)
		(fp_line
			(start -3.24993 -81.000092)
			(end 3.24993 -81.000092)
			(stroke
				(width 0.1524)
				(type default)
			)
			(layer "F.SilkS")
		)
		(fp_poly
			(pts
				(xy -3.763518 -64.792606) (xy -3.109976 -63.863474) (xy -4.245356 -63.898272)
			)
			(stroke
				(width 0)
				(type default)
			)
			(fill yes)
			(layer "F.SilkS")
		)
		(fp_line
			(start 3.24993 81.000092)
			(end -3.24993 81.000092)
			(stroke
				(width 0.1)
				(type default)
			)
			(layer "F.Fab")
		)
		(fp_line
			(start 3.24993 -81.000092)
			(end 3.24993 81.000092)
			(stroke
				(width 0.1)
				(type default)
			)
			(layer "F.Fab")
		)
		(fp_line
			(start -3.24993 81.000092)
			(end -3.24993 -81.000092)
			(stroke
				(width 0.1)
				(type default)
			)
			(layer "F.Fab")
		)
		(fp_line
			(start -3.24993 72.499982)
			(end 3.24993 72.499982)
			(stroke
				(width 0.1)
				(type default)
			)
			(layer "F.Fab")
		)
		(fp_line
			(start -3.24993 71.000112)
			(end 3.24993 71.000112)
			(stroke
				(width 0.1)
				(type default)
			)
			(layer "F.Fab")
		)
		(fp_line
			(start -3.24993 -71.000112)
			(end 3.24993 -71.000112)
			(stroke
				(width 0.1)
				(type default)
			)
			(layer "F.Fab")
		)
		(fp_line
			(start -3.24993 -72.499982)
			(end 3.24993 -72.499982)
			(stroke
				(width 0.1)
				(type default)
			)
			(layer "F.Fab")
		)
		(fp_line
			(start -3.24993 -81.000092)
			(end 3.24993 -81.000092)
			(stroke
				(width 0.1)
				(type default)
			)
			(layer "F.Fab")
		)
		(fp_poly
			(pts
				(xy -3.41503 -63.324994) (xy -4.43103 -62.816994) (xy -4.43103 -63.832994)
			)
			(stroke
				(width 0)
				(type default)
			)
			(fill yes)
			(layer "F.Fab")
		)
		(pad "1" smd rect
			(at -2.050034 -63.324994 90)
			(size 0.519938 1.4986)
			(layers "F.Cu" "F.Mask" "F.Paste")
			(net "P12V_MEM_CPU1")
		)
		(pad "2" smd rect
			(at -2.050034 -62.47511 90)
			(size 0.519938 1.4986)
			(layers "F.Cu" "F.Mask" "F.Paste")
			(net "Net_2270")
		)
		(pad "3" smd rect
			(at -2.050034 -61.624972 90)
			(size 0.519938 1.4986)
			(layers "F.Cu" "F.Mask" "F.Paste")
			(net "P3V3_AUX")
		)
		(pad "4" smd rect
			(at -2.050034 -60.775088 90)
			(size 0.519938 1.4986)
			(layers "F.Cu" "F.Mask" "F.Paste")
			(net "I3C_SPD_DDRB_CPU1_SCL")
		)
		(pad "5" smd rect
			(at -2.050034 -59.92495 90)
			(size 0.519938 1.4986)
			(layers "F.Cu" "F.Mask" "F.Paste")
			(net "I3C_SPD_DDRB_CPU1_SDA")
		)
		(pad "6" smd rect
			(at -2.050034 -59.075066 90)
			(size 0.519938 1.4986)
			(layers "F.Cu" "F.Mask" "F.Paste")
			(net "GND")
		)
		(pad "7" smd rect
			(at -2.050034 -58.224928 90)
			(size 0.519938 1.4986)
			(layers "F.Cu" "F.Mask" "F.Paste")
			(net "M_B_CPU1_SA_DQ<0>")
		)
		(pad "8" smd rect
			(at -2.050034 -57.375044 90)
			(size 0.519938 1.4986)
			(layers "F.Cu" "F.Mask" "F.Paste")
			(net "GND")
		)
		(pad "9" smd rect
			(at -2.050034 -56.524906 90)
			(size 0.519938 1.4986)
			(layers "F.Cu" "F.Mask" "F.Paste")
			(net "M_B_CPU1_SA_DQ<1>")
		)
		(pad "10" smd rect
			(at -2.050034 -55.675022 90)
			(size 0.519938 1.4986)
			(layers "F.Cu" "F.Mask" "F.Paste")
			(net "GND")
		)
		(pad "11" smd rect
			(at -2.050034 -54.824884 90)
			(size 0.519938 1.4986)
			(layers "F.Cu" "F.Mask" "F.Paste")
			(net "M_B_CPU1_SA_DQS_DP<0>")
		)
		(pad "12" smd rect
			(at -2.050034 -53.975 90)
			(size 0.519938 1.4986)
			(layers "F.Cu" "F.Mask" "F.Paste")
			(net "M_B_CPU1_SA_DQS_DN<0>")
		)
		(pad "13" smd rect
			(at -2.050034 -53.125116 90)
			(size 0.519938 1.4986)
			(layers "F.Cu" "F.Mask" "F.Paste")
			(net "GND")
		)
		(pad "14" smd rect
			(at -2.050034 -52.274978 90)
			(size 0.519938 1.4986)
			(layers "F.Cu" "F.Mask" "F.Paste")
			(net "M_B_CPU1_SA_DQ<4>")
		)
		(pad "15" smd rect
			(at -2.050034 -51.425094 90)
			(size 0.519938 1.4986)
			(layers "F.Cu" "F.Mask" "F.Paste")
			(net "GND")
		)
		(pad "16" smd rect
			(at -2.050034 -50.574956 90)
			(size 0.519938 1.4986)
			(layers "F.Cu" "F.Mask" "F.Paste")
			(net "M_B_CPU1_SA_DQ<5>")
		)
		(pad "17" smd rect
			(at -2.050034 -49.725072 90)
			(size 0.519938 1.4986)
			(layers "F.Cu" "F.Mask" "F.Paste")
			(net "GND")
		)
		(pad "18" smd rect
			(at -2.050034 -48.874934 90)
			(size 0.519938 1.4986)
			(layers "F.Cu" "F.Mask" "F.Paste")
			(net "M_B_CPU1_SA_DQ<8>")
		)
		(pad "19" smd rect
			(at -2.050034 -48.02505 90)
			(size 0.519938 1.4986)
			(layers "F.Cu" "F.Mask" "F.Paste")
			(net "GND")
		)
		(pad "20" smd rect
			(at -2.050034 -47.174912 90)
			(size 0.519938 1.4986)
			(layers "F.Cu" "F.Mask" "F.Paste")
			(net "M_B_CPU1_SA_DQ<9>")
		)
		(pad "21" smd rect
			(at -2.050034 -46.325028 90)
			(size 0.519938 1.4986)
			(layers "F.Cu" "F.Mask" "F.Paste")
			(net "GND")
		)
		(pad "22" smd rect
			(at -2.050034 -45.47489 90)
			(size 0.519938 1.4986)
			(layers "F.Cu" "F.Mask" "F.Paste")
			(net "M_B_CPU1_SA_DQS_DP<1>")
		)
		(pad "23" smd rect
			(at -2.050034 -44.625006 90)
			(size 0.519938 1.4986)
			(layers "F.Cu" "F.Mask" "F.Paste")
			(net "M_B_CPU1_SA_DQS_DN<1>")
		)
		(pad "24" smd rect
			(at -2.050034 -43.775122 90)
			(size 0.519938 1.4986)
			(layers "F.Cu" "F.Mask" "F.Paste")
			(net "GND")
		)
		(pad "25" smd rect
			(at -2.050034 -42.924984 90)
			(size 0.519938 1.4986)
			(layers "F.Cu" "F.Mask" "F.Paste")
			(net "M_B_CPU1_SA_DQ<12>")
		)
		(pad "26" smd rect
			(at -2.050034 -42.0751 90)
			(size 0.519938 1.4986)
			(layers "F.Cu" "F.Mask" "F.Paste")
			(net "GND")
		)
		(pad "27" smd rect
			(at -2.050034 -41.224962 90)
			(size 0.519938 1.4986)
			(layers "F.Cu" "F.Mask" "F.Paste")
			(net "M_B_CPU1_SA_DQ<13>")
		)
		(pad "28" smd rect
			(at -2.050034 -40.375078 90)
			(size 0.519938 1.4986)
			(layers "F.Cu" "F.Mask" "F.Paste")
			(net "GND")
		)
		(pad "29" smd rect
			(at -2.050034 -39.52494 90)
			(size 0.519938 1.4986)
			(layers "F.Cu" "F.Mask" "F.Paste")
			(net "M_B_CPU1_SA_DQ<16>")
		)
		(pad "30" smd rect
			(at -2.050034 -38.675056 90)
			(size 0.519938 1.4986)
			(layers "F.Cu" "F.Mask" "F.Paste")
			(net "GND")
		)
		(pad "31" smd rect
			(at -2.050034 -37.824918 90)
			(size 0.519938 1.4986)
			(layers "F.Cu" "F.Mask" "F.Paste")
			(net "M_B_CPU1_SA_DQ<17>")
		)
		(pad "32" smd rect
			(at -2.050034 -36.975034 90)
			(size 0.519938 1.4986)
			(layers "F.Cu" "F.Mask" "F.Paste")
			(net "GND")
		)
		(pad "33" smd rect
			(at -2.050034 -36.124896 90)
			(size 0.519938 1.4986)
			(layers "F.Cu" "F.Mask" "F.Paste")
			(net "M_B_CPU1_SA_DQS_DP<2>")
		)
		(pad "34" smd rect
			(at -2.050034 -35.275012 90)
			(size 0.519938 1.4986)
			(layers "F.Cu" "F.Mask" "F.Paste")
			(net "M_B_CPU1_SA_DQS_DN<2>")
		)
		(pad "35" smd rect
			(at -2.050034 -34.425128 90)
			(size 0.519938 1.4986)
			(layers "F.Cu" "F.Mask" "F.Paste")
			(net "GND")
		)
		(pad "36" smd rect
			(at -2.050034 -33.57499 90)
			(size 0.519938 1.4986)
			(layers "F.Cu" "F.Mask" "F.Paste")
			(net "M_B_CPU1_SA_DQ<20>")
		)
		(pad "37" smd rect
			(at -2.050034 -32.725106 90)
			(size 0.519938 1.4986)
			(layers "F.Cu" "F.Mask" "F.Paste")
			(net "GND")
		)
		(pad "38" smd rect
			(at -2.050034 -31.874968 90)
			(size 0.519938 1.4986)
			(layers "F.Cu" "F.Mask" "F.Paste")
			(net "M_B_CPU1_SA_DQ<21>")
		)
		(pad "39" smd rect
			(at -2.050034 -31.025084 90)
			(size 0.519938 1.4986)
			(layers "F.Cu" "F.Mask" "F.Paste")
			(net "GND")
		)
		(pad "40" smd rect
			(at -2.050034 -30.174946 90)
			(size 0.519938 1.4986)
			(layers "F.Cu" "F.Mask" "F.Paste")
			(net "M_B_CPU1_SA_DQ<24>")
		)
		(pad "41" smd rect
			(at -2.050034 -29.325062 90)
			(size 0.519938 1.4986)
			(layers "F.Cu" "F.Mask" "F.Paste")
			(net "GND")
		)
		(pad "42" smd rect
			(at -2.050034 -28.474924 90)
			(size 0.519938 1.4986)
			(layers "F.Cu" "F.Mask" "F.Paste")
			(net "M_B_CPU1_SA_DQ<25>")
		)
		(pad "43" smd rect
			(at -2.050034 -27.62504 90)
			(size 0.519938 1.4986)
			(layers "F.Cu" "F.Mask" "F.Paste")
			(net "GND")
		)
		(pad "44" smd rect
			(at -2.050034 -26.774902 90)
			(size 0.519938 1.4986)
			(layers "F.Cu" "F.Mask" "F.Paste")
			(net "M_B_CPU1_SA_DQS_DP<3>")
		)
		(pad "45" smd rect
			(at -2.050034 -25.925018 90)
			(size 0.519938 1.4986)
			(layers "F.Cu" "F.Mask" "F.Paste")
			(net "M_B_CPU1_SA_DQS_DN<3>")
		)
		(pad "46" smd rect
			(at -2.050034 -25.07488 90)
			(size 0.519938 1.4986)
			(layers "F.Cu" "F.Mask" "F.Paste")
			(net "GND")
		)
		(pad "47" smd rect
			(at -2.050034 -24.224996 90)
			(size 0.519938 1.4986)
			(layers "F.Cu" "F.Mask" "F.Paste")
			(net "M_B_CPU1_SA_DQ<28>")
		)
		(pad "48" smd rect
			(at -2.050034 -23.375112 90)
			(size 0.519938 1.4986)
			(layers "F.Cu" "F.Mask" "F.Paste")
			(net "GND")
		)
		(pad "49" smd rect
			(at -2.050034 -22.524974 90)
			(size 0.519938 1.4986)
			(layers "F.Cu" "F.Mask" "F.Paste")
			(net "M_B_CPU1_SA_DQ<29>")
		)
		(pad "50" smd rect
			(at -2.050034 -21.67509 90)
			(size 0.519938 1.4986)
			(layers "F.Cu" "F.Mask" "F.Paste")
			(net "GND")
		)
		(pad "51" smd rect
			(at -2.050034 -20.824952 90)
			(size 0.519938 1.4986)
			(layers "F.Cu" "F.Mask" "F.Paste")
			(net "M_B_CPU1_SA_CB<0>")
		)
		(pad "52" smd rect
			(at -2.050034 -19.975068 90)
			(size 0.519938 1.4986)
			(layers "F.Cu" "F.Mask" "F.Paste")
			(net "GND")
		)
		(pad "53" smd rect
			(at -2.050034 -19.12493 90)
			(size 0.519938 1.4986)
			(layers "F.Cu" "F.Mask" "F.Paste")
			(net "M_B_CPU1_SA_CB<1>")
		)
		(pad "54" smd rect
			(at -2.050034 -18.275046 90)
			(size 0.519938 1.4986)
			(layers "F.Cu" "F.Mask" "F.Paste")
			(net "GND")
		)
		(pad "55" smd rect
			(at -2.050034 -17.424908 90)
			(size 0.519938 1.4986)
			(layers "F.Cu" "F.Mask" "F.Paste")
			(net "M_B_CPU1_SA_DQS_DP<4>")
		)
		(pad "56" smd rect
			(at -2.050034 -16.575024 90)
			(size 0.519938 1.4986)
			(layers "F.Cu" "F.Mask" "F.Paste")
			(net "M_B_CPU1_SA_DQS_DN<4>")
		)
		(pad "57" smd rect
			(at -2.050034 -15.724886 90)
			(size 0.519938 1.4986)
			(layers "F.Cu" "F.Mask" "F.Paste")
			(net "GND")
		)
		(pad "58" smd rect
			(at -2.050034 -14.875002 90)
			(size 0.519938 1.4986)
			(layers "F.Cu" "F.Mask" "F.Paste")
			(net "M_B_CPU1_SA_CB<4>")
		)
		(pad "59" smd rect
			(at -2.050034 -14.025118 90)
			(size 0.519938 1.4986)
			(layers "F.Cu" "F.Mask" "F.Paste")
			(net "GND")
		)
		(pad "60" smd rect
			(at -2.050034 -13.17498 90)
			(size 0.519938 1.4986)
			(layers "F.Cu" "F.Mask" "F.Paste")
			(net "M_B_CPU1_SA_CB<5>")
		)
		(pad "61" smd rect
			(at -2.050034 -12.325096 90)
			(size 0.519938 1.4986)
			(layers "F.Cu" "F.Mask" "F.Paste")
			(net "GND")
		)
		(pad "62" smd rect
			(at -2.050034 -11.474958 90)
			(size 0.519938 1.4986)
			(layers "F.Cu" "F.Mask" "F.Paste")
			(net "M_B_CPU1_ALERT_N")
		)
		(pad "63" smd rect
			(at -2.050034 -10.625074 90)
			(size 0.519938 1.4986)
			(layers "F.Cu" "F.Mask" "F.Paste")
			(net "GND")
		)
		(pad "64" smd rect
			(at -2.050034 -9.774936 90)
			(size 0.519938 1.4986)
			(layers "F.Cu" "F.Mask" "F.Paste")
			(net "M_B_CPU1_SA_CS_N<0>")
		)
		(pad "65" smd rect
			(at -2.050034 -8.925052 90)
			(size 0.519938 1.4986)
			(layers "F.Cu" "F.Mask" "F.Paste")
			(net "GND")
		)
		(pad "66" smd rect
			(at -2.050034 -8.074914 90)
			(size 0.519938 1.4986)
			(layers "F.Cu" "F.Mask" "F.Paste")
			(net "M_B_CPU1_SA_CA<0>")
		)
		(pad "67" smd rect
			(at -2.050034 -7.22503 90)
			(size 0.519938 1.4986)
			(layers "F.Cu" "F.Mask" "F.Paste")
			(net "GND")
		)
		(pad "68" smd rect
			(at -2.050034 -6.374892 90)
			(size 0.519938 1.4986)
			(layers "F.Cu" "F.Mask" "F.Paste")
			(net "M_B_CPU1_SA_CA<2>")
		)
		(pad "69" smd rect
			(at -2.050034 -5.525008 90)
			(size 0.519938 1.4986)
			(layers "F.Cu" "F.Mask" "F.Paste")
			(net "GND")
		)
		(pad "70" smd rect
			(at -2.050034 -4.675124 90)
			(size 0.519938 1.4986)
			(layers "F.Cu" "F.Mask" "F.Paste")
			(net "M_B_CPU1_SA_CA<4>")
		)
		(pad "71" smd rect
			(at -2.050034 -3.824986 90)
			(size 0.519938 1.4986)
			(layers "F.Cu" "F.Mask" "F.Paste")
			(net "GND")
		)
		(pad "72" smd rect
			(at -2.050034 -2.975102 90)
			(size 0.519938 1.4986)
			(layers "F.Cu" "F.Mask" "F.Paste")
			(net "M_B_CPU1_SA_CA<6>")
		)
		(pad "73" smd rect
			(at -2.050034 -2.124964 90)
			(size 0.519938 1.4986)
			(layers "F.Cu" "F.Mask" "F.Paste")
			(net "GND")
		)
		(pad "74" smd rect
			(at -2.050034 -1.27508 90)
			(size 0.519938 1.4986)
			(layers "F.Cu" "F.Mask" "F.Paste")
			(net "M_B_CPU1_SA_PAR")
		)
		(pad "75" smd rect
			(at -2.050034 -0.424942 90)
			(size 0.519938 1.4986)
			(layers "F.Cu" "F.Mask" "F.Paste")
			(net "GND")
		)
		(pad "76" smd rect
			(at -2.050034 5.525008 90)
			(size 0.519938 1.4986)
			(layers "F.Cu" "F.Mask" "F.Paste")
			(net "M_B_CPU1_SB_CA<0>")
		)
		(pad "77" smd rect
			(at -2.050034 6.374892 90)
			(size 0.519938 1.4986)
			(layers "F.Cu" "F.Mask" "F.Paste")
			(net "GND")
		)
		(pad "78" smd rect
			(at -2.050034 7.22503 90)
			(size 0.519938 1.4986)
			(layers "F.Cu" "F.Mask" "F.Paste")
			(net "M_B_CPU1_SB_CA<2>")
		)
		(pad "79" smd rect
			(at -2.050034 8.074914 90)
			(size 0.519938 1.4986)
			(layers "F.Cu" "F.Mask" "F.Paste")
			(net "GND")
		)
		(pad "80" smd rect
			(at -2.050034 8.925052 90)
			(size 0.519938 1.4986)
			(layers "F.Cu" "F.Mask" "F.Paste")
			(net "M_B_CPU1_SB_CA<4>")
		)
		(pad "81" smd rect
			(at -2.050034 9.774936 90)
			(size 0.519938 1.4986)
			(layers "F.Cu" "F.Mask" "F.Paste")
			(net "GND")
		)
		(pad "82" smd rect
			(at -2.050034 10.625074 90)
			(size 0.519938 1.4986)
			(layers "F.Cu" "F.Mask" "F.Paste")
			(net "M_B_CPU1_SB_CA<6>")
		)
		(pad "83" smd rect
			(at -2.050034 11.474958 90)
			(size 0.519938 1.4986)
			(layers "F.Cu" "F.Mask" "F.Paste")
			(net "GND")
		)
		(pad "84" smd rect
			(at -2.050034 12.325096 90)
			(size 0.519938 1.4986)
			(layers "F.Cu" "F.Mask" "F.Paste")
			(net "M_B_CPU1_SB_CS_N<0>")
		)
		(pad "85" smd rect
			(at -2.050034 13.17498 90)
			(size 0.519938 1.4986)
			(layers "F.Cu" "F.Mask" "F.Paste")
			(net "GND")
		)
		(pad "86" smd rect
			(at -2.050034 14.025118 90)
			(size 0.519938 1.4986)
			(layers "F.Cu" "F.Mask" "F.Paste")
			(net "M_B_CPU1_SA_RSP<0>")
		)
		(pad "87" smd rect
			(at -2.050034 14.875002 90)
			(size 0.519938 1.4986)
			(layers "F.Cu" "F.Mask" "F.Paste")
			(net "M_B_CPU1_SB_RSP<0>")
		)
		(pad "88" smd rect
			(at -2.050034 15.724886 90)
			(size 0.519938 1.4986)
			(layers "F.Cu" "F.Mask" "F.Paste")
			(net "GND")
		)
		(pad "89" smd rect
			(at -2.050034 16.575024 90)
			(size 0.519938 1.4986)
			(layers "F.Cu" "F.Mask" "F.Paste")
			(net "M_B_CPU1_SB_CB<4>")
		)
		(pad "90" smd rect
			(at -2.050034 17.424908 90)
			(size 0.519938 1.4986)
			(layers "F.Cu" "F.Mask" "F.Paste")
			(net "GND")
		)
		(pad "91" smd rect
			(at -2.050034 18.275046 90)
			(size 0.519938 1.4986)
			(layers "F.Cu" "F.Mask" "F.Paste")
			(net "M_B_CPU1_SB_CB<5>")
		)
		(pad "92" smd rect
			(at -2.050034 19.12493 90)
			(size 0.519938 1.4986)
			(layers "F.Cu" "F.Mask" "F.Paste")
			(net "GND")
		)
		(pad "93" smd rect
			(at -2.050034 19.975068 90)
			(size 0.519938 1.4986)
			(layers "F.Cu" "F.Mask" "F.Paste")
			(net "M_B_CPU1_SB_DQS_DP<9>")
		)
		(pad "94" smd rect
			(at -2.050034 20.824952 90)
			(size 0.519938 1.4986)
			(layers "F.Cu" "F.Mask" "F.Paste")
			(net "M_B_CPU1_SB_DQS_DN<9>")
		)
		(pad "95" smd rect
			(at -2.050034 21.67509 90)
			(size 0.519938 1.4986)
			(layers "F.Cu" "F.Mask" "F.Paste")
			(net "GND")
		)
		(pad "96" smd rect
			(at -2.050034 22.524974 90)
			(size 0.519938 1.4986)
			(layers "F.Cu" "F.Mask" "F.Paste")
			(net "M_B_CPU1_SB_CB<0>")
		)
		(pad "97" smd rect
			(at -2.050034 23.375112 90)
			(size 0.519938 1.4986)
			(layers "F.Cu" "F.Mask" "F.Paste")
			(net "GND")
		)
		(pad "98" smd rect
			(at -2.050034 24.224996 90)
			(size 0.519938 1.4986)
			(layers "F.Cu" "F.Mask" "F.Paste")
			(net "M_B_CPU1_SB_CB<1>")
		)
		(pad "99" smd rect
			(at -2.050034 25.07488 90)
			(size 0.519938 1.4986)
			(layers "F.Cu" "F.Mask" "F.Paste")
			(net "GND")
		)
		(pad "100" smd rect
			(at -2.050034 25.925018 90)
			(size 0.519938 1.4986)
			(layers "F.Cu" "F.Mask" "F.Paste")
			(net "M_B_CPU1_SB_DQ<0>")
		)
		(pad "101" smd rect
			(at -2.050034 26.774902 90)
			(size 0.519938 1.4986)
			(layers "F.Cu" "F.Mask" "F.Paste")
			(net "GND")
		)
		(pad "102" smd rect
			(at -2.050034 27.62504 90)
			(size 0.519938 1.4986)
			(layers "F.Cu" "F.Mask" "F.Paste")
			(net "M_B_CPU1_SB_DQ<1>")
		)
		(pad "103" smd rect
			(at -2.050034 28.474924 90)
			(size 0.519938 1.4986)
			(layers "F.Cu" "F.Mask" "F.Paste")
			(net "GND")
		)
		(pad "104" smd rect
			(at -2.050034 29.325062 90)
			(size 0.519938 1.4986)
			(layers "F.Cu" "F.Mask" "F.Paste")
			(net "M_B_CPU1_SB_DQS_DP<0>")
		)
		(pad "105" smd rect
			(at -2.050034 30.174946 90)
			(size 0.519938 1.4986)
			(layers "F.Cu" "F.Mask" "F.Paste")
			(net "M_B_CPU1_SB_DQS_DN<0>")
		)
		(pad "106" smd rect
			(at -2.050034 31.025084 90)
			(size 0.519938 1.4986)
			(layers "F.Cu" "F.Mask" "F.Paste")
			(net "GND")
		)
		(pad "107" smd rect
			(at -2.050034 31.874968 90)
			(size 0.519938 1.4986)
			(layers "F.Cu" "F.Mask" "F.Paste")
			(net "M_B_CPU1_SB_DQ<4>")
		)
		(pad "108" smd rect
			(at -2.050034 32.725106 90)
			(size 0.519938 1.4986)
			(layers "F.Cu" "F.Mask" "F.Paste")
			(net "GND")
		)
		(pad "109" smd rect
			(at -2.050034 33.57499 90)
			(size 0.519938 1.4986)
			(layers "F.Cu" "F.Mask" "F.Paste")
			(net "M_B_CPU1_SB_DQ<5>")
		)
		(pad "110" smd rect
			(at -2.050034 34.425128 90)
			(size 0.519938 1.4986)
			(layers "F.Cu" "F.Mask" "F.Paste")
			(net "GND")
		)
		(pad "111" smd rect
			(at -2.050034 35.275012 90)
			(size 0.519938 1.4986)
			(layers "F.Cu" "F.Mask" "F.Paste")
			(net "M_B_CPU1_SB_DQ<8>")
		)
		(pad "112" smd rect
			(at -2.050034 36.124896 90)
			(size 0.519938 1.4986)
			(layers "F.Cu" "F.Mask" "F.Paste")
			(net "GND")
		)
		(pad "113" smd rect
			(at -2.050034 36.975034 90)
			(size 0.519938 1.4986)
			(layers "F.Cu" "F.Mask" "F.Paste")
			(net "M_B_CPU1_SB_DQ<9>")
		)
		(pad "114" smd rect
			(at -2.050034 37.824918 90)
			(size 0.519938 1.4986)
			(layers "F.Cu" "F.Mask" "F.Paste")
			(net "GND")
		)
		(pad "115" smd rect
			(at -2.050034 38.675056 90)
			(size 0.519938 1.4986)
			(layers "F.Cu" "F.Mask" "F.Paste")
			(net "M_B_CPU1_SB_DQS_DP<1>")
		)
		(pad "116" smd rect
			(at -2.050034 39.52494 90)
			(size 0.519938 1.4986)
			(layers "F.Cu" "F.Mask" "F.Paste")
			(net "M_B_CPU1_SB_DQS_DN<1>")
		)
		(pad "117" smd rect
			(at -2.050034 40.375078 90)
			(size 0.519938 1.4986)
			(layers "F.Cu" "F.Mask" "F.Paste")
			(net "GND")
		)
		(pad "118" smd rect
			(at -2.050034 41.224962 90)
			(size 0.519938 1.4986)
			(layers "F.Cu" "F.Mask" "F.Paste")
			(net "M_B_CPU1_SB_DQ<12>")
		)
		(pad "119" smd rect
			(at -2.050034 42.0751 90)
			(size 0.519938 1.4986)
			(layers "F.Cu" "F.Mask" "F.Paste")
			(net "GND")
		)
		(pad "120" smd rect
			(at -2.050034 42.924984 90)
			(size 0.519938 1.4986)
			(layers "F.Cu" "F.Mask" "F.Paste")
			(net "M_B_CPU1_SB_DQ<13>")
		)
		(pad "121" smd rect
			(at -2.050034 43.775122 90)
			(size 0.519938 1.4986)
			(layers "F.Cu" "F.Mask" "F.Paste")
			(net "GND")
		)
		(pad "122" smd rect
			(at -2.050034 44.625006 90)
			(size 0.519938 1.4986)
			(layers "F.Cu" "F.Mask" "F.Paste")
			(net "M_B_CPU1_SB_DQ<16>")
		)
		(pad "123" smd rect
			(at -2.050034 45.47489 90)
			(size 0.519938 1.4986)
			(layers "F.Cu" "F.Mask" "F.Paste")
			(net "GND")
		)
		(pad "124" smd rect
			(at -2.050034 46.325028 90)
			(size 0.519938 1.4986)
			(layers "F.Cu" "F.Mask" "F.Paste")
			(net "M_B_CPU1_SB_DQ<17>")
		)
		(pad "125" smd rect
			(at -2.050034 47.174912 90)
			(size 0.519938 1.4986)
			(layers "F.Cu" "F.Mask" "F.Paste")
			(net "GND")
		)
		(pad "126" smd rect
			(at -2.050034 48.02505 90)
			(size 0.519938 1.4986)
			(layers "F.Cu" "F.Mask" "F.Paste")
			(net "M_B_CPU1_SB_DQS_DP<2>")
		)
		(pad "127" smd rect
			(at -2.050034 48.874934 90)
			(size 0.519938 1.4986)
			(layers "F.Cu" "F.Mask" "F.Paste")
			(net "M_B_CPU1_SB_DQS_DN<2>")
		)
		(pad "128" smd rect
			(at -2.050034 49.725072 90)
			(size 0.519938 1.4986)
			(layers "F.Cu" "F.Mask" "F.Paste")
			(net "GND")
		)
		(pad "129" smd rect
			(at -2.050034 50.574956 90)
			(size 0.519938 1.4986)
			(layers "F.Cu" "F.Mask" "F.Paste")
			(net "M_B_CPU1_SB_DQ<20>")
		)
		(pad "130" smd rect
			(at -2.050034 51.425094 90)
			(size 0.519938 1.4986)
			(layers "F.Cu" "F.Mask" "F.Paste")
			(net "GND")
		)
		(pad "131" smd rect
			(at -2.050034 52.274978 90)
			(size 0.519938 1.4986)
			(layers "F.Cu" "F.Mask" "F.Paste")
			(net "M_B_CPU1_SB_DQ<21>")
		)
		(pad "132" smd rect
			(at -2.050034 53.125116 90)
			(size 0.519938 1.4986)
			(layers "F.Cu" "F.Mask" "F.Paste")
			(net "GND")
		)
		(pad "133" smd rect
			(at -2.050034 53.975 90)
			(size 0.519938 1.4986)
			(layers "F.Cu" "F.Mask" "F.Paste")
			(net "M_B_CPU1_SB_DQ<24>")
		)
		(pad "134" smd rect
			(at -2.050034 54.824884 90)
			(size 0.519938 1.4986)
			(layers "F.Cu" "F.Mask" "F.Paste")
			(net "GND")
		)
		(pad "135" smd rect
			(at -2.050034 55.675022 90)
			(size 0.519938 1.4986)
			(layers "F.Cu" "F.Mask" "F.Paste")
			(net "M_B_CPU1_SB_DQ<25>")
		)
		(pad "136" smd rect
			(at -2.050034 56.524906 90)
			(size 0.519938 1.4986)
			(layers "F.Cu" "F.Mask" "F.Paste")
			(net "GND")
		)
		(pad "137" smd rect
			(at -2.050034 57.375044 90)
			(size 0.519938 1.4986)
			(layers "F.Cu" "F.Mask" "F.Paste")
			(net "M_B_CPU1_SB_DQS_DP<3>")
		)
		(pad "138" smd rect
			(at -2.050034 58.224928 90)
			(size 0.519938 1.4986)
			(layers "F.Cu" "F.Mask" "F.Paste")
			(net "M_B_CPU1_SB_DQS_DN<3>")
		)
		(pad "139" smd rect
			(at -2.050034 59.075066 90)
			(size 0.519938 1.4986)
			(layers "F.Cu" "F.Mask" "F.Paste")
			(net "GND")
		)
		(pad "140" smd rect
			(at -2.050034 59.92495 90)
			(size 0.519938 1.4986)
			(layers "F.Cu" "F.Mask" "F.Paste")
			(net "M_B_CPU1_SB_DQ<28>")
		)
		(pad "141" smd rect
			(at -2.050034 60.775088 90)
			(size 0.519938 1.4986)
			(layers "F.Cu" "F.Mask" "F.Paste")
			(net "GND")
		)
		(pad "142" smd rect
			(at -2.050034 61.624972 90)
			(size 0.519938 1.4986)
			(layers "F.Cu" "F.Mask" "F.Paste")
			(net "M_B_CPU1_SB_DQ<29>")
		)
		(pad "143" smd rect
			(at -2.050034 62.47511 90)
			(size 0.519938 1.4986)
			(layers "F.Cu" "F.Mask" "F.Paste")
			(net "GND")
		)
		(pad "144" smd rect
			(at -2.050034 63.324994 90)
			(size 0.519938 1.4986)
			(layers "F.Cu" "F.Mask" "F.Paste")
			(net "Net_2271")
		)
		(pad "145" smd rect
			(at 2.050034 -63.324994 90)
			(size 0.519938 1.4986)
			(layers "F.Cu" "F.Mask" "F.Paste")
			(net "P12V_MEM_CPU1")
		)
		(pad "146" smd rect
			(at 2.050034 -62.47511 90)
			(size 0.519938 1.4986)
			(layers "F.Cu" "F.Mask" "F.Paste")
			(net "P12V_MEM_CPU1")
		)
		(pad "147" smd rect
			(at 2.050034 -61.624972 90)
			(size 0.519938 1.4986)
			(layers "F.Cu" "F.Mask" "F.Paste")
			(net "PWRGD_CHB_CPU1_DIMM")
		)
		(pad "148" smd rect
			(at 2.050034 -60.775088 90)
			(size 0.519938 1.4986)
			(layers "F.Cu" "F.Mask" "F.Paste")
			(net "PD_CHB_CPU1_DIMM_SAA")
		)
		(pad "149" smd rect
			(at 2.050034 -59.92495 90)
			(size 0.519938 1.4986)
			(layers "F.Cu" "F.Mask" "F.Paste")
			(net "Net_2272")
		)
		(pad "150" smd rect
			(at 2.050034 -59.075066 90)
			(size 0.519938 1.4986)
			(layers "F.Cu" "F.Mask" "F.Paste")
			(net "Net_2273")
		)
		(pad "151" smd rect
			(at 2.050034 -58.224928 90)
			(size 0.519938 1.4986)
			(layers "F.Cu" "F.Mask" "F.Paste")
			(net "GND")
		)
		(pad "152" smd rect
			(at 2.050034 -57.375044 90)
			(size 0.519938 1.4986)
			(layers "F.Cu" "F.Mask" "F.Paste")
			(net "M_B_CPU1_SA_DQ<2>")
		)
		(pad "153" smd rect
			(at 2.050034 -56.524906 90)
			(size 0.519938 1.4986)
			(layers "F.Cu" "F.Mask" "F.Paste")
			(net "GND")
		)
		(pad "154" smd rect
			(at 2.050034 -55.675022 90)
			(size 0.519938 1.4986)
			(layers "F.Cu" "F.Mask" "F.Paste")
			(net "M_B_CPU1_SA_DQ<3>")
		)
		(pad "155" smd rect
			(at 2.050034 -54.824884 90)
			(size 0.519938 1.4986)
			(layers "F.Cu" "F.Mask" "F.Paste")
			(net "GND")
		)
		(pad "156" smd rect
			(at 2.050034 -53.975 90)
			(size 0.519938 1.4986)
			(layers "F.Cu" "F.Mask" "F.Paste")
			(net "M_B_CPU1_SA_DQS_DN<5>")
		)
		(pad "157" smd rect
			(at 2.050034 -53.125116 90)
			(size 0.519938 1.4986)
			(layers "F.Cu" "F.Mask" "F.Paste")
			(net "M_B_CPU1_SA_DQS_DP<5>")
		)
		(pad "158" smd rect
			(at 2.050034 -52.274978 90)
			(size 0.519938 1.4986)
			(layers "F.Cu" "F.Mask" "F.Paste")
			(net "GND")
		)
		(pad "159" smd rect
			(at 2.050034 -51.425094 90)
			(size 0.519938 1.4986)
			(layers "F.Cu" "F.Mask" "F.Paste")
			(net "M_B_CPU1_SA_DQ<6>")
		)
		(pad "160" smd rect
			(at 2.050034 -50.574956 90)
			(size 0.519938 1.4986)
			(layers "F.Cu" "F.Mask" "F.Paste")
			(net "GND")
		)
		(pad "161" smd rect
			(at 2.050034 -49.725072 90)
			(size 0.519938 1.4986)
			(layers "F.Cu" "F.Mask" "F.Paste")
			(net "M_B_CPU1_SA_DQ<7>")
		)
		(pad "162" smd rect
			(at 2.050034 -48.874934 90)
			(size 0.519938 1.4986)
			(layers "F.Cu" "F.Mask" "F.Paste")
			(net "GND")
		)
		(pad "163" smd rect
			(at 2.050034 -48.02505 90)
			(size 0.519938 1.4986)
			(layers "F.Cu" "F.Mask" "F.Paste")
			(net "M_B_CPU1_SA_DQ<10>")
		)
		(pad "164" smd rect
			(at 2.050034 -47.174912 90)
			(size 0.519938 1.4986)
			(layers "F.Cu" "F.Mask" "F.Paste")
			(net "GND")
		)
		(pad "165" smd rect
			(at 2.050034 -46.325028 90)
			(size 0.519938 1.4986)
			(layers "F.Cu" "F.Mask" "F.Paste")
			(net "M_B_CPU1_SA_DQ<11>")
		)
		(pad "166" smd rect
			(at 2.050034 -45.47489 90)
			(size 0.519938 1.4986)
			(layers "F.Cu" "F.Mask" "F.Paste")
			(net "GND")
		)
		(pad "167" smd rect
			(at 2.050034 -44.625006 90)
			(size 0.519938 1.4986)
			(layers "F.Cu" "F.Mask" "F.Paste")
			(net "M_B_CPU1_SA_DQS_DN<6>")
		)
		(pad "168" smd rect
			(at 2.050034 -43.775122 90)
			(size 0.519938 1.4986)
			(layers "F.Cu" "F.Mask" "F.Paste")
			(net "M_B_CPU1_SA_DQS_DP<6>")
		)
		(pad "169" smd rect
			(at 2.050034 -42.924984 90)
			(size 0.519938 1.4986)
			(layers "F.Cu" "F.Mask" "F.Paste")
			(net "GND")
		)
		(pad "170" smd rect
			(at 2.050034 -42.0751 90)
			(size 0.519938 1.4986)
			(layers "F.Cu" "F.Mask" "F.Paste")
			(net "M_B_CPU1_SA_DQ<14>")
		)
		(pad "171" smd rect
			(at 2.050034 -41.224962 90)
			(size 0.519938 1.4986)
			(layers "F.Cu" "F.Mask" "F.Paste")
			(net "GND")
		)
		(pad "172" smd rect
			(at 2.050034 -40.375078 90)
			(size 0.519938 1.4986)
			(layers "F.Cu" "F.Mask" "F.Paste")
			(net "M_B_CPU1_SA_DQ<15>")
		)
		(pad "173" smd rect
			(at 2.050034 -39.52494 90)
			(size 0.519938 1.4986)
			(layers "F.Cu" "F.Mask" "F.Paste")
			(net "GND")
		)
		(pad "174" smd rect
			(at 2.050034 -38.675056 90)
			(size 0.519938 1.4986)
			(layers "F.Cu" "F.Mask" "F.Paste")
			(net "M_B_CPU1_SA_DQ<18>")
		)
		(pad "175" smd rect
			(at 2.050034 -37.824918 90)
			(size 0.519938 1.4986)
			(layers "F.Cu" "F.Mask" "F.Paste")
			(net "GND")
		)
		(pad "176" smd rect
			(at 2.050034 -36.975034 90)
			(size 0.519938 1.4986)
			(layers "F.Cu" "F.Mask" "F.Paste")
			(net "M_B_CPU1_SA_DQ<19>")
		)
		(pad "177" smd rect
			(at 2.050034 -36.124896 90)
			(size 0.519938 1.4986)
			(layers "F.Cu" "F.Mask" "F.Paste")
			(net "GND")
		)
		(pad "178" smd rect
			(at 2.050034 -35.275012 90)
			(size 0.519938 1.4986)
			(layers "F.Cu" "F.Mask" "F.Paste")
			(net "M_B_CPU1_SA_DQS_DN<7>")
		)
		(pad "179" smd rect
			(at 2.050034 -34.425128 90)
			(size 0.519938 1.4986)
			(layers "F.Cu" "F.Mask" "F.Paste")
			(net "M_B_CPU1_SA_DQS_DP<7>")
		)
		(pad "180" smd rect
			(at 2.050034 -33.57499 90)
			(size 0.519938 1.4986)
			(layers "F.Cu" "F.Mask" "F.Paste")
			(net "GND")
		)
		(pad "181" smd rect
			(at 2.050034 -32.725106 90)
			(size 0.519938 1.4986)
			(layers "F.Cu" "F.Mask" "F.Paste")
			(net "M_B_CPU1_SA_DQ<22>")
		)
		(pad "182" smd rect
			(at 2.050034 -31.874968 90)
			(size 0.519938 1.4986)
			(layers "F.Cu" "F.Mask" "F.Paste")
			(net "GND")
		)
		(pad "183" smd rect
			(at 2.050034 -31.025084 90)
			(size 0.519938 1.4986)
			(layers "F.Cu" "F.Mask" "F.Paste")
			(net "M_B_CPU1_SA_DQ<23>")
		)
		(pad "184" smd rect
			(at 2.050034 -30.174946 90)
			(size 0.519938 1.4986)
			(layers "F.Cu" "F.Mask" "F.Paste")
			(net "GND")
		)
		(pad "185" smd rect
			(at 2.050034 -29.325062 90)
			(size 0.519938 1.4986)
			(layers "F.Cu" "F.Mask" "F.Paste")
			(net "M_B_CPU1_SA_DQ<26>")
		)
		(pad "186" smd rect
			(at 2.050034 -28.474924 90)
			(size 0.519938 1.4986)
			(layers "F.Cu" "F.Mask" "F.Paste")
			(net "GND")
		)
		(pad "187" smd rect
			(at 2.050034 -27.62504 90)
			(size 0.519938 1.4986)
			(layers "F.Cu" "F.Mask" "F.Paste")
			(net "M_B_CPU1_SA_DQ<27>")
		)
		(pad "188" smd rect
			(at 2.050034 -26.774902 90)
			(size 0.519938 1.4986)
			(layers "F.Cu" "F.Mask" "F.Paste")
			(net "GND")
		)
		(pad "189" smd rect
			(at 2.050034 -25.925018 90)
			(size 0.519938 1.4986)
			(layers "F.Cu" "F.Mask" "F.Paste")
			(net "M_B_CPU1_SA_DQS_DN<8>")
		)
		(pad "190" smd rect
			(at 2.050034 -25.07488 90)
			(size 0.519938 1.4986)
			(layers "F.Cu" "F.Mask" "F.Paste")
			(net "M_B_CPU1_SA_DQS_DP<8>")
		)
		(pad "191" smd rect
			(at 2.050034 -24.224996 90)
			(size 0.519938 1.4986)
			(layers "F.Cu" "F.Mask" "F.Paste")
			(net "GND")
		)
		(pad "192" smd rect
			(at 2.050034 -23.375112 90)
			(size 0.519938 1.4986)
			(layers "F.Cu" "F.Mask" "F.Paste")
			(net "M_B_CPU1_SA_DQ<30>")
		)
		(pad "193" smd rect
			(at 2.050034 -22.524974 90)
			(size 0.519938 1.4986)
			(layers "F.Cu" "F.Mask" "F.Paste")
			(net "GND")
		)
		(pad "194" smd rect
			(at 2.050034 -21.67509 90)
			(size 0.519938 1.4986)
			(layers "F.Cu" "F.Mask" "F.Paste")
			(net "M_B_CPU1_SA_DQ<31>")
		)
		(pad "195" smd rect
			(at 2.050034 -20.824952 90)
			(size 0.519938 1.4986)
			(layers "F.Cu" "F.Mask" "F.Paste")
			(net "GND")
		)
		(pad "196" smd rect
			(at 2.050034 -19.975068 90)
			(size 0.519938 1.4986)
			(layers "F.Cu" "F.Mask" "F.Paste")
			(net "M_B_CPU1_SA_CB<2>")
		)
		(pad "197" smd rect
			(at 2.050034 -19.12493 90)
			(size 0.519938 1.4986)
			(layers "F.Cu" "F.Mask" "F.Paste")
			(net "GND")
		)
		(pad "198" smd rect
			(at 2.050034 -18.275046 90)
			(size 0.519938 1.4986)
			(layers "F.Cu" "F.Mask" "F.Paste")
			(net "M_B_CPU1_SA_CB<3>")
		)
		(pad "199" smd rect
			(at 2.050034 -17.424908 90)
			(size 0.519938 1.4986)
			(layers "F.Cu" "F.Mask" "F.Paste")
			(net "GND")
		)
		(pad "200" smd rect
			(at 2.050034 -16.575024 90)
			(size 0.519938 1.4986)
			(layers "F.Cu" "F.Mask" "F.Paste")
			(net "M_B_CPU1_SA_DQS_DN<9>")
		)
		(pad "201" smd rect
			(at 2.050034 -15.724886 90)
			(size 0.519938 1.4986)
			(layers "F.Cu" "F.Mask" "F.Paste")
			(net "M_B_CPU1_SA_DQS_DP<9>")
		)
		(pad "202" smd rect
			(at 2.050034 -14.875002 90)
			(size 0.519938 1.4986)
			(layers "F.Cu" "F.Mask" "F.Paste")
			(net "GND")
		)
		(pad "203" smd rect
			(at 2.050034 -14.025118 90)
			(size 0.519938 1.4986)
			(layers "F.Cu" "F.Mask" "F.Paste")
			(net "M_B_CPU1_SA_CB<6>")
		)
		(pad "204" smd rect
			(at 2.050034 -13.17498 90)
			(size 0.519938 1.4986)
			(layers "F.Cu" "F.Mask" "F.Paste")
			(net "GND")
		)
		(pad "205" smd rect
			(at 2.050034 -12.325096 90)
			(size 0.519938 1.4986)
			(layers "F.Cu" "F.Mask" "F.Paste")
			(net "M_B_CPU1_SA_CB<7>")
		)
		(pad "206" smd rect
			(at 2.050034 -11.474958 90)
			(size 0.519938 1.4986)
			(layers "F.Cu" "F.Mask" "F.Paste")
			(net "GND")
		)
		(pad "207" smd rect
			(at 2.050034 -10.625074 90)
			(size 0.519938 1.4986)
			(layers "F.Cu" "F.Mask" "F.Paste")
			(net "M_B_CPU1_RESET_N")
		)
		(pad "208" smd rect
			(at 2.050034 -9.774936 90)
			(size 0.519938 1.4986)
			(layers "F.Cu" "F.Mask" "F.Paste")
			(net "GND")
		)
		(pad "209" smd rect
			(at 2.050034 -8.925052 90)
			(size 0.519938 1.4986)
			(layers "F.Cu" "F.Mask" "F.Paste")
			(net "M_B_CPU1_SA_CS_N<1>")
		)
		(pad "210" smd rect
			(at 2.050034 -8.074914 90)
			(size 0.519938 1.4986)
			(layers "F.Cu" "F.Mask" "F.Paste")
			(net "GND")
		)
		(pad "211" smd rect
			(at 2.050034 -7.22503 90)
			(size 0.519938 1.4986)
			(layers "F.Cu" "F.Mask" "F.Paste")
			(net "M_B_CPU1_SA_CA<1>")
		)
		(pad "212" smd rect
			(at 2.050034 -6.374892 90)
			(size 0.519938 1.4986)
			(layers "F.Cu" "F.Mask" "F.Paste")
			(net "GND")
		)
		(pad "213" smd rect
			(at 2.050034 -5.525008 90)
			(size 0.519938 1.4986)
			(layers "F.Cu" "F.Mask" "F.Paste")
			(net "M_B_CPU1_SA_CA<3>")
		)
		(pad "214" smd rect
			(at 2.050034 -4.675124 90)
			(size 0.519938 1.4986)
			(layers "F.Cu" "F.Mask" "F.Paste")
			(net "GND")
		)
		(pad "215" smd rect
			(at 2.050034 -3.824986 90)
			(size 0.519938 1.4986)
			(layers "F.Cu" "F.Mask" "F.Paste")
			(net "M_B_CPU1_SA_CA<5>")
		)
		(pad "216" smd rect
			(at 2.050034 -2.975102 90)
			(size 0.519938 1.4986)
			(layers "F.Cu" "F.Mask" "F.Paste")
			(net "GND")
		)
		(pad "217" smd rect
			(at 2.050034 -2.124964 90)
			(size 0.519938 1.4986)
			(layers "F.Cu" "F.Mask" "F.Paste")
			(net "M_B_CPU1_CLK_DP<0>")
		)
		(pad "218" smd rect
			(at 2.050034 -1.27508 90)
			(size 0.519938 1.4986)
			(layers "F.Cu" "F.Mask" "F.Paste")
			(net "M_B_CPU1_CLK_DN<0>")
		)
		(pad "219" smd rect
			(at 2.050034 -0.424942 90)
			(size 0.519938 1.4986)
			(layers "F.Cu" "F.Mask" "F.Paste")
			(net "GND")
		)
		(pad "220" smd rect
			(at 2.050034 5.525008 90)
			(size 0.519938 1.4986)
			(layers "F.Cu" "F.Mask" "F.Paste")
			(net "Net_2274")
		)
		(pad "221" smd rect
			(at 2.050034 6.374892 90)
			(size 0.519938 1.4986)
			(layers "F.Cu" "F.Mask" "F.Paste")
			(net "M_B_CPU1_SB_CA<1>")
		)
		(pad "222" smd rect
			(at 2.050034 7.22503 90)
			(size 0.519938 1.4986)
			(layers "F.Cu" "F.Mask" "F.Paste")
			(net "GND")
		)
		(pad "223" smd rect
			(at 2.050034 8.074914 90)
			(size 0.519938 1.4986)
			(layers "F.Cu" "F.Mask" "F.Paste")
			(net "M_B_CPU1_SB_CA<3>")
		)
		(pad "224" smd rect
			(at 2.050034 8.925052 90)
			(size 0.519938 1.4986)
			(layers "F.Cu" "F.Mask" "F.Paste")
			(net "GND")
		)
		(pad "225" smd rect
			(at 2.050034 9.774936 90)
			(size 0.519938 1.4986)
			(layers "F.Cu" "F.Mask" "F.Paste")
			(net "M_B_CPU1_SB_CA<5>")
		)
		(pad "226" smd rect
			(at 2.050034 10.625074 90)
			(size 0.519938 1.4986)
			(layers "F.Cu" "F.Mask" "F.Paste")
			(net "GND")
		)
		(pad "227" smd rect
			(at 2.050034 11.474958 90)
			(size 0.519938 1.4986)
			(layers "F.Cu" "F.Mask" "F.Paste")
			(net "M_B_CPU1_SB_PAR")
		)
		(pad "228" smd rect
			(at 2.050034 12.325096 90)
			(size 0.519938 1.4986)
			(layers "F.Cu" "F.Mask" "F.Paste")
			(net "GND")
		)
		(pad "229" smd rect
			(at 2.050034 13.17498 90)
			(size 0.519938 1.4986)
			(layers "F.Cu" "F.Mask" "F.Paste")
			(net "M_B_CPU1_SB_CS_N<1>")
		)
		(pad "230" smd rect
			(at 2.050034 14.025118 90)
			(size 0.519938 1.4986)
			(layers "F.Cu" "F.Mask" "F.Paste")
			(net "GND")
		)
		(pad "231" smd rect
			(at 2.050034 14.875002 90)
			(size 0.519938 1.4986)
			(layers "F.Cu" "F.Mask" "F.Paste")
			(net "Net_2275")
		)
		(pad "232" smd rect
			(at 2.050034 15.724886 90)
			(size 0.519938 1.4986)
			(layers "F.Cu" "F.Mask" "F.Paste")
			(net "Net_2276")
		)
		(pad "233" smd rect
			(at 2.050034 16.575024 90)
			(size 0.519938 1.4986)
			(layers "F.Cu" "F.Mask" "F.Paste")
			(net "GND")
		)
		(pad "234" smd rect
			(at 2.050034 17.424908 90)
			(size 0.519938 1.4986)
			(layers "F.Cu" "F.Mask" "F.Paste")
			(net "M_B_CPU1_SB_CB<6>")
		)
		(pad "235" smd rect
			(at 2.050034 18.275046 90)
			(size 0.519938 1.4986)
			(layers "F.Cu" "F.Mask" "F.Paste")
			(net "GND")
		)
		(pad "236" smd rect
			(at 2.050034 19.12493 90)
			(size 0.519938 1.4986)
			(layers "F.Cu" "F.Mask" "F.Paste")
			(net "M_B_CPU1_SB_CB<7>")
		)
		(pad "237" smd rect
			(at 2.050034 19.975068 90)
			(size 0.519938 1.4986)
			(layers "F.Cu" "F.Mask" "F.Paste")
			(net "GND")
		)
		(pad "238" smd rect
			(at 2.050034 20.824952 90)
			(size 0.519938 1.4986)
			(layers "F.Cu" "F.Mask" "F.Paste")
			(net "M_B_CPU1_SB_DQS_DN<4>")
		)
		(pad "239" smd rect
			(at 2.050034 21.67509 90)
			(size 0.519938 1.4986)
			(layers "F.Cu" "F.Mask" "F.Paste")
			(net "M_B_CPU1_SB_DQS_DP<4>")
		)
		(pad "240" smd rect
			(at 2.050034 22.524974 90)
			(size 0.519938 1.4986)
			(layers "F.Cu" "F.Mask" "F.Paste")
			(net "GND")
		)
		(pad "241" smd rect
			(at 2.050034 23.375112 90)
			(size 0.519938 1.4986)
			(layers "F.Cu" "F.Mask" "F.Paste")
			(net "M_B_CPU1_SB_CB<2>")
		)
		(pad "242" smd rect
			(at 2.050034 24.224996 90)
			(size 0.519938 1.4986)
			(layers "F.Cu" "F.Mask" "F.Paste")
			(net "GND")
		)
		(pad "243" smd rect
			(at 2.050034 25.07488 90)
			(size 0.519938 1.4986)
			(layers "F.Cu" "F.Mask" "F.Paste")
			(net "M_B_CPU1_SB_CB<3>")
		)
		(pad "244" smd rect
			(at 2.050034 25.925018 90)
			(size 0.519938 1.4986)
			(layers "F.Cu" "F.Mask" "F.Paste")
			(net "GND")
		)
		(pad "245" smd rect
			(at 2.050034 26.774902 90)
			(size 0.519938 1.4986)
			(layers "F.Cu" "F.Mask" "F.Paste")
			(net "M_B_CPU1_SB_DQ<2>")
		)
		(pad "246" smd rect
			(at 2.050034 27.62504 90)
			(size 0.519938 1.4986)
			(layers "F.Cu" "F.Mask" "F.Paste")
			(net "GND")
		)
		(pad "247" smd rect
			(at 2.050034 28.474924 90)
			(size 0.519938 1.4986)
			(layers "F.Cu" "F.Mask" "F.Paste")
			(net "M_B_CPU1_SB_DQ<3>")
		)
		(pad "248" smd rect
			(at 2.050034 29.325062 90)
			(size 0.519938 1.4986)
			(layers "F.Cu" "F.Mask" "F.Paste")
			(net "GND")
		)
		(pad "249" smd rect
			(at 2.050034 30.174946 90)
			(size 0.519938 1.4986)
			(layers "F.Cu" "F.Mask" "F.Paste")
			(net "M_B_CPU1_SB_DQS_DN<5>")
		)
		(pad "250" smd rect
			(at 2.050034 31.025084 90)
			(size 0.519938 1.4986)
			(layers "F.Cu" "F.Mask" "F.Paste")
			(net "M_B_CPU1_SB_DQS_DP<5>")
		)
		(pad "251" smd rect
			(at 2.050034 31.874968 90)
			(size 0.519938 1.4986)
			(layers "F.Cu" "F.Mask" "F.Paste")
			(net "GND")
		)
		(pad "252" smd rect
			(at 2.050034 32.725106 90)
			(size 0.519938 1.4986)
			(layers "F.Cu" "F.Mask" "F.Paste")
			(net "M_B_CPU1_SB_DQ<6>")
		)
		(pad "253" smd rect
			(at 2.050034 33.57499 90)
			(size 0.519938 1.4986)
			(layers "F.Cu" "F.Mask" "F.Paste")
			(net "GND")
		)
		(pad "254" smd rect
			(at 2.050034 34.425128 90)
			(size 0.519938 1.4986)
			(layers "F.Cu" "F.Mask" "F.Paste")
			(net "M_B_CPU1_SB_DQ<7>")
		)
		(pad "255" smd rect
			(at 2.050034 35.275012 90)
			(size 0.519938 1.4986)
			(layers "F.Cu" "F.Mask" "F.Paste")
			(net "GND")
		)
		(pad "256" smd rect
			(at 2.050034 36.124896 90)
			(size 0.519938 1.4986)
			(layers "F.Cu" "F.Mask" "F.Paste")
			(net "M_B_CPU1_SB_DQ<10>")
		)
		(pad "257" smd rect
			(at 2.050034 36.975034 90)
			(size 0.519938 1.4986)
			(layers "F.Cu" "F.Mask" "F.Paste")
			(net "GND")
		)
		(pad "258" smd rect
			(at 2.050034 37.824918 90)
			(size 0.519938 1.4986)
			(layers "F.Cu" "F.Mask" "F.Paste")
			(net "M_B_CPU1_SB_DQ<11>")
		)
		(pad "259" smd rect
			(at 2.050034 38.675056 90)
			(size 0.519938 1.4986)
			(layers "F.Cu" "F.Mask" "F.Paste")
			(net "GND")
		)
		(pad "260" smd rect
			(at 2.050034 39.52494 90)
			(size 0.519938 1.4986)
			(layers "F.Cu" "F.Mask" "F.Paste")
			(net "M_B_CPU1_SB_DQS_DN<6>")
		)
		(pad "261" smd rect
			(at 2.050034 40.375078 90)
			(size 0.519938 1.4986)
			(layers "F.Cu" "F.Mask" "F.Paste")
			(net "M_B_CPU1_SB_DQS_DP<6>")
		)
		(pad "262" smd rect
			(at 2.050034 41.224962 90)
			(size 0.519938 1.4986)
			(layers "F.Cu" "F.Mask" "F.Paste")
			(net "GND")
		)
		(pad "263" smd rect
			(at 2.050034 42.0751 90)
			(size 0.519938 1.4986)
			(layers "F.Cu" "F.Mask" "F.Paste")
			(net "M_B_CPU1_SB_DQ<14>")
		)
		(pad "264" smd rect
			(at 2.050034 42.924984 90)
			(size 0.519938 1.4986)
			(layers "F.Cu" "F.Mask" "F.Paste")
			(net "GND")
		)
		(pad "265" smd rect
			(at 2.050034 43.775122 90)
			(size 0.519938 1.4986)
			(layers "F.Cu" "F.Mask" "F.Paste")
			(net "M_B_CPU1_SB_DQ<15>")
		)
		(pad "266" smd rect
			(at 2.050034 44.625006 90)
			(size 0.519938 1.4986)
			(layers "F.Cu" "F.Mask" "F.Paste")
			(net "GND")
		)
		(pad "267" smd rect
			(at 2.050034 45.47489 90)
			(size 0.519938 1.4986)
			(layers "F.Cu" "F.Mask" "F.Paste")
			(net "M_B_CPU1_SB_DQ<18>")
		)
		(pad "268" smd rect
			(at 2.050034 46.325028 90)
			(size 0.519938 1.4986)
			(layers "F.Cu" "F.Mask" "F.Paste")
			(net "GND")
		)
		(pad "269" smd rect
			(at 2.050034 47.174912 90)
			(size 0.519938 1.4986)
			(layers "F.Cu" "F.Mask" "F.Paste")
			(net "M_B_CPU1_SB_DQ<19>")
		)
		(pad "270" smd rect
			(at 2.050034 48.02505 90)
			(size 0.519938 1.4986)
			(layers "F.Cu" "F.Mask" "F.Paste")
			(net "GND")
		)
		(pad "271" smd rect
			(at 2.050034 48.874934 90)
			(size 0.519938 1.4986)
			(layers "F.Cu" "F.Mask" "F.Paste")
			(net "M_B_CPU1_SB_DQS_DN<7>")
		)
		(pad "272" smd rect
			(at 2.050034 49.725072 90)
			(size 0.519938 1.4986)
			(layers "F.Cu" "F.Mask" "F.Paste")
			(net "M_B_CPU1_SB_DQS_DP<7>")
		)
		(pad "273" smd rect
			(at 2.050034 50.574956 90)
			(size 0.519938 1.4986)
			(layers "F.Cu" "F.Mask" "F.Paste")
			(net "GND")
		)
		(pad "274" smd rect
			(at 2.050034 51.425094 90)
			(size 0.519938 1.4986)
			(layers "F.Cu" "F.Mask" "F.Paste")
			(net "M_B_CPU1_SB_DQ<22>")
		)
		(pad "275" smd rect
			(at 2.050034 52.274978 90)
			(size 0.519938 1.4986)
			(layers "F.Cu" "F.Mask" "F.Paste")
			(net "GND")
		)
		(pad "276" smd rect
			(at 2.050034 53.125116 90)
			(size 0.519938 1.4986)
			(layers "F.Cu" "F.Mask" "F.Paste")
			(net "M_B_CPU1_SB_DQ<23>")
		)
		(pad "277" smd rect
			(at 2.050034 53.975 90)
			(size 0.519938 1.4986)
			(layers "F.Cu" "F.Mask" "F.Paste")
			(net "GND")
		)
		(pad "278" smd rect
			(at 2.050034 54.824884 90)
			(size 0.519938 1.4986)
			(layers "F.Cu" "F.Mask" "F.Paste")
			(net "M_B_CPU1_SB_DQ<26>")
		)
		(pad "279" smd rect
			(at 2.050034 55.675022 90)
			(size 0.519938 1.4986)
			(layers "F.Cu" "F.Mask" "F.Paste")
			(net "GND")
		)
		(pad "280" smd rect
			(at 2.050034 56.524906 90)
			(size 0.519938 1.4986)
			(layers "F.Cu" "F.Mask" "F.Paste")
			(net "M_B_CPU1_SB_DQ<27>")
		)
		(pad "281" smd rect
			(at 2.050034 57.375044 90)
			(size 0.519938 1.4986)
			(layers "F.Cu" "F.Mask" "F.Paste")
			(net "GND")
		)
		(pad "282" smd rect
			(at 2.050034 58.224928 90)
			(size 0.519938 1.4986)
			(layers "F.Cu" "F.Mask" "F.Paste")
			(net "M_B_CPU1_SB_DQS_DN<8>")
		)
		(pad "283" smd rect
			(at 2.050034 59.075066 90)
			(size 0.519938 1.4986)
			(layers "F.Cu" "F.Mask" "F.Paste")
			(net "M_B_CPU1_SB_DQS_DP<8>")
		)
		(pad "284" smd rect
			(at 2.050034 59.92495 90)
			(size 0.519938 1.4986)
			(layers "F.Cu" "F.Mask" "F.Paste")
			(net "GND")
		)
		(pad "285" smd rect
			(at 2.050034 60.775088 90)
			(size 0.519938 1.4986)
			(layers "F.Cu" "F.Mask" "F.Paste")
			(net "M_B_CPU1_SB_DQ<30>")
		)
		(pad "286" smd rect
			(at 2.050034 61.624972 90)
			(size 0.519938 1.4986)
			(layers "F.Cu" "F.Mask" "F.Paste")
			(net "GND")
		)
		(pad "287" smd rect
			(at 2.050034 62.47511 90)
			(size 0.519938 1.4986)
			(layers "F.Cu" "F.Mask" "F.Paste")
			(net "M_B_CPU1_SB_DQ<31>")
		)
		(pad "288" smd rect
			(at 2.050034 63.324994 90)
			(size 0.519938 1.4986)
			(layers "F.Cu" "F.Mask" "F.Paste")
			(net "GND")
		)
		(pad "G1" thru_hole oval
			(at 0 -68.97497 90)
			(size 1.7272 3.4798)
			(drill oval 1.2192 2.4638)
			(layers "*.Cu" "*.Mask")
			(remove_unused_layers no)
			(net "GND")
			(clearance 0.127)
			(thermal_gap 0.127)
		)
		(pad "G2" thru_hole oval
			(at 0 3.875024 90)
			(size 1.7272 3.4798)
			(drill oval 1.2192 2.4638)
			(layers "*.Cu" "*.Mask")
			(remove_unused_layers no)
			(net "GND")
			(clearance 0.127)
			(thermal_gap 0.127)
		)
		(pad "G3" thru_hole oval
			(at 0 68.97497 90)
			(size 1.7272 3.4798)
			(drill oval 1.2192 2.4638)
			(layers "*.Cu" "*.Mask")
			(remove_unused_layers no)
			(net "GND")
			(clearance 0.127)
			(thermal_gap 0.127)
		)
	)
	(footprint ""
		(layer "F.Cu")
		(at 453.054212 -24.619458 180)
		(property "Reference" "PC2088"
			(at 0 0 180)
			(layer "F.SilkS")
			(hide yes)
			(effects
				(font
					(size 1.27 1.27)
				)
			)
		)
		(property "Value" ""
			(at 0 0 180)
			(layer "F.Fab")
			(effects
				(font
					(size 1.27 1.27)
				)
			)
		)
		(duplicate_pad_numbers_are_jumpers no)
		(fp_line
			(start 0.7874 0.4064)
			(end -0.7874 0.4064)
			(stroke
				(width 0.1524)
				(type default)
			)
			(layer "F.SilkS")
		)
		(fp_line
			(start 0.7874 -0.4064)
			(end 0.7874 0.4064)
			(stroke
				(width 0.1524)
				(type default)
			)
			(layer "F.SilkS")
		)
		(fp_line
			(start -0.7874 0.4064)
			(end -0.7874 -0.4064)
			(stroke
				(width 0.1524)
				(type default)
			)
			(layer "F.SilkS")
		)
		(fp_line
			(start -0.7874 -0.4064)
			(end 0.7874 -0.4064)
			(stroke
				(width 0.1524)
				(type default)
			)
			(layer "F.SilkS")
		)
		(fp_line
			(start 0.67945 0.3048)
			(end 0.120396 0.3048)
			(stroke
				(width 0.1)
				(type default)
			)
			(layer "F.Fab")
		)
		(fp_line
			(start 0.67945 -0.3048)
			(end 0.67945 0.3048)
			(stroke
				(width 0.1)
				(type default)
			)
			(layer "F.Fab")
		)
		(fp_line
			(start 0.12065 -0.2794)
			(end 0.12065 -0.3048)
			(stroke
				(width 0.1)
				(type default)
			)
			(layer "F.Fab")
		)
		(fp_line
			(start 0.12065 -0.3048)
			(end 0.67945 -0.3048)
			(stroke
				(width 0.1)
				(type default)
			)
			(layer "F.Fab")
		)
		(fp_line
			(start 0.120396 0.3048)
			(end 0.120396 0.2794)
			(stroke
				(width 0.1)
				(type default)
			)
			(layer "F.Fab")
		)
		(fp_line
			(start 0.120396 0.2794)
			(end -0.12065 0.2794)
			(stroke
				(width 0.1)
				(type default)
			)
			(layer "F.Fab")
		)
		(fp_line
			(start -0.12065 0.3048)
			(end -0.67945 0.3048)
			(stroke
				(width 0.1)
				(type default)
			)
			(layer "F.Fab")
		)
		(fp_line
			(start -0.12065 0.2794)
			(end -0.12065 0.3048)
			(stroke
				(width 0.1)
				(type default)
			)
			(layer "F.Fab")
		)
		(fp_line
			(start -0.12065 -0.2794)
			(end 0.12065 -0.2794)
			(stroke
				(width 0.1)
				(type default)
			)
			(layer "F.Fab")
		)
		(fp_line
			(start -0.12065 -0.305054)
			(end -0.12065 -0.2794)
			(stroke
				(width 0.1)
				(type default)
			)
			(layer "F.Fab")
		)
		(fp_line
			(start -0.67945 0.3048)
			(end -0.67945 -0.305054)
			(stroke
				(width 0.1)
				(type default)
			)
			(layer "F.Fab")
		)
		(fp_line
			(start -0.67945 -0.305054)
			(end -0.12065 -0.305054)
			(stroke
				(width 0.1)
				(type default)
			)
			(layer "F.Fab")
		)
		(pad "1" smd circle
			(at -0.40005 0 180)
			(size 0 0)
			(layers "F.Cu" "F.Mask" "F.Paste")
			(net "P12V_OCP_SFF")
		)
		(pad "2" smd circle
			(at 0.40005 0 180)
			(size 0 0)
			(layers "F.Cu" "F.Mask" "F.Paste")
			(net "P12V_OCP_GATE_1")
		)
	)
	(footprint ""
		(layer "F.Cu")
		(at 120.76049 -52.86629 90)
		(property "Reference" "R6108"
			(at 0 0 90)
			(layer "F.SilkS")
			(hide yes)
			(effects
				(font
					(size 1.27 1.27)
				)
			)
		)
		(property "Value" ""
			(at 0 0 90)
			(layer "F.Fab")
			(effects
				(font
					(size 1.27 1.27)
				)
			)
		)
		(duplicate_pad_numbers_are_jumpers no)
		(fp_line
			(start 0.7874 -0.4064)
			(end 0.7874 0.4064)
			(stroke
				(width 0.1524)
				(type default)
			)
			(layer "F.SilkS")
		)
		(fp_line
			(start -0.7874 -0.4064)
			(end 0.7874 -0.4064)
			(stroke
				(width 0.1524)
				(type default)
			)
			(layer "F.SilkS")
		)
		(fp_line
			(start 0.7874 0.4064)
			(end -0.7874 0.4064)
			(stroke
				(width 0.1524)
				(type default)
			)
			(layer "F.SilkS")
		)
		(fp_line
			(start -0.7874 0.4064)
			(end -0.7874 -0.4064)
			(stroke
				(width 0.1524)
				(type default)
			)
			(layer "F.SilkS")
		)
		(fp_line
			(start -0.12065 -0.305054)
			(end -0.12065 -0.2794)
			(stroke
				(width 0.1)
				(type default)
			)
			(layer "F.Fab")
		)
		(fp_line
			(start -0.67945 -0.305054)
			(end -0.12065 -0.305054)
			(stroke
				(width 0.1)
				(type default)
			)
			(layer "F.Fab")
		)
		(fp_line
			(start 0.67945 -0.3048)
			(end 0.67945 0.3048)
			(stroke
				(width 0.1)
				(type default)
			)
			(layer "F.Fab")
		)
		(fp_line
			(start 0.12065 -0.3048)
			(end 0.67945 -0.3048)
			(stroke
				(width 0.1)
				(type default)
			)
			(layer "F.Fab")
		)
		(fp_line
			(start 0.12065 -0.2794)
			(end 0.12065 -0.3048)
			(stroke
				(width 0.1)
				(type default)
			)
			(layer "F.Fab")
		)
		(fp_line
			(start -0.12065 -0.2794)
			(end 0.12065 -0.2794)
			(stroke
				(width 0.1)
				(type default)
			)
			(layer "F.Fab")
		)
		(fp_line
			(start 0.120396 0.2794)
			(end -0.12065 0.2794)
			(stroke
				(width 0.1)
				(type default)
			)
			(layer "F.Fab")
		)
		(fp_line
			(start -0.12065 0.2794)
			(end -0.12065 0.3048)
			(stroke
				(width 0.1)
				(type default)
			)
			(layer "F.Fab")
		)
		(fp_line
			(start 0.67945 0.3048)
			(end 0.120396 0.3048)
			(stroke
				(width 0.1)
				(type default)
			)
			(layer "F.Fab")
		)
		(fp_line
			(start 0.120396 0.3048)
			(end 0.120396 0.2794)
			(stroke
				(width 0.1)
				(type default)
			)
			(layer "F.Fab")
		)
		(fp_line
			(start -0.12065 0.3048)
			(end -0.67945 0.3048)
			(stroke
				(width 0.1)
				(type default)
			)
			(layer "F.Fab")
		)
		(fp_line
			(start -0.67945 0.3048)
			(end -0.67945 -0.305054)
			(stroke
				(width 0.1)
				(type default)
			)
			(layer "F.Fab")
		)
		(pad "1" smd circle
			(at -0.40005 0 90)
			(size 0 0)
			(layers "F.Cu" "F.Mask" "F.Paste")
			(net "HDT_HDR_TDO")
		)
		(pad "2" smd circle
			(at 0.40005 0 90)
			(size 0 0)
			(layers "F.Cu" "F.Mask" "F.Paste")
			(net "HDT_HDR_TDO_R")
		)
	)
	(footprint ""
		(layer "F.Cu")
		(at 327.179178 -43.573954)
		(property "Reference" "R1791"
			(at 0 0 0)
			(layer "F.SilkS")
			(hide yes)
			(effects
				(font
					(size 1.27 1.27)
				)
			)
		)
		(property "Value" ""
			(at 0 0 0)
			(layer "F.Fab")
			(effects
				(font
					(size 1.27 1.27)
				)
			)
		)
		(duplicate_pad_numbers_are_jumpers no)
		(fp_line
			(start -0.7874 -0.4064)
			(end 0.7874 -0.4064)
			(stroke
				(width 0.1524)
				(type default)
			)
			(layer "F.SilkS")
		)
		(fp_line
			(start -0.7874 0.4064)
			(end -0.7874 -0.4064)
			(stroke
				(width 0.1524)
				(type default)
			)
			(layer "F.SilkS")
		)
		(fp_line
			(start 0.7874 -0.4064)
			(end 0.7874 0.4064)
			(stroke
				(width 0.1524)
				(type default)
			)
			(layer "F.SilkS")
		)
		(fp_line
			(start 0.7874 0.4064)
			(end -0.7874 0.4064)
			(stroke
				(width 0.1524)
				(type default)
			)
			(layer "F.SilkS")
		)
		(fp_line
			(start -0.67945 -0.305054)
			(end -0.12065 -0.305054)
			(stroke
				(width 0.1)
				(type default)
			)
			(layer "F.Fab")
		)
		(fp_line
			(start -0.67945 0.3048)
			(end -0.67945 -0.305054)
			(stroke
				(width 0.1)
				(type default)
			)
			(layer "F.Fab")
		)
		(fp_line
			(start -0.12065 -0.305054)
			(end -0.12065 -0.2794)
			(stroke
				(width 0.1)
				(type default)
			)
			(layer "F.Fab")
		)
		(fp_line
			(start -0.12065 -0.2794)
			(end 0.12065 -0.2794)
			(stroke
				(width 0.1)
				(type default)
			)
			(layer "F.Fab")
		)
		(fp_line
			(start -0.12065 0.2794)
			(end -0.12065 0.3048)
			(stroke
				(width 0.1)
				(type default)
			)
			(layer "F.Fab")
		)
		(fp_line
			(start -0.12065 0.3048)
			(end -0.67945 0.3048)
			(stroke
				(width 0.1)
				(type default)
			)
			(layer "F.Fab")
		)
		(fp_line
			(start 0.120396 0.2794)
			(end -0.12065 0.2794)
			(stroke
				(width 0.1)
				(type default)
			)
			(layer "F.Fab")
		)
		(fp_line
			(start 0.120396 0.3048)
			(end 0.120396 0.2794)
			(stroke
				(width 0.1)
				(type default)
			)
			(layer "F.Fab")
		)
		(fp_line
			(start 0.12065 -0.3048)
			(end 0.67945 -0.3048)
			(stroke
				(width 0.1)
				(type default)
			)
			(layer "F.Fab")
		)
		(fp_line
			(start 0.12065 -0.2794)
			(end 0.12065 -0.3048)
			(stroke
				(width 0.1)
				(type default)
			)
			(layer "F.Fab")
		)
		(fp_line
			(start 0.67945 -0.3048)
			(end 0.67945 0.3048)
			(stroke
				(width 0.1)
				(type default)
			)
			(layer "F.Fab")
		)
		(fp_line
			(start 0.67945 0.3048)
			(end 0.120396 0.3048)
			(stroke
				(width 0.1)
				(type default)
			)
			(layer "F.Fab")
		)
		(pad "1" smd circle
			(at -0.40005 0)
			(size 0 0)
			(layers "F.Cu" "F.Mask" "F.Paste")
			(net "P5V_ADC")
		)
		(pad "2" smd circle
			(at 0.40005 0)
			(size 0 0)
			(layers "F.Cu" "F.Mask" "F.Paste")
			(net "GND")
		)
	)
	(footprint ""
		(layer "F.Cu")
		(at 167.386 -95.377 90)
		(property "Reference" "U30"
			(at -3.544316 -2.646172 90)
			(unlocked yes)
			(layer "F.SilkS")
			(effects
				(font
					(size 0.7874 0.5842)
					(thickness 0.1524)
				)
				(justify left)
			)
		)
		(property "Value" ""
			(at 0 0 90)
			(layer "F.Fab")
			(effects
				(font
					(size 1.27 1.27)
				)
			)
		)
		(duplicate_pad_numbers_are_jumpers no)
		(fp_line
			(start 2.0574 -1.651)
			(end 2.0574 1.651)
			(stroke
				(width 0.1524)
				(type default)
			)
			(layer "F.SilkS")
		)
		(fp_line
			(start 0.381 -1.651)
			(end 2.0574 -1.651)
			(stroke
				(width 0.1524)
				(type default)
			)
			(layer "F.SilkS")
		)
		(fp_line
			(start -0.381 -1.651)
			(end 0 -1.016)
			(stroke
				(width 0.1524)
				(type default)
			)
			(layer "F.SilkS")
		)
		(fp_line
			(start -2.0574 -1.651)
			(end -0.381 -1.651)
			(stroke
				(width 0.1524)
				(type default)
			)
			(layer "F.SilkS")
		)
		(fp_line
			(start 0 -1.016)
			(end 0.381 -1.651)
			(stroke
				(width 0.1524)
				(type default)
			)
			(layer "F.SilkS")
		)
		(fp_line
			(start 2.0574 1.651)
			(end -2.0574 1.651)
			(stroke
				(width 0.1524)
				(type default)
			)
			(layer "F.SilkS")
		)
		(fp_line
			(start -2.0574 1.651)
			(end -2.0574 -1.651)
			(stroke
				(width 0.1524)
				(type default)
			)
			(layer "F.SilkS")
		)
		(fp_poly
			(pts
				(xy -2.71272 -0.719328) (xy -2.71272 -1.344168) (xy -2.159 -1.016)
			)
			(stroke
				(width 0)
				(type default)
			)
			(fill yes)
			(layer "F.SilkS")
		)
		(fp_line
			(start 0.899922 -1.549908)
			(end 0.899922 -1.199896)
			(stroke
				(width 0.1)
				(type default)
			)
			(layer "F.Fab")
		)
		(fp_line
			(start -0.899922 -1.549908)
			(end 0.899922 -1.549908)
			(stroke
				(width 0.1)
				(type default)
			)
			(layer "F.Fab")
		)
		(fp_line
			(start 1.599946 -1.199896)
			(end 1.599946 1.199896)
			(stroke
				(width 0.1)
				(type default)
			)
			(layer "F.Fab")
		)
		(fp_line
			(start 0.899922 -1.199896)
			(end 1.599946 -1.199896)
			(stroke
				(width 0.1)
				(type default)
			)
			(layer "F.Fab")
		)
		(fp_line
			(start -0.899922 -1.199896)
			(end -0.899922 -1.549908)
			(stroke
				(width 0.1)
				(type default)
			)
			(layer "F.Fab")
		)
		(fp_line
			(start -1.599946 -1.199896)
			(end -0.899922 -1.199896)
			(stroke
				(width 0.1)
				(type default)
			)
			(layer "F.Fab")
		)
		(fp_line
			(start 1.599946 1.199896)
			(end 0.899922 1.199896)
			(stroke
				(width 0.1)
				(type default)
			)
			(layer "F.Fab")
		)
		(fp_line
			(start 0.899922 1.199896)
			(end 0.899922 1.549908)
			(stroke
				(width 0.1)
				(type default)
			)
			(layer "F.Fab")
		)
		(fp_line
			(start -0.899922 1.199896)
			(end -1.599946 1.199896)
			(stroke
				(width 0.1)
				(type default)
			)
			(layer "F.Fab")
		)
		(fp_line
			(start -1.599946 1.199896)
			(end -1.599946 -1.199896)
			(stroke
				(width 0.1)
				(type default)
			)
			(layer "F.Fab")
		)
		(fp_line
			(start 0.899922 1.549908)
			(end -0.899922 1.549908)
			(stroke
				(width 0.1)
				(type default)
			)
			(layer "F.Fab")
		)
		(fp_line
			(start -0.899922 1.549908)
			(end -0.899922 1.199896)
			(stroke
				(width 0.1)
				(type default)
			)
			(layer "F.Fab")
		)
		(fp_poly
			(pts
				(xy -2.71272 -0.719328) (xy -2.71272 -1.344168) (xy -2.159 -1.016)
			)
			(stroke
				(width 0)
				(type default)
			)
			(fill yes)
			(layer "F.Fab")
		)
		(pad "1" smd rect
			(at -1.225042 -0.94996)
			(size 0.5588 1.3462)
			(layers "F.Cu" "F.Mask" "F.Paste")
			(net "Net_10854")
		)
		(pad "2" smd rect
			(at -1.225042 0)
			(size 0.5588 1.3462)
			(layers "F.Cu" "F.Mask" "F.Paste")
			(net "OCP_V3_1_P3V3_R2_PWRGD")
		)
		(pad "3" smd rect
			(at -1.225042 0.94996)
			(size 0.5588 1.3462)
			(layers "F.Cu" "F.Mask" "F.Paste")
			(net "GND")
		)
		(pad "4" smd rect
			(at 1.225042 0.94996)
			(size 0.5588 1.3462)
			(layers "F.Cu" "F.Mask" "F.Paste")
			(net "OCP_V3_1_P3V3_PLD_PWRGD")
		)
		(pad "5" smd rect
			(at 1.225042 -0.94996)
			(size 0.5588 1.3462)
			(layers "F.Cu" "F.Mask" "F.Paste")
			(net "P3V3_AUX")
		)
	)
	(footprint ""
		(layer "F.Cu")
		(at 329.2348 -15.979394 -90)
		(property "Reference" "R1194"
			(at 0 0 270)
			(layer "F.SilkS")
			(hide yes)
			(effects
				(font
					(size 1.27 1.27)
				)
			)
		)
		(property "Value" ""
			(at 0 0 270)
			(layer "F.Fab")
			(effects
				(font
					(size 1.27 1.27)
				)
			)
		)
		(duplicate_pad_numbers_are_jumpers no)
		(fp_line
			(start -0.7874 0.4064)
			(end -0.7874 -0.4064)
			(stroke
				(width 0.1524)
				(type default)
			)
			(layer "F.SilkS")
		)
		(fp_line
			(start 0.7874 0.4064)
			(end -0.7874 0.4064)
			(stroke
				(width 0.1524)
				(type default)
			)
			(layer "F.SilkS")
		)
		(fp_line
			(start -0.7874 -0.4064)
			(end 0.7874 -0.4064)
			(stroke
				(width 0.1524)
				(type default)
			)
			(layer "F.SilkS")
		)
		(fp_line
			(start 0.7874 -0.4064)
			(end 0.7874 0.4064)
			(stroke
				(width 0.1524)
				(type default)
			)
			(layer "F.SilkS")
		)
		(fp_line
			(start -0.67945 0.3048)
			(end -0.67945 -0.305054)
			(stroke
				(width 0.1)
				(type default)
			)
			(layer "F.Fab")
		)
		(fp_line
			(start -0.12065 0.3048)
			(end -0.67945 0.3048)
			(stroke
				(width 0.1)
				(type default)
			)
			(layer "F.Fab")
		)
		(fp_line
			(start 0.120396 0.3048)
			(end 0.120396 0.2794)
			(stroke
				(width 0.1)
				(type default)
			)
			(layer "F.Fab")
		)
		(fp_line
			(start 0.67945 0.3048)
			(end 0.120396 0.3048)
			(stroke
				(width 0.1)
				(type default)
			)
			(layer "F.Fab")
		)
		(fp_line
			(start -0.12065 0.2794)
			(end -0.12065 0.3048)
			(stroke
				(width 0.1)
				(type default)
			)
			(layer "F.Fab")
		)
		(fp_line
			(start 0.120396 0.2794)
			(end -0.12065 0.2794)
			(stroke
				(width 0.1)
				(type default)
			)
			(layer "F.Fab")
		)
		(fp_line
			(start -0.12065 -0.2794)
			(end 0.12065 -0.2794)
			(stroke
				(width 0.1)
				(type default)
			)
			(layer "F.Fab")
		)
		(fp_line
			(start 0.12065 -0.2794)
			(end 0.12065 -0.3048)
			(stroke
				(width 0.1)
				(type default)
			)
			(layer "F.Fab")
		)
		(fp_line
			(start 0.12065 -0.3048)
			(end 0.67945 -0.3048)
			(stroke
				(width 0.1)
				(type default)
			)
			(layer "F.Fab")
		)
		(fp_line
			(start 0.67945 -0.3048)
			(end 0.67945 0.3048)
			(stroke
				(width 0.1)
				(type default)
			)
			(layer "F.Fab")
		)
		(fp_line
			(start -0.67945 -0.305054)
			(end -0.12065 -0.305054)
			(stroke
				(width 0.1)
				(type default)
			)
			(layer "F.Fab")
		)
		(fp_line
			(start -0.12065 -0.305054)
			(end -0.12065 -0.2794)
			(stroke
				(width 0.1)
				(type default)
			)
			(layer "F.Fab")
		)
		(pad "1" smd circle
			(at -0.40005 0 270)
			(size 0 0)
			(layers "F.Cu" "F.Mask" "F.Paste")
			(net "P3V3_AUX")
		)
		(pad "2" smd circle
			(at 0.40005 0 270)
			(size 0 0)
			(layers "F.Cu" "F.Mask" "F.Paste")
			(net "BMC_FPGA_LED2_R_N")
		)
	)
	(footprint ""
		(layer "F.Cu")
		(at 20.480782 -409.421584 180)
		(property "Reference" "R665"
			(at 0 0 180)
			(layer "F.SilkS")
			(hide yes)
			(effects
				(font
					(size 1.27 1.27)
				)
			)
		)
		(property "Value" ""
			(at 0 0 180)
			(layer "F.Fab")
			(effects
				(font
					(size 1.27 1.27)
				)
			)
		)
		(duplicate_pad_numbers_are_jumpers no)
		(fp_line
			(start 0.7874 0.4064)
			(end -0.7874 0.4064)
			(stroke
				(width 0.1524)
				(type default)
			)
			(layer "F.SilkS")
		)
		(fp_line
			(start 0.7874 -0.4064)
			(end 0.7874 0.4064)
			(stroke
				(width 0.1524)
				(type default)
			)
			(layer "F.SilkS")
		)
		(fp_line
			(start -0.7874 0.4064)
			(end -0.7874 -0.4064)
			(stroke
				(width 0.1524)
				(type default)
			)
			(layer "F.SilkS")
		)
		(fp_line
			(start -0.7874 -0.4064)
			(end 0.7874 -0.4064)
			(stroke
				(width 0.1524)
				(type default)
			)
			(layer "F.SilkS")
		)
		(fp_line
			(start 0.67945 0.3048)
			(end 0.120396 0.3048)
			(stroke
				(width 0.1)
				(type default)
			)
			(layer "F.Fab")
		)
		(fp_line
			(start 0.67945 -0.3048)
			(end 0.67945 0.3048)
			(stroke
				(width 0.1)
				(type default)
			)
			(layer "F.Fab")
		)
		(fp_line
			(start 0.12065 -0.2794)
			(end 0.12065 -0.3048)
			(stroke
				(width 0.1)
				(type default)
			)
			(layer "F.Fab")
		)
		(fp_line
			(start 0.12065 -0.3048)
			(end 0.67945 -0.3048)
			(stroke
				(width 0.1)
				(type default)
			)
			(layer "F.Fab")
		)
		(fp_line
			(start 0.120396 0.3048)
			(end 0.120396 0.2794)
			(stroke
				(width 0.1)
				(type default)
			)
			(layer "F.Fab")
		)
		(fp_line
			(start 0.120396 0.2794)
			(end -0.12065 0.2794)
			(stroke
				(width 0.1)
				(type default)
			)
			(layer "F.Fab")
		)
		(fp_line
			(start -0.12065 0.3048)
			(end -0.67945 0.3048)
			(stroke
				(width 0.1)
				(type default)
			)
			(layer "F.Fab")
		)
		(fp_line
			(start -0.12065 0.2794)
			(end -0.12065 0.3048)
			(stroke
				(width 0.1)
				(type default)
			)
			(layer "F.Fab")
		)
		(fp_line
			(start -0.12065 -0.2794)
			(end 0.12065 -0.2794)
			(stroke
				(width 0.1)
				(type default)
			)
			(layer "F.Fab")
		)
		(fp_line
			(start -0.12065 -0.305054)
			(end -0.12065 -0.2794)
			(stroke
				(width 0.1)
				(type default)
			)
			(layer "F.Fab")
		)
		(fp_line
			(start -0.67945 0.3048)
			(end -0.67945 -0.305054)
			(stroke
				(width 0.1)
				(type default)
			)
			(layer "F.Fab")
		)
		(fp_line
			(start -0.67945 -0.305054)
			(end -0.12065 -0.305054)
			(stroke
				(width 0.1)
				(type default)
			)
			(layer "F.Fab")
		)
		(pad "1" smd circle
			(at -0.40005 0 180)
			(size 0 0)
			(layers "F.Cu" "F.Mask" "F.Paste")
			(net "P3V3_AUX")
		)
		(pad "2" smd circle
			(at 0.40005 0 180)
			(size 0 0)
			(layers "F.Cu" "F.Mask" "F.Paste")
			(net "P0V9_RETIMER_CPU1_INALERT")
		)
	)
	(footprint ""
		(layer "F.Cu")
		(at 338.324444 -381.41783 -90)
		(property "Reference" "C955"
			(at 0 0 270)
			(layer "F.SilkS")
			(hide yes)
			(effects
				(font
					(size 1.27 1.27)
				)
			)
		)
		(property "Value" ""
			(at 0 0 270)
			(layer "F.Fab")
			(effects
				(font
					(size 1.27 1.27)
				)
			)
		)
		(duplicate_pad_numbers_are_jumpers no)
		(fp_line
			(start -0.299974 0.150114)
			(end -0.299974 -0.150114)
			(stroke
				(width 0.1)
				(type default)
			)
			(layer "F.Fab")
		)
		(fp_line
			(start 0.299974 0.150114)
			(end -0.299974 0.150114)
			(stroke
				(width 0.1)
				(type default)
			)
			(layer "F.Fab")
		)
		(fp_line
			(start -0.299974 -0.150114)
			(end 0.299974 -0.150114)
			(stroke
				(width 0.1)
				(type default)
			)
			(layer "F.Fab")
		)
		(fp_line
			(start 0.299974 -0.150114)
			(end 0.299974 0.150114)
			(stroke
				(width 0.1)
				(type default)
			)
			(layer "F.Fab")
		)
		(pad "1" smd rect
			(at -0.2667 0 270)
			(size 0.3048 0.381)
			(layers "F.Cu" "F.Mask" "F.Paste")
			(net "P5E_CPU0_P1_TX_C_DP<5>")
		)
		(pad "2" smd rect
			(at 0.2667 0 270)
			(size 0.3048 0.381)
			(layers "F.Cu" "F.Mask" "F.Paste")
			(net "P5E_CPU0_P1_TX_DP<5>")
		)
	)
	(footprint ""
		(layer "F.Cu")
		(at 175.06188 -21.173948 180)
		(property "Reference" "PC2242"
			(at 0 0 180)
			(layer "F.SilkS")
			(hide yes)
			(effects
				(font
					(size 1.27 1.27)
				)
			)
		)
		(property "Value" ""
			(at 0 0 180)
			(layer "F.Fab")
			(effects
				(font
					(size 1.27 1.27)
				)
			)
		)
		(duplicate_pad_numbers_are_jumpers no)
		(fp_line
			(start 1.524 0.762)
			(end -1.524 0.762)
			(stroke
				(width 0.1524)
				(type default)
			)
			(layer "F.SilkS")
		)
		(fp_line
			(start 1.524 -0.762)
			(end 1.524 0.762)
			(stroke
				(width 0.1524)
				(type default)
			)
			(layer "F.SilkS")
		)
		(fp_line
			(start -1.524 0.762)
			(end -1.524 -0.762)
			(stroke
				(width 0.1524)
				(type default)
			)
			(layer "F.SilkS")
		)
		(fp_line
			(start -1.524 -0.762)
			(end 1.524 -0.762)
			(stroke
				(width 0.1524)
				(type default)
			)
			(layer "F.SilkS")
		)
		(fp_line
			(start 1.1049 0.724916)
			(end 1.1049 -0.724916)
			(stroke
				(width 0.1)
				(type default)
			)
			(layer "F.Fab")
		)
		(fp_line
			(start 1.1049 -0.724916)
			(end -1.1049 -0.724916)
			(stroke
				(width 0.1)
				(type default)
			)
			(layer "F.Fab")
		)
		(fp_line
			(start -1.1049 0.724916)
			(end 1.1049 0.724916)
			(stroke
				(width 0.1)
				(type default)
			)
			(layer "F.Fab")
		)
		(fp_line
			(start -1.1049 -0.724916)
			(end -1.1049 0.724916)
			(stroke
				(width 0.1)
				(type default)
			)
			(layer "F.Fab")
		)
		(pad "1" smd rect
			(at -0.889 0)
			(size 1.016 1.27)
			(layers "F.Cu" "F.Mask" "F.Paste")
			(net "P12V_SCM_R")
		)
		(pad "2" smd rect
			(at 0.889 0)
			(size 1.016 1.27)
			(layers "F.Cu" "F.Mask" "F.Paste")
			(net "GND")
		)
	)
	(footprint ""
		(layer "F.Cu")
		(at 118.11 -418.846 -90)
		(property "Reference" "R3434"
			(at 0 0 270)
			(layer "F.SilkS")
			(hide yes)
			(effects
				(font
					(size 1.27 1.27)
				)
			)
		)
		(property "Value" ""
			(at 0 0 270)
			(layer "F.Fab")
			(effects
				(font
					(size 1.27 1.27)
				)
			)
		)
		(duplicate_pad_numbers_are_jumpers no)
		(fp_line
			(start -0.7874 0.4064)
			(end -0.7874 -0.4064)
			(stroke
				(width 0.1524)
				(type default)
			)
			(layer "F.SilkS")
		)
		(fp_line
			(start 0.7874 0.4064)
			(end -0.7874 0.4064)
			(stroke
				(width 0.1524)
				(type default)
			)
			(layer "F.SilkS")
		)
		(fp_line
			(start -0.7874 -0.4064)
			(end 0.7874 -0.4064)
			(stroke
				(width 0.1524)
				(type default)
			)
			(layer "F.SilkS")
		)
		(fp_line
			(start 0.7874 -0.4064)
			(end 0.7874 0.4064)
			(stroke
				(width 0.1524)
				(type default)
			)
			(layer "F.SilkS")
		)
		(fp_line
			(start -0.67945 0.3048)
			(end -0.67945 -0.305054)
			(stroke
				(width 0.1)
				(type default)
			)
			(layer "F.Fab")
		)
		(fp_line
			(start -0.12065 0.3048)
			(end -0.67945 0.3048)
			(stroke
				(width 0.1)
				(type default)
			)
			(layer "F.Fab")
		)
		(fp_line
			(start 0.120396 0.3048)
			(end 0.120396 0.2794)
			(stroke
				(width 0.1)
				(type default)
			)
			(layer "F.Fab")
		)
		(fp_line
			(start 0.67945 0.3048)
			(end 0.120396 0.3048)
			(stroke
				(width 0.1)
				(type default)
			)
			(layer "F.Fab")
		)
		(fp_line
			(start -0.12065 0.2794)
			(end -0.12065 0.3048)
			(stroke
				(width 0.1)
				(type default)
			)
			(layer "F.Fab")
		)
		(fp_line
			(start 0.120396 0.2794)
			(end -0.12065 0.2794)
			(stroke
				(width 0.1)
				(type default)
			)
			(layer "F.Fab")
		)
		(fp_line
			(start -0.12065 -0.2794)
			(end 0.12065 -0.2794)
			(stroke
				(width 0.1)
				(type default)
			)
			(layer "F.Fab")
		)
		(fp_line
			(start 0.12065 -0.2794)
			(end 0.12065 -0.3048)
			(stroke
				(width 0.1)
				(type default)
			)
			(layer "F.Fab")
		)
		(fp_line
			(start 0.12065 -0.3048)
			(end 0.67945 -0.3048)
			(stroke
				(width 0.1)
				(type default)
			)
			(layer "F.Fab")
		)
		(fp_line
			(start 0.67945 -0.3048)
			(end 0.67945 0.3048)
			(stroke
				(width 0.1)
				(type default)
			)
			(layer "F.Fab")
		)
		(fp_line
			(start -0.67945 -0.305054)
			(end -0.12065 -0.305054)
			(stroke
				(width 0.1)
				(type default)
			)
			(layer "F.Fab")
		)
		(fp_line
			(start -0.12065 -0.305054)
			(end -0.12065 -0.2794)
			(stroke
				(width 0.1)
				(type default)
			)
			(layer "F.Fab")
		)
		(pad "1" smd circle
			(at -0.40005 0 270)
			(size 0 0)
			(layers "F.Cu" "F.Mask" "F.Paste")
			(net "P3V3_AUX")
		)
		(pad "2" smd circle
			(at 0.40005 0 270)
			(size 0 0)
			(layers "F.Cu" "F.Mask" "F.Paste")
			(net "GPU_HMC_PRSNT")
		)
	)
	(footprint ""
		(layer "F.Cu")
		(at 158.16707 -74.75347 90)
		(property "Reference" "R1005"
			(at 0 0 90)
			(layer "F.SilkS")
			(hide yes)
			(effects
				(font
					(size 1.27 1.27)
				)
			)
		)
		(property "Value" ""
			(at 0 0 90)
			(layer "F.Fab")
			(effects
				(font
					(size 1.27 1.27)
				)
			)
		)
		(duplicate_pad_numbers_are_jumpers no)
		(fp_line
			(start 0.7874 -0.4064)
			(end 0.7874 0.4064)
			(stroke
				(width 0.1524)
				(type default)
			)
			(layer "F.SilkS")
		)
		(fp_line
			(start -0.7874 -0.4064)
			(end 0.7874 -0.4064)
			(stroke
				(width 0.1524)
				(type default)
			)
			(layer "F.SilkS")
		)
		(fp_line
			(start 0.7874 0.4064)
			(end -0.7874 0.4064)
			(stroke
				(width 0.1524)
				(type default)
			)
			(layer "F.SilkS")
		)
		(fp_line
			(start -0.7874 0.4064)
			(end -0.7874 -0.4064)
			(stroke
				(width 0.1524)
				(type default)
			)
			(layer "F.SilkS")
		)
		(fp_line
			(start -0.12065 -0.305054)
			(end -0.12065 -0.2794)
			(stroke
				(width 0.1)
				(type default)
			)
			(layer "F.Fab")
		)
		(fp_line
			(start -0.67945 -0.305054)
			(end -0.12065 -0.305054)
			(stroke
				(width 0.1)
				(type default)
			)
			(layer "F.Fab")
		)
		(fp_line
			(start 0.67945 -0.3048)
			(end 0.67945 0.3048)
			(stroke
				(width 0.1)
				(type default)
			)
			(layer "F.Fab")
		)
		(fp_line
			(start 0.12065 -0.3048)
			(end 0.67945 -0.3048)
			(stroke
				(width 0.1)
				(type default)
			)
			(layer "F.Fab")
		)
		(fp_line
			(start 0.12065 -0.2794)
			(end 0.12065 -0.3048)
			(stroke
				(width 0.1)
				(type default)
			)
			(layer "F.Fab")
		)
		(fp_line
			(start -0.12065 -0.2794)
			(end 0.12065 -0.2794)
			(stroke
				(width 0.1)
				(type default)
			)
			(layer "F.Fab")
		)
		(fp_line
			(start 0.120396 0.2794)
			(end -0.12065 0.2794)
			(stroke
				(width 0.1)
				(type default)
			)
			(layer "F.Fab")
		)
		(fp_line
			(start -0.12065 0.2794)
			(end -0.12065 0.3048)
			(stroke
				(width 0.1)
				(type default)
			)
			(layer "F.Fab")
		)
		(fp_line
			(start 0.67945 0.3048)
			(end 0.120396 0.3048)
			(stroke
				(width 0.1)
				(type default)
			)
			(layer "F.Fab")
		)
		(fp_line
			(start 0.120396 0.3048)
			(end 0.120396 0.2794)
			(stroke
				(width 0.1)
				(type default)
			)
			(layer "F.Fab")
		)
		(fp_line
			(start -0.12065 0.3048)
			(end -0.67945 0.3048)
			(stroke
				(width 0.1)
				(type default)
			)
			(layer "F.Fab")
		)
		(fp_line
			(start -0.67945 0.3048)
			(end -0.67945 -0.305054)
			(stroke
				(width 0.1)
				(type default)
			)
			(layer "F.Fab")
		)
		(pad "1" smd circle
			(at -0.40005 0 90)
			(size 0 0)
			(layers "F.Cu" "F.Mask" "F.Paste")
			(net "M2_0_PEWAKE_R_N")
		)
		(pad "2" smd circle
			(at 0.40005 0 90)
			(size 0 0)
			(layers "F.Cu" "F.Mask" "F.Paste")
			(net "IRQ_LVC3_WAKE_N")
		)
	)
	(footprint ""
		(layer "F.Cu")
		(at 367.606326 -37.043868 -90)
		(property "Reference" "U116"
			(at 0.449834 -3.882136 90)
			(unlocked yes)
			(layer "F.SilkS")
			(effects
				(font
					(size 0.7874 0.5842)
					(thickness 0.1524)
				)
				(justify left)
			)
		)
		(property "Value" ""
			(at 0 0 270)
			(layer "F.Fab")
			(effects
				(font
					(size 1.27 1.27)
				)
			)
		)
		(duplicate_pad_numbers_are_jumpers no)
		(fp_line
			(start -1.868932 2.549906)
			(end 1.868932 2.549906)
			(stroke
				(width 0.1524)
				(type default)
			)
			(layer "F.SilkS")
		)
		(fp_line
			(start 1.868932 2.549906)
			(end 1.868932 -2.549906)
			(stroke
				(width 0.1524)
				(type default)
			)
			(layer "F.SilkS")
		)
		(fp_line
			(start 0 -1.524)
			(end -1.025906 -2.549906)
			(stroke
				(width 0.1524)
				(type default)
			)
			(layer "F.SilkS")
		)
		(fp_line
			(start -1.868932 -2.549906)
			(end -1.868932 2.549906)
			(stroke
				(width 0.1524)
				(type default)
			)
			(layer "F.SilkS")
		)
		(fp_line
			(start -1.025906 -2.549906)
			(end -1.868932 -2.549906)
			(stroke
				(width 0.1524)
				(type default)
			)
			(layer "F.SilkS")
		)
		(fp_line
			(start 1.025906 -2.549906)
			(end 0 -1.524)
			(stroke
				(width 0.1524)
				(type default)
			)
			(layer "F.SilkS")
		)
		(fp_line
			(start 1.868932 -2.549906)
			(end 1.025906 -2.549906)
			(stroke
				(width 0.1524)
				(type default)
			)
			(layer "F.SilkS")
		)
		(fp_poly
			(pts
				(xy -4.240276 -2.43078) (xy -5.256276 -1.92278) (xy -5.256276 -2.93878)
			)
			(stroke
				(width 0)
				(type default)
			)
			(fill yes)
			(layer "F.SilkS")
		)
		(fp_line
			(start -2.249932 2.549906)
			(end 2.249932 2.549906)
			(stroke
				(width 0.1)
				(type default)
			)
			(layer "F.Fab")
		)
		(fp_line
			(start 2.249932 2.549906)
			(end 2.249932 -2.549906)
			(stroke
				(width 0.1)
				(type default)
			)
			(layer "F.Fab")
		)
		(fp_line
			(start -2.249932 -2.549906)
			(end -2.249932 2.549906)
			(stroke
				(width 0.1)
				(type default)
			)
			(layer "F.Fab")
		)
		(fp_line
			(start 2.249932 -2.549906)
			(end -2.249932 -2.549906)
			(stroke
				(width 0.1)
				(type default)
			)
			(layer "F.Fab")
		)
		(fp_poly
			(pts
				(xy -4.7752 -1.787398) (xy -4.7752 -2.803398) (xy -3.7592 -2.295398)
			)
			(stroke
				(width 0)
				(type default)
			)
			(fill yes)
			(layer "F.Fab")
		)
		(pad "1" smd rect
			(at -2.800096 -2.275078 180)
			(size 0.3556 1.6002)
			(layers "F.Cu" "F.Mask" "F.Paste")
			(net "PVDD18_S5_P0")
		)
		(pad "2" smd rect
			(at -2.800096 -1.625092 180)
			(size 0.3556 1.6002)
			(layers "F.Cu" "F.Mask" "F.Paste")
			(net "GND")
		)
		(pad "3" smd rect
			(at -2.800096 -0.975106 180)
			(size 0.3556 1.6002)
			(layers "F.Cu" "F.Mask" "F.Paste")
			(net "UART_CPU0_SCM_UART1_TX")
		)
		(pad "4" smd rect
			(at -2.800096 -0.32512 180)
			(size 0.3556 1.6002)
			(layers "F.Cu" "F.Mask" "F.Paste")
			(net "UART_CPU0_SCM_UART1_R_RX")
		)
		(pad "5" smd rect
			(at -2.800096 0.32512 180)
			(size 0.3556 1.6002)
			(layers "F.Cu" "F.Mask" "F.Paste")
			(net "UART_CPU0_UART0_TX")
		)
		(pad "6" smd rect
			(at -2.800096 0.975106 180)
			(size 0.3556 1.6002)
			(layers "F.Cu" "F.Mask" "F.Paste")
			(net "UART_CPU0_UART0_R_RX")
		)
		(pad "7" smd rect
			(at -2.800096 1.625092 180)
			(size 0.3556 1.6002)
			(layers "F.Cu" "F.Mask" "F.Paste")
			(net "PVDD18_S5_P0")
		)
		(pad "8" smd rect
			(at -2.800096 2.275078 180)
			(size 0.3556 1.6002)
			(layers "F.Cu" "F.Mask" "F.Paste")
			(net "GND")
		)
		(pad "9" smd rect
			(at 2.800096 2.275078 180)
			(size 0.3556 1.6002)
			(layers "F.Cu" "F.Mask" "F.Paste")
			(net "UART_LS_EN_N")
		)
		(pad "10" smd rect
			(at 2.800096 1.625092 180)
			(size 0.3556 1.6002)
			(layers "F.Cu" "F.Mask" "F.Paste")
			(net "GND")
		)
		(pad "11" smd rect
			(at 2.800096 0.975106 180)
			(size 0.3556 1.6002)
			(layers "F.Cu" "F.Mask" "F.Paste")
			(net "UART_CPU0_LVC3_UART0_R_RX")
		)
		(pad "12" smd rect
			(at 2.800096 0.32512 180)
			(size 0.3556 1.6002)
			(layers "F.Cu" "F.Mask" "F.Paste")
			(net "UART_CPU0_LVC3_UART0_R_TX")
		)
		(pad "13" smd rect
			(at 2.800096 -0.32512 180)
			(size 0.3556 1.6002)
			(layers "F.Cu" "F.Mask" "F.Paste")
			(net "UART_CPU0_SCM_LVC3_UART1_R_RX")
		)
		(pad "14" smd rect
			(at 2.800096 -0.975106 180)
			(size 0.3556 1.6002)
			(layers "F.Cu" "F.Mask" "F.Paste")
			(net "UART_CPU0_SCM_LVC3_UART1_R_TX")
		)
		(pad "15" smd rect
			(at 2.800096 -1.625092 180)
			(size 0.3556 1.6002)
			(layers "F.Cu" "F.Mask" "F.Paste")
			(net "P3V3_AUX")
		)
		(pad "16" smd rect
			(at 2.800096 -2.275078 180)
			(size 0.3556 1.6002)
			(layers "F.Cu" "F.Mask" "F.Paste")
			(net "PVDD18_S5_P0")
		)
	)
	(footprint ""
		(layer "F.Cu")
		(at 215.9 -96.774 180)
		(property "Reference" "R1145"
			(at 0 0 180)
			(layer "F.SilkS")
			(hide yes)
			(effects
				(font
					(size 1.27 1.27)
				)
			)
		)
		(property "Value" ""
			(at 0 0 180)
			(layer "F.Fab")
			(effects
				(font
					(size 1.27 1.27)
				)
			)
		)
		(duplicate_pad_numbers_are_jumpers no)
		(fp_line
			(start 0.7874 0.4064)
			(end -0.7874 0.4064)
			(stroke
				(width 0.1524)
				(type default)
			)
			(layer "F.SilkS")
		)
		(fp_line
			(start 0.7874 -0.4064)
			(end 0.7874 0.4064)
			(stroke
				(width 0.1524)
				(type default)
			)
			(layer "F.SilkS")
		)
		(fp_line
			(start -0.7874 0.4064)
			(end -0.7874 -0.4064)
			(stroke
				(width 0.1524)
				(type default)
			)
			(layer "F.SilkS")
		)
		(fp_line
			(start -0.7874 -0.4064)
			(end 0.7874 -0.4064)
			(stroke
				(width 0.1524)
				(type default)
			)
			(layer "F.SilkS")
		)
		(fp_line
			(start 0.67945 0.3048)
			(end 0.120396 0.3048)
			(stroke
				(width 0.1)
				(type default)
			)
			(layer "F.Fab")
		)
		(fp_line
			(start 0.67945 -0.3048)
			(end 0.67945 0.3048)
			(stroke
				(width 0.1)
				(type default)
			)
			(layer "F.Fab")
		)
		(fp_line
			(start 0.12065 -0.2794)
			(end 0.12065 -0.3048)
			(stroke
				(width 0.1)
				(type default)
			)
			(layer "F.Fab")
		)
		(fp_line
			(start 0.12065 -0.3048)
			(end 0.67945 -0.3048)
			(stroke
				(width 0.1)
				(type default)
			)
			(layer "F.Fab")
		)
		(fp_line
			(start 0.120396 0.3048)
			(end 0.120396 0.2794)
			(stroke
				(width 0.1)
				(type default)
			)
			(layer "F.Fab")
		)
		(fp_line
			(start 0.120396 0.2794)
			(end -0.12065 0.2794)
			(stroke
				(width 0.1)
				(type default)
			)
			(layer "F.Fab")
		)
		(fp_line
			(start -0.12065 0.3048)
			(end -0.67945 0.3048)
			(stroke
				(width 0.1)
				(type default)
			)
			(layer "F.Fab")
		)
		(fp_line
			(start -0.12065 0.2794)
			(end -0.12065 0.3048)
			(stroke
				(width 0.1)
				(type default)
			)
			(layer "F.Fab")
		)
		(fp_line
			(start -0.12065 -0.2794)
			(end 0.12065 -0.2794)
			(stroke
				(width 0.1)
				(type default)
			)
			(layer "F.Fab")
		)
		(fp_line
			(start -0.12065 -0.305054)
			(end -0.12065 -0.2794)
			(stroke
				(width 0.1)
				(type default)
			)
			(layer "F.Fab")
		)
		(fp_line
			(start -0.67945 0.3048)
			(end -0.67945 -0.305054)
			(stroke
				(width 0.1)
				(type default)
			)
			(layer "F.Fab")
		)
		(fp_line
			(start -0.67945 -0.305054)
			(end -0.12065 -0.305054)
			(stroke
				(width 0.1)
				(type default)
			)
			(layer "F.Fab")
		)
		(pad "1" smd circle
			(at -0.40005 0 180)
			(size 0 0)
			(layers "F.Cu" "F.Mask" "F.Paste")
			(net "P3V3_AUX")
		)
		(pad "2" smd circle
			(at 0.40005 0 180)
			(size 0 0)
			(layers "F.Cu" "F.Mask" "F.Paste")
			(net "OCP_SFF_AUX_PWR_EN")
		)
	)
	(footprint ""
		(layer "F.Cu")
		(at 67.39001 -400.76882 180)
		(property "Reference" "C7004"
			(at -5.550662 -2.19583 90)
			(unlocked yes)
			(layer "F.SilkS")
			(effects
				(font
					(size 0.7874 0.5842)
					(thickness 0.1524)
				)
				(justify left)
			)
		)
		(property "Value" ""
			(at 0 0 180)
			(layer "F.Fab")
			(effects
				(font
					(size 1.27 1.27)
				)
			)
		)
		(duplicate_pad_numbers_are_jumpers no)
		(fp_line
			(start 4.53898 2.15011)
			(end -4.53898 2.15011)
			(stroke
				(width 0.1524)
				(type default)
			)
			(layer "F.SilkS")
		)
		(fp_line
			(start 4.53898 -2.15011)
			(end 4.53898 2.15011)
			(stroke
				(width 0.1524)
				(type default)
			)
			(layer "F.SilkS")
		)
		(fp_line
			(start -4.53898 2.15011)
			(end -4.53898 -2.15011)
			(stroke
				(width 0.1524)
				(type default)
			)
			(layer "F.SilkS")
		)
		(fp_line
			(start -4.53898 -2.15011)
			(end 4.53898 -2.15011)
			(stroke
				(width 0.1524)
				(type default)
			)
			(layer "F.SilkS")
		)
		(fp_line
			(start -4.53898 -2.150618)
			(end -4.539742 2.152142)
			(stroke
				(width 0.1524)
				(type default)
			)
			(layer "F.SilkS")
		)
		(fp_line
			(start -4.69138 -2.150618)
			(end -4.692396 2.161032)
			(stroke
				(width 0.1524)
				(type default)
			)
			(layer "F.SilkS")
		)
		(fp_line
			(start -4.83108 2.150364)
			(end -4.447794 2.149348)
			(stroke
				(width 0.1524)
				(type default)
			)
			(layer "F.SilkS")
		)
		(fp_line
			(start -4.84378 -2.150618)
			(end -4.53898 -2.150618)
			(stroke
				(width 0.1524)
				(type default)
			)
			(layer "F.SilkS")
		)
		(fp_line
			(start -4.84378 -2.150618)
			(end -4.842256 2.163064)
			(stroke
				(width 0.1524)
				(type default)
			)
			(layer "F.SilkS")
		)
		(fp_line
			(start 3.64998 2.15011)
			(end -3.64998 2.15011)
			(stroke
				(width 0.1)
				(type default)
			)
			(layer "F.Fab")
		)
		(fp_line
			(start 3.64998 -2.15011)
			(end 3.64998 2.15011)
			(stroke
				(width 0.1)
				(type default)
			)
			(layer "F.Fab")
		)
		(fp_line
			(start -3.64998 2.15011)
			(end -3.64998 -2.15011)
			(stroke
				(width 0.1)
				(type default)
			)
			(layer "F.Fab")
		)
		(fp_line
			(start -3.64998 -2.15011)
			(end 3.64998 -2.15011)
			(stroke
				(width 0.1)
				(type default)
			)
			(layer "F.Fab")
		)
		(fp_text user "-"
			(at 2.763774 2.270252 180)
			(unlocked yes)
			(layer "F.SilkS")
			(effects
				(font
					(size 1.905 1.4224)
					(thickness 0.1524)
				)
				(justify left)
			)
		)
		(fp_text user "+"
			(at -4.553712 2.639822 180)
			(unlocked yes)
			(layer "F.SilkS")
			(effects
				(font
					(size 1.905 1.4224)
					(thickness 0.1524)
				)
				(justify left)
			)
		)
		(fp_text user "-"
			(at 4.313174 -0.094488 180)
			(unlocked yes)
			(layer "F.Fab")
			(effects
				(font
					(size 1.905 1.4224)
					(thickness 0.1524)
				)
				(justify left)
			)
		)
		(fp_text user "+"
			(at -6.214872 -0.337058 180)
			(unlocked yes)
			(layer "F.Fab")
			(effects
				(font
					(size 1.905 1.4224)
					(thickness 0.1524)
				)
				(justify left)
			)
		)
		(pad "1" smd rect
			(at -3.199892 0 180)
			(size 2.413 2.8194)
			(layers "F.Cu" "F.Mask" "F.Paste")
			(net "P0V9_CPU1_RT_2D")
		)
		(pad "2" smd rect
			(at 3.199892 0 180)
			(size 2.413 2.8194)
			(layers "F.Cu" "F.Mask" "F.Paste")
			(net "GND")
		)
	)
	(footprint ""
		(layer "F.Cu")
		(at 257.89128 -49.402746 180)
		(property "Reference" "R3943"
			(at 0 0 180)
			(layer "F.SilkS")
			(hide yes)
			(effects
				(font
					(size 1.27 1.27)
				)
			)
		)
		(property "Value" ""
			(at 0 0 180)
			(layer "F.Fab")
			(effects
				(font
					(size 1.27 1.27)
				)
			)
		)
		(duplicate_pad_numbers_are_jumpers no)
		(fp_line
			(start 0.7874 0.4064)
			(end -0.7874 0.4064)
			(stroke
				(width 0.1524)
				(type default)
			)
			(layer "F.SilkS")
		)
		(fp_line
			(start 0.7874 -0.4064)
			(end 0.7874 0.4064)
			(stroke
				(width 0.1524)
				(type default)
			)
			(layer "F.SilkS")
		)
		(fp_line
			(start -0.7874 0.4064)
			(end -0.7874 -0.4064)
			(stroke
				(width 0.1524)
				(type default)
			)
			(layer "F.SilkS")
		)
		(fp_line
			(start -0.7874 -0.4064)
			(end 0.7874 -0.4064)
			(stroke
				(width 0.1524)
				(type default)
			)
			(layer "F.SilkS")
		)
		(fp_line
			(start 0.67945 0.3048)
			(end 0.120396 0.3048)
			(stroke
				(width 0.1)
				(type default)
			)
			(layer "F.Fab")
		)
		(fp_line
			(start 0.67945 -0.3048)
			(end 0.67945 0.3048)
			(stroke
				(width 0.1)
				(type default)
			)
			(layer "F.Fab")
		)
		(fp_line
			(start 0.12065 -0.2794)
			(end 0.12065 -0.3048)
			(stroke
				(width 0.1)
				(type default)
			)
			(layer "F.Fab")
		)
		(fp_line
			(start 0.12065 -0.3048)
			(end 0.67945 -0.3048)
			(stroke
				(width 0.1)
				(type default)
			)
			(layer "F.Fab")
		)
		(fp_line
			(start 0.120396 0.3048)
			(end 0.120396 0.2794)
			(stroke
				(width 0.1)
				(type default)
			)
			(layer "F.Fab")
		)
		(fp_line
			(start 0.120396 0.2794)
			(end -0.12065 0.2794)
			(stroke
				(width 0.1)
				(type default)
			)
			(layer "F.Fab")
		)
		(fp_line
			(start -0.12065 0.3048)
			(end -0.67945 0.3048)
			(stroke
				(width 0.1)
				(type default)
			)
			(layer "F.Fab")
		)
		(fp_line
			(start -0.12065 0.2794)
			(end -0.12065 0.3048)
			(stroke
				(width 0.1)
				(type default)
			)
			(layer "F.Fab")
		)
		(fp_line
			(start -0.12065 -0.2794)
			(end 0.12065 -0.2794)
			(stroke
				(width 0.1)
				(type default)
			)
			(layer "F.Fab")
		)
		(fp_line
			(start -0.12065 -0.305054)
			(end -0.12065 -0.2794)
			(stroke
				(width 0.1)
				(type default)
			)
			(layer "F.Fab")
		)
		(fp_line
			(start -0.67945 0.3048)
			(end -0.67945 -0.305054)
			(stroke
				(width 0.1)
				(type default)
			)
			(layer "F.Fab")
		)
		(fp_line
			(start -0.67945 -0.305054)
			(end -0.12065 -0.305054)
			(stroke
				(width 0.1)
				(type default)
			)
			(layer "F.Fab")
		)
		(pad "1" smd circle
			(at -0.40005 0 180)
			(size 0 0)
			(layers "F.Cu" "F.Mask" "F.Paste")
			(net "E1S_0_P12V_EN")
		)
		(pad "2" smd circle
			(at 0.40005 0 180)
			(size 0 0)
			(layers "F.Cu" "F.Mask" "F.Paste")
			(net "P12V_E1S_EN_0_R2")
		)
	)
	(footprint ""
		(layer "F.Cu")
		(at 217.881962 -67.324478 180)
		(property "Reference" "PR3965"
			(at 0 0 180)
			(layer "F.SilkS")
			(hide yes)
			(effects
				(font
					(size 1.27 1.27)
				)
			)
		)
		(property "Value" ""
			(at 0 0 180)
			(layer "F.Fab")
			(effects
				(font
					(size 1.27 1.27)
				)
			)
		)
		(duplicate_pad_numbers_are_jumpers no)
		(fp_line
			(start 0.7874 0.4064)
			(end -0.7874 0.4064)
			(stroke
				(width 0.1524)
				(type default)
			)
			(layer "F.SilkS")
		)
		(fp_line
			(start 0.7874 -0.4064)
			(end 0.7874 0.4064)
			(stroke
				(width 0.1524)
				(type default)
			)
			(layer "F.SilkS")
		)
		(fp_line
			(start -0.7874 0.4064)
			(end -0.7874 -0.4064)
			(stroke
				(width 0.1524)
				(type default)
			)
			(layer "F.SilkS")
		)
		(fp_line
			(start -0.7874 -0.4064)
			(end 0.7874 -0.4064)
			(stroke
				(width 0.1524)
				(type default)
			)
			(layer "F.SilkS")
		)
		(fp_line
			(start 0.67945 0.3048)
			(end 0.120396 0.3048)
			(stroke
				(width 0.1)
				(type default)
			)
			(layer "F.Fab")
		)
		(fp_line
			(start 0.67945 -0.3048)
			(end 0.67945 0.3048)
			(stroke
				(width 0.1)
				(type default)
			)
			(layer "F.Fab")
		)
		(fp_line
			(start 0.12065 -0.2794)
			(end 0.12065 -0.3048)
			(stroke
				(width 0.1)
				(type default)
			)
			(layer "F.Fab")
		)
		(fp_line
			(start 0.12065 -0.3048)
			(end 0.67945 -0.3048)
			(stroke
				(width 0.1)
				(type default)
			)
			(layer "F.Fab")
		)
		(fp_line
			(start 0.120396 0.3048)
			(end 0.120396 0.2794)
			(stroke
				(width 0.1)
				(type default)
			)
			(layer "F.Fab")
		)
		(fp_line
			(start 0.120396 0.2794)
			(end -0.12065 0.2794)
			(stroke
				(width 0.1)
				(type default)
			)
			(layer "F.Fab")
		)
		(fp_line
			(start -0.12065 0.3048)
			(end -0.67945 0.3048)
			(stroke
				(width 0.1)
				(type default)
			)
			(layer "F.Fab")
		)
		(fp_line
			(start -0.12065 0.2794)
			(end -0.12065 0.3048)
			(stroke
				(width 0.1)
				(type default)
			)
			(layer "F.Fab")
		)
		(fp_line
			(start -0.12065 -0.2794)
			(end 0.12065 -0.2794)
			(stroke
				(width 0.1)
				(type default)
			)
			(layer "F.Fab")
		)
		(fp_line
			(start -0.12065 -0.305054)
			(end -0.12065 -0.2794)
			(stroke
				(width 0.1)
				(type default)
			)
			(layer "F.Fab")
		)
		(fp_line
			(start -0.67945 0.3048)
			(end -0.67945 -0.305054)
			(stroke
				(width 0.1)
				(type default)
			)
			(layer "F.Fab")
		)
		(fp_line
			(start -0.67945 -0.305054)
			(end -0.12065 -0.305054)
			(stroke
				(width 0.1)
				(type default)
			)
			(layer "F.Fab")
		)
		(pad "1" smd circle
			(at -0.40005 0 180)
			(size 0 0)
			(layers "F.Cu" "F.Mask" "F.Paste")
			(net "P3V3_E1S_OV_0")
		)
		(pad "2" smd circle
			(at 0.40005 0 180)
			(size 0 0)
			(layers "F.Cu" "F.Mask" "F.Paste")
			(net "GND")
		)
	)
	(footprint ""
		(layer "F.Cu")
		(at 136.188958 -62.28207 90)
		(property "Reference" "C194"
			(at 0 0 90)
			(layer "F.SilkS")
			(hide yes)
			(effects
				(font
					(size 1.27 1.27)
				)
			)
		)
		(property "Value" ""
			(at 0 0 90)
			(layer "F.Fab")
			(effects
				(font
					(size 1.27 1.27)
				)
			)
		)
		(duplicate_pad_numbers_are_jumpers no)
		(fp_line
			(start 0.7874 -0.4064)
			(end 0.7874 0.4064)
			(stroke
				(width 0.1524)
				(type default)
			)
			(layer "F.SilkS")
		)
		(fp_line
			(start -0.7874 -0.4064)
			(end 0.7874 -0.4064)
			(stroke
				(width 0.1524)
				(type default)
			)
			(layer "F.SilkS")
		)
		(fp_line
			(start 0.7874 0.4064)
			(end -0.7874 0.4064)
			(stroke
				(width 0.1524)
				(type default)
			)
			(layer "F.SilkS")
		)
		(fp_line
			(start -0.7874 0.4064)
			(end -0.7874 -0.4064)
			(stroke
				(width 0.1524)
				(type default)
			)
			(layer "F.SilkS")
		)
		(fp_line
			(start -0.12065 -0.305054)
			(end -0.12065 -0.2794)
			(stroke
				(width 0.1)
				(type default)
			)
			(layer "F.Fab")
		)
		(fp_line
			(start -0.67945 -0.305054)
			(end -0.12065 -0.305054)
			(stroke
				(width 0.1)
				(type default)
			)
			(layer "F.Fab")
		)
		(fp_line
			(start 0.67945 -0.3048)
			(end 0.67945 0.3048)
			(stroke
				(width 0.1)
				(type default)
			)
			(layer "F.Fab")
		)
		(fp_line
			(start 0.12065 -0.3048)
			(end 0.67945 -0.3048)
			(stroke
				(width 0.1)
				(type default)
			)
			(layer "F.Fab")
		)
		(fp_line
			(start 0.12065 -0.2794)
			(end 0.12065 -0.3048)
			(stroke
				(width 0.1)
				(type default)
			)
			(layer "F.Fab")
		)
		(fp_line
			(start -0.12065 -0.2794)
			(end 0.12065 -0.2794)
			(stroke
				(width 0.1)
				(type default)
			)
			(layer "F.Fab")
		)
		(fp_line
			(start 0.120396 0.2794)
			(end -0.12065 0.2794)
			(stroke
				(width 0.1)
				(type default)
			)
			(layer "F.Fab")
		)
		(fp_line
			(start -0.12065 0.2794)
			(end -0.12065 0.3048)
			(stroke
				(width 0.1)
				(type default)
			)
			(layer "F.Fab")
		)
		(fp_line
			(start 0.67945 0.3048)
			(end 0.120396 0.3048)
			(stroke
				(width 0.1)
				(type default)
			)
			(layer "F.Fab")
		)
		(fp_line
			(start 0.120396 0.3048)
			(end 0.120396 0.2794)
			(stroke
				(width 0.1)
				(type default)
			)
			(layer "F.Fab")
		)
		(fp_line
			(start -0.12065 0.3048)
			(end -0.67945 0.3048)
			(stroke
				(width 0.1)
				(type default)
			)
			(layer "F.Fab")
		)
		(fp_line
			(start -0.67945 0.3048)
			(end -0.67945 -0.305054)
			(stroke
				(width 0.1)
				(type default)
			)
			(layer "F.Fab")
		)
		(pad "1" smd circle
			(at -0.40005 0 90)
			(size 0 0)
			(layers "F.Cu" "F.Mask" "F.Paste")
			(net "P3V3_AUX")
		)
		(pad "2" smd circle
			(at 0.40005 0 90)
			(size 0 0)
			(layers "F.Cu" "F.Mask" "F.Paste")
			(net "GND")
		)
	)
	(footprint ""
		(layer "F.Cu")
		(at 45.605954 -370.57203 -90)
		(property "Reference" "C830"
			(at 0 0 270)
			(layer "F.SilkS")
			(hide yes)
			(effects
				(font
					(size 1.27 1.27)
				)
			)
		)
		(property "Value" ""
			(at 0 0 270)
			(layer "F.Fab")
			(effects
				(font
					(size 1.27 1.27)
				)
			)
		)
		(duplicate_pad_numbers_are_jumpers no)
		(fp_line
			(start -0.299974 0.150114)
			(end -0.299974 -0.150114)
			(stroke
				(width 0.1)
				(type default)
			)
			(layer "F.Fab")
		)
		(fp_line
			(start 0.299974 0.150114)
			(end -0.299974 0.150114)
			(stroke
				(width 0.1)
				(type default)
			)
			(layer "F.Fab")
		)
		(fp_line
			(start -0.299974 -0.150114)
			(end 0.299974 -0.150114)
			(stroke
				(width 0.1)
				(type default)
			)
			(layer "F.Fab")
		)
		(fp_line
			(start 0.299974 -0.150114)
			(end 0.299974 0.150114)
			(stroke
				(width 0.1)
				(type default)
			)
			(layer "F.Fab")
		)
		(pad "1" smd rect
			(at -0.2667 0 270)
			(size 0.3048 0.381)
			(layers "F.Cu" "F.Mask" "F.Paste")
			(net "P5E_CPU1_P0_TX_C_DN<3>")
		)
		(pad "2" smd rect
			(at 0.2667 0 270)
			(size 0.3048 0.381)
			(layers "F.Cu" "F.Mask" "F.Paste")
			(net "P5E_CPU1_P0_TX_DN<3>")
		)
	)
	(footprint ""
		(layer "F.Cu")
		(at 386.211826 -54.1655 180)
		(property "Reference" "R1353"
			(at 0 0 180)
			(layer "F.SilkS")
			(hide yes)
			(effects
				(font
					(size 1.27 1.27)
				)
			)
		)
		(property "Value" ""
			(at 0 0 180)
			(layer "F.Fab")
			(effects
				(font
					(size 1.27 1.27)
				)
			)
		)
		(duplicate_pad_numbers_are_jumpers no)
		(fp_line
			(start 0.7874 0.4064)
			(end -0.7874 0.4064)
			(stroke
				(width 0.1524)
				(type default)
			)
			(layer "F.SilkS")
		)
		(fp_line
			(start 0.7874 -0.4064)
			(end 0.7874 0.4064)
			(stroke
				(width 0.1524)
				(type default)
			)
			(layer "F.SilkS")
		)
		(fp_line
			(start -0.7874 0.4064)
			(end -0.7874 -0.4064)
			(stroke
				(width 0.1524)
				(type default)
			)
			(layer "F.SilkS")
		)
		(fp_line
			(start -0.7874 -0.4064)
			(end 0.7874 -0.4064)
			(stroke
				(width 0.1524)
				(type default)
			)
			(layer "F.SilkS")
		)
		(fp_line
			(start 0.67945 0.3048)
			(end 0.120396 0.3048)
			(stroke
				(width 0.1)
				(type default)
			)
			(layer "F.Fab")
		)
		(fp_line
			(start 0.67945 -0.3048)
			(end 0.67945 0.3048)
			(stroke
				(width 0.1)
				(type default)
			)
			(layer "F.Fab")
		)
		(fp_line
			(start 0.12065 -0.2794)
			(end 0.12065 -0.3048)
			(stroke
				(width 0.1)
				(type default)
			)
			(layer "F.Fab")
		)
		(fp_line
			(start 0.12065 -0.3048)
			(end 0.67945 -0.3048)
			(stroke
				(width 0.1)
				(type default)
			)
			(layer "F.Fab")
		)
		(fp_line
			(start 0.120396 0.3048)
			(end 0.120396 0.2794)
			(stroke
				(width 0.1)
				(type default)
			)
			(layer "F.Fab")
		)
		(fp_line
			(start 0.120396 0.2794)
			(end -0.12065 0.2794)
			(stroke
				(width 0.1)
				(type default)
			)
			(layer "F.Fab")
		)
		(fp_line
			(start -0.12065 0.3048)
			(end -0.67945 0.3048)
			(stroke
				(width 0.1)
				(type default)
			)
			(layer "F.Fab")
		)
		(fp_line
			(start -0.12065 0.2794)
			(end -0.12065 0.3048)
			(stroke
				(width 0.1)
				(type default)
			)
			(layer "F.Fab")
		)
		(fp_line
			(start -0.12065 -0.2794)
			(end 0.12065 -0.2794)
			(stroke
				(width 0.1)
				(type default)
			)
			(layer "F.Fab")
		)
		(fp_line
			(start -0.12065 -0.305054)
			(end -0.12065 -0.2794)
			(stroke
				(width 0.1)
				(type default)
			)
			(layer "F.Fab")
		)
		(fp_line
			(start -0.67945 0.3048)
			(end -0.67945 -0.305054)
			(stroke
				(width 0.1)
				(type default)
			)
			(layer "F.Fab")
		)
		(fp_line
			(start -0.67945 -0.305054)
			(end -0.12065 -0.305054)
			(stroke
				(width 0.1)
				(type default)
			)
			(layer "F.Fab")
		)
		(pad "1" smd circle
			(at -0.40005 0 180)
			(size 0 0)
			(layers "F.Cu" "F.Mask" "F.Paste")
			(net "HDT_HDR_R_TMS")
		)
		(pad "2" smd circle
			(at 0.40005 0 180)
			(size 0 0)
			(layers "F.Cu" "F.Mask" "F.Paste")
			(net "HDT_HDR_TMS")
		)
	)
	(footprint ""
		(layer "F.Cu")
		(at 243.961158 -380.66853)
		(property "Reference" "PR2535"
			(at 0 0 0)
			(layer "F.SilkS")
			(hide yes)
			(effects
				(font
					(size 1.27 1.27)
				)
			)
		)
		(property "Value" ""
			(at 0 0 0)
			(layer "F.Fab")
			(effects
				(font
					(size 1.27 1.27)
				)
			)
		)
		(duplicate_pad_numbers_are_jumpers no)
		(fp_line
			(start -0.7874 -0.4064)
			(end 0.7874 -0.4064)
			(stroke
				(width 0.1524)
				(type default)
			)
			(layer "F.SilkS")
		)
		(fp_line
			(start -0.7874 0.4064)
			(end -0.7874 -0.4064)
			(stroke
				(width 0.1524)
				(type default)
			)
			(layer "F.SilkS")
		)
		(fp_line
			(start 0.7874 -0.4064)
			(end 0.7874 0.4064)
			(stroke
				(width 0.1524)
				(type default)
			)
			(layer "F.SilkS")
		)
		(fp_line
			(start 0.7874 0.4064)
			(end -0.7874 0.4064)
			(stroke
				(width 0.1524)
				(type default)
			)
			(layer "F.SilkS")
		)
		(fp_line
			(start -0.67945 -0.305054)
			(end -0.12065 -0.305054)
			(stroke
				(width 0.1)
				(type default)
			)
			(layer "F.Fab")
		)
		(fp_line
			(start -0.67945 0.3048)
			(end -0.67945 -0.305054)
			(stroke
				(width 0.1)
				(type default)
			)
			(layer "F.Fab")
		)
		(fp_line
			(start -0.12065 -0.305054)
			(end -0.12065 -0.2794)
			(stroke
				(width 0.1)
				(type default)
			)
			(layer "F.Fab")
		)
		(fp_line
			(start -0.12065 -0.2794)
			(end 0.12065 -0.2794)
			(stroke
				(width 0.1)
				(type default)
			)
			(layer "F.Fab")
		)
		(fp_line
			(start -0.12065 0.2794)
			(end -0.12065 0.3048)
			(stroke
				(width 0.1)
				(type default)
			)
			(layer "F.Fab")
		)
		(fp_line
			(start -0.12065 0.3048)
			(end -0.67945 0.3048)
			(stroke
				(width 0.1)
				(type default)
			)
			(layer "F.Fab")
		)
		(fp_line
			(start 0.120396 0.2794)
			(end -0.12065 0.2794)
			(stroke
				(width 0.1)
				(type default)
			)
			(layer "F.Fab")
		)
		(fp_line
			(start 0.120396 0.3048)
			(end 0.120396 0.2794)
			(stroke
				(width 0.1)
				(type default)
			)
			(layer "F.Fab")
		)
		(fp_line
			(start 0.12065 -0.3048)
			(end 0.67945 -0.3048)
			(stroke
				(width 0.1)
				(type default)
			)
			(layer "F.Fab")
		)
		(fp_line
			(start 0.12065 -0.2794)
			(end 0.12065 -0.3048)
			(stroke
				(width 0.1)
				(type default)
			)
			(layer "F.Fab")
		)
		(fp_line
			(start 0.67945 -0.3048)
			(end 0.67945 0.3048)
			(stroke
				(width 0.1)
				(type default)
			)
			(layer "F.Fab")
		)
		(fp_line
			(start 0.67945 0.3048)
			(end 0.120396 0.3048)
			(stroke
				(width 0.1)
				(type default)
			)
			(layer "F.Fab")
		)
		(pad "1" smd circle
			(at -0.40005 0)
			(size 0 0)
			(layers "F.Cu" "F.Mask" "F.Paste")
			(net "P12V_HSC_GATE_G5")
		)
		(pad "2" smd circle
			(at 0.40005 0)
			(size 0 0)
			(layers "F.Cu" "F.Mask" "F.Paste")
			(net "P12V_HSC_GATE2")
		)
	)
	(footprint ""
		(layer "F.Cu")
		(at 299.265594 -392.1252)
		(property "Reference" "R995"
			(at 0 0 0)
			(layer "F.SilkS")
			(hide yes)
			(effects
				(font
					(size 1.27 1.27)
				)
			)
		)
		(property "Value" ""
			(at 0 0 0)
			(layer "F.Fab")
			(effects
				(font
					(size 1.27 1.27)
				)
			)
		)
		(duplicate_pad_numbers_are_jumpers no)
		(fp_line
			(start -0.32512 -0.175006)
			(end 0.32512 -0.175006)
			(stroke
				(width 0.1)
				(type default)
			)
			(layer "F.Fab")
		)
		(fp_line
			(start -0.32512 0.175006)
			(end -0.32512 -0.175006)
			(stroke
				(width 0.1)
				(type default)
			)
			(layer "F.Fab")
		)
		(fp_line
			(start 0.32512 -0.175006)
			(end 0.32512 0.175006)
			(stroke
				(width 0.1)
				(type default)
			)
			(layer "F.Fab")
		)
		(fp_line
			(start 0.32512 0.175006)
			(end -0.32512 0.175006)
			(stroke
				(width 0.1)
				(type default)
			)
			(layer "F.Fab")
		)
		(pad "1" smd rect
			(at -0.2667 0)
			(size 0.3048 0.381)
			(layers "F.Cu" "F.Mask" "F.Paste")
			(net "TEST2_RT_CPU0_P0")
		)
		(pad "2" smd rect
			(at 0.2667 0 180)
			(size 0.3048 0.381)
			(layers "F.Cu" "F.Mask" "F.Paste")
			(net "GND")
		)
	)
	(footprint ""
		(layer "F.Cu")
		(at 100.442522 -410.672788)
		(property "Reference" "L2"
			(at 0 0 0)
			(layer "F.SilkS")
			(hide yes)
			(effects
				(font
					(size 1.27 1.27)
				)
			)
		)
		(property "Value" ""
			(at 0 0 0)
			(layer "F.Fab")
			(effects
				(font
					(size 1.27 1.27)
				)
			)
		)
		(duplicate_pad_numbers_are_jumpers no)
		(fp_line
			(start -1.63576 -0.8128)
			(end -1.63576 0.8128)
			(stroke
				(width 0.1524)
				(type default)
			)
			(layer "F.SilkS")
		)
		(fp_line
			(start -1.63576 -0.8128)
			(end 1.63576 -0.8128)
			(stroke
				(width 0.1524)
				(type default)
			)
			(layer "F.SilkS")
		)
		(fp_line
			(start 1.63576 -0.8128)
			(end 1.63576 0.8128)
			(stroke
				(width 0.1524)
				(type default)
			)
			(layer "F.SilkS")
		)
		(fp_line
			(start 1.63576 0.8128)
			(end -1.63576 0.8128)
			(stroke
				(width 0.1524)
				(type default)
			)
			(layer "F.SilkS")
		)
		(fp_line
			(start -1.56083 -0.738632)
			(end -1.56083 0.7366)
			(stroke
				(width 0.1)
				(type default)
			)
			(layer "F.Fab")
		)
		(fp_line
			(start -1.56083 0.7366)
			(end -1.524 0.7366)
			(stroke
				(width 0.1)
				(type default)
			)
			(layer "F.Fab")
		)
		(fp_line
			(start -1.524 0.7366)
			(end 1.524 0.7366)
			(stroke
				(width 0.1)
				(type default)
			)
			(layer "F.Fab")
		)
		(fp_line
			(start 1.524 0.7366)
			(end 1.560576 0.7366)
			(stroke
				(width 0.1)
				(type default)
			)
			(layer "F.Fab")
		)
		(fp_line
			(start 1.560576 -0.738632)
			(end -1.56083 -0.738632)
			(stroke
				(width 0.1)
				(type default)
			)
			(layer "F.Fab")
		)
		(fp_line
			(start 1.560576 0.7366)
			(end 1.560576 -0.738632)
			(stroke
				(width 0.1)
				(type default)
			)
			(layer "F.Fab")
		)
		(pad "1" smd rect
			(at -0.94996 0 180)
			(size 1.1176 1.3716)
			(layers "F.Cu" "F.Mask" "F.Paste")
			(net "P3V3_AUX")
		)
		(pad "2" smd rect
			(at 0.94996 0 180)
			(size 1.1176 1.3716)
			(layers "F.Cu" "F.Mask" "F.Paste")
			(net "P3V3_9ZXL045_P1_VDD")
		)
	)
	(footprint ""
		(layer "F.Cu")
		(at 365.835692 -259.355082 180)
		(property "Reference" "C2157"
			(at 0 0 180)
			(layer "F.SilkS")
			(hide yes)
			(effects
				(font
					(size 1.27 1.27)
				)
			)
		)
		(property "Value" ""
			(at 0 0 180)
			(layer "F.Fab")
			(effects
				(font
					(size 1.27 1.27)
				)
			)
		)
		(duplicate_pad_numbers_are_jumpers no)
		(fp_line
			(start 0.7874 0.4064)
			(end -0.7874 0.4064)
			(stroke
				(width 0.1524)
				(type default)
			)
			(layer "F.SilkS")
		)
		(fp_line
			(start 0.7874 -0.4064)
			(end 0.7874 0.4064)
			(stroke
				(width 0.1524)
				(type default)
			)
			(layer "F.SilkS")
		)
		(fp_line
			(start -0.7874 0.4064)
			(end -0.7874 -0.4064)
			(stroke
				(width 0.1524)
				(type default)
			)
			(layer "F.SilkS")
		)
		(fp_line
			(start -0.7874 -0.4064)
			(end 0.7874 -0.4064)
			(stroke
				(width 0.1524)
				(type default)
			)
			(layer "F.SilkS")
		)
		(fp_line
			(start 0.67945 0.3048)
			(end 0.120396 0.3048)
			(stroke
				(width 0.1)
				(type default)
			)
			(layer "F.Fab")
		)
		(fp_line
			(start 0.67945 -0.3048)
			(end 0.67945 0.3048)
			(stroke
				(width 0.1)
				(type default)
			)
			(layer "F.Fab")
		)
		(fp_line
			(start 0.12065 -0.2794)
			(end 0.12065 -0.3048)
			(stroke
				(width 0.1)
				(type default)
			)
			(layer "F.Fab")
		)
		(fp_line
			(start 0.12065 -0.3048)
			(end 0.67945 -0.3048)
			(stroke
				(width 0.1)
				(type default)
			)
			(layer "F.Fab")
		)
		(fp_line
			(start 0.120396 0.3048)
			(end 0.120396 0.2794)
			(stroke
				(width 0.1)
				(type default)
			)
			(layer "F.Fab")
		)
		(fp_line
			(start 0.120396 0.2794)
			(end -0.12065 0.2794)
			(stroke
				(width 0.1)
				(type default)
			)
			(layer "F.Fab")
		)
		(fp_line
			(start -0.12065 0.3048)
			(end -0.67945 0.3048)
			(stroke
				(width 0.1)
				(type default)
			)
			(layer "F.Fab")
		)
		(fp_line
			(start -0.12065 0.2794)
			(end -0.12065 0.3048)
			(stroke
				(width 0.1)
				(type default)
			)
			(layer "F.Fab")
		)
		(fp_line
			(start -0.12065 -0.2794)
			(end 0.12065 -0.2794)
			(stroke
				(width 0.1)
				(type default)
			)
			(layer "F.Fab")
		)
		(fp_line
			(start -0.12065 -0.305054)
			(end -0.12065 -0.2794)
			(stroke
				(width 0.1)
				(type default)
			)
			(layer "F.Fab")
		)
		(fp_line
			(start -0.67945 0.3048)
			(end -0.67945 -0.305054)
			(stroke
				(width 0.1)
				(type default)
			)
			(layer "F.Fab")
		)
		(fp_line
			(start -0.67945 -0.305054)
			(end -0.12065 -0.305054)
			(stroke
				(width 0.1)
				(type default)
			)
			(layer "F.Fab")
		)
		(pad "1" smd circle
			(at -0.40005 0 180)
			(size 0 0)
			(layers "F.Cu" "F.Mask" "F.Paste")
			(net "PVDDCR_SOC_P0")
		)
		(pad "2" smd circle
			(at 0.40005 0 180)
			(size 0 0)
			(layers "F.Cu" "F.Mask" "F.Paste")
			(net "GND")
		)
	)
	(footprint ""
		(layer "F.Cu")
		(at 65.193164 -17.227804 180)
		(property "Reference" "C1829"
			(at 0 0 180)
			(layer "F.SilkS")
			(hide yes)
			(effects
				(font
					(size 1.27 1.27)
				)
			)
		)
		(property "Value" ""
			(at 0 0 180)
			(layer "F.Fab")
			(effects
				(font
					(size 1.27 1.27)
				)
			)
		)
		(duplicate_pad_numbers_are_jumpers no)
		(fp_line
			(start 1.524 0.762)
			(end -1.524 0.762)
			(stroke
				(width 0.1524)
				(type default)
			)
			(layer "F.SilkS")
		)
		(fp_line
			(start 1.524 -0.762)
			(end 1.524 0.762)
			(stroke
				(width 0.1524)
				(type default)
			)
			(layer "F.SilkS")
		)
		(fp_line
			(start -1.524 0.762)
			(end -1.524 -0.762)
			(stroke
				(width 0.1524)
				(type default)
			)
			(layer "F.SilkS")
		)
		(fp_line
			(start -1.524 -0.762)
			(end 1.524 -0.762)
			(stroke
				(width 0.1524)
				(type default)
			)
			(layer "F.SilkS")
		)
		(fp_line
			(start 1.1049 0.724916)
			(end 1.1049 -0.724916)
			(stroke
				(width 0.1)
				(type default)
			)
			(layer "F.Fab")
		)
		(fp_line
			(start 1.1049 -0.724916)
			(end -1.1049 -0.724916)
			(stroke
				(width 0.1)
				(type default)
			)
			(layer "F.Fab")
		)
		(fp_line
			(start -1.1049 0.724916)
			(end 1.1049 0.724916)
			(stroke
				(width 0.1)
				(type default)
			)
			(layer "F.Fab")
		)
		(fp_line
			(start -1.1049 -0.724916)
			(end -1.1049 0.724916)
			(stroke
				(width 0.1)
				(type default)
			)
			(layer "F.Fab")
		)
		(pad "1" smd rect
			(at -0.889 0)
			(size 1.016 1.27)
			(layers "F.Cu" "F.Mask" "F.Paste")
			(net "P12V_OCP_V3_2_R")
		)
		(pad "2" smd rect
			(at 0.889 0)
			(size 1.016 1.27)
			(layers "F.Cu" "F.Mask" "F.Paste")
			(net "GND")
		)
	)
	(footprint ""
		(layer "F.Cu")
		(at 116.158518 -395.340586 -90)
		(property "Reference" "R912"
			(at 0 0 270)
			(layer "F.SilkS")
			(hide yes)
			(effects
				(font
					(size 1.27 1.27)
				)
			)
		)
		(property "Value" ""
			(at 0 0 270)
			(layer "F.Fab")
			(effects
				(font
					(size 1.27 1.27)
				)
			)
		)
		(duplicate_pad_numbers_are_jumpers no)
		(fp_line
			(start -0.32512 0.175006)
			(end -0.32512 -0.175006)
			(stroke
				(width 0.1)
				(type default)
			)
			(layer "F.Fab")
		)
		(fp_line
			(start 0.32512 0.175006)
			(end -0.32512 0.175006)
			(stroke
				(width 0.1)
				(type default)
			)
			(layer "F.Fab")
		)
		(fp_line
			(start -0.32512 -0.175006)
			(end 0.32512 -0.175006)
			(stroke
				(width 0.1)
				(type default)
			)
			(layer "F.Fab")
		)
		(fp_line
			(start 0.32512 -0.175006)
			(end 0.32512 0.175006)
			(stroke
				(width 0.1)
				(type default)
			)
			(layer "F.Fab")
		)
		(pad "1" smd rect
			(at -0.2667 0 270)
			(size 0.3048 0.381)
			(layers "F.Cu" "F.Mask" "F.Paste")
			(net "P1V8_CPU1_RT_1D")
		)
		(pad "2" smd rect
			(at 0.2667 0 90)
			(size 0.3048 0.381)
			(layers "F.Cu" "F.Mask" "F.Paste")
			(net "JTAG_TEST_MODE_RT_CPU1_P3")
		)
	)
	(footprint ""
		(layer "F.Cu")
		(at 120.69826 -31.405576)
		(property "Reference" "R6269"
			(at 0 0 0)
			(layer "F.SilkS")
			(hide yes)
			(effects
				(font
					(size 1.27 1.27)
				)
			)
		)
		(property "Value" ""
			(at 0 0 0)
			(layer "F.Fab")
			(effects
				(font
					(size 1.27 1.27)
				)
			)
		)
		(duplicate_pad_numbers_are_jumpers no)
		(fp_line
			(start -0.7874 -0.4064)
			(end 0.7874 -0.4064)
			(stroke
				(width 0.1524)
				(type default)
			)
			(layer "F.SilkS")
		)
		(fp_line
			(start -0.7874 0.4064)
			(end -0.7874 -0.4064)
			(stroke
				(width 0.1524)
				(type default)
			)
			(layer "F.SilkS")
		)
		(fp_line
			(start 0.7874 -0.4064)
			(end 0.7874 0.4064)
			(stroke
				(width 0.1524)
				(type default)
			)
			(layer "F.SilkS")
		)
		(fp_line
			(start 0.7874 0.4064)
			(end -0.7874 0.4064)
			(stroke
				(width 0.1524)
				(type default)
			)
			(layer "F.SilkS")
		)
		(fp_line
			(start -0.67945 -0.305054)
			(end -0.12065 -0.305054)
			(stroke
				(width 0.1)
				(type default)
			)
			(layer "F.Fab")
		)
		(fp_line
			(start -0.67945 0.3048)
			(end -0.67945 -0.305054)
			(stroke
				(width 0.1)
				(type default)
			)
			(layer "F.Fab")
		)
		(fp_line
			(start -0.12065 -0.305054)
			(end -0.12065 -0.2794)
			(stroke
				(width 0.1)
				(type default)
			)
			(layer "F.Fab")
		)
		(fp_line
			(start -0.12065 -0.2794)
			(end 0.12065 -0.2794)
			(stroke
				(width 0.1)
				(type default)
			)
			(layer "F.Fab")
		)
		(fp_line
			(start -0.12065 0.2794)
			(end -0.12065 0.3048)
			(stroke
				(width 0.1)
				(type default)
			)
			(layer "F.Fab")
		)
		(fp_line
			(start -0.12065 0.3048)
			(end -0.67945 0.3048)
			(stroke
				(width 0.1)
				(type default)
			)
			(layer "F.Fab")
		)
		(fp_line
			(start 0.120396 0.2794)
			(end -0.12065 0.2794)
			(stroke
				(width 0.1)
				(type default)
			)
			(layer "F.Fab")
		)
		(fp_line
			(start 0.120396 0.3048)
			(end 0.120396 0.2794)
			(stroke
				(width 0.1)
				(type default)
			)
			(layer "F.Fab")
		)
		(fp_line
			(start 0.12065 -0.3048)
			(end 0.67945 -0.3048)
			(stroke
				(width 0.1)
				(type default)
			)
			(layer "F.Fab")
		)
		(fp_line
			(start 0.12065 -0.2794)
			(end 0.12065 -0.3048)
			(stroke
				(width 0.1)
				(type default)
			)
			(layer "F.Fab")
		)
		(fp_line
			(start 0.67945 -0.3048)
			(end 0.67945 0.3048)
			(stroke
				(width 0.1)
				(type default)
			)
			(layer "F.Fab")
		)
		(fp_line
			(start 0.67945 0.3048)
			(end 0.120396 0.3048)
			(stroke
				(width 0.1)
				(type default)
			)
			(layer "F.Fab")
		)
		(pad "1" smd circle
			(at -0.40005 0)
			(size 0 0)
			(layers "F.Cu" "F.Mask" "F.Paste")
			(net "USB_HUB2_TI_VDD_MRP_USB3DN_RXDP4")
		)
		(pad "2" smd circle
			(at 0.40005 0)
			(size 0 0)
			(layers "F.Cu" "F.Mask" "F.Paste")
			(net "P1V2_CPU0_USB2_DVDD12")
		)
	)
	(footprint ""
		(layer "F.Cu")
		(at 363.554772 -173.119542 -90)
		(property "Reference" "PR322"
			(at 0 0 270)
			(layer "F.SilkS")
			(hide yes)
			(effects
				(font
					(size 1.27 1.27)
				)
			)
		)
		(property "Value" ""
			(at 0 0 270)
			(layer "F.Fab")
			(effects
				(font
					(size 1.27 1.27)
				)
			)
		)
		(duplicate_pad_numbers_are_jumpers no)
		(fp_line
			(start -0.7874 0.4064)
			(end -0.7874 -0.4064)
			(stroke
				(width 0.1524)
				(type default)
			)
			(layer "F.SilkS")
		)
		(fp_line
			(start 0.7874 0.4064)
			(end -0.7874 0.4064)
			(stroke
				(width 0.1524)
				(type default)
			)
			(layer "F.SilkS")
		)
		(fp_line
			(start -0.7874 -0.4064)
			(end 0.7874 -0.4064)
			(stroke
				(width 0.1524)
				(type default)
			)
			(layer "F.SilkS")
		)
		(fp_line
			(start 0.7874 -0.4064)
			(end 0.7874 0.4064)
			(stroke
				(width 0.1524)
				(type default)
			)
			(layer "F.SilkS")
		)
		(fp_line
			(start -0.67945 0.3048)
			(end -0.67945 -0.305054)
			(stroke
				(width 0.1)
				(type default)
			)
			(layer "F.Fab")
		)
		(fp_line
			(start -0.12065 0.3048)
			(end -0.67945 0.3048)
			(stroke
				(width 0.1)
				(type default)
			)
			(layer "F.Fab")
		)
		(fp_line
			(start 0.120396 0.3048)
			(end 0.120396 0.2794)
			(stroke
				(width 0.1)
				(type default)
			)
			(layer "F.Fab")
		)
		(fp_line
			(start 0.67945 0.3048)
			(end 0.120396 0.3048)
			(stroke
				(width 0.1)
				(type default)
			)
			(layer "F.Fab")
		)
		(fp_line
			(start -0.12065 0.2794)
			(end -0.12065 0.3048)
			(stroke
				(width 0.1)
				(type default)
			)
			(layer "F.Fab")
		)
		(fp_line
			(start 0.120396 0.2794)
			(end -0.12065 0.2794)
			(stroke
				(width 0.1)
				(type default)
			)
			(layer "F.Fab")
		)
		(fp_line
			(start -0.12065 -0.2794)
			(end 0.12065 -0.2794)
			(stroke
				(width 0.1)
				(type default)
			)
			(layer "F.Fab")
		)
		(fp_line
			(start 0.12065 -0.2794)
			(end 0.12065 -0.3048)
			(stroke
				(width 0.1)
				(type default)
			)
			(layer "F.Fab")
		)
		(fp_line
			(start 0.12065 -0.3048)
			(end 0.67945 -0.3048)
			(stroke
				(width 0.1)
				(type default)
			)
			(layer "F.Fab")
		)
		(fp_line
			(start 0.67945 -0.3048)
			(end 0.67945 0.3048)
			(stroke
				(width 0.1)
				(type default)
			)
			(layer "F.Fab")
		)
		(fp_line
			(start -0.67945 -0.305054)
			(end -0.12065 -0.305054)
			(stroke
				(width 0.1)
				(type default)
			)
			(layer "F.Fab")
		)
		(fp_line
			(start -0.12065 -0.305054)
			(end -0.12065 -0.2794)
			(stroke
				(width 0.1)
				(type default)
			)
			(layer "F.Fab")
		)
		(pad "1" smd circle
			(at -0.40005 0 270)
			(size 0 0)
			(layers "F.Cu" "F.Mask" "F.Paste")
			(net "SW_PVDDCR_CPU0_P0_BOOT1")
		)
		(pad "2" smd circle
			(at 0.40005 0 270)
			(size 0 0)
			(layers "F.Cu" "F.Mask" "F.Paste")
			(net "SW_PVDDCR_CPU0_P0_BOOT1_RC")
		)
	)
	(footprint ""
		(layer "F.Cu")
		(at 49.12868 -29.657548 90)
		(property "Reference" "U286"
			(at -2.56286 -1.925828 90)
			(unlocked yes)
			(layer "F.SilkS")
			(effects
				(font
					(size 0.7874 0.5842)
					(thickness 0.1524)
				)
				(justify left)
			)
		)
		(property "Value" ""
			(at 0 0 90)
			(layer "F.Fab")
			(effects
				(font
					(size 1.27 1.27)
				)
			)
		)
		(duplicate_pad_numbers_are_jumpers no)
		(fp_line
			(start 1.400048 -1.100074)
			(end -1.400048 -1.100074)
			(stroke
				(width 0.1524)
				(type default)
			)
			(layer "F.SilkS")
		)
		(fp_line
			(start 1.400048 -1.100074)
			(end 1.400048 1.100074)
			(stroke
				(width 0.1524)
				(type default)
			)
			(layer "F.SilkS")
		)
		(fp_line
			(start 1.400048 1.100074)
			(end -1.400048 1.100074)
			(stroke
				(width 0.1524)
				(type default)
			)
			(layer "F.SilkS")
		)
		(fp_line
			(start -1.400048 1.100074)
			(end -1.400048 -1.100074)
			(stroke
				(width 0.1524)
				(type default)
			)
			(layer "F.SilkS")
		)
		(fp_poly
			(pts
				(xy -2.606548 -0.141986) (xy -2.606548 -1.157986) (xy -1.590548 -0.649986)
			)
			(stroke
				(width 0)
				(type default)
			)
			(fill yes)
			(layer "F.SilkS")
		)
		(fp_line
			(start 0.674878 -1.100074)
			(end 0.674878 1.100074)
			(stroke
				(width 0.1)
				(type default)
			)
			(layer "F.Fab")
		)
		(fp_line
			(start -0.674878 -1.100074)
			(end 0.674878 -1.100074)
			(stroke
				(width 0.1)
				(type default)
			)
			(layer "F.Fab")
		)
		(fp_line
			(start 0.674878 1.100074)
			(end -0.674878 1.100074)
			(stroke
				(width 0.1)
				(type default)
			)
			(layer "F.Fab")
		)
		(fp_line
			(start -0.674878 1.100074)
			(end -0.674878 -1.100074)
			(stroke
				(width 0.1)
				(type default)
			)
			(layer "F.Fab")
		)
		(fp_poly
			(pts
				(xy -1.590548 -0.649986) (xy -2.606548 -1.157986) (xy -2.606548 -0.141986)
			)
			(stroke
				(width 0)
				(type default)
			)
			(fill yes)
			(layer "F.Fab")
		)
		(pad "1" smd rect
			(at -0.94996 -0.649986)
			(size 0.4318 0.6096)
			(layers "F.Cu" "F.Mask" "F.Paste")
			(net "OCP_V3_2_AUX_PWR_EN_R1")
		)
		(pad "2" smd rect
			(at -0.94996 0)
			(size 0.4318 0.6096)
			(layers "F.Cu" "F.Mask" "F.Paste")
			(net "FM_OCP_V3_2_PWR_GOOD")
		)
		(pad "3" smd rect
			(at -0.94996 0.649986)
			(size 0.4318 0.6096)
			(layers "F.Cu" "F.Mask" "F.Paste")
			(net "GND")
		)
		(pad "4" smd rect
			(at 0.94996 0.649986)
			(size 0.4318 0.6096)
			(layers "F.Cu" "F.Mask" "F.Paste")
			(net "FB_BMC_ISOLATE_R2")
		)
		(pad "5" smd rect
			(at 0.94996 -0.649986)
			(size 0.4318 0.6096)
			(layers "F.Cu" "F.Mask" "F.Paste")
			(net "P3V3_AUX")
		)
	)
	(footprint ""
		(layer "F.Cu")
		(at 236.7661 -402.903182)
		(property "Reference" "PR3995"
			(at 0 0 0)
			(layer "F.SilkS")
			(hide yes)
			(effects
				(font
					(size 1.27 1.27)
				)
			)
		)
		(property "Value" ""
			(at 0 0 0)
			(layer "F.Fab")
			(effects
				(font
					(size 1.27 1.27)
				)
			)
		)
		(duplicate_pad_numbers_are_jumpers no)
		(fp_line
			(start -0.7874 -0.4064)
			(end 0.7874 -0.4064)
			(stroke
				(width 0.1524)
				(type default)
			)
			(layer "F.SilkS")
		)
		(fp_line
			(start -0.7874 0.4064)
			(end -0.7874 -0.4064)
			(stroke
				(width 0.1524)
				(type default)
			)
			(layer "F.SilkS")
		)
		(fp_line
			(start 0.7874 -0.4064)
			(end 0.7874 0.4064)
			(stroke
				(width 0.1524)
				(type default)
			)
			(layer "F.SilkS")
		)
		(fp_line
			(start 0.7874 0.4064)
			(end -0.7874 0.4064)
			(stroke
				(width 0.1524)
				(type default)
			)
			(layer "F.SilkS")
		)
		(fp_line
			(start -0.67945 -0.305054)
			(end -0.12065 -0.305054)
			(stroke
				(width 0.1)
				(type default)
			)
			(layer "F.Fab")
		)
		(fp_line
			(start -0.67945 0.3048)
			(end -0.67945 -0.305054)
			(stroke
				(width 0.1)
				(type default)
			)
			(layer "F.Fab")
		)
		(fp_line
			(start -0.12065 -0.305054)
			(end -0.12065 -0.2794)
			(stroke
				(width 0.1)
				(type default)
			)
			(layer "F.Fab")
		)
		(fp_line
			(start -0.12065 -0.2794)
			(end 0.12065 -0.2794)
			(stroke
				(width 0.1)
				(type default)
			)
			(layer "F.Fab")
		)
		(fp_line
			(start -0.12065 0.2794)
			(end -0.12065 0.3048)
			(stroke
				(width 0.1)
				(type default)
			)
			(layer "F.Fab")
		)
		(fp_line
			(start -0.12065 0.3048)
			(end -0.67945 0.3048)
			(stroke
				(width 0.1)
				(type default)
			)
			(layer "F.Fab")
		)
		(fp_line
			(start 0.120396 0.2794)
			(end -0.12065 0.2794)
			(stroke
				(width 0.1)
				(type default)
			)
			(layer "F.Fab")
		)
		(fp_line
			(start 0.120396 0.3048)
			(end 0.120396 0.2794)
			(stroke
				(width 0.1)
				(type default)
			)
			(layer "F.Fab")
		)
		(fp_line
			(start 0.12065 -0.3048)
			(end 0.67945 -0.3048)
			(stroke
				(width 0.1)
				(type default)
			)
			(layer "F.Fab")
		)
		(fp_line
			(start 0.12065 -0.2794)
			(end 0.12065 -0.3048)
			(stroke
				(width 0.1)
				(type default)
			)
			(layer "F.Fab")
		)
		(fp_line
			(start 0.67945 -0.3048)
			(end 0.67945 0.3048)
			(stroke
				(width 0.1)
				(type default)
			)
			(layer "F.Fab")
		)
		(fp_line
			(start 0.67945 0.3048)
			(end 0.120396 0.3048)
			(stroke
				(width 0.1)
				(type default)
			)
			(layer "F.Fab")
		)
		(pad "1" smd circle
			(at -0.40005 0)
			(size 0 0)
			(layers "F.Cu" "F.Mask" "F.Paste")
			(net "HSC_FLT_TYPE_4")
		)
		(pad "2" smd circle
			(at 0.40005 0)
			(size 0 0)
			(layers "F.Cu" "F.Mask" "F.Paste")
			(net "HSC_FLT_TYPE")
		)
	)
	(footprint ""
		(layer "F.Cu")
		(at 113.899696 -167.2717 90)
		(property "Reference" "PC333"
			(at 0 0 90)
			(layer "F.SilkS")
			(hide yes)
			(effects
				(font
					(size 1.27 1.27)
				)
			)
		)
		(property "Value" ""
			(at 0 0 90)
			(layer "F.Fab")
			(effects
				(font
					(size 1.27 1.27)
				)
			)
		)
		(duplicate_pad_numbers_are_jumpers no)
		(fp_line
			(start 0.7874 -0.4064)
			(end 0.7874 0.4064)
			(stroke
				(width 0.1524)
				(type default)
			)
			(layer "F.SilkS")
		)
		(fp_line
			(start -0.7874 -0.4064)
			(end 0.7874 -0.4064)
			(stroke
				(width 0.1524)
				(type default)
			)
			(layer "F.SilkS")
		)
		(fp_line
			(start 0.7874 0.4064)
			(end -0.7874 0.4064)
			(stroke
				(width 0.1524)
				(type default)
			)
			(layer "F.SilkS")
		)
		(fp_line
			(start -0.7874 0.4064)
			(end -0.7874 -0.4064)
			(stroke
				(width 0.1524)
				(type default)
			)
			(layer "F.SilkS")
		)
		(fp_line
			(start -0.12065 -0.305054)
			(end -0.12065 -0.2794)
			(stroke
				(width 0.1)
				(type default)
			)
			(layer "F.Fab")
		)
		(fp_line
			(start -0.67945 -0.305054)
			(end -0.12065 -0.305054)
			(stroke
				(width 0.1)
				(type default)
			)
			(layer "F.Fab")
		)
		(fp_line
			(start 0.67945 -0.3048)
			(end 0.67945 0.3048)
			(stroke
				(width 0.1)
				(type default)
			)
			(layer "F.Fab")
		)
		(fp_line
			(start 0.12065 -0.3048)
			(end 0.67945 -0.3048)
			(stroke
				(width 0.1)
				(type default)
			)
			(layer "F.Fab")
		)
		(fp_line
			(start 0.12065 -0.2794)
			(end 0.12065 -0.3048)
			(stroke
				(width 0.1)
				(type default)
			)
			(layer "F.Fab")
		)
		(fp_line
			(start -0.12065 -0.2794)
			(end 0.12065 -0.2794)
			(stroke
				(width 0.1)
				(type default)
			)
			(layer "F.Fab")
		)
		(fp_line
			(start 0.120396 0.2794)
			(end -0.12065 0.2794)
			(stroke
				(width 0.1)
				(type default)
			)
			(layer "F.Fab")
		)
		(fp_line
			(start -0.12065 0.2794)
			(end -0.12065 0.3048)
			(stroke
				(width 0.1)
				(type default)
			)
			(layer "F.Fab")
		)
		(fp_line
			(start 0.67945 0.3048)
			(end 0.120396 0.3048)
			(stroke
				(width 0.1)
				(type default)
			)
			(layer "F.Fab")
		)
		(fp_line
			(start 0.120396 0.3048)
			(end 0.120396 0.2794)
			(stroke
				(width 0.1)
				(type default)
			)
			(layer "F.Fab")
		)
		(fp_line
			(start -0.12065 0.3048)
			(end -0.67945 0.3048)
			(stroke
				(width 0.1)
				(type default)
			)
			(layer "F.Fab")
		)
		(fp_line
			(start -0.67945 0.3048)
			(end -0.67945 -0.305054)
			(stroke
				(width 0.1)
				(type default)
			)
			(layer "F.Fab")
		)
		(pad "1" smd circle
			(at -0.40005 0 90)
			(size 0 0)
			(layers "F.Cu" "F.Mask" "F.Paste")
			(net "SW_PVDDCR_SOC_P1_BOOT1_RC")
		)
		(pad "2" smd circle
			(at 0.40005 0 90)
			(size 0 0)
			(layers "F.Cu" "F.Mask" "F.Paste")
			(net "SW_PVDDCR_SOC_P1_PH1")
		)
	)
	(footprint ""
		(layer "F.Cu")
		(at 37.211 -361.061 180)
		(property "Reference" "R8241"
			(at 0 0 180)
			(layer "F.SilkS")
			(hide yes)
			(effects
				(font
					(size 1.27 1.27)
				)
			)
		)
		(property "Value" ""
			(at 0 0 180)
			(layer "F.Fab")
			(effects
				(font
					(size 1.27 1.27)
				)
			)
		)
		(duplicate_pad_numbers_are_jumpers no)
		(fp_line
			(start 0.7874 0.4064)
			(end -0.7874 0.4064)
			(stroke
				(width 0.1524)
				(type default)
			)
			(layer "F.SilkS")
		)
		(fp_line
			(start 0.7874 -0.4064)
			(end 0.7874 0.4064)
			(stroke
				(width 0.1524)
				(type default)
			)
			(layer "F.SilkS")
		)
		(fp_line
			(start -0.7874 0.4064)
			(end -0.7874 -0.4064)
			(stroke
				(width 0.1524)
				(type default)
			)
			(layer "F.SilkS")
		)
		(fp_line
			(start -0.7874 -0.4064)
			(end 0.7874 -0.4064)
			(stroke
				(width 0.1524)
				(type default)
			)
			(layer "F.SilkS")
		)
		(fp_line
			(start 0.67945 0.3048)
			(end 0.120396 0.3048)
			(stroke
				(width 0.1)
				(type default)
			)
			(layer "F.Fab")
		)
		(fp_line
			(start 0.67945 -0.3048)
			(end 0.67945 0.3048)
			(stroke
				(width 0.1)
				(type default)
			)
			(layer "F.Fab")
		)
		(fp_line
			(start 0.12065 -0.2794)
			(end 0.12065 -0.3048)
			(stroke
				(width 0.1)
				(type default)
			)
			(layer "F.Fab")
		)
		(fp_line
			(start 0.12065 -0.3048)
			(end 0.67945 -0.3048)
			(stroke
				(width 0.1)
				(type default)
			)
			(layer "F.Fab")
		)
		(fp_line
			(start 0.120396 0.3048)
			(end 0.120396 0.2794)
			(stroke
				(width 0.1)
				(type default)
			)
			(layer "F.Fab")
		)
		(fp_line
			(start 0.120396 0.2794)
			(end -0.12065 0.2794)
			(stroke
				(width 0.1)
				(type default)
			)
			(layer "F.Fab")
		)
		(fp_line
			(start -0.12065 0.3048)
			(end -0.67945 0.3048)
			(stroke
				(width 0.1)
				(type default)
			)
			(layer "F.Fab")
		)
		(fp_line
			(start -0.12065 0.2794)
			(end -0.12065 0.3048)
			(stroke
				(width 0.1)
				(type default)
			)
			(layer "F.Fab")
		)
		(fp_line
			(start -0.12065 -0.2794)
			(end 0.12065 -0.2794)
			(stroke
				(width 0.1)
				(type default)
			)
			(layer "F.Fab")
		)
		(fp_line
			(start -0.12065 -0.305054)
			(end -0.12065 -0.2794)
			(stroke
				(width 0.1)
				(type default)
			)
			(layer "F.Fab")
		)
		(fp_line
			(start -0.67945 0.3048)
			(end -0.67945 -0.305054)
			(stroke
				(width 0.1)
				(type default)
			)
			(layer "F.Fab")
		)
		(fp_line
			(start -0.67945 -0.305054)
			(end -0.12065 -0.305054)
			(stroke
				(width 0.1)
				(type default)
			)
			(layer "F.Fab")
		)
		(pad "1" smd circle
			(at -0.40005 0 180)
			(size 0 0)
			(layers "F.Cu" "F.Mask" "F.Paste")
			(net "PVDDCR_CPU1_P1_OCP_N")
		)
		(pad "2" smd circle
			(at 0.40005 0 180)
			(size 0 0)
			(layers "F.Cu" "F.Mask" "F.Paste")
			(net "PVDDCR_CPU1_P1_OCP_N_R")
		)
	)
	(footprint ""
		(layer "F.Cu")
		(at 351.4217 -164.14369)
		(property "Reference" "PC182"
			(at 0 0 0)
			(layer "F.SilkS")
			(hide yes)
			(effects
				(font
					(size 1.27 1.27)
				)
			)
		)
		(property "Value" ""
			(at 0 0 0)
			(layer "F.Fab")
			(effects
				(font
					(size 1.27 1.27)
				)
			)
		)
		(duplicate_pad_numbers_are_jumpers no)
		(fp_line
			(start -0.7874 -0.4064)
			(end 0.7874 -0.4064)
			(stroke
				(width 0.1524)
				(type default)
			)
			(layer "F.SilkS")
		)
		(fp_line
			(start -0.7874 0.4064)
			(end -0.7874 -0.4064)
			(stroke
				(width 0.1524)
				(type default)
			)
			(layer "F.SilkS")
		)
		(fp_line
			(start 0.7874 -0.4064)
			(end 0.7874 0.4064)
			(stroke
				(width 0.1524)
				(type default)
			)
			(layer "F.SilkS")
		)
		(fp_line
			(start 0.7874 0.4064)
			(end -0.7874 0.4064)
			(stroke
				(width 0.1524)
				(type default)
			)
			(layer "F.SilkS")
		)
		(fp_line
			(start -0.67945 -0.305054)
			(end -0.12065 -0.305054)
			(stroke
				(width 0.1)
				(type default)
			)
			(layer "F.Fab")
		)
		(fp_line
			(start -0.67945 0.3048)
			(end -0.67945 -0.305054)
			(stroke
				(width 0.1)
				(type default)
			)
			(layer "F.Fab")
		)
		(fp_line
			(start -0.12065 -0.305054)
			(end -0.12065 -0.2794)
			(stroke
				(width 0.1)
				(type default)
			)
			(layer "F.Fab")
		)
		(fp_line
			(start -0.12065 -0.2794)
			(end 0.12065 -0.2794)
			(stroke
				(width 0.1)
				(type default)
			)
			(layer "F.Fab")
		)
		(fp_line
			(start -0.12065 0.2794)
			(end -0.12065 0.3048)
			(stroke
				(width 0.1)
				(type default)
			)
			(layer "F.Fab")
		)
		(fp_line
			(start -0.12065 0.3048)
			(end -0.67945 0.3048)
			(stroke
				(width 0.1)
				(type default)
			)
			(layer "F.Fab")
		)
		(fp_line
			(start 0.120396 0.2794)
			(end -0.12065 0.2794)
			(stroke
				(width 0.1)
				(type default)
			)
			(layer "F.Fab")
		)
		(fp_line
			(start 0.120396 0.3048)
			(end 0.120396 0.2794)
			(stroke
				(width 0.1)
				(type default)
			)
			(layer "F.Fab")
		)
		(fp_line
			(start 0.12065 -0.3048)
			(end 0.67945 -0.3048)
			(stroke
				(width 0.1)
				(type default)
			)
			(layer "F.Fab")
		)
		(fp_line
			(start 0.12065 -0.2794)
			(end 0.12065 -0.3048)
			(stroke
				(width 0.1)
				(type default)
			)
			(layer "F.Fab")
		)
		(fp_line
			(start 0.67945 -0.3048)
			(end 0.67945 0.3048)
			(stroke
				(width 0.1)
				(type default)
			)
			(layer "F.Fab")
		)
		(fp_line
			(start 0.67945 0.3048)
			(end 0.120396 0.3048)
			(stroke
				(width 0.1)
				(type default)
			)
			(layer "F.Fab")
		)
		(pad "1" smd circle
			(at -0.40005 0)
			(size 0 0)
			(layers "F.Cu" "F.Mask" "F.Paste")
			(net "SW_PVDDCR_CPU0_P0_SW6")
		)
		(pad "2" smd circle
			(at 0.40005 0)
			(size 0 0)
			(layers "F.Cu" "F.Mask" "F.Paste")
			(net "SW_PVDDCR_CPU0_P0_SW6_RC")
		)
	)
	(footprint ""
		(layer "F.Cu")
		(at 71.663814 -145.801588 180)
		(property "Reference" "PC6006"
			(at 0 0 180)
			(layer "F.SilkS")
			(hide yes)
			(effects
				(font
					(size 1.27 1.27)
				)
			)
		)
		(property "Value" ""
			(at 0 0 180)
			(layer "F.Fab")
			(effects
				(font
					(size 1.27 1.27)
				)
			)
		)
		(duplicate_pad_numbers_are_jumpers no)
		(fp_line
			(start 0.7874 0.4064)
			(end -0.7874 0.4064)
			(stroke
				(width 0.1524)
				(type default)
			)
			(layer "F.SilkS")
		)
		(fp_line
			(start 0.7874 -0.4064)
			(end 0.7874 0.4064)
			(stroke
				(width 0.1524)
				(type default)
			)
			(layer "F.SilkS")
		)
		(fp_line
			(start -0.7874 0.4064)
			(end -0.7874 -0.4064)
			(stroke
				(width 0.1524)
				(type default)
			)
			(layer "F.SilkS")
		)
		(fp_line
			(start -0.7874 -0.4064)
			(end 0.7874 -0.4064)
			(stroke
				(width 0.1524)
				(type default)
			)
			(layer "F.SilkS")
		)
		(fp_line
			(start 0.67945 0.3048)
			(end 0.120396 0.3048)
			(stroke
				(width 0.1)
				(type default)
			)
			(layer "F.Fab")
		)
		(fp_line
			(start 0.67945 -0.3048)
			(end 0.67945 0.3048)
			(stroke
				(width 0.1)
				(type default)
			)
			(layer "F.Fab")
		)
		(fp_line
			(start 0.12065 -0.2794)
			(end 0.12065 -0.3048)
			(stroke
				(width 0.1)
				(type default)
			)
			(layer "F.Fab")
		)
		(fp_line
			(start 0.12065 -0.3048)
			(end 0.67945 -0.3048)
			(stroke
				(width 0.1)
				(type default)
			)
			(layer "F.Fab")
		)
		(fp_line
			(start 0.120396 0.3048)
			(end 0.120396 0.2794)
			(stroke
				(width 0.1)
				(type default)
			)
			(layer "F.Fab")
		)
		(fp_line
			(start 0.120396 0.2794)
			(end -0.12065 0.2794)
			(stroke
				(width 0.1)
				(type default)
			)
			(layer "F.Fab")
		)
		(fp_line
			(start -0.12065 0.3048)
			(end -0.67945 0.3048)
			(stroke
				(width 0.1)
				(type default)
			)
			(layer "F.Fab")
		)
		(fp_line
			(start -0.12065 0.2794)
			(end -0.12065 0.3048)
			(stroke
				(width 0.1)
				(type default)
			)
			(layer "F.Fab")
		)
		(fp_line
			(start -0.12065 -0.2794)
			(end 0.12065 -0.2794)
			(stroke
				(width 0.1)
				(type default)
			)
			(layer "F.Fab")
		)
		(fp_line
			(start -0.12065 -0.305054)
			(end -0.12065 -0.2794)
			(stroke
				(width 0.1)
				(type default)
			)
			(layer "F.Fab")
		)
		(fp_line
			(start -0.67945 0.3048)
			(end -0.67945 -0.305054)
			(stroke
				(width 0.1)
				(type default)
			)
			(layer "F.Fab")
		)
		(fp_line
			(start -0.67945 -0.305054)
			(end -0.12065 -0.305054)
			(stroke
				(width 0.1)
				(type default)
			)
			(layer "F.Fab")
		)
		(pad "1" smd circle
			(at -0.40005 0 180)
			(size 0 0)
			(layers "F.Cu" "F.Mask" "F.Paste")
			(net "PVDD18_S5_P1_FB_RC")
		)
		(pad "2" smd circle
			(at 0.40005 0 180)
			(size 0 0)
			(layers "F.Cu" "F.Mask" "F.Paste")
			(net "PVDD18_SS_P1_RGND")
		)
	)
	(footprint ""
		(layer "F.Cu")
		(at 302.133 -356.997 180)
		(property "Reference" "C305"
			(at 0 0 180)
			(layer "F.SilkS")
			(hide yes)
			(effects
				(font
					(size 1.27 1.27)
				)
			)
		)
		(property "Value" ""
			(at 0 0 180)
			(layer "F.Fab")
			(effects
				(font
					(size 1.27 1.27)
				)
			)
		)
		(duplicate_pad_numbers_are_jumpers no)
		(fp_line
			(start 0.7874 0.4064)
			(end -0.7874 0.4064)
			(stroke
				(width 0.1524)
				(type default)
			)
			(layer "F.SilkS")
		)
		(fp_line
			(start 0.7874 -0.4064)
			(end 0.7874 0.4064)
			(stroke
				(width 0.1524)
				(type default)
			)
			(layer "F.SilkS")
		)
		(fp_line
			(start -0.7874 0.4064)
			(end -0.7874 -0.4064)
			(stroke
				(width 0.1524)
				(type default)
			)
			(layer "F.SilkS")
		)
		(fp_line
			(start -0.7874 -0.4064)
			(end 0.7874 -0.4064)
			(stroke
				(width 0.1524)
				(type default)
			)
			(layer "F.SilkS")
		)
		(fp_line
			(start 0.67945 0.3048)
			(end 0.120396 0.3048)
			(stroke
				(width 0.1)
				(type default)
			)
			(layer "F.Fab")
		)
		(fp_line
			(start 0.67945 -0.3048)
			(end 0.67945 0.3048)
			(stroke
				(width 0.1)
				(type default)
			)
			(layer "F.Fab")
		)
		(fp_line
			(start 0.12065 -0.2794)
			(end 0.12065 -0.3048)
			(stroke
				(width 0.1)
				(type default)
			)
			(layer "F.Fab")
		)
		(fp_line
			(start 0.12065 -0.3048)
			(end 0.67945 -0.3048)
			(stroke
				(width 0.1)
				(type default)
			)
			(layer "F.Fab")
		)
		(fp_line
			(start 0.120396 0.3048)
			(end 0.120396 0.2794)
			(stroke
				(width 0.1)
				(type default)
			)
			(layer "F.Fab")
		)
		(fp_line
			(start 0.120396 0.2794)
			(end -0.12065 0.2794)
			(stroke
				(width 0.1)
				(type default)
			)
			(layer "F.Fab")
		)
		(fp_line
			(start -0.12065 0.3048)
			(end -0.67945 0.3048)
			(stroke
				(width 0.1)
				(type default)
			)
			(layer "F.Fab")
		)
		(fp_line
			(start -0.12065 0.2794)
			(end -0.12065 0.3048)
			(stroke
				(width 0.1)
				(type default)
			)
			(layer "F.Fab")
		)
		(fp_line
			(start -0.12065 -0.2794)
			(end 0.12065 -0.2794)
			(stroke
				(width 0.1)
				(type default)
			)
			(layer "F.Fab")
		)
		(fp_line
			(start -0.12065 -0.305054)
			(end -0.12065 -0.2794)
			(stroke
				(width 0.1)
				(type default)
			)
			(layer "F.Fab")
		)
		(fp_line
			(start -0.67945 0.3048)
			(end -0.67945 -0.305054)
			(stroke
				(width 0.1)
				(type default)
			)
			(layer "F.Fab")
		)
		(fp_line
			(start -0.67945 -0.305054)
			(end -0.12065 -0.305054)
			(stroke
				(width 0.1)
				(type default)
			)
			(layer "F.Fab")
		)
		(pad "1" smd circle
			(at -0.40005 0 180)
			(size 0 0)
			(layers "F.Cu" "F.Mask" "F.Paste")
			(net "SVID_PVDDCR_CPU1_P0_SVC_R")
		)
		(pad "2" smd circle
			(at 0.40005 0 180)
			(size 0 0)
			(layers "F.Cu" "F.Mask" "F.Paste")
			(net "GND")
		)
	)
	(footprint ""
		(layer "F.Cu")
		(at 106.246422 -409.63215 -90)
		(property "Reference" "U10"
			(at -0.080772 -3.860546 90)
			(unlocked yes)
			(layer "F.SilkS")
			(effects
				(font
					(size 0.7874 0.5842)
					(thickness 0.1524)
				)
			)
		)
		(property "Value" ""
			(at 0 0 270)
			(layer "F.Fab")
			(effects
				(font
					(size 1.27 1.27)
				)
			)
		)
		(duplicate_pad_numbers_are_jumpers no)
		(fp_line
			(start -2.500122 2.500122)
			(end -2.01676 2.500122)
			(stroke
				(width 0.1524)
				(type default)
			)
			(layer "F.SilkS")
		)
		(fp_line
			(start 2.01676 2.500122)
			(end 2.500122 2.500122)
			(stroke
				(width 0.1524)
				(type default)
			)
			(layer "F.SilkS")
		)
		(fp_line
			(start 2.500122 2.500122)
			(end 2.500122 2.01676)
			(stroke
				(width 0.1524)
				(type default)
			)
			(layer "F.SilkS")
		)
		(fp_line
			(start -2.500122 2.01676)
			(end -2.500122 2.500122)
			(stroke
				(width 0.1524)
				(type default)
			)
			(layer "F.SilkS")
		)
		(fp_line
			(start 2.500122 -2.01676)
			(end 2.500122 -2.500122)
			(stroke
				(width 0.1524)
				(type default)
			)
			(layer "F.SilkS")
		)
		(fp_line
			(start -2.500122 -2.500122)
			(end -2.500122 -2.01676)
			(stroke
				(width 0.1524)
				(type default)
			)
			(layer "F.SilkS")
		)
		(fp_line
			(start -2.01676 -2.500122)
			(end -2.500122 -2.500122)
			(stroke
				(width 0.1524)
				(type default)
			)
			(layer "F.SilkS")
		)
		(fp_line
			(start 2.500122 -2.500122)
			(end 2.01676 -2.500122)
			(stroke
				(width 0.1524)
				(type default)
			)
			(layer "F.SilkS")
		)
		(fp_poly
			(pts
				(xy -2.733294 -2.21615) (xy -4.065778 -2.318766) (xy -3.450844 -3.343656)
			)
			(stroke
				(width 0)
				(type default)
			)
			(fill yes)
			(layer "F.SilkS")
		)
		(fp_line
			(start -2.500122 2.500122)
			(end 2.500122 2.500122)
			(stroke
				(width 0.1)
				(type default)
			)
			(layer "F.Fab")
		)
		(fp_line
			(start 2.500122 2.500122)
			(end 2.500122 -2.500122)
			(stroke
				(width 0.1)
				(type default)
			)
			(layer "F.Fab")
		)
		(fp_line
			(start -2.500122 -2.500122)
			(end -2.500122 2.500122)
			(stroke
				(width 0.1)
				(type default)
			)
			(layer "F.Fab")
		)
		(fp_line
			(start 2.500122 -2.500122)
			(end -2.500122 -2.500122)
			(stroke
				(width 0.1)
				(type default)
			)
			(layer "F.Fab")
		)
		(fp_poly
			(pts
				(xy -3.044698 -1.75006) (xy -4.240022 -1.152398) (xy -4.240022 -2.347722)
			)
			(stroke
				(width 0)
				(type default)
			)
			(fill yes)
			(layer "F.Fab")
		)
		(pad "1" smd rect
			(at -2.3749 -1.75006 180)
			(size 0.254 0.5588)
			(layers "F.Cu" "F.Mask" "F.Paste")
			(net "FM_9ZXL045_P1_DEV_EN")
		)
		(pad "2" smd rect
			(at -2.3749 -1.249934 180)
			(size 0.254 0.5588)
			(layers "F.Cu" "F.Mask" "F.Paste")
			(net "P3V3_9ZXL045_P1_VDDR")
		)
		(pad "3" smd rect
			(at -2.3749 -0.750062 180)
			(size 0.254 0.5588)
			(layers "F.Cu" "F.Mask" "F.Paste")
			(net "CLK_100M_CPU1_CLK13_DP")
		)
		(pad "4" smd rect
			(at -2.3749 -0.249936 180)
			(size 0.254 0.5588)
			(layers "F.Cu" "F.Mask" "F.Paste")
			(net "CLK_100M_CPU1_CLK13_DN")
		)
		(pad "5" smd rect
			(at -2.3749 0.249936 180)
			(size 0.254 0.5588)
			(layers "F.Cu" "F.Mask" "F.Paste")
			(net "CLK_9ZXL045_P1_SADR0")
		)
		(pad "6" smd rect
			(at -2.3749 0.750062 180)
			(size 0.254 0.5588)
			(layers "F.Cu" "F.Mask" "F.Paste")
			(net "SMB_9ZXL045_P1_SDA")
		)
		(pad "7" smd rect
			(at -2.3749 1.249934 180)
			(size 0.254 0.5588)
			(layers "F.Cu" "F.Mask" "F.Paste")
			(net "SMB_9ZXL045_P1_SCL")
		)
		(pad "8" smd rect
			(at -2.3749 1.75006 180)
			(size 0.254 0.5588)
			(layers "F.Cu" "F.Mask" "F.Paste")
			(net "NC_U10_FBOUT_N")
		)
		(pad "9" smd rect
			(at -1.75006 2.3749 270)
			(size 0.254 0.5588)
			(layers "F.Cu" "F.Mask" "F.Paste")
			(net "NC_U10_FBOUT")
		)
		(pad "10" smd rect
			(at -1.249934 2.3749 270)
			(size 0.254 0.5588)
			(layers "F.Cu" "F.Mask" "F.Paste")
			(net "NC_U10_NC0")
		)
		(pad "11" smd rect
			(at -0.750062 2.3749 270)
			(size 0.254 0.5588)
			(layers "F.Cu" "F.Mask" "F.Paste")
			(net "NC_U10_NC1")
		)
		(pad "12" smd rect
			(at -0.249936 2.3749 270)
			(size 0.254 0.5588)
			(layers "F.Cu" "F.Mask" "F.Paste")
			(net "P3V3_9ZXL045_P1_VDD")
		)
		(pad "13" smd rect
			(at 0.249936 2.3749 270)
			(size 0.254 0.5588)
			(layers "F.Cu" "F.Mask" "F.Paste")
			(net "CLK_100M_RETIMER_CPU1_P0_R_DP")
		)
		(pad "14" smd rect
			(at 0.750062 2.3749 270)
			(size 0.254 0.5588)
			(layers "F.Cu" "F.Mask" "F.Paste")
			(net "CLK_100M_RETIMER_CPU1_P0_R_DN")
		)
		(pad "15" smd rect
			(at 1.249934 2.3749 270)
			(size 0.254 0.5588)
			(layers "F.Cu" "F.Mask" "F.Paste")
			(net "FM_9ZXL045_P1_0_OE_N")
		)
		(pad "16" smd rect
			(at 1.75006 2.3749 270)
			(size 0.254 0.5588)
			(layers "F.Cu" "F.Mask" "F.Paste")
			(net "P3V3_9ZXL045_P1_VDD")
		)
		(pad "17" smd rect
			(at 2.3749 1.75006)
			(size 0.254 0.5588)
			(layers "F.Cu" "F.Mask" "F.Paste")
			(net "NC_U10_NC2")
		)
		(pad "18" smd rect
			(at 2.3749 1.249934)
			(size 0.254 0.5588)
			(layers "F.Cu" "F.Mask" "F.Paste")
			(net "FM_9ZXL045_P1_1_OE_N")
		)
		(pad "19" smd rect
			(at 2.3749 0.750062)
			(size 0.254 0.5588)
			(layers "F.Cu" "F.Mask" "F.Paste")
			(net "CLK_100M_RETIMER_CPU1_P1_R_DP")
		)
		(pad "20" smd rect
			(at 2.3749 0.249936)
			(size 0.254 0.5588)
			(layers "F.Cu" "F.Mask" "F.Paste")
			(net "CLK_100M_RETIMER_CPU1_P1_R_DN")
		)
		(pad "21" smd rect
			(at 2.3749 -0.249936)
			(size 0.254 0.5588)
			(layers "F.Cu" "F.Mask" "F.Paste")
			(net "P3V3_9ZXL045_P1_VDD")
		)
		(pad "22" smd rect
			(at 2.3749 -0.750062)
			(size 0.254 0.5588)
			(layers "F.Cu" "F.Mask" "F.Paste")
			(net "CLK_100M_RETIMER_CPU1_P2_R_DP")
		)
		(pad "23" smd rect
			(at 2.3749 -1.249934)
			(size 0.254 0.5588)
			(layers "F.Cu" "F.Mask" "F.Paste")
			(net "CLK_100M_RETIMER_CPU1_P2_R_DN")
		)
		(pad "24" smd rect
			(at 2.3749 -1.75006)
			(size 0.254 0.5588)
			(layers "F.Cu" "F.Mask" "F.Paste")
			(net "FM_9ZXL045_P1_2_OE_N")
		)
		(pad "25" smd rect
			(at 1.75006 -2.3749 90)
			(size 0.254 0.5588)
			(layers "F.Cu" "F.Mask" "F.Paste")
			(net "P3V3_9ZXL045_P1_VDD")
		)
		(pad "26" smd rect
			(at 1.249934 -2.3749 90)
			(size 0.254 0.5588)
			(layers "F.Cu" "F.Mask" "F.Paste")
			(net "FM_9ZXL045_P1_3_OE_N")
		)
		(pad "27" smd rect
			(at 0.750062 -2.3749 90)
			(size 0.254 0.5588)
			(layers "F.Cu" "F.Mask" "F.Paste")
			(net "CLK_100M_RETIMER_CPU1_P3_R_DP")
		)
		(pad "28" smd rect
			(at 0.249936 -2.3749 90)
			(size 0.254 0.5588)
			(layers "F.Cu" "F.Mask" "F.Paste")
			(net "CLK_100M_RETIMER_CPU1_P3_R_DN")
		)
		(pad "29" smd rect
			(at -0.249936 -2.3749 90)
			(size 0.254 0.5588)
			(layers "F.Cu" "F.Mask" "F.Paste")
			(net "P3V3_9ZXL045_P1_VDD")
		)
		(pad "30" smd rect
			(at -0.750062 -2.3749 90)
			(size 0.254 0.5588)
			(layers "F.Cu" "F.Mask" "F.Paste")
			(net "NC_U10_NC3")
		)
		(pad "31" smd rect
			(at -1.249934 -2.3749 90)
			(size 0.254 0.5588)
			(layers "F.Cu" "F.Mask" "F.Paste")
			(net "P3V3_9ZXL045_P1_VDDA")
		)
		(pad "32" smd rect
			(at -1.75006 -2.3749 90)
			(size 0.254 0.5588)
			(layers "F.Cu" "F.Mask" "F.Paste")
			(net "CLK_9ZXL045_P1_HIBW")
		)
		(pad "33" smd rect
			(at 0 0 270)
			(size 3.1496 3.1496)
			(layers "F.Cu" "F.Mask" "F.Paste")
			(net "GND")
		)
		(zone
			(layer "F.Cu")
			(hatch none 0.5)
			(connect_pads
				(clearance 0)
			)
			(min_thickness 0.25)
			(keepout
				(tracks not_allowed)
				(vias allowed)
				(pads allowed)
				(copperpour not_allowed)
				(footprints allowed)
			)
			(placement
				(enabled no)
				(sheetname "")
			)
			(fill
				(thermal_gap 0.5)
				(thermal_bridge_width 0.5)
				(island_removal_mode 0)
			)
			(polygon
				(pts
					(xy 104.201722 -411.67685) (xy 107.470956 -411.67685) (xy 107.470956 -411.25775) (xy 104.620822 -411.25775)
					(xy 104.620822 -408.00655) (xy 107.872022 -408.00655) (xy 107.872022 -411.25775) (xy 107.496356 -411.25775)
					(xy 107.496356 -411.67685) (xy 108.291122 -411.67685) (xy 108.291122 -407.58745) (xy 104.201722 -407.58745)
				)
			)
		)
	)
	(footprint ""
		(layer "F.Cu")
		(at 446.359788 -32.174434 -90)
		(property "Reference" "R591"
			(at 0 0 270)
			(layer "F.SilkS")
			(hide yes)
			(effects
				(font
					(size 1.27 1.27)
				)
			)
		)
		(property "Value" ""
			(at 0 0 270)
			(layer "F.Fab")
			(effects
				(font
					(size 1.27 1.27)
				)
			)
		)
		(duplicate_pad_numbers_are_jumpers no)
		(fp_line
			(start -0.7874 0.4064)
			(end -0.7874 -0.4064)
			(stroke
				(width 0.1524)
				(type default)
			)
			(layer "F.SilkS")
		)
		(fp_line
			(start 0.7874 0.4064)
			(end -0.7874 0.4064)
			(stroke
				(width 0.1524)
				(type default)
			)
			(layer "F.SilkS")
		)
		(fp_line
			(start -0.7874 -0.4064)
			(end 0.7874 -0.4064)
			(stroke
				(width 0.1524)
				(type default)
			)
			(layer "F.SilkS")
		)
		(fp_line
			(start 0.7874 -0.4064)
			(end 0.7874 0.4064)
			(stroke
				(width 0.1524)
				(type default)
			)
			(layer "F.SilkS")
		)
		(fp_line
			(start -0.67945 0.3048)
			(end -0.67945 -0.305054)
			(stroke
				(width 0.1)
				(type default)
			)
			(layer "F.Fab")
		)
		(fp_line
			(start -0.12065 0.3048)
			(end -0.67945 0.3048)
			(stroke
				(width 0.1)
				(type default)
			)
			(layer "F.Fab")
		)
		(fp_line
			(start 0.120396 0.3048)
			(end 0.120396 0.2794)
			(stroke
				(width 0.1)
				(type default)
			)
			(layer "F.Fab")
		)
		(fp_line
			(start 0.67945 0.3048)
			(end 0.120396 0.3048)
			(stroke
				(width 0.1)
				(type default)
			)
			(layer "F.Fab")
		)
		(fp_line
			(start -0.12065 0.2794)
			(end -0.12065 0.3048)
			(stroke
				(width 0.1)
				(type default)
			)
			(layer "F.Fab")
		)
		(fp_line
			(start 0.120396 0.2794)
			(end -0.12065 0.2794)
			(stroke
				(width 0.1)
				(type default)
			)
			(layer "F.Fab")
		)
		(fp_line
			(start -0.12065 -0.2794)
			(end 0.12065 -0.2794)
			(stroke
				(width 0.1)
				(type default)
			)
			(layer "F.Fab")
		)
		(fp_line
			(start 0.12065 -0.2794)
			(end 0.12065 -0.3048)
			(stroke
				(width 0.1)
				(type default)
			)
			(layer "F.Fab")
		)
		(fp_line
			(start 0.12065 -0.3048)
			(end 0.67945 -0.3048)
			(stroke
				(width 0.1)
				(type default)
			)
			(layer "F.Fab")
		)
		(fp_line
			(start 0.67945 -0.3048)
			(end 0.67945 0.3048)
			(stroke
				(width 0.1)
				(type default)
			)
			(layer "F.Fab")
		)
		(fp_line
			(start -0.67945 -0.305054)
			(end -0.12065 -0.305054)
			(stroke
				(width 0.1)
				(type default)
			)
			(layer "F.Fab")
		)
		(fp_line
			(start -0.12065 -0.305054)
			(end -0.12065 -0.2794)
			(stroke
				(width 0.1)
				(type default)
			)
			(layer "F.Fab")
		)
		(pad "1" smd circle
			(at -0.40005 0 270)
			(size 0 0)
			(layers "F.Cu" "F.Mask" "F.Paste")
			(net "P12V_OCP_SFF_BUF_EN_R")
		)
		(pad "2" smd circle
			(at 0.40005 0 270)
			(size 0 0)
			(layers "F.Cu" "F.Mask" "F.Paste")
			(net "P12V_OCP_EN_1_R2")
		)
	)
	(footprint ""
		(layer "F.Cu")
		(at 351.938844 -381.41783 -90)
		(property "Reference" "C943"
			(at 0 0 270)
			(layer "F.SilkS")
			(hide yes)
			(effects
				(font
					(size 1.27 1.27)
				)
			)
		)
		(property "Value" ""
			(at 0 0 270)
			(layer "F.Fab")
			(effects
				(font
					(size 1.27 1.27)
				)
			)
		)
		(duplicate_pad_numbers_are_jumpers no)
		(fp_line
			(start -0.299974 0.150114)
			(end -0.299974 -0.150114)
			(stroke
				(width 0.1)
				(type default)
			)
			(layer "F.Fab")
		)
		(fp_line
			(start 0.299974 0.150114)
			(end -0.299974 0.150114)
			(stroke
				(width 0.1)
				(type default)
			)
			(layer "F.Fab")
		)
		(fp_line
			(start -0.299974 -0.150114)
			(end 0.299974 -0.150114)
			(stroke
				(width 0.1)
				(type default)
			)
			(layer "F.Fab")
		)
		(fp_line
			(start 0.299974 -0.150114)
			(end 0.299974 0.150114)
			(stroke
				(width 0.1)
				(type default)
			)
			(layer "F.Fab")
		)
		(pad "1" smd rect
			(at -0.2667 0 270)
			(size 0.3048 0.381)
			(layers "F.Cu" "F.Mask" "F.Paste")
			(net "P5E_CPU0_P1_TX_C_DP<11>")
		)
		(pad "2" smd rect
			(at 0.2667 0 270)
			(size 0.3048 0.381)
			(layers "F.Cu" "F.Mask" "F.Paste")
			(net "P5E_CPU0_P1_TX_DP<11>")
		)
	)
	(footprint ""
		(layer "F.Cu")
		(at 113.283238 -41.17975 -90)
		(property "Reference" "R6287"
			(at 0 0 270)
			(layer "F.SilkS")
			(hide yes)
			(effects
				(font
					(size 1.27 1.27)
				)
			)
		)
		(property "Value" ""
			(at 0 0 270)
			(layer "F.Fab")
			(effects
				(font
					(size 1.27 1.27)
				)
			)
		)
		(duplicate_pad_numbers_are_jumpers no)
		(fp_line
			(start -0.7874 0.4064)
			(end -0.7874 -0.4064)
			(stroke
				(width 0.1524)
				(type default)
			)
			(layer "F.SilkS")
		)
		(fp_line
			(start 0.7874 0.4064)
			(end -0.7874 0.4064)
			(stroke
				(width 0.1524)
				(type default)
			)
			(layer "F.SilkS")
		)
		(fp_line
			(start -0.7874 -0.4064)
			(end 0.7874 -0.4064)
			(stroke
				(width 0.1524)
				(type default)
			)
			(layer "F.SilkS")
		)
		(fp_line
			(start 0.7874 -0.4064)
			(end 0.7874 0.4064)
			(stroke
				(width 0.1524)
				(type default)
			)
			(layer "F.SilkS")
		)
		(fp_line
			(start -0.67945 0.3048)
			(end -0.67945 -0.305054)
			(stroke
				(width 0.1)
				(type default)
			)
			(layer "F.Fab")
		)
		(fp_line
			(start -0.12065 0.3048)
			(end -0.67945 0.3048)
			(stroke
				(width 0.1)
				(type default)
			)
			(layer "F.Fab")
		)
		(fp_line
			(start 0.120396 0.3048)
			(end 0.120396 0.2794)
			(stroke
				(width 0.1)
				(type default)
			)
			(layer "F.Fab")
		)
		(fp_line
			(start 0.67945 0.3048)
			(end 0.120396 0.3048)
			(stroke
				(width 0.1)
				(type default)
			)
			(layer "F.Fab")
		)
		(fp_line
			(start -0.12065 0.2794)
			(end -0.12065 0.3048)
			(stroke
				(width 0.1)
				(type default)
			)
			(layer "F.Fab")
		)
		(fp_line
			(start 0.120396 0.2794)
			(end -0.12065 0.2794)
			(stroke
				(width 0.1)
				(type default)
			)
			(layer "F.Fab")
		)
		(fp_line
			(start -0.12065 -0.2794)
			(end 0.12065 -0.2794)
			(stroke
				(width 0.1)
				(type default)
			)
			(layer "F.Fab")
		)
		(fp_line
			(start 0.12065 -0.2794)
			(end 0.12065 -0.3048)
			(stroke
				(width 0.1)
				(type default)
			)
			(layer "F.Fab")
		)
		(fp_line
			(start 0.12065 -0.3048)
			(end 0.67945 -0.3048)
			(stroke
				(width 0.1)
				(type default)
			)
			(layer "F.Fab")
		)
		(fp_line
			(start 0.67945 -0.3048)
			(end 0.67945 0.3048)
			(stroke
				(width 0.1)
				(type default)
			)
			(layer "F.Fab")
		)
		(fp_line
			(start -0.67945 -0.305054)
			(end -0.12065 -0.305054)
			(stroke
				(width 0.1)
				(type default)
			)
			(layer "F.Fab")
		)
		(fp_line
			(start -0.12065 -0.305054)
			(end -0.12065 -0.2794)
			(stroke
				(width 0.1)
				(type default)
			)
			(layer "F.Fab")
		)
		(pad "1" smd circle
			(at -0.40005 0 270)
			(size 0 0)
			(layers "F.Cu" "F.Mask" "F.Paste")
			(net "P3V3_AUX")
		)
		(pad "2" smd circle
			(at 0.40005 0 270)
			(size 0 0)
			(layers "F.Cu" "F.Mask" "F.Paste")
			(net "USB_HUB2_TI_PWRCTL_POL")
		)
	)
	(footprint ""
		(layer "F.Cu")
		(at 420.52494 -105.207308)
		(property "Reference" "PU205"
			(at -5.431282 -0.11684 90)
			(unlocked yes)
			(layer "F.SilkS")
			(effects
				(font
					(size 0.7874 0.5842)
					(thickness 0.1524)
				)
			)
		)
		(property "Value" ""
			(at 0 0 0)
			(layer "F.Fab")
			(effects
				(font
					(size 1.27 1.27)
				)
			)
		)
		(duplicate_pad_numbers_are_jumpers no)
		(fp_line
			(start -1.239774 -1.495298)
			(end 1.239774 -1.495298)
			(stroke
				(width 0.1524)
				(type default)
			)
			(layer "F.SilkS")
		)
		(fp_line
			(start -1.239774 1.495298)
			(end -1.239774 -1.495298)
			(stroke
				(width 0.1524)
				(type default)
			)
			(layer "F.SilkS")
		)
		(fp_line
			(start 1.239774 -1.495298)
			(end 1.239774 1.495298)
			(stroke
				(width 0.1524)
				(type default)
			)
			(layer "F.SilkS")
		)
		(fp_line
			(start 1.239774 1.495298)
			(end -1.239774 1.495298)
			(stroke
				(width 0.1524)
				(type default)
			)
			(layer "F.SilkS")
		)
		(fp_poly
			(pts
				(xy -1.827784 -0.742188) (xy -2.962402 -0.79629) (xy -2.465324 -1.682496)
			)
			(stroke
				(width 0)
				(type default)
			)
			(fill yes)
			(layer "F.SilkS")
		)
		(fp_line
			(start -0.8001 -1.050036)
			(end 0.8001 -1.050036)
			(stroke
				(width 0.1)
				(type default)
			)
			(layer "F.Fab")
		)
		(fp_line
			(start -0.8001 1.050036)
			(end -0.8001 -1.050036)
			(stroke
				(width 0.1)
				(type default)
			)
			(layer "F.Fab")
		)
		(fp_line
			(start 0.8001 -1.050036)
			(end 0.8001 1.050036)
			(stroke
				(width 0.1)
				(type default)
			)
			(layer "F.Fab")
		)
		(fp_line
			(start 0.8001 1.050036)
			(end -0.8001 1.050036)
			(stroke
				(width 0.1)
				(type default)
			)
			(layer "F.Fab")
		)
		(fp_poly
			(pts
				(xy -2.458974 -0.508) (xy -2.458974 0.508) (xy -1.442974 0)
			)
			(stroke
				(width 0)
				(type default)
			)
			(fill yes)
			(layer "F.Fab")
		)
		(pad "1_2" smd circle
			(at -0.374904 0 90)
			(size 0 0)
			(layers "F.Cu" "F.Mask" "F.Paste")
			(net "P3V3_AUX")
		)
		(pad "3" smd rect
			(at -0.499872 0.999998)
			(size 0.254 0.7112)
			(layers "F.Cu" "F.Mask" "F.Paste")
			(net "GND")
		)
		(pad "4" smd rect
			(at 0 0.999998)
			(size 0.254 0.7112)
			(layers "F.Cu" "F.Mask" "F.Paste")
			(net "P3V3_OCP_ILIMIT_1")
		)
		(pad "5" smd rect
			(at 0.499872 0.999998)
			(size 0.254 0.7112)
			(layers "F.Cu" "F.Mask" "F.Paste")
			(net "P3V3_OCP_MODE_1")
		)
		(pad "6_7" smd circle
			(at 0.374904 0 270)
			(size 0 0)
			(layers "F.Cu" "F.Mask" "F.Paste")
			(net "P3V3_OCP_SFF_R")
		)
		(pad "8" smd rect
			(at 0.499872 -0.999998)
			(size 0.254 0.7112)
			(layers "F.Cu" "F.Mask" "F.Paste")
			(net "P3V3_OCP_GATE_1")
		)
		(pad "9" smd rect
			(at 0 -0.999998)
			(size 0.254 0.7112)
			(layers "F.Cu" "F.Mask" "F.Paste")
			(net "P3V3_OCP_EN_1_R2")
		)
		(pad "10" smd rect
			(at -0.499872 -0.999998)
			(size 0.254 0.7112)
			(layers "F.Cu" "F.Mask" "F.Paste")
			(net "P3V3_OCP_DVDT_1")
		)
	)
	(footprint ""
		(layer "F.Cu")
		(at 157.686502 -349.270828 180)
		(property "Reference" "PR391"
			(at 0 0 180)
			(layer "F.SilkS")
			(hide yes)
			(effects
				(font
					(size 1.27 1.27)
				)
			)
		)
		(property "Value" ""
			(at 0 0 180)
			(layer "F.Fab")
			(effects
				(font
					(size 1.27 1.27)
				)
			)
		)
		(duplicate_pad_numbers_are_jumpers no)
		(fp_line
			(start 0.7874 0.4064)
			(end -0.7874 0.4064)
			(stroke
				(width 0.1524)
				(type default)
			)
			(layer "F.SilkS")
		)
		(fp_line
			(start 0.7874 -0.4064)
			(end 0.7874 0.4064)
			(stroke
				(width 0.1524)
				(type default)
			)
			(layer "F.SilkS")
		)
		(fp_line
			(start -0.7874 0.4064)
			(end -0.7874 -0.4064)
			(stroke
				(width 0.1524)
				(type default)
			)
			(layer "F.SilkS")
		)
		(fp_line
			(start -0.7874 -0.4064)
			(end 0.7874 -0.4064)
			(stroke
				(width 0.1524)
				(type default)
			)
			(layer "F.SilkS")
		)
		(fp_line
			(start 0.67945 0.3048)
			(end 0.120396 0.3048)
			(stroke
				(width 0.1)
				(type default)
			)
			(layer "F.Fab")
		)
		(fp_line
			(start 0.67945 -0.3048)
			(end 0.67945 0.3048)
			(stroke
				(width 0.1)
				(type default)
			)
			(layer "F.Fab")
		)
		(fp_line
			(start 0.12065 -0.2794)
			(end 0.12065 -0.3048)
			(stroke
				(width 0.1)
				(type default)
			)
			(layer "F.Fab")
		)
		(fp_line
			(start 0.12065 -0.3048)
			(end 0.67945 -0.3048)
			(stroke
				(width 0.1)
				(type default)
			)
			(layer "F.Fab")
		)
		(fp_line
			(start 0.120396 0.3048)
			(end 0.120396 0.2794)
			(stroke
				(width 0.1)
				(type default)
			)
			(layer "F.Fab")
		)
		(fp_line
			(start 0.120396 0.2794)
			(end -0.12065 0.2794)
			(stroke
				(width 0.1)
				(type default)
			)
			(layer "F.Fab")
		)
		(fp_line
			(start -0.12065 0.3048)
			(end -0.67945 0.3048)
			(stroke
				(width 0.1)
				(type default)
			)
			(layer "F.Fab")
		)
		(fp_line
			(start -0.12065 0.2794)
			(end -0.12065 0.3048)
			(stroke
				(width 0.1)
				(type default)
			)
			(layer "F.Fab")
		)
		(fp_line
			(start -0.12065 -0.2794)
			(end 0.12065 -0.2794)
			(stroke
				(width 0.1)
				(type default)
			)
			(layer "F.Fab")
		)
		(fp_line
			(start -0.12065 -0.305054)
			(end -0.12065 -0.2794)
			(stroke
				(width 0.1)
				(type default)
			)
			(layer "F.Fab")
		)
		(fp_line
			(start -0.67945 0.3048)
			(end -0.67945 -0.305054)
			(stroke
				(width 0.1)
				(type default)
			)
			(layer "F.Fab")
		)
		(fp_line
			(start -0.67945 -0.305054)
			(end -0.12065 -0.305054)
			(stroke
				(width 0.1)
				(type default)
			)
			(layer "F.Fab")
		)
		(pad "1" smd circle
			(at -0.40005 0 180)
			(size 0 0)
			(layers "F.Cu" "F.Mask" "F.Paste")
			(net "PVDD11_S3_P1_RESET_N_R")
		)
		(pad "2" smd circle
			(at 0.40005 0 180)
			(size 0 0)
			(layers "F.Cu" "F.Mask" "F.Paste")
			(net "PVDD18_S5_P1")
		)
	)
	(footprint ""
		(layer "F.Cu")
		(at 154.690826 -408.517344 -90)
		(property "Reference" "C6720"
			(at 0 0 270)
			(layer "F.SilkS")
			(hide yes)
			(effects
				(font
					(size 1.27 1.27)
				)
			)
		)
		(property "Value" ""
			(at 0 0 270)
			(layer "F.Fab")
			(effects
				(font
					(size 1.27 1.27)
				)
			)
		)
		(duplicate_pad_numbers_are_jumpers no)
		(fp_line
			(start -0.299974 0.150114)
			(end -0.299974 -0.150114)
			(stroke
				(width 0.1)
				(type default)
			)
			(layer "F.Fab")
		)
		(fp_line
			(start 0.299974 0.150114)
			(end -0.299974 0.150114)
			(stroke
				(width 0.1)
				(type default)
			)
			(layer "F.Fab")
		)
		(fp_line
			(start -0.299974 -0.150114)
			(end 0.299974 -0.150114)
			(stroke
				(width 0.1)
				(type default)
			)
			(layer "F.Fab")
		)
		(fp_line
			(start 0.299974 -0.150114)
			(end 0.299974 0.150114)
			(stroke
				(width 0.1)
				(type default)
			)
			(layer "F.Fab")
		)
		(pad "1" smd rect
			(at -0.2667 0 270)
			(size 0.3048 0.381)
			(layers "F.Cu" "F.Mask" "F.Paste")
			(net "P5E_CPU1_P2_TX_BUF_C_DN<13>")
		)
		(pad "2" smd rect
			(at 0.2667 0 270)
			(size 0.3048 0.381)
			(layers "F.Cu" "F.Mask" "F.Paste")
			(net "P5E_CPU1_P2_TX_BUF_DN<13>")
		)
	)
	(footprint ""
		(layer "F.Cu")
		(at 24.765 -364.617 180)
		(property "Reference" "C8359"
			(at 0 0 180)
			(layer "F.SilkS")
			(hide yes)
			(effects
				(font
					(size 1.27 1.27)
				)
			)
		)
		(property "Value" ""
			(at 0 0 180)
			(layer "F.Fab")
			(effects
				(font
					(size 1.27 1.27)
				)
			)
		)
		(duplicate_pad_numbers_are_jumpers no)
		(fp_line
			(start 0.7874 0.4064)
			(end -0.7874 0.4064)
			(stroke
				(width 0.1524)
				(type default)
			)
			(layer "F.SilkS")
		)
		(fp_line
			(start 0.7874 -0.4064)
			(end 0.7874 0.4064)
			(stroke
				(width 0.1524)
				(type default)
			)
			(layer "F.SilkS")
		)
		(fp_line
			(start -0.7874 0.4064)
			(end -0.7874 -0.4064)
			(stroke
				(width 0.1524)
				(type default)
			)
			(layer "F.SilkS")
		)
		(fp_line
			(start -0.7874 -0.4064)
			(end 0.7874 -0.4064)
			(stroke
				(width 0.1524)
				(type default)
			)
			(layer "F.SilkS")
		)
		(fp_line
			(start 0.67945 0.3048)
			(end 0.120396 0.3048)
			(stroke
				(width 0.1)
				(type default)
			)
			(layer "F.Fab")
		)
		(fp_line
			(start 0.67945 -0.3048)
			(end 0.67945 0.3048)
			(stroke
				(width 0.1)
				(type default)
			)
			(layer "F.Fab")
		)
		(fp_line
			(start 0.12065 -0.2794)
			(end 0.12065 -0.3048)
			(stroke
				(width 0.1)
				(type default)
			)
			(layer "F.Fab")
		)
		(fp_line
			(start 0.12065 -0.3048)
			(end 0.67945 -0.3048)
			(stroke
				(width 0.1)
				(type default)
			)
			(layer "F.Fab")
		)
		(fp_line
			(start 0.120396 0.3048)
			(end 0.120396 0.2794)
			(stroke
				(width 0.1)
				(type default)
			)
			(layer "F.Fab")
		)
		(fp_line
			(start 0.120396 0.2794)
			(end -0.12065 0.2794)
			(stroke
				(width 0.1)
				(type default)
			)
			(layer "F.Fab")
		)
		(fp_line
			(start -0.12065 0.3048)
			(end -0.67945 0.3048)
			(stroke
				(width 0.1)
				(type default)
			)
			(layer "F.Fab")
		)
		(fp_line
			(start -0.12065 0.2794)
			(end -0.12065 0.3048)
			(stroke
				(width 0.1)
				(type default)
			)
			(layer "F.Fab")
		)
		(fp_line
			(start -0.12065 -0.2794)
			(end 0.12065 -0.2794)
			(stroke
				(width 0.1)
				(type default)
			)
			(layer "F.Fab")
		)
		(fp_line
			(start -0.12065 -0.305054)
			(end -0.12065 -0.2794)
			(stroke
				(width 0.1)
				(type default)
			)
			(layer "F.Fab")
		)
		(fp_line
			(start -0.67945 0.3048)
			(end -0.67945 -0.305054)
			(stroke
				(width 0.1)
				(type default)
			)
			(layer "F.Fab")
		)
		(fp_line
			(start -0.67945 -0.305054)
			(end -0.12065 -0.305054)
			(stroke
				(width 0.1)
				(type default)
			)
			(layer "F.Fab")
		)
		(pad "1" smd circle
			(at -0.40005 0 180)
			(size 0 0)
			(layers "F.Cu" "F.Mask" "F.Paste")
			(net "PVDDCR_CPU1_P1_EN_R")
		)
		(pad "2" smd circle
			(at 0.40005 0 180)
			(size 0 0)
			(layers "F.Cu" "F.Mask" "F.Paste")
			(net "GND")
		)
	)
	(footprint ""
		(layer "F.Cu")
		(at 179.749958 -435.59984)
		(property "Reference" "H106"
			(at -6.56844 -4.312412 0)
			(unlocked yes)
			(layer "F.SilkS")
			(effects
				(font
					(size 0.7874 0.5842)
					(thickness 0.1524)
				)
				(justify left)
			)
		)
		(property "Value" ""
			(at 0 0 0)
			(layer "F.Fab")
			(effects
				(font
					(size 1.27 1.27)
				)
			)
		)
		(duplicate_pad_numbers_are_jumpers no)
		(pad "1" thru_hole circle
			(at 0 0)
			(size 10.0076 10.0076)
			(drill 5.6134)
			(layers "*.Cu" "*.Mask")
			(remove_unused_layers no)
			(net "GND")
			(clearance -1.9431)
		)
	)
	(footprint ""
		(layer "F.Cu")
		(at 397.623538 -393.86256)
		(property "Reference" "R1069"
			(at 0 0 0)
			(layer "F.SilkS")
			(hide yes)
			(effects
				(font
					(size 1.27 1.27)
				)
			)
		)
		(property "Value" ""
			(at 0 0 0)
			(layer "F.Fab")
			(effects
				(font
					(size 1.27 1.27)
				)
			)
		)
		(duplicate_pad_numbers_are_jumpers no)
		(fp_line
			(start -0.32512 -0.175006)
			(end 0.32512 -0.175006)
			(stroke
				(width 0.1)
				(type default)
			)
			(layer "F.Fab")
		)
		(fp_line
			(start -0.32512 0.175006)
			(end -0.32512 -0.175006)
			(stroke
				(width 0.1)
				(type default)
			)
			(layer "F.Fab")
		)
		(fp_line
			(start 0.32512 -0.175006)
			(end 0.32512 0.175006)
			(stroke
				(width 0.1)
				(type default)
			)
			(layer "F.Fab")
		)
		(fp_line
			(start 0.32512 0.175006)
			(end -0.32512 0.175006)
			(stroke
				(width 0.1)
				(type default)
			)
			(layer "F.Fab")
		)
		(pad "1" smd rect
			(at -0.2667 0)
			(size 0.3048 0.381)
			(layers "F.Cu" "F.Mask" "F.Paste")
			(net "P1V8_CPU0_RT_1D")
		)
		(pad "2" smd rect
			(at 0.2667 0 180)
			(size 0.3048 0.381)
			(layers "F.Cu" "F.Mask" "F.Paste")
			(net "GPIO2_RT_CPU0_P2")
		)
	)
	(footprint ""
		(layer "F.Cu")
		(at 307.220366 -429.224186 180)
		(property "Reference" "R4578"
			(at 0 0 180)
			(layer "F.SilkS")
			(hide yes)
			(effects
				(font
					(size 1.27 1.27)
				)
			)
		)
		(property "Value" ""
			(at 0 0 180)
			(layer "F.Fab")
			(effects
				(font
					(size 1.27 1.27)
				)
			)
		)
		(duplicate_pad_numbers_are_jumpers no)
		(fp_line
			(start 0.7874 0.4064)
			(end -0.7874 0.4064)
			(stroke
				(width 0.1524)
				(type default)
			)
			(layer "F.SilkS")
		)
		(fp_line
			(start 0.7874 -0.4064)
			(end 0.7874 0.4064)
			(stroke
				(width 0.1524)
				(type default)
			)
			(layer "F.SilkS")
		)
		(fp_line
			(start -0.7874 0.4064)
			(end -0.7874 -0.4064)
			(stroke
				(width 0.1524)
				(type default)
			)
			(layer "F.SilkS")
		)
		(fp_line
			(start -0.7874 -0.4064)
			(end 0.7874 -0.4064)
			(stroke
				(width 0.1524)
				(type default)
			)
			(layer "F.SilkS")
		)
		(fp_line
			(start 0.67945 0.3048)
			(end 0.120396 0.3048)
			(stroke
				(width 0.1)
				(type default)
			)
			(layer "F.Fab")
		)
		(fp_line
			(start 0.67945 -0.3048)
			(end 0.67945 0.3048)
			(stroke
				(width 0.1)
				(type default)
			)
			(layer "F.Fab")
		)
		(fp_line
			(start 0.12065 -0.2794)
			(end 0.12065 -0.3048)
			(stroke
				(width 0.1)
				(type default)
			)
			(layer "F.Fab")
		)
		(fp_line
			(start 0.12065 -0.3048)
			(end 0.67945 -0.3048)
			(stroke
				(width 0.1)
				(type default)
			)
			(layer "F.Fab")
		)
		(fp_line
			(start 0.120396 0.3048)
			(end 0.120396 0.2794)
			(stroke
				(width 0.1)
				(type default)
			)
			(layer "F.Fab")
		)
		(fp_line
			(start 0.120396 0.2794)
			(end -0.12065 0.2794)
			(stroke
				(width 0.1)
				(type default)
			)
			(layer "F.Fab")
		)
		(fp_line
			(start -0.12065 0.3048)
			(end -0.67945 0.3048)
			(stroke
				(width 0.1)
				(type default)
			)
			(layer "F.Fab")
		)
		(fp_line
			(start -0.12065 0.2794)
			(end -0.12065 0.3048)
			(stroke
				(width 0.1)
				(type default)
			)
			(layer "F.Fab")
		)
		(fp_line
			(start -0.12065 -0.2794)
			(end 0.12065 -0.2794)
			(stroke
				(width 0.1)
				(type default)
			)
			(layer "F.Fab")
		)
		(fp_line
			(start -0.12065 -0.305054)
			(end -0.12065 -0.2794)
			(stroke
				(width 0.1)
				(type default)
			)
			(layer "F.Fab")
		)
		(fp_line
			(start -0.67945 0.3048)
			(end -0.67945 -0.305054)
			(stroke
				(width 0.1)
				(type default)
			)
			(layer "F.Fab")
		)
		(fp_line
			(start -0.67945 -0.305054)
			(end -0.12065 -0.305054)
			(stroke
				(width 0.1)
				(type default)
			)
			(layer "F.Fab")
		)
		(pad "1" smd circle
			(at -0.40005 0 180)
			(size 0 0)
			(layers "F.Cu" "F.Mask" "F.Paste")
			(net "PRSNT_CABLE_GPU_A2_N")
		)
		(pad "2" smd circle
			(at 0.40005 0 180)
			(size 0 0)
			(layers "F.Cu" "F.Mask" "F.Paste")
			(net "PRSNT_CABLE_GPU_A2_ISO_N")
		)
	)
	(footprint ""
		(layer "F.Cu")
		(at 421.262302 -435.186836 -90)
		(property "Reference" "R4569"
			(at 0 0 270)
			(layer "F.SilkS")
			(hide yes)
			(effects
				(font
					(size 1.27 1.27)
				)
			)
		)
		(property "Value" ""
			(at 0 0 270)
			(layer "F.Fab")
			(effects
				(font
					(size 1.27 1.27)
				)
			)
		)
		(duplicate_pad_numbers_are_jumpers no)
		(fp_line
			(start -0.7874 0.4064)
			(end -0.7874 -0.4064)
			(stroke
				(width 0.1524)
				(type default)
			)
			(layer "F.SilkS")
		)
		(fp_line
			(start 0.7874 0.4064)
			(end -0.7874 0.4064)
			(stroke
				(width 0.1524)
				(type default)
			)
			(layer "F.SilkS")
		)
		(fp_line
			(start -0.7874 -0.4064)
			(end 0.7874 -0.4064)
			(stroke
				(width 0.1524)
				(type default)
			)
			(layer "F.SilkS")
		)
		(fp_line
			(start 0.7874 -0.4064)
			(end 0.7874 0.4064)
			(stroke
				(width 0.1524)
				(type default)
			)
			(layer "F.SilkS")
		)
		(fp_line
			(start -0.67945 0.3048)
			(end -0.67945 -0.305054)
			(stroke
				(width 0.1)
				(type default)
			)
			(layer "F.Fab")
		)
		(fp_line
			(start -0.12065 0.3048)
			(end -0.67945 0.3048)
			(stroke
				(width 0.1)
				(type default)
			)
			(layer "F.Fab")
		)
		(fp_line
			(start 0.120396 0.3048)
			(end 0.120396 0.2794)
			(stroke
				(width 0.1)
				(type default)
			)
			(layer "F.Fab")
		)
		(fp_line
			(start 0.67945 0.3048)
			(end 0.120396 0.3048)
			(stroke
				(width 0.1)
				(type default)
			)
			(layer "F.Fab")
		)
		(fp_line
			(start -0.12065 0.2794)
			(end -0.12065 0.3048)
			(stroke
				(width 0.1)
				(type default)
			)
			(layer "F.Fab")
		)
		(fp_line
			(start 0.120396 0.2794)
			(end -0.12065 0.2794)
			(stroke
				(width 0.1)
				(type default)
			)
			(layer "F.Fab")
		)
		(fp_line
			(start -0.12065 -0.2794)
			(end 0.12065 -0.2794)
			(stroke
				(width 0.1)
				(type default)
			)
			(layer "F.Fab")
		)
		(fp_line
			(start 0.12065 -0.2794)
			(end 0.12065 -0.3048)
			(stroke
				(width 0.1)
				(type default)
			)
			(layer "F.Fab")
		)
		(fp_line
			(start 0.12065 -0.3048)
			(end 0.67945 -0.3048)
			(stroke
				(width 0.1)
				(type default)
			)
			(layer "F.Fab")
		)
		(fp_line
			(start 0.67945 -0.3048)
			(end 0.67945 0.3048)
			(stroke
				(width 0.1)
				(type default)
			)
			(layer "F.Fab")
		)
		(fp_line
			(start -0.67945 -0.305054)
			(end -0.12065 -0.305054)
			(stroke
				(width 0.1)
				(type default)
			)
			(layer "F.Fab")
		)
		(fp_line
			(start -0.12065 -0.305054)
			(end -0.12065 -0.2794)
			(stroke
				(width 0.1)
				(type default)
			)
			(layer "F.Fab")
		)
		(pad "1" smd circle
			(at -0.40005 0 270)
			(size 0 0)
			(layers "F.Cu" "F.Mask" "F.Paste")
			(net "GPU_3V3IO_RSVD1")
		)
		(pad "2" smd circle
			(at 0.40005 0 270)
			(size 0 0)
			(layers "F.Cu" "F.Mask" "F.Paste")
			(net "GPU_3V3IO_RSVD1_ISO")
		)
	)
	(footprint ""
		(layer "F.Cu")
		(at 87.590884 -408.517344 -90)
		(property "Reference" "C6656"
			(at 0 0 270)
			(layer "F.SilkS")
			(hide yes)
			(effects
				(font
					(size 1.27 1.27)
				)
			)
		)
		(property "Value" ""
			(at 0 0 270)
			(layer "F.Fab")
			(effects
				(font
					(size 1.27 1.27)
				)
			)
		)
		(duplicate_pad_numbers_are_jumpers no)
		(fp_line
			(start -0.299974 0.150114)
			(end -0.299974 -0.150114)
			(stroke
				(width 0.1)
				(type default)
			)
			(layer "F.Fab")
		)
		(fp_line
			(start 0.299974 0.150114)
			(end -0.299974 0.150114)
			(stroke
				(width 0.1)
				(type default)
			)
			(layer "F.Fab")
		)
		(fp_line
			(start -0.299974 -0.150114)
			(end 0.299974 -0.150114)
			(stroke
				(width 0.1)
				(type default)
			)
			(layer "F.Fab")
		)
		(fp_line
			(start 0.299974 -0.150114)
			(end 0.299974 0.150114)
			(stroke
				(width 0.1)
				(type default)
			)
			(layer "F.Fab")
		)
		(pad "1" smd rect
			(at -0.2667 0 270)
			(size 0.3048 0.381)
			(layers "F.Cu" "F.Mask" "F.Paste")
			(net "P5E_CPU1_P0_TX_BUF_C_DN<13>")
		)
		(pad "2" smd rect
			(at 0.2667 0 270)
			(size 0.3048 0.381)
			(layers "F.Cu" "F.Mask" "F.Paste")
			(net "P5E_CPU1_P0_TX_BUF_DN<13>")
		)
	)
	(footprint ""
		(layer "F.Cu")
		(at 214.973408 -67.220084 -90)
		(property "Reference" "PD113"
			(at 3.924808 2.193544 90)
			(unlocked yes)
			(layer "F.SilkS")
			(effects
				(font
					(size 0.7874 0.5842)
					(thickness 0.1524)
				)
				(justify left)
			)
		)
		(property "Value" ""
			(at 0 0 270)
			(layer "F.Fab")
			(effects
				(font
					(size 1.27 1.27)
				)
			)
		)
		(duplicate_pad_numbers_are_jumpers no)
		(fp_line
			(start -3.400044 1.459992)
			(end -3.400044 -1.459992)
			(stroke
				(width 0.1524)
				(type default)
			)
			(layer "F.SilkS")
		)
		(fp_line
			(start 4.107942 1.459992)
			(end -3.400044 1.459992)
			(stroke
				(width 0.1524)
				(type default)
			)
			(layer "F.SilkS")
		)
		(fp_line
			(start -3.400044 -1.459992)
			(end 4.107942 -1.459992)
			(stroke
				(width 0.1524)
				(type default)
			)
			(layer "F.SilkS")
		)
		(fp_line
			(start 4.107942 -1.459992)
			(end 4.107942 1.459992)
			(stroke
				(width 0.1524)
				(type default)
			)
			(layer "F.SilkS")
		)
		(fp_rect
			(start 4.107942 1.459992)
			(end 3.308096 -1.459992)
			(stroke
				(width 0)
				(type default)
			)
			(fill yes)
			(layer "F.SilkS")
		)
		(fp_line
			(start -2.29997 1.459992)
			(end -2.29997 -1.459992)
			(stroke
				(width 0.1)
				(type default)
			)
			(layer "F.Fab")
		)
		(fp_line
			(start 2.29997 1.459992)
			(end -2.29997 1.459992)
			(stroke
				(width 0.1)
				(type default)
			)
			(layer "F.Fab")
		)
		(fp_line
			(start -2.29997 -1.459992)
			(end 2.29997 -1.459992)
			(stroke
				(width 0.1)
				(type default)
			)
			(layer "F.Fab")
		)
		(fp_line
			(start 2.29997 -1.459992)
			(end 2.29997 1.459992)
			(stroke
				(width 0.1)
				(type default)
			)
			(layer "F.Fab")
		)
		(fp_text user "+"
			(at -4.7752 -0.12065 270)
			(unlocked yes)
			(layer "F.SilkS")
			(effects
				(font
					(size 1.905 1.4224)
					(thickness 0.1524)
				)
				(justify left)
			)
		)
		(fp_text user "-"
			(at 4.545838 -1.956054 90)
			(unlocked yes)
			(layer "F.SilkS")
			(effects
				(font
					(size 1.905 1.4224)
					(thickness 0.1524)
				)
				(justify left)
			)
		)
		(fp_text user "-"
			(at 5.4102 0.29845 90)
			(unlocked yes)
			(layer "F.Fab")
			(effects
				(font
					(size 1.905 1.4224)
					(thickness 0.1524)
				)
				(justify left)
			)
		)
		(fp_text user "+"
			(at -4.7752 -0.12065 270)
			(unlocked yes)
			(layer "F.Fab")
			(effects
				(font
					(size 1.905 1.4224)
					(thickness 0.1524)
				)
				(justify left)
			)
		)
		(pad "A" smd rect
			(at -1.999996 0)
			(size 1.7018 2.5146)
			(layers "F.Cu" "F.Mask" "F.Paste")
			(net "GND")
		)
		(pad "C" smd rect
			(at 1.999996 0)
			(size 1.7018 2.5146)
			(layers "F.Cu" "F.Mask" "F.Paste")
			(net "P3V3_E1S_0_R")
		)
	)
	(footprint ""
		(layer "F.Cu")
		(at 205.590394 -346.505022)
		(property "Reference" "PC6000"
			(at 0 0 0)
			(layer "F.SilkS")
			(hide yes)
			(effects
				(font
					(size 1.27 1.27)
				)
			)
		)
		(property "Value" ""
			(at 0 0 0)
			(layer "F.Fab")
			(effects
				(font
					(size 1.27 1.27)
				)
			)
		)
		(duplicate_pad_numbers_are_jumpers no)
		(fp_line
			(start -0.7874 -0.4064)
			(end 0.7874 -0.4064)
			(stroke
				(width 0.1524)
				(type default)
			)
			(layer "F.SilkS")
		)
		(fp_line
			(start -0.7874 0.4064)
			(end -0.7874 -0.4064)
			(stroke
				(width 0.1524)
				(type default)
			)
			(layer "F.SilkS")
		)
		(fp_line
			(start 0.7874 -0.4064)
			(end 0.7874 0.4064)
			(stroke
				(width 0.1524)
				(type default)
			)
			(layer "F.SilkS")
		)
		(fp_line
			(start 0.7874 0.4064)
			(end -0.7874 0.4064)
			(stroke
				(width 0.1524)
				(type default)
			)
			(layer "F.SilkS")
		)
		(fp_line
			(start -0.67945 -0.305054)
			(end -0.12065 -0.305054)
			(stroke
				(width 0.1)
				(type default)
			)
			(layer "F.Fab")
		)
		(fp_line
			(start -0.67945 0.3048)
			(end -0.67945 -0.305054)
			(stroke
				(width 0.1)
				(type default)
			)
			(layer "F.Fab")
		)
		(fp_line
			(start -0.12065 -0.305054)
			(end -0.12065 -0.2794)
			(stroke
				(width 0.1)
				(type default)
			)
			(layer "F.Fab")
		)
		(fp_line
			(start -0.12065 -0.2794)
			(end 0.12065 -0.2794)
			(stroke
				(width 0.1)
				(type default)
			)
			(layer "F.Fab")
		)
		(fp_line
			(start -0.12065 0.2794)
			(end -0.12065 0.3048)
			(stroke
				(width 0.1)
				(type default)
			)
			(layer "F.Fab")
		)
		(fp_line
			(start -0.12065 0.3048)
			(end -0.67945 0.3048)
			(stroke
				(width 0.1)
				(type default)
			)
			(layer "F.Fab")
		)
		(fp_line
			(start 0.120396 0.2794)
			(end -0.12065 0.2794)
			(stroke
				(width 0.1)
				(type default)
			)
			(layer "F.Fab")
		)
		(fp_line
			(start 0.120396 0.3048)
			(end 0.120396 0.2794)
			(stroke
				(width 0.1)
				(type default)
			)
			(layer "F.Fab")
		)
		(fp_line
			(start 0.12065 -0.3048)
			(end 0.67945 -0.3048)
			(stroke
				(width 0.1)
				(type default)
			)
			(layer "F.Fab")
		)
		(fp_line
			(start 0.12065 -0.2794)
			(end 0.12065 -0.3048)
			(stroke
				(width 0.1)
				(type default)
			)
			(layer "F.Fab")
		)
		(fp_line
			(start 0.67945 -0.3048)
			(end 0.67945 0.3048)
			(stroke
				(width 0.1)
				(type default)
			)
			(layer "F.Fab")
		)
		(fp_line
			(start 0.67945 0.3048)
			(end 0.120396 0.3048)
			(stroke
				(width 0.1)
				(type default)
			)
			(layer "F.Fab")
		)
		(pad "1" smd circle
			(at -0.40005 0)
			(size 0 0)
			(layers "F.Cu" "F.Mask" "F.Paste")
			(net "P12V_AUX")
		)
		(pad "2" smd circle
			(at 0.40005 0)
			(size 0 0)
			(layers "F.Cu" "F.Mask" "F.Paste")
			(net "GND")
		)
	)
	(footprint ""
		(layer "F.Cu")
		(at 305.013106 -346.714572 -90)
		(property "Reference" "PC111_C1P0_4"
			(at 0 0 270)
			(layer "F.SilkS")
			(hide yes)
			(effects
				(font
					(size 1.27 1.27)
				)
			)
		)
		(property "Value" ""
			(at 0 0 270)
			(layer "F.Fab")
			(effects
				(font
					(size 1.27 1.27)
				)
			)
		)
		(duplicate_pad_numbers_are_jumpers no)
		(fp_line
			(start -0.7874 0.4064)
			(end -0.7874 -0.4064)
			(stroke
				(width 0.1524)
				(type default)
			)
			(layer "F.SilkS")
		)
		(fp_line
			(start 0.7874 0.4064)
			(end -0.7874 0.4064)
			(stroke
				(width 0.1524)
				(type default)
			)
			(layer "F.SilkS")
		)
		(fp_line
			(start -0.7874 -0.4064)
			(end 0.7874 -0.4064)
			(stroke
				(width 0.1524)
				(type default)
			)
			(layer "F.SilkS")
		)
		(fp_line
			(start 0.7874 -0.4064)
			(end 0.7874 0.4064)
			(stroke
				(width 0.1524)
				(type default)
			)
			(layer "F.SilkS")
		)
		(fp_line
			(start -0.67945 0.3048)
			(end -0.67945 -0.305054)
			(stroke
				(width 0.1)
				(type default)
			)
			(layer "F.Fab")
		)
		(fp_line
			(start -0.12065 0.3048)
			(end -0.67945 0.3048)
			(stroke
				(width 0.1)
				(type default)
			)
			(layer "F.Fab")
		)
		(fp_line
			(start 0.120396 0.3048)
			(end 0.120396 0.2794)
			(stroke
				(width 0.1)
				(type default)
			)
			(layer "F.Fab")
		)
		(fp_line
			(start 0.67945 0.3048)
			(end 0.120396 0.3048)
			(stroke
				(width 0.1)
				(type default)
			)
			(layer "F.Fab")
		)
		(fp_line
			(start -0.12065 0.2794)
			(end -0.12065 0.3048)
			(stroke
				(width 0.1)
				(type default)
			)
			(layer "F.Fab")
		)
		(fp_line
			(start 0.120396 0.2794)
			(end -0.12065 0.2794)
			(stroke
				(width 0.1)
				(type default)
			)
			(layer "F.Fab")
		)
		(fp_line
			(start -0.12065 -0.2794)
			(end 0.12065 -0.2794)
			(stroke
				(width 0.1)
				(type default)
			)
			(layer "F.Fab")
		)
		(fp_line
			(start 0.12065 -0.2794)
			(end 0.12065 -0.3048)
			(stroke
				(width 0.1)
				(type default)
			)
			(layer "F.Fab")
		)
		(fp_line
			(start 0.12065 -0.3048)
			(end 0.67945 -0.3048)
			(stroke
				(width 0.1)
				(type default)
			)
			(layer "F.Fab")
		)
		(fp_line
			(start 0.67945 -0.3048)
			(end 0.67945 0.3048)
			(stroke
				(width 0.1)
				(type default)
			)
			(layer "F.Fab")
		)
		(fp_line
			(start -0.67945 -0.305054)
			(end -0.12065 -0.305054)
			(stroke
				(width 0.1)
				(type default)
			)
			(layer "F.Fab")
		)
		(fp_line
			(start -0.12065 -0.305054)
			(end -0.12065 -0.2794)
			(stroke
				(width 0.1)
				(type default)
			)
			(layer "F.Fab")
		)
		(pad "1" smd circle
			(at -0.40005 0 270)
			(size 0 0)
			(layers "F.Cu" "F.Mask" "F.Paste")
			(net "PVDDCR_CPU1_P0_PVCC")
		)
		(pad "2" smd circle
			(at 0.40005 0 270)
			(size 0 0)
			(layers "F.Cu" "F.Mask" "F.Paste")
			(net "GND")
		)
	)
	(footprint ""
		(layer "F.Cu")
		(at 109.627924 -387.764274)
		(property "Reference" "R621"
			(at 0 0 0)
			(layer "F.SilkS")
			(hide yes)
			(effects
				(font
					(size 1.27 1.27)
				)
			)
		)
		(property "Value" ""
			(at 0 0 0)
			(layer "F.Fab")
			(effects
				(font
					(size 1.27 1.27)
				)
			)
		)
		(duplicate_pad_numbers_are_jumpers no)
		(fp_line
			(start -0.32512 -0.175006)
			(end 0.32512 -0.175006)
			(stroke
				(width 0.1)
				(type default)
			)
			(layer "F.Fab")
		)
		(fp_line
			(start -0.32512 0.175006)
			(end -0.32512 -0.175006)
			(stroke
				(width 0.1)
				(type default)
			)
			(layer "F.Fab")
		)
		(fp_line
			(start 0.32512 -0.175006)
			(end 0.32512 0.175006)
			(stroke
				(width 0.1)
				(type default)
			)
			(layer "F.Fab")
		)
		(fp_line
			(start 0.32512 0.175006)
			(end -0.32512 0.175006)
			(stroke
				(width 0.1)
				(type default)
			)
			(layer "F.Fab")
		)
		(pad "1" smd rect
			(at -0.2667 0)
			(size 0.3048 0.381)
			(layers "F.Cu" "F.Mask" "F.Paste")
			(net "CLK_100M_RETIMER_CPU1_P3_R_DP")
		)
		(pad "2" smd rect
			(at 0.2667 0 180)
			(size 0.3048 0.381)
			(layers "F.Cu" "F.Mask" "F.Paste")
			(net "CLK_100M_RETIMER_CPU1_P3_DP")
		)
	)
	(footprint ""
		(layer "F.Cu")
		(at 95.885 -78.105)
		(property "Reference" "U33"
			(at -2.032 -2.377948 0)
			(unlocked yes)
			(layer "F.SilkS")
			(effects
				(font
					(size 0.7874 0.5842)
					(thickness 0.1524)
				)
				(justify left)
			)
		)
		(property "Value" ""
			(at 0 0 0)
			(layer "F.Fab")
			(effects
				(font
					(size 1.27 1.27)
				)
			)
		)
		(duplicate_pad_numbers_are_jumpers no)
		(fp_line
			(start -2.0574 -1.651)
			(end -0.381 -1.651)
			(stroke
				(width 0.1524)
				(type default)
			)
			(layer "F.SilkS")
		)
		(fp_line
			(start -2.0574 1.651)
			(end -2.0574 -1.651)
			(stroke
				(width 0.1524)
				(type default)
			)
			(layer "F.SilkS")
		)
		(fp_line
			(start -0.381 -1.651)
			(end 0 -1.016)
			(stroke
				(width 0.1524)
				(type default)
			)
			(layer "F.SilkS")
		)
		(fp_line
			(start 0 -1.016)
			(end 0.381 -1.651)
			(stroke
				(width 0.1524)
				(type default)
			)
			(layer "F.SilkS")
		)
		(fp_line
			(start 0.381 -1.651)
			(end 2.0574 -1.651)
			(stroke
				(width 0.1524)
				(type default)
			)
			(layer "F.SilkS")
		)
		(fp_line
			(start 2.0574 -1.651)
			(end 2.0574 1.651)
			(stroke
				(width 0.1524)
				(type default)
			)
			(layer "F.SilkS")
		)
		(fp_line
			(start 2.0574 1.651)
			(end -2.0574 1.651)
			(stroke
				(width 0.1524)
				(type default)
			)
			(layer "F.SilkS")
		)
		(fp_poly
			(pts
				(xy -2.71272 -0.719328) (xy -2.71272 -1.344168) (xy -2.159 -1.016)
			)
			(stroke
				(width 0)
				(type default)
			)
			(fill yes)
			(layer "F.SilkS")
		)
		(fp_line
			(start -1.599946 -1.199896)
			(end -0.899922 -1.199896)
			(stroke
				(width 0.1)
				(type default)
			)
			(layer "F.Fab")
		)
		(fp_line
			(start -1.599946 1.199896)
			(end -1.599946 -1.199896)
			(stroke
				(width 0.1)
				(type default)
			)
			(layer "F.Fab")
		)
		(fp_line
			(start -0.899922 -1.549908)
			(end 0.899922 -1.549908)
			(stroke
				(width 0.1)
				(type default)
			)
			(layer "F.Fab")
		)
		(fp_line
			(start -0.899922 -1.199896)
			(end -0.899922 -1.549908)
			(stroke
				(width 0.1)
				(type default)
			)
			(layer "F.Fab")
		)
		(fp_line
			(start -0.899922 1.199896)
			(end -1.599946 1.199896)
			(stroke
				(width 0.1)
				(type default)
			)
			(layer "F.Fab")
		)
		(fp_line
			(start -0.899922 1.549908)
			(end -0.899922 1.199896)
			(stroke
				(width 0.1)
				(type default)
			)
			(layer "F.Fab")
		)
		(fp_line
			(start 0.899922 -1.549908)
			(end 0.899922 -1.199896)
			(stroke
				(width 0.1)
				(type default)
			)
			(layer "F.Fab")
		)
		(fp_line
			(start 0.899922 -1.199896)
			(end 1.599946 -1.199896)
			(stroke
				(width 0.1)
				(type default)
			)
			(layer "F.Fab")
		)
		(fp_line
			(start 0.899922 1.199896)
			(end 0.899922 1.549908)
			(stroke
				(width 0.1)
				(type default)
			)
			(layer "F.Fab")
		)
		(fp_line
			(start 0.899922 1.549908)
			(end -0.899922 1.549908)
			(stroke
				(width 0.1)
				(type default)
			)
			(layer "F.Fab")
		)
		(fp_line
			(start 1.599946 -1.199896)
			(end 1.599946 1.199896)
			(stroke
				(width 0.1)
				(type default)
			)
			(layer "F.Fab")
		)
		(fp_line
			(start 1.599946 1.199896)
			(end 0.899922 1.199896)
			(stroke
				(width 0.1)
				(type default)
			)
			(layer "F.Fab")
		)
		(fp_poly
			(pts
				(xy -2.71272 -0.719328) (xy -2.71272 -1.344168) (xy -2.159 -1.016)
			)
			(stroke
				(width 0)
				(type default)
			)
			(fill yes)
			(layer "F.Fab")
		)
		(pad "1" smd rect
			(at -1.225042 -0.94996 270)
			(size 0.5588 1.3462)
			(layers "F.Cu" "F.Mask" "F.Paste")
			(net "Net_10853")
		)
		(pad "2" smd rect
			(at -1.225042 0 270)
			(size 0.5588 1.3462)
			(layers "F.Cu" "F.Mask" "F.Paste")
			(net "HP_LVC3_OCP_V3_2_P12V_R_PWRGD")
		)
		(pad "3" smd rect
			(at -1.225042 0.94996 270)
			(size 0.5588 1.3462)
			(layers "F.Cu" "F.Mask" "F.Paste")
			(net "GND")
		)
		(pad "4" smd rect
			(at 1.225042 0.94996 270)
			(size 0.5588 1.3462)
			(layers "F.Cu" "F.Mask" "F.Paste")
			(net "P12V_OCP_V3_2_PLD_R_PWRGD")
		)
		(pad "5" smd rect
			(at 1.225042 -0.94996 270)
			(size 0.5588 1.3462)
			(layers "F.Cu" "F.Mask" "F.Paste")
			(net "P3V3_AUX")
		)
	)
	(footprint ""
		(layer "F.Cu")
		(at 102.154736 -127.787654 90)
		(property "Reference" "R1443"
			(at 0 0 90)
			(layer "F.SilkS")
			(hide yes)
			(effects
				(font
					(size 1.27 1.27)
				)
			)
		)
		(property "Value" ""
			(at 0 0 90)
			(layer "F.Fab")
			(effects
				(font
					(size 1.27 1.27)
				)
			)
		)
		(duplicate_pad_numbers_are_jumpers no)
		(fp_line
			(start 0.7874 -0.4064)
			(end 0.7874 0.4064)
			(stroke
				(width 0.1524)
				(type default)
			)
			(layer "F.SilkS")
		)
		(fp_line
			(start -0.7874 -0.4064)
			(end 0.7874 -0.4064)
			(stroke
				(width 0.1524)
				(type default)
			)
			(layer "F.SilkS")
		)
		(fp_line
			(start 0.7874 0.4064)
			(end -0.7874 0.4064)
			(stroke
				(width 0.1524)
				(type default)
			)
			(layer "F.SilkS")
		)
		(fp_line
			(start -0.7874 0.4064)
			(end -0.7874 -0.4064)
			(stroke
				(width 0.1524)
				(type default)
			)
			(layer "F.SilkS")
		)
		(fp_line
			(start -0.12065 -0.305054)
			(end -0.12065 -0.2794)
			(stroke
				(width 0.1)
				(type default)
			)
			(layer "F.Fab")
		)
		(fp_line
			(start -0.67945 -0.305054)
			(end -0.12065 -0.305054)
			(stroke
				(width 0.1)
				(type default)
			)
			(layer "F.Fab")
		)
		(fp_line
			(start 0.67945 -0.3048)
			(end 0.67945 0.3048)
			(stroke
				(width 0.1)
				(type default)
			)
			(layer "F.Fab")
		)
		(fp_line
			(start 0.12065 -0.3048)
			(end 0.67945 -0.3048)
			(stroke
				(width 0.1)
				(type default)
			)
			(layer "F.Fab")
		)
		(fp_line
			(start 0.12065 -0.2794)
			(end 0.12065 -0.3048)
			(stroke
				(width 0.1)
				(type default)
			)
			(layer "F.Fab")
		)
		(fp_line
			(start -0.12065 -0.2794)
			(end 0.12065 -0.2794)
			(stroke
				(width 0.1)
				(type default)
			)
			(layer "F.Fab")
		)
		(fp_line
			(start 0.120396 0.2794)
			(end -0.12065 0.2794)
			(stroke
				(width 0.1)
				(type default)
			)
			(layer "F.Fab")
		)
		(fp_line
			(start -0.12065 0.2794)
			(end -0.12065 0.3048)
			(stroke
				(width 0.1)
				(type default)
			)
			(layer "F.Fab")
		)
		(fp_line
			(start 0.67945 0.3048)
			(end 0.120396 0.3048)
			(stroke
				(width 0.1)
				(type default)
			)
			(layer "F.Fab")
		)
		(fp_line
			(start 0.120396 0.3048)
			(end 0.120396 0.2794)
			(stroke
				(width 0.1)
				(type default)
			)
			(layer "F.Fab")
		)
		(fp_line
			(start -0.12065 0.3048)
			(end -0.67945 0.3048)
			(stroke
				(width 0.1)
				(type default)
			)
			(layer "F.Fab")
		)
		(fp_line
			(start -0.67945 0.3048)
			(end -0.67945 -0.305054)
			(stroke
				(width 0.1)
				(type default)
			)
			(layer "F.Fab")
		)
		(pad "1" smd circle
			(at -0.40005 0 90)
			(size 0 0)
			(layers "F.Cu" "F.Mask" "F.Paste")
			(net "PWRGD_P12V_MEM_CPU0_EN")
		)
		(pad "2" smd circle
			(at 0.40005 0 90)
			(size 0 0)
			(layers "F.Cu" "F.Mask" "F.Paste")
			(net "GND")
		)
	)
	(footprint ""
		(layer "F.Cu")
		(at 406.147778 -168.59377 180)
		(property "Reference" "PU50"
			(at 5.635752 -4.803394 0)
			(unlocked yes)
			(layer "F.SilkS")
			(effects
				(font
					(size 0.7874 0.5842)
					(thickness 0.1524)
				)
				(justify left)
			)
		)
		(property "Value" ""
			(at 0 0 180)
			(layer "F.Fab")
			(effects
				(font
					(size 1.27 1.27)
				)
			)
		)
		(duplicate_pad_numbers_are_jumpers no)
		(fp_line
			(start 2.500122 2.999994)
			(end 2.2987 2.999994)
			(stroke
				(width 0.1524)
				(type default)
			)
			(layer "F.SilkS")
		)
		(fp_line
			(start 2.500122 2.339594)
			(end 2.500122 2.999994)
			(stroke
				(width 0.1524)
				(type default)
			)
			(layer "F.SilkS")
		)
		(fp_line
			(start 2.500122 -2.999994)
			(end 2.500122 -2.44348)
			(stroke
				(width 0.1524)
				(type default)
			)
			(layer "F.SilkS")
		)
		(fp_line
			(start 2.31394 -2.999994)
			(end 2.500122 -2.999994)
			(stroke
				(width 0.1524)
				(type default)
			)
			(layer "F.SilkS")
		)
		(fp_line
			(start -2.2987 2.999994)
			(end -2.500122 2.999994)
			(stroke
				(width 0.1524)
				(type default)
			)
			(layer "F.SilkS")
		)
		(fp_line
			(start -2.500122 2.999994)
			(end -2.500122 2.339594)
			(stroke
				(width 0.1524)
				(type default)
			)
			(layer "F.SilkS")
		)
		(fp_line
			(start -2.500122 0.6604)
			(end -2.500122 0.229108)
			(stroke
				(width 0.1524)
				(type default)
			)
			(layer "F.SilkS")
		)
		(fp_line
			(start -2.500122 -2.529078)
			(end -2.500122 -2.999994)
			(stroke
				(width 0.1524)
				(type default)
			)
			(layer "F.SilkS")
		)
		(fp_line
			(start -2.500122 -2.999994)
			(end -2.24409 -2.999994)
			(stroke
				(width 0.1524)
				(type default)
			)
			(layer "F.SilkS")
		)
		(fp_poly
			(pts
				(xy -2.758948 -2.425192) (xy -3.526028 -2.680716) (xy -3.014472 -3.192272)
			)
			(stroke
				(width 0)
				(type default)
			)
			(fill yes)
			(layer "F.SilkS")
		)
		(fp_line
			(start 2.500122 2.999994)
			(end -2.500122 2.999994)
			(stroke
				(width 0.1)
				(type default)
			)
			(layer "F.Fab")
		)
		(fp_line
			(start 2.500122 -2.999994)
			(end 2.500122 2.999994)
			(stroke
				(width 0.1)
				(type default)
			)
			(layer "F.Fab")
		)
		(fp_line
			(start -2.500122 2.999994)
			(end -2.500122 -2.999994)
			(stroke
				(width 0.1)
				(type default)
			)
			(layer "F.Fab")
		)
		(fp_line
			(start -2.500122 -2.999994)
			(end 2.500122 -2.999994)
			(stroke
				(width 0.1)
				(type default)
			)
			(layer "F.Fab")
		)
		(fp_poly
			(pts
				(xy -4.218432 -2.783078) (xy -4.218432 -1.767078) (xy -3.202432 -2.275078)
			)
			(stroke
				(width 0)
				(type default)
			)
			(fill yes)
			(layer "F.Fab")
		)
		(pad "1" smd rect
			(at -2.400046 -2.275078 270)
			(size 0.2286 0.6096)
			(layers "F.Cu" "F.Mask" "F.Paste")
			(net "PVDDCR_SOC_P0_VOS2")
		)
		(pad "2" smd rect
			(at -2.400046 -1.82499 270)
			(size 0.2286 0.6096)
			(layers "F.Cu" "F.Mask" "F.Paste")
			(net "GND")
		)
		(pad "3" smd rect
			(at -2.400046 -1.374902 270)
			(size 0.2286 0.6096)
			(layers "F.Cu" "F.Mask" "F.Paste")
			(net "PVDDCR_SOC_P0_VCC2")
		)
		(pad "4" smd rect
			(at -2.400046 -0.925068 270)
			(size 0.2286 0.6096)
			(layers "F.Cu" "F.Mask" "F.Paste")
			(net "PVDDCR_CPU0_P0_PVCC")
		)
		(pad "5" smd rect
			(at -2.400046 -0.47498 270)
			(size 0.2286 0.6096)
			(layers "F.Cu" "F.Mask" "F.Paste")
			(net "GND")
		)
		(pad "6" smd rect
			(at -2.400046 -0.024892 270)
			(size 0.2286 0.6096)
			(layers "F.Cu" "F.Mask" "F.Paste")
			(net "NC_PVDDCR_SOC_P0_GL1_2")
		)
		(pad "7_9-20_24" smd circle
			(at 0 1.150112 270)
			(size 0 0)
			(layers "F.Cu" "F.Mask" "F.Paste")
			(net "GND")
		)
		(pad "10_19" smd rect
			(at 0 2.899918 270)
			(size 0.6096 4.318)
			(layers "F.Cu" "F.Mask" "F.Paste")
			(net "SW_PVDDCR_SOC_P0_SW2")
		)
		(pad "25_29" smd rect
			(at 1.549908 -1.279906 90)
			(size 2.0574 2.3114)
			(layers "F.Cu" "F.Mask" "F.Paste")
			(net "SW_P12V_AUX_PVDDCR_SOC_P0_FLT")
		)
		(pad "30" smd rect
			(at 2.05994 -2.899918 180)
			(size 0.2286 0.6096)
			(layers "F.Cu" "F.Mask" "F.Paste")
			(net "SW_P12V_AUX_PVDDCR_SOC_P0_FLT")
		)
		(pad "31" smd rect
			(at 1.610106 -2.899918 180)
			(size 0.2286 0.6096)
			(layers "F.Cu" "F.Mask" "F.Paste")
			(net "NC_PVDDCR_SOC_P0_DNC2")
		)
		(pad "32" smd rect
			(at 1.160018 -2.899918 180)
			(size 0.2286 0.6096)
			(layers "F.Cu" "F.Mask" "F.Paste")
			(net "SW_PVDDCR_SOC_P0_PH2")
		)
		(pad "33" smd rect
			(at 0.70993 -2.899918 180)
			(size 0.2286 0.6096)
			(layers "F.Cu" "F.Mask" "F.Paste")
			(net "SW_PVDDCR_SOC_P0_BOOT2")
		)
		(pad "34" smd rect
			(at 0.260096 -2.899918 180)
			(size 0.2286 0.6096)
			(layers "F.Cu" "F.Mask" "F.Paste")
			(net "PVDDCR_SOC_P0_PWM2")
		)
		(pad "35" smd rect
			(at -0.189992 -2.899918 180)
			(size 0.2286 0.6096)
			(layers "F.Cu" "F.Mask" "F.Paste")
			(net "PVDDCR_SOC_P0_VCC2")
		)
		(pad "36" smd rect
			(at -0.64008 -2.899918 180)
			(size 0.2286 0.6096)
			(layers "F.Cu" "F.Mask" "F.Paste")
			(net "PVDDCR_SOC_P0_TEMP1")
		)
		(pad "37" smd rect
			(at -1.089914 -2.899918 180)
			(size 0.2286 0.6096)
			(layers "F.Cu" "F.Mask" "F.Paste")
			(net "PVDDCR_SOC_P0_LSET2")
		)
		(pad "38" smd rect
			(at -1.540002 -2.899918 180)
			(size 0.2286 0.6096)
			(layers "F.Cu" "F.Mask" "F.Paste")
			(net "PVDDCR_SOC_P0_IMON2")
		)
		(pad "39" smd rect
			(at -1.99009 -2.899918 180)
			(size 0.2286 0.6096)
			(layers "F.Cu" "F.Mask" "F.Paste")
			(net "PVDDCR_CPU0_P0_VCCS")
		)
		(pad "40" smd rect
			(at -0.87503 -1.27508 180)
			(size 1.7526 1.9558)
			(layers "F.Cu" "F.Mask" "F.Paste")
			(net "GND")
		)
		(pad "41" smd rect
			(at -1.525016 0.249936 90)
			(size 0.3048 0.4572)
			(layers "F.Cu" "F.Mask" "F.Paste")
			(net "NC_PVDDCR_SOC_P0_GL2_2")
		)
		(zone
			(layer "F.Cu")
			(hatch none 0.5)
			(connect_pads
				(clearance 0)
			)
			(min_thickness 0.25)
			(keepout
				(tracks not_allowed)
				(vias allowed)
				(pads allowed)
				(copperpour not_allowed)
				(footprints allowed)
			)
			(placement
				(enabled no)
				(sheetname "")
			)
			(fill
				(thermal_gap 0.5)
				(thermal_bridge_width 0.5)
				(island_removal_mode 0)
			)
			(polygon
				(pts
					(xy 408.6479 -171.186856) (xy 408.6479 -170.844464) (xy 403.647656 -170.844464) (xy 403.647656 -171.175934)
					(xy 403.937978 -171.175934) (xy 403.937978 -171.138088) (xy 408.357578 -171.138088) (xy 408.357578 -171.186856)
				)
			)
		)
		(zone
			(layer "F.Cu")
			(hatch none 0.5)
			(connect_pads
				(clearance 0)
			)
			(min_thickness 0.25)
			(keepout
				(tracks not_allowed)
				(vias allowed)
				(pads allowed)
				(copperpour not_allowed)
				(footprints allowed)
			)
			(placement
				(enabled no)
				(sheetname "")
			)
			(fill
				(thermal_gap 0.5)
				(thermal_bridge_width 0.5)
				(island_removal_mode 0)
			)
			(polygon
				(pts
					(xy 406.095708 -168.34739) (xy 406.095708 -166.28999) (xy 407.949908 -166.28999) (xy 407.949908 -166.531036)
					(xy 408.192224 -166.531036) (xy 408.192224 -166.049452) (xy 404.298658 -166.049452) (xy 404.298658 -166.234364)
					(xy 405.80437 -166.234364) (xy 405.80437 -168.393364) (xy 403.647656 -168.393364) (xy 403.647656 -168.643046)
					(xy 405.800052 -168.643046)
				)
			)
		)
	)
	(footprint ""
		(layer "F.Cu")
		(at 33.81248 -368.467132 90)
		(property "Reference" "PC93"
			(at 0 0 90)
			(layer "F.SilkS")
			(hide yes)
			(effects
				(font
					(size 1.27 1.27)
				)
			)
		)
		(property "Value" ""
			(at 0 0 90)
			(layer "F.Fab")
			(effects
				(font
					(size 1.27 1.27)
				)
			)
		)
		(duplicate_pad_numbers_are_jumpers no)
		(fp_line
			(start 0.7874 -0.4064)
			(end 0.7874 0.4064)
			(stroke
				(width 0.1524)
				(type default)
			)
			(layer "F.SilkS")
		)
		(fp_line
			(start -0.7874 -0.4064)
			(end 0.7874 -0.4064)
			(stroke
				(width 0.1524)
				(type default)
			)
			(layer "F.SilkS")
		)
		(fp_line
			(start 0.7874 0.4064)
			(end -0.7874 0.4064)
			(stroke
				(width 0.1524)
				(type default)
			)
			(layer "F.SilkS")
		)
		(fp_line
			(start -0.7874 0.4064)
			(end -0.7874 -0.4064)
			(stroke
				(width 0.1524)
				(type default)
			)
			(layer "F.SilkS")
		)
		(fp_line
			(start -0.12065 -0.305054)
			(end -0.12065 -0.2794)
			(stroke
				(width 0.1)
				(type default)
			)
			(layer "F.Fab")
		)
		(fp_line
			(start -0.67945 -0.305054)
			(end -0.12065 -0.305054)
			(stroke
				(width 0.1)
				(type default)
			)
			(layer "F.Fab")
		)
		(fp_line
			(start 0.67945 -0.3048)
			(end 0.67945 0.3048)
			(stroke
				(width 0.1)
				(type default)
			)
			(layer "F.Fab")
		)
		(fp_line
			(start 0.12065 -0.3048)
			(end 0.67945 -0.3048)
			(stroke
				(width 0.1)
				(type default)
			)
			(layer "F.Fab")
		)
		(fp_line
			(start 0.12065 -0.2794)
			(end 0.12065 -0.3048)
			(stroke
				(width 0.1)
				(type default)
			)
			(layer "F.Fab")
		)
		(fp_line
			(start -0.12065 -0.2794)
			(end 0.12065 -0.2794)
			(stroke
				(width 0.1)
				(type default)
			)
			(layer "F.Fab")
		)
		(fp_line
			(start 0.120396 0.2794)
			(end -0.12065 0.2794)
			(stroke
				(width 0.1)
				(type default)
			)
			(layer "F.Fab")
		)
		(fp_line
			(start -0.12065 0.2794)
			(end -0.12065 0.3048)
			(stroke
				(width 0.1)
				(type default)
			)
			(layer "F.Fab")
		)
		(fp_line
			(start 0.67945 0.3048)
			(end 0.120396 0.3048)
			(stroke
				(width 0.1)
				(type default)
			)
			(layer "F.Fab")
		)
		(fp_line
			(start 0.120396 0.3048)
			(end 0.120396 0.2794)
			(stroke
				(width 0.1)
				(type default)
			)
			(layer "F.Fab")
		)
		(fp_line
			(start -0.12065 0.3048)
			(end -0.67945 0.3048)
			(stroke
				(width 0.1)
				(type default)
			)
			(layer "F.Fab")
		)
		(fp_line
			(start -0.67945 0.3048)
			(end -0.67945 -0.305054)
			(stroke
				(width 0.1)
				(type default)
			)
			(layer "F.Fab")
		)
		(pad "1" smd circle
			(at -0.40005 0 90)
			(size 0 0)
			(layers "F.Cu" "F.Mask" "F.Paste")
			(net "PVDDCR_CPU1_P1_VCCS")
		)
		(pad "2" smd circle
			(at 0.40005 0 90)
			(size 0 0)
			(layers "F.Cu" "F.Mask" "F.Paste")
			(net "GND")
		)
	)
	(footprint ""
		(layer "F.Cu")
		(at 173.597062 -32.935672 90)
		(property "Reference" "PR4005"
			(at 0 0 90)
			(layer "F.SilkS")
			(hide yes)
			(effects
				(font
					(size 1.27 1.27)
				)
			)
		)
		(property "Value" ""
			(at 0 0 90)
			(layer "F.Fab")
			(effects
				(font
					(size 1.27 1.27)
				)
			)
		)
		(duplicate_pad_numbers_are_jumpers no)
		(fp_line
			(start 0.7874 -0.4064)
			(end 0.7874 0.4064)
			(stroke
				(width 0.1524)
				(type default)
			)
			(layer "F.SilkS")
		)
		(fp_line
			(start -0.7874 -0.4064)
			(end 0.7874 -0.4064)
			(stroke
				(width 0.1524)
				(type default)
			)
			(layer "F.SilkS")
		)
		(fp_line
			(start 0.7874 0.4064)
			(end -0.7874 0.4064)
			(stroke
				(width 0.1524)
				(type default)
			)
			(layer "F.SilkS")
		)
		(fp_line
			(start -0.7874 0.4064)
			(end -0.7874 -0.4064)
			(stroke
				(width 0.1524)
				(type default)
			)
			(layer "F.SilkS")
		)
		(fp_line
			(start -0.12065 -0.305054)
			(end -0.12065 -0.2794)
			(stroke
				(width 0.1)
				(type default)
			)
			(layer "F.Fab")
		)
		(fp_line
			(start -0.67945 -0.305054)
			(end -0.12065 -0.305054)
			(stroke
				(width 0.1)
				(type default)
			)
			(layer "F.Fab")
		)
		(fp_line
			(start 0.67945 -0.3048)
			(end 0.67945 0.3048)
			(stroke
				(width 0.1)
				(type default)
			)
			(layer "F.Fab")
		)
		(fp_line
			(start 0.12065 -0.3048)
			(end 0.67945 -0.3048)
			(stroke
				(width 0.1)
				(type default)
			)
			(layer "F.Fab")
		)
		(fp_line
			(start 0.12065 -0.2794)
			(end 0.12065 -0.3048)
			(stroke
				(width 0.1)
				(type default)
			)
			(layer "F.Fab")
		)
		(fp_line
			(start -0.12065 -0.2794)
			(end 0.12065 -0.2794)
			(stroke
				(width 0.1)
				(type default)
			)
			(layer "F.Fab")
		)
		(fp_line
			(start 0.120396 0.2794)
			(end -0.12065 0.2794)
			(stroke
				(width 0.1)
				(type default)
			)
			(layer "F.Fab")
		)
		(fp_line
			(start -0.12065 0.2794)
			(end -0.12065 0.3048)
			(stroke
				(width 0.1)
				(type default)
			)
			(layer "F.Fab")
		)
		(fp_line
			(start 0.67945 0.3048)
			(end 0.120396 0.3048)
			(stroke
				(width 0.1)
				(type default)
			)
			(layer "F.Fab")
		)
		(fp_line
			(start 0.120396 0.3048)
			(end 0.120396 0.2794)
			(stroke
				(width 0.1)
				(type default)
			)
			(layer "F.Fab")
		)
		(fp_line
			(start -0.12065 0.3048)
			(end -0.67945 0.3048)
			(stroke
				(width 0.1)
				(type default)
			)
			(layer "F.Fab")
		)
		(fp_line
			(start -0.67945 0.3048)
			(end -0.67945 -0.305054)
			(stroke
				(width 0.1)
				(type default)
			)
			(layer "F.Fab")
		)
		(pad "1" smd circle
			(at -0.40005 0 90)
			(size 0 0)
			(layers "F.Cu" "F.Mask" "F.Paste")
			(net "P12V_SCM_IMON")
		)
		(pad "2" smd circle
			(at 0.40005 0 90)
			(size 0 0)
			(layers "F.Cu" "F.Mask" "F.Paste")
			(net "GND")
		)
	)
	(footprint ""
		(layer "F.Cu")
		(at 359.49509 -391.0584 180)
		(property "Reference" "R1017"
			(at 0 0 180)
			(layer "F.SilkS")
			(hide yes)
			(effects
				(font
					(size 1.27 1.27)
				)
			)
		)
		(property "Value" ""
			(at 0 0 180)
			(layer "F.Fab")
			(effects
				(font
					(size 1.27 1.27)
				)
			)
		)
		(duplicate_pad_numbers_are_jumpers no)
		(fp_line
			(start 0.32512 0.175006)
			(end -0.32512 0.175006)
			(stroke
				(width 0.1)
				(type default)
			)
			(layer "F.Fab")
		)
		(fp_line
			(start 0.32512 -0.175006)
			(end 0.32512 0.175006)
			(stroke
				(width 0.1)
				(type default)
			)
			(layer "F.Fab")
		)
		(fp_line
			(start -0.32512 0.175006)
			(end -0.32512 -0.175006)
			(stroke
				(width 0.1)
				(type default)
			)
			(layer "F.Fab")
		)
		(fp_line
			(start -0.32512 -0.175006)
			(end 0.32512 -0.175006)
			(stroke
				(width 0.1)
				(type default)
			)
			(layer "F.Fab")
		)
		(pad "1" smd rect
			(at -0.2667 0 180)
			(size 0.3048 0.381)
			(layers "F.Cu" "F.Mask" "F.Paste")
			(net "P1V8_CPU0_RT_1D")
		)
		(pad "2" smd rect
			(at 0.2667 0)
			(size 0.3048 0.381)
			(layers "F.Cu" "F.Mask" "F.Paste")
			(net "RT_CPU0_P1_ADDR1")
		)
	)
	(footprint ""
		(layer "F.Cu")
		(at 171.20743 -103.96728)
		(property "Reference" "R12"
			(at 0 0 0)
			(layer "F.SilkS")
			(hide yes)
			(effects
				(font
					(size 1.27 1.27)
				)
			)
		)
		(property "Value" ""
			(at 0 0 0)
			(layer "F.Fab")
			(effects
				(font
					(size 1.27 1.27)
				)
			)
		)
		(duplicate_pad_numbers_are_jumpers no)
		(fp_line
			(start -0.7874 -0.4064)
			(end 0.7874 -0.4064)
			(stroke
				(width 0.1524)
				(type default)
			)
			(layer "F.SilkS")
		)
		(fp_line
			(start -0.7874 0.4064)
			(end -0.7874 -0.4064)
			(stroke
				(width 0.1524)
				(type default)
			)
			(layer "F.SilkS")
		)
		(fp_line
			(start 0.7874 -0.4064)
			(end 0.7874 0.4064)
			(stroke
				(width 0.1524)
				(type default)
			)
			(layer "F.SilkS")
		)
		(fp_line
			(start 0.7874 0.4064)
			(end -0.7874 0.4064)
			(stroke
				(width 0.1524)
				(type default)
			)
			(layer "F.SilkS")
		)
		(fp_line
			(start -0.67945 -0.305054)
			(end -0.12065 -0.305054)
			(stroke
				(width 0.1)
				(type default)
			)
			(layer "F.Fab")
		)
		(fp_line
			(start -0.67945 0.3048)
			(end -0.67945 -0.305054)
			(stroke
				(width 0.1)
				(type default)
			)
			(layer "F.Fab")
		)
		(fp_line
			(start -0.12065 -0.305054)
			(end -0.12065 -0.2794)
			(stroke
				(width 0.1)
				(type default)
			)
			(layer "F.Fab")
		)
		(fp_line
			(start -0.12065 -0.2794)
			(end 0.12065 -0.2794)
			(stroke
				(width 0.1)
				(type default)
			)
			(layer "F.Fab")
		)
		(fp_line
			(start -0.12065 0.2794)
			(end -0.12065 0.3048)
			(stroke
				(width 0.1)
				(type default)
			)
			(layer "F.Fab")
		)
		(fp_line
			(start -0.12065 0.3048)
			(end -0.67945 0.3048)
			(stroke
				(width 0.1)
				(type default)
			)
			(layer "F.Fab")
		)
		(fp_line
			(start 0.120396 0.2794)
			(end -0.12065 0.2794)
			(stroke
				(width 0.1)
				(type default)
			)
			(layer "F.Fab")
		)
		(fp_line
			(start 0.120396 0.3048)
			(end 0.120396 0.2794)
			(stroke
				(width 0.1)
				(type default)
			)
			(layer "F.Fab")
		)
		(fp_line
			(start 0.12065 -0.3048)
			(end 0.67945 -0.3048)
			(stroke
				(width 0.1)
				(type default)
			)
			(layer "F.Fab")
		)
		(fp_line
			(start 0.12065 -0.2794)
			(end 0.12065 -0.3048)
			(stroke
				(width 0.1)
				(type default)
			)
			(layer "F.Fab")
		)
		(fp_line
			(start 0.67945 -0.3048)
			(end 0.67945 0.3048)
			(stroke
				(width 0.1)
				(type default)
			)
			(layer "F.Fab")
		)
		(fp_line
			(start 0.67945 0.3048)
			(end 0.120396 0.3048)
			(stroke
				(width 0.1)
				(type default)
			)
			(layer "F.Fab")
		)
		(pad "1" smd circle
			(at -0.40005 0)
			(size 0 0)
			(layers "F.Cu" "F.Mask" "F.Paste")
			(net "FM_I3C_CPU1_MUX0_OE_N")
		)
		(pad "2" smd circle
			(at 0.40005 0)
			(size 0 0)
			(layers "F.Cu" "F.Mask" "F.Paste")
			(net "GND")
		)
	)
	(footprint ""
		(layer "F.Cu")
		(at 292.655244 -397.884396 -90)
		(property "Reference" "R1218"
			(at 0 0 270)
			(layer "F.SilkS")
			(hide yes)
			(effects
				(font
					(size 1.27 1.27)
				)
			)
		)
		(property "Value" ""
			(at 0 0 270)
			(layer "F.Fab")
			(effects
				(font
					(size 1.27 1.27)
				)
			)
		)
		(duplicate_pad_numbers_are_jumpers no)
		(fp_line
			(start -0.32512 0.175006)
			(end -0.32512 -0.175006)
			(stroke
				(width 0.1)
				(type default)
			)
			(layer "F.Fab")
		)
		(fp_line
			(start 0.32512 0.175006)
			(end -0.32512 0.175006)
			(stroke
				(width 0.1)
				(type default)
			)
			(layer "F.Fab")
		)
		(fp_line
			(start -0.32512 -0.175006)
			(end 0.32512 -0.175006)
			(stroke
				(width 0.1)
				(type default)
			)
			(layer "F.Fab")
		)
		(fp_line
			(start 0.32512 -0.175006)
			(end 0.32512 0.175006)
			(stroke
				(width 0.1)
				(type default)
			)
			(layer "F.Fab")
		)
		(pad "1" smd rect
			(at -0.2667 0 270)
			(size 0.3048 0.381)
			(layers "F.Cu" "F.Mask" "F.Paste")
			(net "GND")
		)
		(pad "2" smd rect
			(at 0.2667 0 90)
			(size 0.3048 0.381)
			(layers "F.Cu" "F.Mask" "F.Paste")
			(net "RT_ROM_MUX6_OE_N")
		)
	)
	(footprint ""
		(layer "F.Cu")
		(at 102.563422 -39.886636 180)
		(property "Reference" "R3182"
			(at 0 0 180)
			(layer "F.SilkS")
			(hide yes)
			(effects
				(font
					(size 1.27 1.27)
				)
			)
		)
		(property "Value" ""
			(at 0 0 180)
			(layer "F.Fab")
			(effects
				(font
					(size 1.27 1.27)
				)
			)
		)
		(duplicate_pad_numbers_are_jumpers no)
		(fp_line
			(start 0.7874 0.4064)
			(end -0.7874 0.4064)
			(stroke
				(width 0.1524)
				(type default)
			)
			(layer "F.SilkS")
		)
		(fp_line
			(start 0.7874 -0.4064)
			(end 0.7874 0.4064)
			(stroke
				(width 0.1524)
				(type default)
			)
			(layer "F.SilkS")
		)
		(fp_line
			(start -0.7874 0.4064)
			(end -0.7874 -0.4064)
			(stroke
				(width 0.1524)
				(type default)
			)
			(layer "F.SilkS")
		)
		(fp_line
			(start -0.7874 -0.4064)
			(end 0.7874 -0.4064)
			(stroke
				(width 0.1524)
				(type default)
			)
			(layer "F.SilkS")
		)
		(fp_line
			(start 0.67945 0.3048)
			(end 0.120396 0.3048)
			(stroke
				(width 0.1)
				(type default)
			)
			(layer "F.Fab")
		)
		(fp_line
			(start 0.67945 -0.3048)
			(end 0.67945 0.3048)
			(stroke
				(width 0.1)
				(type default)
			)
			(layer "F.Fab")
		)
		(fp_line
			(start 0.12065 -0.2794)
			(end 0.12065 -0.3048)
			(stroke
				(width 0.1)
				(type default)
			)
			(layer "F.Fab")
		)
		(fp_line
			(start 0.12065 -0.3048)
			(end 0.67945 -0.3048)
			(stroke
				(width 0.1)
				(type default)
			)
			(layer "F.Fab")
		)
		(fp_line
			(start 0.120396 0.3048)
			(end 0.120396 0.2794)
			(stroke
				(width 0.1)
				(type default)
			)
			(layer "F.Fab")
		)
		(fp_line
			(start 0.120396 0.2794)
			(end -0.12065 0.2794)
			(stroke
				(width 0.1)
				(type default)
			)
			(layer "F.Fab")
		)
		(fp_line
			(start -0.12065 0.3048)
			(end -0.67945 0.3048)
			(stroke
				(width 0.1)
				(type default)
			)
			(layer "F.Fab")
		)
		(fp_line
			(start -0.12065 0.2794)
			(end -0.12065 0.3048)
			(stroke
				(width 0.1)
				(type default)
			)
			(layer "F.Fab")
		)
		(fp_line
			(start -0.12065 -0.2794)
			(end 0.12065 -0.2794)
			(stroke
				(width 0.1)
				(type default)
			)
			(layer "F.Fab")
		)
		(fp_line
			(start -0.12065 -0.305054)
			(end -0.12065 -0.2794)
			(stroke
				(width 0.1)
				(type default)
			)
			(layer "F.Fab")
		)
		(fp_line
			(start -0.67945 0.3048)
			(end -0.67945 -0.305054)
			(stroke
				(width 0.1)
				(type default)
			)
			(layer "F.Fab")
		)
		(fp_line
			(start -0.67945 -0.305054)
			(end -0.12065 -0.305054)
			(stroke
				(width 0.1)
				(type default)
			)
			(layer "F.Fab")
		)
		(pad "1" smd circle
			(at -0.40005 0 180)
			(size 0 0)
			(layers "F.Cu" "F.Mask" "F.Paste")
			(net "P3V3_OCP_V3_2")
		)
		(pad "2" smd circle
			(at 0.40005 0 180)
			(size 0 0)
			(layers "F.Cu" "F.Mask" "F.Paste")
			(net "IRQ_LVC3_OCP_V3_2_WAKE_N")
		)
	)
	(footprint ""
		(layer "F.Cu")
		(at 297.554142 -397.4084)
		(property "Reference" "R971"
			(at 0 0 0)
			(layer "F.SilkS")
			(hide yes)
			(effects
				(font
					(size 1.27 1.27)
				)
			)
		)
		(property "Value" ""
			(at 0 0 0)
			(layer "F.Fab")
			(effects
				(font
					(size 1.27 1.27)
				)
			)
		)
		(duplicate_pad_numbers_are_jumpers no)
		(fp_line
			(start -0.32512 -0.175006)
			(end 0.32512 -0.175006)
			(stroke
				(width 0.1)
				(type default)
			)
			(layer "F.Fab")
		)
		(fp_line
			(start -0.32512 0.175006)
			(end -0.32512 -0.175006)
			(stroke
				(width 0.1)
				(type default)
			)
			(layer "F.Fab")
		)
		(fp_line
			(start 0.32512 -0.175006)
			(end 0.32512 0.175006)
			(stroke
				(width 0.1)
				(type default)
			)
			(layer "F.Fab")
		)
		(fp_line
			(start 0.32512 0.175006)
			(end -0.32512 0.175006)
			(stroke
				(width 0.1)
				(type default)
			)
			(layer "F.Fab")
		)
		(pad "1" smd rect
			(at -0.2667 0)
			(size 0.3048 0.381)
			(layers "F.Cu" "F.Mask" "F.Paste")
			(net "RST_RT_CPU0_P0_RESET_R_N")
		)
		(pad "2" smd rect
			(at 0.2667 0 180)
			(size 0.3048 0.381)
			(layers "F.Cu" "F.Mask" "F.Paste")
			(net "GND")
		)
	)
	(footprint ""
		(layer "F.Cu")
		(at 257.766312 -66.86931 90)
		(property "Reference" "R4074"
			(at 0 0 90)
			(layer "F.SilkS")
			(hide yes)
			(effects
				(font
					(size 1.27 1.27)
				)
			)
		)
		(property "Value" ""
			(at 0 0 90)
			(layer "F.Fab")
			(effects
				(font
					(size 1.27 1.27)
				)
			)
		)
		(duplicate_pad_numbers_are_jumpers no)
		(fp_line
			(start 0.7874 -0.4064)
			(end 0.7874 0.4064)
			(stroke
				(width 0.1524)
				(type default)
			)
			(layer "F.SilkS")
		)
		(fp_line
			(start -0.7874 -0.4064)
			(end 0.7874 -0.4064)
			(stroke
				(width 0.1524)
				(type default)
			)
			(layer "F.SilkS")
		)
		(fp_line
			(start 0.7874 0.4064)
			(end -0.7874 0.4064)
			(stroke
				(width 0.1524)
				(type default)
			)
			(layer "F.SilkS")
		)
		(fp_line
			(start -0.7874 0.4064)
			(end -0.7874 -0.4064)
			(stroke
				(width 0.1524)
				(type default)
			)
			(layer "F.SilkS")
		)
		(fp_line
			(start -0.12065 -0.305054)
			(end -0.12065 -0.2794)
			(stroke
				(width 0.1)
				(type default)
			)
			(layer "F.Fab")
		)
		(fp_line
			(start -0.67945 -0.305054)
			(end -0.12065 -0.305054)
			(stroke
				(width 0.1)
				(type default)
			)
			(layer "F.Fab")
		)
		(fp_line
			(start 0.67945 -0.3048)
			(end 0.67945 0.3048)
			(stroke
				(width 0.1)
				(type default)
			)
			(layer "F.Fab")
		)
		(fp_line
			(start 0.12065 -0.3048)
			(end 0.67945 -0.3048)
			(stroke
				(width 0.1)
				(type default)
			)
			(layer "F.Fab")
		)
		(fp_line
			(start 0.12065 -0.2794)
			(end 0.12065 -0.3048)
			(stroke
				(width 0.1)
				(type default)
			)
			(layer "F.Fab")
		)
		(fp_line
			(start -0.12065 -0.2794)
			(end 0.12065 -0.2794)
			(stroke
				(width 0.1)
				(type default)
			)
			(layer "F.Fab")
		)
		(fp_line
			(start 0.120396 0.2794)
			(end -0.12065 0.2794)
			(stroke
				(width 0.1)
				(type default)
			)
			(layer "F.Fab")
		)
		(fp_line
			(start -0.12065 0.2794)
			(end -0.12065 0.3048)
			(stroke
				(width 0.1)
				(type default)
			)
			(layer "F.Fab")
		)
		(fp_line
			(start 0.67945 0.3048)
			(end 0.120396 0.3048)
			(stroke
				(width 0.1)
				(type default)
			)
			(layer "F.Fab")
		)
		(fp_line
			(start 0.120396 0.3048)
			(end 0.120396 0.2794)
			(stroke
				(width 0.1)
				(type default)
			)
			(layer "F.Fab")
		)
		(fp_line
			(start -0.12065 0.3048)
			(end -0.67945 0.3048)
			(stroke
				(width 0.1)
				(type default)
			)
			(layer "F.Fab")
		)
		(fp_line
			(start -0.67945 0.3048)
			(end -0.67945 -0.305054)
			(stroke
				(width 0.1)
				(type default)
			)
			(layer "F.Fab")
		)
		(pad "1" smd circle
			(at -0.40005 0 90)
			(size 0 0)
			(layers "F.Cu" "F.Mask" "F.Paste")
			(net "P12V_AUX")
		)
		(pad "2" smd circle
			(at 0.40005 0 90)
			(size 0 0)
			(layers "F.Cu" "F.Mask" "F.Paste")
			(net "P12V_E1S_0_EN_G")
		)
	)
	(footprint ""
		(layer "F.Cu")
		(at 109.22 -397.03248 90)
		(property "Reference" "R689"
			(at 0 0 90)
			(layer "F.SilkS")
			(hide yes)
			(effects
				(font
					(size 1.27 1.27)
				)
			)
		)
		(property "Value" ""
			(at 0 0 90)
			(layer "F.Fab")
			(effects
				(font
					(size 1.27 1.27)
				)
			)
		)
		(duplicate_pad_numbers_are_jumpers no)
		(fp_line
			(start 0.32512 -0.175006)
			(end 0.32512 0.175006)
			(stroke
				(width 0.1)
				(type default)
			)
			(layer "F.Fab")
		)
		(fp_line
			(start -0.32512 -0.175006)
			(end 0.32512 -0.175006)
			(stroke
				(width 0.1)
				(type default)
			)
			(layer "F.Fab")
		)
		(fp_line
			(start 0.32512 0.175006)
			(end -0.32512 0.175006)
			(stroke
				(width 0.1)
				(type default)
			)
			(layer "F.Fab")
		)
		(fp_line
			(start -0.32512 0.175006)
			(end -0.32512 -0.175006)
			(stroke
				(width 0.1)
				(type default)
			)
			(layer "F.Fab")
		)
		(pad "1" smd rect
			(at -0.2667 0 90)
			(size 0.3048 0.381)
			(layers "F.Cu" "F.Mask" "F.Paste")
			(net "SMB_RT_CPU1_P1_ROM_R_SCL")
		)
		(pad "2" smd rect
			(at 0.2667 0 270)
			(size 0.3048 0.381)
			(layers "F.Cu" "F.Mask" "F.Paste")
			(net "SMB_RT_CPU1_P1_ROM_SCL")
		)
	)
	(footprint ""
		(layer "F.Cu")
		(at 332.914498 -143.705834 180)
		(property "Reference" "PR8001"
			(at 0 0 180)
			(layer "F.SilkS")
			(hide yes)
			(effects
				(font
					(size 1.27 1.27)
				)
			)
		)
		(property "Value" ""
			(at 0 0 180)
			(layer "F.Fab")
			(effects
				(font
					(size 1.27 1.27)
				)
			)
		)
		(duplicate_pad_numbers_are_jumpers no)
		(fp_line
			(start 0.7874 0.4064)
			(end -0.7874 0.4064)
			(stroke
				(width 0.1524)
				(type default)
			)
			(layer "F.SilkS")
		)
		(fp_line
			(start 0.7874 -0.4064)
			(end 0.7874 0.4064)
			(stroke
				(width 0.1524)
				(type default)
			)
			(layer "F.SilkS")
		)
		(fp_line
			(start -0.7874 0.4064)
			(end -0.7874 -0.4064)
			(stroke
				(width 0.1524)
				(type default)
			)
			(layer "F.SilkS")
		)
		(fp_line
			(start -0.7874 -0.4064)
			(end 0.7874 -0.4064)
			(stroke
				(width 0.1524)
				(type default)
			)
			(layer "F.SilkS")
		)
		(fp_line
			(start 0.67945 0.3048)
			(end 0.120396 0.3048)
			(stroke
				(width 0.1)
				(type default)
			)
			(layer "F.Fab")
		)
		(fp_line
			(start 0.67945 -0.3048)
			(end 0.67945 0.3048)
			(stroke
				(width 0.1)
				(type default)
			)
			(layer "F.Fab")
		)
		(fp_line
			(start 0.12065 -0.2794)
			(end 0.12065 -0.3048)
			(stroke
				(width 0.1)
				(type default)
			)
			(layer "F.Fab")
		)
		(fp_line
			(start 0.12065 -0.3048)
			(end 0.67945 -0.3048)
			(stroke
				(width 0.1)
				(type default)
			)
			(layer "F.Fab")
		)
		(fp_line
			(start 0.120396 0.3048)
			(end 0.120396 0.2794)
			(stroke
				(width 0.1)
				(type default)
			)
			(layer "F.Fab")
		)
		(fp_line
			(start 0.120396 0.2794)
			(end -0.12065 0.2794)
			(stroke
				(width 0.1)
				(type default)
			)
			(layer "F.Fab")
		)
		(fp_line
			(start -0.12065 0.3048)
			(end -0.67945 0.3048)
			(stroke
				(width 0.1)
				(type default)
			)
			(layer "F.Fab")
		)
		(fp_line
			(start -0.12065 0.2794)
			(end -0.12065 0.3048)
			(stroke
				(width 0.1)
				(type default)
			)
			(layer "F.Fab")
		)
		(fp_line
			(start -0.12065 -0.2794)
			(end 0.12065 -0.2794)
			(stroke
				(width 0.1)
				(type default)
			)
			(layer "F.Fab")
		)
		(fp_line
			(start -0.12065 -0.305054)
			(end -0.12065 -0.2794)
			(stroke
				(width 0.1)
				(type default)
			)
			(layer "F.Fab")
		)
		(fp_line
			(start -0.67945 0.3048)
			(end -0.67945 -0.305054)
			(stroke
				(width 0.1)
				(type default)
			)
			(layer "F.Fab")
		)
		(fp_line
			(start -0.67945 -0.305054)
			(end -0.12065 -0.305054)
			(stroke
				(width 0.1)
				(type default)
			)
			(layer "F.Fab")
		)
		(pad "1" smd circle
			(at -0.40005 0 180)
			(size 0 0)
			(layers "F.Cu" "F.Mask" "F.Paste")
			(net "SW_PVDD18_S5_P0_BST")
		)
		(pad "2" smd circle
			(at 0.40005 0 180)
			(size 0 0)
			(layers "F.Cu" "F.Mask" "F.Paste")
			(net "SW_PVDD18_S5_P0_BST_R")
		)
	)
	(footprint ""
		(layer "F.Cu")
		(at 390.614662 -143.323056 -90)
		(property "Reference" "R6077"
			(at 0 0 270)
			(layer "F.SilkS")
			(hide yes)
			(effects
				(font
					(size 1.27 1.27)
				)
			)
		)
		(property "Value" ""
			(at 0 0 270)
			(layer "F.Fab")
			(effects
				(font
					(size 1.27 1.27)
				)
			)
		)
		(duplicate_pad_numbers_are_jumpers no)
		(fp_line
			(start -0.7874 0.4064)
			(end -0.7874 -0.4064)
			(stroke
				(width 0.1524)
				(type default)
			)
			(layer "F.SilkS")
		)
		(fp_line
			(start 0.7874 0.4064)
			(end -0.7874 0.4064)
			(stroke
				(width 0.1524)
				(type default)
			)
			(layer "F.SilkS")
		)
		(fp_line
			(start -0.7874 -0.4064)
			(end 0.7874 -0.4064)
			(stroke
				(width 0.1524)
				(type default)
			)
			(layer "F.SilkS")
		)
		(fp_line
			(start 0.7874 -0.4064)
			(end 0.7874 0.4064)
			(stroke
				(width 0.1524)
				(type default)
			)
			(layer "F.SilkS")
		)
		(fp_line
			(start -0.67945 0.3048)
			(end -0.67945 -0.305054)
			(stroke
				(width 0.1)
				(type default)
			)
			(layer "F.Fab")
		)
		(fp_line
			(start -0.12065 0.3048)
			(end -0.67945 0.3048)
			(stroke
				(width 0.1)
				(type default)
			)
			(layer "F.Fab")
		)
		(fp_line
			(start 0.120396 0.3048)
			(end 0.120396 0.2794)
			(stroke
				(width 0.1)
				(type default)
			)
			(layer "F.Fab")
		)
		(fp_line
			(start 0.67945 0.3048)
			(end 0.120396 0.3048)
			(stroke
				(width 0.1)
				(type default)
			)
			(layer "F.Fab")
		)
		(fp_line
			(start -0.12065 0.2794)
			(end -0.12065 0.3048)
			(stroke
				(width 0.1)
				(type default)
			)
			(layer "F.Fab")
		)
		(fp_line
			(start 0.120396 0.2794)
			(end -0.12065 0.2794)
			(stroke
				(width 0.1)
				(type default)
			)
			(layer "F.Fab")
		)
		(fp_line
			(start -0.12065 -0.2794)
			(end 0.12065 -0.2794)
			(stroke
				(width 0.1)
				(type default)
			)
			(layer "F.Fab")
		)
		(fp_line
			(start 0.12065 -0.2794)
			(end 0.12065 -0.3048)
			(stroke
				(width 0.1)
				(type default)
			)
			(layer "F.Fab")
		)
		(fp_line
			(start 0.12065 -0.3048)
			(end 0.67945 -0.3048)
			(stroke
				(width 0.1)
				(type default)
			)
			(layer "F.Fab")
		)
		(fp_line
			(start 0.67945 -0.3048)
			(end 0.67945 0.3048)
			(stroke
				(width 0.1)
				(type default)
			)
			(layer "F.Fab")
		)
		(fp_line
			(start -0.67945 -0.305054)
			(end -0.12065 -0.305054)
			(stroke
				(width 0.1)
				(type default)
			)
			(layer "F.Fab")
		)
		(fp_line
			(start -0.12065 -0.305054)
			(end -0.12065 -0.2794)
			(stroke
				(width 0.1)
				(type default)
			)
			(layer "F.Fab")
		)
		(pad "1" smd circle
			(at -0.40005 0 270)
			(size 0 0)
			(layers "F.Cu" "F.Mask" "F.Paste")
			(net "SMB_SCM_2_R3_SDA")
		)
		(pad "2" smd circle
			(at 0.40005 0 270)
			(size 0 0)
			(layers "F.Cu" "F.Mask" "F.Paste")
			(net "SMB_SCM_2_R4_SDA")
		)
	)
	(footprint ""
		(layer "F.Cu")
		(at 298.704 -108.966 -90)
		(property "Reference" "R1344"
			(at 0 0 270)
			(layer "F.SilkS")
			(hide yes)
			(effects
				(font
					(size 1.27 1.27)
				)
			)
		)
		(property "Value" ""
			(at 0 0 270)
			(layer "F.Fab")
			(effects
				(font
					(size 1.27 1.27)
				)
			)
		)
		(duplicate_pad_numbers_are_jumpers no)
		(fp_line
			(start -0.7874 0.4064)
			(end -0.7874 -0.4064)
			(stroke
				(width 0.1524)
				(type default)
			)
			(layer "F.SilkS")
		)
		(fp_line
			(start 0.7874 0.4064)
			(end -0.7874 0.4064)
			(stroke
				(width 0.1524)
				(type default)
			)
			(layer "F.SilkS")
		)
		(fp_line
			(start -0.7874 -0.4064)
			(end 0.7874 -0.4064)
			(stroke
				(width 0.1524)
				(type default)
			)
			(layer "F.SilkS")
		)
		(fp_line
			(start 0.7874 -0.4064)
			(end 0.7874 0.4064)
			(stroke
				(width 0.1524)
				(type default)
			)
			(layer "F.SilkS")
		)
		(fp_line
			(start -0.67945 0.3048)
			(end -0.67945 -0.305054)
			(stroke
				(width 0.1)
				(type default)
			)
			(layer "F.Fab")
		)
		(fp_line
			(start -0.12065 0.3048)
			(end -0.67945 0.3048)
			(stroke
				(width 0.1)
				(type default)
			)
			(layer "F.Fab")
		)
		(fp_line
			(start 0.120396 0.3048)
			(end 0.120396 0.2794)
			(stroke
				(width 0.1)
				(type default)
			)
			(layer "F.Fab")
		)
		(fp_line
			(start 0.67945 0.3048)
			(end 0.120396 0.3048)
			(stroke
				(width 0.1)
				(type default)
			)
			(layer "F.Fab")
		)
		(fp_line
			(start -0.12065 0.2794)
			(end -0.12065 0.3048)
			(stroke
				(width 0.1)
				(type default)
			)
			(layer "F.Fab")
		)
		(fp_line
			(start 0.120396 0.2794)
			(end -0.12065 0.2794)
			(stroke
				(width 0.1)
				(type default)
			)
			(layer "F.Fab")
		)
		(fp_line
			(start -0.12065 -0.2794)
			(end 0.12065 -0.2794)
			(stroke
				(width 0.1)
				(type default)
			)
			(layer "F.Fab")
		)
		(fp_line
			(start 0.12065 -0.2794)
			(end 0.12065 -0.3048)
			(stroke
				(width 0.1)
				(type default)
			)
			(layer "F.Fab")
		)
		(fp_line
			(start 0.12065 -0.3048)
			(end 0.67945 -0.3048)
			(stroke
				(width 0.1)
				(type default)
			)
			(layer "F.Fab")
		)
		(fp_line
			(start 0.67945 -0.3048)
			(end 0.67945 0.3048)
			(stroke
				(width 0.1)
				(type default)
			)
			(layer "F.Fab")
		)
		(fp_line
			(start -0.67945 -0.305054)
			(end -0.12065 -0.305054)
			(stroke
				(width 0.1)
				(type default)
			)
			(layer "F.Fab")
		)
		(fp_line
			(start -0.12065 -0.305054)
			(end -0.12065 -0.2794)
			(stroke
				(width 0.1)
				(type default)
			)
			(layer "F.Fab")
		)
		(pad "1" smd circle
			(at -0.40005 0 270)
			(size 0 0)
			(layers "F.Cu" "F.Mask" "F.Paste")
			(net "SMB_INA230_3V3AUX_SCL")
		)
		(pad "2" smd circle
			(at 0.40005 0 270)
			(size 0 0)
			(layers "F.Cu" "F.Mask" "F.Paste")
			(net "SMB_INA230_6_3V3AUX_SCL_R")
		)
	)
	(footprint ""
		(layer "F.Cu")
		(at 386.211826 -60.456318 180)
		(property "Reference" "R1630"
			(at 0 0 180)
			(layer "F.SilkS")
			(hide yes)
			(effects
				(font
					(size 1.27 1.27)
				)
			)
		)
		(property "Value" ""
			(at 0 0 180)
			(layer "F.Fab")
			(effects
				(font
					(size 1.27 1.27)
				)
			)
		)
		(duplicate_pad_numbers_are_jumpers no)
		(fp_line
			(start 0.7874 0.4064)
			(end -0.7874 0.4064)
			(stroke
				(width 0.1524)
				(type default)
			)
			(layer "F.SilkS")
		)
		(fp_line
			(start 0.7874 -0.4064)
			(end 0.7874 0.4064)
			(stroke
				(width 0.1524)
				(type default)
			)
			(layer "F.SilkS")
		)
		(fp_line
			(start -0.7874 0.4064)
			(end -0.7874 -0.4064)
			(stroke
				(width 0.1524)
				(type default)
			)
			(layer "F.SilkS")
		)
		(fp_line
			(start -0.7874 -0.4064)
			(end 0.7874 -0.4064)
			(stroke
				(width 0.1524)
				(type default)
			)
			(layer "F.SilkS")
		)
		(fp_line
			(start 0.67945 0.3048)
			(end 0.120396 0.3048)
			(stroke
				(width 0.1)
				(type default)
			)
			(layer "F.Fab")
		)
		(fp_line
			(start 0.67945 -0.3048)
			(end 0.67945 0.3048)
			(stroke
				(width 0.1)
				(type default)
			)
			(layer "F.Fab")
		)
		(fp_line
			(start 0.12065 -0.2794)
			(end 0.12065 -0.3048)
			(stroke
				(width 0.1)
				(type default)
			)
			(layer "F.Fab")
		)
		(fp_line
			(start 0.12065 -0.3048)
			(end 0.67945 -0.3048)
			(stroke
				(width 0.1)
				(type default)
			)
			(layer "F.Fab")
		)
		(fp_line
			(start 0.120396 0.3048)
			(end 0.120396 0.2794)
			(stroke
				(width 0.1)
				(type default)
			)
			(layer "F.Fab")
		)
		(fp_line
			(start 0.120396 0.2794)
			(end -0.12065 0.2794)
			(stroke
				(width 0.1)
				(type default)
			)
			(layer "F.Fab")
		)
		(fp_line
			(start -0.12065 0.3048)
			(end -0.67945 0.3048)
			(stroke
				(width 0.1)
				(type default)
			)
			(layer "F.Fab")
		)
		(fp_line
			(start -0.12065 0.2794)
			(end -0.12065 0.3048)
			(stroke
				(width 0.1)
				(type default)
			)
			(layer "F.Fab")
		)
		(fp_line
			(start -0.12065 -0.2794)
			(end 0.12065 -0.2794)
			(stroke
				(width 0.1)
				(type default)
			)
			(layer "F.Fab")
		)
		(fp_line
			(start -0.12065 -0.305054)
			(end -0.12065 -0.2794)
			(stroke
				(width 0.1)
				(type default)
			)
			(layer "F.Fab")
		)
		(fp_line
			(start -0.67945 0.3048)
			(end -0.67945 -0.305054)
			(stroke
				(width 0.1)
				(type default)
			)
			(layer "F.Fab")
		)
		(fp_line
			(start -0.67945 -0.305054)
			(end -0.12065 -0.305054)
			(stroke
				(width 0.1)
				(type default)
			)
			(layer "F.Fab")
		)
		(pad "1" smd circle
			(at -0.40005 0 180)
			(size 0 0)
			(layers "F.Cu" "F.Mask" "F.Paste")
			(net "PVDD18_S5_P0")
		)
		(pad "2" smd circle
			(at 0.40005 0 180)
			(size 0 0)
			(layers "F.Cu" "F.Mask" "F.Paste")
			(net "HDT_HDR_DBREQ_R_N")
		)
	)
	(footprint ""
		(layer "F.Cu")
		(at 277.352252 -116.10467)
		(property "Reference" "R1090"
			(at 0 0 0)
			(layer "F.SilkS")
			(hide yes)
			(effects
				(font
					(size 1.27 1.27)
				)
			)
		)
		(property "Value" ""
			(at 0 0 0)
			(layer "F.Fab")
			(effects
				(font
					(size 1.27 1.27)
				)
			)
		)
		(duplicate_pad_numbers_are_jumpers no)
		(fp_line
			(start -0.7874 -0.4064)
			(end 0.7874 -0.4064)
			(stroke
				(width 0.1524)
				(type default)
			)
			(layer "F.SilkS")
		)
		(fp_line
			(start -0.7874 0.4064)
			(end -0.7874 -0.4064)
			(stroke
				(width 0.1524)
				(type default)
			)
			(layer "F.SilkS")
		)
		(fp_line
			(start 0.7874 -0.4064)
			(end 0.7874 0.4064)
			(stroke
				(width 0.1524)
				(type default)
			)
			(layer "F.SilkS")
		)
		(fp_line
			(start 0.7874 0.4064)
			(end -0.7874 0.4064)
			(stroke
				(width 0.1524)
				(type default)
			)
			(layer "F.SilkS")
		)
		(fp_line
			(start -0.67945 -0.305054)
			(end -0.12065 -0.305054)
			(stroke
				(width 0.1)
				(type default)
			)
			(layer "F.Fab")
		)
		(fp_line
			(start -0.67945 0.3048)
			(end -0.67945 -0.305054)
			(stroke
				(width 0.1)
				(type default)
			)
			(layer "F.Fab")
		)
		(fp_line
			(start -0.12065 -0.305054)
			(end -0.12065 -0.2794)
			(stroke
				(width 0.1)
				(type default)
			)
			(layer "F.Fab")
		)
		(fp_line
			(start -0.12065 -0.2794)
			(end 0.12065 -0.2794)
			(stroke
				(width 0.1)
				(type default)
			)
			(layer "F.Fab")
		)
		(fp_line
			(start -0.12065 0.2794)
			(end -0.12065 0.3048)
			(stroke
				(width 0.1)
				(type default)
			)
			(layer "F.Fab")
		)
		(fp_line
			(start -0.12065 0.3048)
			(end -0.67945 0.3048)
			(stroke
				(width 0.1)
				(type default)
			)
			(layer "F.Fab")
		)
		(fp_line
			(start 0.120396 0.2794)
			(end -0.12065 0.2794)
			(stroke
				(width 0.1)
				(type default)
			)
			(layer "F.Fab")
		)
		(fp_line
			(start 0.120396 0.3048)
			(end 0.120396 0.2794)
			(stroke
				(width 0.1)
				(type default)
			)
			(layer "F.Fab")
		)
		(fp_line
			(start 0.12065 -0.3048)
			(end 0.67945 -0.3048)
			(stroke
				(width 0.1)
				(type default)
			)
			(layer "F.Fab")
		)
		(fp_line
			(start 0.12065 -0.2794)
			(end 0.12065 -0.3048)
			(stroke
				(width 0.1)
				(type default)
			)
			(layer "F.Fab")
		)
		(fp_line
			(start 0.67945 -0.3048)
			(end 0.67945 0.3048)
			(stroke
				(width 0.1)
				(type default)
			)
			(layer "F.Fab")
		)
		(fp_line
			(start 0.67945 0.3048)
			(end 0.120396 0.3048)
			(stroke
				(width 0.1)
				(type default)
			)
			(layer "F.Fab")
		)
		(pad "1" smd circle
			(at -0.40005 0)
			(size 0 0)
			(layers "F.Cu" "F.Mask" "F.Paste")
			(net "P3V3_AUX")
		)
		(pad "2" smd circle
			(at 0.40005 0)
			(size 0 0)
			(layers "F.Cu" "F.Mask" "F.Paste")
			(net "SMB_SENSOR_M2_P1_3V3AUX_SDA")
		)
	)
	(footprint ""
		(layer "F.Cu")
		(at 117.811296 -373.03583 -90)
		(property "Reference" "C1536"
			(at 0 0 270)
			(layer "F.SilkS")
			(hide yes)
			(effects
				(font
					(size 1.27 1.27)
				)
			)
		)
		(property "Value" ""
			(at 0 0 270)
			(layer "F.Fab")
			(effects
				(font
					(size 1.27 1.27)
				)
			)
		)
		(duplicate_pad_numbers_are_jumpers no)
		(fp_line
			(start -0.299974 0.150114)
			(end -0.299974 -0.150114)
			(stroke
				(width 0.1)
				(type default)
			)
			(layer "F.Fab")
		)
		(fp_line
			(start 0.299974 0.150114)
			(end -0.299974 0.150114)
			(stroke
				(width 0.1)
				(type default)
			)
			(layer "F.Fab")
		)
		(fp_line
			(start -0.299974 -0.150114)
			(end 0.299974 -0.150114)
			(stroke
				(width 0.1)
				(type default)
			)
			(layer "F.Fab")
		)
		(fp_line
			(start 0.299974 -0.150114)
			(end 0.299974 0.150114)
			(stroke
				(width 0.1)
				(type default)
			)
			(layer "F.Fab")
		)
		(pad "1" smd rect
			(at -0.2667 0 270)
			(size 0.3048 0.381)
			(layers "F.Cu" "F.Mask" "F.Paste")
			(net "P5E_CPU1_P3_TX_C_DN<5>")
		)
		(pad "2" smd rect
			(at 0.2667 0 270)
			(size 0.3048 0.381)
			(layers "F.Cu" "F.Mask" "F.Paste")
			(net "P5E_CPU1_P3_TX_DN<5>")
		)
	)
	(footprint ""
		(layer "F.Cu")
		(at 301.605696 -378.95403 -90)
		(property "Reference" "C926"
			(at 0 0 270)
			(layer "F.SilkS")
			(hide yes)
			(effects
				(font
					(size 1.27 1.27)
				)
			)
		)
		(property "Value" ""
			(at 0 0 270)
			(layer "F.Fab")
			(effects
				(font
					(size 1.27 1.27)
				)
			)
		)
		(duplicate_pad_numbers_are_jumpers no)
		(fp_line
			(start -0.299974 0.150114)
			(end -0.299974 -0.150114)
			(stroke
				(width 0.1)
				(type default)
			)
			(layer "F.Fab")
		)
		(fp_line
			(start 0.299974 0.150114)
			(end -0.299974 0.150114)
			(stroke
				(width 0.1)
				(type default)
			)
			(layer "F.Fab")
		)
		(fp_line
			(start -0.299974 -0.150114)
			(end 0.299974 -0.150114)
			(stroke
				(width 0.1)
				(type default)
			)
			(layer "F.Fab")
		)
		(fp_line
			(start 0.299974 -0.150114)
			(end 0.299974 0.150114)
			(stroke
				(width 0.1)
				(type default)
			)
			(layer "F.Fab")
		)
		(pad "1" smd rect
			(at -0.2667 0 270)
			(size 0.3048 0.381)
			(layers "F.Cu" "F.Mask" "F.Paste")
			(net "P5E_CPU0_P0_TX_C_DN<3>")
		)
		(pad "2" smd rect
			(at 0.2667 0 270)
			(size 0.3048 0.381)
			(layers "F.Cu" "F.Mask" "F.Paste")
			(net "P5E_CPU0_P0_TX_DN<3>")
		)
	)
	(footprint ""
		(layer "F.Cu")
		(at 42.527982 -387.764274)
		(property "Reference" "R599"
			(at 0 0 0)
			(layer "F.SilkS")
			(hide yes)
			(effects
				(font
					(size 1.27 1.27)
				)
			)
		)
		(property "Value" ""
			(at 0 0 0)
			(layer "F.Fab")
			(effects
				(font
					(size 1.27 1.27)
				)
			)
		)
		(duplicate_pad_numbers_are_jumpers no)
		(fp_line
			(start -0.32512 -0.175006)
			(end 0.32512 -0.175006)
			(stroke
				(width 0.1)
				(type default)
			)
			(layer "F.Fab")
		)
		(fp_line
			(start -0.32512 0.175006)
			(end -0.32512 -0.175006)
			(stroke
				(width 0.1)
				(type default)
			)
			(layer "F.Fab")
		)
		(fp_line
			(start 0.32512 -0.175006)
			(end 0.32512 0.175006)
			(stroke
				(width 0.1)
				(type default)
			)
			(layer "F.Fab")
		)
		(fp_line
			(start 0.32512 0.175006)
			(end -0.32512 0.175006)
			(stroke
				(width 0.1)
				(type default)
			)
			(layer "F.Fab")
		)
		(pad "1" smd rect
			(at -0.2667 0)
			(size 0.3048 0.381)
			(layers "F.Cu" "F.Mask" "F.Paste")
			(net "CLK_100M_RETIMER_CPU1_P0_R_DP")
		)
		(pad "2" smd rect
			(at 0.2667 0 180)
			(size 0.3048 0.381)
			(layers "F.Cu" "F.Mask" "F.Paste")
			(net "CLK_100M_RETIMER_CPU1_P0_DP")
		)
	)
	(footprint ""
		(layer "F.Cu")
		(at 155.829 -111.76)
		(property "Reference" "C552"
			(at 0 0 0)
			(layer "F.SilkS")
			(hide yes)
			(effects
				(font
					(size 1.27 1.27)
				)
			)
		)
		(property "Value" ""
			(at 0 0 0)
			(layer "F.Fab")
			(effects
				(font
					(size 1.27 1.27)
				)
			)
		)
		(duplicate_pad_numbers_are_jumpers no)
		(fp_line
			(start -0.7874 -0.4064)
			(end 0.7874 -0.4064)
			(stroke
				(width 0.1524)
				(type default)
			)
			(layer "F.SilkS")
		)
		(fp_line
			(start -0.7874 0.4064)
			(end -0.7874 -0.4064)
			(stroke
				(width 0.1524)
				(type default)
			)
			(layer "F.SilkS")
		)
		(fp_line
			(start 0.7874 -0.4064)
			(end 0.7874 0.4064)
			(stroke
				(width 0.1524)
				(type default)
			)
			(layer "F.SilkS")
		)
		(fp_line
			(start 0.7874 0.4064)
			(end -0.7874 0.4064)
			(stroke
				(width 0.1524)
				(type default)
			)
			(layer "F.SilkS")
		)
		(fp_line
			(start -0.67945 -0.305054)
			(end -0.12065 -0.305054)
			(stroke
				(width 0.1)
				(type default)
			)
			(layer "F.Fab")
		)
		(fp_line
			(start -0.67945 0.3048)
			(end -0.67945 -0.305054)
			(stroke
				(width 0.1)
				(type default)
			)
			(layer "F.Fab")
		)
		(fp_line
			(start -0.12065 -0.305054)
			(end -0.12065 -0.2794)
			(stroke
				(width 0.1)
				(type default)
			)
			(layer "F.Fab")
		)
		(fp_line
			(start -0.12065 -0.2794)
			(end 0.12065 -0.2794)
			(stroke
				(width 0.1)
				(type default)
			)
			(layer "F.Fab")
		)
		(fp_line
			(start -0.12065 0.2794)
			(end -0.12065 0.3048)
			(stroke
				(width 0.1)
				(type default)
			)
			(layer "F.Fab")
		)
		(fp_line
			(start -0.12065 0.3048)
			(end -0.67945 0.3048)
			(stroke
				(width 0.1)
				(type default)
			)
			(layer "F.Fab")
		)
		(fp_line
			(start 0.120396 0.2794)
			(end -0.12065 0.2794)
			(stroke
				(width 0.1)
				(type default)
			)
			(layer "F.Fab")
		)
		(fp_line
			(start 0.120396 0.3048)
			(end 0.120396 0.2794)
			(stroke
				(width 0.1)
				(type default)
			)
			(layer "F.Fab")
		)
		(fp_line
			(start 0.12065 -0.3048)
			(end 0.67945 -0.3048)
			(stroke
				(width 0.1)
				(type default)
			)
			(layer "F.Fab")
		)
		(fp_line
			(start 0.12065 -0.2794)
			(end 0.12065 -0.3048)
			(stroke
				(width 0.1)
				(type default)
			)
			(layer "F.Fab")
		)
		(fp_line
			(start 0.67945 -0.3048)
			(end 0.67945 0.3048)
			(stroke
				(width 0.1)
				(type default)
			)
			(layer "F.Fab")
		)
		(fp_line
			(start 0.67945 0.3048)
			(end 0.120396 0.3048)
			(stroke
				(width 0.1)
				(type default)
			)
			(layer "F.Fab")
		)
		(pad "1" smd circle
			(at -0.40005 0)
			(size 0 0)
			(layers "F.Cu" "F.Mask" "F.Paste")
			(net "P1V8_AUX")
		)
		(pad "2" smd circle
			(at 0.40005 0)
			(size 0 0)
			(layers "F.Cu" "F.Mask" "F.Paste")
			(net "GND")
		)
	)
	(footprint ""
		(layer "F.Cu")
		(at 100.696268 -394.3604 -90)
		(property "Reference" "R749"
			(at 0 0 270)
			(layer "F.SilkS")
			(hide yes)
			(effects
				(font
					(size 1.27 1.27)
				)
			)
		)
		(property "Value" ""
			(at 0 0 270)
			(layer "F.Fab")
			(effects
				(font
					(size 1.27 1.27)
				)
			)
		)
		(duplicate_pad_numbers_are_jumpers no)
		(fp_line
			(start -0.32512 0.175006)
			(end -0.32512 -0.175006)
			(stroke
				(width 0.1)
				(type default)
			)
			(layer "F.Fab")
		)
		(fp_line
			(start 0.32512 0.175006)
			(end -0.32512 0.175006)
			(stroke
				(width 0.1)
				(type default)
			)
			(layer "F.Fab")
		)
		(fp_line
			(start -0.32512 -0.175006)
			(end 0.32512 -0.175006)
			(stroke
				(width 0.1)
				(type default)
			)
			(layer "F.Fab")
		)
		(fp_line
			(start 0.32512 -0.175006)
			(end 0.32512 0.175006)
			(stroke
				(width 0.1)
				(type default)
			)
			(layer "F.Fab")
		)
		(pad "1" smd rect
			(at -0.2667 0 270)
			(size 0.3048 0.381)
			(layers "F.Cu" "F.Mask" "F.Paste")
			(net "RST_RT_CPU1_P1_PERST_R_N")
		)
		(pad "2" smd rect
			(at 0.2667 0 90)
			(size 0.3048 0.381)
			(layers "F.Cu" "F.Mask" "F.Paste")
			(net "GND")
		)
	)
	(footprint ""
		(layer "F.Cu")
		(at 109.210602 -395.782038 90)
		(property "Reference" "R6734"
			(at 0 0 90)
			(layer "F.SilkS")
			(hide yes)
			(effects
				(font
					(size 1.27 1.27)
				)
			)
		)
		(property "Value" ""
			(at 0 0 90)
			(layer "F.Fab")
			(effects
				(font
					(size 1.27 1.27)
				)
			)
		)
		(duplicate_pad_numbers_are_jumpers no)
		(fp_line
			(start 0.32512 -0.175006)
			(end 0.32512 0.175006)
			(stroke
				(width 0.1)
				(type default)
			)
			(layer "F.Fab")
		)
		(fp_line
			(start -0.32512 -0.175006)
			(end 0.32512 -0.175006)
			(stroke
				(width 0.1)
				(type default)
			)
			(layer "F.Fab")
		)
		(fp_line
			(start 0.32512 0.175006)
			(end -0.32512 0.175006)
			(stroke
				(width 0.1)
				(type default)
			)
			(layer "F.Fab")
		)
		(fp_line
			(start -0.32512 0.175006)
			(end -0.32512 -0.175006)
			(stroke
				(width 0.1)
				(type default)
			)
			(layer "F.Fab")
		)
		(pad "1" smd rect
			(at -0.2667 0 90)
			(size 0.3048 0.381)
			(layers "F.Cu" "F.Mask" "F.Paste")
			(net "P1V8_CPU1_RT_1D")
		)
		(pad "2" smd rect
			(at 0.2667 0 270)
			(size 0.3048 0.381)
			(layers "F.Cu" "F.Mask" "F.Paste")
			(net "SMB_RT_CPU1_P1_ROM_R_SCL")
		)
	)
	(footprint ""
		(layer "F.Cu")
		(at 394.811758 -323.796152 90)
		(property "Reference" "R1505"
			(at 0 0 90)
			(layer "F.SilkS")
			(hide yes)
			(effects
				(font
					(size 1.27 1.27)
				)
			)
		)
		(property "Value" ""
			(at 0 0 90)
			(layer "F.Fab")
			(effects
				(font
					(size 1.27 1.27)
				)
			)
		)
		(duplicate_pad_numbers_are_jumpers no)
		(fp_line
			(start 0.7874 -0.4064)
			(end 0.7874 0.4064)
			(stroke
				(width 0.1524)
				(type default)
			)
			(layer "F.SilkS")
		)
		(fp_line
			(start -0.7874 -0.4064)
			(end 0.7874 -0.4064)
			(stroke
				(width 0.1524)
				(type default)
			)
			(layer "F.SilkS")
		)
		(fp_line
			(start 0.7874 0.4064)
			(end -0.7874 0.4064)
			(stroke
				(width 0.1524)
				(type default)
			)
			(layer "F.SilkS")
		)
		(fp_line
			(start -0.7874 0.4064)
			(end -0.7874 -0.4064)
			(stroke
				(width 0.1524)
				(type default)
			)
			(layer "F.SilkS")
		)
		(fp_line
			(start -0.12065 -0.305054)
			(end -0.12065 -0.2794)
			(stroke
				(width 0.1)
				(type default)
			)
			(layer "F.Fab")
		)
		(fp_line
			(start -0.67945 -0.305054)
			(end -0.12065 -0.305054)
			(stroke
				(width 0.1)
				(type default)
			)
			(layer "F.Fab")
		)
		(fp_line
			(start 0.67945 -0.3048)
			(end 0.67945 0.3048)
			(stroke
				(width 0.1)
				(type default)
			)
			(layer "F.Fab")
		)
		(fp_line
			(start 0.12065 -0.3048)
			(end 0.67945 -0.3048)
			(stroke
				(width 0.1)
				(type default)
			)
			(layer "F.Fab")
		)
		(fp_line
			(start 0.12065 -0.2794)
			(end 0.12065 -0.3048)
			(stroke
				(width 0.1)
				(type default)
			)
			(layer "F.Fab")
		)
		(fp_line
			(start -0.12065 -0.2794)
			(end 0.12065 -0.2794)
			(stroke
				(width 0.1)
				(type default)
			)
			(layer "F.Fab")
		)
		(fp_line
			(start 0.120396 0.2794)
			(end -0.12065 0.2794)
			(stroke
				(width 0.1)
				(type default)
			)
			(layer "F.Fab")
		)
		(fp_line
			(start -0.12065 0.2794)
			(end -0.12065 0.3048)
			(stroke
				(width 0.1)
				(type default)
			)
			(layer "F.Fab")
		)
		(fp_line
			(start 0.67945 0.3048)
			(end 0.120396 0.3048)
			(stroke
				(width 0.1)
				(type default)
			)
			(layer "F.Fab")
		)
		(fp_line
			(start 0.120396 0.3048)
			(end 0.120396 0.2794)
			(stroke
				(width 0.1)
				(type default)
			)
			(layer "F.Fab")
		)
		(fp_line
			(start -0.12065 0.3048)
			(end -0.67945 0.3048)
			(stroke
				(width 0.1)
				(type default)
			)
			(layer "F.Fab")
		)
		(fp_line
			(start -0.67945 0.3048)
			(end -0.67945 -0.305054)
			(stroke
				(width 0.1)
				(type default)
			)
			(layer "F.Fab")
		)
		(pad "1" smd circle
			(at -0.40005 0 90)
			(size 0 0)
			(layers "F.Cu" "F.Mask" "F.Paste")
			(net "PVDD18_S5_P0")
		)
		(pad "2" smd circle
			(at 0.40005 0 90)
			(size 0 0)
			(layers "F.Cu" "F.Mask" "F.Paste")
			(net "ESPI_CPU0_D2")
		)
	)
	(footprint ""
		(layer "F.Cu")
		(at 63.582804 -47.049944 90)
		(property "Reference" "H74"
			(at 0.04826 -7.363968 90)
			(unlocked yes)
			(layer "F.SilkS")
			(effects
				(font
					(size 0.7874 0.5842)
					(thickness 0.1524)
				)
			)
		)
		(property "Value" ""
			(at 0 0 90)
			(layer "F.Fab")
			(effects
				(font
					(size 1.27 1.27)
				)
			)
		)
		(duplicate_pad_numbers_are_jumpers no)
		(pad "" np_thru_hole circle
			(at 0 0 90)
			(size 0 0)
			(drill oval 3.2004 4.8006)
			(layers "*.Cu" "*.Mask")
			(clearance -1.2192)
			(thermal_gap 0.381)
			(padstack
				(mode front_inner_back)
				(layer "Inner"
					(shape oval)
					(size 3.2004 4.8006)
					(clearance 0.381)
				)
				(layer "B.Cu"
					(shape circle)
					(size 0 0)
					(clearance -1.2192)
				)
			)
		)
		(zone
			(layers "F.Cu" "B.Cu" "In1.Cu" "In2.Cu" "In3.Cu" "In4.Cu" "In5.Cu" "In6.Cu"
				"In7.Cu" "In8.Cu" "In9.Cu" "In10.Cu" "In11.Cu" "In12.Cu" "In13.Cu" "In14.Cu"
				"In15.Cu" "In16.Cu"
			)
			(hatch none 0.5)
			(connect_pads
				(clearance 0)
			)
			(min_thickness 0.25)
			(keepout
				(tracks not_allowed)
				(vias allowed)
				(pads allowed)
				(copperpour not_allowed)
				(footprints allowed)
			)
			(placement
				(enabled no)
				(sheetname "")
			)
			(fill
				(thermal_gap 0.5)
				(thermal_bridge_width 0.5)
				(island_removal_mode 0)
			)
			(polygon
				(pts
					(arc
						(start 64.382904 -49.158144)
						(mid 66.491104 -47.049944)
						(end 64.382904 -44.941744)
					)
					(arc
						(start 62.782704 -44.941744)
						(mid 60.674504 -47.049944)
						(end 62.782704 -49.158144)
					)
				)
			)
		)
		(zone
			(layers "F.Cu" "B.Cu" "In1.Cu" "In2.Cu" "In3.Cu" "In4.Cu" "In5.Cu" "In6.Cu"
				"In7.Cu" "In8.Cu" "In9.Cu" "In10.Cu" "In11.Cu" "In12.Cu" "In13.Cu" "In14.Cu"
				"In15.Cu" "In16.Cu"
			)
			(hatch none 0.5)
			(connect_pads
				(clearance 0)
			)
			(min_thickness 0.25)
			(keepout
				(tracks not_allowed)
				(vias allowed)
				(pads allowed)
				(copperpour not_allowed)
				(footprints allowed)
			)
			(placement
				(enabled no)
				(sheetname "")
			)
			(fill
				(thermal_gap 0.5)
				(thermal_bridge_width 0.5)
				(island_removal_mode 0)
			)
			(polygon
				(pts
					(arc
						(start 64.382904 -50.050192)
						(mid 67.383152 -47.049944)
						(end 64.382904 -44.049696)
					)
					(arc
						(start 62.782704 -44.049696)
						(mid 59.782456 -47.049944)
						(end 62.782704 -50.050192)
					)
				)
			)
		)
	)
	(footprint ""
		(layer "F.Cu")
		(at 196.536564 -71.836788 90)
		(property "Reference" "PC2200"
			(at 0 0 90)
			(layer "F.SilkS")
			(hide yes)
			(effects
				(font
					(size 1.27 1.27)
				)
			)
		)
		(property "Value" ""
			(at 0 0 90)
			(layer "F.Fab")
			(effects
				(font
					(size 1.27 1.27)
				)
			)
		)
		(duplicate_pad_numbers_are_jumpers no)
		(fp_line
			(start 0.7874 -0.4064)
			(end 0.7874 0.4064)
			(stroke
				(width 0.1524)
				(type default)
			)
			(layer "F.SilkS")
		)
		(fp_line
			(start -0.7874 -0.4064)
			(end 0.7874 -0.4064)
			(stroke
				(width 0.1524)
				(type default)
			)
			(layer "F.SilkS")
		)
		(fp_line
			(start 0.7874 0.4064)
			(end -0.7874 0.4064)
			(stroke
				(width 0.1524)
				(type default)
			)
			(layer "F.SilkS")
		)
		(fp_line
			(start -0.7874 0.4064)
			(end -0.7874 -0.4064)
			(stroke
				(width 0.1524)
				(type default)
			)
			(layer "F.SilkS")
		)
		(fp_line
			(start -0.12065 -0.305054)
			(end -0.12065 -0.2794)
			(stroke
				(width 0.1)
				(type default)
			)
			(layer "F.Fab")
		)
		(fp_line
			(start -0.67945 -0.305054)
			(end -0.12065 -0.305054)
			(stroke
				(width 0.1)
				(type default)
			)
			(layer "F.Fab")
		)
		(fp_line
			(start 0.67945 -0.3048)
			(end 0.67945 0.3048)
			(stroke
				(width 0.1)
				(type default)
			)
			(layer "F.Fab")
		)
		(fp_line
			(start 0.12065 -0.3048)
			(end 0.67945 -0.3048)
			(stroke
				(width 0.1)
				(type default)
			)
			(layer "F.Fab")
		)
		(fp_line
			(start 0.12065 -0.2794)
			(end 0.12065 -0.3048)
			(stroke
				(width 0.1)
				(type default)
			)
			(layer "F.Fab")
		)
		(fp_line
			(start -0.12065 -0.2794)
			(end 0.12065 -0.2794)
			(stroke
				(width 0.1)
				(type default)
			)
			(layer "F.Fab")
		)
		(fp_line
			(start 0.120396 0.2794)
			(end -0.12065 0.2794)
			(stroke
				(width 0.1)
				(type default)
			)
			(layer "F.Fab")
		)
		(fp_line
			(start -0.12065 0.2794)
			(end -0.12065 0.3048)
			(stroke
				(width 0.1)
				(type default)
			)
			(layer "F.Fab")
		)
		(fp_line
			(start 0.67945 0.3048)
			(end 0.120396 0.3048)
			(stroke
				(width 0.1)
				(type default)
			)
			(layer "F.Fab")
		)
		(fp_line
			(start 0.120396 0.3048)
			(end 0.120396 0.2794)
			(stroke
				(width 0.1)
				(type default)
			)
			(layer "F.Fab")
		)
		(fp_line
			(start -0.12065 0.3048)
			(end -0.67945 0.3048)
			(stroke
				(width 0.1)
				(type default)
			)
			(layer "F.Fab")
		)
		(fp_line
			(start -0.67945 0.3048)
			(end -0.67945 -0.305054)
			(stroke
				(width 0.1)
				(type default)
			)
			(layer "F.Fab")
		)
		(pad "1" smd circle
			(at -0.40005 0 90)
			(size 0 0)
			(layers "F.Cu" "F.Mask" "F.Paste")
			(net "P3V3_AUX")
		)
		(pad "2" smd circle
			(at 0.40005 0 90)
			(size 0 0)
			(layers "F.Cu" "F.Mask" "F.Paste")
			(net "GND")
		)
	)
	(footprint ""
		(layer "F.Cu")
		(at 16.422878 -16.099536 90)
		(property "Reference" "C679"
			(at 0 0 90)
			(layer "F.SilkS")
			(hide yes)
			(effects
				(font
					(size 1.27 1.27)
				)
			)
		)
		(property "Value" ""
			(at 0 0 90)
			(layer "F.Fab")
			(effects
				(font
					(size 1.27 1.27)
				)
			)
		)
		(duplicate_pad_numbers_are_jumpers no)
		(fp_line
			(start 0.299974 -0.150114)
			(end 0.299974 0.150114)
			(stroke
				(width 0.1)
				(type default)
			)
			(layer "F.Fab")
		)
		(fp_line
			(start -0.299974 -0.150114)
			(end 0.299974 -0.150114)
			(stroke
				(width 0.1)
				(type default)
			)
			(layer "F.Fab")
		)
		(fp_line
			(start 0.299974 0.150114)
			(end -0.299974 0.150114)
			(stroke
				(width 0.1)
				(type default)
			)
			(layer "F.Fab")
		)
		(fp_line
			(start -0.299974 0.150114)
			(end -0.299974 -0.150114)
			(stroke
				(width 0.1)
				(type default)
			)
			(layer "F.Fab")
		)
		(pad "1" smd rect
			(at -0.2667 0 90)
			(size 0.3048 0.381)
			(layers "F.Cu" "F.Mask" "F.Paste")
			(net "P5E_CPU1_G1_TX_C_DP<15>")
		)
		(pad "2" smd rect
			(at 0.2667 0 90)
			(size 0.3048 0.381)
			(layers "F.Cu" "F.Mask" "F.Paste")
			(net "P5E_CPU1_G1_TX_DP<15>")
		)
	)
	(footprint ""
		(layer "F.Cu")
		(at 200.600564 -69.804788 180)
		(property "Reference" "R3946"
			(at 0 0 180)
			(layer "F.SilkS")
			(hide yes)
			(effects
				(font
					(size 1.27 1.27)
				)
			)
		)
		(property "Value" ""
			(at 0 0 180)
			(layer "F.Fab")
			(effects
				(font
					(size 1.27 1.27)
				)
			)
		)
		(duplicate_pad_numbers_are_jumpers no)
		(fp_line
			(start 0.7874 0.4064)
			(end -0.7874 0.4064)
			(stroke
				(width 0.1524)
				(type default)
			)
			(layer "F.SilkS")
		)
		(fp_line
			(start 0.7874 -0.4064)
			(end 0.7874 0.4064)
			(stroke
				(width 0.1524)
				(type default)
			)
			(layer "F.SilkS")
		)
		(fp_line
			(start -0.7874 0.4064)
			(end -0.7874 -0.4064)
			(stroke
				(width 0.1524)
				(type default)
			)
			(layer "F.SilkS")
		)
		(fp_line
			(start -0.7874 -0.4064)
			(end 0.7874 -0.4064)
			(stroke
				(width 0.1524)
				(type default)
			)
			(layer "F.SilkS")
		)
		(fp_line
			(start 0.67945 0.3048)
			(end 0.120396 0.3048)
			(stroke
				(width 0.1)
				(type default)
			)
			(layer "F.Fab")
		)
		(fp_line
			(start 0.67945 -0.3048)
			(end 0.67945 0.3048)
			(stroke
				(width 0.1)
				(type default)
			)
			(layer "F.Fab")
		)
		(fp_line
			(start 0.12065 -0.2794)
			(end 0.12065 -0.3048)
			(stroke
				(width 0.1)
				(type default)
			)
			(layer "F.Fab")
		)
		(fp_line
			(start 0.12065 -0.3048)
			(end 0.67945 -0.3048)
			(stroke
				(width 0.1)
				(type default)
			)
			(layer "F.Fab")
		)
		(fp_line
			(start 0.120396 0.3048)
			(end 0.120396 0.2794)
			(stroke
				(width 0.1)
				(type default)
			)
			(layer "F.Fab")
		)
		(fp_line
			(start 0.120396 0.2794)
			(end -0.12065 0.2794)
			(stroke
				(width 0.1)
				(type default)
			)
			(layer "F.Fab")
		)
		(fp_line
			(start -0.12065 0.3048)
			(end -0.67945 0.3048)
			(stroke
				(width 0.1)
				(type default)
			)
			(layer "F.Fab")
		)
		(fp_line
			(start -0.12065 0.2794)
			(end -0.12065 0.3048)
			(stroke
				(width 0.1)
				(type default)
			)
			(layer "F.Fab")
		)
		(fp_line
			(start -0.12065 -0.2794)
			(end 0.12065 -0.2794)
			(stroke
				(width 0.1)
				(type default)
			)
			(layer "F.Fab")
		)
		(fp_line
			(start -0.12065 -0.305054)
			(end -0.12065 -0.2794)
			(stroke
				(width 0.1)
				(type default)
			)
			(layer "F.Fab")
		)
		(fp_line
			(start -0.67945 0.3048)
			(end -0.67945 -0.305054)
			(stroke
				(width 0.1)
				(type default)
			)
			(layer "F.Fab")
		)
		(fp_line
			(start -0.67945 -0.305054)
			(end -0.12065 -0.305054)
			(stroke
				(width 0.1)
				(type default)
			)
			(layer "F.Fab")
		)
		(pad "1" smd circle
			(at -0.40005 0 180)
			(size 0 0)
			(layers "F.Cu" "F.Mask" "F.Paste")
			(net "E1S_0_P3V3_EN")
		)
		(pad "2" smd circle
			(at 0.40005 0 180)
			(size 0 0)
			(layers "F.Cu" "F.Mask" "F.Paste")
			(net "P3V3_E1S_EN_0_R2")
		)
	)
	(footprint ""
		(layer "F.Cu")
		(at 360.987594 -320.132964 90)
		(property "Reference" "R8305"
			(at 0 0 90)
			(layer "F.SilkS")
			(hide yes)
			(effects
				(font
					(size 1.27 1.27)
				)
			)
		)
		(property "Value" ""
			(at 0 0 90)
			(layer "F.Fab")
			(effects
				(font
					(size 1.27 1.27)
				)
			)
		)
		(duplicate_pad_numbers_are_jumpers no)
		(fp_line
			(start -0.372364 -0.4064)
			(end 0.364236 -0.4064)
			(stroke
				(width 0.1524)
				(type default)
			)
			(layer "F.SilkS")
		)
		(fp_line
			(start 0.7874 0.073406)
			(end 0.7874 0.4064)
			(stroke
				(width 0.1524)
				(type default)
			)
			(layer "F.SilkS")
		)
		(fp_line
			(start 0.7874 0.4064)
			(end -0.7874 0.4064)
			(stroke
				(width 0.1524)
				(type default)
			)
			(layer "F.SilkS")
		)
		(fp_line
			(start -0.7874 0.4064)
			(end -0.7874 0.022606)
			(stroke
				(width 0.1524)
				(type default)
			)
			(layer "F.SilkS")
		)
		(fp_line
			(start -0.12065 -0.305054)
			(end -0.12065 -0.2794)
			(stroke
				(width 0.1)
				(type default)
			)
			(layer "F.Fab")
		)
		(fp_line
			(start -0.67945 -0.305054)
			(end -0.12065 -0.305054)
			(stroke
				(width 0.1)
				(type default)
			)
			(layer "F.Fab")
		)
		(fp_line
			(start 0.67945 -0.3048)
			(end 0.67945 0.3048)
			(stroke
				(width 0.1)
				(type default)
			)
			(layer "F.Fab")
		)
		(fp_line
			(start 0.12065 -0.3048)
			(end 0.67945 -0.3048)
			(stroke
				(width 0.1)
				(type default)
			)
			(layer "F.Fab")
		)
		(fp_line
			(start 0.12065 -0.2794)
			(end 0.12065 -0.3048)
			(stroke
				(width 0.1)
				(type default)
			)
			(layer "F.Fab")
		)
		(fp_line
			(start -0.12065 -0.2794)
			(end 0.12065 -0.2794)
			(stroke
				(width 0.1)
				(type default)
			)
			(layer "F.Fab")
		)
		(fp_line
			(start 0.120396 0.2794)
			(end -0.12065 0.2794)
			(stroke
				(width 0.1)
				(type default)
			)
			(layer "F.Fab")
		)
		(fp_line
			(start -0.12065 0.2794)
			(end -0.12065 0.3048)
			(stroke
				(width 0.1)
				(type default)
			)
			(layer "F.Fab")
		)
		(fp_line
			(start 0.67945 0.3048)
			(end 0.120396 0.3048)
			(stroke
				(width 0.1)
				(type default)
			)
			(layer "F.Fab")
		)
		(fp_line
			(start 0.120396 0.3048)
			(end 0.120396 0.2794)
			(stroke
				(width 0.1)
				(type default)
			)
			(layer "F.Fab")
		)
		(fp_line
			(start -0.12065 0.3048)
			(end -0.67945 0.3048)
			(stroke
				(width 0.1)
				(type default)
			)
			(layer "F.Fab")
		)
		(fp_line
			(start -0.67945 0.3048)
			(end -0.67945 -0.305054)
			(stroke
				(width 0.1)
				(type default)
			)
			(layer "F.Fab")
		)
		(pad "1" smd circle
			(at -0.40005 0 90)
			(size 0 0)
			(layers "F.Cu" "F.Mask" "F.Paste")
			(net "CLK_100M_CPU0_CLK13_R_DP")
		)
		(pad "2" smd circle
			(at 0.40005 0 90)
			(size 0 0)
			(layers "F.Cu" "F.Mask" "F.Paste")
			(net "CLK_100M_CPU0_CLK13_DP")
		)
	)
	(footprint ""
		(layer "F.Cu")
		(at 53.594 -435.229 -90)
		(property "Reference" "C1957"
			(at 0 0 270)
			(layer "F.SilkS")
			(hide yes)
			(effects
				(font
					(size 1.27 1.27)
				)
			)
		)
		(property "Value" ""
			(at 0 0 270)
			(layer "F.Fab")
			(effects
				(font
					(size 1.27 1.27)
				)
			)
		)
		(duplicate_pad_numbers_are_jumpers no)
		(fp_line
			(start -0.7874 0.4064)
			(end -0.7874 -0.4064)
			(stroke
				(width 0.1524)
				(type default)
			)
			(layer "F.SilkS")
		)
		(fp_line
			(start 0.7874 0.4064)
			(end -0.7874 0.4064)
			(stroke
				(width 0.1524)
				(type default)
			)
			(layer "F.SilkS")
		)
		(fp_line
			(start -0.7874 -0.4064)
			(end 0.7874 -0.4064)
			(stroke
				(width 0.1524)
				(type default)
			)
			(layer "F.SilkS")
		)
		(fp_line
			(start 0.7874 -0.4064)
			(end 0.7874 0.4064)
			(stroke
				(width 0.1524)
				(type default)
			)
			(layer "F.SilkS")
		)
		(fp_line
			(start -0.67945 0.3048)
			(end -0.67945 -0.305054)
			(stroke
				(width 0.1)
				(type default)
			)
			(layer "F.Fab")
		)
		(fp_line
			(start -0.12065 0.3048)
			(end -0.67945 0.3048)
			(stroke
				(width 0.1)
				(type default)
			)
			(layer "F.Fab")
		)
		(fp_line
			(start 0.120396 0.3048)
			(end 0.120396 0.2794)
			(stroke
				(width 0.1)
				(type default)
			)
			(layer "F.Fab")
		)
		(fp_line
			(start 0.67945 0.3048)
			(end 0.120396 0.3048)
			(stroke
				(width 0.1)
				(type default)
			)
			(layer "F.Fab")
		)
		(fp_line
			(start -0.12065 0.2794)
			(end -0.12065 0.3048)
			(stroke
				(width 0.1)
				(type default)
			)
			(layer "F.Fab")
		)
		(fp_line
			(start 0.120396 0.2794)
			(end -0.12065 0.2794)
			(stroke
				(width 0.1)
				(type default)
			)
			(layer "F.Fab")
		)
		(fp_line
			(start -0.12065 -0.2794)
			(end 0.12065 -0.2794)
			(stroke
				(width 0.1)
				(type default)
			)
			(layer "F.Fab")
		)
		(fp_line
			(start 0.12065 -0.2794)
			(end 0.12065 -0.3048)
			(stroke
				(width 0.1)
				(type default)
			)
			(layer "F.Fab")
		)
		(fp_line
			(start 0.12065 -0.3048)
			(end 0.67945 -0.3048)
			(stroke
				(width 0.1)
				(type default)
			)
			(layer "F.Fab")
		)
		(fp_line
			(start 0.67945 -0.3048)
			(end 0.67945 0.3048)
			(stroke
				(width 0.1)
				(type default)
			)
			(layer "F.Fab")
		)
		(fp_line
			(start -0.67945 -0.305054)
			(end -0.12065 -0.305054)
			(stroke
				(width 0.1)
				(type default)
			)
			(layer "F.Fab")
		)
		(fp_line
			(start -0.12065 -0.305054)
			(end -0.12065 -0.2794)
			(stroke
				(width 0.1)
				(type default)
			)
			(layer "F.Fab")
		)
		(pad "1" smd circle
			(at -0.40005 0 270)
			(size 0 0)
			(layers "F.Cu" "F.Mask" "F.Paste")
			(net "P3V3_AUX")
		)
		(pad "2" smd circle
			(at 0.40005 0 270)
			(size 0 0)
			(layers "F.Cu" "F.Mask" "F.Paste")
			(net "GND")
		)
	)
	(footprint ""
		(layer "F.Cu")
		(at 241.656108 -385.27736 90)
		(property "Reference" "PPQ1"
			(at -1.930908 -3.4417 90)
			(unlocked yes)
			(layer "F.SilkS")
			(effects
				(font
					(size 0.7874 0.5842)
					(thickness 0.1524)
				)
				(justify left)
			)
		)
		(property "Value" ""
			(at 0 0 90)
			(layer "F.Fab")
			(effects
				(font
					(size 1.27 1.27)
				)
			)
		)
		(duplicate_pad_numbers_are_jumpers no)
		(fp_line
			(start 2.350008 -2.649982)
			(end 2.350008 -2.4892)
			(stroke
				(width 0.1524)
				(type default)
			)
			(layer "F.SilkS")
		)
		(fp_line
			(start -2.350008 -2.649982)
			(end 2.350008 -2.649982)
			(stroke
				(width 0.1524)
				(type default)
			)
			(layer "F.SilkS")
		)
		(fp_line
			(start -2.350008 -2.4384)
			(end -2.350008 -2.649982)
			(stroke
				(width 0.1524)
				(type default)
			)
			(layer "F.SilkS")
		)
		(fp_line
			(start 2.350008 2.4892)
			(end 2.350008 2.649982)
			(stroke
				(width 0.1524)
				(type default)
			)
			(layer "F.SilkS")
		)
		(fp_line
			(start 2.350008 2.649982)
			(end -2.350008 2.649982)
			(stroke
				(width 0.1524)
				(type default)
			)
			(layer "F.SilkS")
		)
		(fp_line
			(start -2.350008 2.649982)
			(end -2.350008 2.413)
			(stroke
				(width 0.1524)
				(type default)
			)
			(layer "F.SilkS")
		)
		(fp_poly
			(pts
				(xy -3.28803 -4.262628) (xy -2.492502 -4.177538) (xy -3.02006 -3.186684)
			)
			(stroke
				(width 0)
				(type default)
			)
			(fill yes)
			(layer "F.SilkS")
		)
		(fp_line
			(start 2.350008 -2.649982)
			(end 2.350008 2.649982)
			(stroke
				(width 0.1)
				(type default)
			)
			(layer "F.Fab")
		)
		(fp_line
			(start -2.350008 -2.649982)
			(end 2.350008 -2.649982)
			(stroke
				(width 0.1)
				(type default)
			)
			(layer "F.Fab")
		)
		(fp_line
			(start 2.350008 2.649982)
			(end -2.350008 2.649982)
			(stroke
				(width 0.1)
				(type default)
			)
			(layer "F.Fab")
		)
		(fp_line
			(start -2.350008 2.649982)
			(end -2.350008 -2.649982)
			(stroke
				(width 0.1)
				(type default)
			)
			(layer "F.Fab")
		)
		(fp_poly
			(pts
				(xy -3.717544 -1.905) (xy -4.758944 -2.3241) (xy -4.758944 -1.524)
			)
			(stroke
				(width 0)
				(type default)
			)
			(fill yes)
			(layer "F.Fab")
		)
		(pad "1" smd rect
			(at -2.999994 -1.905)
			(size 0.7112 1.1684)
			(layers "F.Cu" "F.Mask" "F.Paste")
			(net "P12V_AUX")
		)
		(pad "2" smd rect
			(at -2.999994 -0.635)
			(size 0.7112 1.1684)
			(layers "F.Cu" "F.Mask" "F.Paste")
			(net "P12V_AUX")
		)
		(pad "3" smd rect
			(at -2.999994 0.635)
			(size 0.7112 1.1684)
			(layers "F.Cu" "F.Mask" "F.Paste")
			(net "P12V_AUX")
		)
		(pad "4" smd rect
			(at -2.999994 1.905)
			(size 0.7112 1.1684)
			(layers "F.Cu" "F.Mask" "F.Paste")
			(net "P12V_HSC_GATE_G5")
		)
		(pad "5" smd circle
			(at 0.925068 0)
			(size 0 0)
			(layers "F.Cu" "F.Mask" "F.Paste")
			(net "P12V_MAIN_R")
		)
		(zone
			(layer "F.Cu")
			(hatch none 0.5)
			(connect_pads
				(clearance 0)
			)
			(min_thickness 0.25)
			(keepout
				(tracks not_allowed)
				(vias allowed)
				(pads allowed)
				(copperpour not_allowed)
				(footprints allowed)
			)
			(placement
				(enabled no)
				(sheetname "")
			)
			(fill
				(thermal_gap 0.5)
				(thermal_bridge_width 0.5)
				(island_removal_mode 0)
			)
			(polygon
				(pts
					(xy 239.014508 -383.7178) (xy 244.297708 -383.7178) (xy 244.297708 -382.92786) (xy 239.014508 -382.92786)
				)
			)
		)
	)
	(footprint ""
		(layer "F.Cu")
		(at 13.206984 -394.447268 90)
		(property "Reference" "PC6611_1"
			(at 0 0 90)
			(layer "F.SilkS")
			(hide yes)
			(effects
				(font
					(size 1.27 1.27)
				)
			)
		)
		(property "Value" ""
			(at 0 0 90)
			(layer "F.Fab")
			(effects
				(font
					(size 1.27 1.27)
				)
			)
		)
		(duplicate_pad_numbers_are_jumpers no)
		(fp_line
			(start 0.7874 -0.4064)
			(end 0.7874 0.4064)
			(stroke
				(width 0.1524)
				(type default)
			)
			(layer "F.SilkS")
		)
		(fp_line
			(start -0.7874 -0.4064)
			(end 0.7874 -0.4064)
			(stroke
				(width 0.1524)
				(type default)
			)
			(layer "F.SilkS")
		)
		(fp_line
			(start 0.7874 0.4064)
			(end -0.7874 0.4064)
			(stroke
				(width 0.1524)
				(type default)
			)
			(layer "F.SilkS")
		)
		(fp_line
			(start -0.7874 0.4064)
			(end -0.7874 -0.4064)
			(stroke
				(width 0.1524)
				(type default)
			)
			(layer "F.SilkS")
		)
		(fp_line
			(start -0.12065 -0.305054)
			(end -0.12065 -0.2794)
			(stroke
				(width 0.1)
				(type default)
			)
			(layer "F.Fab")
		)
		(fp_line
			(start -0.67945 -0.305054)
			(end -0.12065 -0.305054)
			(stroke
				(width 0.1)
				(type default)
			)
			(layer "F.Fab")
		)
		(fp_line
			(start 0.67945 -0.3048)
			(end 0.67945 0.3048)
			(stroke
				(width 0.1)
				(type default)
			)
			(layer "F.Fab")
		)
		(fp_line
			(start 0.12065 -0.3048)
			(end 0.67945 -0.3048)
			(stroke
				(width 0.1)
				(type default)
			)
			(layer "F.Fab")
		)
		(fp_line
			(start 0.12065 -0.2794)
			(end 0.12065 -0.3048)
			(stroke
				(width 0.1)
				(type default)
			)
			(layer "F.Fab")
		)
		(fp_line
			(start -0.12065 -0.2794)
			(end 0.12065 -0.2794)
			(stroke
				(width 0.1)
				(type default)
			)
			(layer "F.Fab")
		)
		(fp_line
			(start 0.120396 0.2794)
			(end -0.12065 0.2794)
			(stroke
				(width 0.1)
				(type default)
			)
			(layer "F.Fab")
		)
		(fp_line
			(start -0.12065 0.2794)
			(end -0.12065 0.3048)
			(stroke
				(width 0.1)
				(type default)
			)
			(layer "F.Fab")
		)
		(fp_line
			(start 0.67945 0.3048)
			(end 0.120396 0.3048)
			(stroke
				(width 0.1)
				(type default)
			)
			(layer "F.Fab")
		)
		(fp_line
			(start 0.120396 0.3048)
			(end 0.120396 0.2794)
			(stroke
				(width 0.1)
				(type default)
			)
			(layer "F.Fab")
		)
		(fp_line
			(start -0.12065 0.3048)
			(end -0.67945 0.3048)
			(stroke
				(width 0.1)
				(type default)
			)
			(layer "F.Fab")
		)
		(fp_line
			(start -0.67945 0.3048)
			(end -0.67945 -0.305054)
			(stroke
				(width 0.1)
				(type default)
			)
			(layer "F.Fab")
		)
		(pad "1" smd circle
			(at -0.40005 0 90)
			(size 0 0)
			(layers "F.Cu" "F.Mask" "F.Paste")
			(net "PV09_RETIMER_CPU1_VCCS")
		)
		(pad "2" smd circle
			(at 0.40005 0 90)
			(size 0 0)
			(layers "F.Cu" "F.Mask" "F.Paste")
			(net "GND")
		)
	)
	(footprint ""
		(layer "F.Cu")
		(at 100.500434 -435.59984)
		(property "Reference" "H94"
			(at -5.619242 -4.539742 0)
			(unlocked yes)
			(layer "F.SilkS")
			(effects
				(font
					(size 0.7874 0.5842)
					(thickness 0.1524)
				)
				(justify left)
			)
		)
		(property "Value" ""
			(at 0 0 0)
			(layer "F.Fab")
			(effects
				(font
					(size 1.27 1.27)
				)
			)
		)
		(duplicate_pad_numbers_are_jumpers no)
		(pad "1" thru_hole circle
			(at 0 0)
			(size 10.0076 10.0076)
			(drill 5.6134)
			(layers "*.Cu" "*.Mask")
			(remove_unused_layers no)
			(net "GND")
			(clearance -1.9431)
		)
	)
	(footprint ""
		(layer "F.Cu")
		(at 194.945 -100.294948 -90)
		(property "Reference" "R182"
			(at 0 0 270)
			(layer "F.SilkS")
			(hide yes)
			(effects
				(font
					(size 1.27 1.27)
				)
			)
		)
		(property "Value" ""
			(at 0 0 270)
			(layer "F.Fab")
			(effects
				(font
					(size 1.27 1.27)
				)
			)
		)
		(duplicate_pad_numbers_are_jumpers no)
		(fp_line
			(start -0.7874 0.4064)
			(end -0.7874 -0.4064)
			(stroke
				(width 0.1524)
				(type default)
			)
			(layer "F.SilkS")
		)
		(fp_line
			(start 0.7874 0.4064)
			(end -0.7874 0.4064)
			(stroke
				(width 0.1524)
				(type default)
			)
			(layer "F.SilkS")
		)
		(fp_line
			(start -0.7874 -0.4064)
			(end 0.7874 -0.4064)
			(stroke
				(width 0.1524)
				(type default)
			)
			(layer "F.SilkS")
		)
		(fp_line
			(start 0.7874 -0.4064)
			(end 0.7874 0.4064)
			(stroke
				(width 0.1524)
				(type default)
			)
			(layer "F.SilkS")
		)
		(fp_line
			(start -0.67945 0.3048)
			(end -0.67945 -0.305054)
			(stroke
				(width 0.1)
				(type default)
			)
			(layer "F.Fab")
		)
		(fp_line
			(start -0.12065 0.3048)
			(end -0.67945 0.3048)
			(stroke
				(width 0.1)
				(type default)
			)
			(layer "F.Fab")
		)
		(fp_line
			(start 0.120396 0.3048)
			(end 0.120396 0.2794)
			(stroke
				(width 0.1)
				(type default)
			)
			(layer "F.Fab")
		)
		(fp_line
			(start 0.67945 0.3048)
			(end 0.120396 0.3048)
			(stroke
				(width 0.1)
				(type default)
			)
			(layer "F.Fab")
		)
		(fp_line
			(start -0.12065 0.2794)
			(end -0.12065 0.3048)
			(stroke
				(width 0.1)
				(type default)
			)
			(layer "F.Fab")
		)
		(fp_line
			(start 0.120396 0.2794)
			(end -0.12065 0.2794)
			(stroke
				(width 0.1)
				(type default)
			)
			(layer "F.Fab")
		)
		(fp_line
			(start -0.12065 -0.2794)
			(end 0.12065 -0.2794)
			(stroke
				(width 0.1)
				(type default)
			)
			(layer "F.Fab")
		)
		(fp_line
			(start 0.12065 -0.2794)
			(end 0.12065 -0.3048)
			(stroke
				(width 0.1)
				(type default)
			)
			(layer "F.Fab")
		)
		(fp_line
			(start 0.12065 -0.3048)
			(end 0.67945 -0.3048)
			(stroke
				(width 0.1)
				(type default)
			)
			(layer "F.Fab")
		)
		(fp_line
			(start 0.67945 -0.3048)
			(end 0.67945 0.3048)
			(stroke
				(width 0.1)
				(type default)
			)
			(layer "F.Fab")
		)
		(fp_line
			(start -0.67945 -0.305054)
			(end -0.12065 -0.305054)
			(stroke
				(width 0.1)
				(type default)
			)
			(layer "F.Fab")
		)
		(fp_line
			(start -0.12065 -0.305054)
			(end -0.12065 -0.2794)
			(stroke
				(width 0.1)
				(type default)
			)
			(layer "F.Fab")
		)
		(pad "1" smd circle
			(at -0.40005 0 270)
			(size 0 0)
			(layers "F.Cu" "F.Mask" "F.Paste")
			(net "FM_PRSNT_CPU0_R_N")
		)
		(pad "2" smd circle
			(at 0.40005 0 270)
			(size 0 0)
			(layers "F.Cu" "F.Mask" "F.Paste")
			(net "FM_PRSNT_CPU0_N")
		)
	)
	(footprint ""
		(layer "F.Cu")
		(at 328.514964 -151.641302)
		(property "Reference" "PR438"
			(at 0 0 0)
			(layer "F.SilkS")
			(hide yes)
			(effects
				(font
					(size 1.27 1.27)
				)
			)
		)
		(property "Value" ""
			(at 0 0 0)
			(layer "F.Fab")
			(effects
				(font
					(size 1.27 1.27)
				)
			)
		)
		(duplicate_pad_numbers_are_jumpers no)
		(fp_line
			(start -0.7874 -0.4064)
			(end 0.7874 -0.4064)
			(stroke
				(width 0.1524)
				(type default)
			)
			(layer "F.SilkS")
		)
		(fp_line
			(start -0.7874 0.4064)
			(end -0.7874 -0.4064)
			(stroke
				(width 0.1524)
				(type default)
			)
			(layer "F.SilkS")
		)
		(fp_line
			(start 0.7874 -0.4064)
			(end 0.7874 0.4064)
			(stroke
				(width 0.1524)
				(type default)
			)
			(layer "F.SilkS")
		)
		(fp_line
			(start 0.7874 0.4064)
			(end -0.7874 0.4064)
			(stroke
				(width 0.1524)
				(type default)
			)
			(layer "F.SilkS")
		)
		(fp_line
			(start -0.67945 -0.305054)
			(end -0.12065 -0.305054)
			(stroke
				(width 0.1)
				(type default)
			)
			(layer "F.Fab")
		)
		(fp_line
			(start -0.67945 0.3048)
			(end -0.67945 -0.305054)
			(stroke
				(width 0.1)
				(type default)
			)
			(layer "F.Fab")
		)
		(fp_line
			(start -0.12065 -0.305054)
			(end -0.12065 -0.2794)
			(stroke
				(width 0.1)
				(type default)
			)
			(layer "F.Fab")
		)
		(fp_line
			(start -0.12065 -0.2794)
			(end 0.12065 -0.2794)
			(stroke
				(width 0.1)
				(type default)
			)
			(layer "F.Fab")
		)
		(fp_line
			(start -0.12065 0.2794)
			(end -0.12065 0.3048)
			(stroke
				(width 0.1)
				(type default)
			)
			(layer "F.Fab")
		)
		(fp_line
			(start -0.12065 0.3048)
			(end -0.67945 0.3048)
			(stroke
				(width 0.1)
				(type default)
			)
			(layer "F.Fab")
		)
		(fp_line
			(start 0.120396 0.2794)
			(end -0.12065 0.2794)
			(stroke
				(width 0.1)
				(type default)
			)
			(layer "F.Fab")
		)
		(fp_line
			(start 0.120396 0.3048)
			(end 0.120396 0.2794)
			(stroke
				(width 0.1)
				(type default)
			)
			(layer "F.Fab")
		)
		(fp_line
			(start 0.12065 -0.3048)
			(end 0.67945 -0.3048)
			(stroke
				(width 0.1)
				(type default)
			)
			(layer "F.Fab")
		)
		(fp_line
			(start 0.12065 -0.2794)
			(end 0.12065 -0.3048)
			(stroke
				(width 0.1)
				(type default)
			)
			(layer "F.Fab")
		)
		(fp_line
			(start 0.67945 -0.3048)
			(end 0.67945 0.3048)
			(stroke
				(width 0.1)
				(type default)
			)
			(layer "F.Fab")
		)
		(fp_line
			(start 0.67945 0.3048)
			(end 0.120396 0.3048)
			(stroke
				(width 0.1)
				(type default)
			)
			(layer "F.Fab")
		)
		(pad "1" smd circle
			(at -0.40005 0)
			(size 0 0)
			(layers "F.Cu" "F.Mask" "F.Paste")
			(net "PVDD18_S5_P0_FB_RC")
		)
		(pad "2" smd circle
			(at 0.40005 0)
			(size 0 0)
			(layers "F.Cu" "F.Mask" "F.Paste")
			(net "PVDD18_S5_P0")
		)
	)
	(footprint ""
		(layer "F.Cu")
		(at 227.488242 -289.012122 180)
		(property "Reference" "C105"
			(at 0 0 180)
			(layer "F.SilkS")
			(hide yes)
			(effects
				(font
					(size 1.27 1.27)
				)
			)
		)
		(property "Value" ""
			(at 0 0 180)
			(layer "F.Fab")
			(effects
				(font
					(size 1.27 1.27)
				)
			)
		)
		(duplicate_pad_numbers_are_jumpers no)
		(fp_line
			(start 0.7874 0.4064)
			(end -0.7874 0.4064)
			(stroke
				(width 0.1524)
				(type default)
			)
			(layer "F.SilkS")
		)
		(fp_line
			(start 0.7874 -0.4064)
			(end 0.7874 0.4064)
			(stroke
				(width 0.1524)
				(type default)
			)
			(layer "F.SilkS")
		)
		(fp_line
			(start -0.7874 0.4064)
			(end -0.7874 -0.4064)
			(stroke
				(width 0.1524)
				(type default)
			)
			(layer "F.SilkS")
		)
		(fp_line
			(start -0.7874 -0.4064)
			(end 0.7874 -0.4064)
			(stroke
				(width 0.1524)
				(type default)
			)
			(layer "F.SilkS")
		)
		(fp_line
			(start 0.67945 0.3048)
			(end 0.120396 0.3048)
			(stroke
				(width 0.1)
				(type default)
			)
			(layer "F.Fab")
		)
		(fp_line
			(start 0.67945 -0.3048)
			(end 0.67945 0.3048)
			(stroke
				(width 0.1)
				(type default)
			)
			(layer "F.Fab")
		)
		(fp_line
			(start 0.12065 -0.2794)
			(end 0.12065 -0.3048)
			(stroke
				(width 0.1)
				(type default)
			)
			(layer "F.Fab")
		)
		(fp_line
			(start 0.12065 -0.3048)
			(end 0.67945 -0.3048)
			(stroke
				(width 0.1)
				(type default)
			)
			(layer "F.Fab")
		)
		(fp_line
			(start 0.120396 0.3048)
			(end 0.120396 0.2794)
			(stroke
				(width 0.1)
				(type default)
			)
			(layer "F.Fab")
		)
		(fp_line
			(start 0.120396 0.2794)
			(end -0.12065 0.2794)
			(stroke
				(width 0.1)
				(type default)
			)
			(layer "F.Fab")
		)
		(fp_line
			(start -0.12065 0.3048)
			(end -0.67945 0.3048)
			(stroke
				(width 0.1)
				(type default)
			)
			(layer "F.Fab")
		)
		(fp_line
			(start -0.12065 0.2794)
			(end -0.12065 0.3048)
			(stroke
				(width 0.1)
				(type default)
			)
			(layer "F.Fab")
		)
		(fp_line
			(start -0.12065 -0.2794)
			(end 0.12065 -0.2794)
			(stroke
				(width 0.1)
				(type default)
			)
			(layer "F.Fab")
		)
		(fp_line
			(start -0.12065 -0.305054)
			(end -0.12065 -0.2794)
			(stroke
				(width 0.1)
				(type default)
			)
			(layer "F.Fab")
		)
		(fp_line
			(start -0.67945 0.3048)
			(end -0.67945 -0.305054)
			(stroke
				(width 0.1)
				(type default)
			)
			(layer "F.Fab")
		)
		(fp_line
			(start -0.67945 -0.305054)
			(end -0.12065 -0.305054)
			(stroke
				(width 0.1)
				(type default)
			)
			(layer "F.Fab")
		)
		(pad "1" smd circle
			(at -0.40005 0 180)
			(size 0 0)
			(layers "F.Cu" "F.Mask" "F.Paste")
			(net "P1V8_RETIMER_CPU1_EN")
		)
		(pad "2" smd circle
			(at 0.40005 0 180)
			(size 0 0)
			(layers "F.Cu" "F.Mask" "F.Paste")
			(net "GND")
		)
	)
	(footprint ""
		(layer "F.Cu")
		(at 259.831586 -101.022404)
		(property "Reference" "C1512"
			(at 0 0 0)
			(layer "F.SilkS")
			(hide yes)
			(effects
				(font
					(size 1.27 1.27)
				)
			)
		)
		(property "Value" ""
			(at 0 0 0)
			(layer "F.Fab")
			(effects
				(font
					(size 1.27 1.27)
				)
			)
		)
		(duplicate_pad_numbers_are_jumpers no)
		(fp_line
			(start -0.7874 -0.4064)
			(end 0.7874 -0.4064)
			(stroke
				(width 0.1524)
				(type default)
			)
			(layer "F.SilkS")
		)
		(fp_line
			(start -0.7874 0.4064)
			(end -0.7874 -0.4064)
			(stroke
				(width 0.1524)
				(type default)
			)
			(layer "F.SilkS")
		)
		(fp_line
			(start 0.7874 -0.4064)
			(end 0.7874 0.4064)
			(stroke
				(width 0.1524)
				(type default)
			)
			(layer "F.SilkS")
		)
		(fp_line
			(start 0.7874 0.4064)
			(end -0.7874 0.4064)
			(stroke
				(width 0.1524)
				(type default)
			)
			(layer "F.SilkS")
		)
		(fp_line
			(start -0.67945 -0.305054)
			(end -0.12065 -0.305054)
			(stroke
				(width 0.1)
				(type default)
			)
			(layer "F.Fab")
		)
		(fp_line
			(start -0.67945 0.3048)
			(end -0.67945 -0.305054)
			(stroke
				(width 0.1)
				(type default)
			)
			(layer "F.Fab")
		)
		(fp_line
			(start -0.12065 -0.305054)
			(end -0.12065 -0.2794)
			(stroke
				(width 0.1)
				(type default)
			)
			(layer "F.Fab")
		)
		(fp_line
			(start -0.12065 -0.2794)
			(end 0.12065 -0.2794)
			(stroke
				(width 0.1)
				(type default)
			)
			(layer "F.Fab")
		)
		(fp_line
			(start -0.12065 0.2794)
			(end -0.12065 0.3048)
			(stroke
				(width 0.1)
				(type default)
			)
			(layer "F.Fab")
		)
		(fp_line
			(start -0.12065 0.3048)
			(end -0.67945 0.3048)
			(stroke
				(width 0.1)
				(type default)
			)
			(layer "F.Fab")
		)
		(fp_line
			(start 0.120396 0.2794)
			(end -0.12065 0.2794)
			(stroke
				(width 0.1)
				(type default)
			)
			(layer "F.Fab")
		)
		(fp_line
			(start 0.120396 0.3048)
			(end 0.120396 0.2794)
			(stroke
				(width 0.1)
				(type default)
			)
			(layer "F.Fab")
		)
		(fp_line
			(start 0.12065 -0.3048)
			(end 0.67945 -0.3048)
			(stroke
				(width 0.1)
				(type default)
			)
			(layer "F.Fab")
		)
		(fp_line
			(start 0.12065 -0.2794)
			(end 0.12065 -0.3048)
			(stroke
				(width 0.1)
				(type default)
			)
			(layer "F.Fab")
		)
		(fp_line
			(start 0.67945 -0.3048)
			(end 0.67945 0.3048)
			(stroke
				(width 0.1)
				(type default)
			)
			(layer "F.Fab")
		)
		(fp_line
			(start 0.67945 0.3048)
			(end 0.120396 0.3048)
			(stroke
				(width 0.1)
				(type default)
			)
			(layer "F.Fab")
		)
		(pad "1" smd circle
			(at -0.40005 0)
			(size 0 0)
			(layers "F.Cu" "F.Mask" "F.Paste")
			(net "JTAG_DBREQ_N")
		)
		(pad "2" smd circle
			(at 0.40005 0)
			(size 0 0)
			(layers "F.Cu" "F.Mask" "F.Paste")
			(net "GND")
		)
	)
	(footprint ""
		(layer "F.Cu")
		(at 23.916132 -332.638654 90)
		(property "Reference" "PC451"
			(at 0 0 90)
			(layer "F.SilkS")
			(hide yes)
			(effects
				(font
					(size 1.27 1.27)
				)
			)
		)
		(property "Value" ""
			(at 0 0 90)
			(layer "F.Fab")
			(effects
				(font
					(size 1.27 1.27)
				)
			)
		)
		(duplicate_pad_numbers_are_jumpers no)
		(fp_line
			(start 0.7874 -0.4064)
			(end 0.7874 0.4064)
			(stroke
				(width 0.1524)
				(type default)
			)
			(layer "F.SilkS")
		)
		(fp_line
			(start -0.7874 -0.4064)
			(end 0.7874 -0.4064)
			(stroke
				(width 0.1524)
				(type default)
			)
			(layer "F.SilkS")
		)
		(fp_line
			(start 0.7874 0.4064)
			(end -0.7874 0.4064)
			(stroke
				(width 0.1524)
				(type default)
			)
			(layer "F.SilkS")
		)
		(fp_line
			(start -0.7874 0.4064)
			(end -0.7874 -0.4064)
			(stroke
				(width 0.1524)
				(type default)
			)
			(layer "F.SilkS")
		)
		(fp_line
			(start -0.12065 -0.305054)
			(end -0.12065 -0.2794)
			(stroke
				(width 0.1)
				(type default)
			)
			(layer "F.Fab")
		)
		(fp_line
			(start -0.67945 -0.305054)
			(end -0.12065 -0.305054)
			(stroke
				(width 0.1)
				(type default)
			)
			(layer "F.Fab")
		)
		(fp_line
			(start 0.67945 -0.3048)
			(end 0.67945 0.3048)
			(stroke
				(width 0.1)
				(type default)
			)
			(layer "F.Fab")
		)
		(fp_line
			(start 0.12065 -0.3048)
			(end 0.67945 -0.3048)
			(stroke
				(width 0.1)
				(type default)
			)
			(layer "F.Fab")
		)
		(fp_line
			(start 0.12065 -0.2794)
			(end 0.12065 -0.3048)
			(stroke
				(width 0.1)
				(type default)
			)
			(layer "F.Fab")
		)
		(fp_line
			(start -0.12065 -0.2794)
			(end 0.12065 -0.2794)
			(stroke
				(width 0.1)
				(type default)
			)
			(layer "F.Fab")
		)
		(fp_line
			(start 0.120396 0.2794)
			(end -0.12065 0.2794)
			(stroke
				(width 0.1)
				(type default)
			)
			(layer "F.Fab")
		)
		(fp_line
			(start -0.12065 0.2794)
			(end -0.12065 0.3048)
			(stroke
				(width 0.1)
				(type default)
			)
			(layer "F.Fab")
		)
		(fp_line
			(start 0.67945 0.3048)
			(end 0.120396 0.3048)
			(stroke
				(width 0.1)
				(type default)
			)
			(layer "F.Fab")
		)
		(fp_line
			(start 0.120396 0.3048)
			(end 0.120396 0.2794)
			(stroke
				(width 0.1)
				(type default)
			)
			(layer "F.Fab")
		)
		(fp_line
			(start -0.12065 0.3048)
			(end -0.67945 0.3048)
			(stroke
				(width 0.1)
				(type default)
			)
			(layer "F.Fab")
		)
		(fp_line
			(start -0.67945 0.3048)
			(end -0.67945 -0.305054)
			(stroke
				(width 0.1)
				(type default)
			)
			(layer "F.Fab")
		)
		(pad "1" smd circle
			(at -0.40005 0 90)
			(size 0 0)
			(layers "F.Cu" "F.Mask" "F.Paste")
			(net "PVDDIO_P1")
		)
		(pad "2" smd circle
			(at 0.40005 0 90)
			(size 0 0)
			(layers "F.Cu" "F.Mask" "F.Paste")
			(net "GND")
		)
	)
	(footprint ""
		(layer "F.Cu")
		(at 37.402262 -429.790098 -90)
		(property "Reference" "R3286"
			(at 0 0 270)
			(layer "F.SilkS")
			(hide yes)
			(effects
				(font
					(size 1.27 1.27)
				)
			)
		)
		(property "Value" ""
			(at 0 0 270)
			(layer "F.Fab")
			(effects
				(font
					(size 1.27 1.27)
				)
			)
		)
		(duplicate_pad_numbers_are_jumpers no)
		(fp_line
			(start -0.7874 0.4064)
			(end -0.7874 -0.4064)
			(stroke
				(width 0.1524)
				(type default)
			)
			(layer "F.SilkS")
		)
		(fp_line
			(start 0.7874 0.4064)
			(end -0.7874 0.4064)
			(stroke
				(width 0.1524)
				(type default)
			)
			(layer "F.SilkS")
		)
		(fp_line
			(start -0.7874 -0.4064)
			(end 0.7874 -0.4064)
			(stroke
				(width 0.1524)
				(type default)
			)
			(layer "F.SilkS")
		)
		(fp_line
			(start 0.7874 -0.4064)
			(end 0.7874 0.4064)
			(stroke
				(width 0.1524)
				(type default)
			)
			(layer "F.SilkS")
		)
		(fp_line
			(start -0.67945 0.3048)
			(end -0.67945 -0.305054)
			(stroke
				(width 0.1)
				(type default)
			)
			(layer "F.Fab")
		)
		(fp_line
			(start -0.12065 0.3048)
			(end -0.67945 0.3048)
			(stroke
				(width 0.1)
				(type default)
			)
			(layer "F.Fab")
		)
		(fp_line
			(start 0.120396 0.3048)
			(end 0.120396 0.2794)
			(stroke
				(width 0.1)
				(type default)
			)
			(layer "F.Fab")
		)
		(fp_line
			(start 0.67945 0.3048)
			(end 0.120396 0.3048)
			(stroke
				(width 0.1)
				(type default)
			)
			(layer "F.Fab")
		)
		(fp_line
			(start -0.12065 0.2794)
			(end -0.12065 0.3048)
			(stroke
				(width 0.1)
				(type default)
			)
			(layer "F.Fab")
		)
		(fp_line
			(start 0.120396 0.2794)
			(end -0.12065 0.2794)
			(stroke
				(width 0.1)
				(type default)
			)
			(layer "F.Fab")
		)
		(fp_line
			(start -0.12065 -0.2794)
			(end 0.12065 -0.2794)
			(stroke
				(width 0.1)
				(type default)
			)
			(layer "F.Fab")
		)
		(fp_line
			(start 0.12065 -0.2794)
			(end 0.12065 -0.3048)
			(stroke
				(width 0.1)
				(type default)
			)
			(layer "F.Fab")
		)
		(fp_line
			(start 0.12065 -0.3048)
			(end 0.67945 -0.3048)
			(stroke
				(width 0.1)
				(type default)
			)
			(layer "F.Fab")
		)
		(fp_line
			(start 0.67945 -0.3048)
			(end 0.67945 0.3048)
			(stroke
				(width 0.1)
				(type default)
			)
			(layer "F.Fab")
		)
		(fp_line
			(start -0.67945 -0.305054)
			(end -0.12065 -0.305054)
			(stroke
				(width 0.1)
				(type default)
			)
			(layer "F.Fab")
		)
		(fp_line
			(start -0.12065 -0.305054)
			(end -0.12065 -0.2794)
			(stroke
				(width 0.1)
				(type default)
			)
			(layer "F.Fab")
		)
		(pad "1" smd circle
			(at -0.40005 0 270)
			(size 0 0)
			(layers "F.Cu" "F.Mask" "F.Paste")
			(net "P3V3_AUX")
		)
		(pad "2" smd circle
			(at 0.40005 0 270)
			(size 0 0)
			(layers "F.Cu" "F.Mask" "F.Paste")
			(net "FM_P2E_SWB")
		)
	)
	(footprint ""
		(layer "F.Cu")
		(at 76.835 -64.008 90)
		(property "Reference" "R8095"
			(at 0 0 90)
			(layer "F.SilkS")
			(hide yes)
			(effects
				(font
					(size 1.27 1.27)
				)
			)
		)
		(property "Value" ""
			(at 0 0 90)
			(layer "F.Fab")
			(effects
				(font
					(size 1.27 1.27)
				)
			)
		)
		(duplicate_pad_numbers_are_jumpers no)
		(fp_line
			(start 0.7874 -0.4064)
			(end 0.7874 0.4064)
			(stroke
				(width 0.1524)
				(type default)
			)
			(layer "F.SilkS")
		)
		(fp_line
			(start -0.7874 -0.4064)
			(end 0.7874 -0.4064)
			(stroke
				(width 0.1524)
				(type default)
			)
			(layer "F.SilkS")
		)
		(fp_line
			(start 0.7874 0.4064)
			(end -0.7874 0.4064)
			(stroke
				(width 0.1524)
				(type default)
			)
			(layer "F.SilkS")
		)
		(fp_line
			(start -0.7874 0.4064)
			(end -0.7874 -0.4064)
			(stroke
				(width 0.1524)
				(type default)
			)
			(layer "F.SilkS")
		)
		(fp_line
			(start -0.12065 -0.305054)
			(end -0.12065 -0.2794)
			(stroke
				(width 0.1)
				(type default)
			)
			(layer "F.Fab")
		)
		(fp_line
			(start -0.67945 -0.305054)
			(end -0.12065 -0.305054)
			(stroke
				(width 0.1)
				(type default)
			)
			(layer "F.Fab")
		)
		(fp_line
			(start 0.67945 -0.3048)
			(end 0.67945 0.3048)
			(stroke
				(width 0.1)
				(type default)
			)
			(layer "F.Fab")
		)
		(fp_line
			(start 0.12065 -0.3048)
			(end 0.67945 -0.3048)
			(stroke
				(width 0.1)
				(type default)
			)
			(layer "F.Fab")
		)
		(fp_line
			(start 0.12065 -0.2794)
			(end 0.12065 -0.3048)
			(stroke
				(width 0.1)
				(type default)
			)
			(layer "F.Fab")
		)
		(fp_line
			(start -0.12065 -0.2794)
			(end 0.12065 -0.2794)
			(stroke
				(width 0.1)
				(type default)
			)
			(layer "F.Fab")
		)
		(fp_line
			(start 0.120396 0.2794)
			(end -0.12065 0.2794)
			(stroke
				(width 0.1)
				(type default)
			)
			(layer "F.Fab")
		)
		(fp_line
			(start -0.12065 0.2794)
			(end -0.12065 0.3048)
			(stroke
				(width 0.1)
				(type default)
			)
			(layer "F.Fab")
		)
		(fp_line
			(start 0.67945 0.3048)
			(end 0.120396 0.3048)
			(stroke
				(width 0.1)
				(type default)
			)
			(layer "F.Fab")
		)
		(fp_line
			(start 0.120396 0.3048)
			(end 0.120396 0.2794)
			(stroke
				(width 0.1)
				(type default)
			)
			(layer "F.Fab")
		)
		(fp_line
			(start -0.12065 0.3048)
			(end -0.67945 0.3048)
			(stroke
				(width 0.1)
				(type default)
			)
			(layer "F.Fab")
		)
		(fp_line
			(start -0.67945 0.3048)
			(end -0.67945 -0.305054)
			(stroke
				(width 0.1)
				(type default)
			)
			(layer "F.Fab")
		)
		(pad "1" smd circle
			(at -0.40005 0 90)
			(size 0 0)
			(layers "F.Cu" "F.Mask" "F.Paste")
			(net "P3V3_OCP_V3_2_R")
		)
		(pad "2" smd circle
			(at 0.40005 0 90)
			(size 0 0)
			(layers "F.Cu" "F.Mask" "F.Paste")
			(net "OCP_V3_2_P3V3_R1_PWRGD")
		)
	)
	(footprint ""
		(layer "F.Cu")
		(at 58.67273 -17.623536 90)
		(property "Reference" "C709"
			(at 0 0 90)
			(layer "F.SilkS")
			(hide yes)
			(effects
				(font
					(size 1.27 1.27)
				)
			)
		)
		(property "Value" ""
			(at 0 0 90)
			(layer "F.Fab")
			(effects
				(font
					(size 1.27 1.27)
				)
			)
		)
		(duplicate_pad_numbers_are_jumpers no)
		(fp_line
			(start 0.299974 -0.150114)
			(end 0.299974 0.150114)
			(stroke
				(width 0.1)
				(type default)
			)
			(layer "F.Fab")
		)
		(fp_line
			(start -0.299974 -0.150114)
			(end 0.299974 -0.150114)
			(stroke
				(width 0.1)
				(type default)
			)
			(layer "F.Fab")
		)
		(fp_line
			(start 0.299974 0.150114)
			(end -0.299974 0.150114)
			(stroke
				(width 0.1)
				(type default)
			)
			(layer "F.Fab")
		)
		(fp_line
			(start -0.299974 0.150114)
			(end -0.299974 -0.150114)
			(stroke
				(width 0.1)
				(type default)
			)
			(layer "F.Fab")
		)
		(pad "1" smd rect
			(at -0.2667 0 90)
			(size 0.3048 0.381)
			(layers "F.Cu" "F.Mask" "F.Paste")
			(net "P5E_CPU1_G1_TX_C_DP<0>")
		)
		(pad "2" smd rect
			(at 0.2667 0 90)
			(size 0.3048 0.381)
			(layers "F.Cu" "F.Mask" "F.Paste")
			(net "P5E_CPU1_G1_TX_DP<0>")
		)
	)
	(footprint ""
		(layer "F.Cu")
		(at 111.581946 -54.882034 90)
		(property "Reference" "R6309"
			(at 0 0 90)
			(layer "F.SilkS")
			(hide yes)
			(effects
				(font
					(size 1.27 1.27)
				)
			)
		)
		(property "Value" ""
			(at 0 0 90)
			(layer "F.Fab")
			(effects
				(font
					(size 1.27 1.27)
				)
			)
		)
		(duplicate_pad_numbers_are_jumpers no)
		(fp_line
			(start 0.7874 -0.4064)
			(end 0.7874 0.4064)
			(stroke
				(width 0.1524)
				(type default)
			)
			(layer "F.SilkS")
		)
		(fp_line
			(start -0.7874 -0.4064)
			(end 0.7874 -0.4064)
			(stroke
				(width 0.1524)
				(type default)
			)
			(layer "F.SilkS")
		)
		(fp_line
			(start 0.7874 0.4064)
			(end -0.7874 0.4064)
			(stroke
				(width 0.1524)
				(type default)
			)
			(layer "F.SilkS")
		)
		(fp_line
			(start -0.7874 0.4064)
			(end -0.7874 -0.4064)
			(stroke
				(width 0.1524)
				(type default)
			)
			(layer "F.SilkS")
		)
		(fp_line
			(start -0.12065 -0.305054)
			(end -0.12065 -0.2794)
			(stroke
				(width 0.1)
				(type default)
			)
			(layer "F.Fab")
		)
		(fp_line
			(start -0.67945 -0.305054)
			(end -0.12065 -0.305054)
			(stroke
				(width 0.1)
				(type default)
			)
			(layer "F.Fab")
		)
		(fp_line
			(start 0.67945 -0.3048)
			(end 0.67945 0.3048)
			(stroke
				(width 0.1)
				(type default)
			)
			(layer "F.Fab")
		)
		(fp_line
			(start 0.12065 -0.3048)
			(end 0.67945 -0.3048)
			(stroke
				(width 0.1)
				(type default)
			)
			(layer "F.Fab")
		)
		(fp_line
			(start 0.12065 -0.2794)
			(end 0.12065 -0.3048)
			(stroke
				(width 0.1)
				(type default)
			)
			(layer "F.Fab")
		)
		(fp_line
			(start -0.12065 -0.2794)
			(end 0.12065 -0.2794)
			(stroke
				(width 0.1)
				(type default)
			)
			(layer "F.Fab")
		)
		(fp_line
			(start 0.120396 0.2794)
			(end -0.12065 0.2794)
			(stroke
				(width 0.1)
				(type default)
			)
			(layer "F.Fab")
		)
		(fp_line
			(start -0.12065 0.2794)
			(end -0.12065 0.3048)
			(stroke
				(width 0.1)
				(type default)
			)
			(layer "F.Fab")
		)
		(fp_line
			(start 0.67945 0.3048)
			(end 0.120396 0.3048)
			(stroke
				(width 0.1)
				(type default)
			)
			(layer "F.Fab")
		)
		(fp_line
			(start 0.120396 0.3048)
			(end 0.120396 0.2794)
			(stroke
				(width 0.1)
				(type default)
			)
			(layer "F.Fab")
		)
		(fp_line
			(start -0.12065 0.3048)
			(end -0.67945 0.3048)
			(stroke
				(width 0.1)
				(type default)
			)
			(layer "F.Fab")
		)
		(fp_line
			(start -0.67945 0.3048)
			(end -0.67945 -0.305054)
			(stroke
				(width 0.1)
				(type default)
			)
			(layer "F.Fab")
		)
		(pad "1" smd circle
			(at -0.40005 0 90)
			(size 0 0)
			(layers "F.Cu" "F.Mask" "F.Paste")
			(net "USB_HUB2_MRP_CFG_NON_REM")
		)
		(pad "2" smd circle
			(at 0.40005 0 90)
			(size 0 0)
			(layers "F.Cu" "F.Mask" "F.Paste")
			(net "GND")
		)
	)
	(footprint ""
		(layer "F.Cu")
		(at 456.132184 -62.074298 90)
		(property "Reference" "PL8066"
			(at -4.96824 -7.257288 90)
			(unlocked yes)
			(layer "F.SilkS")
			(effects
				(font
					(size 0.7874 0.5842)
					(thickness 0.1524)
				)
				(justify left)
			)
		)
		(property "Value" ""
			(at 0 0 90)
			(layer "F.Fab")
			(effects
				(font
					(size 1.27 1.27)
				)
			)
		)
		(duplicate_pad_numbers_are_jumpers no)
		(fp_line
			(start 7.1501 -6.450076)
			(end -7.1501 -6.450076)
			(stroke
				(width 0.1524)
				(type default)
			)
			(layer "F.SilkS")
		)
		(fp_line
			(start -7.1501 -6.450076)
			(end -7.1501 -2.6416)
			(stroke
				(width 0.1524)
				(type default)
			)
			(layer "F.SilkS")
		)
		(fp_line
			(start 7.1501 -2.6416)
			(end 7.1501 -6.450076)
			(stroke
				(width 0.1524)
				(type default)
			)
			(layer "F.SilkS")
		)
		(fp_line
			(start 7.1501 2.6416)
			(end 7.1501 6.450076)
			(stroke
				(width 0.1524)
				(type default)
			)
			(layer "F.SilkS")
		)
		(fp_line
			(start 7.1501 6.450076)
			(end -7.1501 6.450076)
			(stroke
				(width 0.1524)
				(type default)
			)
			(layer "F.SilkS")
		)
		(fp_line
			(start -7.1501 6.450076)
			(end -7.1501 2.6416)
			(stroke
				(width 0.1524)
				(type default)
			)
			(layer "F.SilkS")
		)
		(fp_line
			(start 7.1501 -6.450076)
			(end -7.1501 -6.450076)
			(stroke
				(width 0.1)
				(type default)
			)
			(layer "F.Fab")
		)
		(fp_line
			(start -7.1501 -6.450076)
			(end -7.1501 6.450076)
			(stroke
				(width 0.1)
				(type default)
			)
			(layer "F.Fab")
		)
		(fp_line
			(start 7.1501 6.450076)
			(end 7.1501 -6.450076)
			(stroke
				(width 0.1)
				(type default)
			)
			(layer "F.Fab")
		)
		(fp_line
			(start -7.1501 6.450076)
			(end 7.1501 6.450076)
			(stroke
				(width 0.1)
				(type default)
			)
			(layer "F.Fab")
		)
		(pad "1" smd rect
			(at -5.625084 0 90)
			(size 3.2512 5.0038)
			(layers "F.Cu" "F.Mask" "F.Paste")
			(net "SW_P3V3_AUX_SW")
		)
		(pad "2" smd rect
			(at 5.625084 0 90)
			(size 3.2512 5.0038)
			(layers "F.Cu" "F.Mask" "F.Paste")
			(net "P3V3_AUX")
		)
	)
	(footprint ""
		(layer "F.Cu")
		(at 154.530044 -375.49963 -90)
		(property "Reference" "C759"
			(at 0 0 270)
			(layer "F.SilkS")
			(hide yes)
			(effects
				(font
					(size 1.27 1.27)
				)
			)
		)
		(property "Value" ""
			(at 0 0 270)
			(layer "F.Fab")
			(effects
				(font
					(size 1.27 1.27)
				)
			)
		)
		(duplicate_pad_numbers_are_jumpers no)
		(fp_line
			(start -0.299974 0.150114)
			(end -0.299974 -0.150114)
			(stroke
				(width 0.1)
				(type default)
			)
			(layer "F.Fab")
		)
		(fp_line
			(start 0.299974 0.150114)
			(end -0.299974 0.150114)
			(stroke
				(width 0.1)
				(type default)
			)
			(layer "F.Fab")
		)
		(fp_line
			(start -0.299974 -0.150114)
			(end 0.299974 -0.150114)
			(stroke
				(width 0.1)
				(type default)
			)
			(layer "F.Fab")
		)
		(fp_line
			(start 0.299974 -0.150114)
			(end 0.299974 0.150114)
			(stroke
				(width 0.1)
				(type default)
			)
			(layer "F.Fab")
		)
		(pad "1" smd rect
			(at -0.2667 0 270)
			(size 0.3048 0.381)
			(layers "F.Cu" "F.Mask" "F.Paste")
			(net "P5E_CPU1_P2_TX_C_DP<7>")
		)
		(pad "2" smd rect
			(at 0.2667 0 270)
			(size 0.3048 0.381)
			(layers "F.Cu" "F.Mask" "F.Paste")
			(net "P5E_CPU1_P2_TX_DP<7>")
		)
	)
	(footprint ""
		(layer "F.Cu")
		(at 29.214064 -75.234038 -90)
		(property "Reference" "R6181"
			(at 0 0 270)
			(layer "F.SilkS")
			(hide yes)
			(effects
				(font
					(size 1.27 1.27)
				)
			)
		)
		(property "Value" ""
			(at 0 0 270)
			(layer "F.Fab")
			(effects
				(font
					(size 1.27 1.27)
				)
			)
		)
		(duplicate_pad_numbers_are_jumpers no)
		(fp_line
			(start -0.7874 0.4064)
			(end -0.7874 -0.4064)
			(stroke
				(width 0.1524)
				(type default)
			)
			(layer "F.SilkS")
		)
		(fp_line
			(start 0.7874 0.4064)
			(end -0.7874 0.4064)
			(stroke
				(width 0.1524)
				(type default)
			)
			(layer "F.SilkS")
		)
		(fp_line
			(start -0.7874 -0.4064)
			(end 0.7874 -0.4064)
			(stroke
				(width 0.1524)
				(type default)
			)
			(layer "F.SilkS")
		)
		(fp_line
			(start 0.7874 -0.4064)
			(end 0.7874 0.4064)
			(stroke
				(width 0.1524)
				(type default)
			)
			(layer "F.SilkS")
		)
		(fp_line
			(start -0.67945 0.3048)
			(end -0.67945 -0.305054)
			(stroke
				(width 0.1)
				(type default)
			)
			(layer "F.Fab")
		)
		(fp_line
			(start -0.12065 0.3048)
			(end -0.67945 0.3048)
			(stroke
				(width 0.1)
				(type default)
			)
			(layer "F.Fab")
		)
		(fp_line
			(start 0.120396 0.3048)
			(end 0.120396 0.2794)
			(stroke
				(width 0.1)
				(type default)
			)
			(layer "F.Fab")
		)
		(fp_line
			(start 0.67945 0.3048)
			(end 0.120396 0.3048)
			(stroke
				(width 0.1)
				(type default)
			)
			(layer "F.Fab")
		)
		(fp_line
			(start -0.12065 0.2794)
			(end -0.12065 0.3048)
			(stroke
				(width 0.1)
				(type default)
			)
			(layer "F.Fab")
		)
		(fp_line
			(start 0.120396 0.2794)
			(end -0.12065 0.2794)
			(stroke
				(width 0.1)
				(type default)
			)
			(layer "F.Fab")
		)
		(fp_line
			(start -0.12065 -0.2794)
			(end 0.12065 -0.2794)
			(stroke
				(width 0.1)
				(type default)
			)
			(layer "F.Fab")
		)
		(fp_line
			(start 0.12065 -0.2794)
			(end 0.12065 -0.3048)
			(stroke
				(width 0.1)
				(type default)
			)
			(layer "F.Fab")
		)
		(fp_line
			(start 0.12065 -0.3048)
			(end 0.67945 -0.3048)
			(stroke
				(width 0.1)
				(type default)
			)
			(layer "F.Fab")
		)
		(fp_line
			(start 0.67945 -0.3048)
			(end 0.67945 0.3048)
			(stroke
				(width 0.1)
				(type default)
			)
			(layer "F.Fab")
		)
		(fp_line
			(start -0.67945 -0.305054)
			(end -0.12065 -0.305054)
			(stroke
				(width 0.1)
				(type default)
			)
			(layer "F.Fab")
		)
		(fp_line
			(start -0.12065 -0.305054)
			(end -0.12065 -0.2794)
			(stroke
				(width 0.1)
				(type default)
			)
			(layer "F.Fab")
		)
		(pad "1" smd circle
			(at -0.40005 0 270)
			(size 0 0)
			(layers "F.Cu" "F.Mask" "F.Paste")
			(net "P3V3_AUX")
		)
		(pad "2" smd circle
			(at 0.40005 0 270)
			(size 0 0)
			(layers "F.Cu" "F.Mask" "F.Paste")
			(net "PU_U212_EN_N")
		)
	)
	(footprint ""
		(layer "F.Cu")
		(at 414.331912 -363.790992 180)
		(property "Reference" "C197"
			(at 0 0 180)
			(layer "F.SilkS")
			(hide yes)
			(effects
				(font
					(size 1.27 1.27)
				)
			)
		)
		(property "Value" ""
			(at 0 0 180)
			(layer "F.Fab")
			(effects
				(font
					(size 1.27 1.27)
				)
			)
		)
		(duplicate_pad_numbers_are_jumpers no)
		(fp_line
			(start 0.7874 0.4064)
			(end -0.7874 0.4064)
			(stroke
				(width 0.1524)
				(type default)
			)
			(layer "F.SilkS")
		)
		(fp_line
			(start 0.7874 -0.4064)
			(end 0.7874 0.4064)
			(stroke
				(width 0.1524)
				(type default)
			)
			(layer "F.SilkS")
		)
		(fp_line
			(start -0.7874 0.4064)
			(end -0.7874 -0.4064)
			(stroke
				(width 0.1524)
				(type default)
			)
			(layer "F.SilkS")
		)
		(fp_line
			(start -0.7874 -0.4064)
			(end 0.7874 -0.4064)
			(stroke
				(width 0.1524)
				(type default)
			)
			(layer "F.SilkS")
		)
		(fp_line
			(start 0.67945 0.3048)
			(end 0.120396 0.3048)
			(stroke
				(width 0.1)
				(type default)
			)
			(layer "F.Fab")
		)
		(fp_line
			(start 0.67945 -0.3048)
			(end 0.67945 0.3048)
			(stroke
				(width 0.1)
				(type default)
			)
			(layer "F.Fab")
		)
		(fp_line
			(start 0.12065 -0.2794)
			(end 0.12065 -0.3048)
			(stroke
				(width 0.1)
				(type default)
			)
			(layer "F.Fab")
		)
		(fp_line
			(start 0.12065 -0.3048)
			(end 0.67945 -0.3048)
			(stroke
				(width 0.1)
				(type default)
			)
			(layer "F.Fab")
		)
		(fp_line
			(start 0.120396 0.3048)
			(end 0.120396 0.2794)
			(stroke
				(width 0.1)
				(type default)
			)
			(layer "F.Fab")
		)
		(fp_line
			(start 0.120396 0.2794)
			(end -0.12065 0.2794)
			(stroke
				(width 0.1)
				(type default)
			)
			(layer "F.Fab")
		)
		(fp_line
			(start -0.12065 0.3048)
			(end -0.67945 0.3048)
			(stroke
				(width 0.1)
				(type default)
			)
			(layer "F.Fab")
		)
		(fp_line
			(start -0.12065 0.2794)
			(end -0.12065 0.3048)
			(stroke
				(width 0.1)
				(type default)
			)
			(layer "F.Fab")
		)
		(fp_line
			(start -0.12065 -0.2794)
			(end 0.12065 -0.2794)
			(stroke
				(width 0.1)
				(type default)
			)
			(layer "F.Fab")
		)
		(fp_line
			(start -0.12065 -0.305054)
			(end -0.12065 -0.2794)
			(stroke
				(width 0.1)
				(type default)
			)
			(layer "F.Fab")
		)
		(fp_line
			(start -0.67945 0.3048)
			(end -0.67945 -0.305054)
			(stroke
				(width 0.1)
				(type default)
			)
			(layer "F.Fab")
		)
		(fp_line
			(start -0.67945 -0.305054)
			(end -0.12065 -0.305054)
			(stroke
				(width 0.1)
				(type default)
			)
			(layer "F.Fab")
		)
		(pad "1" smd circle
			(at -0.40005 0 180)
			(size 0 0)
			(layers "F.Cu" "F.Mask" "F.Paste")
			(net "PVDD11_S3_P0_EN_R")
		)
		(pad "2" smd circle
			(at 0.40005 0 180)
			(size 0 0)
			(layers "F.Cu" "F.Mask" "F.Paste")
			(net "GND")
		)
	)
	(footprint ""
		(layer "F.Cu")
		(at 217.066114 -126.710694)
		(property "Reference" "R6781"
			(at 0 0 0)
			(layer "F.SilkS")
			(hide yes)
			(effects
				(font
					(size 1.27 1.27)
				)
			)
		)
		(property "Value" ""
			(at 0 0 0)
			(layer "F.Fab")
			(effects
				(font
					(size 1.27 1.27)
				)
			)
		)
		(duplicate_pad_numbers_are_jumpers no)
		(fp_line
			(start -0.7874 -0.4064)
			(end 0.7874 -0.4064)
			(stroke
				(width 0.1524)
				(type default)
			)
			(layer "F.SilkS")
		)
		(fp_line
			(start -0.7874 0.4064)
			(end -0.7874 -0.4064)
			(stroke
				(width 0.1524)
				(type default)
			)
			(layer "F.SilkS")
		)
		(fp_line
			(start 0.7874 -0.4064)
			(end 0.7874 0.4064)
			(stroke
				(width 0.1524)
				(type default)
			)
			(layer "F.SilkS")
		)
		(fp_line
			(start 0.7874 0.4064)
			(end -0.7874 0.4064)
			(stroke
				(width 0.1524)
				(type default)
			)
			(layer "F.SilkS")
		)
		(fp_line
			(start -0.67945 -0.305054)
			(end -0.12065 -0.305054)
			(stroke
				(width 0.1)
				(type default)
			)
			(layer "F.Fab")
		)
		(fp_line
			(start -0.67945 0.3048)
			(end -0.67945 -0.305054)
			(stroke
				(width 0.1)
				(type default)
			)
			(layer "F.Fab")
		)
		(fp_line
			(start -0.12065 -0.305054)
			(end -0.12065 -0.2794)
			(stroke
				(width 0.1)
				(type default)
			)
			(layer "F.Fab")
		)
		(fp_line
			(start -0.12065 -0.2794)
			(end 0.12065 -0.2794)
			(stroke
				(width 0.1)
				(type default)
			)
			(layer "F.Fab")
		)
		(fp_line
			(start -0.12065 0.2794)
			(end -0.12065 0.3048)
			(stroke
				(width 0.1)
				(type default)
			)
			(layer "F.Fab")
		)
		(fp_line
			(start -0.12065 0.3048)
			(end -0.67945 0.3048)
			(stroke
				(width 0.1)
				(type default)
			)
			(layer "F.Fab")
		)
		(fp_line
			(start 0.120396 0.2794)
			(end -0.12065 0.2794)
			(stroke
				(width 0.1)
				(type default)
			)
			(layer "F.Fab")
		)
		(fp_line
			(start 0.120396 0.3048)
			(end 0.120396 0.2794)
			(stroke
				(width 0.1)
				(type default)
			)
			(layer "F.Fab")
		)
		(fp_line
			(start 0.12065 -0.3048)
			(end 0.67945 -0.3048)
			(stroke
				(width 0.1)
				(type default)
			)
			(layer "F.Fab")
		)
		(fp_line
			(start 0.12065 -0.2794)
			(end 0.12065 -0.3048)
			(stroke
				(width 0.1)
				(type default)
			)
			(layer "F.Fab")
		)
		(fp_line
			(start 0.67945 -0.3048)
			(end 0.67945 0.3048)
			(stroke
				(width 0.1)
				(type default)
			)
			(layer "F.Fab")
		)
		(fp_line
			(start 0.67945 0.3048)
			(end 0.120396 0.3048)
			(stroke
				(width 0.1)
				(type default)
			)
			(layer "F.Fab")
		)
		(pad "1" smd circle
			(at -0.40005 0)
			(size 0 0)
			(layers "F.Cu" "F.Mask" "F.Paste")
			(net "RST_SMB_RT_ROM_R2_N")
		)
		(pad "2" smd circle
			(at 0.40005 0)
			(size 0 0)
			(layers "F.Cu" "F.Mask" "F.Paste")
			(net "RST_SMB_RT_ROM_R1_N")
		)
	)
	(footprint ""
		(layer "F.Cu")
		(at 398.893538 -392.1252)
		(property "Reference" "R1078"
			(at 0 0 0)
			(layer "F.SilkS")
			(hide yes)
			(effects
				(font
					(size 1.27 1.27)
				)
			)
		)
		(property "Value" ""
			(at 0 0 0)
			(layer "F.Fab")
			(effects
				(font
					(size 1.27 1.27)
				)
			)
		)
		(duplicate_pad_numbers_are_jumpers no)
		(fp_line
			(start -0.32512 -0.175006)
			(end 0.32512 -0.175006)
			(stroke
				(width 0.1)
				(type default)
			)
			(layer "F.Fab")
		)
		(fp_line
			(start -0.32512 0.175006)
			(end -0.32512 -0.175006)
			(stroke
				(width 0.1)
				(type default)
			)
			(layer "F.Fab")
		)
		(fp_line
			(start 0.32512 -0.175006)
			(end 0.32512 0.175006)
			(stroke
				(width 0.1)
				(type default)
			)
			(layer "F.Fab")
		)
		(fp_line
			(start 0.32512 0.175006)
			(end -0.32512 0.175006)
			(stroke
				(width 0.1)
				(type default)
			)
			(layer "F.Fab")
		)
		(pad "1" smd rect
			(at -0.2667 0)
			(size 0.3048 0.381)
			(layers "F.Cu" "F.Mask" "F.Paste")
			(net "TEST2_RT_CPU0_P2")
		)
		(pad "2" smd rect
			(at 0.2667 0 180)
			(size 0.3048 0.381)
			(layers "F.Cu" "F.Mask" "F.Paste")
			(net "GND")
		)
	)
	(footprint ""
		(layer "F.Cu")
		(at 448.32778 -65.792858 -90)
		(property "Reference" "C1333"
			(at 0 0 270)
			(layer "F.SilkS")
			(hide yes)
			(effects
				(font
					(size 1.27 1.27)
				)
			)
		)
		(property "Value" ""
			(at 0 0 270)
			(layer "F.Fab")
			(effects
				(font
					(size 1.27 1.27)
				)
			)
		)
		(duplicate_pad_numbers_are_jumpers no)
		(fp_line
			(start -1.524 0.762)
			(end -1.524 -0.762)
			(stroke
				(width 0.1524)
				(type default)
			)
			(layer "F.SilkS")
		)
		(fp_line
			(start 1.524 0.762)
			(end -1.524 0.762)
			(stroke
				(width 0.1524)
				(type default)
			)
			(layer "F.SilkS")
		)
		(fp_line
			(start -1.524 -0.762)
			(end 1.524 -0.762)
			(stroke
				(width 0.1524)
				(type default)
			)
			(layer "F.SilkS")
		)
		(fp_line
			(start 1.524 -0.762)
			(end 1.524 0.762)
			(stroke
				(width 0.1524)
				(type default)
			)
			(layer "F.SilkS")
		)
		(fp_line
			(start -1.1049 0.724916)
			(end 1.1049 0.724916)
			(stroke
				(width 0.1)
				(type default)
			)
			(layer "F.Fab")
		)
		(fp_line
			(start 1.1049 0.724916)
			(end 1.1049 -0.724916)
			(stroke
				(width 0.1)
				(type default)
			)
			(layer "F.Fab")
		)
		(fp_line
			(start -1.1049 -0.724916)
			(end -1.1049 0.724916)
			(stroke
				(width 0.1)
				(type default)
			)
			(layer "F.Fab")
		)
		(fp_line
			(start 1.1049 -0.724916)
			(end -1.1049 -0.724916)
			(stroke
				(width 0.1)
				(type default)
			)
			(layer "F.Fab")
		)
		(pad "1" smd rect
			(at -0.889 0 90)
			(size 1.016 1.27)
			(layers "F.Cu" "F.Mask" "F.Paste")
			(net "P3V3_AUX")
		)
		(pad "2" smd rect
			(at 0.889 0 90)
			(size 1.016 1.27)
			(layers "F.Cu" "F.Mask" "F.Paste")
			(net "GND")
		)
	)
	(footprint ""
		(layer "F.Cu")
		(at 322.837048 -46.986698 180)
		(property "Reference" "R3680"
			(at 0 0 180)
			(layer "F.SilkS")
			(hide yes)
			(effects
				(font
					(size 1.27 1.27)
				)
			)
		)
		(property "Value" ""
			(at 0 0 180)
			(layer "F.Fab")
			(effects
				(font
					(size 1.27 1.27)
				)
			)
		)
		(duplicate_pad_numbers_are_jumpers no)
		(fp_line
			(start 0.7874 0.4064)
			(end -0.7874 0.4064)
			(stroke
				(width 0.1524)
				(type default)
			)
			(layer "F.SilkS")
		)
		(fp_line
			(start 0.7874 -0.4064)
			(end 0.7874 0.4064)
			(stroke
				(width 0.1524)
				(type default)
			)
			(layer "F.SilkS")
		)
		(fp_line
			(start -0.7874 0.4064)
			(end -0.7874 -0.4064)
			(stroke
				(width 0.1524)
				(type default)
			)
			(layer "F.SilkS")
		)
		(fp_line
			(start -0.7874 -0.4064)
			(end 0.7874 -0.4064)
			(stroke
				(width 0.1524)
				(type default)
			)
			(layer "F.SilkS")
		)
		(fp_line
			(start 0.67945 0.3048)
			(end 0.120396 0.3048)
			(stroke
				(width 0.1)
				(type default)
			)
			(layer "F.Fab")
		)
		(fp_line
			(start 0.67945 -0.3048)
			(end 0.67945 0.3048)
			(stroke
				(width 0.1)
				(type default)
			)
			(layer "F.Fab")
		)
		(fp_line
			(start 0.12065 -0.2794)
			(end 0.12065 -0.3048)
			(stroke
				(width 0.1)
				(type default)
			)
			(layer "F.Fab")
		)
		(fp_line
			(start 0.12065 -0.3048)
			(end 0.67945 -0.3048)
			(stroke
				(width 0.1)
				(type default)
			)
			(layer "F.Fab")
		)
		(fp_line
			(start 0.120396 0.3048)
			(end 0.120396 0.2794)
			(stroke
				(width 0.1)
				(type default)
			)
			(layer "F.Fab")
		)
		(fp_line
			(start 0.120396 0.2794)
			(end -0.12065 0.2794)
			(stroke
				(width 0.1)
				(type default)
			)
			(layer "F.Fab")
		)
		(fp_line
			(start -0.12065 0.3048)
			(end -0.67945 0.3048)
			(stroke
				(width 0.1)
				(type default)
			)
			(layer "F.Fab")
		)
		(fp_line
			(start -0.12065 0.2794)
			(end -0.12065 0.3048)
			(stroke
				(width 0.1)
				(type default)
			)
			(layer "F.Fab")
		)
		(fp_line
			(start -0.12065 -0.2794)
			(end 0.12065 -0.2794)
			(stroke
				(width 0.1)
				(type default)
			)
			(layer "F.Fab")
		)
		(fp_line
			(start -0.12065 -0.305054)
			(end -0.12065 -0.2794)
			(stroke
				(width 0.1)
				(type default)
			)
			(layer "F.Fab")
		)
		(fp_line
			(start -0.67945 0.3048)
			(end -0.67945 -0.305054)
			(stroke
				(width 0.1)
				(type default)
			)
			(layer "F.Fab")
		)
		(fp_line
			(start -0.67945 -0.305054)
			(end -0.12065 -0.305054)
			(stroke
				(width 0.1)
				(type default)
			)
			(layer "F.Fab")
		)
		(pad "1" smd rect
			(at -0.40005 0)
			(size 0.4572 0.508)
			(layers "F.Cu" "F.Mask" "F.Paste")
			(net "P12V_AUX_ADC")
		)
		(pad "2" smd rect
			(at 0.40005 0)
			(size 0.4572 0.508)
			(layers "F.Cu" "F.Mask" "F.Paste")
			(net "P12V_AUX_ADC_TIC")
		)
	)
	(footprint ""
		(layer "F.Cu")
		(at 443.308486 -21.676106 180)
		(property "Reference" "R1284"
			(at 0 0 180)
			(layer "F.SilkS")
			(hide yes)
			(effects
				(font
					(size 1.27 1.27)
				)
			)
		)
		(property "Value" ""
			(at 0 0 180)
			(layer "F.Fab")
			(effects
				(font
					(size 1.27 1.27)
				)
			)
		)
		(duplicate_pad_numbers_are_jumpers no)
		(fp_line
			(start 0.7874 0.4064)
			(end -0.7874 0.4064)
			(stroke
				(width 0.1524)
				(type default)
			)
			(layer "F.SilkS")
		)
		(fp_line
			(start 0.7874 -0.4064)
			(end 0.7874 0.4064)
			(stroke
				(width 0.1524)
				(type default)
			)
			(layer "F.SilkS")
		)
		(fp_line
			(start -0.7874 0.4064)
			(end -0.7874 -0.4064)
			(stroke
				(width 0.1524)
				(type default)
			)
			(layer "F.SilkS")
		)
		(fp_line
			(start -0.7874 -0.4064)
			(end 0.7874 -0.4064)
			(stroke
				(width 0.1524)
				(type default)
			)
			(layer "F.SilkS")
		)
		(fp_line
			(start 0.67945 0.3048)
			(end 0.120396 0.3048)
			(stroke
				(width 0.1)
				(type default)
			)
			(layer "F.Fab")
		)
		(fp_line
			(start 0.67945 -0.3048)
			(end 0.67945 0.3048)
			(stroke
				(width 0.1)
				(type default)
			)
			(layer "F.Fab")
		)
		(fp_line
			(start 0.12065 -0.2794)
			(end 0.12065 -0.3048)
			(stroke
				(width 0.1)
				(type default)
			)
			(layer "F.Fab")
		)
		(fp_line
			(start 0.12065 -0.3048)
			(end 0.67945 -0.3048)
			(stroke
				(width 0.1)
				(type default)
			)
			(layer "F.Fab")
		)
		(fp_line
			(start 0.120396 0.3048)
			(end 0.120396 0.2794)
			(stroke
				(width 0.1)
				(type default)
			)
			(layer "F.Fab")
		)
		(fp_line
			(start 0.120396 0.2794)
			(end -0.12065 0.2794)
			(stroke
				(width 0.1)
				(type default)
			)
			(layer "F.Fab")
		)
		(fp_line
			(start -0.12065 0.3048)
			(end -0.67945 0.3048)
			(stroke
				(width 0.1)
				(type default)
			)
			(layer "F.Fab")
		)
		(fp_line
			(start -0.12065 0.2794)
			(end -0.12065 0.3048)
			(stroke
				(width 0.1)
				(type default)
			)
			(layer "F.Fab")
		)
		(fp_line
			(start -0.12065 -0.2794)
			(end 0.12065 -0.2794)
			(stroke
				(width 0.1)
				(type default)
			)
			(layer "F.Fab")
		)
		(fp_line
			(start -0.12065 -0.305054)
			(end -0.12065 -0.2794)
			(stroke
				(width 0.1)
				(type default)
			)
			(layer "F.Fab")
		)
		(fp_line
			(start -0.67945 0.3048)
			(end -0.67945 -0.305054)
			(stroke
				(width 0.1)
				(type default)
			)
			(layer "F.Fab")
		)
		(fp_line
			(start -0.67945 -0.305054)
			(end -0.12065 -0.305054)
			(stroke
				(width 0.1)
				(type default)
			)
			(layer "F.Fab")
		)
		(pad "1" smd circle
			(at -0.40005 0 180)
			(size 0 0)
			(layers "F.Cu" "F.Mask" "F.Paste")
			(net "P12V_OCP_SFF")
		)
		(pad "2" smd circle
			(at 0.40005 0 180)
			(size 0 0)
			(layers "F.Cu" "F.Mask" "F.Paste")
			(net "VSENSE_P12V_INA230_6_INP")
		)
	)
	(footprint ""
		(layer "F.Cu")
		(at 13.335 -77.089)
		(property "Reference" "C8004"
			(at 0 0 0)
			(layer "F.SilkS")
			(hide yes)
			(effects
				(font
					(size 1.27 1.27)
				)
			)
		)
		(property "Value" ""
			(at 0 0 0)
			(layer "F.Fab")
			(effects
				(font
					(size 1.27 1.27)
				)
			)
		)
		(duplicate_pad_numbers_are_jumpers no)
		(fp_line
			(start -0.7874 -0.4064)
			(end 0.7874 -0.4064)
			(stroke
				(width 0.1524)
				(type default)
			)
			(layer "F.SilkS")
		)
		(fp_line
			(start -0.7874 0.4064)
			(end -0.7874 -0.4064)
			(stroke
				(width 0.1524)
				(type default)
			)
			(layer "F.SilkS")
		)
		(fp_line
			(start 0.7874 -0.4064)
			(end 0.7874 0.4064)
			(stroke
				(width 0.1524)
				(type default)
			)
			(layer "F.SilkS")
		)
		(fp_line
			(start 0.7874 0.4064)
			(end -0.7874 0.4064)
			(stroke
				(width 0.1524)
				(type default)
			)
			(layer "F.SilkS")
		)
		(fp_line
			(start -0.67945 -0.305054)
			(end -0.12065 -0.305054)
			(stroke
				(width 0.1)
				(type default)
			)
			(layer "F.Fab")
		)
		(fp_line
			(start -0.67945 0.3048)
			(end -0.67945 -0.305054)
			(stroke
				(width 0.1)
				(type default)
			)
			(layer "F.Fab")
		)
		(fp_line
			(start -0.12065 -0.305054)
			(end -0.12065 -0.2794)
			(stroke
				(width 0.1)
				(type default)
			)
			(layer "F.Fab")
		)
		(fp_line
			(start -0.12065 -0.2794)
			(end 0.12065 -0.2794)
			(stroke
				(width 0.1)
				(type default)
			)
			(layer "F.Fab")
		)
		(fp_line
			(start -0.12065 0.2794)
			(end -0.12065 0.3048)
			(stroke
				(width 0.1)
				(type default)
			)
			(layer "F.Fab")
		)
		(fp_line
			(start -0.12065 0.3048)
			(end -0.67945 0.3048)
			(stroke
				(width 0.1)
				(type default)
			)
			(layer "F.Fab")
		)
		(fp_line
			(start 0.120396 0.2794)
			(end -0.12065 0.2794)
			(stroke
				(width 0.1)
				(type default)
			)
			(layer "F.Fab")
		)
		(fp_line
			(start 0.120396 0.3048)
			(end 0.120396 0.2794)
			(stroke
				(width 0.1)
				(type default)
			)
			(layer "F.Fab")
		)
		(fp_line
			(start 0.12065 -0.3048)
			(end 0.67945 -0.3048)
			(stroke
				(width 0.1)
				(type default)
			)
			(layer "F.Fab")
		)
		(fp_line
			(start 0.12065 -0.2794)
			(end 0.12065 -0.3048)
			(stroke
				(width 0.1)
				(type default)
			)
			(layer "F.Fab")
		)
		(fp_line
			(start 0.67945 -0.3048)
			(end 0.67945 0.3048)
			(stroke
				(width 0.1)
				(type default)
			)
			(layer "F.Fab")
		)
		(fp_line
			(start 0.67945 0.3048)
			(end 0.120396 0.3048)
			(stroke
				(width 0.1)
				(type default)
			)
			(layer "F.Fab")
		)
		(pad "1" smd circle
			(at -0.40005 0)
			(size 0 0)
			(layers "F.Cu" "F.Mask" "F.Paste")
			(net "OCP_V3_2_PRSNT23_R1_N")
		)
		(pad "2" smd circle
			(at 0.40005 0)
			(size 0 0)
			(layers "F.Cu" "F.Mask" "F.Paste")
			(net "GND")
		)
	)
	(footprint ""
		(layer "F.Cu")
		(at 108.360464 -257.750564)
		(property "Reference" "C2664"
			(at 0 0 0)
			(layer "F.SilkS")
			(hide yes)
			(effects
				(font
					(size 1.27 1.27)
				)
			)
		)
		(property "Value" ""
			(at 0 0 0)
			(layer "F.Fab")
			(effects
				(font
					(size 1.27 1.27)
				)
			)
		)
		(duplicate_pad_numbers_are_jumpers no)
		(fp_line
			(start -0.7874 -0.4064)
			(end 0.7874 -0.4064)
			(stroke
				(width 0.1524)
				(type default)
			)
			(layer "F.SilkS")
		)
		(fp_line
			(start -0.7874 0.4064)
			(end -0.7874 -0.4064)
			(stroke
				(width 0.1524)
				(type default)
			)
			(layer "F.SilkS")
		)
		(fp_line
			(start 0.7874 -0.4064)
			(end 0.7874 0.4064)
			(stroke
				(width 0.1524)
				(type default)
			)
			(layer "F.SilkS")
		)
		(fp_line
			(start 0.7874 0.4064)
			(end -0.7874 0.4064)
			(stroke
				(width 0.1524)
				(type default)
			)
			(layer "F.SilkS")
		)
		(fp_line
			(start -0.67945 -0.305054)
			(end -0.12065 -0.305054)
			(stroke
				(width 0.1)
				(type default)
			)
			(layer "F.Fab")
		)
		(fp_line
			(start -0.67945 0.3048)
			(end -0.67945 -0.305054)
			(stroke
				(width 0.1)
				(type default)
			)
			(layer "F.Fab")
		)
		(fp_line
			(start -0.12065 -0.305054)
			(end -0.12065 -0.2794)
			(stroke
				(width 0.1)
				(type default)
			)
			(layer "F.Fab")
		)
		(fp_line
			(start -0.12065 -0.2794)
			(end 0.12065 -0.2794)
			(stroke
				(width 0.1)
				(type default)
			)
			(layer "F.Fab")
		)
		(fp_line
			(start -0.12065 0.2794)
			(end -0.12065 0.3048)
			(stroke
				(width 0.1)
				(type default)
			)
			(layer "F.Fab")
		)
		(fp_line
			(start -0.12065 0.3048)
			(end -0.67945 0.3048)
			(stroke
				(width 0.1)
				(type default)
			)
			(layer "F.Fab")
		)
		(fp_line
			(start 0.120396 0.2794)
			(end -0.12065 0.2794)
			(stroke
				(width 0.1)
				(type default)
			)
			(layer "F.Fab")
		)
		(fp_line
			(start 0.120396 0.3048)
			(end 0.120396 0.2794)
			(stroke
				(width 0.1)
				(type default)
			)
			(layer "F.Fab")
		)
		(fp_line
			(start 0.12065 -0.3048)
			(end 0.67945 -0.3048)
			(stroke
				(width 0.1)
				(type default)
			)
			(layer "F.Fab")
		)
		(fp_line
			(start 0.12065 -0.2794)
			(end 0.12065 -0.3048)
			(stroke
				(width 0.1)
				(type default)
			)
			(layer "F.Fab")
		)
		(fp_line
			(start 0.67945 -0.3048)
			(end 0.67945 0.3048)
			(stroke
				(width 0.1)
				(type default)
			)
			(layer "F.Fab")
		)
		(fp_line
			(start 0.67945 0.3048)
			(end 0.120396 0.3048)
			(stroke
				(width 0.1)
				(type default)
			)
			(layer "F.Fab")
		)
		(pad "1" smd circle
			(at -0.40005 0)
			(size 0 0)
			(layers "F.Cu" "F.Mask" "F.Paste")
			(net "PVDD18_S5_P1")
		)
		(pad "2" smd circle
			(at 0.40005 0)
			(size 0 0)
			(layers "F.Cu" "F.Mask" "F.Paste")
			(net "GND")
		)
	)
	(footprint ""
		(layer "F.Cu")
		(at 124.618496 -373.03583 -90)
		(property "Reference" "C1530"
			(at 0 0 270)
			(layer "F.SilkS")
			(hide yes)
			(effects
				(font
					(size 1.27 1.27)
				)
			)
		)
		(property "Value" ""
			(at 0 0 270)
			(layer "F.Fab")
			(effects
				(font
					(size 1.27 1.27)
				)
			)
		)
		(duplicate_pad_numbers_are_jumpers no)
		(fp_line
			(start -0.299974 0.150114)
			(end -0.299974 -0.150114)
			(stroke
				(width 0.1)
				(type default)
			)
			(layer "F.Fab")
		)
		(fp_line
			(start 0.299974 0.150114)
			(end -0.299974 0.150114)
			(stroke
				(width 0.1)
				(type default)
			)
			(layer "F.Fab")
		)
		(fp_line
			(start -0.299974 -0.150114)
			(end 0.299974 -0.150114)
			(stroke
				(width 0.1)
				(type default)
			)
			(layer "F.Fab")
		)
		(fp_line
			(start 0.299974 -0.150114)
			(end 0.299974 0.150114)
			(stroke
				(width 0.1)
				(type default)
			)
			(layer "F.Fab")
		)
		(pad "1" smd rect
			(at -0.2667 0 270)
			(size 0.3048 0.381)
			(layers "F.Cu" "F.Mask" "F.Paste")
			(net "P5E_CPU1_P3_TX_C_DN<8>")
		)
		(pad "2" smd rect
			(at 0.2667 0 270)
			(size 0.3048 0.381)
			(layers "F.Cu" "F.Mask" "F.Paste")
			(net "P5E_CPU1_P3_TX_DN<8>")
		)
	)
	(footprint ""
		(layer "F.Cu")
		(at 307.213 -355.854)
		(property "Reference" "PC68"
			(at 0 0 0)
			(layer "F.SilkS")
			(hide yes)
			(effects
				(font
					(size 1.27 1.27)
				)
			)
		)
		(property "Value" ""
			(at 0 0 0)
			(layer "F.Fab")
			(effects
				(font
					(size 1.27 1.27)
				)
			)
		)
		(duplicate_pad_numbers_are_jumpers no)
		(fp_line
			(start -0.7874 -0.4064)
			(end 0.7874 -0.4064)
			(stroke
				(width 0.1524)
				(type default)
			)
			(layer "F.SilkS")
		)
		(fp_line
			(start -0.7874 0.4064)
			(end -0.7874 -0.4064)
			(stroke
				(width 0.1524)
				(type default)
			)
			(layer "F.SilkS")
		)
		(fp_line
			(start 0.7874 -0.4064)
			(end 0.7874 0.4064)
			(stroke
				(width 0.1524)
				(type default)
			)
			(layer "F.SilkS")
		)
		(fp_line
			(start 0.7874 0.4064)
			(end -0.7874 0.4064)
			(stroke
				(width 0.1524)
				(type default)
			)
			(layer "F.SilkS")
		)
		(fp_line
			(start -0.67945 -0.305054)
			(end -0.12065 -0.305054)
			(stroke
				(width 0.1)
				(type default)
			)
			(layer "F.Fab")
		)
		(fp_line
			(start -0.67945 0.3048)
			(end -0.67945 -0.305054)
			(stroke
				(width 0.1)
				(type default)
			)
			(layer "F.Fab")
		)
		(fp_line
			(start -0.12065 -0.305054)
			(end -0.12065 -0.2794)
			(stroke
				(width 0.1)
				(type default)
			)
			(layer "F.Fab")
		)
		(fp_line
			(start -0.12065 -0.2794)
			(end 0.12065 -0.2794)
			(stroke
				(width 0.1)
				(type default)
			)
			(layer "F.Fab")
		)
		(fp_line
			(start -0.12065 0.2794)
			(end -0.12065 0.3048)
			(stroke
				(width 0.1)
				(type default)
			)
			(layer "F.Fab")
		)
		(fp_line
			(start -0.12065 0.3048)
			(end -0.67945 0.3048)
			(stroke
				(width 0.1)
				(type default)
			)
			(layer "F.Fab")
		)
		(fp_line
			(start 0.120396 0.2794)
			(end -0.12065 0.2794)
			(stroke
				(width 0.1)
				(type default)
			)
			(layer "F.Fab")
		)
		(fp_line
			(start 0.120396 0.3048)
			(end 0.120396 0.2794)
			(stroke
				(width 0.1)
				(type default)
			)
			(layer "F.Fab")
		)
		(fp_line
			(start 0.12065 -0.3048)
			(end 0.67945 -0.3048)
			(stroke
				(width 0.1)
				(type default)
			)
			(layer "F.Fab")
		)
		(fp_line
			(start 0.12065 -0.2794)
			(end 0.12065 -0.3048)
			(stroke
				(width 0.1)
				(type default)
			)
			(layer "F.Fab")
		)
		(fp_line
			(start 0.67945 -0.3048)
			(end 0.67945 0.3048)
			(stroke
				(width 0.1)
				(type default)
			)
			(layer "F.Fab")
		)
		(fp_line
			(start 0.67945 0.3048)
			(end 0.120396 0.3048)
			(stroke
				(width 0.1)
				(type default)
			)
			(layer "F.Fab")
		)
		(pad "1" smd circle
			(at -0.40005 0)
			(size 0 0)
			(layers "F.Cu" "F.Mask" "F.Paste")
			(net "VSENSE_PVDDCR_CPU1_P0_VSEN0")
		)
		(pad "2" smd circle
			(at 0.40005 0)
			(size 0 0)
			(layers "F.Cu" "F.Mask" "F.Paste")
			(net "VSENSE_VSS_SENSE_C_P0")
		)
	)
	(footprint ""
		(layer "F.Cu")
		(at 217.58402 -16.381222 -90)
		(property "Reference" "R3181"
			(at 0 0 270)
			(layer "F.SilkS")
			(hide yes)
			(effects
				(font
					(size 1.27 1.27)
				)
			)
		)
		(property "Value" ""
			(at 0 0 270)
			(layer "F.Fab")
			(effects
				(font
					(size 1.27 1.27)
				)
			)
		)
		(duplicate_pad_numbers_are_jumpers no)
		(fp_line
			(start -0.7874 0.4064)
			(end -0.7874 -0.4064)
			(stroke
				(width 0.1524)
				(type default)
			)
			(layer "F.SilkS")
		)
		(fp_line
			(start 0.7874 0.4064)
			(end -0.7874 0.4064)
			(stroke
				(width 0.1524)
				(type default)
			)
			(layer "F.SilkS")
		)
		(fp_line
			(start -0.7874 -0.4064)
			(end 0.7874 -0.4064)
			(stroke
				(width 0.1524)
				(type default)
			)
			(layer "F.SilkS")
		)
		(fp_line
			(start 0.7874 -0.4064)
			(end 0.7874 0.4064)
			(stroke
				(width 0.1524)
				(type default)
			)
			(layer "F.SilkS")
		)
		(fp_line
			(start -0.67945 0.3048)
			(end -0.67945 -0.305054)
			(stroke
				(width 0.1)
				(type default)
			)
			(layer "F.Fab")
		)
		(fp_line
			(start -0.12065 0.3048)
			(end -0.67945 0.3048)
			(stroke
				(width 0.1)
				(type default)
			)
			(layer "F.Fab")
		)
		(fp_line
			(start 0.120396 0.3048)
			(end 0.120396 0.2794)
			(stroke
				(width 0.1)
				(type default)
			)
			(layer "F.Fab")
		)
		(fp_line
			(start 0.67945 0.3048)
			(end 0.120396 0.3048)
			(stroke
				(width 0.1)
				(type default)
			)
			(layer "F.Fab")
		)
		(fp_line
			(start -0.12065 0.2794)
			(end -0.12065 0.3048)
			(stroke
				(width 0.1)
				(type default)
			)
			(layer "F.Fab")
		)
		(fp_line
			(start 0.120396 0.2794)
			(end -0.12065 0.2794)
			(stroke
				(width 0.1)
				(type default)
			)
			(layer "F.Fab")
		)
		(fp_line
			(start -0.12065 -0.2794)
			(end 0.12065 -0.2794)
			(stroke
				(width 0.1)
				(type default)
			)
			(layer "F.Fab")
		)
		(fp_line
			(start 0.12065 -0.2794)
			(end 0.12065 -0.3048)
			(stroke
				(width 0.1)
				(type default)
			)
			(layer "F.Fab")
		)
		(fp_line
			(start 0.12065 -0.3048)
			(end 0.67945 -0.3048)
			(stroke
				(width 0.1)
				(type default)
			)
			(layer "F.Fab")
		)
		(fp_line
			(start 0.67945 -0.3048)
			(end 0.67945 0.3048)
			(stroke
				(width 0.1)
				(type default)
			)
			(layer "F.Fab")
		)
		(fp_line
			(start -0.67945 -0.305054)
			(end -0.12065 -0.305054)
			(stroke
				(width 0.1)
				(type default)
			)
			(layer "F.Fab")
		)
		(fp_line
			(start -0.12065 -0.305054)
			(end -0.12065 -0.2794)
			(stroke
				(width 0.1)
				(type default)
			)
			(layer "F.Fab")
		)
		(pad "1" smd circle
			(at -0.40005 0 270)
			(size 0 0)
			(layers "F.Cu" "F.Mask" "F.Paste")
			(net "CLK_50M_NCSI_OCP_2")
		)
		(pad "2" smd circle
			(at 0.40005 0 270)
			(size 0 0)
			(layers "F.Cu" "F.Mask" "F.Paste")
			(net "CLK_50M_NCSI_OCP_V3_2")
		)
	)
	(footprint ""
		(layer "F.Cu")
		(at 147.877022 -21.506942 90)
		(property "Reference" "R6071"
			(at 0 0 90)
			(layer "F.SilkS")
			(hide yes)
			(effects
				(font
					(size 1.27 1.27)
				)
			)
		)
		(property "Value" ""
			(at 0 0 90)
			(layer "F.Fab")
			(effects
				(font
					(size 1.27 1.27)
				)
			)
		)
		(duplicate_pad_numbers_are_jumpers no)
		(fp_line
			(start 0.7874 -0.4064)
			(end 0.7874 0.4064)
			(stroke
				(width 0.1524)
				(type default)
			)
			(layer "F.SilkS")
		)
		(fp_line
			(start -0.7874 -0.4064)
			(end 0.7874 -0.4064)
			(stroke
				(width 0.1524)
				(type default)
			)
			(layer "F.SilkS")
		)
		(fp_line
			(start 0.7874 0.4064)
			(end -0.7874 0.4064)
			(stroke
				(width 0.1524)
				(type default)
			)
			(layer "F.SilkS")
		)
		(fp_line
			(start -0.7874 0.4064)
			(end -0.7874 -0.4064)
			(stroke
				(width 0.1524)
				(type default)
			)
			(layer "F.SilkS")
		)
		(fp_line
			(start -0.12065 -0.305054)
			(end -0.12065 -0.2794)
			(stroke
				(width 0.1)
				(type default)
			)
			(layer "F.Fab")
		)
		(fp_line
			(start -0.67945 -0.305054)
			(end -0.12065 -0.305054)
			(stroke
				(width 0.1)
				(type default)
			)
			(layer "F.Fab")
		)
		(fp_line
			(start 0.67945 -0.3048)
			(end 0.67945 0.3048)
			(stroke
				(width 0.1)
				(type default)
			)
			(layer "F.Fab")
		)
		(fp_line
			(start 0.12065 -0.3048)
			(end 0.67945 -0.3048)
			(stroke
				(width 0.1)
				(type default)
			)
			(layer "F.Fab")
		)
		(fp_line
			(start 0.12065 -0.2794)
			(end 0.12065 -0.3048)
			(stroke
				(width 0.1)
				(type default)
			)
			(layer "F.Fab")
		)
		(fp_line
			(start -0.12065 -0.2794)
			(end 0.12065 -0.2794)
			(stroke
				(width 0.1)
				(type default)
			)
			(layer "F.Fab")
		)
		(fp_line
			(start 0.120396 0.2794)
			(end -0.12065 0.2794)
			(stroke
				(width 0.1)
				(type default)
			)
			(layer "F.Fab")
		)
		(fp_line
			(start -0.12065 0.2794)
			(end -0.12065 0.3048)
			(stroke
				(width 0.1)
				(type default)
			)
			(layer "F.Fab")
		)
		(fp_line
			(start 0.67945 0.3048)
			(end 0.120396 0.3048)
			(stroke
				(width 0.1)
				(type default)
			)
			(layer "F.Fab")
		)
		(fp_line
			(start 0.120396 0.3048)
			(end 0.120396 0.2794)
			(stroke
				(width 0.1)
				(type default)
			)
			(layer "F.Fab")
		)
		(fp_line
			(start -0.12065 0.3048)
			(end -0.67945 0.3048)
			(stroke
				(width 0.1)
				(type default)
			)
			(layer "F.Fab")
		)
		(fp_line
			(start -0.67945 0.3048)
			(end -0.67945 -0.305054)
			(stroke
				(width 0.1)
				(type default)
			)
			(layer "F.Fab")
		)
		(pad "1" smd circle
			(at -0.40005 0 90)
			(size 0 0)
			(layers "F.Cu" "F.Mask" "F.Paste")
			(net "P3V3_AUX")
		)
		(pad "2" smd circle
			(at 0.40005 0 90)
			(size 0 0)
			(layers "F.Cu" "F.Mask" "F.Paste")
			(net "PU_JTAG_DBP_BMC_PRDY_N")
		)
	)
	(footprint ""
		(layer "F.Cu")
		(at 356.53726 -327.09231 -90)
		(property "Reference" "PC99"
			(at 0 0 270)
			(layer "F.SilkS")
			(hide yes)
			(effects
				(font
					(size 1.27 1.27)
				)
			)
		)
		(property "Value" ""
			(at 0 0 270)
			(layer "F.Fab")
			(effects
				(font
					(size 1.27 1.27)
				)
			)
		)
		(duplicate_pad_numbers_are_jumpers no)
		(fp_line
			(start -0.7874 0.4064)
			(end -0.7874 -0.4064)
			(stroke
				(width 0.1524)
				(type default)
			)
			(layer "F.SilkS")
		)
		(fp_line
			(start 0.7874 0.4064)
			(end -0.7874 0.4064)
			(stroke
				(width 0.1524)
				(type default)
			)
			(layer "F.SilkS")
		)
		(fp_line
			(start -0.7874 -0.4064)
			(end 0.7874 -0.4064)
			(stroke
				(width 0.1524)
				(type default)
			)
			(layer "F.SilkS")
		)
		(fp_line
			(start 0.7874 -0.4064)
			(end 0.7874 0.4064)
			(stroke
				(width 0.1524)
				(type default)
			)
			(layer "F.SilkS")
		)
		(fp_line
			(start -0.67945 0.3048)
			(end -0.67945 -0.305054)
			(stroke
				(width 0.1)
				(type default)
			)
			(layer "F.Fab")
		)
		(fp_line
			(start -0.12065 0.3048)
			(end -0.67945 0.3048)
			(stroke
				(width 0.1)
				(type default)
			)
			(layer "F.Fab")
		)
		(fp_line
			(start 0.120396 0.3048)
			(end 0.120396 0.2794)
			(stroke
				(width 0.1)
				(type default)
			)
			(layer "F.Fab")
		)
		(fp_line
			(start 0.67945 0.3048)
			(end 0.120396 0.3048)
			(stroke
				(width 0.1)
				(type default)
			)
			(layer "F.Fab")
		)
		(fp_line
			(start -0.12065 0.2794)
			(end -0.12065 0.3048)
			(stroke
				(width 0.1)
				(type default)
			)
			(layer "F.Fab")
		)
		(fp_line
			(start 0.120396 0.2794)
			(end -0.12065 0.2794)
			(stroke
				(width 0.1)
				(type default)
			)
			(layer "F.Fab")
		)
		(fp_line
			(start -0.12065 -0.2794)
			(end 0.12065 -0.2794)
			(stroke
				(width 0.1)
				(type default)
			)
			(layer "F.Fab")
		)
		(fp_line
			(start 0.12065 -0.2794)
			(end 0.12065 -0.3048)
			(stroke
				(width 0.1)
				(type default)
			)
			(layer "F.Fab")
		)
		(fp_line
			(start 0.12065 -0.3048)
			(end 0.67945 -0.3048)
			(stroke
				(width 0.1)
				(type default)
			)
			(layer "F.Fab")
		)
		(fp_line
			(start 0.67945 -0.3048)
			(end 0.67945 0.3048)
			(stroke
				(width 0.1)
				(type default)
			)
			(layer "F.Fab")
		)
		(fp_line
			(start -0.67945 -0.305054)
			(end -0.12065 -0.305054)
			(stroke
				(width 0.1)
				(type default)
			)
			(layer "F.Fab")
		)
		(fp_line
			(start -0.12065 -0.305054)
			(end -0.12065 -0.2794)
			(stroke
				(width 0.1)
				(type default)
			)
			(layer "F.Fab")
		)
		(pad "1" smd circle
			(at -0.40005 0 270)
			(size 0 0)
			(layers "F.Cu" "F.Mask" "F.Paste")
			(net "PVDDCR_CPU1_P0")
		)
		(pad "2" smd circle
			(at 0.40005 0 270)
			(size 0 0)
			(layers "F.Cu" "F.Mask" "F.Paste")
			(net "GND")
		)
	)
	(footprint ""
		(layer "F.Cu")
		(at 26.793444 -425.593256 180)
		(property "Reference" "R3284"
			(at 0 0 180)
			(layer "F.SilkS")
			(hide yes)
			(effects
				(font
					(size 1.27 1.27)
				)
			)
		)
		(property "Value" ""
			(at 0 0 180)
			(layer "F.Fab")
			(effects
				(font
					(size 1.27 1.27)
				)
			)
		)
		(duplicate_pad_numbers_are_jumpers no)
		(fp_line
			(start 0.7874 0.4064)
			(end -0.7874 0.4064)
			(stroke
				(width 0.1524)
				(type default)
			)
			(layer "F.SilkS")
		)
		(fp_line
			(start 0.7874 -0.4064)
			(end 0.7874 0.4064)
			(stroke
				(width 0.1524)
				(type default)
			)
			(layer "F.SilkS")
		)
		(fp_line
			(start -0.7874 0.4064)
			(end -0.7874 -0.4064)
			(stroke
				(width 0.1524)
				(type default)
			)
			(layer "F.SilkS")
		)
		(fp_line
			(start -0.7874 -0.4064)
			(end 0.7874 -0.4064)
			(stroke
				(width 0.1524)
				(type default)
			)
			(layer "F.SilkS")
		)
		(fp_line
			(start 0.67945 0.3048)
			(end 0.120396 0.3048)
			(stroke
				(width 0.1)
				(type default)
			)
			(layer "F.Fab")
		)
		(fp_line
			(start 0.67945 -0.3048)
			(end 0.67945 0.3048)
			(stroke
				(width 0.1)
				(type default)
			)
			(layer "F.Fab")
		)
		(fp_line
			(start 0.12065 -0.2794)
			(end 0.12065 -0.3048)
			(stroke
				(width 0.1)
				(type default)
			)
			(layer "F.Fab")
		)
		(fp_line
			(start 0.12065 -0.3048)
			(end 0.67945 -0.3048)
			(stroke
				(width 0.1)
				(type default)
			)
			(layer "F.Fab")
		)
		(fp_line
			(start 0.120396 0.3048)
			(end 0.120396 0.2794)
			(stroke
				(width 0.1)
				(type default)
			)
			(layer "F.Fab")
		)
		(fp_line
			(start 0.120396 0.2794)
			(end -0.12065 0.2794)
			(stroke
				(width 0.1)
				(type default)
			)
			(layer "F.Fab")
		)
		(fp_line
			(start -0.12065 0.3048)
			(end -0.67945 0.3048)
			(stroke
				(width 0.1)
				(type default)
			)
			(layer "F.Fab")
		)
		(fp_line
			(start -0.12065 0.2794)
			(end -0.12065 0.3048)
			(stroke
				(width 0.1)
				(type default)
			)
			(layer "F.Fab")
		)
		(fp_line
			(start -0.12065 -0.2794)
			(end 0.12065 -0.2794)
			(stroke
				(width 0.1)
				(type default)
			)
			(layer "F.Fab")
		)
		(fp_line
			(start -0.12065 -0.305054)
			(end -0.12065 -0.2794)
			(stroke
				(width 0.1)
				(type default)
			)
			(layer "F.Fab")
		)
		(fp_line
			(start -0.67945 0.3048)
			(end -0.67945 -0.305054)
			(stroke
				(width 0.1)
				(type default)
			)
			(layer "F.Fab")
		)
		(fp_line
			(start -0.67945 -0.305054)
			(end -0.12065 -0.305054)
			(stroke
				(width 0.1)
				(type default)
			)
			(layer "F.Fab")
		)
		(pad "1" smd circle
			(at -0.40005 0 180)
			(size 0 0)
			(layers "F.Cu" "F.Mask" "F.Paste")
			(net "FM_P2E_EQB0")
		)
		(pad "2" smd circle
			(at 0.40005 0 180)
			(size 0 0)
			(layers "F.Cu" "F.Mask" "F.Paste")
			(net "GND")
		)
	)
	(footprint ""
		(layer "F.Cu")
		(at 168.656 -433.878736)
		(property "Reference" "R2672"
			(at 0 0 0)
			(layer "F.SilkS")
			(hide yes)
			(effects
				(font
					(size 1.27 1.27)
				)
			)
		)
		(property "Value" ""
			(at 0 0 0)
			(layer "F.Fab")
			(effects
				(font
					(size 1.27 1.27)
				)
			)
		)
		(duplicate_pad_numbers_are_jumpers no)
		(fp_line
			(start -0.7874 -0.4064)
			(end 0.7874 -0.4064)
			(stroke
				(width 0.1524)
				(type default)
			)
			(layer "F.SilkS")
		)
		(fp_line
			(start -0.7874 0.4064)
			(end -0.7874 -0.4064)
			(stroke
				(width 0.1524)
				(type default)
			)
			(layer "F.SilkS")
		)
		(fp_line
			(start 0.7874 -0.4064)
			(end 0.7874 0.4064)
			(stroke
				(width 0.1524)
				(type default)
			)
			(layer "F.SilkS")
		)
		(fp_line
			(start 0.7874 0.4064)
			(end -0.7874 0.4064)
			(stroke
				(width 0.1524)
				(type default)
			)
			(layer "F.SilkS")
		)
		(fp_line
			(start -0.67945 -0.305054)
			(end -0.12065 -0.305054)
			(stroke
				(width 0.1)
				(type default)
			)
			(layer "F.Fab")
		)
		(fp_line
			(start -0.67945 0.3048)
			(end -0.67945 -0.305054)
			(stroke
				(width 0.1)
				(type default)
			)
			(layer "F.Fab")
		)
		(fp_line
			(start -0.12065 -0.305054)
			(end -0.12065 -0.2794)
			(stroke
				(width 0.1)
				(type default)
			)
			(layer "F.Fab")
		)
		(fp_line
			(start -0.12065 -0.2794)
			(end 0.12065 -0.2794)
			(stroke
				(width 0.1)
				(type default)
			)
			(layer "F.Fab")
		)
		(fp_line
			(start -0.12065 0.2794)
			(end -0.12065 0.3048)
			(stroke
				(width 0.1)
				(type default)
			)
			(layer "F.Fab")
		)
		(fp_line
			(start -0.12065 0.3048)
			(end -0.67945 0.3048)
			(stroke
				(width 0.1)
				(type default)
			)
			(layer "F.Fab")
		)
		(fp_line
			(start 0.120396 0.2794)
			(end -0.12065 0.2794)
			(stroke
				(width 0.1)
				(type default)
			)
			(layer "F.Fab")
		)
		(fp_line
			(start 0.120396 0.3048)
			(end 0.120396 0.2794)
			(stroke
				(width 0.1)
				(type default)
			)
			(layer "F.Fab")
		)
		(fp_line
			(start 0.12065 -0.3048)
			(end 0.67945 -0.3048)
			(stroke
				(width 0.1)
				(type default)
			)
			(layer "F.Fab")
		)
		(fp_line
			(start 0.12065 -0.2794)
			(end 0.12065 -0.3048)
			(stroke
				(width 0.1)
				(type default)
			)
			(layer "F.Fab")
		)
		(fp_line
			(start 0.67945 -0.3048)
			(end 0.67945 0.3048)
			(stroke
				(width 0.1)
				(type default)
			)
			(layer "F.Fab")
		)
		(fp_line
			(start 0.67945 0.3048)
			(end 0.120396 0.3048)
			(stroke
				(width 0.1)
				(type default)
			)
			(layer "F.Fab")
		)
		(pad "1" smd circle
			(at -0.40005 0)
			(size 0 0)
			(layers "F.Cu" "F.Mask" "F.Paste")
			(net "SMB_BMC_SWB_BUF_R_SDA")
		)
		(pad "2" smd circle
			(at 0.40005 0)
			(size 0 0)
			(layers "F.Cu" "F.Mask" "F.Paste")
			(net "SMB_BMC_SWB_BUF_SDA")
		)
	)
	(footprint ""
		(layer "F.Cu")
		(at 312.330592 -346.866464 -90)
		(property "Reference" "PC117_4"
			(at 0 0 270)
			(layer "F.SilkS")
			(hide yes)
			(effects
				(font
					(size 1.27 1.27)
				)
			)
		)
		(property "Value" ""
			(at 0 0 270)
			(layer "F.Fab")
			(effects
				(font
					(size 1.27 1.27)
				)
			)
		)
		(duplicate_pad_numbers_are_jumpers no)
		(fp_line
			(start -0.7874 0.4064)
			(end -0.7874 -0.4064)
			(stroke
				(width 0.1524)
				(type default)
			)
			(layer "F.SilkS")
		)
		(fp_line
			(start 0.7874 0.4064)
			(end -0.7874 0.4064)
			(stroke
				(width 0.1524)
				(type default)
			)
			(layer "F.SilkS")
		)
		(fp_line
			(start -0.7874 -0.4064)
			(end 0.7874 -0.4064)
			(stroke
				(width 0.1524)
				(type default)
			)
			(layer "F.SilkS")
		)
		(fp_line
			(start 0.7874 -0.4064)
			(end 0.7874 0.4064)
			(stroke
				(width 0.1524)
				(type default)
			)
			(layer "F.SilkS")
		)
		(fp_line
			(start -0.67945 0.3048)
			(end -0.67945 -0.305054)
			(stroke
				(width 0.1)
				(type default)
			)
			(layer "F.Fab")
		)
		(fp_line
			(start -0.12065 0.3048)
			(end -0.67945 0.3048)
			(stroke
				(width 0.1)
				(type default)
			)
			(layer "F.Fab")
		)
		(fp_line
			(start 0.120396 0.3048)
			(end 0.120396 0.2794)
			(stroke
				(width 0.1)
				(type default)
			)
			(layer "F.Fab")
		)
		(fp_line
			(start 0.67945 0.3048)
			(end 0.120396 0.3048)
			(stroke
				(width 0.1)
				(type default)
			)
			(layer "F.Fab")
		)
		(fp_line
			(start -0.12065 0.2794)
			(end -0.12065 0.3048)
			(stroke
				(width 0.1)
				(type default)
			)
			(layer "F.Fab")
		)
		(fp_line
			(start 0.120396 0.2794)
			(end -0.12065 0.2794)
			(stroke
				(width 0.1)
				(type default)
			)
			(layer "F.Fab")
		)
		(fp_line
			(start -0.12065 -0.2794)
			(end 0.12065 -0.2794)
			(stroke
				(width 0.1)
				(type default)
			)
			(layer "F.Fab")
		)
		(fp_line
			(start 0.12065 -0.2794)
			(end 0.12065 -0.3048)
			(stroke
				(width 0.1)
				(type default)
			)
			(layer "F.Fab")
		)
		(fp_line
			(start 0.12065 -0.3048)
			(end 0.67945 -0.3048)
			(stroke
				(width 0.1)
				(type default)
			)
			(layer "F.Fab")
		)
		(fp_line
			(start 0.67945 -0.3048)
			(end 0.67945 0.3048)
			(stroke
				(width 0.1)
				(type default)
			)
			(layer "F.Fab")
		)
		(fp_line
			(start -0.67945 -0.305054)
			(end -0.12065 -0.305054)
			(stroke
				(width 0.1)
				(type default)
			)
			(layer "F.Fab")
		)
		(fp_line
			(start -0.12065 -0.305054)
			(end -0.12065 -0.2794)
			(stroke
				(width 0.1)
				(type default)
			)
			(layer "F.Fab")
		)
		(pad "1" smd circle
			(at -0.40005 0 270)
			(size 0 0)
			(layers "F.Cu" "F.Mask" "F.Paste")
			(net "SW_P12V_AUX_PVDDCR_CPU1_P0_FLT")
		)
		(pad "2" smd circle
			(at 0.40005 0 270)
			(size 0 0)
			(layers "F.Cu" "F.Mask" "F.Paste")
			(net "GND")
		)
	)
	(footprint ""
		(layer "F.Cu")
		(at 95.88373 -37.865558 180)
		(property "Reference" "C1822"
			(at 0 0 180)
			(layer "F.SilkS")
			(hide yes)
			(effects
				(font
					(size 1.27 1.27)
				)
			)
		)
		(property "Value" ""
			(at 0 0 180)
			(layer "F.Fab")
			(effects
				(font
					(size 1.27 1.27)
				)
			)
		)
		(duplicate_pad_numbers_are_jumpers no)
		(fp_line
			(start 0.7874 0.4064)
			(end -0.7874 0.4064)
			(stroke
				(width 0.1524)
				(type default)
			)
			(layer "F.SilkS")
		)
		(fp_line
			(start 0.7874 -0.4064)
			(end 0.7874 0.4064)
			(stroke
				(width 0.1524)
				(type default)
			)
			(layer "F.SilkS")
		)
		(fp_line
			(start -0.7874 0.4064)
			(end -0.7874 -0.4064)
			(stroke
				(width 0.1524)
				(type default)
			)
			(layer "F.SilkS")
		)
		(fp_line
			(start -0.7874 -0.4064)
			(end 0.7874 -0.4064)
			(stroke
				(width 0.1524)
				(type default)
			)
			(layer "F.SilkS")
		)
		(fp_line
			(start 0.67945 0.3048)
			(end 0.120396 0.3048)
			(stroke
				(width 0.1)
				(type default)
			)
			(layer "F.Fab")
		)
		(fp_line
			(start 0.67945 -0.3048)
			(end 0.67945 0.3048)
			(stroke
				(width 0.1)
				(type default)
			)
			(layer "F.Fab")
		)
		(fp_line
			(start 0.12065 -0.2794)
			(end 0.12065 -0.3048)
			(stroke
				(width 0.1)
				(type default)
			)
			(layer "F.Fab")
		)
		(fp_line
			(start 0.12065 -0.3048)
			(end 0.67945 -0.3048)
			(stroke
				(width 0.1)
				(type default)
			)
			(layer "F.Fab")
		)
		(fp_line
			(start 0.120396 0.3048)
			(end 0.120396 0.2794)
			(stroke
				(width 0.1)
				(type default)
			)
			(layer "F.Fab")
		)
		(fp_line
			(start 0.120396 0.2794)
			(end -0.12065 0.2794)
			(stroke
				(width 0.1)
				(type default)
			)
			(layer "F.Fab")
		)
		(fp_line
			(start -0.12065 0.3048)
			(end -0.67945 0.3048)
			(stroke
				(width 0.1)
				(type default)
			)
			(layer "F.Fab")
		)
		(fp_line
			(start -0.12065 0.2794)
			(end -0.12065 0.3048)
			(stroke
				(width 0.1)
				(type default)
			)
			(layer "F.Fab")
		)
		(fp_line
			(start -0.12065 -0.2794)
			(end 0.12065 -0.2794)
			(stroke
				(width 0.1)
				(type default)
			)
			(layer "F.Fab")
		)
		(fp_line
			(start -0.12065 -0.305054)
			(end -0.12065 -0.2794)
			(stroke
				(width 0.1)
				(type default)
			)
			(layer "F.Fab")
		)
		(fp_line
			(start -0.67945 0.3048)
			(end -0.67945 -0.305054)
			(stroke
				(width 0.1)
				(type default)
			)
			(layer "F.Fab")
		)
		(fp_line
			(start -0.67945 -0.305054)
			(end -0.12065 -0.305054)
			(stroke
				(width 0.1)
				(type default)
			)
			(layer "F.Fab")
		)
		(pad "1" smd circle
			(at -0.40005 0 180)
			(size 0 0)
			(layers "F.Cu" "F.Mask" "F.Paste")
			(net "P3V3_AUX")
		)
		(pad "2" smd circle
			(at 0.40005 0 180)
			(size 0 0)
			(layers "F.Cu" "F.Mask" "F.Paste")
			(net "GND")
		)
	)
	(footprint ""
		(layer "F.Cu")
		(at 314.567316 -111.57077 180)
		(property "Reference" "R121"
			(at 0 0 180)
			(layer "F.SilkS")
			(hide yes)
			(effects
				(font
					(size 1.27 1.27)
				)
			)
		)
		(property "Value" ""
			(at 0 0 180)
			(layer "F.Fab")
			(effects
				(font
					(size 1.27 1.27)
				)
			)
		)
		(duplicate_pad_numbers_are_jumpers no)
		(fp_line
			(start 0.7874 0.4064)
			(end -0.7874 0.4064)
			(stroke
				(width 0.1524)
				(type default)
			)
			(layer "F.SilkS")
		)
		(fp_line
			(start 0.7874 -0.4064)
			(end 0.7874 0.4064)
			(stroke
				(width 0.1524)
				(type default)
			)
			(layer "F.SilkS")
		)
		(fp_line
			(start -0.7874 0.4064)
			(end -0.7874 -0.4064)
			(stroke
				(width 0.1524)
				(type default)
			)
			(layer "F.SilkS")
		)
		(fp_line
			(start -0.7874 -0.4064)
			(end 0.7874 -0.4064)
			(stroke
				(width 0.1524)
				(type default)
			)
			(layer "F.SilkS")
		)
		(fp_line
			(start 0.67945 0.3048)
			(end 0.120396 0.3048)
			(stroke
				(width 0.1)
				(type default)
			)
			(layer "F.Fab")
		)
		(fp_line
			(start 0.67945 -0.3048)
			(end 0.67945 0.3048)
			(stroke
				(width 0.1)
				(type default)
			)
			(layer "F.Fab")
		)
		(fp_line
			(start 0.12065 -0.2794)
			(end 0.12065 -0.3048)
			(stroke
				(width 0.1)
				(type default)
			)
			(layer "F.Fab")
		)
		(fp_line
			(start 0.12065 -0.3048)
			(end 0.67945 -0.3048)
			(stroke
				(width 0.1)
				(type default)
			)
			(layer "F.Fab")
		)
		(fp_line
			(start 0.120396 0.3048)
			(end 0.120396 0.2794)
			(stroke
				(width 0.1)
				(type default)
			)
			(layer "F.Fab")
		)
		(fp_line
			(start 0.120396 0.2794)
			(end -0.12065 0.2794)
			(stroke
				(width 0.1)
				(type default)
			)
			(layer "F.Fab")
		)
		(fp_line
			(start -0.12065 0.3048)
			(end -0.67945 0.3048)
			(stroke
				(width 0.1)
				(type default)
			)
			(layer "F.Fab")
		)
		(fp_line
			(start -0.12065 0.2794)
			(end -0.12065 0.3048)
			(stroke
				(width 0.1)
				(type default)
			)
			(layer "F.Fab")
		)
		(fp_line
			(start -0.12065 -0.2794)
			(end 0.12065 -0.2794)
			(stroke
				(width 0.1)
				(type default)
			)
			(layer "F.Fab")
		)
		(fp_line
			(start -0.12065 -0.305054)
			(end -0.12065 -0.2794)
			(stroke
				(width 0.1)
				(type default)
			)
			(layer "F.Fab")
		)
		(fp_line
			(start -0.67945 0.3048)
			(end -0.67945 -0.305054)
			(stroke
				(width 0.1)
				(type default)
			)
			(layer "F.Fab")
		)
		(fp_line
			(start -0.67945 -0.305054)
			(end -0.12065 -0.305054)
			(stroke
				(width 0.1)
				(type default)
			)
			(layer "F.Fab")
		)
		(pad "1" smd circle
			(at -0.40005 0 180)
			(size 0 0)
			(layers "F.Cu" "F.Mask" "F.Paste")
			(net "SMB_FRU_3V3AUX_SCL")
		)
		(pad "2" smd circle
			(at 0.40005 0 180)
			(size 0 0)
			(layers "F.Cu" "F.Mask" "F.Paste")
			(net "SMB_CPU_FRU_3V3AUX_SCL")
		)
	)
	(footprint ""
		(layer "F.Cu")
		(at 386.211826 -62.0395 180)
		(property "Reference" "R1631"
			(at 0 0 180)
			(layer "F.SilkS")
			(hide yes)
			(effects
				(font
					(size 1.27 1.27)
				)
			)
		)
		(property "Value" ""
			(at 0 0 180)
			(layer "F.Fab")
			(effects
				(font
					(size 1.27 1.27)
				)
			)
		)
		(duplicate_pad_numbers_are_jumpers no)
		(fp_line
			(start 0.7874 0.4064)
			(end -0.7874 0.4064)
			(stroke
				(width 0.1524)
				(type default)
			)
			(layer "F.SilkS")
		)
		(fp_line
			(start 0.7874 -0.4064)
			(end 0.7874 0.4064)
			(stroke
				(width 0.1524)
				(type default)
			)
			(layer "F.SilkS")
		)
		(fp_line
			(start -0.7874 0.4064)
			(end -0.7874 -0.4064)
			(stroke
				(width 0.1524)
				(type default)
			)
			(layer "F.SilkS")
		)
		(fp_line
			(start -0.7874 -0.4064)
			(end 0.7874 -0.4064)
			(stroke
				(width 0.1524)
				(type default)
			)
			(layer "F.SilkS")
		)
		(fp_line
			(start 0.67945 0.3048)
			(end 0.120396 0.3048)
			(stroke
				(width 0.1)
				(type default)
			)
			(layer "F.Fab")
		)
		(fp_line
			(start 0.67945 -0.3048)
			(end 0.67945 0.3048)
			(stroke
				(width 0.1)
				(type default)
			)
			(layer "F.Fab")
		)
		(fp_line
			(start 0.12065 -0.2794)
			(end 0.12065 -0.3048)
			(stroke
				(width 0.1)
				(type default)
			)
			(layer "F.Fab")
		)
		(fp_line
			(start 0.12065 -0.3048)
			(end 0.67945 -0.3048)
			(stroke
				(width 0.1)
				(type default)
			)
			(layer "F.Fab")
		)
		(fp_line
			(start 0.120396 0.3048)
			(end 0.120396 0.2794)
			(stroke
				(width 0.1)
				(type default)
			)
			(layer "F.Fab")
		)
		(fp_line
			(start 0.120396 0.2794)
			(end -0.12065 0.2794)
			(stroke
				(width 0.1)
				(type default)
			)
			(layer "F.Fab")
		)
		(fp_line
			(start -0.12065 0.3048)
			(end -0.67945 0.3048)
			(stroke
				(width 0.1)
				(type default)
			)
			(layer "F.Fab")
		)
		(fp_line
			(start -0.12065 0.2794)
			(end -0.12065 0.3048)
			(stroke
				(width 0.1)
				(type default)
			)
			(layer "F.Fab")
		)
		(fp_line
			(start -0.12065 -0.2794)
			(end 0.12065 -0.2794)
			(stroke
				(width 0.1)
				(type default)
			)
			(layer "F.Fab")
		)
		(fp_line
			(start -0.12065 -0.305054)
			(end -0.12065 -0.2794)
			(stroke
				(width 0.1)
				(type default)
			)
			(layer "F.Fab")
		)
		(fp_line
			(start -0.67945 0.3048)
			(end -0.67945 -0.305054)
			(stroke
				(width 0.1)
				(type default)
			)
			(layer "F.Fab")
		)
		(fp_line
			(start -0.67945 -0.305054)
			(end -0.12065 -0.305054)
			(stroke
				(width 0.1)
				(type default)
			)
			(layer "F.Fab")
		)
		(pad "1" smd circle
			(at -0.40005 0 180)
			(size 0 0)
			(layers "F.Cu" "F.Mask" "F.Paste")
			(net "HDT_HDR_DBREQ_R_N")
		)
		(pad "2" smd circle
			(at 0.40005 0 180)
			(size 0 0)
			(layers "F.Cu" "F.Mask" "F.Paste")
			(net "HDT_HDR_DBREQ_N")
		)
	)
	(footprint ""
		(layer "F.Cu")
		(at 215.4301 -406.052782)
		(property "Reference" "PR3922"
			(at 0 0 0)
			(layer "F.SilkS")
			(hide yes)
			(effects
				(font
					(size 1.27 1.27)
				)
			)
		)
		(property "Value" ""
			(at 0 0 0)
			(layer "F.Fab")
			(effects
				(font
					(size 1.27 1.27)
				)
			)
		)
		(duplicate_pad_numbers_are_jumpers no)
		(fp_line
			(start -0.7874 -0.4064)
			(end 0.7874 -0.4064)
			(stroke
				(width 0.1524)
				(type default)
			)
			(layer "F.SilkS")
		)
		(fp_line
			(start -0.7874 0.4064)
			(end -0.7874 -0.4064)
			(stroke
				(width 0.1524)
				(type default)
			)
			(layer "F.SilkS")
		)
		(fp_line
			(start 0.7874 -0.4064)
			(end 0.7874 0.4064)
			(stroke
				(width 0.1524)
				(type default)
			)
			(layer "F.SilkS")
		)
		(fp_line
			(start 0.7874 0.4064)
			(end -0.7874 0.4064)
			(stroke
				(width 0.1524)
				(type default)
			)
			(layer "F.SilkS")
		)
		(fp_line
			(start -0.67945 -0.305054)
			(end -0.12065 -0.305054)
			(stroke
				(width 0.1)
				(type default)
			)
			(layer "F.Fab")
		)
		(fp_line
			(start -0.67945 0.3048)
			(end -0.67945 -0.305054)
			(stroke
				(width 0.1)
				(type default)
			)
			(layer "F.Fab")
		)
		(fp_line
			(start -0.12065 -0.305054)
			(end -0.12065 -0.2794)
			(stroke
				(width 0.1)
				(type default)
			)
			(layer "F.Fab")
		)
		(fp_line
			(start -0.12065 -0.2794)
			(end 0.12065 -0.2794)
			(stroke
				(width 0.1)
				(type default)
			)
			(layer "F.Fab")
		)
		(fp_line
			(start -0.12065 0.2794)
			(end -0.12065 0.3048)
			(stroke
				(width 0.1)
				(type default)
			)
			(layer "F.Fab")
		)
		(fp_line
			(start -0.12065 0.3048)
			(end -0.67945 0.3048)
			(stroke
				(width 0.1)
				(type default)
			)
			(layer "F.Fab")
		)
		(fp_line
			(start 0.120396 0.2794)
			(end -0.12065 0.2794)
			(stroke
				(width 0.1)
				(type default)
			)
			(layer "F.Fab")
		)
		(fp_line
			(start 0.120396 0.3048)
			(end 0.120396 0.2794)
			(stroke
				(width 0.1)
				(type default)
			)
			(layer "F.Fab")
		)
		(fp_line
			(start 0.12065 -0.3048)
			(end 0.67945 -0.3048)
			(stroke
				(width 0.1)
				(type default)
			)
			(layer "F.Fab")
		)
		(fp_line
			(start 0.12065 -0.2794)
			(end 0.12065 -0.3048)
			(stroke
				(width 0.1)
				(type default)
			)
			(layer "F.Fab")
		)
		(fp_line
			(start 0.67945 -0.3048)
			(end 0.67945 0.3048)
			(stroke
				(width 0.1)
				(type default)
			)
			(layer "F.Fab")
		)
		(fp_line
			(start 0.67945 0.3048)
			(end 0.120396 0.3048)
			(stroke
				(width 0.1)
				(type default)
			)
			(layer "F.Fab")
		)
		(pad "1" smd circle
			(at -0.40005 0)
			(size 0 0)
			(layers "F.Cu" "F.Mask" "F.Paste")
			(net "HSC_FLT_TYPE_2")
		)
		(pad "2" smd circle
			(at 0.40005 0)
			(size 0 0)
			(layers "F.Cu" "F.Mask" "F.Paste")
			(net "HSC_FLT_TYPE")
		)
	)
	(footprint ""
		(layer "F.Cu")
		(at 147.877022 -23.284942 90)
		(property "Reference" "C6000"
			(at 0 0 90)
			(layer "F.SilkS")
			(hide yes)
			(effects
				(font
					(size 1.27 1.27)
				)
			)
		)
		(property "Value" ""
			(at 0 0 90)
			(layer "F.Fab")
			(effects
				(font
					(size 1.27 1.27)
				)
			)
		)
		(duplicate_pad_numbers_are_jumpers no)
		(fp_line
			(start 0.7874 -0.4064)
			(end 0.7874 0.4064)
			(stroke
				(width 0.1524)
				(type default)
			)
			(layer "F.SilkS")
		)
		(fp_line
			(start -0.7874 -0.4064)
			(end 0.7874 -0.4064)
			(stroke
				(width 0.1524)
				(type default)
			)
			(layer "F.SilkS")
		)
		(fp_line
			(start 0.7874 0.4064)
			(end -0.7874 0.4064)
			(stroke
				(width 0.1524)
				(type default)
			)
			(layer "F.SilkS")
		)
		(fp_line
			(start -0.7874 0.4064)
			(end -0.7874 -0.4064)
			(stroke
				(width 0.1524)
				(type default)
			)
			(layer "F.SilkS")
		)
		(fp_line
			(start -0.12065 -0.305054)
			(end -0.12065 -0.2794)
			(stroke
				(width 0.1)
				(type default)
			)
			(layer "F.Fab")
		)
		(fp_line
			(start -0.67945 -0.305054)
			(end -0.12065 -0.305054)
			(stroke
				(width 0.1)
				(type default)
			)
			(layer "F.Fab")
		)
		(fp_line
			(start 0.67945 -0.3048)
			(end 0.67945 0.3048)
			(stroke
				(width 0.1)
				(type default)
			)
			(layer "F.Fab")
		)
		(fp_line
			(start 0.12065 -0.3048)
			(end 0.67945 -0.3048)
			(stroke
				(width 0.1)
				(type default)
			)
			(layer "F.Fab")
		)
		(fp_line
			(start 0.12065 -0.2794)
			(end 0.12065 -0.3048)
			(stroke
				(width 0.1)
				(type default)
			)
			(layer "F.Fab")
		)
		(fp_line
			(start -0.12065 -0.2794)
			(end 0.12065 -0.2794)
			(stroke
				(width 0.1)
				(type default)
			)
			(layer "F.Fab")
		)
		(fp_line
			(start 0.120396 0.2794)
			(end -0.12065 0.2794)
			(stroke
				(width 0.1)
				(type default)
			)
			(layer "F.Fab")
		)
		(fp_line
			(start -0.12065 0.2794)
			(end -0.12065 0.3048)
			(stroke
				(width 0.1)
				(type default)
			)
			(layer "F.Fab")
		)
		(fp_line
			(start 0.67945 0.3048)
			(end 0.120396 0.3048)
			(stroke
				(width 0.1)
				(type default)
			)
			(layer "F.Fab")
		)
		(fp_line
			(start 0.120396 0.3048)
			(end 0.120396 0.2794)
			(stroke
				(width 0.1)
				(type default)
			)
			(layer "F.Fab")
		)
		(fp_line
			(start -0.12065 0.3048)
			(end -0.67945 0.3048)
			(stroke
				(width 0.1)
				(type default)
			)
			(layer "F.Fab")
		)
		(fp_line
			(start -0.67945 0.3048)
			(end -0.67945 -0.305054)
			(stroke
				(width 0.1)
				(type default)
			)
			(layer "F.Fab")
		)
		(pad "1" smd circle
			(at -0.40005 0 90)
			(size 0 0)
			(layers "F.Cu" "F.Mask" "F.Paste")
			(net "SCM_VDD_RTC")
		)
		(pad "2" smd circle
			(at 0.40005 0 90)
			(size 0 0)
			(layers "F.Cu" "F.Mask" "F.Paste")
			(net "GND")
		)
	)
	(footprint ""
		(layer "F.Cu")
		(at 115.70589 -257.74523)
		(property "Reference" "C2423"
			(at 0 0 0)
			(layer "F.SilkS")
			(hide yes)
			(effects
				(font
					(size 1.27 1.27)
				)
			)
		)
		(property "Value" ""
			(at 0 0 0)
			(layer "F.Fab")
			(effects
				(font
					(size 1.27 1.27)
				)
			)
		)
		(duplicate_pad_numbers_are_jumpers no)
		(fp_line
			(start -0.7874 -0.4064)
			(end 0.7874 -0.4064)
			(stroke
				(width 0.1524)
				(type default)
			)
			(layer "F.SilkS")
		)
		(fp_line
			(start -0.7874 0.4064)
			(end -0.7874 -0.4064)
			(stroke
				(width 0.1524)
				(type default)
			)
			(layer "F.SilkS")
		)
		(fp_line
			(start 0.7874 -0.4064)
			(end 0.7874 0.4064)
			(stroke
				(width 0.1524)
				(type default)
			)
			(layer "F.SilkS")
		)
		(fp_line
			(start 0.7874 0.4064)
			(end -0.7874 0.4064)
			(stroke
				(width 0.1524)
				(type default)
			)
			(layer "F.SilkS")
		)
		(fp_line
			(start -0.67945 -0.305054)
			(end -0.12065 -0.305054)
			(stroke
				(width 0.1)
				(type default)
			)
			(layer "F.Fab")
		)
		(fp_line
			(start -0.67945 0.3048)
			(end -0.67945 -0.305054)
			(stroke
				(width 0.1)
				(type default)
			)
			(layer "F.Fab")
		)
		(fp_line
			(start -0.12065 -0.305054)
			(end -0.12065 -0.2794)
			(stroke
				(width 0.1)
				(type default)
			)
			(layer "F.Fab")
		)
		(fp_line
			(start -0.12065 -0.2794)
			(end 0.12065 -0.2794)
			(stroke
				(width 0.1)
				(type default)
			)
			(layer "F.Fab")
		)
		(fp_line
			(start -0.12065 0.2794)
			(end -0.12065 0.3048)
			(stroke
				(width 0.1)
				(type default)
			)
			(layer "F.Fab")
		)
		(fp_line
			(start -0.12065 0.3048)
			(end -0.67945 0.3048)
			(stroke
				(width 0.1)
				(type default)
			)
			(layer "F.Fab")
		)
		(fp_line
			(start 0.120396 0.2794)
			(end -0.12065 0.2794)
			(stroke
				(width 0.1)
				(type default)
			)
			(layer "F.Fab")
		)
		(fp_line
			(start 0.120396 0.3048)
			(end 0.120396 0.2794)
			(stroke
				(width 0.1)
				(type default)
			)
			(layer "F.Fab")
		)
		(fp_line
			(start 0.12065 -0.3048)
			(end 0.67945 -0.3048)
			(stroke
				(width 0.1)
				(type default)
			)
			(layer "F.Fab")
		)
		(fp_line
			(start 0.12065 -0.2794)
			(end 0.12065 -0.3048)
			(stroke
				(width 0.1)
				(type default)
			)
			(layer "F.Fab")
		)
		(fp_line
			(start 0.67945 -0.3048)
			(end 0.67945 0.3048)
			(stroke
				(width 0.1)
				(type default)
			)
			(layer "F.Fab")
		)
		(fp_line
			(start 0.67945 0.3048)
			(end 0.120396 0.3048)
			(stroke
				(width 0.1)
				(type default)
			)
			(layer "F.Fab")
		)
		(pad "1" smd circle
			(at -0.40005 0)
			(size 0 0)
			(layers "F.Cu" "F.Mask" "F.Paste")
			(net "PVDDCR_SOC_P1")
		)
		(pad "2" smd circle
			(at 0.40005 0)
			(size 0 0)
			(layers "F.Cu" "F.Mask" "F.Paste")
			(net "GND")
		)
	)
	(footprint ""
		(layer "F.Cu")
		(at 353.900232 -255.554988)
		(property "Reference" "C2164"
			(at 0 0 0)
			(layer "F.SilkS")
			(hide yes)
			(effects
				(font
					(size 1.27 1.27)
				)
			)
		)
		(property "Value" ""
			(at 0 0 0)
			(layer "F.Fab")
			(effects
				(font
					(size 1.27 1.27)
				)
			)
		)
		(duplicate_pad_numbers_are_jumpers no)
		(fp_line
			(start -0.7874 -0.4064)
			(end 0.7874 -0.4064)
			(stroke
				(width 0.1524)
				(type default)
			)
			(layer "F.SilkS")
		)
		(fp_line
			(start -0.7874 0.4064)
			(end -0.7874 -0.4064)
			(stroke
				(width 0.1524)
				(type default)
			)
			(layer "F.SilkS")
		)
		(fp_line
			(start 0.7874 -0.4064)
			(end 0.7874 0.4064)
			(stroke
				(width 0.1524)
				(type default)
			)
			(layer "F.SilkS")
		)
		(fp_line
			(start 0.7874 0.4064)
			(end -0.7874 0.4064)
			(stroke
				(width 0.1524)
				(type default)
			)
			(layer "F.SilkS")
		)
		(fp_line
			(start -0.67945 -0.305054)
			(end -0.12065 -0.305054)
			(stroke
				(width 0.1)
				(type default)
			)
			(layer "F.Fab")
		)
		(fp_line
			(start -0.67945 0.3048)
			(end -0.67945 -0.305054)
			(stroke
				(width 0.1)
				(type default)
			)
			(layer "F.Fab")
		)
		(fp_line
			(start -0.12065 -0.305054)
			(end -0.12065 -0.2794)
			(stroke
				(width 0.1)
				(type default)
			)
			(layer "F.Fab")
		)
		(fp_line
			(start -0.12065 -0.2794)
			(end 0.12065 -0.2794)
			(stroke
				(width 0.1)
				(type default)
			)
			(layer "F.Fab")
		)
		(fp_line
			(start -0.12065 0.2794)
			(end -0.12065 0.3048)
			(stroke
				(width 0.1)
				(type default)
			)
			(layer "F.Fab")
		)
		(fp_line
			(start -0.12065 0.3048)
			(end -0.67945 0.3048)
			(stroke
				(width 0.1)
				(type default)
			)
			(layer "F.Fab")
		)
		(fp_line
			(start 0.120396 0.2794)
			(end -0.12065 0.2794)
			(stroke
				(width 0.1)
				(type default)
			)
			(layer "F.Fab")
		)
		(fp_line
			(start 0.120396 0.3048)
			(end 0.120396 0.2794)
			(stroke
				(width 0.1)
				(type default)
			)
			(layer "F.Fab")
		)
		(fp_line
			(start 0.12065 -0.3048)
			(end 0.67945 -0.3048)
			(stroke
				(width 0.1)
				(type default)
			)
			(layer "F.Fab")
		)
		(fp_line
			(start 0.12065 -0.2794)
			(end 0.12065 -0.3048)
			(stroke
				(width 0.1)
				(type default)
			)
			(layer "F.Fab")
		)
		(fp_line
			(start 0.67945 -0.3048)
			(end 0.67945 0.3048)
			(stroke
				(width 0.1)
				(type default)
			)
			(layer "F.Fab")
		)
		(fp_line
			(start 0.67945 0.3048)
			(end 0.120396 0.3048)
			(stroke
				(width 0.1)
				(type default)
			)
			(layer "F.Fab")
		)
		(pad "1" smd circle
			(at -0.40005 0)
			(size 0 0)
			(layers "F.Cu" "F.Mask" "F.Paste")
			(net "PVDD18_S5_P0")
		)
		(pad "2" smd circle
			(at 0.40005 0)
			(size 0 0)
			(layers "F.Cu" "F.Mask" "F.Paste")
			(net "GND")
		)
	)
	(footprint ""
		(layer "F.Cu")
		(at 429.136302 -434.386736 -90)
		(property "Reference" "C1754"
			(at 0 0 270)
			(layer "F.SilkS")
			(hide yes)
			(effects
				(font
					(size 1.27 1.27)
				)
			)
		)
		(property "Value" ""
			(at 0 0 270)
			(layer "F.Fab")
			(effects
				(font
					(size 1.27 1.27)
				)
			)
		)
		(duplicate_pad_numbers_are_jumpers no)
		(fp_line
			(start -0.7874 0.4064)
			(end -0.7874 -0.4064)
			(stroke
				(width 0.1524)
				(type default)
			)
			(layer "F.SilkS")
		)
		(fp_line
			(start 0.7874 0.4064)
			(end -0.7874 0.4064)
			(stroke
				(width 0.1524)
				(type default)
			)
			(layer "F.SilkS")
		)
		(fp_line
			(start -0.7874 -0.4064)
			(end 0.7874 -0.4064)
			(stroke
				(width 0.1524)
				(type default)
			)
			(layer "F.SilkS")
		)
		(fp_line
			(start 0.7874 -0.4064)
			(end 0.7874 0.4064)
			(stroke
				(width 0.1524)
				(type default)
			)
			(layer "F.SilkS")
		)
		(fp_line
			(start -0.67945 0.3048)
			(end -0.67945 -0.305054)
			(stroke
				(width 0.1)
				(type default)
			)
			(layer "F.Fab")
		)
		(fp_line
			(start -0.12065 0.3048)
			(end -0.67945 0.3048)
			(stroke
				(width 0.1)
				(type default)
			)
			(layer "F.Fab")
		)
		(fp_line
			(start 0.120396 0.3048)
			(end 0.120396 0.2794)
			(stroke
				(width 0.1)
				(type default)
			)
			(layer "F.Fab")
		)
		(fp_line
			(start 0.67945 0.3048)
			(end 0.120396 0.3048)
			(stroke
				(width 0.1)
				(type default)
			)
			(layer "F.Fab")
		)
		(fp_line
			(start -0.12065 0.2794)
			(end -0.12065 0.3048)
			(stroke
				(width 0.1)
				(type default)
			)
			(layer "F.Fab")
		)
		(fp_line
			(start 0.120396 0.2794)
			(end -0.12065 0.2794)
			(stroke
				(width 0.1)
				(type default)
			)
			(layer "F.Fab")
		)
		(fp_line
			(start -0.12065 -0.2794)
			(end 0.12065 -0.2794)
			(stroke
				(width 0.1)
				(type default)
			)
			(layer "F.Fab")
		)
		(fp_line
			(start 0.12065 -0.2794)
			(end 0.12065 -0.3048)
			(stroke
				(width 0.1)
				(type default)
			)
			(layer "F.Fab")
		)
		(fp_line
			(start 0.12065 -0.3048)
			(end 0.67945 -0.3048)
			(stroke
				(width 0.1)
				(type default)
			)
			(layer "F.Fab")
		)
		(fp_line
			(start 0.67945 -0.3048)
			(end 0.67945 0.3048)
			(stroke
				(width 0.1)
				(type default)
			)
			(layer "F.Fab")
		)
		(fp_line
			(start -0.67945 -0.305054)
			(end -0.12065 -0.305054)
			(stroke
				(width 0.1)
				(type default)
			)
			(layer "F.Fab")
		)
		(fp_line
			(start -0.12065 -0.305054)
			(end -0.12065 -0.2794)
			(stroke
				(width 0.1)
				(type default)
			)
			(layer "F.Fab")
		)
		(pad "1" smd circle
			(at -0.40005 0 270)
			(size 0 0)
			(layers "F.Cu" "F.Mask" "F.Paste")
			(net "FM_SWB_BIC_READY_ISO_N")
		)
		(pad "2" smd circle
			(at 0.40005 0 270)
			(size 0 0)
			(layers "F.Cu" "F.Mask" "F.Paste")
			(net "GND")
		)
	)
	(footprint ""
		(layer "F.Cu")
		(at 294.421052 -122.349514)
		(property "Reference" "R317"
			(at 0 0 0)
			(layer "F.SilkS")
			(hide yes)
			(effects
				(font
					(size 1.27 1.27)
				)
			)
		)
		(property "Value" ""
			(at 0 0 0)
			(layer "F.Fab")
			(effects
				(font
					(size 1.27 1.27)
				)
			)
		)
		(duplicate_pad_numbers_are_jumpers no)
		(fp_line
			(start -0.7874 -0.4064)
			(end 0.7874 -0.4064)
			(stroke
				(width 0.1524)
				(type default)
			)
			(layer "F.SilkS")
		)
		(fp_line
			(start -0.7874 0.4064)
			(end -0.7874 -0.4064)
			(stroke
				(width 0.1524)
				(type default)
			)
			(layer "F.SilkS")
		)
		(fp_line
			(start 0.7874 -0.4064)
			(end 0.7874 0.4064)
			(stroke
				(width 0.1524)
				(type default)
			)
			(layer "F.SilkS")
		)
		(fp_line
			(start 0.7874 0.4064)
			(end -0.7874 0.4064)
			(stroke
				(width 0.1524)
				(type default)
			)
			(layer "F.SilkS")
		)
		(fp_line
			(start -0.67945 -0.305054)
			(end -0.12065 -0.305054)
			(stroke
				(width 0.1)
				(type default)
			)
			(layer "F.Fab")
		)
		(fp_line
			(start -0.67945 0.3048)
			(end -0.67945 -0.305054)
			(stroke
				(width 0.1)
				(type default)
			)
			(layer "F.Fab")
		)
		(fp_line
			(start -0.12065 -0.305054)
			(end -0.12065 -0.2794)
			(stroke
				(width 0.1)
				(type default)
			)
			(layer "F.Fab")
		)
		(fp_line
			(start -0.12065 -0.2794)
			(end 0.12065 -0.2794)
			(stroke
				(width 0.1)
				(type default)
			)
			(layer "F.Fab")
		)
		(fp_line
			(start -0.12065 0.2794)
			(end -0.12065 0.3048)
			(stroke
				(width 0.1)
				(type default)
			)
			(layer "F.Fab")
		)
		(fp_line
			(start -0.12065 0.3048)
			(end -0.67945 0.3048)
			(stroke
				(width 0.1)
				(type default)
			)
			(layer "F.Fab")
		)
		(fp_line
			(start 0.120396 0.2794)
			(end -0.12065 0.2794)
			(stroke
				(width 0.1)
				(type default)
			)
			(layer "F.Fab")
		)
		(fp_line
			(start 0.120396 0.3048)
			(end 0.120396 0.2794)
			(stroke
				(width 0.1)
				(type default)
			)
			(layer "F.Fab")
		)
		(fp_line
			(start 0.12065 -0.3048)
			(end 0.67945 -0.3048)
			(stroke
				(width 0.1)
				(type default)
			)
			(layer "F.Fab")
		)
		(fp_line
			(start 0.12065 -0.2794)
			(end 0.12065 -0.3048)
			(stroke
				(width 0.1)
				(type default)
			)
			(layer "F.Fab")
		)
		(fp_line
			(start 0.67945 -0.3048)
			(end 0.67945 0.3048)
			(stroke
				(width 0.1)
				(type default)
			)
			(layer "F.Fab")
		)
		(fp_line
			(start 0.67945 0.3048)
			(end 0.120396 0.3048)
			(stroke
				(width 0.1)
				(type default)
			)
			(layer "F.Fab")
		)
		(pad "1" smd circle
			(at -0.40005 0)
			(size 0 0)
			(layers "F.Cu" "F.Mask" "F.Paste")
			(net "PCA9548_PCIE3_ADDR2")
		)
		(pad "2" smd circle
			(at 0.40005 0)
			(size 0 0)
			(layers "F.Cu" "F.Mask" "F.Paste")
			(net "GND")
		)
	)
	(footprint ""
		(layer "F.Cu")
		(at 441.470034 -69.861176 -90)
		(property "Reference" "Q56"
			(at -1.4478 3.592576 90)
			(unlocked yes)
			(layer "F.SilkS")
			(effects
				(font
					(size 0.7874 0.5842)
					(thickness 0.1524)
				)
			)
		)
		(property "Value" ""
			(at 0 0 270)
			(layer "F.Fab")
			(effects
				(font
					(size 1.27 1.27)
				)
			)
		)
		(duplicate_pad_numbers_are_jumpers no)
		(fp_line
			(start -2.350008 2.649982)
			(end -2.350008 2.413)
			(stroke
				(width 0.1524)
				(type default)
			)
			(layer "F.SilkS")
		)
		(fp_line
			(start 2.350008 2.649982)
			(end -2.350008 2.649982)
			(stroke
				(width 0.1524)
				(type default)
			)
			(layer "F.SilkS")
		)
		(fp_line
			(start 2.350008 2.4892)
			(end 2.350008 2.649982)
			(stroke
				(width 0.1524)
				(type default)
			)
			(layer "F.SilkS")
		)
		(fp_line
			(start -2.350008 -2.4384)
			(end -2.350008 -2.649982)
			(stroke
				(width 0.1524)
				(type default)
			)
			(layer "F.SilkS")
		)
		(fp_line
			(start -2.350008 -2.649982)
			(end 2.350008 -2.649982)
			(stroke
				(width 0.1524)
				(type default)
			)
			(layer "F.SilkS")
		)
		(fp_line
			(start 2.350008 -2.649982)
			(end 2.350008 -2.4892)
			(stroke
				(width 0.1524)
				(type default)
			)
			(layer "F.SilkS")
		)
		(fp_poly
			(pts
				(xy -2.58699 -3.70967) (xy -3.00609 -2.66827) (xy -3.38709 -3.70967)
			)
			(stroke
				(width 0)
				(type default)
			)
			(fill yes)
			(layer "F.SilkS")
		)
		(fp_line
			(start -2.350008 2.649982)
			(end -2.350008 -2.649982)
			(stroke
				(width 0.1)
				(type default)
			)
			(layer "F.Fab")
		)
		(fp_line
			(start 2.350008 2.649982)
			(end -2.350008 2.649982)
			(stroke
				(width 0.1)
				(type default)
			)
			(layer "F.Fab")
		)
		(fp_line
			(start -2.350008 -2.649982)
			(end 2.350008 -2.649982)
			(stroke
				(width 0.1)
				(type default)
			)
			(layer "F.Fab")
		)
		(fp_line
			(start 2.350008 -2.649982)
			(end 2.350008 2.649982)
			(stroke
				(width 0.1)
				(type default)
			)
			(layer "F.Fab")
		)
		(fp_poly
			(pts
				(xy -3.717544 -1.905) (xy -4.758944 -2.3241) (xy -4.758944 -1.524)
			)
			(stroke
				(width 0)
				(type default)
			)
			(fill yes)
			(layer "F.Fab")
		)
		(pad "1" smd rect
			(at -2.999994 -1.905 180)
			(size 0.7112 1.1684)
			(layers "F.Cu" "F.Mask" "F.Paste")
			(net "P3V3")
		)
		(pad "2" smd rect
			(at -2.999994 -0.635 180)
			(size 0.7112 1.1684)
			(layers "F.Cu" "F.Mask" "F.Paste")
			(net "P3V3")
		)
		(pad "3" smd rect
			(at -2.999994 0.635 180)
			(size 0.7112 1.1684)
			(layers "F.Cu" "F.Mask" "F.Paste")
			(net "P3V3")
		)
		(pad "4" smd rect
			(at -2.999994 1.905 180)
			(size 0.7112 1.1684)
			(layers "F.Cu" "F.Mask" "F.Paste")
			(net "SW_P3V3_EN_ISO_R")
		)
		(pad "5" smd circle
			(at 0.925068 0 180)
			(size 0 0)
			(layers "F.Cu" "F.Mask" "F.Paste")
			(net "P3V3_AUX")
		)
		(zone
			(layer "F.Cu")
			(hatch none 0.5)
			(connect_pads
				(clearance 0)
			)
			(min_thickness 0.25)
			(keepout
				(tracks not_allowed)
				(vias allowed)
				(pads allowed)
				(copperpour not_allowed)
				(footprints allowed)
			)
			(placement
				(enabled no)
				(sheetname "")
			)
			(fill
				(thermal_gap 0.5)
				(thermal_bridge_width 0.5)
				(island_removal_mode 0)
			)
			(polygon
				(pts
					(xy 443.629034 -71.308976) (xy 439.311034 -71.308976) (xy 438.828434 -71.308976) (xy 438.828434 -72.210676)
					(xy 444.111634 -72.210676) (xy 444.111634 -71.571104) (xy 443.849506 -71.308976)
				)
			)
		)
	)
	(footprint ""
		(layer "F.Cu")
		(at 156.30779 -103.738934 90)
		(property "Reference" "C1873"
			(at 0 0 90)
			(layer "F.SilkS")
			(hide yes)
			(effects
				(font
					(size 1.27 1.27)
				)
			)
		)
		(property "Value" ""
			(at 0 0 90)
			(layer "F.Fab")
			(effects
				(font
					(size 1.27 1.27)
				)
			)
		)
		(duplicate_pad_numbers_are_jumpers no)
		(fp_line
			(start 0.7874 -0.4064)
			(end 0.7874 0.4064)
			(stroke
				(width 0.1524)
				(type default)
			)
			(layer "F.SilkS")
		)
		(fp_line
			(start -0.7874 -0.4064)
			(end 0.7874 -0.4064)
			(stroke
				(width 0.1524)
				(type default)
			)
			(layer "F.SilkS")
		)
		(fp_line
			(start 0.7874 0.4064)
			(end -0.7874 0.4064)
			(stroke
				(width 0.1524)
				(type default)
			)
			(layer "F.SilkS")
		)
		(fp_line
			(start -0.7874 0.4064)
			(end -0.7874 -0.4064)
			(stroke
				(width 0.1524)
				(type default)
			)
			(layer "F.SilkS")
		)
		(fp_line
			(start -0.12065 -0.305054)
			(end -0.12065 -0.2794)
			(stroke
				(width 0.1)
				(type default)
			)
			(layer "F.Fab")
		)
		(fp_line
			(start -0.67945 -0.305054)
			(end -0.12065 -0.305054)
			(stroke
				(width 0.1)
				(type default)
			)
			(layer "F.Fab")
		)
		(fp_line
			(start 0.67945 -0.3048)
			(end 0.67945 0.3048)
			(stroke
				(width 0.1)
				(type default)
			)
			(layer "F.Fab")
		)
		(fp_line
			(start 0.12065 -0.3048)
			(end 0.67945 -0.3048)
			(stroke
				(width 0.1)
				(type default)
			)
			(layer "F.Fab")
		)
		(fp_line
			(start 0.12065 -0.2794)
			(end 0.12065 -0.3048)
			(stroke
				(width 0.1)
				(type default)
			)
			(layer "F.Fab")
		)
		(fp_line
			(start -0.12065 -0.2794)
			(end 0.12065 -0.2794)
			(stroke
				(width 0.1)
				(type default)
			)
			(layer "F.Fab")
		)
		(fp_line
			(start 0.120396 0.2794)
			(end -0.12065 0.2794)
			(stroke
				(width 0.1)
				(type default)
			)
			(layer "F.Fab")
		)
		(fp_line
			(start -0.12065 0.2794)
			(end -0.12065 0.3048)
			(stroke
				(width 0.1)
				(type default)
			)
			(layer "F.Fab")
		)
		(fp_line
			(start 0.67945 0.3048)
			(end 0.120396 0.3048)
			(stroke
				(width 0.1)
				(type default)
			)
			(layer "F.Fab")
		)
		(fp_line
			(start 0.120396 0.3048)
			(end 0.120396 0.2794)
			(stroke
				(width 0.1)
				(type default)
			)
			(layer "F.Fab")
		)
		(fp_line
			(start -0.12065 0.3048)
			(end -0.67945 0.3048)
			(stroke
				(width 0.1)
				(type default)
			)
			(layer "F.Fab")
		)
		(fp_line
			(start -0.67945 0.3048)
			(end -0.67945 -0.305054)
			(stroke
				(width 0.1)
				(type default)
			)
			(layer "F.Fab")
		)
		(pad "1" smd circle
			(at -0.40005 0 90)
			(size 0 0)
			(layers "F.Cu" "F.Mask" "F.Paste")
			(net "P3V3_AUX")
		)
		(pad "2" smd circle
			(at 0.40005 0 90)
			(size 0 0)
			(layers "F.Cu" "F.Mask" "F.Paste")
			(net "GND")
		)
	)
	(footprint ""
		(layer "F.Cu")
		(at 80.913478 -23.317962)
		(property "Reference" "PC2150"
			(at 0 0 0)
			(layer "F.SilkS")
			(hide yes)
			(effects
				(font
					(size 1.27 1.27)
				)
			)
		)
		(property "Value" ""
			(at 0 0 0)
			(layer "F.Fab")
			(effects
				(font
					(size 1.27 1.27)
				)
			)
		)
		(duplicate_pad_numbers_are_jumpers no)
		(fp_line
			(start -0.7874 -0.4064)
			(end 0.7874 -0.4064)
			(stroke
				(width 0.1524)
				(type default)
			)
			(layer "F.SilkS")
		)
		(fp_line
			(start -0.7874 0.4064)
			(end -0.7874 -0.4064)
			(stroke
				(width 0.1524)
				(type default)
			)
			(layer "F.SilkS")
		)
		(fp_line
			(start 0.7874 -0.4064)
			(end 0.7874 0.4064)
			(stroke
				(width 0.1524)
				(type default)
			)
			(layer "F.SilkS")
		)
		(fp_line
			(start 0.7874 0.4064)
			(end -0.7874 0.4064)
			(stroke
				(width 0.1524)
				(type default)
			)
			(layer "F.SilkS")
		)
		(fp_line
			(start -0.67945 -0.305054)
			(end -0.12065 -0.305054)
			(stroke
				(width 0.1)
				(type default)
			)
			(layer "F.Fab")
		)
		(fp_line
			(start -0.67945 0.3048)
			(end -0.67945 -0.305054)
			(stroke
				(width 0.1)
				(type default)
			)
			(layer "F.Fab")
		)
		(fp_line
			(start -0.12065 -0.305054)
			(end -0.12065 -0.2794)
			(stroke
				(width 0.1)
				(type default)
			)
			(layer "F.Fab")
		)
		(fp_line
			(start -0.12065 -0.2794)
			(end 0.12065 -0.2794)
			(stroke
				(width 0.1)
				(type default)
			)
			(layer "F.Fab")
		)
		(fp_line
			(start -0.12065 0.2794)
			(end -0.12065 0.3048)
			(stroke
				(width 0.1)
				(type default)
			)
			(layer "F.Fab")
		)
		(fp_line
			(start -0.12065 0.3048)
			(end -0.67945 0.3048)
			(stroke
				(width 0.1)
				(type default)
			)
			(layer "F.Fab")
		)
		(fp_line
			(start 0.120396 0.2794)
			(end -0.12065 0.2794)
			(stroke
				(width 0.1)
				(type default)
			)
			(layer "F.Fab")
		)
		(fp_line
			(start 0.120396 0.3048)
			(end 0.120396 0.2794)
			(stroke
				(width 0.1)
				(type default)
			)
			(layer "F.Fab")
		)
		(fp_line
			(start 0.12065 -0.3048)
			(end 0.67945 -0.3048)
			(stroke
				(width 0.1)
				(type default)
			)
			(layer "F.Fab")
		)
		(fp_line
			(start 0.12065 -0.2794)
			(end 0.12065 -0.3048)
			(stroke
				(width 0.1)
				(type default)
			)
			(layer "F.Fab")
		)
		(fp_line
			(start 0.67945 -0.3048)
			(end 0.67945 0.3048)
			(stroke
				(width 0.1)
				(type default)
			)
			(layer "F.Fab")
		)
		(fp_line
			(start 0.67945 0.3048)
			(end 0.120396 0.3048)
			(stroke
				(width 0.1)
				(type default)
			)
			(layer "F.Fab")
		)
		(pad "1" smd circle
			(at -0.40005 0)
			(size 0 0)
			(layers "F.Cu" "F.Mask" "F.Paste")
			(net "P12V_OCP_GATE_2")
		)
		(pad "2" smd circle
			(at 0.40005 0)
			(size 0 0)
			(layers "F.Cu" "F.Mask" "F.Paste")
			(net "GND")
		)
	)
	(footprint ""
		(layer "F.Cu")
		(at 100.884736 -127.787654 -90)
		(property "Reference" "R1457"
			(at 0 0 270)
			(layer "F.SilkS")
			(hide yes)
			(effects
				(font
					(size 1.27 1.27)
				)
			)
		)
		(property "Value" ""
			(at 0 0 270)
			(layer "F.Fab")
			(effects
				(font
					(size 1.27 1.27)
				)
			)
		)
		(duplicate_pad_numbers_are_jumpers no)
		(fp_line
			(start -0.7874 0.4064)
			(end -0.7874 -0.4064)
			(stroke
				(width 0.1524)
				(type default)
			)
			(layer "F.SilkS")
		)
		(fp_line
			(start 0.7874 0.4064)
			(end -0.7874 0.4064)
			(stroke
				(width 0.1524)
				(type default)
			)
			(layer "F.SilkS")
		)
		(fp_line
			(start -0.7874 -0.4064)
			(end 0.7874 -0.4064)
			(stroke
				(width 0.1524)
				(type default)
			)
			(layer "F.SilkS")
		)
		(fp_line
			(start 0.7874 -0.4064)
			(end 0.7874 0.4064)
			(stroke
				(width 0.1524)
				(type default)
			)
			(layer "F.SilkS")
		)
		(fp_line
			(start -0.67945 0.3048)
			(end -0.67945 -0.305054)
			(stroke
				(width 0.1)
				(type default)
			)
			(layer "F.Fab")
		)
		(fp_line
			(start -0.12065 0.3048)
			(end -0.67945 0.3048)
			(stroke
				(width 0.1)
				(type default)
			)
			(layer "F.Fab")
		)
		(fp_line
			(start 0.120396 0.3048)
			(end 0.120396 0.2794)
			(stroke
				(width 0.1)
				(type default)
			)
			(layer "F.Fab")
		)
		(fp_line
			(start 0.67945 0.3048)
			(end 0.120396 0.3048)
			(stroke
				(width 0.1)
				(type default)
			)
			(layer "F.Fab")
		)
		(fp_line
			(start -0.12065 0.2794)
			(end -0.12065 0.3048)
			(stroke
				(width 0.1)
				(type default)
			)
			(layer "F.Fab")
		)
		(fp_line
			(start 0.120396 0.2794)
			(end -0.12065 0.2794)
			(stroke
				(width 0.1)
				(type default)
			)
			(layer "F.Fab")
		)
		(fp_line
			(start -0.12065 -0.2794)
			(end 0.12065 -0.2794)
			(stroke
				(width 0.1)
				(type default)
			)
			(layer "F.Fab")
		)
		(fp_line
			(start 0.12065 -0.2794)
			(end 0.12065 -0.3048)
			(stroke
				(width 0.1)
				(type default)
			)
			(layer "F.Fab")
		)
		(fp_line
			(start 0.12065 -0.3048)
			(end 0.67945 -0.3048)
			(stroke
				(width 0.1)
				(type default)
			)
			(layer "F.Fab")
		)
		(fp_line
			(start 0.67945 -0.3048)
			(end 0.67945 0.3048)
			(stroke
				(width 0.1)
				(type default)
			)
			(layer "F.Fab")
		)
		(fp_line
			(start -0.67945 -0.305054)
			(end -0.12065 -0.305054)
			(stroke
				(width 0.1)
				(type default)
			)
			(layer "F.Fab")
		)
		(fp_line
			(start -0.12065 -0.305054)
			(end -0.12065 -0.2794)
			(stroke
				(width 0.1)
				(type default)
			)
			(layer "F.Fab")
		)
		(pad "1" smd circle
			(at -0.40005 0 270)
			(size 0 0)
			(layers "F.Cu" "F.Mask" "F.Paste")
			(net "P1V8_AUX")
		)
		(pad "2" smd circle
			(at 0.40005 0 270)
			(size 0 0)
			(layers "F.Cu" "F.Mask" "F.Paste")
			(net "PWRGD_P12V_MEM_CPU0")
		)
	)
	(footprint ""
		(layer "F.Cu")
		(at 461.916526 -100.470208)
		(property "Reference" "C639"
			(at 0 0 0)
			(layer "F.SilkS")
			(hide yes)
			(effects
				(font
					(size 1.27 1.27)
				)
			)
		)
		(property "Value" ""
			(at 0 0 0)
			(layer "F.Fab")
			(effects
				(font
					(size 1.27 1.27)
				)
			)
		)
		(duplicate_pad_numbers_are_jumpers no)
		(fp_line
			(start -0.7874 -0.4064)
			(end 0.7874 -0.4064)
			(stroke
				(width 0.1524)
				(type default)
			)
			(layer "F.SilkS")
		)
		(fp_line
			(start -0.7874 0.4064)
			(end -0.7874 -0.4064)
			(stroke
				(width 0.1524)
				(type default)
			)
			(layer "F.SilkS")
		)
		(fp_line
			(start 0.7874 -0.4064)
			(end 0.7874 0.4064)
			(stroke
				(width 0.1524)
				(type default)
			)
			(layer "F.SilkS")
		)
		(fp_line
			(start 0.7874 0.4064)
			(end -0.7874 0.4064)
			(stroke
				(width 0.1524)
				(type default)
			)
			(layer "F.SilkS")
		)
		(fp_line
			(start -0.67945 -0.305054)
			(end -0.12065 -0.305054)
			(stroke
				(width 0.1)
				(type default)
			)
			(layer "F.Fab")
		)
		(fp_line
			(start -0.67945 0.3048)
			(end -0.67945 -0.305054)
			(stroke
				(width 0.1)
				(type default)
			)
			(layer "F.Fab")
		)
		(fp_line
			(start -0.12065 -0.305054)
			(end -0.12065 -0.2794)
			(stroke
				(width 0.1)
				(type default)
			)
			(layer "F.Fab")
		)
		(fp_line
			(start -0.12065 -0.2794)
			(end 0.12065 -0.2794)
			(stroke
				(width 0.1)
				(type default)
			)
			(layer "F.Fab")
		)
		(fp_line
			(start -0.12065 0.2794)
			(end -0.12065 0.3048)
			(stroke
				(width 0.1)
				(type default)
			)
			(layer "F.Fab")
		)
		(fp_line
			(start -0.12065 0.3048)
			(end -0.67945 0.3048)
			(stroke
				(width 0.1)
				(type default)
			)
			(layer "F.Fab")
		)
		(fp_line
			(start 0.120396 0.2794)
			(end -0.12065 0.2794)
			(stroke
				(width 0.1)
				(type default)
			)
			(layer "F.Fab")
		)
		(fp_line
			(start 0.120396 0.3048)
			(end 0.120396 0.2794)
			(stroke
				(width 0.1)
				(type default)
			)
			(layer "F.Fab")
		)
		(fp_line
			(start 0.12065 -0.3048)
			(end 0.67945 -0.3048)
			(stroke
				(width 0.1)
				(type default)
			)
			(layer "F.Fab")
		)
		(fp_line
			(start 0.12065 -0.2794)
			(end 0.12065 -0.3048)
			(stroke
				(width 0.1)
				(type default)
			)
			(layer "F.Fab")
		)
		(fp_line
			(start 0.67945 -0.3048)
			(end 0.67945 0.3048)
			(stroke
				(width 0.1)
				(type default)
			)
			(layer "F.Fab")
		)
		(fp_line
			(start 0.67945 0.3048)
			(end 0.120396 0.3048)
			(stroke
				(width 0.1)
				(type default)
			)
			(layer "F.Fab")
		)
		(pad "1" smd circle
			(at -0.40005 0)
			(size 0 0)
			(layers "F.Cu" "F.Mask" "F.Paste")
			(net "P3V3_AUX")
		)
		(pad "2" smd circle
			(at 0.40005 0)
			(size 0 0)
			(layers "F.Cu" "F.Mask" "F.Paste")
			(net "GND")
		)
	)
	(footprint ""
		(layer "F.Cu")
		(at 256.210308 -110.090204)
		(property "Reference" "C1823"
			(at 0 0 0)
			(layer "F.SilkS")
			(hide yes)
			(effects
				(font
					(size 1.27 1.27)
				)
			)
		)
		(property "Value" ""
			(at 0 0 0)
			(layer "F.Fab")
			(effects
				(font
					(size 1.27 1.27)
				)
			)
		)
		(duplicate_pad_numbers_are_jumpers no)
		(fp_line
			(start -0.7874 -0.4064)
			(end 0.7874 -0.4064)
			(stroke
				(width 0.1524)
				(type default)
			)
			(layer "F.SilkS")
		)
		(fp_line
			(start -0.7874 0.4064)
			(end -0.7874 -0.4064)
			(stroke
				(width 0.1524)
				(type default)
			)
			(layer "F.SilkS")
		)
		(fp_line
			(start 0.7874 -0.4064)
			(end 0.7874 0.4064)
			(stroke
				(width 0.1524)
				(type default)
			)
			(layer "F.SilkS")
		)
		(fp_line
			(start 0.7874 0.4064)
			(end -0.7874 0.4064)
			(stroke
				(width 0.1524)
				(type default)
			)
			(layer "F.SilkS")
		)
		(fp_line
			(start -0.67945 -0.305054)
			(end -0.12065 -0.305054)
			(stroke
				(width 0.1)
				(type default)
			)
			(layer "F.Fab")
		)
		(fp_line
			(start -0.67945 0.3048)
			(end -0.67945 -0.305054)
			(stroke
				(width 0.1)
				(type default)
			)
			(layer "F.Fab")
		)
		(fp_line
			(start -0.12065 -0.305054)
			(end -0.12065 -0.2794)
			(stroke
				(width 0.1)
				(type default)
			)
			(layer "F.Fab")
		)
		(fp_line
			(start -0.12065 -0.2794)
			(end 0.12065 -0.2794)
			(stroke
				(width 0.1)
				(type default)
			)
			(layer "F.Fab")
		)
		(fp_line
			(start -0.12065 0.2794)
			(end -0.12065 0.3048)
			(stroke
				(width 0.1)
				(type default)
			)
			(layer "F.Fab")
		)
		(fp_line
			(start -0.12065 0.3048)
			(end -0.67945 0.3048)
			(stroke
				(width 0.1)
				(type default)
			)
			(layer "F.Fab")
		)
		(fp_line
			(start 0.120396 0.2794)
			(end -0.12065 0.2794)
			(stroke
				(width 0.1)
				(type default)
			)
			(layer "F.Fab")
		)
		(fp_line
			(start 0.120396 0.3048)
			(end 0.120396 0.2794)
			(stroke
				(width 0.1)
				(type default)
			)
			(layer "F.Fab")
		)
		(fp_line
			(start 0.12065 -0.3048)
			(end 0.67945 -0.3048)
			(stroke
				(width 0.1)
				(type default)
			)
			(layer "F.Fab")
		)
		(fp_line
			(start 0.12065 -0.2794)
			(end 0.12065 -0.3048)
			(stroke
				(width 0.1)
				(type default)
			)
			(layer "F.Fab")
		)
		(fp_line
			(start 0.67945 -0.3048)
			(end 0.67945 0.3048)
			(stroke
				(width 0.1)
				(type default)
			)
			(layer "F.Fab")
		)
		(fp_line
			(start 0.67945 0.3048)
			(end 0.120396 0.3048)
			(stroke
				(width 0.1)
				(type default)
			)
			(layer "F.Fab")
		)
		(pad "1" smd circle
			(at -0.40005 0)
			(size 0 0)
			(layers "F.Cu" "F.Mask" "F.Paste")
			(net "P3V3_AUX")
		)
		(pad "2" smd circle
			(at 0.40005 0)
			(size 0 0)
			(layers "F.Cu" "F.Mask" "F.Paste")
			(net "GND")
		)
	)
	(footprint ""
		(layer "F.Cu")
		(at 503.645424 -457.3397 90)
		(property "Reference" "X9008"
			(at -2.017268 1.17475 0)
			(unlocked yes)
			(layer "F.SilkS")
			(effects
				(font
					(size 0.7874 0.5842)
					(thickness 0.1524)
				)
				(justify left)
			)
		)
		(property "Value" ""
			(at 0 0 90)
			(layer "F.Fab")
			(effects
				(font
					(size 1.27 1.27)
				)
			)
		)
		(property "User Part Number" "N_A"
			(at 1.30175 1.27 180)
			(unlocked yes)
			(layer "Cmts.User")
			(hide yes)
			(effects
				(font
					(size 0.635 0.4064)
					(thickness 0.1524)
				)
			)
		)
		(property "Device Type" "TP_TDR_4P_FTS_TH-TP_TDR_4P_DIP,EMPTY,TP15"
			(at 1.30175 1.27 180)
			(unlocked yes)
			(layer "F.Fab")
			(hide yes)
			(effects
				(font
					(size 0.635 0.4064)
					(thickness 0.1524)
				)
			)
		)
		(duplicate_pad_numbers_are_jumpers no)
		(fp_line
			(start 2.54 -1.27)
			(end 0 -1.27)
			(stroke
				(width 0.1524)
				(type default)
			)
			(layer "F.SilkS")
		)
		(fp_line
			(start 0 -1.27)
			(end 0 -0.635)
			(stroke
				(width 0.1524)
				(type default)
			)
			(layer "F.SilkS")
		)
		(fp_line
			(start 2.54 -1.1303)
			(end 2.54 -1.27)
			(stroke
				(width 0.1524)
				(type default)
			)
			(layer "F.SilkS")
		)
		(fp_line
			(start 0 0.635)
			(end 0 1.905)
			(stroke
				(width 0.1524)
				(type default)
			)
			(layer "F.SilkS")
		)
		(fp_line
			(start 2.54 1.4097)
			(end 2.54 1.1303)
			(stroke
				(width 0.1524)
				(type default)
			)
			(layer "F.SilkS")
		)
		(fp_line
			(start 0 3.175)
			(end 0 3.81)
			(stroke
				(width 0.1524)
				(type default)
			)
			(layer "F.SilkS")
		)
		(fp_line
			(start 2.54 3.81)
			(end 2.54 3.6703)
			(stroke
				(width 0.1524)
				(type default)
			)
			(layer "F.SilkS")
		)
		(fp_line
			(start 0 3.81)
			(end 2.54 3.81)
			(stroke
				(width 0.1524)
				(type default)
			)
			(layer "F.SilkS")
		)
		(fp_poly
			(pts
				(xy -2.285746 -0.762) (xy -0.761746 0) (xy -2.285746 0.762)
			)
			(stroke
				(width 0)
				(type default)
			)
			(fill yes)
			(layer "F.SilkS")
		)
		(fp_line
			(start 2.54 -1.27)
			(end 0 -1.27)
			(stroke
				(width 0.1)
				(type default)
			)
			(layer "F.Fab")
		)
		(fp_line
			(start 0 -1.27)
			(end 0 3.81)
			(stroke
				(width 0.1)
				(type default)
			)
			(layer "F.Fab")
		)
		(fp_line
			(start 2.54 3.81)
			(end 2.54 -1.27)
			(stroke
				(width 0.1)
				(type default)
			)
			(layer "F.Fab")
		)
		(fp_line
			(start 0 3.81)
			(end 2.54 3.81)
			(stroke
				(width 0.1)
				(type default)
			)
			(layer "F.Fab")
		)
		(fp_poly
			(pts
				(xy -0.761746 0) (xy -2.285746 -0.762) (xy -2.285746 0.762)
			)
			(stroke
				(width 0)
				(type default)
			)
			(fill yes)
			(layer "F.Fab")
		)
		(pad "1" thru_hole circle
			(at 0 0 90)
			(size 1.0033 1.0033)
			(drill 0.249936)
			(layers "*.Cu" "*.Mask")
			(remove_unused_layers no)
			(net "TDR_DIFF_85_NECK_IN1_DN")
			(clearance 0.10795)
			(thermal_gap 0.10795)
			(padstack
				(mode front_inner_back)
				(layer "Inner"
					(shape circle)
					(size 0.8001 0.8001)
					(clearance 0.1524)
				)
				(layer "B.Cu"
					(shape circle)
					(size 1.0033 1.0033)
					(clearance 0.10795)
				)
			)
		)
		(pad "2" thru_hole circle
			(at 2.54 0 90)
			(size 1.9939 1.9939)
			(drill 0.249936)
			(layers "*.Cu" "*.Mask")
			(remove_unused_layers no)
			(net "T1_GND")
			(clearance 0.10795)
			(thermal_gap 0.10795)
			(padstack
				(mode front_inner_back)
				(layer "Inner"
					(shape circle)
					(size 0.8001 0.8001)
					(clearance 0.1524)
				)
				(layer "B.Cu"
					(shape circle)
					(size 1.9939 1.9939)
					(clearance 0.10795)
				)
			)
		)
		(pad "3" thru_hole circle
			(at 2.54 2.54 90)
			(size 1.9939 1.9939)
			(drill 0.249936)
			(layers "*.Cu" "*.Mask")
			(remove_unused_layers no)
			(net "T1_GND")
			(clearance 0.10795)
			(thermal_gap 0.10795)
			(padstack
				(mode front_inner_back)
				(layer "Inner"
					(shape circle)
					(size 0.8001 0.8001)
					(clearance 0.1524)
				)
				(layer "B.Cu"
					(shape circle)
					(size 1.9939 1.9939)
					(clearance 0.10795)
				)
			)
		)
		(pad "4" thru_hole circle
			(at 0 2.54 90)
			(size 1.0033 1.0033)
			(drill 0.249936)
			(layers "*.Cu" "*.Mask")
			(remove_unused_layers no)
			(net "TDR_DIFF_85_NECK_IN1_DP")
			(clearance 0.10795)
			(thermal_gap 0.10795)
			(padstack
				(mode front_inner_back)
				(layer "Inner"
					(shape circle)
					(size 0.8001 0.8001)
					(clearance 0.1524)
				)
				(layer "B.Cu"
					(shape circle)
					(size 1.0033 1.0033)
					(clearance 0.10795)
				)
			)
		)
	)
	(footprint ""
		(layer "F.Cu")
		(at 62.00775 -168.843452 90)
		(property "Reference" "PC128_6"
			(at 0 0 90)
			(layer "F.SilkS")
			(hide yes)
			(effects
				(font
					(size 1.27 1.27)
				)
			)
		)
		(property "Value" ""
			(at 0 0 90)
			(layer "F.Fab")
			(effects
				(font
					(size 1.27 1.27)
				)
			)
		)
		(duplicate_pad_numbers_are_jumpers no)
		(fp_line
			(start 0.7874 -0.4064)
			(end 0.7874 0.4064)
			(stroke
				(width 0.1524)
				(type default)
			)
			(layer "F.SilkS")
		)
		(fp_line
			(start -0.7874 -0.4064)
			(end 0.7874 -0.4064)
			(stroke
				(width 0.1524)
				(type default)
			)
			(layer "F.SilkS")
		)
		(fp_line
			(start 0.7874 0.4064)
			(end -0.7874 0.4064)
			(stroke
				(width 0.1524)
				(type default)
			)
			(layer "F.SilkS")
		)
		(fp_line
			(start -0.7874 0.4064)
			(end -0.7874 -0.4064)
			(stroke
				(width 0.1524)
				(type default)
			)
			(layer "F.SilkS")
		)
		(fp_line
			(start -0.12065 -0.305054)
			(end -0.12065 -0.2794)
			(stroke
				(width 0.1)
				(type default)
			)
			(layer "F.Fab")
		)
		(fp_line
			(start -0.67945 -0.305054)
			(end -0.12065 -0.305054)
			(stroke
				(width 0.1)
				(type default)
			)
			(layer "F.Fab")
		)
		(fp_line
			(start 0.67945 -0.3048)
			(end 0.67945 0.3048)
			(stroke
				(width 0.1)
				(type default)
			)
			(layer "F.Fab")
		)
		(fp_line
			(start 0.12065 -0.3048)
			(end 0.67945 -0.3048)
			(stroke
				(width 0.1)
				(type default)
			)
			(layer "F.Fab")
		)
		(fp_line
			(start 0.12065 -0.2794)
			(end 0.12065 -0.3048)
			(stroke
				(width 0.1)
				(type default)
			)
			(layer "F.Fab")
		)
		(fp_line
			(start -0.12065 -0.2794)
			(end 0.12065 -0.2794)
			(stroke
				(width 0.1)
				(type default)
			)
			(layer "F.Fab")
		)
		(fp_line
			(start 0.120396 0.2794)
			(end -0.12065 0.2794)
			(stroke
				(width 0.1)
				(type default)
			)
			(layer "F.Fab")
		)
		(fp_line
			(start -0.12065 0.2794)
			(end -0.12065 0.3048)
			(stroke
				(width 0.1)
				(type default)
			)
			(layer "F.Fab")
		)
		(fp_line
			(start 0.67945 0.3048)
			(end 0.120396 0.3048)
			(stroke
				(width 0.1)
				(type default)
			)
			(layer "F.Fab")
		)
		(fp_line
			(start 0.120396 0.3048)
			(end 0.120396 0.2794)
			(stroke
				(width 0.1)
				(type default)
			)
			(layer "F.Fab")
		)
		(fp_line
			(start -0.12065 0.3048)
			(end -0.67945 0.3048)
			(stroke
				(width 0.1)
				(type default)
			)
			(layer "F.Fab")
		)
		(fp_line
			(start -0.67945 0.3048)
			(end -0.67945 -0.305054)
			(stroke
				(width 0.1)
				(type default)
			)
			(layer "F.Fab")
		)
		(pad "1" smd circle
			(at -0.40005 0 90)
			(size 0 0)
			(layers "F.Cu" "F.Mask" "F.Paste")
			(net "SW_P12V_AUX_PVDDCR_CPU0_P1_FLT")
		)
		(pad "2" smd circle
			(at 0.40005 0 90)
			(size 0 0)
			(layers "F.Cu" "F.Mask" "F.Paste")
			(net "GND")
		)
	)
	(footprint ""
		(layer "F.Cu")
		(at 391.616692 -378.95403 -90)
		(property "Reference" "C875"
			(at 0 0 270)
			(layer "F.SilkS")
			(hide yes)
			(effects
				(font
					(size 1.27 1.27)
				)
			)
		)
		(property "Value" ""
			(at 0 0 270)
			(layer "F.Fab")
			(effects
				(font
					(size 1.27 1.27)
				)
			)
		)
		(duplicate_pad_numbers_are_jumpers no)
		(fp_line
			(start -0.299974 0.150114)
			(end -0.299974 -0.150114)
			(stroke
				(width 0.1)
				(type default)
			)
			(layer "F.Fab")
		)
		(fp_line
			(start 0.299974 0.150114)
			(end -0.299974 0.150114)
			(stroke
				(width 0.1)
				(type default)
			)
			(layer "F.Fab")
		)
		(fp_line
			(start -0.299974 -0.150114)
			(end 0.299974 -0.150114)
			(stroke
				(width 0.1)
				(type default)
			)
			(layer "F.Fab")
		)
		(fp_line
			(start 0.299974 -0.150114)
			(end 0.299974 0.150114)
			(stroke
				(width 0.1)
				(type default)
			)
			(layer "F.Fab")
		)
		(pad "1" smd rect
			(at -0.2667 0 270)
			(size 0.3048 0.381)
			(layers "F.Cu" "F.Mask" "F.Paste")
			(net "P5E_CPU0_P3_TX_C_DP<13>")
		)
		(pad "2" smd rect
			(at 0.2667 0 270)
			(size 0.3048 0.381)
			(layers "F.Cu" "F.Mask" "F.Paste")
			(net "P5E_CPU0_P3_TX_DP<13>")
		)
	)
	(footprint ""
		(layer "F.Cu")
		(at 167.132 -115.280948 180)
		(property "Reference" "R64"
			(at 0 0 180)
			(layer "F.SilkS")
			(hide yes)
			(effects
				(font
					(size 1.27 1.27)
				)
			)
		)
		(property "Value" ""
			(at 0 0 180)
			(layer "F.Fab")
			(effects
				(font
					(size 1.27 1.27)
				)
			)
		)
		(duplicate_pad_numbers_are_jumpers no)
		(fp_line
			(start 0.7874 0.4064)
			(end -0.7874 0.4064)
			(stroke
				(width 0.1524)
				(type default)
			)
			(layer "F.SilkS")
		)
		(fp_line
			(start 0.7874 -0.4064)
			(end 0.7874 0.4064)
			(stroke
				(width 0.1524)
				(type default)
			)
			(layer "F.SilkS")
		)
		(fp_line
			(start -0.7874 0.4064)
			(end -0.7874 -0.4064)
			(stroke
				(width 0.1524)
				(type default)
			)
			(layer "F.SilkS")
		)
		(fp_line
			(start -0.7874 -0.4064)
			(end 0.7874 -0.4064)
			(stroke
				(width 0.1524)
				(type default)
			)
			(layer "F.SilkS")
		)
		(fp_line
			(start 0.67945 0.3048)
			(end 0.120396 0.3048)
			(stroke
				(width 0.1)
				(type default)
			)
			(layer "F.Fab")
		)
		(fp_line
			(start 0.67945 -0.3048)
			(end 0.67945 0.3048)
			(stroke
				(width 0.1)
				(type default)
			)
			(layer "F.Fab")
		)
		(fp_line
			(start 0.12065 -0.2794)
			(end 0.12065 -0.3048)
			(stroke
				(width 0.1)
				(type default)
			)
			(layer "F.Fab")
		)
		(fp_line
			(start 0.12065 -0.3048)
			(end 0.67945 -0.3048)
			(stroke
				(width 0.1)
				(type default)
			)
			(layer "F.Fab")
		)
		(fp_line
			(start 0.120396 0.3048)
			(end 0.120396 0.2794)
			(stroke
				(width 0.1)
				(type default)
			)
			(layer "F.Fab")
		)
		(fp_line
			(start 0.120396 0.2794)
			(end -0.12065 0.2794)
			(stroke
				(width 0.1)
				(type default)
			)
			(layer "F.Fab")
		)
		(fp_line
			(start -0.12065 0.3048)
			(end -0.67945 0.3048)
			(stroke
				(width 0.1)
				(type default)
			)
			(layer "F.Fab")
		)
		(fp_line
			(start -0.12065 0.2794)
			(end -0.12065 0.3048)
			(stroke
				(width 0.1)
				(type default)
			)
			(layer "F.Fab")
		)
		(fp_line
			(start -0.12065 -0.2794)
			(end 0.12065 -0.2794)
			(stroke
				(width 0.1)
				(type default)
			)
			(layer "F.Fab")
		)
		(fp_line
			(start -0.12065 -0.305054)
			(end -0.12065 -0.2794)
			(stroke
				(width 0.1)
				(type default)
			)
			(layer "F.Fab")
		)
		(fp_line
			(start -0.67945 0.3048)
			(end -0.67945 -0.305054)
			(stroke
				(width 0.1)
				(type default)
			)
			(layer "F.Fab")
		)
		(fp_line
			(start -0.67945 -0.305054)
			(end -0.12065 -0.305054)
			(stroke
				(width 0.1)
				(type default)
			)
			(layer "F.Fab")
		)
		(pad "1" smd circle
			(at -0.40005 0 180)
			(size 0 0)
			(layers "F.Cu" "F.Mask" "F.Paste")
			(net "SCM_SYS_PWRBTN_N")
		)
		(pad "2" smd circle
			(at 0.40005 0 180)
			(size 0 0)
			(layers "F.Cu" "F.Mask" "F.Paste")
			(net "P3V3_AUX")
		)
	)
	(footprint ""
		(layer "F.Cu")
		(at 171.196 -114.264948 180)
		(property "Reference" "R160"
			(at 0 0 180)
			(layer "F.SilkS")
			(hide yes)
			(effects
				(font
					(size 1.27 1.27)
				)
			)
		)
		(property "Value" ""
			(at 0 0 180)
			(layer "F.Fab")
			(effects
				(font
					(size 1.27 1.27)
				)
			)
		)
		(duplicate_pad_numbers_are_jumpers no)
		(fp_line
			(start 0.7874 0.4064)
			(end -0.7874 0.4064)
			(stroke
				(width 0.1524)
				(type default)
			)
			(layer "F.SilkS")
		)
		(fp_line
			(start 0.7874 -0.4064)
			(end 0.7874 0.4064)
			(stroke
				(width 0.1524)
				(type default)
			)
			(layer "F.SilkS")
		)
		(fp_line
			(start -0.7874 0.4064)
			(end -0.7874 -0.4064)
			(stroke
				(width 0.1524)
				(type default)
			)
			(layer "F.SilkS")
		)
		(fp_line
			(start -0.7874 -0.4064)
			(end 0.7874 -0.4064)
			(stroke
				(width 0.1524)
				(type default)
			)
			(layer "F.SilkS")
		)
		(fp_line
			(start 0.67945 0.3048)
			(end 0.120396 0.3048)
			(stroke
				(width 0.1)
				(type default)
			)
			(layer "F.Fab")
		)
		(fp_line
			(start 0.67945 -0.3048)
			(end 0.67945 0.3048)
			(stroke
				(width 0.1)
				(type default)
			)
			(layer "F.Fab")
		)
		(fp_line
			(start 0.12065 -0.2794)
			(end 0.12065 -0.3048)
			(stroke
				(width 0.1)
				(type default)
			)
			(layer "F.Fab")
		)
		(fp_line
			(start 0.12065 -0.3048)
			(end 0.67945 -0.3048)
			(stroke
				(width 0.1)
				(type default)
			)
			(layer "F.Fab")
		)
		(fp_line
			(start 0.120396 0.3048)
			(end 0.120396 0.2794)
			(stroke
				(width 0.1)
				(type default)
			)
			(layer "F.Fab")
		)
		(fp_line
			(start 0.120396 0.2794)
			(end -0.12065 0.2794)
			(stroke
				(width 0.1)
				(type default)
			)
			(layer "F.Fab")
		)
		(fp_line
			(start -0.12065 0.3048)
			(end -0.67945 0.3048)
			(stroke
				(width 0.1)
				(type default)
			)
			(layer "F.Fab")
		)
		(fp_line
			(start -0.12065 0.2794)
			(end -0.12065 0.3048)
			(stroke
				(width 0.1)
				(type default)
			)
			(layer "F.Fab")
		)
		(fp_line
			(start -0.12065 -0.2794)
			(end 0.12065 -0.2794)
			(stroke
				(width 0.1)
				(type default)
			)
			(layer "F.Fab")
		)
		(fp_line
			(start -0.12065 -0.305054)
			(end -0.12065 -0.2794)
			(stroke
				(width 0.1)
				(type default)
			)
			(layer "F.Fab")
		)
		(fp_line
			(start -0.67945 0.3048)
			(end -0.67945 -0.305054)
			(stroke
				(width 0.1)
				(type default)
			)
			(layer "F.Fab")
		)
		(fp_line
			(start -0.67945 -0.305054)
			(end -0.12065 -0.305054)
			(stroke
				(width 0.1)
				(type default)
			)
			(layer "F.Fab")
		)
		(pad "1" smd circle
			(at -0.40005 0 180)
			(size 0 0)
			(layers "F.Cu" "F.Mask" "F.Paste")
			(net "JTAG_SCM_TRST_R_N")
		)
		(pad "2" smd circle
			(at 0.40005 0 180)
			(size 0 0)
			(layers "F.Cu" "F.Mask" "F.Paste")
			(net "JTAG_SCM_TRST_N")
		)
	)
	(footprint ""
		(layer "F.Cu")
		(at 323.637148 -40.144954)
		(property "Reference" "R3687"
			(at 0 0 0)
			(layer "F.SilkS")
			(hide yes)
			(effects
				(font
					(size 1.27 1.27)
				)
			)
		)
		(property "Value" ""
			(at 0 0 0)
			(layer "F.Fab")
			(effects
				(font
					(size 1.27 1.27)
				)
			)
		)
		(duplicate_pad_numbers_are_jumpers no)
		(fp_line
			(start -0.7874 -0.4064)
			(end 0.7874 -0.4064)
			(stroke
				(width 0.1524)
				(type default)
			)
			(layer "F.SilkS")
		)
		(fp_line
			(start -0.7874 0.4064)
			(end -0.7874 -0.4064)
			(stroke
				(width 0.1524)
				(type default)
			)
			(layer "F.SilkS")
		)
		(fp_line
			(start 0.7874 -0.4064)
			(end 0.7874 0.4064)
			(stroke
				(width 0.1524)
				(type default)
			)
			(layer "F.SilkS")
		)
		(fp_line
			(start 0.7874 0.4064)
			(end -0.7874 0.4064)
			(stroke
				(width 0.1524)
				(type default)
			)
			(layer "F.SilkS")
		)
		(fp_line
			(start -0.67945 -0.305054)
			(end -0.12065 -0.305054)
			(stroke
				(width 0.1)
				(type default)
			)
			(layer "F.Fab")
		)
		(fp_line
			(start -0.67945 0.3048)
			(end -0.67945 -0.305054)
			(stroke
				(width 0.1)
				(type default)
			)
			(layer "F.Fab")
		)
		(fp_line
			(start -0.12065 -0.305054)
			(end -0.12065 -0.2794)
			(stroke
				(width 0.1)
				(type default)
			)
			(layer "F.Fab")
		)
		(fp_line
			(start -0.12065 -0.2794)
			(end 0.12065 -0.2794)
			(stroke
				(width 0.1)
				(type default)
			)
			(layer "F.Fab")
		)
		(fp_line
			(start -0.12065 0.2794)
			(end -0.12065 0.3048)
			(stroke
				(width 0.1)
				(type default)
			)
			(layer "F.Fab")
		)
		(fp_line
			(start -0.12065 0.3048)
			(end -0.67945 0.3048)
			(stroke
				(width 0.1)
				(type default)
			)
			(layer "F.Fab")
		)
		(fp_line
			(start 0.120396 0.2794)
			(end -0.12065 0.2794)
			(stroke
				(width 0.1)
				(type default)
			)
			(layer "F.Fab")
		)
		(fp_line
			(start 0.120396 0.3048)
			(end 0.120396 0.2794)
			(stroke
				(width 0.1)
				(type default)
			)
			(layer "F.Fab")
		)
		(fp_line
			(start 0.12065 -0.3048)
			(end 0.67945 -0.3048)
			(stroke
				(width 0.1)
				(type default)
			)
			(layer "F.Fab")
		)
		(fp_line
			(start 0.12065 -0.2794)
			(end 0.12065 -0.3048)
			(stroke
				(width 0.1)
				(type default)
			)
			(layer "F.Fab")
		)
		(fp_line
			(start 0.67945 -0.3048)
			(end 0.67945 0.3048)
			(stroke
				(width 0.1)
				(type default)
			)
			(layer "F.Fab")
		)
		(fp_line
			(start 0.67945 0.3048)
			(end 0.120396 0.3048)
			(stroke
				(width 0.1)
				(type default)
			)
			(layer "F.Fab")
		)
		(pad "1" smd rect
			(at -0.40005 0 180)
			(size 0.4572 0.508)
			(layers "F.Cu" "F.Mask" "F.Paste")
			(net "P1V581_PDB_ADC")
		)
		(pad "2" smd rect
			(at 0.40005 0 180)
			(size 0.4572 0.508)
			(layers "F.Cu" "F.Mask" "F.Paste")
			(net "P3V3_PDB_AUX_ADC_MAM")
		)
	)
	(footprint ""
		(layer "F.Cu")
		(at 242.952016 -304.162206 90)
		(property "Reference" "PL6501"
			(at -7.490206 7.391654 90)
			(unlocked yes)
			(layer "F.SilkS")
			(effects
				(font
					(size 0.7874 0.5842)
					(thickness 0.1524)
				)
				(justify left)
			)
		)
		(property "Value" ""
			(at 0 0 90)
			(layer "F.Fab")
			(effects
				(font
					(size 1.27 1.27)
				)
			)
		)
		(duplicate_pad_numbers_are_jumpers no)
		(fp_line
			(start 7.4422 -6.400038)
			(end 7.4422 6.400038)
			(stroke
				(width 0.1524)
				(type default)
			)
			(layer "F.SilkS")
		)
		(fp_line
			(start -7.4422 -6.400038)
			(end 7.4422 -6.400038)
			(stroke
				(width 0.1524)
				(type default)
			)
			(layer "F.SilkS")
		)
		(fp_line
			(start 7.4422 6.400038)
			(end -7.4422 6.400038)
			(stroke
				(width 0.1524)
				(type default)
			)
			(layer "F.SilkS")
		)
		(fp_line
			(start -7.4422 6.400038)
			(end -7.4422 -6.400038)
			(stroke
				(width 0.1524)
				(type default)
			)
			(layer "F.SilkS")
		)
		(fp_line
			(start 6.938264 -6.400038)
			(end -6.862064 -6.400038)
			(stroke
				(width 0.1)
				(type default)
			)
			(layer "F.Fab")
		)
		(fp_line
			(start -6.862064 -6.400038)
			(end -6.862064 6.400038)
			(stroke
				(width 0.1)
				(type default)
			)
			(layer "F.Fab")
		)
		(fp_line
			(start 6.938264 6.400038)
			(end 6.938264 -6.400038)
			(stroke
				(width 0.1)
				(type default)
			)
			(layer "F.Fab")
		)
		(fp_line
			(start -6.862064 6.400038)
			(end 6.938264 6.400038)
			(stroke
				(width 0.1)
				(type default)
			)
			(layer "F.Fab")
		)
		(pad "1" smd rect
			(at -5.650484 0 90)
			(size 3.302 4.29768)
			(layers "F.Cu" "F.Mask" "F.Paste")
			(net "SW_P1V8_RETIMER_CPU0_SW")
		)
		(pad "2" smd rect
			(at 5.650484 0 90)
			(size 3.302 4.29768)
			(layers "F.Cu" "F.Mask" "F.Paste")
			(net "P1V8_CPU0_RT_1D")
		)
	)
	(footprint ""
		(layer "F.Cu")
		(at 290.15944 -397.589248)
		(property "Reference" "R837"
			(at 0 0 0)
			(layer "F.SilkS")
			(hide yes)
			(effects
				(font
					(size 1.27 1.27)
				)
			)
		)
		(property "Value" ""
			(at 0 0 0)
			(layer "F.Fab")
			(effects
				(font
					(size 1.27 1.27)
				)
			)
		)
		(duplicate_pad_numbers_are_jumpers no)
		(fp_line
			(start -0.32512 -0.175006)
			(end 0.32512 -0.175006)
			(stroke
				(width 0.1)
				(type default)
			)
			(layer "F.Fab")
		)
		(fp_line
			(start -0.32512 0.175006)
			(end -0.32512 -0.175006)
			(stroke
				(width 0.1)
				(type default)
			)
			(layer "F.Fab")
		)
		(fp_line
			(start 0.32512 -0.175006)
			(end 0.32512 0.175006)
			(stroke
				(width 0.1)
				(type default)
			)
			(layer "F.Fab")
		)
		(fp_line
			(start 0.32512 0.175006)
			(end -0.32512 0.175006)
			(stroke
				(width 0.1)
				(type default)
			)
			(layer "F.Fab")
		)
		(pad "1" smd rect
			(at -0.2667 0)
			(size 0.3048 0.381)
			(layers "F.Cu" "F.Mask" "F.Paste")
			(net "P1V8_CPU0_RT_1D")
		)
		(pad "2" smd rect
			(at 0.2667 0 180)
			(size 0.3048 0.381)
			(layers "F.Cu" "F.Mask" "F.Paste")
			(net "SMB_RT_CPU0_P1_ROM_R_SCL")
		)
	)
	(footprint ""
		(layer "F.Cu")
		(at 43.012106 19.444716 -90)
		(property "Reference" "PJ38_NUT"
			(at 0 0 270)
			(layer "F.SilkS")
			(hide yes)
			(effects
				(font
					(size 1.27 1.27)
				)
			)
		)
		(property "Value" ""
			(at 0 0 270)
			(layer "F.Fab")
			(effects
				(font
					(size 1.27 1.27)
				)
			)
		)
		(duplicate_pad_numbers_are_jumpers no)
		(pad "1" smd circle
			(at 0 0 270)
			(size 0.762 0.762)
			(layers "F.Cu" "F.Mask" "F.Paste")
			(net "Net_10790")
		)
	)
	(footprint ""
		(layer "F.Cu")
		(at 312.342022 -32.572706 180)
		(property "Reference" "R3860"
			(at 0 0 180)
			(layer "F.SilkS")
			(hide yes)
			(effects
				(font
					(size 1.27 1.27)
				)
			)
		)
		(property "Value" ""
			(at 0 0 180)
			(layer "F.Fab")
			(effects
				(font
					(size 1.27 1.27)
				)
			)
		)
		(duplicate_pad_numbers_are_jumpers no)
		(fp_line
			(start 0.7874 0.4064)
			(end -0.7874 0.4064)
			(stroke
				(width 0.1524)
				(type default)
			)
			(layer "F.SilkS")
		)
		(fp_line
			(start 0.7874 -0.4064)
			(end 0.7874 0.4064)
			(stroke
				(width 0.1524)
				(type default)
			)
			(layer "F.SilkS")
		)
		(fp_line
			(start -0.7874 0.4064)
			(end -0.7874 -0.4064)
			(stroke
				(width 0.1524)
				(type default)
			)
			(layer "F.SilkS")
		)
		(fp_line
			(start -0.7874 -0.4064)
			(end 0.7874 -0.4064)
			(stroke
				(width 0.1524)
				(type default)
			)
			(layer "F.SilkS")
		)
		(fp_line
			(start 0.67945 0.3048)
			(end 0.120396 0.3048)
			(stroke
				(width 0.1)
				(type default)
			)
			(layer "F.Fab")
		)
		(fp_line
			(start 0.67945 -0.3048)
			(end 0.67945 0.3048)
			(stroke
				(width 0.1)
				(type default)
			)
			(layer "F.Fab")
		)
		(fp_line
			(start 0.12065 -0.2794)
			(end 0.12065 -0.3048)
			(stroke
				(width 0.1)
				(type default)
			)
			(layer "F.Fab")
		)
		(fp_line
			(start 0.12065 -0.3048)
			(end 0.67945 -0.3048)
			(stroke
				(width 0.1)
				(type default)
			)
			(layer "F.Fab")
		)
		(fp_line
			(start 0.120396 0.3048)
			(end 0.120396 0.2794)
			(stroke
				(width 0.1)
				(type default)
			)
			(layer "F.Fab")
		)
		(fp_line
			(start 0.120396 0.2794)
			(end -0.12065 0.2794)
			(stroke
				(width 0.1)
				(type default)
			)
			(layer "F.Fab")
		)
		(fp_line
			(start -0.12065 0.3048)
			(end -0.67945 0.3048)
			(stroke
				(width 0.1)
				(type default)
			)
			(layer "F.Fab")
		)
		(fp_line
			(start -0.12065 0.2794)
			(end -0.12065 0.3048)
			(stroke
				(width 0.1)
				(type default)
			)
			(layer "F.Fab")
		)
		(fp_line
			(start -0.12065 -0.2794)
			(end 0.12065 -0.2794)
			(stroke
				(width 0.1)
				(type default)
			)
			(layer "F.Fab")
		)
		(fp_line
			(start -0.12065 -0.305054)
			(end -0.12065 -0.2794)
			(stroke
				(width 0.1)
				(type default)
			)
			(layer "F.Fab")
		)
		(fp_line
			(start -0.67945 0.3048)
			(end -0.67945 -0.305054)
			(stroke
				(width 0.1)
				(type default)
			)
			(layer "F.Fab")
		)
		(fp_line
			(start -0.67945 -0.305054)
			(end -0.12065 -0.305054)
			(stroke
				(width 0.1)
				(type default)
			)
			(layer "F.Fab")
		)
		(pad "1" smd rect
			(at -0.40005 0)
			(size 0.4572 0.508)
			(layers "F.Cu" "F.Mask" "F.Paste")
			(net "P12V_OCP_V3_2_ISENSE_MPS_MAM")
		)
		(pad "2" smd rect
			(at 0.40005 0)
			(size 0.4572 0.508)
			(layers "F.Cu" "F.Mask" "F.Paste")
			(net "P12V_OCP_V3_2_ISENSE_MAM")
		)
	)
	(footprint ""
		(layer "F.Cu")
		(at 98.344736 -123.628404 -90)
		(property "Reference" "U38"
			(at 0.808736 2.012188 90)
			(unlocked yes)
			(layer "F.SilkS")
			(effects
				(font
					(size 0.7874 0.5842)
					(thickness 0.1524)
				)
				(justify left)
			)
		)
		(property "Value" ""
			(at 0 0 270)
			(layer "F.Fab")
			(effects
				(font
					(size 1.27 1.27)
				)
			)
		)
		(duplicate_pad_numbers_are_jumpers no)
		(fp_line
			(start -1.690624 1.074928)
			(end 1.690624 1.074928)
			(stroke
				(width 0.1524)
				(type default)
			)
			(layer "F.SilkS")
		)
		(fp_line
			(start 1.690624 1.074928)
			(end 1.690624 -1.074928)
			(stroke
				(width 0.1524)
				(type default)
			)
			(layer "F.SilkS")
		)
		(fp_line
			(start 0 -0.381)
			(end -0.439928 -1.074928)
			(stroke
				(width 0.1524)
				(type default)
			)
			(layer "F.SilkS")
		)
		(fp_line
			(start -1.690624 -1.074928)
			(end -1.690624 1.074928)
			(stroke
				(width 0.1524)
				(type default)
			)
			(layer "F.SilkS")
		)
		(fp_line
			(start -0.439928 -1.074928)
			(end -1.690624 -1.074928)
			(stroke
				(width 0.1524)
				(type default)
			)
			(layer "F.SilkS")
		)
		(fp_line
			(start 0.439928 -1.074928)
			(end 0 -0.381)
			(stroke
				(width 0.1524)
				(type default)
			)
			(layer "F.SilkS")
		)
		(fp_line
			(start 1.690624 -1.074928)
			(end 0.439928 -1.074928)
			(stroke
				(width 0.1524)
				(type default)
			)
			(layer "F.SilkS")
		)
		(fp_poly
			(pts
				(xy -2.7686 -0.175768) (xy -2.7686 -1.124204) (xy -1.81991 -0.649986)
			)
			(stroke
				(width 0)
				(type default)
			)
			(fill yes)
			(layer "F.SilkS")
		)
		(fp_line
			(start -0.700024 1.074928)
			(end -0.700024 -1.074928)
			(stroke
				(width 0.1)
				(type default)
			)
			(layer "F.Fab")
		)
		(fp_line
			(start 0.700024 1.074928)
			(end -0.700024 1.074928)
			(stroke
				(width 0.1)
				(type default)
			)
			(layer "F.Fab")
		)
		(fp_line
			(start -0.700024 -1.074928)
			(end 0.700024 -1.074928)
			(stroke
				(width 0.1)
				(type default)
			)
			(layer "F.Fab")
		)
		(fp_line
			(start 0.700024 -1.074928)
			(end 0.700024 1.074928)
			(stroke
				(width 0.1)
				(type default)
			)
			(layer "F.Fab")
		)
		(fp_poly
			(pts
				(xy -2.7686 -1.124204) (xy -1.81991 -0.649986) (xy -2.7686 -0.175768)
			)
			(stroke
				(width 0)
				(type default)
			)
			(fill yes)
			(layer "F.Fab")
		)
		(pad "1" smd rect
			(at -1.100074 -0.649986)
			(size 0.4064 0.9144)
			(layers "F.Cu" "F.Mask" "F.Paste")
			(net "PWRGD_P12V_MEM_CPU0_R")
		)
		(pad "2" smd rect
			(at -1.100074 0)
			(size 0.4064 0.9144)
			(layers "F.Cu" "F.Mask" "F.Paste")
			(net "GND")
		)
		(pad "3" smd rect
			(at -1.100074 0.649986)
			(size 0.4064 0.9144)
			(layers "F.Cu" "F.Mask" "F.Paste")
			(net "PWRGD_P12V_MEM_CPU1_R")
		)
		(pad "4" smd rect
			(at 1.100074 0.649986)
			(size 0.4064 0.9144)
			(layers "F.Cu" "F.Mask" "F.Paste")
			(net "PWRGD_P12V_MEM")
		)
		(pad "5" smd rect
			(at 1.100074 0)
			(size 0.4064 0.9144)
			(layers "F.Cu" "F.Mask" "F.Paste")
			(net "P1V8_AUX")
		)
		(pad "6" smd rect
			(at 1.100074 -0.649986)
			(size 0.4064 0.9144)
			(layers "F.Cu" "F.Mask" "F.Paste")
			(net "PU_U38_6")
		)
	)
	(footprint ""
		(layer "F.Cu")
		(at 170.8912 -94.833948 -90)
		(property "Reference" "R6025"
			(at 0 0 270)
			(layer "F.SilkS")
			(hide yes)
			(effects
				(font
					(size 1.27 1.27)
				)
			)
		)
		(property "Value" ""
			(at 0 0 270)
			(layer "F.Fab")
			(effects
				(font
					(size 1.27 1.27)
				)
			)
		)
		(duplicate_pad_numbers_are_jumpers no)
		(fp_line
			(start -0.7874 0.4064)
			(end -0.7874 -0.4064)
			(stroke
				(width 0.1524)
				(type default)
			)
			(layer "F.SilkS")
		)
		(fp_line
			(start 0.7874 0.4064)
			(end -0.7874 0.4064)
			(stroke
				(width 0.1524)
				(type default)
			)
			(layer "F.SilkS")
		)
		(fp_line
			(start -0.7874 -0.4064)
			(end 0.7874 -0.4064)
			(stroke
				(width 0.1524)
				(type default)
			)
			(layer "F.SilkS")
		)
		(fp_line
			(start 0.7874 -0.4064)
			(end 0.7874 0.4064)
			(stroke
				(width 0.1524)
				(type default)
			)
			(layer "F.SilkS")
		)
		(fp_line
			(start -0.67945 0.3048)
			(end -0.67945 -0.305054)
			(stroke
				(width 0.1)
				(type default)
			)
			(layer "F.Fab")
		)
		(fp_line
			(start -0.12065 0.3048)
			(end -0.67945 0.3048)
			(stroke
				(width 0.1)
				(type default)
			)
			(layer "F.Fab")
		)
		(fp_line
			(start 0.120396 0.3048)
			(end 0.120396 0.2794)
			(stroke
				(width 0.1)
				(type default)
			)
			(layer "F.Fab")
		)
		(fp_line
			(start 0.67945 0.3048)
			(end 0.120396 0.3048)
			(stroke
				(width 0.1)
				(type default)
			)
			(layer "F.Fab")
		)
		(fp_line
			(start -0.12065 0.2794)
			(end -0.12065 0.3048)
			(stroke
				(width 0.1)
				(type default)
			)
			(layer "F.Fab")
		)
		(fp_line
			(start 0.120396 0.2794)
			(end -0.12065 0.2794)
			(stroke
				(width 0.1)
				(type default)
			)
			(layer "F.Fab")
		)
		(fp_line
			(start -0.12065 -0.2794)
			(end 0.12065 -0.2794)
			(stroke
				(width 0.1)
				(type default)
			)
			(layer "F.Fab")
		)
		(fp_line
			(start 0.12065 -0.2794)
			(end 0.12065 -0.3048)
			(stroke
				(width 0.1)
				(type default)
			)
			(layer "F.Fab")
		)
		(fp_line
			(start 0.12065 -0.3048)
			(end 0.67945 -0.3048)
			(stroke
				(width 0.1)
				(type default)
			)
			(layer "F.Fab")
		)
		(fp_line
			(start 0.67945 -0.3048)
			(end 0.67945 0.3048)
			(stroke
				(width 0.1)
				(type default)
			)
			(layer "F.Fab")
		)
		(fp_line
			(start -0.67945 -0.305054)
			(end -0.12065 -0.305054)
			(stroke
				(width 0.1)
				(type default)
			)
			(layer "F.Fab")
		)
		(fp_line
			(start -0.12065 -0.305054)
			(end -0.12065 -0.2794)
			(stroke
				(width 0.1)
				(type default)
			)
			(layer "F.Fab")
		)
		(pad "1" smd circle
			(at -0.40005 0 270)
			(size 0 0)
			(layers "F.Cu" "F.Mask" "F.Paste")
			(net "SGPIO_SCM_RESET_N")
		)
		(pad "2" smd circle
			(at 0.40005 0 270)
			(size 0 0)
			(layers "F.Cu" "F.Mask" "F.Paste")
			(net "SGPIO_SCM_RESET_R_N")
		)
	)
	(footprint ""
		(layer "F.Cu")
		(at 102.268782 -379.471428)
		(property "Reference" "C711"
			(at 0 0 0)
			(layer "F.SilkS")
			(hide yes)
			(effects
				(font
					(size 1.27 1.27)
				)
			)
		)
		(property "Value" ""
			(at 0 0 0)
			(layer "F.Fab")
			(effects
				(font
					(size 1.27 1.27)
				)
			)
		)
		(duplicate_pad_numbers_are_jumpers no)
		(fp_line
			(start -0.299974 -0.150114)
			(end 0.299974 -0.150114)
			(stroke
				(width 0.1)
				(type default)
			)
			(layer "F.Fab")
		)
		(fp_line
			(start -0.299974 0.150114)
			(end -0.299974 -0.150114)
			(stroke
				(width 0.1)
				(type default)
			)
			(layer "F.Fab")
		)
		(fp_line
			(start 0.299974 -0.150114)
			(end 0.299974 0.150114)
			(stroke
				(width 0.1)
				(type default)
			)
			(layer "F.Fab")
		)
		(fp_line
			(start 0.299974 0.150114)
			(end -0.299974 0.150114)
			(stroke
				(width 0.1)
				(type default)
			)
			(layer "F.Fab")
		)
		(pad "1" smd rect
			(at -0.2667 0)
			(size 0.3048 0.381)
			(layers "F.Cu" "F.Mask" "F.Paste")
			(net "P5E_CPU1_P1_TX_C_DP<15>")
		)
		(pad "2" smd rect
			(at 0.2667 0)
			(size 0.3048 0.381)
			(layers "F.Cu" "F.Mask" "F.Paste")
			(net "P5E_CPU1_P1_TX_DP<15>")
		)
	)
	(footprint ""
		(layer "F.Cu")
		(at 197.269608 -112.609376 180)
		(property "Reference" "R282"
			(at 0 0 180)
			(layer "F.SilkS")
			(hide yes)
			(effects
				(font
					(size 1.27 1.27)
				)
			)
		)
		(property "Value" ""
			(at 0 0 180)
			(layer "F.Fab")
			(effects
				(font
					(size 1.27 1.27)
				)
			)
		)
		(duplicate_pad_numbers_are_jumpers no)
		(fp_line
			(start 0.7874 0.4064)
			(end -0.7874 0.4064)
			(stroke
				(width 0.1524)
				(type default)
			)
			(layer "F.SilkS")
		)
		(fp_line
			(start 0.7874 -0.4064)
			(end 0.7874 0.4064)
			(stroke
				(width 0.1524)
				(type default)
			)
			(layer "F.SilkS")
		)
		(fp_line
			(start -0.7874 0.4064)
			(end -0.7874 -0.4064)
			(stroke
				(width 0.1524)
				(type default)
			)
			(layer "F.SilkS")
		)
		(fp_line
			(start -0.7874 -0.4064)
			(end 0.7874 -0.4064)
			(stroke
				(width 0.1524)
				(type default)
			)
			(layer "F.SilkS")
		)
		(fp_line
			(start 0.67945 0.3048)
			(end 0.120396 0.3048)
			(stroke
				(width 0.1)
				(type default)
			)
			(layer "F.Fab")
		)
		(fp_line
			(start 0.67945 -0.3048)
			(end 0.67945 0.3048)
			(stroke
				(width 0.1)
				(type default)
			)
			(layer "F.Fab")
		)
		(fp_line
			(start 0.12065 -0.2794)
			(end 0.12065 -0.3048)
			(stroke
				(width 0.1)
				(type default)
			)
			(layer "F.Fab")
		)
		(fp_line
			(start 0.12065 -0.3048)
			(end 0.67945 -0.3048)
			(stroke
				(width 0.1)
				(type default)
			)
			(layer "F.Fab")
		)
		(fp_line
			(start 0.120396 0.3048)
			(end 0.120396 0.2794)
			(stroke
				(width 0.1)
				(type default)
			)
			(layer "F.Fab")
		)
		(fp_line
			(start 0.120396 0.2794)
			(end -0.12065 0.2794)
			(stroke
				(width 0.1)
				(type default)
			)
			(layer "F.Fab")
		)
		(fp_line
			(start -0.12065 0.3048)
			(end -0.67945 0.3048)
			(stroke
				(width 0.1)
				(type default)
			)
			(layer "F.Fab")
		)
		(fp_line
			(start -0.12065 0.2794)
			(end -0.12065 0.3048)
			(stroke
				(width 0.1)
				(type default)
			)
			(layer "F.Fab")
		)
		(fp_line
			(start -0.12065 -0.2794)
			(end 0.12065 -0.2794)
			(stroke
				(width 0.1)
				(type default)
			)
			(layer "F.Fab")
		)
		(fp_line
			(start -0.12065 -0.305054)
			(end -0.12065 -0.2794)
			(stroke
				(width 0.1)
				(type default)
			)
			(layer "F.Fab")
		)
		(fp_line
			(start -0.67945 0.3048)
			(end -0.67945 -0.305054)
			(stroke
				(width 0.1)
				(type default)
			)
			(layer "F.Fab")
		)
		(fp_line
			(start -0.67945 -0.305054)
			(end -0.12065 -0.305054)
			(stroke
				(width 0.1)
				(type default)
			)
			(layer "F.Fab")
		)
		(pad "1" smd circle
			(at -0.40005 0 180)
			(size 0 0)
			(layers "F.Cu" "F.Mask" "F.Paste")
			(net "PVDDIO_P1_EN")
		)
		(pad "2" smd circle
			(at 0.40005 0 180)
			(size 0 0)
			(layers "F.Cu" "F.Mask" "F.Paste")
			(net "FM_PVDDIO_P1_EN")
		)
	)
	(footprint ""
		(layer "F.Cu")
		(at 115.275868 -256.012442 90)
		(property "Reference" "C2434"
			(at 0 0 90)
			(layer "F.SilkS")
			(hide yes)
			(effects
				(font
					(size 1.27 1.27)
				)
			)
		)
		(property "Value" ""
			(at 0 0 90)
			(layer "F.Fab")
			(effects
				(font
					(size 1.27 1.27)
				)
			)
		)
		(duplicate_pad_numbers_are_jumpers no)
		(fp_line
			(start 0.7874 -0.4064)
			(end 0.7874 0.4064)
			(stroke
				(width 0.1524)
				(type default)
			)
			(layer "F.SilkS")
		)
		(fp_line
			(start -0.7874 -0.4064)
			(end 0.7874 -0.4064)
			(stroke
				(width 0.1524)
				(type default)
			)
			(layer "F.SilkS")
		)
		(fp_line
			(start 0.7874 0.4064)
			(end -0.7874 0.4064)
			(stroke
				(width 0.1524)
				(type default)
			)
			(layer "F.SilkS")
		)
		(fp_line
			(start -0.7874 0.4064)
			(end -0.7874 -0.4064)
			(stroke
				(width 0.1524)
				(type default)
			)
			(layer "F.SilkS")
		)
		(fp_line
			(start -0.12065 -0.305054)
			(end -0.12065 -0.2794)
			(stroke
				(width 0.1)
				(type default)
			)
			(layer "F.Fab")
		)
		(fp_line
			(start -0.67945 -0.305054)
			(end -0.12065 -0.305054)
			(stroke
				(width 0.1)
				(type default)
			)
			(layer "F.Fab")
		)
		(fp_line
			(start 0.67945 -0.3048)
			(end 0.67945 0.3048)
			(stroke
				(width 0.1)
				(type default)
			)
			(layer "F.Fab")
		)
		(fp_line
			(start 0.12065 -0.3048)
			(end 0.67945 -0.3048)
			(stroke
				(width 0.1)
				(type default)
			)
			(layer "F.Fab")
		)
		(fp_line
			(start 0.12065 -0.2794)
			(end 0.12065 -0.3048)
			(stroke
				(width 0.1)
				(type default)
			)
			(layer "F.Fab")
		)
		(fp_line
			(start -0.12065 -0.2794)
			(end 0.12065 -0.2794)
			(stroke
				(width 0.1)
				(type default)
			)
			(layer "F.Fab")
		)
		(fp_line
			(start 0.120396 0.2794)
			(end -0.12065 0.2794)
			(stroke
				(width 0.1)
				(type default)
			)
			(layer "F.Fab")
		)
		(fp_line
			(start -0.12065 0.2794)
			(end -0.12065 0.3048)
			(stroke
				(width 0.1)
				(type default)
			)
			(layer "F.Fab")
		)
		(fp_line
			(start 0.67945 0.3048)
			(end 0.120396 0.3048)
			(stroke
				(width 0.1)
				(type default)
			)
			(layer "F.Fab")
		)
		(fp_line
			(start 0.120396 0.3048)
			(end 0.120396 0.2794)
			(stroke
				(width 0.1)
				(type default)
			)
			(layer "F.Fab")
		)
		(fp_line
			(start -0.12065 0.3048)
			(end -0.67945 0.3048)
			(stroke
				(width 0.1)
				(type default)
			)
			(layer "F.Fab")
		)
		(fp_line
			(start -0.67945 0.3048)
			(end -0.67945 -0.305054)
			(stroke
				(width 0.1)
				(type default)
			)
			(layer "F.Fab")
		)
		(pad "1" smd circle
			(at -0.40005 0 90)
			(size 0 0)
			(layers "F.Cu" "F.Mask" "F.Paste")
			(net "PVDDCR_SOC_P1")
		)
		(pad "2" smd circle
			(at 0.40005 0 90)
			(size 0 0)
			(layers "F.Cu" "F.Mask" "F.Paste")
			(net "GND")
		)
	)
	(footprint ""
		(layer "F.Cu")
		(at 458.661008 -411.8737)
		(property "Reference" "PC6810"
			(at -1.969008 -3.64363 0)
			(unlocked yes)
			(layer "F.SilkS")
			(effects
				(font
					(size 0.7874 0.5842)
					(thickness 0.1524)
				)
				(justify left)
			)
		)
		(property "Value" ""
			(at 0 0 0)
			(layer "F.Fab")
			(effects
				(font
					(size 1.27 1.27)
				)
			)
		)
		(duplicate_pad_numbers_are_jumpers no)
		(fp_line
			(start -2.750058 -1.988058)
			(end -2.750058 -0.9398)
			(stroke
				(width 0.1524)
				(type default)
			)
			(layer "F.SilkS")
		)
		(fp_line
			(start -2.750058 0.9398)
			(end -2.750058 1.988058)
			(stroke
				(width 0.1524)
				(type default)
			)
			(layer "F.SilkS")
		)
		(fp_line
			(start -2.750058 1.988058)
			(end -1.988058 2.750058)
			(stroke
				(width 0.1524)
				(type default)
			)
			(layer "F.SilkS")
		)
		(fp_line
			(start -1.988058 -2.750058)
			(end -2.750058 -1.988058)
			(stroke
				(width 0.1524)
				(type default)
			)
			(layer "F.SilkS")
		)
		(fp_line
			(start -1.988058 2.750058)
			(end 2.750058 2.750058)
			(stroke
				(width 0.1524)
				(type default)
			)
			(layer "F.SilkS")
		)
		(fp_line
			(start 2.750058 -2.750058)
			(end -1.988058 -2.750058)
			(stroke
				(width 0.1524)
				(type default)
			)
			(layer "F.SilkS")
		)
		(fp_line
			(start 2.750058 -0.9398)
			(end 2.750058 -2.750058)
			(stroke
				(width 0.1524)
				(type default)
			)
			(layer "F.SilkS")
		)
		(fp_line
			(start 2.750058 2.750058)
			(end 2.750058 0.9398)
			(stroke
				(width 0.1524)
				(type default)
			)
			(layer "F.SilkS")
		)
		(fp_line
			(start -2.750058 -2.750058)
			(end -2.750058 2.750058)
			(stroke
				(width 0.1)
				(type default)
			)
			(layer "F.Fab")
		)
		(fp_line
			(start -2.750058 2.750058)
			(end 2.750058 2.750058)
			(stroke
				(width 0.1)
				(type default)
			)
			(layer "F.Fab")
		)
		(fp_line
			(start 2.750058 -2.750058)
			(end -2.750058 -2.750058)
			(stroke
				(width 0.1)
				(type default)
			)
			(layer "F.Fab")
		)
		(fp_line
			(start 2.750058 2.750058)
			(end 2.750058 -2.750058)
			(stroke
				(width 0.1)
				(type default)
			)
			(layer "F.Fab")
		)
		(pad "1" smd rect
			(at -2.199894 0 90)
			(size 1.6002 3.0226)
			(layers "F.Cu" "F.Mask" "F.Paste")
			(net "SW_P12V_AUX_P0V9_RETIMER_CPU0_FLT")
		)
		(pad "2" smd rect
			(at 2.199894 0 90)
			(size 1.6002 3.0226)
			(layers "F.Cu" "F.Mask" "F.Paste")
			(net "GND")
		)
	)
	(footprint ""
		(layer "F.Cu")
		(at 445.131952 -397.245332)
		(property "Reference" "PU6503"
			(at -3.99415 -7.331456 0)
			(unlocked yes)
			(layer "F.SilkS")
			(effects
				(font
					(size 0.7874 0.5842)
					(thickness 0.1524)
				)
				(justify left)
			)
		)
		(property "Value" ""
			(at 0 0 0)
			(layer "F.Fab")
			(effects
				(font
					(size 1.27 1.27)
				)
			)
		)
		(duplicate_pad_numbers_are_jumpers no)
		(fp_line
			(start -2.500122 -2.999994)
			(end -2.24409 -2.999994)
			(stroke
				(width 0.1524)
				(type default)
			)
			(layer "F.SilkS")
		)
		(fp_line
			(start -2.500122 -2.529078)
			(end -2.500122 -2.999994)
			(stroke
				(width 0.1524)
				(type default)
			)
			(layer "F.SilkS")
		)
		(fp_line
			(start -2.500122 0.6604)
			(end -2.500122 0.229108)
			(stroke
				(width 0.1524)
				(type default)
			)
			(layer "F.SilkS")
		)
		(fp_line
			(start -2.500122 2.999994)
			(end -2.500122 2.339594)
			(stroke
				(width 0.1524)
				(type default)
			)
			(layer "F.SilkS")
		)
		(fp_line
			(start -2.2987 2.999994)
			(end -2.500122 2.999994)
			(stroke
				(width 0.1524)
				(type default)
			)
			(layer "F.SilkS")
		)
		(fp_line
			(start 2.31394 -2.999994)
			(end 2.500122 -2.999994)
			(stroke
				(width 0.1524)
				(type default)
			)
			(layer "F.SilkS")
		)
		(fp_line
			(start 2.500122 -2.999994)
			(end 2.500122 -2.44348)
			(stroke
				(width 0.1524)
				(type default)
			)
			(layer "F.SilkS")
		)
		(fp_line
			(start 2.500122 2.339594)
			(end 2.500122 2.999994)
			(stroke
				(width 0.1524)
				(type default)
			)
			(layer "F.SilkS")
		)
		(fp_line
			(start 2.500122 2.999994)
			(end 2.2987 2.999994)
			(stroke
				(width 0.1524)
				(type default)
			)
			(layer "F.SilkS")
		)
		(fp_poly
			(pts
				(xy -3.052318 -3.555746) (xy -3.770884 -2.83718) (xy -2.693162 -2.478024)
			)
			(stroke
				(width 0)
				(type default)
			)
			(fill yes)
			(layer "F.SilkS")
		)
		(fp_line
			(start -2.500122 -2.999994)
			(end 2.500122 -2.999994)
			(stroke
				(width 0.1)
				(type default)
			)
			(layer "F.Fab")
		)
		(fp_line
			(start -2.500122 2.999994)
			(end -2.500122 -2.999994)
			(stroke
				(width 0.1)
				(type default)
			)
			(layer "F.Fab")
		)
		(fp_line
			(start 2.500122 -2.999994)
			(end 2.500122 2.999994)
			(stroke
				(width 0.1)
				(type default)
			)
			(layer "F.Fab")
		)
		(fp_line
			(start 2.500122 2.999994)
			(end -2.500122 2.999994)
			(stroke
				(width 0.1)
				(type default)
			)
			(layer "F.Fab")
		)
		(fp_poly
			(pts
				(xy -4.218432 -2.783078) (xy -4.218432 -1.767078) (xy -3.202432 -2.275078)
			)
			(stroke
				(width 0)
				(type default)
			)
			(fill yes)
			(layer "F.Fab")
		)
		(pad "1" smd rect
			(at -2.400046 -2.275078 90)
			(size 0.2286 0.6096)
			(layers "F.Cu" "F.Mask" "F.Paste")
			(net "P0V9_RETIMER_CPU0_VOS1")
		)
		(pad "2" smd rect
			(at -2.400046 -1.82499 90)
			(size 0.2286 0.6096)
			(layers "F.Cu" "F.Mask" "F.Paste")
			(net "GND")
		)
		(pad "3" smd rect
			(at -2.400046 -1.374902 90)
			(size 0.2286 0.6096)
			(layers "F.Cu" "F.Mask" "F.Paste")
			(net "P0V9_RETIMER_CPU0_VCC1")
		)
		(pad "4" smd rect
			(at -2.400046 -0.925068 90)
			(size 0.2286 0.6096)
			(layers "F.Cu" "F.Mask" "F.Paste")
			(net "P0V9_RETIMER_CPU0_PVCC")
		)
		(pad "5" smd rect
			(at -2.400046 -0.47498 90)
			(size 0.2286 0.6096)
			(layers "F.Cu" "F.Mask" "F.Paste")
			(net "GND")
		)
		(pad "6" smd rect
			(at -2.400046 -0.024892 90)
			(size 0.2286 0.6096)
			(layers "F.Cu" "F.Mask" "F.Paste")
			(net "NC_PV09_RETIMER_CPU0_GL1_1")
		)
		(pad "7_9-20_24" smd circle
			(at 0 1.150112 90)
			(size 0 0)
			(layers "F.Cu" "F.Mask" "F.Paste")
			(net "GND")
		)
		(pad "10_19" smd rect
			(at 0 2.899918 90)
			(size 0.6096 4.318)
			(layers "F.Cu" "F.Mask" "F.Paste")
			(net "SW_P0V9_RETIMER_CPU0_SW1")
		)
		(pad "25_29" smd rect
			(at 1.549908 -1.279906 270)
			(size 2.0574 2.3114)
			(layers "F.Cu" "F.Mask" "F.Paste")
			(net "SW_P12V_AUX_P0V9_RETIMER_CPU0_FLT")
		)
		(pad "30" smd rect
			(at 2.05994 -2.899918)
			(size 0.2286 0.6096)
			(layers "F.Cu" "F.Mask" "F.Paste")
			(net "SW_P12V_AUX_P0V9_RETIMER_CPU0_FLT")
		)
		(pad "31" smd rect
			(at 1.610106 -2.899918)
			(size 0.2286 0.6096)
			(layers "F.Cu" "F.Mask" "F.Paste")
			(net "NC_PV09_RETIMER_CPU0_DNC1")
		)
		(pad "32" smd rect
			(at 1.160018 -2.899918)
			(size 0.2286 0.6096)
			(layers "F.Cu" "F.Mask" "F.Paste")
			(net "SW_P0V9_RETIMER_CPU0_PH1")
		)
		(pad "33" smd rect
			(at 0.70993 -2.899918)
			(size 0.2286 0.6096)
			(layers "F.Cu" "F.Mask" "F.Paste")
			(net "SW_P0V9_RETIMER_CPU0_BOOT1")
		)
		(pad "34" smd rect
			(at 0.260096 -2.899918)
			(size 0.2286 0.6096)
			(layers "F.Cu" "F.Mask" "F.Paste")
			(net "P0V9_RETIMER_CPU0_PWM1")
		)
		(pad "35" smd rect
			(at -0.189992 -2.899918)
			(size 0.2286 0.6096)
			(layers "F.Cu" "F.Mask" "F.Paste")
			(net "P0V9_RETIMER_CPU0_VCC1")
		)
		(pad "36" smd rect
			(at -0.64008 -2.899918)
			(size 0.2286 0.6096)
			(layers "F.Cu" "F.Mask" "F.Paste")
			(net "P0V9_RETIMER_CPU0_TEMP0")
		)
		(pad "37" smd rect
			(at -1.089914 -2.899918)
			(size 0.2286 0.6096)
			(layers "F.Cu" "F.Mask" "F.Paste")
			(net "P0V9_RETIMER_CPU0_LSET1")
		)
		(pad "38" smd rect
			(at -1.540002 -2.899918)
			(size 0.2286 0.6096)
			(layers "F.Cu" "F.Mask" "F.Paste")
			(net "P0V9_RETIMER_CPU0_IMON1")
		)
		(pad "39" smd rect
			(at -1.99009 -2.899918)
			(size 0.2286 0.6096)
			(layers "F.Cu" "F.Mask" "F.Paste")
			(net "PV09_RETIMER_CPU0_VCCS")
		)
		(pad "40" smd rect
			(at -0.87503 -1.27508)
			(size 1.7526 1.9558)
			(layers "F.Cu" "F.Mask" "F.Paste")
			(net "GND")
		)
		(pad "41" smd rect
			(at -1.525016 0.249936 270)
			(size 0.3048 0.4572)
			(layers "F.Cu" "F.Mask" "F.Paste")
			(net "NC_PV09_RETIMER_CPU0_GL2_1")
		)
		(zone
			(layer "F.Cu")
			(hatch none 0.5)
			(connect_pads
				(clearance 0)
			)
			(min_thickness 0.25)
			(keepout
				(tracks not_allowed)
				(vias allowed)
				(pads allowed)
				(copperpour not_allowed)
				(footprints allowed)
			)
			(placement
				(enabled no)
				(sheetname "")
			)
			(fill
				(thermal_gap 0.5)
				(thermal_bridge_width 0.5)
				(island_removal_mode 0)
			)
			(polygon
				(pts
					(xy 442.63183 -394.245338) (xy 442.63183 -394.994638) (xy 447.632074 -394.994638) (xy 447.632074 -394.245338)
					(xy 447.341752 -394.245338) (xy 447.341752 -394.701014) (xy 442.922152 -394.701014) (xy 442.922152 -394.245338)
				)
			)
		)
		(zone
			(layer "F.Cu")
			(hatch none 0.5)
			(connect_pads
				(clearance 0)
			)
			(min_thickness 0.25)
			(keepout
				(tracks not_allowed)
				(vias allowed)
				(pads allowed)
				(copperpour not_allowed)
				(footprints allowed)
			)
			(placement
				(enabled no)
				(sheetname "")
			)
			(fill
				(thermal_gap 0.5)
				(thermal_bridge_width 0.5)
				(island_removal_mode 0)
			)
			(polygon
				(pts
					(xy 442.63183 -396.496032) (xy 442.63183 -396.952724) (xy 443.327536 -396.952724) (xy 443.327536 -396.792196)
					(xy 443.886336 -396.792196) (xy 443.886336 -397.198596) (xy 443.327536 -397.198596) (xy 443.327536 -396.978124)
					(xy 442.63183 -396.978124) (xy 442.63183 -397.105124) (xy 443.087506 -397.105124) (xy 443.087506 -399.282666)
					(xy 443.329822 -399.282666) (xy 443.329822 -397.491712) (xy 445.184022 -397.491712) (xy 445.184022 -399.549112)
					(xy 443.329822 -399.549112) (xy 443.329822 -399.308066) (xy 443.087506 -399.308066) (xy 443.087506 -399.78965)
					(xy 447.632074 -399.78965) (xy 447.632074 -399.604738) (xy 445.47536 -399.604738) (xy 445.47536 -397.445738)
					(xy 447.632074 -397.445738) (xy 447.632074 -397.196056) (xy 444.18123 -397.196056) (xy 444.18123 -396.496032)
				)
			)
		)
	)
	(footprint ""
		(layer "F.Cu")
		(at 319.084706 -416.899344 -90)
		(property "Reference" "C6512"
			(at 0 0 270)
			(layer "F.SilkS")
			(hide yes)
			(effects
				(font
					(size 1.27 1.27)
				)
			)
		)
		(property "Value" ""
			(at 0 0 270)
			(layer "F.Fab")
			(effects
				(font
					(size 1.27 1.27)
				)
			)
		)
		(duplicate_pad_numbers_are_jumpers no)
		(fp_line
			(start -0.299974 0.150114)
			(end -0.299974 -0.150114)
			(stroke
				(width 0.1)
				(type default)
			)
			(layer "F.Fab")
		)
		(fp_line
			(start 0.299974 0.150114)
			(end -0.299974 0.150114)
			(stroke
				(width 0.1)
				(type default)
			)
			(layer "F.Fab")
		)
		(fp_line
			(start -0.299974 -0.150114)
			(end 0.299974 -0.150114)
			(stroke
				(width 0.1)
				(type default)
			)
			(layer "F.Fab")
		)
		(fp_line
			(start 0.299974 -0.150114)
			(end 0.299974 0.150114)
			(stroke
				(width 0.1)
				(type default)
			)
			(layer "F.Fab")
		)
		(pad "1" smd rect
			(at -0.2667 0 270)
			(size 0.3048 0.381)
			(layers "F.Cu" "F.Mask" "F.Paste")
			(net "P5E_CPU0_P0_TX_BUF_C_DN<5>")
		)
		(pad "2" smd rect
			(at 0.2667 0 270)
			(size 0.3048 0.381)
			(layers "F.Cu" "F.Mask" "F.Paste")
			(net "P5E_CPU0_P0_TX_BUF_DN<5>")
		)
	)
	(footprint ""
		(layer "F.Cu")
		(at 161.571686 -58.66765 180)
		(property "Reference" "R3574"
			(at 0 0 180)
			(layer "F.SilkS")
			(hide yes)
			(effects
				(font
					(size 1.27 1.27)
				)
			)
		)
		(property "Value" ""
			(at 0 0 180)
			(layer "F.Fab")
			(effects
				(font
					(size 1.27 1.27)
				)
			)
		)
		(duplicate_pad_numbers_are_jumpers no)
		(fp_line
			(start 0.7874 0.4064)
			(end -0.7874 0.4064)
			(stroke
				(width 0.1524)
				(type default)
			)
			(layer "F.SilkS")
		)
		(fp_line
			(start 0.7874 -0.4064)
			(end 0.7874 0.4064)
			(stroke
				(width 0.1524)
				(type default)
			)
			(layer "F.SilkS")
		)
		(fp_line
			(start -0.7874 0.4064)
			(end -0.7874 -0.4064)
			(stroke
				(width 0.1524)
				(type default)
			)
			(layer "F.SilkS")
		)
		(fp_line
			(start -0.7874 -0.4064)
			(end 0.7874 -0.4064)
			(stroke
				(width 0.1524)
				(type default)
			)
			(layer "F.SilkS")
		)
		(fp_line
			(start 0.67945 0.3048)
			(end 0.120396 0.3048)
			(stroke
				(width 0.1)
				(type default)
			)
			(layer "F.Fab")
		)
		(fp_line
			(start 0.67945 -0.3048)
			(end 0.67945 0.3048)
			(stroke
				(width 0.1)
				(type default)
			)
			(layer "F.Fab")
		)
		(fp_line
			(start 0.12065 -0.2794)
			(end 0.12065 -0.3048)
			(stroke
				(width 0.1)
				(type default)
			)
			(layer "F.Fab")
		)
		(fp_line
			(start 0.12065 -0.3048)
			(end 0.67945 -0.3048)
			(stroke
				(width 0.1)
				(type default)
			)
			(layer "F.Fab")
		)
		(fp_line
			(start 0.120396 0.3048)
			(end 0.120396 0.2794)
			(stroke
				(width 0.1)
				(type default)
			)
			(layer "F.Fab")
		)
		(fp_line
			(start 0.120396 0.2794)
			(end -0.12065 0.2794)
			(stroke
				(width 0.1)
				(type default)
			)
			(layer "F.Fab")
		)
		(fp_line
			(start -0.12065 0.3048)
			(end -0.67945 0.3048)
			(stroke
				(width 0.1)
				(type default)
			)
			(layer "F.Fab")
		)
		(fp_line
			(start -0.12065 0.2794)
			(end -0.12065 0.3048)
			(stroke
				(width 0.1)
				(type default)
			)
			(layer "F.Fab")
		)
		(fp_line
			(start -0.12065 -0.2794)
			(end 0.12065 -0.2794)
			(stroke
				(width 0.1)
				(type default)
			)
			(layer "F.Fab")
		)
		(fp_line
			(start -0.12065 -0.305054)
			(end -0.12065 -0.2794)
			(stroke
				(width 0.1)
				(type default)
			)
			(layer "F.Fab")
		)
		(fp_line
			(start -0.67945 0.3048)
			(end -0.67945 -0.305054)
			(stroke
				(width 0.1)
				(type default)
			)
			(layer "F.Fab")
		)
		(fp_line
			(start -0.67945 -0.305054)
			(end -0.12065 -0.305054)
			(stroke
				(width 0.1)
				(type default)
			)
			(layer "F.Fab")
		)
		(pad "1" smd circle
			(at -0.40005 0 180)
			(size 0 0)
			(layers "F.Cu" "F.Mask" "F.Paste")
			(net "P3V3")
		)
		(pad "2" smd circle
			(at 0.40005 0 180)
			(size 0 0)
			(layers "F.Cu" "F.Mask" "F.Paste")
			(net "VSENSE_P12V_INA230_4_INP")
		)
	)
	(footprint ""
		(layer "F.Cu")
		(at 106.934 -415.036 180)
		(property "Reference" "C84"
			(at 0 0 180)
			(layer "F.SilkS")
			(hide yes)
			(effects
				(font
					(size 1.27 1.27)
				)
			)
		)
		(property "Value" ""
			(at 0 0 180)
			(layer "F.Fab")
			(effects
				(font
					(size 1.27 1.27)
				)
			)
		)
		(duplicate_pad_numbers_are_jumpers no)
		(fp_line
			(start 0.7874 0.4064)
			(end -0.7874 0.4064)
			(stroke
				(width 0.1524)
				(type default)
			)
			(layer "F.SilkS")
		)
		(fp_line
			(start 0.7874 -0.4064)
			(end 0.7874 0.4064)
			(stroke
				(width 0.1524)
				(type default)
			)
			(layer "F.SilkS")
		)
		(fp_line
			(start -0.7874 0.4064)
			(end -0.7874 -0.4064)
			(stroke
				(width 0.1524)
				(type default)
			)
			(layer "F.SilkS")
		)
		(fp_line
			(start -0.7874 -0.4064)
			(end 0.7874 -0.4064)
			(stroke
				(width 0.1524)
				(type default)
			)
			(layer "F.SilkS")
		)
		(fp_line
			(start 0.67945 0.3048)
			(end 0.120396 0.3048)
			(stroke
				(width 0.1)
				(type default)
			)
			(layer "F.Fab")
		)
		(fp_line
			(start 0.67945 -0.3048)
			(end 0.67945 0.3048)
			(stroke
				(width 0.1)
				(type default)
			)
			(layer "F.Fab")
		)
		(fp_line
			(start 0.12065 -0.2794)
			(end 0.12065 -0.3048)
			(stroke
				(width 0.1)
				(type default)
			)
			(layer "F.Fab")
		)
		(fp_line
			(start 0.12065 -0.3048)
			(end 0.67945 -0.3048)
			(stroke
				(width 0.1)
				(type default)
			)
			(layer "F.Fab")
		)
		(fp_line
			(start 0.120396 0.3048)
			(end 0.120396 0.2794)
			(stroke
				(width 0.1)
				(type default)
			)
			(layer "F.Fab")
		)
		(fp_line
			(start 0.120396 0.2794)
			(end -0.12065 0.2794)
			(stroke
				(width 0.1)
				(type default)
			)
			(layer "F.Fab")
		)
		(fp_line
			(start -0.12065 0.3048)
			(end -0.67945 0.3048)
			(stroke
				(width 0.1)
				(type default)
			)
			(layer "F.Fab")
		)
		(fp_line
			(start -0.12065 0.2794)
			(end -0.12065 0.3048)
			(stroke
				(width 0.1)
				(type default)
			)
			(layer "F.Fab")
		)
		(fp_line
			(start -0.12065 -0.2794)
			(end 0.12065 -0.2794)
			(stroke
				(width 0.1)
				(type default)
			)
			(layer "F.Fab")
		)
		(fp_line
			(start -0.12065 -0.305054)
			(end -0.12065 -0.2794)
			(stroke
				(width 0.1)
				(type default)
			)
			(layer "F.Fab")
		)
		(fp_line
			(start -0.67945 0.3048)
			(end -0.67945 -0.305054)
			(stroke
				(width 0.1)
				(type default)
			)
			(layer "F.Fab")
		)
		(fp_line
			(start -0.67945 -0.305054)
			(end -0.12065 -0.305054)
			(stroke
				(width 0.1)
				(type default)
			)
			(layer "F.Fab")
		)
		(pad "1" smd circle
			(at -0.40005 0 180)
			(size 0 0)
			(layers "F.Cu" "F.Mask" "F.Paste")
			(net "P3V3_9ZXL045_P1_VDDR")
		)
		(pad "2" smd circle
			(at 0.40005 0 180)
			(size 0 0)
			(layers "F.Cu" "F.Mask" "F.Paste")
			(net "GND")
		)
	)
	(footprint ""
		(layer "F.Cu")
		(at 12.741148 -385.91109 180)
		(property "Reference" "PC6622"
			(at 0 0 180)
			(layer "F.SilkS")
			(hide yes)
			(effects
				(font
					(size 1.27 1.27)
				)
			)
		)
		(property "Value" ""
			(at 0 0 180)
			(layer "F.Fab")
			(effects
				(font
					(size 1.27 1.27)
				)
			)
		)
		(duplicate_pad_numbers_are_jumpers no)
		(fp_line
			(start 0.7874 0.4064)
			(end -0.7874 0.4064)
			(stroke
				(width 0.1524)
				(type default)
			)
			(layer "F.SilkS")
		)
		(fp_line
			(start 0.7874 -0.4064)
			(end 0.7874 0.4064)
			(stroke
				(width 0.1524)
				(type default)
			)
			(layer "F.SilkS")
		)
		(fp_line
			(start -0.7874 0.4064)
			(end -0.7874 -0.4064)
			(stroke
				(width 0.1524)
				(type default)
			)
			(layer "F.SilkS")
		)
		(fp_line
			(start -0.7874 -0.4064)
			(end 0.7874 -0.4064)
			(stroke
				(width 0.1524)
				(type default)
			)
			(layer "F.SilkS")
		)
		(fp_line
			(start 0.67945 0.3048)
			(end 0.120396 0.3048)
			(stroke
				(width 0.1)
				(type default)
			)
			(layer "F.Fab")
		)
		(fp_line
			(start 0.67945 -0.3048)
			(end 0.67945 0.3048)
			(stroke
				(width 0.1)
				(type default)
			)
			(layer "F.Fab")
		)
		(fp_line
			(start 0.12065 -0.2794)
			(end 0.12065 -0.3048)
			(stroke
				(width 0.1)
				(type default)
			)
			(layer "F.Fab")
		)
		(fp_line
			(start 0.12065 -0.3048)
			(end 0.67945 -0.3048)
			(stroke
				(width 0.1)
				(type default)
			)
			(layer "F.Fab")
		)
		(fp_line
			(start 0.120396 0.3048)
			(end 0.120396 0.2794)
			(stroke
				(width 0.1)
				(type default)
			)
			(layer "F.Fab")
		)
		(fp_line
			(start 0.120396 0.2794)
			(end -0.12065 0.2794)
			(stroke
				(width 0.1)
				(type default)
			)
			(layer "F.Fab")
		)
		(fp_line
			(start -0.12065 0.3048)
			(end -0.67945 0.3048)
			(stroke
				(width 0.1)
				(type default)
			)
			(layer "F.Fab")
		)
		(fp_line
			(start -0.12065 0.2794)
			(end -0.12065 0.3048)
			(stroke
				(width 0.1)
				(type default)
			)
			(layer "F.Fab")
		)
		(fp_line
			(start -0.12065 -0.2794)
			(end 0.12065 -0.2794)
			(stroke
				(width 0.1)
				(type default)
			)
			(layer "F.Fab")
		)
		(fp_line
			(start -0.12065 -0.305054)
			(end -0.12065 -0.2794)
			(stroke
				(width 0.1)
				(type default)
			)
			(layer "F.Fab")
		)
		(fp_line
			(start -0.67945 0.3048)
			(end -0.67945 -0.305054)
			(stroke
				(width 0.1)
				(type default)
			)
			(layer "F.Fab")
		)
		(fp_line
			(start -0.67945 -0.305054)
			(end -0.12065 -0.305054)
			(stroke
				(width 0.1)
				(type default)
			)
			(layer "F.Fab")
		)
		(pad "1" smd circle
			(at -0.40005 0 180)
			(size 0 0)
			(layers "F.Cu" "F.Mask" "F.Paste")
			(net "SW_P0V9_RETIMER_CPU1_SW1")
		)
		(pad "2" smd circle
			(at 0.40005 0 180)
			(size 0 0)
			(layers "F.Cu" "F.Mask" "F.Paste")
			(net "SW_P0V9_RETIMER_CPU1_SW1_RC")
		)
	)
	(footprint ""
		(layer "F.Cu")
		(at 17.32915 -68.128642 180)
		(property "Reference" "R1192"
			(at 0 0 180)
			(layer "F.SilkS")
			(hide yes)
			(effects
				(font
					(size 1.27 1.27)
				)
			)
		)
		(property "Value" ""
			(at 0 0 180)
			(layer "F.Fab")
			(effects
				(font
					(size 1.27 1.27)
				)
			)
		)
		(duplicate_pad_numbers_are_jumpers no)
		(fp_line
			(start 0.7874 0.4064)
			(end -0.7874 0.4064)
			(stroke
				(width 0.1524)
				(type default)
			)
			(layer "F.SilkS")
		)
		(fp_line
			(start 0.7874 -0.4064)
			(end 0.7874 0.4064)
			(stroke
				(width 0.1524)
				(type default)
			)
			(layer "F.SilkS")
		)
		(fp_line
			(start -0.7874 0.4064)
			(end -0.7874 -0.4064)
			(stroke
				(width 0.1524)
				(type default)
			)
			(layer "F.SilkS")
		)
		(fp_line
			(start -0.7874 -0.4064)
			(end 0.7874 -0.4064)
			(stroke
				(width 0.1524)
				(type default)
			)
			(layer "F.SilkS")
		)
		(fp_line
			(start 0.67945 0.3048)
			(end 0.120396 0.3048)
			(stroke
				(width 0.1)
				(type default)
			)
			(layer "F.Fab")
		)
		(fp_line
			(start 0.67945 -0.3048)
			(end 0.67945 0.3048)
			(stroke
				(width 0.1)
				(type default)
			)
			(layer "F.Fab")
		)
		(fp_line
			(start 0.12065 -0.2794)
			(end 0.12065 -0.3048)
			(stroke
				(width 0.1)
				(type default)
			)
			(layer "F.Fab")
		)
		(fp_line
			(start 0.12065 -0.3048)
			(end 0.67945 -0.3048)
			(stroke
				(width 0.1)
				(type default)
			)
			(layer "F.Fab")
		)
		(fp_line
			(start 0.120396 0.3048)
			(end 0.120396 0.2794)
			(stroke
				(width 0.1)
				(type default)
			)
			(layer "F.Fab")
		)
		(fp_line
			(start 0.120396 0.2794)
			(end -0.12065 0.2794)
			(stroke
				(width 0.1)
				(type default)
			)
			(layer "F.Fab")
		)
		(fp_line
			(start -0.12065 0.3048)
			(end -0.67945 0.3048)
			(stroke
				(width 0.1)
				(type default)
			)
			(layer "F.Fab")
		)
		(fp_line
			(start -0.12065 0.2794)
			(end -0.12065 0.3048)
			(stroke
				(width 0.1)
				(type default)
			)
			(layer "F.Fab")
		)
		(fp_line
			(start -0.12065 -0.2794)
			(end 0.12065 -0.2794)
			(stroke
				(width 0.1)
				(type default)
			)
			(layer "F.Fab")
		)
		(fp_line
			(start -0.12065 -0.305054)
			(end -0.12065 -0.2794)
			(stroke
				(width 0.1)
				(type default)
			)
			(layer "F.Fab")
		)
		(fp_line
			(start -0.67945 0.3048)
			(end -0.67945 -0.305054)
			(stroke
				(width 0.1)
				(type default)
			)
			(layer "F.Fab")
		)
		(fp_line
			(start -0.67945 -0.305054)
			(end -0.12065 -0.305054)
			(stroke
				(width 0.1)
				(type default)
			)
			(layer "F.Fab")
		)
		(pad "1" smd circle
			(at -0.40005 0 180)
			(size 0 0)
			(layers "F.Cu" "F.Mask" "F.Paste")
			(net "P3V3_AUX")
		)
		(pad "2" smd circle
			(at 0.40005 0 180)
			(size 0 0)
			(layers "F.Cu" "F.Mask" "F.Paste")
			(net "HP_LVC3_OCP_V3_2_PRSNT2_N")
		)
	)
	(footprint ""
		(layer "F.Cu")
		(at 333.215488 -402.548852 -90)
		(property "Reference" "R1020"
			(at 0 0 270)
			(layer "F.SilkS")
			(hide yes)
			(effects
				(font
					(size 1.27 1.27)
				)
			)
		)
		(property "Value" ""
			(at 0 0 270)
			(layer "F.Fab")
			(effects
				(font
					(size 1.27 1.27)
				)
			)
		)
		(duplicate_pad_numbers_are_jumpers no)
		(fp_line
			(start -0.32512 0.175006)
			(end -0.32512 -0.175006)
			(stroke
				(width 0.1)
				(type default)
			)
			(layer "F.Fab")
		)
		(fp_line
			(start 0.32512 0.175006)
			(end -0.32512 0.175006)
			(stroke
				(width 0.1)
				(type default)
			)
			(layer "F.Fab")
		)
		(fp_line
			(start -0.32512 -0.175006)
			(end 0.32512 -0.175006)
			(stroke
				(width 0.1)
				(type default)
			)
			(layer "F.Fab")
		)
		(fp_line
			(start 0.32512 -0.175006)
			(end 0.32512 0.175006)
			(stroke
				(width 0.1)
				(type default)
			)
			(layer "F.Fab")
		)
		(pad "1" smd rect
			(at -0.2667 0 270)
			(size 0.3048 0.381)
			(layers "F.Cu" "F.Mask" "F.Paste")
			(net "RST_RT_CPU0_P1_RESET_R_N")
		)
		(pad "2" smd rect
			(at 0.2667 0 90)
			(size 0.3048 0.381)
			(layers "F.Cu" "F.Mask" "F.Paste")
			(net "GND")
		)
	)
	(footprint ""
		(layer "F.Cu")
		(at 441.430156 -399.213578 90)
		(property "Reference" "PC6552"
			(at 0 0 90)
			(layer "F.SilkS")
			(hide yes)
			(effects
				(font
					(size 1.27 1.27)
				)
			)
		)
		(property "Value" ""
			(at 0 0 90)
			(layer "F.Fab")
			(effects
				(font
					(size 1.27 1.27)
				)
			)
		)
		(duplicate_pad_numbers_are_jumpers no)
		(fp_line
			(start 0.7874 -0.4064)
			(end 0.7874 -0.105156)
			(stroke
				(width 0.1524)
				(type default)
			)
			(layer "F.SilkS")
		)
		(fp_line
			(start -0.7874 -0.4064)
			(end 0.7874 -0.4064)
			(stroke
				(width 0.1524)
				(type default)
			)
			(layer "F.SilkS")
		)
		(fp_line
			(start 0.582422 0.4064)
			(end -0.7874 0.4064)
			(stroke
				(width 0.1524)
				(type default)
			)
			(layer "F.SilkS")
		)
		(fp_line
			(start -0.7874 0.4064)
			(end -0.7874 -0.4064)
			(stroke
				(width 0.1524)
				(type default)
			)
			(layer "F.SilkS")
		)
		(fp_line
			(start -0.12065 -0.305054)
			(end -0.12065 -0.2794)
			(stroke
				(width 0.1)
				(type default)
			)
			(layer "F.Fab")
		)
		(fp_line
			(start -0.67945 -0.305054)
			(end -0.12065 -0.305054)
			(stroke
				(width 0.1)
				(type default)
			)
			(layer "F.Fab")
		)
		(fp_line
			(start 0.67945 -0.3048)
			(end 0.67945 0.3048)
			(stroke
				(width 0.1)
				(type default)
			)
			(layer "F.Fab")
		)
		(fp_line
			(start 0.12065 -0.3048)
			(end 0.67945 -0.3048)
			(stroke
				(width 0.1)
				(type default)
			)
			(layer "F.Fab")
		)
		(fp_line
			(start 0.12065 -0.2794)
			(end 0.12065 -0.3048)
			(stroke
				(width 0.1)
				(type default)
			)
			(layer "F.Fab")
		)
		(fp_line
			(start -0.12065 -0.2794)
			(end 0.12065 -0.2794)
			(stroke
				(width 0.1)
				(type default)
			)
			(layer "F.Fab")
		)
		(fp_line
			(start 0.120396 0.2794)
			(end -0.12065 0.2794)
			(stroke
				(width 0.1)
				(type default)
			)
			(layer "F.Fab")
		)
		(fp_line
			(start -0.12065 0.2794)
			(end -0.12065 0.3048)
			(stroke
				(width 0.1)
				(type default)
			)
			(layer "F.Fab")
		)
		(fp_line
			(start 0.67945 0.3048)
			(end 0.120396 0.3048)
			(stroke
				(width 0.1)
				(type default)
			)
			(layer "F.Fab")
		)
		(fp_line
			(start 0.120396 0.3048)
			(end 0.120396 0.2794)
			(stroke
				(width 0.1)
				(type default)
			)
			(layer "F.Fab")
		)
		(fp_line
			(start -0.12065 0.3048)
			(end -0.67945 0.3048)
			(stroke
				(width 0.1)
				(type default)
			)
			(layer "F.Fab")
		)
		(fp_line
			(start -0.67945 0.3048)
			(end -0.67945 -0.305054)
			(stroke
				(width 0.1)
				(type default)
			)
			(layer "F.Fab")
		)
		(pad "1" smd circle
			(at -0.40005 0 90)
			(size 0 0)
			(layers "F.Cu" "F.Mask" "F.Paste")
			(net "P0V9_RETIMER_CPU0_VCC1")
		)
		(pad "2" smd circle
			(at 0.40005 0 90)
			(size 0 0)
			(layers "F.Cu" "F.Mask" "F.Paste")
			(net "GND")
		)
	)
	(footprint ""
		(layer "F.Cu")
		(at 196.469 -92.456)
		(property "Reference" "R8040"
			(at 0 0 0)
			(layer "F.SilkS")
			(hide yes)
			(effects
				(font
					(size 1.27 1.27)
				)
			)
		)
		(property "Value" ""
			(at 0 0 0)
			(layer "F.Fab")
			(effects
				(font
					(size 1.27 1.27)
				)
			)
		)
		(duplicate_pad_numbers_are_jumpers no)
		(fp_line
			(start -0.7874 -0.4064)
			(end 0.7874 -0.4064)
			(stroke
				(width 0.1524)
				(type default)
			)
			(layer "F.SilkS")
		)
		(fp_line
			(start -0.7874 0.4064)
			(end -0.7874 -0.4064)
			(stroke
				(width 0.1524)
				(type default)
			)
			(layer "F.SilkS")
		)
		(fp_line
			(start 0.7874 -0.4064)
			(end 0.7874 0.4064)
			(stroke
				(width 0.1524)
				(type default)
			)
			(layer "F.SilkS")
		)
		(fp_line
			(start 0.7874 0.4064)
			(end -0.7874 0.4064)
			(stroke
				(width 0.1524)
				(type default)
			)
			(layer "F.SilkS")
		)
		(fp_line
			(start -0.67945 -0.305054)
			(end -0.12065 -0.305054)
			(stroke
				(width 0.1)
				(type default)
			)
			(layer "F.Fab")
		)
		(fp_line
			(start -0.67945 0.3048)
			(end -0.67945 -0.305054)
			(stroke
				(width 0.1)
				(type default)
			)
			(layer "F.Fab")
		)
		(fp_line
			(start -0.12065 -0.305054)
			(end -0.12065 -0.2794)
			(stroke
				(width 0.1)
				(type default)
			)
			(layer "F.Fab")
		)
		(fp_line
			(start -0.12065 -0.2794)
			(end 0.12065 -0.2794)
			(stroke
				(width 0.1)
				(type default)
			)
			(layer "F.Fab")
		)
		(fp_line
			(start -0.12065 0.2794)
			(end -0.12065 0.3048)
			(stroke
				(width 0.1)
				(type default)
			)
			(layer "F.Fab")
		)
		(fp_line
			(start -0.12065 0.3048)
			(end -0.67945 0.3048)
			(stroke
				(width 0.1)
				(type default)
			)
			(layer "F.Fab")
		)
		(fp_line
			(start 0.120396 0.2794)
			(end -0.12065 0.2794)
			(stroke
				(width 0.1)
				(type default)
			)
			(layer "F.Fab")
		)
		(fp_line
			(start 0.120396 0.3048)
			(end 0.120396 0.2794)
			(stroke
				(width 0.1)
				(type default)
			)
			(layer "F.Fab")
		)
		(fp_line
			(start 0.12065 -0.3048)
			(end 0.67945 -0.3048)
			(stroke
				(width 0.1)
				(type default)
			)
			(layer "F.Fab")
		)
		(fp_line
			(start 0.12065 -0.2794)
			(end 0.12065 -0.3048)
			(stroke
				(width 0.1)
				(type default)
			)
			(layer "F.Fab")
		)
		(fp_line
			(start 0.67945 -0.3048)
			(end 0.67945 0.3048)
			(stroke
				(width 0.1)
				(type default)
			)
			(layer "F.Fab")
		)
		(fp_line
			(start 0.67945 0.3048)
			(end 0.120396 0.3048)
			(stroke
				(width 0.1)
				(type default)
			)
			(layer "F.Fab")
		)
		(pad "1" smd circle
			(at -0.40005 0)
			(size 0 0)
			(layers "F.Cu" "F.Mask" "F.Paste")
			(net "P3V3_AUX")
		)
		(pad "2" smd circle
			(at 0.40005 0)
			(size 0 0)
			(layers "F.Cu" "F.Mask" "F.Paste")
			(net "PWRGD_CHGL_CPU1")
		)
	)
	(footprint ""
		(layer "F.Cu")
		(at 90.209878 -145.90141)
		(property "Reference" "R8166"
			(at 0 0 0)
			(layer "F.SilkS")
			(hide yes)
			(effects
				(font
					(size 1.27 1.27)
				)
			)
		)
		(property "Value" ""
			(at 0 0 0)
			(layer "F.Fab")
			(effects
				(font
					(size 1.27 1.27)
				)
			)
		)
		(duplicate_pad_numbers_are_jumpers no)
		(fp_line
			(start -0.7874 -0.4064)
			(end 0.7874 -0.4064)
			(stroke
				(width 0.1524)
				(type default)
			)
			(layer "F.SilkS")
		)
		(fp_line
			(start -0.7874 0.4064)
			(end -0.7874 -0.4064)
			(stroke
				(width 0.1524)
				(type default)
			)
			(layer "F.SilkS")
		)
		(fp_line
			(start 0.7874 -0.4064)
			(end 0.7874 0.4064)
			(stroke
				(width 0.1524)
				(type default)
			)
			(layer "F.SilkS")
		)
		(fp_line
			(start 0.7874 0.4064)
			(end -0.7874 0.4064)
			(stroke
				(width 0.1524)
				(type default)
			)
			(layer "F.SilkS")
		)
		(fp_line
			(start -0.67945 -0.305054)
			(end -0.12065 -0.305054)
			(stroke
				(width 0.1)
				(type default)
			)
			(layer "F.Fab")
		)
		(fp_line
			(start -0.67945 0.3048)
			(end -0.67945 -0.305054)
			(stroke
				(width 0.1)
				(type default)
			)
			(layer "F.Fab")
		)
		(fp_line
			(start -0.12065 -0.305054)
			(end -0.12065 -0.2794)
			(stroke
				(width 0.1)
				(type default)
			)
			(layer "F.Fab")
		)
		(fp_line
			(start -0.12065 -0.2794)
			(end 0.12065 -0.2794)
			(stroke
				(width 0.1)
				(type default)
			)
			(layer "F.Fab")
		)
		(fp_line
			(start -0.12065 0.2794)
			(end -0.12065 0.3048)
			(stroke
				(width 0.1)
				(type default)
			)
			(layer "F.Fab")
		)
		(fp_line
			(start -0.12065 0.3048)
			(end -0.67945 0.3048)
			(stroke
				(width 0.1)
				(type default)
			)
			(layer "F.Fab")
		)
		(fp_line
			(start 0.120396 0.2794)
			(end -0.12065 0.2794)
			(stroke
				(width 0.1)
				(type default)
			)
			(layer "F.Fab")
		)
		(fp_line
			(start 0.120396 0.3048)
			(end 0.120396 0.2794)
			(stroke
				(width 0.1)
				(type default)
			)
			(layer "F.Fab")
		)
		(fp_line
			(start 0.12065 -0.3048)
			(end 0.67945 -0.3048)
			(stroke
				(width 0.1)
				(type default)
			)
			(layer "F.Fab")
		)
		(fp_line
			(start 0.12065 -0.2794)
			(end 0.12065 -0.3048)
			(stroke
				(width 0.1)
				(type default)
			)
			(layer "F.Fab")
		)
		(fp_line
			(start 0.67945 -0.3048)
			(end 0.67945 0.3048)
			(stroke
				(width 0.1)
				(type default)
			)
			(layer "F.Fab")
		)
		(fp_line
			(start 0.67945 0.3048)
			(end 0.120396 0.3048)
			(stroke
				(width 0.1)
				(type default)
			)
			(layer "F.Fab")
		)
		(pad "1" smd circle
			(at -0.40005 0)
			(size 0 0)
			(layers "F.Cu" "F.Mask" "F.Paste")
			(net "PWRGD_PVDDCR_SOC_P1")
		)
		(pad "2" smd circle
			(at 0.40005 0)
			(size 0 0)
			(layers "F.Cu" "F.Mask" "F.Paste")
			(net "PWRGD_PVDDCR_SOC_P1_R")
		)
	)
	(footprint ""
		(layer "F.Cu")
		(at 146.194018 -76.877672 90)
		(property "Reference" "PR8003"
			(at 0 0 90)
			(layer "F.SilkS")
			(hide yes)
			(effects
				(font
					(size 1.27 1.27)
				)
			)
		)
		(property "Value" ""
			(at 0 0 90)
			(layer "F.Fab")
			(effects
				(font
					(size 1.27 1.27)
				)
			)
		)
		(duplicate_pad_numbers_are_jumpers no)
		(fp_line
			(start 0.7874 -0.4064)
			(end 0.7874 0.4064)
			(stroke
				(width 0.1524)
				(type default)
			)
			(layer "F.SilkS")
		)
		(fp_line
			(start -0.7874 -0.4064)
			(end 0.7874 -0.4064)
			(stroke
				(width 0.1524)
				(type default)
			)
			(layer "F.SilkS")
		)
		(fp_line
			(start 0.7874 0.4064)
			(end -0.7874 0.4064)
			(stroke
				(width 0.1524)
				(type default)
			)
			(layer "F.SilkS")
		)
		(fp_line
			(start -0.7874 0.4064)
			(end -0.7874 -0.4064)
			(stroke
				(width 0.1524)
				(type default)
			)
			(layer "F.SilkS")
		)
		(fp_line
			(start -0.12065 -0.305054)
			(end -0.12065 -0.2794)
			(stroke
				(width 0.1)
				(type default)
			)
			(layer "F.Fab")
		)
		(fp_line
			(start -0.67945 -0.305054)
			(end -0.12065 -0.305054)
			(stroke
				(width 0.1)
				(type default)
			)
			(layer "F.Fab")
		)
		(fp_line
			(start 0.67945 -0.3048)
			(end 0.67945 0.3048)
			(stroke
				(width 0.1)
				(type default)
			)
			(layer "F.Fab")
		)
		(fp_line
			(start 0.12065 -0.3048)
			(end 0.67945 -0.3048)
			(stroke
				(width 0.1)
				(type default)
			)
			(layer "F.Fab")
		)
		(fp_line
			(start 0.12065 -0.2794)
			(end 0.12065 -0.3048)
			(stroke
				(width 0.1)
				(type default)
			)
			(layer "F.Fab")
		)
		(fp_line
			(start -0.12065 -0.2794)
			(end 0.12065 -0.2794)
			(stroke
				(width 0.1)
				(type default)
			)
			(layer "F.Fab")
		)
		(fp_line
			(start 0.120396 0.2794)
			(end -0.12065 0.2794)
			(stroke
				(width 0.1)
				(type default)
			)
			(layer "F.Fab")
		)
		(fp_line
			(start -0.12065 0.2794)
			(end -0.12065 0.3048)
			(stroke
				(width 0.1)
				(type default)
			)
			(layer "F.Fab")
		)
		(fp_line
			(start 0.67945 0.3048)
			(end 0.120396 0.3048)
			(stroke
				(width 0.1)
				(type default)
			)
			(layer "F.Fab")
		)
		(fp_line
			(start 0.120396 0.3048)
			(end 0.120396 0.2794)
			(stroke
				(width 0.1)
				(type default)
			)
			(layer "F.Fab")
		)
		(fp_line
			(start -0.12065 0.3048)
			(end -0.67945 0.3048)
			(stroke
				(width 0.1)
				(type default)
			)
			(layer "F.Fab")
		)
		(fp_line
			(start -0.67945 0.3048)
			(end -0.67945 -0.305054)
			(stroke
				(width 0.1)
				(type default)
			)
			(layer "F.Fab")
		)
		(pad "1" smd circle
			(at -0.40005 0 90)
			(size 0 0)
			(layers "F.Cu" "F.Mask" "F.Paste")
			(net "SW_P1V8_AUX_BT")
		)
		(pad "2" smd circle
			(at 0.40005 0 90)
			(size 0 0)
			(layers "F.Cu" "F.Mask" "F.Paste")
			(net "SW_P1V8_AUX_BT_R")
		)
	)
	(footprint ""
		(layer "F.Cu")
		(at 116.36121 -61.602112 90)
		(property "Reference" "C1554"
			(at 0 0 90)
			(layer "F.SilkS")
			(hide yes)
			(effects
				(font
					(size 1.27 1.27)
				)
			)
		)
		(property "Value" ""
			(at 0 0 90)
			(layer "F.Fab")
			(effects
				(font
					(size 1.27 1.27)
				)
			)
		)
		(duplicate_pad_numbers_are_jumpers no)
		(fp_line
			(start 0.7874 -0.4064)
			(end 0.7874 0.4064)
			(stroke
				(width 0.1524)
				(type default)
			)
			(layer "F.SilkS")
		)
		(fp_line
			(start -0.7874 -0.4064)
			(end 0.7874 -0.4064)
			(stroke
				(width 0.1524)
				(type default)
			)
			(layer "F.SilkS")
		)
		(fp_line
			(start 0.7874 0.4064)
			(end -0.7874 0.4064)
			(stroke
				(width 0.1524)
				(type default)
			)
			(layer "F.SilkS")
		)
		(fp_line
			(start -0.7874 0.4064)
			(end -0.7874 -0.4064)
			(stroke
				(width 0.1524)
				(type default)
			)
			(layer "F.SilkS")
		)
		(fp_line
			(start -0.12065 -0.305054)
			(end -0.12065 -0.2794)
			(stroke
				(width 0.1)
				(type default)
			)
			(layer "F.Fab")
		)
		(fp_line
			(start -0.67945 -0.305054)
			(end -0.12065 -0.305054)
			(stroke
				(width 0.1)
				(type default)
			)
			(layer "F.Fab")
		)
		(fp_line
			(start 0.67945 -0.3048)
			(end 0.67945 0.3048)
			(stroke
				(width 0.1)
				(type default)
			)
			(layer "F.Fab")
		)
		(fp_line
			(start 0.12065 -0.3048)
			(end 0.67945 -0.3048)
			(stroke
				(width 0.1)
				(type default)
			)
			(layer "F.Fab")
		)
		(fp_line
			(start 0.12065 -0.2794)
			(end 0.12065 -0.3048)
			(stroke
				(width 0.1)
				(type default)
			)
			(layer "F.Fab")
		)
		(fp_line
			(start -0.12065 -0.2794)
			(end 0.12065 -0.2794)
			(stroke
				(width 0.1)
				(type default)
			)
			(layer "F.Fab")
		)
		(fp_line
			(start 0.120396 0.2794)
			(end -0.12065 0.2794)
			(stroke
				(width 0.1)
				(type default)
			)
			(layer "F.Fab")
		)
		(fp_line
			(start -0.12065 0.2794)
			(end -0.12065 0.3048)
			(stroke
				(width 0.1)
				(type default)
			)
			(layer "F.Fab")
		)
		(fp_line
			(start 0.67945 0.3048)
			(end 0.120396 0.3048)
			(stroke
				(width 0.1)
				(type default)
			)
			(layer "F.Fab")
		)
		(fp_line
			(start 0.120396 0.3048)
			(end 0.120396 0.2794)
			(stroke
				(width 0.1)
				(type default)
			)
			(layer "F.Fab")
		)
		(fp_line
			(start -0.12065 0.3048)
			(end -0.67945 0.3048)
			(stroke
				(width 0.1)
				(type default)
			)
			(layer "F.Fab")
		)
		(fp_line
			(start -0.67945 0.3048)
			(end -0.67945 -0.305054)
			(stroke
				(width 0.1)
				(type default)
			)
			(layer "F.Fab")
		)
		(pad "1" smd circle
			(at -0.40005 0 90)
			(size 0 0)
			(layers "F.Cu" "F.Mask" "F.Paste")
			(net "P3V3_AUX")
		)
		(pad "2" smd circle
			(at 0.40005 0 90)
			(size 0 0)
			(layers "F.Cu" "F.Mask" "F.Paste")
			(net "GND")
		)
	)
	(footprint ""
		(layer "F.Cu")
		(at 78.028546 -394.166852 -90)
		(property "Reference" "R794"
			(at 0 0 270)
			(layer "F.SilkS")
			(hide yes)
			(effects
				(font
					(size 1.27 1.27)
				)
			)
		)
		(property "Value" ""
			(at 0 0 270)
			(layer "F.Fab")
			(effects
				(font
					(size 1.27 1.27)
				)
			)
		)
		(duplicate_pad_numbers_are_jumpers no)
		(fp_line
			(start -0.32512 0.175006)
			(end -0.32512 -0.175006)
			(stroke
				(width 0.1)
				(type default)
			)
			(layer "F.Fab")
		)
		(fp_line
			(start 0.32512 0.175006)
			(end -0.32512 0.175006)
			(stroke
				(width 0.1)
				(type default)
			)
			(layer "F.Fab")
		)
		(fp_line
			(start -0.32512 -0.175006)
			(end 0.32512 -0.175006)
			(stroke
				(width 0.1)
				(type default)
			)
			(layer "F.Fab")
		)
		(fp_line
			(start 0.32512 -0.175006)
			(end 0.32512 0.175006)
			(stroke
				(width 0.1)
				(type default)
			)
			(layer "F.Fab")
		)
		(pad "1" smd rect
			(at -0.2667 0 270)
			(size 0.3048 0.381)
			(layers "F.Cu" "F.Mask" "F.Paste")
			(net "MODE_RT_CPU1_P1")
		)
		(pad "2" smd rect
			(at 0.2667 0 90)
			(size 0.3048 0.381)
			(layers "F.Cu" "F.Mask" "F.Paste")
			(net "GND")
		)
	)
	(footprint ""
		(layer "F.Cu")
		(at 43.904154 -373.03583 -90)
		(property "Reference" "C832"
			(at 0 0 270)
			(layer "F.SilkS")
			(hide yes)
			(effects
				(font
					(size 1.27 1.27)
				)
			)
		)
		(property "Value" ""
			(at 0 0 270)
			(layer "F.Fab")
			(effects
				(font
					(size 1.27 1.27)
				)
			)
		)
		(duplicate_pad_numbers_are_jumpers no)
		(fp_line
			(start -0.299974 0.150114)
			(end -0.299974 -0.150114)
			(stroke
				(width 0.1)
				(type default)
			)
			(layer "F.Fab")
		)
		(fp_line
			(start 0.299974 0.150114)
			(end -0.299974 0.150114)
			(stroke
				(width 0.1)
				(type default)
			)
			(layer "F.Fab")
		)
		(fp_line
			(start -0.299974 -0.150114)
			(end 0.299974 -0.150114)
			(stroke
				(width 0.1)
				(type default)
			)
			(layer "F.Fab")
		)
		(fp_line
			(start 0.299974 -0.150114)
			(end 0.299974 0.150114)
			(stroke
				(width 0.1)
				(type default)
			)
			(layer "F.Fab")
		)
		(pad "1" smd rect
			(at -0.2667 0 270)
			(size 0.3048 0.381)
			(layers "F.Cu" "F.Mask" "F.Paste")
			(net "P5E_CPU1_P0_TX_C_DN<2>")
		)
		(pad "2" smd rect
			(at 0.2667 0 270)
			(size 0.3048 0.381)
			(layers "F.Cu" "F.Mask" "F.Paste")
			(net "P5E_CPU1_P0_TX_DN<2>")
		)
	)
	(footprint ""
		(layer "F.Cu")
		(at 250.30303 -45.995082 -90)
		(property "Reference" "PR3960"
			(at 0 0 270)
			(layer "F.SilkS")
			(hide yes)
			(effects
				(font
					(size 1.27 1.27)
				)
			)
		)
		(property "Value" ""
			(at 0 0 270)
			(layer "F.Fab")
			(effects
				(font
					(size 1.27 1.27)
				)
			)
		)
		(duplicate_pad_numbers_are_jumpers no)
		(fp_line
			(start -0.7874 0.4064)
			(end -0.7874 -0.4064)
			(stroke
				(width 0.1524)
				(type default)
			)
			(layer "F.SilkS")
		)
		(fp_line
			(start 0.7874 0.4064)
			(end -0.7874 0.4064)
			(stroke
				(width 0.1524)
				(type default)
			)
			(layer "F.SilkS")
		)
		(fp_line
			(start -0.7874 -0.4064)
			(end 0.7874 -0.4064)
			(stroke
				(width 0.1524)
				(type default)
			)
			(layer "F.SilkS")
		)
		(fp_line
			(start 0.7874 -0.4064)
			(end 0.7874 0.4064)
			(stroke
				(width 0.1524)
				(type default)
			)
			(layer "F.SilkS")
		)
		(fp_line
			(start -0.67945 0.3048)
			(end -0.67945 -0.305054)
			(stroke
				(width 0.1)
				(type default)
			)
			(layer "F.Fab")
		)
		(fp_line
			(start -0.12065 0.3048)
			(end -0.67945 0.3048)
			(stroke
				(width 0.1)
				(type default)
			)
			(layer "F.Fab")
		)
		(fp_line
			(start 0.120396 0.3048)
			(end 0.120396 0.2794)
			(stroke
				(width 0.1)
				(type default)
			)
			(layer "F.Fab")
		)
		(fp_line
			(start 0.67945 0.3048)
			(end 0.120396 0.3048)
			(stroke
				(width 0.1)
				(type default)
			)
			(layer "F.Fab")
		)
		(fp_line
			(start -0.12065 0.2794)
			(end -0.12065 0.3048)
			(stroke
				(width 0.1)
				(type default)
			)
			(layer "F.Fab")
		)
		(fp_line
			(start 0.120396 0.2794)
			(end -0.12065 0.2794)
			(stroke
				(width 0.1)
				(type default)
			)
			(layer "F.Fab")
		)
		(fp_line
			(start -0.12065 -0.2794)
			(end 0.12065 -0.2794)
			(stroke
				(width 0.1)
				(type default)
			)
			(layer "F.Fab")
		)
		(fp_line
			(start 0.12065 -0.2794)
			(end 0.12065 -0.3048)
			(stroke
				(width 0.1)
				(type default)
			)
			(layer "F.Fab")
		)
		(fp_line
			(start 0.12065 -0.3048)
			(end 0.67945 -0.3048)
			(stroke
				(width 0.1)
				(type default)
			)
			(layer "F.Fab")
		)
		(fp_line
			(start 0.67945 -0.3048)
			(end 0.67945 0.3048)
			(stroke
				(width 0.1)
				(type default)
			)
			(layer "F.Fab")
		)
		(fp_line
			(start -0.67945 -0.305054)
			(end -0.12065 -0.305054)
			(stroke
				(width 0.1)
				(type default)
			)
			(layer "F.Fab")
		)
		(fp_line
			(start -0.12065 -0.305054)
			(end -0.12065 -0.2794)
			(stroke
				(width 0.1)
				(type default)
			)
			(layer "F.Fab")
		)
		(pad "1" smd circle
			(at -0.40005 0 270)
			(size 0 0)
			(layers "F.Cu" "F.Mask" "F.Paste")
			(net "P12V_AUX")
		)
		(pad "2" smd circle
			(at 0.40005 0 270)
			(size 0 0)
			(layers "F.Cu" "F.Mask" "F.Paste")
			(net "P12V_E1S_UV_0")
		)
	)
	(footprint ""
		(layer "F.Cu")
		(at 317.246 -362.839 90)
		(property "Reference" "PR600"
			(at 0 0 90)
			(layer "F.SilkS")
			(hide yes)
			(effects
				(font
					(size 1.27 1.27)
				)
			)
		)
		(property "Value" ""
			(at 0 0 90)
			(layer "F.Fab")
			(effects
				(font
					(size 1.27 1.27)
				)
			)
		)
		(duplicate_pad_numbers_are_jumpers no)
		(fp_line
			(start 0.7874 -0.4064)
			(end 0.7874 0.4064)
			(stroke
				(width 0.1524)
				(type default)
			)
			(layer "F.SilkS")
		)
		(fp_line
			(start -0.7874 -0.4064)
			(end 0.7874 -0.4064)
			(stroke
				(width 0.1524)
				(type default)
			)
			(layer "F.SilkS")
		)
		(fp_line
			(start 0.7874 0.4064)
			(end -0.7874 0.4064)
			(stroke
				(width 0.1524)
				(type default)
			)
			(layer "F.SilkS")
		)
		(fp_line
			(start -0.7874 0.4064)
			(end -0.7874 -0.4064)
			(stroke
				(width 0.1524)
				(type default)
			)
			(layer "F.SilkS")
		)
		(fp_line
			(start -0.12065 -0.305054)
			(end -0.12065 -0.2794)
			(stroke
				(width 0.1)
				(type default)
			)
			(layer "F.Fab")
		)
		(fp_line
			(start -0.67945 -0.305054)
			(end -0.12065 -0.305054)
			(stroke
				(width 0.1)
				(type default)
			)
			(layer "F.Fab")
		)
		(fp_line
			(start 0.67945 -0.3048)
			(end 0.67945 0.3048)
			(stroke
				(width 0.1)
				(type default)
			)
			(layer "F.Fab")
		)
		(fp_line
			(start 0.12065 -0.3048)
			(end 0.67945 -0.3048)
			(stroke
				(width 0.1)
				(type default)
			)
			(layer "F.Fab")
		)
		(fp_line
			(start 0.12065 -0.2794)
			(end 0.12065 -0.3048)
			(stroke
				(width 0.1)
				(type default)
			)
			(layer "F.Fab")
		)
		(fp_line
			(start -0.12065 -0.2794)
			(end 0.12065 -0.2794)
			(stroke
				(width 0.1)
				(type default)
			)
			(layer "F.Fab")
		)
		(fp_line
			(start 0.120396 0.2794)
			(end -0.12065 0.2794)
			(stroke
				(width 0.1)
				(type default)
			)
			(layer "F.Fab")
		)
		(fp_line
			(start -0.12065 0.2794)
			(end -0.12065 0.3048)
			(stroke
				(width 0.1)
				(type default)
			)
			(layer "F.Fab")
		)
		(fp_line
			(start 0.67945 0.3048)
			(end 0.120396 0.3048)
			(stroke
				(width 0.1)
				(type default)
			)
			(layer "F.Fab")
		)
		(fp_line
			(start 0.120396 0.3048)
			(end 0.120396 0.2794)
			(stroke
				(width 0.1)
				(type default)
			)
			(layer "F.Fab")
		)
		(fp_line
			(start -0.12065 0.3048)
			(end -0.67945 0.3048)
			(stroke
				(width 0.1)
				(type default)
			)
			(layer "F.Fab")
		)
		(fp_line
			(start -0.67945 0.3048)
			(end -0.67945 -0.305054)
			(stroke
				(width 0.1)
				(type default)
			)
			(layer "F.Fab")
		)
		(pad "1" smd circle
			(at -0.40005 0 90)
			(size 0 0)
			(layers "F.Cu" "F.Mask" "F.Paste")
			(net "PVDDCR_CPU1_P0_VINSEN")
		)
		(pad "2" smd circle
			(at 0.40005 0 90)
			(size 0 0)
			(layers "F.Cu" "F.Mask" "F.Paste")
			(net "GND")
		)
	)
	(footprint ""
		(layer "F.Cu")
		(at 94.631764 -408.517344 -90)
		(property "Reference" "C6659"
			(at 0 0 270)
			(layer "F.SilkS")
			(hide yes)
			(effects
				(font
					(size 1.27 1.27)
				)
			)
		)
		(property "Value" ""
			(at 0 0 270)
			(layer "F.Fab")
			(effects
				(font
					(size 1.27 1.27)
				)
			)
		)
		(duplicate_pad_numbers_are_jumpers no)
		(fp_line
			(start -0.299974 0.150114)
			(end -0.299974 -0.150114)
			(stroke
				(width 0.1)
				(type default)
			)
			(layer "F.Fab")
		)
		(fp_line
			(start 0.299974 0.150114)
			(end -0.299974 0.150114)
			(stroke
				(width 0.1)
				(type default)
			)
			(layer "F.Fab")
		)
		(fp_line
			(start -0.299974 -0.150114)
			(end 0.299974 -0.150114)
			(stroke
				(width 0.1)
				(type default)
			)
			(layer "F.Fab")
		)
		(fp_line
			(start 0.299974 -0.150114)
			(end 0.299974 0.150114)
			(stroke
				(width 0.1)
				(type default)
			)
			(layer "F.Fab")
		)
		(pad "1" smd rect
			(at -0.2667 0 270)
			(size 0.3048 0.381)
			(layers "F.Cu" "F.Mask" "F.Paste")
			(net "P5E_CPU1_P0_TX_BUF_C_DP<15>")
		)
		(pad "2" smd rect
			(at 0.2667 0 270)
			(size 0.3048 0.381)
			(layers "F.Cu" "F.Mask" "F.Paste")
			(net "P5E_CPU1_P0_TX_BUF_DP<15>")
		)
	)
	(footprint ""
		(layer "F.Cu")
		(at 116.10086 -181.240684 180)
		(property "Reference" "PL35"
			(at -0.781304 6.250178 0)
			(unlocked yes)
			(layer "F.SilkS")
			(effects
				(font
					(size 0.7874 0.5842)
					(thickness 0.1524)
				)
				(justify left)
			)
		)
		(property "Value" ""
			(at 0 0 180)
			(layer "F.Fab")
			(effects
				(font
					(size 1.27 1.27)
				)
			)
		)
		(duplicate_pad_numbers_are_jumpers no)
		(fp_line
			(start 3.750056 5.500116)
			(end 3.750056 -5.500116)
			(stroke
				(width 0.1524)
				(type default)
			)
			(layer "F.SilkS")
		)
		(fp_line
			(start 3.750056 -5.500116)
			(end 2.393442 -5.500116)
			(stroke
				(width 0.1524)
				(type default)
			)
			(layer "F.SilkS")
		)
		(fp_line
			(start 2.393442 5.500116)
			(end 3.750056 5.500116)
			(stroke
				(width 0.1524)
				(type default)
			)
			(layer "F.SilkS")
		)
		(fp_line
			(start -2.393442 5.500116)
			(end -3.750056 5.500116)
			(stroke
				(width 0.1524)
				(type default)
			)
			(layer "F.SilkS")
		)
		(fp_line
			(start -3.750056 5.500116)
			(end -3.750056 -5.500116)
			(stroke
				(width 0.1524)
				(type default)
			)
			(layer "F.SilkS")
		)
		(fp_line
			(start -3.750056 -5.500116)
			(end -2.393442 -5.500116)
			(stroke
				(width 0.1524)
				(type default)
			)
			(layer "F.SilkS")
		)
		(fp_poly
			(pts
				(xy -3.9116 -4.249928) (xy -4.3434 -4.034028) (xy -4.3434 -4.465828)
			)
			(stroke
				(width 0)
				(type default)
			)
			(fill yes)
			(layer "F.SilkS")
		)
		(fp_line
			(start 3.750056 5.500116)
			(end 3.750056 -5.500116)
			(stroke
				(width 0.1)
				(type default)
			)
			(layer "F.Fab")
		)
		(fp_line
			(start 3.750056 -5.500116)
			(end -3.750056 -5.500116)
			(stroke
				(width 0.1)
				(type default)
			)
			(layer "F.Fab")
		)
		(fp_line
			(start -3.750056 5.500116)
			(end 3.750056 5.500116)
			(stroke
				(width 0.1)
				(type default)
			)
			(layer "F.Fab")
		)
		(fp_line
			(start -3.750056 -5.500116)
			(end -3.750056 5.500116)
			(stroke
				(width 0.1)
				(type default)
			)
			(layer "F.Fab")
		)
		(fp_poly
			(pts
				(xy -4.9276 -4.757928) (xy -4.9276 -3.741928) (xy -3.9116 -4.249928)
			)
			(stroke
				(width 0)
				(type default)
			)
			(fill yes)
			(layer "F.Fab")
		)
		(pad "1" smd rect
			(at 0 -4.249928 90)
			(size 2.413 4.5212)
			(layers "F.Cu" "F.Mask" "F.Paste")
			(net "SW_PVDDCR_SOC_P1_SW1")
		)
		(pad "2" smd rect
			(at 0 -1.175004 90)
			(size 1.3716 4.5212)
			(layers "F.Cu" "F.Mask" "F.Paste")
			(net "IND_SOC_P1_CPL2")
		)
		(pad "3" smd rect
			(at 0 1.175004 90)
			(size 1.3716 4.5212)
			(layers "F.Cu" "F.Mask" "F.Paste")
			(net "GND")
		)
		(pad "4" smd rect
			(at 0 4.249928 90)
			(size 2.413 4.5212)
			(layers "F.Cu" "F.Mask" "F.Paste")
			(net "PVDDCR_SOC_P1")
		)
	)
	(footprint ""
		(layer "F.Cu")
		(at 315.651896 -339.852762 90)
		(property "Reference" "PC114_3"
			(at 0 0 90)
			(layer "F.SilkS")
			(hide yes)
			(effects
				(font
					(size 1.27 1.27)
				)
			)
		)
		(property "Value" ""
			(at 0 0 90)
			(layer "F.Fab")
			(effects
				(font
					(size 1.27 1.27)
				)
			)
		)
		(duplicate_pad_numbers_are_jumpers no)
		(fp_line
			(start 0.7874 -0.4064)
			(end 0.7874 0.4064)
			(stroke
				(width 0.1524)
				(type default)
			)
			(layer "F.SilkS")
		)
		(fp_line
			(start -0.7874 -0.4064)
			(end 0.7874 -0.4064)
			(stroke
				(width 0.1524)
				(type default)
			)
			(layer "F.SilkS")
		)
		(fp_line
			(start 0.7874 0.4064)
			(end -0.7874 0.4064)
			(stroke
				(width 0.1524)
				(type default)
			)
			(layer "F.SilkS")
		)
		(fp_line
			(start -0.7874 0.4064)
			(end -0.7874 -0.4064)
			(stroke
				(width 0.1524)
				(type default)
			)
			(layer "F.SilkS")
		)
		(fp_line
			(start -0.12065 -0.305054)
			(end -0.12065 -0.2794)
			(stroke
				(width 0.1)
				(type default)
			)
			(layer "F.Fab")
		)
		(fp_line
			(start -0.67945 -0.305054)
			(end -0.12065 -0.305054)
			(stroke
				(width 0.1)
				(type default)
			)
			(layer "F.Fab")
		)
		(fp_line
			(start 0.67945 -0.3048)
			(end 0.67945 0.3048)
			(stroke
				(width 0.1)
				(type default)
			)
			(layer "F.Fab")
		)
		(fp_line
			(start 0.12065 -0.3048)
			(end 0.67945 -0.3048)
			(stroke
				(width 0.1)
				(type default)
			)
			(layer "F.Fab")
		)
		(fp_line
			(start 0.12065 -0.2794)
			(end 0.12065 -0.3048)
			(stroke
				(width 0.1)
				(type default)
			)
			(layer "F.Fab")
		)
		(fp_line
			(start -0.12065 -0.2794)
			(end 0.12065 -0.2794)
			(stroke
				(width 0.1)
				(type default)
			)
			(layer "F.Fab")
		)
		(fp_line
			(start 0.120396 0.2794)
			(end -0.12065 0.2794)
			(stroke
				(width 0.1)
				(type default)
			)
			(layer "F.Fab")
		)
		(fp_line
			(start -0.12065 0.2794)
			(end -0.12065 0.3048)
			(stroke
				(width 0.1)
				(type default)
			)
			(layer "F.Fab")
		)
		(fp_line
			(start 0.67945 0.3048)
			(end 0.120396 0.3048)
			(stroke
				(width 0.1)
				(type default)
			)
			(layer "F.Fab")
		)
		(fp_line
			(start 0.120396 0.3048)
			(end 0.120396 0.2794)
			(stroke
				(width 0.1)
				(type default)
			)
			(layer "F.Fab")
		)
		(fp_line
			(start -0.12065 0.3048)
			(end -0.67945 0.3048)
			(stroke
				(width 0.1)
				(type default)
			)
			(layer "F.Fab")
		)
		(fp_line
			(start -0.67945 0.3048)
			(end -0.67945 -0.305054)
			(stroke
				(width 0.1)
				(type default)
			)
			(layer "F.Fab")
		)
		(pad "1" smd circle
			(at -0.40005 0 90)
			(size 0 0)
			(layers "F.Cu" "F.Mask" "F.Paste")
			(net "PVDDCR_CPU1_P0_VCCS")
		)
		(pad "2" smd circle
			(at 0.40005 0 90)
			(size 0 0)
			(layers "F.Cu" "F.Mask" "F.Paste")
			(net "GND")
		)
	)
	(footprint ""
		(layer "F.Cu")
		(at 190.43269 -41.011602 180)
		(property "Reference" "R3997"
			(at 0 0 180)
			(layer "F.SilkS")
			(hide yes)
			(effects
				(font
					(size 1.27 1.27)
				)
			)
		)
		(property "Value" ""
			(at 0 0 180)
			(layer "F.Fab")
			(effects
				(font
					(size 1.27 1.27)
				)
			)
		)
		(duplicate_pad_numbers_are_jumpers no)
		(fp_line
			(start 0.7874 0.4064)
			(end -0.7874 0.4064)
			(stroke
				(width 0.1524)
				(type default)
			)
			(layer "F.SilkS")
		)
		(fp_line
			(start 0.7874 -0.4064)
			(end 0.7874 0.4064)
			(stroke
				(width 0.1524)
				(type default)
			)
			(layer "F.SilkS")
		)
		(fp_line
			(start -0.7874 0.4064)
			(end -0.7874 -0.4064)
			(stroke
				(width 0.1524)
				(type default)
			)
			(layer "F.SilkS")
		)
		(fp_line
			(start -0.7874 -0.4064)
			(end 0.7874 -0.4064)
			(stroke
				(width 0.1524)
				(type default)
			)
			(layer "F.SilkS")
		)
		(fp_line
			(start 0.67945 0.3048)
			(end 0.120396 0.3048)
			(stroke
				(width 0.1)
				(type default)
			)
			(layer "F.Fab")
		)
		(fp_line
			(start 0.67945 -0.3048)
			(end 0.67945 0.3048)
			(stroke
				(width 0.1)
				(type default)
			)
			(layer "F.Fab")
		)
		(fp_line
			(start 0.12065 -0.2794)
			(end 0.12065 -0.3048)
			(stroke
				(width 0.1)
				(type default)
			)
			(layer "F.Fab")
		)
		(fp_line
			(start 0.12065 -0.3048)
			(end 0.67945 -0.3048)
			(stroke
				(width 0.1)
				(type default)
			)
			(layer "F.Fab")
		)
		(fp_line
			(start 0.120396 0.3048)
			(end 0.120396 0.2794)
			(stroke
				(width 0.1)
				(type default)
			)
			(layer "F.Fab")
		)
		(fp_line
			(start 0.120396 0.2794)
			(end -0.12065 0.2794)
			(stroke
				(width 0.1)
				(type default)
			)
			(layer "F.Fab")
		)
		(fp_line
			(start -0.12065 0.3048)
			(end -0.67945 0.3048)
			(stroke
				(width 0.1)
				(type default)
			)
			(layer "F.Fab")
		)
		(fp_line
			(start -0.12065 0.2794)
			(end -0.12065 0.3048)
			(stroke
				(width 0.1)
				(type default)
			)
			(layer "F.Fab")
		)
		(fp_line
			(start -0.12065 -0.2794)
			(end 0.12065 -0.2794)
			(stroke
				(width 0.1)
				(type default)
			)
			(layer "F.Fab")
		)
		(fp_line
			(start -0.12065 -0.305054)
			(end -0.12065 -0.2794)
			(stroke
				(width 0.1)
				(type default)
			)
			(layer "F.Fab")
		)
		(fp_line
			(start -0.67945 0.3048)
			(end -0.67945 -0.305054)
			(stroke
				(width 0.1)
				(type default)
			)
			(layer "F.Fab")
		)
		(fp_line
			(start -0.67945 -0.305054)
			(end -0.12065 -0.305054)
			(stroke
				(width 0.1)
				(type default)
			)
			(layer "F.Fab")
		)
		(pad "1" smd circle
			(at -0.40005 0 180)
			(size 0 0)
			(layers "F.Cu" "F.Mask" "F.Paste")
			(net "P12V_SCM_UV_R")
		)
		(pad "2" smd circle
			(at 0.40005 0 180)
			(size 0 0)
			(layers "F.Cu" "F.Mask" "F.Paste")
			(net "P12V_SCM_UV")
		)
	)
	(footprint ""
		(layer "F.Cu")
		(at 264.478516 -133.622796 180)
		(property "Reference" "R601"
			(at 0 0 180)
			(layer "F.SilkS")
			(hide yes)
			(effects
				(font
					(size 1.27 1.27)
				)
			)
		)
		(property "Value" ""
			(at 0 0 180)
			(layer "F.Fab")
			(effects
				(font
					(size 1.27 1.27)
				)
			)
		)
		(duplicate_pad_numbers_are_jumpers no)
		(fp_line
			(start 0.7874 0.4064)
			(end -0.7874 0.4064)
			(stroke
				(width 0.1524)
				(type default)
			)
			(layer "F.SilkS")
		)
		(fp_line
			(start 0.7874 -0.4064)
			(end 0.7874 0.4064)
			(stroke
				(width 0.1524)
				(type default)
			)
			(layer "F.SilkS")
		)
		(fp_line
			(start -0.7874 0.4064)
			(end -0.7874 -0.4064)
			(stroke
				(width 0.1524)
				(type default)
			)
			(layer "F.SilkS")
		)
		(fp_line
			(start -0.7874 -0.4064)
			(end 0.7874 -0.4064)
			(stroke
				(width 0.1524)
				(type default)
			)
			(layer "F.SilkS")
		)
		(fp_line
			(start 0.67945 0.3048)
			(end 0.120396 0.3048)
			(stroke
				(width 0.1)
				(type default)
			)
			(layer "F.Fab")
		)
		(fp_line
			(start 0.67945 -0.3048)
			(end 0.67945 0.3048)
			(stroke
				(width 0.1)
				(type default)
			)
			(layer "F.Fab")
		)
		(fp_line
			(start 0.12065 -0.2794)
			(end 0.12065 -0.3048)
			(stroke
				(width 0.1)
				(type default)
			)
			(layer "F.Fab")
		)
		(fp_line
			(start 0.12065 -0.3048)
			(end 0.67945 -0.3048)
			(stroke
				(width 0.1)
				(type default)
			)
			(layer "F.Fab")
		)
		(fp_line
			(start 0.120396 0.3048)
			(end 0.120396 0.2794)
			(stroke
				(width 0.1)
				(type default)
			)
			(layer "F.Fab")
		)
		(fp_line
			(start 0.120396 0.2794)
			(end -0.12065 0.2794)
			(stroke
				(width 0.1)
				(type default)
			)
			(layer "F.Fab")
		)
		(fp_line
			(start -0.12065 0.3048)
			(end -0.67945 0.3048)
			(stroke
				(width 0.1)
				(type default)
			)
			(layer "F.Fab")
		)
		(fp_line
			(start -0.12065 0.2794)
			(end -0.12065 0.3048)
			(stroke
				(width 0.1)
				(type default)
			)
			(layer "F.Fab")
		)
		(fp_line
			(start -0.12065 -0.2794)
			(end 0.12065 -0.2794)
			(stroke
				(width 0.1)
				(type default)
			)
			(layer "F.Fab")
		)
		(fp_line
			(start -0.12065 -0.305054)
			(end -0.12065 -0.2794)
			(stroke
				(width 0.1)
				(type default)
			)
			(layer "F.Fab")
		)
		(fp_line
			(start -0.67945 0.3048)
			(end -0.67945 -0.305054)
			(stroke
				(width 0.1)
				(type default)
			)
			(layer "F.Fab")
		)
		(fp_line
			(start -0.67945 -0.305054)
			(end -0.12065 -0.305054)
			(stroke
				(width 0.1)
				(type default)
			)
			(layer "F.Fab")
		)
		(pad "1" smd circle
			(at -0.40005 0 180)
			(size 0 0)
			(layers "F.Cu" "F.Mask" "F.Paste")
			(net "PVDD18_S5_P0")
		)
		(pad "2" smd circle
			(at 0.40005 0 180)
			(size 0 0)
			(layers "F.Cu" "F.Mask" "F.Paste")
			(net "SPI_CPU0_CS1_N")
		)
	)
	(footprint ""
		(layer "F.Cu")
		(at 64.591438 -31.887922 90)
		(property "Reference" "PC2167"
			(at 0 0 90)
			(layer "F.SilkS")
			(hide yes)
			(effects
				(font
					(size 1.27 1.27)
				)
			)
		)
		(property "Value" ""
			(at 0 0 90)
			(layer "F.Fab")
			(effects
				(font
					(size 1.27 1.27)
				)
			)
		)
		(duplicate_pad_numbers_are_jumpers no)
		(fp_line
			(start 0.7874 -0.4064)
			(end 0.7874 0.4064)
			(stroke
				(width 0.1524)
				(type default)
			)
			(layer "F.SilkS")
		)
		(fp_line
			(start -0.7874 -0.4064)
			(end 0.7874 -0.4064)
			(stroke
				(width 0.1524)
				(type default)
			)
			(layer "F.SilkS")
		)
		(fp_line
			(start 0.7874 0.4064)
			(end -0.7874 0.4064)
			(stroke
				(width 0.1524)
				(type default)
			)
			(layer "F.SilkS")
		)
		(fp_line
			(start -0.7874 0.4064)
			(end -0.7874 -0.4064)
			(stroke
				(width 0.1524)
				(type default)
			)
			(layer "F.SilkS")
		)
		(fp_line
			(start -0.12065 -0.305054)
			(end -0.12065 -0.2794)
			(stroke
				(width 0.1)
				(type default)
			)
			(layer "F.Fab")
		)
		(fp_line
			(start -0.67945 -0.305054)
			(end -0.12065 -0.305054)
			(stroke
				(width 0.1)
				(type default)
			)
			(layer "F.Fab")
		)
		(fp_line
			(start 0.67945 -0.3048)
			(end 0.67945 0.3048)
			(stroke
				(width 0.1)
				(type default)
			)
			(layer "F.Fab")
		)
		(fp_line
			(start 0.12065 -0.3048)
			(end 0.67945 -0.3048)
			(stroke
				(width 0.1)
				(type default)
			)
			(layer "F.Fab")
		)
		(fp_line
			(start 0.12065 -0.2794)
			(end 0.12065 -0.3048)
			(stroke
				(width 0.1)
				(type default)
			)
			(layer "F.Fab")
		)
		(fp_line
			(start -0.12065 -0.2794)
			(end 0.12065 -0.2794)
			(stroke
				(width 0.1)
				(type default)
			)
			(layer "F.Fab")
		)
		(fp_line
			(start 0.120396 0.2794)
			(end -0.12065 0.2794)
			(stroke
				(width 0.1)
				(type default)
			)
			(layer "F.Fab")
		)
		(fp_line
			(start -0.12065 0.2794)
			(end -0.12065 0.3048)
			(stroke
				(width 0.1)
				(type default)
			)
			(layer "F.Fab")
		)
		(fp_line
			(start 0.67945 0.3048)
			(end 0.120396 0.3048)
			(stroke
				(width 0.1)
				(type default)
			)
			(layer "F.Fab")
		)
		(fp_line
			(start 0.120396 0.3048)
			(end 0.120396 0.2794)
			(stroke
				(width 0.1)
				(type default)
			)
			(layer "F.Fab")
		)
		(fp_line
			(start -0.12065 0.3048)
			(end -0.67945 0.3048)
			(stroke
				(width 0.1)
				(type default)
			)
			(layer "F.Fab")
		)
		(fp_line
			(start -0.67945 0.3048)
			(end -0.67945 -0.305054)
			(stroke
				(width 0.1)
				(type default)
			)
			(layer "F.Fab")
		)
		(pad "1" smd circle
			(at -0.40005 0 90)
			(size 0 0)
			(layers "F.Cu" "F.Mask" "F.Paste")
			(net "P12V_OCP_IMON_2")
		)
		(pad "2" smd circle
			(at 0.40005 0 90)
			(size 0 0)
			(layers "F.Cu" "F.Mask" "F.Paste")
			(net "GND")
		)
	)
	(footprint ""
		(layer "F.Cu")
		(at 94.14891 -340.240874)
		(property "Reference" "PR270"
			(at 0 0 0)
			(layer "F.SilkS")
			(hide yes)
			(effects
				(font
					(size 1.27 1.27)
				)
			)
		)
		(property "Value" ""
			(at 0 0 0)
			(layer "F.Fab")
			(effects
				(font
					(size 1.27 1.27)
				)
			)
		)
		(duplicate_pad_numbers_are_jumpers no)
		(fp_line
			(start -0.7874 -0.4064)
			(end 0.7874 -0.4064)
			(stroke
				(width 0.1524)
				(type default)
			)
			(layer "F.SilkS")
		)
		(fp_line
			(start -0.7874 0.4064)
			(end -0.7874 -0.4064)
			(stroke
				(width 0.1524)
				(type default)
			)
			(layer "F.SilkS")
		)
		(fp_line
			(start 0.7874 -0.4064)
			(end 0.7874 0.4064)
			(stroke
				(width 0.1524)
				(type default)
			)
			(layer "F.SilkS")
		)
		(fp_line
			(start 0.7874 0.4064)
			(end -0.7874 0.4064)
			(stroke
				(width 0.1524)
				(type default)
			)
			(layer "F.SilkS")
		)
		(fp_line
			(start -0.67945 -0.305054)
			(end -0.12065 -0.305054)
			(stroke
				(width 0.1)
				(type default)
			)
			(layer "F.Fab")
		)
		(fp_line
			(start -0.67945 0.3048)
			(end -0.67945 -0.305054)
			(stroke
				(width 0.1)
				(type default)
			)
			(layer "F.Fab")
		)
		(fp_line
			(start -0.12065 -0.305054)
			(end -0.12065 -0.2794)
			(stroke
				(width 0.1)
				(type default)
			)
			(layer "F.Fab")
		)
		(fp_line
			(start -0.12065 -0.2794)
			(end 0.12065 -0.2794)
			(stroke
				(width 0.1)
				(type default)
			)
			(layer "F.Fab")
		)
		(fp_line
			(start -0.12065 0.2794)
			(end -0.12065 0.3048)
			(stroke
				(width 0.1)
				(type default)
			)
			(layer "F.Fab")
		)
		(fp_line
			(start -0.12065 0.3048)
			(end -0.67945 0.3048)
			(stroke
				(width 0.1)
				(type default)
			)
			(layer "F.Fab")
		)
		(fp_line
			(start 0.120396 0.2794)
			(end -0.12065 0.2794)
			(stroke
				(width 0.1)
				(type default)
			)
			(layer "F.Fab")
		)
		(fp_line
			(start 0.120396 0.3048)
			(end 0.120396 0.2794)
			(stroke
				(width 0.1)
				(type default)
			)
			(layer "F.Fab")
		)
		(fp_line
			(start 0.12065 -0.3048)
			(end 0.67945 -0.3048)
			(stroke
				(width 0.1)
				(type default)
			)
			(layer "F.Fab")
		)
		(fp_line
			(start 0.12065 -0.2794)
			(end 0.12065 -0.3048)
			(stroke
				(width 0.1)
				(type default)
			)
			(layer "F.Fab")
		)
		(fp_line
			(start 0.67945 -0.3048)
			(end 0.67945 0.3048)
			(stroke
				(width 0.1)
				(type default)
			)
			(layer "F.Fab")
		)
		(fp_line
			(start 0.67945 0.3048)
			(end 0.120396 0.3048)
			(stroke
				(width 0.1)
				(type default)
			)
			(layer "F.Fab")
		)
		(pad "1" smd circle
			(at -0.40005 0)
			(size 0 0)
			(layers "F.Cu" "F.Mask" "F.Paste")
			(net "PVDDCR_CPU1_P1_LSET5")
		)
		(pad "2" smd circle
			(at 0.40005 0)
			(size 0 0)
			(layers "F.Cu" "F.Mask" "F.Paste")
			(net "GND")
		)
	)
	(footprint ""
		(layer "F.Cu")
		(at 321.106546 -100.36175 180)
		(property "Reference" "R1326"
			(at 0 0 180)
			(layer "F.SilkS")
			(hide yes)
			(effects
				(font
					(size 1.27 1.27)
				)
			)
		)
		(property "Value" ""
			(at 0 0 180)
			(layer "F.Fab")
			(effects
				(font
					(size 1.27 1.27)
				)
			)
		)
		(duplicate_pad_numbers_are_jumpers no)
		(fp_line
			(start 0.7874 0.4064)
			(end -0.7874 0.4064)
			(stroke
				(width 0.1524)
				(type default)
			)
			(layer "F.SilkS")
		)
		(fp_line
			(start 0.7874 -0.4064)
			(end 0.7874 0.4064)
			(stroke
				(width 0.1524)
				(type default)
			)
			(layer "F.SilkS")
		)
		(fp_line
			(start -0.7874 0.4064)
			(end -0.7874 -0.4064)
			(stroke
				(width 0.1524)
				(type default)
			)
			(layer "F.SilkS")
		)
		(fp_line
			(start -0.7874 -0.4064)
			(end 0.7874 -0.4064)
			(stroke
				(width 0.1524)
				(type default)
			)
			(layer "F.SilkS")
		)
		(fp_line
			(start 0.67945 0.3048)
			(end 0.120396 0.3048)
			(stroke
				(width 0.1)
				(type default)
			)
			(layer "F.Fab")
		)
		(fp_line
			(start 0.67945 -0.3048)
			(end 0.67945 0.3048)
			(stroke
				(width 0.1)
				(type default)
			)
			(layer "F.Fab")
		)
		(fp_line
			(start 0.12065 -0.2794)
			(end 0.12065 -0.3048)
			(stroke
				(width 0.1)
				(type default)
			)
			(layer "F.Fab")
		)
		(fp_line
			(start 0.12065 -0.3048)
			(end 0.67945 -0.3048)
			(stroke
				(width 0.1)
				(type default)
			)
			(layer "F.Fab")
		)
		(fp_line
			(start 0.120396 0.3048)
			(end 0.120396 0.2794)
			(stroke
				(width 0.1)
				(type default)
			)
			(layer "F.Fab")
		)
		(fp_line
			(start 0.120396 0.2794)
			(end -0.12065 0.2794)
			(stroke
				(width 0.1)
				(type default)
			)
			(layer "F.Fab")
		)
		(fp_line
			(start -0.12065 0.3048)
			(end -0.67945 0.3048)
			(stroke
				(width 0.1)
				(type default)
			)
			(layer "F.Fab")
		)
		(fp_line
			(start -0.12065 0.2794)
			(end -0.12065 0.3048)
			(stroke
				(width 0.1)
				(type default)
			)
			(layer "F.Fab")
		)
		(fp_line
			(start -0.12065 -0.2794)
			(end 0.12065 -0.2794)
			(stroke
				(width 0.1)
				(type default)
			)
			(layer "F.Fab")
		)
		(fp_line
			(start -0.12065 -0.305054)
			(end -0.12065 -0.2794)
			(stroke
				(width 0.1)
				(type default)
			)
			(layer "F.Fab")
		)
		(fp_line
			(start -0.67945 0.3048)
			(end -0.67945 -0.305054)
			(stroke
				(width 0.1)
				(type default)
			)
			(layer "F.Fab")
		)
		(fp_line
			(start -0.67945 -0.305054)
			(end -0.12065 -0.305054)
			(stroke
				(width 0.1)
				(type default)
			)
			(layer "F.Fab")
		)
		(pad "1" smd circle
			(at -0.40005 0 180)
			(size 0 0)
			(layers "F.Cu" "F.Mask" "F.Paste")
			(net "P3V3_AUX")
		)
		(pad "2" smd circle
			(at 0.40005 0 180)
			(size 0 0)
			(layers "F.Cu" "F.Mask" "F.Paste")
			(net "E1S_0_P3V3_P12V_ADC_R_ALERT")
		)
	)
	(footprint ""
		(layer "F.Cu")
		(at 98.555302 -370.57203 -90)
		(property "Reference" "C716"
			(at 0 0 270)
			(layer "F.SilkS")
			(hide yes)
			(effects
				(font
					(size 1.27 1.27)
				)
			)
		)
		(property "Value" ""
			(at 0 0 270)
			(layer "F.Fab")
			(effects
				(font
					(size 1.27 1.27)
				)
			)
		)
		(duplicate_pad_numbers_are_jumpers no)
		(fp_line
			(start -0.299974 0.150114)
			(end -0.299974 -0.150114)
			(stroke
				(width 0.1)
				(type default)
			)
			(layer "F.Fab")
		)
		(fp_line
			(start 0.299974 0.150114)
			(end -0.299974 0.150114)
			(stroke
				(width 0.1)
				(type default)
			)
			(layer "F.Fab")
		)
		(fp_line
			(start -0.299974 -0.150114)
			(end 0.299974 -0.150114)
			(stroke
				(width 0.1)
				(type default)
			)
			(layer "F.Fab")
		)
		(fp_line
			(start 0.299974 -0.150114)
			(end 0.299974 0.150114)
			(stroke
				(width 0.1)
				(type default)
			)
			(layer "F.Fab")
		)
		(pad "1" smd rect
			(at -0.2667 0 270)
			(size 0.3048 0.381)
			(layers "F.Cu" "F.Mask" "F.Paste")
			(net "P5E_CPU1_P1_TX_C_DN<12>")
		)
		(pad "2" smd rect
			(at 0.2667 0 270)
			(size 0.3048 0.381)
			(layers "F.Cu" "F.Mask" "F.Paste")
			(net "P5E_CPU1_P1_TX_DN<12>")
		)
	)
	(footprint ""
		(layer "F.Cu")
		(at 412.75 -98.425 -90)
		(property "Reference" "R8094"
			(at 0 0 270)
			(layer "F.SilkS")
			(hide yes)
			(effects
				(font
					(size 1.27 1.27)
				)
			)
		)
		(property "Value" ""
			(at 0 0 270)
			(layer "F.Fab")
			(effects
				(font
					(size 1.27 1.27)
				)
			)
		)
		(duplicate_pad_numbers_are_jumpers no)
		(fp_line
			(start -0.7874 0.4064)
			(end -0.7874 -0.4064)
			(stroke
				(width 0.1524)
				(type default)
			)
			(layer "F.SilkS")
		)
		(fp_line
			(start 0.7874 0.4064)
			(end -0.7874 0.4064)
			(stroke
				(width 0.1524)
				(type default)
			)
			(layer "F.SilkS")
		)
		(fp_line
			(start -0.7874 -0.4064)
			(end 0.7874 -0.4064)
			(stroke
				(width 0.1524)
				(type default)
			)
			(layer "F.SilkS")
		)
		(fp_line
			(start 0.7874 -0.4064)
			(end 0.7874 0.4064)
			(stroke
				(width 0.1524)
				(type default)
			)
			(layer "F.SilkS")
		)
		(fp_line
			(start -0.67945 0.3048)
			(end -0.67945 -0.305054)
			(stroke
				(width 0.1)
				(type default)
			)
			(layer "F.Fab")
		)
		(fp_line
			(start -0.12065 0.3048)
			(end -0.67945 0.3048)
			(stroke
				(width 0.1)
				(type default)
			)
			(layer "F.Fab")
		)
		(fp_line
			(start 0.120396 0.3048)
			(end 0.120396 0.2794)
			(stroke
				(width 0.1)
				(type default)
			)
			(layer "F.Fab")
		)
		(fp_line
			(start 0.67945 0.3048)
			(end 0.120396 0.3048)
			(stroke
				(width 0.1)
				(type default)
			)
			(layer "F.Fab")
		)
		(fp_line
			(start -0.12065 0.2794)
			(end -0.12065 0.3048)
			(stroke
				(width 0.1)
				(type default)
			)
			(layer "F.Fab")
		)
		(fp_line
			(start 0.120396 0.2794)
			(end -0.12065 0.2794)
			(stroke
				(width 0.1)
				(type default)
			)
			(layer "F.Fab")
		)
		(fp_line
			(start -0.12065 -0.2794)
			(end 0.12065 -0.2794)
			(stroke
				(width 0.1)
				(type default)
			)
			(layer "F.Fab")
		)
		(fp_line
			(start 0.12065 -0.2794)
			(end 0.12065 -0.3048)
			(stroke
				(width 0.1)
				(type default)
			)
			(layer "F.Fab")
		)
		(fp_line
			(start 0.12065 -0.3048)
			(end 0.67945 -0.3048)
			(stroke
				(width 0.1)
				(type default)
			)
			(layer "F.Fab")
		)
		(fp_line
			(start 0.67945 -0.3048)
			(end 0.67945 0.3048)
			(stroke
				(width 0.1)
				(type default)
			)
			(layer "F.Fab")
		)
		(fp_line
			(start -0.67945 -0.305054)
			(end -0.12065 -0.305054)
			(stroke
				(width 0.1)
				(type default)
			)
			(layer "F.Fab")
		)
		(fp_line
			(start -0.12065 -0.305054)
			(end -0.12065 -0.2794)
			(stroke
				(width 0.1)
				(type default)
			)
			(layer "F.Fab")
		)
		(pad "1" smd circle
			(at -0.40005 0 270)
			(size 0 0)
			(layers "F.Cu" "F.Mask" "F.Paste")
			(net "OCP_V3_1_P3V3_R1_PWRGD")
		)
		(pad "2" smd circle
			(at 0.40005 0 270)
			(size 0 0)
			(layers "F.Cu" "F.Mask" "F.Paste")
			(net "OCP_V3_1_P3V3_PWRGD")
		)
	)
	(footprint ""
		(layer "F.Cu")
		(at 357.93426 -326.58431 180)
		(property "Reference" "PR49"
			(at 0 0 180)
			(layer "F.SilkS")
			(hide yes)
			(effects
				(font
					(size 1.27 1.27)
				)
			)
		)
		(property "Value" ""
			(at 0 0 180)
			(layer "F.Fab")
			(effects
				(font
					(size 1.27 1.27)
				)
			)
		)
		(duplicate_pad_numbers_are_jumpers no)
		(fp_line
			(start 0.7874 0.4064)
			(end -0.7874 0.4064)
			(stroke
				(width 0.1524)
				(type default)
			)
			(layer "F.SilkS")
		)
		(fp_line
			(start 0.7874 -0.4064)
			(end 0.7874 0.4064)
			(stroke
				(width 0.1524)
				(type default)
			)
			(layer "F.SilkS")
		)
		(fp_line
			(start -0.7874 0.4064)
			(end -0.7874 -0.4064)
			(stroke
				(width 0.1524)
				(type default)
			)
			(layer "F.SilkS")
		)
		(fp_line
			(start -0.7874 -0.4064)
			(end 0.7874 -0.4064)
			(stroke
				(width 0.1524)
				(type default)
			)
			(layer "F.SilkS")
		)
		(fp_line
			(start 0.67945 0.3048)
			(end 0.120396 0.3048)
			(stroke
				(width 0.1)
				(type default)
			)
			(layer "F.Fab")
		)
		(fp_line
			(start 0.67945 -0.3048)
			(end 0.67945 0.3048)
			(stroke
				(width 0.1)
				(type default)
			)
			(layer "F.Fab")
		)
		(fp_line
			(start 0.12065 -0.2794)
			(end 0.12065 -0.3048)
			(stroke
				(width 0.1)
				(type default)
			)
			(layer "F.Fab")
		)
		(fp_line
			(start 0.12065 -0.3048)
			(end 0.67945 -0.3048)
			(stroke
				(width 0.1)
				(type default)
			)
			(layer "F.Fab")
		)
		(fp_line
			(start 0.120396 0.3048)
			(end 0.120396 0.2794)
			(stroke
				(width 0.1)
				(type default)
			)
			(layer "F.Fab")
		)
		(fp_line
			(start 0.120396 0.2794)
			(end -0.12065 0.2794)
			(stroke
				(width 0.1)
				(type default)
			)
			(layer "F.Fab")
		)
		(fp_line
			(start -0.12065 0.3048)
			(end -0.67945 0.3048)
			(stroke
				(width 0.1)
				(type default)
			)
			(layer "F.Fab")
		)
		(fp_line
			(start -0.12065 0.2794)
			(end -0.12065 0.3048)
			(stroke
				(width 0.1)
				(type default)
			)
			(layer "F.Fab")
		)
		(fp_line
			(start -0.12065 -0.2794)
			(end 0.12065 -0.2794)
			(stroke
				(width 0.1)
				(type default)
			)
			(layer "F.Fab")
		)
		(fp_line
			(start -0.12065 -0.305054)
			(end -0.12065 -0.2794)
			(stroke
				(width 0.1)
				(type default)
			)
			(layer "F.Fab")
		)
		(fp_line
			(start -0.67945 0.3048)
			(end -0.67945 -0.305054)
			(stroke
				(width 0.1)
				(type default)
			)
			(layer "F.Fab")
		)
		(fp_line
			(start -0.67945 -0.305054)
			(end -0.12065 -0.305054)
			(stroke
				(width 0.1)
				(type default)
			)
			(layer "F.Fab")
		)
		(pad "1" smd circle
			(at -0.40005 0 180)
			(size 0 0)
			(layers "F.Cu" "F.Mask" "F.Paste")
			(net "VSENSE_VSS_SENSE_C_P0")
		)
		(pad "2" smd circle
			(at 0.40005 0 180)
			(size 0 0)
			(layers "F.Cu" "F.Mask" "F.Paste")
			(net "GND")
		)
	)
	(footprint ""
		(layer "F.Cu")
		(at 302.133 -358.14 180)
		(property "Reference" "C304"
			(at 0 0 180)
			(layer "F.SilkS")
			(hide yes)
			(effects
				(font
					(size 1.27 1.27)
				)
			)
		)
		(property "Value" ""
			(at 0 0 180)
			(layer "F.Fab")
			(effects
				(font
					(size 1.27 1.27)
				)
			)
		)
		(duplicate_pad_numbers_are_jumpers no)
		(fp_line
			(start 0.7874 0.4064)
			(end -0.7874 0.4064)
			(stroke
				(width 0.1524)
				(type default)
			)
			(layer "F.SilkS")
		)
		(fp_line
			(start 0.7874 -0.4064)
			(end 0.7874 0.4064)
			(stroke
				(width 0.1524)
				(type default)
			)
			(layer "F.SilkS")
		)
		(fp_line
			(start -0.7874 0.4064)
			(end -0.7874 -0.4064)
			(stroke
				(width 0.1524)
				(type default)
			)
			(layer "F.SilkS")
		)
		(fp_line
			(start -0.7874 -0.4064)
			(end 0.7874 -0.4064)
			(stroke
				(width 0.1524)
				(type default)
			)
			(layer "F.SilkS")
		)
		(fp_line
			(start 0.67945 0.3048)
			(end 0.120396 0.3048)
			(stroke
				(width 0.1)
				(type default)
			)
			(layer "F.Fab")
		)
		(fp_line
			(start 0.67945 -0.3048)
			(end 0.67945 0.3048)
			(stroke
				(width 0.1)
				(type default)
			)
			(layer "F.Fab")
		)
		(fp_line
			(start 0.12065 -0.2794)
			(end 0.12065 -0.3048)
			(stroke
				(width 0.1)
				(type default)
			)
			(layer "F.Fab")
		)
		(fp_line
			(start 0.12065 -0.3048)
			(end 0.67945 -0.3048)
			(stroke
				(width 0.1)
				(type default)
			)
			(layer "F.Fab")
		)
		(fp_line
			(start 0.120396 0.3048)
			(end 0.120396 0.2794)
			(stroke
				(width 0.1)
				(type default)
			)
			(layer "F.Fab")
		)
		(fp_line
			(start 0.120396 0.2794)
			(end -0.12065 0.2794)
			(stroke
				(width 0.1)
				(type default)
			)
			(layer "F.Fab")
		)
		(fp_line
			(start -0.12065 0.3048)
			(end -0.67945 0.3048)
			(stroke
				(width 0.1)
				(type default)
			)
			(layer "F.Fab")
		)
		(fp_line
			(start -0.12065 0.2794)
			(end -0.12065 0.3048)
			(stroke
				(width 0.1)
				(type default)
			)
			(layer "F.Fab")
		)
		(fp_line
			(start -0.12065 -0.2794)
			(end 0.12065 -0.2794)
			(stroke
				(width 0.1)
				(type default)
			)
			(layer "F.Fab")
		)
		(fp_line
			(start -0.12065 -0.305054)
			(end -0.12065 -0.2794)
			(stroke
				(width 0.1)
				(type default)
			)
			(layer "F.Fab")
		)
		(fp_line
			(start -0.67945 0.3048)
			(end -0.67945 -0.305054)
			(stroke
				(width 0.1)
				(type default)
			)
			(layer "F.Fab")
		)
		(fp_line
			(start -0.67945 -0.305054)
			(end -0.12065 -0.305054)
			(stroke
				(width 0.1)
				(type default)
			)
			(layer "F.Fab")
		)
		(pad "1" smd circle
			(at -0.40005 0 180)
			(size 0 0)
			(layers "F.Cu" "F.Mask" "F.Paste")
			(net "SVID_PVDDCR_CPU1_P0_SVD_R")
		)
		(pad "2" smd circle
			(at 0.40005 0 180)
			(size 0 0)
			(layers "F.Cu" "F.Mask" "F.Paste")
			(net "GND")
		)
	)
	(footprint ""
		(layer "F.Cu")
		(at 111.004096 -373.03583 -90)
		(property "Reference" "C1542"
			(at 0 0 270)
			(layer "F.SilkS")
			(hide yes)
			(effects
				(font
					(size 1.27 1.27)
				)
			)
		)
		(property "Value" ""
			(at 0 0 270)
			(layer "F.Fab")
			(effects
				(font
					(size 1.27 1.27)
				)
			)
		)
		(duplicate_pad_numbers_are_jumpers no)
		(fp_line
			(start -0.299974 0.150114)
			(end -0.299974 -0.150114)
			(stroke
				(width 0.1)
				(type default)
			)
			(layer "F.Fab")
		)
		(fp_line
			(start 0.299974 0.150114)
			(end -0.299974 0.150114)
			(stroke
				(width 0.1)
				(type default)
			)
			(layer "F.Fab")
		)
		(fp_line
			(start -0.299974 -0.150114)
			(end 0.299974 -0.150114)
			(stroke
				(width 0.1)
				(type default)
			)
			(layer "F.Fab")
		)
		(fp_line
			(start 0.299974 -0.150114)
			(end 0.299974 0.150114)
			(stroke
				(width 0.1)
				(type default)
			)
			(layer "F.Fab")
		)
		(pad "1" smd rect
			(at -0.2667 0 270)
			(size 0.3048 0.381)
			(layers "F.Cu" "F.Mask" "F.Paste")
			(net "P5E_CPU1_P3_TX_C_DN<2>")
		)
		(pad "2" smd rect
			(at 0.2667 0 270)
			(size 0.3048 0.381)
			(layers "F.Cu" "F.Mask" "F.Paste")
			(net "P5E_CPU1_P3_TX_DN<2>")
		)
	)
	(footprint ""
		(layer "F.Cu")
		(at 142.437866 -408.517344 -90)
		(property "Reference" "C6712"
			(at 0 0 270)
			(layer "F.SilkS")
			(hide yes)
			(effects
				(font
					(size 1.27 1.27)
				)
			)
		)
		(property "Value" ""
			(at 0 0 270)
			(layer "F.Fab")
			(effects
				(font
					(size 1.27 1.27)
				)
			)
		)
		(duplicate_pad_numbers_are_jumpers no)
		(fp_line
			(start -0.299974 0.150114)
			(end -0.299974 -0.150114)
			(stroke
				(width 0.1)
				(type default)
			)
			(layer "F.Fab")
		)
		(fp_line
			(start 0.299974 0.150114)
			(end -0.299974 0.150114)
			(stroke
				(width 0.1)
				(type default)
			)
			(layer "F.Fab")
		)
		(fp_line
			(start -0.299974 -0.150114)
			(end 0.299974 -0.150114)
			(stroke
				(width 0.1)
				(type default)
			)
			(layer "F.Fab")
		)
		(fp_line
			(start 0.299974 -0.150114)
			(end 0.299974 0.150114)
			(stroke
				(width 0.1)
				(type default)
			)
			(layer "F.Fab")
		)
		(pad "1" smd rect
			(at -0.2667 0 270)
			(size 0.3048 0.381)
			(layers "F.Cu" "F.Mask" "F.Paste")
			(net "P5E_CPU1_P2_TX_BUF_C_DN<9>")
		)
		(pad "2" smd rect
			(at 0.2667 0 270)
			(size 0.3048 0.381)
			(layers "F.Cu" "F.Mask" "F.Paste")
			(net "P5E_CPU1_P2_TX_BUF_DN<9>")
		)
	)
	(footprint ""
		(layer "F.Cu")
		(at 11.7221 -394.22832 -90)
		(property "Reference" "PR6619"
			(at 0 0 270)
			(layer "F.SilkS")
			(hide yes)
			(effects
				(font
					(size 1.27 1.27)
				)
			)
		)
		(property "Value" ""
			(at 0 0 270)
			(layer "F.Fab")
			(effects
				(font
					(size 1.27 1.27)
				)
			)
		)
		(duplicate_pad_numbers_are_jumpers no)
		(fp_line
			(start -0.7874 0.4064)
			(end -0.7874 -0.4064)
			(stroke
				(width 0.1524)
				(type default)
			)
			(layer "F.SilkS")
		)
		(fp_line
			(start 0.7874 0.4064)
			(end -0.7874 0.4064)
			(stroke
				(width 0.1524)
				(type default)
			)
			(layer "F.SilkS")
		)
		(fp_line
			(start -0.7874 -0.4064)
			(end 0.7874 -0.4064)
			(stroke
				(width 0.1524)
				(type default)
			)
			(layer "F.SilkS")
		)
		(fp_line
			(start 0.7874 -0.4064)
			(end 0.7874 0.4064)
			(stroke
				(width 0.1524)
				(type default)
			)
			(layer "F.SilkS")
		)
		(fp_line
			(start -0.67945 0.3048)
			(end -0.67945 -0.305054)
			(stroke
				(width 0.1)
				(type default)
			)
			(layer "F.Fab")
		)
		(fp_line
			(start -0.12065 0.3048)
			(end -0.67945 0.3048)
			(stroke
				(width 0.1)
				(type default)
			)
			(layer "F.Fab")
		)
		(fp_line
			(start 0.120396 0.3048)
			(end 0.120396 0.2794)
			(stroke
				(width 0.1)
				(type default)
			)
			(layer "F.Fab")
		)
		(fp_line
			(start 0.67945 0.3048)
			(end 0.120396 0.3048)
			(stroke
				(width 0.1)
				(type default)
			)
			(layer "F.Fab")
		)
		(fp_line
			(start -0.12065 0.2794)
			(end -0.12065 0.3048)
			(stroke
				(width 0.1)
				(type default)
			)
			(layer "F.Fab")
		)
		(fp_line
			(start 0.120396 0.2794)
			(end -0.12065 0.2794)
			(stroke
				(width 0.1)
				(type default)
			)
			(layer "F.Fab")
		)
		(fp_line
			(start -0.12065 -0.2794)
			(end 0.12065 -0.2794)
			(stroke
				(width 0.1)
				(type default)
			)
			(layer "F.Fab")
		)
		(fp_line
			(start 0.12065 -0.2794)
			(end 0.12065 -0.3048)
			(stroke
				(width 0.1)
				(type default)
			)
			(layer "F.Fab")
		)
		(fp_line
			(start 0.12065 -0.3048)
			(end 0.67945 -0.3048)
			(stroke
				(width 0.1)
				(type default)
			)
			(layer "F.Fab")
		)
		(fp_line
			(start 0.67945 -0.3048)
			(end 0.67945 0.3048)
			(stroke
				(width 0.1)
				(type default)
			)
			(layer "F.Fab")
		)
		(fp_line
			(start -0.67945 -0.305054)
			(end -0.12065 -0.305054)
			(stroke
				(width 0.1)
				(type default)
			)
			(layer "F.Fab")
		)
		(fp_line
			(start -0.12065 -0.305054)
			(end -0.12065 -0.2794)
			(stroke
				(width 0.1)
				(type default)
			)
			(layer "F.Fab")
		)
		(pad "1" smd circle
			(at -0.40005 0 270)
			(size 0 0)
			(layers "F.Cu" "F.Mask" "F.Paste")
			(net "P5V_AUX")
		)
		(pad "2" smd circle
			(at 0.40005 0 270)
			(size 0 0)
			(layers "F.Cu" "F.Mask" "F.Paste")
			(net "P0V9_RETIMER_CPU1_PVCC")
		)
	)
	(footprint ""
		(layer "F.Cu")
		(at 375.513092 -378.95403 -90)
		(property "Reference" "C888"
			(at 0 0 270)
			(layer "F.SilkS")
			(hide yes)
			(effects
				(font
					(size 1.27 1.27)
				)
			)
		)
		(property "Value" ""
			(at 0 0 270)
			(layer "F.Fab")
			(effects
				(font
					(size 1.27 1.27)
				)
			)
		)
		(duplicate_pad_numbers_are_jumpers no)
		(fp_line
			(start -0.299974 0.150114)
			(end -0.299974 -0.150114)
			(stroke
				(width 0.1)
				(type default)
			)
			(layer "F.Fab")
		)
		(fp_line
			(start 0.299974 0.150114)
			(end -0.299974 0.150114)
			(stroke
				(width 0.1)
				(type default)
			)
			(layer "F.Fab")
		)
		(fp_line
			(start -0.299974 -0.150114)
			(end 0.299974 -0.150114)
			(stroke
				(width 0.1)
				(type default)
			)
			(layer "F.Fab")
		)
		(fp_line
			(start 0.299974 -0.150114)
			(end 0.299974 0.150114)
			(stroke
				(width 0.1)
				(type default)
			)
			(layer "F.Fab")
		)
		(pad "1" smd rect
			(at -0.2667 0 270)
			(size 0.3048 0.381)
			(layers "F.Cu" "F.Mask" "F.Paste")
			(net "P5E_CPU0_P3_TX_C_DN<6>")
		)
		(pad "2" smd rect
			(at 0.2667 0 270)
			(size 0.3048 0.381)
			(layers "F.Cu" "F.Mask" "F.Paste")
			(net "P5E_CPU0_P3_TX_DN<6>")
		)
	)
	(footprint ""
		(layer "F.Cu")
		(at 244.58803 -47.719234)
		(property "Reference" "R1323"
			(at 1.28397 -3.816096 0)
			(unlocked yes)
			(layer "F.SilkS")
			(effects
				(font
					(size 0.7874 0.5842)
					(thickness 0.1524)
				)
				(justify left)
			)
		)
		(property "Value" ""
			(at 0 0 0)
			(layer "F.Fab")
			(effects
				(font
					(size 1.27 1.27)
				)
			)
		)
		(duplicate_pad_numbers_are_jumpers no)
		(fp_line
			(start -3.937508 -1.8796)
			(end -3.937508 1.8796)
			(stroke
				(width 0.1524)
				(type default)
			)
			(layer "F.SilkS")
		)
		(fp_line
			(start -3.937508 1.8796)
			(end 3.937508 1.8796)
			(stroke
				(width 0.1524)
				(type default)
			)
			(layer "F.SilkS")
		)
		(fp_line
			(start 3.937508 -1.8796)
			(end -3.937508 -1.8796)
			(stroke
				(width 0.1524)
				(type default)
			)
			(layer "F.SilkS")
		)
		(fp_line
			(start 3.937508 1.8796)
			(end 3.937508 -1.8796)
			(stroke
				(width 0.1524)
				(type default)
			)
			(layer "F.SilkS")
		)
		(fp_line
			(start -3.275076 -1.674876)
			(end -3.275076 1.674876)
			(stroke
				(width 0.1)
				(type default)
			)
			(layer "F.Fab")
		)
		(fp_line
			(start -3.275076 1.674876)
			(end 3.275076 1.674876)
			(stroke
				(width 0.1)
				(type default)
			)
			(layer "F.Fab")
		)
		(fp_line
			(start 3.275076 -1.674876)
			(end -3.275076 -1.674876)
			(stroke
				(width 0.1)
				(type default)
			)
			(layer "F.Fab")
		)
		(fp_line
			(start 3.275076 1.674876)
			(end 3.275076 -1.674876)
			(stroke
				(width 0.1)
				(type default)
			)
			(layer "F.Fab")
		)
		(pad "1" smd rect
			(at -2.350008 0)
			(size 2.921 3.5052)
			(layers "F.Cu" "F.Mask" "F.Paste")
			(net "P12V_E1S_0_R")
		)
		(pad "2" smd rect
			(at 2.350008 0)
			(size 2.921 3.5052)
			(layers "F.Cu" "F.Mask" "F.Paste")
			(net "P12V_E1S_0")
		)
	)
	(footprint ""
		(layer "F.Cu")
		(at 449.795392 -52.84851 90)
		(property "Reference" "PC8567"
			(at 0 0 90)
			(layer "F.SilkS")
			(hide yes)
			(effects
				(font
					(size 1.27 1.27)
				)
			)
		)
		(property "Value" ""
			(at 0 0 90)
			(layer "F.Fab")
			(effects
				(font
					(size 1.27 1.27)
				)
			)
		)
		(duplicate_pad_numbers_are_jumpers no)
		(fp_line
			(start 1.524 -0.762)
			(end 1.524 0.762)
			(stroke
				(width 0.1524)
				(type default)
			)
			(layer "F.SilkS")
		)
		(fp_line
			(start -1.524 -0.762)
			(end 1.524 -0.762)
			(stroke
				(width 0.1524)
				(type default)
			)
			(layer "F.SilkS")
		)
		(fp_line
			(start 1.524 0.762)
			(end -1.524 0.762)
			(stroke
				(width 0.1524)
				(type default)
			)
			(layer "F.SilkS")
		)
		(fp_line
			(start -1.524 0.762)
			(end -1.524 -0.762)
			(stroke
				(width 0.1524)
				(type default)
			)
			(layer "F.SilkS")
		)
		(fp_line
			(start 1.1049 -0.724916)
			(end -1.1049 -0.724916)
			(stroke
				(width 0.1)
				(type default)
			)
			(layer "F.Fab")
		)
		(fp_line
			(start -1.1049 -0.724916)
			(end -1.1049 0.724916)
			(stroke
				(width 0.1)
				(type default)
			)
			(layer "F.Fab")
		)
		(fp_line
			(start 1.1049 0.724916)
			(end 1.1049 -0.724916)
			(stroke
				(width 0.1)
				(type default)
			)
			(layer "F.Fab")
		)
		(fp_line
			(start -1.1049 0.724916)
			(end 1.1049 0.724916)
			(stroke
				(width 0.1)
				(type default)
			)
			(layer "F.Fab")
		)
		(pad "1" smd rect
			(at -0.889 0 270)
			(size 1.016 1.27)
			(layers "F.Cu" "F.Mask" "F.Paste")
			(net "SW_P3V3_AUX_FLT")
		)
		(pad "2" smd rect
			(at 0.889 0 270)
			(size 1.016 1.27)
			(layers "F.Cu" "F.Mask" "F.Paste")
			(net "GND")
		)
	)
	(footprint ""
		(layer "F.Cu")
		(at 325.545958 -193.925952 -90)
		(property "Reference" "R247"
			(at 0 0 270)
			(layer "F.SilkS")
			(hide yes)
			(effects
				(font
					(size 1.27 1.27)
				)
			)
		)
		(property "Value" ""
			(at 0 0 270)
			(layer "F.Fab")
			(effects
				(font
					(size 1.27 1.27)
				)
			)
		)
		(duplicate_pad_numbers_are_jumpers no)
		(fp_line
			(start -0.7874 0.4064)
			(end -0.7874 -0.4064)
			(stroke
				(width 0.1524)
				(type default)
			)
			(layer "F.SilkS")
		)
		(fp_line
			(start 0.7874 0.4064)
			(end -0.7874 0.4064)
			(stroke
				(width 0.1524)
				(type default)
			)
			(layer "F.SilkS")
		)
		(fp_line
			(start -0.7874 -0.4064)
			(end 0.7874 -0.4064)
			(stroke
				(width 0.1524)
				(type default)
			)
			(layer "F.SilkS")
		)
		(fp_line
			(start 0.7874 -0.4064)
			(end 0.7874 0.4064)
			(stroke
				(width 0.1524)
				(type default)
			)
			(layer "F.SilkS")
		)
		(fp_line
			(start -0.67945 0.3048)
			(end -0.67945 -0.305054)
			(stroke
				(width 0.1)
				(type default)
			)
			(layer "F.Fab")
		)
		(fp_line
			(start -0.12065 0.3048)
			(end -0.67945 0.3048)
			(stroke
				(width 0.1)
				(type default)
			)
			(layer "F.Fab")
		)
		(fp_line
			(start 0.120396 0.3048)
			(end 0.120396 0.2794)
			(stroke
				(width 0.1)
				(type default)
			)
			(layer "F.Fab")
		)
		(fp_line
			(start 0.67945 0.3048)
			(end 0.120396 0.3048)
			(stroke
				(width 0.1)
				(type default)
			)
			(layer "F.Fab")
		)
		(fp_line
			(start -0.12065 0.2794)
			(end -0.12065 0.3048)
			(stroke
				(width 0.1)
				(type default)
			)
			(layer "F.Fab")
		)
		(fp_line
			(start 0.120396 0.2794)
			(end -0.12065 0.2794)
			(stroke
				(width 0.1)
				(type default)
			)
			(layer "F.Fab")
		)
		(fp_line
			(start -0.12065 -0.2794)
			(end 0.12065 -0.2794)
			(stroke
				(width 0.1)
				(type default)
			)
			(layer "F.Fab")
		)
		(fp_line
			(start 0.12065 -0.2794)
			(end 0.12065 -0.3048)
			(stroke
				(width 0.1)
				(type default)
			)
			(layer "F.Fab")
		)
		(fp_line
			(start 0.12065 -0.3048)
			(end 0.67945 -0.3048)
			(stroke
				(width 0.1)
				(type default)
			)
			(layer "F.Fab")
		)
		(fp_line
			(start 0.67945 -0.3048)
			(end 0.67945 0.3048)
			(stroke
				(width 0.1)
				(type default)
			)
			(layer "F.Fab")
		)
		(fp_line
			(start -0.67945 -0.305054)
			(end -0.12065 -0.305054)
			(stroke
				(width 0.1)
				(type default)
			)
			(layer "F.Fab")
		)
		(fp_line
			(start -0.12065 -0.305054)
			(end -0.12065 -0.2794)
			(stroke
				(width 0.1)
				(type default)
			)
			(layer "F.Fab")
		)
		(pad "1" smd circle
			(at -0.40005 0 270)
			(size 0 0)
			(layers "F.Cu" "F.Mask" "F.Paste")
			(net "APML_CPU0_ALERT_N")
		)
		(pad "2" smd circle
			(at 0.40005 0 270)
			(size 0 0)
			(layers "F.Cu" "F.Mask" "F.Paste")
			(net "APML_CPU0_ALERT_R_N")
		)
	)
	(footprint ""
		(layer "F.Cu")
		(at 87.88146 -339.630258 90)
		(property "Reference" "PR258"
			(at 0 0 90)
			(layer "F.SilkS")
			(hide yes)
			(effects
				(font
					(size 1.27 1.27)
				)
			)
		)
		(property "Value" ""
			(at 0 0 90)
			(layer "F.Fab")
			(effects
				(font
					(size 1.27 1.27)
				)
			)
		)
		(duplicate_pad_numbers_are_jumpers no)
		(fp_line
			(start 0.7874 -0.4064)
			(end 0.7874 0.4064)
			(stroke
				(width 0.1524)
				(type default)
			)
			(layer "F.SilkS")
		)
		(fp_line
			(start -0.7874 -0.4064)
			(end 0.7874 -0.4064)
			(stroke
				(width 0.1524)
				(type default)
			)
			(layer "F.SilkS")
		)
		(fp_line
			(start 0.7874 0.4064)
			(end -0.7874 0.4064)
			(stroke
				(width 0.1524)
				(type default)
			)
			(layer "F.SilkS")
		)
		(fp_line
			(start -0.7874 0.4064)
			(end -0.7874 -0.4064)
			(stroke
				(width 0.1524)
				(type default)
			)
			(layer "F.SilkS")
		)
		(fp_line
			(start -0.12065 -0.305054)
			(end -0.12065 -0.2794)
			(stroke
				(width 0.1)
				(type default)
			)
			(layer "F.Fab")
		)
		(fp_line
			(start -0.67945 -0.305054)
			(end -0.12065 -0.305054)
			(stroke
				(width 0.1)
				(type default)
			)
			(layer "F.Fab")
		)
		(fp_line
			(start 0.67945 -0.3048)
			(end 0.67945 0.3048)
			(stroke
				(width 0.1)
				(type default)
			)
			(layer "F.Fab")
		)
		(fp_line
			(start 0.12065 -0.3048)
			(end 0.67945 -0.3048)
			(stroke
				(width 0.1)
				(type default)
			)
			(layer "F.Fab")
		)
		(fp_line
			(start 0.12065 -0.2794)
			(end 0.12065 -0.3048)
			(stroke
				(width 0.1)
				(type default)
			)
			(layer "F.Fab")
		)
		(fp_line
			(start -0.12065 -0.2794)
			(end 0.12065 -0.2794)
			(stroke
				(width 0.1)
				(type default)
			)
			(layer "F.Fab")
		)
		(fp_line
			(start 0.120396 0.2794)
			(end -0.12065 0.2794)
			(stroke
				(width 0.1)
				(type default)
			)
			(layer "F.Fab")
		)
		(fp_line
			(start -0.12065 0.2794)
			(end -0.12065 0.3048)
			(stroke
				(width 0.1)
				(type default)
			)
			(layer "F.Fab")
		)
		(fp_line
			(start 0.67945 0.3048)
			(end 0.120396 0.3048)
			(stroke
				(width 0.1)
				(type default)
			)
			(layer "F.Fab")
		)
		(fp_line
			(start 0.120396 0.3048)
			(end 0.120396 0.2794)
			(stroke
				(width 0.1)
				(type default)
			)
			(layer "F.Fab")
		)
		(fp_line
			(start -0.12065 0.3048)
			(end -0.67945 0.3048)
			(stroke
				(width 0.1)
				(type default)
			)
			(layer "F.Fab")
		)
		(fp_line
			(start -0.67945 0.3048)
			(end -0.67945 -0.305054)
			(stroke
				(width 0.1)
				(type default)
			)
			(layer "F.Fab")
		)
		(pad "1" smd circle
			(at -0.40005 0 90)
			(size 0 0)
			(layers "F.Cu" "F.Mask" "F.Paste")
			(net "SW_PVDDCR_CPU1_P1_BOOT1")
		)
		(pad "2" smd circle
			(at 0.40005 0 90)
			(size 0 0)
			(layers "F.Cu" "F.Mask" "F.Paste")
			(net "SW_PVDDCR_CPU1_P1_BOOT1_R")
		)
	)
	(footprint ""
		(layer "F.Cu")
		(at 304.57521 -351.050352)
		(property "Reference" "PC178_4"
			(at 0 0 0)
			(layer "F.SilkS")
			(hide yes)
			(effects
				(font
					(size 1.27 1.27)
				)
			)
		)
		(property "Value" ""
			(at 0 0 0)
			(layer "F.Fab")
			(effects
				(font
					(size 1.27 1.27)
				)
			)
		)
		(duplicate_pad_numbers_are_jumpers no)
		(fp_line
			(start -0.7874 -0.4064)
			(end 0.7874 -0.4064)
			(stroke
				(width 0.1524)
				(type default)
			)
			(layer "F.SilkS")
		)
		(fp_line
			(start -0.7874 0.4064)
			(end -0.7874 -0.4064)
			(stroke
				(width 0.1524)
				(type default)
			)
			(layer "F.SilkS")
		)
		(fp_line
			(start 0.7874 -0.4064)
			(end 0.7874 0.4064)
			(stroke
				(width 0.1524)
				(type default)
			)
			(layer "F.SilkS")
		)
		(fp_line
			(start 0.7874 0.4064)
			(end -0.7874 0.4064)
			(stroke
				(width 0.1524)
				(type default)
			)
			(layer "F.SilkS")
		)
		(fp_line
			(start -0.67945 -0.305054)
			(end -0.12065 -0.305054)
			(stroke
				(width 0.1)
				(type default)
			)
			(layer "F.Fab")
		)
		(fp_line
			(start -0.67945 0.3048)
			(end -0.67945 -0.305054)
			(stroke
				(width 0.1)
				(type default)
			)
			(layer "F.Fab")
		)
		(fp_line
			(start -0.12065 -0.305054)
			(end -0.12065 -0.2794)
			(stroke
				(width 0.1)
				(type default)
			)
			(layer "F.Fab")
		)
		(fp_line
			(start -0.12065 -0.2794)
			(end 0.12065 -0.2794)
			(stroke
				(width 0.1)
				(type default)
			)
			(layer "F.Fab")
		)
		(fp_line
			(start -0.12065 0.2794)
			(end -0.12065 0.3048)
			(stroke
				(width 0.1)
				(type default)
			)
			(layer "F.Fab")
		)
		(fp_line
			(start -0.12065 0.3048)
			(end -0.67945 0.3048)
			(stroke
				(width 0.1)
				(type default)
			)
			(layer "F.Fab")
		)
		(fp_line
			(start 0.120396 0.2794)
			(end -0.12065 0.2794)
			(stroke
				(width 0.1)
				(type default)
			)
			(layer "F.Fab")
		)
		(fp_line
			(start 0.120396 0.3048)
			(end 0.120396 0.2794)
			(stroke
				(width 0.1)
				(type default)
			)
			(layer "F.Fab")
		)
		(fp_line
			(start 0.12065 -0.3048)
			(end 0.67945 -0.3048)
			(stroke
				(width 0.1)
				(type default)
			)
			(layer "F.Fab")
		)
		(fp_line
			(start 0.12065 -0.2794)
			(end 0.12065 -0.3048)
			(stroke
				(width 0.1)
				(type default)
			)
			(layer "F.Fab")
		)
		(fp_line
			(start 0.67945 -0.3048)
			(end 0.67945 0.3048)
			(stroke
				(width 0.1)
				(type default)
			)
			(layer "F.Fab")
		)
		(fp_line
			(start 0.67945 0.3048)
			(end 0.120396 0.3048)
			(stroke
				(width 0.1)
				(type default)
			)
			(layer "F.Fab")
		)
		(pad "1" smd circle
			(at -0.40005 0)
			(size 0 0)
			(layers "F.Cu" "F.Mask" "F.Paste")
			(net "SW_P12V_AUX_PVDDIO_P0_FLT")
		)
		(pad "2" smd circle
			(at 0.40005 0)
			(size 0 0)
			(layers "F.Cu" "F.Mask" "F.Paste")
			(net "GND")
		)
	)
	(footprint ""
		(layer "F.Cu")
		(at 166.937944 -348.284546)
		(property "Reference" "PC643"
			(at 0 0 0)
			(layer "F.SilkS")
			(hide yes)
			(effects
				(font
					(size 1.27 1.27)
				)
			)
		)
		(property "Value" ""
			(at 0 0 0)
			(layer "F.Fab")
			(effects
				(font
					(size 1.27 1.27)
				)
			)
		)
		(duplicate_pad_numbers_are_jumpers no)
		(fp_line
			(start -0.7874 -0.4064)
			(end 0.7874 -0.4064)
			(stroke
				(width 0.1524)
				(type default)
			)
			(layer "F.SilkS")
		)
		(fp_line
			(start -0.7874 0.4064)
			(end -0.7874 -0.4064)
			(stroke
				(width 0.1524)
				(type default)
			)
			(layer "F.SilkS")
		)
		(fp_line
			(start 0.7874 -0.4064)
			(end 0.7874 0.4064)
			(stroke
				(width 0.1524)
				(type default)
			)
			(layer "F.SilkS")
		)
		(fp_line
			(start 0.7874 0.4064)
			(end -0.7874 0.4064)
			(stroke
				(width 0.1524)
				(type default)
			)
			(layer "F.SilkS")
		)
		(fp_line
			(start -0.67945 -0.305054)
			(end -0.12065 -0.305054)
			(stroke
				(width 0.1)
				(type default)
			)
			(layer "F.Fab")
		)
		(fp_line
			(start -0.67945 0.3048)
			(end -0.67945 -0.305054)
			(stroke
				(width 0.1)
				(type default)
			)
			(layer "F.Fab")
		)
		(fp_line
			(start -0.12065 -0.305054)
			(end -0.12065 -0.2794)
			(stroke
				(width 0.1)
				(type default)
			)
			(layer "F.Fab")
		)
		(fp_line
			(start -0.12065 -0.2794)
			(end 0.12065 -0.2794)
			(stroke
				(width 0.1)
				(type default)
			)
			(layer "F.Fab")
		)
		(fp_line
			(start -0.12065 0.2794)
			(end -0.12065 0.3048)
			(stroke
				(width 0.1)
				(type default)
			)
			(layer "F.Fab")
		)
		(fp_line
			(start -0.12065 0.3048)
			(end -0.67945 0.3048)
			(stroke
				(width 0.1)
				(type default)
			)
			(layer "F.Fab")
		)
		(fp_line
			(start 0.120396 0.2794)
			(end -0.12065 0.2794)
			(stroke
				(width 0.1)
				(type default)
			)
			(layer "F.Fab")
		)
		(fp_line
			(start 0.120396 0.3048)
			(end 0.120396 0.2794)
			(stroke
				(width 0.1)
				(type default)
			)
			(layer "F.Fab")
		)
		(fp_line
			(start 0.12065 -0.3048)
			(end 0.67945 -0.3048)
			(stroke
				(width 0.1)
				(type default)
			)
			(layer "F.Fab")
		)
		(fp_line
			(start 0.12065 -0.2794)
			(end 0.12065 -0.3048)
			(stroke
				(width 0.1)
				(type default)
			)
			(layer "F.Fab")
		)
		(fp_line
			(start 0.67945 -0.3048)
			(end 0.67945 0.3048)
			(stroke
				(width 0.1)
				(type default)
			)
			(layer "F.Fab")
		)
		(fp_line
			(start 0.67945 0.3048)
			(end 0.120396 0.3048)
			(stroke
				(width 0.1)
				(type default)
			)
			(layer "F.Fab")
		)
		(pad "1" smd circle
			(at -0.40005 0)
			(size 0 0)
			(layers "F.Cu" "F.Mask" "F.Paste")
			(net "PVDD11_S3_P1_TEMP0")
		)
		(pad "2" smd circle
			(at 0.40005 0)
			(size 0 0)
			(layers "F.Cu" "F.Mask" "F.Paste")
			(net "GND")
		)
	)
	(footprint ""
		(layer "F.Cu")
		(at 189.80023 -35.017456 180)
		(property "Reference" "R1854"
			(at 0 0 180)
			(layer "F.SilkS")
			(hide yes)
			(effects
				(font
					(size 1.27 1.27)
				)
			)
		)
		(property "Value" ""
			(at 0 0 180)
			(layer "F.Fab")
			(effects
				(font
					(size 1.27 1.27)
				)
			)
		)
		(duplicate_pad_numbers_are_jumpers no)
		(fp_line
			(start 0.7874 0.4064)
			(end -0.7874 0.4064)
			(stroke
				(width 0.1524)
				(type default)
			)
			(layer "F.SilkS")
		)
		(fp_line
			(start 0.7874 -0.4064)
			(end 0.7874 0.4064)
			(stroke
				(width 0.1524)
				(type default)
			)
			(layer "F.SilkS")
		)
		(fp_line
			(start -0.7874 0.4064)
			(end -0.7874 -0.4064)
			(stroke
				(width 0.1524)
				(type default)
			)
			(layer "F.SilkS")
		)
		(fp_line
			(start -0.7874 -0.4064)
			(end 0.7874 -0.4064)
			(stroke
				(width 0.1524)
				(type default)
			)
			(layer "F.SilkS")
		)
		(fp_line
			(start 0.67945 0.3048)
			(end 0.120396 0.3048)
			(stroke
				(width 0.1)
				(type default)
			)
			(layer "F.Fab")
		)
		(fp_line
			(start 0.67945 -0.3048)
			(end 0.67945 0.3048)
			(stroke
				(width 0.1)
				(type default)
			)
			(layer "F.Fab")
		)
		(fp_line
			(start 0.12065 -0.2794)
			(end 0.12065 -0.3048)
			(stroke
				(width 0.1)
				(type default)
			)
			(layer "F.Fab")
		)
		(fp_line
			(start 0.12065 -0.3048)
			(end 0.67945 -0.3048)
			(stroke
				(width 0.1)
				(type default)
			)
			(layer "F.Fab")
		)
		(fp_line
			(start 0.120396 0.3048)
			(end 0.120396 0.2794)
			(stroke
				(width 0.1)
				(type default)
			)
			(layer "F.Fab")
		)
		(fp_line
			(start 0.120396 0.2794)
			(end -0.12065 0.2794)
			(stroke
				(width 0.1)
				(type default)
			)
			(layer "F.Fab")
		)
		(fp_line
			(start -0.12065 0.3048)
			(end -0.67945 0.3048)
			(stroke
				(width 0.1)
				(type default)
			)
			(layer "F.Fab")
		)
		(fp_line
			(start -0.12065 0.2794)
			(end -0.12065 0.3048)
			(stroke
				(width 0.1)
				(type default)
			)
			(layer "F.Fab")
		)
		(fp_line
			(start -0.12065 -0.2794)
			(end 0.12065 -0.2794)
			(stroke
				(width 0.1)
				(type default)
			)
			(layer "F.Fab")
		)
		(fp_line
			(start -0.12065 -0.305054)
			(end -0.12065 -0.2794)
			(stroke
				(width 0.1)
				(type default)
			)
			(layer "F.Fab")
		)
		(fp_line
			(start -0.67945 0.3048)
			(end -0.67945 -0.305054)
			(stroke
				(width 0.1)
				(type default)
			)
			(layer "F.Fab")
		)
		(fp_line
			(start -0.67945 -0.305054)
			(end -0.12065 -0.305054)
			(stroke
				(width 0.1)
				(type default)
			)
			(layer "F.Fab")
		)
		(pad "1" smd circle
			(at -0.40005 0 180)
			(size 0 0)
			(layers "F.Cu" "F.Mask" "F.Paste")
			(net "P3V3_AUX")
		)
		(pad "2" smd circle
			(at 0.40005 0 180)
			(size 0 0)
			(layers "F.Cu" "F.Mask" "F.Paste")
			(net "FM_SCM_PRSNT1_N")
		)
	)
	(footprint ""
		(layer "F.Cu")
		(at 277.352252 -124.368814)
		(property "Reference" "R318"
			(at 0 0 0)
			(layer "F.SilkS")
			(hide yes)
			(effects
				(font
					(size 1.27 1.27)
				)
			)
		)
		(property "Value" ""
			(at 0 0 0)
			(layer "F.Fab")
			(effects
				(font
					(size 1.27 1.27)
				)
			)
		)
		(duplicate_pad_numbers_are_jumpers no)
		(fp_line
			(start -0.7874 -0.4064)
			(end 0.7874 -0.4064)
			(stroke
				(width 0.1524)
				(type default)
			)
			(layer "F.SilkS")
		)
		(fp_line
			(start -0.7874 0.4064)
			(end -0.7874 -0.4064)
			(stroke
				(width 0.1524)
				(type default)
			)
			(layer "F.SilkS")
		)
		(fp_line
			(start 0.7874 -0.4064)
			(end 0.7874 0.4064)
			(stroke
				(width 0.1524)
				(type default)
			)
			(layer "F.SilkS")
		)
		(fp_line
			(start 0.7874 0.4064)
			(end -0.7874 0.4064)
			(stroke
				(width 0.1524)
				(type default)
			)
			(layer "F.SilkS")
		)
		(fp_line
			(start -0.67945 -0.305054)
			(end -0.12065 -0.305054)
			(stroke
				(width 0.1)
				(type default)
			)
			(layer "F.Fab")
		)
		(fp_line
			(start -0.67945 0.3048)
			(end -0.67945 -0.305054)
			(stroke
				(width 0.1)
				(type default)
			)
			(layer "F.Fab")
		)
		(fp_line
			(start -0.12065 -0.305054)
			(end -0.12065 -0.2794)
			(stroke
				(width 0.1)
				(type default)
			)
			(layer "F.Fab")
		)
		(fp_line
			(start -0.12065 -0.2794)
			(end 0.12065 -0.2794)
			(stroke
				(width 0.1)
				(type default)
			)
			(layer "F.Fab")
		)
		(fp_line
			(start -0.12065 0.2794)
			(end -0.12065 0.3048)
			(stroke
				(width 0.1)
				(type default)
			)
			(layer "F.Fab")
		)
		(fp_line
			(start -0.12065 0.3048)
			(end -0.67945 0.3048)
			(stroke
				(width 0.1)
				(type default)
			)
			(layer "F.Fab")
		)
		(fp_line
			(start 0.120396 0.2794)
			(end -0.12065 0.2794)
			(stroke
				(width 0.1)
				(type default)
			)
			(layer "F.Fab")
		)
		(fp_line
			(start 0.120396 0.3048)
			(end 0.120396 0.2794)
			(stroke
				(width 0.1)
				(type default)
			)
			(layer "F.Fab")
		)
		(fp_line
			(start 0.12065 -0.3048)
			(end 0.67945 -0.3048)
			(stroke
				(width 0.1)
				(type default)
			)
			(layer "F.Fab")
		)
		(fp_line
			(start 0.12065 -0.2794)
			(end 0.12065 -0.3048)
			(stroke
				(width 0.1)
				(type default)
			)
			(layer "F.Fab")
		)
		(fp_line
			(start 0.67945 -0.3048)
			(end 0.67945 0.3048)
			(stroke
				(width 0.1)
				(type default)
			)
			(layer "F.Fab")
		)
		(fp_line
			(start 0.67945 0.3048)
			(end 0.120396 0.3048)
			(stroke
				(width 0.1)
				(type default)
			)
			(layer "F.Fab")
		)
		(pad "1" smd circle
			(at -0.40005 0)
			(size 0 0)
			(layers "F.Cu" "F.Mask" "F.Paste")
			(net "P3V3_AUX")
		)
		(pad "2" smd circle
			(at 0.40005 0)
			(size 0 0)
			(layers "F.Cu" "F.Mask" "F.Paste")
			(net "PCA9548_PCIE3_ADDR1")
		)
	)
	(footprint ""
		(layer "F.Cu")
		(at 387.206998 -162.65271 180)
		(property "Reference" "PC596"
			(at 1.796796 -2.887472 0)
			(unlocked yes)
			(layer "F.SilkS")
			(effects
				(font
					(size 0.7874 0.5842)
					(thickness 0.1524)
				)
				(justify left)
			)
		)
		(property "Value" ""
			(at 0 0 180)
			(layer "F.Fab")
			(effects
				(font
					(size 1.27 1.27)
				)
			)
		)
		(duplicate_pad_numbers_are_jumpers no)
		(fp_line
			(start -3.400044 1.249934)
			(end 3.400044 1.249934)
			(stroke
				(width 0.1524)
				(type default)
			)
			(layer "F.SilkS")
		)
		(fp_circle
			(center 0 1.249934)
			(end -3.400044 1.249934)
			(stroke
				(width 0.1524)
				(type default)
			)
			(fill no)
			(layer "F.SilkS")
		)
		(fp_poly
			(pts
				(arc
					(start 3.400044 1.249934)
					(mid 0 4.649978)
					(end -3.400044 1.249934)
				)
			)
			(stroke
				(width 0)
				(type default)
			)
			(fill yes)
			(layer "F.SilkS")
		)
		(fp_circle
			(center 0 1.249934)
			(end -3.400044 1.249934)
			(stroke
				(width 0.1)
				(type default)
			)
			(fill no)
			(layer "F.Fab")
		)
		(pad "1" thru_hole rect
			(at 0 0 180)
			(size 1.524 1.524)
			(drill 1.016)
			(layers "*.Cu" "*.Mask")
			(remove_unused_layers no)
			(net "SW_P12V_AUX_PVDDCR_SOC_P0_FLT")
			(clearance 0)
			(padstack
				(mode front_inner_back)
				(layer "Inner"
					(shape circle)
					(size 1.524 1.524)
					(clearance 0)
				)
				(layer "B.Cu"
					(shape rect)
					(size 1.524 1.524)
					(clearance 0)
				)
			)
		)
		(pad "2" thru_hole circle
			(at 0 2.500122 180)
			(size 1.524 1.524)
			(drill 1.016)
			(layers "*.Cu" "*.Mask")
			(remove_unused_layers no)
			(net "GND")
			(clearance 0)
		)
	)
	(footprint ""
		(layer "F.Cu")
		(at 196.654166 -255.560322 180)
		(property "Reference" "J99"
			(at -0.4318 -81.730088 0)
			(unlocked yes)
			(layer "F.SilkS")
			(effects
				(font
					(size 0.7874 0.5842)
					(thickness 0.1524)
				)
			)
		)
		(property "Value" ""
			(at 0 0 180)
			(layer "F.Fab")
			(effects
				(font
					(size 1.27 1.27)
				)
			)
		)
		(duplicate_pad_numbers_are_jumpers no)
		(fp_line
			(start 3.24993 -81.000092)
			(end 3.24993 73.156318)
			(stroke
				(width 0.1524)
				(type default)
			)
			(layer "F.SilkS")
		)
		(fp_line
			(start 1.036066 81.000092)
			(end -1.196594 81.000092)
			(stroke
				(width 0.1524)
				(type default)
			)
			(layer "F.SilkS")
		)
		(fp_line
			(start -3.24993 72.780398)
			(end -3.24993 -81.000092)
			(stroke
				(width 0.1524)
				(type default)
			)
			(layer "F.SilkS")
		)
		(fp_line
			(start -3.24993 72.499982)
			(end 3.24993 72.499982)
			(stroke
				(width 0.1524)
				(type default)
			)
			(layer "F.SilkS")
		)
		(fp_line
			(start -3.24993 -72.499982)
			(end 3.24993 -72.499982)
			(stroke
				(width 0.1524)
				(type default)
			)
			(layer "F.SilkS")
		)
		(fp_line
			(start -3.24993 -81.000092)
			(end 3.24993 -81.000092)
			(stroke
				(width 0.1524)
				(type default)
			)
			(layer "F.SilkS")
		)
		(fp_poly
			(pts
				(xy -3.734816 -64.758316) (xy -3.064764 -63.841122) (xy -4.200398 -63.855346)
			)
			(stroke
				(width 0)
				(type default)
			)
			(fill yes)
			(layer "F.SilkS")
		)
		(fp_line
			(start 3.24993 81.000092)
			(end -3.24993 81.000092)
			(stroke
				(width 0.1)
				(type default)
			)
			(layer "F.Fab")
		)
		(fp_line
			(start 3.24993 -81.000092)
			(end 3.24993 81.000092)
			(stroke
				(width 0.1)
				(type default)
			)
			(layer "F.Fab")
		)
		(fp_line
			(start -3.24993 81.000092)
			(end -3.24993 -81.000092)
			(stroke
				(width 0.1)
				(type default)
			)
			(layer "F.Fab")
		)
		(fp_line
			(start -3.24993 72.499982)
			(end 3.24993 72.499982)
			(stroke
				(width 0.1)
				(type default)
			)
			(layer "F.Fab")
		)
		(fp_line
			(start -3.24993 71.000112)
			(end 3.24993 71.000112)
			(stroke
				(width 0.1)
				(type default)
			)
			(layer "F.Fab")
		)
		(fp_line
			(start -3.24993 -71.000112)
			(end 3.24993 -71.000112)
			(stroke
				(width 0.1)
				(type default)
			)
			(layer "F.Fab")
		)
		(fp_line
			(start -3.24993 -72.499982)
			(end 3.24993 -72.499982)
			(stroke
				(width 0.1)
				(type default)
			)
			(layer "F.Fab")
		)
		(fp_line
			(start -3.24993 -81.000092)
			(end 3.24993 -81.000092)
			(stroke
				(width 0.1)
				(type default)
			)
			(layer "F.Fab")
		)
		(fp_poly
			(pts
				(xy -3.41503 -63.324994) (xy -4.43103 -62.816994) (xy -4.43103 -63.832994)
			)
			(stroke
				(width 0)
				(type default)
			)
			(fill yes)
			(layer "F.Fab")
		)
		(pad "1" smd rect
			(at -2.050034 -63.324994 90)
			(size 0.519938 1.4986)
			(layers "F.Cu" "F.Mask" "F.Paste")
			(net "P12V_MEM_CPU1")
		)
		(pad "2" smd rect
			(at -2.050034 -62.47511 90)
			(size 0.519938 1.4986)
			(layers "F.Cu" "F.Mask" "F.Paste")
			(net "Net_2396")
		)
		(pad "3" smd rect
			(at -2.050034 -61.624972 90)
			(size 0.519938 1.4986)
			(layers "F.Cu" "F.Mask" "F.Paste")
			(net "P3V3_AUX")
		)
		(pad "4" smd rect
			(at -2.050034 -60.775088 90)
			(size 0.519938 1.4986)
			(layers "F.Cu" "F.Mask" "F.Paste")
			(net "I3C_SPD_DDRK_CPU1_SCL")
		)
		(pad "5" smd rect
			(at -2.050034 -59.92495 90)
			(size 0.519938 1.4986)
			(layers "F.Cu" "F.Mask" "F.Paste")
			(net "I3C_SPD_DDRK_CPU1_SDA")
		)
		(pad "6" smd rect
			(at -2.050034 -59.075066 90)
			(size 0.519938 1.4986)
			(layers "F.Cu" "F.Mask" "F.Paste")
			(net "GND")
		)
		(pad "7" smd rect
			(at -2.050034 -58.224928 90)
			(size 0.519938 1.4986)
			(layers "F.Cu" "F.Mask" "F.Paste")
			(net "M_K_CPU1_SA_DQ<0>")
		)
		(pad "8" smd rect
			(at -2.050034 -57.375044 90)
			(size 0.519938 1.4986)
			(layers "F.Cu" "F.Mask" "F.Paste")
			(net "GND")
		)
		(pad "9" smd rect
			(at -2.050034 -56.524906 90)
			(size 0.519938 1.4986)
			(layers "F.Cu" "F.Mask" "F.Paste")
			(net "M_K_CPU1_SA_DQ<1>")
		)
		(pad "10" smd rect
			(at -2.050034 -55.675022 90)
			(size 0.519938 1.4986)
			(layers "F.Cu" "F.Mask" "F.Paste")
			(net "GND")
		)
		(pad "11" smd rect
			(at -2.050034 -54.824884 90)
			(size 0.519938 1.4986)
			(layers "F.Cu" "F.Mask" "F.Paste")
			(net "M_K_CPU1_SA_DQS_DP<0>")
		)
		(pad "12" smd rect
			(at -2.050034 -53.975 90)
			(size 0.519938 1.4986)
			(layers "F.Cu" "F.Mask" "F.Paste")
			(net "M_K_CPU1_SA_DQS_DN<0>")
		)
		(pad "13" smd rect
			(at -2.050034 -53.125116 90)
			(size 0.519938 1.4986)
			(layers "F.Cu" "F.Mask" "F.Paste")
			(net "GND")
		)
		(pad "14" smd rect
			(at -2.050034 -52.274978 90)
			(size 0.519938 1.4986)
			(layers "F.Cu" "F.Mask" "F.Paste")
			(net "M_K_CPU1_SA_DQ<4>")
		)
		(pad "15" smd rect
			(at -2.050034 -51.425094 90)
			(size 0.519938 1.4986)
			(layers "F.Cu" "F.Mask" "F.Paste")
			(net "GND")
		)
		(pad "16" smd rect
			(at -2.050034 -50.574956 90)
			(size 0.519938 1.4986)
			(layers "F.Cu" "F.Mask" "F.Paste")
			(net "M_K_CPU1_SA_DQ<5>")
		)
		(pad "17" smd rect
			(at -2.050034 -49.725072 90)
			(size 0.519938 1.4986)
			(layers "F.Cu" "F.Mask" "F.Paste")
			(net "GND")
		)
		(pad "18" smd rect
			(at -2.050034 -48.874934 90)
			(size 0.519938 1.4986)
			(layers "F.Cu" "F.Mask" "F.Paste")
			(net "M_K_CPU1_SA_DQ<8>")
		)
		(pad "19" smd rect
			(at -2.050034 -48.02505 90)
			(size 0.519938 1.4986)
			(layers "F.Cu" "F.Mask" "F.Paste")
			(net "GND")
		)
		(pad "20" smd rect
			(at -2.050034 -47.174912 90)
			(size 0.519938 1.4986)
			(layers "F.Cu" "F.Mask" "F.Paste")
			(net "M_K_CPU1_SA_DQ<9>")
		)
		(pad "21" smd rect
			(at -2.050034 -46.325028 90)
			(size 0.519938 1.4986)
			(layers "F.Cu" "F.Mask" "F.Paste")
			(net "GND")
		)
		(pad "22" smd rect
			(at -2.050034 -45.47489 90)
			(size 0.519938 1.4986)
			(layers "F.Cu" "F.Mask" "F.Paste")
			(net "M_K_CPU1_SA_DQS_DP<1>")
		)
		(pad "23" smd rect
			(at -2.050034 -44.625006 90)
			(size 0.519938 1.4986)
			(layers "F.Cu" "F.Mask" "F.Paste")
			(net "M_K_CPU1_SA_DQS_DN<1>")
		)
		(pad "24" smd rect
			(at -2.050034 -43.775122 90)
			(size 0.519938 1.4986)
			(layers "F.Cu" "F.Mask" "F.Paste")
			(net "GND")
		)
		(pad "25" smd rect
			(at -2.050034 -42.924984 90)
			(size 0.519938 1.4986)
			(layers "F.Cu" "F.Mask" "F.Paste")
			(net "M_K_CPU1_SA_DQ<12>")
		)
		(pad "26" smd rect
			(at -2.050034 -42.0751 90)
			(size 0.519938 1.4986)
			(layers "F.Cu" "F.Mask" "F.Paste")
			(net "GND")
		)
		(pad "27" smd rect
			(at -2.050034 -41.224962 90)
			(size 0.519938 1.4986)
			(layers "F.Cu" "F.Mask" "F.Paste")
			(net "M_K_CPU1_SA_DQ<13>")
		)
		(pad "28" smd rect
			(at -2.050034 -40.375078 90)
			(size 0.519938 1.4986)
			(layers "F.Cu" "F.Mask" "F.Paste")
			(net "GND")
		)
		(pad "29" smd rect
			(at -2.050034 -39.52494 90)
			(size 0.519938 1.4986)
			(layers "F.Cu" "F.Mask" "F.Paste")
			(net "M_K_CPU1_SA_DQ<16>")
		)
		(pad "30" smd rect
			(at -2.050034 -38.675056 90)
			(size 0.519938 1.4986)
			(layers "F.Cu" "F.Mask" "F.Paste")
			(net "GND")
		)
		(pad "31" smd rect
			(at -2.050034 -37.824918 90)
			(size 0.519938 1.4986)
			(layers "F.Cu" "F.Mask" "F.Paste")
			(net "M_K_CPU1_SA_DQ<17>")
		)
		(pad "32" smd rect
			(at -2.050034 -36.975034 90)
			(size 0.519938 1.4986)
			(layers "F.Cu" "F.Mask" "F.Paste")
			(net "GND")
		)
		(pad "33" smd rect
			(at -2.050034 -36.124896 90)
			(size 0.519938 1.4986)
			(layers "F.Cu" "F.Mask" "F.Paste")
			(net "M_K_CPU1_SA_DQS_DP<2>")
		)
		(pad "34" smd rect
			(at -2.050034 -35.275012 90)
			(size 0.519938 1.4986)
			(layers "F.Cu" "F.Mask" "F.Paste")
			(net "M_K_CPU1_SA_DQS_DN<2>")
		)
		(pad "35" smd rect
			(at -2.050034 -34.425128 90)
			(size 0.519938 1.4986)
			(layers "F.Cu" "F.Mask" "F.Paste")
			(net "GND")
		)
		(pad "36" smd rect
			(at -2.050034 -33.57499 90)
			(size 0.519938 1.4986)
			(layers "F.Cu" "F.Mask" "F.Paste")
			(net "M_K_CPU1_SA_DQ<20>")
		)
		(pad "37" smd rect
			(at -2.050034 -32.725106 90)
			(size 0.519938 1.4986)
			(layers "F.Cu" "F.Mask" "F.Paste")
			(net "GND")
		)
		(pad "38" smd rect
			(at -2.050034 -31.874968 90)
			(size 0.519938 1.4986)
			(layers "F.Cu" "F.Mask" "F.Paste")
			(net "M_K_CPU1_SA_DQ<21>")
		)
		(pad "39" smd rect
			(at -2.050034 -31.025084 90)
			(size 0.519938 1.4986)
			(layers "F.Cu" "F.Mask" "F.Paste")
			(net "GND")
		)
		(pad "40" smd rect
			(at -2.050034 -30.174946 90)
			(size 0.519938 1.4986)
			(layers "F.Cu" "F.Mask" "F.Paste")
			(net "M_K_CPU1_SA_DQ<24>")
		)
		(pad "41" smd rect
			(at -2.050034 -29.325062 90)
			(size 0.519938 1.4986)
			(layers "F.Cu" "F.Mask" "F.Paste")
			(net "GND")
		)
		(pad "42" smd rect
			(at -2.050034 -28.474924 90)
			(size 0.519938 1.4986)
			(layers "F.Cu" "F.Mask" "F.Paste")
			(net "M_K_CPU1_SA_DQ<25>")
		)
		(pad "43" smd rect
			(at -2.050034 -27.62504 90)
			(size 0.519938 1.4986)
			(layers "F.Cu" "F.Mask" "F.Paste")
			(net "GND")
		)
		(pad "44" smd rect
			(at -2.050034 -26.774902 90)
			(size 0.519938 1.4986)
			(layers "F.Cu" "F.Mask" "F.Paste")
			(net "M_K_CPU1_SA_DQS_DP<3>")
		)
		(pad "45" smd rect
			(at -2.050034 -25.925018 90)
			(size 0.519938 1.4986)
			(layers "F.Cu" "F.Mask" "F.Paste")
			(net "M_K_CPU1_SA_DQS_DN<3>")
		)
		(pad "46" smd rect
			(at -2.050034 -25.07488 90)
			(size 0.519938 1.4986)
			(layers "F.Cu" "F.Mask" "F.Paste")
			(net "GND")
		)
		(pad "47" smd rect
			(at -2.050034 -24.224996 90)
			(size 0.519938 1.4986)
			(layers "F.Cu" "F.Mask" "F.Paste")
			(net "M_K_CPU1_SA_DQ<28>")
		)
		(pad "48" smd rect
			(at -2.050034 -23.375112 90)
			(size 0.519938 1.4986)
			(layers "F.Cu" "F.Mask" "F.Paste")
			(net "GND")
		)
		(pad "49" smd rect
			(at -2.050034 -22.524974 90)
			(size 0.519938 1.4986)
			(layers "F.Cu" "F.Mask" "F.Paste")
			(net "M_K_CPU1_SA_DQ<29>")
		)
		(pad "50" smd rect
			(at -2.050034 -21.67509 90)
			(size 0.519938 1.4986)
			(layers "F.Cu" "F.Mask" "F.Paste")
			(net "GND")
		)
		(pad "51" smd rect
			(at -2.050034 -20.824952 90)
			(size 0.519938 1.4986)
			(layers "F.Cu" "F.Mask" "F.Paste")
			(net "M_K_CPU1_SA_CB<0>")
		)
		(pad "52" smd rect
			(at -2.050034 -19.975068 90)
			(size 0.519938 1.4986)
			(layers "F.Cu" "F.Mask" "F.Paste")
			(net "GND")
		)
		(pad "53" smd rect
			(at -2.050034 -19.12493 90)
			(size 0.519938 1.4986)
			(layers "F.Cu" "F.Mask" "F.Paste")
			(net "M_K_CPU1_SA_CB<1>")
		)
		(pad "54" smd rect
			(at -2.050034 -18.275046 90)
			(size 0.519938 1.4986)
			(layers "F.Cu" "F.Mask" "F.Paste")
			(net "GND")
		)
		(pad "55" smd rect
			(at -2.050034 -17.424908 90)
			(size 0.519938 1.4986)
			(layers "F.Cu" "F.Mask" "F.Paste")
			(net "M_K_CPU1_SA_DQS_DP<4>")
		)
		(pad "56" smd rect
			(at -2.050034 -16.575024 90)
			(size 0.519938 1.4986)
			(layers "F.Cu" "F.Mask" "F.Paste")
			(net "M_K_CPU1_SA_DQS_DN<4>")
		)
		(pad "57" smd rect
			(at -2.050034 -15.724886 90)
			(size 0.519938 1.4986)
			(layers "F.Cu" "F.Mask" "F.Paste")
			(net "GND")
		)
		(pad "58" smd rect
			(at -2.050034 -14.875002 90)
			(size 0.519938 1.4986)
			(layers "F.Cu" "F.Mask" "F.Paste")
			(net "M_K_CPU1_SA_CB<4>")
		)
		(pad "59" smd rect
			(at -2.050034 -14.025118 90)
			(size 0.519938 1.4986)
			(layers "F.Cu" "F.Mask" "F.Paste")
			(net "GND")
		)
		(pad "60" smd rect
			(at -2.050034 -13.17498 90)
			(size 0.519938 1.4986)
			(layers "F.Cu" "F.Mask" "F.Paste")
			(net "M_K_CPU1_SA_CB<5>")
		)
		(pad "61" smd rect
			(at -2.050034 -12.325096 90)
			(size 0.519938 1.4986)
			(layers "F.Cu" "F.Mask" "F.Paste")
			(net "GND")
		)
		(pad "62" smd rect
			(at -2.050034 -11.474958 90)
			(size 0.519938 1.4986)
			(layers "F.Cu" "F.Mask" "F.Paste")
			(net "M_K_CPU1_ALERT_N")
		)
		(pad "63" smd rect
			(at -2.050034 -10.625074 90)
			(size 0.519938 1.4986)
			(layers "F.Cu" "F.Mask" "F.Paste")
			(net "GND")
		)
		(pad "64" smd rect
			(at -2.050034 -9.774936 90)
			(size 0.519938 1.4986)
			(layers "F.Cu" "F.Mask" "F.Paste")
			(net "M_K_CPU1_SA_CS_N<0>")
		)
		(pad "65" smd rect
			(at -2.050034 -8.925052 90)
			(size 0.519938 1.4986)
			(layers "F.Cu" "F.Mask" "F.Paste")
			(net "GND")
		)
		(pad "66" smd rect
			(at -2.050034 -8.074914 90)
			(size 0.519938 1.4986)
			(layers "F.Cu" "F.Mask" "F.Paste")
			(net "M_K_CPU1_SA_CA<0>")
		)
		(pad "67" smd rect
			(at -2.050034 -7.22503 90)
			(size 0.519938 1.4986)
			(layers "F.Cu" "F.Mask" "F.Paste")
			(net "GND")
		)
		(pad "68" smd rect
			(at -2.050034 -6.374892 90)
			(size 0.519938 1.4986)
			(layers "F.Cu" "F.Mask" "F.Paste")
			(net "M_K_CPU1_SA_CA<2>")
		)
		(pad "69" smd rect
			(at -2.050034 -5.525008 90)
			(size 0.519938 1.4986)
			(layers "F.Cu" "F.Mask" "F.Paste")
			(net "GND")
		)
		(pad "70" smd rect
			(at -2.050034 -4.675124 90)
			(size 0.519938 1.4986)
			(layers "F.Cu" "F.Mask" "F.Paste")
			(net "M_K_CPU1_SA_CA<4>")
		)
		(pad "71" smd rect
			(at -2.050034 -3.824986 90)
			(size 0.519938 1.4986)
			(layers "F.Cu" "F.Mask" "F.Paste")
			(net "GND")
		)
		(pad "72" smd rect
			(at -2.050034 -2.975102 90)
			(size 0.519938 1.4986)
			(layers "F.Cu" "F.Mask" "F.Paste")
			(net "M_K_CPU1_SA_CA<6>")
		)
		(pad "73" smd rect
			(at -2.050034 -2.124964 90)
			(size 0.519938 1.4986)
			(layers "F.Cu" "F.Mask" "F.Paste")
			(net "GND")
		)
		(pad "74" smd rect
			(at -2.050034 -1.27508 90)
			(size 0.519938 1.4986)
			(layers "F.Cu" "F.Mask" "F.Paste")
			(net "M_K_CPU1_SA_PAR")
		)
		(pad "75" smd rect
			(at -2.050034 -0.424942 90)
			(size 0.519938 1.4986)
			(layers "F.Cu" "F.Mask" "F.Paste")
			(net "GND")
		)
		(pad "76" smd rect
			(at -2.050034 5.525008 90)
			(size 0.519938 1.4986)
			(layers "F.Cu" "F.Mask" "F.Paste")
			(net "M_K_CPU1_SB_CA<0>")
		)
		(pad "77" smd rect
			(at -2.050034 6.374892 90)
			(size 0.519938 1.4986)
			(layers "F.Cu" "F.Mask" "F.Paste")
			(net "GND")
		)
		(pad "78" smd rect
			(at -2.050034 7.22503 90)
			(size 0.519938 1.4986)
			(layers "F.Cu" "F.Mask" "F.Paste")
			(net "M_K_CPU1_SB_CA<2>")
		)
		(pad "79" smd rect
			(at -2.050034 8.074914 90)
			(size 0.519938 1.4986)
			(layers "F.Cu" "F.Mask" "F.Paste")
			(net "GND")
		)
		(pad "80" smd rect
			(at -2.050034 8.925052 90)
			(size 0.519938 1.4986)
			(layers "F.Cu" "F.Mask" "F.Paste")
			(net "M_K_CPU1_SB_CA<4>")
		)
		(pad "81" smd rect
			(at -2.050034 9.774936 90)
			(size 0.519938 1.4986)
			(layers "F.Cu" "F.Mask" "F.Paste")
			(net "GND")
		)
		(pad "82" smd rect
			(at -2.050034 10.625074 90)
			(size 0.519938 1.4986)
			(layers "F.Cu" "F.Mask" "F.Paste")
			(net "M_K_CPU1_SB_CA<6>")
		)
		(pad "83" smd rect
			(at -2.050034 11.474958 90)
			(size 0.519938 1.4986)
			(layers "F.Cu" "F.Mask" "F.Paste")
			(net "GND")
		)
		(pad "84" smd rect
			(at -2.050034 12.325096 90)
			(size 0.519938 1.4986)
			(layers "F.Cu" "F.Mask" "F.Paste")
			(net "M_K_CPU1_SB_CS_N<0>")
		)
		(pad "85" smd rect
			(at -2.050034 13.17498 90)
			(size 0.519938 1.4986)
			(layers "F.Cu" "F.Mask" "F.Paste")
			(net "GND")
		)
		(pad "86" smd rect
			(at -2.050034 14.025118 90)
			(size 0.519938 1.4986)
			(layers "F.Cu" "F.Mask" "F.Paste")
			(net "M_K_CPU1_SA_RSP<0>")
		)
		(pad "87" smd rect
			(at -2.050034 14.875002 90)
			(size 0.519938 1.4986)
			(layers "F.Cu" "F.Mask" "F.Paste")
			(net "M_K_CPU1_SB_RSP<0>")
		)
		(pad "88" smd rect
			(at -2.050034 15.724886 90)
			(size 0.519938 1.4986)
			(layers "F.Cu" "F.Mask" "F.Paste")
			(net "GND")
		)
		(pad "89" smd rect
			(at -2.050034 16.575024 90)
			(size 0.519938 1.4986)
			(layers "F.Cu" "F.Mask" "F.Paste")
			(net "M_K_CPU1_SB_CB<4>")
		)
		(pad "90" smd rect
			(at -2.050034 17.424908 90)
			(size 0.519938 1.4986)
			(layers "F.Cu" "F.Mask" "F.Paste")
			(net "GND")
		)
		(pad "91" smd rect
			(at -2.050034 18.275046 90)
			(size 0.519938 1.4986)
			(layers "F.Cu" "F.Mask" "F.Paste")
			(net "M_K_CPU1_SB_CB<5>")
		)
		(pad "92" smd rect
			(at -2.050034 19.12493 90)
			(size 0.519938 1.4986)
			(layers "F.Cu" "F.Mask" "F.Paste")
			(net "GND")
		)
		(pad "93" smd rect
			(at -2.050034 19.975068 90)
			(size 0.519938 1.4986)
			(layers "F.Cu" "F.Mask" "F.Paste")
			(net "M_K_CPU1_SB_DQS_DP<9>")
		)
		(pad "94" smd rect
			(at -2.050034 20.824952 90)
			(size 0.519938 1.4986)
			(layers "F.Cu" "F.Mask" "F.Paste")
			(net "M_K_CPU1_SB_DQS_DN<9>")
		)
		(pad "95" smd rect
			(at -2.050034 21.67509 90)
			(size 0.519938 1.4986)
			(layers "F.Cu" "F.Mask" "F.Paste")
			(net "GND")
		)
		(pad "96" smd rect
			(at -2.050034 22.524974 90)
			(size 0.519938 1.4986)
			(layers "F.Cu" "F.Mask" "F.Paste")
			(net "M_K_CPU1_SB_CB<0>")
		)
		(pad "97" smd rect
			(at -2.050034 23.375112 90)
			(size 0.519938 1.4986)
			(layers "F.Cu" "F.Mask" "F.Paste")
			(net "GND")
		)
		(pad "98" smd rect
			(at -2.050034 24.224996 90)
			(size 0.519938 1.4986)
			(layers "F.Cu" "F.Mask" "F.Paste")
			(net "M_K_CPU1_SB_CB<1>")
		)
		(pad "99" smd rect
			(at -2.050034 25.07488 90)
			(size 0.519938 1.4986)
			(layers "F.Cu" "F.Mask" "F.Paste")
			(net "GND")
		)
		(pad "100" smd rect
			(at -2.050034 25.925018 90)
			(size 0.519938 1.4986)
			(layers "F.Cu" "F.Mask" "F.Paste")
			(net "M_K_CPU1_SB_DQ<0>")
		)
		(pad "101" smd rect
			(at -2.050034 26.774902 90)
			(size 0.519938 1.4986)
			(layers "F.Cu" "F.Mask" "F.Paste")
			(net "GND")
		)
		(pad "102" smd rect
			(at -2.050034 27.62504 90)
			(size 0.519938 1.4986)
			(layers "F.Cu" "F.Mask" "F.Paste")
			(net "M_K_CPU1_SB_DQ<1>")
		)
		(pad "103" smd rect
			(at -2.050034 28.474924 90)
			(size 0.519938 1.4986)
			(layers "F.Cu" "F.Mask" "F.Paste")
			(net "GND")
		)
		(pad "104" smd rect
			(at -2.050034 29.325062 90)
			(size 0.519938 1.4986)
			(layers "F.Cu" "F.Mask" "F.Paste")
			(net "M_K_CPU1_SB_DQS_DP<0>")
		)
		(pad "105" smd rect
			(at -2.050034 30.174946 90)
			(size 0.519938 1.4986)
			(layers "F.Cu" "F.Mask" "F.Paste")
			(net "M_K_CPU1_SB_DQS_DN<0>")
		)
		(pad "106" smd rect
			(at -2.050034 31.025084 90)
			(size 0.519938 1.4986)
			(layers "F.Cu" "F.Mask" "F.Paste")
			(net "GND")
		)
		(pad "107" smd rect
			(at -2.050034 31.874968 90)
			(size 0.519938 1.4986)
			(layers "F.Cu" "F.Mask" "F.Paste")
			(net "M_K_CPU1_SB_DQ<4>")
		)
		(pad "108" smd rect
			(at -2.050034 32.725106 90)
			(size 0.519938 1.4986)
			(layers "F.Cu" "F.Mask" "F.Paste")
			(net "GND")
		)
		(pad "109" smd rect
			(at -2.050034 33.57499 90)
			(size 0.519938 1.4986)
			(layers "F.Cu" "F.Mask" "F.Paste")
			(net "M_K_CPU1_SB_DQ<5>")
		)
		(pad "110" smd rect
			(at -2.050034 34.425128 90)
			(size 0.519938 1.4986)
			(layers "F.Cu" "F.Mask" "F.Paste")
			(net "GND")
		)
		(pad "111" smd rect
			(at -2.050034 35.275012 90)
			(size 0.519938 1.4986)
			(layers "F.Cu" "F.Mask" "F.Paste")
			(net "M_K_CPU1_SB_DQ<8>")
		)
		(pad "112" smd rect
			(at -2.050034 36.124896 90)
			(size 0.519938 1.4986)
			(layers "F.Cu" "F.Mask" "F.Paste")
			(net "GND")
		)
		(pad "113" smd rect
			(at -2.050034 36.975034 90)
			(size 0.519938 1.4986)
			(layers "F.Cu" "F.Mask" "F.Paste")
			(net "M_K_CPU1_SB_DQ<9>")
		)
		(pad "114" smd rect
			(at -2.050034 37.824918 90)
			(size 0.519938 1.4986)
			(layers "F.Cu" "F.Mask" "F.Paste")
			(net "GND")
		)
		(pad "115" smd rect
			(at -2.050034 38.675056 90)
			(size 0.519938 1.4986)
			(layers "F.Cu" "F.Mask" "F.Paste")
			(net "M_K_CPU1_SB_DQS_DP<1>")
		)
		(pad "116" smd rect
			(at -2.050034 39.52494 90)
			(size 0.519938 1.4986)
			(layers "F.Cu" "F.Mask" "F.Paste")
			(net "M_K_CPU1_SB_DQS_DN<1>")
		)
		(pad "117" smd rect
			(at -2.050034 40.375078 90)
			(size 0.519938 1.4986)
			(layers "F.Cu" "F.Mask" "F.Paste")
			(net "GND")
		)
		(pad "118" smd rect
			(at -2.050034 41.224962 90)
			(size 0.519938 1.4986)
			(layers "F.Cu" "F.Mask" "F.Paste")
			(net "M_K_CPU1_SB_DQ<12>")
		)
		(pad "119" smd rect
			(at -2.050034 42.0751 90)
			(size 0.519938 1.4986)
			(layers "F.Cu" "F.Mask" "F.Paste")
			(net "GND")
		)
		(pad "120" smd rect
			(at -2.050034 42.924984 90)
			(size 0.519938 1.4986)
			(layers "F.Cu" "F.Mask" "F.Paste")
			(net "M_K_CPU1_SB_DQ<13>")
		)
		(pad "121" smd rect
			(at -2.050034 43.775122 90)
			(size 0.519938 1.4986)
			(layers "F.Cu" "F.Mask" "F.Paste")
			(net "GND")
		)
		(pad "122" smd rect
			(at -2.050034 44.625006 90)
			(size 0.519938 1.4986)
			(layers "F.Cu" "F.Mask" "F.Paste")
			(net "M_K_CPU1_SB_DQ<16>")
		)
		(pad "123" smd rect
			(at -2.050034 45.47489 90)
			(size 0.519938 1.4986)
			(layers "F.Cu" "F.Mask" "F.Paste")
			(net "GND")
		)
		(pad "124" smd rect
			(at -2.050034 46.325028 90)
			(size 0.519938 1.4986)
			(layers "F.Cu" "F.Mask" "F.Paste")
			(net "M_K_CPU1_SB_DQ<17>")
		)
		(pad "125" smd rect
			(at -2.050034 47.174912 90)
			(size 0.519938 1.4986)
			(layers "F.Cu" "F.Mask" "F.Paste")
			(net "GND")
		)
		(pad "126" smd rect
			(at -2.050034 48.02505 90)
			(size 0.519938 1.4986)
			(layers "F.Cu" "F.Mask" "F.Paste")
			(net "M_K_CPU1_SB_DQS_DP<2>")
		)
		(pad "127" smd rect
			(at -2.050034 48.874934 90)
			(size 0.519938 1.4986)
			(layers "F.Cu" "F.Mask" "F.Paste")
			(net "M_K_CPU1_SB_DQS_DN<2>")
		)
		(pad "128" smd rect
			(at -2.050034 49.725072 90)
			(size 0.519938 1.4986)
			(layers "F.Cu" "F.Mask" "F.Paste")
			(net "GND")
		)
		(pad "129" smd rect
			(at -2.050034 50.574956 90)
			(size 0.519938 1.4986)
			(layers "F.Cu" "F.Mask" "F.Paste")
			(net "M_K_CPU1_SB_DQ<20>")
		)
		(pad "130" smd rect
			(at -2.050034 51.425094 90)
			(size 0.519938 1.4986)
			(layers "F.Cu" "F.Mask" "F.Paste")
			(net "GND")
		)
		(pad "131" smd rect
			(at -2.050034 52.274978 90)
			(size 0.519938 1.4986)
			(layers "F.Cu" "F.Mask" "F.Paste")
			(net "M_K_CPU1_SB_DQ<21>")
		)
		(pad "132" smd rect
			(at -2.050034 53.125116 90)
			(size 0.519938 1.4986)
			(layers "F.Cu" "F.Mask" "F.Paste")
			(net "GND")
		)
		(pad "133" smd rect
			(at -2.050034 53.975 90)
			(size 0.519938 1.4986)
			(layers "F.Cu" "F.Mask" "F.Paste")
			(net "M_K_CPU1_SB_DQ<24>")
		)
		(pad "134" smd rect
			(at -2.050034 54.824884 90)
			(size 0.519938 1.4986)
			(layers "F.Cu" "F.Mask" "F.Paste")
			(net "GND")
		)
		(pad "135" smd rect
			(at -2.050034 55.675022 90)
			(size 0.519938 1.4986)
			(layers "F.Cu" "F.Mask" "F.Paste")
			(net "M_K_CPU1_SB_DQ<25>")
		)
		(pad "136" smd rect
			(at -2.050034 56.524906 90)
			(size 0.519938 1.4986)
			(layers "F.Cu" "F.Mask" "F.Paste")
			(net "GND")
		)
		(pad "137" smd rect
			(at -2.050034 57.375044 90)
			(size 0.519938 1.4986)
			(layers "F.Cu" "F.Mask" "F.Paste")
			(net "M_K_CPU1_SB_DQS_DP<3>")
		)
		(pad "138" smd rect
			(at -2.050034 58.224928 90)
			(size 0.519938 1.4986)
			(layers "F.Cu" "F.Mask" "F.Paste")
			(net "M_K_CPU1_SB_DQS_DN<3>")
		)
		(pad "139" smd rect
			(at -2.050034 59.075066 90)
			(size 0.519938 1.4986)
			(layers "F.Cu" "F.Mask" "F.Paste")
			(net "GND")
		)
		(pad "140" smd rect
			(at -2.050034 59.92495 90)
			(size 0.519938 1.4986)
			(layers "F.Cu" "F.Mask" "F.Paste")
			(net "M_K_CPU1_SB_DQ<28>")
		)
		(pad "141" smd rect
			(at -2.050034 60.775088 90)
			(size 0.519938 1.4986)
			(layers "F.Cu" "F.Mask" "F.Paste")
			(net "GND")
		)
		(pad "142" smd rect
			(at -2.050034 61.624972 90)
			(size 0.519938 1.4986)
			(layers "F.Cu" "F.Mask" "F.Paste")
			(net "M_K_CPU1_SB_DQ<29>")
		)
		(pad "143" smd rect
			(at -2.050034 62.47511 90)
			(size 0.519938 1.4986)
			(layers "F.Cu" "F.Mask" "F.Paste")
			(net "GND")
		)
		(pad "144" smd rect
			(at -2.050034 63.324994 90)
			(size 0.519938 1.4986)
			(layers "F.Cu" "F.Mask" "F.Paste")
			(net "Net_2397")
		)
		(pad "145" smd rect
			(at 2.050034 -63.324994 90)
			(size 0.519938 1.4986)
			(layers "F.Cu" "F.Mask" "F.Paste")
			(net "P12V_MEM_CPU1")
		)
		(pad "146" smd rect
			(at 2.050034 -62.47511 90)
			(size 0.519938 1.4986)
			(layers "F.Cu" "F.Mask" "F.Paste")
			(net "P12V_MEM_CPU1")
		)
		(pad "147" smd rect
			(at 2.050034 -61.624972 90)
			(size 0.519938 1.4986)
			(layers "F.Cu" "F.Mask" "F.Paste")
			(net "PWRGD_CHK_CPU1_DIMM")
		)
		(pad "148" smd rect
			(at 2.050034 -60.775088 90)
			(size 0.519938 1.4986)
			(layers "F.Cu" "F.Mask" "F.Paste")
			(net "PD_CHK_CPU1_DIMM_SAA")
		)
		(pad "149" smd rect
			(at 2.050034 -59.92495 90)
			(size 0.519938 1.4986)
			(layers "F.Cu" "F.Mask" "F.Paste")
			(net "Net_2398")
		)
		(pad "150" smd rect
			(at 2.050034 -59.075066 90)
			(size 0.519938 1.4986)
			(layers "F.Cu" "F.Mask" "F.Paste")
			(net "Net_2399")
		)
		(pad "151" smd rect
			(at 2.050034 -58.224928 90)
			(size 0.519938 1.4986)
			(layers "F.Cu" "F.Mask" "F.Paste")
			(net "GND")
		)
		(pad "152" smd rect
			(at 2.050034 -57.375044 90)
			(size 0.519938 1.4986)
			(layers "F.Cu" "F.Mask" "F.Paste")
			(net "M_K_CPU1_SA_DQ<2>")
		)
		(pad "153" smd rect
			(at 2.050034 -56.524906 90)
			(size 0.519938 1.4986)
			(layers "F.Cu" "F.Mask" "F.Paste")
			(net "GND")
		)
		(pad "154" smd rect
			(at 2.050034 -55.675022 90)
			(size 0.519938 1.4986)
			(layers "F.Cu" "F.Mask" "F.Paste")
			(net "M_K_CPU1_SA_DQ<3>")
		)
		(pad "155" smd rect
			(at 2.050034 -54.824884 90)
			(size 0.519938 1.4986)
			(layers "F.Cu" "F.Mask" "F.Paste")
			(net "GND")
		)
		(pad "156" smd rect
			(at 2.050034 -53.975 90)
			(size 0.519938 1.4986)
			(layers "F.Cu" "F.Mask" "F.Paste")
			(net "M_K_CPU1_SA_DQS_DN<5>")
		)
		(pad "157" smd rect
			(at 2.050034 -53.125116 90)
			(size 0.519938 1.4986)
			(layers "F.Cu" "F.Mask" "F.Paste")
			(net "M_K_CPU1_SA_DQS_DP<5>")
		)
		(pad "158" smd rect
			(at 2.050034 -52.274978 90)
			(size 0.519938 1.4986)
			(layers "F.Cu" "F.Mask" "F.Paste")
			(net "GND")
		)
		(pad "159" smd rect
			(at 2.050034 -51.425094 90)
			(size 0.519938 1.4986)
			(layers "F.Cu" "F.Mask" "F.Paste")
			(net "M_K_CPU1_SA_DQ<6>")
		)
		(pad "160" smd rect
			(at 2.050034 -50.574956 90)
			(size 0.519938 1.4986)
			(layers "F.Cu" "F.Mask" "F.Paste")
			(net "GND")
		)
		(pad "161" smd rect
			(at 2.050034 -49.725072 90)
			(size 0.519938 1.4986)
			(layers "F.Cu" "F.Mask" "F.Paste")
			(net "M_K_CPU1_SA_DQ<7>")
		)
		(pad "162" smd rect
			(at 2.050034 -48.874934 90)
			(size 0.519938 1.4986)
			(layers "F.Cu" "F.Mask" "F.Paste")
			(net "GND")
		)
		(pad "163" smd rect
			(at 2.050034 -48.02505 90)
			(size 0.519938 1.4986)
			(layers "F.Cu" "F.Mask" "F.Paste")
			(net "M_K_CPU1_SA_DQ<10>")
		)
		(pad "164" smd rect
			(at 2.050034 -47.174912 90)
			(size 0.519938 1.4986)
			(layers "F.Cu" "F.Mask" "F.Paste")
			(net "GND")
		)
		(pad "165" smd rect
			(at 2.050034 -46.325028 90)
			(size 0.519938 1.4986)
			(layers "F.Cu" "F.Mask" "F.Paste")
			(net "M_K_CPU1_SA_DQ<11>")
		)
		(pad "166" smd rect
			(at 2.050034 -45.47489 90)
			(size 0.519938 1.4986)
			(layers "F.Cu" "F.Mask" "F.Paste")
			(net "GND")
		)
		(pad "167" smd rect
			(at 2.050034 -44.625006 90)
			(size 0.519938 1.4986)
			(layers "F.Cu" "F.Mask" "F.Paste")
			(net "M_K_CPU1_SA_DQS_DN<6>")
		)
		(pad "168" smd rect
			(at 2.050034 -43.775122 90)
			(size 0.519938 1.4986)
			(layers "F.Cu" "F.Mask" "F.Paste")
			(net "M_K_CPU1_SA_DQS_DP<6>")
		)
		(pad "169" smd rect
			(at 2.050034 -42.924984 90)
			(size 0.519938 1.4986)
			(layers "F.Cu" "F.Mask" "F.Paste")
			(net "GND")
		)
		(pad "170" smd rect
			(at 2.050034 -42.0751 90)
			(size 0.519938 1.4986)
			(layers "F.Cu" "F.Mask" "F.Paste")
			(net "M_K_CPU1_SA_DQ<14>")
		)
		(pad "171" smd rect
			(at 2.050034 -41.224962 90)
			(size 0.519938 1.4986)
			(layers "F.Cu" "F.Mask" "F.Paste")
			(net "GND")
		)
		(pad "172" smd rect
			(at 2.050034 -40.375078 90)
			(size 0.519938 1.4986)
			(layers "F.Cu" "F.Mask" "F.Paste")
			(net "M_K_CPU1_SA_DQ<15>")
		)
		(pad "173" smd rect
			(at 2.050034 -39.52494 90)
			(size 0.519938 1.4986)
			(layers "F.Cu" "F.Mask" "F.Paste")
			(net "GND")
		)
		(pad "174" smd rect
			(at 2.050034 -38.675056 90)
			(size 0.519938 1.4986)
			(layers "F.Cu" "F.Mask" "F.Paste")
			(net "M_K_CPU1_SA_DQ<18>")
		)
		(pad "175" smd rect
			(at 2.050034 -37.824918 90)
			(size 0.519938 1.4986)
			(layers "F.Cu" "F.Mask" "F.Paste")
			(net "GND")
		)
		(pad "176" smd rect
			(at 2.050034 -36.975034 90)
			(size 0.519938 1.4986)
			(layers "F.Cu" "F.Mask" "F.Paste")
			(net "M_K_CPU1_SA_DQ<19>")
		)
		(pad "177" smd rect
			(at 2.050034 -36.124896 90)
			(size 0.519938 1.4986)
			(layers "F.Cu" "F.Mask" "F.Paste")
			(net "GND")
		)
		(pad "178" smd rect
			(at 2.050034 -35.275012 90)
			(size 0.519938 1.4986)
			(layers "F.Cu" "F.Mask" "F.Paste")
			(net "M_K_CPU1_SA_DQS_DN<7>")
		)
		(pad "179" smd rect
			(at 2.050034 -34.425128 90)
			(size 0.519938 1.4986)
			(layers "F.Cu" "F.Mask" "F.Paste")
			(net "M_K_CPU1_SA_DQS_DP<7>")
		)
		(pad "180" smd rect
			(at 2.050034 -33.57499 90)
			(size 0.519938 1.4986)
			(layers "F.Cu" "F.Mask" "F.Paste")
			(net "GND")
		)
		(pad "181" smd rect
			(at 2.050034 -32.725106 90)
			(size 0.519938 1.4986)
			(layers "F.Cu" "F.Mask" "F.Paste")
			(net "M_K_CPU1_SA_DQ<22>")
		)
		(pad "182" smd rect
			(at 2.050034 -31.874968 90)
			(size 0.519938 1.4986)
			(layers "F.Cu" "F.Mask" "F.Paste")
			(net "GND")
		)
		(pad "183" smd rect
			(at 2.050034 -31.025084 90)
			(size 0.519938 1.4986)
			(layers "F.Cu" "F.Mask" "F.Paste")
			(net "M_K_CPU1_SA_DQ<23>")
		)
		(pad "184" smd rect
			(at 2.050034 -30.174946 90)
			(size 0.519938 1.4986)
			(layers "F.Cu" "F.Mask" "F.Paste")
			(net "GND")
		)
		(pad "185" smd rect
			(at 2.050034 -29.325062 90)
			(size 0.519938 1.4986)
			(layers "F.Cu" "F.Mask" "F.Paste")
			(net "M_K_CPU1_SA_DQ<26>")
		)
		(pad "186" smd rect
			(at 2.050034 -28.474924 90)
			(size 0.519938 1.4986)
			(layers "F.Cu" "F.Mask" "F.Paste")
			(net "GND")
		)
		(pad "187" smd rect
			(at 2.050034 -27.62504 90)
			(size 0.519938 1.4986)
			(layers "F.Cu" "F.Mask" "F.Paste")
			(net "M_K_CPU1_SA_DQ<27>")
		)
		(pad "188" smd rect
			(at 2.050034 -26.774902 90)
			(size 0.519938 1.4986)
			(layers "F.Cu" "F.Mask" "F.Paste")
			(net "GND")
		)
		(pad "189" smd rect
			(at 2.050034 -25.925018 90)
			(size 0.519938 1.4986)
			(layers "F.Cu" "F.Mask" "F.Paste")
			(net "M_K_CPU1_SA_DQS_DN<8>")
		)
		(pad "190" smd rect
			(at 2.050034 -25.07488 90)
			(size 0.519938 1.4986)
			(layers "F.Cu" "F.Mask" "F.Paste")
			(net "M_K_CPU1_SA_DQS_DP<8>")
		)
		(pad "191" smd rect
			(at 2.050034 -24.224996 90)
			(size 0.519938 1.4986)
			(layers "F.Cu" "F.Mask" "F.Paste")
			(net "GND")
		)
		(pad "192" smd rect
			(at 2.050034 -23.375112 90)
			(size 0.519938 1.4986)
			(layers "F.Cu" "F.Mask" "F.Paste")
			(net "M_K_CPU1_SA_DQ<30>")
		)
		(pad "193" smd rect
			(at 2.050034 -22.524974 90)
			(size 0.519938 1.4986)
			(layers "F.Cu" "F.Mask" "F.Paste")
			(net "GND")
		)
		(pad "194" smd rect
			(at 2.050034 -21.67509 90)
			(size 0.519938 1.4986)
			(layers "F.Cu" "F.Mask" "F.Paste")
			(net "M_K_CPU1_SA_DQ<31>")
		)
		(pad "195" smd rect
			(at 2.050034 -20.824952 90)
			(size 0.519938 1.4986)
			(layers "F.Cu" "F.Mask" "F.Paste")
			(net "GND")
		)
		(pad "196" smd rect
			(at 2.050034 -19.975068 90)
			(size 0.519938 1.4986)
			(layers "F.Cu" "F.Mask" "F.Paste")
			(net "M_K_CPU1_SA_CB<2>")
		)
		(pad "197" smd rect
			(at 2.050034 -19.12493 90)
			(size 0.519938 1.4986)
			(layers "F.Cu" "F.Mask" "F.Paste")
			(net "GND")
		)
		(pad "198" smd rect
			(at 2.050034 -18.275046 90)
			(size 0.519938 1.4986)
			(layers "F.Cu" "F.Mask" "F.Paste")
			(net "M_K_CPU1_SA_CB<3>")
		)
		(pad "199" smd rect
			(at 2.050034 -17.424908 90)
			(size 0.519938 1.4986)
			(layers "F.Cu" "F.Mask" "F.Paste")
			(net "GND")
		)
		(pad "200" smd rect
			(at 2.050034 -16.575024 90)
			(size 0.519938 1.4986)
			(layers "F.Cu" "F.Mask" "F.Paste")
			(net "M_K_CPU1_SA_DQS_DN<9>")
		)
		(pad "201" smd rect
			(at 2.050034 -15.724886 90)
			(size 0.519938 1.4986)
			(layers "F.Cu" "F.Mask" "F.Paste")
			(net "M_K_CPU1_SA_DQS_DP<9>")
		)
		(pad "202" smd rect
			(at 2.050034 -14.875002 90)
			(size 0.519938 1.4986)
			(layers "F.Cu" "F.Mask" "F.Paste")
			(net "GND")
		)
		(pad "203" smd rect
			(at 2.050034 -14.025118 90)
			(size 0.519938 1.4986)
			(layers "F.Cu" "F.Mask" "F.Paste")
			(net "M_K_CPU1_SA_CB<6>")
		)
		(pad "204" smd rect
			(at 2.050034 -13.17498 90)
			(size 0.519938 1.4986)
			(layers "F.Cu" "F.Mask" "F.Paste")
			(net "GND")
		)
		(pad "205" smd rect
			(at 2.050034 -12.325096 90)
			(size 0.519938 1.4986)
			(layers "F.Cu" "F.Mask" "F.Paste")
			(net "M_K_CPU1_SA_CB<7>")
		)
		(pad "206" smd rect
			(at 2.050034 -11.474958 90)
			(size 0.519938 1.4986)
			(layers "F.Cu" "F.Mask" "F.Paste")
			(net "GND")
		)
		(pad "207" smd rect
			(at 2.050034 -10.625074 90)
			(size 0.519938 1.4986)
			(layers "F.Cu" "F.Mask" "F.Paste")
			(net "M_K_CPU1_RESET_N")
		)
		(pad "208" smd rect
			(at 2.050034 -9.774936 90)
			(size 0.519938 1.4986)
			(layers "F.Cu" "F.Mask" "F.Paste")
			(net "GND")
		)
		(pad "209" smd rect
			(at 2.050034 -8.925052 90)
			(size 0.519938 1.4986)
			(layers "F.Cu" "F.Mask" "F.Paste")
			(net "M_K_CPU1_SA_CS_N<1>")
		)
		(pad "210" smd rect
			(at 2.050034 -8.074914 90)
			(size 0.519938 1.4986)
			(layers "F.Cu" "F.Mask" "F.Paste")
			(net "GND")
		)
		(pad "211" smd rect
			(at 2.050034 -7.22503 90)
			(size 0.519938 1.4986)
			(layers "F.Cu" "F.Mask" "F.Paste")
			(net "M_K_CPU1_SA_CA<1>")
		)
		(pad "212" smd rect
			(at 2.050034 -6.374892 90)
			(size 0.519938 1.4986)
			(layers "F.Cu" "F.Mask" "F.Paste")
			(net "GND")
		)
		(pad "213" smd rect
			(at 2.050034 -5.525008 90)
			(size 0.519938 1.4986)
			(layers "F.Cu" "F.Mask" "F.Paste")
			(net "M_K_CPU1_SA_CA<3>")
		)
		(pad "214" smd rect
			(at 2.050034 -4.675124 90)
			(size 0.519938 1.4986)
			(layers "F.Cu" "F.Mask" "F.Paste")
			(net "GND")
		)
		(pad "215" smd rect
			(at 2.050034 -3.824986 90)
			(size 0.519938 1.4986)
			(layers "F.Cu" "F.Mask" "F.Paste")
			(net "M_K_CPU1_SA_CA<5>")
		)
		(pad "216" smd rect
			(at 2.050034 -2.975102 90)
			(size 0.519938 1.4986)
			(layers "F.Cu" "F.Mask" "F.Paste")
			(net "GND")
		)
		(pad "217" smd rect
			(at 2.050034 -2.124964 90)
			(size 0.519938 1.4986)
			(layers "F.Cu" "F.Mask" "F.Paste")
			(net "M_K_CPU1_CLK_DP<0>")
		)
		(pad "218" smd rect
			(at 2.050034 -1.27508 90)
			(size 0.519938 1.4986)
			(layers "F.Cu" "F.Mask" "F.Paste")
			(net "M_K_CPU1_CLK_DN<0>")
		)
		(pad "219" smd rect
			(at 2.050034 -0.424942 90)
			(size 0.519938 1.4986)
			(layers "F.Cu" "F.Mask" "F.Paste")
			(net "GND")
		)
		(pad "220" smd rect
			(at 2.050034 5.525008 90)
			(size 0.519938 1.4986)
			(layers "F.Cu" "F.Mask" "F.Paste")
			(net "Net_2400")
		)
		(pad "221" smd rect
			(at 2.050034 6.374892 90)
			(size 0.519938 1.4986)
			(layers "F.Cu" "F.Mask" "F.Paste")
			(net "M_K_CPU1_SB_CA<1>")
		)
		(pad "222" smd rect
			(at 2.050034 7.22503 90)
			(size 0.519938 1.4986)
			(layers "F.Cu" "F.Mask" "F.Paste")
			(net "GND")
		)
		(pad "223" smd rect
			(at 2.050034 8.074914 90)
			(size 0.519938 1.4986)
			(layers "F.Cu" "F.Mask" "F.Paste")
			(net "M_K_CPU1_SB_CA<3>")
		)
		(pad "224" smd rect
			(at 2.050034 8.925052 90)
			(size 0.519938 1.4986)
			(layers "F.Cu" "F.Mask" "F.Paste")
			(net "GND")
		)
		(pad "225" smd rect
			(at 2.050034 9.774936 90)
			(size 0.519938 1.4986)
			(layers "F.Cu" "F.Mask" "F.Paste")
			(net "M_K_CPU1_SB_CA<5>")
		)
		(pad "226" smd rect
			(at 2.050034 10.625074 90)
			(size 0.519938 1.4986)
			(layers "F.Cu" "F.Mask" "F.Paste")
			(net "GND")
		)
		(pad "227" smd rect
			(at 2.050034 11.474958 90)
			(size 0.519938 1.4986)
			(layers "F.Cu" "F.Mask" "F.Paste")
			(net "M_K_CPU1_SB_PAR")
		)
		(pad "228" smd rect
			(at 2.050034 12.325096 90)
			(size 0.519938 1.4986)
			(layers "F.Cu" "F.Mask" "F.Paste")
			(net "GND")
		)
		(pad "229" smd rect
			(at 2.050034 13.17498 90)
			(size 0.519938 1.4986)
			(layers "F.Cu" "F.Mask" "F.Paste")
			(net "M_K_CPU1_SB_CS_N<1>")
		)
		(pad "230" smd rect
			(at 2.050034 14.025118 90)
			(size 0.519938 1.4986)
			(layers "F.Cu" "F.Mask" "F.Paste")
			(net "GND")
		)
		(pad "231" smd rect
			(at 2.050034 14.875002 90)
			(size 0.519938 1.4986)
			(layers "F.Cu" "F.Mask" "F.Paste")
			(net "Net_2401")
		)
		(pad "232" smd rect
			(at 2.050034 15.724886 90)
			(size 0.519938 1.4986)
			(layers "F.Cu" "F.Mask" "F.Paste")
			(net "Net_2402")
		)
		(pad "233" smd rect
			(at 2.050034 16.575024 90)
			(size 0.519938 1.4986)
			(layers "F.Cu" "F.Mask" "F.Paste")
			(net "GND")
		)
		(pad "234" smd rect
			(at 2.050034 17.424908 90)
			(size 0.519938 1.4986)
			(layers "F.Cu" "F.Mask" "F.Paste")
			(net "M_K_CPU1_SB_CB<6>")
		)
		(pad "235" smd rect
			(at 2.050034 18.275046 90)
			(size 0.519938 1.4986)
			(layers "F.Cu" "F.Mask" "F.Paste")
			(net "GND")
		)
		(pad "236" smd rect
			(at 2.050034 19.12493 90)
			(size 0.519938 1.4986)
			(layers "F.Cu" "F.Mask" "F.Paste")
			(net "M_K_CPU1_SB_CB<7>")
		)
		(pad "237" smd rect
			(at 2.050034 19.975068 90)
			(size 0.519938 1.4986)
			(layers "F.Cu" "F.Mask" "F.Paste")
			(net "GND")
		)
		(pad "238" smd rect
			(at 2.050034 20.824952 90)
			(size 0.519938 1.4986)
			(layers "F.Cu" "F.Mask" "F.Paste")
			(net "M_K_CPU1_SB_DQS_DN<4>")
		)
		(pad "239" smd rect
			(at 2.050034 21.67509 90)
			(size 0.519938 1.4986)
			(layers "F.Cu" "F.Mask" "F.Paste")
			(net "M_K_CPU1_SB_DQS_DP<4>")
		)
		(pad "240" smd rect
			(at 2.050034 22.524974 90)
			(size 0.519938 1.4986)
			(layers "F.Cu" "F.Mask" "F.Paste")
			(net "GND")
		)
		(pad "241" smd rect
			(at 2.050034 23.375112 90)
			(size 0.519938 1.4986)
			(layers "F.Cu" "F.Mask" "F.Paste")
			(net "M_K_CPU1_SB_CB<2>")
		)
		(pad "242" smd rect
			(at 2.050034 24.224996 90)
			(size 0.519938 1.4986)
			(layers "F.Cu" "F.Mask" "F.Paste")
			(net "GND")
		)
		(pad "243" smd rect
			(at 2.050034 25.07488 90)
			(size 0.519938 1.4986)
			(layers "F.Cu" "F.Mask" "F.Paste")
			(net "M_K_CPU1_SB_CB<3>")
		)
		(pad "244" smd rect
			(at 2.050034 25.925018 90)
			(size 0.519938 1.4986)
			(layers "F.Cu" "F.Mask" "F.Paste")
			(net "GND")
		)
		(pad "245" smd rect
			(at 2.050034 26.774902 90)
			(size 0.519938 1.4986)
			(layers "F.Cu" "F.Mask" "F.Paste")
			(net "M_K_CPU1_SB_DQ<2>")
		)
		(pad "246" smd rect
			(at 2.050034 27.62504 90)
			(size 0.519938 1.4986)
			(layers "F.Cu" "F.Mask" "F.Paste")
			(net "GND")
		)
		(pad "247" smd rect
			(at 2.050034 28.474924 90)
			(size 0.519938 1.4986)
			(layers "F.Cu" "F.Mask" "F.Paste")
			(net "M_K_CPU1_SB_DQ<3>")
		)
		(pad "248" smd rect
			(at 2.050034 29.325062 90)
			(size 0.519938 1.4986)
			(layers "F.Cu" "F.Mask" "F.Paste")
			(net "GND")
		)
		(pad "249" smd rect
			(at 2.050034 30.174946 90)
			(size 0.519938 1.4986)
			(layers "F.Cu" "F.Mask" "F.Paste")
			(net "M_K_CPU1_SB_DQS_DN<5>")
		)
		(pad "250" smd rect
			(at 2.050034 31.025084 90)
			(size 0.519938 1.4986)
			(layers "F.Cu" "F.Mask" "F.Paste")
			(net "M_K_CPU1_SB_DQS_DP<5>")
		)
		(pad "251" smd rect
			(at 2.050034 31.874968 90)
			(size 0.519938 1.4986)
			(layers "F.Cu" "F.Mask" "F.Paste")
			(net "GND")
		)
		(pad "252" smd rect
			(at 2.050034 32.725106 90)
			(size 0.519938 1.4986)
			(layers "F.Cu" "F.Mask" "F.Paste")
			(net "M_K_CPU1_SB_DQ<6>")
		)
		(pad "253" smd rect
			(at 2.050034 33.57499 90)
			(size 0.519938 1.4986)
			(layers "F.Cu" "F.Mask" "F.Paste")
			(net "GND")
		)
		(pad "254" smd rect
			(at 2.050034 34.425128 90)
			(size 0.519938 1.4986)
			(layers "F.Cu" "F.Mask" "F.Paste")
			(net "M_K_CPU1_SB_DQ<7>")
		)
		(pad "255" smd rect
			(at 2.050034 35.275012 90)
			(size 0.519938 1.4986)
			(layers "F.Cu" "F.Mask" "F.Paste")
			(net "GND")
		)
		(pad "256" smd rect
			(at 2.050034 36.124896 90)
			(size 0.519938 1.4986)
			(layers "F.Cu" "F.Mask" "F.Paste")
			(net "M_K_CPU1_SB_DQ<10>")
		)
		(pad "257" smd rect
			(at 2.050034 36.975034 90)
			(size 0.519938 1.4986)
			(layers "F.Cu" "F.Mask" "F.Paste")
			(net "GND")
		)
		(pad "258" smd rect
			(at 2.050034 37.824918 90)
			(size 0.519938 1.4986)
			(layers "F.Cu" "F.Mask" "F.Paste")
			(net "M_K_CPU1_SB_DQ<11>")
		)
		(pad "259" smd rect
			(at 2.050034 38.675056 90)
			(size 0.519938 1.4986)
			(layers "F.Cu" "F.Mask" "F.Paste")
			(net "GND")
		)
		(pad "260" smd rect
			(at 2.050034 39.52494 90)
			(size 0.519938 1.4986)
			(layers "F.Cu" "F.Mask" "F.Paste")
			(net "M_K_CPU1_SB_DQS_DN<6>")
		)
		(pad "261" smd rect
			(at 2.050034 40.375078 90)
			(size 0.519938 1.4986)
			(layers "F.Cu" "F.Mask" "F.Paste")
			(net "M_K_CPU1_SB_DQS_DP<6>")
		)
		(pad "262" smd rect
			(at 2.050034 41.224962 90)
			(size 0.519938 1.4986)
			(layers "F.Cu" "F.Mask" "F.Paste")
			(net "GND")
		)
		(pad "263" smd rect
			(at 2.050034 42.0751 90)
			(size 0.519938 1.4986)
			(layers "F.Cu" "F.Mask" "F.Paste")
			(net "M_K_CPU1_SB_DQ<14>")
		)
		(pad "264" smd rect
			(at 2.050034 42.924984 90)
			(size 0.519938 1.4986)
			(layers "F.Cu" "F.Mask" "F.Paste")
			(net "GND")
		)
		(pad "265" smd rect
			(at 2.050034 43.775122 90)
			(size 0.519938 1.4986)
			(layers "F.Cu" "F.Mask" "F.Paste")
			(net "M_K_CPU1_SB_DQ<15>")
		)
		(pad "266" smd rect
			(at 2.050034 44.625006 90)
			(size 0.519938 1.4986)
			(layers "F.Cu" "F.Mask" "F.Paste")
			(net "GND")
		)
		(pad "267" smd rect
			(at 2.050034 45.47489 90)
			(size 0.519938 1.4986)
			(layers "F.Cu" "F.Mask" "F.Paste")
			(net "M_K_CPU1_SB_DQ<18>")
		)
		(pad "268" smd rect
			(at 2.050034 46.325028 90)
			(size 0.519938 1.4986)
			(layers "F.Cu" "F.Mask" "F.Paste")
			(net "GND")
		)
		(pad "269" smd rect
			(at 2.050034 47.174912 90)
			(size 0.519938 1.4986)
			(layers "F.Cu" "F.Mask" "F.Paste")
			(net "M_K_CPU1_SB_DQ<19>")
		)
		(pad "270" smd rect
			(at 2.050034 48.02505 90)
			(size 0.519938 1.4986)
			(layers "F.Cu" "F.Mask" "F.Paste")
			(net "GND")
		)
		(pad "271" smd rect
			(at 2.050034 48.874934 90)
			(size 0.519938 1.4986)
			(layers "F.Cu" "F.Mask" "F.Paste")
			(net "M_K_CPU1_SB_DQS_DN<7>")
		)
		(pad "272" smd rect
			(at 2.050034 49.725072 90)
			(size 0.519938 1.4986)
			(layers "F.Cu" "F.Mask" "F.Paste")
			(net "M_K_CPU1_SB_DQS_DP<7>")
		)
		(pad "273" smd rect
			(at 2.050034 50.574956 90)
			(size 0.519938 1.4986)
			(layers "F.Cu" "F.Mask" "F.Paste")
			(net "GND")
		)
		(pad "274" smd rect
			(at 2.050034 51.425094 90)
			(size 0.519938 1.4986)
			(layers "F.Cu" "F.Mask" "F.Paste")
			(net "M_K_CPU1_SB_DQ<22>")
		)
		(pad "275" smd rect
			(at 2.050034 52.274978 90)
			(size 0.519938 1.4986)
			(layers "F.Cu" "F.Mask" "F.Paste")
			(net "GND")
		)
		(pad "276" smd rect
			(at 2.050034 53.125116 90)
			(size 0.519938 1.4986)
			(layers "F.Cu" "F.Mask" "F.Paste")
			(net "M_K_CPU1_SB_DQ<23>")
		)
		(pad "277" smd rect
			(at 2.050034 53.975 90)
			(size 0.519938 1.4986)
			(layers "F.Cu" "F.Mask" "F.Paste")
			(net "GND")
		)
		(pad "278" smd rect
			(at 2.050034 54.824884 90)
			(size 0.519938 1.4986)
			(layers "F.Cu" "F.Mask" "F.Paste")
			(net "M_K_CPU1_SB_DQ<26>")
		)
		(pad "279" smd rect
			(at 2.050034 55.675022 90)
			(size 0.519938 1.4986)
			(layers "F.Cu" "F.Mask" "F.Paste")
			(net "GND")
		)
		(pad "280" smd rect
			(at 2.050034 56.524906 90)
			(size 0.519938 1.4986)
			(layers "F.Cu" "F.Mask" "F.Paste")
			(net "M_K_CPU1_SB_DQ<27>")
		)
		(pad "281" smd rect
			(at 2.050034 57.375044 90)
			(size 0.519938 1.4986)
			(layers "F.Cu" "F.Mask" "F.Paste")
			(net "GND")
		)
		(pad "282" smd rect
			(at 2.050034 58.224928 90)
			(size 0.519938 1.4986)
			(layers "F.Cu" "F.Mask" "F.Paste")
			(net "M_K_CPU1_SB_DQS_DN<8>")
		)
		(pad "283" smd rect
			(at 2.050034 59.075066 90)
			(size 0.519938 1.4986)
			(layers "F.Cu" "F.Mask" "F.Paste")
			(net "M_K_CPU1_SB_DQS_DP<8>")
		)
		(pad "284" smd rect
			(at 2.050034 59.92495 90)
			(size 0.519938 1.4986)
			(layers "F.Cu" "F.Mask" "F.Paste")
			(net "GND")
		)
		(pad "285" smd rect
			(at 2.050034 60.775088 90)
			(size 0.519938 1.4986)
			(layers "F.Cu" "F.Mask" "F.Paste")
			(net "M_K_CPU1_SB_DQ<30>")
		)
		(pad "286" smd rect
			(at 2.050034 61.624972 90)
			(size 0.519938 1.4986)
			(layers "F.Cu" "F.Mask" "F.Paste")
			(net "GND")
		)
		(pad "287" smd rect
			(at 2.050034 62.47511 90)
			(size 0.519938 1.4986)
			(layers "F.Cu" "F.Mask" "F.Paste")
			(net "M_K_CPU1_SB_DQ<31>")
		)
		(pad "288" smd rect
			(at 2.050034 63.324994 90)
			(size 0.519938 1.4986)
			(layers "F.Cu" "F.Mask" "F.Paste")
			(net "GND")
		)
		(pad "G1" thru_hole oval
			(at 0 -68.97497 90)
			(size 1.7272 3.4798)
			(drill oval 1.2192 2.4638)
			(layers "*.Cu" "*.Mask")
			(remove_unused_layers no)
			(net "GND")
			(clearance 0.127)
			(thermal_gap 0.127)
		)
		(pad "G2" thru_hole oval
			(at 0 3.875024 90)
			(size 1.7272 3.4798)
			(drill oval 1.2192 2.4638)
			(layers "*.Cu" "*.Mask")
			(remove_unused_layers no)
			(net "GND")
			(clearance 0.127)
			(thermal_gap 0.127)
		)
		(pad "G3" thru_hole oval
			(at 0 68.97497 90)
			(size 1.7272 3.4798)
			(drill oval 1.2192 2.4638)
			(layers "*.Cu" "*.Mask")
			(remove_unused_layers no)
			(net "GND")
			(clearance 0.127)
			(thermal_gap 0.127)
		)
	)
	(footprint ""
		(layer "F.Cu")
		(at 14.257782 -416.050984 90)
		(property "Reference" "PR6541"
			(at 0 0 90)
			(layer "F.SilkS")
			(hide yes)
			(effects
				(font
					(size 1.27 1.27)
				)
			)
		)
		(property "Value" ""
			(at 0 0 90)
			(layer "F.Fab")
			(effects
				(font
					(size 1.27 1.27)
				)
			)
		)
		(duplicate_pad_numbers_are_jumpers no)
		(fp_line
			(start 0.7874 -0.4064)
			(end 0.7874 0.4064)
			(stroke
				(width 0.1524)
				(type default)
			)
			(layer "F.SilkS")
		)
		(fp_line
			(start -0.7874 -0.4064)
			(end 0.7874 -0.4064)
			(stroke
				(width 0.1524)
				(type default)
			)
			(layer "F.SilkS")
		)
		(fp_line
			(start 0.7874 0.4064)
			(end -0.7874 0.4064)
			(stroke
				(width 0.1524)
				(type default)
			)
			(layer "F.SilkS")
		)
		(fp_line
			(start -0.7874 0.4064)
			(end -0.7874 -0.4064)
			(stroke
				(width 0.1524)
				(type default)
			)
			(layer "F.SilkS")
		)
		(fp_line
			(start -0.12065 -0.305054)
			(end -0.12065 -0.2794)
			(stroke
				(width 0.1)
				(type default)
			)
			(layer "F.Fab")
		)
		(fp_line
			(start -0.67945 -0.305054)
			(end -0.12065 -0.305054)
			(stroke
				(width 0.1)
				(type default)
			)
			(layer "F.Fab")
		)
		(fp_line
			(start 0.67945 -0.3048)
			(end 0.67945 0.3048)
			(stroke
				(width 0.1)
				(type default)
			)
			(layer "F.Fab")
		)
		(fp_line
			(start 0.12065 -0.3048)
			(end 0.67945 -0.3048)
			(stroke
				(width 0.1)
				(type default)
			)
			(layer "F.Fab")
		)
		(fp_line
			(start 0.12065 -0.2794)
			(end 0.12065 -0.3048)
			(stroke
				(width 0.1)
				(type default)
			)
			(layer "F.Fab")
		)
		(fp_line
			(start -0.12065 -0.2794)
			(end 0.12065 -0.2794)
			(stroke
				(width 0.1)
				(type default)
			)
			(layer "F.Fab")
		)
		(fp_line
			(start 0.120396 0.2794)
			(end -0.12065 0.2794)
			(stroke
				(width 0.1)
				(type default)
			)
			(layer "F.Fab")
		)
		(fp_line
			(start -0.12065 0.2794)
			(end -0.12065 0.3048)
			(stroke
				(width 0.1)
				(type default)
			)
			(layer "F.Fab")
		)
		(fp_line
			(start 0.67945 0.3048)
			(end 0.120396 0.3048)
			(stroke
				(width 0.1)
				(type default)
			)
			(layer "F.Fab")
		)
		(fp_line
			(start 0.120396 0.3048)
			(end 0.120396 0.2794)
			(stroke
				(width 0.1)
				(type default)
			)
			(layer "F.Fab")
		)
		(fp_line
			(start -0.12065 0.3048)
			(end -0.67945 0.3048)
			(stroke
				(width 0.1)
				(type default)
			)
			(layer "F.Fab")
		)
		(fp_line
			(start -0.67945 0.3048)
			(end -0.67945 -0.305054)
			(stroke
				(width 0.1)
				(type default)
			)
			(layer "F.Fab")
		)
		(pad "1" smd circle
			(at -0.40005 0 90)
			(size 0 0)
			(layers "F.Cu" "F.Mask" "F.Paste")
			(net "NC_P0V9_RETIMER_CPU1_IMON5")
		)
		(pad "2" smd circle
			(at 0.40005 0 90)
			(size 0 0)
			(layers "F.Cu" "F.Mask" "F.Paste")
			(net "GND")
		)
	)
	(footprint ""
		(layer "F.Cu")
		(at 16.039592 -139.25804 -90)
		(property "Reference" "R4076"
			(at 0 0 270)
			(layer "F.SilkS")
			(hide yes)
			(effects
				(font
					(size 1.27 1.27)
				)
			)
		)
		(property "Value" ""
			(at 0 0 270)
			(layer "F.Fab")
			(effects
				(font
					(size 1.27 1.27)
				)
			)
		)
		(duplicate_pad_numbers_are_jumpers no)
		(fp_line
			(start -0.7874 0.4064)
			(end -0.7874 -0.4064)
			(stroke
				(width 0.1524)
				(type default)
			)
			(layer "F.SilkS")
		)
		(fp_line
			(start 0.7874 0.4064)
			(end -0.7874 0.4064)
			(stroke
				(width 0.1524)
				(type default)
			)
			(layer "F.SilkS")
		)
		(fp_line
			(start -0.7874 -0.4064)
			(end 0.7874 -0.4064)
			(stroke
				(width 0.1524)
				(type default)
			)
			(layer "F.SilkS")
		)
		(fp_line
			(start 0.7874 -0.4064)
			(end 0.7874 0.4064)
			(stroke
				(width 0.1524)
				(type default)
			)
			(layer "F.SilkS")
		)
		(fp_line
			(start -0.67945 0.3048)
			(end -0.67945 -0.305054)
			(stroke
				(width 0.1)
				(type default)
			)
			(layer "F.Fab")
		)
		(fp_line
			(start -0.12065 0.3048)
			(end -0.67945 0.3048)
			(stroke
				(width 0.1)
				(type default)
			)
			(layer "F.Fab")
		)
		(fp_line
			(start 0.120396 0.3048)
			(end 0.120396 0.2794)
			(stroke
				(width 0.1)
				(type default)
			)
			(layer "F.Fab")
		)
		(fp_line
			(start 0.67945 0.3048)
			(end 0.120396 0.3048)
			(stroke
				(width 0.1)
				(type default)
			)
			(layer "F.Fab")
		)
		(fp_line
			(start -0.12065 0.2794)
			(end -0.12065 0.3048)
			(stroke
				(width 0.1)
				(type default)
			)
			(layer "F.Fab")
		)
		(fp_line
			(start 0.120396 0.2794)
			(end -0.12065 0.2794)
			(stroke
				(width 0.1)
				(type default)
			)
			(layer "F.Fab")
		)
		(fp_line
			(start -0.12065 -0.2794)
			(end 0.12065 -0.2794)
			(stroke
				(width 0.1)
				(type default)
			)
			(layer "F.Fab")
		)
		(fp_line
			(start 0.12065 -0.2794)
			(end 0.12065 -0.3048)
			(stroke
				(width 0.1)
				(type default)
			)
			(layer "F.Fab")
		)
		(fp_line
			(start 0.12065 -0.3048)
			(end 0.67945 -0.3048)
			(stroke
				(width 0.1)
				(type default)
			)
			(layer "F.Fab")
		)
		(fp_line
			(start 0.67945 -0.3048)
			(end 0.67945 0.3048)
			(stroke
				(width 0.1)
				(type default)
			)
			(layer "F.Fab")
		)
		(fp_line
			(start -0.67945 -0.305054)
			(end -0.12065 -0.305054)
			(stroke
				(width 0.1)
				(type default)
			)
			(layer "F.Fab")
		)
		(fp_line
			(start -0.12065 -0.305054)
			(end -0.12065 -0.2794)
			(stroke
				(width 0.1)
				(type default)
			)
			(layer "F.Fab")
		)
		(pad "1" smd circle
			(at -0.40005 0 270)
			(size 0 0)
			(layers "F.Cu" "F.Mask" "F.Paste")
			(net "CLK_GEN2_GPU_FPGA_OE_OR_N")
		)
		(pad "2" smd circle
			(at 0.40005 0 270)
			(size 0 0)
			(layers "F.Cu" "F.Mask" "F.Paste")
			(net "CLK_GEN2_GPU_OE_N")
		)
	)
	(footprint ""
		(layer "F.Cu")
		(at 422.74617 -153.594562)
		(property "Reference" "PC1845"
			(at -1.86817 3.761232 0)
			(unlocked yes)
			(layer "F.SilkS")
			(effects
				(font
					(size 0.7874 0.5842)
					(thickness 0.1524)
				)
				(justify left)
			)
		)
		(property "Value" ""
			(at 0 0 0)
			(layer "F.Fab")
			(effects
				(font
					(size 1.27 1.27)
				)
			)
		)
		(duplicate_pad_numbers_are_jumpers no)
		(fp_line
			(start -2.750058 -1.988058)
			(end -2.750058 -0.9398)
			(stroke
				(width 0.1524)
				(type default)
			)
			(layer "F.SilkS")
		)
		(fp_line
			(start -2.750058 0.9398)
			(end -2.750058 1.988058)
			(stroke
				(width 0.1524)
				(type default)
			)
			(layer "F.SilkS")
		)
		(fp_line
			(start -2.750058 1.988058)
			(end -1.988058 2.750058)
			(stroke
				(width 0.1524)
				(type default)
			)
			(layer "F.SilkS")
		)
		(fp_line
			(start -1.988058 -2.750058)
			(end -2.750058 -1.988058)
			(stroke
				(width 0.1524)
				(type default)
			)
			(layer "F.SilkS")
		)
		(fp_line
			(start -1.988058 2.750058)
			(end 2.750058 2.750058)
			(stroke
				(width 0.1524)
				(type default)
			)
			(layer "F.SilkS")
		)
		(fp_line
			(start 2.750058 -2.750058)
			(end -1.988058 -2.750058)
			(stroke
				(width 0.1524)
				(type default)
			)
			(layer "F.SilkS")
		)
		(fp_line
			(start 2.750058 -0.9398)
			(end 2.750058 -2.750058)
			(stroke
				(width 0.1524)
				(type default)
			)
			(layer "F.SilkS")
		)
		(fp_line
			(start 2.750058 2.750058)
			(end 2.750058 0.9398)
			(stroke
				(width 0.1524)
				(type default)
			)
			(layer "F.SilkS")
		)
		(fp_line
			(start -2.750058 -2.750058)
			(end -2.750058 2.750058)
			(stroke
				(width 0.1)
				(type default)
			)
			(layer "F.Fab")
		)
		(fp_line
			(start -2.750058 2.750058)
			(end 2.750058 2.750058)
			(stroke
				(width 0.1)
				(type default)
			)
			(layer "F.Fab")
		)
		(fp_line
			(start 2.750058 -2.750058)
			(end -2.750058 -2.750058)
			(stroke
				(width 0.1)
				(type default)
			)
			(layer "F.Fab")
		)
		(fp_line
			(start 2.750058 2.750058)
			(end 2.750058 -2.750058)
			(stroke
				(width 0.1)
				(type default)
			)
			(layer "F.Fab")
		)
		(pad "1" smd rect
			(at -2.199894 0 90)
			(size 1.6002 3.0226)
			(layers "F.Cu" "F.Mask" "F.Paste")
			(net "P5V_AUX")
		)
		(pad "2" smd rect
			(at 2.199894 0 90)
			(size 1.6002 3.0226)
			(layers "F.Cu" "F.Mask" "F.Paste")
			(net "GND")
		)
	)
	(footprint ""
		(layer "F.Cu")
		(at 120.68175 -26.815796)
		(property "Reference" "R6265"
			(at 0 0 0)
			(layer "F.SilkS")
			(hide yes)
			(effects
				(font
					(size 1.27 1.27)
				)
			)
		)
		(property "Value" ""
			(at 0 0 0)
			(layer "F.Fab")
			(effects
				(font
					(size 1.27 1.27)
				)
			)
		)
		(duplicate_pad_numbers_are_jumpers no)
		(fp_line
			(start -0.7874 -0.4064)
			(end 0.7874 -0.4064)
			(stroke
				(width 0.1524)
				(type default)
			)
			(layer "F.SilkS")
		)
		(fp_line
			(start -0.7874 0.4064)
			(end -0.7874 -0.4064)
			(stroke
				(width 0.1524)
				(type default)
			)
			(layer "F.SilkS")
		)
		(fp_line
			(start 0.7874 -0.4064)
			(end 0.7874 0.4064)
			(stroke
				(width 0.1524)
				(type default)
			)
			(layer "F.SilkS")
		)
		(fp_line
			(start 0.7874 0.4064)
			(end -0.7874 0.4064)
			(stroke
				(width 0.1524)
				(type default)
			)
			(layer "F.SilkS")
		)
		(fp_line
			(start -0.67945 -0.305054)
			(end -0.12065 -0.305054)
			(stroke
				(width 0.1)
				(type default)
			)
			(layer "F.Fab")
		)
		(fp_line
			(start -0.67945 0.3048)
			(end -0.67945 -0.305054)
			(stroke
				(width 0.1)
				(type default)
			)
			(layer "F.Fab")
		)
		(fp_line
			(start -0.12065 -0.305054)
			(end -0.12065 -0.2794)
			(stroke
				(width 0.1)
				(type default)
			)
			(layer "F.Fab")
		)
		(fp_line
			(start -0.12065 -0.2794)
			(end 0.12065 -0.2794)
			(stroke
				(width 0.1)
				(type default)
			)
			(layer "F.Fab")
		)
		(fp_line
			(start -0.12065 0.2794)
			(end -0.12065 0.3048)
			(stroke
				(width 0.1)
				(type default)
			)
			(layer "F.Fab")
		)
		(fp_line
			(start -0.12065 0.3048)
			(end -0.67945 0.3048)
			(stroke
				(width 0.1)
				(type default)
			)
			(layer "F.Fab")
		)
		(fp_line
			(start 0.120396 0.2794)
			(end -0.12065 0.2794)
			(stroke
				(width 0.1)
				(type default)
			)
			(layer "F.Fab")
		)
		(fp_line
			(start 0.120396 0.3048)
			(end 0.120396 0.2794)
			(stroke
				(width 0.1)
				(type default)
			)
			(layer "F.Fab")
		)
		(fp_line
			(start 0.12065 -0.3048)
			(end 0.67945 -0.3048)
			(stroke
				(width 0.1)
				(type default)
			)
			(layer "F.Fab")
		)
		(fp_line
			(start 0.12065 -0.2794)
			(end 0.12065 -0.3048)
			(stroke
				(width 0.1)
				(type default)
			)
			(layer "F.Fab")
		)
		(fp_line
			(start 0.67945 -0.3048)
			(end 0.67945 0.3048)
			(stroke
				(width 0.1)
				(type default)
			)
			(layer "F.Fab")
		)
		(fp_line
			(start 0.67945 0.3048)
			(end 0.120396 0.3048)
			(stroke
				(width 0.1)
				(type default)
			)
			(layer "F.Fab")
		)
		(pad "1" smd circle
			(at -0.40005 0)
			(size 0 0)
			(layers "F.Cu" "F.Mask" "F.Paste")
			(net "USB_HUB2_TI_VDD_MRP_USB3DN_TXDP3")
		)
		(pad "2" smd circle
			(at 0.40005 0)
			(size 0 0)
			(layers "F.Cu" "F.Mask" "F.Paste")
			(net "P1V2_CPU0_USB2_DVDD12")
		)
	)
	(footprint ""
		(layer "F.Cu")
		(at 200.952608 -119.721376)
		(property "Reference" "R804"
			(at 0 0 0)
			(layer "F.SilkS")
			(hide yes)
			(effects
				(font
					(size 1.27 1.27)
				)
			)
		)
		(property "Value" ""
			(at 0 0 0)
			(layer "F.Fab")
			(effects
				(font
					(size 1.27 1.27)
				)
			)
		)
		(duplicate_pad_numbers_are_jumpers no)
		(fp_line
			(start -0.7874 -0.4064)
			(end 0.7874 -0.4064)
			(stroke
				(width 0.1524)
				(type default)
			)
			(layer "F.SilkS")
		)
		(fp_line
			(start -0.7874 0.4064)
			(end -0.7874 -0.4064)
			(stroke
				(width 0.1524)
				(type default)
			)
			(layer "F.SilkS")
		)
		(fp_line
			(start 0.7874 -0.4064)
			(end 0.7874 0.4064)
			(stroke
				(width 0.1524)
				(type default)
			)
			(layer "F.SilkS")
		)
		(fp_line
			(start 0.7874 0.4064)
			(end -0.7874 0.4064)
			(stroke
				(width 0.1524)
				(type default)
			)
			(layer "F.SilkS")
		)
		(fp_line
			(start -0.67945 -0.305054)
			(end -0.12065 -0.305054)
			(stroke
				(width 0.1)
				(type default)
			)
			(layer "F.Fab")
		)
		(fp_line
			(start -0.67945 0.3048)
			(end -0.67945 -0.305054)
			(stroke
				(width 0.1)
				(type default)
			)
			(layer "F.Fab")
		)
		(fp_line
			(start -0.12065 -0.305054)
			(end -0.12065 -0.2794)
			(stroke
				(width 0.1)
				(type default)
			)
			(layer "F.Fab")
		)
		(fp_line
			(start -0.12065 -0.2794)
			(end 0.12065 -0.2794)
			(stroke
				(width 0.1)
				(type default)
			)
			(layer "F.Fab")
		)
		(fp_line
			(start -0.12065 0.2794)
			(end -0.12065 0.3048)
			(stroke
				(width 0.1)
				(type default)
			)
			(layer "F.Fab")
		)
		(fp_line
			(start -0.12065 0.3048)
			(end -0.67945 0.3048)
			(stroke
				(width 0.1)
				(type default)
			)
			(layer "F.Fab")
		)
		(fp_line
			(start 0.120396 0.2794)
			(end -0.12065 0.2794)
			(stroke
				(width 0.1)
				(type default)
			)
			(layer "F.Fab")
		)
		(fp_line
			(start 0.120396 0.3048)
			(end 0.120396 0.2794)
			(stroke
				(width 0.1)
				(type default)
			)
			(layer "F.Fab")
		)
		(fp_line
			(start 0.12065 -0.3048)
			(end 0.67945 -0.3048)
			(stroke
				(width 0.1)
				(type default)
			)
			(layer "F.Fab")
		)
		(fp_line
			(start 0.12065 -0.2794)
			(end 0.12065 -0.3048)
			(stroke
				(width 0.1)
				(type default)
			)
			(layer "F.Fab")
		)
		(fp_line
			(start 0.67945 -0.3048)
			(end 0.67945 0.3048)
			(stroke
				(width 0.1)
				(type default)
			)
			(layer "F.Fab")
		)
		(fp_line
			(start 0.67945 0.3048)
			(end 0.120396 0.3048)
			(stroke
				(width 0.1)
				(type default)
			)
			(layer "F.Fab")
		)
		(pad "1" smd circle
			(at -0.40005 0)
			(size 0 0)
			(layers "F.Cu" "F.Mask" "F.Paste")
			(net "RST_PERST_M2_0_N")
		)
		(pad "2" smd circle
			(at 0.40005 0)
			(size 0 0)
			(layers "F.Cu" "F.Mask" "F.Paste")
			(net "GND")
		)
	)
	(footprint ""
		(layer "F.Cu")
		(at 149.606 -123.444 180)
		(property "Reference" "D8005"
			(at 3.213862 1.346962 0)
			(unlocked yes)
			(layer "F.SilkS")
			(effects
				(font
					(size 0.7874 0.5842)
					(thickness 0.1524)
				)
				(justify left)
			)
		)
		(property "Value" ""
			(at 0 0 180)
			(layer "F.Fab")
			(effects
				(font
					(size 1.27 1.27)
				)
			)
		)
		(duplicate_pad_numbers_are_jumpers no)
		(fp_line
			(start 2.343404 0.6985)
			(end 2.216404 0.6985)
			(stroke
				(width 0.1524)
				(type default)
			)
			(layer "F.SilkS")
		)
		(fp_line
			(start 2.343404 -0.6985)
			(end 2.343404 0.6985)
			(stroke
				(width 0.1524)
				(type default)
			)
			(layer "F.SilkS")
		)
		(fp_line
			(start 2.229104 0.6985)
			(end 2.051304 0.6985)
			(stroke
				(width 0.1524)
				(type default)
			)
			(layer "F.SilkS")
		)
		(fp_line
			(start 2.229104 -0.6985)
			(end 2.229104 0.6985)
			(stroke
				(width 0.1524)
				(type default)
			)
			(layer "F.SilkS")
		)
		(fp_line
			(start 2.152904 0.635)
			(end 2.152904 -0.6985)
			(stroke
				(width 0.1524)
				(type default)
			)
			(layer "F.SilkS")
		)
		(fp_line
			(start 2.152904 -0.6985)
			(end 2.343404 -0.6985)
			(stroke
				(width 0.1524)
				(type default)
			)
			(layer "F.SilkS")
		)
		(fp_line
			(start 2.064004 -0.6731)
			(end 2.064004 -0.6985)
			(stroke
				(width 0.1524)
				(type default)
			)
			(layer "F.SilkS")
		)
		(fp_line
			(start 2.064004 -0.6985)
			(end 2.229104 -0.6985)
			(stroke
				(width 0.1524)
				(type default)
			)
			(layer "F.SilkS")
		)
		(fp_line
			(start 2.051304 0.6985)
			(end 2.051304 0.635)
			(stroke
				(width 0.1524)
				(type default)
			)
			(layer "F.SilkS")
		)
		(fp_line
			(start 2.051304 0.635)
			(end 2.152904 0.635)
			(stroke
				(width 0.1524)
				(type default)
			)
			(layer "F.SilkS")
		)
		(fp_line
			(start 2.050796 0.700024)
			(end -2.050796 0.700024)
			(stroke
				(width 0.1524)
				(type default)
			)
			(layer "F.SilkS")
		)
		(fp_line
			(start 2.050796 -0.700024)
			(end 2.050796 0.700024)
			(stroke
				(width 0.1524)
				(type default)
			)
			(layer "F.SilkS")
		)
		(fp_line
			(start 0.293878 -0.500126)
			(end 0.293878 0.500126)
			(stroke
				(width 0.1524)
				(type default)
			)
			(layer "F.SilkS")
		)
		(fp_line
			(start 0.193802 0)
			(end -0.30607 -0.500126)
			(stroke
				(width 0.1524)
				(type default)
			)
			(layer "F.SilkS")
		)
		(fp_line
			(start -0.30607 0.500126)
			(end 0.193802 0)
			(stroke
				(width 0.1524)
				(type default)
			)
			(layer "F.SilkS")
		)
		(fp_line
			(start -0.30607 -0.500126)
			(end -0.30607 0.500126)
			(stroke
				(width 0.1524)
				(type default)
			)
			(layer "F.SilkS")
		)
		(fp_line
			(start -2.050796 0.700024)
			(end -2.050796 -0.700024)
			(stroke
				(width 0.1524)
				(type default)
			)
			(layer "F.SilkS")
		)
		(fp_line
			(start -2.050796 -0.700024)
			(end 2.050796 -0.700024)
			(stroke
				(width 0.1524)
				(type default)
			)
			(layer "F.SilkS")
		)
		(fp_line
			(start 0.899922 0.700024)
			(end -0.899922 0.700024)
			(stroke
				(width 0.1)
				(type default)
			)
			(layer "F.Fab")
		)
		(fp_line
			(start 0.899922 -0.700024)
			(end 0.899922 0.700024)
			(stroke
				(width 0.1)
				(type default)
			)
			(layer "F.Fab")
		)
		(fp_line
			(start -0.899922 0.700024)
			(end -0.899922 -0.700024)
			(stroke
				(width 0.1)
				(type default)
			)
			(layer "F.Fab")
		)
		(fp_line
			(start -0.899922 -0.700024)
			(end 0.899922 -0.700024)
			(stroke
				(width 0.1)
				(type default)
			)
			(layer "F.Fab")
		)
		(fp_text user "-"
			(at 3.880104 0.23495 0)
			(unlocked yes)
			(layer "F.SilkS")
			(effects
				(font
					(size 1.905 1.4224)
					(thickness 0.1524)
				)
				(justify left)
			)
		)
		(fp_text user "+"
			(at -3.362706 1.093978 270)
			(unlocked yes)
			(layer "F.SilkS")
			(effects
				(font
					(size 1.905 1.4224)
					(thickness 0.1524)
				)
				(justify left)
			)
		)
		(fp_text user "-"
			(at 3.880104 0.23495 0)
			(unlocked yes)
			(layer "F.Fab")
			(effects
				(font
					(size 1.905 1.4224)
					(thickness 0.1524)
				)
				(justify left)
			)
		)
		(fp_text user "+"
			(at -3.123946 0.762 270)
			(unlocked yes)
			(layer "F.Fab")
			(effects
				(font
					(size 1.905 1.4224)
					(thickness 0.1524)
				)
				(justify left)
			)
		)
		(pad "1" smd rect
			(at -1.199896 0 90)
			(size 0.6604 1.3716)
			(layers "F.Cu" "F.Mask" "F.Paste")
			(net "PWRGD_CHAF_CPU1_R1")
		)
		(pad "2" smd rect
			(at 1.199896 0 270)
			(size 0.6604 1.3716)
			(layers "F.Cu" "F.Mask" "F.Paste")
			(net "P3V3_AUX")
		)
	)
	(footprint ""
		(layer "F.Cu")
		(at 112.597946 -54.882034 -90)
		(property "Reference" "R6301"
			(at 0 0 270)
			(layer "F.SilkS")
			(hide yes)
			(effects
				(font
					(size 1.27 1.27)
				)
			)
		)
		(property "Value" ""
			(at 0 0 270)
			(layer "F.Fab")
			(effects
				(font
					(size 1.27 1.27)
				)
			)
		)
		(duplicate_pad_numbers_are_jumpers no)
		(fp_line
			(start -0.7874 0.4064)
			(end -0.7874 -0.4064)
			(stroke
				(width 0.1524)
				(type default)
			)
			(layer "F.SilkS")
		)
		(fp_line
			(start 0.7874 0.4064)
			(end -0.7874 0.4064)
			(stroke
				(width 0.1524)
				(type default)
			)
			(layer "F.SilkS")
		)
		(fp_line
			(start -0.7874 -0.4064)
			(end 0.7874 -0.4064)
			(stroke
				(width 0.1524)
				(type default)
			)
			(layer "F.SilkS")
		)
		(fp_line
			(start 0.7874 -0.4064)
			(end 0.7874 0.4064)
			(stroke
				(width 0.1524)
				(type default)
			)
			(layer "F.SilkS")
		)
		(fp_line
			(start -0.67945 0.3048)
			(end -0.67945 -0.305054)
			(stroke
				(width 0.1)
				(type default)
			)
			(layer "F.Fab")
		)
		(fp_line
			(start -0.12065 0.3048)
			(end -0.67945 0.3048)
			(stroke
				(width 0.1)
				(type default)
			)
			(layer "F.Fab")
		)
		(fp_line
			(start 0.120396 0.3048)
			(end 0.120396 0.2794)
			(stroke
				(width 0.1)
				(type default)
			)
			(layer "F.Fab")
		)
		(fp_line
			(start 0.67945 0.3048)
			(end 0.120396 0.3048)
			(stroke
				(width 0.1)
				(type default)
			)
			(layer "F.Fab")
		)
		(fp_line
			(start -0.12065 0.2794)
			(end -0.12065 0.3048)
			(stroke
				(width 0.1)
				(type default)
			)
			(layer "F.Fab")
		)
		(fp_line
			(start 0.120396 0.2794)
			(end -0.12065 0.2794)
			(stroke
				(width 0.1)
				(type default)
			)
			(layer "F.Fab")
		)
		(fp_line
			(start -0.12065 -0.2794)
			(end 0.12065 -0.2794)
			(stroke
				(width 0.1)
				(type default)
			)
			(layer "F.Fab")
		)
		(fp_line
			(start 0.12065 -0.2794)
			(end 0.12065 -0.3048)
			(stroke
				(width 0.1)
				(type default)
			)
			(layer "F.Fab")
		)
		(fp_line
			(start 0.12065 -0.3048)
			(end 0.67945 -0.3048)
			(stroke
				(width 0.1)
				(type default)
			)
			(layer "F.Fab")
		)
		(fp_line
			(start 0.67945 -0.3048)
			(end 0.67945 0.3048)
			(stroke
				(width 0.1)
				(type default)
			)
			(layer "F.Fab")
		)
		(fp_line
			(start -0.67945 -0.305054)
			(end -0.12065 -0.305054)
			(stroke
				(width 0.1)
				(type default)
			)
			(layer "F.Fab")
		)
		(fp_line
			(start -0.12065 -0.305054)
			(end -0.12065 -0.2794)
			(stroke
				(width 0.1)
				(type default)
			)
			(layer "F.Fab")
		)
		(pad "1" smd circle
			(at -0.40005 0 270)
			(size 0 0)
			(layers "F.Cu" "F.Mask" "F.Paste")
			(net "P3V3_AUX")
		)
		(pad "2" smd circle
			(at 0.40005 0 270)
			(size 0 0)
			(layers "F.Cu" "F.Mask" "F.Paste")
			(net "USB_HUB2_TI_OVERCUR3")
		)
	)
	(footprint ""
		(layer "F.Cu")
		(at 198.489824 -96.422718 90)
		(property "Reference" "R1129"
			(at 0 0 90)
			(layer "F.SilkS")
			(hide yes)
			(effects
				(font
					(size 1.27 1.27)
				)
			)
		)
		(property "Value" ""
			(at 0 0 90)
			(layer "F.Fab")
			(effects
				(font
					(size 1.27 1.27)
				)
			)
		)
		(duplicate_pad_numbers_are_jumpers no)
		(fp_line
			(start 0.7874 -0.4064)
			(end 0.7874 0.4064)
			(stroke
				(width 0.1524)
				(type default)
			)
			(layer "F.SilkS")
		)
		(fp_line
			(start -0.7874 -0.4064)
			(end 0.7874 -0.4064)
			(stroke
				(width 0.1524)
				(type default)
			)
			(layer "F.SilkS")
		)
		(fp_line
			(start 0.7874 0.4064)
			(end -0.7874 0.4064)
			(stroke
				(width 0.1524)
				(type default)
			)
			(layer "F.SilkS")
		)
		(fp_line
			(start -0.7874 0.4064)
			(end -0.7874 -0.4064)
			(stroke
				(width 0.1524)
				(type default)
			)
			(layer "F.SilkS")
		)
		(fp_line
			(start -0.12065 -0.305054)
			(end -0.12065 -0.2794)
			(stroke
				(width 0.1)
				(type default)
			)
			(layer "F.Fab")
		)
		(fp_line
			(start -0.67945 -0.305054)
			(end -0.12065 -0.305054)
			(stroke
				(width 0.1)
				(type default)
			)
			(layer "F.Fab")
		)
		(fp_line
			(start 0.67945 -0.3048)
			(end 0.67945 0.3048)
			(stroke
				(width 0.1)
				(type default)
			)
			(layer "F.Fab")
		)
		(fp_line
			(start 0.12065 -0.3048)
			(end 0.67945 -0.3048)
			(stroke
				(width 0.1)
				(type default)
			)
			(layer "F.Fab")
		)
		(fp_line
			(start 0.12065 -0.2794)
			(end 0.12065 -0.3048)
			(stroke
				(width 0.1)
				(type default)
			)
			(layer "F.Fab")
		)
		(fp_line
			(start -0.12065 -0.2794)
			(end 0.12065 -0.2794)
			(stroke
				(width 0.1)
				(type default)
			)
			(layer "F.Fab")
		)
		(fp_line
			(start 0.120396 0.2794)
			(end -0.12065 0.2794)
			(stroke
				(width 0.1)
				(type default)
			)
			(layer "F.Fab")
		)
		(fp_line
			(start -0.12065 0.2794)
			(end -0.12065 0.3048)
			(stroke
				(width 0.1)
				(type default)
			)
			(layer "F.Fab")
		)
		(fp_line
			(start 0.67945 0.3048)
			(end 0.120396 0.3048)
			(stroke
				(width 0.1)
				(type default)
			)
			(layer "F.Fab")
		)
		(fp_line
			(start 0.120396 0.3048)
			(end 0.120396 0.2794)
			(stroke
				(width 0.1)
				(type default)
			)
			(layer "F.Fab")
		)
		(fp_line
			(start -0.12065 0.3048)
			(end -0.67945 0.3048)
			(stroke
				(width 0.1)
				(type default)
			)
			(layer "F.Fab")
		)
		(fp_line
			(start -0.67945 0.3048)
			(end -0.67945 -0.305054)
			(stroke
				(width 0.1)
				(type default)
			)
			(layer "F.Fab")
		)
		(pad "1" smd circle
			(at -0.40005 0 90)
			(size 0 0)
			(layers "F.Cu" "F.Mask" "F.Paste")
			(net "HP_LVC3_OCP_V3_1_P12V_PWRGD")
		)
		(pad "2" smd circle
			(at 0.40005 0 90)
			(size 0 0)
			(layers "F.Cu" "F.Mask" "F.Paste")
			(net "HP_LVC3_OCP_V3_1_P12V_R_PWRGD")
		)
	)
	(footprint ""
		(layer "F.Cu")
		(at 355.915722 -178.813206 180)
		(property "Reference" "PL61"
			(at 3.57124 8.140954 0)
			(unlocked yes)
			(layer "F.SilkS")
			(effects
				(font
					(size 0.7874 0.5842)
					(thickness 0.1524)
				)
				(justify left)
			)
		)
		(property "Value" ""
			(at 0 0 180)
			(layer "F.Fab")
			(effects
				(font
					(size 1.27 1.27)
				)
			)
		)
		(duplicate_pad_numbers_are_jumpers no)
		(fp_line
			(start 3.750056 5.500116)
			(end 3.750056 -5.500116)
			(stroke
				(width 0.1524)
				(type default)
			)
			(layer "F.SilkS")
		)
		(fp_line
			(start 3.750056 -5.500116)
			(end 2.393442 -5.500116)
			(stroke
				(width 0.1524)
				(type default)
			)
			(layer "F.SilkS")
		)
		(fp_line
			(start 2.393442 5.500116)
			(end 3.750056 5.500116)
			(stroke
				(width 0.1524)
				(type default)
			)
			(layer "F.SilkS")
		)
		(fp_line
			(start -2.393442 5.500116)
			(end -3.750056 5.500116)
			(stroke
				(width 0.1524)
				(type default)
			)
			(layer "F.SilkS")
		)
		(fp_line
			(start -3.750056 5.500116)
			(end -3.750056 -5.500116)
			(stroke
				(width 0.1524)
				(type default)
			)
			(layer "F.SilkS")
		)
		(fp_line
			(start -3.750056 -5.500116)
			(end -2.393442 -5.500116)
			(stroke
				(width 0.1524)
				(type default)
			)
			(layer "F.SilkS")
		)
		(fp_poly
			(pts
				(xy -4.149598 -5.301742) (xy -5.165598 -4.793742) (xy -5.165598 -5.809742)
			)
			(stroke
				(width 0)
				(type default)
			)
			(fill yes)
			(layer "F.SilkS")
		)
		(fp_line
			(start 3.750056 5.500116)
			(end 3.750056 -5.500116)
			(stroke
				(width 0.1)
				(type default)
			)
			(layer "F.Fab")
		)
		(fp_line
			(start 3.750056 -5.500116)
			(end -3.750056 -5.500116)
			(stroke
				(width 0.1)
				(type default)
			)
			(layer "F.Fab")
		)
		(fp_line
			(start -3.750056 5.500116)
			(end 3.750056 5.500116)
			(stroke
				(width 0.1)
				(type default)
			)
			(layer "F.Fab")
		)
		(fp_line
			(start -3.750056 -5.500116)
			(end -3.750056 5.500116)
			(stroke
				(width 0.1)
				(type default)
			)
			(layer "F.Fab")
		)
		(fp_poly
			(pts
				(xy -4.9276 -4.757928) (xy -4.9276 -3.741928) (xy -3.9116 -4.249928)
			)
			(stroke
				(width 0)
				(type default)
			)
			(fill yes)
			(layer "F.Fab")
		)
		(pad "1" smd rect
			(at 0 -4.249928 90)
			(size 2.413 4.5212)
			(layers "F.Cu" "F.Mask" "F.Paste")
			(net "SW_PVDDCR_CPU0_P0_SW5")
		)
		(pad "2" smd rect
			(at 0 -1.175004 90)
			(size 1.3716 4.5212)
			(layers "F.Cu" "F.Mask" "F.Paste")
			(net "IND_CPU0_P0_CPL6")
		)
		(pad "3" smd rect
			(at 0 1.175004 90)
			(size 1.3716 4.5212)
			(layers "F.Cu" "F.Mask" "F.Paste")
			(net "IND_CPU0_P0_CPL5")
		)
		(pad "4" smd rect
			(at 0 4.249928 90)
			(size 2.413 4.5212)
			(layers "F.Cu" "F.Mask" "F.Paste")
			(net "PVDDCR_CPU0_P0")
		)
	)
	(footprint ""
		(layer "F.Cu")
		(at 457.329794 -46.264576 -90)
		(property "Reference" "PR830"
			(at 0 0 270)
			(layer "F.SilkS")
			(hide yes)
			(effects
				(font
					(size 1.27 1.27)
				)
			)
		)
		(property "Value" ""
			(at 0 0 270)
			(layer "F.Fab")
			(effects
				(font
					(size 1.27 1.27)
				)
			)
		)
		(duplicate_pad_numbers_are_jumpers no)
		(fp_line
			(start -0.7874 0.4064)
			(end -0.7874 -0.4064)
			(stroke
				(width 0.1524)
				(type default)
			)
			(layer "F.SilkS")
		)
		(fp_line
			(start 0.7874 0.4064)
			(end -0.7874 0.4064)
			(stroke
				(width 0.1524)
				(type default)
			)
			(layer "F.SilkS")
		)
		(fp_line
			(start -0.7874 -0.4064)
			(end 0.7874 -0.4064)
			(stroke
				(width 0.1524)
				(type default)
			)
			(layer "F.SilkS")
		)
		(fp_line
			(start 0.7874 -0.4064)
			(end 0.7874 0.4064)
			(stroke
				(width 0.1524)
				(type default)
			)
			(layer "F.SilkS")
		)
		(fp_line
			(start -0.67945 0.3048)
			(end -0.67945 -0.305054)
			(stroke
				(width 0.1)
				(type default)
			)
			(layer "F.Fab")
		)
		(fp_line
			(start -0.12065 0.3048)
			(end -0.67945 0.3048)
			(stroke
				(width 0.1)
				(type default)
			)
			(layer "F.Fab")
		)
		(fp_line
			(start 0.120396 0.3048)
			(end 0.120396 0.2794)
			(stroke
				(width 0.1)
				(type default)
			)
			(layer "F.Fab")
		)
		(fp_line
			(start 0.67945 0.3048)
			(end 0.120396 0.3048)
			(stroke
				(width 0.1)
				(type default)
			)
			(layer "F.Fab")
		)
		(fp_line
			(start -0.12065 0.2794)
			(end -0.12065 0.3048)
			(stroke
				(width 0.1)
				(type default)
			)
			(layer "F.Fab")
		)
		(fp_line
			(start 0.120396 0.2794)
			(end -0.12065 0.2794)
			(stroke
				(width 0.1)
				(type default)
			)
			(layer "F.Fab")
		)
		(fp_line
			(start -0.12065 -0.2794)
			(end 0.12065 -0.2794)
			(stroke
				(width 0.1)
				(type default)
			)
			(layer "F.Fab")
		)
		(fp_line
			(start 0.12065 -0.2794)
			(end 0.12065 -0.3048)
			(stroke
				(width 0.1)
				(type default)
			)
			(layer "F.Fab")
		)
		(fp_line
			(start 0.12065 -0.3048)
			(end 0.67945 -0.3048)
			(stroke
				(width 0.1)
				(type default)
			)
			(layer "F.Fab")
		)
		(fp_line
			(start 0.67945 -0.3048)
			(end 0.67945 0.3048)
			(stroke
				(width 0.1)
				(type default)
			)
			(layer "F.Fab")
		)
		(fp_line
			(start -0.67945 -0.305054)
			(end -0.12065 -0.305054)
			(stroke
				(width 0.1)
				(type default)
			)
			(layer "F.Fab")
		)
		(fp_line
			(start -0.12065 -0.305054)
			(end -0.12065 -0.2794)
			(stroke
				(width 0.1)
				(type default)
			)
			(layer "F.Fab")
		)
		(pad "1" smd circle
			(at -0.40005 0 270)
			(size 0 0)
			(layers "F.Cu" "F.Mask" "F.Paste")
			(net "P3V3_AUX_FB")
		)
		(pad "2" smd circle
			(at 0.40005 0 270)
			(size 0 0)
			(layers "F.Cu" "F.Mask" "F.Paste")
			(net "GND")
		)
	)
	(footprint ""
		(layer "F.Cu")
		(at 331.793342 -393.96416)
		(property "Reference" "R1028"
			(at 0 0 0)
			(layer "F.SilkS")
			(hide yes)
			(effects
				(font
					(size 1.27 1.27)
				)
			)
		)
		(property "Value" ""
			(at 0 0 0)
			(layer "F.Fab")
			(effects
				(font
					(size 1.27 1.27)
				)
			)
		)
		(duplicate_pad_numbers_are_jumpers no)
		(fp_line
			(start -0.32512 -0.175006)
			(end 0.32512 -0.175006)
			(stroke
				(width 0.1)
				(type default)
			)
			(layer "F.Fab")
		)
		(fp_line
			(start -0.32512 0.175006)
			(end -0.32512 -0.175006)
			(stroke
				(width 0.1)
				(type default)
			)
			(layer "F.Fab")
		)
		(fp_line
			(start 0.32512 -0.175006)
			(end 0.32512 0.175006)
			(stroke
				(width 0.1)
				(type default)
			)
			(layer "F.Fab")
		)
		(fp_line
			(start 0.32512 0.175006)
			(end -0.32512 0.175006)
			(stroke
				(width 0.1)
				(type default)
			)
			(layer "F.Fab")
		)
		(pad "1" smd rect
			(at -0.2667 0)
			(size 0.3048 0.381)
			(layers "F.Cu" "F.Mask" "F.Paste")
			(net "GPIO2_RT_CPU0_P1")
		)
		(pad "2" smd rect
			(at 0.2667 0 180)
			(size 0.3048 0.381)
			(layers "F.Cu" "F.Mask" "F.Paste")
			(net "GND")
		)
	)
	(footprint ""
		(layer "F.Cu")
		(at 173.9392 -94.833948 -90)
		(property "Reference" "R6009"
			(at 0 0 270)
			(layer "F.SilkS")
			(hide yes)
			(effects
				(font
					(size 1.27 1.27)
				)
			)
		)
		(property "Value" ""
			(at 0 0 270)
			(layer "F.Fab")
			(effects
				(font
					(size 1.27 1.27)
				)
			)
		)
		(duplicate_pad_numbers_are_jumpers no)
		(fp_line
			(start -0.7874 0.4064)
			(end -0.7874 -0.4064)
			(stroke
				(width 0.1524)
				(type default)
			)
			(layer "F.SilkS")
		)
		(fp_line
			(start 0.7874 0.4064)
			(end -0.7874 0.4064)
			(stroke
				(width 0.1524)
				(type default)
			)
			(layer "F.SilkS")
		)
		(fp_line
			(start -0.7874 -0.4064)
			(end 0.7874 -0.4064)
			(stroke
				(width 0.1524)
				(type default)
			)
			(layer "F.SilkS")
		)
		(fp_line
			(start 0.7874 -0.4064)
			(end 0.7874 0.4064)
			(stroke
				(width 0.1524)
				(type default)
			)
			(layer "F.SilkS")
		)
		(fp_line
			(start -0.67945 0.3048)
			(end -0.67945 -0.305054)
			(stroke
				(width 0.1)
				(type default)
			)
			(layer "F.Fab")
		)
		(fp_line
			(start -0.12065 0.3048)
			(end -0.67945 0.3048)
			(stroke
				(width 0.1)
				(type default)
			)
			(layer "F.Fab")
		)
		(fp_line
			(start 0.120396 0.3048)
			(end 0.120396 0.2794)
			(stroke
				(width 0.1)
				(type default)
			)
			(layer "F.Fab")
		)
		(fp_line
			(start 0.67945 0.3048)
			(end 0.120396 0.3048)
			(stroke
				(width 0.1)
				(type default)
			)
			(layer "F.Fab")
		)
		(fp_line
			(start -0.12065 0.2794)
			(end -0.12065 0.3048)
			(stroke
				(width 0.1)
				(type default)
			)
			(layer "F.Fab")
		)
		(fp_line
			(start 0.120396 0.2794)
			(end -0.12065 0.2794)
			(stroke
				(width 0.1)
				(type default)
			)
			(layer "F.Fab")
		)
		(fp_line
			(start -0.12065 -0.2794)
			(end 0.12065 -0.2794)
			(stroke
				(width 0.1)
				(type default)
			)
			(layer "F.Fab")
		)
		(fp_line
			(start 0.12065 -0.2794)
			(end 0.12065 -0.3048)
			(stroke
				(width 0.1)
				(type default)
			)
			(layer "F.Fab")
		)
		(fp_line
			(start 0.12065 -0.3048)
			(end 0.67945 -0.3048)
			(stroke
				(width 0.1)
				(type default)
			)
			(layer "F.Fab")
		)
		(fp_line
			(start 0.67945 -0.3048)
			(end 0.67945 0.3048)
			(stroke
				(width 0.1)
				(type default)
			)
			(layer "F.Fab")
		)
		(fp_line
			(start -0.67945 -0.305054)
			(end -0.12065 -0.305054)
			(stroke
				(width 0.1)
				(type default)
			)
			(layer "F.Fab")
		)
		(fp_line
			(start -0.12065 -0.305054)
			(end -0.12065 -0.2794)
			(stroke
				(width 0.1)
				(type default)
			)
			(layer "F.Fab")
		)
		(pad "1" smd circle
			(at -0.40005 0 270)
			(size 0 0)
			(layers "F.Cu" "F.Mask" "F.Paste")
			(net "SGPIO_SCM_CLK_<0>")
		)
		(pad "2" smd circle
			(at 0.40005 0 270)
			(size 0 0)
			(layers "F.Cu" "F.Mask" "F.Paste")
			(net "SGPIO_SCM_CLK_R_<0>")
		)
	)
	(footprint ""
		(layer "F.Cu")
		(at 104.409748 -385.5212 90)
		(property "Reference" "R735"
			(at 0 0 90)
			(layer "F.SilkS")
			(hide yes)
			(effects
				(font
					(size 1.27 1.27)
				)
			)
		)
		(property "Value" ""
			(at 0 0 90)
			(layer "F.Fab")
			(effects
				(font
					(size 1.27 1.27)
				)
			)
		)
		(duplicate_pad_numbers_are_jumpers no)
		(fp_line
			(start 0.32512 -0.175006)
			(end 0.32512 0.175006)
			(stroke
				(width 0.1)
				(type default)
			)
			(layer "F.Fab")
		)
		(fp_line
			(start -0.32512 -0.175006)
			(end 0.32512 -0.175006)
			(stroke
				(width 0.1)
				(type default)
			)
			(layer "F.Fab")
		)
		(fp_line
			(start 0.32512 0.175006)
			(end -0.32512 0.175006)
			(stroke
				(width 0.1)
				(type default)
			)
			(layer "F.Fab")
		)
		(fp_line
			(start -0.32512 0.175006)
			(end -0.32512 -0.175006)
			(stroke
				(width 0.1)
				(type default)
			)
			(layer "F.Fab")
		)
		(pad "1" smd rect
			(at -0.2667 0 90)
			(size 0.3048 0.381)
			(layers "F.Cu" "F.Mask" "F.Paste")
			(net "P1V8_CPU1_RT_1D")
		)
		(pad "2" smd rect
			(at 0.2667 0 270)
			(size 0.3048 0.381)
			(layers "F.Cu" "F.Mask" "F.Paste")
			(net "RT_CPU1_P1_ADDR3")
		)
	)
	(footprint ""
		(layer "F.Cu")
		(at 291.652706 -140.770864 180)
		(property "Reference" ""
			(at 0 0 180)
			(layer "F.SilkS")
			(hide yes)
			(effects
				(font
					(size 1.27 1.27)
				)
			)
		)
		(property "Value" ""
			(at 0 0 180)
			(layer "F.Fab")
			(effects
				(font
					(size 1.27 1.27)
				)
			)
		)
		(duplicate_pad_numbers_are_jumpers no)
		(pad "1" smd circle
			(at 0 0 180)
			(size 0.9906 0.9906)
			(layers "F.Cu" "F.Mask" "F.Paste")
			(net "Net_2237")
		)
		(zone
			(layer "F.Cu")
			(hatch none 0.5)
			(connect_pads
				(clearance 0)
			)
			(min_thickness 0.25)
			(keepout
				(tracks not_allowed)
				(vias allowed)
				(pads allowed)
				(copperpour not_allowed)
				(footprints allowed)
			)
			(placement
				(enabled no)
				(sheetname "")
			)
			(fill
				(thermal_gap 0.5)
				(thermal_bridge_width 0.5)
				(island_removal_mode 0)
			)
			(polygon
				(pts
					(arc
						(start 293.278306 -140.770864)
						(mid 290.027106 -140.770864)
						(end 293.278306 -140.770864)
					)
				)
			)
		)
	)
	(footprint ""
		(layer "F.Cu")
		(at 143.385286 -321.694556 -90)
		(property "Reference" "R570"
			(at 0 0 270)
			(layer "F.SilkS")
			(hide yes)
			(effects
				(font
					(size 1.27 1.27)
				)
			)
		)
		(property "Value" ""
			(at 0 0 270)
			(layer "F.Fab")
			(effects
				(font
					(size 1.27 1.27)
				)
			)
		)
		(duplicate_pad_numbers_are_jumpers no)
		(fp_line
			(start -0.7874 0.4064)
			(end -0.7874 -0.4064)
			(stroke
				(width 0.1524)
				(type default)
			)
			(layer "F.SilkS")
		)
		(fp_line
			(start 0.7874 0.4064)
			(end -0.7874 0.4064)
			(stroke
				(width 0.1524)
				(type default)
			)
			(layer "F.SilkS")
		)
		(fp_line
			(start -0.7874 -0.4064)
			(end 0.7874 -0.4064)
			(stroke
				(width 0.1524)
				(type default)
			)
			(layer "F.SilkS")
		)
		(fp_line
			(start 0.7874 -0.4064)
			(end 0.7874 0.4064)
			(stroke
				(width 0.1524)
				(type default)
			)
			(layer "F.SilkS")
		)
		(fp_line
			(start -0.67945 0.3048)
			(end -0.67945 -0.305054)
			(stroke
				(width 0.1)
				(type default)
			)
			(layer "F.Fab")
		)
		(fp_line
			(start -0.12065 0.3048)
			(end -0.67945 0.3048)
			(stroke
				(width 0.1)
				(type default)
			)
			(layer "F.Fab")
		)
		(fp_line
			(start 0.120396 0.3048)
			(end 0.120396 0.2794)
			(stroke
				(width 0.1)
				(type default)
			)
			(layer "F.Fab")
		)
		(fp_line
			(start 0.67945 0.3048)
			(end 0.120396 0.3048)
			(stroke
				(width 0.1)
				(type default)
			)
			(layer "F.Fab")
		)
		(fp_line
			(start -0.12065 0.2794)
			(end -0.12065 0.3048)
			(stroke
				(width 0.1)
				(type default)
			)
			(layer "F.Fab")
		)
		(fp_line
			(start 0.120396 0.2794)
			(end -0.12065 0.2794)
			(stroke
				(width 0.1)
				(type default)
			)
			(layer "F.Fab")
		)
		(fp_line
			(start -0.12065 -0.2794)
			(end 0.12065 -0.2794)
			(stroke
				(width 0.1)
				(type default)
			)
			(layer "F.Fab")
		)
		(fp_line
			(start 0.12065 -0.2794)
			(end 0.12065 -0.3048)
			(stroke
				(width 0.1)
				(type default)
			)
			(layer "F.Fab")
		)
		(fp_line
			(start 0.12065 -0.3048)
			(end 0.67945 -0.3048)
			(stroke
				(width 0.1)
				(type default)
			)
			(layer "F.Fab")
		)
		(fp_line
			(start 0.67945 -0.3048)
			(end 0.67945 0.3048)
			(stroke
				(width 0.1)
				(type default)
			)
			(layer "F.Fab")
		)
		(fp_line
			(start -0.67945 -0.305054)
			(end -0.12065 -0.305054)
			(stroke
				(width 0.1)
				(type default)
			)
			(layer "F.Fab")
		)
		(fp_line
			(start -0.12065 -0.305054)
			(end -0.12065 -0.2794)
			(stroke
				(width 0.1)
				(type default)
			)
			(layer "F.Fab")
		)
		(pad "1" smd circle
			(at -0.40005 0 270)
			(size 0 0)
			(layers "F.Cu" "F.Mask" "F.Paste")
			(net "CPU1_SPD_HOST_CTRL_N")
		)
		(pad "2" smd circle
			(at 0.40005 0 270)
			(size 0 0)
			(layers "F.Cu" "F.Mask" "F.Paste")
			(net "CPU1_SPD_HOST_CTRL_R_N")
		)
	)
	(footprint ""
		(layer "F.Cu")
		(at 229.5652 -152.954228 180)
		(property "Reference" "R6105"
			(at 0 0 180)
			(layer "F.SilkS")
			(hide yes)
			(effects
				(font
					(size 1.27 1.27)
				)
			)
		)
		(property "Value" ""
			(at 0 0 180)
			(layer "F.Fab")
			(effects
				(font
					(size 1.27 1.27)
				)
			)
		)
		(duplicate_pad_numbers_are_jumpers no)
		(fp_line
			(start 0.7874 0.4064)
			(end -0.7874 0.4064)
			(stroke
				(width 0.1524)
				(type default)
			)
			(layer "F.SilkS")
		)
		(fp_line
			(start 0.7874 -0.4064)
			(end 0.7874 0.4064)
			(stroke
				(width 0.1524)
				(type default)
			)
			(layer "F.SilkS")
		)
		(fp_line
			(start -0.7874 0.4064)
			(end -0.7874 -0.4064)
			(stroke
				(width 0.1524)
				(type default)
			)
			(layer "F.SilkS")
		)
		(fp_line
			(start -0.7874 -0.4064)
			(end 0.7874 -0.4064)
			(stroke
				(width 0.1524)
				(type default)
			)
			(layer "F.SilkS")
		)
		(fp_line
			(start 0.67945 0.3048)
			(end 0.120396 0.3048)
			(stroke
				(width 0.1)
				(type default)
			)
			(layer "F.Fab")
		)
		(fp_line
			(start 0.67945 -0.3048)
			(end 0.67945 0.3048)
			(stroke
				(width 0.1)
				(type default)
			)
			(layer "F.Fab")
		)
		(fp_line
			(start 0.12065 -0.2794)
			(end 0.12065 -0.3048)
			(stroke
				(width 0.1)
				(type default)
			)
			(layer "F.Fab")
		)
		(fp_line
			(start 0.12065 -0.3048)
			(end 0.67945 -0.3048)
			(stroke
				(width 0.1)
				(type default)
			)
			(layer "F.Fab")
		)
		(fp_line
			(start 0.120396 0.3048)
			(end 0.120396 0.2794)
			(stroke
				(width 0.1)
				(type default)
			)
			(layer "F.Fab")
		)
		(fp_line
			(start 0.120396 0.2794)
			(end -0.12065 0.2794)
			(stroke
				(width 0.1)
				(type default)
			)
			(layer "F.Fab")
		)
		(fp_line
			(start -0.12065 0.3048)
			(end -0.67945 0.3048)
			(stroke
				(width 0.1)
				(type default)
			)
			(layer "F.Fab")
		)
		(fp_line
			(start -0.12065 0.2794)
			(end -0.12065 0.3048)
			(stroke
				(width 0.1)
				(type default)
			)
			(layer "F.Fab")
		)
		(fp_line
			(start -0.12065 -0.2794)
			(end 0.12065 -0.2794)
			(stroke
				(width 0.1)
				(type default)
			)
			(layer "F.Fab")
		)
		(fp_line
			(start -0.12065 -0.305054)
			(end -0.12065 -0.2794)
			(stroke
				(width 0.1)
				(type default)
			)
			(layer "F.Fab")
		)
		(fp_line
			(start -0.67945 0.3048)
			(end -0.67945 -0.305054)
			(stroke
				(width 0.1)
				(type default)
			)
			(layer "F.Fab")
		)
		(fp_line
			(start -0.67945 -0.305054)
			(end -0.12065 -0.305054)
			(stroke
				(width 0.1)
				(type default)
			)
			(layer "F.Fab")
		)
		(pad "1" smd circle
			(at -0.40005 0 180)
			(size 0 0)
			(layers "F.Cu" "F.Mask" "F.Paste")
			(net "JTAG_CPU0_TDO_CPU1_TDI_R1")
		)
		(pad "2" smd circle
			(at 0.40005 0 180)
			(size 0 0)
			(layers "F.Cu" "F.Mask" "F.Paste")
			(net "JTAG_CPU0_TDO_CPU1_TDI")
		)
	)
	(footprint ""
		(layer "F.Cu")
		(at 449.443602 -429.25111)
		(property "Reference" "PR6608"
			(at 0 0 0)
			(layer "F.SilkS")
			(hide yes)
			(effects
				(font
					(size 1.27 1.27)
				)
			)
		)
		(property "Value" ""
			(at 0 0 0)
			(layer "F.Fab")
			(effects
				(font
					(size 1.27 1.27)
				)
			)
		)
		(duplicate_pad_numbers_are_jumpers no)
		(fp_line
			(start -0.7874 -0.4064)
			(end 0.7874 -0.4064)
			(stroke
				(width 0.1524)
				(type default)
			)
			(layer "F.SilkS")
		)
		(fp_line
			(start -0.7874 0.4064)
			(end -0.7874 -0.4064)
			(stroke
				(width 0.1524)
				(type default)
			)
			(layer "F.SilkS")
		)
		(fp_line
			(start 0.7874 -0.4064)
			(end 0.7874 0.4064)
			(stroke
				(width 0.1524)
				(type default)
			)
			(layer "F.SilkS")
		)
		(fp_line
			(start 0.7874 0.4064)
			(end -0.7874 0.4064)
			(stroke
				(width 0.1524)
				(type default)
			)
			(layer "F.SilkS")
		)
		(fp_line
			(start -0.67945 -0.305054)
			(end -0.12065 -0.305054)
			(stroke
				(width 0.1)
				(type default)
			)
			(layer "F.Fab")
		)
		(fp_line
			(start -0.67945 0.3048)
			(end -0.67945 -0.305054)
			(stroke
				(width 0.1)
				(type default)
			)
			(layer "F.Fab")
		)
		(fp_line
			(start -0.12065 -0.305054)
			(end -0.12065 -0.2794)
			(stroke
				(width 0.1)
				(type default)
			)
			(layer "F.Fab")
		)
		(fp_line
			(start -0.12065 -0.2794)
			(end 0.12065 -0.2794)
			(stroke
				(width 0.1)
				(type default)
			)
			(layer "F.Fab")
		)
		(fp_line
			(start -0.12065 0.2794)
			(end -0.12065 0.3048)
			(stroke
				(width 0.1)
				(type default)
			)
			(layer "F.Fab")
		)
		(fp_line
			(start -0.12065 0.3048)
			(end -0.67945 0.3048)
			(stroke
				(width 0.1)
				(type default)
			)
			(layer "F.Fab")
		)
		(fp_line
			(start 0.120396 0.2794)
			(end -0.12065 0.2794)
			(stroke
				(width 0.1)
				(type default)
			)
			(layer "F.Fab")
		)
		(fp_line
			(start 0.120396 0.3048)
			(end 0.120396 0.2794)
			(stroke
				(width 0.1)
				(type default)
			)
			(layer "F.Fab")
		)
		(fp_line
			(start 0.12065 -0.3048)
			(end 0.67945 -0.3048)
			(stroke
				(width 0.1)
				(type default)
			)
			(layer "F.Fab")
		)
		(fp_line
			(start 0.12065 -0.2794)
			(end 0.12065 -0.3048)
			(stroke
				(width 0.1)
				(type default)
			)
			(layer "F.Fab")
		)
		(fp_line
			(start 0.67945 -0.3048)
			(end 0.67945 0.3048)
			(stroke
				(width 0.1)
				(type default)
			)
			(layer "F.Fab")
		)
		(fp_line
			(start 0.67945 0.3048)
			(end 0.120396 0.3048)
			(stroke
				(width 0.1)
				(type default)
			)
			(layer "F.Fab")
		)
		(pad "1" smd circle
			(at -0.40005 0)
			(size 0 0)
			(layers "F.Cu" "F.Mask" "F.Paste")
			(net "P0V9_RETIMER_CPU0_VCC")
		)
		(pad "2" smd circle
			(at 0.40005 0)
			(size 0 0)
			(layers "F.Cu" "F.Mask" "F.Paste")
			(net "P3V3_AUX")
		)
	)
	(footprint ""
		(layer "F.Cu")
		(at 302.133 -365.125 180)
		(property "Reference" "C5013"
			(at 0 0 180)
			(layer "F.SilkS")
			(hide yes)
			(effects
				(font
					(size 1.27 1.27)
				)
			)
		)
		(property "Value" ""
			(at 0 0 180)
			(layer "F.Fab")
			(effects
				(font
					(size 1.27 1.27)
				)
			)
		)
		(duplicate_pad_numbers_are_jumpers no)
		(fp_line
			(start 0.7874 0.4064)
			(end -0.7874 0.4064)
			(stroke
				(width 0.1524)
				(type default)
			)
			(layer "F.SilkS")
		)
		(fp_line
			(start 0.7874 -0.4064)
			(end 0.7874 0.4064)
			(stroke
				(width 0.1524)
				(type default)
			)
			(layer "F.SilkS")
		)
		(fp_line
			(start -0.7874 0.4064)
			(end -0.7874 -0.4064)
			(stroke
				(width 0.1524)
				(type default)
			)
			(layer "F.SilkS")
		)
		(fp_line
			(start -0.7874 -0.4064)
			(end 0.7874 -0.4064)
			(stroke
				(width 0.1524)
				(type default)
			)
			(layer "F.SilkS")
		)
		(fp_line
			(start 0.67945 0.3048)
			(end 0.120396 0.3048)
			(stroke
				(width 0.1)
				(type default)
			)
			(layer "F.Fab")
		)
		(fp_line
			(start 0.67945 -0.3048)
			(end 0.67945 0.3048)
			(stroke
				(width 0.1)
				(type default)
			)
			(layer "F.Fab")
		)
		(fp_line
			(start 0.12065 -0.2794)
			(end 0.12065 -0.3048)
			(stroke
				(width 0.1)
				(type default)
			)
			(layer "F.Fab")
		)
		(fp_line
			(start 0.12065 -0.3048)
			(end 0.67945 -0.3048)
			(stroke
				(width 0.1)
				(type default)
			)
			(layer "F.Fab")
		)
		(fp_line
			(start 0.120396 0.3048)
			(end 0.120396 0.2794)
			(stroke
				(width 0.1)
				(type default)
			)
			(layer "F.Fab")
		)
		(fp_line
			(start 0.120396 0.2794)
			(end -0.12065 0.2794)
			(stroke
				(width 0.1)
				(type default)
			)
			(layer "F.Fab")
		)
		(fp_line
			(start -0.12065 0.3048)
			(end -0.67945 0.3048)
			(stroke
				(width 0.1)
				(type default)
			)
			(layer "F.Fab")
		)
		(fp_line
			(start -0.12065 0.2794)
			(end -0.12065 0.3048)
			(stroke
				(width 0.1)
				(type default)
			)
			(layer "F.Fab")
		)
		(fp_line
			(start -0.12065 -0.2794)
			(end 0.12065 -0.2794)
			(stroke
				(width 0.1)
				(type default)
			)
			(layer "F.Fab")
		)
		(fp_line
			(start -0.12065 -0.305054)
			(end -0.12065 -0.2794)
			(stroke
				(width 0.1)
				(type default)
			)
			(layer "F.Fab")
		)
		(fp_line
			(start -0.67945 0.3048)
			(end -0.67945 -0.305054)
			(stroke
				(width 0.1)
				(type default)
			)
			(layer "F.Fab")
		)
		(fp_line
			(start -0.67945 -0.305054)
			(end -0.12065 -0.305054)
			(stroke
				(width 0.1)
				(type default)
			)
			(layer "F.Fab")
		)
		(pad "1" smd circle
			(at -0.40005 0 180)
			(size 0 0)
			(layers "F.Cu" "F.Mask" "F.Paste")
			(net "PVDDCR_CPU1_P0_SMB_ALERT")
		)
		(pad "2" smd circle
			(at 0.40005 0 180)
			(size 0 0)
			(layers "F.Cu" "F.Mask" "F.Paste")
			(net "GND")
		)
	)
	(footprint ""
		(layer "F.Cu")
		(at 166.116 -99.06)
		(property "Reference" "R1144"
			(at 0 0 0)
			(layer "F.SilkS")
			(hide yes)
			(effects
				(font
					(size 1.27 1.27)
				)
			)
		)
		(property "Value" ""
			(at 0 0 0)
			(layer "F.Fab")
			(effects
				(font
					(size 1.27 1.27)
				)
			)
		)
		(duplicate_pad_numbers_are_jumpers no)
		(fp_line
			(start -0.7874 -0.4064)
			(end 0.7874 -0.4064)
			(stroke
				(width 0.1524)
				(type default)
			)
			(layer "F.SilkS")
		)
		(fp_line
			(start -0.7874 0.4064)
			(end -0.7874 -0.4064)
			(stroke
				(width 0.1524)
				(type default)
			)
			(layer "F.SilkS")
		)
		(fp_line
			(start 0.7874 -0.4064)
			(end 0.7874 0.4064)
			(stroke
				(width 0.1524)
				(type default)
			)
			(layer "F.SilkS")
		)
		(fp_line
			(start 0.7874 0.4064)
			(end -0.7874 0.4064)
			(stroke
				(width 0.1524)
				(type default)
			)
			(layer "F.SilkS")
		)
		(fp_line
			(start -0.67945 -0.305054)
			(end -0.12065 -0.305054)
			(stroke
				(width 0.1)
				(type default)
			)
			(layer "F.Fab")
		)
		(fp_line
			(start -0.67945 0.3048)
			(end -0.67945 -0.305054)
			(stroke
				(width 0.1)
				(type default)
			)
			(layer "F.Fab")
		)
		(fp_line
			(start -0.12065 -0.305054)
			(end -0.12065 -0.2794)
			(stroke
				(width 0.1)
				(type default)
			)
			(layer "F.Fab")
		)
		(fp_line
			(start -0.12065 -0.2794)
			(end 0.12065 -0.2794)
			(stroke
				(width 0.1)
				(type default)
			)
			(layer "F.Fab")
		)
		(fp_line
			(start -0.12065 0.2794)
			(end -0.12065 0.3048)
			(stroke
				(width 0.1)
				(type default)
			)
			(layer "F.Fab")
		)
		(fp_line
			(start -0.12065 0.3048)
			(end -0.67945 0.3048)
			(stroke
				(width 0.1)
				(type default)
			)
			(layer "F.Fab")
		)
		(fp_line
			(start 0.120396 0.2794)
			(end -0.12065 0.2794)
			(stroke
				(width 0.1)
				(type default)
			)
			(layer "F.Fab")
		)
		(fp_line
			(start 0.120396 0.3048)
			(end 0.120396 0.2794)
			(stroke
				(width 0.1)
				(type default)
			)
			(layer "F.Fab")
		)
		(fp_line
			(start 0.12065 -0.3048)
			(end 0.67945 -0.3048)
			(stroke
				(width 0.1)
				(type default)
			)
			(layer "F.Fab")
		)
		(fp_line
			(start 0.12065 -0.2794)
			(end 0.12065 -0.3048)
			(stroke
				(width 0.1)
				(type default)
			)
			(layer "F.Fab")
		)
		(fp_line
			(start 0.67945 -0.3048)
			(end 0.67945 0.3048)
			(stroke
				(width 0.1)
				(type default)
			)
			(layer "F.Fab")
		)
		(fp_line
			(start 0.67945 0.3048)
			(end 0.120396 0.3048)
			(stroke
				(width 0.1)
				(type default)
			)
			(layer "F.Fab")
		)
		(pad "1" smd circle
			(at -0.40005 0)
			(size 0 0)
			(layers "F.Cu" "F.Mask" "F.Paste")
			(net "P3V3_AUX")
		)
		(pad "2" smd circle
			(at 0.40005 0)
			(size 0 0)
			(layers "F.Cu" "F.Mask" "F.Paste")
			(net "OCP_V3_1_P3V3_PLD_R_PWRGD")
		)
	)
	(footprint ""
		(layer "F.Cu")
		(at 103.998522 -31.788354 -90)
		(property "Reference" "R345"
			(at 0 0 270)
			(layer "F.SilkS")
			(hide yes)
			(effects
				(font
					(size 1.27 1.27)
				)
			)
		)
		(property "Value" ""
			(at 0 0 270)
			(layer "F.Fab")
			(effects
				(font
					(size 1.27 1.27)
				)
			)
		)
		(duplicate_pad_numbers_are_jumpers no)
		(fp_line
			(start -0.32512 0.175006)
			(end -0.32512 -0.175006)
			(stroke
				(width 0.1)
				(type default)
			)
			(layer "F.Fab")
		)
		(fp_line
			(start 0.32512 0.175006)
			(end -0.32512 0.175006)
			(stroke
				(width 0.1)
				(type default)
			)
			(layer "F.Fab")
		)
		(fp_line
			(start -0.32512 -0.175006)
			(end 0.32512 -0.175006)
			(stroke
				(width 0.1)
				(type default)
			)
			(layer "F.Fab")
		)
		(fp_line
			(start 0.32512 -0.175006)
			(end 0.32512 0.175006)
			(stroke
				(width 0.1)
				(type default)
			)
			(layer "F.Fab")
		)
		(pad "1" smd rect
			(at -0.2667 0 270)
			(size 0.3048 0.381)
			(layers "F.Cu" "F.Mask" "F.Paste")
			(net "USB2_CPU0_P0_R2_DN")
		)
		(pad "2" smd rect
			(at 0.2667 0 90)
			(size 0.3048 0.381)
			(layers "F.Cu" "F.Mask" "F.Paste")
			(net "GND")
		)
	)
	(footprint ""
		(layer "F.Cu")
		(at 164.927026 -58.06821 90)
		(property "Reference" "R3634"
			(at 4.77012 -1.859026 0)
			(unlocked yes)
			(layer "F.SilkS")
			(effects
				(font
					(size 0.7874 0.5842)
					(thickness 0.1524)
				)
				(justify left)
			)
		)
		(property "Value" ""
			(at 0 0 90)
			(layer "F.Fab")
			(effects
				(font
					(size 1.27 1.27)
				)
			)
		)
		(duplicate_pad_numbers_are_jumpers no)
		(fp_line
			(start 3.937508 -1.8796)
			(end -3.937508 -1.8796)
			(stroke
				(width 0.1524)
				(type default)
			)
			(layer "F.SilkS")
		)
		(fp_line
			(start -3.937508 -1.8796)
			(end -3.937508 1.8796)
			(stroke
				(width 0.1524)
				(type default)
			)
			(layer "F.SilkS")
		)
		(fp_line
			(start 3.937508 1.8796)
			(end 3.937508 -1.8796)
			(stroke
				(width 0.1524)
				(type default)
			)
			(layer "F.SilkS")
		)
		(fp_line
			(start -3.937508 1.8796)
			(end 3.937508 1.8796)
			(stroke
				(width 0.1524)
				(type default)
			)
			(layer "F.SilkS")
		)
		(fp_line
			(start 3.275076 -1.674876)
			(end -3.275076 -1.674876)
			(stroke
				(width 0.1)
				(type default)
			)
			(layer "F.Fab")
		)
		(fp_line
			(start -3.275076 -1.674876)
			(end -3.275076 1.674876)
			(stroke
				(width 0.1)
				(type default)
			)
			(layer "F.Fab")
		)
		(fp_line
			(start 3.275076 1.674876)
			(end 3.275076 -1.674876)
			(stroke
				(width 0.1)
				(type default)
			)
			(layer "F.Fab")
		)
		(fp_line
			(start -3.275076 1.674876)
			(end 3.275076 1.674876)
			(stroke
				(width 0.1)
				(type default)
			)
			(layer "F.Fab")
		)
		(pad "1" smd rect
			(at -2.350008 0 90)
			(size 2.921 3.5052)
			(layers "F.Cu" "F.Mask" "F.Paste")
			(net "P3V3_M2_0")
		)
		(pad "2" smd rect
			(at 2.350008 0 90)
			(size 2.921 3.5052)
			(layers "F.Cu" "F.Mask" "F.Paste")
			(net "P3V3")
		)
	)
	(footprint ""
		(layer "F.Cu")
		(at 68.147438 -32.776922 90)
		(property "Reference" "PR3847"
			(at 0 0 90)
			(layer "F.SilkS")
			(hide yes)
			(effects
				(font
					(size 1.27 1.27)
				)
			)
		)
		(property "Value" ""
			(at 0 0 90)
			(layer "F.Fab")
			(effects
				(font
					(size 1.27 1.27)
				)
			)
		)
		(duplicate_pad_numbers_are_jumpers no)
		(fp_line
			(start 0.7874 -0.4064)
			(end 0.7874 0.4064)
			(stroke
				(width 0.1524)
				(type default)
			)
			(layer "F.SilkS")
		)
		(fp_line
			(start -0.7874 -0.4064)
			(end 0.7874 -0.4064)
			(stroke
				(width 0.1524)
				(type default)
			)
			(layer "F.SilkS")
		)
		(fp_line
			(start 0.7874 0.4064)
			(end -0.7874 0.4064)
			(stroke
				(width 0.1524)
				(type default)
			)
			(layer "F.SilkS")
		)
		(fp_line
			(start -0.7874 0.4064)
			(end -0.7874 -0.4064)
			(stroke
				(width 0.1524)
				(type default)
			)
			(layer "F.SilkS")
		)
		(fp_line
			(start -0.12065 -0.305054)
			(end -0.12065 -0.2794)
			(stroke
				(width 0.1)
				(type default)
			)
			(layer "F.Fab")
		)
		(fp_line
			(start -0.67945 -0.305054)
			(end -0.12065 -0.305054)
			(stroke
				(width 0.1)
				(type default)
			)
			(layer "F.Fab")
		)
		(fp_line
			(start 0.67945 -0.3048)
			(end 0.67945 0.3048)
			(stroke
				(width 0.1)
				(type default)
			)
			(layer "F.Fab")
		)
		(fp_line
			(start 0.12065 -0.3048)
			(end 0.67945 -0.3048)
			(stroke
				(width 0.1)
				(type default)
			)
			(layer "F.Fab")
		)
		(fp_line
			(start 0.12065 -0.2794)
			(end 0.12065 -0.3048)
			(stroke
				(width 0.1)
				(type default)
			)
			(layer "F.Fab")
		)
		(fp_line
			(start -0.12065 -0.2794)
			(end 0.12065 -0.2794)
			(stroke
				(width 0.1)
				(type default)
			)
			(layer "F.Fab")
		)
		(fp_line
			(start 0.120396 0.2794)
			(end -0.12065 0.2794)
			(stroke
				(width 0.1)
				(type default)
			)
			(layer "F.Fab")
		)
		(fp_line
			(start -0.12065 0.2794)
			(end -0.12065 0.3048)
			(stroke
				(width 0.1)
				(type default)
			)
			(layer "F.Fab")
		)
		(fp_line
			(start 0.67945 0.3048)
			(end 0.120396 0.3048)
			(stroke
				(width 0.1)
				(type default)
			)
			(layer "F.Fab")
		)
		(fp_line
			(start 0.120396 0.3048)
			(end 0.120396 0.2794)
			(stroke
				(width 0.1)
				(type default)
			)
			(layer "F.Fab")
		)
		(fp_line
			(start -0.12065 0.3048)
			(end -0.67945 0.3048)
			(stroke
				(width 0.1)
				(type default)
			)
			(layer "F.Fab")
		)
		(fp_line
			(start -0.67945 0.3048)
			(end -0.67945 -0.305054)
			(stroke
				(width 0.1)
				(type default)
			)
			(layer "F.Fab")
		)
		(pad "1" smd circle
			(at -0.40005 0 90)
			(size 0 0)
			(layers "F.Cu" "F.Mask" "F.Paste")
			(net "P12V_OCP_ISET_2")
		)
		(pad "2" smd circle
			(at 0.40005 0 90)
			(size 0 0)
			(layers "F.Cu" "F.Mask" "F.Paste")
			(net "GND")
		)
	)
	(footprint ""
		(layer "F.Cu")
		(at 340.969346 -20.093686 -90)
		(property "Reference" "Q2"
			(at -0.023114 1.751076 90)
			(unlocked yes)
			(layer "F.SilkS")
			(effects
				(font
					(size 0.7874 0.5842)
					(thickness 0.1524)
				)
				(justify left)
			)
		)
		(property "Value" ""
			(at 0 0 270)
			(layer "F.Fab")
			(effects
				(font
					(size 1.27 1.27)
				)
			)
		)
		(duplicate_pad_numbers_are_jumpers no)
		(fp_line
			(start -1.332738 1.100074)
			(end -1.332738 -1.100074)
			(stroke
				(width 0.1524)
				(type default)
			)
			(layer "F.SilkS")
		)
		(fp_line
			(start 1.332738 1.100074)
			(end -1.332738 1.100074)
			(stroke
				(width 0.1524)
				(type default)
			)
			(layer "F.SilkS")
		)
		(fp_line
			(start 0 -0.541274)
			(end 0.4826 -1.100074)
			(stroke
				(width 0.1524)
				(type default)
			)
			(layer "F.SilkS")
		)
		(fp_line
			(start -1.332738 -1.100074)
			(end -0.4826 -1.100074)
			(stroke
				(width 0.1524)
				(type default)
			)
			(layer "F.SilkS")
		)
		(fp_line
			(start -0.4826 -1.100074)
			(end 0 -0.541274)
			(stroke
				(width 0.1524)
				(type default)
			)
			(layer "F.SilkS")
		)
		(fp_line
			(start 0.4826 -1.100074)
			(end 1.332738 -1.100074)
			(stroke
				(width 0.1524)
				(type default)
			)
			(layer "F.SilkS")
		)
		(fp_line
			(start 1.332738 -1.100074)
			(end 1.332738 1.100074)
			(stroke
				(width 0.1524)
				(type default)
			)
			(layer "F.SilkS")
		)
		(fp_poly
			(pts
				(xy -2.067306 -0.649986) (xy -2.769362 -0.298958) (xy -2.769362 -1.001014)
			)
			(stroke
				(width 0)
				(type default)
			)
			(fill yes)
			(layer "F.SilkS")
		)
		(fp_line
			(start -0.674878 1.100074)
			(end -0.674878 -1.100074)
			(stroke
				(width 0.1)
				(type default)
			)
			(layer "F.Fab")
		)
		(fp_line
			(start 0.674878 1.100074)
			(end -0.674878 1.100074)
			(stroke
				(width 0.1)
				(type default)
			)
			(layer "F.Fab")
		)
		(fp_line
			(start -0.674878 -1.100074)
			(end 0.674878 -1.100074)
			(stroke
				(width 0.1)
				(type default)
			)
			(layer "F.Fab")
		)
		(fp_line
			(start 0.674878 -1.100074)
			(end 0.674878 1.100074)
			(stroke
				(width 0.1)
				(type default)
			)
			(layer "F.Fab")
		)
		(fp_poly
			(pts
				(xy -2.2352 -0.298958) (xy -2.2352 -1.001014) (xy -1.533144 -0.649986)
			)
			(stroke
				(width 0)
				(type default)
			)
			(fill yes)
			(layer "F.Fab")
		)
		(pad "1" smd rect
			(at -0.94996 -0.649986)
			(size 0.4318 0.508)
			(layers "F.Cu" "F.Mask" "F.Paste")
			(net "GND")
		)
		(pad "2" smd rect
			(at -0.94996 0)
			(size 0.4318 0.508)
			(layers "F.Cu" "F.Mask" "F.Paste")
			(net "BOOT_RDY_BUF_LED")
		)
		(pad "3" smd rect
			(at -0.94996 0.649986)
			(size 0.4318 0.508)
			(layers "F.Cu" "F.Mask" "F.Paste")
			(net "BOOT_RDY_LED_N")
		)
		(pad "4" smd rect
			(at 0.94996 0.649986)
			(size 0.4318 0.508)
			(layers "F.Cu" "F.Mask" "F.Paste")
			(net "GND")
		)
		(pad "5" smd rect
			(at 0.94996 0)
			(size 0.4318 0.508)
			(layers "F.Cu" "F.Mask" "F.Paste")
			(net "BOOT_RDY_LED")
		)
		(pad "6" smd rect
			(at 0.94996 -0.649986)
			(size 0.4318 0.508)
			(layers "F.Cu" "F.Mask" "F.Paste")
			(net "BOOT_RDY_LED")
		)
	)
	(footprint ""
		(layer "F.Cu")
		(at 110.643924 -388.030974 90)
		(property "Reference" "R642"
			(at 0 0 90)
			(layer "F.SilkS")
			(hide yes)
			(effects
				(font
					(size 1.27 1.27)
				)
			)
		)
		(property "Value" ""
			(at 0 0 90)
			(layer "F.Fab")
			(effects
				(font
					(size 1.27 1.27)
				)
			)
		)
		(duplicate_pad_numbers_are_jumpers no)
		(fp_line
			(start 0.32512 -0.175006)
			(end 0.32512 0.175006)
			(stroke
				(width 0.1)
				(type default)
			)
			(layer "F.Fab")
		)
		(fp_line
			(start -0.32512 -0.175006)
			(end 0.32512 -0.175006)
			(stroke
				(width 0.1)
				(type default)
			)
			(layer "F.Fab")
		)
		(fp_line
			(start 0.32512 0.175006)
			(end -0.32512 0.175006)
			(stroke
				(width 0.1)
				(type default)
			)
			(layer "F.Fab")
		)
		(fp_line
			(start -0.32512 0.175006)
			(end -0.32512 -0.175006)
			(stroke
				(width 0.1)
				(type default)
			)
			(layer "F.Fab")
		)
		(pad "1" smd rect
			(at -0.2667 0 90)
			(size 0.3048 0.381)
			(layers "F.Cu" "F.Mask" "F.Paste")
			(net "CLK_100M_RETIMER_CPU1_P3_DP")
		)
		(pad "2" smd rect
			(at 0.2667 0 270)
			(size 0.3048 0.381)
			(layers "F.Cu" "F.Mask" "F.Paste")
			(net "GND")
		)
	)
	(footprint ""
		(layer "F.Cu")
		(at 11.557 -77.089)
		(property "Reference" "R8016"
			(at 0 0 0)
			(layer "F.SilkS")
			(hide yes)
			(effects
				(font
					(size 1.27 1.27)
				)
			)
		)
		(property "Value" ""
			(at 0 0 0)
			(layer "F.Fab")
			(effects
				(font
					(size 1.27 1.27)
				)
			)
		)
		(duplicate_pad_numbers_are_jumpers no)
		(fp_line
			(start -0.7874 -0.4064)
			(end 0.7874 -0.4064)
			(stroke
				(width 0.1524)
				(type default)
			)
			(layer "F.SilkS")
		)
		(fp_line
			(start -0.7874 0.4064)
			(end -0.7874 -0.4064)
			(stroke
				(width 0.1524)
				(type default)
			)
			(layer "F.SilkS")
		)
		(fp_line
			(start 0.7874 -0.4064)
			(end 0.7874 0.4064)
			(stroke
				(width 0.1524)
				(type default)
			)
			(layer "F.SilkS")
		)
		(fp_line
			(start 0.7874 0.4064)
			(end -0.7874 0.4064)
			(stroke
				(width 0.1524)
				(type default)
			)
			(layer "F.SilkS")
		)
		(fp_line
			(start -0.67945 -0.305054)
			(end -0.12065 -0.305054)
			(stroke
				(width 0.1)
				(type default)
			)
			(layer "F.Fab")
		)
		(fp_line
			(start -0.67945 0.3048)
			(end -0.67945 -0.305054)
			(stroke
				(width 0.1)
				(type default)
			)
			(layer "F.Fab")
		)
		(fp_line
			(start -0.12065 -0.305054)
			(end -0.12065 -0.2794)
			(stroke
				(width 0.1)
				(type default)
			)
			(layer "F.Fab")
		)
		(fp_line
			(start -0.12065 -0.2794)
			(end 0.12065 -0.2794)
			(stroke
				(width 0.1)
				(type default)
			)
			(layer "F.Fab")
		)
		(fp_line
			(start -0.12065 0.2794)
			(end -0.12065 0.3048)
			(stroke
				(width 0.1)
				(type default)
			)
			(layer "F.Fab")
		)
		(fp_line
			(start -0.12065 0.3048)
			(end -0.67945 0.3048)
			(stroke
				(width 0.1)
				(type default)
			)
			(layer "F.Fab")
		)
		(fp_line
			(start 0.120396 0.2794)
			(end -0.12065 0.2794)
			(stroke
				(width 0.1)
				(type default)
			)
			(layer "F.Fab")
		)
		(fp_line
			(start 0.120396 0.3048)
			(end 0.120396 0.2794)
			(stroke
				(width 0.1)
				(type default)
			)
			(layer "F.Fab")
		)
		(fp_line
			(start 0.12065 -0.3048)
			(end 0.67945 -0.3048)
			(stroke
				(width 0.1)
				(type default)
			)
			(layer "F.Fab")
		)
		(fp_line
			(start 0.12065 -0.2794)
			(end 0.12065 -0.3048)
			(stroke
				(width 0.1)
				(type default)
			)
			(layer "F.Fab")
		)
		(fp_line
			(start 0.67945 -0.3048)
			(end 0.67945 0.3048)
			(stroke
				(width 0.1)
				(type default)
			)
			(layer "F.Fab")
		)
		(fp_line
			(start 0.67945 0.3048)
			(end 0.120396 0.3048)
			(stroke
				(width 0.1)
				(type default)
			)
			(layer "F.Fab")
		)
		(pad "1" smd circle
			(at -0.40005 0)
			(size 0 0)
			(layers "F.Cu" "F.Mask" "F.Paste")
			(net "OCP_V3_2_PRSNT23_R_N")
		)
		(pad "2" smd circle
			(at 0.40005 0)
			(size 0 0)
			(layers "F.Cu" "F.Mask" "F.Paste")
			(net "OCP_V3_2_PRSNT23_R1_N")
		)
	)
	(footprint ""
		(layer "F.Cu")
		(at 204.851 -101.473)
		(property "Reference" "D8004"
			(at 3.037586 0.680466 0)
			(unlocked yes)
			(layer "F.SilkS")
			(effects
				(font
					(size 0.7874 0.5842)
					(thickness 0.1524)
				)
				(justify left)
			)
		)
		(property "Value" ""
			(at 0 0 0)
			(layer "F.Fab")
			(effects
				(font
					(size 1.27 1.27)
				)
			)
		)
		(duplicate_pad_numbers_are_jumpers no)
		(fp_line
			(start -2.050796 -0.700024)
			(end 2.050796 -0.700024)
			(stroke
				(width 0.1524)
				(type default)
			)
			(layer "F.SilkS")
		)
		(fp_line
			(start -2.050796 0.700024)
			(end -2.050796 -0.700024)
			(stroke
				(width 0.1524)
				(type default)
			)
			(layer "F.SilkS")
		)
		(fp_line
			(start -0.30607 -0.500126)
			(end -0.30607 0.500126)
			(stroke
				(width 0.1524)
				(type default)
			)
			(layer "F.SilkS")
		)
		(fp_line
			(start -0.30607 0.500126)
			(end 0.193802 0)
			(stroke
				(width 0.1524)
				(type default)
			)
			(layer "F.SilkS")
		)
		(fp_line
			(start 0.193802 0)
			(end -0.30607 -0.500126)
			(stroke
				(width 0.1524)
				(type default)
			)
			(layer "F.SilkS")
		)
		(fp_line
			(start 0.293878 -0.500126)
			(end 0.293878 0.500126)
			(stroke
				(width 0.1524)
				(type default)
			)
			(layer "F.SilkS")
		)
		(fp_line
			(start 2.050796 -0.700024)
			(end 2.050796 0.700024)
			(stroke
				(width 0.1524)
				(type default)
			)
			(layer "F.SilkS")
		)
		(fp_line
			(start 2.050796 0.700024)
			(end -2.050796 0.700024)
			(stroke
				(width 0.1524)
				(type default)
			)
			(layer "F.SilkS")
		)
		(fp_line
			(start 2.051304 0.635)
			(end 2.152904 0.635)
			(stroke
				(width 0.1524)
				(type default)
			)
			(layer "F.SilkS")
		)
		(fp_line
			(start 2.051304 0.6985)
			(end 2.051304 0.635)
			(stroke
				(width 0.1524)
				(type default)
			)
			(layer "F.SilkS")
		)
		(fp_line
			(start 2.064004 -0.6985)
			(end 2.229104 -0.6985)
			(stroke
				(width 0.1524)
				(type default)
			)
			(layer "F.SilkS")
		)
		(fp_line
			(start 2.064004 -0.6731)
			(end 2.064004 -0.6985)
			(stroke
				(width 0.1524)
				(type default)
			)
			(layer "F.SilkS")
		)
		(fp_line
			(start 2.152904 -0.6985)
			(end 2.343404 -0.6985)
			(stroke
				(width 0.1524)
				(type default)
			)
			(layer "F.SilkS")
		)
		(fp_line
			(start 2.152904 0.635)
			(end 2.152904 -0.6985)
			(stroke
				(width 0.1524)
				(type default)
			)
			(layer "F.SilkS")
		)
		(fp_line
			(start 2.229104 -0.6985)
			(end 2.229104 0.6985)
			(stroke
				(width 0.1524)
				(type default)
			)
			(layer "F.SilkS")
		)
		(fp_line
			(start 2.229104 0.6985)
			(end 2.051304 0.6985)
			(stroke
				(width 0.1524)
				(type default)
			)
			(layer "F.SilkS")
		)
		(fp_line
			(start 2.343404 -0.6985)
			(end 2.343404 0.6985)
			(stroke
				(width 0.1524)
				(type default)
			)
			(layer "F.SilkS")
		)
		(fp_line
			(start 2.343404 0.6985)
			(end 2.216404 0.6985)
			(stroke
				(width 0.1524)
				(type default)
			)
			(layer "F.SilkS")
		)
		(fp_line
			(start -0.899922 -0.700024)
			(end 0.899922 -0.700024)
			(stroke
				(width 0.1)
				(type default)
			)
			(layer "F.Fab")
		)
		(fp_line
			(start -0.899922 0.700024)
			(end -0.899922 -0.700024)
			(stroke
				(width 0.1)
				(type default)
			)
			(layer "F.Fab")
		)
		(fp_line
			(start 0.899922 -0.700024)
			(end 0.899922 0.700024)
			(stroke
				(width 0.1)
				(type default)
			)
			(layer "F.Fab")
		)
		(fp_line
			(start 0.899922 0.700024)
			(end -0.899922 0.700024)
			(stroke
				(width 0.1)
				(type default)
			)
			(layer "F.Fab")
		)
		(fp_text user "+"
			(at -2.772664 0.87757 90)
			(unlocked yes)
			(layer "F.SilkS")
			(effects
				(font
					(size 1.905 1.4224)
					(thickness 0.1524)
				)
				(justify left)
			)
		)
		(fp_text user "-"
			(at 3.880104 0.23495 180)
			(unlocked yes)
			(layer "F.SilkS")
			(effects
				(font
					(size 1.905 1.4224)
					(thickness 0.1524)
				)
				(justify left)
			)
		)
		(fp_text user "+"
			(at -3.123946 0.762 90)
			(unlocked yes)
			(layer "F.Fab")
			(effects
				(font
					(size 1.905 1.4224)
					(thickness 0.1524)
				)
				(justify left)
			)
		)
		(fp_text user "-"
			(at 3.880104 0.23495 180)
			(unlocked yes)
			(layer "F.Fab")
			(effects
				(font
					(size 1.905 1.4224)
					(thickness 0.1524)
				)
				(justify left)
			)
		)
		(pad "1" smd rect
			(at -1.199896 0 270)
			(size 0.6604 1.3716)
			(layers "F.Cu" "F.Mask" "F.Paste")
			(net "PWRGD_CHGL_CPU0_R1")
		)
		(pad "2" smd rect
			(at 1.199896 0 90)
			(size 0.6604 1.3716)
			(layers "F.Cu" "F.Mask" "F.Paste")
			(net "P3V3_AUX")
		)
	)
	(footprint ""
		(layer "F.Cu")
		(at 239.432592 -289.012122 180)
		(property "Reference" "C6757"
			(at 0 0 180)
			(layer "F.SilkS")
			(hide yes)
			(effects
				(font
					(size 1.27 1.27)
				)
			)
		)
		(property "Value" ""
			(at 0 0 180)
			(layer "F.Fab")
			(effects
				(font
					(size 1.27 1.27)
				)
			)
		)
		(duplicate_pad_numbers_are_jumpers no)
		(fp_line
			(start 0.7874 0.4064)
			(end -0.7874 0.4064)
			(stroke
				(width 0.1524)
				(type default)
			)
			(layer "F.SilkS")
		)
		(fp_line
			(start 0.7874 -0.4064)
			(end 0.7874 0.4064)
			(stroke
				(width 0.1524)
				(type default)
			)
			(layer "F.SilkS")
		)
		(fp_line
			(start -0.7874 0.4064)
			(end -0.7874 -0.4064)
			(stroke
				(width 0.1524)
				(type default)
			)
			(layer "F.SilkS")
		)
		(fp_line
			(start -0.7874 -0.4064)
			(end 0.7874 -0.4064)
			(stroke
				(width 0.1524)
				(type default)
			)
			(layer "F.SilkS")
		)
		(fp_line
			(start 0.67945 0.3048)
			(end 0.120396 0.3048)
			(stroke
				(width 0.1)
				(type default)
			)
			(layer "F.Fab")
		)
		(fp_line
			(start 0.67945 -0.3048)
			(end 0.67945 0.3048)
			(stroke
				(width 0.1)
				(type default)
			)
			(layer "F.Fab")
		)
		(fp_line
			(start 0.12065 -0.2794)
			(end 0.12065 -0.3048)
			(stroke
				(width 0.1)
				(type default)
			)
			(layer "F.Fab")
		)
		(fp_line
			(start 0.12065 -0.3048)
			(end 0.67945 -0.3048)
			(stroke
				(width 0.1)
				(type default)
			)
			(layer "F.Fab")
		)
		(fp_line
			(start 0.120396 0.3048)
			(end 0.120396 0.2794)
			(stroke
				(width 0.1)
				(type default)
			)
			(layer "F.Fab")
		)
		(fp_line
			(start 0.120396 0.2794)
			(end -0.12065 0.2794)
			(stroke
				(width 0.1)
				(type default)
			)
			(layer "F.Fab")
		)
		(fp_line
			(start -0.12065 0.3048)
			(end -0.67945 0.3048)
			(stroke
				(width 0.1)
				(type default)
			)
			(layer "F.Fab")
		)
		(fp_line
			(start -0.12065 0.2794)
			(end -0.12065 0.3048)
			(stroke
				(width 0.1)
				(type default)
			)
			(layer "F.Fab")
		)
		(fp_line
			(start -0.12065 -0.2794)
			(end 0.12065 -0.2794)
			(stroke
				(width 0.1)
				(type default)
			)
			(layer "F.Fab")
		)
		(fp_line
			(start -0.12065 -0.305054)
			(end -0.12065 -0.2794)
			(stroke
				(width 0.1)
				(type default)
			)
			(layer "F.Fab")
		)
		(fp_line
			(start -0.67945 0.3048)
			(end -0.67945 -0.305054)
			(stroke
				(width 0.1)
				(type default)
			)
			(layer "F.Fab")
		)
		(fp_line
			(start -0.67945 -0.305054)
			(end -0.12065 -0.305054)
			(stroke
				(width 0.1)
				(type default)
			)
			(layer "F.Fab")
		)
		(pad "1" smd circle
			(at -0.40005 0 180)
			(size 0 0)
			(layers "F.Cu" "F.Mask" "F.Paste")
			(net "P1V8_RETIMER_CPU0_EN")
		)
		(pad "2" smd circle
			(at 0.40005 0 180)
			(size 0 0)
			(layers "F.Cu" "F.Mask" "F.Paste")
			(net "GND")
		)
	)
	(footprint ""
		(layer "F.Cu")
		(at 213.106 -98.425 90)
		(property "Reference" "R9030"
			(at 0 0 90)
			(layer "F.SilkS")
			(hide yes)
			(effects
				(font
					(size 1.27 1.27)
				)
			)
		)
		(property "Value" ""
			(at 0 0 90)
			(layer "F.Fab")
			(effects
				(font
					(size 1.27 1.27)
				)
			)
		)
		(duplicate_pad_numbers_are_jumpers no)
		(fp_line
			(start 0.7874 -0.4064)
			(end 0.7874 0.4064)
			(stroke
				(width 0.1524)
				(type default)
			)
			(layer "F.SilkS")
		)
		(fp_line
			(start -0.7874 -0.4064)
			(end 0.7874 -0.4064)
			(stroke
				(width 0.1524)
				(type default)
			)
			(layer "F.SilkS")
		)
		(fp_line
			(start 0.7874 0.4064)
			(end -0.7874 0.4064)
			(stroke
				(width 0.1524)
				(type default)
			)
			(layer "F.SilkS")
		)
		(fp_line
			(start -0.7874 0.4064)
			(end -0.7874 -0.4064)
			(stroke
				(width 0.1524)
				(type default)
			)
			(layer "F.SilkS")
		)
		(fp_line
			(start -0.12065 -0.305054)
			(end -0.12065 -0.2794)
			(stroke
				(width 0.1)
				(type default)
			)
			(layer "F.Fab")
		)
		(fp_line
			(start -0.67945 -0.305054)
			(end -0.12065 -0.305054)
			(stroke
				(width 0.1)
				(type default)
			)
			(layer "F.Fab")
		)
		(fp_line
			(start 0.67945 -0.3048)
			(end 0.67945 0.3048)
			(stroke
				(width 0.1)
				(type default)
			)
			(layer "F.Fab")
		)
		(fp_line
			(start 0.12065 -0.3048)
			(end 0.67945 -0.3048)
			(stroke
				(width 0.1)
				(type default)
			)
			(layer "F.Fab")
		)
		(fp_line
			(start 0.12065 -0.2794)
			(end 0.12065 -0.3048)
			(stroke
				(width 0.1)
				(type default)
			)
			(layer "F.Fab")
		)
		(fp_line
			(start -0.12065 -0.2794)
			(end 0.12065 -0.2794)
			(stroke
				(width 0.1)
				(type default)
			)
			(layer "F.Fab")
		)
		(fp_line
			(start 0.120396 0.2794)
			(end -0.12065 0.2794)
			(stroke
				(width 0.1)
				(type default)
			)
			(layer "F.Fab")
		)
		(fp_line
			(start -0.12065 0.2794)
			(end -0.12065 0.3048)
			(stroke
				(width 0.1)
				(type default)
			)
			(layer "F.Fab")
		)
		(fp_line
			(start 0.67945 0.3048)
			(end 0.120396 0.3048)
			(stroke
				(width 0.1)
				(type default)
			)
			(layer "F.Fab")
		)
		(fp_line
			(start 0.120396 0.3048)
			(end 0.120396 0.2794)
			(stroke
				(width 0.1)
				(type default)
			)
			(layer "F.Fab")
		)
		(fp_line
			(start -0.12065 0.3048)
			(end -0.67945 0.3048)
			(stroke
				(width 0.1)
				(type default)
			)
			(layer "F.Fab")
		)
		(fp_line
			(start -0.67945 0.3048)
			(end -0.67945 -0.305054)
			(stroke
				(width 0.1)
				(type default)
			)
			(layer "F.Fab")
		)
		(pad "1" smd circle
			(at -0.40005 0 90)
			(size 0 0)
			(layers "F.Cu" "F.Mask" "F.Paste")
			(net "OCP_SFF_AUX_PWR_EN_R3")
		)
		(pad "2" smd circle
			(at 0.40005 0 90)
			(size 0 0)
			(layers "F.Cu" "F.Mask" "F.Paste")
			(net "FM_PLD_OCP_SFF_AUX_PWR_EN")
		)
	)
	(footprint ""
		(layer "F.Cu")
		(at 12.777216 -15.32128 90)
		(property "Reference" "R3177"
			(at 0 0 90)
			(layer "F.SilkS")
			(hide yes)
			(effects
				(font
					(size 1.27 1.27)
				)
			)
		)
		(property "Value" ""
			(at 0 0 90)
			(layer "F.Fab")
			(effects
				(font
					(size 1.27 1.27)
				)
			)
		)
		(duplicate_pad_numbers_are_jumpers no)
		(fp_line
			(start 0.7874 -0.4064)
			(end 0.7874 0.4064)
			(stroke
				(width 0.1524)
				(type default)
			)
			(layer "F.SilkS")
		)
		(fp_line
			(start -0.7874 -0.4064)
			(end 0.7874 -0.4064)
			(stroke
				(width 0.1524)
				(type default)
			)
			(layer "F.SilkS")
		)
		(fp_line
			(start 0.7874 0.4064)
			(end -0.7874 0.4064)
			(stroke
				(width 0.1524)
				(type default)
			)
			(layer "F.SilkS")
		)
		(fp_line
			(start -0.7874 0.4064)
			(end -0.7874 -0.4064)
			(stroke
				(width 0.1524)
				(type default)
			)
			(layer "F.SilkS")
		)
		(fp_line
			(start -0.12065 -0.305054)
			(end -0.12065 -0.2794)
			(stroke
				(width 0.1)
				(type default)
			)
			(layer "F.Fab")
		)
		(fp_line
			(start -0.67945 -0.305054)
			(end -0.12065 -0.305054)
			(stroke
				(width 0.1)
				(type default)
			)
			(layer "F.Fab")
		)
		(fp_line
			(start 0.67945 -0.3048)
			(end 0.67945 0.3048)
			(stroke
				(width 0.1)
				(type default)
			)
			(layer "F.Fab")
		)
		(fp_line
			(start 0.12065 -0.3048)
			(end 0.67945 -0.3048)
			(stroke
				(width 0.1)
				(type default)
			)
			(layer "F.Fab")
		)
		(fp_line
			(start 0.12065 -0.2794)
			(end 0.12065 -0.3048)
			(stroke
				(width 0.1)
				(type default)
			)
			(layer "F.Fab")
		)
		(fp_line
			(start -0.12065 -0.2794)
			(end 0.12065 -0.2794)
			(stroke
				(width 0.1)
				(type default)
			)
			(layer "F.Fab")
		)
		(fp_line
			(start 0.120396 0.2794)
			(end -0.12065 0.2794)
			(stroke
				(width 0.1)
				(type default)
			)
			(layer "F.Fab")
		)
		(fp_line
			(start -0.12065 0.2794)
			(end -0.12065 0.3048)
			(stroke
				(width 0.1)
				(type default)
			)
			(layer "F.Fab")
		)
		(fp_line
			(start 0.67945 0.3048)
			(end 0.120396 0.3048)
			(stroke
				(width 0.1)
				(type default)
			)
			(layer "F.Fab")
		)
		(fp_line
			(start 0.120396 0.3048)
			(end 0.120396 0.2794)
			(stroke
				(width 0.1)
				(type default)
			)
			(layer "F.Fab")
		)
		(fp_line
			(start -0.12065 0.3048)
			(end -0.67945 0.3048)
			(stroke
				(width 0.1)
				(type default)
			)
			(layer "F.Fab")
		)
		(fp_line
			(start -0.67945 0.3048)
			(end -0.67945 -0.305054)
			(stroke
				(width 0.1)
				(type default)
			)
			(layer "F.Fab")
		)
		(pad "1" smd circle
			(at -0.40005 0 90)
			(size 0 0)
			(layers "F.Cu" "F.Mask" "F.Paste")
			(net "USB2_P10_DN")
		)
		(pad "2" smd circle
			(at 0.40005 0 90)
			(size 0 0)
			(layers "F.Cu" "F.Mask" "F.Paste")
			(net "USB2_CPU0_P10_DN")
		)
	)
	(footprint ""
		(layer "F.Cu")
		(at 99.650296 -417.725098 90)
		(property "Reference" "U272"
			(at 1.712976 -3.64998 90)
			(unlocked yes)
			(layer "F.SilkS")
			(effects
				(font
					(size 0.7874 0.5842)
					(thickness 0.1524)
				)
				(justify left)
			)
		)
		(property "Value" ""
			(at 0 0 90)
			(layer "F.Fab")
			(effects
				(font
					(size 1.27 1.27)
				)
			)
		)
		(duplicate_pad_numbers_are_jumpers no)
		(fp_line
			(start 3.447796 -2.500122)
			(end 1.484122 -2.500122)
			(stroke
				(width 0.1524)
				(type default)
			)
			(layer "F.SilkS")
		)
		(fp_line
			(start 1.484122 -2.500122)
			(end 0 -1.016)
			(stroke
				(width 0.1524)
				(type default)
			)
			(layer "F.SilkS")
		)
		(fp_line
			(start -1.484122 -2.500122)
			(end -3.447796 -2.500122)
			(stroke
				(width 0.1524)
				(type default)
			)
			(layer "F.SilkS")
		)
		(fp_line
			(start -3.447796 -2.500122)
			(end -3.447796 2.500122)
			(stroke
				(width 0.1524)
				(type default)
			)
			(layer "F.SilkS")
		)
		(fp_line
			(start 0 -1.016)
			(end -1.484122 -2.500122)
			(stroke
				(width 0.1524)
				(type default)
			)
			(layer "F.SilkS")
		)
		(fp_line
			(start 3.447796 2.500122)
			(end 3.447796 -2.500122)
			(stroke
				(width 0.1524)
				(type default)
			)
			(layer "F.SilkS")
		)
		(fp_line
			(start -3.447796 2.500122)
			(end 3.447796 2.500122)
			(stroke
				(width 0.1524)
				(type default)
			)
			(layer "F.SilkS")
		)
		(fp_poly
			(pts
				(xy -2.37871 -3.737102) (xy -3.39471 -3.737102) (xy -2.88671 -2.721102)
			)
			(stroke
				(width 0)
				(type default)
			)
			(fill yes)
			(layer "F.SilkS")
		)
		(fp_line
			(start 1.999996 -2.500122)
			(end -1.999996 -2.500122)
			(stroke
				(width 0.1)
				(type default)
			)
			(layer "F.Fab")
		)
		(fp_line
			(start -1.999996 -2.500122)
			(end -1.999996 2.500122)
			(stroke
				(width 0.1)
				(type default)
			)
			(layer "F.Fab")
		)
		(fp_line
			(start 1.999996 2.500122)
			(end 1.999996 -2.500122)
			(stroke
				(width 0.1)
				(type default)
			)
			(layer "F.Fab")
		)
		(fp_line
			(start -1.999996 2.500122)
			(end 1.999996 2.500122)
			(stroke
				(width 0.1)
				(type default)
			)
			(layer "F.Fab")
		)
		(fp_poly
			(pts
				(xy -4.5974 -2.413) (xy -4.5974 -1.397) (xy -3.5814 -1.905)
			)
			(stroke
				(width 0)
				(type default)
			)
			(fill yes)
			(layer "F.Fab")
		)
		(pad "1" smd rect
			(at -2.649982 -1.905)
			(size 0.6096 1.3208)
			(layers "F.Cu" "F.Mask" "F.Paste")
			(net "SMB_LM75_2_3V3AUX_SDA_R1")
		)
		(pad "2" smd rect
			(at -2.649982 -0.635)
			(size 0.6096 1.3208)
			(layers "F.Cu" "F.Mask" "F.Paste")
			(net "SMB_LM75_2_3V3AUX_SCL_R1")
		)
		(pad "3" smd rect
			(at -2.649982 0.635)
			(size 0.6096 1.3208)
			(layers "F.Cu" "F.Mask" "F.Paste")
			(net "FM_LM75_2_ALERT_N")
		)
		(pad "4" smd rect
			(at -2.649982 1.905)
			(size 0.6096 1.3208)
			(layers "F.Cu" "F.Mask" "F.Paste")
			(net "GND")
		)
		(pad "5" smd rect
			(at 2.649982 1.905)
			(size 0.6096 1.3208)
			(layers "F.Cu" "F.Mask" "F.Paste")
			(net "U272_2_ADD2")
		)
		(pad "6" smd rect
			(at 2.649982 0.635)
			(size 0.6096 1.3208)
			(layers "F.Cu" "F.Mask" "F.Paste")
			(net "U272_2_ADD1")
		)
		(pad "7" smd rect
			(at 2.649982 -0.635)
			(size 0.6096 1.3208)
			(layers "F.Cu" "F.Mask" "F.Paste")
			(net "U272_2_ADD0")
		)
		(pad "8" smd rect
			(at 2.649982 -1.905)
			(size 0.6096 1.3208)
			(layers "F.Cu" "F.Mask" "F.Paste")
			(net "P3V3_AUX")
		)
	)
	(footprint ""
		(layer "F.Cu")
		(at 21.712682 -422.437052)
		(property "Reference" "C6012"
			(at 0 0 0)
			(layer "F.SilkS")
			(hide yes)
			(effects
				(font
					(size 1.27 1.27)
				)
			)
		)
		(property "Value" ""
			(at 0 0 0)
			(layer "F.Fab")
			(effects
				(font
					(size 1.27 1.27)
				)
			)
		)
		(duplicate_pad_numbers_are_jumpers no)
		(fp_line
			(start -0.7874 -0.4064)
			(end 0.7874 -0.4064)
			(stroke
				(width 0.1524)
				(type default)
			)
			(layer "F.SilkS")
		)
		(fp_line
			(start -0.7874 0.4064)
			(end -0.7874 -0.4064)
			(stroke
				(width 0.1524)
				(type default)
			)
			(layer "F.SilkS")
		)
		(fp_line
			(start 0.7874 -0.4064)
			(end 0.7874 0.4064)
			(stroke
				(width 0.1524)
				(type default)
			)
			(layer "F.SilkS")
		)
		(fp_line
			(start 0.7874 0.4064)
			(end -0.7874 0.4064)
			(stroke
				(width 0.1524)
				(type default)
			)
			(layer "F.SilkS")
		)
		(fp_line
			(start -0.67945 -0.305054)
			(end -0.12065 -0.305054)
			(stroke
				(width 0.1)
				(type default)
			)
			(layer "F.Fab")
		)
		(fp_line
			(start -0.67945 0.3048)
			(end -0.67945 -0.305054)
			(stroke
				(width 0.1)
				(type default)
			)
			(layer "F.Fab")
		)
		(fp_line
			(start -0.12065 -0.305054)
			(end -0.12065 -0.2794)
			(stroke
				(width 0.1)
				(type default)
			)
			(layer "F.Fab")
		)
		(fp_line
			(start -0.12065 -0.2794)
			(end 0.12065 -0.2794)
			(stroke
				(width 0.1)
				(type default)
			)
			(layer "F.Fab")
		)
		(fp_line
			(start -0.12065 0.2794)
			(end -0.12065 0.3048)
			(stroke
				(width 0.1)
				(type default)
			)
			(layer "F.Fab")
		)
		(fp_line
			(start -0.12065 0.3048)
			(end -0.67945 0.3048)
			(stroke
				(width 0.1)
				(type default)
			)
			(layer "F.Fab")
		)
		(fp_line
			(start 0.120396 0.2794)
			(end -0.12065 0.2794)
			(stroke
				(width 0.1)
				(type default)
			)
			(layer "F.Fab")
		)
		(fp_line
			(start 0.120396 0.3048)
			(end 0.120396 0.2794)
			(stroke
				(width 0.1)
				(type default)
			)
			(layer "F.Fab")
		)
		(fp_line
			(start 0.12065 -0.3048)
			(end 0.67945 -0.3048)
			(stroke
				(width 0.1)
				(type default)
			)
			(layer "F.Fab")
		)
		(fp_line
			(start 0.12065 -0.2794)
			(end 0.12065 -0.3048)
			(stroke
				(width 0.1)
				(type default)
			)
			(layer "F.Fab")
		)
		(fp_line
			(start 0.67945 -0.3048)
			(end 0.67945 0.3048)
			(stroke
				(width 0.1)
				(type default)
			)
			(layer "F.Fab")
		)
		(fp_line
			(start 0.67945 0.3048)
			(end 0.120396 0.3048)
			(stroke
				(width 0.1)
				(type default)
			)
			(layer "F.Fab")
		)
		(pad "1" smd circle
			(at -0.40005 0)
			(size 0 0)
			(layers "F.Cu" "F.Mask" "F.Paste")
			(net "BUF2_VDD")
		)
		(pad "2" smd circle
			(at 0.40005 0)
			(size 0 0)
			(layers "F.Cu" "F.Mask" "F.Paste")
			(net "GND")
		)
	)
	(footprint ""
		(layer "F.Cu")
		(at 179.244752 -418.831268 -90)
		(property "Reference" "R9008"
			(at 0 0 270)
			(layer "F.SilkS")
			(hide yes)
			(effects
				(font
					(size 1.27 1.27)
				)
			)
		)
		(property "Value" ""
			(at 0 0 270)
			(layer "F.Fab")
			(effects
				(font
					(size 1.27 1.27)
				)
			)
		)
		(duplicate_pad_numbers_are_jumpers no)
		(fp_line
			(start -0.7874 0.4064)
			(end -0.7874 -0.4064)
			(stroke
				(width 0.1524)
				(type default)
			)
			(layer "F.SilkS")
		)
		(fp_line
			(start 0.7874 0.4064)
			(end -0.7874 0.4064)
			(stroke
				(width 0.1524)
				(type default)
			)
			(layer "F.SilkS")
		)
		(fp_line
			(start -0.7874 -0.4064)
			(end 0.7874 -0.4064)
			(stroke
				(width 0.1524)
				(type default)
			)
			(layer "F.SilkS")
		)
		(fp_line
			(start 0.7874 -0.4064)
			(end 0.7874 0.4064)
			(stroke
				(width 0.1524)
				(type default)
			)
			(layer "F.SilkS")
		)
		(fp_line
			(start -0.67945 0.3048)
			(end -0.67945 -0.305054)
			(stroke
				(width 0.1)
				(type default)
			)
			(layer "F.Fab")
		)
		(fp_line
			(start -0.12065 0.3048)
			(end -0.67945 0.3048)
			(stroke
				(width 0.1)
				(type default)
			)
			(layer "F.Fab")
		)
		(fp_line
			(start 0.120396 0.3048)
			(end 0.120396 0.2794)
			(stroke
				(width 0.1)
				(type default)
			)
			(layer "F.Fab")
		)
		(fp_line
			(start 0.67945 0.3048)
			(end 0.120396 0.3048)
			(stroke
				(width 0.1)
				(type default)
			)
			(layer "F.Fab")
		)
		(fp_line
			(start -0.12065 0.2794)
			(end -0.12065 0.3048)
			(stroke
				(width 0.1)
				(type default)
			)
			(layer "F.Fab")
		)
		(fp_line
			(start 0.120396 0.2794)
			(end -0.12065 0.2794)
			(stroke
				(width 0.1)
				(type default)
			)
			(layer "F.Fab")
		)
		(fp_line
			(start -0.12065 -0.2794)
			(end 0.12065 -0.2794)
			(stroke
				(width 0.1)
				(type default)
			)
			(layer "F.Fab")
		)
		(fp_line
			(start 0.12065 -0.2794)
			(end 0.12065 -0.3048)
			(stroke
				(width 0.1)
				(type default)
			)
			(layer "F.Fab")
		)
		(fp_line
			(start 0.12065 -0.3048)
			(end 0.67945 -0.3048)
			(stroke
				(width 0.1)
				(type default)
			)
			(layer "F.Fab")
		)
		(fp_line
			(start 0.67945 -0.3048)
			(end 0.67945 0.3048)
			(stroke
				(width 0.1)
				(type default)
			)
			(layer "F.Fab")
		)
		(fp_line
			(start -0.67945 -0.305054)
			(end -0.12065 -0.305054)
			(stroke
				(width 0.1)
				(type default)
			)
			(layer "F.Fab")
		)
		(fp_line
			(start -0.12065 -0.305054)
			(end -0.12065 -0.2794)
			(stroke
				(width 0.1)
				(type default)
			)
			(layer "F.Fab")
		)
		(pad "1" smd circle
			(at -0.40005 0 270)
			(size 0 0)
			(layers "F.Cu" "F.Mask" "F.Paste")
			(net "P3V3_AUX")
		)
		(pad "2" smd circle
			(at 0.40005 0 270)
			(size 0 0)
			(layers "F.Cu" "F.Mask" "F.Paste")
			(net "PRSNT_CABLE_SWB_B2")
		)
	)
	(footprint ""
		(layer "F.Cu")
		(at 112.427004 -261.748016 -90)
		(property "Reference" "C2499"
			(at 0 0 270)
			(layer "F.SilkS")
			(hide yes)
			(effects
				(font
					(size 1.27 1.27)
				)
			)
		)
		(property "Value" ""
			(at 0 0 270)
			(layer "F.Fab")
			(effects
				(font
					(size 1.27 1.27)
				)
			)
		)
		(duplicate_pad_numbers_are_jumpers no)
		(fp_line
			(start -0.7874 0.4064)
			(end -0.7874 -0.4064)
			(stroke
				(width 0.1524)
				(type default)
			)
			(layer "F.SilkS")
		)
		(fp_line
			(start 0.7874 0.4064)
			(end -0.7874 0.4064)
			(stroke
				(width 0.1524)
				(type default)
			)
			(layer "F.SilkS")
		)
		(fp_line
			(start -0.7874 -0.4064)
			(end 0.7874 -0.4064)
			(stroke
				(width 0.1524)
				(type default)
			)
			(layer "F.SilkS")
		)
		(fp_line
			(start 0.7874 -0.4064)
			(end 0.7874 0.4064)
			(stroke
				(width 0.1524)
				(type default)
			)
			(layer "F.SilkS")
		)
		(fp_line
			(start -0.67945 0.3048)
			(end -0.67945 -0.305054)
			(stroke
				(width 0.1)
				(type default)
			)
			(layer "F.Fab")
		)
		(fp_line
			(start -0.12065 0.3048)
			(end -0.67945 0.3048)
			(stroke
				(width 0.1)
				(type default)
			)
			(layer "F.Fab")
		)
		(fp_line
			(start 0.120396 0.3048)
			(end 0.120396 0.2794)
			(stroke
				(width 0.1)
				(type default)
			)
			(layer "F.Fab")
		)
		(fp_line
			(start 0.67945 0.3048)
			(end 0.120396 0.3048)
			(stroke
				(width 0.1)
				(type default)
			)
			(layer "F.Fab")
		)
		(fp_line
			(start -0.12065 0.2794)
			(end -0.12065 0.3048)
			(stroke
				(width 0.1)
				(type default)
			)
			(layer "F.Fab")
		)
		(fp_line
			(start 0.120396 0.2794)
			(end -0.12065 0.2794)
			(stroke
				(width 0.1)
				(type default)
			)
			(layer "F.Fab")
		)
		(fp_line
			(start -0.12065 -0.2794)
			(end 0.12065 -0.2794)
			(stroke
				(width 0.1)
				(type default)
			)
			(layer "F.Fab")
		)
		(fp_line
			(start 0.12065 -0.2794)
			(end 0.12065 -0.3048)
			(stroke
				(width 0.1)
				(type default)
			)
			(layer "F.Fab")
		)
		(fp_line
			(start 0.12065 -0.3048)
			(end 0.67945 -0.3048)
			(stroke
				(width 0.1)
				(type default)
			)
			(layer "F.Fab")
		)
		(fp_line
			(start 0.67945 -0.3048)
			(end 0.67945 0.3048)
			(stroke
				(width 0.1)
				(type default)
			)
			(layer "F.Fab")
		)
		(fp_line
			(start -0.67945 -0.305054)
			(end -0.12065 -0.305054)
			(stroke
				(width 0.1)
				(type default)
			)
			(layer "F.Fab")
		)
		(fp_line
			(start -0.12065 -0.305054)
			(end -0.12065 -0.2794)
			(stroke
				(width 0.1)
				(type default)
			)
			(layer "F.Fab")
		)
		(pad "1" smd circle
			(at -0.40005 0 270)
			(size 0 0)
			(layers "F.Cu" "F.Mask" "F.Paste")
			(net "PVDD11_S3_P1")
		)
		(pad "2" smd circle
			(at 0.40005 0 270)
			(size 0 0)
			(layers "F.Cu" "F.Mask" "F.Paste")
			(net "GND")
		)
	)
	(footprint ""
		(layer "F.Cu")
		(at 90.819478 -148.94941 180)
		(property "Reference" "R154"
			(at 0 0 180)
			(layer "F.SilkS")
			(hide yes)
			(effects
				(font
					(size 1.27 1.27)
				)
			)
		)
		(property "Value" ""
			(at 0 0 180)
			(layer "F.Fab")
			(effects
				(font
					(size 1.27 1.27)
				)
			)
		)
		(duplicate_pad_numbers_are_jumpers no)
		(fp_line
			(start 0.7874 0.4064)
			(end -0.7874 0.4064)
			(stroke
				(width 0.1524)
				(type default)
			)
			(layer "F.SilkS")
		)
		(fp_line
			(start 0.7874 -0.4064)
			(end 0.7874 0.4064)
			(stroke
				(width 0.1524)
				(type default)
			)
			(layer "F.SilkS")
		)
		(fp_line
			(start -0.7874 0.4064)
			(end -0.7874 -0.4064)
			(stroke
				(width 0.1524)
				(type default)
			)
			(layer "F.SilkS")
		)
		(fp_line
			(start -0.7874 -0.4064)
			(end 0.7874 -0.4064)
			(stroke
				(width 0.1524)
				(type default)
			)
			(layer "F.SilkS")
		)
		(fp_line
			(start 0.67945 0.3048)
			(end 0.120396 0.3048)
			(stroke
				(width 0.1)
				(type default)
			)
			(layer "F.Fab")
		)
		(fp_line
			(start 0.67945 -0.3048)
			(end 0.67945 0.3048)
			(stroke
				(width 0.1)
				(type default)
			)
			(layer "F.Fab")
		)
		(fp_line
			(start 0.12065 -0.2794)
			(end 0.12065 -0.3048)
			(stroke
				(width 0.1)
				(type default)
			)
			(layer "F.Fab")
		)
		(fp_line
			(start 0.12065 -0.3048)
			(end 0.67945 -0.3048)
			(stroke
				(width 0.1)
				(type default)
			)
			(layer "F.Fab")
		)
		(fp_line
			(start 0.120396 0.3048)
			(end 0.120396 0.2794)
			(stroke
				(width 0.1)
				(type default)
			)
			(layer "F.Fab")
		)
		(fp_line
			(start 0.120396 0.2794)
			(end -0.12065 0.2794)
			(stroke
				(width 0.1)
				(type default)
			)
			(layer "F.Fab")
		)
		(fp_line
			(start -0.12065 0.3048)
			(end -0.67945 0.3048)
			(stroke
				(width 0.1)
				(type default)
			)
			(layer "F.Fab")
		)
		(fp_line
			(start -0.12065 0.2794)
			(end -0.12065 0.3048)
			(stroke
				(width 0.1)
				(type default)
			)
			(layer "F.Fab")
		)
		(fp_line
			(start -0.12065 -0.2794)
			(end 0.12065 -0.2794)
			(stroke
				(width 0.1)
				(type default)
			)
			(layer "F.Fab")
		)
		(fp_line
			(start -0.12065 -0.305054)
			(end -0.12065 -0.2794)
			(stroke
				(width 0.1)
				(type default)
			)
			(layer "F.Fab")
		)
		(fp_line
			(start -0.67945 0.3048)
			(end -0.67945 -0.305054)
			(stroke
				(width 0.1)
				(type default)
			)
			(layer "F.Fab")
		)
		(fp_line
			(start -0.67945 -0.305054)
			(end -0.12065 -0.305054)
			(stroke
				(width 0.1)
				(type default)
			)
			(layer "F.Fab")
		)
		(pad "1" smd circle
			(at -0.40005 0 180)
			(size 0 0)
			(layers "F.Cu" "F.Mask" "F.Paste")
			(net "PVDD18_S5_P1")
		)
		(pad "2" smd circle
			(at 0.40005 0 180)
			(size 0 0)
			(layers "F.Cu" "F.Mask" "F.Paste")
			(net "SVID_PVDDCR_CPU0_P1_SVTO")
		)
	)
	(footprint ""
		(layer "F.Cu")
		(at 206.756 -99.695 180)
		(property "Reference" "R8038"
			(at 0 0 180)
			(layer "F.SilkS")
			(hide yes)
			(effects
				(font
					(size 1.27 1.27)
				)
			)
		)
		(property "Value" ""
			(at 0 0 180)
			(layer "F.Fab")
			(effects
				(font
					(size 1.27 1.27)
				)
			)
		)
		(duplicate_pad_numbers_are_jumpers no)
		(fp_line
			(start 0.7874 0.4064)
			(end -0.7874 0.4064)
			(stroke
				(width 0.1524)
				(type default)
			)
			(layer "F.SilkS")
		)
		(fp_line
			(start 0.7874 -0.4064)
			(end 0.7874 0.4064)
			(stroke
				(width 0.1524)
				(type default)
			)
			(layer "F.SilkS")
		)
		(fp_line
			(start -0.7874 0.4064)
			(end -0.7874 -0.4064)
			(stroke
				(width 0.1524)
				(type default)
			)
			(layer "F.SilkS")
		)
		(fp_line
			(start -0.7874 -0.4064)
			(end 0.7874 -0.4064)
			(stroke
				(width 0.1524)
				(type default)
			)
			(layer "F.SilkS")
		)
		(fp_line
			(start 0.67945 0.3048)
			(end 0.120396 0.3048)
			(stroke
				(width 0.1)
				(type default)
			)
			(layer "F.Fab")
		)
		(fp_line
			(start 0.67945 -0.3048)
			(end 0.67945 0.3048)
			(stroke
				(width 0.1)
				(type default)
			)
			(layer "F.Fab")
		)
		(fp_line
			(start 0.12065 -0.2794)
			(end 0.12065 -0.3048)
			(stroke
				(width 0.1)
				(type default)
			)
			(layer "F.Fab")
		)
		(fp_line
			(start 0.12065 -0.3048)
			(end 0.67945 -0.3048)
			(stroke
				(width 0.1)
				(type default)
			)
			(layer "F.Fab")
		)
		(fp_line
			(start 0.120396 0.3048)
			(end 0.120396 0.2794)
			(stroke
				(width 0.1)
				(type default)
			)
			(layer "F.Fab")
		)
		(fp_line
			(start 0.120396 0.2794)
			(end -0.12065 0.2794)
			(stroke
				(width 0.1)
				(type default)
			)
			(layer "F.Fab")
		)
		(fp_line
			(start -0.12065 0.3048)
			(end -0.67945 0.3048)
			(stroke
				(width 0.1)
				(type default)
			)
			(layer "F.Fab")
		)
		(fp_line
			(start -0.12065 0.2794)
			(end -0.12065 0.3048)
			(stroke
				(width 0.1)
				(type default)
			)
			(layer "F.Fab")
		)
		(fp_line
			(start -0.12065 -0.2794)
			(end 0.12065 -0.2794)
			(stroke
				(width 0.1)
				(type default)
			)
			(layer "F.Fab")
		)
		(fp_line
			(start -0.12065 -0.305054)
			(end -0.12065 -0.2794)
			(stroke
				(width 0.1)
				(type default)
			)
			(layer "F.Fab")
		)
		(fp_line
			(start -0.67945 0.3048)
			(end -0.67945 -0.305054)
			(stroke
				(width 0.1)
				(type default)
			)
			(layer "F.Fab")
		)
		(fp_line
			(start -0.67945 -0.305054)
			(end -0.12065 -0.305054)
			(stroke
				(width 0.1)
				(type default)
			)
			(layer "F.Fab")
		)
		(pad "1" smd circle
			(at -0.40005 0 180)
			(size 0 0)
			(layers "F.Cu" "F.Mask" "F.Paste")
			(net "P3V3_AUX")
		)
		(pad "2" smd circle
			(at 0.40005 0 180)
			(size 0 0)
			(layers "F.Cu" "F.Mask" "F.Paste")
			(net "PWRGD_CHGL_CPU0")
		)
	)
	(footprint ""
		(layer "F.Cu")
		(at 299.767498 -15.62481 180)
		(property "Reference" "R4204"
			(at 0 0 180)
			(layer "F.SilkS")
			(hide yes)
			(effects
				(font
					(size 1.27 1.27)
				)
			)
		)
		(property "Value" ""
			(at 0 0 180)
			(layer "F.Fab")
			(effects
				(font
					(size 1.27 1.27)
				)
			)
		)
		(duplicate_pad_numbers_are_jumpers no)
		(fp_line
			(start 0.7874 0.4064)
			(end -0.7874 0.4064)
			(stroke
				(width 0.1524)
				(type default)
			)
			(layer "F.SilkS")
		)
		(fp_line
			(start 0.7874 -0.4064)
			(end 0.7874 0.4064)
			(stroke
				(width 0.1524)
				(type default)
			)
			(layer "F.SilkS")
		)
		(fp_line
			(start -0.7874 0.4064)
			(end -0.7874 -0.4064)
			(stroke
				(width 0.1524)
				(type default)
			)
			(layer "F.SilkS")
		)
		(fp_line
			(start -0.7874 -0.4064)
			(end 0.7874 -0.4064)
			(stroke
				(width 0.1524)
				(type default)
			)
			(layer "F.SilkS")
		)
		(fp_line
			(start 0.67945 0.3048)
			(end 0.120396 0.3048)
			(stroke
				(width 0.1)
				(type default)
			)
			(layer "F.Fab")
		)
		(fp_line
			(start 0.67945 -0.3048)
			(end 0.67945 0.3048)
			(stroke
				(width 0.1)
				(type default)
			)
			(layer "F.Fab")
		)
		(fp_line
			(start 0.12065 -0.2794)
			(end 0.12065 -0.3048)
			(stroke
				(width 0.1)
				(type default)
			)
			(layer "F.Fab")
		)
		(fp_line
			(start 0.12065 -0.3048)
			(end 0.67945 -0.3048)
			(stroke
				(width 0.1)
				(type default)
			)
			(layer "F.Fab")
		)
		(fp_line
			(start 0.120396 0.3048)
			(end 0.120396 0.2794)
			(stroke
				(width 0.1)
				(type default)
			)
			(layer "F.Fab")
		)
		(fp_line
			(start 0.120396 0.2794)
			(end -0.12065 0.2794)
			(stroke
				(width 0.1)
				(type default)
			)
			(layer "F.Fab")
		)
		(fp_line
			(start -0.12065 0.3048)
			(end -0.67945 0.3048)
			(stroke
				(width 0.1)
				(type default)
			)
			(layer "F.Fab")
		)
		(fp_line
			(start -0.12065 0.2794)
			(end -0.12065 0.3048)
			(stroke
				(width 0.1)
				(type default)
			)
			(layer "F.Fab")
		)
		(fp_line
			(start -0.12065 -0.2794)
			(end 0.12065 -0.2794)
			(stroke
				(width 0.1)
				(type default)
			)
			(layer "F.Fab")
		)
		(fp_line
			(start -0.12065 -0.305054)
			(end -0.12065 -0.2794)
			(stroke
				(width 0.1)
				(type default)
			)
			(layer "F.Fab")
		)
		(fp_line
			(start -0.67945 0.3048)
			(end -0.67945 -0.305054)
			(stroke
				(width 0.1)
				(type default)
			)
			(layer "F.Fab")
		)
		(fp_line
			(start -0.67945 -0.305054)
			(end -0.12065 -0.305054)
			(stroke
				(width 0.1)
				(type default)
			)
			(layer "F.Fab")
		)
		(pad "1" smd circle
			(at -0.40005 0 180)
			(size 0 0)
			(layers "F.Cu" "F.Mask" "F.Paste")
			(net "P3V3_AUX")
		)
		(pad "2" smd circle
			(at 0.40005 0 180)
			(size 0 0)
			(layers "F.Cu" "F.Mask" "F.Paste")
			(net "U271_1_ADD0")
		)
	)
	(footprint ""
		(layer "F.Cu")
		(at 72.6948 -385.5212 90)
		(property "Reference" "R6714"
			(at 0 0 90)
			(layer "F.SilkS")
			(hide yes)
			(effects
				(font
					(size 1.27 1.27)
				)
			)
		)
		(property "Value" ""
			(at 0 0 90)
			(layer "F.Fab")
			(effects
				(font
					(size 1.27 1.27)
				)
			)
		)
		(duplicate_pad_numbers_are_jumpers no)
		(fp_line
			(start 0.32512 -0.175006)
			(end 0.32512 0.175006)
			(stroke
				(width 0.1)
				(type default)
			)
			(layer "F.Fab")
		)
		(fp_line
			(start -0.32512 -0.175006)
			(end 0.32512 -0.175006)
			(stroke
				(width 0.1)
				(type default)
			)
			(layer "F.Fab")
		)
		(fp_line
			(start 0.32512 0.175006)
			(end -0.32512 0.175006)
			(stroke
				(width 0.1)
				(type default)
			)
			(layer "F.Fab")
		)
		(fp_line
			(start -0.32512 0.175006)
			(end -0.32512 -0.175006)
			(stroke
				(width 0.1)
				(type default)
			)
			(layer "F.Fab")
		)
		(pad "1" smd rect
			(at -0.2667 0 90)
			(size 0.3048 0.381)
			(layers "F.Cu" "F.Mask" "F.Paste")
			(net "P1V8_CPU1_RT_1D")
		)
		(pad "2" smd rect
			(at 0.2667 0 270)
			(size 0.3048 0.381)
			(layers "F.Cu" "F.Mask" "F.Paste")
			(net "RT_CPU1_P0_ADDR2")
		)
	)
	(footprint ""
		(layer "F.Cu")
		(at 384.113278 -138.170158)
		(property "Reference" "PR599"
			(at 0 0 0)
			(layer "F.SilkS")
			(hide yes)
			(effects
				(font
					(size 1.27 1.27)
				)
			)
		)
		(property "Value" ""
			(at 0 0 0)
			(layer "F.Fab")
			(effects
				(font
					(size 1.27 1.27)
				)
			)
		)
		(duplicate_pad_numbers_are_jumpers no)
		(fp_line
			(start -0.7874 -0.4064)
			(end 0.7874 -0.4064)
			(stroke
				(width 0.1524)
				(type default)
			)
			(layer "F.SilkS")
		)
		(fp_line
			(start -0.7874 0.4064)
			(end -0.7874 -0.4064)
			(stroke
				(width 0.1524)
				(type default)
			)
			(layer "F.SilkS")
		)
		(fp_line
			(start 0.7874 -0.4064)
			(end 0.7874 0.4064)
			(stroke
				(width 0.1524)
				(type default)
			)
			(layer "F.SilkS")
		)
		(fp_line
			(start 0.7874 0.4064)
			(end -0.7874 0.4064)
			(stroke
				(width 0.1524)
				(type default)
			)
			(layer "F.SilkS")
		)
		(fp_line
			(start -0.67945 -0.305054)
			(end -0.12065 -0.305054)
			(stroke
				(width 0.1)
				(type default)
			)
			(layer "F.Fab")
		)
		(fp_line
			(start -0.67945 0.3048)
			(end -0.67945 -0.305054)
			(stroke
				(width 0.1)
				(type default)
			)
			(layer "F.Fab")
		)
		(fp_line
			(start -0.12065 -0.305054)
			(end -0.12065 -0.2794)
			(stroke
				(width 0.1)
				(type default)
			)
			(layer "F.Fab")
		)
		(fp_line
			(start -0.12065 -0.2794)
			(end 0.12065 -0.2794)
			(stroke
				(width 0.1)
				(type default)
			)
			(layer "F.Fab")
		)
		(fp_line
			(start -0.12065 0.2794)
			(end -0.12065 0.3048)
			(stroke
				(width 0.1)
				(type default)
			)
			(layer "F.Fab")
		)
		(fp_line
			(start -0.12065 0.3048)
			(end -0.67945 0.3048)
			(stroke
				(width 0.1)
				(type default)
			)
			(layer "F.Fab")
		)
		(fp_line
			(start 0.120396 0.2794)
			(end -0.12065 0.2794)
			(stroke
				(width 0.1)
				(type default)
			)
			(layer "F.Fab")
		)
		(fp_line
			(start 0.120396 0.3048)
			(end 0.120396 0.2794)
			(stroke
				(width 0.1)
				(type default)
			)
			(layer "F.Fab")
		)
		(fp_line
			(start 0.12065 -0.3048)
			(end 0.67945 -0.3048)
			(stroke
				(width 0.1)
				(type default)
			)
			(layer "F.Fab")
		)
		(fp_line
			(start 0.12065 -0.2794)
			(end 0.12065 -0.3048)
			(stroke
				(width 0.1)
				(type default)
			)
			(layer "F.Fab")
		)
		(fp_line
			(start 0.67945 -0.3048)
			(end 0.67945 0.3048)
			(stroke
				(width 0.1)
				(type default)
			)
			(layer "F.Fab")
		)
		(fp_line
			(start 0.67945 0.3048)
			(end 0.120396 0.3048)
			(stroke
				(width 0.1)
				(type default)
			)
			(layer "F.Fab")
		)
		(pad "1" smd circle
			(at -0.40005 0)
			(size 0 0)
			(layers "F.Cu" "F.Mask" "F.Paste")
			(net "PVDDCR_CPU0_P0_VINSEN")
		)
		(pad "2" smd circle
			(at 0.40005 0)
			(size 0 0)
			(layers "F.Cu" "F.Mask" "F.Paste")
			(net "GND")
		)
	)
	(footprint ""
		(layer "F.Cu")
		(at 399.53184 -381.41783 -90)
		(property "Reference" "C864"
			(at 0 0 270)
			(layer "F.SilkS")
			(hide yes)
			(effects
				(font
					(size 1.27 1.27)
				)
			)
		)
		(property "Value" ""
			(at 0 0 270)
			(layer "F.Fab")
			(effects
				(font
					(size 1.27 1.27)
				)
			)
		)
		(duplicate_pad_numbers_are_jumpers no)
		(fp_line
			(start -0.299974 0.150114)
			(end -0.299974 -0.150114)
			(stroke
				(width 0.1)
				(type default)
			)
			(layer "F.Fab")
		)
		(fp_line
			(start 0.299974 0.150114)
			(end -0.299974 0.150114)
			(stroke
				(width 0.1)
				(type default)
			)
			(layer "F.Fab")
		)
		(fp_line
			(start -0.299974 -0.150114)
			(end 0.299974 -0.150114)
			(stroke
				(width 0.1)
				(type default)
			)
			(layer "F.Fab")
		)
		(fp_line
			(start 0.299974 -0.150114)
			(end 0.299974 0.150114)
			(stroke
				(width 0.1)
				(type default)
			)
			(layer "F.Fab")
		)
		(pad "1" smd rect
			(at -0.2667 0 270)
			(size 0.3048 0.381)
			(layers "F.Cu" "F.Mask" "F.Paste")
			(net "P5E_CPU0_P2_TX_C_DN<2>")
		)
		(pad "2" smd rect
			(at 0.2667 0 270)
			(size 0.3048 0.381)
			(layers "F.Cu" "F.Mask" "F.Paste")
			(net "P5E_CPU0_P2_TX_DN<2>")
		)
	)
	(footprint ""
		(layer "F.Cu")
		(at 336.68462 -15.924276 90)
		(property "Reference" "D9"
			(at -2.94894 0.009652 90)
			(unlocked yes)
			(layer "F.SilkS")
			(effects
				(font
					(size 0.7874 0.5842)
					(thickness 0.1524)
				)
				(justify left)
			)
		)
		(property "Value" ""
			(at 0 0 90)
			(layer "F.Fab")
			(effects
				(font
					(size 1.27 1.27)
				)
			)
		)
		(duplicate_pad_numbers_are_jumpers no)
		(fp_line
			(start 1.16078 -0.4826)
			(end 1.16078 0.4826)
			(stroke
				(width 0.1524)
				(type default)
			)
			(layer "F.SilkS")
		)
		(fp_line
			(start 1.03378 -0.4826)
			(end 1.03378 0.4826)
			(stroke
				(width 0.1524)
				(type default)
			)
			(layer "F.SilkS")
		)
		(fp_line
			(start 0.90678 -0.4826)
			(end 0.90678 0.4826)
			(stroke
				(width 0.1524)
				(type default)
			)
			(layer "F.SilkS")
		)
		(fp_line
			(start -0.64008 -0.4826)
			(end 1.16078 -0.4826)
			(stroke
				(width 0.1524)
				(type default)
			)
			(layer "F.SilkS")
		)
		(fp_line
			(start -0.79248 -0.4826)
			(end 1.03378 -0.4826)
			(stroke
				(width 0.1524)
				(type default)
			)
			(layer "F.SilkS")
		)
		(fp_line
			(start -0.89408 -0.4826)
			(end 0.90678 -0.4826)
			(stroke
				(width 0.1524)
				(type default)
			)
			(layer "F.SilkS")
		)
		(fp_line
			(start 1.16078 0.4826)
			(end -0.64008 0.4826)
			(stroke
				(width 0.1524)
				(type default)
			)
			(layer "F.SilkS")
		)
		(fp_line
			(start 1.03378 0.4826)
			(end -0.79248 0.4826)
			(stroke
				(width 0.1524)
				(type default)
			)
			(layer "F.SilkS")
		)
		(fp_line
			(start 0.90678 0.4826)
			(end -0.90678 0.4826)
			(stroke
				(width 0.1524)
				(type default)
			)
			(layer "F.SilkS")
		)
		(fp_line
			(start -0.90678 0.4826)
			(end -0.90678 -0.4699)
			(stroke
				(width 0.1524)
				(type default)
			)
			(layer "F.SilkS")
		)
		(fp_line
			(start 0.499872 -0.249936)
			(end 0.499872 0.249936)
			(stroke
				(width 0.1)
				(type default)
			)
			(layer "F.Fab")
		)
		(fp_line
			(start -0.499872 -0.249936)
			(end 0.499872 -0.249936)
			(stroke
				(width 0.1)
				(type default)
			)
			(layer "F.Fab")
		)
		(fp_line
			(start 0.499872 0.249936)
			(end -0.499872 0.249936)
			(stroke
				(width 0.1)
				(type default)
			)
			(layer "F.Fab")
		)
		(fp_line
			(start -0.499872 0.249936)
			(end -0.499872 -0.249936)
			(stroke
				(width 0.1)
				(type default)
			)
			(layer "F.Fab")
		)
		(pad "A" smd rect
			(at -0.47498 0 90)
			(size 0.6096 0.7112)
			(layers "F.Cu" "F.Mask" "F.Paste")
			(net "LED_BIOS_DBG_MODE_R")
		)
		(pad "C" smd rect
			(at 0.47498 0 90)
			(size 0.6096 0.7112)
			(layers "F.Cu" "F.Mask" "F.Paste")
			(net "LED_BIOS_DBG_MODE")
		)
	)
	(footprint ""
		(layer "F.Cu")
		(at 226.0981 -401.988782 180)
		(property "Reference" "PR3991"
			(at 0 0 180)
			(layer "F.SilkS")
			(hide yes)
			(effects
				(font
					(size 1.27 1.27)
				)
			)
		)
		(property "Value" ""
			(at 0 0 180)
			(layer "F.Fab")
			(effects
				(font
					(size 1.27 1.27)
				)
			)
		)
		(duplicate_pad_numbers_are_jumpers no)
		(fp_line
			(start 0.7874 0.4064)
			(end -0.7874 0.4064)
			(stroke
				(width 0.1524)
				(type default)
			)
			(layer "F.SilkS")
		)
		(fp_line
			(start 0.7874 -0.4064)
			(end 0.7874 0.4064)
			(stroke
				(width 0.1524)
				(type default)
			)
			(layer "F.SilkS")
		)
		(fp_line
			(start -0.7874 0.4064)
			(end -0.7874 -0.4064)
			(stroke
				(width 0.1524)
				(type default)
			)
			(layer "F.SilkS")
		)
		(fp_line
			(start -0.7874 -0.4064)
			(end 0.7874 -0.4064)
			(stroke
				(width 0.1524)
				(type default)
			)
			(layer "F.SilkS")
		)
		(fp_line
			(start 0.67945 0.3048)
			(end 0.120396 0.3048)
			(stroke
				(width 0.1)
				(type default)
			)
			(layer "F.Fab")
		)
		(fp_line
			(start 0.67945 -0.3048)
			(end 0.67945 0.3048)
			(stroke
				(width 0.1)
				(type default)
			)
			(layer "F.Fab")
		)
		(fp_line
			(start 0.12065 -0.2794)
			(end 0.12065 -0.3048)
			(stroke
				(width 0.1)
				(type default)
			)
			(layer "F.Fab")
		)
		(fp_line
			(start 0.12065 -0.3048)
			(end 0.67945 -0.3048)
			(stroke
				(width 0.1)
				(type default)
			)
			(layer "F.Fab")
		)
		(fp_line
			(start 0.120396 0.3048)
			(end 0.120396 0.2794)
			(stroke
				(width 0.1)
				(type default)
			)
			(layer "F.Fab")
		)
		(fp_line
			(start 0.120396 0.2794)
			(end -0.12065 0.2794)
			(stroke
				(width 0.1)
				(type default)
			)
			(layer "F.Fab")
		)
		(fp_line
			(start -0.12065 0.3048)
			(end -0.67945 0.3048)
			(stroke
				(width 0.1)
				(type default)
			)
			(layer "F.Fab")
		)
		(fp_line
			(start -0.12065 0.2794)
			(end -0.12065 0.3048)
			(stroke
				(width 0.1)
				(type default)
			)
			(layer "F.Fab")
		)
		(fp_line
			(start -0.12065 -0.2794)
			(end 0.12065 -0.2794)
			(stroke
				(width 0.1)
				(type default)
			)
			(layer "F.Fab")
		)
		(fp_line
			(start -0.12065 -0.305054)
			(end -0.12065 -0.2794)
			(stroke
				(width 0.1)
				(type default)
			)
			(layer "F.Fab")
		)
		(fp_line
			(start -0.67945 0.3048)
			(end -0.67945 -0.305054)
			(stroke
				(width 0.1)
				(type default)
			)
			(layer "F.Fab")
		)
		(fp_line
			(start -0.67945 -0.305054)
			(end -0.12065 -0.305054)
			(stroke
				(width 0.1)
				(type default)
			)
			(layer "F.Fab")
		)
		(pad "1" smd circle
			(at -0.40005 0 180)
			(size 0 0)
			(layers "F.Cu" "F.Mask" "F.Paste")
			(net "HSC_IMON")
		)
		(pad "2" smd circle
			(at 0.40005 0 180)
			(size 0 0)
			(layers "F.Cu" "F.Mask" "F.Paste")
			(net "AGND_HSC")
		)
	)
	(footprint ""
		(layer "F.Cu")
		(at 315.341 -357.251 180)
		(property "Reference" "PC71"
			(at 0 0 180)
			(layer "F.SilkS")
			(hide yes)
			(effects
				(font
					(size 1.27 1.27)
				)
			)
		)
		(property "Value" ""
			(at 0 0 180)
			(layer "F.Fab")
			(effects
				(font
					(size 1.27 1.27)
				)
			)
		)
		(duplicate_pad_numbers_are_jumpers no)
		(fp_line
			(start 0.7874 0.4064)
			(end -0.7874 0.4064)
			(stroke
				(width 0.1524)
				(type default)
			)
			(layer "F.SilkS")
		)
		(fp_line
			(start 0.7874 -0.4064)
			(end 0.7874 0.4064)
			(stroke
				(width 0.1524)
				(type default)
			)
			(layer "F.SilkS")
		)
		(fp_line
			(start -0.7874 0.4064)
			(end -0.7874 -0.4064)
			(stroke
				(width 0.1524)
				(type default)
			)
			(layer "F.SilkS")
		)
		(fp_line
			(start -0.7874 -0.4064)
			(end 0.7874 -0.4064)
			(stroke
				(width 0.1524)
				(type default)
			)
			(layer "F.SilkS")
		)
		(fp_line
			(start 0.67945 0.3048)
			(end 0.120396 0.3048)
			(stroke
				(width 0.1)
				(type default)
			)
			(layer "F.Fab")
		)
		(fp_line
			(start 0.67945 -0.3048)
			(end 0.67945 0.3048)
			(stroke
				(width 0.1)
				(type default)
			)
			(layer "F.Fab")
		)
		(fp_line
			(start 0.12065 -0.2794)
			(end 0.12065 -0.3048)
			(stroke
				(width 0.1)
				(type default)
			)
			(layer "F.Fab")
		)
		(fp_line
			(start 0.12065 -0.3048)
			(end 0.67945 -0.3048)
			(stroke
				(width 0.1)
				(type default)
			)
			(layer "F.Fab")
		)
		(fp_line
			(start 0.120396 0.3048)
			(end 0.120396 0.2794)
			(stroke
				(width 0.1)
				(type default)
			)
			(layer "F.Fab")
		)
		(fp_line
			(start 0.120396 0.2794)
			(end -0.12065 0.2794)
			(stroke
				(width 0.1)
				(type default)
			)
			(layer "F.Fab")
		)
		(fp_line
			(start -0.12065 0.3048)
			(end -0.67945 0.3048)
			(stroke
				(width 0.1)
				(type default)
			)
			(layer "F.Fab")
		)
		(fp_line
			(start -0.12065 0.2794)
			(end -0.12065 0.3048)
			(stroke
				(width 0.1)
				(type default)
			)
			(layer "F.Fab")
		)
		(fp_line
			(start -0.12065 -0.2794)
			(end 0.12065 -0.2794)
			(stroke
				(width 0.1)
				(type default)
			)
			(layer "F.Fab")
		)
		(fp_line
			(start -0.12065 -0.305054)
			(end -0.12065 -0.2794)
			(stroke
				(width 0.1)
				(type default)
			)
			(layer "F.Fab")
		)
		(fp_line
			(start -0.67945 0.3048)
			(end -0.67945 -0.305054)
			(stroke
				(width 0.1)
				(type default)
			)
			(layer "F.Fab")
		)
		(fp_line
			(start -0.67945 -0.305054)
			(end -0.12065 -0.305054)
			(stroke
				(width 0.1)
				(type default)
			)
			(layer "F.Fab")
		)
		(pad "1" smd circle
			(at -0.40005 0 180)
			(size 0 0)
			(layers "F.Cu" "F.Mask" "F.Paste")
			(net "VSENSE_PVDDIO_P0_VSEN1")
		)
		(pad "2" smd circle
			(at 0.40005 0 180)
			(size 0 0)
			(layers "F.Cu" "F.Mask" "F.Paste")
			(net "VSENSE_VSS_SENSE_B_P0")
		)
	)
	(footprint ""
		(layer "F.Cu")
		(at 90.209878 -143.86941)
		(property "Reference" "R8184"
			(at 0 0 0)
			(layer "F.SilkS")
			(hide yes)
			(effects
				(font
					(size 1.27 1.27)
				)
			)
		)
		(property "Value" ""
			(at 0 0 0)
			(layer "F.Fab")
			(effects
				(font
					(size 1.27 1.27)
				)
			)
		)
		(duplicate_pad_numbers_are_jumpers no)
		(fp_line
			(start -0.7874 -0.4064)
			(end 0.7874 -0.4064)
			(stroke
				(width 0.1524)
				(type default)
			)
			(layer "F.SilkS")
		)
		(fp_line
			(start -0.7874 0.4064)
			(end -0.7874 -0.4064)
			(stroke
				(width 0.1524)
				(type default)
			)
			(layer "F.SilkS")
		)
		(fp_line
			(start 0.7874 -0.4064)
			(end 0.7874 0.4064)
			(stroke
				(width 0.1524)
				(type default)
			)
			(layer "F.SilkS")
		)
		(fp_line
			(start 0.7874 0.4064)
			(end -0.7874 0.4064)
			(stroke
				(width 0.1524)
				(type default)
			)
			(layer "F.SilkS")
		)
		(fp_line
			(start -0.67945 -0.305054)
			(end -0.12065 -0.305054)
			(stroke
				(width 0.1)
				(type default)
			)
			(layer "F.Fab")
		)
		(fp_line
			(start -0.67945 0.3048)
			(end -0.67945 -0.305054)
			(stroke
				(width 0.1)
				(type default)
			)
			(layer "F.Fab")
		)
		(fp_line
			(start -0.12065 -0.305054)
			(end -0.12065 -0.2794)
			(stroke
				(width 0.1)
				(type default)
			)
			(layer "F.Fab")
		)
		(fp_line
			(start -0.12065 -0.2794)
			(end 0.12065 -0.2794)
			(stroke
				(width 0.1)
				(type default)
			)
			(layer "F.Fab")
		)
		(fp_line
			(start -0.12065 0.2794)
			(end -0.12065 0.3048)
			(stroke
				(width 0.1)
				(type default)
			)
			(layer "F.Fab")
		)
		(fp_line
			(start -0.12065 0.3048)
			(end -0.67945 0.3048)
			(stroke
				(width 0.1)
				(type default)
			)
			(layer "F.Fab")
		)
		(fp_line
			(start 0.120396 0.2794)
			(end -0.12065 0.2794)
			(stroke
				(width 0.1)
				(type default)
			)
			(layer "F.Fab")
		)
		(fp_line
			(start 0.120396 0.3048)
			(end 0.120396 0.2794)
			(stroke
				(width 0.1)
				(type default)
			)
			(layer "F.Fab")
		)
		(fp_line
			(start 0.12065 -0.3048)
			(end 0.67945 -0.3048)
			(stroke
				(width 0.1)
				(type default)
			)
			(layer "F.Fab")
		)
		(fp_line
			(start 0.12065 -0.2794)
			(end 0.12065 -0.3048)
			(stroke
				(width 0.1)
				(type default)
			)
			(layer "F.Fab")
		)
		(fp_line
			(start 0.67945 -0.3048)
			(end 0.67945 0.3048)
			(stroke
				(width 0.1)
				(type default)
			)
			(layer "F.Fab")
		)
		(fp_line
			(start 0.67945 0.3048)
			(end 0.120396 0.3048)
			(stroke
				(width 0.1)
				(type default)
			)
			(layer "F.Fab")
		)
		(pad "1" smd circle
			(at -0.40005 0)
			(size 0 0)
			(layers "F.Cu" "F.Mask" "F.Paste")
			(net "PVDD18_S5_P1")
		)
		(pad "2" smd circle
			(at 0.40005 0)
			(size 0 0)
			(layers "F.Cu" "F.Mask" "F.Paste")
			(net "PVDDCR_CPU0_P1_RESET_N_R")
		)
	)
	(footprint ""
		(layer "F.Cu")
		(at 18.702782 -137.976102)
		(property "Reference" "R3338"
			(at 0 0 0)
			(layer "F.SilkS")
			(hide yes)
			(effects
				(font
					(size 1.27 1.27)
				)
			)
		)
		(property "Value" ""
			(at 0 0 0)
			(layer "F.Fab")
			(effects
				(font
					(size 1.27 1.27)
				)
			)
		)
		(duplicate_pad_numbers_are_jumpers no)
		(fp_line
			(start -0.7874 -0.4064)
			(end 0.7874 -0.4064)
			(stroke
				(width 0.1524)
				(type default)
			)
			(layer "F.SilkS")
		)
		(fp_line
			(start -0.7874 0.4064)
			(end -0.7874 -0.4064)
			(stroke
				(width 0.1524)
				(type default)
			)
			(layer "F.SilkS")
		)
		(fp_line
			(start 0.7874 -0.4064)
			(end 0.7874 0.4064)
			(stroke
				(width 0.1524)
				(type default)
			)
			(layer "F.SilkS")
		)
		(fp_line
			(start 0.7874 0.4064)
			(end -0.7874 0.4064)
			(stroke
				(width 0.1524)
				(type default)
			)
			(layer "F.SilkS")
		)
		(fp_line
			(start -0.67945 -0.305054)
			(end -0.12065 -0.305054)
			(stroke
				(width 0.1)
				(type default)
			)
			(layer "F.Fab")
		)
		(fp_line
			(start -0.67945 0.3048)
			(end -0.67945 -0.305054)
			(stroke
				(width 0.1)
				(type default)
			)
			(layer "F.Fab")
		)
		(fp_line
			(start -0.12065 -0.305054)
			(end -0.12065 -0.2794)
			(stroke
				(width 0.1)
				(type default)
			)
			(layer "F.Fab")
		)
		(fp_line
			(start -0.12065 -0.2794)
			(end 0.12065 -0.2794)
			(stroke
				(width 0.1)
				(type default)
			)
			(layer "F.Fab")
		)
		(fp_line
			(start -0.12065 0.2794)
			(end -0.12065 0.3048)
			(stroke
				(width 0.1)
				(type default)
			)
			(layer "F.Fab")
		)
		(fp_line
			(start -0.12065 0.3048)
			(end -0.67945 0.3048)
			(stroke
				(width 0.1)
				(type default)
			)
			(layer "F.Fab")
		)
		(fp_line
			(start 0.120396 0.2794)
			(end -0.12065 0.2794)
			(stroke
				(width 0.1)
				(type default)
			)
			(layer "F.Fab")
		)
		(fp_line
			(start 0.120396 0.3048)
			(end 0.120396 0.2794)
			(stroke
				(width 0.1)
				(type default)
			)
			(layer "F.Fab")
		)
		(fp_line
			(start 0.12065 -0.3048)
			(end 0.67945 -0.3048)
			(stroke
				(width 0.1)
				(type default)
			)
			(layer "F.Fab")
		)
		(fp_line
			(start 0.12065 -0.2794)
			(end 0.12065 -0.3048)
			(stroke
				(width 0.1)
				(type default)
			)
			(layer "F.Fab")
		)
		(fp_line
			(start 0.67945 -0.3048)
			(end 0.67945 0.3048)
			(stroke
				(width 0.1)
				(type default)
			)
			(layer "F.Fab")
		)
		(fp_line
			(start 0.67945 0.3048)
			(end 0.120396 0.3048)
			(stroke
				(width 0.1)
				(type default)
			)
			(layer "F.Fab")
		)
		(pad "1" smd circle
			(at -0.40005 0)
			(size 0 0)
			(layers "F.Cu" "F.Mask" "F.Paste")
			(net "CLK_100M_GPU_FPGA_DN_R")
		)
		(pad "2" smd circle
			(at 0.40005 0)
			(size 0 0)
			(layers "F.Cu" "F.Mask" "F.Paste")
			(net "CLK_100M_GPU_FPGA_DN")
		)
	)
	(footprint ""
		(layer "F.Cu")
		(at 331.793342 -393.04468)
		(property "Reference" "R1029"
			(at 0 0 0)
			(layer "F.SilkS")
			(hide yes)
			(effects
				(font
					(size 1.27 1.27)
				)
			)
		)
		(property "Value" ""
			(at 0 0 0)
			(layer "F.Fab")
			(effects
				(font
					(size 1.27 1.27)
				)
			)
		)
		(duplicate_pad_numbers_are_jumpers no)
		(fp_line
			(start -0.32512 -0.175006)
			(end 0.32512 -0.175006)
			(stroke
				(width 0.1)
				(type default)
			)
			(layer "F.Fab")
		)
		(fp_line
			(start -0.32512 0.175006)
			(end -0.32512 -0.175006)
			(stroke
				(width 0.1)
				(type default)
			)
			(layer "F.Fab")
		)
		(fp_line
			(start 0.32512 -0.175006)
			(end 0.32512 0.175006)
			(stroke
				(width 0.1)
				(type default)
			)
			(layer "F.Fab")
		)
		(fp_line
			(start 0.32512 0.175006)
			(end -0.32512 0.175006)
			(stroke
				(width 0.1)
				(type default)
			)
			(layer "F.Fab")
		)
		(pad "1" smd rect
			(at -0.2667 0)
			(size 0.3048 0.381)
			(layers "F.Cu" "F.Mask" "F.Paste")
			(net "GPIO3_RT_CPU0_P1")
		)
		(pad "2" smd rect
			(at 0.2667 0 180)
			(size 0.3048 0.381)
			(layers "F.Cu" "F.Mask" "F.Paste")
			(net "GND")
		)
	)
	(footprint ""
		(layer "F.Cu")
		(at 142.155672 -386.951474)
		(property "Reference" "R620"
			(at 0 0 0)
			(layer "F.SilkS")
			(hide yes)
			(effects
				(font
					(size 1.27 1.27)
				)
			)
		)
		(property "Value" ""
			(at 0 0 0)
			(layer "F.Fab")
			(effects
				(font
					(size 1.27 1.27)
				)
			)
		)
		(duplicate_pad_numbers_are_jumpers no)
		(fp_line
			(start -0.32512 -0.175006)
			(end 0.32512 -0.175006)
			(stroke
				(width 0.1)
				(type default)
			)
			(layer "F.Fab")
		)
		(fp_line
			(start -0.32512 0.175006)
			(end -0.32512 -0.175006)
			(stroke
				(width 0.1)
				(type default)
			)
			(layer "F.Fab")
		)
		(fp_line
			(start 0.32512 -0.175006)
			(end 0.32512 0.175006)
			(stroke
				(width 0.1)
				(type default)
			)
			(layer "F.Fab")
		)
		(fp_line
			(start 0.32512 0.175006)
			(end -0.32512 0.175006)
			(stroke
				(width 0.1)
				(type default)
			)
			(layer "F.Fab")
		)
		(pad "1" smd rect
			(at -0.2667 0)
			(size 0.3048 0.381)
			(layers "F.Cu" "F.Mask" "F.Paste")
			(net "CLK_100M_RETIMER_CPU1_P2_R_DN")
		)
		(pad "2" smd rect
			(at 0.2667 0 180)
			(size 0.3048 0.381)
			(layers "F.Cu" "F.Mask" "F.Paste")
			(net "CLK_100M_RETIMER_CPU1_P2_DN")
		)
	)
	(footprint ""
		(layer "F.Cu")
		(at 403.72284 -383.88163 -90)
		(property "Reference" "C861"
			(at 0 0 270)
			(layer "F.SilkS")
			(hide yes)
			(effects
				(font
					(size 1.27 1.27)
				)
			)
		)
		(property "Value" ""
			(at 0 0 270)
			(layer "F.Fab")
			(effects
				(font
					(size 1.27 1.27)
				)
			)
		)
		(duplicate_pad_numbers_are_jumpers no)
		(fp_line
			(start -0.299974 0.150114)
			(end -0.299974 -0.150114)
			(stroke
				(width 0.1)
				(type default)
			)
			(layer "F.Fab")
		)
		(fp_line
			(start 0.299974 0.150114)
			(end -0.299974 0.150114)
			(stroke
				(width 0.1)
				(type default)
			)
			(layer "F.Fab")
		)
		(fp_line
			(start -0.299974 -0.150114)
			(end 0.299974 -0.150114)
			(stroke
				(width 0.1)
				(type default)
			)
			(layer "F.Fab")
		)
		(fp_line
			(start 0.299974 -0.150114)
			(end 0.299974 0.150114)
			(stroke
				(width 0.1)
				(type default)
			)
			(layer "F.Fab")
		)
		(pad "1" smd rect
			(at -0.2667 0 270)
			(size 0.3048 0.381)
			(layers "F.Cu" "F.Mask" "F.Paste")
			(net "P5E_CPU0_P2_TX_C_DP<4>")
		)
		(pad "2" smd rect
			(at 0.2667 0 270)
			(size 0.3048 0.381)
			(layers "F.Cu" "F.Mask" "F.Paste")
			(net "P5E_CPU0_P2_TX_DP<4>")
		)
	)
	(footprint ""
		(layer "F.Cu")
		(at 225.171762 -69.318378 -90)
		(property "Reference" "R3979"
			(at 0 0 270)
			(layer "F.SilkS")
			(hide yes)
			(effects
				(font
					(size 1.27 1.27)
				)
			)
		)
		(property "Value" ""
			(at 0 0 270)
			(layer "F.Fab")
			(effects
				(font
					(size 1.27 1.27)
				)
			)
		)
		(duplicate_pad_numbers_are_jumpers no)
		(fp_line
			(start -0.7874 0.4064)
			(end -0.7874 -0.4064)
			(stroke
				(width 0.1524)
				(type default)
			)
			(layer "F.SilkS")
		)
		(fp_line
			(start 0.7874 0.4064)
			(end -0.7874 0.4064)
			(stroke
				(width 0.1524)
				(type default)
			)
			(layer "F.SilkS")
		)
		(fp_line
			(start -0.7874 -0.4064)
			(end 0.7874 -0.4064)
			(stroke
				(width 0.1524)
				(type default)
			)
			(layer "F.SilkS")
		)
		(fp_line
			(start 0.7874 -0.4064)
			(end 0.7874 0.4064)
			(stroke
				(width 0.1524)
				(type default)
			)
			(layer "F.SilkS")
		)
		(fp_line
			(start -0.67945 0.3048)
			(end -0.67945 -0.305054)
			(stroke
				(width 0.1)
				(type default)
			)
			(layer "F.Fab")
		)
		(fp_line
			(start -0.12065 0.3048)
			(end -0.67945 0.3048)
			(stroke
				(width 0.1)
				(type default)
			)
			(layer "F.Fab")
		)
		(fp_line
			(start 0.120396 0.3048)
			(end 0.120396 0.2794)
			(stroke
				(width 0.1)
				(type default)
			)
			(layer "F.Fab")
		)
		(fp_line
			(start 0.67945 0.3048)
			(end 0.120396 0.3048)
			(stroke
				(width 0.1)
				(type default)
			)
			(layer "F.Fab")
		)
		(fp_line
			(start -0.12065 0.2794)
			(end -0.12065 0.3048)
			(stroke
				(width 0.1)
				(type default)
			)
			(layer "F.Fab")
		)
		(fp_line
			(start 0.120396 0.2794)
			(end -0.12065 0.2794)
			(stroke
				(width 0.1)
				(type default)
			)
			(layer "F.Fab")
		)
		(fp_line
			(start -0.12065 -0.2794)
			(end 0.12065 -0.2794)
			(stroke
				(width 0.1)
				(type default)
			)
			(layer "F.Fab")
		)
		(fp_line
			(start 0.12065 -0.2794)
			(end 0.12065 -0.3048)
			(stroke
				(width 0.1)
				(type default)
			)
			(layer "F.Fab")
		)
		(fp_line
			(start 0.12065 -0.3048)
			(end 0.67945 -0.3048)
			(stroke
				(width 0.1)
				(type default)
			)
			(layer "F.Fab")
		)
		(fp_line
			(start 0.67945 -0.3048)
			(end 0.67945 0.3048)
			(stroke
				(width 0.1)
				(type default)
			)
			(layer "F.Fab")
		)
		(fp_line
			(start -0.67945 -0.305054)
			(end -0.12065 -0.305054)
			(stroke
				(width 0.1)
				(type default)
			)
			(layer "F.Fab")
		)
		(fp_line
			(start -0.12065 -0.305054)
			(end -0.12065 -0.2794)
			(stroke
				(width 0.1)
				(type default)
			)
			(layer "F.Fab")
		)
		(pad "1" smd circle
			(at -0.40005 0 270)
			(size 0 0)
			(layers "F.Cu" "F.Mask" "F.Paste")
			(net "P3V3_AUX")
		)
		(pad "2" smd circle
			(at 0.40005 0 270)
			(size 0 0)
			(layers "F.Cu" "F.Mask" "F.Paste")
			(net "P3V3_E1S_PWRGD_0_R")
		)
	)
	(footprint ""
		(layer "F.Cu")
		(at 84.978494 -177.88636 -90)
		(property "Reference" "PC254_1"
			(at 0 0 270)
			(layer "F.SilkS")
			(hide yes)
			(effects
				(font
					(size 1.27 1.27)
				)
			)
		)
		(property "Value" ""
			(at 0 0 270)
			(layer "F.Fab")
			(effects
				(font
					(size 1.27 1.27)
				)
			)
		)
		(duplicate_pad_numbers_are_jumpers no)
		(fp_line
			(start -0.7874 0.4064)
			(end -0.7874 -0.4064)
			(stroke
				(width 0.1524)
				(type default)
			)
			(layer "F.SilkS")
		)
		(fp_line
			(start 0.7874 0.4064)
			(end -0.7874 0.4064)
			(stroke
				(width 0.1524)
				(type default)
			)
			(layer "F.SilkS")
		)
		(fp_line
			(start -0.7874 -0.4064)
			(end 0.7874 -0.4064)
			(stroke
				(width 0.1524)
				(type default)
			)
			(layer "F.SilkS")
		)
		(fp_line
			(start 0.7874 -0.4064)
			(end 0.7874 0.4064)
			(stroke
				(width 0.1524)
				(type default)
			)
			(layer "F.SilkS")
		)
		(fp_line
			(start -0.67945 0.3048)
			(end -0.67945 -0.305054)
			(stroke
				(width 0.1)
				(type default)
			)
			(layer "F.Fab")
		)
		(fp_line
			(start -0.12065 0.3048)
			(end -0.67945 0.3048)
			(stroke
				(width 0.1)
				(type default)
			)
			(layer "F.Fab")
		)
		(fp_line
			(start 0.120396 0.3048)
			(end 0.120396 0.2794)
			(stroke
				(width 0.1)
				(type default)
			)
			(layer "F.Fab")
		)
		(fp_line
			(start 0.67945 0.3048)
			(end 0.120396 0.3048)
			(stroke
				(width 0.1)
				(type default)
			)
			(layer "F.Fab")
		)
		(fp_line
			(start -0.12065 0.2794)
			(end -0.12065 0.3048)
			(stroke
				(width 0.1)
				(type default)
			)
			(layer "F.Fab")
		)
		(fp_line
			(start 0.120396 0.2794)
			(end -0.12065 0.2794)
			(stroke
				(width 0.1)
				(type default)
			)
			(layer "F.Fab")
		)
		(fp_line
			(start -0.12065 -0.2794)
			(end 0.12065 -0.2794)
			(stroke
				(width 0.1)
				(type default)
			)
			(layer "F.Fab")
		)
		(fp_line
			(start 0.12065 -0.2794)
			(end 0.12065 -0.3048)
			(stroke
				(width 0.1)
				(type default)
			)
			(layer "F.Fab")
		)
		(fp_line
			(start 0.12065 -0.3048)
			(end 0.67945 -0.3048)
			(stroke
				(width 0.1)
				(type default)
			)
			(layer "F.Fab")
		)
		(fp_line
			(start 0.67945 -0.3048)
			(end 0.67945 0.3048)
			(stroke
				(width 0.1)
				(type default)
			)
			(layer "F.Fab")
		)
		(fp_line
			(start -0.67945 -0.305054)
			(end -0.12065 -0.305054)
			(stroke
				(width 0.1)
				(type default)
			)
			(layer "F.Fab")
		)
		(fp_line
			(start -0.12065 -0.305054)
			(end -0.12065 -0.2794)
			(stroke
				(width 0.1)
				(type default)
			)
			(layer "F.Fab")
		)
		(pad "1" smd circle
			(at -0.40005 0 270)
			(size 0 0)
			(layers "F.Cu" "F.Mask" "F.Paste")
			(net "PVDDCR_CPU0_P1_VCCS")
		)
		(pad "2" smd circle
			(at 0.40005 0 270)
			(size 0 0)
			(layers "F.Cu" "F.Mask" "F.Paste")
			(net "GND")
		)
	)
	(footprint ""
		(layer "F.Cu")
		(at 433.756562 -355.743764 -90)
		(property "Reference" "PC218"
			(at 0 0 270)
			(layer "F.SilkS")
			(hide yes)
			(effects
				(font
					(size 1.27 1.27)
				)
			)
		)
		(property "Value" ""
			(at 0 0 270)
			(layer "F.Fab")
			(effects
				(font
					(size 1.27 1.27)
				)
			)
		)
		(duplicate_pad_numbers_are_jumpers no)
		(fp_line
			(start -0.7874 0.4064)
			(end -0.7874 -0.4064)
			(stroke
				(width 0.1524)
				(type default)
			)
			(layer "F.SilkS")
		)
		(fp_line
			(start 0.7874 0.4064)
			(end -0.7874 0.4064)
			(stroke
				(width 0.1524)
				(type default)
			)
			(layer "F.SilkS")
		)
		(fp_line
			(start -0.7874 -0.4064)
			(end 0.7874 -0.4064)
			(stroke
				(width 0.1524)
				(type default)
			)
			(layer "F.SilkS")
		)
		(fp_line
			(start 0.7874 -0.4064)
			(end 0.7874 0.4064)
			(stroke
				(width 0.1524)
				(type default)
			)
			(layer "F.SilkS")
		)
		(fp_line
			(start -0.67945 0.3048)
			(end -0.67945 -0.305054)
			(stroke
				(width 0.1)
				(type default)
			)
			(layer "F.Fab")
		)
		(fp_line
			(start -0.12065 0.3048)
			(end -0.67945 0.3048)
			(stroke
				(width 0.1)
				(type default)
			)
			(layer "F.Fab")
		)
		(fp_line
			(start 0.120396 0.3048)
			(end 0.120396 0.2794)
			(stroke
				(width 0.1)
				(type default)
			)
			(layer "F.Fab")
		)
		(fp_line
			(start 0.67945 0.3048)
			(end 0.120396 0.3048)
			(stroke
				(width 0.1)
				(type default)
			)
			(layer "F.Fab")
		)
		(fp_line
			(start -0.12065 0.2794)
			(end -0.12065 0.3048)
			(stroke
				(width 0.1)
				(type default)
			)
			(layer "F.Fab")
		)
		(fp_line
			(start 0.120396 0.2794)
			(end -0.12065 0.2794)
			(stroke
				(width 0.1)
				(type default)
			)
			(layer "F.Fab")
		)
		(fp_line
			(start -0.12065 -0.2794)
			(end 0.12065 -0.2794)
			(stroke
				(width 0.1)
				(type default)
			)
			(layer "F.Fab")
		)
		(fp_line
			(start 0.12065 -0.2794)
			(end 0.12065 -0.3048)
			(stroke
				(width 0.1)
				(type default)
			)
			(layer "F.Fab")
		)
		(fp_line
			(start 0.12065 -0.3048)
			(end 0.67945 -0.3048)
			(stroke
				(width 0.1)
				(type default)
			)
			(layer "F.Fab")
		)
		(fp_line
			(start 0.67945 -0.3048)
			(end 0.67945 0.3048)
			(stroke
				(width 0.1)
				(type default)
			)
			(layer "F.Fab")
		)
		(fp_line
			(start -0.67945 -0.305054)
			(end -0.12065 -0.305054)
			(stroke
				(width 0.1)
				(type default)
			)
			(layer "F.Fab")
		)
		(fp_line
			(start -0.12065 -0.305054)
			(end -0.12065 -0.2794)
			(stroke
				(width 0.1)
				(type default)
			)
			(layer "F.Fab")
		)
		(pad "1" smd circle
			(at -0.40005 0 270)
			(size 0 0)
			(layers "F.Cu" "F.Mask" "F.Paste")
			(net "SW_PVDD11_S3_P0_BOOT2_RC")
		)
		(pad "2" smd circle
			(at 0.40005 0 270)
			(size 0 0)
			(layers "F.Cu" "F.Mask" "F.Paste")
			(net "SW_PVDD11_S3_P0_PH2")
		)
	)
	(footprint ""
		(layer "F.Cu")
		(at 27.487626 -428.755302 180)
		(property "Reference" "R6158"
			(at 0 0 180)
			(layer "F.SilkS")
			(hide yes)
			(effects
				(font
					(size 1.27 1.27)
				)
			)
		)
		(property "Value" ""
			(at 0 0 180)
			(layer "F.Fab")
			(effects
				(font
					(size 1.27 1.27)
				)
			)
		)
		(duplicate_pad_numbers_are_jumpers no)
		(fp_line
			(start 0.32512 0.175006)
			(end -0.32512 0.175006)
			(stroke
				(width 0.1)
				(type default)
			)
			(layer "F.Fab")
		)
		(fp_line
			(start 0.32512 -0.175006)
			(end 0.32512 0.175006)
			(stroke
				(width 0.1)
				(type default)
			)
			(layer "F.Fab")
		)
		(fp_line
			(start -0.32512 0.175006)
			(end -0.32512 -0.175006)
			(stroke
				(width 0.1)
				(type default)
			)
			(layer "F.Fab")
		)
		(fp_line
			(start -0.32512 -0.175006)
			(end 0.32512 -0.175006)
			(stroke
				(width 0.1)
				(type default)
			)
			(layer "F.Fab")
		)
		(pad "1" smd rect
			(at -0.2667 0 180)
			(size 0.3048 0.381)
			(layers "F.Cu" "F.Mask" "F.Paste")
			(net "P2E_MB_BMC_RX_DP<0>")
		)
		(pad "2" smd rect
			(at 0.2667 0)
			(size 0.3048 0.381)
			(layers "F.Cu" "F.Mask" "F.Paste")
			(net "P2E_MB_BMC_RX_R2_DP<0>")
		)
	)
	(footprint ""
		(layer "F.Cu")
		(at 33.198054 -349.386398 90)
		(property "Reference" "PC617"
			(at 0 0 90)
			(layer "F.SilkS")
			(hide yes)
			(effects
				(font
					(size 1.27 1.27)
				)
			)
		)
		(property "Value" ""
			(at 0 0 90)
			(layer "F.Fab")
			(effects
				(font
					(size 1.27 1.27)
				)
			)
		)
		(duplicate_pad_numbers_are_jumpers no)
		(fp_line
			(start 0.7874 -0.4064)
			(end 0.7874 0.4064)
			(stroke
				(width 0.1524)
				(type default)
			)
			(layer "F.SilkS")
		)
		(fp_line
			(start -0.7874 -0.4064)
			(end 0.7874 -0.4064)
			(stroke
				(width 0.1524)
				(type default)
			)
			(layer "F.SilkS")
		)
		(fp_line
			(start 0.7874 0.4064)
			(end 0.447802 0.4064)
			(stroke
				(width 0.1524)
				(type default)
			)
			(layer "F.SilkS")
		)
		(fp_line
			(start -0.237998 0.4064)
			(end -0.7874 0.4064)
			(stroke
				(width 0.1524)
				(type default)
			)
			(layer "F.SilkS")
		)
		(fp_line
			(start -0.7874 0.4064)
			(end -0.7874 -0.4064)
			(stroke
				(width 0.1524)
				(type default)
			)
			(layer "F.SilkS")
		)
		(fp_line
			(start -0.12065 -0.305054)
			(end -0.12065 -0.2794)
			(stroke
				(width 0.1)
				(type default)
			)
			(layer "F.Fab")
		)
		(fp_line
			(start -0.67945 -0.305054)
			(end -0.12065 -0.305054)
			(stroke
				(width 0.1)
				(type default)
			)
			(layer "F.Fab")
		)
		(fp_line
			(start 0.67945 -0.3048)
			(end 0.67945 0.3048)
			(stroke
				(width 0.1)
				(type default)
			)
			(layer "F.Fab")
		)
		(fp_line
			(start 0.12065 -0.3048)
			(end 0.67945 -0.3048)
			(stroke
				(width 0.1)
				(type default)
			)
			(layer "F.Fab")
		)
		(fp_line
			(start 0.12065 -0.2794)
			(end 0.12065 -0.3048)
			(stroke
				(width 0.1)
				(type default)
			)
			(layer "F.Fab")
		)
		(fp_line
			(start -0.12065 -0.2794)
			(end 0.12065 -0.2794)
			(stroke
				(width 0.1)
				(type default)
			)
			(layer "F.Fab")
		)
		(fp_line
			(start 0.120396 0.2794)
			(end -0.12065 0.2794)
			(stroke
				(width 0.1)
				(type default)
			)
			(layer "F.Fab")
		)
		(fp_line
			(start -0.12065 0.2794)
			(end -0.12065 0.3048)
			(stroke
				(width 0.1)
				(type default)
			)
			(layer "F.Fab")
		)
		(fp_line
			(start 0.67945 0.3048)
			(end 0.120396 0.3048)
			(stroke
				(width 0.1)
				(type default)
			)
			(layer "F.Fab")
		)
		(fp_line
			(start 0.120396 0.3048)
			(end 0.120396 0.2794)
			(stroke
				(width 0.1)
				(type default)
			)
			(layer "F.Fab")
		)
		(fp_line
			(start -0.12065 0.3048)
			(end -0.67945 0.3048)
			(stroke
				(width 0.1)
				(type default)
			)
			(layer "F.Fab")
		)
		(fp_line
			(start -0.67945 0.3048)
			(end -0.67945 -0.305054)
			(stroke
				(width 0.1)
				(type default)
			)
			(layer "F.Fab")
		)
		(pad "1" smd circle
			(at -0.40005 0 90)
			(size 0 0)
			(layers "F.Cu" "F.Mask" "F.Paste")
			(net "PVDDIO_P1_VCC3")
		)
		(pad "2" smd circle
			(at 0.40005 0 90)
			(size 0 0)
			(layers "F.Cu" "F.Mask" "F.Paste")
			(net "GND")
		)
	)
	(footprint ""
		(layer "F.Cu")
		(at 18.828258 -427.580298 90)
		(property "Reference" "R6160"
			(at 0 0 90)
			(layer "F.SilkS")
			(hide yes)
			(effects
				(font
					(size 1.27 1.27)
				)
			)
		)
		(property "Value" ""
			(at 0 0 90)
			(layer "F.Fab")
			(effects
				(font
					(size 1.27 1.27)
				)
			)
		)
		(duplicate_pad_numbers_are_jumpers no)
		(fp_line
			(start 0.7874 -0.4064)
			(end 0.7874 0.4064)
			(stroke
				(width 0.1524)
				(type default)
			)
			(layer "F.SilkS")
		)
		(fp_line
			(start -0.7874 -0.4064)
			(end 0.7874 -0.4064)
			(stroke
				(width 0.1524)
				(type default)
			)
			(layer "F.SilkS")
		)
		(fp_line
			(start 0.7874 0.4064)
			(end -0.7874 0.4064)
			(stroke
				(width 0.1524)
				(type default)
			)
			(layer "F.SilkS")
		)
		(fp_line
			(start -0.7874 0.4064)
			(end -0.7874 -0.4064)
			(stroke
				(width 0.1524)
				(type default)
			)
			(layer "F.SilkS")
		)
		(fp_line
			(start -0.12065 -0.305054)
			(end -0.12065 -0.2794)
			(stroke
				(width 0.1)
				(type default)
			)
			(layer "F.Fab")
		)
		(fp_line
			(start -0.67945 -0.305054)
			(end -0.12065 -0.305054)
			(stroke
				(width 0.1)
				(type default)
			)
			(layer "F.Fab")
		)
		(fp_line
			(start 0.67945 -0.3048)
			(end 0.67945 0.3048)
			(stroke
				(width 0.1)
				(type default)
			)
			(layer "F.Fab")
		)
		(fp_line
			(start 0.12065 -0.3048)
			(end 0.67945 -0.3048)
			(stroke
				(width 0.1)
				(type default)
			)
			(layer "F.Fab")
		)
		(fp_line
			(start 0.12065 -0.2794)
			(end 0.12065 -0.3048)
			(stroke
				(width 0.1)
				(type default)
			)
			(layer "F.Fab")
		)
		(fp_line
			(start -0.12065 -0.2794)
			(end 0.12065 -0.2794)
			(stroke
				(width 0.1)
				(type default)
			)
			(layer "F.Fab")
		)
		(fp_line
			(start 0.120396 0.2794)
			(end -0.12065 0.2794)
			(stroke
				(width 0.1)
				(type default)
			)
			(layer "F.Fab")
		)
		(fp_line
			(start -0.12065 0.2794)
			(end -0.12065 0.3048)
			(stroke
				(width 0.1)
				(type default)
			)
			(layer "F.Fab")
		)
		(fp_line
			(start 0.67945 0.3048)
			(end 0.120396 0.3048)
			(stroke
				(width 0.1)
				(type default)
			)
			(layer "F.Fab")
		)
		(fp_line
			(start 0.120396 0.3048)
			(end 0.120396 0.2794)
			(stroke
				(width 0.1)
				(type default)
			)
			(layer "F.Fab")
		)
		(fp_line
			(start -0.12065 0.3048)
			(end -0.67945 0.3048)
			(stroke
				(width 0.1)
				(type default)
			)
			(layer "F.Fab")
		)
		(fp_line
			(start -0.67945 0.3048)
			(end -0.67945 -0.305054)
			(stroke
				(width 0.1)
				(type default)
			)
			(layer "F.Fab")
		)
		(pad "1" smd circle
			(at -0.40005 0 90)
			(size 0 0)
			(layers "F.Cu" "F.Mask" "F.Paste")
			(net "PD_P2E_BUF2_ENSMB")
		)
		(pad "2" smd circle
			(at 0.40005 0 90)
			(size 0 0)
			(layers "F.Cu" "F.Mask" "F.Paste")
			(net "GND")
		)
	)
	(footprint ""
		(layer "F.Cu")
		(at 122.952002 -78.732888 -90)
		(property "Reference" "PR6005"
			(at 0 0 270)
			(layer "F.SilkS")
			(hide yes)
			(effects
				(font
					(size 1.27 1.27)
				)
			)
		)
		(property "Value" ""
			(at 0 0 270)
			(layer "F.Fab")
			(effects
				(font
					(size 1.27 1.27)
				)
			)
		)
		(duplicate_pad_numbers_are_jumpers no)
		(fp_line
			(start -0.7874 0.4064)
			(end -0.7874 -0.4064)
			(stroke
				(width 0.1524)
				(type default)
			)
			(layer "F.SilkS")
		)
		(fp_line
			(start 0.7874 0.4064)
			(end -0.7874 0.4064)
			(stroke
				(width 0.1524)
				(type default)
			)
			(layer "F.SilkS")
		)
		(fp_line
			(start -0.7874 -0.4064)
			(end 0.7874 -0.4064)
			(stroke
				(width 0.1524)
				(type default)
			)
			(layer "F.SilkS")
		)
		(fp_line
			(start 0.7874 -0.4064)
			(end 0.7874 0.4064)
			(stroke
				(width 0.1524)
				(type default)
			)
			(layer "F.SilkS")
		)
		(fp_line
			(start -0.67945 0.3048)
			(end -0.67945 -0.305054)
			(stroke
				(width 0.1)
				(type default)
			)
			(layer "F.Fab")
		)
		(fp_line
			(start -0.12065 0.3048)
			(end -0.67945 0.3048)
			(stroke
				(width 0.1)
				(type default)
			)
			(layer "F.Fab")
		)
		(fp_line
			(start 0.120396 0.3048)
			(end 0.120396 0.2794)
			(stroke
				(width 0.1)
				(type default)
			)
			(layer "F.Fab")
		)
		(fp_line
			(start 0.67945 0.3048)
			(end 0.120396 0.3048)
			(stroke
				(width 0.1)
				(type default)
			)
			(layer "F.Fab")
		)
		(fp_line
			(start -0.12065 0.2794)
			(end -0.12065 0.3048)
			(stroke
				(width 0.1)
				(type default)
			)
			(layer "F.Fab")
		)
		(fp_line
			(start 0.120396 0.2794)
			(end -0.12065 0.2794)
			(stroke
				(width 0.1)
				(type default)
			)
			(layer "F.Fab")
		)
		(fp_line
			(start -0.12065 -0.2794)
			(end 0.12065 -0.2794)
			(stroke
				(width 0.1)
				(type default)
			)
			(layer "F.Fab")
		)
		(fp_line
			(start 0.12065 -0.2794)
			(end 0.12065 -0.3048)
			(stroke
				(width 0.1)
				(type default)
			)
			(layer "F.Fab")
		)
		(fp_line
			(start 0.12065 -0.3048)
			(end 0.67945 -0.3048)
			(stroke
				(width 0.1)
				(type default)
			)
			(layer "F.Fab")
		)
		(fp_line
			(start 0.67945 -0.3048)
			(end 0.67945 0.3048)
			(stroke
				(width 0.1)
				(type default)
			)
			(layer "F.Fab")
		)
		(fp_line
			(start -0.67945 -0.305054)
			(end -0.12065 -0.305054)
			(stroke
				(width 0.1)
				(type default)
			)
			(layer "F.Fab")
		)
		(fp_line
			(start -0.12065 -0.305054)
			(end -0.12065 -0.2794)
			(stroke
				(width 0.1)
				(type default)
			)
			(layer "F.Fab")
		)
		(pad "1" smd circle
			(at -0.40005 0 270)
			(size 0 0)
			(layers "F.Cu" "F.Mask" "F.Paste")
			(net "GND")
		)
		(pad "2" smd circle
			(at 0.40005 0 270)
			(size 0 0)
			(layers "F.Cu" "F.Mask" "F.Paste")
			(net "P1V2_AUX_MODE")
		)
	)
	(footprint ""
		(layer "F.Cu")
		(at 283.820362 -337.399122)
		(property "Reference" "PL21"
			(at -2.607056 -16.014446 0)
			(unlocked yes)
			(layer "F.SilkS")
			(effects
				(font
					(size 0.7874 0.5842)
					(thickness 0.1524)
				)
				(justify left)
			)
		)
		(property "Value" ""
			(at 0 0 0)
			(layer "F.Fab")
			(effects
				(font
					(size 1.27 1.27)
				)
			)
		)
		(duplicate_pad_numbers_are_jumpers no)
		(fp_line
			(start -3.750056 -5.500116)
			(end -2.393442 -5.500116)
			(stroke
				(width 0.1524)
				(type default)
			)
			(layer "F.SilkS")
		)
		(fp_line
			(start -3.750056 5.500116)
			(end -3.750056 -5.500116)
			(stroke
				(width 0.1524)
				(type default)
			)
			(layer "F.SilkS")
		)
		(fp_line
			(start -2.393442 5.500116)
			(end -3.750056 5.500116)
			(stroke
				(width 0.1524)
				(type default)
			)
			(layer "F.SilkS")
		)
		(fp_line
			(start 2.393442 5.500116)
			(end 3.750056 5.500116)
			(stroke
				(width 0.1524)
				(type default)
			)
			(layer "F.SilkS")
		)
		(fp_line
			(start 3.750056 -5.500116)
			(end 2.393442 -5.500116)
			(stroke
				(width 0.1524)
				(type default)
			)
			(layer "F.SilkS")
		)
		(fp_line
			(start 3.750056 5.500116)
			(end 3.750056 -5.500116)
			(stroke
				(width 0.1524)
				(type default)
			)
			(layer "F.SilkS")
		)
		(fp_poly
			(pts
				(xy -3.9116 -4.249928) (xy -4.3434 -4.034028) (xy -4.3434 -4.465828)
			)
			(stroke
				(width 0)
				(type default)
			)
			(fill yes)
			(layer "F.SilkS")
		)
		(fp_line
			(start -3.750056 -5.500116)
			(end -3.750056 5.500116)
			(stroke
				(width 0.1)
				(type default)
			)
			(layer "F.Fab")
		)
		(fp_line
			(start -3.750056 5.500116)
			(end 3.750056 5.500116)
			(stroke
				(width 0.1)
				(type default)
			)
			(layer "F.Fab")
		)
		(fp_line
			(start 3.750056 -5.500116)
			(end -3.750056 -5.500116)
			(stroke
				(width 0.1)
				(type default)
			)
			(layer "F.Fab")
		)
		(fp_line
			(start 3.750056 5.500116)
			(end 3.750056 -5.500116)
			(stroke
				(width 0.1)
				(type default)
			)
			(layer "F.Fab")
		)
		(fp_poly
			(pts
				(xy -4.9276 -4.757928) (xy -4.9276 -3.741928) (xy -3.9116 -4.249928)
			)
			(stroke
				(width 0)
				(type default)
			)
			(fill yes)
			(layer "F.Fab")
		)
		(pad "1" smd rect
			(at 0 -4.249928 270)
			(size 2.413 4.5212)
			(layers "F.Cu" "F.Mask" "F.Paste")
			(net "SW_PVDDIO_P0_SW3")
		)
		(pad "2" smd rect
			(at 0 -1.175004 270)
			(size 1.3716 4.5212)
			(layers "F.Cu" "F.Mask" "F.Paste")
			(net "IND_PVDDIO_P0_CPL4")
		)
		(pad "3" smd rect
			(at 0 1.175004 270)
			(size 1.3716 4.5212)
			(layers "F.Cu" "F.Mask" "F.Paste")
			(net "IND_PVDDIO_P0_CPL3")
		)
		(pad "4" smd rect
			(at 0 4.249928 270)
			(size 2.413 4.5212)
			(layers "F.Cu" "F.Mask" "F.Paste")
			(net "PVDDIO_P0")
		)
	)
	(footprint ""
		(layer "F.Cu")
		(at 36.881054 -346.721176)
		(property "Reference" "PU52"
			(at -2.972054 -7.709154 0)
			(unlocked yes)
			(layer "F.SilkS")
			(effects
				(font
					(size 0.7874 0.5842)
					(thickness 0.1524)
				)
				(justify left)
			)
		)
		(property "Value" ""
			(at 0 0 0)
			(layer "F.Fab")
			(effects
				(font
					(size 1.27 1.27)
				)
			)
		)
		(duplicate_pad_numbers_are_jumpers no)
		(fp_line
			(start -2.500122 -2.999994)
			(end -2.24409 -2.999994)
			(stroke
				(width 0.1524)
				(type default)
			)
			(layer "F.SilkS")
		)
		(fp_line
			(start -2.500122 -2.529078)
			(end -2.500122 -2.999994)
			(stroke
				(width 0.1524)
				(type default)
			)
			(layer "F.SilkS")
		)
		(fp_line
			(start -2.500122 0.6604)
			(end -2.500122 0.229108)
			(stroke
				(width 0.1524)
				(type default)
			)
			(layer "F.SilkS")
		)
		(fp_line
			(start -2.500122 2.999994)
			(end -2.500122 2.339594)
			(stroke
				(width 0.1524)
				(type default)
			)
			(layer "F.SilkS")
		)
		(fp_line
			(start -2.2987 2.999994)
			(end -2.500122 2.999994)
			(stroke
				(width 0.1524)
				(type default)
			)
			(layer "F.SilkS")
		)
		(fp_line
			(start 2.31394 -2.999994)
			(end 2.500122 -2.999994)
			(stroke
				(width 0.1524)
				(type default)
			)
			(layer "F.SilkS")
		)
		(fp_line
			(start 2.500122 -2.999994)
			(end 2.500122 -2.44348)
			(stroke
				(width 0.1524)
				(type default)
			)
			(layer "F.SilkS")
		)
		(fp_line
			(start 2.500122 2.339594)
			(end 2.500122 2.999994)
			(stroke
				(width 0.1524)
				(type default)
			)
			(layer "F.SilkS")
		)
		(fp_line
			(start 2.500122 2.999994)
			(end 2.2987 2.999994)
			(stroke
				(width 0.1524)
				(type default)
			)
			(layer "F.SilkS")
		)
		(fp_poly
			(pts
				(xy -2.785872 -2.44094) (xy -3.45948 -2.665476) (xy -3.010408 -3.114548)
			)
			(stroke
				(width 0)
				(type default)
			)
			(fill yes)
			(layer "F.SilkS")
		)
		(fp_line
			(start -2.500122 -2.999994)
			(end 2.500122 -2.999994)
			(stroke
				(width 0.1)
				(type default)
			)
			(layer "F.Fab")
		)
		(fp_line
			(start -2.500122 2.999994)
			(end -2.500122 -2.999994)
			(stroke
				(width 0.1)
				(type default)
			)
			(layer "F.Fab")
		)
		(fp_line
			(start 2.500122 -2.999994)
			(end 2.500122 2.999994)
			(stroke
				(width 0.1)
				(type default)
			)
			(layer "F.Fab")
		)
		(fp_line
			(start 2.500122 2.999994)
			(end -2.500122 2.999994)
			(stroke
				(width 0.1)
				(type default)
			)
			(layer "F.Fab")
		)
		(fp_poly
			(pts
				(xy -4.218432 -2.783078) (xy -4.218432 -1.767078) (xy -3.202432 -2.275078)
			)
			(stroke
				(width 0)
				(type default)
			)
			(fill yes)
			(layer "F.Fab")
		)
		(pad "1" smd rect
			(at -2.400046 -2.275078 90)
			(size 0.2286 0.6096)
			(layers "F.Cu" "F.Mask" "F.Paste")
			(net "PVDDIO_P1_VOS3")
		)
		(pad "2" smd rect
			(at -2.400046 -1.82499 90)
			(size 0.2286 0.6096)
			(layers "F.Cu" "F.Mask" "F.Paste")
			(net "GND")
		)
		(pad "3" smd rect
			(at -2.400046 -1.374902 90)
			(size 0.2286 0.6096)
			(layers "F.Cu" "F.Mask" "F.Paste")
			(net "PVDDIO_P1_VCC3")
		)
		(pad "4" smd rect
			(at -2.400046 -0.925068 90)
			(size 0.2286 0.6096)
			(layers "F.Cu" "F.Mask" "F.Paste")
			(net "PVDDCR_CPU1_P1_PVCC")
		)
		(pad "5" smd rect
			(at -2.400046 -0.47498 90)
			(size 0.2286 0.6096)
			(layers "F.Cu" "F.Mask" "F.Paste")
			(net "GND")
		)
		(pad "6" smd rect
			(at -2.400046 -0.024892 90)
			(size 0.2286 0.6096)
			(layers "F.Cu" "F.Mask" "F.Paste")
			(net "NC_PVDDIO_P1_GL1_3")
		)
		(pad "7_9-20_24" smd circle
			(at 0 1.150112 90)
			(size 0 0)
			(layers "F.Cu" "F.Mask" "F.Paste")
			(net "GND")
		)
		(pad "10_19" smd rect
			(at 0 2.899918 90)
			(size 0.6096 4.318)
			(layers "F.Cu" "F.Mask" "F.Paste")
			(net "SW_PVDDIO_P1_SW3")
		)
		(pad "25_29" smd rect
			(at 1.549908 -1.279906 270)
			(size 2.0574 2.3114)
			(layers "F.Cu" "F.Mask" "F.Paste")
			(net "SW_P12V_AUX_PVDDIO_P1_FLT")
		)
		(pad "30" smd rect
			(at 2.05994 -2.899918)
			(size 0.2286 0.6096)
			(layers "F.Cu" "F.Mask" "F.Paste")
			(net "SW_P12V_AUX_PVDDIO_P1_FLT")
		)
		(pad "31" smd rect
			(at 1.610106 -2.899918)
			(size 0.2286 0.6096)
			(layers "F.Cu" "F.Mask" "F.Paste")
			(net "NC_PVDDIO_P1_DNC3")
		)
		(pad "32" smd rect
			(at 1.160018 -2.899918)
			(size 0.2286 0.6096)
			(layers "F.Cu" "F.Mask" "F.Paste")
			(net "SW_PVDDIO_P1_BOOTR3")
		)
		(pad "33" smd rect
			(at 0.70993 -2.899918)
			(size 0.2286 0.6096)
			(layers "F.Cu" "F.Mask" "F.Paste")
			(net "SW_PVDDIO_P1_BOOT3")
		)
		(pad "34" smd rect
			(at 0.260096 -2.899918)
			(size 0.2286 0.6096)
			(layers "F.Cu" "F.Mask" "F.Paste")
			(net "PVDDIO_P1_PWM3")
		)
		(pad "35" smd rect
			(at -0.189992 -2.899918)
			(size 0.2286 0.6096)
			(layers "F.Cu" "F.Mask" "F.Paste")
			(net "PVDDIO_P1_VCC3")
		)
		(pad "36" smd rect
			(at -0.64008 -2.899918)
			(size 0.2286 0.6096)
			(layers "F.Cu" "F.Mask" "F.Paste")
			(net "PVDDIO_P1_TEMP1")
		)
		(pad "37" smd rect
			(at -1.089914 -2.899918)
			(size 0.2286 0.6096)
			(layers "F.Cu" "F.Mask" "F.Paste")
			(net "PVDDIO_P1_LSET3")
		)
		(pad "38" smd rect
			(at -1.540002 -2.899918)
			(size 0.2286 0.6096)
			(layers "F.Cu" "F.Mask" "F.Paste")
			(net "PVDDIO_P1_IMON3")
		)
		(pad "39" smd rect
			(at -1.99009 -2.899918)
			(size 0.2286 0.6096)
			(layers "F.Cu" "F.Mask" "F.Paste")
			(net "PVDDCR_CPU1_P1_VCCS")
		)
		(pad "40" smd rect
			(at -0.87503 -1.27508)
			(size 1.7526 1.9558)
			(layers "F.Cu" "F.Mask" "F.Paste")
			(net "GND")
		)
		(pad "41" smd rect
			(at -1.525016 0.249936 270)
			(size 0.3048 0.4572)
			(layers "F.Cu" "F.Mask" "F.Paste")
			(net "NC_PVDDIO_P1_GL2_3")
		)
		(zone
			(layer "F.Cu")
			(hatch none 0.5)
			(connect_pads
				(clearance 0)
			)
			(min_thickness 0.25)
			(keepout
				(tracks not_allowed)
				(vias allowed)
				(pads allowed)
				(copperpour not_allowed)
				(footprints allowed)
			)
			(placement
				(enabled no)
				(sheetname "")
			)
			(fill
				(thermal_gap 0.5)
				(thermal_bridge_width 0.5)
				(island_removal_mode 0)
			)
			(polygon
				(pts
					(xy 34.836608 -347.4212) (xy 34.836608 -348.382082) (xy 35.078924 -348.382082) (xy 35.078924 -347.4212)
				)
			)
		)
		(zone
			(layer "F.Cu")
			(hatch none 0.5)
			(connect_pads
				(clearance 0)
			)
			(min_thickness 0.25)
			(keepout
				(tracks not_allowed)
				(vias allowed)
				(pads allowed)
				(copperpour not_allowed)
				(footprints allowed)
			)
			(placement
				(enabled no)
				(sheetname "")
			)
			(fill
				(thermal_gap 0.5)
				(thermal_bridge_width 0.5)
				(island_removal_mode 0)
			)
			(polygon
				(pts
					(xy 34.380932 -344.138758) (xy 34.380932 -344.470482) (xy 39.381176 -344.470482) (xy 39.381176 -344.147648)
					(xy 39.090854 -344.147648) (xy 39.090854 -344.176858) (xy 34.671254 -344.176858) (xy 34.671254 -344.138758)
				)
			)
		)
	)
	(footprint ""
		(layer "F.Cu")
		(at 27.20213 -255.560322 180)
		(property "Reference" "J32"
			(at 1.80086 -81.974436 0)
			(unlocked yes)
			(layer "F.SilkS")
			(effects
				(font
					(size 0.7874 0.5842)
					(thickness 0.1524)
				)
			)
		)
		(property "Value" ""
			(at 0 0 180)
			(layer "F.Fab")
			(effects
				(font
					(size 1.27 1.27)
				)
			)
		)
		(duplicate_pad_numbers_are_jumpers no)
		(fp_line
			(start 3.24993 -81.000092)
			(end 3.24993 75.401678)
			(stroke
				(width 0.1524)
				(type default)
			)
			(layer "F.SilkS")
		)
		(fp_line
			(start -3.24993 75.401678)
			(end -3.24993 -81.000092)
			(stroke
				(width 0.1524)
				(type default)
			)
			(layer "F.SilkS")
		)
		(fp_line
			(start -3.24993 72.499982)
			(end 3.24993 72.499982)
			(stroke
				(width 0.1524)
				(type default)
			)
			(layer "F.SilkS")
		)
		(fp_line
			(start -3.24993 -72.499982)
			(end 3.24993 -72.499982)
			(stroke
				(width 0.1524)
				(type default)
			)
			(layer "F.SilkS")
		)
		(fp_line
			(start -3.24993 -81.000092)
			(end 3.24993 -81.000092)
			(stroke
				(width 0.1524)
				(type default)
			)
			(layer "F.SilkS")
		)
		(fp_poly
			(pts
				(xy -3.690366 -64.748156) (xy -3.080512 -63.789814) (xy -4.213098 -63.876936)
			)
			(stroke
				(width 0)
				(type default)
			)
			(fill yes)
			(layer "F.SilkS")
		)
		(fp_line
			(start 3.24993 81.000092)
			(end -3.24993 81.000092)
			(stroke
				(width 0.1)
				(type default)
			)
			(layer "F.Fab")
		)
		(fp_line
			(start 3.24993 -81.000092)
			(end 3.24993 81.000092)
			(stroke
				(width 0.1)
				(type default)
			)
			(layer "F.Fab")
		)
		(fp_line
			(start -3.24993 81.000092)
			(end -3.24993 -81.000092)
			(stroke
				(width 0.1)
				(type default)
			)
			(layer "F.Fab")
		)
		(fp_line
			(start -3.24993 72.499982)
			(end 3.24993 72.499982)
			(stroke
				(width 0.1)
				(type default)
			)
			(layer "F.Fab")
		)
		(fp_line
			(start -3.24993 71.000112)
			(end 3.24993 71.000112)
			(stroke
				(width 0.1)
				(type default)
			)
			(layer "F.Fab")
		)
		(fp_line
			(start -3.24993 -71.000112)
			(end 3.24993 -71.000112)
			(stroke
				(width 0.1)
				(type default)
			)
			(layer "F.Fab")
		)
		(fp_line
			(start -3.24993 -72.499982)
			(end 3.24993 -72.499982)
			(stroke
				(width 0.1)
				(type default)
			)
			(layer "F.Fab")
		)
		(fp_line
			(start -3.24993 -81.000092)
			(end 3.24993 -81.000092)
			(stroke
				(width 0.1)
				(type default)
			)
			(layer "F.Fab")
		)
		(fp_poly
			(pts
				(xy -3.41503 -63.324994) (xy -4.43103 -62.816994) (xy -4.43103 -63.832994)
			)
			(stroke
				(width 0)
				(type default)
			)
			(fill yes)
			(layer "F.Fab")
		)
		(pad "1" smd rect
			(at -2.050034 -63.324994 90)
			(size 0.519938 1.4986)
			(layers "F.Cu" "F.Mask" "F.Paste")
			(net "P12V_MEM_CPU1")
		)
		(pad "2" smd rect
			(at -2.050034 -62.47511 90)
			(size 0.519938 1.4986)
			(layers "F.Cu" "F.Mask" "F.Paste")
			(net "Net_2312")
		)
		(pad "3" smd rect
			(at -2.050034 -61.624972 90)
			(size 0.519938 1.4986)
			(layers "F.Cu" "F.Mask" "F.Paste")
			(net "P3V3_AUX")
		)
		(pad "4" smd rect
			(at -2.050034 -60.775088 90)
			(size 0.519938 1.4986)
			(layers "F.Cu" "F.Mask" "F.Paste")
			(net "I3C_SPD_DDRE_CPU1_SCL")
		)
		(pad "5" smd rect
			(at -2.050034 -59.92495 90)
			(size 0.519938 1.4986)
			(layers "F.Cu" "F.Mask" "F.Paste")
			(net "I3C_SPD_DDRE_CPU1_SDA")
		)
		(pad "6" smd rect
			(at -2.050034 -59.075066 90)
			(size 0.519938 1.4986)
			(layers "F.Cu" "F.Mask" "F.Paste")
			(net "GND")
		)
		(pad "7" smd rect
			(at -2.050034 -58.224928 90)
			(size 0.519938 1.4986)
			(layers "F.Cu" "F.Mask" "F.Paste")
			(net "M_E_CPU1_SA_DQ<0>")
		)
		(pad "8" smd rect
			(at -2.050034 -57.375044 90)
			(size 0.519938 1.4986)
			(layers "F.Cu" "F.Mask" "F.Paste")
			(net "GND")
		)
		(pad "9" smd rect
			(at -2.050034 -56.524906 90)
			(size 0.519938 1.4986)
			(layers "F.Cu" "F.Mask" "F.Paste")
			(net "M_E_CPU1_SA_DQ<1>")
		)
		(pad "10" smd rect
			(at -2.050034 -55.675022 90)
			(size 0.519938 1.4986)
			(layers "F.Cu" "F.Mask" "F.Paste")
			(net "GND")
		)
		(pad "11" smd rect
			(at -2.050034 -54.824884 90)
			(size 0.519938 1.4986)
			(layers "F.Cu" "F.Mask" "F.Paste")
			(net "M_E_CPU1_SA_DQS_DP<0>")
		)
		(pad "12" smd rect
			(at -2.050034 -53.975 90)
			(size 0.519938 1.4986)
			(layers "F.Cu" "F.Mask" "F.Paste")
			(net "M_E_CPU1_SA_DQS_DN<0>")
		)
		(pad "13" smd rect
			(at -2.050034 -53.125116 90)
			(size 0.519938 1.4986)
			(layers "F.Cu" "F.Mask" "F.Paste")
			(net "GND")
		)
		(pad "14" smd rect
			(at -2.050034 -52.274978 90)
			(size 0.519938 1.4986)
			(layers "F.Cu" "F.Mask" "F.Paste")
			(net "M_E_CPU1_SA_DQ<4>")
		)
		(pad "15" smd rect
			(at -2.050034 -51.425094 90)
			(size 0.519938 1.4986)
			(layers "F.Cu" "F.Mask" "F.Paste")
			(net "GND")
		)
		(pad "16" smd rect
			(at -2.050034 -50.574956 90)
			(size 0.519938 1.4986)
			(layers "F.Cu" "F.Mask" "F.Paste")
			(net "M_E_CPU1_SA_DQ<5>")
		)
		(pad "17" smd rect
			(at -2.050034 -49.725072 90)
			(size 0.519938 1.4986)
			(layers "F.Cu" "F.Mask" "F.Paste")
			(net "GND")
		)
		(pad "18" smd rect
			(at -2.050034 -48.874934 90)
			(size 0.519938 1.4986)
			(layers "F.Cu" "F.Mask" "F.Paste")
			(net "M_E_CPU1_SA_DQ<8>")
		)
		(pad "19" smd rect
			(at -2.050034 -48.02505 90)
			(size 0.519938 1.4986)
			(layers "F.Cu" "F.Mask" "F.Paste")
			(net "GND")
		)
		(pad "20" smd rect
			(at -2.050034 -47.174912 90)
			(size 0.519938 1.4986)
			(layers "F.Cu" "F.Mask" "F.Paste")
			(net "M_E_CPU1_SA_DQ<9>")
		)
		(pad "21" smd rect
			(at -2.050034 -46.325028 90)
			(size 0.519938 1.4986)
			(layers "F.Cu" "F.Mask" "F.Paste")
			(net "GND")
		)
		(pad "22" smd rect
			(at -2.050034 -45.47489 90)
			(size 0.519938 1.4986)
			(layers "F.Cu" "F.Mask" "F.Paste")
			(net "M_E_CPU1_SA_DQS_DP<1>")
		)
		(pad "23" smd rect
			(at -2.050034 -44.625006 90)
			(size 0.519938 1.4986)
			(layers "F.Cu" "F.Mask" "F.Paste")
			(net "M_E_CPU1_SA_DQS_DN<1>")
		)
		(pad "24" smd rect
			(at -2.050034 -43.775122 90)
			(size 0.519938 1.4986)
			(layers "F.Cu" "F.Mask" "F.Paste")
			(net "GND")
		)
		(pad "25" smd rect
			(at -2.050034 -42.924984 90)
			(size 0.519938 1.4986)
			(layers "F.Cu" "F.Mask" "F.Paste")
			(net "M_E_CPU1_SA_DQ<12>")
		)
		(pad "26" smd rect
			(at -2.050034 -42.0751 90)
			(size 0.519938 1.4986)
			(layers "F.Cu" "F.Mask" "F.Paste")
			(net "GND")
		)
		(pad "27" smd rect
			(at -2.050034 -41.224962 90)
			(size 0.519938 1.4986)
			(layers "F.Cu" "F.Mask" "F.Paste")
			(net "M_E_CPU1_SA_DQ<13>")
		)
		(pad "28" smd rect
			(at -2.050034 -40.375078 90)
			(size 0.519938 1.4986)
			(layers "F.Cu" "F.Mask" "F.Paste")
			(net "GND")
		)
		(pad "29" smd rect
			(at -2.050034 -39.52494 90)
			(size 0.519938 1.4986)
			(layers "F.Cu" "F.Mask" "F.Paste")
			(net "M_E_CPU1_SA_DQ<16>")
		)
		(pad "30" smd rect
			(at -2.050034 -38.675056 90)
			(size 0.519938 1.4986)
			(layers "F.Cu" "F.Mask" "F.Paste")
			(net "GND")
		)
		(pad "31" smd rect
			(at -2.050034 -37.824918 90)
			(size 0.519938 1.4986)
			(layers "F.Cu" "F.Mask" "F.Paste")
			(net "M_E_CPU1_SA_DQ<17>")
		)
		(pad "32" smd rect
			(at -2.050034 -36.975034 90)
			(size 0.519938 1.4986)
			(layers "F.Cu" "F.Mask" "F.Paste")
			(net "GND")
		)
		(pad "33" smd rect
			(at -2.050034 -36.124896 90)
			(size 0.519938 1.4986)
			(layers "F.Cu" "F.Mask" "F.Paste")
			(net "M_E_CPU1_SA_DQS_DP<2>")
		)
		(pad "34" smd rect
			(at -2.050034 -35.275012 90)
			(size 0.519938 1.4986)
			(layers "F.Cu" "F.Mask" "F.Paste")
			(net "M_E_CPU1_SA_DQS_DN<2>")
		)
		(pad "35" smd rect
			(at -2.050034 -34.425128 90)
			(size 0.519938 1.4986)
			(layers "F.Cu" "F.Mask" "F.Paste")
			(net "GND")
		)
		(pad "36" smd rect
			(at -2.050034 -33.57499 90)
			(size 0.519938 1.4986)
			(layers "F.Cu" "F.Mask" "F.Paste")
			(net "M_E_CPU1_SA_DQ<20>")
		)
		(pad "37" smd rect
			(at -2.050034 -32.725106 90)
			(size 0.519938 1.4986)
			(layers "F.Cu" "F.Mask" "F.Paste")
			(net "GND")
		)
		(pad "38" smd rect
			(at -2.050034 -31.874968 90)
			(size 0.519938 1.4986)
			(layers "F.Cu" "F.Mask" "F.Paste")
			(net "M_E_CPU1_SA_DQ<21>")
		)
		(pad "39" smd rect
			(at -2.050034 -31.025084 90)
			(size 0.519938 1.4986)
			(layers "F.Cu" "F.Mask" "F.Paste")
			(net "GND")
		)
		(pad "40" smd rect
			(at -2.050034 -30.174946 90)
			(size 0.519938 1.4986)
			(layers "F.Cu" "F.Mask" "F.Paste")
			(net "M_E_CPU1_SA_DQ<24>")
		)
		(pad "41" smd rect
			(at -2.050034 -29.325062 90)
			(size 0.519938 1.4986)
			(layers "F.Cu" "F.Mask" "F.Paste")
			(net "GND")
		)
		(pad "42" smd rect
			(at -2.050034 -28.474924 90)
			(size 0.519938 1.4986)
			(layers "F.Cu" "F.Mask" "F.Paste")
			(net "M_E_CPU1_SA_DQ<25>")
		)
		(pad "43" smd rect
			(at -2.050034 -27.62504 90)
			(size 0.519938 1.4986)
			(layers "F.Cu" "F.Mask" "F.Paste")
			(net "GND")
		)
		(pad "44" smd rect
			(at -2.050034 -26.774902 90)
			(size 0.519938 1.4986)
			(layers "F.Cu" "F.Mask" "F.Paste")
			(net "M_E_CPU1_SA_DQS_DP<3>")
		)
		(pad "45" smd rect
			(at -2.050034 -25.925018 90)
			(size 0.519938 1.4986)
			(layers "F.Cu" "F.Mask" "F.Paste")
			(net "M_E_CPU1_SA_DQS_DN<3>")
		)
		(pad "46" smd rect
			(at -2.050034 -25.07488 90)
			(size 0.519938 1.4986)
			(layers "F.Cu" "F.Mask" "F.Paste")
			(net "GND")
		)
		(pad "47" smd rect
			(at -2.050034 -24.224996 90)
			(size 0.519938 1.4986)
			(layers "F.Cu" "F.Mask" "F.Paste")
			(net "M_E_CPU1_SA_DQ<28>")
		)
		(pad "48" smd rect
			(at -2.050034 -23.375112 90)
			(size 0.519938 1.4986)
			(layers "F.Cu" "F.Mask" "F.Paste")
			(net "GND")
		)
		(pad "49" smd rect
			(at -2.050034 -22.524974 90)
			(size 0.519938 1.4986)
			(layers "F.Cu" "F.Mask" "F.Paste")
			(net "M_E_CPU1_SA_DQ<29>")
		)
		(pad "50" smd rect
			(at -2.050034 -21.67509 90)
			(size 0.519938 1.4986)
			(layers "F.Cu" "F.Mask" "F.Paste")
			(net "GND")
		)
		(pad "51" smd rect
			(at -2.050034 -20.824952 90)
			(size 0.519938 1.4986)
			(layers "F.Cu" "F.Mask" "F.Paste")
			(net "M_E_CPU1_SA_CB<0>")
		)
		(pad "52" smd rect
			(at -2.050034 -19.975068 90)
			(size 0.519938 1.4986)
			(layers "F.Cu" "F.Mask" "F.Paste")
			(net "GND")
		)
		(pad "53" smd rect
			(at -2.050034 -19.12493 90)
			(size 0.519938 1.4986)
			(layers "F.Cu" "F.Mask" "F.Paste")
			(net "M_E_CPU1_SA_CB<1>")
		)
		(pad "54" smd rect
			(at -2.050034 -18.275046 90)
			(size 0.519938 1.4986)
			(layers "F.Cu" "F.Mask" "F.Paste")
			(net "GND")
		)
		(pad "55" smd rect
			(at -2.050034 -17.424908 90)
			(size 0.519938 1.4986)
			(layers "F.Cu" "F.Mask" "F.Paste")
			(net "M_E_CPU1_SA_DQS_DP<4>")
		)
		(pad "56" smd rect
			(at -2.050034 -16.575024 90)
			(size 0.519938 1.4986)
			(layers "F.Cu" "F.Mask" "F.Paste")
			(net "M_E_CPU1_SA_DQS_DN<4>")
		)
		(pad "57" smd rect
			(at -2.050034 -15.724886 90)
			(size 0.519938 1.4986)
			(layers "F.Cu" "F.Mask" "F.Paste")
			(net "GND")
		)
		(pad "58" smd rect
			(at -2.050034 -14.875002 90)
			(size 0.519938 1.4986)
			(layers "F.Cu" "F.Mask" "F.Paste")
			(net "M_E_CPU1_SA_CB<4>")
		)
		(pad "59" smd rect
			(at -2.050034 -14.025118 90)
			(size 0.519938 1.4986)
			(layers "F.Cu" "F.Mask" "F.Paste")
			(net "GND")
		)
		(pad "60" smd rect
			(at -2.050034 -13.17498 90)
			(size 0.519938 1.4986)
			(layers "F.Cu" "F.Mask" "F.Paste")
			(net "M_E_CPU1_SA_CB<5>")
		)
		(pad "61" smd rect
			(at -2.050034 -12.325096 90)
			(size 0.519938 1.4986)
			(layers "F.Cu" "F.Mask" "F.Paste")
			(net "GND")
		)
		(pad "62" smd rect
			(at -2.050034 -11.474958 90)
			(size 0.519938 1.4986)
			(layers "F.Cu" "F.Mask" "F.Paste")
			(net "M_E_CPU1_ALERT_N")
		)
		(pad "63" smd rect
			(at -2.050034 -10.625074 90)
			(size 0.519938 1.4986)
			(layers "F.Cu" "F.Mask" "F.Paste")
			(net "GND")
		)
		(pad "64" smd rect
			(at -2.050034 -9.774936 90)
			(size 0.519938 1.4986)
			(layers "F.Cu" "F.Mask" "F.Paste")
			(net "M_E_CPU1_SA_CS_N<0>")
		)
		(pad "65" smd rect
			(at -2.050034 -8.925052 90)
			(size 0.519938 1.4986)
			(layers "F.Cu" "F.Mask" "F.Paste")
			(net "GND")
		)
		(pad "66" smd rect
			(at -2.050034 -8.074914 90)
			(size 0.519938 1.4986)
			(layers "F.Cu" "F.Mask" "F.Paste")
			(net "M_E_CPU1_SA_CA<0>")
		)
		(pad "67" smd rect
			(at -2.050034 -7.22503 90)
			(size 0.519938 1.4986)
			(layers "F.Cu" "F.Mask" "F.Paste")
			(net "GND")
		)
		(pad "68" smd rect
			(at -2.050034 -6.374892 90)
			(size 0.519938 1.4986)
			(layers "F.Cu" "F.Mask" "F.Paste")
			(net "M_E_CPU1_SA_CA<2>")
		)
		(pad "69" smd rect
			(at -2.050034 -5.525008 90)
			(size 0.519938 1.4986)
			(layers "F.Cu" "F.Mask" "F.Paste")
			(net "GND")
		)
		(pad "70" smd rect
			(at -2.050034 -4.675124 90)
			(size 0.519938 1.4986)
			(layers "F.Cu" "F.Mask" "F.Paste")
			(net "M_E_CPU1_SA_CA<4>")
		)
		(pad "71" smd rect
			(at -2.050034 -3.824986 90)
			(size 0.519938 1.4986)
			(layers "F.Cu" "F.Mask" "F.Paste")
			(net "GND")
		)
		(pad "72" smd rect
			(at -2.050034 -2.975102 90)
			(size 0.519938 1.4986)
			(layers "F.Cu" "F.Mask" "F.Paste")
			(net "M_E_CPU1_SA_CA<6>")
		)
		(pad "73" smd rect
			(at -2.050034 -2.124964 90)
			(size 0.519938 1.4986)
			(layers "F.Cu" "F.Mask" "F.Paste")
			(net "GND")
		)
		(pad "74" smd rect
			(at -2.050034 -1.27508 90)
			(size 0.519938 1.4986)
			(layers "F.Cu" "F.Mask" "F.Paste")
			(net "M_E_CPU1_SA_PAR")
		)
		(pad "75" smd rect
			(at -2.050034 -0.424942 90)
			(size 0.519938 1.4986)
			(layers "F.Cu" "F.Mask" "F.Paste")
			(net "GND")
		)
		(pad "76" smd rect
			(at -2.050034 5.525008 90)
			(size 0.519938 1.4986)
			(layers "F.Cu" "F.Mask" "F.Paste")
			(net "M_E_CPU1_SB_CA<0>")
		)
		(pad "77" smd rect
			(at -2.050034 6.374892 90)
			(size 0.519938 1.4986)
			(layers "F.Cu" "F.Mask" "F.Paste")
			(net "GND")
		)
		(pad "78" smd rect
			(at -2.050034 7.22503 90)
			(size 0.519938 1.4986)
			(layers "F.Cu" "F.Mask" "F.Paste")
			(net "M_E_CPU1_SB_CA<2>")
		)
		(pad "79" smd rect
			(at -2.050034 8.074914 90)
			(size 0.519938 1.4986)
			(layers "F.Cu" "F.Mask" "F.Paste")
			(net "GND")
		)
		(pad "80" smd rect
			(at -2.050034 8.925052 90)
			(size 0.519938 1.4986)
			(layers "F.Cu" "F.Mask" "F.Paste")
			(net "M_E_CPU1_SB_CA<4>")
		)
		(pad "81" smd rect
			(at -2.050034 9.774936 90)
			(size 0.519938 1.4986)
			(layers "F.Cu" "F.Mask" "F.Paste")
			(net "GND")
		)
		(pad "82" smd rect
			(at -2.050034 10.625074 90)
			(size 0.519938 1.4986)
			(layers "F.Cu" "F.Mask" "F.Paste")
			(net "M_E_CPU1_SB_CA<6>")
		)
		(pad "83" smd rect
			(at -2.050034 11.474958 90)
			(size 0.519938 1.4986)
			(layers "F.Cu" "F.Mask" "F.Paste")
			(net "GND")
		)
		(pad "84" smd rect
			(at -2.050034 12.325096 90)
			(size 0.519938 1.4986)
			(layers "F.Cu" "F.Mask" "F.Paste")
			(net "M_E_CPU1_SB_CS_N<0>")
		)
		(pad "85" smd rect
			(at -2.050034 13.17498 90)
			(size 0.519938 1.4986)
			(layers "F.Cu" "F.Mask" "F.Paste")
			(net "GND")
		)
		(pad "86" smd rect
			(at -2.050034 14.025118 90)
			(size 0.519938 1.4986)
			(layers "F.Cu" "F.Mask" "F.Paste")
			(net "M_E_CPU1_SA_RSP<0>")
		)
		(pad "87" smd rect
			(at -2.050034 14.875002 90)
			(size 0.519938 1.4986)
			(layers "F.Cu" "F.Mask" "F.Paste")
			(net "M_E_CPU1_SB_RSP<0>")
		)
		(pad "88" smd rect
			(at -2.050034 15.724886 90)
			(size 0.519938 1.4986)
			(layers "F.Cu" "F.Mask" "F.Paste")
			(net "GND")
		)
		(pad "89" smd rect
			(at -2.050034 16.575024 90)
			(size 0.519938 1.4986)
			(layers "F.Cu" "F.Mask" "F.Paste")
			(net "M_E_CPU1_SB_CB<4>")
		)
		(pad "90" smd rect
			(at -2.050034 17.424908 90)
			(size 0.519938 1.4986)
			(layers "F.Cu" "F.Mask" "F.Paste")
			(net "GND")
		)
		(pad "91" smd rect
			(at -2.050034 18.275046 90)
			(size 0.519938 1.4986)
			(layers "F.Cu" "F.Mask" "F.Paste")
			(net "M_E_CPU1_SB_CB<5>")
		)
		(pad "92" smd rect
			(at -2.050034 19.12493 90)
			(size 0.519938 1.4986)
			(layers "F.Cu" "F.Mask" "F.Paste")
			(net "GND")
		)
		(pad "93" smd rect
			(at -2.050034 19.975068 90)
			(size 0.519938 1.4986)
			(layers "F.Cu" "F.Mask" "F.Paste")
			(net "M_E_CPU1_SB_DQS_DP<9>")
		)
		(pad "94" smd rect
			(at -2.050034 20.824952 90)
			(size 0.519938 1.4986)
			(layers "F.Cu" "F.Mask" "F.Paste")
			(net "M_E_CPU1_SB_DQS_DN<9>")
		)
		(pad "95" smd rect
			(at -2.050034 21.67509 90)
			(size 0.519938 1.4986)
			(layers "F.Cu" "F.Mask" "F.Paste")
			(net "GND")
		)
		(pad "96" smd rect
			(at -2.050034 22.524974 90)
			(size 0.519938 1.4986)
			(layers "F.Cu" "F.Mask" "F.Paste")
			(net "M_E_CPU1_SB_CB<0>")
		)
		(pad "97" smd rect
			(at -2.050034 23.375112 90)
			(size 0.519938 1.4986)
			(layers "F.Cu" "F.Mask" "F.Paste")
			(net "GND")
		)
		(pad "98" smd rect
			(at -2.050034 24.224996 90)
			(size 0.519938 1.4986)
			(layers "F.Cu" "F.Mask" "F.Paste")
			(net "M_E_CPU1_SB_CB<1>")
		)
		(pad "99" smd rect
			(at -2.050034 25.07488 90)
			(size 0.519938 1.4986)
			(layers "F.Cu" "F.Mask" "F.Paste")
			(net "GND")
		)
		(pad "100" smd rect
			(at -2.050034 25.925018 90)
			(size 0.519938 1.4986)
			(layers "F.Cu" "F.Mask" "F.Paste")
			(net "M_E_CPU1_SB_DQ<0>")
		)
		(pad "101" smd rect
			(at -2.050034 26.774902 90)
			(size 0.519938 1.4986)
			(layers "F.Cu" "F.Mask" "F.Paste")
			(net "GND")
		)
		(pad "102" smd rect
			(at -2.050034 27.62504 90)
			(size 0.519938 1.4986)
			(layers "F.Cu" "F.Mask" "F.Paste")
			(net "M_E_CPU1_SB_DQ<1>")
		)
		(pad "103" smd rect
			(at -2.050034 28.474924 90)
			(size 0.519938 1.4986)
			(layers "F.Cu" "F.Mask" "F.Paste")
			(net "GND")
		)
		(pad "104" smd rect
			(at -2.050034 29.325062 90)
			(size 0.519938 1.4986)
			(layers "F.Cu" "F.Mask" "F.Paste")
			(net "M_E_CPU1_SB_DQS_DP<0>")
		)
		(pad "105" smd rect
			(at -2.050034 30.174946 90)
			(size 0.519938 1.4986)
			(layers "F.Cu" "F.Mask" "F.Paste")
			(net "M_E_CPU1_SB_DQS_DN<0>")
		)
		(pad "106" smd rect
			(at -2.050034 31.025084 90)
			(size 0.519938 1.4986)
			(layers "F.Cu" "F.Mask" "F.Paste")
			(net "GND")
		)
		(pad "107" smd rect
			(at -2.050034 31.874968 90)
			(size 0.519938 1.4986)
			(layers "F.Cu" "F.Mask" "F.Paste")
			(net "M_E_CPU1_SB_DQ<4>")
		)
		(pad "108" smd rect
			(at -2.050034 32.725106 90)
			(size 0.519938 1.4986)
			(layers "F.Cu" "F.Mask" "F.Paste")
			(net "GND")
		)
		(pad "109" smd rect
			(at -2.050034 33.57499 90)
			(size 0.519938 1.4986)
			(layers "F.Cu" "F.Mask" "F.Paste")
			(net "M_E_CPU1_SB_DQ<5>")
		)
		(pad "110" smd rect
			(at -2.050034 34.425128 90)
			(size 0.519938 1.4986)
			(layers "F.Cu" "F.Mask" "F.Paste")
			(net "GND")
		)
		(pad "111" smd rect
			(at -2.050034 35.275012 90)
			(size 0.519938 1.4986)
			(layers "F.Cu" "F.Mask" "F.Paste")
			(net "M_E_CPU1_SB_DQ<8>")
		)
		(pad "112" smd rect
			(at -2.050034 36.124896 90)
			(size 0.519938 1.4986)
			(layers "F.Cu" "F.Mask" "F.Paste")
			(net "GND")
		)
		(pad "113" smd rect
			(at -2.050034 36.975034 90)
			(size 0.519938 1.4986)
			(layers "F.Cu" "F.Mask" "F.Paste")
			(net "M_E_CPU1_SB_DQ<9>")
		)
		(pad "114" smd rect
			(at -2.050034 37.824918 90)
			(size 0.519938 1.4986)
			(layers "F.Cu" "F.Mask" "F.Paste")
			(net "GND")
		)
		(pad "115" smd rect
			(at -2.050034 38.675056 90)
			(size 0.519938 1.4986)
			(layers "F.Cu" "F.Mask" "F.Paste")
			(net "M_E_CPU1_SB_DQS_DP<1>")
		)
		(pad "116" smd rect
			(at -2.050034 39.52494 90)
			(size 0.519938 1.4986)
			(layers "F.Cu" "F.Mask" "F.Paste")
			(net "M_E_CPU1_SB_DQS_DN<1>")
		)
		(pad "117" smd rect
			(at -2.050034 40.375078 90)
			(size 0.519938 1.4986)
			(layers "F.Cu" "F.Mask" "F.Paste")
			(net "GND")
		)
		(pad "118" smd rect
			(at -2.050034 41.224962 90)
			(size 0.519938 1.4986)
			(layers "F.Cu" "F.Mask" "F.Paste")
			(net "M_E_CPU1_SB_DQ<12>")
		)
		(pad "119" smd rect
			(at -2.050034 42.0751 90)
			(size 0.519938 1.4986)
			(layers "F.Cu" "F.Mask" "F.Paste")
			(net "GND")
		)
		(pad "120" smd rect
			(at -2.050034 42.924984 90)
			(size 0.519938 1.4986)
			(layers "F.Cu" "F.Mask" "F.Paste")
			(net "M_E_CPU1_SB_DQ<13>")
		)
		(pad "121" smd rect
			(at -2.050034 43.775122 90)
			(size 0.519938 1.4986)
			(layers "F.Cu" "F.Mask" "F.Paste")
			(net "GND")
		)
		(pad "122" smd rect
			(at -2.050034 44.625006 90)
			(size 0.519938 1.4986)
			(layers "F.Cu" "F.Mask" "F.Paste")
			(net "M_E_CPU1_SB_DQ<16>")
		)
		(pad "123" smd rect
			(at -2.050034 45.47489 90)
			(size 0.519938 1.4986)
			(layers "F.Cu" "F.Mask" "F.Paste")
			(net "GND")
		)
		(pad "124" smd rect
			(at -2.050034 46.325028 90)
			(size 0.519938 1.4986)
			(layers "F.Cu" "F.Mask" "F.Paste")
			(net "M_E_CPU1_SB_DQ<17>")
		)
		(pad "125" smd rect
			(at -2.050034 47.174912 90)
			(size 0.519938 1.4986)
			(layers "F.Cu" "F.Mask" "F.Paste")
			(net "GND")
		)
		(pad "126" smd rect
			(at -2.050034 48.02505 90)
			(size 0.519938 1.4986)
			(layers "F.Cu" "F.Mask" "F.Paste")
			(net "M_E_CPU1_SB_DQS_DP<2>")
		)
		(pad "127" smd rect
			(at -2.050034 48.874934 90)
			(size 0.519938 1.4986)
			(layers "F.Cu" "F.Mask" "F.Paste")
			(net "M_E_CPU1_SB_DQS_DN<2>")
		)
		(pad "128" smd rect
			(at -2.050034 49.725072 90)
			(size 0.519938 1.4986)
			(layers "F.Cu" "F.Mask" "F.Paste")
			(net "GND")
		)
		(pad "129" smd rect
			(at -2.050034 50.574956 90)
			(size 0.519938 1.4986)
			(layers "F.Cu" "F.Mask" "F.Paste")
			(net "M_E_CPU1_SB_DQ<20>")
		)
		(pad "130" smd rect
			(at -2.050034 51.425094 90)
			(size 0.519938 1.4986)
			(layers "F.Cu" "F.Mask" "F.Paste")
			(net "GND")
		)
		(pad "131" smd rect
			(at -2.050034 52.274978 90)
			(size 0.519938 1.4986)
			(layers "F.Cu" "F.Mask" "F.Paste")
			(net "M_E_CPU1_SB_DQ<21>")
		)
		(pad "132" smd rect
			(at -2.050034 53.125116 90)
			(size 0.519938 1.4986)
			(layers "F.Cu" "F.Mask" "F.Paste")
			(net "GND")
		)
		(pad "133" smd rect
			(at -2.050034 53.975 90)
			(size 0.519938 1.4986)
			(layers "F.Cu" "F.Mask" "F.Paste")
			(net "M_E_CPU1_SB_DQ<24>")
		)
		(pad "134" smd rect
			(at -2.050034 54.824884 90)
			(size 0.519938 1.4986)
			(layers "F.Cu" "F.Mask" "F.Paste")
			(net "GND")
		)
		(pad "135" smd rect
			(at -2.050034 55.675022 90)
			(size 0.519938 1.4986)
			(layers "F.Cu" "F.Mask" "F.Paste")
			(net "M_E_CPU1_SB_DQ<25>")
		)
		(pad "136" smd rect
			(at -2.050034 56.524906 90)
			(size 0.519938 1.4986)
			(layers "F.Cu" "F.Mask" "F.Paste")
			(net "GND")
		)
		(pad "137" smd rect
			(at -2.050034 57.375044 90)
			(size 0.519938 1.4986)
			(layers "F.Cu" "F.Mask" "F.Paste")
			(net "M_E_CPU1_SB_DQS_DP<3>")
		)
		(pad "138" smd rect
			(at -2.050034 58.224928 90)
			(size 0.519938 1.4986)
			(layers "F.Cu" "F.Mask" "F.Paste")
			(net "M_E_CPU1_SB_DQS_DN<3>")
		)
		(pad "139" smd rect
			(at -2.050034 59.075066 90)
			(size 0.519938 1.4986)
			(layers "F.Cu" "F.Mask" "F.Paste")
			(net "GND")
		)
		(pad "140" smd rect
			(at -2.050034 59.92495 90)
			(size 0.519938 1.4986)
			(layers "F.Cu" "F.Mask" "F.Paste")
			(net "M_E_CPU1_SB_DQ<28>")
		)
		(pad "141" smd rect
			(at -2.050034 60.775088 90)
			(size 0.519938 1.4986)
			(layers "F.Cu" "F.Mask" "F.Paste")
			(net "GND")
		)
		(pad "142" smd rect
			(at -2.050034 61.624972 90)
			(size 0.519938 1.4986)
			(layers "F.Cu" "F.Mask" "F.Paste")
			(net "M_E_CPU1_SB_DQ<29>")
		)
		(pad "143" smd rect
			(at -2.050034 62.47511 90)
			(size 0.519938 1.4986)
			(layers "F.Cu" "F.Mask" "F.Paste")
			(net "GND")
		)
		(pad "144" smd rect
			(at -2.050034 63.324994 90)
			(size 0.519938 1.4986)
			(layers "F.Cu" "F.Mask" "F.Paste")
			(net "Net_2313")
		)
		(pad "145" smd rect
			(at 2.050034 -63.324994 90)
			(size 0.519938 1.4986)
			(layers "F.Cu" "F.Mask" "F.Paste")
			(net "P12V_MEM_CPU1")
		)
		(pad "146" smd rect
			(at 2.050034 -62.47511 90)
			(size 0.519938 1.4986)
			(layers "F.Cu" "F.Mask" "F.Paste")
			(net "P12V_MEM_CPU1")
		)
		(pad "147" smd rect
			(at 2.050034 -61.624972 90)
			(size 0.519938 1.4986)
			(layers "F.Cu" "F.Mask" "F.Paste")
			(net "PWRGD_CHE_CPU1_DIMM")
		)
		(pad "148" smd rect
			(at 2.050034 -60.775088 90)
			(size 0.519938 1.4986)
			(layers "F.Cu" "F.Mask" "F.Paste")
			(net "PD_CHE_CPU1_DIMM_SAA")
		)
		(pad "149" smd rect
			(at 2.050034 -59.92495 90)
			(size 0.519938 1.4986)
			(layers "F.Cu" "F.Mask" "F.Paste")
			(net "Net_2314")
		)
		(pad "150" smd rect
			(at 2.050034 -59.075066 90)
			(size 0.519938 1.4986)
			(layers "F.Cu" "F.Mask" "F.Paste")
			(net "Net_2315")
		)
		(pad "151" smd rect
			(at 2.050034 -58.224928 90)
			(size 0.519938 1.4986)
			(layers "F.Cu" "F.Mask" "F.Paste")
			(net "GND")
		)
		(pad "152" smd rect
			(at 2.050034 -57.375044 90)
			(size 0.519938 1.4986)
			(layers "F.Cu" "F.Mask" "F.Paste")
			(net "M_E_CPU1_SA_DQ<2>")
		)
		(pad "153" smd rect
			(at 2.050034 -56.524906 90)
			(size 0.519938 1.4986)
			(layers "F.Cu" "F.Mask" "F.Paste")
			(net "GND")
		)
		(pad "154" smd rect
			(at 2.050034 -55.675022 90)
			(size 0.519938 1.4986)
			(layers "F.Cu" "F.Mask" "F.Paste")
			(net "M_E_CPU1_SA_DQ<3>")
		)
		(pad "155" smd rect
			(at 2.050034 -54.824884 90)
			(size 0.519938 1.4986)
			(layers "F.Cu" "F.Mask" "F.Paste")
			(net "GND")
		)
		(pad "156" smd rect
			(at 2.050034 -53.975 90)
			(size 0.519938 1.4986)
			(layers "F.Cu" "F.Mask" "F.Paste")
			(net "M_E_CPU1_SA_DQS_DN<5>")
		)
		(pad "157" smd rect
			(at 2.050034 -53.125116 90)
			(size 0.519938 1.4986)
			(layers "F.Cu" "F.Mask" "F.Paste")
			(net "M_E_CPU1_SA_DQS_DP<5>")
		)
		(pad "158" smd rect
			(at 2.050034 -52.274978 90)
			(size 0.519938 1.4986)
			(layers "F.Cu" "F.Mask" "F.Paste")
			(net "GND")
		)
		(pad "159" smd rect
			(at 2.050034 -51.425094 90)
			(size 0.519938 1.4986)
			(layers "F.Cu" "F.Mask" "F.Paste")
			(net "M_E_CPU1_SA_DQ<6>")
		)
		(pad "160" smd rect
			(at 2.050034 -50.574956 90)
			(size 0.519938 1.4986)
			(layers "F.Cu" "F.Mask" "F.Paste")
			(net "GND")
		)
		(pad "161" smd rect
			(at 2.050034 -49.725072 90)
			(size 0.519938 1.4986)
			(layers "F.Cu" "F.Mask" "F.Paste")
			(net "M_E_CPU1_SA_DQ<7>")
		)
		(pad "162" smd rect
			(at 2.050034 -48.874934 90)
			(size 0.519938 1.4986)
			(layers "F.Cu" "F.Mask" "F.Paste")
			(net "GND")
		)
		(pad "163" smd rect
			(at 2.050034 -48.02505 90)
			(size 0.519938 1.4986)
			(layers "F.Cu" "F.Mask" "F.Paste")
			(net "M_E_CPU1_SA_DQ<10>")
		)
		(pad "164" smd rect
			(at 2.050034 -47.174912 90)
			(size 0.519938 1.4986)
			(layers "F.Cu" "F.Mask" "F.Paste")
			(net "GND")
		)
		(pad "165" smd rect
			(at 2.050034 -46.325028 90)
			(size 0.519938 1.4986)
			(layers "F.Cu" "F.Mask" "F.Paste")
			(net "M_E_CPU1_SA_DQ<11>")
		)
		(pad "166" smd rect
			(at 2.050034 -45.47489 90)
			(size 0.519938 1.4986)
			(layers "F.Cu" "F.Mask" "F.Paste")
			(net "GND")
		)
		(pad "167" smd rect
			(at 2.050034 -44.625006 90)
			(size 0.519938 1.4986)
			(layers "F.Cu" "F.Mask" "F.Paste")
			(net "M_E_CPU1_SA_DQS_DN<6>")
		)
		(pad "168" smd rect
			(at 2.050034 -43.775122 90)
			(size 0.519938 1.4986)
			(layers "F.Cu" "F.Mask" "F.Paste")
			(net "M_E_CPU1_SA_DQS_DP<6>")
		)
		(pad "169" smd rect
			(at 2.050034 -42.924984 90)
			(size 0.519938 1.4986)
			(layers "F.Cu" "F.Mask" "F.Paste")
			(net "GND")
		)
		(pad "170" smd rect
			(at 2.050034 -42.0751 90)
			(size 0.519938 1.4986)
			(layers "F.Cu" "F.Mask" "F.Paste")
			(net "M_E_CPU1_SA_DQ<14>")
		)
		(pad "171" smd rect
			(at 2.050034 -41.224962 90)
			(size 0.519938 1.4986)
			(layers "F.Cu" "F.Mask" "F.Paste")
			(net "GND")
		)
		(pad "172" smd rect
			(at 2.050034 -40.375078 90)
			(size 0.519938 1.4986)
			(layers "F.Cu" "F.Mask" "F.Paste")
			(net "M_E_CPU1_SA_DQ<15>")
		)
		(pad "173" smd rect
			(at 2.050034 -39.52494 90)
			(size 0.519938 1.4986)
			(layers "F.Cu" "F.Mask" "F.Paste")
			(net "GND")
		)
		(pad "174" smd rect
			(at 2.050034 -38.675056 90)
			(size 0.519938 1.4986)
			(layers "F.Cu" "F.Mask" "F.Paste")
			(net "M_E_CPU1_SA_DQ<18>")
		)
		(pad "175" smd rect
			(at 2.050034 -37.824918 90)
			(size 0.519938 1.4986)
			(layers "F.Cu" "F.Mask" "F.Paste")
			(net "GND")
		)
		(pad "176" smd rect
			(at 2.050034 -36.975034 90)
			(size 0.519938 1.4986)
			(layers "F.Cu" "F.Mask" "F.Paste")
			(net "M_E_CPU1_SA_DQ<19>")
		)
		(pad "177" smd rect
			(at 2.050034 -36.124896 90)
			(size 0.519938 1.4986)
			(layers "F.Cu" "F.Mask" "F.Paste")
			(net "GND")
		)
		(pad "178" smd rect
			(at 2.050034 -35.275012 90)
			(size 0.519938 1.4986)
			(layers "F.Cu" "F.Mask" "F.Paste")
			(net "M_E_CPU1_SA_DQS_DN<7>")
		)
		(pad "179" smd rect
			(at 2.050034 -34.425128 90)
			(size 0.519938 1.4986)
			(layers "F.Cu" "F.Mask" "F.Paste")
			(net "M_E_CPU1_SA_DQS_DP<7>")
		)
		(pad "180" smd rect
			(at 2.050034 -33.57499 90)
			(size 0.519938 1.4986)
			(layers "F.Cu" "F.Mask" "F.Paste")
			(net "GND")
		)
		(pad "181" smd rect
			(at 2.050034 -32.725106 90)
			(size 0.519938 1.4986)
			(layers "F.Cu" "F.Mask" "F.Paste")
			(net "M_E_CPU1_SA_DQ<22>")
		)
		(pad "182" smd rect
			(at 2.050034 -31.874968 90)
			(size 0.519938 1.4986)
			(layers "F.Cu" "F.Mask" "F.Paste")
			(net "GND")
		)
		(pad "183" smd rect
			(at 2.050034 -31.025084 90)
			(size 0.519938 1.4986)
			(layers "F.Cu" "F.Mask" "F.Paste")
			(net "M_E_CPU1_SA_DQ<23>")
		)
		(pad "184" smd rect
			(at 2.050034 -30.174946 90)
			(size 0.519938 1.4986)
			(layers "F.Cu" "F.Mask" "F.Paste")
			(net "GND")
		)
		(pad "185" smd rect
			(at 2.050034 -29.325062 90)
			(size 0.519938 1.4986)
			(layers "F.Cu" "F.Mask" "F.Paste")
			(net "M_E_CPU1_SA_DQ<26>")
		)
		(pad "186" smd rect
			(at 2.050034 -28.474924 90)
			(size 0.519938 1.4986)
			(layers "F.Cu" "F.Mask" "F.Paste")
			(net "GND")
		)
		(pad "187" smd rect
			(at 2.050034 -27.62504 90)
			(size 0.519938 1.4986)
			(layers "F.Cu" "F.Mask" "F.Paste")
			(net "M_E_CPU1_SA_DQ<27>")
		)
		(pad "188" smd rect
			(at 2.050034 -26.774902 90)
			(size 0.519938 1.4986)
			(layers "F.Cu" "F.Mask" "F.Paste")
			(net "GND")
		)
		(pad "189" smd rect
			(at 2.050034 -25.925018 90)
			(size 0.519938 1.4986)
			(layers "F.Cu" "F.Mask" "F.Paste")
			(net "M_E_CPU1_SA_DQS_DN<8>")
		)
		(pad "190" smd rect
			(at 2.050034 -25.07488 90)
			(size 0.519938 1.4986)
			(layers "F.Cu" "F.Mask" "F.Paste")
			(net "M_E_CPU1_SA_DQS_DP<8>")
		)
		(pad "191" smd rect
			(at 2.050034 -24.224996 90)
			(size 0.519938 1.4986)
			(layers "F.Cu" "F.Mask" "F.Paste")
			(net "GND")
		)
		(pad "192" smd rect
			(at 2.050034 -23.375112 90)
			(size 0.519938 1.4986)
			(layers "F.Cu" "F.Mask" "F.Paste")
			(net "M_E_CPU1_SA_DQ<30>")
		)
		(pad "193" smd rect
			(at 2.050034 -22.524974 90)
			(size 0.519938 1.4986)
			(layers "F.Cu" "F.Mask" "F.Paste")
			(net "GND")
		)
		(pad "194" smd rect
			(at 2.050034 -21.67509 90)
			(size 0.519938 1.4986)
			(layers "F.Cu" "F.Mask" "F.Paste")
			(net "M_E_CPU1_SA_DQ<31>")
		)
		(pad "195" smd rect
			(at 2.050034 -20.824952 90)
			(size 0.519938 1.4986)
			(layers "F.Cu" "F.Mask" "F.Paste")
			(net "GND")
		)
		(pad "196" smd rect
			(at 2.050034 -19.975068 90)
			(size 0.519938 1.4986)
			(layers "F.Cu" "F.Mask" "F.Paste")
			(net "M_E_CPU1_SA_CB<2>")
		)
		(pad "197" smd rect
			(at 2.050034 -19.12493 90)
			(size 0.519938 1.4986)
			(layers "F.Cu" "F.Mask" "F.Paste")
			(net "GND")
		)
		(pad "198" smd rect
			(at 2.050034 -18.275046 90)
			(size 0.519938 1.4986)
			(layers "F.Cu" "F.Mask" "F.Paste")
			(net "M_E_CPU1_SA_CB<3>")
		)
		(pad "199" smd rect
			(at 2.050034 -17.424908 90)
			(size 0.519938 1.4986)
			(layers "F.Cu" "F.Mask" "F.Paste")
			(net "GND")
		)
		(pad "200" smd rect
			(at 2.050034 -16.575024 90)
			(size 0.519938 1.4986)
			(layers "F.Cu" "F.Mask" "F.Paste")
			(net "M_E_CPU1_SA_DQS_DN<9>")
		)
		(pad "201" smd rect
			(at 2.050034 -15.724886 90)
			(size 0.519938 1.4986)
			(layers "F.Cu" "F.Mask" "F.Paste")
			(net "M_E_CPU1_SA_DQS_DP<9>")
		)
		(pad "202" smd rect
			(at 2.050034 -14.875002 90)
			(size 0.519938 1.4986)
			(layers "F.Cu" "F.Mask" "F.Paste")
			(net "GND")
		)
		(pad "203" smd rect
			(at 2.050034 -14.025118 90)
			(size 0.519938 1.4986)
			(layers "F.Cu" "F.Mask" "F.Paste")
			(net "M_E_CPU1_SA_CB<6>")
		)
		(pad "204" smd rect
			(at 2.050034 -13.17498 90)
			(size 0.519938 1.4986)
			(layers "F.Cu" "F.Mask" "F.Paste")
			(net "GND")
		)
		(pad "205" smd rect
			(at 2.050034 -12.325096 90)
			(size 0.519938 1.4986)
			(layers "F.Cu" "F.Mask" "F.Paste")
			(net "M_E_CPU1_SA_CB<7>")
		)
		(pad "206" smd rect
			(at 2.050034 -11.474958 90)
			(size 0.519938 1.4986)
			(layers "F.Cu" "F.Mask" "F.Paste")
			(net "GND")
		)
		(pad "207" smd rect
			(at 2.050034 -10.625074 90)
			(size 0.519938 1.4986)
			(layers "F.Cu" "F.Mask" "F.Paste")
			(net "M_E_CPU1_RESET_N")
		)
		(pad "208" smd rect
			(at 2.050034 -9.774936 90)
			(size 0.519938 1.4986)
			(layers "F.Cu" "F.Mask" "F.Paste")
			(net "GND")
		)
		(pad "209" smd rect
			(at 2.050034 -8.925052 90)
			(size 0.519938 1.4986)
			(layers "F.Cu" "F.Mask" "F.Paste")
			(net "M_E_CPU1_SA_CS_N<1>")
		)
		(pad "210" smd rect
			(at 2.050034 -8.074914 90)
			(size 0.519938 1.4986)
			(layers "F.Cu" "F.Mask" "F.Paste")
			(net "GND")
		)
		(pad "211" smd rect
			(at 2.050034 -7.22503 90)
			(size 0.519938 1.4986)
			(layers "F.Cu" "F.Mask" "F.Paste")
			(net "M_E_CPU1_SA_CA<1>")
		)
		(pad "212" smd rect
			(at 2.050034 -6.374892 90)
			(size 0.519938 1.4986)
			(layers "F.Cu" "F.Mask" "F.Paste")
			(net "GND")
		)
		(pad "213" smd rect
			(at 2.050034 -5.525008 90)
			(size 0.519938 1.4986)
			(layers "F.Cu" "F.Mask" "F.Paste")
			(net "M_E_CPU1_SA_CA<3>")
		)
		(pad "214" smd rect
			(at 2.050034 -4.675124 90)
			(size 0.519938 1.4986)
			(layers "F.Cu" "F.Mask" "F.Paste")
			(net "GND")
		)
		(pad "215" smd rect
			(at 2.050034 -3.824986 90)
			(size 0.519938 1.4986)
			(layers "F.Cu" "F.Mask" "F.Paste")
			(net "M_E_CPU1_SA_CA<5>")
		)
		(pad "216" smd rect
			(at 2.050034 -2.975102 90)
			(size 0.519938 1.4986)
			(layers "F.Cu" "F.Mask" "F.Paste")
			(net "GND")
		)
		(pad "217" smd rect
			(at 2.050034 -2.124964 90)
			(size 0.519938 1.4986)
			(layers "F.Cu" "F.Mask" "F.Paste")
			(net "M_E_CPU1_CLK_DP<0>")
		)
		(pad "218" smd rect
			(at 2.050034 -1.27508 90)
			(size 0.519938 1.4986)
			(layers "F.Cu" "F.Mask" "F.Paste")
			(net "M_E_CPU1_CLK_DN<0>")
		)
		(pad "219" smd rect
			(at 2.050034 -0.424942 90)
			(size 0.519938 1.4986)
			(layers "F.Cu" "F.Mask" "F.Paste")
			(net "GND")
		)
		(pad "220" smd rect
			(at 2.050034 5.525008 90)
			(size 0.519938 1.4986)
			(layers "F.Cu" "F.Mask" "F.Paste")
			(net "Net_2316")
		)
		(pad "221" smd rect
			(at 2.050034 6.374892 90)
			(size 0.519938 1.4986)
			(layers "F.Cu" "F.Mask" "F.Paste")
			(net "M_E_CPU1_SB_CA<1>")
		)
		(pad "222" smd rect
			(at 2.050034 7.22503 90)
			(size 0.519938 1.4986)
			(layers "F.Cu" "F.Mask" "F.Paste")
			(net "GND")
		)
		(pad "223" smd rect
			(at 2.050034 8.074914 90)
			(size 0.519938 1.4986)
			(layers "F.Cu" "F.Mask" "F.Paste")
			(net "M_E_CPU1_SB_CA<3>")
		)
		(pad "224" smd rect
			(at 2.050034 8.925052 90)
			(size 0.519938 1.4986)
			(layers "F.Cu" "F.Mask" "F.Paste")
			(net "GND")
		)
		(pad "225" smd rect
			(at 2.050034 9.774936 90)
			(size 0.519938 1.4986)
			(layers "F.Cu" "F.Mask" "F.Paste")
			(net "M_E_CPU1_SB_CA<5>")
		)
		(pad "226" smd rect
			(at 2.050034 10.625074 90)
			(size 0.519938 1.4986)
			(layers "F.Cu" "F.Mask" "F.Paste")
			(net "GND")
		)
		(pad "227" smd rect
			(at 2.050034 11.474958 90)
			(size 0.519938 1.4986)
			(layers "F.Cu" "F.Mask" "F.Paste")
			(net "M_E_CPU1_SB_PAR")
		)
		(pad "228" smd rect
			(at 2.050034 12.325096 90)
			(size 0.519938 1.4986)
			(layers "F.Cu" "F.Mask" "F.Paste")
			(net "GND")
		)
		(pad "229" smd rect
			(at 2.050034 13.17498 90)
			(size 0.519938 1.4986)
			(layers "F.Cu" "F.Mask" "F.Paste")
			(net "M_E_CPU1_SB_CS_N<1>")
		)
		(pad "230" smd rect
			(at 2.050034 14.025118 90)
			(size 0.519938 1.4986)
			(layers "F.Cu" "F.Mask" "F.Paste")
			(net "GND")
		)
		(pad "231" smd rect
			(at 2.050034 14.875002 90)
			(size 0.519938 1.4986)
			(layers "F.Cu" "F.Mask" "F.Paste")
			(net "Net_2317")
		)
		(pad "232" smd rect
			(at 2.050034 15.724886 90)
			(size 0.519938 1.4986)
			(layers "F.Cu" "F.Mask" "F.Paste")
			(net "Net_2318")
		)
		(pad "233" smd rect
			(at 2.050034 16.575024 90)
			(size 0.519938 1.4986)
			(layers "F.Cu" "F.Mask" "F.Paste")
			(net "GND")
		)
		(pad "234" smd rect
			(at 2.050034 17.424908 90)
			(size 0.519938 1.4986)
			(layers "F.Cu" "F.Mask" "F.Paste")
			(net "M_E_CPU1_SB_CB<6>")
		)
		(pad "235" smd rect
			(at 2.050034 18.275046 90)
			(size 0.519938 1.4986)
			(layers "F.Cu" "F.Mask" "F.Paste")
			(net "GND")
		)
		(pad "236" smd rect
			(at 2.050034 19.12493 90)
			(size 0.519938 1.4986)
			(layers "F.Cu" "F.Mask" "F.Paste")
			(net "M_E_CPU1_SB_CB<7>")
		)
		(pad "237" smd rect
			(at 2.050034 19.975068 90)
			(size 0.519938 1.4986)
			(layers "F.Cu" "F.Mask" "F.Paste")
			(net "GND")
		)
		(pad "238" smd rect
			(at 2.050034 20.824952 90)
			(size 0.519938 1.4986)
			(layers "F.Cu" "F.Mask" "F.Paste")
			(net "M_E_CPU1_SB_DQS_DN<4>")
		)
		(pad "239" smd rect
			(at 2.050034 21.67509 90)
			(size 0.519938 1.4986)
			(layers "F.Cu" "F.Mask" "F.Paste")
			(net "M_E_CPU1_SB_DQS_DP<4>")
		)
		(pad "240" smd rect
			(at 2.050034 22.524974 90)
			(size 0.519938 1.4986)
			(layers "F.Cu" "F.Mask" "F.Paste")
			(net "GND")
		)
		(pad "241" smd rect
			(at 2.050034 23.375112 90)
			(size 0.519938 1.4986)
			(layers "F.Cu" "F.Mask" "F.Paste")
			(net "M_E_CPU1_SB_CB<2>")
		)
		(pad "242" smd rect
			(at 2.050034 24.224996 90)
			(size 0.519938 1.4986)
			(layers "F.Cu" "F.Mask" "F.Paste")
			(net "GND")
		)
		(pad "243" smd rect
			(at 2.050034 25.07488 90)
			(size 0.519938 1.4986)
			(layers "F.Cu" "F.Mask" "F.Paste")
			(net "M_E_CPU1_SB_CB<3>")
		)
		(pad "244" smd rect
			(at 2.050034 25.925018 90)
			(size 0.519938 1.4986)
			(layers "F.Cu" "F.Mask" "F.Paste")
			(net "GND")
		)
		(pad "245" smd rect
			(at 2.050034 26.774902 90)
			(size 0.519938 1.4986)
			(layers "F.Cu" "F.Mask" "F.Paste")
			(net "M_E_CPU1_SB_DQ<2>")
		)
		(pad "246" smd rect
			(at 2.050034 27.62504 90)
			(size 0.519938 1.4986)
			(layers "F.Cu" "F.Mask" "F.Paste")
			(net "GND")
		)
		(pad "247" smd rect
			(at 2.050034 28.474924 90)
			(size 0.519938 1.4986)
			(layers "F.Cu" "F.Mask" "F.Paste")
			(net "M_E_CPU1_SB_DQ<3>")
		)
		(pad "248" smd rect
			(at 2.050034 29.325062 90)
			(size 0.519938 1.4986)
			(layers "F.Cu" "F.Mask" "F.Paste")
			(net "GND")
		)
		(pad "249" smd rect
			(at 2.050034 30.174946 90)
			(size 0.519938 1.4986)
			(layers "F.Cu" "F.Mask" "F.Paste")
			(net "M_E_CPU1_SB_DQS_DN<5>")
		)
		(pad "250" smd rect
			(at 2.050034 31.025084 90)
			(size 0.519938 1.4986)
			(layers "F.Cu" "F.Mask" "F.Paste")
			(net "M_E_CPU1_SB_DQS_DP<5>")
		)
		(pad "251" smd rect
			(at 2.050034 31.874968 90)
			(size 0.519938 1.4986)
			(layers "F.Cu" "F.Mask" "F.Paste")
			(net "GND")
		)
		(pad "252" smd rect
			(at 2.050034 32.725106 90)
			(size 0.519938 1.4986)
			(layers "F.Cu" "F.Mask" "F.Paste")
			(net "M_E_CPU1_SB_DQ<6>")
		)
		(pad "253" smd rect
			(at 2.050034 33.57499 90)
			(size 0.519938 1.4986)
			(layers "F.Cu" "F.Mask" "F.Paste")
			(net "GND")
		)
		(pad "254" smd rect
			(at 2.050034 34.425128 90)
			(size 0.519938 1.4986)
			(layers "F.Cu" "F.Mask" "F.Paste")
			(net "M_E_CPU1_SB_DQ<7>")
		)
		(pad "255" smd rect
			(at 2.050034 35.275012 90)
			(size 0.519938 1.4986)
			(layers "F.Cu" "F.Mask" "F.Paste")
			(net "GND")
		)
		(pad "256" smd rect
			(at 2.050034 36.124896 90)
			(size 0.519938 1.4986)
			(layers "F.Cu" "F.Mask" "F.Paste")
			(net "M_E_CPU1_SB_DQ<10>")
		)
		(pad "257" smd rect
			(at 2.050034 36.975034 90)
			(size 0.519938 1.4986)
			(layers "F.Cu" "F.Mask" "F.Paste")
			(net "GND")
		)
		(pad "258" smd rect
			(at 2.050034 37.824918 90)
			(size 0.519938 1.4986)
			(layers "F.Cu" "F.Mask" "F.Paste")
			(net "M_E_CPU1_SB_DQ<11>")
		)
		(pad "259" smd rect
			(at 2.050034 38.675056 90)
			(size 0.519938 1.4986)
			(layers "F.Cu" "F.Mask" "F.Paste")
			(net "GND")
		)
		(pad "260" smd rect
			(at 2.050034 39.52494 90)
			(size 0.519938 1.4986)
			(layers "F.Cu" "F.Mask" "F.Paste")
			(net "M_E_CPU1_SB_DQS_DN<6>")
		)
		(pad "261" smd rect
			(at 2.050034 40.375078 90)
			(size 0.519938 1.4986)
			(layers "F.Cu" "F.Mask" "F.Paste")
			(net "M_E_CPU1_SB_DQS_DP<6>")
		)
		(pad "262" smd rect
			(at 2.050034 41.224962 90)
			(size 0.519938 1.4986)
			(layers "F.Cu" "F.Mask" "F.Paste")
			(net "GND")
		)
		(pad "263" smd rect
			(at 2.050034 42.0751 90)
			(size 0.519938 1.4986)
			(layers "F.Cu" "F.Mask" "F.Paste")
			(net "M_E_CPU1_SB_DQ<14>")
		)
		(pad "264" smd rect
			(at 2.050034 42.924984 90)
			(size 0.519938 1.4986)
			(layers "F.Cu" "F.Mask" "F.Paste")
			(net "GND")
		)
		(pad "265" smd rect
			(at 2.050034 43.775122 90)
			(size 0.519938 1.4986)
			(layers "F.Cu" "F.Mask" "F.Paste")
			(net "M_E_CPU1_SB_DQ<15>")
		)
		(pad "266" smd rect
			(at 2.050034 44.625006 90)
			(size 0.519938 1.4986)
			(layers "F.Cu" "F.Mask" "F.Paste")
			(net "GND")
		)
		(pad "267" smd rect
			(at 2.050034 45.47489 90)
			(size 0.519938 1.4986)
			(layers "F.Cu" "F.Mask" "F.Paste")
			(net "M_E_CPU1_SB_DQ<18>")
		)
		(pad "268" smd rect
			(at 2.050034 46.325028 90)
			(size 0.519938 1.4986)
			(layers "F.Cu" "F.Mask" "F.Paste")
			(net "GND")
		)
		(pad "269" smd rect
			(at 2.050034 47.174912 90)
			(size 0.519938 1.4986)
			(layers "F.Cu" "F.Mask" "F.Paste")
			(net "M_E_CPU1_SB_DQ<19>")
		)
		(pad "270" smd rect
			(at 2.050034 48.02505 90)
			(size 0.519938 1.4986)
			(layers "F.Cu" "F.Mask" "F.Paste")
			(net "GND")
		)
		(pad "271" smd rect
			(at 2.050034 48.874934 90)
			(size 0.519938 1.4986)
			(layers "F.Cu" "F.Mask" "F.Paste")
			(net "M_E_CPU1_SB_DQS_DN<7>")
		)
		(pad "272" smd rect
			(at 2.050034 49.725072 90)
			(size 0.519938 1.4986)
			(layers "F.Cu" "F.Mask" "F.Paste")
			(net "M_E_CPU1_SB_DQS_DP<7>")
		)
		(pad "273" smd rect
			(at 2.050034 50.574956 90)
			(size 0.519938 1.4986)
			(layers "F.Cu" "F.Mask" "F.Paste")
			(net "GND")
		)
		(pad "274" smd rect
			(at 2.050034 51.425094 90)
			(size 0.519938 1.4986)
			(layers "F.Cu" "F.Mask" "F.Paste")
			(net "M_E_CPU1_SB_DQ<22>")
		)
		(pad "275" smd rect
			(at 2.050034 52.274978 90)
			(size 0.519938 1.4986)
			(layers "F.Cu" "F.Mask" "F.Paste")
			(net "GND")
		)
		(pad "276" smd rect
			(at 2.050034 53.125116 90)
			(size 0.519938 1.4986)
			(layers "F.Cu" "F.Mask" "F.Paste")
			(net "M_E_CPU1_SB_DQ<23>")
		)
		(pad "277" smd rect
			(at 2.050034 53.975 90)
			(size 0.519938 1.4986)
			(layers "F.Cu" "F.Mask" "F.Paste")
			(net "GND")
		)
		(pad "278" smd rect
			(at 2.050034 54.824884 90)
			(size 0.519938 1.4986)
			(layers "F.Cu" "F.Mask" "F.Paste")
			(net "M_E_CPU1_SB_DQ<26>")
		)
		(pad "279" smd rect
			(at 2.050034 55.675022 90)
			(size 0.519938 1.4986)
			(layers "F.Cu" "F.Mask" "F.Paste")
			(net "GND")
		)
		(pad "280" smd rect
			(at 2.050034 56.524906 90)
			(size 0.519938 1.4986)
			(layers "F.Cu" "F.Mask" "F.Paste")
			(net "M_E_CPU1_SB_DQ<27>")
		)
		(pad "281" smd rect
			(at 2.050034 57.375044 90)
			(size 0.519938 1.4986)
			(layers "F.Cu" "F.Mask" "F.Paste")
			(net "GND")
		)
		(pad "282" smd rect
			(at 2.050034 58.224928 90)
			(size 0.519938 1.4986)
			(layers "F.Cu" "F.Mask" "F.Paste")
			(net "M_E_CPU1_SB_DQS_DN<8>")
		)
		(pad "283" smd rect
			(at 2.050034 59.075066 90)
			(size 0.519938 1.4986)
			(layers "F.Cu" "F.Mask" "F.Paste")
			(net "M_E_CPU1_SB_DQS_DP<8>")
		)
		(pad "284" smd rect
			(at 2.050034 59.92495 90)
			(size 0.519938 1.4986)
			(layers "F.Cu" "F.Mask" "F.Paste")
			(net "GND")
		)
		(pad "285" smd rect
			(at 2.050034 60.775088 90)
			(size 0.519938 1.4986)
			(layers "F.Cu" "F.Mask" "F.Paste")
			(net "M_E_CPU1_SB_DQ<30>")
		)
		(pad "286" smd rect
			(at 2.050034 61.624972 90)
			(size 0.519938 1.4986)
			(layers "F.Cu" "F.Mask" "F.Paste")
			(net "GND")
		)
		(pad "287" smd rect
			(at 2.050034 62.47511 90)
			(size 0.519938 1.4986)
			(layers "F.Cu" "F.Mask" "F.Paste")
			(net "M_E_CPU1_SB_DQ<31>")
		)
		(pad "288" smd rect
			(at 2.050034 63.324994 90)
			(size 0.519938 1.4986)
			(layers "F.Cu" "F.Mask" "F.Paste")
			(net "GND")
		)
		(pad "G1" thru_hole oval
			(at 0 -68.97497 90)
			(size 1.7272 3.4798)
			(drill oval 1.2192 2.4638)
			(layers "*.Cu" "*.Mask")
			(remove_unused_layers no)
			(net "GND")
			(clearance 0.127)
			(thermal_gap 0.127)
		)
		(pad "G2" thru_hole oval
			(at 0 3.875024 90)
			(size 1.7272 3.4798)
			(drill oval 1.2192 2.4638)
			(layers "*.Cu" "*.Mask")
			(remove_unused_layers no)
			(net "GND")
			(clearance 0.127)
			(thermal_gap 0.127)
		)
		(pad "G3" thru_hole oval
			(at 0 68.97497 90)
			(size 1.7272 3.4798)
			(drill oval 1.2192 2.4638)
			(layers "*.Cu" "*.Mask")
			(remove_unused_layers no)
			(net "GND")
			(clearance 0.127)
			(thermal_gap 0.127)
		)
	)
	(footprint ""
		(layer "F.Cu")
		(at 149.987254 -23.284942 -90)
		(property "Reference" "R6026"
			(at 0 0 270)
			(layer "F.SilkS")
			(hide yes)
			(effects
				(font
					(size 1.27 1.27)
				)
			)
		)
		(property "Value" ""
			(at 0 0 270)
			(layer "F.Fab")
			(effects
				(font
					(size 1.27 1.27)
				)
			)
		)
		(duplicate_pad_numbers_are_jumpers no)
		(fp_line
			(start -0.7874 0.4064)
			(end -0.7874 -0.4064)
			(stroke
				(width 0.1524)
				(type default)
			)
			(layer "F.SilkS")
		)
		(fp_line
			(start 0.7874 0.4064)
			(end -0.7874 0.4064)
			(stroke
				(width 0.1524)
				(type default)
			)
			(layer "F.SilkS")
		)
		(fp_line
			(start -0.7874 -0.4064)
			(end 0.7874 -0.4064)
			(stroke
				(width 0.1524)
				(type default)
			)
			(layer "F.SilkS")
		)
		(fp_line
			(start 0.7874 -0.4064)
			(end 0.7874 0.4064)
			(stroke
				(width 0.1524)
				(type default)
			)
			(layer "F.SilkS")
		)
		(fp_line
			(start -0.67945 0.3048)
			(end -0.67945 -0.305054)
			(stroke
				(width 0.1)
				(type default)
			)
			(layer "F.Fab")
		)
		(fp_line
			(start -0.12065 0.3048)
			(end -0.67945 0.3048)
			(stroke
				(width 0.1)
				(type default)
			)
			(layer "F.Fab")
		)
		(fp_line
			(start 0.120396 0.3048)
			(end 0.120396 0.2794)
			(stroke
				(width 0.1)
				(type default)
			)
			(layer "F.Fab")
		)
		(fp_line
			(start 0.67945 0.3048)
			(end 0.120396 0.3048)
			(stroke
				(width 0.1)
				(type default)
			)
			(layer "F.Fab")
		)
		(fp_line
			(start -0.12065 0.2794)
			(end -0.12065 0.3048)
			(stroke
				(width 0.1)
				(type default)
			)
			(layer "F.Fab")
		)
		(fp_line
			(start 0.120396 0.2794)
			(end -0.12065 0.2794)
			(stroke
				(width 0.1)
				(type default)
			)
			(layer "F.Fab")
		)
		(fp_line
			(start -0.12065 -0.2794)
			(end 0.12065 -0.2794)
			(stroke
				(width 0.1)
				(type default)
			)
			(layer "F.Fab")
		)
		(fp_line
			(start 0.12065 -0.2794)
			(end 0.12065 -0.3048)
			(stroke
				(width 0.1)
				(type default)
			)
			(layer "F.Fab")
		)
		(fp_line
			(start 0.12065 -0.3048)
			(end 0.67945 -0.3048)
			(stroke
				(width 0.1)
				(type default)
			)
			(layer "F.Fab")
		)
		(fp_line
			(start 0.67945 -0.3048)
			(end 0.67945 0.3048)
			(stroke
				(width 0.1)
				(type default)
			)
			(layer "F.Fab")
		)
		(fp_line
			(start -0.67945 -0.305054)
			(end -0.12065 -0.305054)
			(stroke
				(width 0.1)
				(type default)
			)
			(layer "F.Fab")
		)
		(fp_line
			(start -0.12065 -0.305054)
			(end -0.12065 -0.2794)
			(stroke
				(width 0.1)
				(type default)
			)
			(layer "F.Fab")
		)
		(pad "1" smd circle
			(at -0.40005 0 270)
			(size 0 0)
			(layers "F.Cu" "F.Mask" "F.Paste")
			(net "SGPIO_SCM_INTR_N")
		)
		(pad "2" smd circle
			(at 0.40005 0 270)
			(size 0 0)
			(layers "F.Cu" "F.Mask" "F.Paste")
			(net "SGPIO_SCM_INTR_R1_N")
		)
	)
	(footprint ""
		(layer "F.Cu")
		(at 180.9242 -96.103948 90)
		(property "Reference" "R246"
			(at 0 0 90)
			(layer "F.SilkS")
			(hide yes)
			(effects
				(font
					(size 1.27 1.27)
				)
			)
		)
		(property "Value" ""
			(at 0 0 90)
			(layer "F.Fab")
			(effects
				(font
					(size 1.27 1.27)
				)
			)
		)
		(duplicate_pad_numbers_are_jumpers no)
		(fp_line
			(start 0.7874 -0.4064)
			(end 0.7874 0.4064)
			(stroke
				(width 0.1524)
				(type default)
			)
			(layer "F.SilkS")
		)
		(fp_line
			(start -0.7874 -0.4064)
			(end 0.7874 -0.4064)
			(stroke
				(width 0.1524)
				(type default)
			)
			(layer "F.SilkS")
		)
		(fp_line
			(start 0.7874 0.4064)
			(end -0.7874 0.4064)
			(stroke
				(width 0.1524)
				(type default)
			)
			(layer "F.SilkS")
		)
		(fp_line
			(start -0.7874 0.4064)
			(end -0.7874 -0.4064)
			(stroke
				(width 0.1524)
				(type default)
			)
			(layer "F.SilkS")
		)
		(fp_line
			(start -0.12065 -0.305054)
			(end -0.12065 -0.2794)
			(stroke
				(width 0.1)
				(type default)
			)
			(layer "F.Fab")
		)
		(fp_line
			(start -0.67945 -0.305054)
			(end -0.12065 -0.305054)
			(stroke
				(width 0.1)
				(type default)
			)
			(layer "F.Fab")
		)
		(fp_line
			(start 0.67945 -0.3048)
			(end 0.67945 0.3048)
			(stroke
				(width 0.1)
				(type default)
			)
			(layer "F.Fab")
		)
		(fp_line
			(start 0.12065 -0.3048)
			(end 0.67945 -0.3048)
			(stroke
				(width 0.1)
				(type default)
			)
			(layer "F.Fab")
		)
		(fp_line
			(start 0.12065 -0.2794)
			(end 0.12065 -0.3048)
			(stroke
				(width 0.1)
				(type default)
			)
			(layer "F.Fab")
		)
		(fp_line
			(start -0.12065 -0.2794)
			(end 0.12065 -0.2794)
			(stroke
				(width 0.1)
				(type default)
			)
			(layer "F.Fab")
		)
		(fp_line
			(start 0.120396 0.2794)
			(end -0.12065 0.2794)
			(stroke
				(width 0.1)
				(type default)
			)
			(layer "F.Fab")
		)
		(fp_line
			(start -0.12065 0.2794)
			(end -0.12065 0.3048)
			(stroke
				(width 0.1)
				(type default)
			)
			(layer "F.Fab")
		)
		(fp_line
			(start 0.67945 0.3048)
			(end 0.120396 0.3048)
			(stroke
				(width 0.1)
				(type default)
			)
			(layer "F.Fab")
		)
		(fp_line
			(start 0.120396 0.3048)
			(end 0.120396 0.2794)
			(stroke
				(width 0.1)
				(type default)
			)
			(layer "F.Fab")
		)
		(fp_line
			(start -0.12065 0.3048)
			(end -0.67945 0.3048)
			(stroke
				(width 0.1)
				(type default)
			)
			(layer "F.Fab")
		)
		(fp_line
			(start -0.67945 0.3048)
			(end -0.67945 -0.305054)
			(stroke
				(width 0.1)
				(type default)
			)
			(layer "F.Fab")
		)
		(pad "1" smd circle
			(at -0.40005 0 90)
			(size 0 0)
			(layers "F.Cu" "F.Mask" "F.Paste")
			(net "IRQ_TPM_SPI_R_N")
		)
		(pad "2" smd circle
			(at 0.40005 0 90)
			(size 0 0)
			(layers "F.Cu" "F.Mask" "F.Paste")
			(net "IRQ_TPM_SPI_R1_N")
		)
	)
	(footprint ""
		(layer "F.Cu")
		(at 52.011072 -401.989036 90)
		(property "Reference" "C7038"
			(at 0 0 90)
			(layer "F.SilkS")
			(hide yes)
			(effects
				(font
					(size 1.27 1.27)
				)
			)
		)
		(property "Value" ""
			(at 0 0 90)
			(layer "F.Fab")
			(effects
				(font
					(size 1.27 1.27)
				)
			)
		)
		(duplicate_pad_numbers_are_jumpers no)
		(fp_line
			(start 1.524 -0.762)
			(end 1.524 0.762)
			(stroke
				(width 0.1524)
				(type default)
			)
			(layer "F.SilkS")
		)
		(fp_line
			(start -1.524 -0.762)
			(end 1.524 -0.762)
			(stroke
				(width 0.1524)
				(type default)
			)
			(layer "F.SilkS")
		)
		(fp_line
			(start 1.524 0.762)
			(end -1.524 0.762)
			(stroke
				(width 0.1524)
				(type default)
			)
			(layer "F.SilkS")
		)
		(fp_line
			(start -1.524 0.762)
			(end -1.524 -0.762)
			(stroke
				(width 0.1524)
				(type default)
			)
			(layer "F.SilkS")
		)
		(fp_line
			(start 1.1049 -0.724916)
			(end -1.1049 -0.724916)
			(stroke
				(width 0.1)
				(type default)
			)
			(layer "F.Fab")
		)
		(fp_line
			(start -1.1049 -0.724916)
			(end -1.1049 0.724916)
			(stroke
				(width 0.1)
				(type default)
			)
			(layer "F.Fab")
		)
		(fp_line
			(start 1.1049 0.724916)
			(end 1.1049 -0.724916)
			(stroke
				(width 0.1)
				(type default)
			)
			(layer "F.Fab")
		)
		(fp_line
			(start -1.1049 0.724916)
			(end 1.1049 0.724916)
			(stroke
				(width 0.1)
				(type default)
			)
			(layer "F.Fab")
		)
		(pad "1" smd rect
			(at -0.889 0 270)
			(size 1.016 1.27)
			(layers "F.Cu" "F.Mask" "F.Paste")
			(net "P0V9_CPU1_RT_2D")
		)
		(pad "2" smd rect
			(at 0.889 0 270)
			(size 1.016 1.27)
			(layers "F.Cu" "F.Mask" "F.Paste")
			(net "GND")
		)
	)
	(footprint ""
		(layer "F.Cu")
		(at 302.1584 -363.982)
		(property "Reference" "R8057"
			(at 0 0 0)
			(layer "F.SilkS")
			(hide yes)
			(effects
				(font
					(size 1.27 1.27)
				)
			)
		)
		(property "Value" ""
			(at 0 0 0)
			(layer "F.Fab")
			(effects
				(font
					(size 1.27 1.27)
				)
			)
		)
		(duplicate_pad_numbers_are_jumpers no)
		(fp_line
			(start -0.7874 -0.4064)
			(end 0.7874 -0.4064)
			(stroke
				(width 0.1524)
				(type default)
			)
			(layer "F.SilkS")
		)
		(fp_line
			(start -0.7874 0.4064)
			(end -0.7874 -0.4064)
			(stroke
				(width 0.1524)
				(type default)
			)
			(layer "F.SilkS")
		)
		(fp_line
			(start 0.7874 -0.4064)
			(end 0.7874 0.4064)
			(stroke
				(width 0.1524)
				(type default)
			)
			(layer "F.SilkS")
		)
		(fp_line
			(start 0.7874 0.4064)
			(end -0.7874 0.4064)
			(stroke
				(width 0.1524)
				(type default)
			)
			(layer "F.SilkS")
		)
		(fp_line
			(start -0.67945 -0.305054)
			(end -0.12065 -0.305054)
			(stroke
				(width 0.1)
				(type default)
			)
			(layer "F.Fab")
		)
		(fp_line
			(start -0.67945 0.3048)
			(end -0.67945 -0.305054)
			(stroke
				(width 0.1)
				(type default)
			)
			(layer "F.Fab")
		)
		(fp_line
			(start -0.12065 -0.305054)
			(end -0.12065 -0.2794)
			(stroke
				(width 0.1)
				(type default)
			)
			(layer "F.Fab")
		)
		(fp_line
			(start -0.12065 -0.2794)
			(end 0.12065 -0.2794)
			(stroke
				(width 0.1)
				(type default)
			)
			(layer "F.Fab")
		)
		(fp_line
			(start -0.12065 0.2794)
			(end -0.12065 0.3048)
			(stroke
				(width 0.1)
				(type default)
			)
			(layer "F.Fab")
		)
		(fp_line
			(start -0.12065 0.3048)
			(end -0.67945 0.3048)
			(stroke
				(width 0.1)
				(type default)
			)
			(layer "F.Fab")
		)
		(fp_line
			(start 0.120396 0.2794)
			(end -0.12065 0.2794)
			(stroke
				(width 0.1)
				(type default)
			)
			(layer "F.Fab")
		)
		(fp_line
			(start 0.120396 0.3048)
			(end 0.120396 0.2794)
			(stroke
				(width 0.1)
				(type default)
			)
			(layer "F.Fab")
		)
		(fp_line
			(start 0.12065 -0.3048)
			(end 0.67945 -0.3048)
			(stroke
				(width 0.1)
				(type default)
			)
			(layer "F.Fab")
		)
		(fp_line
			(start 0.12065 -0.2794)
			(end 0.12065 -0.3048)
			(stroke
				(width 0.1)
				(type default)
			)
			(layer "F.Fab")
		)
		(fp_line
			(start 0.67945 -0.3048)
			(end 0.67945 0.3048)
			(stroke
				(width 0.1)
				(type default)
			)
			(layer "F.Fab")
		)
		(fp_line
			(start 0.67945 0.3048)
			(end 0.120396 0.3048)
			(stroke
				(width 0.1)
				(type default)
			)
			(layer "F.Fab")
		)
		(pad "1" smd circle
			(at -0.40005 0)
			(size 0 0)
			(layers "F.Cu" "F.Mask" "F.Paste")
			(net "PWRGD_PVDDCR_CPU1_P0")
		)
		(pad "2" smd circle
			(at 0.40005 0)
			(size 0 0)
			(layers "F.Cu" "F.Mask" "F.Paste")
			(net "PWRGD_PVDDCR_CPU1_P0_R")
		)
	)
	(footprint ""
		(layer "F.Cu")
		(at 53.543454 -346.721176)
		(property "Reference" "PU39"
			(at -3.124454 -7.709154 0)
			(unlocked yes)
			(layer "F.SilkS")
			(effects
				(font
					(size 0.7874 0.5842)
					(thickness 0.1524)
				)
				(justify left)
			)
		)
		(property "Value" ""
			(at 0 0 0)
			(layer "F.Fab")
			(effects
				(font
					(size 1.27 1.27)
				)
			)
		)
		(duplicate_pad_numbers_are_jumpers no)
		(fp_line
			(start -2.500122 -2.999994)
			(end -2.24409 -2.999994)
			(stroke
				(width 0.1524)
				(type default)
			)
			(layer "F.SilkS")
		)
		(fp_line
			(start -2.500122 -2.529078)
			(end -2.500122 -2.999994)
			(stroke
				(width 0.1524)
				(type default)
			)
			(layer "F.SilkS")
		)
		(fp_line
			(start -2.500122 0.6604)
			(end -2.500122 0.229108)
			(stroke
				(width 0.1524)
				(type default)
			)
			(layer "F.SilkS")
		)
		(fp_line
			(start -2.500122 2.999994)
			(end -2.500122 2.339594)
			(stroke
				(width 0.1524)
				(type default)
			)
			(layer "F.SilkS")
		)
		(fp_line
			(start -2.2987 2.999994)
			(end -2.500122 2.999994)
			(stroke
				(width 0.1524)
				(type default)
			)
			(layer "F.SilkS")
		)
		(fp_line
			(start 2.31394 -2.999994)
			(end 2.500122 -2.999994)
			(stroke
				(width 0.1524)
				(type default)
			)
			(layer "F.SilkS")
		)
		(fp_line
			(start 2.500122 -2.999994)
			(end 2.500122 -2.44348)
			(stroke
				(width 0.1524)
				(type default)
			)
			(layer "F.SilkS")
		)
		(fp_line
			(start 2.500122 2.339594)
			(end 2.500122 2.999994)
			(stroke
				(width 0.1524)
				(type default)
			)
			(layer "F.SilkS")
		)
		(fp_line
			(start 2.500122 2.999994)
			(end 2.2987 2.999994)
			(stroke
				(width 0.1524)
				(type default)
			)
			(layer "F.SilkS")
		)
		(fp_poly
			(pts
				(xy -2.72923 -2.454148) (xy -3.402838 -2.678684) (xy -2.953766 -3.127756)
			)
			(stroke
				(width 0)
				(type default)
			)
			(fill yes)
			(layer "F.SilkS")
		)
		(fp_line
			(start -2.500122 -2.999994)
			(end 2.500122 -2.999994)
			(stroke
				(width 0.1)
				(type default)
			)
			(layer "F.Fab")
		)
		(fp_line
			(start -2.500122 2.999994)
			(end -2.500122 -2.999994)
			(stroke
				(width 0.1)
				(type default)
			)
			(layer "F.Fab")
		)
		(fp_line
			(start 2.500122 -2.999994)
			(end 2.500122 2.999994)
			(stroke
				(width 0.1)
				(type default)
			)
			(layer "F.Fab")
		)
		(fp_line
			(start 2.500122 2.999994)
			(end -2.500122 2.999994)
			(stroke
				(width 0.1)
				(type default)
			)
			(layer "F.Fab")
		)
		(fp_poly
			(pts
				(xy -4.218432 -2.783078) (xy -4.218432 -1.767078) (xy -3.202432 -2.275078)
			)
			(stroke
				(width 0)
				(type default)
			)
			(fill yes)
			(layer "F.Fab")
		)
		(pad "1" smd rect
			(at -2.400046 -2.275078 90)
			(size 0.2286 0.6096)
			(layers "F.Cu" "F.Mask" "F.Paste")
			(net "PVDDIO_P1_VOS1")
		)
		(pad "2" smd rect
			(at -2.400046 -1.82499 90)
			(size 0.2286 0.6096)
			(layers "F.Cu" "F.Mask" "F.Paste")
			(net "GND")
		)
		(pad "3" smd rect
			(at -2.400046 -1.374902 90)
			(size 0.2286 0.6096)
			(layers "F.Cu" "F.Mask" "F.Paste")
			(net "PVDDIO_P1_VCC1")
		)
		(pad "4" smd rect
			(at -2.400046 -0.925068 90)
			(size 0.2286 0.6096)
			(layers "F.Cu" "F.Mask" "F.Paste")
			(net "PVDDCR_CPU1_P1_PVCC")
		)
		(pad "5" smd rect
			(at -2.400046 -0.47498 90)
			(size 0.2286 0.6096)
			(layers "F.Cu" "F.Mask" "F.Paste")
			(net "GND")
		)
		(pad "6" smd rect
			(at -2.400046 -0.024892 90)
			(size 0.2286 0.6096)
			(layers "F.Cu" "F.Mask" "F.Paste")
			(net "NC_PVDDIO_P1_GL1_1")
		)
		(pad "7_9-20_24" smd circle
			(at 0 1.150112 90)
			(size 0 0)
			(layers "F.Cu" "F.Mask" "F.Paste")
			(net "GND")
		)
		(pad "10_19" smd rect
			(at 0 2.899918 90)
			(size 0.6096 4.318)
			(layers "F.Cu" "F.Mask" "F.Paste")
			(net "SW_PVDDIO_P1_SW1")
		)
		(pad "25_29" smd rect
			(at 1.549908 -1.279906 270)
			(size 2.0574 2.3114)
			(layers "F.Cu" "F.Mask" "F.Paste")
			(net "SW_P12V_AUX_PVDDIO_P1_FLT")
		)
		(pad "30" smd rect
			(at 2.05994 -2.899918)
			(size 0.2286 0.6096)
			(layers "F.Cu" "F.Mask" "F.Paste")
			(net "SW_P12V_AUX_PVDDIO_P1_FLT")
		)
		(pad "31" smd rect
			(at 1.610106 -2.899918)
			(size 0.2286 0.6096)
			(layers "F.Cu" "F.Mask" "F.Paste")
			(net "NC_PVDDIO_P1_DNC1")
		)
		(pad "32" smd rect
			(at 1.160018 -2.899918)
			(size 0.2286 0.6096)
			(layers "F.Cu" "F.Mask" "F.Paste")
			(net "SW_PVDDIO_P1_BOOTR1")
		)
		(pad "33" smd rect
			(at 0.70993 -2.899918)
			(size 0.2286 0.6096)
			(layers "F.Cu" "F.Mask" "F.Paste")
			(net "SW_PVDDIO_P1_BOOT1")
		)
		(pad "34" smd rect
			(at 0.260096 -2.899918)
			(size 0.2286 0.6096)
			(layers "F.Cu" "F.Mask" "F.Paste")
			(net "PVDDIO_P1_PWM1")
		)
		(pad "35" smd rect
			(at -0.189992 -2.899918)
			(size 0.2286 0.6096)
			(layers "F.Cu" "F.Mask" "F.Paste")
			(net "PVDDIO_P1_VCC1")
		)
		(pad "36" smd rect
			(at -0.64008 -2.899918)
			(size 0.2286 0.6096)
			(layers "F.Cu" "F.Mask" "F.Paste")
			(net "PVDDIO_P1_TEMP1")
		)
		(pad "37" smd rect
			(at -1.089914 -2.899918)
			(size 0.2286 0.6096)
			(layers "F.Cu" "F.Mask" "F.Paste")
			(net "PVDDIO_P1_LSET1")
		)
		(pad "38" smd rect
			(at -1.540002 -2.899918)
			(size 0.2286 0.6096)
			(layers "F.Cu" "F.Mask" "F.Paste")
			(net "PVDDIO_P1_IMON1")
		)
		(pad "39" smd rect
			(at -1.99009 -2.899918)
			(size 0.2286 0.6096)
			(layers "F.Cu" "F.Mask" "F.Paste")
			(net "PVDDCR_CPU1_P1_VCCS")
		)
		(pad "40" smd rect
			(at -0.87503 -1.27508)
			(size 1.7526 1.9558)
			(layers "F.Cu" "F.Mask" "F.Paste")
			(net "GND")
		)
		(pad "41" smd rect
			(at -1.525016 0.249936 270)
			(size 0.3048 0.4572)
			(layers "F.Cu" "F.Mask" "F.Paste")
			(net "NC_PVDDIO_P1_GL2_1")
		)
		(zone
			(layer "F.Cu")
			(hatch none 0.5)
			(connect_pads
				(clearance 0)
			)
			(min_thickness 0.25)
			(keepout
				(tracks not_allowed)
				(vias allowed)
				(pads allowed)
				(copperpour not_allowed)
				(footprints allowed)
			)
			(placement
				(enabled no)
				(sheetname "")
			)
			(fill
				(thermal_gap 0.5)
				(thermal_bridge_width 0.5)
				(island_removal_mode 0)
			)
			(polygon
				(pts
					(xy 51.043332 -344.156284) (xy 51.043332 -344.470482) (xy 56.043576 -344.470482) (xy 56.043576 -344.138758)
					(xy 55.753254 -344.138758) (xy 55.753254 -344.176858) (xy 51.333654 -344.176858) (xy 51.333654 -344.156284)
				)
			)
		)
		(zone
			(layer "F.Cu")
			(hatch none 0.5)
			(connect_pads
				(clearance 0)
			)
			(min_thickness 0.25)
			(keepout
				(tracks not_allowed)
				(vias allowed)
				(pads allowed)
				(copperpour not_allowed)
				(footprints allowed)
			)
			(placement
				(enabled no)
				(sheetname "")
			)
			(fill
				(thermal_gap 0.5)
				(thermal_bridge_width 0.5)
				(island_removal_mode 0)
			)
			(polygon
				(pts
					(xy 53.595524 -346.967556) (xy 53.595524 -349.024956) (xy 51.741324 -349.024956) (xy 51.741324 -348.78391)
					(xy 51.499008 -348.78391) (xy 51.499008 -349.265494) (xy 55.350664 -349.265494) (xy 55.350664 -349.080582)
					(xy 53.886862 -349.080582) (xy 53.886862 -346.921582) (xy 56.043576 -346.921582) (xy 56.043576 -346.6719)
					(xy 53.89118 -346.6719)
				)
			)
		)
	)
	(footprint ""
		(layer "F.Cu")
		(at 136.50468 -29.01442 -90)
		(property "Reference" "R6194"
			(at 0 0 270)
			(layer "F.SilkS")
			(hide yes)
			(effects
				(font
					(size 1.27 1.27)
				)
			)
		)
		(property "Value" ""
			(at 0 0 270)
			(layer "F.Fab")
			(effects
				(font
					(size 1.27 1.27)
				)
			)
		)
		(duplicate_pad_numbers_are_jumpers no)
		(fp_line
			(start -0.32512 0.175006)
			(end -0.32512 -0.175006)
			(stroke
				(width 0.1)
				(type default)
			)
			(layer "F.Fab")
		)
		(fp_line
			(start 0.32512 0.175006)
			(end -0.32512 0.175006)
			(stroke
				(width 0.1)
				(type default)
			)
			(layer "F.Fab")
		)
		(fp_line
			(start -0.32512 -0.175006)
			(end 0.32512 -0.175006)
			(stroke
				(width 0.1)
				(type default)
			)
			(layer "F.Fab")
		)
		(fp_line
			(start 0.32512 -0.175006)
			(end 0.32512 0.175006)
			(stroke
				(width 0.1)
				(type default)
			)
			(layer "F.Fab")
		)
		(pad "1" smd rect
			(at -0.2667 0 270)
			(size 0.3048 0.381)
			(layers "F.Cu" "F.Mask" "F.Paste")
			(net "USB2_CPU0_P0_HUB1_R_DP")
		)
		(pad "2" smd rect
			(at 0.2667 0 90)
			(size 0.3048 0.381)
			(layers "F.Cu" "F.Mask" "F.Paste")
			(net "USB2_HUB_EXT_DP")
		)
	)
	(footprint ""
		(layer "F.Cu")
		(at 418.206936 -165.502082 -90)
		(property "Reference" "PR505"
			(at 0 0 270)
			(layer "F.SilkS")
			(hide yes)
			(effects
				(font
					(size 1.27 1.27)
				)
			)
		)
		(property "Value" ""
			(at 0 0 270)
			(layer "F.Fab")
			(effects
				(font
					(size 1.27 1.27)
				)
			)
		)
		(duplicate_pad_numbers_are_jumpers no)
		(fp_line
			(start -0.7874 0.4064)
			(end -0.7874 -0.4064)
			(stroke
				(width 0.1524)
				(type default)
			)
			(layer "F.SilkS")
		)
		(fp_line
			(start 0.7874 0.4064)
			(end -0.7874 0.4064)
			(stroke
				(width 0.1524)
				(type default)
			)
			(layer "F.SilkS")
		)
		(fp_line
			(start -0.7874 -0.4064)
			(end 0.7874 -0.4064)
			(stroke
				(width 0.1524)
				(type default)
			)
			(layer "F.SilkS")
		)
		(fp_line
			(start 0.7874 -0.4064)
			(end 0.7874 0.4064)
			(stroke
				(width 0.1524)
				(type default)
			)
			(layer "F.SilkS")
		)
		(fp_line
			(start -0.67945 0.3048)
			(end -0.67945 -0.305054)
			(stroke
				(width 0.1)
				(type default)
			)
			(layer "F.Fab")
		)
		(fp_line
			(start -0.12065 0.3048)
			(end -0.67945 0.3048)
			(stroke
				(width 0.1)
				(type default)
			)
			(layer "F.Fab")
		)
		(fp_line
			(start 0.120396 0.3048)
			(end 0.120396 0.2794)
			(stroke
				(width 0.1)
				(type default)
			)
			(layer "F.Fab")
		)
		(fp_line
			(start 0.67945 0.3048)
			(end 0.120396 0.3048)
			(stroke
				(width 0.1)
				(type default)
			)
			(layer "F.Fab")
		)
		(fp_line
			(start -0.12065 0.2794)
			(end -0.12065 0.3048)
			(stroke
				(width 0.1)
				(type default)
			)
			(layer "F.Fab")
		)
		(fp_line
			(start 0.120396 0.2794)
			(end -0.12065 0.2794)
			(stroke
				(width 0.1)
				(type default)
			)
			(layer "F.Fab")
		)
		(fp_line
			(start -0.12065 -0.2794)
			(end 0.12065 -0.2794)
			(stroke
				(width 0.1)
				(type default)
			)
			(layer "F.Fab")
		)
		(fp_line
			(start 0.12065 -0.2794)
			(end 0.12065 -0.3048)
			(stroke
				(width 0.1)
				(type default)
			)
			(layer "F.Fab")
		)
		(fp_line
			(start 0.12065 -0.3048)
			(end 0.67945 -0.3048)
			(stroke
				(width 0.1)
				(type default)
			)
			(layer "F.Fab")
		)
		(fp_line
			(start 0.67945 -0.3048)
			(end 0.67945 0.3048)
			(stroke
				(width 0.1)
				(type default)
			)
			(layer "F.Fab")
		)
		(fp_line
			(start -0.67945 -0.305054)
			(end -0.12065 -0.305054)
			(stroke
				(width 0.1)
				(type default)
			)
			(layer "F.Fab")
		)
		(fp_line
			(start -0.12065 -0.305054)
			(end -0.12065 -0.2794)
			(stroke
				(width 0.1)
				(type default)
			)
			(layer "F.Fab")
		)
		(pad "1" smd circle
			(at -0.40005 0 270)
			(size 0 0)
			(layers "F.Cu" "F.Mask" "F.Paste")
			(net "SW_PVDDCR_SOC_P0_SW3_RC")
		)
		(pad "2" smd circle
			(at 0.40005 0 270)
			(size 0 0)
			(layers "F.Cu" "F.Mask" "F.Paste")
			(net "GND")
		)
	)
	(footprint ""
		(layer "F.Cu")
		(at 327.881742 -393.9032 90)
		(property "Reference" "R964"
			(at 0 0 90)
			(layer "F.SilkS")
			(hide yes)
			(effects
				(font
					(size 1.27 1.27)
				)
			)
		)
		(property "Value" ""
			(at 0 0 90)
			(layer "F.Fab")
			(effects
				(font
					(size 1.27 1.27)
				)
			)
		)
		(duplicate_pad_numbers_are_jumpers no)
		(fp_line
			(start 0.32512 -0.175006)
			(end 0.32512 0.175006)
			(stroke
				(width 0.1)
				(type default)
			)
			(layer "F.Fab")
		)
		(fp_line
			(start -0.32512 -0.175006)
			(end 0.32512 -0.175006)
			(stroke
				(width 0.1)
				(type default)
			)
			(layer "F.Fab")
		)
		(fp_line
			(start 0.32512 0.175006)
			(end -0.32512 0.175006)
			(stroke
				(width 0.1)
				(type default)
			)
			(layer "F.Fab")
		)
		(fp_line
			(start -0.32512 0.175006)
			(end -0.32512 -0.175006)
			(stroke
				(width 0.1)
				(type default)
			)
			(layer "F.Fab")
		)
		(pad "1" smd rect
			(at -0.2667 0 90)
			(size 0.3048 0.381)
			(layers "F.Cu" "F.Mask" "F.Paste")
			(net "P1V8_CPU0_RT_1D")
		)
		(pad "2" smd rect
			(at 0.2667 0 270)
			(size 0.3048 0.381)
			(layers "F.Cu" "F.Mask" "F.Paste")
			(net "RT_CPU0_P0_ADDR3")
		)
	)
	(footprint ""
		(layer "F.Cu")
		(at 428.880016 -102.37724 -90)
		(property "Reference" "R3794"
			(at 0 0 270)
			(layer "F.SilkS")
			(hide yes)
			(effects
				(font
					(size 1.27 1.27)
				)
			)
		)
		(property "Value" ""
			(at 0 0 270)
			(layer "F.Fab")
			(effects
				(font
					(size 1.27 1.27)
				)
			)
		)
		(duplicate_pad_numbers_are_jumpers no)
		(fp_line
			(start -0.7874 0.4064)
			(end -0.7874 -0.4064)
			(stroke
				(width 0.1524)
				(type default)
			)
			(layer "F.SilkS")
		)
		(fp_line
			(start 0.7874 0.4064)
			(end -0.7874 0.4064)
			(stroke
				(width 0.1524)
				(type default)
			)
			(layer "F.SilkS")
		)
		(fp_line
			(start -0.7874 -0.4064)
			(end 0.7874 -0.4064)
			(stroke
				(width 0.1524)
				(type default)
			)
			(layer "F.SilkS")
		)
		(fp_line
			(start 0.7874 -0.4064)
			(end 0.7874 0.4064)
			(stroke
				(width 0.1524)
				(type default)
			)
			(layer "F.SilkS")
		)
		(fp_line
			(start -0.67945 0.3048)
			(end -0.67945 -0.305054)
			(stroke
				(width 0.1)
				(type default)
			)
			(layer "F.Fab")
		)
		(fp_line
			(start -0.12065 0.3048)
			(end -0.67945 0.3048)
			(stroke
				(width 0.1)
				(type default)
			)
			(layer "F.Fab")
		)
		(fp_line
			(start 0.120396 0.3048)
			(end 0.120396 0.2794)
			(stroke
				(width 0.1)
				(type default)
			)
			(layer "F.Fab")
		)
		(fp_line
			(start 0.67945 0.3048)
			(end 0.120396 0.3048)
			(stroke
				(width 0.1)
				(type default)
			)
			(layer "F.Fab")
		)
		(fp_line
			(start -0.12065 0.2794)
			(end -0.12065 0.3048)
			(stroke
				(width 0.1)
				(type default)
			)
			(layer "F.Fab")
		)
		(fp_line
			(start 0.120396 0.2794)
			(end -0.12065 0.2794)
			(stroke
				(width 0.1)
				(type default)
			)
			(layer "F.Fab")
		)
		(fp_line
			(start -0.12065 -0.2794)
			(end 0.12065 -0.2794)
			(stroke
				(width 0.1)
				(type default)
			)
			(layer "F.Fab")
		)
		(fp_line
			(start 0.12065 -0.2794)
			(end 0.12065 -0.3048)
			(stroke
				(width 0.1)
				(type default)
			)
			(layer "F.Fab")
		)
		(fp_line
			(start 0.12065 -0.3048)
			(end 0.67945 -0.3048)
			(stroke
				(width 0.1)
				(type default)
			)
			(layer "F.Fab")
		)
		(fp_line
			(start 0.67945 -0.3048)
			(end 0.67945 0.3048)
			(stroke
				(width 0.1)
				(type default)
			)
			(layer "F.Fab")
		)
		(fp_line
			(start -0.67945 -0.305054)
			(end -0.12065 -0.305054)
			(stroke
				(width 0.1)
				(type default)
			)
			(layer "F.Fab")
		)
		(fp_line
			(start -0.12065 -0.305054)
			(end -0.12065 -0.2794)
			(stroke
				(width 0.1)
				(type default)
			)
			(layer "F.Fab")
		)
		(pad "1" smd circle
			(at -0.40005 0 270)
			(size 0 0)
			(layers "F.Cu" "F.Mask" "F.Paste")
			(net "P3V3_OCP_PWRGD_1")
		)
		(pad "2" smd circle
			(at 0.40005 0 270)
			(size 0 0)
			(layers "F.Cu" "F.Mask" "F.Paste")
			(net "OCP_V3_1_P3V3_PWRGD")
		)
	)
	(footprint ""
		(layer "F.Cu")
		(at 190.119 -129.377948 90)
		(property "Reference" "R174"
			(at 0 0 90)
			(layer "F.SilkS")
			(hide yes)
			(effects
				(font
					(size 1.27 1.27)
				)
			)
		)
		(property "Value" ""
			(at 0 0 90)
			(layer "F.Fab")
			(effects
				(font
					(size 1.27 1.27)
				)
			)
		)
		(duplicate_pad_numbers_are_jumpers no)
		(fp_line
			(start 0.7874 -0.4064)
			(end 0.7874 0.4064)
			(stroke
				(width 0.1524)
				(type default)
			)
			(layer "F.SilkS")
		)
		(fp_line
			(start -0.7874 -0.4064)
			(end 0.7874 -0.4064)
			(stroke
				(width 0.1524)
				(type default)
			)
			(layer "F.SilkS")
		)
		(fp_line
			(start 0.7874 0.4064)
			(end -0.7874 0.4064)
			(stroke
				(width 0.1524)
				(type default)
			)
			(layer "F.SilkS")
		)
		(fp_line
			(start -0.7874 0.4064)
			(end -0.7874 -0.4064)
			(stroke
				(width 0.1524)
				(type default)
			)
			(layer "F.SilkS")
		)
		(fp_line
			(start -0.12065 -0.305054)
			(end -0.12065 -0.2794)
			(stroke
				(width 0.1)
				(type default)
			)
			(layer "F.Fab")
		)
		(fp_line
			(start -0.67945 -0.305054)
			(end -0.12065 -0.305054)
			(stroke
				(width 0.1)
				(type default)
			)
			(layer "F.Fab")
		)
		(fp_line
			(start 0.67945 -0.3048)
			(end 0.67945 0.3048)
			(stroke
				(width 0.1)
				(type default)
			)
			(layer "F.Fab")
		)
		(fp_line
			(start 0.12065 -0.3048)
			(end 0.67945 -0.3048)
			(stroke
				(width 0.1)
				(type default)
			)
			(layer "F.Fab")
		)
		(fp_line
			(start 0.12065 -0.2794)
			(end 0.12065 -0.3048)
			(stroke
				(width 0.1)
				(type default)
			)
			(layer "F.Fab")
		)
		(fp_line
			(start -0.12065 -0.2794)
			(end 0.12065 -0.2794)
			(stroke
				(width 0.1)
				(type default)
			)
			(layer "F.Fab")
		)
		(fp_line
			(start 0.120396 0.2794)
			(end -0.12065 0.2794)
			(stroke
				(width 0.1)
				(type default)
			)
			(layer "F.Fab")
		)
		(fp_line
			(start -0.12065 0.2794)
			(end -0.12065 0.3048)
			(stroke
				(width 0.1)
				(type default)
			)
			(layer "F.Fab")
		)
		(fp_line
			(start 0.67945 0.3048)
			(end 0.120396 0.3048)
			(stroke
				(width 0.1)
				(type default)
			)
			(layer "F.Fab")
		)
		(fp_line
			(start 0.120396 0.3048)
			(end 0.120396 0.2794)
			(stroke
				(width 0.1)
				(type default)
			)
			(layer "F.Fab")
		)
		(fp_line
			(start -0.12065 0.3048)
			(end -0.67945 0.3048)
			(stroke
				(width 0.1)
				(type default)
			)
			(layer "F.Fab")
		)
		(fp_line
			(start -0.67945 0.3048)
			(end -0.67945 -0.305054)
			(stroke
				(width 0.1)
				(type default)
			)
			(layer "F.Fab")
		)
		(pad "1" smd circle
			(at -0.40005 0 90)
			(size 0 0)
			(layers "F.Cu" "F.Mask" "F.Paste")
			(net "SCM_IRQ_1V8_R_N")
		)
		(pad "2" smd circle
			(at 0.40005 0 90)
			(size 0 0)
			(layers "F.Cu" "F.Mask" "F.Paste")
			(net "SCM_IRQ_1V8_N")
		)
	)
	(footprint ""
		(layer "F.Cu")
		(at 21.181314 -95.510604)
		(property "Reference" "R3664"
			(at 0 0 0)
			(layer "F.SilkS")
			(hide yes)
			(effects
				(font
					(size 1.27 1.27)
				)
			)
		)
		(property "Value" ""
			(at 0 0 0)
			(layer "F.Fab")
			(effects
				(font
					(size 1.27 1.27)
				)
			)
		)
		(duplicate_pad_numbers_are_jumpers no)
		(fp_line
			(start -0.7874 -0.4064)
			(end 0.7874 -0.4064)
			(stroke
				(width 0.1524)
				(type default)
			)
			(layer "F.SilkS")
		)
		(fp_line
			(start -0.7874 0.4064)
			(end -0.7874 -0.4064)
			(stroke
				(width 0.1524)
				(type default)
			)
			(layer "F.SilkS")
		)
		(fp_line
			(start 0.7874 -0.4064)
			(end 0.7874 0.4064)
			(stroke
				(width 0.1524)
				(type default)
			)
			(layer "F.SilkS")
		)
		(fp_line
			(start 0.7874 0.4064)
			(end -0.7874 0.4064)
			(stroke
				(width 0.1524)
				(type default)
			)
			(layer "F.SilkS")
		)
		(fp_line
			(start -0.67945 -0.305054)
			(end -0.12065 -0.305054)
			(stroke
				(width 0.1)
				(type default)
			)
			(layer "F.Fab")
		)
		(fp_line
			(start -0.67945 0.3048)
			(end -0.67945 -0.305054)
			(stroke
				(width 0.1)
				(type default)
			)
			(layer "F.Fab")
		)
		(fp_line
			(start -0.12065 -0.305054)
			(end -0.12065 -0.2794)
			(stroke
				(width 0.1)
				(type default)
			)
			(layer "F.Fab")
		)
		(fp_line
			(start -0.12065 -0.2794)
			(end 0.12065 -0.2794)
			(stroke
				(width 0.1)
				(type default)
			)
			(layer "F.Fab")
		)
		(fp_line
			(start -0.12065 0.2794)
			(end -0.12065 0.3048)
			(stroke
				(width 0.1)
				(type default)
			)
			(layer "F.Fab")
		)
		(fp_line
			(start -0.12065 0.3048)
			(end -0.67945 0.3048)
			(stroke
				(width 0.1)
				(type default)
			)
			(layer "F.Fab")
		)
		(fp_line
			(start 0.120396 0.2794)
			(end -0.12065 0.2794)
			(stroke
				(width 0.1)
				(type default)
			)
			(layer "F.Fab")
		)
		(fp_line
			(start 0.120396 0.3048)
			(end 0.120396 0.2794)
			(stroke
				(width 0.1)
				(type default)
			)
			(layer "F.Fab")
		)
		(fp_line
			(start 0.12065 -0.3048)
			(end 0.67945 -0.3048)
			(stroke
				(width 0.1)
				(type default)
			)
			(layer "F.Fab")
		)
		(fp_line
			(start 0.12065 -0.2794)
			(end 0.12065 -0.3048)
			(stroke
				(width 0.1)
				(type default)
			)
			(layer "F.Fab")
		)
		(fp_line
			(start 0.67945 -0.3048)
			(end 0.67945 0.3048)
			(stroke
				(width 0.1)
				(type default)
			)
			(layer "F.Fab")
		)
		(fp_line
			(start 0.67945 0.3048)
			(end 0.120396 0.3048)
			(stroke
				(width 0.1)
				(type default)
			)
			(layer "F.Fab")
		)
		(pad "1" smd circle
			(at -0.40005 0)
			(size 0 0)
			(layers "F.Cu" "F.Mask" "F.Paste")
			(net "USB_HUB_PSELF")
		)
		(pad "2" smd circle
			(at 0.40005 0)
			(size 0 0)
			(layers "F.Cu" "F.Mask" "F.Paste")
			(net "GND")
		)
	)
	(footprint ""
		(layer "F.Cu")
		(at 341.33536 -15.979394 90)
		(property "Reference" "R950"
			(at 0 0 90)
			(layer "F.SilkS")
			(hide yes)
			(effects
				(font
					(size 1.27 1.27)
				)
			)
		)
		(property "Value" ""
			(at 0 0 90)
			(layer "F.Fab")
			(effects
				(font
					(size 1.27 1.27)
				)
			)
		)
		(duplicate_pad_numbers_are_jumpers no)
		(fp_line
			(start 0.7874 -0.4064)
			(end 0.7874 0.4064)
			(stroke
				(width 0.1524)
				(type default)
			)
			(layer "F.SilkS")
		)
		(fp_line
			(start -0.7874 -0.4064)
			(end 0.7874 -0.4064)
			(stroke
				(width 0.1524)
				(type default)
			)
			(layer "F.SilkS")
		)
		(fp_line
			(start 0.7874 0.4064)
			(end -0.7874 0.4064)
			(stroke
				(width 0.1524)
				(type default)
			)
			(layer "F.SilkS")
		)
		(fp_line
			(start -0.7874 0.4064)
			(end -0.7874 -0.4064)
			(stroke
				(width 0.1524)
				(type default)
			)
			(layer "F.SilkS")
		)
		(fp_line
			(start -0.12065 -0.305054)
			(end -0.12065 -0.2794)
			(stroke
				(width 0.1)
				(type default)
			)
			(layer "F.Fab")
		)
		(fp_line
			(start -0.67945 -0.305054)
			(end -0.12065 -0.305054)
			(stroke
				(width 0.1)
				(type default)
			)
			(layer "F.Fab")
		)
		(fp_line
			(start 0.67945 -0.3048)
			(end 0.67945 0.3048)
			(stroke
				(width 0.1)
				(type default)
			)
			(layer "F.Fab")
		)
		(fp_line
			(start 0.12065 -0.3048)
			(end 0.67945 -0.3048)
			(stroke
				(width 0.1)
				(type default)
			)
			(layer "F.Fab")
		)
		(fp_line
			(start 0.12065 -0.2794)
			(end 0.12065 -0.3048)
			(stroke
				(width 0.1)
				(type default)
			)
			(layer "F.Fab")
		)
		(fp_line
			(start -0.12065 -0.2794)
			(end 0.12065 -0.2794)
			(stroke
				(width 0.1)
				(type default)
			)
			(layer "F.Fab")
		)
		(fp_line
			(start 0.120396 0.2794)
			(end -0.12065 0.2794)
			(stroke
				(width 0.1)
				(type default)
			)
			(layer "F.Fab")
		)
		(fp_line
			(start -0.12065 0.2794)
			(end -0.12065 0.3048)
			(stroke
				(width 0.1)
				(type default)
			)
			(layer "F.Fab")
		)
		(fp_line
			(start 0.67945 0.3048)
			(end 0.120396 0.3048)
			(stroke
				(width 0.1)
				(type default)
			)
			(layer "F.Fab")
		)
		(fp_line
			(start 0.120396 0.3048)
			(end 0.120396 0.2794)
			(stroke
				(width 0.1)
				(type default)
			)
			(layer "F.Fab")
		)
		(fp_line
			(start -0.12065 0.3048)
			(end -0.67945 0.3048)
			(stroke
				(width 0.1)
				(type default)
			)
			(layer "F.Fab")
		)
		(fp_line
			(start -0.67945 0.3048)
			(end -0.67945 -0.305054)
			(stroke
				(width 0.1)
				(type default)
			)
			(layer "F.Fab")
		)
		(pad "1" smd circle
			(at -0.40005 0 90)
			(size 0 0)
			(layers "F.Cu" "F.Mask" "F.Paste")
			(net "PU_SMERR_LED")
		)
		(pad "2" smd circle
			(at 0.40005 0 90)
			(size 0 0)
			(layers "F.Cu" "F.Mask" "F.Paste")
			(net "P3V3_AUX")
		)
	)
	(footprint ""
		(layer "F.Cu")
		(at 335.264252 -357.703628 180)
		(property "Reference" "PC85"
			(at 0 0 180)
			(layer "F.SilkS")
			(hide yes)
			(effects
				(font
					(size 1.27 1.27)
				)
			)
		)
		(property "Value" ""
			(at 0 0 180)
			(layer "F.Fab")
			(effects
				(font
					(size 1.27 1.27)
				)
			)
		)
		(duplicate_pad_numbers_are_jumpers no)
		(fp_line
			(start 0.7874 0.4064)
			(end -0.7874 0.4064)
			(stroke
				(width 0.1524)
				(type default)
			)
			(layer "F.SilkS")
		)
		(fp_line
			(start 0.7874 -0.4064)
			(end 0.7874 0.4064)
			(stroke
				(width 0.1524)
				(type default)
			)
			(layer "F.SilkS")
		)
		(fp_line
			(start -0.7874 0.4064)
			(end -0.7874 -0.4064)
			(stroke
				(width 0.1524)
				(type default)
			)
			(layer "F.SilkS")
		)
		(fp_line
			(start -0.7874 -0.4064)
			(end 0.7874 -0.4064)
			(stroke
				(width 0.1524)
				(type default)
			)
			(layer "F.SilkS")
		)
		(fp_line
			(start 0.67945 0.3048)
			(end 0.120396 0.3048)
			(stroke
				(width 0.1)
				(type default)
			)
			(layer "F.Fab")
		)
		(fp_line
			(start 0.67945 -0.3048)
			(end 0.67945 0.3048)
			(stroke
				(width 0.1)
				(type default)
			)
			(layer "F.Fab")
		)
		(fp_line
			(start 0.12065 -0.2794)
			(end 0.12065 -0.3048)
			(stroke
				(width 0.1)
				(type default)
			)
			(layer "F.Fab")
		)
		(fp_line
			(start 0.12065 -0.3048)
			(end 0.67945 -0.3048)
			(stroke
				(width 0.1)
				(type default)
			)
			(layer "F.Fab")
		)
		(fp_line
			(start 0.120396 0.3048)
			(end 0.120396 0.2794)
			(stroke
				(width 0.1)
				(type default)
			)
			(layer "F.Fab")
		)
		(fp_line
			(start 0.120396 0.2794)
			(end -0.12065 0.2794)
			(stroke
				(width 0.1)
				(type default)
			)
			(layer "F.Fab")
		)
		(fp_line
			(start -0.12065 0.3048)
			(end -0.67945 0.3048)
			(stroke
				(width 0.1)
				(type default)
			)
			(layer "F.Fab")
		)
		(fp_line
			(start -0.12065 0.2794)
			(end -0.12065 0.3048)
			(stroke
				(width 0.1)
				(type default)
			)
			(layer "F.Fab")
		)
		(fp_line
			(start -0.12065 -0.2794)
			(end 0.12065 -0.2794)
			(stroke
				(width 0.1)
				(type default)
			)
			(layer "F.Fab")
		)
		(fp_line
			(start -0.12065 -0.305054)
			(end -0.12065 -0.2794)
			(stroke
				(width 0.1)
				(type default)
			)
			(layer "F.Fab")
		)
		(fp_line
			(start -0.67945 0.3048)
			(end -0.67945 -0.305054)
			(stroke
				(width 0.1)
				(type default)
			)
			(layer "F.Fab")
		)
		(fp_line
			(start -0.67945 -0.305054)
			(end -0.12065 -0.305054)
			(stroke
				(width 0.1)
				(type default)
			)
			(layer "F.Fab")
		)
		(pad "1" smd circle
			(at -0.40005 0 180)
			(size 0 0)
			(layers "F.Cu" "F.Mask" "F.Paste")
			(net "P12V_AUX")
		)
		(pad "2" smd circle
			(at 0.40005 0 180)
			(size 0 0)
			(layers "F.Cu" "F.Mask" "F.Paste")
			(net "GND")
		)
	)
	(footprint ""
		(layer "F.Cu")
		(at 208.894426 -110.649512 180)
		(property "Reference" "R2845"
			(at 0 0 180)
			(layer "F.SilkS")
			(hide yes)
			(effects
				(font
					(size 1.27 1.27)
				)
			)
		)
		(property "Value" ""
			(at 0 0 180)
			(layer "F.Fab")
			(effects
				(font
					(size 1.27 1.27)
				)
			)
		)
		(duplicate_pad_numbers_are_jumpers no)
		(fp_line
			(start 0.7874 0.4064)
			(end -0.7874 0.4064)
			(stroke
				(width 0.1524)
				(type default)
			)
			(layer "F.SilkS")
		)
		(fp_line
			(start 0.7874 -0.4064)
			(end 0.7874 0.4064)
			(stroke
				(width 0.1524)
				(type default)
			)
			(layer "F.SilkS")
		)
		(fp_line
			(start -0.7874 0.4064)
			(end -0.7874 -0.4064)
			(stroke
				(width 0.1524)
				(type default)
			)
			(layer "F.SilkS")
		)
		(fp_line
			(start -0.7874 -0.4064)
			(end 0.7874 -0.4064)
			(stroke
				(width 0.1524)
				(type default)
			)
			(layer "F.SilkS")
		)
		(fp_line
			(start 0.67945 0.3048)
			(end 0.120396 0.3048)
			(stroke
				(width 0.1)
				(type default)
			)
			(layer "F.Fab")
		)
		(fp_line
			(start 0.67945 -0.3048)
			(end 0.67945 0.3048)
			(stroke
				(width 0.1)
				(type default)
			)
			(layer "F.Fab")
		)
		(fp_line
			(start 0.12065 -0.2794)
			(end 0.12065 -0.3048)
			(stroke
				(width 0.1)
				(type default)
			)
			(layer "F.Fab")
		)
		(fp_line
			(start 0.12065 -0.3048)
			(end 0.67945 -0.3048)
			(stroke
				(width 0.1)
				(type default)
			)
			(layer "F.Fab")
		)
		(fp_line
			(start 0.120396 0.3048)
			(end 0.120396 0.2794)
			(stroke
				(width 0.1)
				(type default)
			)
			(layer "F.Fab")
		)
		(fp_line
			(start 0.120396 0.2794)
			(end -0.12065 0.2794)
			(stroke
				(width 0.1)
				(type default)
			)
			(layer "F.Fab")
		)
		(fp_line
			(start -0.12065 0.3048)
			(end -0.67945 0.3048)
			(stroke
				(width 0.1)
				(type default)
			)
			(layer "F.Fab")
		)
		(fp_line
			(start -0.12065 0.2794)
			(end -0.12065 0.3048)
			(stroke
				(width 0.1)
				(type default)
			)
			(layer "F.Fab")
		)
		(fp_line
			(start -0.12065 -0.2794)
			(end 0.12065 -0.2794)
			(stroke
				(width 0.1)
				(type default)
			)
			(layer "F.Fab")
		)
		(fp_line
			(start -0.12065 -0.305054)
			(end -0.12065 -0.2794)
			(stroke
				(width 0.1)
				(type default)
			)
			(layer "F.Fab")
		)
		(fp_line
			(start -0.67945 0.3048)
			(end -0.67945 -0.305054)
			(stroke
				(width 0.1)
				(type default)
			)
			(layer "F.Fab")
		)
		(fp_line
			(start -0.67945 -0.305054)
			(end -0.12065 -0.305054)
			(stroke
				(width 0.1)
				(type default)
			)
			(layer "F.Fab")
		)
		(pad "1" smd circle
			(at -0.40005 0 180)
			(size 0 0)
			(layers "F.Cu" "F.Mask" "F.Paste")
			(net "BMC_MONITER_R")
		)
		(pad "2" smd circle
			(at 0.40005 0 180)
			(size 0 0)
			(layers "F.Cu" "F.Mask" "F.Paste")
			(net "BMC_MONITER")
		)
	)
	(footprint ""
		(layer "F.Cu")
		(at 180.7718 -40.071548)
		(property "Reference" "R1396"
			(at 0 0 0)
			(layer "F.SilkS")
			(hide yes)
			(effects
				(font
					(size 1.27 1.27)
				)
			)
		)
		(property "Value" ""
			(at 0 0 0)
			(layer "F.Fab")
			(effects
				(font
					(size 1.27 1.27)
				)
			)
		)
		(duplicate_pad_numbers_are_jumpers no)
		(fp_line
			(start -0.7874 -0.4064)
			(end 0.7874 -0.4064)
			(stroke
				(width 0.1524)
				(type default)
			)
			(layer "F.SilkS")
		)
		(fp_line
			(start -0.7874 0.4064)
			(end -0.7874 -0.4064)
			(stroke
				(width 0.1524)
				(type default)
			)
			(layer "F.SilkS")
		)
		(fp_line
			(start 0.7874 -0.4064)
			(end 0.7874 0.4064)
			(stroke
				(width 0.1524)
				(type default)
			)
			(layer "F.SilkS")
		)
		(fp_line
			(start 0.7874 0.4064)
			(end -0.7874 0.4064)
			(stroke
				(width 0.1524)
				(type default)
			)
			(layer "F.SilkS")
		)
		(fp_line
			(start -0.67945 -0.305054)
			(end -0.12065 -0.305054)
			(stroke
				(width 0.1)
				(type default)
			)
			(layer "F.Fab")
		)
		(fp_line
			(start -0.67945 0.3048)
			(end -0.67945 -0.305054)
			(stroke
				(width 0.1)
				(type default)
			)
			(layer "F.Fab")
		)
		(fp_line
			(start -0.12065 -0.305054)
			(end -0.12065 -0.2794)
			(stroke
				(width 0.1)
				(type default)
			)
			(layer "F.Fab")
		)
		(fp_line
			(start -0.12065 -0.2794)
			(end 0.12065 -0.2794)
			(stroke
				(width 0.1)
				(type default)
			)
			(layer "F.Fab")
		)
		(fp_line
			(start -0.12065 0.2794)
			(end -0.12065 0.3048)
			(stroke
				(width 0.1)
				(type default)
			)
			(layer "F.Fab")
		)
		(fp_line
			(start -0.12065 0.3048)
			(end -0.67945 0.3048)
			(stroke
				(width 0.1)
				(type default)
			)
			(layer "F.Fab")
		)
		(fp_line
			(start 0.120396 0.2794)
			(end -0.12065 0.2794)
			(stroke
				(width 0.1)
				(type default)
			)
			(layer "F.Fab")
		)
		(fp_line
			(start 0.120396 0.3048)
			(end 0.120396 0.2794)
			(stroke
				(width 0.1)
				(type default)
			)
			(layer "F.Fab")
		)
		(fp_line
			(start 0.12065 -0.3048)
			(end 0.67945 -0.3048)
			(stroke
				(width 0.1)
				(type default)
			)
			(layer "F.Fab")
		)
		(fp_line
			(start 0.12065 -0.2794)
			(end 0.12065 -0.3048)
			(stroke
				(width 0.1)
				(type default)
			)
			(layer "F.Fab")
		)
		(fp_line
			(start 0.67945 -0.3048)
			(end 0.67945 0.3048)
			(stroke
				(width 0.1)
				(type default)
			)
			(layer "F.Fab")
		)
		(fp_line
			(start 0.67945 0.3048)
			(end 0.120396 0.3048)
			(stroke
				(width 0.1)
				(type default)
			)
			(layer "F.Fab")
		)
		(pad "1" smd circle
			(at -0.40005 0)
			(size 0 0)
			(layers "F.Cu" "F.Mask" "F.Paste")
			(net "FM_M2_SSD_0_PEDET")
		)
		(pad "2" smd circle
			(at 0.40005 0)
			(size 0 0)
			(layers "F.Cu" "F.Mask" "F.Paste")
			(net "P3V3_AUX")
		)
	)
	(footprint ""
		(layer "F.Cu")
		(at 48.19904 -434.057552 -90)
		(property "Reference" "R3315"
			(at 0 0 270)
			(layer "F.SilkS")
			(hide yes)
			(effects
				(font
					(size 1.27 1.27)
				)
			)
		)
		(property "Value" ""
			(at 0 0 270)
			(layer "F.Fab")
			(effects
				(font
					(size 1.27 1.27)
				)
			)
		)
		(duplicate_pad_numbers_are_jumpers no)
		(fp_line
			(start -0.7874 0.4064)
			(end -0.7874 -0.4064)
			(stroke
				(width 0.1524)
				(type default)
			)
			(layer "F.SilkS")
		)
		(fp_line
			(start 0.7874 0.4064)
			(end -0.7874 0.4064)
			(stroke
				(width 0.1524)
				(type default)
			)
			(layer "F.SilkS")
		)
		(fp_line
			(start -0.7874 -0.4064)
			(end 0.7874 -0.4064)
			(stroke
				(width 0.1524)
				(type default)
			)
			(layer "F.SilkS")
		)
		(fp_line
			(start 0.7874 -0.4064)
			(end 0.7874 0.4064)
			(stroke
				(width 0.1524)
				(type default)
			)
			(layer "F.SilkS")
		)
		(fp_line
			(start -0.67945 0.3048)
			(end -0.67945 -0.305054)
			(stroke
				(width 0.1)
				(type default)
			)
			(layer "F.Fab")
		)
		(fp_line
			(start -0.12065 0.3048)
			(end -0.67945 0.3048)
			(stroke
				(width 0.1)
				(type default)
			)
			(layer "F.Fab")
		)
		(fp_line
			(start 0.120396 0.3048)
			(end 0.120396 0.2794)
			(stroke
				(width 0.1)
				(type default)
			)
			(layer "F.Fab")
		)
		(fp_line
			(start 0.67945 0.3048)
			(end 0.120396 0.3048)
			(stroke
				(width 0.1)
				(type default)
			)
			(layer "F.Fab")
		)
		(fp_line
			(start -0.12065 0.2794)
			(end -0.12065 0.3048)
			(stroke
				(width 0.1)
				(type default)
			)
			(layer "F.Fab")
		)
		(fp_line
			(start 0.120396 0.2794)
			(end -0.12065 0.2794)
			(stroke
				(width 0.1)
				(type default)
			)
			(layer "F.Fab")
		)
		(fp_line
			(start -0.12065 -0.2794)
			(end 0.12065 -0.2794)
			(stroke
				(width 0.1)
				(type default)
			)
			(layer "F.Fab")
		)
		(fp_line
			(start 0.12065 -0.2794)
			(end 0.12065 -0.3048)
			(stroke
				(width 0.1)
				(type default)
			)
			(layer "F.Fab")
		)
		(fp_line
			(start 0.12065 -0.3048)
			(end 0.67945 -0.3048)
			(stroke
				(width 0.1)
				(type default)
			)
			(layer "F.Fab")
		)
		(fp_line
			(start 0.67945 -0.3048)
			(end 0.67945 0.3048)
			(stroke
				(width 0.1)
				(type default)
			)
			(layer "F.Fab")
		)
		(fp_line
			(start -0.67945 -0.305054)
			(end -0.12065 -0.305054)
			(stroke
				(width 0.1)
				(type default)
			)
			(layer "F.Fab")
		)
		(fp_line
			(start -0.12065 -0.305054)
			(end -0.12065 -0.2794)
			(stroke
				(width 0.1)
				(type default)
			)
			(layer "F.Fab")
		)
		(pad "1" smd circle
			(at -0.40005 0 270)
			(size 0 0)
			(layers "F.Cu" "F.Mask" "F.Paste")
			(net "GPU_FPGA_RST_R1_BUF_N")
		)
		(pad "2" smd circle
			(at 0.40005 0 270)
			(size 0 0)
			(layers "F.Cu" "F.Mask" "F.Paste")
			(net "GPU_FPGA_RST_R_BUF_N")
		)
	)
	(footprint ""
		(layer "F.Cu")
		(at 21.176996 -99.413314 180)
		(property "Reference" "R3657"
			(at 0 0 180)
			(layer "F.SilkS")
			(hide yes)
			(effects
				(font
					(size 1.27 1.27)
				)
			)
		)
		(property "Value" ""
			(at 0 0 180)
			(layer "F.Fab")
			(effects
				(font
					(size 1.27 1.27)
				)
			)
		)
		(duplicate_pad_numbers_are_jumpers no)
		(fp_line
			(start 0.7874 0.4064)
			(end -0.7874 0.4064)
			(stroke
				(width 0.1524)
				(type default)
			)
			(layer "F.SilkS")
		)
		(fp_line
			(start 0.7874 -0.4064)
			(end 0.7874 0.4064)
			(stroke
				(width 0.1524)
				(type default)
			)
			(layer "F.SilkS")
		)
		(fp_line
			(start -0.7874 0.4064)
			(end -0.7874 -0.4064)
			(stroke
				(width 0.1524)
				(type default)
			)
			(layer "F.SilkS")
		)
		(fp_line
			(start -0.7874 -0.4064)
			(end 0.7874 -0.4064)
			(stroke
				(width 0.1524)
				(type default)
			)
			(layer "F.SilkS")
		)
		(fp_line
			(start 0.67945 0.3048)
			(end 0.120396 0.3048)
			(stroke
				(width 0.1)
				(type default)
			)
			(layer "F.Fab")
		)
		(fp_line
			(start 0.67945 -0.3048)
			(end 0.67945 0.3048)
			(stroke
				(width 0.1)
				(type default)
			)
			(layer "F.Fab")
		)
		(fp_line
			(start 0.12065 -0.2794)
			(end 0.12065 -0.3048)
			(stroke
				(width 0.1)
				(type default)
			)
			(layer "F.Fab")
		)
		(fp_line
			(start 0.12065 -0.3048)
			(end 0.67945 -0.3048)
			(stroke
				(width 0.1)
				(type default)
			)
			(layer "F.Fab")
		)
		(fp_line
			(start 0.120396 0.3048)
			(end 0.120396 0.2794)
			(stroke
				(width 0.1)
				(type default)
			)
			(layer "F.Fab")
		)
		(fp_line
			(start 0.120396 0.2794)
			(end -0.12065 0.2794)
			(stroke
				(width 0.1)
				(type default)
			)
			(layer "F.Fab")
		)
		(fp_line
			(start -0.12065 0.3048)
			(end -0.67945 0.3048)
			(stroke
				(width 0.1)
				(type default)
			)
			(layer "F.Fab")
		)
		(fp_line
			(start -0.12065 0.2794)
			(end -0.12065 0.3048)
			(stroke
				(width 0.1)
				(type default)
			)
			(layer "F.Fab")
		)
		(fp_line
			(start -0.12065 -0.2794)
			(end 0.12065 -0.2794)
			(stroke
				(width 0.1)
				(type default)
			)
			(layer "F.Fab")
		)
		(fp_line
			(start -0.12065 -0.305054)
			(end -0.12065 -0.2794)
			(stroke
				(width 0.1)
				(type default)
			)
			(layer "F.Fab")
		)
		(fp_line
			(start -0.67945 0.3048)
			(end -0.67945 -0.305054)
			(stroke
				(width 0.1)
				(type default)
			)
			(layer "F.Fab")
		)
		(fp_line
			(start -0.67945 -0.305054)
			(end -0.12065 -0.305054)
			(stroke
				(width 0.1)
				(type default)
			)
			(layer "F.Fab")
		)
		(pad "1" smd circle
			(at -0.40005 0 180)
			(size 0 0)
			(layers "F.Cu" "F.Mask" "F.Paste")
			(net "P3V3_AUX")
		)
		(pad "2" smd circle
			(at 0.40005 0 180)
			(size 0 0)
			(layers "F.Cu" "F.Mask" "F.Paste")
			(net "USB_HUB_OVCUR2")
		)
	)
	(footprint ""
		(layer "F.Cu")
		(at 103.413814 -37.6682)
		(property "Reference" "R6327"
			(at 0 0 0)
			(layer "F.SilkS")
			(hide yes)
			(effects
				(font
					(size 1.27 1.27)
				)
			)
		)
		(property "Value" ""
			(at 0 0 0)
			(layer "F.Fab")
			(effects
				(font
					(size 1.27 1.27)
				)
			)
		)
		(duplicate_pad_numbers_are_jumpers no)
		(fp_line
			(start -0.7874 -0.4064)
			(end 0.7874 -0.4064)
			(stroke
				(width 0.1524)
				(type default)
			)
			(layer "F.SilkS")
		)
		(fp_line
			(start -0.7874 0.4064)
			(end -0.7874 -0.4064)
			(stroke
				(width 0.1524)
				(type default)
			)
			(layer "F.SilkS")
		)
		(fp_line
			(start 0.7874 -0.4064)
			(end 0.7874 0.4064)
			(stroke
				(width 0.1524)
				(type default)
			)
			(layer "F.SilkS")
		)
		(fp_line
			(start 0.7874 0.4064)
			(end -0.7874 0.4064)
			(stroke
				(width 0.1524)
				(type default)
			)
			(layer "F.SilkS")
		)
		(fp_line
			(start -0.67945 -0.305054)
			(end -0.12065 -0.305054)
			(stroke
				(width 0.1)
				(type default)
			)
			(layer "F.Fab")
		)
		(fp_line
			(start -0.67945 0.3048)
			(end -0.67945 -0.305054)
			(stroke
				(width 0.1)
				(type default)
			)
			(layer "F.Fab")
		)
		(fp_line
			(start -0.12065 -0.305054)
			(end -0.12065 -0.2794)
			(stroke
				(width 0.1)
				(type default)
			)
			(layer "F.Fab")
		)
		(fp_line
			(start -0.12065 -0.2794)
			(end 0.12065 -0.2794)
			(stroke
				(width 0.1)
				(type default)
			)
			(layer "F.Fab")
		)
		(fp_line
			(start -0.12065 0.2794)
			(end -0.12065 0.3048)
			(stroke
				(width 0.1)
				(type default)
			)
			(layer "F.Fab")
		)
		(fp_line
			(start -0.12065 0.3048)
			(end -0.67945 0.3048)
			(stroke
				(width 0.1)
				(type default)
			)
			(layer "F.Fab")
		)
		(fp_line
			(start 0.120396 0.2794)
			(end -0.12065 0.2794)
			(stroke
				(width 0.1)
				(type default)
			)
			(layer "F.Fab")
		)
		(fp_line
			(start 0.120396 0.3048)
			(end 0.120396 0.2794)
			(stroke
				(width 0.1)
				(type default)
			)
			(layer "F.Fab")
		)
		(fp_line
			(start 0.12065 -0.3048)
			(end 0.67945 -0.3048)
			(stroke
				(width 0.1)
				(type default)
			)
			(layer "F.Fab")
		)
		(fp_line
			(start 0.12065 -0.2794)
			(end 0.12065 -0.3048)
			(stroke
				(width 0.1)
				(type default)
			)
			(layer "F.Fab")
		)
		(fp_line
			(start 0.67945 -0.3048)
			(end 0.67945 0.3048)
			(stroke
				(width 0.1)
				(type default)
			)
			(layer "F.Fab")
		)
		(fp_line
			(start 0.67945 0.3048)
			(end 0.120396 0.3048)
			(stroke
				(width 0.1)
				(type default)
			)
			(layer "F.Fab")
		)
		(pad "1" smd circle
			(at -0.40005 0)
			(size 0 0)
			(layers "F.Cu" "F.Mask" "F.Paste")
			(net "P3V3_AUX")
		)
		(pad "2" smd circle
			(at 0.40005 0)
			(size 0 0)
			(layers "F.Cu" "F.Mask" "F.Paste")
			(net "USB_HUB2_MRP_PROG_FUNC6")
		)
	)
	(footprint ""
		(layer "F.Cu")
		(at 171.196 -121.376948)
		(property "Reference" "R6029"
			(at 0 0 0)
			(layer "F.SilkS")
			(hide yes)
			(effects
				(font
					(size 1.27 1.27)
				)
			)
		)
		(property "Value" ""
			(at 0 0 0)
			(layer "F.Fab")
			(effects
				(font
					(size 1.27 1.27)
				)
			)
		)
		(duplicate_pad_numbers_are_jumpers no)
		(fp_line
			(start -0.7874 -0.4064)
			(end 0.7874 -0.4064)
			(stroke
				(width 0.1524)
				(type default)
			)
			(layer "F.SilkS")
		)
		(fp_line
			(start -0.7874 0.4064)
			(end -0.7874 -0.4064)
			(stroke
				(width 0.1524)
				(type default)
			)
			(layer "F.SilkS")
		)
		(fp_line
			(start 0.7874 -0.4064)
			(end 0.7874 0.4064)
			(stroke
				(width 0.1524)
				(type default)
			)
			(layer "F.SilkS")
		)
		(fp_line
			(start 0.7874 0.4064)
			(end -0.7874 0.4064)
			(stroke
				(width 0.1524)
				(type default)
			)
			(layer "F.SilkS")
		)
		(fp_line
			(start -0.67945 -0.305054)
			(end -0.12065 -0.305054)
			(stroke
				(width 0.1)
				(type default)
			)
			(layer "F.Fab")
		)
		(fp_line
			(start -0.67945 0.3048)
			(end -0.67945 -0.305054)
			(stroke
				(width 0.1)
				(type default)
			)
			(layer "F.Fab")
		)
		(fp_line
			(start -0.12065 -0.305054)
			(end -0.12065 -0.2794)
			(stroke
				(width 0.1)
				(type default)
			)
			(layer "F.Fab")
		)
		(fp_line
			(start -0.12065 -0.2794)
			(end 0.12065 -0.2794)
			(stroke
				(width 0.1)
				(type default)
			)
			(layer "F.Fab")
		)
		(fp_line
			(start -0.12065 0.2794)
			(end -0.12065 0.3048)
			(stroke
				(width 0.1)
				(type default)
			)
			(layer "F.Fab")
		)
		(fp_line
			(start -0.12065 0.3048)
			(end -0.67945 0.3048)
			(stroke
				(width 0.1)
				(type default)
			)
			(layer "F.Fab")
		)
		(fp_line
			(start 0.120396 0.2794)
			(end -0.12065 0.2794)
			(stroke
				(width 0.1)
				(type default)
			)
			(layer "F.Fab")
		)
		(fp_line
			(start 0.120396 0.3048)
			(end 0.120396 0.2794)
			(stroke
				(width 0.1)
				(type default)
			)
			(layer "F.Fab")
		)
		(fp_line
			(start 0.12065 -0.3048)
			(end 0.67945 -0.3048)
			(stroke
				(width 0.1)
				(type default)
			)
			(layer "F.Fab")
		)
		(fp_line
			(start 0.12065 -0.2794)
			(end 0.12065 -0.3048)
			(stroke
				(width 0.1)
				(type default)
			)
			(layer "F.Fab")
		)
		(fp_line
			(start 0.67945 -0.3048)
			(end 0.67945 0.3048)
			(stroke
				(width 0.1)
				(type default)
			)
			(layer "F.Fab")
		)
		(fp_line
			(start 0.67945 0.3048)
			(end 0.120396 0.3048)
			(stroke
				(width 0.1)
				(type default)
			)
			(layer "F.Fab")
		)
		(pad "1" smd circle
			(at -0.40005 0)
			(size 0 0)
			(layers "F.Cu" "F.Mask" "F.Paste")
			(net "CLK_GEN2_BMC_RC_OE_N")
		)
		(pad "2" smd circle
			(at 0.40005 0)
			(size 0 0)
			(layers "F.Cu" "F.Mask" "F.Paste")
			(net "CLK_GEN2_BMC_RC_OE_R_N")
		)
	)
	(footprint ""
		(layer "F.Cu")
		(at 148.564346 -408.517344 -90)
		(property "Reference" "C6716"
			(at 0 0 270)
			(layer "F.SilkS")
			(hide yes)
			(effects
				(font
					(size 1.27 1.27)
				)
			)
		)
		(property "Value" ""
			(at 0 0 270)
			(layer "F.Fab")
			(effects
				(font
					(size 1.27 1.27)
				)
			)
		)
		(duplicate_pad_numbers_are_jumpers no)
		(fp_line
			(start -0.299974 0.150114)
			(end -0.299974 -0.150114)
			(stroke
				(width 0.1)
				(type default)
			)
			(layer "F.Fab")
		)
		(fp_line
			(start 0.299974 0.150114)
			(end -0.299974 0.150114)
			(stroke
				(width 0.1)
				(type default)
			)
			(layer "F.Fab")
		)
		(fp_line
			(start -0.299974 -0.150114)
			(end 0.299974 -0.150114)
			(stroke
				(width 0.1)
				(type default)
			)
			(layer "F.Fab")
		)
		(fp_line
			(start 0.299974 -0.150114)
			(end 0.299974 0.150114)
			(stroke
				(width 0.1)
				(type default)
			)
			(layer "F.Fab")
		)
		(pad "1" smd rect
			(at -0.2667 0 270)
			(size 0.3048 0.381)
			(layers "F.Cu" "F.Mask" "F.Paste")
			(net "P5E_CPU1_P2_TX_BUF_C_DN<11>")
		)
		(pad "2" smd rect
			(at 0.2667 0 270)
			(size 0.3048 0.381)
			(layers "F.Cu" "F.Mask" "F.Paste")
			(net "P5E_CPU1_P2_TX_BUF_DN<11>")
		)
	)
	(footprint ""
		(layer "F.Cu")
		(at 266.726416 -422.626536 -90)
		(property "Reference" "R1526"
			(at 0 0 270)
			(layer "F.SilkS")
			(hide yes)
			(effects
				(font
					(size 1.27 1.27)
				)
			)
		)
		(property "Value" ""
			(at 0 0 270)
			(layer "F.Fab")
			(effects
				(font
					(size 1.27 1.27)
				)
			)
		)
		(duplicate_pad_numbers_are_jumpers no)
		(fp_line
			(start -0.7874 0.4064)
			(end -0.7874 -0.4064)
			(stroke
				(width 0.1524)
				(type default)
			)
			(layer "F.SilkS")
		)
		(fp_line
			(start 0.7874 0.4064)
			(end -0.7874 0.4064)
			(stroke
				(width 0.1524)
				(type default)
			)
			(layer "F.SilkS")
		)
		(fp_line
			(start -0.7874 -0.4064)
			(end 0.7874 -0.4064)
			(stroke
				(width 0.1524)
				(type default)
			)
			(layer "F.SilkS")
		)
		(fp_line
			(start 0.7874 -0.4064)
			(end 0.7874 0.4064)
			(stroke
				(width 0.1524)
				(type default)
			)
			(layer "F.SilkS")
		)
		(fp_line
			(start -0.67945 0.3048)
			(end -0.67945 -0.305054)
			(stroke
				(width 0.1)
				(type default)
			)
			(layer "F.Fab")
		)
		(fp_line
			(start -0.12065 0.3048)
			(end -0.67945 0.3048)
			(stroke
				(width 0.1)
				(type default)
			)
			(layer "F.Fab")
		)
		(fp_line
			(start 0.120396 0.3048)
			(end 0.120396 0.2794)
			(stroke
				(width 0.1)
				(type default)
			)
			(layer "F.Fab")
		)
		(fp_line
			(start 0.67945 0.3048)
			(end 0.120396 0.3048)
			(stroke
				(width 0.1)
				(type default)
			)
			(layer "F.Fab")
		)
		(fp_line
			(start -0.12065 0.2794)
			(end -0.12065 0.3048)
			(stroke
				(width 0.1)
				(type default)
			)
			(layer "F.Fab")
		)
		(fp_line
			(start 0.120396 0.2794)
			(end -0.12065 0.2794)
			(stroke
				(width 0.1)
				(type default)
			)
			(layer "F.Fab")
		)
		(fp_line
			(start -0.12065 -0.2794)
			(end 0.12065 -0.2794)
			(stroke
				(width 0.1)
				(type default)
			)
			(layer "F.Fab")
		)
		(fp_line
			(start 0.12065 -0.2794)
			(end 0.12065 -0.3048)
			(stroke
				(width 0.1)
				(type default)
			)
			(layer "F.Fab")
		)
		(fp_line
			(start 0.12065 -0.3048)
			(end 0.67945 -0.3048)
			(stroke
				(width 0.1)
				(type default)
			)
			(layer "F.Fab")
		)
		(fp_line
			(start 0.67945 -0.3048)
			(end 0.67945 0.3048)
			(stroke
				(width 0.1)
				(type default)
			)
			(layer "F.Fab")
		)
		(fp_line
			(start -0.67945 -0.305054)
			(end -0.12065 -0.305054)
			(stroke
				(width 0.1)
				(type default)
			)
			(layer "F.Fab")
		)
		(fp_line
			(start -0.12065 -0.305054)
			(end -0.12065 -0.2794)
			(stroke
				(width 0.1)
				(type default)
			)
			(layer "F.Fab")
		)
		(pad "1" smd circle
			(at -0.40005 0 270)
			(size 0 0)
			(layers "F.Cu" "F.Mask" "F.Paste")
			(net "PDB_PRSNT_N")
		)
		(pad "2" smd circle
			(at 0.40005 0 270)
			(size 0 0)
			(layers "F.Cu" "F.Mask" "F.Paste")
			(net "PDB_PRSNT_R_N")
		)
	)
	(footprint ""
		(layer "F.Cu")
		(at 208.878932 -117.748812)
		(property "Reference" "R3481"
			(at 0 0 0)
			(layer "F.SilkS")
			(hide yes)
			(effects
				(font
					(size 1.27 1.27)
				)
			)
		)
		(property "Value" ""
			(at 0 0 0)
			(layer "F.Fab")
			(effects
				(font
					(size 1.27 1.27)
				)
			)
		)
		(duplicate_pad_numbers_are_jumpers no)
		(fp_line
			(start -0.7874 -0.4064)
			(end 0.7874 -0.4064)
			(stroke
				(width 0.1524)
				(type default)
			)
			(layer "F.SilkS")
		)
		(fp_line
			(start -0.7874 0.4064)
			(end -0.7874 -0.4064)
			(stroke
				(width 0.1524)
				(type default)
			)
			(layer "F.SilkS")
		)
		(fp_line
			(start 0.7874 -0.4064)
			(end 0.7874 0.4064)
			(stroke
				(width 0.1524)
				(type default)
			)
			(layer "F.SilkS")
		)
		(fp_line
			(start 0.7874 0.4064)
			(end -0.7874 0.4064)
			(stroke
				(width 0.1524)
				(type default)
			)
			(layer "F.SilkS")
		)
		(fp_line
			(start -0.67945 -0.305054)
			(end -0.12065 -0.305054)
			(stroke
				(width 0.1)
				(type default)
			)
			(layer "F.Fab")
		)
		(fp_line
			(start -0.67945 0.3048)
			(end -0.67945 -0.305054)
			(stroke
				(width 0.1)
				(type default)
			)
			(layer "F.Fab")
		)
		(fp_line
			(start -0.12065 -0.305054)
			(end -0.12065 -0.2794)
			(stroke
				(width 0.1)
				(type default)
			)
			(layer "F.Fab")
		)
		(fp_line
			(start -0.12065 -0.2794)
			(end 0.12065 -0.2794)
			(stroke
				(width 0.1)
				(type default)
			)
			(layer "F.Fab")
		)
		(fp_line
			(start -0.12065 0.2794)
			(end -0.12065 0.3048)
			(stroke
				(width 0.1)
				(type default)
			)
			(layer "F.Fab")
		)
		(fp_line
			(start -0.12065 0.3048)
			(end -0.67945 0.3048)
			(stroke
				(width 0.1)
				(type default)
			)
			(layer "F.Fab")
		)
		(fp_line
			(start 0.120396 0.2794)
			(end -0.12065 0.2794)
			(stroke
				(width 0.1)
				(type default)
			)
			(layer "F.Fab")
		)
		(fp_line
			(start 0.120396 0.3048)
			(end 0.120396 0.2794)
			(stroke
				(width 0.1)
				(type default)
			)
			(layer "F.Fab")
		)
		(fp_line
			(start 0.12065 -0.3048)
			(end 0.67945 -0.3048)
			(stroke
				(width 0.1)
				(type default)
			)
			(layer "F.Fab")
		)
		(fp_line
			(start 0.12065 -0.2794)
			(end 0.12065 -0.3048)
			(stroke
				(width 0.1)
				(type default)
			)
			(layer "F.Fab")
		)
		(fp_line
			(start 0.67945 -0.3048)
			(end 0.67945 0.3048)
			(stroke
				(width 0.1)
				(type default)
			)
			(layer "F.Fab")
		)
		(fp_line
			(start 0.67945 0.3048)
			(end 0.120396 0.3048)
			(stroke
				(width 0.1)
				(type default)
			)
			(layer "F.Fab")
		)
		(pad "1" smd circle
			(at -0.40005 0)
			(size 0 0)
			(layers "F.Cu" "F.Mask" "F.Paste")
			(net "GPU_HMC_PRSNT_ISO_R_N")
		)
		(pad "2" smd circle
			(at 0.40005 0)
			(size 0 0)
			(layers "F.Cu" "F.Mask" "F.Paste")
			(net "GPU_HMC_PRSNT_ISO_N")
		)
	)
	(footprint ""
		(layer "F.Cu")
		(at 136.311386 -408.517344 -90)
		(property "Reference" "C6708"
			(at 0 0 270)
			(layer "F.SilkS")
			(hide yes)
			(effects
				(font
					(size 1.27 1.27)
				)
			)
		)
		(property "Value" ""
			(at 0 0 270)
			(layer "F.Fab")
			(effects
				(font
					(size 1.27 1.27)
				)
			)
		)
		(duplicate_pad_numbers_are_jumpers no)
		(fp_line
			(start -0.299974 0.150114)
			(end -0.299974 -0.150114)
			(stroke
				(width 0.1)
				(type default)
			)
			(layer "F.Fab")
		)
		(fp_line
			(start 0.299974 0.150114)
			(end -0.299974 0.150114)
			(stroke
				(width 0.1)
				(type default)
			)
			(layer "F.Fab")
		)
		(fp_line
			(start -0.299974 -0.150114)
			(end 0.299974 -0.150114)
			(stroke
				(width 0.1)
				(type default)
			)
			(layer "F.Fab")
		)
		(fp_line
			(start 0.299974 -0.150114)
			(end 0.299974 0.150114)
			(stroke
				(width 0.1)
				(type default)
			)
			(layer "F.Fab")
		)
		(pad "1" smd rect
			(at -0.2667 0 270)
			(size 0.3048 0.381)
			(layers "F.Cu" "F.Mask" "F.Paste")
			(net "P5E_CPU1_P2_TX_BUF_C_DN<7>")
		)
		(pad "2" smd rect
			(at 0.2667 0 270)
			(size 0.3048 0.381)
			(layers "F.Cu" "F.Mask" "F.Paste")
			(net "P5E_CPU1_P2_TX_BUF_DN<7>")
		)
	)
	(footprint ""
		(layer "F.Cu")
		(at 70.739 -54.61 180)
		(property "Reference" "R1146"
			(at 0 0 180)
			(layer "F.SilkS")
			(hide yes)
			(effects
				(font
					(size 1.27 1.27)
				)
			)
		)
		(property "Value" ""
			(at 0 0 180)
			(layer "F.Fab")
			(effects
				(font
					(size 1.27 1.27)
				)
			)
		)
		(duplicate_pad_numbers_are_jumpers no)
		(fp_line
			(start 0.7874 0.4064)
			(end -0.7874 0.4064)
			(stroke
				(width 0.1524)
				(type default)
			)
			(layer "F.SilkS")
		)
		(fp_line
			(start 0.7874 -0.4064)
			(end 0.7874 0.4064)
			(stroke
				(width 0.1524)
				(type default)
			)
			(layer "F.SilkS")
		)
		(fp_line
			(start -0.7874 0.4064)
			(end -0.7874 -0.4064)
			(stroke
				(width 0.1524)
				(type default)
			)
			(layer "F.SilkS")
		)
		(fp_line
			(start -0.7874 -0.4064)
			(end 0.7874 -0.4064)
			(stroke
				(width 0.1524)
				(type default)
			)
			(layer "F.SilkS")
		)
		(fp_line
			(start 0.67945 0.3048)
			(end 0.120396 0.3048)
			(stroke
				(width 0.1)
				(type default)
			)
			(layer "F.Fab")
		)
		(fp_line
			(start 0.67945 -0.3048)
			(end 0.67945 0.3048)
			(stroke
				(width 0.1)
				(type default)
			)
			(layer "F.Fab")
		)
		(fp_line
			(start 0.12065 -0.2794)
			(end 0.12065 -0.3048)
			(stroke
				(width 0.1)
				(type default)
			)
			(layer "F.Fab")
		)
		(fp_line
			(start 0.12065 -0.3048)
			(end 0.67945 -0.3048)
			(stroke
				(width 0.1)
				(type default)
			)
			(layer "F.Fab")
		)
		(fp_line
			(start 0.120396 0.3048)
			(end 0.120396 0.2794)
			(stroke
				(width 0.1)
				(type default)
			)
			(layer "F.Fab")
		)
		(fp_line
			(start 0.120396 0.2794)
			(end -0.12065 0.2794)
			(stroke
				(width 0.1)
				(type default)
			)
			(layer "F.Fab")
		)
		(fp_line
			(start -0.12065 0.3048)
			(end -0.67945 0.3048)
			(stroke
				(width 0.1)
				(type default)
			)
			(layer "F.Fab")
		)
		(fp_line
			(start -0.12065 0.2794)
			(end -0.12065 0.3048)
			(stroke
				(width 0.1)
				(type default)
			)
			(layer "F.Fab")
		)
		(fp_line
			(start -0.12065 -0.2794)
			(end 0.12065 -0.2794)
			(stroke
				(width 0.1)
				(type default)
			)
			(layer "F.Fab")
		)
		(fp_line
			(start -0.12065 -0.305054)
			(end -0.12065 -0.2794)
			(stroke
				(width 0.1)
				(type default)
			)
			(layer "F.Fab")
		)
		(fp_line
			(start -0.67945 0.3048)
			(end -0.67945 -0.305054)
			(stroke
				(width 0.1)
				(type default)
			)
			(layer "F.Fab")
		)
		(fp_line
			(start -0.67945 -0.305054)
			(end -0.12065 -0.305054)
			(stroke
				(width 0.1)
				(type default)
			)
			(layer "F.Fab")
		)
		(pad "1" smd circle
			(at -0.40005 0 180)
			(size 0 0)
			(layers "F.Cu" "F.Mask" "F.Paste")
			(net "OCP_V3_2_AUX_PWR_EN_R2")
		)
		(pad "2" smd circle
			(at 0.40005 0 180)
			(size 0 0)
			(layers "F.Cu" "F.Mask" "F.Paste")
			(net "HP_LVC3_OCP_V3_2_PWRGD_R1")
		)
	)
	(footprint ""
		(layer "F.Cu")
		(at 171.577 -100.294948 -90)
		(property "Reference" "R6011"
			(at 0 0 270)
			(layer "F.SilkS")
			(hide yes)
			(effects
				(font
					(size 1.27 1.27)
				)
			)
		)
		(property "Value" ""
			(at 0 0 270)
			(layer "F.Fab")
			(effects
				(font
					(size 1.27 1.27)
				)
			)
		)
		(duplicate_pad_numbers_are_jumpers no)
		(fp_line
			(start -0.7874 0.4064)
			(end -0.7874 -0.4064)
			(stroke
				(width 0.1524)
				(type default)
			)
			(layer "F.SilkS")
		)
		(fp_line
			(start 0.7874 0.4064)
			(end -0.7874 0.4064)
			(stroke
				(width 0.1524)
				(type default)
			)
			(layer "F.SilkS")
		)
		(fp_line
			(start -0.7874 -0.4064)
			(end 0.7874 -0.4064)
			(stroke
				(width 0.1524)
				(type default)
			)
			(layer "F.SilkS")
		)
		(fp_line
			(start 0.7874 -0.4064)
			(end 0.7874 0.4064)
			(stroke
				(width 0.1524)
				(type default)
			)
			(layer "F.SilkS")
		)
		(fp_line
			(start -0.67945 0.3048)
			(end -0.67945 -0.305054)
			(stroke
				(width 0.1)
				(type default)
			)
			(layer "F.Fab")
		)
		(fp_line
			(start -0.12065 0.3048)
			(end -0.67945 0.3048)
			(stroke
				(width 0.1)
				(type default)
			)
			(layer "F.Fab")
		)
		(fp_line
			(start 0.120396 0.3048)
			(end 0.120396 0.2794)
			(stroke
				(width 0.1)
				(type default)
			)
			(layer "F.Fab")
		)
		(fp_line
			(start 0.67945 0.3048)
			(end 0.120396 0.3048)
			(stroke
				(width 0.1)
				(type default)
			)
			(layer "F.Fab")
		)
		(fp_line
			(start -0.12065 0.2794)
			(end -0.12065 0.3048)
			(stroke
				(width 0.1)
				(type default)
			)
			(layer "F.Fab")
		)
		(fp_line
			(start 0.120396 0.2794)
			(end -0.12065 0.2794)
			(stroke
				(width 0.1)
				(type default)
			)
			(layer "F.Fab")
		)
		(fp_line
			(start -0.12065 -0.2794)
			(end 0.12065 -0.2794)
			(stroke
				(width 0.1)
				(type default)
			)
			(layer "F.Fab")
		)
		(fp_line
			(start 0.12065 -0.2794)
			(end 0.12065 -0.3048)
			(stroke
				(width 0.1)
				(type default)
			)
			(layer "F.Fab")
		)
		(fp_line
			(start 0.12065 -0.3048)
			(end 0.67945 -0.3048)
			(stroke
				(width 0.1)
				(type default)
			)
			(layer "F.Fab")
		)
		(fp_line
			(start 0.67945 -0.3048)
			(end 0.67945 0.3048)
			(stroke
				(width 0.1)
				(type default)
			)
			(layer "F.Fab")
		)
		(fp_line
			(start -0.67945 -0.305054)
			(end -0.12065 -0.305054)
			(stroke
				(width 0.1)
				(type default)
			)
			(layer "F.Fab")
		)
		(fp_line
			(start -0.12065 -0.305054)
			(end -0.12065 -0.2794)
			(stroke
				(width 0.1)
				(type default)
			)
			(layer "F.Fab")
		)
		(pad "1" smd circle
			(at -0.40005 0 270)
			(size 0 0)
			(layers "F.Cu" "F.Mask" "F.Paste")
			(net "SGPIO_SCM_LD_<0>")
		)
		(pad "2" smd circle
			(at 0.40005 0 270)
			(size 0 0)
			(layers "F.Cu" "F.Mask" "F.Paste")
			(net "SGPIO_SCM_LD_R_<0>")
		)
	)
	(footprint ""
		(layer "F.Cu")
		(at 105.659936 -119.479568 90)
		(property "Reference" "R1449"
			(at 0 0 90)
			(layer "F.SilkS")
			(hide yes)
			(effects
				(font
					(size 1.27 1.27)
				)
			)
		)
		(property "Value" ""
			(at 0 0 90)
			(layer "F.Fab")
			(effects
				(font
					(size 1.27 1.27)
				)
			)
		)
		(duplicate_pad_numbers_are_jumpers no)
		(fp_line
			(start 0.7874 -0.4064)
			(end 0.7874 0.4064)
			(stroke
				(width 0.1524)
				(type default)
			)
			(layer "F.SilkS")
		)
		(fp_line
			(start -0.7874 -0.4064)
			(end 0.7874 -0.4064)
			(stroke
				(width 0.1524)
				(type default)
			)
			(layer "F.SilkS")
		)
		(fp_line
			(start 0.7874 0.4064)
			(end -0.7874 0.4064)
			(stroke
				(width 0.1524)
				(type default)
			)
			(layer "F.SilkS")
		)
		(fp_line
			(start -0.7874 0.4064)
			(end -0.7874 -0.4064)
			(stroke
				(width 0.1524)
				(type default)
			)
			(layer "F.SilkS")
		)
		(fp_line
			(start -0.12065 -0.305054)
			(end -0.12065 -0.2794)
			(stroke
				(width 0.1)
				(type default)
			)
			(layer "F.Fab")
		)
		(fp_line
			(start -0.67945 -0.305054)
			(end -0.12065 -0.305054)
			(stroke
				(width 0.1)
				(type default)
			)
			(layer "F.Fab")
		)
		(fp_line
			(start 0.67945 -0.3048)
			(end 0.67945 0.3048)
			(stroke
				(width 0.1)
				(type default)
			)
			(layer "F.Fab")
		)
		(fp_line
			(start 0.12065 -0.3048)
			(end 0.67945 -0.3048)
			(stroke
				(width 0.1)
				(type default)
			)
			(layer "F.Fab")
		)
		(fp_line
			(start 0.12065 -0.2794)
			(end 0.12065 -0.3048)
			(stroke
				(width 0.1)
				(type default)
			)
			(layer "F.Fab")
		)
		(fp_line
			(start -0.12065 -0.2794)
			(end 0.12065 -0.2794)
			(stroke
				(width 0.1)
				(type default)
			)
			(layer "F.Fab")
		)
		(fp_line
			(start 0.120396 0.2794)
			(end -0.12065 0.2794)
			(stroke
				(width 0.1)
				(type default)
			)
			(layer "F.Fab")
		)
		(fp_line
			(start -0.12065 0.2794)
			(end -0.12065 0.3048)
			(stroke
				(width 0.1)
				(type default)
			)
			(layer "F.Fab")
		)
		(fp_line
			(start 0.67945 0.3048)
			(end 0.120396 0.3048)
			(stroke
				(width 0.1)
				(type default)
			)
			(layer "F.Fab")
		)
		(fp_line
			(start 0.120396 0.3048)
			(end 0.120396 0.2794)
			(stroke
				(width 0.1)
				(type default)
			)
			(layer "F.Fab")
		)
		(fp_line
			(start -0.12065 0.3048)
			(end -0.67945 0.3048)
			(stroke
				(width 0.1)
				(type default)
			)
			(layer "F.Fab")
		)
		(fp_line
			(start -0.67945 0.3048)
			(end -0.67945 -0.305054)
			(stroke
				(width 0.1)
				(type default)
			)
			(layer "F.Fab")
		)
		(pad "1" smd circle
			(at -0.40005 0 90)
			(size 0 0)
			(layers "F.Cu" "F.Mask" "F.Paste")
			(net "P3V3_AUX")
		)
		(pad "2" smd circle
			(at 0.40005 0 90)
			(size 0 0)
			(layers "F.Cu" "F.Mask" "F.Paste")
			(net "PWRGD_P12V_MEM_CPU1_EN_N")
		)
	)
	(footprint ""
		(layer "F.Cu")
		(at 331.58303 -20.397978)
		(property "Reference" "Q28"
			(at -3.251962 1.45542 90)
			(unlocked yes)
			(layer "F.SilkS")
			(effects
				(font
					(size 0.7874 0.5842)
					(thickness 0.1524)
				)
				(justify left)
			)
		)
		(property "Value" ""
			(at 0 0 0)
			(layer "F.Fab")
			(effects
				(font
					(size 1.27 1.27)
				)
			)
		)
		(duplicate_pad_numbers_are_jumpers no)
		(fp_line
			(start -1.332738 -1.100074)
			(end -0.4826 -1.100074)
			(stroke
				(width 0.1524)
				(type default)
			)
			(layer "F.SilkS")
		)
		(fp_line
			(start -1.332738 1.100074)
			(end -1.332738 -1.100074)
			(stroke
				(width 0.1524)
				(type default)
			)
			(layer "F.SilkS")
		)
		(fp_line
			(start -0.4826 -1.100074)
			(end 0 -0.541274)
			(stroke
				(width 0.1524)
				(type default)
			)
			(layer "F.SilkS")
		)
		(fp_line
			(start 0 -0.541274)
			(end 0.4826 -1.100074)
			(stroke
				(width 0.1524)
				(type default)
			)
			(layer "F.SilkS")
		)
		(fp_line
			(start 0.4826 -1.100074)
			(end 1.332738 -1.100074)
			(stroke
				(width 0.1524)
				(type default)
			)
			(layer "F.SilkS")
		)
		(fp_line
			(start 1.332738 -1.100074)
			(end 1.332738 1.100074)
			(stroke
				(width 0.1524)
				(type default)
			)
			(layer "F.SilkS")
		)
		(fp_line
			(start 1.332738 1.100074)
			(end -1.332738 1.100074)
			(stroke
				(width 0.1524)
				(type default)
			)
			(layer "F.SilkS")
		)
		(fp_poly
			(pts
				(xy -1.533144 -0.649986) (xy -2.2352 -0.298958) (xy -2.2352 -1.001014)
			)
			(stroke
				(width 0)
				(type default)
			)
			(fill yes)
			(layer "F.SilkS")
		)
		(fp_line
			(start -0.674878 -1.100074)
			(end 0.674878 -1.100074)
			(stroke
				(width 0.1)
				(type default)
			)
			(layer "F.Fab")
		)
		(fp_line
			(start -0.674878 1.100074)
			(end -0.674878 -1.100074)
			(stroke
				(width 0.1)
				(type default)
			)
			(layer "F.Fab")
		)
		(fp_line
			(start 0.674878 -1.100074)
			(end 0.674878 1.100074)
			(stroke
				(width 0.1)
				(type default)
			)
			(layer "F.Fab")
		)
		(fp_line
			(start 0.674878 1.100074)
			(end -0.674878 1.100074)
			(stroke
				(width 0.1)
				(type default)
			)
			(layer "F.Fab")
		)
		(fp_poly
			(pts
				(xy -2.2352 -0.298958) (xy -2.2352 -1.001014) (xy -1.533144 -0.649986)
			)
			(stroke
				(width 0)
				(type default)
			)
			(fill yes)
			(layer "F.Fab")
		)
		(pad "1" smd rect
			(at -0.94996 -0.649986 90)
			(size 0.4318 0.508)
			(layers "F.Cu" "F.Mask" "F.Paste")
			(net "GND")
		)
		(pad "2" smd rect
			(at -0.94996 0 90)
			(size 0.4318 0.508)
			(layers "F.Cu" "F.Mask" "F.Paste")
			(net "BMC_FPGA_LED1")
		)
		(pad "3" smd rect
			(at -0.94996 0.649986 90)
			(size 0.4318 0.508)
			(layers "F.Cu" "F.Mask" "F.Paste")
			(net "BMC_FPGA_LED2_N")
		)
		(pad "4" smd rect
			(at 0.94996 0.649986 90)
			(size 0.4318 0.508)
			(layers "F.Cu" "F.Mask" "F.Paste")
			(net "GND")
		)
		(pad "5" smd rect
			(at 0.94996 0 90)
			(size 0.4318 0.508)
			(layers "F.Cu" "F.Mask" "F.Paste")
			(net "BMC_FPGA_LED2")
		)
		(pad "6" smd rect
			(at 0.94996 -0.649986 90)
			(size 0.4318 0.508)
			(layers "F.Cu" "F.Mask" "F.Paste")
			(net "BMC_FPGA_LED1_N")
		)
	)
	(footprint ""
		(layer "F.Cu")
		(at 377.909582 -416.899344 -90)
		(property "Reference" "C6569"
			(at 0 0 270)
			(layer "F.SilkS")
			(hide yes)
			(effects
				(font
					(size 1.27 1.27)
				)
			)
		)
		(property "Value" ""
			(at 0 0 270)
			(layer "F.Fab")
			(effects
				(font
					(size 1.27 1.27)
				)
			)
		)
		(duplicate_pad_numbers_are_jumpers no)
		(fp_line
			(start -0.299974 0.150114)
			(end -0.299974 -0.150114)
			(stroke
				(width 0.1)
				(type default)
			)
			(layer "F.Fab")
		)
		(fp_line
			(start 0.299974 0.150114)
			(end -0.299974 0.150114)
			(stroke
				(width 0.1)
				(type default)
			)
			(layer "F.Fab")
		)
		(fp_line
			(start -0.299974 -0.150114)
			(end 0.299974 -0.150114)
			(stroke
				(width 0.1)
				(type default)
			)
			(layer "F.Fab")
		)
		(fp_line
			(start 0.299974 -0.150114)
			(end 0.299974 0.150114)
			(stroke
				(width 0.1)
				(type default)
			)
			(layer "F.Fab")
		)
		(pad "1" smd rect
			(at -0.2667 0 270)
			(size 0.3048 0.381)
			(layers "F.Cu" "F.Mask" "F.Paste")
			(net "P5E_CPU0_P2_TX_BUF_C_DP<2>")
		)
		(pad "2" smd rect
			(at 0.2667 0 270)
			(size 0.3048 0.381)
			(layers "F.Cu" "F.Mask" "F.Paste")
			(net "P5E_CPU0_P2_TX_BUF_DP<2>")
		)
	)
	(footprint ""
		(layer "F.Cu")
		(at 412.095696 -395.724634)
		(property "Reference" "U6012"
			(at -8.00862 -7.649972 0)
			(unlocked yes)
			(layer "F.SilkS")
			(effects
				(font
					(size 0.7874 0.5842)
					(thickness 0.1524)
				)
				(justify left)
			)
		)
		(property "Value" ""
			(at 0 0 0)
			(layer "F.Fab")
			(effects
				(font
					(size 1.27 1.27)
				)
			)
		)
		(duplicate_pad_numbers_are_jumpers no)
		(fp_line
			(start -11.400028 -4.45008)
			(end -9.658096 -4.45008)
			(stroke
				(width 0.1524)
				(type default)
			)
			(layer "F.SilkS")
		)
		(fp_line
			(start -11.400028 -0.794766)
			(end -11.400028 -4.45008)
			(stroke
				(width 0.1524)
				(type default)
			)
			(layer "F.SilkS")
		)
		(fp_line
			(start -11.400028 4.45008)
			(end -11.400028 0.272034)
			(stroke
				(width 0.1524)
				(type default)
			)
			(layer "F.SilkS")
		)
		(fp_line
			(start -9.785096 4.45008)
			(end -11.400028 4.45008)
			(stroke
				(width 0.1524)
				(type default)
			)
			(layer "F.SilkS")
		)
		(fp_line
			(start 9.620504 -4.45008)
			(end 11.400028 -4.45008)
			(stroke
				(width 0.1524)
				(type default)
			)
			(layer "F.SilkS")
		)
		(fp_line
			(start 11.400028 -4.45008)
			(end 11.400028 4.45008)
			(stroke
				(width 0.1524)
				(type default)
			)
			(layer "F.SilkS")
		)
		(fp_line
			(start 11.400028 4.45008)
			(end 9.620504 4.45008)
			(stroke
				(width 0.1524)
				(type default)
			)
			(layer "F.SilkS")
		)
		(fp_poly
			(pts
				(xy 10.450068 -4.45008) (xy 10.450068 -5.21208) (xy 12.162028 -5.21208) (xy 12.162028 -3.41884)
				(xy 11.400028 -3.41884) (xy 11.400028 -4.45008)
			)
			(stroke
				(width 0)
				(type default)
			)
			(fill yes)
			(layer "F.SilkS")
		)
		(fp_line
			(start -11.400028 -4.45008)
			(end -11.400028 4.45008)
			(stroke
				(width 0.1)
				(type default)
			)
			(layer "F.Fab")
		)
		(fp_line
			(start -11.400028 4.45008)
			(end 11.400028 4.45008)
			(stroke
				(width 0.1)
				(type default)
			)
			(layer "F.Fab")
		)
		(fp_line
			(start 11.400028 -4.45008)
			(end -11.400028 -4.45008)
			(stroke
				(width 0.1)
				(type default)
			)
			(layer "F.Fab")
		)
		(fp_line
			(start 11.400028 4.45008)
			(end 11.400028 -4.45008)
			(stroke
				(width 0.1)
				(type default)
			)
			(layer "F.Fab")
		)
		(fp_poly
			(pts
				(xy 10.450068 -4.45008) (xy 10.450068 -5.21208) (xy 12.162028 -5.21208) (xy 12.162028 -3.41884)
				(xy 11.400028 -3.41884) (xy 11.400028 -4.45008)
			)
			(stroke
				(width 0)
				(type default)
			)
			(fill yes)
			(layer "F.Fab")
		)
		(pad "A1" smd oval
			(at 11.050016 -3.938524)
			(size 0.254 0.3302)
			(layers "F.Cu" "F.Mask" "F.Paste")
			(net "NCF_A1_CPU0_P2_GND")
		)
		(pad "A35" smd oval
			(at 11.050016 3.940048)
			(size 0.254 0.3302)
			(layers "F.Cu" "F.Mask" "F.Paste")
			(net "NCF_CPU0_P2_GND")
		)
		(pad "AA10" smd circle
			(at 7.602728 -1.431798)
			(size 0.381 0.381)
			(layers "F.Cu" "F.Mask" "F.Paste")
			(net "P5E_CPU0_P2_TX_BUF_DN<14>")
		)
		(pad "AA29" smd circle
			(at 7.602728 2.032254)
			(size 0.381 0.381)
			(layers "F.Cu" "F.Mask" "F.Paste")
			(net "P5E_CPU0_P2_RX_DN<14>")
		)
		(pad "AB1" smd oval
			(at 7.450074 -3.938524)
			(size 0.254 0.3302)
			(layers "F.Cu" "F.Mask" "F.Paste")
			(net "P5E_CPU0_P2_RX_BUF_DP<14>")
		)
		(pad "AB35" smd oval
			(at 7.450074 3.940048)
			(size 0.254 0.3302)
			(layers "F.Cu" "F.Mask" "F.Paste")
			(net "P5E_CPU0_P2_TX_C_DP<14>")
		)
		(pad "AC4" smd circle
			(at 7.202678 -2.817368)
			(size 0.381 0.381)
			(layers "F.Cu" "F.Mask" "F.Paste")
			(net "GND")
		)
		(pad "AC13" smd circle
			(at 7.202678 -0.79629)
			(size 0.3048 0.3048)
			(layers "F.Cu" "F.Mask" "F.Paste")
			(net "GND")
		)
		(pad "AC17" smd circle
			(at 7.202678 -0.296164)
			(size 0.3048 0.3048)
			(layers "F.Cu" "F.Mask" "F.Paste")
			(net "P0V9_CPU0_RT2_2A")
		)
		(pad "AC20" smd circle
			(at 7.202678 0.203708)
			(size 0.3048 0.3048)
			(layers "F.Cu" "F.Mask" "F.Paste")
			(net "P0V9_CPU0_RT2_2A")
		)
		(pad "AC22" smd circle
			(at 7.202678 0.703834)
			(size 0.3048 0.3048)
			(layers "F.Cu" "F.Mask" "F.Paste")
			(net "GND")
		)
		(pad "AC32" smd circle
			(at 7.202678 2.724912)
			(size 0.381 0.381)
			(layers "F.Cu" "F.Mask" "F.Paste")
			(net "GND")
		)
		(pad "AD2" smd circle
			(at 7.1501 -3.41884)
			(size 0.3048 0.3048)
			(layers "F.Cu" "F.Mask" "F.Paste")
			(net "GND")
		)
		(pad "AD34" smd circle
			(at 7.1501 3.420364)
			(size 0.3048 0.3048)
			(layers "F.Cu" "F.Mask" "F.Paste")
			(net "GND")
		)
		(pad "AE1" smd oval
			(at 6.849872 -3.938524)
			(size 0.254 0.3302)
			(layers "F.Cu" "F.Mask" "F.Paste")
			(net "GND")
		)
		(pad "AE35" smd oval
			(at 6.849872 3.940048)
			(size 0.254 0.3302)
			(layers "F.Cu" "F.Mask" "F.Paste")
			(net "GND")
		)
		(pad "AF7" smd circle
			(at 6.802628 -2.12471)
			(size 0.381 0.381)
			(layers "F.Cu" "F.Mask" "F.Paste")
			(net "P5E_CPU0_P2_TX_BUF_DP<13>")
		)
		(pad "AF26" smd circle
			(at 6.802628 1.339342)
			(size 0.381 0.381)
			(layers "F.Cu" "F.Mask" "F.Paste")
			(net "P5E_CPU0_P2_RX_DP<13>")
		)
		(pad "AG2" smd circle
			(at 6.549898 -3.41884)
			(size 0.3048 0.3048)
			(layers "F.Cu" "F.Mask" "F.Paste")
			(net "P5E_CPU0_P2_RX_BUF_DN<13>")
		)
		(pad "AG34" smd circle
			(at 6.549898 3.420364)
			(size 0.3048 0.3048)
			(layers "F.Cu" "F.Mask" "F.Paste")
			(net "P5E_CPU0_P2_TX_C_DN<13>")
		)
		(pad "AH10" smd circle
			(at 6.402578 -1.431798)
			(size 0.381 0.381)
			(layers "F.Cu" "F.Mask" "F.Paste")
			(net "P5E_CPU0_P2_TX_BUF_DN<13>")
		)
		(pad "AH29" smd circle
			(at 6.402578 2.032254)
			(size 0.381 0.381)
			(layers "F.Cu" "F.Mask" "F.Paste")
			(net "P5E_CPU0_P2_RX_DN<13>")
		)
		(pad "AJ1" smd oval
			(at 6.249924 -3.938524)
			(size 0.254 0.3302)
			(layers "F.Cu" "F.Mask" "F.Paste")
			(net "P5E_CPU0_P2_RX_BUF_DP<13>")
		)
		(pad "AJ35" smd oval
			(at 6.249924 3.940048)
			(size 0.254 0.3302)
			(layers "F.Cu" "F.Mask" "F.Paste")
			(net "P5E_CPU0_P2_TX_C_DP<13>")
		)
		(pad "AK4" smd circle
			(at 6.002528 -2.817368)
			(size 0.381 0.381)
			(layers "F.Cu" "F.Mask" "F.Paste")
			(net "GND")
		)
		(pad "AK13" smd circle
			(at 6.002528 -0.79629)
			(size 0.3048 0.3048)
			(layers "F.Cu" "F.Mask" "F.Paste")
			(net "GND")
		)
		(pad "AK17" smd circle
			(at 6.002528 -0.296164)
			(size 0.3048 0.3048)
			(layers "F.Cu" "F.Mask" "F.Paste")
			(net "P0V9_CPU0_RT2_2A")
		)
		(pad "AK20" smd circle
			(at 6.002528 0.203708)
			(size 0.3048 0.3048)
			(layers "F.Cu" "F.Mask" "F.Paste")
			(net "P0V9_CPU0_RT2_2A")
		)
		(pad "AK22" smd circle
			(at 6.002528 0.703834)
			(size 0.3048 0.3048)
			(layers "F.Cu" "F.Mask" "F.Paste")
			(net "GND")
		)
		(pad "AK32" smd circle
			(at 6.002528 2.724912)
			(size 0.381 0.381)
			(layers "F.Cu" "F.Mask" "F.Paste")
			(net "GND")
		)
		(pad "AL2" smd circle
			(at 5.94995 -3.41884)
			(size 0.3048 0.3048)
			(layers "F.Cu" "F.Mask" "F.Paste")
			(net "GND")
		)
		(pad "AL34" smd circle
			(at 5.94995 3.420364)
			(size 0.3048 0.3048)
			(layers "F.Cu" "F.Mask" "F.Paste")
			(net "GND")
		)
		(pad "AM1" smd oval
			(at 5.649976 -3.938524)
			(size 0.254 0.3302)
			(layers "F.Cu" "F.Mask" "F.Paste")
			(net "GND")
		)
		(pad "AM35" smd oval
			(at 5.649976 3.940048)
			(size 0.254 0.3302)
			(layers "F.Cu" "F.Mask" "F.Paste")
			(net "GND")
		)
		(pad "AN7" smd circle
			(at 5.602478 -2.12471)
			(size 0.381 0.381)
			(layers "F.Cu" "F.Mask" "F.Paste")
			(net "P5E_CPU0_P2_TX_BUF_DP<12>")
		)
		(pad "AN26" smd circle
			(at 5.602478 1.339342)
			(size 0.381 0.381)
			(layers "F.Cu" "F.Mask" "F.Paste")
			(net "P5E_CPU0_P2_RX_DP<12>")
		)
		(pad "AP2" smd circle
			(at 5.350002 -3.41884)
			(size 0.3048 0.3048)
			(layers "F.Cu" "F.Mask" "F.Paste")
			(net "P5E_CPU0_P2_RX_BUF_DN<12>")
		)
		(pad "AP34" smd circle
			(at 5.350002 3.420364)
			(size 0.3048 0.3048)
			(layers "F.Cu" "F.Mask" "F.Paste")
			(net "P5E_CPU0_P2_TX_C_DN<12>")
		)
		(pad "AR10" smd circle
			(at 5.202682 -1.431798)
			(size 0.381 0.381)
			(layers "F.Cu" "F.Mask" "F.Paste")
			(net "P5E_CPU0_P2_TX_BUF_DN<12>")
		)
		(pad "AR29" smd circle
			(at 5.202682 2.032254)
			(size 0.381 0.381)
			(layers "F.Cu" "F.Mask" "F.Paste")
			(net "P5E_CPU0_P2_RX_DN<12>")
		)
		(pad "AT1" smd oval
			(at 5.050028 -3.938524)
			(size 0.254 0.3302)
			(layers "F.Cu" "F.Mask" "F.Paste")
			(net "P5E_CPU0_P2_RX_BUF_DP<12>")
		)
		(pad "AT35" smd oval
			(at 5.050028 3.940048)
			(size 0.254 0.3302)
			(layers "F.Cu" "F.Mask" "F.Paste")
			(net "P5E_CPU0_P2_TX_C_DP<12>")
		)
		(pad "AU4" smd circle
			(at 4.802632 -2.817368)
			(size 0.381 0.381)
			(layers "F.Cu" "F.Mask" "F.Paste")
			(net "GND")
		)
		(pad "AU13" smd circle
			(at 4.802632 -0.79629)
			(size 0.3048 0.3048)
			(layers "F.Cu" "F.Mask" "F.Paste")
			(net "GND")
		)
		(pad "AU17" smd circle
			(at 4.802632 -0.296164)
			(size 0.3048 0.3048)
			(layers "F.Cu" "F.Mask" "F.Paste")
			(net "P0V9_CPU0_RT2_2A")
		)
		(pad "AU20" smd circle
			(at 4.802632 0.203708)
			(size 0.3048 0.3048)
			(layers "F.Cu" "F.Mask" "F.Paste")
			(net "P0V9_CPU0_RT2_2A")
		)
		(pad "AU22" smd circle
			(at 4.802632 0.703834)
			(size 0.3048 0.3048)
			(layers "F.Cu" "F.Mask" "F.Paste")
			(net "GND")
		)
		(pad "AU32" smd circle
			(at 4.802632 2.724912)
			(size 0.381 0.381)
			(layers "F.Cu" "F.Mask" "F.Paste")
			(net "GND")
		)
		(pad "AV2" smd circle
			(at 4.750054 -3.41884)
			(size 0.3048 0.3048)
			(layers "F.Cu" "F.Mask" "F.Paste")
			(net "GND")
		)
		(pad "AV34" smd circle
			(at 4.750054 3.420364)
			(size 0.3048 0.3048)
			(layers "F.Cu" "F.Mask" "F.Paste")
			(net "GND")
		)
		(pad "AW1" smd oval
			(at 4.45008 -3.938524)
			(size 0.254 0.3302)
			(layers "F.Cu" "F.Mask" "F.Paste")
			(net "GND")
		)
		(pad "AW35" smd oval
			(at 4.45008 3.940048)
			(size 0.254 0.3302)
			(layers "F.Cu" "F.Mask" "F.Paste")
			(net "GND")
		)
		(pad "AY7" smd circle
			(at 4.402582 -2.12471)
			(size 0.381 0.381)
			(layers "F.Cu" "F.Mask" "F.Paste")
			(net "P5E_CPU0_P2_TX_BUF_DP<11>")
		)
		(pad "AY26" smd circle
			(at 4.402582 1.339342)
			(size 0.381 0.381)
			(layers "F.Cu" "F.Mask" "F.Paste")
			(net "P5E_CPU0_P2_RX_DP<11>")
		)
		(pad "B3" smd oval
			(at 10.885932 -2.888488 90)
			(size 0.254 0.3302)
			(layers "F.Cu" "F.Mask" "F.Paste")
			(net "JTAG_TCK_RT_CPU0_P2")
		)
		(pad "B6" smd oval
			(at 10.885932 -2.288286 90)
			(size 0.254 0.3302)
			(layers "F.Cu" "F.Mask" "F.Paste")
			(net "JTAG_TDI_RT_CPU0_P2")
		)
		(pad "B9" smd oval
			(at 10.885932 -1.688338 90)
			(size 0.254 0.3302)
			(layers "F.Cu" "F.Mask" "F.Paste")
			(net "JTAG_TDO_RT_CPU0_P2")
		)
		(pad "B12" smd oval
			(at 10.885932 -1.08839 90)
			(size 0.254 0.3302)
			(layers "F.Cu" "F.Mask" "F.Paste")
			(net "JTAG_TMS_RT_CPU0_P2")
		)
		(pad "B16" smd oval
			(at 10.885932 -0.488442 90)
			(size 0.254 0.3302)
			(layers "F.Cu" "F.Mask" "F.Paste")
			(net "Net_2211")
		)
		(pad "B19" smd oval
			(at 10.885932 0.111506 90)
			(size 0.254 0.3302)
			(layers "F.Cu" "F.Mask" "F.Paste")
			(net "GND")
		)
		(pad "B23" smd oval
			(at 10.885932 0.711708 90)
			(size 0.254 0.3302)
			(layers "F.Cu" "F.Mask" "F.Paste")
			(net "RT_CPU0_P2_ADDR2")
		)
		(pad "B25" smd oval
			(at 10.885932 1.311656 90)
			(size 0.254 0.3302)
			(layers "F.Cu" "F.Mask" "F.Paste")
			(net "RT_CPU0_P2_ADDR3")
		)
		(pad "B28" smd oval
			(at 10.885932 1.911604 90)
			(size 0.254 0.3302)
			(layers "F.Cu" "F.Mask" "F.Paste")
			(net "SMB_RT_CPU0_P2_R2_SDA")
		)
		(pad "B31" smd oval
			(at 10.885932 2.511552 90)
			(size 0.254 0.3302)
			(layers "F.Cu" "F.Mask" "F.Paste")
			(net "SMB_RT_CPU0_P2_R2_SCL")
		)
		(pad "BA2" smd circle
			(at 4.150106 -3.41884)
			(size 0.3048 0.3048)
			(layers "F.Cu" "F.Mask" "F.Paste")
			(net "P5E_CPU0_P2_RX_BUF_DN<11>")
		)
		(pad "BA34" smd circle
			(at 4.150106 3.420364)
			(size 0.3048 0.3048)
			(layers "F.Cu" "F.Mask" "F.Paste")
			(net "P5E_CPU0_P2_TX_C_DN<11>")
		)
		(pad "BB10" smd circle
			(at 4.002532 -1.431798)
			(size 0.381 0.381)
			(layers "F.Cu" "F.Mask" "F.Paste")
			(net "P5E_CPU0_P2_TX_BUF_DN<11>")
		)
		(pad "BB29" smd circle
			(at 4.002532 2.032254)
			(size 0.381 0.381)
			(layers "F.Cu" "F.Mask" "F.Paste")
			(net "P5E_CPU0_P2_RX_DN<11>")
		)
		(pad "BC1" smd oval
			(at 3.849878 -3.938524)
			(size 0.254 0.3302)
			(layers "F.Cu" "F.Mask" "F.Paste")
			(net "P5E_CPU0_P2_RX_BUF_DP<11>")
		)
		(pad "BC35" smd oval
			(at 3.849878 3.940048)
			(size 0.254 0.3302)
			(layers "F.Cu" "F.Mask" "F.Paste")
			(net "P5E_CPU0_P2_TX_C_DP<11>")
		)
		(pad "BD4" smd circle
			(at 3.602482 -2.817368)
			(size 0.381 0.381)
			(layers "F.Cu" "F.Mask" "F.Paste")
			(net "GND")
		)
		(pad "BD13" smd circle
			(at 3.602482 -0.79629)
			(size 0.3048 0.3048)
			(layers "F.Cu" "F.Mask" "F.Paste")
			(net "GND")
		)
		(pad "BD17" smd circle
			(at 3.602482 -0.296164)
			(size 0.3048 0.3048)
			(layers "F.Cu" "F.Mask" "F.Paste")
			(net "P0V9_CPU0_RT2_2A_2D")
		)
		(pad "BD20" smd circle
			(at 3.602482 0.203708)
			(size 0.3048 0.3048)
			(layers "F.Cu" "F.Mask" "F.Paste")
			(net "P0V9_CPU0_RT2_2A_2D")
		)
		(pad "BD22" smd circle
			(at 3.602482 0.703834)
			(size 0.3048 0.3048)
			(layers "F.Cu" "F.Mask" "F.Paste")
			(net "GND")
		)
		(pad "BD32" smd circle
			(at 3.602482 2.724912)
			(size 0.381 0.381)
			(layers "F.Cu" "F.Mask" "F.Paste")
			(net "GND")
		)
		(pad "BE2" smd circle
			(at 3.549904 -3.41884)
			(size 0.3048 0.3048)
			(layers "F.Cu" "F.Mask" "F.Paste")
			(net "GND")
		)
		(pad "BE34" smd circle
			(at 3.549904 3.420364)
			(size 0.3048 0.3048)
			(layers "F.Cu" "F.Mask" "F.Paste")
			(net "GND")
		)
		(pad "BF1" smd oval
			(at 3.24993 -3.938524)
			(size 0.254 0.3302)
			(layers "F.Cu" "F.Mask" "F.Paste")
			(net "GND")
		)
		(pad "BF35" smd oval
			(at 3.24993 3.940048)
			(size 0.254 0.3302)
			(layers "F.Cu" "F.Mask" "F.Paste")
			(net "GND")
		)
		(pad "BG7" smd circle
			(at 3.202686 -2.12471)
			(size 0.381 0.381)
			(layers "F.Cu" "F.Mask" "F.Paste")
			(net "P5E_CPU0_P2_TX_BUF_DP<10>")
		)
		(pad "BG26" smd circle
			(at 3.202686 1.339342)
			(size 0.381 0.381)
			(layers "F.Cu" "F.Mask" "F.Paste")
			(net "P5E_CPU0_P2_RX_DP<10>")
		)
		(pad "BH2" smd circle
			(at 2.949956 -3.41884)
			(size 0.3048 0.3048)
			(layers "F.Cu" "F.Mask" "F.Paste")
			(net "P5E_CPU0_P2_RX_BUF_DN<10>")
		)
		(pad "BH34" smd circle
			(at 2.949956 3.420364)
			(size 0.3048 0.3048)
			(layers "F.Cu" "F.Mask" "F.Paste")
			(net "P5E_CPU0_P2_TX_C_DN<10>")
		)
		(pad "BJ10" smd circle
			(at 2.802636 -1.431798)
			(size 0.381 0.381)
			(layers "F.Cu" "F.Mask" "F.Paste")
			(net "P5E_CPU0_P2_TX_BUF_DN<10>")
		)
		(pad "BJ29" smd circle
			(at 2.802636 2.032254)
			(size 0.381 0.381)
			(layers "F.Cu" "F.Mask" "F.Paste")
			(net "P5E_CPU0_P2_RX_DN<10>")
		)
		(pad "BK1" smd oval
			(at 2.649982 -3.938524)
			(size 0.254 0.3302)
			(layers "F.Cu" "F.Mask" "F.Paste")
			(net "P5E_CPU0_P2_RX_BUF_DP<10>")
		)
		(pad "BK35" smd oval
			(at 2.649982 3.940048)
			(size 0.254 0.3302)
			(layers "F.Cu" "F.Mask" "F.Paste")
			(net "P5E_CPU0_P2_TX_C_DP<10>")
		)
		(pad "BL4" smd circle
			(at 2.402586 -2.817368)
			(size 0.381 0.381)
			(layers "F.Cu" "F.Mask" "F.Paste")
			(net "GND")
		)
		(pad "BL13" smd circle
			(at 2.402586 -0.79629)
			(size 0.3048 0.3048)
			(layers "F.Cu" "F.Mask" "F.Paste")
			(net "GND")
		)
		(pad "BL17" smd circle
			(at 2.402586 -0.296164)
			(size 0.3048 0.3048)
			(layers "F.Cu" "F.Mask" "F.Paste")
			(net "P0V9_CPU0_RT_2D")
		)
		(pad "BL20" smd circle
			(at 2.402586 0.203708)
			(size 0.3048 0.3048)
			(layers "F.Cu" "F.Mask" "F.Paste")
			(net "P0V9_CPU0_RT_2D")
		)
		(pad "BL22" smd circle
			(at 2.402586 0.703834)
			(size 0.3048 0.3048)
			(layers "F.Cu" "F.Mask" "F.Paste")
			(net "GND")
		)
		(pad "BL32" smd circle
			(at 2.402586 2.724912)
			(size 0.381 0.381)
			(layers "F.Cu" "F.Mask" "F.Paste")
			(net "GND")
		)
		(pad "BM2" smd circle
			(at 2.350008 -3.41884)
			(size 0.3048 0.3048)
			(layers "F.Cu" "F.Mask" "F.Paste")
			(net "GND")
		)
		(pad "BM34" smd circle
			(at 2.350008 3.420364)
			(size 0.3048 0.3048)
			(layers "F.Cu" "F.Mask" "F.Paste")
			(net "GND")
		)
		(pad "BN1" smd oval
			(at 2.050034 -3.938524)
			(size 0.254 0.3302)
			(layers "F.Cu" "F.Mask" "F.Paste")
			(net "GND")
		)
		(pad "BN35" smd oval
			(at 2.050034 3.940048)
			(size 0.254 0.3302)
			(layers "F.Cu" "F.Mask" "F.Paste")
			(net "GND")
		)
		(pad "BP7" smd circle
			(at 2.002536 -2.12471)
			(size 0.381 0.381)
			(layers "F.Cu" "F.Mask" "F.Paste")
			(net "P5E_CPU0_P2_TX_BUF_DP<9>")
		)
		(pad "BP26" smd circle
			(at 2.002536 1.339342)
			(size 0.381 0.381)
			(layers "F.Cu" "F.Mask" "F.Paste")
			(net "P5E_CPU0_P2_RX_DP<9>")
		)
		(pad "BR2" smd circle
			(at 1.75006 -3.41884)
			(size 0.3048 0.3048)
			(layers "F.Cu" "F.Mask" "F.Paste")
			(net "P5E_CPU0_P2_RX_BUF_DN<9>")
		)
		(pad "BR34" smd circle
			(at 1.75006 3.420364)
			(size 0.3048 0.3048)
			(layers "F.Cu" "F.Mask" "F.Paste")
			(net "P5E_CPU0_P2_TX_C_DN<9>")
		)
		(pad "BT10" smd circle
			(at 1.602486 -1.431798)
			(size 0.381 0.381)
			(layers "F.Cu" "F.Mask" "F.Paste")
			(net "P5E_CPU0_P2_TX_BUF_DN<9>")
		)
		(pad "BT29" smd circle
			(at 1.602486 2.032254)
			(size 0.381 0.381)
			(layers "F.Cu" "F.Mask" "F.Paste")
			(net "P5E_CPU0_P2_RX_DN<9>")
		)
		(pad "BU1" smd oval
			(at 1.450086 -3.938524)
			(size 0.254 0.3302)
			(layers "F.Cu" "F.Mask" "F.Paste")
			(net "P5E_CPU0_P2_RX_BUF_DP<9>")
		)
		(pad "BU35" smd oval
			(at 1.450086 3.940048)
			(size 0.254 0.3302)
			(layers "F.Cu" "F.Mask" "F.Paste")
			(net "P5E_CPU0_P2_TX_C_DP<9>")
		)
		(pad "BV4" smd circle
			(at 1.20269 -2.817368)
			(size 0.381 0.381)
			(layers "F.Cu" "F.Mask" "F.Paste")
			(net "GND")
		)
		(pad "BV13" smd circle
			(at 1.20269 -0.79629)
			(size 0.3048 0.3048)
			(layers "F.Cu" "F.Mask" "F.Paste")
			(net "GND")
		)
		(pad "BV17" smd circle
			(at 1.20269 -0.296164)
			(size 0.3048 0.3048)
			(layers "F.Cu" "F.Mask" "F.Paste")
			(net "P1V8_CPU0_RT2_1A_1D")
		)
		(pad "BV20" smd circle
			(at 1.20269 0.203708)
			(size 0.3048 0.3048)
			(layers "F.Cu" "F.Mask" "F.Paste")
			(net "P1V8_CPU0_RT2_1A")
		)
		(pad "BV22" smd circle
			(at 1.20269 0.703834)
			(size 0.3048 0.3048)
			(layers "F.Cu" "F.Mask" "F.Paste")
			(net "GND")
		)
		(pad "BV32" smd circle
			(at 1.20269 2.724912)
			(size 0.381 0.381)
			(layers "F.Cu" "F.Mask" "F.Paste")
			(net "GND")
		)
		(pad "BW2" smd circle
			(at 1.150112 -3.41884)
			(size 0.3048 0.3048)
			(layers "F.Cu" "F.Mask" "F.Paste")
			(net "GND")
		)
		(pad "BW34" smd circle
			(at 1.150112 3.420364)
			(size 0.3048 0.3048)
			(layers "F.Cu" "F.Mask" "F.Paste")
			(net "GND")
		)
		(pad "BY1" smd oval
			(at 0.849884 -3.938524)
			(size 0.254 0.3302)
			(layers "F.Cu" "F.Mask" "F.Paste")
			(net "GND")
		)
		(pad "BY35" smd oval
			(at 0.849884 3.940048)
			(size 0.254 0.3302)
			(layers "F.Cu" "F.Mask" "F.Paste")
			(net "GND")
		)
		(pad "C2" smd circle
			(at 10.750042 -3.41884)
			(size 0.3048 0.3048)
			(layers "F.Cu" "F.Mask" "F.Paste")
			(net "NCF_CPU0_P2_GND")
		)
		(pad "C34" smd circle
			(at 10.750042 3.420364)
			(size 0.3048 0.3048)
			(layers "F.Cu" "F.Mask" "F.Paste")
			(net "NCF_CPU0_P2_GND")
		)
		(pad "CA7" smd circle
			(at 0.80264 -2.12471)
			(size 0.381 0.381)
			(layers "F.Cu" "F.Mask" "F.Paste")
			(net "P5E_CPU0_P2_TX_BUF_DP<8>")
		)
		(pad "CA26" smd circle
			(at 0.80264 1.339342)
			(size 0.381 0.381)
			(layers "F.Cu" "F.Mask" "F.Paste")
			(net "P5E_CPU0_P2_RX_DP<8>")
		)
		(pad "CB2" smd circle
			(at 0.54991 -3.41884)
			(size 0.3048 0.3048)
			(layers "F.Cu" "F.Mask" "F.Paste")
			(net "P5E_CPU0_P2_RX_BUF_DN<8>")
		)
		(pad "CB34" smd circle
			(at 0.54991 3.420364)
			(size 0.3048 0.3048)
			(layers "F.Cu" "F.Mask" "F.Paste")
			(net "P5E_CPU0_P2_TX_C_DN<8>")
		)
		(pad "CC10" smd circle
			(at 0.40259 -1.431798)
			(size 0.381 0.381)
			(layers "F.Cu" "F.Mask" "F.Paste")
			(net "P5E_CPU0_P2_TX_BUF_DN<8>")
		)
		(pad "CC29" smd circle
			(at 0.40259 2.032254)
			(size 0.381 0.381)
			(layers "F.Cu" "F.Mask" "F.Paste")
			(net "P5E_CPU0_P2_RX_DN<8>")
		)
		(pad "CD1" smd oval
			(at 0.249936 -3.938524)
			(size 0.254 0.3302)
			(layers "F.Cu" "F.Mask" "F.Paste")
			(net "P5E_CPU0_P2_RX_BUF_DP<8>")
		)
		(pad "CD35" smd oval
			(at 0.249936 3.940048)
			(size 0.254 0.3302)
			(layers "F.Cu" "F.Mask" "F.Paste")
			(net "P5E_CPU0_P2_TX_C_DP<8>")
		)
		(pad "CE4" smd circle
			(at 0.00254 -2.817368)
			(size 0.381 0.381)
			(layers "F.Cu" "F.Mask" "F.Paste")
			(net "GND")
		)
		(pad "CE13" smd circle
			(at 0.00254 -0.79629)
			(size 0.3048 0.3048)
			(layers "F.Cu" "F.Mask" "F.Paste")
			(net "GND")
		)
		(pad "CE17" smd circle
			(at 0.00254 -0.296164)
			(size 0.3048 0.3048)
			(layers "F.Cu" "F.Mask" "F.Paste")
			(net "P1V8_CPU0_RT2_1A")
		)
		(pad "CE20" smd circle
			(at 0.00254 0.203708)
			(size 0.3048 0.3048)
			(layers "F.Cu" "F.Mask" "F.Paste")
			(net "P1V8_CPU0_RT2_1A")
		)
		(pad "CE22" smd circle
			(at 0.00254 0.703834)
			(size 0.3048 0.3048)
			(layers "F.Cu" "F.Mask" "F.Paste")
			(net "GND")
		)
		(pad "CE32" smd circle
			(at 0.00254 2.724912)
			(size 0.381 0.381)
			(layers "F.Cu" "F.Mask" "F.Paste")
			(net "GND")
		)
		(pad "CF2" smd circle
			(at -0.050038 -3.41884)
			(size 0.3048 0.3048)
			(layers "F.Cu" "F.Mask" "F.Paste")
			(net "GND")
		)
		(pad "CF34" smd circle
			(at -0.050038 3.420364)
			(size 0.3048 0.3048)
			(layers "F.Cu" "F.Mask" "F.Paste")
			(net "GND")
		)
		(pad "CG1" smd oval
			(at -0.350012 -3.938524)
			(size 0.254 0.3302)
			(layers "F.Cu" "F.Mask" "F.Paste")
			(net "GND")
		)
		(pad "CG35" smd oval
			(at -0.350012 3.940048)
			(size 0.254 0.3302)
			(layers "F.Cu" "F.Mask" "F.Paste")
			(net "GND")
		)
		(pad "CH7" smd circle
			(at -0.39751 -2.12471)
			(size 0.381 0.381)
			(layers "F.Cu" "F.Mask" "F.Paste")
			(net "P5E_CPU0_P2_TX_BUF_DP<7>")
		)
		(pad "CH26" smd circle
			(at -0.39751 1.339342)
			(size 0.381 0.381)
			(layers "F.Cu" "F.Mask" "F.Paste")
			(net "P5E_CPU0_P2_RX_DP<7>")
		)
		(pad "CJ2" smd circle
			(at -0.649986 -3.41884)
			(size 0.3048 0.3048)
			(layers "F.Cu" "F.Mask" "F.Paste")
			(net "P5E_CPU0_P2_RX_BUF_DN<7>")
		)
		(pad "CJ34" smd circle
			(at -0.649986 3.420364)
			(size 0.3048 0.3048)
			(layers "F.Cu" "F.Mask" "F.Paste")
			(net "P5E_CPU0_P2_TX_C_DN<7>")
		)
		(pad "CK10" smd circle
			(at -0.797306 -1.431798)
			(size 0.381 0.381)
			(layers "F.Cu" "F.Mask" "F.Paste")
			(net "P5E_CPU0_P2_TX_BUF_DN<7>")
		)
		(pad "CK29" smd circle
			(at -0.797306 2.032254)
			(size 0.381 0.381)
			(layers "F.Cu" "F.Mask" "F.Paste")
			(net "P5E_CPU0_P2_RX_DN<7>")
		)
		(pad "CL1" smd oval
			(at -0.94996 -3.938524)
			(size 0.254 0.3302)
			(layers "F.Cu" "F.Mask" "F.Paste")
			(net "P5E_CPU0_P2_RX_BUF_DP<7>")
		)
		(pad "CL35" smd oval
			(at -0.94996 3.940048)
			(size 0.254 0.3302)
			(layers "F.Cu" "F.Mask" "F.Paste")
			(net "P5E_CPU0_P2_TX_C_DP<7>")
		)
		(pad "CM4" smd circle
			(at -1.197356 -2.817368)
			(size 0.381 0.381)
			(layers "F.Cu" "F.Mask" "F.Paste")
			(net "GND")
		)
		(pad "CM13" smd circle
			(at -1.197356 -0.79629)
			(size 0.3048 0.3048)
			(layers "F.Cu" "F.Mask" "F.Paste")
			(net "GND")
		)
		(pad "CM17" smd circle
			(at -1.197356 -0.296164)
			(size 0.3048 0.3048)
			(layers "F.Cu" "F.Mask" "F.Paste")
			(net "P1V8_CPU0_RT2_1A")
		)
		(pad "CM20" smd circle
			(at -1.197356 0.203708)
			(size 0.3048 0.3048)
			(layers "F.Cu" "F.Mask" "F.Paste")
			(net "P1V8_CPU0_RT2_1A")
		)
		(pad "CM22" smd circle
			(at -1.197356 0.703834)
			(size 0.3048 0.3048)
			(layers "F.Cu" "F.Mask" "F.Paste")
			(net "GND")
		)
		(pad "CM32" smd circle
			(at -1.197356 2.724912)
			(size 0.381 0.381)
			(layers "F.Cu" "F.Mask" "F.Paste")
			(net "GND")
		)
		(pad "CN2" smd circle
			(at -1.249934 -3.41884)
			(size 0.3048 0.3048)
			(layers "F.Cu" "F.Mask" "F.Paste")
			(net "GND")
		)
		(pad "CN34" smd circle
			(at -1.249934 3.420364)
			(size 0.3048 0.3048)
			(layers "F.Cu" "F.Mask" "F.Paste")
			(net "GND")
		)
		(pad "CP1" smd oval
			(at -1.549908 -3.938524)
			(size 0.254 0.3302)
			(layers "F.Cu" "F.Mask" "F.Paste")
			(net "GND")
		)
		(pad "CP35" smd oval
			(at -1.549908 3.940048)
			(size 0.254 0.3302)
			(layers "F.Cu" "F.Mask" "F.Paste")
			(net "GND")
		)
		(pad "CR7" smd circle
			(at -1.597406 -2.12471)
			(size 0.381 0.381)
			(layers "F.Cu" "F.Mask" "F.Paste")
			(net "P5E_CPU0_P2_TX_BUF_DP<6>")
		)
		(pad "CR26" smd circle
			(at -1.597406 1.339342)
			(size 0.381 0.381)
			(layers "F.Cu" "F.Mask" "F.Paste")
			(net "P5E_CPU0_P2_RX_DP<6>")
		)
		(pad "CT2" smd circle
			(at -1.849882 -3.41884)
			(size 0.3048 0.3048)
			(layers "F.Cu" "F.Mask" "F.Paste")
			(net "P5E_CPU0_P2_RX_BUF_DN<6>")
		)
		(pad "CT34" smd circle
			(at -1.849882 3.420364)
			(size 0.3048 0.3048)
			(layers "F.Cu" "F.Mask" "F.Paste")
			(net "P5E_CPU0_P2_TX_C_DN<6>")
		)
		(pad "CU10" smd circle
			(at -1.997456 -1.431798)
			(size 0.381 0.381)
			(layers "F.Cu" "F.Mask" "F.Paste")
			(net "P5E_CPU0_P2_TX_BUF_DN<6>")
		)
		(pad "CU29" smd circle
			(at -1.997456 2.032254)
			(size 0.381 0.381)
			(layers "F.Cu" "F.Mask" "F.Paste")
			(net "P5E_CPU0_P2_RX_DN<6>")
		)
		(pad "CV1" smd oval
			(at -2.15011 -3.938524)
			(size 0.254 0.3302)
			(layers "F.Cu" "F.Mask" "F.Paste")
			(net "P5E_CPU0_P2_RX_BUF_DP<6>")
		)
		(pad "CV35" smd oval
			(at -2.15011 3.940048)
			(size 0.254 0.3302)
			(layers "F.Cu" "F.Mask" "F.Paste")
			(net "P5E_CPU0_P2_TX_C_DP<6>")
		)
		(pad "CW4" smd circle
			(at -2.397506 -2.817368)
			(size 0.381 0.381)
			(layers "F.Cu" "F.Mask" "F.Paste")
			(net "GND")
		)
		(pad "CW13" smd circle
			(at -2.397506 -0.79629)
			(size 0.3048 0.3048)
			(layers "F.Cu" "F.Mask" "F.Paste")
			(net "GND")
		)
		(pad "CW17" smd circle
			(at -2.397506 -0.296164)
			(size 0.3048 0.3048)
			(layers "F.Cu" "F.Mask" "F.Paste")
			(net "P0V9_CPU0_RT_2D")
		)
		(pad "CW20" smd circle
			(at -2.397506 0.203708)
			(size 0.3048 0.3048)
			(layers "F.Cu" "F.Mask" "F.Paste")
			(net "P0V9_CPU0_RT_2D")
		)
		(pad "CW22" smd circle
			(at -2.397506 0.703834)
			(size 0.3048 0.3048)
			(layers "F.Cu" "F.Mask" "F.Paste")
			(net "GND")
		)
		(pad "CW32" smd circle
			(at -2.397506 2.724912)
			(size 0.381 0.381)
			(layers "F.Cu" "F.Mask" "F.Paste")
			(net "GND")
		)
		(pad "CY2" smd circle
			(at -2.450084 -3.41884)
			(size 0.3048 0.3048)
			(layers "F.Cu" "F.Mask" "F.Paste")
			(net "GND")
		)
		(pad "CY34" smd circle
			(at -2.450084 3.420364)
			(size 0.3048 0.3048)
			(layers "F.Cu" "F.Mask" "F.Paste")
			(net "GND")
		)
		(pad "D1" smd oval
			(at 10.450068 -3.938524)
			(size 0.254 0.3302)
			(layers "F.Cu" "F.Mask" "F.Paste")
			(net "NCF_CPU0_P2_GND")
		)
		(pad "D35" smd oval
			(at 10.450068 3.940048)
			(size 0.254 0.3302)
			(layers "F.Cu" "F.Mask" "F.Paste")
			(net "NCF_CPU0_P2_GND")
		)
		(pad "DA1" smd oval
			(at -2.750058 -3.938524)
			(size 0.254 0.3302)
			(layers "F.Cu" "F.Mask" "F.Paste")
			(net "GND")
		)
		(pad "DA35" smd oval
			(at -2.750058 3.940048)
			(size 0.254 0.3302)
			(layers "F.Cu" "F.Mask" "F.Paste")
			(net "GND")
		)
		(pad "DB7" smd circle
			(at -2.797302 -2.12471)
			(size 0.381 0.381)
			(layers "F.Cu" "F.Mask" "F.Paste")
			(net "P5E_CPU0_P2_TX_BUF_DP<5>")
		)
		(pad "DB26" smd circle
			(at -2.797302 1.339342)
			(size 0.381 0.381)
			(layers "F.Cu" "F.Mask" "F.Paste")
			(net "P5E_CPU0_P2_RX_DP<5>")
		)
		(pad "DC2" smd circle
			(at -3.050032 -3.41884)
			(size 0.3048 0.3048)
			(layers "F.Cu" "F.Mask" "F.Paste")
			(net "P5E_CPU0_P2_RX_BUF_DN<5>")
		)
		(pad "DC34" smd circle
			(at -3.050032 3.420364)
			(size 0.3048 0.3048)
			(layers "F.Cu" "F.Mask" "F.Paste")
			(net "P5E_CPU0_P2_TX_C_DN<5>")
		)
		(pad "DD10" smd circle
			(at -3.197352 -1.431798)
			(size 0.381 0.381)
			(layers "F.Cu" "F.Mask" "F.Paste")
			(net "P5E_CPU0_P2_TX_BUF_DN<5>")
		)
		(pad "DD29" smd circle
			(at -3.197352 2.032254)
			(size 0.381 0.381)
			(layers "F.Cu" "F.Mask" "F.Paste")
			(net "P5E_CPU0_P2_RX_DN<5>")
		)
		(pad "DE1" smd oval
			(at -3.350006 -3.938524)
			(size 0.254 0.3302)
			(layers "F.Cu" "F.Mask" "F.Paste")
			(net "P5E_CPU0_P2_RX_BUF_DP<5>")
		)
		(pad "DE35" smd oval
			(at -3.350006 3.940048)
			(size 0.254 0.3302)
			(layers "F.Cu" "F.Mask" "F.Paste")
			(net "P5E_CPU0_P2_TX_C_DP<5>")
		)
		(pad "DF4" smd circle
			(at -3.597402 -2.817368)
			(size 0.381 0.381)
			(layers "F.Cu" "F.Mask" "F.Paste")
			(net "GND")
		)
		(pad "DF13" smd circle
			(at -3.597402 -0.79629)
			(size 0.3048 0.3048)
			(layers "F.Cu" "F.Mask" "F.Paste")
			(net "GND")
		)
		(pad "DF17" smd circle
			(at -3.597402 -0.296164)
			(size 0.3048 0.3048)
			(layers "F.Cu" "F.Mask" "F.Paste")
			(net "P0V9_CPU0_RT2_2A_2D")
		)
		(pad "DF20" smd circle
			(at -3.597402 0.203708)
			(size 0.3048 0.3048)
			(layers "F.Cu" "F.Mask" "F.Paste")
			(net "P0V9_CPU0_RT2_2A_2D")
		)
		(pad "DF22" smd circle
			(at -3.597402 0.703834)
			(size 0.3048 0.3048)
			(layers "F.Cu" "F.Mask" "F.Paste")
			(net "GND")
		)
		(pad "DF32" smd circle
			(at -3.597402 2.724912)
			(size 0.381 0.381)
			(layers "F.Cu" "F.Mask" "F.Paste")
			(net "GND")
		)
		(pad "DG2" smd circle
			(at -3.64998 -3.41884)
			(size 0.3048 0.3048)
			(layers "F.Cu" "F.Mask" "F.Paste")
			(net "GND")
		)
		(pad "DG34" smd circle
			(at -3.64998 3.420364)
			(size 0.3048 0.3048)
			(layers "F.Cu" "F.Mask" "F.Paste")
			(net "GND")
		)
		(pad "DH1" smd oval
			(at -3.949954 -3.938524)
			(size 0.254 0.3302)
			(layers "F.Cu" "F.Mask" "F.Paste")
			(net "GND")
		)
		(pad "DH35" smd oval
			(at -3.949954 3.940048)
			(size 0.254 0.3302)
			(layers "F.Cu" "F.Mask" "F.Paste")
			(net "GND")
		)
		(pad "DJ7" smd circle
			(at -3.997452 -2.12471)
			(size 0.381 0.381)
			(layers "F.Cu" "F.Mask" "F.Paste")
			(net "P5E_CPU0_P2_TX_BUF_DP<4>")
		)
		(pad "DJ26" smd circle
			(at -3.997452 1.339342)
			(size 0.381 0.381)
			(layers "F.Cu" "F.Mask" "F.Paste")
			(net "P5E_CPU0_P2_RX_DP<4>")
		)
		(pad "DK2" smd circle
			(at -4.249928 -3.41884)
			(size 0.3048 0.3048)
			(layers "F.Cu" "F.Mask" "F.Paste")
			(net "P5E_CPU0_P2_RX_BUF_DN<4>")
		)
		(pad "DK34" smd circle
			(at -4.249928 3.420364)
			(size 0.3048 0.3048)
			(layers "F.Cu" "F.Mask" "F.Paste")
			(net "P5E_CPU0_P2_TX_C_DN<4>")
		)
		(pad "DL10" smd circle
			(at -4.397502 -1.431798)
			(size 0.381 0.381)
			(layers "F.Cu" "F.Mask" "F.Paste")
			(net "P5E_CPU0_P2_TX_BUF_DN<4>")
		)
		(pad "DL29" smd circle
			(at -4.397502 2.032254)
			(size 0.381 0.381)
			(layers "F.Cu" "F.Mask" "F.Paste")
			(net "P5E_CPU0_P2_RX_DN<4>")
		)
		(pad "DM1" smd oval
			(at -4.549902 -3.938524)
			(size 0.254 0.3302)
			(layers "F.Cu" "F.Mask" "F.Paste")
			(net "P5E_CPU0_P2_RX_BUF_DP<4>")
		)
		(pad "DM35" smd oval
			(at -4.549902 3.940048)
			(size 0.254 0.3302)
			(layers "F.Cu" "F.Mask" "F.Paste")
			(net "P5E_CPU0_P2_TX_C_DP<4>")
		)
		(pad "DN4" smd circle
			(at -4.797298 -2.817368)
			(size 0.381 0.381)
			(layers "F.Cu" "F.Mask" "F.Paste")
			(net "GND")
		)
		(pad "DN13" smd circle
			(at -4.797298 -0.79629)
			(size 0.3048 0.3048)
			(layers "F.Cu" "F.Mask" "F.Paste")
			(net "GND")
		)
		(pad "DN17" smd circle
			(at -4.797298 -0.296164)
			(size 0.3048 0.3048)
			(layers "F.Cu" "F.Mask" "F.Paste")
			(net "P0V9_CPU0_RT2_2A")
		)
		(pad "DN20" smd circle
			(at -4.797298 0.203708)
			(size 0.3048 0.3048)
			(layers "F.Cu" "F.Mask" "F.Paste")
			(net "P0V9_CPU0_RT2_2A")
		)
		(pad "DN22" smd circle
			(at -4.797298 0.703834)
			(size 0.3048 0.3048)
			(layers "F.Cu" "F.Mask" "F.Paste")
			(net "GND")
		)
		(pad "DN32" smd circle
			(at -4.797298 2.724912)
			(size 0.381 0.381)
			(layers "F.Cu" "F.Mask" "F.Paste")
			(net "GND")
		)
		(pad "DP2" smd circle
			(at -4.849876 -3.41884)
			(size 0.3048 0.3048)
			(layers "F.Cu" "F.Mask" "F.Paste")
			(net "GND")
		)
		(pad "DP34" smd circle
			(at -4.849876 3.420364)
			(size 0.3048 0.3048)
			(layers "F.Cu" "F.Mask" "F.Paste")
			(net "GND")
		)
		(pad "DR1" smd oval
			(at -5.150104 -3.938524)
			(size 0.254 0.3302)
			(layers "F.Cu" "F.Mask" "F.Paste")
			(net "GND")
		)
		(pad "DR35" smd oval
			(at -5.150104 3.940048)
			(size 0.254 0.3302)
			(layers "F.Cu" "F.Mask" "F.Paste")
			(net "GND")
		)
		(pad "DT7" smd circle
			(at -5.197348 -2.12471)
			(size 0.381 0.381)
			(layers "F.Cu" "F.Mask" "F.Paste")
			(net "P5E_CPU0_P2_TX_BUF_DP<3>")
		)
		(pad "DT26" smd circle
			(at -5.197348 1.339342)
			(size 0.381 0.381)
			(layers "F.Cu" "F.Mask" "F.Paste")
			(net "P5E_CPU0_P2_RX_DP<3>")
		)
		(pad "DU2" smd circle
			(at -5.450078 -3.41884)
			(size 0.3048 0.3048)
			(layers "F.Cu" "F.Mask" "F.Paste")
			(net "P5E_CPU0_P2_RX_BUF_DN<3>")
		)
		(pad "DU34" smd circle
			(at -5.450078 3.420364)
			(size 0.3048 0.3048)
			(layers "F.Cu" "F.Mask" "F.Paste")
			(net "P5E_CPU0_P2_TX_C_DN<3>")
		)
		(pad "DV10" smd circle
			(at -5.597398 -1.431798)
			(size 0.381 0.381)
			(layers "F.Cu" "F.Mask" "F.Paste")
			(net "P5E_CPU0_P2_TX_BUF_DN<3>")
		)
		(pad "DV29" smd circle
			(at -5.597398 2.032254)
			(size 0.381 0.381)
			(layers "F.Cu" "F.Mask" "F.Paste")
			(net "P5E_CPU0_P2_RX_DN<3>")
		)
		(pad "DW1" smd oval
			(at -5.750052 -3.938524)
			(size 0.254 0.3302)
			(layers "F.Cu" "F.Mask" "F.Paste")
			(net "P5E_CPU0_P2_RX_BUF_DP<3>")
		)
		(pad "DW35" smd oval
			(at -5.750052 3.940048)
			(size 0.254 0.3302)
			(layers "F.Cu" "F.Mask" "F.Paste")
			(net "P5E_CPU0_P2_TX_C_DP<3>")
		)
		(pad "DY4" smd circle
			(at -5.997448 -2.817368)
			(size 0.381 0.381)
			(layers "F.Cu" "F.Mask" "F.Paste")
			(net "GND")
		)
		(pad "DY13" smd circle
			(at -5.997448 -0.79629)
			(size 0.3048 0.3048)
			(layers "F.Cu" "F.Mask" "F.Paste")
			(net "GND")
		)
		(pad "DY17" smd circle
			(at -5.997448 -0.296164)
			(size 0.3048 0.3048)
			(layers "F.Cu" "F.Mask" "F.Paste")
			(net "P0V9_CPU0_RT2_2A")
		)
		(pad "DY20" smd circle
			(at -5.997448 0.203708)
			(size 0.3048 0.3048)
			(layers "F.Cu" "F.Mask" "F.Paste")
			(net "P0V9_CPU0_RT2_2A")
		)
		(pad "DY22" smd circle
			(at -5.997448 0.703834)
			(size 0.3048 0.3048)
			(layers "F.Cu" "F.Mask" "F.Paste")
			(net "GND")
		)
		(pad "DY32" smd circle
			(at -5.997448 2.724912)
			(size 0.381 0.381)
			(layers "F.Cu" "F.Mask" "F.Paste")
			(net "GND")
		)
		(pad "E8" smd circle
			(at 10.366502 -1.988312)
			(size 0.3048 0.3048)
			(layers "F.Cu" "F.Mask" "F.Paste")
			(net "JTAG_TRST_RT_CPU0_P2_N")
		)
		(pad "E11" smd circle
			(at 10.366502 -1.388364)
			(size 0.3048 0.3048)
			(layers "F.Cu" "F.Mask" "F.Paste")
			(net "RXDET_BYP_RT_CPU0_P2")
		)
		(pad "E14" smd circle
			(at 10.366502 -0.788416)
			(size 0.3048 0.3048)
			(layers "F.Cu" "F.Mask" "F.Paste")
			(net "GND")
		)
		(pad "E18" smd circle
			(at 10.366502 -0.188468)
			(size 0.3048 0.3048)
			(layers "F.Cu" "F.Mask" "F.Paste")
			(net "Net_2210")
		)
		(pad "E27" smd circle
			(at 10.366502 1.61163)
			(size 0.3048 0.3048)
			(layers "F.Cu" "F.Mask" "F.Paste")
			(net "GND")
		)
		(pad "E30" smd circle
			(at 10.366502 2.211578)
			(size 0.3048 0.3048)
			(layers "F.Cu" "F.Mask" "F.Paste")
			(net "GND")
		)
		(pad "E33" smd circle
			(at 10.366502 2.811526)
			(size 0.3048 0.3048)
			(layers "F.Cu" "F.Mask" "F.Paste")
			(net "GND")
		)
		(pad "EA2" smd circle
			(at -6.050026 -3.41884)
			(size 0.3048 0.3048)
			(layers "F.Cu" "F.Mask" "F.Paste")
			(net "GND")
		)
		(pad "EA34" smd circle
			(at -6.050026 3.420364)
			(size 0.3048 0.3048)
			(layers "F.Cu" "F.Mask" "F.Paste")
			(net "GND")
		)
		(pad "EB1" smd oval
			(at -6.35 -3.938524)
			(size 0.254 0.3302)
			(layers "F.Cu" "F.Mask" "F.Paste")
			(net "GND")
		)
		(pad "EB35" smd oval
			(at -6.35 3.940048)
			(size 0.254 0.3302)
			(layers "F.Cu" "F.Mask" "F.Paste")
			(net "GND")
		)
		(pad "EC7" smd circle
			(at -6.397498 -2.12471)
			(size 0.381 0.381)
			(layers "F.Cu" "F.Mask" "F.Paste")
			(net "P5E_CPU0_P2_TX_BUF_DP<2>")
		)
		(pad "EC26" smd circle
			(at -6.397498 1.339342)
			(size 0.381 0.381)
			(layers "F.Cu" "F.Mask" "F.Paste")
			(net "P5E_CPU0_P2_RX_DP<2>")
		)
		(pad "ED2" smd circle
			(at -6.649974 -3.41884)
			(size 0.3048 0.3048)
			(layers "F.Cu" "F.Mask" "F.Paste")
			(net "P5E_CPU0_P2_RX_BUF_DN<2>")
		)
		(pad "ED34" smd circle
			(at -6.649974 3.420364)
			(size 0.3048 0.3048)
			(layers "F.Cu" "F.Mask" "F.Paste")
			(net "P5E_CPU0_P2_TX_C_DN<2>")
		)
		(pad "EE10" smd circle
			(at -6.797294 -1.431798)
			(size 0.381 0.381)
			(layers "F.Cu" "F.Mask" "F.Paste")
			(net "P5E_CPU0_P2_TX_BUF_DN<2>")
		)
		(pad "EE29" smd circle
			(at -6.797294 2.032254)
			(size 0.381 0.381)
			(layers "F.Cu" "F.Mask" "F.Paste")
			(net "P5E_CPU0_P2_RX_DN<2>")
		)
		(pad "EF1" smd oval
			(at -6.949948 -3.938524)
			(size 0.254 0.3302)
			(layers "F.Cu" "F.Mask" "F.Paste")
			(net "P5E_CPU0_P2_RX_BUF_DP<2>")
		)
		(pad "EF35" smd oval
			(at -6.949948 3.940048)
			(size 0.254 0.3302)
			(layers "F.Cu" "F.Mask" "F.Paste")
			(net "P5E_CPU0_P2_TX_C_DP<2>")
		)
		(pad "EG4" smd circle
			(at -7.197344 -2.817368)
			(size 0.381 0.381)
			(layers "F.Cu" "F.Mask" "F.Paste")
			(net "GND")
		)
		(pad "EG13" smd circle
			(at -7.197344 -0.79629)
			(size 0.3048 0.3048)
			(layers "F.Cu" "F.Mask" "F.Paste")
			(net "GND")
		)
		(pad "EG17" smd circle
			(at -7.197344 -0.296164)
			(size 0.3048 0.3048)
			(layers "F.Cu" "F.Mask" "F.Paste")
			(net "P0V9_CPU0_RT2_2A")
		)
		(pad "EG20" smd circle
			(at -7.197344 0.203708)
			(size 0.3048 0.3048)
			(layers "F.Cu" "F.Mask" "F.Paste")
			(net "P0V9_CPU0_RT2_2A")
		)
		(pad "EG22" smd circle
			(at -7.197344 0.703834)
			(size 0.3048 0.3048)
			(layers "F.Cu" "F.Mask" "F.Paste")
			(net "GND")
		)
		(pad "EG32" smd circle
			(at -7.197344 2.724912)
			(size 0.381 0.381)
			(layers "F.Cu" "F.Mask" "F.Paste")
			(net "GND")
		)
		(pad "EH2" smd circle
			(at -7.249922 -3.41884)
			(size 0.3048 0.3048)
			(layers "F.Cu" "F.Mask" "F.Paste")
			(net "GND")
		)
		(pad "EH34" smd circle
			(at -7.249922 3.420364)
			(size 0.3048 0.3048)
			(layers "F.Cu" "F.Mask" "F.Paste")
			(net "GND")
		)
		(pad "EJ1" smd oval
			(at -7.549896 -3.938524)
			(size 0.254 0.3302)
			(layers "F.Cu" "F.Mask" "F.Paste")
			(net "GND")
		)
		(pad "EJ35" smd oval
			(at -7.549896 3.940048)
			(size 0.254 0.3302)
			(layers "F.Cu" "F.Mask" "F.Paste")
			(net "GND")
		)
		(pad "EK7" smd circle
			(at -7.597394 -2.12471)
			(size 0.381 0.381)
			(layers "F.Cu" "F.Mask" "F.Paste")
			(net "P5E_CPU0_P2_TX_BUF_DP<1>")
		)
		(pad "EK26" smd circle
			(at -7.597394 1.339342)
			(size 0.381 0.381)
			(layers "F.Cu" "F.Mask" "F.Paste")
			(net "P5E_CPU0_P2_RX_DP<1>")
		)
		(pad "EL2" smd circle
			(at -7.850124 -3.41884)
			(size 0.3048 0.3048)
			(layers "F.Cu" "F.Mask" "F.Paste")
			(net "P5E_CPU0_P2_RX_BUF_DN<1>")
		)
		(pad "EL34" smd circle
			(at -7.850124 3.420364)
			(size 0.3048 0.3048)
			(layers "F.Cu" "F.Mask" "F.Paste")
			(net "P5E_CPU0_P2_TX_C_DP<1>")
		)
		(pad "EM10" smd circle
			(at -7.997444 -1.431798)
			(size 0.381 0.381)
			(layers "F.Cu" "F.Mask" "F.Paste")
			(net "P5E_CPU0_P2_TX_BUF_DN<1>")
		)
		(pad "EM29" smd circle
			(at -7.997444 2.032254)
			(size 0.381 0.381)
			(layers "F.Cu" "F.Mask" "F.Paste")
			(net "P5E_CPU0_P2_RX_DN<1>")
		)
		(pad "EN1" smd oval
			(at -8.150098 -3.938524)
			(size 0.254 0.3302)
			(layers "F.Cu" "F.Mask" "F.Paste")
			(net "P5E_CPU0_P2_RX_BUF_DP<1>")
		)
		(pad "EN35" smd oval
			(at -8.150098 3.940048)
			(size 0.254 0.3302)
			(layers "F.Cu" "F.Mask" "F.Paste")
			(net "P5E_CPU0_P2_TX_C_DN<1>")
		)
		(pad "EP4" smd circle
			(at -8.397494 -2.817368)
			(size 0.381 0.381)
			(layers "F.Cu" "F.Mask" "F.Paste")
			(net "GND")
		)
		(pad "EP13" smd circle
			(at -8.397494 -0.79629)
			(size 0.3048 0.3048)
			(layers "F.Cu" "F.Mask" "F.Paste")
			(net "GND")
		)
		(pad "EP17" smd circle
			(at -8.397494 -0.296164)
			(size 0.3048 0.3048)
			(layers "F.Cu" "F.Mask" "F.Paste")
			(net "P0V9_CPU0_RT2_2A")
		)
		(pad "EP20" smd circle
			(at -8.397494 0.203708)
			(size 0.3048 0.3048)
			(layers "F.Cu" "F.Mask" "F.Paste")
			(net "P0V9_CPU0_RT2_2A")
		)
		(pad "EP22" smd circle
			(at -8.397494 0.703834)
			(size 0.3048 0.3048)
			(layers "F.Cu" "F.Mask" "F.Paste")
			(net "GND")
		)
		(pad "EP32" smd circle
			(at -8.397494 2.724912)
			(size 0.381 0.381)
			(layers "F.Cu" "F.Mask" "F.Paste")
			(net "GND")
		)
		(pad "ER2" smd circle
			(at -8.450072 -3.41884)
			(size 0.3048 0.3048)
			(layers "F.Cu" "F.Mask" "F.Paste")
			(net "GND")
		)
		(pad "ER34" smd circle
			(at -8.450072 3.420364)
			(size 0.3048 0.3048)
			(layers "F.Cu" "F.Mask" "F.Paste")
			(net "GND")
		)
		(pad "ET1" smd oval
			(at -8.750046 -3.938524)
			(size 0.254 0.3302)
			(layers "F.Cu" "F.Mask" "F.Paste")
			(net "GND")
		)
		(pad "ET35" smd oval
			(at -8.750046 3.940048)
			(size 0.254 0.3302)
			(layers "F.Cu" "F.Mask" "F.Paste")
			(net "GND")
		)
		(pad "EU7" smd circle
			(at -8.79729 -2.12471)
			(size 0.381 0.381)
			(layers "F.Cu" "F.Mask" "F.Paste")
			(net "P5E_CPU0_P2_TX_BUF_DP<0>")
		)
		(pad "EU26" smd circle
			(at -8.79729 1.339342)
			(size 0.381 0.381)
			(layers "F.Cu" "F.Mask" "F.Paste")
			(net "P5E_CPU0_P2_RX_DP<0>")
		)
		(pad "EV2" smd circle
			(at -9.05002 -3.41884)
			(size 0.3048 0.3048)
			(layers "F.Cu" "F.Mask" "F.Paste")
			(net "P5E_CPU0_P2_RX_BUF_DN<0>")
		)
		(pad "EV34" smd circle
			(at -9.05002 3.420364)
			(size 0.3048 0.3048)
			(layers "F.Cu" "F.Mask" "F.Paste")
			(net "P5E_CPU0_P2_TX_C_DN<0>")
		)
		(pad "EW10" smd circle
			(at -9.19734 -1.431798)
			(size 0.381 0.381)
			(layers "F.Cu" "F.Mask" "F.Paste")
			(net "P5E_CPU0_P2_TX_BUF_DN<0>")
		)
		(pad "EW29" smd circle
			(at -9.19734 2.032254)
			(size 0.381 0.381)
			(layers "F.Cu" "F.Mask" "F.Paste")
			(net "P5E_CPU0_P2_RX_DN<0>")
		)
		(pad "EY1" smd oval
			(at -9.349994 -3.938524)
			(size 0.254 0.3302)
			(layers "F.Cu" "F.Mask" "F.Paste")
			(net "P5E_CPU0_P2_RX_BUF_DP<0>")
		)
		(pad "EY35" smd oval
			(at -9.349994 3.940048)
			(size 0.254 0.3302)
			(layers "F.Cu" "F.Mask" "F.Paste")
			(net "P5E_CPU0_P2_TX_C_DP<0>")
		)
		(pad "F2" smd circle
			(at 10.150094 -3.41884)
			(size 0.3048 0.3048)
			(layers "F.Cu" "F.Mask" "F.Paste")
			(net "RST_RT_CPU0_P2_PERST_N")
		)
		(pad "F34" smd circle
			(at 10.150094 3.420364)
			(size 0.3048 0.3048)
			(layers "F.Cu" "F.Mask" "F.Paste")
			(net "RT_CPU0_P2_ADDR1")
		)
		(pad "FA15" smd circle
			(at -9.59739 -0.738886)
			(size 0.381 0.381)
			(layers "F.Cu" "F.Mask" "F.Paste")
			(net "GND")
		)
		(pad "FA32" smd circle
			(at -9.59739 2.724912)
			(size 0.381 0.381)
			(layers "F.Cu" "F.Mask" "F.Paste")
			(net "GND")
		)
		(pad "FB2" smd circle
			(at -9.649968 -3.41884)
			(size 0.3048 0.3048)
			(layers "F.Cu" "F.Mask" "F.Paste")
			(net "GND")
		)
		(pad "FB34" smd circle
			(at -9.649968 3.420364)
			(size 0.3048 0.3048)
			(layers "F.Cu" "F.Mask" "F.Paste")
			(net "GND")
		)
		(pad "FC3" smd circle
			(at -9.846818 -2.888488)
			(size 0.3048 0.3048)
			(layers "F.Cu" "F.Mask" "F.Paste")
			(net "GND")
		)
		(pad "FC6" smd circle
			(at -9.846818 -2.288286)
			(size 0.3048 0.3048)
			(layers "F.Cu" "F.Mask" "F.Paste")
			(net "GND")
		)
		(pad "FC9" smd circle
			(at -9.846818 -1.688338)
			(size 0.3048 0.3048)
			(layers "F.Cu" "F.Mask" "F.Paste")
			(net "GND")
		)
		(pad "FC19" smd circle
			(at -9.846818 0.111506)
			(size 0.3048 0.3048)
			(layers "F.Cu" "F.Mask" "F.Paste")
			(net "GND")
		)
		(pad "FC23" smd circle
			(at -9.846818 0.711708)
			(size 0.3048 0.3048)
			(layers "F.Cu" "F.Mask" "F.Paste")
			(net "GND")
		)
		(pad "FC25" smd circle
			(at -9.846818 1.311656)
			(size 0.3048 0.3048)
			(layers "F.Cu" "F.Mask" "F.Paste")
			(net "GND")
		)
		(pad "FC28" smd circle
			(at -9.846818 1.911604)
			(size 0.3048 0.3048)
			(layers "F.Cu" "F.Mask" "F.Paste")
			(net "GND")
		)
		(pad "FD1" smd oval
			(at -9.949942 -3.938524)
			(size 0.254 0.3302)
			(layers "F.Cu" "F.Mask" "F.Paste")
			(net "GND")
		)
		(pad "FD35" smd oval
			(at -9.949942 3.940048)
			(size 0.254 0.3302)
			(layers "F.Cu" "F.Mask" "F.Paste")
			(net "GND")
		)
		(pad "FE2" smd circle
			(at -10.249916 -3.41884)
			(size 0.3048 0.3048)
			(layers "F.Cu" "F.Mask" "F.Paste")
			(net "NCF_CPU0_P2_GND")
		)
		(pad "FE34" smd circle
			(at -10.249916 3.420364)
			(size 0.3048 0.3048)
			(layers "F.Cu" "F.Mask" "F.Paste")
			(net "NCF_CPU0_P2_GND")
		)
		(pad "FF5" smd circle
			(at -10.366248 -2.588514)
			(size 0.3048 0.3048)
			(layers "F.Cu" "F.Mask" "F.Paste")
			(net "SMB_RT_CPU0_P2_ROM_MUX_1D_R_SCL")
		)
		(pad "FF8" smd circle
			(at -10.366248 -1.988312)
			(size 0.3048 0.3048)
			(layers "F.Cu" "F.Mask" "F.Paste")
			(net "JTAG_TEST_MODE_RT_CPU0_P2")
		)
		(pad "FF11" smd circle
			(at -10.366248 -1.388364)
			(size 0.3048 0.3048)
			(layers "F.Cu" "F.Mask" "F.Paste")
			(net "RST_RT_CPU0_P2_RESET_N")
		)
		(pad "FF14" smd circle
			(at -10.366248 -0.788416)
			(size 0.3048 0.3048)
			(layers "F.Cu" "F.Mask" "F.Paste")
			(net "GND")
		)
		(pad "FF18" smd circle
			(at -10.366248 -0.188468)
			(size 0.3048 0.3048)
			(layers "F.Cu" "F.Mask" "F.Paste")
			(net "CLK_100M_RETIMER_CPU0_P2_DN")
		)
		(pad "FF21" smd circle
			(at -10.366248 0.41148)
			(size 0.3048 0.3048)
			(layers "F.Cu" "F.Mask" "F.Paste")
			(net "GND")
		)
		(pad "FF24" smd circle
			(at -10.366248 1.011682)
			(size 0.3048 0.3048)
			(layers "F.Cu" "F.Mask" "F.Paste")
			(net "TEST0_RT_CPU0_P2")
		)
		(pad "FF27" smd circle
			(at -10.366248 1.61163)
			(size 0.3048 0.3048)
			(layers "F.Cu" "F.Mask" "F.Paste")
			(net "TEST1_RT_CPU0_P2")
		)
		(pad "FF30" smd circle
			(at -10.366248 2.211578)
			(size 0.3048 0.3048)
			(layers "F.Cu" "F.Mask" "F.Paste")
			(net "TEST2_RT_CPU0_P2")
		)
		(pad "FF33" smd circle
			(at -10.366248 2.811526)
			(size 0.3048 0.3048)
			(layers "F.Cu" "F.Mask" "F.Paste")
			(net "RT_CPU0_P2_SCAN_MODE")
		)
		(pad "FG1" smd oval
			(at -10.54989 -3.938524)
			(size 0.254 0.3302)
			(layers "F.Cu" "F.Mask" "F.Paste")
			(net "NCF_CPU0_P2_GND")
		)
		(pad "FG35" smd oval
			(at -10.54989 3.940048)
			(size 0.254 0.3302)
			(layers "F.Cu" "F.Mask" "F.Paste")
			(net "NCF_CPU0_P2_GND")
		)
		(pad "FH2" smd circle
			(at -10.850118 -3.41884)
			(size 0.3048 0.3048)
			(layers "F.Cu" "F.Mask" "F.Paste")
			(net "NCF_CPU0_P2_GND")
		)
		(pad "FH34" smd circle
			(at -10.850118 3.420364)
			(size 0.3048 0.3048)
			(layers "F.Cu" "F.Mask" "F.Paste")
			(net "NCF_CPU0_P2_GND")
		)
		(pad "FJ3" smd oval
			(at -10.885932 -2.888488 90)
			(size 0.254 0.3302)
			(layers "F.Cu" "F.Mask" "F.Paste")
			(net "SMB_RT_CPU0_P2_ROM_MUX_1D_R_SDA")
		)
		(pad "FJ6" smd oval
			(at -10.885932 -2.288286 90)
			(size 0.254 0.3302)
			(layers "F.Cu" "F.Mask" "F.Paste")
			(net "Net_2208")
		)
		(pad "FJ9" smd oval
			(at -10.885932 -1.688338 90)
			(size 0.254 0.3302)
			(layers "F.Cu" "F.Mask" "F.Paste")
			(net "MODE_RT_CPU0_P2")
		)
		(pad "FJ12" smd oval
			(at -10.885932 -1.08839 90)
			(size 0.254 0.3302)
			(layers "F.Cu" "F.Mask" "F.Paste")
			(net "GND")
		)
		(pad "FJ16" smd oval
			(at -10.885932 -0.488442 90)
			(size 0.254 0.3302)
			(layers "F.Cu" "F.Mask" "F.Paste")
			(net "CLK_100M_RETIMER_CPU0_P2_DP")
		)
		(pad "FJ19" smd oval
			(at -10.885932 0.111506 90)
			(size 0.254 0.3302)
			(layers "F.Cu" "F.Mask" "F.Paste")
			(net "GND")
		)
		(pad "FJ23" smd oval
			(at -10.885932 0.711708 90)
			(size 0.254 0.3302)
			(layers "F.Cu" "F.Mask" "F.Paste")
			(net "Net_2209")
		)
		(pad "FJ25" smd oval
			(at -10.885932 1.311656 90)
			(size 0.254 0.3302)
			(layers "F.Cu" "F.Mask" "F.Paste")
			(net "GPIO2_RT_CPU0_P2")
		)
		(pad "FJ28" smd oval
			(at -10.885932 1.911604 90)
			(size 0.254 0.3302)
			(layers "F.Cu" "F.Mask" "F.Paste")
			(net "GPIO3_RT_CPU0_P2")
		)
		(pad "FJ31" smd oval
			(at -10.885932 2.511552 90)
			(size 0.254 0.3302)
			(layers "F.Cu" "F.Mask" "F.Paste")
			(net "Net_52")
		)
		(pad "G1" smd oval
			(at 9.85012 -3.938524)
			(size 0.254 0.3302)
			(layers "F.Cu" "F.Mask" "F.Paste")
			(net "RT_CPU0_P2_VQPS")
		)
		(pad "G35" smd oval
			(at 9.85012 3.940048)
			(size 0.254 0.3302)
			(layers "F.Cu" "F.Mask" "F.Paste")
			(net "CLKREQ_RT_CPU0_P2_N")
		)
		(pad "H12" smd circle
			(at 9.846818 -1.08839)
			(size 0.3048 0.3048)
			(layers "F.Cu" "F.Mask" "F.Paste")
			(net "GND")
		)
		(pad "H16" smd circle
			(at 9.846818 -0.488442)
			(size 0.3048 0.3048)
			(layers "F.Cu" "F.Mask" "F.Paste")
			(net "GND")
		)
		(pad "H19" smd circle
			(at 9.846818 0.111506)
			(size 0.3048 0.3048)
			(layers "F.Cu" "F.Mask" "F.Paste")
			(net "GND")
		)
		(pad "H31" smd circle
			(at 9.846818 2.511552)
			(size 0.3048 0.3048)
			(layers "F.Cu" "F.Mask" "F.Paste")
			(net "GND")
		)
		(pad "J4" smd circle
			(at 9.602724 -2.817368)
			(size 0.381 0.381)
			(layers "F.Cu" "F.Mask" "F.Paste")
			(net "GND")
		)
		(pad "J22" smd circle
			(at 9.602724 0.703834)
			(size 0.3048 0.3048)
			(layers "F.Cu" "F.Mask" "F.Paste")
			(net "GND")
		)
		(pad "K2" smd circle
			(at 9.549892 -3.41884)
			(size 0.3048 0.3048)
			(layers "F.Cu" "F.Mask" "F.Paste")
			(net "GND")
		)
		(pad "K34" smd circle
			(at 9.549892 3.420364)
			(size 0.3048 0.3048)
			(layers "F.Cu" "F.Mask" "F.Paste")
			(net "GND")
		)
		(pad "L1" smd oval
			(at 9.249918 -3.938524)
			(size 0.254 0.3302)
			(layers "F.Cu" "F.Mask" "F.Paste")
			(net "GND")
		)
		(pad "L35" smd oval
			(at 9.249918 3.940048)
			(size 0.254 0.3302)
			(layers "F.Cu" "F.Mask" "F.Paste")
			(net "GND")
		)
		(pad "M7" smd circle
			(at 9.202674 -2.12471)
			(size 0.381 0.381)
			(layers "F.Cu" "F.Mask" "F.Paste")
			(net "P5E_CPU0_P2_TX_BUF_DP<15>")
		)
		(pad "M26" smd circle
			(at 9.202674 1.339342)
			(size 0.381 0.381)
			(layers "F.Cu" "F.Mask" "F.Paste")
			(net "P5E_CPU0_P2_RX_DP<15>")
		)
		(pad "N2" smd circle
			(at 8.949944 -3.41884)
			(size 0.3048 0.3048)
			(layers "F.Cu" "F.Mask" "F.Paste")
			(net "P5E_CPU0_P2_RX_BUF_DN<15>")
		)
		(pad "N34" smd circle
			(at 8.949944 3.420364)
			(size 0.3048 0.3048)
			(layers "F.Cu" "F.Mask" "F.Paste")
			(net "P5E_CPU0_P2_TX_C_DN<15>")
		)
		(pad "P10" smd circle
			(at 8.802624 -1.431798)
			(size 0.381 0.381)
			(layers "F.Cu" "F.Mask" "F.Paste")
			(net "P5E_CPU0_P2_TX_BUF_DN<15>")
		)
		(pad "P29" smd circle
			(at 8.802624 2.032254)
			(size 0.381 0.381)
			(layers "F.Cu" "F.Mask" "F.Paste")
			(net "P5E_CPU0_P2_RX_DN<15>")
		)
		(pad "R1" smd oval
			(at 8.64997 -3.938524)
			(size 0.254 0.3302)
			(layers "F.Cu" "F.Mask" "F.Paste")
			(net "P5E_CPU0_P2_RX_BUF_DP<15>")
		)
		(pad "R35" smd oval
			(at 8.64997 3.940048)
			(size 0.254 0.3302)
			(layers "F.Cu" "F.Mask" "F.Paste")
			(net "P5E_CPU0_P2_TX_C_DP<15>")
		)
		(pad "T4" smd circle
			(at 8.402574 -2.817368)
			(size 0.381 0.381)
			(layers "F.Cu" "F.Mask" "F.Paste")
			(net "GND")
		)
		(pad "T13" smd circle
			(at 8.402574 -0.79629)
			(size 0.3048 0.3048)
			(layers "F.Cu" "F.Mask" "F.Paste")
			(net "GND")
		)
		(pad "T17" smd circle
			(at 8.402574 -0.296164)
			(size 0.3048 0.3048)
			(layers "F.Cu" "F.Mask" "F.Paste")
			(net "P0V9_CPU0_RT2_2A")
		)
		(pad "T20" smd circle
			(at 8.402574 0.203708)
			(size 0.3048 0.3048)
			(layers "F.Cu" "F.Mask" "F.Paste")
			(net "P0V9_CPU0_RT2_2A")
		)
		(pad "T22" smd circle
			(at 8.402574 0.703834)
			(size 0.3048 0.3048)
			(layers "F.Cu" "F.Mask" "F.Paste")
			(net "GND")
		)
		(pad "T32" smd circle
			(at 8.402574 2.724912)
			(size 0.381 0.381)
			(layers "F.Cu" "F.Mask" "F.Paste")
			(net "GND")
		)
		(pad "U2" smd circle
			(at 8.349996 -3.41884)
			(size 0.3048 0.3048)
			(layers "F.Cu" "F.Mask" "F.Paste")
			(net "GND")
		)
		(pad "U34" smd circle
			(at 8.349996 3.420364)
			(size 0.3048 0.3048)
			(layers "F.Cu" "F.Mask" "F.Paste")
			(net "GND")
		)
		(pad "V1" smd oval
			(at 8.050022 -3.938524)
			(size 0.254 0.3302)
			(layers "F.Cu" "F.Mask" "F.Paste")
			(net "GND")
		)
		(pad "V35" smd oval
			(at 8.050022 3.940048)
			(size 0.254 0.3302)
			(layers "F.Cu" "F.Mask" "F.Paste")
			(net "GND")
		)
		(pad "W7" smd circle
			(at 8.002524 -2.12471)
			(size 0.381 0.381)
			(layers "F.Cu" "F.Mask" "F.Paste")
			(net "P5E_CPU0_P2_TX_BUF_DP<14>")
		)
		(pad "W26" smd circle
			(at 8.002524 1.339342)
			(size 0.381 0.381)
			(layers "F.Cu" "F.Mask" "F.Paste")
			(net "P5E_CPU0_P2_RX_DP<14>")
		)
		(pad "Y2" smd circle
			(at 7.750048 -3.41884)
			(size 0.3048 0.3048)
			(layers "F.Cu" "F.Mask" "F.Paste")
			(net "P5E_CPU0_P2_RX_BUF_DN<14>")
		)
		(pad "Y34" smd circle
			(at 7.750048 3.420364)
			(size 0.3048 0.3048)
			(layers "F.Cu" "F.Mask" "F.Paste")
			(net "P5E_CPU0_P2_TX_C_DN<14>")
		)
	)
	(footprint ""
		(layer "F.Cu")
		(at 445.003682 -65.947798 -90)
		(property "Reference" "C1332"
			(at 0 0 270)
			(layer "F.SilkS")
			(hide yes)
			(effects
				(font
					(size 1.27 1.27)
				)
			)
		)
		(property "Value" ""
			(at 0 0 270)
			(layer "F.Fab")
			(effects
				(font
					(size 1.27 1.27)
				)
			)
		)
		(duplicate_pad_numbers_are_jumpers no)
		(fp_line
			(start -0.7874 0.4064)
			(end -0.7874 -0.4064)
			(stroke
				(width 0.1524)
				(type default)
			)
			(layer "F.SilkS")
		)
		(fp_line
			(start 0.7874 0.4064)
			(end -0.7874 0.4064)
			(stroke
				(width 0.1524)
				(type default)
			)
			(layer "F.SilkS")
		)
		(fp_line
			(start -0.7874 -0.4064)
			(end 0.7874 -0.4064)
			(stroke
				(width 0.1524)
				(type default)
			)
			(layer "F.SilkS")
		)
		(fp_line
			(start 0.7874 -0.4064)
			(end 0.7874 0.4064)
			(stroke
				(width 0.1524)
				(type default)
			)
			(layer "F.SilkS")
		)
		(fp_line
			(start -0.67945 0.3048)
			(end -0.67945 -0.305054)
			(stroke
				(width 0.1)
				(type default)
			)
			(layer "F.Fab")
		)
		(fp_line
			(start -0.12065 0.3048)
			(end -0.67945 0.3048)
			(stroke
				(width 0.1)
				(type default)
			)
			(layer "F.Fab")
		)
		(fp_line
			(start 0.120396 0.3048)
			(end 0.120396 0.2794)
			(stroke
				(width 0.1)
				(type default)
			)
			(layer "F.Fab")
		)
		(fp_line
			(start 0.67945 0.3048)
			(end 0.120396 0.3048)
			(stroke
				(width 0.1)
				(type default)
			)
			(layer "F.Fab")
		)
		(fp_line
			(start -0.12065 0.2794)
			(end -0.12065 0.3048)
			(stroke
				(width 0.1)
				(type default)
			)
			(layer "F.Fab")
		)
		(fp_line
			(start 0.120396 0.2794)
			(end -0.12065 0.2794)
			(stroke
				(width 0.1)
				(type default)
			)
			(layer "F.Fab")
		)
		(fp_line
			(start -0.12065 -0.2794)
			(end 0.12065 -0.2794)
			(stroke
				(width 0.1)
				(type default)
			)
			(layer "F.Fab")
		)
		(fp_line
			(start 0.12065 -0.2794)
			(end 0.12065 -0.3048)
			(stroke
				(width 0.1)
				(type default)
			)
			(layer "F.Fab")
		)
		(fp_line
			(start 0.12065 -0.3048)
			(end 0.67945 -0.3048)
			(stroke
				(width 0.1)
				(type default)
			)
			(layer "F.Fab")
		)
		(fp_line
			(start 0.67945 -0.3048)
			(end 0.67945 0.3048)
			(stroke
				(width 0.1)
				(type default)
			)
			(layer "F.Fab")
		)
		(fp_line
			(start -0.67945 -0.305054)
			(end -0.12065 -0.305054)
			(stroke
				(width 0.1)
				(type default)
			)
			(layer "F.Fab")
		)
		(fp_line
			(start -0.12065 -0.305054)
			(end -0.12065 -0.2794)
			(stroke
				(width 0.1)
				(type default)
			)
			(layer "F.Fab")
		)
		(pad "1" smd circle
			(at -0.40005 0 270)
			(size 0 0)
			(layers "F.Cu" "F.Mask" "F.Paste")
			(net "P3V3_AUX")
		)
		(pad "2" smd circle
			(at 0.40005 0 270)
			(size 0 0)
			(layers "F.Cu" "F.Mask" "F.Paste")
			(net "GND")
		)
	)
	(footprint ""
		(layer "F.Cu")
		(at 154.633676 -50.739294 90)
		(property "Reference" "R3594"
			(at 0 0 90)
			(layer "F.SilkS")
			(hide yes)
			(effects
				(font
					(size 1.27 1.27)
				)
			)
		)
		(property "Value" ""
			(at 0 0 90)
			(layer "F.Fab")
			(effects
				(font
					(size 1.27 1.27)
				)
			)
		)
		(duplicate_pad_numbers_are_jumpers no)
		(fp_line
			(start 0.7874 -0.4064)
			(end 0.7874 0.4064)
			(stroke
				(width 0.1524)
				(type default)
			)
			(layer "F.SilkS")
		)
		(fp_line
			(start -0.7874 -0.4064)
			(end 0.7874 -0.4064)
			(stroke
				(width 0.1524)
				(type default)
			)
			(layer "F.SilkS")
		)
		(fp_line
			(start 0.7874 0.4064)
			(end -0.7874 0.4064)
			(stroke
				(width 0.1524)
				(type default)
			)
			(layer "F.SilkS")
		)
		(fp_line
			(start -0.7874 0.4064)
			(end -0.7874 -0.4064)
			(stroke
				(width 0.1524)
				(type default)
			)
			(layer "F.SilkS")
		)
		(fp_line
			(start -0.12065 -0.305054)
			(end -0.12065 -0.2794)
			(stroke
				(width 0.1)
				(type default)
			)
			(layer "F.Fab")
		)
		(fp_line
			(start -0.67945 -0.305054)
			(end -0.12065 -0.305054)
			(stroke
				(width 0.1)
				(type default)
			)
			(layer "F.Fab")
		)
		(fp_line
			(start 0.67945 -0.3048)
			(end 0.67945 0.3048)
			(stroke
				(width 0.1)
				(type default)
			)
			(layer "F.Fab")
		)
		(fp_line
			(start 0.12065 -0.3048)
			(end 0.67945 -0.3048)
			(stroke
				(width 0.1)
				(type default)
			)
			(layer "F.Fab")
		)
		(fp_line
			(start 0.12065 -0.2794)
			(end 0.12065 -0.3048)
			(stroke
				(width 0.1)
				(type default)
			)
			(layer "F.Fab")
		)
		(fp_line
			(start -0.12065 -0.2794)
			(end 0.12065 -0.2794)
			(stroke
				(width 0.1)
				(type default)
			)
			(layer "F.Fab")
		)
		(fp_line
			(start 0.120396 0.2794)
			(end -0.12065 0.2794)
			(stroke
				(width 0.1)
				(type default)
			)
			(layer "F.Fab")
		)
		(fp_line
			(start -0.12065 0.2794)
			(end -0.12065 0.3048)
			(stroke
				(width 0.1)
				(type default)
			)
			(layer "F.Fab")
		)
		(fp_line
			(start 0.67945 0.3048)
			(end 0.120396 0.3048)
			(stroke
				(width 0.1)
				(type default)
			)
			(layer "F.Fab")
		)
		(fp_line
			(start 0.120396 0.3048)
			(end 0.120396 0.2794)
			(stroke
				(width 0.1)
				(type default)
			)
			(layer "F.Fab")
		)
		(fp_line
			(start -0.12065 0.3048)
			(end -0.67945 0.3048)
			(stroke
				(width 0.1)
				(type default)
			)
			(layer "F.Fab")
		)
		(fp_line
			(start -0.67945 0.3048)
			(end -0.67945 -0.305054)
			(stroke
				(width 0.1)
				(type default)
			)
			(layer "F.Fab")
		)
		(pad "1" smd circle
			(at -0.40005 0 90)
			(size 0 0)
			(layers "F.Cu" "F.Mask" "F.Paste")
			(net "SMB_INA230_3V3AUX_SCL")
		)
		(pad "2" smd circle
			(at 0.40005 0 90)
			(size 0 0)
			(layers "F.Cu" "F.Mask" "F.Paste")
			(net "SMB_INA230_4_3V3AUX_SCL_R")
		)
	)
	(footprint ""
		(layer "F.Cu")
		(at 304.094896 -383.88163 -90)
		(property "Reference" "C925"
			(at 0 0 270)
			(layer "F.SilkS")
			(hide yes)
			(effects
				(font
					(size 1.27 1.27)
				)
			)
		)
		(property "Value" ""
			(at 0 0 270)
			(layer "F.Fab")
			(effects
				(font
					(size 1.27 1.27)
				)
			)
		)
		(duplicate_pad_numbers_are_jumpers no)
		(fp_line
			(start -0.299974 0.150114)
			(end -0.299974 -0.150114)
			(stroke
				(width 0.1)
				(type default)
			)
			(layer "F.Fab")
		)
		(fp_line
			(start 0.299974 0.150114)
			(end -0.299974 0.150114)
			(stroke
				(width 0.1)
				(type default)
			)
			(layer "F.Fab")
		)
		(fp_line
			(start -0.299974 -0.150114)
			(end 0.299974 -0.150114)
			(stroke
				(width 0.1)
				(type default)
			)
			(layer "F.Fab")
		)
		(fp_line
			(start 0.299974 -0.150114)
			(end 0.299974 0.150114)
			(stroke
				(width 0.1)
				(type default)
			)
			(layer "F.Fab")
		)
		(pad "1" smd rect
			(at -0.2667 0 270)
			(size 0.3048 0.381)
			(layers "F.Cu" "F.Mask" "F.Paste")
			(net "P5E_CPU0_P0_TX_C_DP<4>")
		)
		(pad "2" smd rect
			(at 0.2667 0 270)
			(size 0.3048 0.381)
			(layers "F.Cu" "F.Mask" "F.Paste")
			(net "P5E_CPU0_P0_TX_DP<4>")
		)
	)
	(footprint ""
		(layer "F.Cu")
		(at 160.274762 -111.221774 180)
		(property "Reference" "R6116"
			(at 0 0 180)
			(layer "F.SilkS")
			(hide yes)
			(effects
				(font
					(size 1.27 1.27)
				)
			)
		)
		(property "Value" ""
			(at 0 0 180)
			(layer "F.Fab")
			(effects
				(font
					(size 1.27 1.27)
				)
			)
		)
		(duplicate_pad_numbers_are_jumpers no)
		(fp_line
			(start 0.7874 0.4064)
			(end -0.7874 0.4064)
			(stroke
				(width 0.1524)
				(type default)
			)
			(layer "F.SilkS")
		)
		(fp_line
			(start 0.7874 -0.4064)
			(end 0.7874 0.4064)
			(stroke
				(width 0.1524)
				(type default)
			)
			(layer "F.SilkS")
		)
		(fp_line
			(start -0.7874 0.4064)
			(end -0.7874 -0.4064)
			(stroke
				(width 0.1524)
				(type default)
			)
			(layer "F.SilkS")
		)
		(fp_line
			(start -0.7874 -0.4064)
			(end 0.7874 -0.4064)
			(stroke
				(width 0.1524)
				(type default)
			)
			(layer "F.SilkS")
		)
		(fp_line
			(start 0.67945 0.3048)
			(end 0.120396 0.3048)
			(stroke
				(width 0.1)
				(type default)
			)
			(layer "F.Fab")
		)
		(fp_line
			(start 0.67945 -0.3048)
			(end 0.67945 0.3048)
			(stroke
				(width 0.1)
				(type default)
			)
			(layer "F.Fab")
		)
		(fp_line
			(start 0.12065 -0.2794)
			(end 0.12065 -0.3048)
			(stroke
				(width 0.1)
				(type default)
			)
			(layer "F.Fab")
		)
		(fp_line
			(start 0.12065 -0.3048)
			(end 0.67945 -0.3048)
			(stroke
				(width 0.1)
				(type default)
			)
			(layer "F.Fab")
		)
		(fp_line
			(start 0.120396 0.3048)
			(end 0.120396 0.2794)
			(stroke
				(width 0.1)
				(type default)
			)
			(layer "F.Fab")
		)
		(fp_line
			(start 0.120396 0.2794)
			(end -0.12065 0.2794)
			(stroke
				(width 0.1)
				(type default)
			)
			(layer "F.Fab")
		)
		(fp_line
			(start -0.12065 0.3048)
			(end -0.67945 0.3048)
			(stroke
				(width 0.1)
				(type default)
			)
			(layer "F.Fab")
		)
		(fp_line
			(start -0.12065 0.2794)
			(end -0.12065 0.3048)
			(stroke
				(width 0.1)
				(type default)
			)
			(layer "F.Fab")
		)
		(fp_line
			(start -0.12065 -0.2794)
			(end 0.12065 -0.2794)
			(stroke
				(width 0.1)
				(type default)
			)
			(layer "F.Fab")
		)
		(fp_line
			(start -0.12065 -0.305054)
			(end -0.12065 -0.2794)
			(stroke
				(width 0.1)
				(type default)
			)
			(layer "F.Fab")
		)
		(fp_line
			(start -0.67945 0.3048)
			(end -0.67945 -0.305054)
			(stroke
				(width 0.1)
				(type default)
			)
			(layer "F.Fab")
		)
		(fp_line
			(start -0.67945 -0.305054)
			(end -0.12065 -0.305054)
			(stroke
				(width 0.1)
				(type default)
			)
			(layer "F.Fab")
		)
		(pad "1" smd circle
			(at -0.40005 0 180)
			(size 0 0)
			(layers "F.Cu" "F.Mask" "F.Paste")
			(net "E1S_0_PERST1_CLKREQ_R_N")
		)
		(pad "2" smd circle
			(at 0.40005 0 180)
			(size 0 0)
			(layers "F.Cu" "F.Mask" "F.Paste")
			(net "E1S_0_PRSNT_N")
		)
	)
	(footprint ""
		(layer "F.Cu")
		(at 146.939 -120.777)
		(property "Reference" "R8086"
			(at 0 0 0)
			(layer "F.SilkS")
			(hide yes)
			(effects
				(font
					(size 1.27 1.27)
				)
			)
		)
		(property "Value" ""
			(at 0 0 0)
			(layer "F.Fab")
			(effects
				(font
					(size 1.27 1.27)
				)
			)
		)
		(duplicate_pad_numbers_are_jumpers no)
		(fp_line
			(start -0.7874 -0.4064)
			(end 0.7874 -0.4064)
			(stroke
				(width 0.1524)
				(type default)
			)
			(layer "F.SilkS")
		)
		(fp_line
			(start -0.7874 0.4064)
			(end -0.7874 -0.4064)
			(stroke
				(width 0.1524)
				(type default)
			)
			(layer "F.SilkS")
		)
		(fp_line
			(start 0.7874 -0.4064)
			(end 0.7874 0.4064)
			(stroke
				(width 0.1524)
				(type default)
			)
			(layer "F.SilkS")
		)
		(fp_line
			(start 0.7874 0.4064)
			(end -0.7874 0.4064)
			(stroke
				(width 0.1524)
				(type default)
			)
			(layer "F.SilkS")
		)
		(fp_line
			(start -0.67945 -0.305054)
			(end -0.12065 -0.305054)
			(stroke
				(width 0.1)
				(type default)
			)
			(layer "F.Fab")
		)
		(fp_line
			(start -0.67945 0.3048)
			(end -0.67945 -0.305054)
			(stroke
				(width 0.1)
				(type default)
			)
			(layer "F.Fab")
		)
		(fp_line
			(start -0.12065 -0.305054)
			(end -0.12065 -0.2794)
			(stroke
				(width 0.1)
				(type default)
			)
			(layer "F.Fab")
		)
		(fp_line
			(start -0.12065 -0.2794)
			(end 0.12065 -0.2794)
			(stroke
				(width 0.1)
				(type default)
			)
			(layer "F.Fab")
		)
		(fp_line
			(start -0.12065 0.2794)
			(end -0.12065 0.3048)
			(stroke
				(width 0.1)
				(type default)
			)
			(layer "F.Fab")
		)
		(fp_line
			(start -0.12065 0.3048)
			(end -0.67945 0.3048)
			(stroke
				(width 0.1)
				(type default)
			)
			(layer "F.Fab")
		)
		(fp_line
			(start 0.120396 0.2794)
			(end -0.12065 0.2794)
			(stroke
				(width 0.1)
				(type default)
			)
			(layer "F.Fab")
		)
		(fp_line
			(start 0.120396 0.3048)
			(end 0.120396 0.2794)
			(stroke
				(width 0.1)
				(type default)
			)
			(layer "F.Fab")
		)
		(fp_line
			(start 0.12065 -0.3048)
			(end 0.67945 -0.3048)
			(stroke
				(width 0.1)
				(type default)
			)
			(layer "F.Fab")
		)
		(fp_line
			(start 0.12065 -0.2794)
			(end 0.12065 -0.3048)
			(stroke
				(width 0.1)
				(type default)
			)
			(layer "F.Fab")
		)
		(fp_line
			(start 0.67945 -0.3048)
			(end 0.67945 0.3048)
			(stroke
				(width 0.1)
				(type default)
			)
			(layer "F.Fab")
		)
		(fp_line
			(start 0.67945 0.3048)
			(end 0.120396 0.3048)
			(stroke
				(width 0.1)
				(type default)
			)
			(layer "F.Fab")
		)
		(pad "1" smd circle
			(at -0.40005 0)
			(size 0 0)
			(layers "F.Cu" "F.Mask" "F.Paste")
			(net "PWRGD_CHAF_CPU1")
		)
		(pad "2" smd circle
			(at 0.40005 0)
			(size 0 0)
			(layers "F.Cu" "F.Mask" "F.Paste")
			(net "PWRGD_CHAF_CPU1_R1")
		)
	)
	(footprint ""
		(layer "F.Cu")
		(at 103.505 -418.973 180)
		(property "Reference" "R3492"
			(at 0 0 180)
			(layer "F.SilkS")
			(hide yes)
			(effects
				(font
					(size 1.27 1.27)
				)
			)
		)
		(property "Value" ""
			(at 0 0 180)
			(layer "F.Fab")
			(effects
				(font
					(size 1.27 1.27)
				)
			)
		)
		(duplicate_pad_numbers_are_jumpers no)
		(fp_line
			(start 0.7874 0.4064)
			(end -0.7874 0.4064)
			(stroke
				(width 0.1524)
				(type default)
			)
			(layer "F.SilkS")
		)
		(fp_line
			(start 0.7874 -0.4064)
			(end 0.7874 0.4064)
			(stroke
				(width 0.1524)
				(type default)
			)
			(layer "F.SilkS")
		)
		(fp_line
			(start -0.7874 0.4064)
			(end -0.7874 -0.4064)
			(stroke
				(width 0.1524)
				(type default)
			)
			(layer "F.SilkS")
		)
		(fp_line
			(start -0.7874 -0.4064)
			(end 0.7874 -0.4064)
			(stroke
				(width 0.1524)
				(type default)
			)
			(layer "F.SilkS")
		)
		(fp_line
			(start 0.67945 0.3048)
			(end 0.120396 0.3048)
			(stroke
				(width 0.1)
				(type default)
			)
			(layer "F.Fab")
		)
		(fp_line
			(start 0.67945 -0.3048)
			(end 0.67945 0.3048)
			(stroke
				(width 0.1)
				(type default)
			)
			(layer "F.Fab")
		)
		(fp_line
			(start 0.12065 -0.2794)
			(end 0.12065 -0.3048)
			(stroke
				(width 0.1)
				(type default)
			)
			(layer "F.Fab")
		)
		(fp_line
			(start 0.12065 -0.3048)
			(end 0.67945 -0.3048)
			(stroke
				(width 0.1)
				(type default)
			)
			(layer "F.Fab")
		)
		(fp_line
			(start 0.120396 0.3048)
			(end 0.120396 0.2794)
			(stroke
				(width 0.1)
				(type default)
			)
			(layer "F.Fab")
		)
		(fp_line
			(start 0.120396 0.2794)
			(end -0.12065 0.2794)
			(stroke
				(width 0.1)
				(type default)
			)
			(layer "F.Fab")
		)
		(fp_line
			(start -0.12065 0.3048)
			(end -0.67945 0.3048)
			(stroke
				(width 0.1)
				(type default)
			)
			(layer "F.Fab")
		)
		(fp_line
			(start -0.12065 0.2794)
			(end -0.12065 0.3048)
			(stroke
				(width 0.1)
				(type default)
			)
			(layer "F.Fab")
		)
		(fp_line
			(start -0.12065 -0.2794)
			(end 0.12065 -0.2794)
			(stroke
				(width 0.1)
				(type default)
			)
			(layer "F.Fab")
		)
		(fp_line
			(start -0.12065 -0.305054)
			(end -0.12065 -0.2794)
			(stroke
				(width 0.1)
				(type default)
			)
			(layer "F.Fab")
		)
		(fp_line
			(start -0.67945 0.3048)
			(end -0.67945 -0.305054)
			(stroke
				(width 0.1)
				(type default)
			)
			(layer "F.Fab")
		)
		(fp_line
			(start -0.67945 -0.305054)
			(end -0.12065 -0.305054)
			(stroke
				(width 0.1)
				(type default)
			)
			(layer "F.Fab")
		)
		(pad "1" smd circle
			(at -0.40005 0 180)
			(size 0 0)
			(layers "F.Cu" "F.Mask" "F.Paste")
			(net "P3V3_AUX")
		)
		(pad "2" smd circle
			(at 0.40005 0 180)
			(size 0 0)
			(layers "F.Cu" "F.Mask" "F.Paste")
			(net "GPU_FPGA_EROT_RST_BUF_R_N")
		)
	)
	(footprint ""
		(layer "F.Cu")
		(at 397.125952 -323.45503)
		(property "Reference" "R1504"
			(at 0 0 0)
			(layer "F.SilkS")
			(hide yes)
			(effects
				(font
					(size 1.27 1.27)
				)
			)
		)
		(property "Value" ""
			(at 0 0 0)
			(layer "F.Fab")
			(effects
				(font
					(size 1.27 1.27)
				)
			)
		)
		(duplicate_pad_numbers_are_jumpers no)
		(fp_line
			(start -0.7874 -0.4064)
			(end 0.7874 -0.4064)
			(stroke
				(width 0.1524)
				(type default)
			)
			(layer "F.SilkS")
		)
		(fp_line
			(start -0.7874 0.4064)
			(end -0.7874 -0.4064)
			(stroke
				(width 0.1524)
				(type default)
			)
			(layer "F.SilkS")
		)
		(fp_line
			(start 0.7874 -0.4064)
			(end 0.7874 0.4064)
			(stroke
				(width 0.1524)
				(type default)
			)
			(layer "F.SilkS")
		)
		(fp_line
			(start 0.7874 0.4064)
			(end -0.7874 0.4064)
			(stroke
				(width 0.1524)
				(type default)
			)
			(layer "F.SilkS")
		)
		(fp_line
			(start -0.67945 -0.305054)
			(end -0.12065 -0.305054)
			(stroke
				(width 0.1)
				(type default)
			)
			(layer "F.Fab")
		)
		(fp_line
			(start -0.67945 0.3048)
			(end -0.67945 -0.305054)
			(stroke
				(width 0.1)
				(type default)
			)
			(layer "F.Fab")
		)
		(fp_line
			(start -0.12065 -0.305054)
			(end -0.12065 -0.2794)
			(stroke
				(width 0.1)
				(type default)
			)
			(layer "F.Fab")
		)
		(fp_line
			(start -0.12065 -0.2794)
			(end 0.12065 -0.2794)
			(stroke
				(width 0.1)
				(type default)
			)
			(layer "F.Fab")
		)
		(fp_line
			(start -0.12065 0.2794)
			(end -0.12065 0.3048)
			(stroke
				(width 0.1)
				(type default)
			)
			(layer "F.Fab")
		)
		(fp_line
			(start -0.12065 0.3048)
			(end -0.67945 0.3048)
			(stroke
				(width 0.1)
				(type default)
			)
			(layer "F.Fab")
		)
		(fp_line
			(start 0.120396 0.2794)
			(end -0.12065 0.2794)
			(stroke
				(width 0.1)
				(type default)
			)
			(layer "F.Fab")
		)
		(fp_line
			(start 0.120396 0.3048)
			(end 0.120396 0.2794)
			(stroke
				(width 0.1)
				(type default)
			)
			(layer "F.Fab")
		)
		(fp_line
			(start 0.12065 -0.3048)
			(end 0.67945 -0.3048)
			(stroke
				(width 0.1)
				(type default)
			)
			(layer "F.Fab")
		)
		(fp_line
			(start 0.12065 -0.2794)
			(end 0.12065 -0.3048)
			(stroke
				(width 0.1)
				(type default)
			)
			(layer "F.Fab")
		)
		(fp_line
			(start 0.67945 -0.3048)
			(end 0.67945 0.3048)
			(stroke
				(width 0.1)
				(type default)
			)
			(layer "F.Fab")
		)
		(fp_line
			(start 0.67945 0.3048)
			(end 0.120396 0.3048)
			(stroke
				(width 0.1)
				(type default)
			)
			(layer "F.Fab")
		)
		(pad "1" smd circle
			(at -0.40005 0)
			(size 0 0)
			(layers "F.Cu" "F.Mask" "F.Paste")
			(net "PVDD18_S5_P0")
		)
		(pad "2" smd circle
			(at 0.40005 0)
			(size 0 0)
			(layers "F.Cu" "F.Mask" "F.Paste")
			(net "ESPI_CPU0_D1")
		)
	)
	(footprint ""
		(layer "F.Cu")
		(at 308.696106 -346.71635)
		(property "Reference" "PU14"
			(at -6.182106 -6.82498 0)
			(unlocked yes)
			(layer "F.SilkS")
			(effects
				(font
					(size 0.7874 0.5842)
					(thickness 0.1524)
				)
				(justify left)
			)
		)
		(property "Value" ""
			(at 0 0 0)
			(layer "F.Fab")
			(effects
				(font
					(size 1.27 1.27)
				)
			)
		)
		(duplicate_pad_numbers_are_jumpers no)
		(fp_line
			(start -2.500122 -2.999994)
			(end -2.24409 -2.999994)
			(stroke
				(width 0.1524)
				(type default)
			)
			(layer "F.SilkS")
		)
		(fp_line
			(start -2.500122 -2.529078)
			(end -2.500122 -2.999994)
			(stroke
				(width 0.1524)
				(type default)
			)
			(layer "F.SilkS")
		)
		(fp_line
			(start -2.500122 0.6604)
			(end -2.500122 0.229108)
			(stroke
				(width 0.1524)
				(type default)
			)
			(layer "F.SilkS")
		)
		(fp_line
			(start -2.500122 2.999994)
			(end -2.500122 2.339594)
			(stroke
				(width 0.1524)
				(type default)
			)
			(layer "F.SilkS")
		)
		(fp_line
			(start -2.2987 2.999994)
			(end -2.500122 2.999994)
			(stroke
				(width 0.1524)
				(type default)
			)
			(layer "F.SilkS")
		)
		(fp_line
			(start 2.31394 -2.999994)
			(end 2.500122 -2.999994)
			(stroke
				(width 0.1524)
				(type default)
			)
			(layer "F.SilkS")
		)
		(fp_line
			(start 2.500122 -2.999994)
			(end 2.500122 -2.44348)
			(stroke
				(width 0.1524)
				(type default)
			)
			(layer "F.SilkS")
		)
		(fp_line
			(start 2.500122 2.339594)
			(end 2.500122 2.999994)
			(stroke
				(width 0.1524)
				(type default)
			)
			(layer "F.SilkS")
		)
		(fp_line
			(start 2.500122 2.999994)
			(end 2.2987 2.999994)
			(stroke
				(width 0.1524)
				(type default)
			)
			(layer "F.SilkS")
		)
		(fp_poly
			(pts
				(xy -3.438652 -2.681478) (xy -2.968752 -3.151378) (xy -2.734056 -2.446782)
			)
			(stroke
				(width 0)
				(type default)
			)
			(fill yes)
			(layer "F.SilkS")
		)
		(fp_line
			(start -2.500122 -2.999994)
			(end 2.500122 -2.999994)
			(stroke
				(width 0.1)
				(type default)
			)
			(layer "F.Fab")
		)
		(fp_line
			(start -2.500122 2.999994)
			(end -2.500122 -2.999994)
			(stroke
				(width 0.1)
				(type default)
			)
			(layer "F.Fab")
		)
		(fp_line
			(start 2.500122 -2.999994)
			(end 2.500122 2.999994)
			(stroke
				(width 0.1)
				(type default)
			)
			(layer "F.Fab")
		)
		(fp_line
			(start 2.500122 2.999994)
			(end -2.500122 2.999994)
			(stroke
				(width 0.1)
				(type default)
			)
			(layer "F.Fab")
		)
		(fp_poly
			(pts
				(xy -4.218432 -2.783078) (xy -4.218432 -1.767078) (xy -3.202432 -2.275078)
			)
			(stroke
				(width 0)
				(type default)
			)
			(fill yes)
			(layer "F.Fab")
		)
		(pad "1" smd rect
			(at -2.400046 -2.275078 90)
			(size 0.2286 0.6096)
			(layers "F.Cu" "F.Mask" "F.Paste")
			(net "PVDDCR_CPU1_P0_VOS4")
		)
		(pad "2" smd rect
			(at -2.400046 -1.82499 90)
			(size 0.2286 0.6096)
			(layers "F.Cu" "F.Mask" "F.Paste")
			(net "GND")
		)
		(pad "3" smd rect
			(at -2.400046 -1.374902 90)
			(size 0.2286 0.6096)
			(layers "F.Cu" "F.Mask" "F.Paste")
			(net "PVDDCR_CPU1_P0_VCC4")
		)
		(pad "4" smd rect
			(at -2.400046 -0.925068 90)
			(size 0.2286 0.6096)
			(layers "F.Cu" "F.Mask" "F.Paste")
			(net "PVDDCR_CPU1_P0_PVCC")
		)
		(pad "5" smd rect
			(at -2.400046 -0.47498 90)
			(size 0.2286 0.6096)
			(layers "F.Cu" "F.Mask" "F.Paste")
			(net "GND")
		)
		(pad "6" smd rect
			(at -2.400046 -0.024892 90)
			(size 0.2286 0.6096)
			(layers "F.Cu" "F.Mask" "F.Paste")
			(net "NC_PVDDCR_CPU1_P0_GL1_4")
		)
		(pad "7_9-20_24" smd circle
			(at 0 1.150112 90)
			(size 0 0)
			(layers "F.Cu" "F.Mask" "F.Paste")
			(net "GND")
		)
		(pad "10_19" smd rect
			(at 0 2.899918 90)
			(size 0.6096 4.318)
			(layers "F.Cu" "F.Mask" "F.Paste")
			(net "SW_PVDDCR_CPU1_P0_SW4")
		)
		(pad "25_29" smd rect
			(at 1.549908 -1.279906 270)
			(size 2.0574 2.3114)
			(layers "F.Cu" "F.Mask" "F.Paste")
			(net "SW_P12V_AUX_PVDDCR_CPU1_P0_FLT")
		)
		(pad "30" smd rect
			(at 2.05994 -2.899918)
			(size 0.2286 0.6096)
			(layers "F.Cu" "F.Mask" "F.Paste")
			(net "SW_P12V_AUX_PVDDCR_CPU1_P0_FLT")
		)
		(pad "31" smd rect
			(at 1.610106 -2.899918)
			(size 0.2286 0.6096)
			(layers "F.Cu" "F.Mask" "F.Paste")
			(net "NC_PVDDCR_CPU1_P0_DNC4")
		)
		(pad "32" smd rect
			(at 1.160018 -2.899918)
			(size 0.2286 0.6096)
			(layers "F.Cu" "F.Mask" "F.Paste")
			(net "SW_PVDDCR_CPU1_P0_BOOTR4")
		)
		(pad "33" smd rect
			(at 0.70993 -2.899918)
			(size 0.2286 0.6096)
			(layers "F.Cu" "F.Mask" "F.Paste")
			(net "SW_PVDDCR_CPU1_P0_BOOT4")
		)
		(pad "34" smd rect
			(at 0.260096 -2.899918)
			(size 0.2286 0.6096)
			(layers "F.Cu" "F.Mask" "F.Paste")
			(net "PVDDCR_CPU1_P0_PWM4")
		)
		(pad "35" smd rect
			(at -0.189992 -2.899918)
			(size 0.2286 0.6096)
			(layers "F.Cu" "F.Mask" "F.Paste")
			(net "PVDDCR_CPU1_P0_VCC4")
		)
		(pad "36" smd rect
			(at -0.64008 -2.899918)
			(size 0.2286 0.6096)
			(layers "F.Cu" "F.Mask" "F.Paste")
			(net "PVDDCR_CPU1_P0_TEMP0")
		)
		(pad "37" smd rect
			(at -1.089914 -2.899918)
			(size 0.2286 0.6096)
			(layers "F.Cu" "F.Mask" "F.Paste")
			(net "PVDDCR_CPU1_P0_LSET4")
		)
		(pad "38" smd rect
			(at -1.540002 -2.899918)
			(size 0.2286 0.6096)
			(layers "F.Cu" "F.Mask" "F.Paste")
			(net "PVDDCR_CPU1_P0_IMON4")
		)
		(pad "39" smd rect
			(at -1.99009 -2.899918)
			(size 0.2286 0.6096)
			(layers "F.Cu" "F.Mask" "F.Paste")
			(net "PVDDCR_CPU1_P0_VCCS")
		)
		(pad "40" smd rect
			(at -0.87503 -1.27508)
			(size 1.7526 1.9558)
			(layers "F.Cu" "F.Mask" "F.Paste")
			(net "GND")
		)
		(pad "41" smd rect
			(at -1.525016 0.249936 270)
			(size 0.3048 0.4572)
			(layers "F.Cu" "F.Mask" "F.Paste")
			(net "NC_PVDDCR_CPU1_P0_GL2_4")
		)
		(zone
			(layer "F.Cu")
			(hatch none 0.5)
			(connect_pads
				(clearance 0)
			)
			(min_thickness 0.25)
			(keepout
				(tracks not_allowed)
				(vias allowed)
				(pads allowed)
				(copperpour not_allowed)
				(footprints allowed)
			)
			(placement
				(enabled no)
				(sheetname "")
			)
			(fill
				(thermal_gap 0.5)
				(thermal_bridge_width 0.5)
				(island_removal_mode 0)
			)
			(polygon
				(pts
					(xy 306.195984 -344.147394) (xy 306.195984 -344.465656) (xy 311.196228 -344.465656) (xy 311.196228 -344.136472)
					(xy 310.905906 -344.136472) (xy 310.905906 -344.172032) (xy 306.486306 -344.172032) (xy 306.486306 -344.147394)
				)
			)
		)
		(zone
			(layer "F.Cu")
			(hatch none 0.5)
			(connect_pads
				(clearance 0)
			)
			(min_thickness 0.25)
			(keepout
				(tracks not_allowed)
				(vias allowed)
				(pads allowed)
				(copperpour not_allowed)
				(footprints allowed)
			)
			(placement
				(enabled no)
				(sheetname "")
			)
			(fill
				(thermal_gap 0.5)
				(thermal_bridge_width 0.5)
				(island_removal_mode 0)
			)
			(polygon
				(pts
					(xy 308.748176 -346.96273) (xy 308.748176 -349.02013) (xy 306.893976 -349.02013) (xy 306.893976 -348.779084)
					(xy 306.65166 -348.779084) (xy 306.65166 -349.260668) (xy 310.491886 -349.260668) (xy 310.491886 -349.075756)
					(xy 309.039514 -349.075756) (xy 309.039514 -346.916756) (xy 311.196228 -346.916756) (xy 311.196228 -346.667074)
					(xy 309.043832 -346.667074)
				)
			)
		)
	)
	(footprint ""
		(layer "F.Cu")
		(at 390.162542 -416.899344 -90)
		(property "Reference" "C6577"
			(at 0 0 270)
			(layer "F.SilkS")
			(hide yes)
			(effects
				(font
					(size 1.27 1.27)
				)
			)
		)
		(property "Value" ""
			(at 0 0 270)
			(layer "F.Fab")
			(effects
				(font
					(size 1.27 1.27)
				)
			)
		)
		(duplicate_pad_numbers_are_jumpers no)
		(fp_line
			(start -0.299974 0.150114)
			(end -0.299974 -0.150114)
			(stroke
				(width 0.1)
				(type default)
			)
			(layer "F.Fab")
		)
		(fp_line
			(start 0.299974 0.150114)
			(end -0.299974 0.150114)
			(stroke
				(width 0.1)
				(type default)
			)
			(layer "F.Fab")
		)
		(fp_line
			(start -0.299974 -0.150114)
			(end 0.299974 -0.150114)
			(stroke
				(width 0.1)
				(type default)
			)
			(layer "F.Fab")
		)
		(fp_line
			(start 0.299974 -0.150114)
			(end 0.299974 0.150114)
			(stroke
				(width 0.1)
				(type default)
			)
			(layer "F.Fab")
		)
		(pad "1" smd rect
			(at -0.2667 0 270)
			(size 0.3048 0.381)
			(layers "F.Cu" "F.Mask" "F.Paste")
			(net "P5E_CPU0_P2_TX_BUF_C_DP<6>")
		)
		(pad "2" smd rect
			(at 0.2667 0 270)
			(size 0.3048 0.381)
			(layers "F.Cu" "F.Mask" "F.Paste")
			(net "P5E_CPU0_P2_TX_BUF_DP<6>")
		)
	)
	(footprint ""
		(layer "F.Cu")
		(at 99.278186 -31.847536 -90)
		(property "Reference" "R6333"
			(at 0 0 270)
			(layer "F.SilkS")
			(hide yes)
			(effects
				(font
					(size 1.27 1.27)
				)
			)
		)
		(property "Value" ""
			(at 0 0 270)
			(layer "F.Fab")
			(effects
				(font
					(size 1.27 1.27)
				)
			)
		)
		(duplicate_pad_numbers_are_jumpers no)
		(fp_line
			(start -0.7874 0.4064)
			(end -0.7874 -0.4064)
			(stroke
				(width 0.1524)
				(type default)
			)
			(layer "F.SilkS")
		)
		(fp_line
			(start 0.7874 0.4064)
			(end -0.7874 0.4064)
			(stroke
				(width 0.1524)
				(type default)
			)
			(layer "F.SilkS")
		)
		(fp_line
			(start -0.7874 -0.4064)
			(end 0.7874 -0.4064)
			(stroke
				(width 0.1524)
				(type default)
			)
			(layer "F.SilkS")
		)
		(fp_line
			(start 0.7874 -0.4064)
			(end 0.7874 0.4064)
			(stroke
				(width 0.1524)
				(type default)
			)
			(layer "F.SilkS")
		)
		(fp_line
			(start -0.67945 0.3048)
			(end -0.67945 -0.305054)
			(stroke
				(width 0.1)
				(type default)
			)
			(layer "F.Fab")
		)
		(fp_line
			(start -0.12065 0.3048)
			(end -0.67945 0.3048)
			(stroke
				(width 0.1)
				(type default)
			)
			(layer "F.Fab")
		)
		(fp_line
			(start 0.120396 0.3048)
			(end 0.120396 0.2794)
			(stroke
				(width 0.1)
				(type default)
			)
			(layer "F.Fab")
		)
		(fp_line
			(start 0.67945 0.3048)
			(end 0.120396 0.3048)
			(stroke
				(width 0.1)
				(type default)
			)
			(layer "F.Fab")
		)
		(fp_line
			(start -0.12065 0.2794)
			(end -0.12065 0.3048)
			(stroke
				(width 0.1)
				(type default)
			)
			(layer "F.Fab")
		)
		(fp_line
			(start 0.120396 0.2794)
			(end -0.12065 0.2794)
			(stroke
				(width 0.1)
				(type default)
			)
			(layer "F.Fab")
		)
		(fp_line
			(start -0.12065 -0.2794)
			(end 0.12065 -0.2794)
			(stroke
				(width 0.1)
				(type default)
			)
			(layer "F.Fab")
		)
		(fp_line
			(start 0.12065 -0.2794)
			(end 0.12065 -0.3048)
			(stroke
				(width 0.1)
				(type default)
			)
			(layer "F.Fab")
		)
		(fp_line
			(start 0.12065 -0.3048)
			(end 0.67945 -0.3048)
			(stroke
				(width 0.1)
				(type default)
			)
			(layer "F.Fab")
		)
		(fp_line
			(start 0.67945 -0.3048)
			(end 0.67945 0.3048)
			(stroke
				(width 0.1)
				(type default)
			)
			(layer "F.Fab")
		)
		(fp_line
			(start -0.67945 -0.305054)
			(end -0.12065 -0.305054)
			(stroke
				(width 0.1)
				(type default)
			)
			(layer "F.Fab")
		)
		(fp_line
			(start -0.12065 -0.305054)
			(end -0.12065 -0.2794)
			(stroke
				(width 0.1)
				(type default)
			)
			(layer "F.Fab")
		)
		(pad "1" smd circle
			(at -0.40005 0 270)
			(size 0 0)
			(layers "F.Cu" "F.Mask" "F.Paste")
			(net "USB_HUB2_TI_GRSTZ_MRP_PROG_FUNC1")
		)
		(pad "2" smd circle
			(at 0.40005 0 270)
			(size 0 0)
			(layers "F.Cu" "F.Mask" "F.Paste")
			(net "GND")
		)
	)
	(footprint ""
		(layer "F.Cu")
		(at 309.894986 -416.899344 -90)
		(property "Reference" "C6506"
			(at 0 0 270)
			(layer "F.SilkS")
			(hide yes)
			(effects
				(font
					(size 1.27 1.27)
				)
			)
		)
		(property "Value" ""
			(at 0 0 270)
			(layer "F.Fab")
			(effects
				(font
					(size 1.27 1.27)
				)
			)
		)
		(duplicate_pad_numbers_are_jumpers no)
		(fp_line
			(start -0.299974 0.150114)
			(end -0.299974 -0.150114)
			(stroke
				(width 0.1)
				(type default)
			)
			(layer "F.Fab")
		)
		(fp_line
			(start 0.299974 0.150114)
			(end -0.299974 0.150114)
			(stroke
				(width 0.1)
				(type default)
			)
			(layer "F.Fab")
		)
		(fp_line
			(start -0.299974 -0.150114)
			(end 0.299974 -0.150114)
			(stroke
				(width 0.1)
				(type default)
			)
			(layer "F.Fab")
		)
		(fp_line
			(start 0.299974 -0.150114)
			(end 0.299974 0.150114)
			(stroke
				(width 0.1)
				(type default)
			)
			(layer "F.Fab")
		)
		(pad "1" smd rect
			(at -0.2667 0 270)
			(size 0.3048 0.381)
			(layers "F.Cu" "F.Mask" "F.Paste")
			(net "P5E_CPU0_P0_TX_BUF_C_DN<2>")
		)
		(pad "2" smd rect
			(at 0.2667 0 270)
			(size 0.3048 0.381)
			(layers "F.Cu" "F.Mask" "F.Paste")
			(net "P5E_CPU0_P0_TX_BUF_DN<2>")
		)
	)
	(footprint ""
		(layer "F.Cu")
		(at 333.376524 -24.771858 -90)
		(property "Reference" "C5032"
			(at 0 0 270)
			(layer "F.SilkS")
			(hide yes)
			(effects
				(font
					(size 1.27 1.27)
				)
			)
		)
		(property "Value" ""
			(at 0 0 270)
			(layer "F.Fab")
			(effects
				(font
					(size 1.27 1.27)
				)
			)
		)
		(duplicate_pad_numbers_are_jumpers no)
		(fp_line
			(start -1.524 0.762)
			(end -1.524 -0.762)
			(stroke
				(width 0.1524)
				(type default)
			)
			(layer "F.SilkS")
		)
		(fp_line
			(start 1.524 0.762)
			(end -1.524 0.762)
			(stroke
				(width 0.1524)
				(type default)
			)
			(layer "F.SilkS")
		)
		(fp_line
			(start -1.524 -0.762)
			(end 1.524 -0.762)
			(stroke
				(width 0.1524)
				(type default)
			)
			(layer "F.SilkS")
		)
		(fp_line
			(start 1.524 -0.762)
			(end 1.524 0.762)
			(stroke
				(width 0.1524)
				(type default)
			)
			(layer "F.SilkS")
		)
		(fp_line
			(start -1.1049 0.724916)
			(end 1.1049 0.724916)
			(stroke
				(width 0.1)
				(type default)
			)
			(layer "F.Fab")
		)
		(fp_line
			(start 1.1049 0.724916)
			(end 1.1049 -0.724916)
			(stroke
				(width 0.1)
				(type default)
			)
			(layer "F.Fab")
		)
		(fp_line
			(start -1.1049 -0.724916)
			(end -1.1049 0.724916)
			(stroke
				(width 0.1)
				(type default)
			)
			(layer "F.Fab")
		)
		(fp_line
			(start 1.1049 -0.724916)
			(end -1.1049 -0.724916)
			(stroke
				(width 0.1)
				(type default)
			)
			(layer "F.Fab")
		)
		(pad "1" smd rect
			(at -0.889 0 90)
			(size 1.016 1.27)
			(layers "F.Cu" "F.Mask" "F.Paste")
			(net "P1V5_BAT")
		)
		(pad "2" smd rect
			(at 0.889 0 90)
			(size 1.016 1.27)
			(layers "F.Cu" "F.Mask" "F.Paste")
			(net "GND")
		)
	)
	(footprint ""
		(layer "F.Cu")
		(at 138.426952 -56.500014 180)
		(property "Reference" "R1658"
			(at 0 0 180)
			(layer "F.SilkS")
			(hide yes)
			(effects
				(font
					(size 1.27 1.27)
				)
			)
		)
		(property "Value" ""
			(at 0 0 180)
			(layer "F.Fab")
			(effects
				(font
					(size 1.27 1.27)
				)
			)
		)
		(duplicate_pad_numbers_are_jumpers no)
		(fp_line
			(start 0.7874 0.4064)
			(end -0.7874 0.4064)
			(stroke
				(width 0.1524)
				(type default)
			)
			(layer "F.SilkS")
		)
		(fp_line
			(start 0.7874 -0.4064)
			(end 0.7874 0.4064)
			(stroke
				(width 0.1524)
				(type default)
			)
			(layer "F.SilkS")
		)
		(fp_line
			(start -0.7874 0.4064)
			(end -0.7874 -0.4064)
			(stroke
				(width 0.1524)
				(type default)
			)
			(layer "F.SilkS")
		)
		(fp_line
			(start -0.7874 -0.4064)
			(end 0.7874 -0.4064)
			(stroke
				(width 0.1524)
				(type default)
			)
			(layer "F.SilkS")
		)
		(fp_line
			(start 0.67945 0.3048)
			(end 0.120396 0.3048)
			(stroke
				(width 0.1)
				(type default)
			)
			(layer "F.Fab")
		)
		(fp_line
			(start 0.67945 -0.3048)
			(end 0.67945 0.3048)
			(stroke
				(width 0.1)
				(type default)
			)
			(layer "F.Fab")
		)
		(fp_line
			(start 0.12065 -0.2794)
			(end 0.12065 -0.3048)
			(stroke
				(width 0.1)
				(type default)
			)
			(layer "F.Fab")
		)
		(fp_line
			(start 0.12065 -0.3048)
			(end 0.67945 -0.3048)
			(stroke
				(width 0.1)
				(type default)
			)
			(layer "F.Fab")
		)
		(fp_line
			(start 0.120396 0.3048)
			(end 0.120396 0.2794)
			(stroke
				(width 0.1)
				(type default)
			)
			(layer "F.Fab")
		)
		(fp_line
			(start 0.120396 0.2794)
			(end -0.12065 0.2794)
			(stroke
				(width 0.1)
				(type default)
			)
			(layer "F.Fab")
		)
		(fp_line
			(start -0.12065 0.3048)
			(end -0.67945 0.3048)
			(stroke
				(width 0.1)
				(type default)
			)
			(layer "F.Fab")
		)
		(fp_line
			(start -0.12065 0.2794)
			(end -0.12065 0.3048)
			(stroke
				(width 0.1)
				(type default)
			)
			(layer "F.Fab")
		)
		(fp_line
			(start -0.12065 -0.2794)
			(end 0.12065 -0.2794)
			(stroke
				(width 0.1)
				(type default)
			)
			(layer "F.Fab")
		)
		(fp_line
			(start -0.12065 -0.305054)
			(end -0.12065 -0.2794)
			(stroke
				(width 0.1)
				(type default)
			)
			(layer "F.Fab")
		)
		(fp_line
			(start -0.67945 0.3048)
			(end -0.67945 -0.305054)
			(stroke
				(width 0.1)
				(type default)
			)
			(layer "F.Fab")
		)
		(fp_line
			(start -0.67945 -0.305054)
			(end -0.12065 -0.305054)
			(stroke
				(width 0.1)
				(type default)
			)
			(layer "F.Fab")
		)
		(pad "1" smd circle
			(at -0.40005 0 180)
			(size 0 0)
			(layers "F.Cu" "F.Mask" "F.Paste")
			(net "SCM_JTAG_MUX_S0")
		)
		(pad "2" smd circle
			(at 0.40005 0 180)
			(size 0 0)
			(layers "F.Cu" "F.Mask" "F.Paste")
			(net "GND")
		)
	)
	(footprint ""
		(layer "F.Cu")
		(at 334.731614 -144.055592 180)
		(property "Reference" "PC237"
			(at 0 0 180)
			(layer "F.SilkS")
			(hide yes)
			(effects
				(font
					(size 1.27 1.27)
				)
			)
		)
		(property "Value" ""
			(at 0 0 180)
			(layer "F.Fab")
			(effects
				(font
					(size 1.27 1.27)
				)
			)
		)
		(duplicate_pad_numbers_are_jumpers no)
		(fp_line
			(start 0.7874 0.4064)
			(end -0.7874 0.4064)
			(stroke
				(width 0.1524)
				(type default)
			)
			(layer "F.SilkS")
		)
		(fp_line
			(start 0.7874 -0.4064)
			(end 0.7874 0.4064)
			(stroke
				(width 0.1524)
				(type default)
			)
			(layer "F.SilkS")
		)
		(fp_line
			(start -0.7874 0.4064)
			(end -0.7874 -0.4064)
			(stroke
				(width 0.1524)
				(type default)
			)
			(layer "F.SilkS")
		)
		(fp_line
			(start -0.7874 -0.4064)
			(end 0.7874 -0.4064)
			(stroke
				(width 0.1524)
				(type default)
			)
			(layer "F.SilkS")
		)
		(fp_line
			(start 0.67945 0.3048)
			(end 0.120396 0.3048)
			(stroke
				(width 0.1)
				(type default)
			)
			(layer "F.Fab")
		)
		(fp_line
			(start 0.67945 -0.3048)
			(end 0.67945 0.3048)
			(stroke
				(width 0.1)
				(type default)
			)
			(layer "F.Fab")
		)
		(fp_line
			(start 0.12065 -0.2794)
			(end 0.12065 -0.3048)
			(stroke
				(width 0.1)
				(type default)
			)
			(layer "F.Fab")
		)
		(fp_line
			(start 0.12065 -0.3048)
			(end 0.67945 -0.3048)
			(stroke
				(width 0.1)
				(type default)
			)
			(layer "F.Fab")
		)
		(fp_line
			(start 0.120396 0.3048)
			(end 0.120396 0.2794)
			(stroke
				(width 0.1)
				(type default)
			)
			(layer "F.Fab")
		)
		(fp_line
			(start 0.120396 0.2794)
			(end -0.12065 0.2794)
			(stroke
				(width 0.1)
				(type default)
			)
			(layer "F.Fab")
		)
		(fp_line
			(start -0.12065 0.3048)
			(end -0.67945 0.3048)
			(stroke
				(width 0.1)
				(type default)
			)
			(layer "F.Fab")
		)
		(fp_line
			(start -0.12065 0.2794)
			(end -0.12065 0.3048)
			(stroke
				(width 0.1)
				(type default)
			)
			(layer "F.Fab")
		)
		(fp_line
			(start -0.12065 -0.2794)
			(end 0.12065 -0.2794)
			(stroke
				(width 0.1)
				(type default)
			)
			(layer "F.Fab")
		)
		(fp_line
			(start -0.12065 -0.305054)
			(end -0.12065 -0.2794)
			(stroke
				(width 0.1)
				(type default)
			)
			(layer "F.Fab")
		)
		(fp_line
			(start -0.67945 0.3048)
			(end -0.67945 -0.305054)
			(stroke
				(width 0.1)
				(type default)
			)
			(layer "F.Fab")
		)
		(fp_line
			(start -0.67945 -0.305054)
			(end -0.12065 -0.305054)
			(stroke
				(width 0.1)
				(type default)
			)
			(layer "F.Fab")
		)
		(pad "1" smd circle
			(at -0.40005 0 180)
			(size 0 0)
			(layers "F.Cu" "F.Mask" "F.Paste")
			(net "SW_P12V_AUX_PVDD18_S5_P0_FLT")
		)
		(pad "2" smd circle
			(at 0.40005 0 180)
			(size 0 0)
			(layers "F.Cu" "F.Mask" "F.Paste")
			(net "GND")
		)
	)
	(footprint ""
		(layer "F.Cu")
		(at 443.982602 -418.17671 -90)
		(property "Reference" "PR6609"
			(at 0 0 270)
			(layer "F.SilkS")
			(hide yes)
			(effects
				(font
					(size 1.27 1.27)
				)
			)
		)
		(property "Value" ""
			(at 0 0 270)
			(layer "F.Fab")
			(effects
				(font
					(size 1.27 1.27)
				)
			)
		)
		(duplicate_pad_numbers_are_jumpers no)
		(fp_line
			(start -0.7874 0.4064)
			(end -0.7874 -0.4064)
			(stroke
				(width 0.1524)
				(type default)
			)
			(layer "F.SilkS")
		)
		(fp_line
			(start 0.7874 0.4064)
			(end -0.7874 0.4064)
			(stroke
				(width 0.1524)
				(type default)
			)
			(layer "F.SilkS")
		)
		(fp_line
			(start -0.7874 -0.4064)
			(end 0.7874 -0.4064)
			(stroke
				(width 0.1524)
				(type default)
			)
			(layer "F.SilkS")
		)
		(fp_line
			(start 0.7874 -0.4064)
			(end 0.7874 0.4064)
			(stroke
				(width 0.1524)
				(type default)
			)
			(layer "F.SilkS")
		)
		(fp_line
			(start -0.67945 0.3048)
			(end -0.67945 -0.305054)
			(stroke
				(width 0.1)
				(type default)
			)
			(layer "F.Fab")
		)
		(fp_line
			(start -0.12065 0.3048)
			(end -0.67945 0.3048)
			(stroke
				(width 0.1)
				(type default)
			)
			(layer "F.Fab")
		)
		(fp_line
			(start 0.120396 0.3048)
			(end 0.120396 0.2794)
			(stroke
				(width 0.1)
				(type default)
			)
			(layer "F.Fab")
		)
		(fp_line
			(start 0.67945 0.3048)
			(end 0.120396 0.3048)
			(stroke
				(width 0.1)
				(type default)
			)
			(layer "F.Fab")
		)
		(fp_line
			(start -0.12065 0.2794)
			(end -0.12065 0.3048)
			(stroke
				(width 0.1)
				(type default)
			)
			(layer "F.Fab")
		)
		(fp_line
			(start 0.120396 0.2794)
			(end -0.12065 0.2794)
			(stroke
				(width 0.1)
				(type default)
			)
			(layer "F.Fab")
		)
		(fp_line
			(start -0.12065 -0.2794)
			(end 0.12065 -0.2794)
			(stroke
				(width 0.1)
				(type default)
			)
			(layer "F.Fab")
		)
		(fp_line
			(start 0.12065 -0.2794)
			(end 0.12065 -0.3048)
			(stroke
				(width 0.1)
				(type default)
			)
			(layer "F.Fab")
		)
		(fp_line
			(start 0.12065 -0.3048)
			(end 0.67945 -0.3048)
			(stroke
				(width 0.1)
				(type default)
			)
			(layer "F.Fab")
		)
		(fp_line
			(start 0.67945 -0.3048)
			(end 0.67945 0.3048)
			(stroke
				(width 0.1)
				(type default)
			)
			(layer "F.Fab")
		)
		(fp_line
			(start -0.67945 -0.305054)
			(end -0.12065 -0.305054)
			(stroke
				(width 0.1)
				(type default)
			)
			(layer "F.Fab")
		)
		(fp_line
			(start -0.12065 -0.305054)
			(end -0.12065 -0.2794)
			(stroke
				(width 0.1)
				(type default)
			)
			(layer "F.Fab")
		)
		(pad "1" smd circle
			(at -0.40005 0 270)
			(size 0 0)
			(layers "F.Cu" "F.Mask" "F.Paste")
			(net "NC_P0V9_RETIMER_CPU0_IMON3")
		)
		(pad "2" smd circle
			(at 0.40005 0 270)
			(size 0 0)
			(layers "F.Cu" "F.Mask" "F.Paste")
			(net "GND")
		)
	)
	(footprint ""
		(layer "F.Cu")
		(at 94.478348 -136.059418 90)
		(property "Reference" "R149"
			(at 0 0 90)
			(layer "F.SilkS")
			(hide yes)
			(effects
				(font
					(size 1.27 1.27)
				)
			)
		)
		(property "Value" ""
			(at 0 0 90)
			(layer "F.Fab")
			(effects
				(font
					(size 1.27 1.27)
				)
			)
		)
		(duplicate_pad_numbers_are_jumpers no)
		(fp_line
			(start 0.7874 -0.4064)
			(end 0.7874 0.4064)
			(stroke
				(width 0.1524)
				(type default)
			)
			(layer "F.SilkS")
		)
		(fp_line
			(start -0.7874 -0.4064)
			(end 0.7874 -0.4064)
			(stroke
				(width 0.1524)
				(type default)
			)
			(layer "F.SilkS")
		)
		(fp_line
			(start 0.7874 0.4064)
			(end -0.7874 0.4064)
			(stroke
				(width 0.1524)
				(type default)
			)
			(layer "F.SilkS")
		)
		(fp_line
			(start -0.7874 0.4064)
			(end -0.7874 -0.4064)
			(stroke
				(width 0.1524)
				(type default)
			)
			(layer "F.SilkS")
		)
		(fp_line
			(start -0.12065 -0.305054)
			(end -0.12065 -0.2794)
			(stroke
				(width 0.1)
				(type default)
			)
			(layer "F.Fab")
		)
		(fp_line
			(start -0.67945 -0.305054)
			(end -0.12065 -0.305054)
			(stroke
				(width 0.1)
				(type default)
			)
			(layer "F.Fab")
		)
		(fp_line
			(start 0.67945 -0.3048)
			(end 0.67945 0.3048)
			(stroke
				(width 0.1)
				(type default)
			)
			(layer "F.Fab")
		)
		(fp_line
			(start 0.12065 -0.3048)
			(end 0.67945 -0.3048)
			(stroke
				(width 0.1)
				(type default)
			)
			(layer "F.Fab")
		)
		(fp_line
			(start 0.12065 -0.2794)
			(end 0.12065 -0.3048)
			(stroke
				(width 0.1)
				(type default)
			)
			(layer "F.Fab")
		)
		(fp_line
			(start -0.12065 -0.2794)
			(end 0.12065 -0.2794)
			(stroke
				(width 0.1)
				(type default)
			)
			(layer "F.Fab")
		)
		(fp_line
			(start 0.120396 0.2794)
			(end -0.12065 0.2794)
			(stroke
				(width 0.1)
				(type default)
			)
			(layer "F.Fab")
		)
		(fp_line
			(start -0.12065 0.2794)
			(end -0.12065 0.3048)
			(stroke
				(width 0.1)
				(type default)
			)
			(layer "F.Fab")
		)
		(fp_line
			(start 0.67945 0.3048)
			(end 0.120396 0.3048)
			(stroke
				(width 0.1)
				(type default)
			)
			(layer "F.Fab")
		)
		(fp_line
			(start 0.120396 0.3048)
			(end 0.120396 0.2794)
			(stroke
				(width 0.1)
				(type default)
			)
			(layer "F.Fab")
		)
		(fp_line
			(start -0.12065 0.3048)
			(end -0.67945 0.3048)
			(stroke
				(width 0.1)
				(type default)
			)
			(layer "F.Fab")
		)
		(fp_line
			(start -0.67945 0.3048)
			(end -0.67945 -0.305054)
			(stroke
				(width 0.1)
				(type default)
			)
			(layer "F.Fab")
		)
		(pad "1" smd circle
			(at -0.40005 0 90)
			(size 0 0)
			(layers "F.Cu" "F.Mask" "F.Paste")
			(net "PVDDCR_SOC_P1_EN")
		)
		(pad "2" smd circle
			(at 0.40005 0 90)
			(size 0 0)
			(layers "F.Cu" "F.Mask" "F.Paste")
			(net "PVDDCR_SOC_P1_EN_RC")
		)
	)
	(footprint ""
		(layer "F.Cu")
		(at 355.617272 -261.747762 -90)
		(property "Reference" "C2150"
			(at 0 0 270)
			(layer "F.SilkS")
			(hide yes)
			(effects
				(font
					(size 1.27 1.27)
				)
			)
		)
		(property "Value" ""
			(at 0 0 270)
			(layer "F.Fab")
			(effects
				(font
					(size 1.27 1.27)
				)
			)
		)
		(duplicate_pad_numbers_are_jumpers no)
		(fp_line
			(start -0.7874 0.4064)
			(end -0.7874 -0.4064)
			(stroke
				(width 0.1524)
				(type default)
			)
			(layer "F.SilkS")
		)
		(fp_line
			(start 0.7874 0.4064)
			(end -0.7874 0.4064)
			(stroke
				(width 0.1524)
				(type default)
			)
			(layer "F.SilkS")
		)
		(fp_line
			(start -0.7874 -0.4064)
			(end 0.7874 -0.4064)
			(stroke
				(width 0.1524)
				(type default)
			)
			(layer "F.SilkS")
		)
		(fp_line
			(start 0.7874 -0.4064)
			(end 0.7874 0.4064)
			(stroke
				(width 0.1524)
				(type default)
			)
			(layer "F.SilkS")
		)
		(fp_line
			(start -0.67945 0.3048)
			(end -0.67945 -0.305054)
			(stroke
				(width 0.1)
				(type default)
			)
			(layer "F.Fab")
		)
		(fp_line
			(start -0.12065 0.3048)
			(end -0.67945 0.3048)
			(stroke
				(width 0.1)
				(type default)
			)
			(layer "F.Fab")
		)
		(fp_line
			(start 0.120396 0.3048)
			(end 0.120396 0.2794)
			(stroke
				(width 0.1)
				(type default)
			)
			(layer "F.Fab")
		)
		(fp_line
			(start 0.67945 0.3048)
			(end 0.120396 0.3048)
			(stroke
				(width 0.1)
				(type default)
			)
			(layer "F.Fab")
		)
		(fp_line
			(start -0.12065 0.2794)
			(end -0.12065 0.3048)
			(stroke
				(width 0.1)
				(type default)
			)
			(layer "F.Fab")
		)
		(fp_line
			(start 0.120396 0.2794)
			(end -0.12065 0.2794)
			(stroke
				(width 0.1)
				(type default)
			)
			(layer "F.Fab")
		)
		(fp_line
			(start -0.12065 -0.2794)
			(end 0.12065 -0.2794)
			(stroke
				(width 0.1)
				(type default)
			)
			(layer "F.Fab")
		)
		(fp_line
			(start 0.12065 -0.2794)
			(end 0.12065 -0.3048)
			(stroke
				(width 0.1)
				(type default)
			)
			(layer "F.Fab")
		)
		(fp_line
			(start 0.12065 -0.3048)
			(end 0.67945 -0.3048)
			(stroke
				(width 0.1)
				(type default)
			)
			(layer "F.Fab")
		)
		(fp_line
			(start 0.67945 -0.3048)
			(end 0.67945 0.3048)
			(stroke
				(width 0.1)
				(type default)
			)
			(layer "F.Fab")
		)
		(fp_line
			(start -0.67945 -0.305054)
			(end -0.12065 -0.305054)
			(stroke
				(width 0.1)
				(type default)
			)
			(layer "F.Fab")
		)
		(fp_line
			(start -0.12065 -0.305054)
			(end -0.12065 -0.2794)
			(stroke
				(width 0.1)
				(type default)
			)
			(layer "F.Fab")
		)
		(pad "1" smd circle
			(at -0.40005 0 270)
			(size 0 0)
			(layers "F.Cu" "F.Mask" "F.Paste")
			(net "PVDD11_S3_P0")
		)
		(pad "2" smd circle
			(at 0.40005 0 270)
			(size 0 0)
			(layers "F.Cu" "F.Mask" "F.Paste")
			(net "GND")
		)
	)
	(footprint ""
		(layer "F.Cu")
		(at 352.05543 -431.809652 180)
		(property "Reference" "R4550"
			(at 0 0 180)
			(layer "F.SilkS")
			(hide yes)
			(effects
				(font
					(size 1.27 1.27)
				)
			)
		)
		(property "Value" ""
			(at 0 0 180)
			(layer "F.Fab")
			(effects
				(font
					(size 1.27 1.27)
				)
			)
		)
		(duplicate_pad_numbers_are_jumpers no)
		(fp_line
			(start 0.7874 0.4064)
			(end -0.7874 0.4064)
			(stroke
				(width 0.1524)
				(type default)
			)
			(layer "F.SilkS")
		)
		(fp_line
			(start 0.7874 -0.4064)
			(end 0.7874 0.4064)
			(stroke
				(width 0.1524)
				(type default)
			)
			(layer "F.SilkS")
		)
		(fp_line
			(start -0.7874 0.4064)
			(end -0.7874 -0.4064)
			(stroke
				(width 0.1524)
				(type default)
			)
			(layer "F.SilkS")
		)
		(fp_line
			(start -0.7874 -0.4064)
			(end 0.7874 -0.4064)
			(stroke
				(width 0.1524)
				(type default)
			)
			(layer "F.SilkS")
		)
		(fp_line
			(start 0.67945 0.3048)
			(end 0.120396 0.3048)
			(stroke
				(width 0.1)
				(type default)
			)
			(layer "F.Fab")
		)
		(fp_line
			(start 0.67945 -0.3048)
			(end 0.67945 0.3048)
			(stroke
				(width 0.1)
				(type default)
			)
			(layer "F.Fab")
		)
		(fp_line
			(start 0.12065 -0.2794)
			(end 0.12065 -0.3048)
			(stroke
				(width 0.1)
				(type default)
			)
			(layer "F.Fab")
		)
		(fp_line
			(start 0.12065 -0.3048)
			(end 0.67945 -0.3048)
			(stroke
				(width 0.1)
				(type default)
			)
			(layer "F.Fab")
		)
		(fp_line
			(start 0.120396 0.3048)
			(end 0.120396 0.2794)
			(stroke
				(width 0.1)
				(type default)
			)
			(layer "F.Fab")
		)
		(fp_line
			(start 0.120396 0.2794)
			(end -0.12065 0.2794)
			(stroke
				(width 0.1)
				(type default)
			)
			(layer "F.Fab")
		)
		(fp_line
			(start -0.12065 0.3048)
			(end -0.67945 0.3048)
			(stroke
				(width 0.1)
				(type default)
			)
			(layer "F.Fab")
		)
		(fp_line
			(start -0.12065 0.2794)
			(end -0.12065 0.3048)
			(stroke
				(width 0.1)
				(type default)
			)
			(layer "F.Fab")
		)
		(fp_line
			(start -0.12065 -0.2794)
			(end 0.12065 -0.2794)
			(stroke
				(width 0.1)
				(type default)
			)
			(layer "F.Fab")
		)
		(fp_line
			(start -0.12065 -0.305054)
			(end -0.12065 -0.2794)
			(stroke
				(width 0.1)
				(type default)
			)
			(layer "F.Fab")
		)
		(fp_line
			(start -0.67945 0.3048)
			(end -0.67945 -0.305054)
			(stroke
				(width 0.1)
				(type default)
			)
			(layer "F.Fab")
		)
		(fp_line
			(start -0.67945 -0.305054)
			(end -0.12065 -0.305054)
			(stroke
				(width 0.1)
				(type default)
			)
			(layer "F.Fab")
		)
		(pad "1" smd circle
			(at -0.40005 0 180)
			(size 0 0)
			(layers "F.Cu" "F.Mask" "F.Paste")
			(net "SWB_HSC_EN_BUF_R")
		)
		(pad "2" smd circle
			(at 0.40005 0 180)
			(size 0 0)
			(layers "F.Cu" "F.Mask" "F.Paste")
			(net "SWB_HSC_EN_BUF")
		)
	)
	(footprint ""
		(layer "F.Cu")
		(at 409.46451 -136.835642 180)
		(property "Reference" "R2316"
			(at 0 0 180)
			(layer "F.SilkS")
			(hide yes)
			(effects
				(font
					(size 1.27 1.27)
				)
			)
		)
		(property "Value" ""
			(at 0 0 180)
			(layer "F.Fab")
			(effects
				(font
					(size 1.27 1.27)
				)
			)
		)
		(duplicate_pad_numbers_are_jumpers no)
		(fp_line
			(start 0.7874 0.4064)
			(end -0.7874 0.4064)
			(stroke
				(width 0.1524)
				(type default)
			)
			(layer "F.SilkS")
		)
		(fp_line
			(start 0.7874 -0.4064)
			(end 0.7874 0.4064)
			(stroke
				(width 0.1524)
				(type default)
			)
			(layer "F.SilkS")
		)
		(fp_line
			(start -0.7874 0.4064)
			(end -0.7874 -0.4064)
			(stroke
				(width 0.1524)
				(type default)
			)
			(layer "F.SilkS")
		)
		(fp_line
			(start -0.7874 -0.4064)
			(end 0.7874 -0.4064)
			(stroke
				(width 0.1524)
				(type default)
			)
			(layer "F.SilkS")
		)
		(fp_line
			(start 0.67945 0.3048)
			(end 0.120396 0.3048)
			(stroke
				(width 0.1)
				(type default)
			)
			(layer "F.Fab")
		)
		(fp_line
			(start 0.67945 -0.3048)
			(end 0.67945 0.3048)
			(stroke
				(width 0.1)
				(type default)
			)
			(layer "F.Fab")
		)
		(fp_line
			(start 0.12065 -0.2794)
			(end 0.12065 -0.3048)
			(stroke
				(width 0.1)
				(type default)
			)
			(layer "F.Fab")
		)
		(fp_line
			(start 0.12065 -0.3048)
			(end 0.67945 -0.3048)
			(stroke
				(width 0.1)
				(type default)
			)
			(layer "F.Fab")
		)
		(fp_line
			(start 0.120396 0.3048)
			(end 0.120396 0.2794)
			(stroke
				(width 0.1)
				(type default)
			)
			(layer "F.Fab")
		)
		(fp_line
			(start 0.120396 0.2794)
			(end -0.12065 0.2794)
			(stroke
				(width 0.1)
				(type default)
			)
			(layer "F.Fab")
		)
		(fp_line
			(start -0.12065 0.3048)
			(end -0.67945 0.3048)
			(stroke
				(width 0.1)
				(type default)
			)
			(layer "F.Fab")
		)
		(fp_line
			(start -0.12065 0.2794)
			(end -0.12065 0.3048)
			(stroke
				(width 0.1)
				(type default)
			)
			(layer "F.Fab")
		)
		(fp_line
			(start -0.12065 -0.2794)
			(end 0.12065 -0.2794)
			(stroke
				(width 0.1)
				(type default)
			)
			(layer "F.Fab")
		)
		(fp_line
			(start -0.12065 -0.305054)
			(end -0.12065 -0.2794)
			(stroke
				(width 0.1)
				(type default)
			)
			(layer "F.Fab")
		)
		(fp_line
			(start -0.67945 0.3048)
			(end -0.67945 -0.305054)
			(stroke
				(width 0.1)
				(type default)
			)
			(layer "F.Fab")
		)
		(fp_line
			(start -0.67945 -0.305054)
			(end -0.12065 -0.305054)
			(stroke
				(width 0.1)
				(type default)
			)
			(layer "F.Fab")
		)
		(pad "1" smd circle
			(at -0.40005 0 180)
			(size 0 0)
			(layers "F.Cu" "F.Mask" "F.Paste")
			(net "PWRGD_P5V_AUX_R")
		)
		(pad "2" smd circle
			(at 0.40005 0 180)
			(size 0 0)
			(layers "F.Cu" "F.Mask" "F.Paste")
			(net "PWRGD_P5V_AUX")
		)
	)
	(footprint ""
		(layer "F.Cu")
		(at 94.338648 -69.488558 90)
		(property "Reference" "PC2137"
			(at 0 0 90)
			(layer "F.SilkS")
			(hide yes)
			(effects
				(font
					(size 1.27 1.27)
				)
			)
		)
		(property "Value" ""
			(at 0 0 90)
			(layer "F.Fab")
			(effects
				(font
					(size 1.27 1.27)
				)
			)
		)
		(duplicate_pad_numbers_are_jumpers no)
		(fp_line
			(start 0.7874 -0.4064)
			(end 0.7874 0.4064)
			(stroke
				(width 0.1524)
				(type default)
			)
			(layer "F.SilkS")
		)
		(fp_line
			(start -0.7874 -0.4064)
			(end 0.7874 -0.4064)
			(stroke
				(width 0.1524)
				(type default)
			)
			(layer "F.SilkS")
		)
		(fp_line
			(start 0.7874 0.4064)
			(end -0.7874 0.4064)
			(stroke
				(width 0.1524)
				(type default)
			)
			(layer "F.SilkS")
		)
		(fp_line
			(start -0.7874 0.4064)
			(end -0.7874 -0.4064)
			(stroke
				(width 0.1524)
				(type default)
			)
			(layer "F.SilkS")
		)
		(fp_line
			(start -0.12065 -0.305054)
			(end -0.12065 -0.2794)
			(stroke
				(width 0.1)
				(type default)
			)
			(layer "F.Fab")
		)
		(fp_line
			(start -0.67945 -0.305054)
			(end -0.12065 -0.305054)
			(stroke
				(width 0.1)
				(type default)
			)
			(layer "F.Fab")
		)
		(fp_line
			(start 0.67945 -0.3048)
			(end 0.67945 0.3048)
			(stroke
				(width 0.1)
				(type default)
			)
			(layer "F.Fab")
		)
		(fp_line
			(start 0.12065 -0.3048)
			(end 0.67945 -0.3048)
			(stroke
				(width 0.1)
				(type default)
			)
			(layer "F.Fab")
		)
		(fp_line
			(start 0.12065 -0.2794)
			(end 0.12065 -0.3048)
			(stroke
				(width 0.1)
				(type default)
			)
			(layer "F.Fab")
		)
		(fp_line
			(start -0.12065 -0.2794)
			(end 0.12065 -0.2794)
			(stroke
				(width 0.1)
				(type default)
			)
			(layer "F.Fab")
		)
		(fp_line
			(start 0.120396 0.2794)
			(end -0.12065 0.2794)
			(stroke
				(width 0.1)
				(type default)
			)
			(layer "F.Fab")
		)
		(fp_line
			(start -0.12065 0.2794)
			(end -0.12065 0.3048)
			(stroke
				(width 0.1)
				(type default)
			)
			(layer "F.Fab")
		)
		(fp_line
			(start 0.67945 0.3048)
			(end 0.120396 0.3048)
			(stroke
				(width 0.1)
				(type default)
			)
			(layer "F.Fab")
		)
		(fp_line
			(start 0.120396 0.3048)
			(end 0.120396 0.2794)
			(stroke
				(width 0.1)
				(type default)
			)
			(layer "F.Fab")
		)
		(fp_line
			(start -0.12065 0.3048)
			(end -0.67945 0.3048)
			(stroke
				(width 0.1)
				(type default)
			)
			(layer "F.Fab")
		)
		(fp_line
			(start -0.67945 0.3048)
			(end -0.67945 -0.305054)
			(stroke
				(width 0.1)
				(type default)
			)
			(layer "F.Fab")
		)
		(pad "1" smd circle
			(at -0.40005 0 90)
			(size 0 0)
			(layers "F.Cu" "F.Mask" "F.Paste")
			(net "P3V3_OCP_V3_2_R")
		)
		(pad "2" smd circle
			(at 0.40005 0 90)
			(size 0 0)
			(layers "F.Cu" "F.Mask" "F.Paste")
			(net "GND")
		)
	)
	(footprint ""
		(layer "F.Cu")
		(at 182.9562 -96.103948 90)
		(property "Reference" "R488"
			(at 0 0 90)
			(layer "F.SilkS")
			(hide yes)
			(effects
				(font
					(size 1.27 1.27)
				)
			)
		)
		(property "Value" ""
			(at 0 0 90)
			(layer "F.Fab")
			(effects
				(font
					(size 1.27 1.27)
				)
			)
		)
		(duplicate_pad_numbers_are_jumpers no)
		(fp_line
			(start 0.7874 -0.4064)
			(end 0.7874 0.4064)
			(stroke
				(width 0.1524)
				(type default)
			)
			(layer "F.SilkS")
		)
		(fp_line
			(start -0.7874 -0.4064)
			(end 0.7874 -0.4064)
			(stroke
				(width 0.1524)
				(type default)
			)
			(layer "F.SilkS")
		)
		(fp_line
			(start 0.7874 0.4064)
			(end -0.7874 0.4064)
			(stroke
				(width 0.1524)
				(type default)
			)
			(layer "F.SilkS")
		)
		(fp_line
			(start -0.7874 0.4064)
			(end -0.7874 -0.4064)
			(stroke
				(width 0.1524)
				(type default)
			)
			(layer "F.SilkS")
		)
		(fp_line
			(start -0.12065 -0.305054)
			(end -0.12065 -0.2794)
			(stroke
				(width 0.1)
				(type default)
			)
			(layer "F.Fab")
		)
		(fp_line
			(start -0.67945 -0.305054)
			(end -0.12065 -0.305054)
			(stroke
				(width 0.1)
				(type default)
			)
			(layer "F.Fab")
		)
		(fp_line
			(start 0.67945 -0.3048)
			(end 0.67945 0.3048)
			(stroke
				(width 0.1)
				(type default)
			)
			(layer "F.Fab")
		)
		(fp_line
			(start 0.12065 -0.3048)
			(end 0.67945 -0.3048)
			(stroke
				(width 0.1)
				(type default)
			)
			(layer "F.Fab")
		)
		(fp_line
			(start 0.12065 -0.2794)
			(end 0.12065 -0.3048)
			(stroke
				(width 0.1)
				(type default)
			)
			(layer "F.Fab")
		)
		(fp_line
			(start -0.12065 -0.2794)
			(end 0.12065 -0.2794)
			(stroke
				(width 0.1)
				(type default)
			)
			(layer "F.Fab")
		)
		(fp_line
			(start 0.120396 0.2794)
			(end -0.12065 0.2794)
			(stroke
				(width 0.1)
				(type default)
			)
			(layer "F.Fab")
		)
		(fp_line
			(start -0.12065 0.2794)
			(end -0.12065 0.3048)
			(stroke
				(width 0.1)
				(type default)
			)
			(layer "F.Fab")
		)
		(fp_line
			(start 0.67945 0.3048)
			(end 0.120396 0.3048)
			(stroke
				(width 0.1)
				(type default)
			)
			(layer "F.Fab")
		)
		(fp_line
			(start 0.120396 0.3048)
			(end 0.120396 0.2794)
			(stroke
				(width 0.1)
				(type default)
			)
			(layer "F.Fab")
		)
		(fp_line
			(start -0.12065 0.3048)
			(end -0.67945 0.3048)
			(stroke
				(width 0.1)
				(type default)
			)
			(layer "F.Fab")
		)
		(fp_line
			(start -0.67945 0.3048)
			(end -0.67945 -0.305054)
			(stroke
				(width 0.1)
				(type default)
			)
			(layer "F.Fab")
		)
		(pad "1" smd circle
			(at -0.40005 0 90)
			(size 0 0)
			(layers "F.Cu" "F.Mask" "F.Paste")
			(net "CPU1_THERMTRIP_N")
		)
		(pad "2" smd circle
			(at 0.40005 0 90)
			(size 0 0)
			(layers "F.Cu" "F.Mask" "F.Paste")
			(net "CPU1_THERMTRIP_R_N")
		)
	)
	(footprint ""
		(layer "F.Cu")
		(at 6.029198 -135.388096)
		(property "Reference" "Y8003"
			(at -1.6002 -3.17373 0)
			(unlocked yes)
			(layer "F.SilkS")
			(effects
				(font
					(size 0.7874 0.5842)
					(thickness 0.1524)
				)
				(justify left)
			)
		)
		(property "Value" ""
			(at 0 0 0)
			(layer "F.Fab")
			(effects
				(font
					(size 1.27 1.27)
				)
			)
		)
		(duplicate_pad_numbers_are_jumpers no)
		(fp_line
			(start -1.5367 -1.9558)
			(end 1.5367 -1.9558)
			(stroke
				(width 0.1524)
				(type default)
			)
			(layer "F.SilkS")
		)
		(fp_line
			(start -1.5367 1.9558)
			(end -1.5367 -1.9558)
			(stroke
				(width 0.1524)
				(type default)
			)
			(layer "F.SilkS")
		)
		(fp_line
			(start 1.5367 -1.9558)
			(end 1.5367 1.9558)
			(stroke
				(width 0.1524)
				(type default)
			)
			(layer "F.SilkS")
		)
		(fp_line
			(start 1.5367 1.9558)
			(end -1.5367 1.9558)
			(stroke
				(width 0.1524)
				(type default)
			)
			(layer "F.SilkS")
		)
		(fp_poly
			(pts
				(xy -1.6129 -1.9558) (xy -0.1778 -1.9558) (xy -0.1778 -2.54) (xy -1.6129 -2.54)
			)
			(stroke
				(width 0)
				(type default)
			)
			(fill yes)
			(layer "F.SilkS")
		)
		(fp_line
			(start -1.299972 -1.649984)
			(end 1.299972 -1.649984)
			(stroke
				(width 0.1)
				(type default)
			)
			(layer "F.Fab")
		)
		(fp_line
			(start -1.299972 1.649984)
			(end -1.299972 -1.649984)
			(stroke
				(width 0.1)
				(type default)
			)
			(layer "F.Fab")
		)
		(fp_line
			(start 1.299972 -1.649984)
			(end 1.299972 1.649984)
			(stroke
				(width 0.1)
				(type default)
			)
			(layer "F.Fab")
		)
		(fp_line
			(start 1.299972 1.649984)
			(end -1.299972 1.649984)
			(stroke
				(width 0.1)
				(type default)
			)
			(layer "F.Fab")
		)
		(fp_poly
			(pts
				(xy -1.6129 -1.9558) (xy -0.1778 -1.9558) (xy -0.1778 -2.54) (xy -1.6129 -2.54)
			)
			(stroke
				(width 0)
				(type default)
			)
			(fill yes)
			(layer "F.Fab")
		)
		(pad "1" smd rect
			(at -0.8001 -1.100074)
			(size 1.2192 1.4224)
			(layers "F.Cu" "F.Mask" "F.Paste")
			(net "CLK_GEN2_XTAL_IN_R")
		)
		(pad "2" smd rect
			(at -0.8001 1.100074)
			(size 1.2192 1.4224)
			(layers "F.Cu" "F.Mask" "F.Paste")
			(net "GND")
		)
		(pad "3" smd rect
			(at 0.8001 1.100074)
			(size 1.2192 1.4224)
			(layers "F.Cu" "F.Mask" "F.Paste")
			(net "CLK_GEN2_XTAL_OUT")
		)
		(pad "4" smd rect
			(at 0.8001 -1.100074)
			(size 1.2192 1.4224)
			(layers "F.Cu" "F.Mask" "F.Paste")
			(net "GND")
		)
	)
	(footprint ""
		(layer "F.Cu")
		(at 220.190822 -56.835802 180)
		(property "Reference" "R3760"
			(at 0 0 180)
			(layer "F.SilkS")
			(hide yes)
			(effects
				(font
					(size 1.27 1.27)
				)
			)
		)
		(property "Value" ""
			(at 0 0 180)
			(layer "F.Fab")
			(effects
				(font
					(size 1.27 1.27)
				)
			)
		)
		(duplicate_pad_numbers_are_jumpers no)
		(fp_line
			(start 0.7874 0.4064)
			(end -0.7874 0.4064)
			(stroke
				(width 0.1524)
				(type default)
			)
			(layer "F.SilkS")
		)
		(fp_line
			(start 0.7874 -0.4064)
			(end 0.7874 0.4064)
			(stroke
				(width 0.1524)
				(type default)
			)
			(layer "F.SilkS")
		)
		(fp_line
			(start -0.7874 0.4064)
			(end -0.7874 -0.4064)
			(stroke
				(width 0.1524)
				(type default)
			)
			(layer "F.SilkS")
		)
		(fp_line
			(start -0.7874 -0.4064)
			(end 0.7874 -0.4064)
			(stroke
				(width 0.1524)
				(type default)
			)
			(layer "F.SilkS")
		)
		(fp_line
			(start 0.67945 0.3048)
			(end 0.120396 0.3048)
			(stroke
				(width 0.1)
				(type default)
			)
			(layer "F.Fab")
		)
		(fp_line
			(start 0.67945 -0.3048)
			(end 0.67945 0.3048)
			(stroke
				(width 0.1)
				(type default)
			)
			(layer "F.Fab")
		)
		(fp_line
			(start 0.12065 -0.2794)
			(end 0.12065 -0.3048)
			(stroke
				(width 0.1)
				(type default)
			)
			(layer "F.Fab")
		)
		(fp_line
			(start 0.12065 -0.3048)
			(end 0.67945 -0.3048)
			(stroke
				(width 0.1)
				(type default)
			)
			(layer "F.Fab")
		)
		(fp_line
			(start 0.120396 0.3048)
			(end 0.120396 0.2794)
			(stroke
				(width 0.1)
				(type default)
			)
			(layer "F.Fab")
		)
		(fp_line
			(start 0.120396 0.2794)
			(end -0.12065 0.2794)
			(stroke
				(width 0.1)
				(type default)
			)
			(layer "F.Fab")
		)
		(fp_line
			(start -0.12065 0.3048)
			(end -0.67945 0.3048)
			(stroke
				(width 0.1)
				(type default)
			)
			(layer "F.Fab")
		)
		(fp_line
			(start -0.12065 0.2794)
			(end -0.12065 0.3048)
			(stroke
				(width 0.1)
				(type default)
			)
			(layer "F.Fab")
		)
		(fp_line
			(start -0.12065 -0.2794)
			(end 0.12065 -0.2794)
			(stroke
				(width 0.1)
				(type default)
			)
			(layer "F.Fab")
		)
		(fp_line
			(start -0.12065 -0.305054)
			(end -0.12065 -0.2794)
			(stroke
				(width 0.1)
				(type default)
			)
			(layer "F.Fab")
		)
		(fp_line
			(start -0.67945 0.3048)
			(end -0.67945 -0.305054)
			(stroke
				(width 0.1)
				(type default)
			)
			(layer "F.Fab")
		)
		(fp_line
			(start -0.67945 -0.305054)
			(end -0.12065 -0.305054)
			(stroke
				(width 0.1)
				(type default)
			)
			(layer "F.Fab")
		)
		(pad "1" smd circle
			(at -0.40005 0 180)
			(size 0 0)
			(layers "F.Cu" "F.Mask" "F.Paste")
			(net "P3V3_E1S_0")
		)
		(pad "2" smd circle
			(at 0.40005 0 180)
			(size 0 0)
			(layers "F.Cu" "F.Mask" "F.Paste")
			(net "VSENSE_P3V3_INA230_2_INN")
		)
	)
	(footprint ""
		(layer "F.Cu")
		(at 184.622694 -409.128722 180)
		(property "Reference" "PC2188"
			(at 0 0 180)
			(layer "F.SilkS")
			(hide yes)
			(effects
				(font
					(size 1.27 1.27)
				)
			)
		)
		(property "Value" ""
			(at 0 0 180)
			(layer "F.Fab")
			(effects
				(font
					(size 1.27 1.27)
				)
			)
		)
		(duplicate_pad_numbers_are_jumpers no)
		(fp_line
			(start 0.7874 0.4064)
			(end -0.7874 0.4064)
			(stroke
				(width 0.1524)
				(type default)
			)
			(layer "F.SilkS")
		)
		(fp_line
			(start 0.7874 -0.4064)
			(end 0.7874 0.4064)
			(stroke
				(width 0.1524)
				(type default)
			)
			(layer "F.SilkS")
		)
		(fp_line
			(start -0.7874 0.4064)
			(end -0.7874 -0.4064)
			(stroke
				(width 0.1524)
				(type default)
			)
			(layer "F.SilkS")
		)
		(fp_line
			(start -0.7874 -0.4064)
			(end 0.7874 -0.4064)
			(stroke
				(width 0.1524)
				(type default)
			)
			(layer "F.SilkS")
		)
		(fp_line
			(start 0.67945 0.3048)
			(end 0.120396 0.3048)
			(stroke
				(width 0.1)
				(type default)
			)
			(layer "F.Fab")
		)
		(fp_line
			(start 0.67945 -0.3048)
			(end 0.67945 0.3048)
			(stroke
				(width 0.1)
				(type default)
			)
			(layer "F.Fab")
		)
		(fp_line
			(start 0.12065 -0.2794)
			(end 0.12065 -0.3048)
			(stroke
				(width 0.1)
				(type default)
			)
			(layer "F.Fab")
		)
		(fp_line
			(start 0.12065 -0.3048)
			(end 0.67945 -0.3048)
			(stroke
				(width 0.1)
				(type default)
			)
			(layer "F.Fab")
		)
		(fp_line
			(start 0.120396 0.3048)
			(end 0.120396 0.2794)
			(stroke
				(width 0.1)
				(type default)
			)
			(layer "F.Fab")
		)
		(fp_line
			(start 0.120396 0.2794)
			(end -0.12065 0.2794)
			(stroke
				(width 0.1)
				(type default)
			)
			(layer "F.Fab")
		)
		(fp_line
			(start -0.12065 0.3048)
			(end -0.67945 0.3048)
			(stroke
				(width 0.1)
				(type default)
			)
			(layer "F.Fab")
		)
		(fp_line
			(start -0.12065 0.2794)
			(end -0.12065 0.3048)
			(stroke
				(width 0.1)
				(type default)
			)
			(layer "F.Fab")
		)
		(fp_line
			(start -0.12065 -0.2794)
			(end 0.12065 -0.2794)
			(stroke
				(width 0.1)
				(type default)
			)
			(layer "F.Fab")
		)
		(fp_line
			(start -0.12065 -0.305054)
			(end -0.12065 -0.2794)
			(stroke
				(width 0.1)
				(type default)
			)
			(layer "F.Fab")
		)
		(fp_line
			(start -0.67945 0.3048)
			(end -0.67945 -0.305054)
			(stroke
				(width 0.1)
				(type default)
			)
			(layer "F.Fab")
		)
		(fp_line
			(start -0.67945 -0.305054)
			(end -0.12065 -0.305054)
			(stroke
				(width 0.1)
				(type default)
			)
			(layer "F.Fab")
		)
		(pad "1" smd circle
			(at -0.40005 0 180)
			(size 0 0)
			(layers "F.Cu" "F.Mask" "F.Paste")
			(net "P12V_PSU")
		)
		(pad "2" smd circle
			(at 0.40005 0 180)
			(size 0 0)
			(layers "F.Cu" "F.Mask" "F.Paste")
			(net "GND")
		)
	)
	(footprint ""
		(layer "F.Cu")
		(at 393.363958 -325.675752)
		(property "Reference" "R213"
			(at 0 0 0)
			(layer "F.SilkS")
			(hide yes)
			(effects
				(font
					(size 1.27 1.27)
				)
			)
		)
		(property "Value" ""
			(at 0 0 0)
			(layer "F.Fab")
			(effects
				(font
					(size 1.27 1.27)
				)
			)
		)
		(duplicate_pad_numbers_are_jumpers no)
		(fp_line
			(start -0.7874 -0.4064)
			(end 0.7874 -0.4064)
			(stroke
				(width 0.1524)
				(type default)
			)
			(layer "F.SilkS")
		)
		(fp_line
			(start -0.7874 0.4064)
			(end -0.7874 -0.4064)
			(stroke
				(width 0.1524)
				(type default)
			)
			(layer "F.SilkS")
		)
		(fp_line
			(start 0.7874 -0.4064)
			(end 0.7874 0.4064)
			(stroke
				(width 0.1524)
				(type default)
			)
			(layer "F.SilkS")
		)
		(fp_line
			(start 0.7874 0.4064)
			(end -0.7874 0.4064)
			(stroke
				(width 0.1524)
				(type default)
			)
			(layer "F.SilkS")
		)
		(fp_line
			(start -0.67945 -0.305054)
			(end -0.12065 -0.305054)
			(stroke
				(width 0.1)
				(type default)
			)
			(layer "F.Fab")
		)
		(fp_line
			(start -0.67945 0.3048)
			(end -0.67945 -0.305054)
			(stroke
				(width 0.1)
				(type default)
			)
			(layer "F.Fab")
		)
		(fp_line
			(start -0.12065 -0.305054)
			(end -0.12065 -0.2794)
			(stroke
				(width 0.1)
				(type default)
			)
			(layer "F.Fab")
		)
		(fp_line
			(start -0.12065 -0.2794)
			(end 0.12065 -0.2794)
			(stroke
				(width 0.1)
				(type default)
			)
			(layer "F.Fab")
		)
		(fp_line
			(start -0.12065 0.2794)
			(end -0.12065 0.3048)
			(stroke
				(width 0.1)
				(type default)
			)
			(layer "F.Fab")
		)
		(fp_line
			(start -0.12065 0.3048)
			(end -0.67945 0.3048)
			(stroke
				(width 0.1)
				(type default)
			)
			(layer "F.Fab")
		)
		(fp_line
			(start 0.120396 0.2794)
			(end -0.12065 0.2794)
			(stroke
				(width 0.1)
				(type default)
			)
			(layer "F.Fab")
		)
		(fp_line
			(start 0.120396 0.3048)
			(end 0.120396 0.2794)
			(stroke
				(width 0.1)
				(type default)
			)
			(layer "F.Fab")
		)
		(fp_line
			(start 0.12065 -0.3048)
			(end 0.67945 -0.3048)
			(stroke
				(width 0.1)
				(type default)
			)
			(layer "F.Fab")
		)
		(fp_line
			(start 0.12065 -0.2794)
			(end 0.12065 -0.3048)
			(stroke
				(width 0.1)
				(type default)
			)
			(layer "F.Fab")
		)
		(fp_line
			(start 0.67945 -0.3048)
			(end 0.67945 0.3048)
			(stroke
				(width 0.1)
				(type default)
			)
			(layer "F.Fab")
		)
		(fp_line
			(start 0.67945 0.3048)
			(end 0.120396 0.3048)
			(stroke
				(width 0.1)
				(type default)
			)
			(layer "F.Fab")
		)
		(pad "1" smd circle
			(at -0.40005 0)
			(size 0 0)
			(layers "F.Cu" "F.Mask" "F.Paste")
			(net "SMB_CPU_5_R_SDA")
		)
		(pad "2" smd circle
			(at 0.40005 0)
			(size 0 0)
			(layers "F.Cu" "F.Mask" "F.Paste")
			(net "SMB_CPU_5_SDA")
		)
	)
	(footprint ""
		(layer "F.Cu")
		(at 187.28436 -29.77769 -90)
		(property "Reference" "PC2230"
			(at 0 0 270)
			(layer "F.SilkS")
			(hide yes)
			(effects
				(font
					(size 1.27 1.27)
				)
			)
		)
		(property "Value" ""
			(at 0 0 270)
			(layer "F.Fab")
			(effects
				(font
					(size 1.27 1.27)
				)
			)
		)
		(duplicate_pad_numbers_are_jumpers no)
		(fp_line
			(start -0.7874 0.4064)
			(end -0.7874 -0.4064)
			(stroke
				(width 0.1524)
				(type default)
			)
			(layer "F.SilkS")
		)
		(fp_line
			(start 0.7874 0.4064)
			(end -0.7874 0.4064)
			(stroke
				(width 0.1524)
				(type default)
			)
			(layer "F.SilkS")
		)
		(fp_line
			(start -0.7874 -0.4064)
			(end 0.7874 -0.4064)
			(stroke
				(width 0.1524)
				(type default)
			)
			(layer "F.SilkS")
		)
		(fp_line
			(start 0.7874 -0.4064)
			(end 0.7874 0.4064)
			(stroke
				(width 0.1524)
				(type default)
			)
			(layer "F.SilkS")
		)
		(fp_line
			(start -0.67945 0.3048)
			(end -0.67945 -0.305054)
			(stroke
				(width 0.1)
				(type default)
			)
			(layer "F.Fab")
		)
		(fp_line
			(start -0.12065 0.3048)
			(end -0.67945 0.3048)
			(stroke
				(width 0.1)
				(type default)
			)
			(layer "F.Fab")
		)
		(fp_line
			(start 0.120396 0.3048)
			(end 0.120396 0.2794)
			(stroke
				(width 0.1)
				(type default)
			)
			(layer "F.Fab")
		)
		(fp_line
			(start 0.67945 0.3048)
			(end 0.120396 0.3048)
			(stroke
				(width 0.1)
				(type default)
			)
			(layer "F.Fab")
		)
		(fp_line
			(start -0.12065 0.2794)
			(end -0.12065 0.3048)
			(stroke
				(width 0.1)
				(type default)
			)
			(layer "F.Fab")
		)
		(fp_line
			(start 0.120396 0.2794)
			(end -0.12065 0.2794)
			(stroke
				(width 0.1)
				(type default)
			)
			(layer "F.Fab")
		)
		(fp_line
			(start -0.12065 -0.2794)
			(end 0.12065 -0.2794)
			(stroke
				(width 0.1)
				(type default)
			)
			(layer "F.Fab")
		)
		(fp_line
			(start 0.12065 -0.2794)
			(end 0.12065 -0.3048)
			(stroke
				(width 0.1)
				(type default)
			)
			(layer "F.Fab")
		)
		(fp_line
			(start 0.12065 -0.3048)
			(end 0.67945 -0.3048)
			(stroke
				(width 0.1)
				(type default)
			)
			(layer "F.Fab")
		)
		(fp_line
			(start 0.67945 -0.3048)
			(end 0.67945 0.3048)
			(stroke
				(width 0.1)
				(type default)
			)
			(layer "F.Fab")
		)
		(fp_line
			(start -0.67945 -0.305054)
			(end -0.12065 -0.305054)
			(stroke
				(width 0.1)
				(type default)
			)
			(layer "F.Fab")
		)
		(fp_line
			(start -0.12065 -0.305054)
			(end -0.12065 -0.2794)
			(stroke
				(width 0.1)
				(type default)
			)
			(layer "F.Fab")
		)
		(pad "1" smd circle
			(at -0.40005 0 270)
			(size 0 0)
			(layers "F.Cu" "F.Mask" "F.Paste")
			(net "P12V_AUX")
		)
		(pad "2" smd circle
			(at 0.40005 0 270)
			(size 0 0)
			(layers "F.Cu" "F.Mask" "F.Paste")
			(net "GND")
		)
	)
	(footprint ""
		(layer "F.Cu")
		(at 89.809828 -141.42466 90)
		(property "Reference" "R8167"
			(at 0 0 90)
			(layer "F.SilkS")
			(hide yes)
			(effects
				(font
					(size 1.27 1.27)
				)
			)
		)
		(property "Value" ""
			(at 0 0 90)
			(layer "F.Fab")
			(effects
				(font
					(size 1.27 1.27)
				)
			)
		)
		(duplicate_pad_numbers_are_jumpers no)
		(fp_line
			(start 0.7874 -0.4064)
			(end 0.7874 0.4064)
			(stroke
				(width 0.1524)
				(type default)
			)
			(layer "F.SilkS")
		)
		(fp_line
			(start -0.7874 -0.4064)
			(end 0.7874 -0.4064)
			(stroke
				(width 0.1524)
				(type default)
			)
			(layer "F.SilkS")
		)
		(fp_line
			(start 0.7874 0.4064)
			(end -0.7874 0.4064)
			(stroke
				(width 0.1524)
				(type default)
			)
			(layer "F.SilkS")
		)
		(fp_line
			(start -0.7874 0.4064)
			(end -0.7874 -0.4064)
			(stroke
				(width 0.1524)
				(type default)
			)
			(layer "F.SilkS")
		)
		(fp_line
			(start -0.12065 -0.305054)
			(end -0.12065 -0.2794)
			(stroke
				(width 0.1)
				(type default)
			)
			(layer "F.Fab")
		)
		(fp_line
			(start -0.67945 -0.305054)
			(end -0.12065 -0.305054)
			(stroke
				(width 0.1)
				(type default)
			)
			(layer "F.Fab")
		)
		(fp_line
			(start 0.67945 -0.3048)
			(end 0.67945 0.3048)
			(stroke
				(width 0.1)
				(type default)
			)
			(layer "F.Fab")
		)
		(fp_line
			(start 0.12065 -0.3048)
			(end 0.67945 -0.3048)
			(stroke
				(width 0.1)
				(type default)
			)
			(layer "F.Fab")
		)
		(fp_line
			(start 0.12065 -0.2794)
			(end 0.12065 -0.3048)
			(stroke
				(width 0.1)
				(type default)
			)
			(layer "F.Fab")
		)
		(fp_line
			(start -0.12065 -0.2794)
			(end 0.12065 -0.2794)
			(stroke
				(width 0.1)
				(type default)
			)
			(layer "F.Fab")
		)
		(fp_line
			(start 0.120396 0.2794)
			(end -0.12065 0.2794)
			(stroke
				(width 0.1)
				(type default)
			)
			(layer "F.Fab")
		)
		(fp_line
			(start -0.12065 0.2794)
			(end -0.12065 0.3048)
			(stroke
				(width 0.1)
				(type default)
			)
			(layer "F.Fab")
		)
		(fp_line
			(start 0.67945 0.3048)
			(end 0.120396 0.3048)
			(stroke
				(width 0.1)
				(type default)
			)
			(layer "F.Fab")
		)
		(fp_line
			(start 0.120396 0.3048)
			(end 0.120396 0.2794)
			(stroke
				(width 0.1)
				(type default)
			)
			(layer "F.Fab")
		)
		(fp_line
			(start -0.12065 0.3048)
			(end -0.67945 0.3048)
			(stroke
				(width 0.1)
				(type default)
			)
			(layer "F.Fab")
		)
		(fp_line
			(start -0.67945 0.3048)
			(end -0.67945 -0.305054)
			(stroke
				(width 0.1)
				(type default)
			)
			(layer "F.Fab")
		)
		(pad "1" smd circle
			(at -0.40005 0 90)
			(size 0 0)
			(layers "F.Cu" "F.Mask" "F.Paste")
			(net "P3V3_AUX")
		)
		(pad "2" smd circle
			(at 0.40005 0 90)
			(size 0 0)
			(layers "F.Cu" "F.Mask" "F.Paste")
			(net "PWRGD_PVDDCR_CPU0_P1_R")
		)
	)
	(footprint ""
		(layer "F.Cu")
		(at 409.478226 -137.854182)
		(property "Reference" "R6097"
			(at 0 0 0)
			(layer "F.SilkS")
			(hide yes)
			(effects
				(font
					(size 1.27 1.27)
				)
			)
		)
		(property "Value" ""
			(at 0 0 0)
			(layer "F.Fab")
			(effects
				(font
					(size 1.27 1.27)
				)
			)
		)
		(duplicate_pad_numbers_are_jumpers no)
		(fp_line
			(start -0.7874 -0.4064)
			(end 0.7874 -0.4064)
			(stroke
				(width 0.1524)
				(type default)
			)
			(layer "F.SilkS")
		)
		(fp_line
			(start -0.7874 0.4064)
			(end -0.7874 -0.4064)
			(stroke
				(width 0.1524)
				(type default)
			)
			(layer "F.SilkS")
		)
		(fp_line
			(start 0.7874 -0.4064)
			(end 0.7874 0.4064)
			(stroke
				(width 0.1524)
				(type default)
			)
			(layer "F.SilkS")
		)
		(fp_line
			(start 0.7874 0.4064)
			(end -0.7874 0.4064)
			(stroke
				(width 0.1524)
				(type default)
			)
			(layer "F.SilkS")
		)
		(fp_line
			(start -0.67945 -0.305054)
			(end -0.12065 -0.305054)
			(stroke
				(width 0.1)
				(type default)
			)
			(layer "F.Fab")
		)
		(fp_line
			(start -0.67945 0.3048)
			(end -0.67945 -0.305054)
			(stroke
				(width 0.1)
				(type default)
			)
			(layer "F.Fab")
		)
		(fp_line
			(start -0.12065 -0.305054)
			(end -0.12065 -0.2794)
			(stroke
				(width 0.1)
				(type default)
			)
			(layer "F.Fab")
		)
		(fp_line
			(start -0.12065 -0.2794)
			(end 0.12065 -0.2794)
			(stroke
				(width 0.1)
				(type default)
			)
			(layer "F.Fab")
		)
		(fp_line
			(start -0.12065 0.2794)
			(end -0.12065 0.3048)
			(stroke
				(width 0.1)
				(type default)
			)
			(layer "F.Fab")
		)
		(fp_line
			(start -0.12065 0.3048)
			(end -0.67945 0.3048)
			(stroke
				(width 0.1)
				(type default)
			)
			(layer "F.Fab")
		)
		(fp_line
			(start 0.120396 0.2794)
			(end -0.12065 0.2794)
			(stroke
				(width 0.1)
				(type default)
			)
			(layer "F.Fab")
		)
		(fp_line
			(start 0.120396 0.3048)
			(end 0.120396 0.2794)
			(stroke
				(width 0.1)
				(type default)
			)
			(layer "F.Fab")
		)
		(fp_line
			(start 0.12065 -0.3048)
			(end 0.67945 -0.3048)
			(stroke
				(width 0.1)
				(type default)
			)
			(layer "F.Fab")
		)
		(fp_line
			(start 0.12065 -0.2794)
			(end 0.12065 -0.3048)
			(stroke
				(width 0.1)
				(type default)
			)
			(layer "F.Fab")
		)
		(fp_line
			(start 0.67945 -0.3048)
			(end 0.67945 0.3048)
			(stroke
				(width 0.1)
				(type default)
			)
			(layer "F.Fab")
		)
		(fp_line
			(start 0.67945 0.3048)
			(end 0.120396 0.3048)
			(stroke
				(width 0.1)
				(type default)
			)
			(layer "F.Fab")
		)
		(pad "1" smd circle
			(at -0.40005 0)
			(size 0 0)
			(layers "F.Cu" "F.Mask" "F.Paste")
			(net "MB0_P12V_STBY_PWRGD")
		)
		(pad "2" smd circle
			(at 0.40005 0)
			(size 0 0)
			(layers "F.Cu" "F.Mask" "F.Paste")
			(net "P5V_AUX_EN")
		)
	)
	(footprint ""
		(layer "F.Cu")
		(at 266.971526 -97.780856 180)
		(property "Reference" "U149"
			(at 1.889252 -3.344164 0)
			(unlocked yes)
			(layer "F.SilkS")
			(effects
				(font
					(size 0.7874 0.5842)
					(thickness 0.1524)
				)
				(justify left)
			)
		)
		(property "Value" ""
			(at 0 0 180)
			(layer "F.Fab")
			(effects
				(font
					(size 1.27 1.27)
				)
			)
		)
		(duplicate_pad_numbers_are_jumpers no)
		(fp_line
			(start 1.868932 2.549906)
			(end 1.868932 -2.549906)
			(stroke
				(width 0.1524)
				(type default)
			)
			(layer "F.SilkS")
		)
		(fp_line
			(start 1.868932 -2.549906)
			(end 1.025906 -2.549906)
			(stroke
				(width 0.1524)
				(type default)
			)
			(layer "F.SilkS")
		)
		(fp_line
			(start 1.025906 -2.549906)
			(end 0 -1.524)
			(stroke
				(width 0.1524)
				(type default)
			)
			(layer "F.SilkS")
		)
		(fp_line
			(start 0 -1.524)
			(end -1.025906 -2.549906)
			(stroke
				(width 0.1524)
				(type default)
			)
			(layer "F.SilkS")
		)
		(fp_line
			(start -1.025906 -2.549906)
			(end -1.868932 -2.549906)
			(stroke
				(width 0.1524)
				(type default)
			)
			(layer "F.SilkS")
		)
		(fp_line
			(start -1.868932 2.549906)
			(end 1.868932 2.549906)
			(stroke
				(width 0.1524)
				(type default)
			)
			(layer "F.SilkS")
		)
		(fp_line
			(start -1.868932 -2.549906)
			(end -1.868932 2.549906)
			(stroke
				(width 0.1524)
				(type default)
			)
			(layer "F.SilkS")
		)
		(fp_poly
			(pts
				(xy -3.7592 -2.295398) (xy -4.7752 -1.787398) (xy -4.7752 -2.803398)
			)
			(stroke
				(width 0)
				(type default)
			)
			(fill yes)
			(layer "F.SilkS")
		)
		(fp_line
			(start 2.249932 2.549906)
			(end 2.249932 -2.549906)
			(stroke
				(width 0.1)
				(type default)
			)
			(layer "F.Fab")
		)
		(fp_line
			(start 2.249932 -2.549906)
			(end -2.249932 -2.549906)
			(stroke
				(width 0.1)
				(type default)
			)
			(layer "F.Fab")
		)
		(fp_line
			(start -2.249932 2.549906)
			(end 2.249932 2.549906)
			(stroke
				(width 0.1)
				(type default)
			)
			(layer "F.Fab")
		)
		(fp_line
			(start -2.249932 -2.549906)
			(end -2.249932 2.549906)
			(stroke
				(width 0.1)
				(type default)
			)
			(layer "F.Fab")
		)
		(fp_poly
			(pts
				(xy -4.7752 -1.787398) (xy -4.7752 -2.803398) (xy -3.7592 -2.295398)
			)
			(stroke
				(width 0)
				(type default)
			)
			(fill yes)
			(layer "F.Fab")
		)
		(pad "1" smd rect
			(at -2.800096 -2.275078 90)
			(size 0.3556 1.6002)
			(layers "F.Cu" "F.Mask" "F.Paste")
			(net "PVDD18_S5_P0")
		)
		(pad "2" smd rect
			(at -2.800096 -1.625092 90)
			(size 0.3556 1.6002)
			(layers "F.Cu" "F.Mask" "F.Paste")
			(net "PVDD18_S5_P0")
		)
		(pad "3" smd rect
			(at -2.800096 -0.975106 90)
			(size 0.3556 1.6002)
			(layers "F.Cu" "F.Mask" "F.Paste")
			(net "HDT_HDR_TCK")
		)
		(pad "4" smd rect
			(at -2.800096 -0.32512 90)
			(size 0.3556 1.6002)
			(layers "F.Cu" "F.Mask" "F.Paste")
			(net "HDT_HDR_TMS")
		)
		(pad "5" smd rect
			(at -2.800096 0.32512 90)
			(size 0.3556 1.6002)
			(layers "F.Cu" "F.Mask" "F.Paste")
			(net "HDT_HDR_TRST_N")
		)
		(pad "6" smd rect
			(at -2.800096 0.975106 90)
			(size 0.3556 1.6002)
			(layers "F.Cu" "F.Mask" "F.Paste")
			(net "HDT_HDR_DBREQ_N")
		)
		(pad "7" smd rect
			(at -2.800096 1.625092 90)
			(size 0.3556 1.6002)
			(layers "F.Cu" "F.Mask" "F.Paste")
			(net "PVDD18_S5_P0")
		)
		(pad "8" smd rect
			(at -2.800096 2.275078 90)
			(size 0.3556 1.6002)
			(layers "F.Cu" "F.Mask" "F.Paste")
			(net "PVDD18_S5_P0")
		)
		(pad "9" smd rect
			(at 2.800096 2.275078 90)
			(size 0.3556 1.6002)
			(layers "F.Cu" "F.Mask" "F.Paste")
			(net "JTAG_BMC_R_D_OE")
		)
		(pad "10" smd rect
			(at 2.800096 1.625092 90)
			(size 0.3556 1.6002)
			(layers "F.Cu" "F.Mask" "F.Paste")
			(net "GND")
		)
		(pad "11" smd rect
			(at 2.800096 0.975106 90)
			(size 0.3556 1.6002)
			(layers "F.Cu" "F.Mask" "F.Paste")
			(net "JTAG_DBREQ_R_N")
		)
		(pad "12" smd rect
			(at 2.800096 0.32512 90)
			(size 0.3556 1.6002)
			(layers "F.Cu" "F.Mask" "F.Paste")
			(net "JTAG_TRST_R_N")
		)
		(pad "13" smd rect
			(at 2.800096 -0.32512 90)
			(size 0.3556 1.6002)
			(layers "F.Cu" "F.Mask" "F.Paste")
			(net "JTAG_TMS_R")
		)
		(pad "14" smd rect
			(at 2.800096 -0.975106 90)
			(size 0.3556 1.6002)
			(layers "F.Cu" "F.Mask" "F.Paste")
			(net "JTAG_TCK_R")
		)
		(pad "15" smd rect
			(at 2.800096 -1.625092 90)
			(size 0.3556 1.6002)
			(layers "F.Cu" "F.Mask" "F.Paste")
			(net "PVDD18_S5_P0")
		)
		(pad "16" smd rect
			(at 2.800096 -2.275078 90)
			(size 0.3556 1.6002)
			(layers "F.Cu" "F.Mask" "F.Paste")
			(net "PVDD18_S5_P0")
		)
	)
	(footprint ""
		(layer "F.Cu")
		(at 401.51812 -180.175408)
		(property "Reference" "PC185"
			(at 0 0 0)
			(layer "F.SilkS")
			(hide yes)
			(effects
				(font
					(size 1.27 1.27)
				)
			)
		)
		(property "Value" ""
			(at 0 0 0)
			(layer "F.Fab")
			(effects
				(font
					(size 1.27 1.27)
				)
			)
		)
		(duplicate_pad_numbers_are_jumpers no)
		(fp_line
			(start -0.7874 -0.4064)
			(end 0.7874 -0.4064)
			(stroke
				(width 0.1524)
				(type default)
			)
			(layer "F.SilkS")
		)
		(fp_line
			(start -0.7874 0.4064)
			(end -0.7874 -0.4064)
			(stroke
				(width 0.1524)
				(type default)
			)
			(layer "F.SilkS")
		)
		(fp_line
			(start 0.7874 -0.4064)
			(end 0.7874 0.4064)
			(stroke
				(width 0.1524)
				(type default)
			)
			(layer "F.SilkS")
		)
		(fp_line
			(start 0.7874 0.4064)
			(end -0.7874 0.4064)
			(stroke
				(width 0.1524)
				(type default)
			)
			(layer "F.SilkS")
		)
		(fp_line
			(start -0.67945 -0.305054)
			(end -0.12065 -0.305054)
			(stroke
				(width 0.1)
				(type default)
			)
			(layer "F.Fab")
		)
		(fp_line
			(start -0.67945 0.3048)
			(end -0.67945 -0.305054)
			(stroke
				(width 0.1)
				(type default)
			)
			(layer "F.Fab")
		)
		(fp_line
			(start -0.12065 -0.305054)
			(end -0.12065 -0.2794)
			(stroke
				(width 0.1)
				(type default)
			)
			(layer "F.Fab")
		)
		(fp_line
			(start -0.12065 -0.2794)
			(end 0.12065 -0.2794)
			(stroke
				(width 0.1)
				(type default)
			)
			(layer "F.Fab")
		)
		(fp_line
			(start -0.12065 0.2794)
			(end -0.12065 0.3048)
			(stroke
				(width 0.1)
				(type default)
			)
			(layer "F.Fab")
		)
		(fp_line
			(start -0.12065 0.3048)
			(end -0.67945 0.3048)
			(stroke
				(width 0.1)
				(type default)
			)
			(layer "F.Fab")
		)
		(fp_line
			(start 0.120396 0.2794)
			(end -0.12065 0.2794)
			(stroke
				(width 0.1)
				(type default)
			)
			(layer "F.Fab")
		)
		(fp_line
			(start 0.120396 0.3048)
			(end 0.120396 0.2794)
			(stroke
				(width 0.1)
				(type default)
			)
			(layer "F.Fab")
		)
		(fp_line
			(start 0.12065 -0.3048)
			(end 0.67945 -0.3048)
			(stroke
				(width 0.1)
				(type default)
			)
			(layer "F.Fab")
		)
		(fp_line
			(start 0.12065 -0.2794)
			(end 0.12065 -0.3048)
			(stroke
				(width 0.1)
				(type default)
			)
			(layer "F.Fab")
		)
		(fp_line
			(start 0.67945 -0.3048)
			(end 0.67945 0.3048)
			(stroke
				(width 0.1)
				(type default)
			)
			(layer "F.Fab")
		)
		(fp_line
			(start 0.67945 0.3048)
			(end 0.120396 0.3048)
			(stroke
				(width 0.1)
				(type default)
			)
			(layer "F.Fab")
		)
		(pad "1" smd circle
			(at -0.40005 0)
			(size 0 0)
			(layers "F.Cu" "F.Mask" "F.Paste")
			(net "SW_PVDDCR_SOC_P0_SW1")
		)
		(pad "2" smd circle
			(at 0.40005 0)
			(size 0 0)
			(layers "F.Cu" "F.Mask" "F.Paste")
			(net "SW_PVDDCR_SOC_P0_SW1_RC")
		)
	)
	(footprint ""
		(layer "F.Cu")
		(at 86.311994 -31.667958 90)
		(property "Reference" "R4602"
			(at 0 0 90)
			(layer "F.SilkS")
			(hide yes)
			(effects
				(font
					(size 1.27 1.27)
				)
			)
		)
		(property "Value" ""
			(at 0 0 90)
			(layer "F.Fab")
			(effects
				(font
					(size 1.27 1.27)
				)
			)
		)
		(duplicate_pad_numbers_are_jumpers no)
		(fp_line
			(start 0.7874 -0.4064)
			(end 0.7874 0.4064)
			(stroke
				(width 0.1524)
				(type default)
			)
			(layer "F.SilkS")
		)
		(fp_line
			(start -0.7874 -0.4064)
			(end 0.7874 -0.4064)
			(stroke
				(width 0.1524)
				(type default)
			)
			(layer "F.SilkS")
		)
		(fp_line
			(start 0.7874 0.4064)
			(end -0.7874 0.4064)
			(stroke
				(width 0.1524)
				(type default)
			)
			(layer "F.SilkS")
		)
		(fp_line
			(start -0.7874 0.4064)
			(end -0.7874 -0.4064)
			(stroke
				(width 0.1524)
				(type default)
			)
			(layer "F.SilkS")
		)
		(fp_line
			(start -0.12065 -0.305054)
			(end -0.12065 -0.2794)
			(stroke
				(width 0.1)
				(type default)
			)
			(layer "F.Fab")
		)
		(fp_line
			(start -0.67945 -0.305054)
			(end -0.12065 -0.305054)
			(stroke
				(width 0.1)
				(type default)
			)
			(layer "F.Fab")
		)
		(fp_line
			(start 0.67945 -0.3048)
			(end 0.67945 0.3048)
			(stroke
				(width 0.1)
				(type default)
			)
			(layer "F.Fab")
		)
		(fp_line
			(start 0.12065 -0.3048)
			(end 0.67945 -0.3048)
			(stroke
				(width 0.1)
				(type default)
			)
			(layer "F.Fab")
		)
		(fp_line
			(start 0.12065 -0.2794)
			(end 0.12065 -0.3048)
			(stroke
				(width 0.1)
				(type default)
			)
			(layer "F.Fab")
		)
		(fp_line
			(start -0.12065 -0.2794)
			(end 0.12065 -0.2794)
			(stroke
				(width 0.1)
				(type default)
			)
			(layer "F.Fab")
		)
		(fp_line
			(start 0.120396 0.2794)
			(end -0.12065 0.2794)
			(stroke
				(width 0.1)
				(type default)
			)
			(layer "F.Fab")
		)
		(fp_line
			(start -0.12065 0.2794)
			(end -0.12065 0.3048)
			(stroke
				(width 0.1)
				(type default)
			)
			(layer "F.Fab")
		)
		(fp_line
			(start 0.67945 0.3048)
			(end 0.120396 0.3048)
			(stroke
				(width 0.1)
				(type default)
			)
			(layer "F.Fab")
		)
		(fp_line
			(start 0.120396 0.3048)
			(end 0.120396 0.2794)
			(stroke
				(width 0.1)
				(type default)
			)
			(layer "F.Fab")
		)
		(fp_line
			(start -0.12065 0.3048)
			(end -0.67945 0.3048)
			(stroke
				(width 0.1)
				(type default)
			)
			(layer "F.Fab")
		)
		(fp_line
			(start -0.67945 0.3048)
			(end -0.67945 -0.305054)
			(stroke
				(width 0.1)
				(type default)
			)
			(layer "F.Fab")
		)
		(pad "1" smd circle
			(at -0.40005 0 90)
			(size 0 0)
			(layers "F.Cu" "F.Mask" "F.Paste")
			(net "CLK_50M_NCSI_OCP_V3_2_ISO")
		)
		(pad "2" smd circle
			(at 0.40005 0 90)
			(size 0 0)
			(layers "F.Cu" "F.Mask" "F.Paste")
			(net "CLK_50M_NCSI_OCP_V3_2_ISO_R")
		)
	)
	(footprint ""
		(layer "F.Cu")
		(at 297.330368 -148.493988)
		(property "Reference" "R5007"
			(at 0 0 0)
			(layer "F.SilkS")
			(hide yes)
			(effects
				(font
					(size 1.27 1.27)
				)
			)
		)
		(property "Value" ""
			(at 0 0 0)
			(layer "F.Fab")
			(effects
				(font
					(size 1.27 1.27)
				)
			)
		)
		(duplicate_pad_numbers_are_jumpers no)
		(fp_line
			(start -0.7874 -0.4064)
			(end 0.7874 -0.4064)
			(stroke
				(width 0.1524)
				(type default)
			)
			(layer "F.SilkS")
		)
		(fp_line
			(start -0.7874 0.4064)
			(end -0.7874 -0.4064)
			(stroke
				(width 0.1524)
				(type default)
			)
			(layer "F.SilkS")
		)
		(fp_line
			(start 0.7874 -0.4064)
			(end 0.7874 0.4064)
			(stroke
				(width 0.1524)
				(type default)
			)
			(layer "F.SilkS")
		)
		(fp_line
			(start 0.7874 0.4064)
			(end -0.7874 0.4064)
			(stroke
				(width 0.1524)
				(type default)
			)
			(layer "F.SilkS")
		)
		(fp_line
			(start -0.67945 -0.305054)
			(end -0.12065 -0.305054)
			(stroke
				(width 0.1)
				(type default)
			)
			(layer "F.Fab")
		)
		(fp_line
			(start -0.67945 0.3048)
			(end -0.67945 -0.305054)
			(stroke
				(width 0.1)
				(type default)
			)
			(layer "F.Fab")
		)
		(fp_line
			(start -0.12065 -0.305054)
			(end -0.12065 -0.2794)
			(stroke
				(width 0.1)
				(type default)
			)
			(layer "F.Fab")
		)
		(fp_line
			(start -0.12065 -0.2794)
			(end 0.12065 -0.2794)
			(stroke
				(width 0.1)
				(type default)
			)
			(layer "F.Fab")
		)
		(fp_line
			(start -0.12065 0.2794)
			(end -0.12065 0.3048)
			(stroke
				(width 0.1)
				(type default)
			)
			(layer "F.Fab")
		)
		(fp_line
			(start -0.12065 0.3048)
			(end -0.67945 0.3048)
			(stroke
				(width 0.1)
				(type default)
			)
			(layer "F.Fab")
		)
		(fp_line
			(start 0.120396 0.2794)
			(end -0.12065 0.2794)
			(stroke
				(width 0.1)
				(type default)
			)
			(layer "F.Fab")
		)
		(fp_line
			(start 0.120396 0.3048)
			(end 0.120396 0.2794)
			(stroke
				(width 0.1)
				(type default)
			)
			(layer "F.Fab")
		)
		(fp_line
			(start 0.12065 -0.3048)
			(end 0.67945 -0.3048)
			(stroke
				(width 0.1)
				(type default)
			)
			(layer "F.Fab")
		)
		(fp_line
			(start 0.12065 -0.2794)
			(end 0.12065 -0.3048)
			(stroke
				(width 0.1)
				(type default)
			)
			(layer "F.Fab")
		)
		(fp_line
			(start 0.67945 -0.3048)
			(end 0.67945 0.3048)
			(stroke
				(width 0.1)
				(type default)
			)
			(layer "F.Fab")
		)
		(fp_line
			(start 0.67945 0.3048)
			(end 0.120396 0.3048)
			(stroke
				(width 0.1)
				(type default)
			)
			(layer "F.Fab")
		)
		(pad "1" smd circle
			(at -0.40005 0)
			(size 0 0)
			(layers "F.Cu" "F.Mask" "F.Paste")
			(net "PVDD11_S3_P0")
		)
		(pad "2" smd circle
			(at 0.40005 0)
			(size 0 0)
			(layers "F.Cu" "F.Mask" "F.Paste")
			(net "I3C_SPD_DDRAF_CPU0_LVC1_SDA")
		)
	)
	(footprint ""
		(layer "F.Cu")
		(at 92.178632 -69.84238 180)
		(property "Reference" "PC2173"
			(at 0 0 180)
			(layer "F.SilkS")
			(hide yes)
			(effects
				(font
					(size 1.27 1.27)
				)
			)
		)
		(property "Value" ""
			(at 0 0 180)
			(layer "F.Fab")
			(effects
				(font
					(size 1.27 1.27)
				)
			)
		)
		(duplicate_pad_numbers_are_jumpers no)
		(fp_line
			(start 1.524 0.762)
			(end -1.524 0.762)
			(stroke
				(width 0.1524)
				(type default)
			)
			(layer "F.SilkS")
		)
		(fp_line
			(start 1.524 -0.762)
			(end 1.524 0.762)
			(stroke
				(width 0.1524)
				(type default)
			)
			(layer "F.SilkS")
		)
		(fp_line
			(start -1.524 0.762)
			(end -1.524 -0.762)
			(stroke
				(width 0.1524)
				(type default)
			)
			(layer "F.SilkS")
		)
		(fp_line
			(start -1.524 -0.762)
			(end 1.524 -0.762)
			(stroke
				(width 0.1524)
				(type default)
			)
			(layer "F.SilkS")
		)
		(fp_line
			(start 1.1049 0.724916)
			(end 1.1049 -0.724916)
			(stroke
				(width 0.1)
				(type default)
			)
			(layer "F.Fab")
		)
		(fp_line
			(start 1.1049 -0.724916)
			(end -1.1049 -0.724916)
			(stroke
				(width 0.1)
				(type default)
			)
			(layer "F.Fab")
		)
		(fp_line
			(start -1.1049 0.724916)
			(end 1.1049 0.724916)
			(stroke
				(width 0.1)
				(type default)
			)
			(layer "F.Fab")
		)
		(fp_line
			(start -1.1049 -0.724916)
			(end -1.1049 0.724916)
			(stroke
				(width 0.1)
				(type default)
			)
			(layer "F.Fab")
		)
		(pad "1" smd rect
			(at -0.889 0)
			(size 1.016 1.27)
			(layers "F.Cu" "F.Mask" "F.Paste")
			(net "P3V3_OCP_V3_2_R")
		)
		(pad "2" smd rect
			(at 0.889 0)
			(size 1.016 1.27)
			(layers "F.Cu" "F.Mask" "F.Paste")
			(net "GND")
		)
	)
	(footprint ""
		(layer "F.Cu")
		(at 355.300534 -340.084664 -90)
		(property "Reference" "PC115_6"
			(at 0 0 270)
			(layer "F.SilkS")
			(hide yes)
			(effects
				(font
					(size 1.27 1.27)
				)
			)
		)
		(property "Value" ""
			(at 0 0 270)
			(layer "F.Fab")
			(effects
				(font
					(size 1.27 1.27)
				)
			)
		)
		(duplicate_pad_numbers_are_jumpers no)
		(fp_line
			(start -0.7874 0.4064)
			(end -0.7874 -0.4064)
			(stroke
				(width 0.1524)
				(type default)
			)
			(layer "F.SilkS")
		)
		(fp_line
			(start 0.7874 0.4064)
			(end -0.7874 0.4064)
			(stroke
				(width 0.1524)
				(type default)
			)
			(layer "F.SilkS")
		)
		(fp_line
			(start -0.7874 -0.4064)
			(end 0.7874 -0.4064)
			(stroke
				(width 0.1524)
				(type default)
			)
			(layer "F.SilkS")
		)
		(fp_line
			(start 0.7874 -0.4064)
			(end 0.7874 0.4064)
			(stroke
				(width 0.1524)
				(type default)
			)
			(layer "F.SilkS")
		)
		(fp_line
			(start -0.67945 0.3048)
			(end -0.67945 -0.305054)
			(stroke
				(width 0.1)
				(type default)
			)
			(layer "F.Fab")
		)
		(fp_line
			(start -0.12065 0.3048)
			(end -0.67945 0.3048)
			(stroke
				(width 0.1)
				(type default)
			)
			(layer "F.Fab")
		)
		(fp_line
			(start 0.120396 0.3048)
			(end 0.120396 0.2794)
			(stroke
				(width 0.1)
				(type default)
			)
			(layer "F.Fab")
		)
		(fp_line
			(start 0.67945 0.3048)
			(end 0.120396 0.3048)
			(stroke
				(width 0.1)
				(type default)
			)
			(layer "F.Fab")
		)
		(fp_line
			(start -0.12065 0.2794)
			(end -0.12065 0.3048)
			(stroke
				(width 0.1)
				(type default)
			)
			(layer "F.Fab")
		)
		(fp_line
			(start 0.120396 0.2794)
			(end -0.12065 0.2794)
			(stroke
				(width 0.1)
				(type default)
			)
			(layer "F.Fab")
		)
		(fp_line
			(start -0.12065 -0.2794)
			(end 0.12065 -0.2794)
			(stroke
				(width 0.1)
				(type default)
			)
			(layer "F.Fab")
		)
		(fp_line
			(start 0.12065 -0.2794)
			(end 0.12065 -0.3048)
			(stroke
				(width 0.1)
				(type default)
			)
			(layer "F.Fab")
		)
		(fp_line
			(start 0.12065 -0.3048)
			(end 0.67945 -0.3048)
			(stroke
				(width 0.1)
				(type default)
			)
			(layer "F.Fab")
		)
		(fp_line
			(start 0.67945 -0.3048)
			(end 0.67945 0.3048)
			(stroke
				(width 0.1)
				(type default)
			)
			(layer "F.Fab")
		)
		(fp_line
			(start -0.67945 -0.305054)
			(end -0.12065 -0.305054)
			(stroke
				(width 0.1)
				(type default)
			)
			(layer "F.Fab")
		)
		(fp_line
			(start -0.12065 -0.305054)
			(end -0.12065 -0.2794)
			(stroke
				(width 0.1)
				(type default)
			)
			(layer "F.Fab")
		)
		(pad "1" smd circle
			(at -0.40005 0 270)
			(size 0 0)
			(layers "F.Cu" "F.Mask" "F.Paste")
			(net "SW_P12V_AUX_PVDDCR_CPU1_P0_FLT")
		)
		(pad "2" smd circle
			(at 0.40005 0 270)
			(size 0 0)
			(layers "F.Cu" "F.Mask" "F.Paste")
			(net "GND")
		)
	)
	(footprint ""
		(layer "F.Cu")
		(at 73.393046 -62.969394 -90)
		(property "Reference" "R1173"
			(at 0 0 270)
			(layer "F.SilkS")
			(hide yes)
			(effects
				(font
					(size 1.27 1.27)
				)
			)
		)
		(property "Value" ""
			(at 0 0 270)
			(layer "F.Fab")
			(effects
				(font
					(size 1.27 1.27)
				)
			)
		)
		(duplicate_pad_numbers_are_jumpers no)
		(fp_line
			(start -0.7874 0.4064)
			(end -0.7874 -0.4064)
			(stroke
				(width 0.1524)
				(type default)
			)
			(layer "F.SilkS")
		)
		(fp_line
			(start 0.7874 0.4064)
			(end -0.7874 0.4064)
			(stroke
				(width 0.1524)
				(type default)
			)
			(layer "F.SilkS")
		)
		(fp_line
			(start -0.7874 -0.4064)
			(end 0.7874 -0.4064)
			(stroke
				(width 0.1524)
				(type default)
			)
			(layer "F.SilkS")
		)
		(fp_line
			(start 0.7874 -0.4064)
			(end 0.7874 0.4064)
			(stroke
				(width 0.1524)
				(type default)
			)
			(layer "F.SilkS")
		)
		(fp_line
			(start -0.67945 0.3048)
			(end -0.67945 -0.305054)
			(stroke
				(width 0.1)
				(type default)
			)
			(layer "F.Fab")
		)
		(fp_line
			(start -0.12065 0.3048)
			(end -0.67945 0.3048)
			(stroke
				(width 0.1)
				(type default)
			)
			(layer "F.Fab")
		)
		(fp_line
			(start 0.120396 0.3048)
			(end 0.120396 0.2794)
			(stroke
				(width 0.1)
				(type default)
			)
			(layer "F.Fab")
		)
		(fp_line
			(start 0.67945 0.3048)
			(end 0.120396 0.3048)
			(stroke
				(width 0.1)
				(type default)
			)
			(layer "F.Fab")
		)
		(fp_line
			(start -0.12065 0.2794)
			(end -0.12065 0.3048)
			(stroke
				(width 0.1)
				(type default)
			)
			(layer "F.Fab")
		)
		(fp_line
			(start 0.120396 0.2794)
			(end -0.12065 0.2794)
			(stroke
				(width 0.1)
				(type default)
			)
			(layer "F.Fab")
		)
		(fp_line
			(start -0.12065 -0.2794)
			(end 0.12065 -0.2794)
			(stroke
				(width 0.1)
				(type default)
			)
			(layer "F.Fab")
		)
		(fp_line
			(start 0.12065 -0.2794)
			(end 0.12065 -0.3048)
			(stroke
				(width 0.1)
				(type default)
			)
			(layer "F.Fab")
		)
		(fp_line
			(start 0.12065 -0.3048)
			(end 0.67945 -0.3048)
			(stroke
				(width 0.1)
				(type default)
			)
			(layer "F.Fab")
		)
		(fp_line
			(start 0.67945 -0.3048)
			(end 0.67945 0.3048)
			(stroke
				(width 0.1)
				(type default)
			)
			(layer "F.Fab")
		)
		(fp_line
			(start -0.67945 -0.305054)
			(end -0.12065 -0.305054)
			(stroke
				(width 0.1)
				(type default)
			)
			(layer "F.Fab")
		)
		(fp_line
			(start -0.12065 -0.305054)
			(end -0.12065 -0.2794)
			(stroke
				(width 0.1)
				(type default)
			)
			(layer "F.Fab")
		)
		(pad "1" smd circle
			(at -0.40005 0 270)
			(size 0 0)
			(layers "F.Cu" "F.Mask" "F.Paste")
			(net "OCP_V3_2_P3V3_R3_PWRGD")
		)
		(pad "2" smd circle
			(at 0.40005 0 270)
			(size 0 0)
			(layers "F.Cu" "F.Mask" "F.Paste")
			(net "HP_LVC3_OCP_V3_2_PWRGD")
		)
	)
	(footprint ""
		(layer "F.Cu")
		(at 424.579288 -53.388514 180)
		(property "Reference" "D1"
			(at -1.418844 -2.46126 0)
			(unlocked yes)
			(layer "F.SilkS")
			(effects
				(font
					(size 0.7874 0.5842)
					(thickness 0.1524)
				)
				(justify left)
			)
		)
		(property "Value" ""
			(at 0 0 180)
			(layer "F.Fab")
			(effects
				(font
					(size 1.27 1.27)
				)
			)
		)
		(duplicate_pad_numbers_are_jumpers no)
		(fp_line
			(start 1.584198 1.500124)
			(end 1.584198 -1.500124)
			(stroke
				(width 0.1524)
				(type default)
			)
			(layer "F.SilkS")
		)
		(fp_line
			(start 1.584198 -1.500124)
			(end -1.584198 -1.500124)
			(stroke
				(width 0.1524)
				(type default)
			)
			(layer "F.SilkS")
		)
		(fp_line
			(start -1.584198 1.500124)
			(end 1.584198 1.500124)
			(stroke
				(width 0.1524)
				(type default)
			)
			(layer "F.SilkS")
		)
		(fp_line
			(start -1.584198 -1.500124)
			(end -1.584198 1.500124)
			(stroke
				(width 0.1524)
				(type default)
			)
			(layer "F.SilkS")
		)
		(fp_line
			(start 0.700024 1.500124)
			(end 0.700024 -1.500124)
			(stroke
				(width 0.1)
				(type default)
			)
			(layer "F.Fab")
		)
		(fp_line
			(start 0.700024 -1.500124)
			(end -0.700024 -1.500124)
			(stroke
				(width 0.1)
				(type default)
			)
			(layer "F.Fab")
		)
		(fp_line
			(start -0.700024 1.500124)
			(end 0.700024 1.500124)
			(stroke
				(width 0.1)
				(type default)
			)
			(layer "F.Fab")
		)
		(fp_line
			(start -0.700024 -1.500124)
			(end -0.700024 1.500124)
			(stroke
				(width 0.1)
				(type default)
			)
			(layer "F.Fab")
		)
		(pad "1" smd rect
			(at -0.999998 -0.94996 90)
			(size 0.8128 0.9144)
			(layers "F.Cu" "F.Mask" "F.Paste")
			(net "P3V3")
		)
		(pad "2" smd rect
			(at -0.999998 0.94996 90)
			(size 0.8128 0.9144)
			(layers "F.Cu" "F.Mask" "F.Paste")
			(net "Net_10752")
		)
		(pad "3" smd rect
			(at 0.999998 0 90)
			(size 0.8128 0.9144)
			(layers "F.Cu" "F.Mask" "F.Paste")
			(net "P5V")
		)
	)
	(footprint ""
		(layer "F.Cu")
		(at 215.259666 -54.455314)
		(property "Reference" "U276"
			(at 4.349242 0.209042 0)
			(unlocked yes)
			(layer "F.SilkS")
			(effects
				(font
					(size 0.7874 0.5842)
					(thickness 0.1524)
				)
			)
		)
		(property "Value" ""
			(at 0 0 0)
			(layer "F.Fab")
			(effects
				(font
					(size 1.27 1.27)
				)
			)
		)
		(duplicate_pad_numbers_are_jumpers no)
		(fp_line
			(start -1.500124 -1.500124)
			(end -1.004062 -1.500124)
			(stroke
				(width 0.1524)
				(type default)
			)
			(layer "F.SilkS")
		)
		(fp_line
			(start -1.500124 -1.004062)
			(end -1.500124 -1.500124)
			(stroke
				(width 0.1524)
				(type default)
			)
			(layer "F.SilkS")
		)
		(fp_line
			(start -1.500124 1.500124)
			(end -1.500124 1.004062)
			(stroke
				(width 0.1524)
				(type default)
			)
			(layer "F.SilkS")
		)
		(fp_line
			(start -1.004062 1.500124)
			(end -1.500124 1.500124)
			(stroke
				(width 0.1524)
				(type default)
			)
			(layer "F.SilkS")
		)
		(fp_line
			(start 1.004062 -1.500124)
			(end 1.500124 -1.500124)
			(stroke
				(width 0.1524)
				(type default)
			)
			(layer "F.SilkS")
		)
		(fp_line
			(start 1.500124 -1.500124)
			(end 1.500124 -1.004062)
			(stroke
				(width 0.1524)
				(type default)
			)
			(layer "F.SilkS")
		)
		(fp_line
			(start 1.500124 1.004062)
			(end 1.500124 1.500124)
			(stroke
				(width 0.1524)
				(type default)
			)
			(layer "F.SilkS")
		)
		(fp_line
			(start 1.500124 1.500124)
			(end 1.004062 1.500124)
			(stroke
				(width 0.1524)
				(type default)
			)
			(layer "F.SilkS")
		)
		(fp_poly
			(pts
				(xy -2.515616 -1.309878) (xy -2.07137 -1.831086) (xy -1.772158 -1.126236)
			)
			(stroke
				(width 0)
				(type default)
			)
			(fill yes)
			(layer "F.SilkS")
		)
		(fp_line
			(start -1.500124 -1.500124)
			(end 1.500124 -1.500124)
			(stroke
				(width 0.1)
				(type default)
			)
			(layer "F.Fab")
		)
		(fp_line
			(start -1.500124 1.500124)
			(end -1.500124 -1.500124)
			(stroke
				(width 0.1)
				(type default)
			)
			(layer "F.Fab")
		)
		(fp_line
			(start 1.500124 -1.500124)
			(end 1.500124 1.500124)
			(stroke
				(width 0.1)
				(type default)
			)
			(layer "F.Fab")
		)
		(fp_line
			(start 1.500124 1.500124)
			(end -1.500124 1.500124)
			(stroke
				(width 0.1)
				(type default)
			)
			(layer "F.Fab")
		)
		(fp_poly
			(pts
				(xy -2.847848 -1.258062) (xy -2.847848 -0.242062) (xy -1.831848 -0.750062)
			)
			(stroke
				(width 0)
				(type default)
			)
			(fill yes)
			(layer "F.Fab")
		)
		(pad "1" smd rect
			(at -1.400048 -0.750062 270)
			(size 0.2286 0.6096)
			(layers "F.Cu" "F.Mask" "F.Paste")
			(net "INA230_2_A1")
		)
		(pad "2" smd rect
			(at -1.400048 -0.249936 270)
			(size 0.2286 0.6096)
			(layers "F.Cu" "F.Mask" "F.Paste")
			(net "INA230_2_A0")
		)
		(pad "3" smd rect
			(at -1.400048 0.249936 270)
			(size 0.2286 0.6096)
			(layers "F.Cu" "F.Mask" "F.Paste")
			(net "E1S_0_P3V3_ADC_ALERT_R")
		)
		(pad "4" smd rect
			(at -1.400048 0.750062 270)
			(size 0.2286 0.6096)
			(layers "F.Cu" "F.Mask" "F.Paste")
			(net "SMB_INA230_2_3V3AUX_SDA_R1")
		)
		(pad "5" smd rect
			(at -0.750062 1.400048)
			(size 0.2286 0.6096)
			(layers "F.Cu" "F.Mask" "F.Paste")
			(net "SMB_INA230_2_3V3AUX_SCL_R1")
		)
		(pad "6" smd rect
			(at -0.249936 1.400048)
			(size 0.2286 0.6096)
			(layers "F.Cu" "F.Mask" "F.Paste")
			(net "NC_INA230_2_NC0")
		)
		(pad "7" smd rect
			(at 0.249936 1.400048)
			(size 0.2286 0.6096)
			(layers "F.Cu" "F.Mask" "F.Paste")
			(net "NC_INA230_2_NC1")
		)
		(pad "8" smd rect
			(at 0.750062 1.400048)
			(size 0.2286 0.6096)
			(layers "F.Cu" "F.Mask" "F.Paste")
			(net "NC_INA230_2_NC2")
		)
		(pad "9" smd rect
			(at 1.400048 0.750062 270)
			(size 0.2286 0.6096)
			(layers "F.Cu" "F.Mask" "F.Paste")
			(net "P3V3_AUX")
		)
		(pad "10" smd rect
			(at 1.400048 0.249936 270)
			(size 0.2286 0.6096)
			(layers "F.Cu" "F.Mask" "F.Paste")
			(net "GND")
		)
		(pad "11" smd rect
			(at 1.400048 -0.249936 270)
			(size 0.2286 0.6096)
			(layers "F.Cu" "F.Mask" "F.Paste")
			(net "P3V3_E1S_0_R")
		)
		(pad "12" smd rect
			(at 1.400048 -0.750062 270)
			(size 0.2286 0.6096)
			(layers "F.Cu" "F.Mask" "F.Paste")
			(net "VSENSE_P3V3_INA230_2_INN")
		)
		(pad "13" smd rect
			(at 0.750062 -1.400048)
			(size 0.2286 0.6096)
			(layers "F.Cu" "F.Mask" "F.Paste")
			(net "VSENSE_P3V3_INA230_2_INP")
		)
		(pad "14" smd rect
			(at 0.249936 -1.400048)
			(size 0.2286 0.6096)
			(layers "F.Cu" "F.Mask" "F.Paste")
			(net "NC_INA230_2_NC3")
		)
		(pad "15" smd rect
			(at -0.249936 -1.400048)
			(size 0.2286 0.6096)
			(layers "F.Cu" "F.Mask" "F.Paste")
			(net "NC_INA230_2_NC4")
		)
		(pad "16" smd rect
			(at -0.750062 -1.400048)
			(size 0.2286 0.6096)
			(layers "F.Cu" "F.Mask" "F.Paste")
			(net "NC_INA230_2_NC5")
		)
		(pad "TH" smd rect
			(at 0 0)
			(size 1.7018 1.7018)
			(layers "F.Cu" "F.Mask" "F.Paste")
			(net "GND")
		)
		(zone
			(layer "F.Cu")
			(hatch none 0.5)
			(connect_pads
				(clearance 0)
			)
			(min_thickness 0.25)
			(keepout
				(tracks not_allowed)
				(vias allowed)
				(pads allowed)
				(copperpour not_allowed)
				(footprints allowed)
			)
			(placement
				(enabled no)
				(sheetname "")
			)
			(fill
				(thermal_gap 0.5)
				(thermal_bridge_width 0.5)
				(island_removal_mode 0)
			)
			(polygon
				(pts
					(xy 214.215218 -54.455314) (xy 214.357966 -54.455314) (xy 214.357966 -53.553614) (xy 216.161366 -53.553614)
					(xy 216.161366 -53.967888) (xy 216.304114 -53.967888) (xy 216.304114 -53.410866) (xy 214.215218 -53.410866)
				)
			)
		)
	)
	(footprint ""
		(layer "F.Cu")
		(at 122.427238 -41.17975 -90)
		(property "Reference" "R6259"
			(at 0 0 270)
			(layer "F.SilkS")
			(hide yes)
			(effects
				(font
					(size 1.27 1.27)
				)
			)
		)
		(property "Value" ""
			(at 0 0 270)
			(layer "F.Fab")
			(effects
				(font
					(size 1.27 1.27)
				)
			)
		)
		(duplicate_pad_numbers_are_jumpers no)
		(fp_line
			(start -0.7874 0.4064)
			(end -0.7874 -0.4064)
			(stroke
				(width 0.1524)
				(type default)
			)
			(layer "F.SilkS")
		)
		(fp_line
			(start 0.7874 0.4064)
			(end -0.7874 0.4064)
			(stroke
				(width 0.1524)
				(type default)
			)
			(layer "F.SilkS")
		)
		(fp_line
			(start -0.7874 -0.4064)
			(end 0.7874 -0.4064)
			(stroke
				(width 0.1524)
				(type default)
			)
			(layer "F.SilkS")
		)
		(fp_line
			(start 0.7874 -0.4064)
			(end 0.7874 0.4064)
			(stroke
				(width 0.1524)
				(type default)
			)
			(layer "F.SilkS")
		)
		(fp_line
			(start -0.67945 0.3048)
			(end -0.67945 -0.305054)
			(stroke
				(width 0.1)
				(type default)
			)
			(layer "F.Fab")
		)
		(fp_line
			(start -0.12065 0.3048)
			(end -0.67945 0.3048)
			(stroke
				(width 0.1)
				(type default)
			)
			(layer "F.Fab")
		)
		(fp_line
			(start 0.120396 0.3048)
			(end 0.120396 0.2794)
			(stroke
				(width 0.1)
				(type default)
			)
			(layer "F.Fab")
		)
		(fp_line
			(start 0.67945 0.3048)
			(end 0.120396 0.3048)
			(stroke
				(width 0.1)
				(type default)
			)
			(layer "F.Fab")
		)
		(fp_line
			(start -0.12065 0.2794)
			(end -0.12065 0.3048)
			(stroke
				(width 0.1)
				(type default)
			)
			(layer "F.Fab")
		)
		(fp_line
			(start 0.120396 0.2794)
			(end -0.12065 0.2794)
			(stroke
				(width 0.1)
				(type default)
			)
			(layer "F.Fab")
		)
		(fp_line
			(start -0.12065 -0.2794)
			(end 0.12065 -0.2794)
			(stroke
				(width 0.1)
				(type default)
			)
			(layer "F.Fab")
		)
		(fp_line
			(start 0.12065 -0.2794)
			(end 0.12065 -0.3048)
			(stroke
				(width 0.1)
				(type default)
			)
			(layer "F.Fab")
		)
		(fp_line
			(start 0.12065 -0.3048)
			(end 0.67945 -0.3048)
			(stroke
				(width 0.1)
				(type default)
			)
			(layer "F.Fab")
		)
		(fp_line
			(start 0.67945 -0.3048)
			(end 0.67945 0.3048)
			(stroke
				(width 0.1)
				(type default)
			)
			(layer "F.Fab")
		)
		(fp_line
			(start -0.67945 -0.305054)
			(end -0.12065 -0.305054)
			(stroke
				(width 0.1)
				(type default)
			)
			(layer "F.Fab")
		)
		(fp_line
			(start -0.12065 -0.305054)
			(end -0.12065 -0.2794)
			(stroke
				(width 0.1)
				(type default)
			)
			(layer "F.Fab")
		)
		(pad "1" smd circle
			(at -0.40005 0 270)
			(size 0 0)
			(layers "F.Cu" "F.Mask" "F.Paste")
			(net "P1V2_CPU0_USB2_DVDD12")
		)
		(pad "2" smd circle
			(at 0.40005 0 270)
			(size 0 0)
			(layers "F.Cu" "F.Mask" "F.Paste")
			(net "USB_HUB2_TI_PWRCTL2_MRP_VDD12")
		)
	)
	(footprint ""
		(layer "F.Cu")
		(at 294.759888 -392.32205 180)
		(property "Reference" "R1418"
			(at 0 0 180)
			(layer "F.SilkS")
			(hide yes)
			(effects
				(font
					(size 1.27 1.27)
				)
			)
		)
		(property "Value" ""
			(at 0 0 180)
			(layer "F.Fab")
			(effects
				(font
					(size 1.27 1.27)
				)
			)
		)
		(duplicate_pad_numbers_are_jumpers no)
		(fp_line
			(start 0.32512 0.175006)
			(end -0.32512 0.175006)
			(stroke
				(width 0.1)
				(type default)
			)
			(layer "F.Fab")
		)
		(fp_line
			(start 0.32512 -0.175006)
			(end 0.32512 0.175006)
			(stroke
				(width 0.1)
				(type default)
			)
			(layer "F.Fab")
		)
		(fp_line
			(start -0.32512 0.175006)
			(end -0.32512 -0.175006)
			(stroke
				(width 0.1)
				(type default)
			)
			(layer "F.Fab")
		)
		(fp_line
			(start -0.32512 -0.175006)
			(end 0.32512 -0.175006)
			(stroke
				(width 0.1)
				(type default)
			)
			(layer "F.Fab")
		)
		(pad "1" smd rect
			(at -0.2667 0 180)
			(size 0.3048 0.381)
			(layers "F.Cu" "F.Mask" "F.Paste")
			(net "P1V8_CPU0_RT_1D")
		)
		(pad "2" smd rect
			(at 0.2667 0)
			(size 0.3048 0.381)
			(layers "F.Cu" "F.Mask" "F.Paste")
			(net "SMB_RT_CPU0_P1_ROM_MUX_1D_SCL")
		)
	)
	(footprint ""
		(layer "F.Cu")
		(at 328.339958 -194.052952 -90)
		(property "Reference" "R356"
			(at 0 0 270)
			(layer "F.SilkS")
			(hide yes)
			(effects
				(font
					(size 1.27 1.27)
				)
			)
		)
		(property "Value" ""
			(at 0 0 270)
			(layer "F.Fab")
			(effects
				(font
					(size 1.27 1.27)
				)
			)
		)
		(duplicate_pad_numbers_are_jumpers no)
		(fp_line
			(start -0.7874 0.4064)
			(end -0.7874 -0.4064)
			(stroke
				(width 0.1524)
				(type default)
			)
			(layer "F.SilkS")
		)
		(fp_line
			(start 0.7874 0.4064)
			(end -0.7874 0.4064)
			(stroke
				(width 0.1524)
				(type default)
			)
			(layer "F.SilkS")
		)
		(fp_line
			(start -0.7874 -0.4064)
			(end 0.7874 -0.4064)
			(stroke
				(width 0.1524)
				(type default)
			)
			(layer "F.SilkS")
		)
		(fp_line
			(start 0.7874 -0.4064)
			(end 0.7874 0.4064)
			(stroke
				(width 0.1524)
				(type default)
			)
			(layer "F.SilkS")
		)
		(fp_line
			(start -0.67945 0.3048)
			(end -0.67945 -0.305054)
			(stroke
				(width 0.1)
				(type default)
			)
			(layer "F.Fab")
		)
		(fp_line
			(start -0.12065 0.3048)
			(end -0.67945 0.3048)
			(stroke
				(width 0.1)
				(type default)
			)
			(layer "F.Fab")
		)
		(fp_line
			(start 0.120396 0.3048)
			(end 0.120396 0.2794)
			(stroke
				(width 0.1)
				(type default)
			)
			(layer "F.Fab")
		)
		(fp_line
			(start 0.67945 0.3048)
			(end 0.120396 0.3048)
			(stroke
				(width 0.1)
				(type default)
			)
			(layer "F.Fab")
		)
		(fp_line
			(start -0.12065 0.2794)
			(end -0.12065 0.3048)
			(stroke
				(width 0.1)
				(type default)
			)
			(layer "F.Fab")
		)
		(fp_line
			(start 0.120396 0.2794)
			(end -0.12065 0.2794)
			(stroke
				(width 0.1)
				(type default)
			)
			(layer "F.Fab")
		)
		(fp_line
			(start -0.12065 -0.2794)
			(end 0.12065 -0.2794)
			(stroke
				(width 0.1)
				(type default)
			)
			(layer "F.Fab")
		)
		(fp_line
			(start 0.12065 -0.2794)
			(end 0.12065 -0.3048)
			(stroke
				(width 0.1)
				(type default)
			)
			(layer "F.Fab")
		)
		(fp_line
			(start 0.12065 -0.3048)
			(end 0.67945 -0.3048)
			(stroke
				(width 0.1)
				(type default)
			)
			(layer "F.Fab")
		)
		(fp_line
			(start 0.67945 -0.3048)
			(end 0.67945 0.3048)
			(stroke
				(width 0.1)
				(type default)
			)
			(layer "F.Fab")
		)
		(fp_line
			(start -0.67945 -0.305054)
			(end -0.12065 -0.305054)
			(stroke
				(width 0.1)
				(type default)
			)
			(layer "F.Fab")
		)
		(fp_line
			(start -0.12065 -0.305054)
			(end -0.12065 -0.2794)
			(stroke
				(width 0.1)
				(type default)
			)
			(layer "F.Fab")
		)
		(pad "1" smd circle
			(at -0.40005 0 270)
			(size 0 0)
			(layers "F.Cu" "F.Mask" "F.Paste")
			(net "CPU0_XTRIG_R2_L6")
		)
		(pad "2" smd circle
			(at 0.40005 0 270)
			(size 0 0)
			(layers "F.Cu" "F.Mask" "F.Paste")
			(net "CPU0_XTRIG_L6")
		)
	)
	(footprint ""
		(layer "F.Cu")
		(at 320.171318 -115.410488 180)
		(property "Reference" "R43"
			(at 0 0 180)
			(layer "F.SilkS")
			(hide yes)
			(effects
				(font
					(size 1.27 1.27)
				)
			)
		)
		(property "Value" ""
			(at 0 0 180)
			(layer "F.Fab")
			(effects
				(font
					(size 1.27 1.27)
				)
			)
		)
		(duplicate_pad_numbers_are_jumpers no)
		(fp_line
			(start 0.7874 0.4064)
			(end -0.7874 0.4064)
			(stroke
				(width 0.1524)
				(type default)
			)
			(layer "F.SilkS")
		)
		(fp_line
			(start 0.7874 -0.4064)
			(end 0.7874 0.4064)
			(stroke
				(width 0.1524)
				(type default)
			)
			(layer "F.SilkS")
		)
		(fp_line
			(start -0.7874 0.4064)
			(end -0.7874 -0.4064)
			(stroke
				(width 0.1524)
				(type default)
			)
			(layer "F.SilkS")
		)
		(fp_line
			(start -0.7874 -0.4064)
			(end 0.7874 -0.4064)
			(stroke
				(width 0.1524)
				(type default)
			)
			(layer "F.SilkS")
		)
		(fp_line
			(start 0.67945 0.3048)
			(end 0.120396 0.3048)
			(stroke
				(width 0.1)
				(type default)
			)
			(layer "F.Fab")
		)
		(fp_line
			(start 0.67945 -0.3048)
			(end 0.67945 0.3048)
			(stroke
				(width 0.1)
				(type default)
			)
			(layer "F.Fab")
		)
		(fp_line
			(start 0.12065 -0.2794)
			(end 0.12065 -0.3048)
			(stroke
				(width 0.1)
				(type default)
			)
			(layer "F.Fab")
		)
		(fp_line
			(start 0.12065 -0.3048)
			(end 0.67945 -0.3048)
			(stroke
				(width 0.1)
				(type default)
			)
			(layer "F.Fab")
		)
		(fp_line
			(start 0.120396 0.3048)
			(end 0.120396 0.2794)
			(stroke
				(width 0.1)
				(type default)
			)
			(layer "F.Fab")
		)
		(fp_line
			(start 0.120396 0.2794)
			(end -0.12065 0.2794)
			(stroke
				(width 0.1)
				(type default)
			)
			(layer "F.Fab")
		)
		(fp_line
			(start -0.12065 0.3048)
			(end -0.67945 0.3048)
			(stroke
				(width 0.1)
				(type default)
			)
			(layer "F.Fab")
		)
		(fp_line
			(start -0.12065 0.2794)
			(end -0.12065 0.3048)
			(stroke
				(width 0.1)
				(type default)
			)
			(layer "F.Fab")
		)
		(fp_line
			(start -0.12065 -0.2794)
			(end 0.12065 -0.2794)
			(stroke
				(width 0.1)
				(type default)
			)
			(layer "F.Fab")
		)
		(fp_line
			(start -0.12065 -0.305054)
			(end -0.12065 -0.2794)
			(stroke
				(width 0.1)
				(type default)
			)
			(layer "F.Fab")
		)
		(fp_line
			(start -0.67945 0.3048)
			(end -0.67945 -0.305054)
			(stroke
				(width 0.1)
				(type default)
			)
			(layer "F.Fab")
		)
		(fp_line
			(start -0.67945 -0.305054)
			(end -0.12065 -0.305054)
			(stroke
				(width 0.1)
				(type default)
			)
			(layer "F.Fab")
		)
		(pad "1" smd circle
			(at -0.40005 0 180)
			(size 0 0)
			(layers "F.Cu" "F.Mask" "F.Paste")
			(net "P3V3_AUX")
		)
		(pad "2" smd circle
			(at 0.40005 0 180)
			(size 0 0)
			(layers "F.Cu" "F.Mask" "F.Paste")
			(net "SMB_FRU_3V3AUX_R1_SDA")
		)
	)
	(footprint ""
		(layer "F.Cu")
		(at 208.878932 -118.762272)
		(property "Reference" "R3505"
			(at 0 0 0)
			(layer "F.SilkS")
			(hide yes)
			(effects
				(font
					(size 1.27 1.27)
				)
			)
		)
		(property "Value" ""
			(at 0 0 0)
			(layer "F.Fab")
			(effects
				(font
					(size 1.27 1.27)
				)
			)
		)
		(duplicate_pad_numbers_are_jumpers no)
		(fp_line
			(start -0.7874 -0.4064)
			(end 0.7874 -0.4064)
			(stroke
				(width 0.1524)
				(type default)
			)
			(layer "F.SilkS")
		)
		(fp_line
			(start -0.7874 0.4064)
			(end -0.7874 -0.4064)
			(stroke
				(width 0.1524)
				(type default)
			)
			(layer "F.SilkS")
		)
		(fp_line
			(start 0.7874 -0.4064)
			(end 0.7874 0.4064)
			(stroke
				(width 0.1524)
				(type default)
			)
			(layer "F.SilkS")
		)
		(fp_line
			(start 0.7874 0.4064)
			(end -0.7874 0.4064)
			(stroke
				(width 0.1524)
				(type default)
			)
			(layer "F.SilkS")
		)
		(fp_line
			(start -0.67945 -0.305054)
			(end -0.12065 -0.305054)
			(stroke
				(width 0.1)
				(type default)
			)
			(layer "F.Fab")
		)
		(fp_line
			(start -0.67945 0.3048)
			(end -0.67945 -0.305054)
			(stroke
				(width 0.1)
				(type default)
			)
			(layer "F.Fab")
		)
		(fp_line
			(start -0.12065 -0.305054)
			(end -0.12065 -0.2794)
			(stroke
				(width 0.1)
				(type default)
			)
			(layer "F.Fab")
		)
		(fp_line
			(start -0.12065 -0.2794)
			(end 0.12065 -0.2794)
			(stroke
				(width 0.1)
				(type default)
			)
			(layer "F.Fab")
		)
		(fp_line
			(start -0.12065 0.2794)
			(end -0.12065 0.3048)
			(stroke
				(width 0.1)
				(type default)
			)
			(layer "F.Fab")
		)
		(fp_line
			(start -0.12065 0.3048)
			(end -0.67945 0.3048)
			(stroke
				(width 0.1)
				(type default)
			)
			(layer "F.Fab")
		)
		(fp_line
			(start 0.120396 0.2794)
			(end -0.12065 0.2794)
			(stroke
				(width 0.1)
				(type default)
			)
			(layer "F.Fab")
		)
		(fp_line
			(start 0.120396 0.3048)
			(end 0.120396 0.2794)
			(stroke
				(width 0.1)
				(type default)
			)
			(layer "F.Fab")
		)
		(fp_line
			(start 0.12065 -0.3048)
			(end 0.67945 -0.3048)
			(stroke
				(width 0.1)
				(type default)
			)
			(layer "F.Fab")
		)
		(fp_line
			(start 0.12065 -0.2794)
			(end 0.12065 -0.3048)
			(stroke
				(width 0.1)
				(type default)
			)
			(layer "F.Fab")
		)
		(fp_line
			(start 0.67945 -0.3048)
			(end 0.67945 0.3048)
			(stroke
				(width 0.1)
				(type default)
			)
			(layer "F.Fab")
		)
		(fp_line
			(start 0.67945 0.3048)
			(end 0.120396 0.3048)
			(stroke
				(width 0.1)
				(type default)
			)
			(layer "F.Fab")
		)
		(pad "1" smd circle
			(at -0.40005 0)
			(size 0 0)
			(layers "F.Cu" "F.Mask" "F.Paste")
			(net "GPU_FPGA_EROT_FATALERR_ISO_R_N")
		)
		(pad "2" smd circle
			(at 0.40005 0)
			(size 0 0)
			(layers "F.Cu" "F.Mask" "F.Paste")
			(net "GPU_FPGA_EROT_FATALERR_ISO_N")
		)
	)
	(footprint ""
		(layer "F.Cu")
		(at 281.008582 -351.573846 90)
		(property "Reference" "PC175_9"
			(at 0 0 90)
			(layer "F.SilkS")
			(hide yes)
			(effects
				(font
					(size 1.27 1.27)
				)
			)
		)
		(property "Value" ""
			(at 0 0 90)
			(layer "F.Fab")
			(effects
				(font
					(size 1.27 1.27)
				)
			)
		)
		(duplicate_pad_numbers_are_jumpers no)
		(fp_line
			(start 0.7874 -0.4064)
			(end 0.7874 0.4064)
			(stroke
				(width 0.1524)
				(type default)
			)
			(layer "F.SilkS")
		)
		(fp_line
			(start -0.7874 -0.4064)
			(end 0.7874 -0.4064)
			(stroke
				(width 0.1524)
				(type default)
			)
			(layer "F.SilkS")
		)
		(fp_line
			(start 0.7874 0.4064)
			(end -0.7874 0.4064)
			(stroke
				(width 0.1524)
				(type default)
			)
			(layer "F.SilkS")
		)
		(fp_line
			(start -0.7874 0.4064)
			(end -0.7874 -0.4064)
			(stroke
				(width 0.1524)
				(type default)
			)
			(layer "F.SilkS")
		)
		(fp_line
			(start -0.12065 -0.305054)
			(end -0.12065 -0.2794)
			(stroke
				(width 0.1)
				(type default)
			)
			(layer "F.Fab")
		)
		(fp_line
			(start -0.67945 -0.305054)
			(end -0.12065 -0.305054)
			(stroke
				(width 0.1)
				(type default)
			)
			(layer "F.Fab")
		)
		(fp_line
			(start 0.67945 -0.3048)
			(end 0.67945 0.3048)
			(stroke
				(width 0.1)
				(type default)
			)
			(layer "F.Fab")
		)
		(fp_line
			(start 0.12065 -0.3048)
			(end 0.67945 -0.3048)
			(stroke
				(width 0.1)
				(type default)
			)
			(layer "F.Fab")
		)
		(fp_line
			(start 0.12065 -0.2794)
			(end 0.12065 -0.3048)
			(stroke
				(width 0.1)
				(type default)
			)
			(layer "F.Fab")
		)
		(fp_line
			(start -0.12065 -0.2794)
			(end 0.12065 -0.2794)
			(stroke
				(width 0.1)
				(type default)
			)
			(layer "F.Fab")
		)
		(fp_line
			(start 0.120396 0.2794)
			(end -0.12065 0.2794)
			(stroke
				(width 0.1)
				(type default)
			)
			(layer "F.Fab")
		)
		(fp_line
			(start -0.12065 0.2794)
			(end -0.12065 0.3048)
			(stroke
				(width 0.1)
				(type default)
			)
			(layer "F.Fab")
		)
		(fp_line
			(start 0.67945 0.3048)
			(end 0.120396 0.3048)
			(stroke
				(width 0.1)
				(type default)
			)
			(layer "F.Fab")
		)
		(fp_line
			(start 0.120396 0.3048)
			(end 0.120396 0.2794)
			(stroke
				(width 0.1)
				(type default)
			)
			(layer "F.Fab")
		)
		(fp_line
			(start -0.12065 0.3048)
			(end -0.67945 0.3048)
			(stroke
				(width 0.1)
				(type default)
			)
			(layer "F.Fab")
		)
		(fp_line
			(start -0.67945 0.3048)
			(end -0.67945 -0.305054)
			(stroke
				(width 0.1)
				(type default)
			)
			(layer "F.Fab")
		)
		(pad "1" smd circle
			(at -0.40005 0 90)
			(size 0 0)
			(layers "F.Cu" "F.Mask" "F.Paste")
			(net "PVDDCR_CPU1_P0_VCCS")
		)
		(pad "2" smd circle
			(at 0.40005 0 90)
			(size 0 0)
			(layers "F.Cu" "F.Mask" "F.Paste")
			(net "GND")
		)
	)
	(footprint ""
		(layer "F.Cu")
		(at 93.29801 -55.717694)
		(property "Reference" "C39"
			(at 0 0 0)
			(layer "F.SilkS")
			(hide yes)
			(effects
				(font
					(size 1.27 1.27)
				)
			)
		)
		(property "Value" ""
			(at 0 0 0)
			(layer "F.Fab")
			(effects
				(font
					(size 1.27 1.27)
				)
			)
		)
		(duplicate_pad_numbers_are_jumpers no)
		(fp_line
			(start -0.7874 -0.4064)
			(end 0.7874 -0.4064)
			(stroke
				(width 0.1524)
				(type default)
			)
			(layer "F.SilkS")
		)
		(fp_line
			(start -0.7874 0.4064)
			(end -0.7874 -0.4064)
			(stroke
				(width 0.1524)
				(type default)
			)
			(layer "F.SilkS")
		)
		(fp_line
			(start 0.7874 -0.4064)
			(end 0.7874 0.4064)
			(stroke
				(width 0.1524)
				(type default)
			)
			(layer "F.SilkS")
		)
		(fp_line
			(start 0.7874 0.4064)
			(end -0.7874 0.4064)
			(stroke
				(width 0.1524)
				(type default)
			)
			(layer "F.SilkS")
		)
		(fp_line
			(start -0.67945 -0.305054)
			(end -0.12065 -0.305054)
			(stroke
				(width 0.1)
				(type default)
			)
			(layer "F.Fab")
		)
		(fp_line
			(start -0.67945 0.3048)
			(end -0.67945 -0.305054)
			(stroke
				(width 0.1)
				(type default)
			)
			(layer "F.Fab")
		)
		(fp_line
			(start -0.12065 -0.305054)
			(end -0.12065 -0.2794)
			(stroke
				(width 0.1)
				(type default)
			)
			(layer "F.Fab")
		)
		(fp_line
			(start -0.12065 -0.2794)
			(end 0.12065 -0.2794)
			(stroke
				(width 0.1)
				(type default)
			)
			(layer "F.Fab")
		)
		(fp_line
			(start -0.12065 0.2794)
			(end -0.12065 0.3048)
			(stroke
				(width 0.1)
				(type default)
			)
			(layer "F.Fab")
		)
		(fp_line
			(start -0.12065 0.3048)
			(end -0.67945 0.3048)
			(stroke
				(width 0.1)
				(type default)
			)
			(layer "F.Fab")
		)
		(fp_line
			(start 0.120396 0.2794)
			(end -0.12065 0.2794)
			(stroke
				(width 0.1)
				(type default)
			)
			(layer "F.Fab")
		)
		(fp_line
			(start 0.120396 0.3048)
			(end 0.120396 0.2794)
			(stroke
				(width 0.1)
				(type default)
			)
			(layer "F.Fab")
		)
		(fp_line
			(start 0.12065 -0.3048)
			(end 0.67945 -0.3048)
			(stroke
				(width 0.1)
				(type default)
			)
			(layer "F.Fab")
		)
		(fp_line
			(start 0.12065 -0.2794)
			(end 0.12065 -0.3048)
			(stroke
				(width 0.1)
				(type default)
			)
			(layer "F.Fab")
		)
		(fp_line
			(start 0.67945 -0.3048)
			(end 0.67945 0.3048)
			(stroke
				(width 0.1)
				(type default)
			)
			(layer "F.Fab")
		)
		(fp_line
			(start 0.67945 0.3048)
			(end 0.120396 0.3048)
			(stroke
				(width 0.1)
				(type default)
			)
			(layer "F.Fab")
		)
		(pad "1" smd circle
			(at -0.40005 0)
			(size 0 0)
			(layers "F.Cu" "F.Mask" "F.Paste")
			(net "P3V3_OCP_VCC_2")
		)
		(pad "2" smd circle
			(at 0.40005 0)
			(size 0 0)
			(layers "F.Cu" "F.Mask" "F.Paste")
			(net "GND")
		)
	)
	(footprint ""
		(layer "F.Cu")
		(at 143.171672 -388.030974 90)
		(property "Reference" "R640"
			(at 0 0 90)
			(layer "F.SilkS")
			(hide yes)
			(effects
				(font
					(size 1.27 1.27)
				)
			)
		)
		(property "Value" ""
			(at 0 0 90)
			(layer "F.Fab")
			(effects
				(font
					(size 1.27 1.27)
				)
			)
		)
		(duplicate_pad_numbers_are_jumpers no)
		(fp_line
			(start 0.32512 -0.175006)
			(end 0.32512 0.175006)
			(stroke
				(width 0.1)
				(type default)
			)
			(layer "F.Fab")
		)
		(fp_line
			(start -0.32512 -0.175006)
			(end 0.32512 -0.175006)
			(stroke
				(width 0.1)
				(type default)
			)
			(layer "F.Fab")
		)
		(fp_line
			(start 0.32512 0.175006)
			(end -0.32512 0.175006)
			(stroke
				(width 0.1)
				(type default)
			)
			(layer "F.Fab")
		)
		(fp_line
			(start -0.32512 0.175006)
			(end -0.32512 -0.175006)
			(stroke
				(width 0.1)
				(type default)
			)
			(layer "F.Fab")
		)
		(pad "1" smd rect
			(at -0.2667 0 90)
			(size 0.3048 0.381)
			(layers "F.Cu" "F.Mask" "F.Paste")
			(net "CLK_100M_RETIMER_CPU1_P2_DP")
		)
		(pad "2" smd rect
			(at 0.2667 0 270)
			(size 0.3048 0.381)
			(layers "F.Cu" "F.Mask" "F.Paste")
			(net "GND")
		)
	)
	(footprint ""
		(layer "F.Cu")
		(at 239.53597 -291.863526 180)
		(property "Reference" "PC6518"
			(at 0 0 180)
			(layer "F.SilkS")
			(hide yes)
			(effects
				(font
					(size 1.27 1.27)
				)
			)
		)
		(property "Value" ""
			(at 0 0 180)
			(layer "F.Fab")
			(effects
				(font
					(size 1.27 1.27)
				)
			)
		)
		(duplicate_pad_numbers_are_jumpers no)
		(fp_line
			(start 0.7874 0.4064)
			(end -0.7874 0.4064)
			(stroke
				(width 0.1524)
				(type default)
			)
			(layer "F.SilkS")
		)
		(fp_line
			(start 0.7874 -0.4064)
			(end 0.7874 0.4064)
			(stroke
				(width 0.1524)
				(type default)
			)
			(layer "F.SilkS")
		)
		(fp_line
			(start -0.7874 0.4064)
			(end -0.7874 -0.4064)
			(stroke
				(width 0.1524)
				(type default)
			)
			(layer "F.SilkS")
		)
		(fp_line
			(start -0.7874 -0.4064)
			(end 0.7874 -0.4064)
			(stroke
				(width 0.1524)
				(type default)
			)
			(layer "F.SilkS")
		)
		(fp_line
			(start 0.67945 0.3048)
			(end 0.120396 0.3048)
			(stroke
				(width 0.1)
				(type default)
			)
			(layer "F.Fab")
		)
		(fp_line
			(start 0.67945 -0.3048)
			(end 0.67945 0.3048)
			(stroke
				(width 0.1)
				(type default)
			)
			(layer "F.Fab")
		)
		(fp_line
			(start 0.12065 -0.2794)
			(end 0.12065 -0.3048)
			(stroke
				(width 0.1)
				(type default)
			)
			(layer "F.Fab")
		)
		(fp_line
			(start 0.12065 -0.3048)
			(end 0.67945 -0.3048)
			(stroke
				(width 0.1)
				(type default)
			)
			(layer "F.Fab")
		)
		(fp_line
			(start 0.120396 0.3048)
			(end 0.120396 0.2794)
			(stroke
				(width 0.1)
				(type default)
			)
			(layer "F.Fab")
		)
		(fp_line
			(start 0.120396 0.2794)
			(end -0.12065 0.2794)
			(stroke
				(width 0.1)
				(type default)
			)
			(layer "F.Fab")
		)
		(fp_line
			(start -0.12065 0.3048)
			(end -0.67945 0.3048)
			(stroke
				(width 0.1)
				(type default)
			)
			(layer "F.Fab")
		)
		(fp_line
			(start -0.12065 0.2794)
			(end -0.12065 0.3048)
			(stroke
				(width 0.1)
				(type default)
			)
			(layer "F.Fab")
		)
		(fp_line
			(start -0.12065 -0.2794)
			(end 0.12065 -0.2794)
			(stroke
				(width 0.1)
				(type default)
			)
			(layer "F.Fab")
		)
		(fp_line
			(start -0.12065 -0.305054)
			(end -0.12065 -0.2794)
			(stroke
				(width 0.1)
				(type default)
			)
			(layer "F.Fab")
		)
		(fp_line
			(start -0.67945 0.3048)
			(end -0.67945 -0.305054)
			(stroke
				(width 0.1)
				(type default)
			)
			(layer "F.Fab")
		)
		(fp_line
			(start -0.67945 -0.305054)
			(end -0.12065 -0.305054)
			(stroke
				(width 0.1)
				(type default)
			)
			(layer "F.Fab")
		)
		(pad "1" smd circle
			(at -0.40005 0 180)
			(size 0 0)
			(layers "F.Cu" "F.Mask" "F.Paste")
			(net "P1V8_RETIMER_CPU0_REF")
		)
		(pad "2" smd circle
			(at 0.40005 0 180)
			(size 0 0)
			(layers "F.Cu" "F.Mask" "F.Paste")
			(net "GND")
		)
	)
	(footprint ""
		(layer "F.Cu")
		(at 460.204058 -52.196492 90)
		(property "Reference" "PC581"
			(at 0 0 90)
			(layer "F.SilkS")
			(hide yes)
			(effects
				(font
					(size 1.27 1.27)
				)
			)
		)
		(property "Value" ""
			(at 0 0 90)
			(layer "F.Fab")
			(effects
				(font
					(size 1.27 1.27)
				)
			)
		)
		(duplicate_pad_numbers_are_jumpers no)
		(fp_line
			(start 1.2954 -0.5842)
			(end 1.2954 0.5842)
			(stroke
				(width 0.1524)
				(type default)
			)
			(layer "F.SilkS")
		)
		(fp_line
			(start -1.2954 -0.5842)
			(end 1.2954 -0.5842)
			(stroke
				(width 0.1524)
				(type default)
			)
			(layer "F.SilkS")
		)
		(fp_line
			(start 1.2954 0.5842)
			(end -1.2954 0.5842)
			(stroke
				(width 0.1524)
				(type default)
			)
			(layer "F.SilkS")
		)
		(fp_line
			(start -1.2954 0.5842)
			(end -1.2954 -0.5842)
			(stroke
				(width 0.1524)
				(type default)
			)
			(layer "F.SilkS")
		)
		(fp_line
			(start 0.8636 -0.4572)
			(end 0.8636 -0.4064)
			(stroke
				(width 0.1)
				(type default)
			)
			(layer "F.Fab")
		)
		(fp_line
			(start -0.8636 -0.4572)
			(end 0.8636 -0.4572)
			(stroke
				(width 0.1)
				(type default)
			)
			(layer "F.Fab")
		)
		(fp_line
			(start 1.1938 -0.4064)
			(end 1.1938 0.4064)
			(stroke
				(width 0.1)
				(type default)
			)
			(layer "F.Fab")
		)
		(fp_line
			(start 0.8636 -0.4064)
			(end 1.1938 -0.4064)
			(stroke
				(width 0.1)
				(type default)
			)
			(layer "F.Fab")
		)
		(fp_line
			(start -0.8636 -0.4064)
			(end -0.8636 -0.4572)
			(stroke
				(width 0.1)
				(type default)
			)
			(layer "F.Fab")
		)
		(fp_line
			(start -1.1938 -0.4064)
			(end -0.8636 -0.4064)
			(stroke
				(width 0.1)
				(type default)
			)
			(layer "F.Fab")
		)
		(fp_line
			(start 1.1938 0.4064)
			(end 0.8636 0.4064)
			(stroke
				(width 0.1)
				(type default)
			)
			(layer "F.Fab")
		)
		(fp_line
			(start 0.8636 0.4064)
			(end 0.8636 0.4572)
			(stroke
				(width 0.1)
				(type default)
			)
			(layer "F.Fab")
		)
		(fp_line
			(start -0.8636 0.4064)
			(end -1.1938 0.4064)
			(stroke
				(width 0.1)
				(type default)
			)
			(layer "F.Fab")
		)
		(fp_line
			(start -1.1938 0.4064)
			(end -1.1938 -0.4064)
			(stroke
				(width 0.1)
				(type default)
			)
			(layer "F.Fab")
		)
		(fp_line
			(start 0.8636 0.4572)
			(end -0.8636 0.4572)
			(stroke
				(width 0.1)
				(type default)
			)
			(layer "F.Fab")
		)
		(fp_line
			(start -0.8636 0.4572)
			(end -0.8636 0.4064)
			(stroke
				(width 0.1)
				(type default)
			)
			(layer "F.Fab")
		)
		(pad "1" smd rect
			(at -0.7366 0)
			(size 0.7112 0.8128)
			(layers "F.Cu" "F.Mask" "F.Paste")
			(net "P3V3_AUX_VDRV")
		)
		(pad "2" smd rect
			(at 0.7366 0)
			(size 0.7112 0.8128)
			(layers "F.Cu" "F.Mask" "F.Paste")
			(net "GND")
		)
	)
	(footprint ""
		(layer "F.Cu")
		(at 319.22339 -192.09766 -90)
		(property "Reference" "R2311"
			(at 0 0 270)
			(layer "F.SilkS")
			(hide yes)
			(effects
				(font
					(size 1.27 1.27)
				)
			)
		)
		(property "Value" ""
			(at 0 0 270)
			(layer "F.Fab")
			(effects
				(font
					(size 1.27 1.27)
				)
			)
		)
		(duplicate_pad_numbers_are_jumpers no)
		(fp_line
			(start -0.7874 0.4064)
			(end -0.7874 -0.4064)
			(stroke
				(width 0.1524)
				(type default)
			)
			(layer "F.SilkS")
		)
		(fp_line
			(start 0.7874 0.4064)
			(end -0.7874 0.4064)
			(stroke
				(width 0.1524)
				(type default)
			)
			(layer "F.SilkS")
		)
		(fp_line
			(start -0.7874 -0.4064)
			(end 0.7874 -0.4064)
			(stroke
				(width 0.1524)
				(type default)
			)
			(layer "F.SilkS")
		)
		(fp_line
			(start 0.7874 -0.4064)
			(end 0.7874 0.4064)
			(stroke
				(width 0.1524)
				(type default)
			)
			(layer "F.SilkS")
		)
		(fp_line
			(start -0.67945 0.3048)
			(end -0.67945 -0.305054)
			(stroke
				(width 0.1)
				(type default)
			)
			(layer "F.Fab")
		)
		(fp_line
			(start -0.12065 0.3048)
			(end -0.67945 0.3048)
			(stroke
				(width 0.1)
				(type default)
			)
			(layer "F.Fab")
		)
		(fp_line
			(start 0.120396 0.3048)
			(end 0.120396 0.2794)
			(stroke
				(width 0.1)
				(type default)
			)
			(layer "F.Fab")
		)
		(fp_line
			(start 0.67945 0.3048)
			(end 0.120396 0.3048)
			(stroke
				(width 0.1)
				(type default)
			)
			(layer "F.Fab")
		)
		(fp_line
			(start -0.12065 0.2794)
			(end -0.12065 0.3048)
			(stroke
				(width 0.1)
				(type default)
			)
			(layer "F.Fab")
		)
		(fp_line
			(start 0.120396 0.2794)
			(end -0.12065 0.2794)
			(stroke
				(width 0.1)
				(type default)
			)
			(layer "F.Fab")
		)
		(fp_line
			(start -0.12065 -0.2794)
			(end 0.12065 -0.2794)
			(stroke
				(width 0.1)
				(type default)
			)
			(layer "F.Fab")
		)
		(fp_line
			(start 0.12065 -0.2794)
			(end 0.12065 -0.3048)
			(stroke
				(width 0.1)
				(type default)
			)
			(layer "F.Fab")
		)
		(fp_line
			(start 0.12065 -0.3048)
			(end 0.67945 -0.3048)
			(stroke
				(width 0.1)
				(type default)
			)
			(layer "F.Fab")
		)
		(fp_line
			(start 0.67945 -0.3048)
			(end 0.67945 0.3048)
			(stroke
				(width 0.1)
				(type default)
			)
			(layer "F.Fab")
		)
		(fp_line
			(start -0.67945 -0.305054)
			(end -0.12065 -0.305054)
			(stroke
				(width 0.1)
				(type default)
			)
			(layer "F.Fab")
		)
		(fp_line
			(start -0.12065 -0.305054)
			(end -0.12065 -0.2794)
			(stroke
				(width 0.1)
				(type default)
			)
			(layer "F.Fab")
		)
		(pad "1" smd rect
			(at -0.40005 0 90)
			(size 0.4572 0.508)
			(layers "F.Cu" "F.Mask" "F.Paste")
			(net "I3C_0_SPD_DDRAF_CPU0_R_SDA")
		)
		(pad "2" smd rect
			(at 0.40005 0 90)
			(size 0.4572 0.508)
			(layers "F.Cu" "F.Mask" "F.Paste")
			(net "I3C_SPD_DDRAF_CPU0_BYPASS_SDA")
		)
	)
	(footprint ""
		(layer "F.Cu")
		(at 347.727778 -161.139378 180)
		(property "Reference" "PU10"
			(at 6.094476 -1.518666 0)
			(unlocked yes)
			(layer "F.SilkS")
			(effects
				(font
					(size 0.7874 0.5842)
					(thickness 0.1524)
				)
				(justify left)
			)
		)
		(property "Value" ""
			(at 0 0 180)
			(layer "F.Fab")
			(effects
				(font
					(size 1.27 1.27)
				)
			)
		)
		(duplicate_pad_numbers_are_jumpers no)
		(fp_line
			(start 2.500122 2.999994)
			(end 2.2987 2.999994)
			(stroke
				(width 0.1524)
				(type default)
			)
			(layer "F.SilkS")
		)
		(fp_line
			(start 2.500122 2.339594)
			(end 2.500122 2.999994)
			(stroke
				(width 0.1524)
				(type default)
			)
			(layer "F.SilkS")
		)
		(fp_line
			(start 2.500122 -2.999994)
			(end 2.500122 -2.44348)
			(stroke
				(width 0.1524)
				(type default)
			)
			(layer "F.SilkS")
		)
		(fp_line
			(start 2.31394 -2.999994)
			(end 2.500122 -2.999994)
			(stroke
				(width 0.1524)
				(type default)
			)
			(layer "F.SilkS")
		)
		(fp_line
			(start -2.2987 2.999994)
			(end -2.500122 2.999994)
			(stroke
				(width 0.1524)
				(type default)
			)
			(layer "F.SilkS")
		)
		(fp_line
			(start -2.500122 2.999994)
			(end -2.500122 2.339594)
			(stroke
				(width 0.1524)
				(type default)
			)
			(layer "F.SilkS")
		)
		(fp_line
			(start -2.500122 0.6604)
			(end -2.500122 0.229108)
			(stroke
				(width 0.1524)
				(type default)
			)
			(layer "F.SilkS")
		)
		(fp_line
			(start -2.500122 -2.529078)
			(end -2.500122 -2.999994)
			(stroke
				(width 0.1524)
				(type default)
			)
			(layer "F.SilkS")
		)
		(fp_line
			(start -2.500122 -2.999994)
			(end -2.24409 -2.999994)
			(stroke
				(width 0.1524)
				(type default)
			)
			(layer "F.SilkS")
		)
		(fp_poly
			(pts
				(xy -2.644902 -2.457196) (xy -3.412236 -2.712974) (xy -2.90068 -3.22453)
			)
			(stroke
				(width 0)
				(type default)
			)
			(fill yes)
			(layer "F.SilkS")
		)
		(fp_line
			(start 2.500122 2.999994)
			(end -2.500122 2.999994)
			(stroke
				(width 0.1)
				(type default)
			)
			(layer "F.Fab")
		)
		(fp_line
			(start 2.500122 -2.999994)
			(end 2.500122 2.999994)
			(stroke
				(width 0.1)
				(type default)
			)
			(layer "F.Fab")
		)
		(fp_line
			(start -2.500122 2.999994)
			(end -2.500122 -2.999994)
			(stroke
				(width 0.1)
				(type default)
			)
			(layer "F.Fab")
		)
		(fp_line
			(start -2.500122 -2.999994)
			(end 2.500122 -2.999994)
			(stroke
				(width 0.1)
				(type default)
			)
			(layer "F.Fab")
		)
		(fp_poly
			(pts
				(xy -4.218432 -2.783078) (xy -4.218432 -1.767078) (xy -3.202432 -2.275078)
			)
			(stroke
				(width 0)
				(type default)
			)
			(fill yes)
			(layer "F.Fab")
		)
		(pad "1" smd rect
			(at -2.400046 -2.275078 270)
			(size 0.2286 0.6096)
			(layers "F.Cu" "F.Mask" "F.Paste")
			(net "PVDDCR_CPU0_P0_VOS6")
		)
		(pad "2" smd rect
			(at -2.400046 -1.82499 270)
			(size 0.2286 0.6096)
			(layers "F.Cu" "F.Mask" "F.Paste")
			(net "GND")
		)
		(pad "3" smd rect
			(at -2.400046 -1.374902 270)
			(size 0.2286 0.6096)
			(layers "F.Cu" "F.Mask" "F.Paste")
			(net "PVDDCR_CPU0_P0_VCC6")
		)
		(pad "4" smd rect
			(at -2.400046 -0.925068 270)
			(size 0.2286 0.6096)
			(layers "F.Cu" "F.Mask" "F.Paste")
			(net "PVDDCR_CPU0_P0_PVCC")
		)
		(pad "5" smd rect
			(at -2.400046 -0.47498 270)
			(size 0.2286 0.6096)
			(layers "F.Cu" "F.Mask" "F.Paste")
			(net "GND")
		)
		(pad "6" smd rect
			(at -2.400046 -0.024892 270)
			(size 0.2286 0.6096)
			(layers "F.Cu" "F.Mask" "F.Paste")
			(net "NC_PVDDCR_CPU0_P0_GL1_6")
		)
		(pad "7_9-20_24" smd circle
			(at 0 1.150112 270)
			(size 0 0)
			(layers "F.Cu" "F.Mask" "F.Paste")
			(net "GND")
		)
		(pad "10_19" smd rect
			(at 0 2.899918 270)
			(size 0.6096 4.318)
			(layers "F.Cu" "F.Mask" "F.Paste")
			(net "SW_PVDDCR_CPU0_P0_SW6")
		)
		(pad "25_29" smd rect
			(at 1.549908 -1.279906 90)
			(size 2.0574 2.3114)
			(layers "F.Cu" "F.Mask" "F.Paste")
			(net "SW_P12V_AUX_PVDDCR_CPU0_P0_FLT")
		)
		(pad "30" smd rect
			(at 2.05994 -2.899918 180)
			(size 0.2286 0.6096)
			(layers "F.Cu" "F.Mask" "F.Paste")
			(net "SW_P12V_AUX_PVDDCR_CPU0_P0_FLT")
		)
		(pad "31" smd rect
			(at 1.610106 -2.899918 180)
			(size 0.2286 0.6096)
			(layers "F.Cu" "F.Mask" "F.Paste")
			(net "NC_PVDDCR_CPU0_P0_DNC6")
		)
		(pad "32" smd rect
			(at 1.160018 -2.899918 180)
			(size 0.2286 0.6096)
			(layers "F.Cu" "F.Mask" "F.Paste")
			(net "SW_PVDDCR_CPU0_P0_PH6")
		)
		(pad "33" smd rect
			(at 0.70993 -2.899918 180)
			(size 0.2286 0.6096)
			(layers "F.Cu" "F.Mask" "F.Paste")
			(net "SW_PVDDCR_CPU0_P0_BOOT6")
		)
		(pad "34" smd rect
			(at 0.260096 -2.899918 180)
			(size 0.2286 0.6096)
			(layers "F.Cu" "F.Mask" "F.Paste")
			(net "PVDDCR_CPU0_P0_PWM6")
		)
		(pad "35" smd rect
			(at -0.189992 -2.899918 180)
			(size 0.2286 0.6096)
			(layers "F.Cu" "F.Mask" "F.Paste")
			(net "PVDDCR_CPU0_P0_VCC6")
		)
		(pad "36" smd rect
			(at -0.64008 -2.899918 180)
			(size 0.2286 0.6096)
			(layers "F.Cu" "F.Mask" "F.Paste")
			(net "PVDDCR_CPU0_P0_TEMP0")
		)
		(pad "37" smd rect
			(at -1.089914 -2.899918 180)
			(size 0.2286 0.6096)
			(layers "F.Cu" "F.Mask" "F.Paste")
			(net "PVDDCR_CPU0_P0_LSET6")
		)
		(pad "38" smd rect
			(at -1.540002 -2.899918 180)
			(size 0.2286 0.6096)
			(layers "F.Cu" "F.Mask" "F.Paste")
			(net "PVDDCR_CPU0_P0_IMON6")
		)
		(pad "39" smd rect
			(at -1.99009 -2.899918 180)
			(size 0.2286 0.6096)
			(layers "F.Cu" "F.Mask" "F.Paste")
			(net "PVDDCR_CPU0_P0_VCCS")
		)
		(pad "40" smd rect
			(at -0.87503 -1.27508 180)
			(size 1.7526 1.9558)
			(layers "F.Cu" "F.Mask" "F.Paste")
			(net "GND")
		)
		(pad "41" smd rect
			(at -1.525016 0.249936 90)
			(size 0.3048 0.4572)
			(layers "F.Cu" "F.Mask" "F.Paste")
			(net "NC_PVDDCR_CPU0_P0_GL2_6")
		)
		(zone
			(layer "F.Cu")
			(hatch none 0.5)
			(connect_pads
				(clearance 0)
			)
			(min_thickness 0.25)
			(keepout
				(tracks not_allowed)
				(vias allowed)
				(pads allowed)
				(copperpour not_allowed)
				(footprints allowed)
			)
			(placement
				(enabled no)
				(sheetname "")
			)
			(fill
				(thermal_gap 0.5)
				(thermal_bridge_width 0.5)
				(island_removal_mode 0)
			)
			(polygon
				(pts
					(xy 350.2279 -163.726114) (xy 350.2279 -163.390072) (xy 345.227656 -163.390072) (xy 345.227656 -163.711128)
					(xy 345.517978 -163.711128) (xy 345.517978 -163.683696) (xy 349.937578 -163.683696) (xy 349.937578 -163.726114)
				)
			)
		)
		(zone
			(layer "F.Cu")
			(hatch none 0.5)
			(connect_pads
				(clearance 0)
			)
			(min_thickness 0.25)
			(keepout
				(tracks not_allowed)
				(vias allowed)
				(pads allowed)
				(copperpour not_allowed)
				(footprints allowed)
			)
			(placement
				(enabled no)
				(sheetname "")
			)
			(fill
				(thermal_gap 0.5)
				(thermal_bridge_width 0.5)
				(island_removal_mode 0)
			)
			(polygon
				(pts
					(xy 347.675708 -160.892998) (xy 347.675708 -158.835598) (xy 349.529908 -158.835598) (xy 349.529908 -159.076644)
					(xy 349.772224 -159.076644) (xy 349.772224 -158.59506) (xy 345.886024 -158.59506) (xy 345.886024 -158.779972)
					(xy 347.38437 -158.779972) (xy 347.38437 -160.938972) (xy 345.227656 -160.938972) (xy 345.227656 -161.188654)
					(xy 347.380052 -161.188654)
				)
			)
		)
	)
	(footprint ""
		(layer "F.Cu")
		(at 410.690822 -416.899344 -90)
		(property "Reference" "C6592"
			(at 0 0 270)
			(layer "F.SilkS")
			(hide yes)
			(effects
				(font
					(size 1.27 1.27)
				)
			)
		)
		(property "Value" ""
			(at 0 0 270)
			(layer "F.Fab")
			(effects
				(font
					(size 1.27 1.27)
				)
			)
		)
		(duplicate_pad_numbers_are_jumpers no)
		(fp_line
			(start -0.299974 0.150114)
			(end -0.299974 -0.150114)
			(stroke
				(width 0.1)
				(type default)
			)
			(layer "F.Fab")
		)
		(fp_line
			(start 0.299974 0.150114)
			(end -0.299974 0.150114)
			(stroke
				(width 0.1)
				(type default)
			)
			(layer "F.Fab")
		)
		(fp_line
			(start -0.299974 -0.150114)
			(end 0.299974 -0.150114)
			(stroke
				(width 0.1)
				(type default)
			)
			(layer "F.Fab")
		)
		(fp_line
			(start 0.299974 -0.150114)
			(end 0.299974 0.150114)
			(stroke
				(width 0.1)
				(type default)
			)
			(layer "F.Fab")
		)
		(pad "1" smd rect
			(at -0.2667 0 270)
			(size 0.3048 0.381)
			(layers "F.Cu" "F.Mask" "F.Paste")
			(net "P5E_CPU0_P2_TX_BUF_C_DN<13>")
		)
		(pad "2" smd rect
			(at 0.2667 0 270)
			(size 0.3048 0.381)
			(layers "F.Cu" "F.Mask" "F.Paste")
			(net "P5E_CPU0_P2_TX_BUF_DN<13>")
		)
	)
	(footprint ""
		(layer "F.Cu")
		(at 380.972822 -416.899344 -90)
		(property "Reference" "C6571"
			(at 0 0 270)
			(layer "F.SilkS")
			(hide yes)
			(effects
				(font
					(size 1.27 1.27)
				)
			)
		)
		(property "Value" ""
			(at 0 0 270)
			(layer "F.Fab")
			(effects
				(font
					(size 1.27 1.27)
				)
			)
		)
		(duplicate_pad_numbers_are_jumpers no)
		(fp_line
			(start -0.299974 0.150114)
			(end -0.299974 -0.150114)
			(stroke
				(width 0.1)
				(type default)
			)
			(layer "F.Fab")
		)
		(fp_line
			(start 0.299974 0.150114)
			(end -0.299974 0.150114)
			(stroke
				(width 0.1)
				(type default)
			)
			(layer "F.Fab")
		)
		(fp_line
			(start -0.299974 -0.150114)
			(end 0.299974 -0.150114)
			(stroke
				(width 0.1)
				(type default)
			)
			(layer "F.Fab")
		)
		(fp_line
			(start 0.299974 -0.150114)
			(end 0.299974 0.150114)
			(stroke
				(width 0.1)
				(type default)
			)
			(layer "F.Fab")
		)
		(pad "1" smd rect
			(at -0.2667 0 270)
			(size 0.3048 0.381)
			(layers "F.Cu" "F.Mask" "F.Paste")
			(net "P5E_CPU0_P2_TX_BUF_C_DP<3>")
		)
		(pad "2" smd rect
			(at 0.2667 0 270)
			(size 0.3048 0.381)
			(layers "F.Cu" "F.Mask" "F.Paste")
			(net "P5E_CPU0_P2_TX_BUF_DP<3>")
		)
	)
	(footprint ""
		(layer "F.Cu")
		(at 302.241458 -111.811308 180)
		(property "Reference" "R62"
			(at 0 0 180)
			(layer "F.SilkS")
			(hide yes)
			(effects
				(font
					(size 1.27 1.27)
				)
			)
		)
		(property "Value" ""
			(at 0 0 180)
			(layer "F.Fab")
			(effects
				(font
					(size 1.27 1.27)
				)
			)
		)
		(duplicate_pad_numbers_are_jumpers no)
		(fp_line
			(start 0.7874 0.4064)
			(end -0.7874 0.4064)
			(stroke
				(width 0.1524)
				(type default)
			)
			(layer "F.SilkS")
		)
		(fp_line
			(start 0.7874 -0.4064)
			(end 0.7874 0.4064)
			(stroke
				(width 0.1524)
				(type default)
			)
			(layer "F.SilkS")
		)
		(fp_line
			(start -0.7874 0.4064)
			(end -0.7874 -0.4064)
			(stroke
				(width 0.1524)
				(type default)
			)
			(layer "F.SilkS")
		)
		(fp_line
			(start -0.7874 -0.4064)
			(end 0.7874 -0.4064)
			(stroke
				(width 0.1524)
				(type default)
			)
			(layer "F.SilkS")
		)
		(fp_line
			(start 0.67945 0.3048)
			(end 0.120396 0.3048)
			(stroke
				(width 0.1)
				(type default)
			)
			(layer "F.Fab")
		)
		(fp_line
			(start 0.67945 -0.3048)
			(end 0.67945 0.3048)
			(stroke
				(width 0.1)
				(type default)
			)
			(layer "F.Fab")
		)
		(fp_line
			(start 0.12065 -0.2794)
			(end 0.12065 -0.3048)
			(stroke
				(width 0.1)
				(type default)
			)
			(layer "F.Fab")
		)
		(fp_line
			(start 0.12065 -0.3048)
			(end 0.67945 -0.3048)
			(stroke
				(width 0.1)
				(type default)
			)
			(layer "F.Fab")
		)
		(fp_line
			(start 0.120396 0.3048)
			(end 0.120396 0.2794)
			(stroke
				(width 0.1)
				(type default)
			)
			(layer "F.Fab")
		)
		(fp_line
			(start 0.120396 0.2794)
			(end -0.12065 0.2794)
			(stroke
				(width 0.1)
				(type default)
			)
			(layer "F.Fab")
		)
		(fp_line
			(start -0.12065 0.3048)
			(end -0.67945 0.3048)
			(stroke
				(width 0.1)
				(type default)
			)
			(layer "F.Fab")
		)
		(fp_line
			(start -0.12065 0.2794)
			(end -0.12065 0.3048)
			(stroke
				(width 0.1)
				(type default)
			)
			(layer "F.Fab")
		)
		(fp_line
			(start -0.12065 -0.2794)
			(end 0.12065 -0.2794)
			(stroke
				(width 0.1)
				(type default)
			)
			(layer "F.Fab")
		)
		(fp_line
			(start -0.12065 -0.305054)
			(end -0.12065 -0.2794)
			(stroke
				(width 0.1)
				(type default)
			)
			(layer "F.Fab")
		)
		(fp_line
			(start -0.67945 0.3048)
			(end -0.67945 -0.305054)
			(stroke
				(width 0.1)
				(type default)
			)
			(layer "F.Fab")
		)
		(fp_line
			(start -0.67945 -0.305054)
			(end -0.12065 -0.305054)
			(stroke
				(width 0.1)
				(type default)
			)
			(layer "F.Fab")
		)
		(pad "1" smd circle
			(at -0.40005 0 180)
			(size 0 0)
			(layers "F.Cu" "F.Mask" "F.Paste")
			(net "CPU_FRU_ADDR1")
		)
		(pad "2" smd circle
			(at 0.40005 0 180)
			(size 0 0)
			(layers "F.Cu" "F.Mask" "F.Paste")
			(net "GND")
		)
	)
	(footprint ""
		(layer "F.Cu")
		(at 367.787936 -403.818852 -90)
		(property "Reference" "R1107"
			(at 0 0 270)
			(layer "F.SilkS")
			(hide yes)
			(effects
				(font
					(size 1.27 1.27)
				)
			)
		)
		(property "Value" ""
			(at 0 0 270)
			(layer "F.Fab")
			(effects
				(font
					(size 1.27 1.27)
				)
			)
		)
		(duplicate_pad_numbers_are_jumpers no)
		(fp_line
			(start -0.32512 0.175006)
			(end -0.32512 -0.175006)
			(stroke
				(width 0.1)
				(type default)
			)
			(layer "F.Fab")
		)
		(fp_line
			(start 0.32512 0.175006)
			(end -0.32512 0.175006)
			(stroke
				(width 0.1)
				(type default)
			)
			(layer "F.Fab")
		)
		(fp_line
			(start -0.32512 -0.175006)
			(end 0.32512 -0.175006)
			(stroke
				(width 0.1)
				(type default)
			)
			(layer "F.Fab")
		)
		(fp_line
			(start 0.32512 -0.175006)
			(end 0.32512 0.175006)
			(stroke
				(width 0.1)
				(type default)
			)
			(layer "F.Fab")
		)
		(pad "1" smd rect
			(at -0.2667 0 270)
			(size 0.3048 0.381)
			(layers "F.Cu" "F.Mask" "F.Paste")
			(net "P1V8_CPU0_RT_1D")
		)
		(pad "2" smd rect
			(at 0.2667 0 90)
			(size 0.3048 0.381)
			(layers "F.Cu" "F.Mask" "F.Paste")
			(net "RST_RT_CPU0_P3_RESET_R_N")
		)
	)
	(footprint ""
		(layer "F.Cu")
		(at 66.47434 -52.74564)
		(property "Reference" "R1524"
			(at 0 0 0)
			(layer "F.SilkS")
			(hide yes)
			(effects
				(font
					(size 1.27 1.27)
				)
			)
		)
		(property "Value" ""
			(at 0 0 0)
			(layer "F.Fab")
			(effects
				(font
					(size 1.27 1.27)
				)
			)
		)
		(duplicate_pad_numbers_are_jumpers no)
		(fp_line
			(start -0.7874 -0.4064)
			(end 0.7874 -0.4064)
			(stroke
				(width 0.1524)
				(type default)
			)
			(layer "F.SilkS")
		)
		(fp_line
			(start -0.7874 0.4064)
			(end -0.7874 -0.4064)
			(stroke
				(width 0.1524)
				(type default)
			)
			(layer "F.SilkS")
		)
		(fp_line
			(start 0.7874 -0.4064)
			(end 0.7874 0.4064)
			(stroke
				(width 0.1524)
				(type default)
			)
			(layer "F.SilkS")
		)
		(fp_line
			(start 0.7874 0.4064)
			(end -0.7874 0.4064)
			(stroke
				(width 0.1524)
				(type default)
			)
			(layer "F.SilkS")
		)
		(fp_line
			(start -0.67945 -0.305054)
			(end -0.12065 -0.305054)
			(stroke
				(width 0.1)
				(type default)
			)
			(layer "F.Fab")
		)
		(fp_line
			(start -0.67945 0.3048)
			(end -0.67945 -0.305054)
			(stroke
				(width 0.1)
				(type default)
			)
			(layer "F.Fab")
		)
		(fp_line
			(start -0.12065 -0.305054)
			(end -0.12065 -0.2794)
			(stroke
				(width 0.1)
				(type default)
			)
			(layer "F.Fab")
		)
		(fp_line
			(start -0.12065 -0.2794)
			(end 0.12065 -0.2794)
			(stroke
				(width 0.1)
				(type default)
			)
			(layer "F.Fab")
		)
		(fp_line
			(start -0.12065 0.2794)
			(end -0.12065 0.3048)
			(stroke
				(width 0.1)
				(type default)
			)
			(layer "F.Fab")
		)
		(fp_line
			(start -0.12065 0.3048)
			(end -0.67945 0.3048)
			(stroke
				(width 0.1)
				(type default)
			)
			(layer "F.Fab")
		)
		(fp_line
			(start 0.120396 0.2794)
			(end -0.12065 0.2794)
			(stroke
				(width 0.1)
				(type default)
			)
			(layer "F.Fab")
		)
		(fp_line
			(start 0.120396 0.3048)
			(end 0.120396 0.2794)
			(stroke
				(width 0.1)
				(type default)
			)
			(layer "F.Fab")
		)
		(fp_line
			(start 0.12065 -0.3048)
			(end 0.67945 -0.3048)
			(stroke
				(width 0.1)
				(type default)
			)
			(layer "F.Fab")
		)
		(fp_line
			(start 0.12065 -0.2794)
			(end 0.12065 -0.3048)
			(stroke
				(width 0.1)
				(type default)
			)
			(layer "F.Fab")
		)
		(fp_line
			(start 0.67945 -0.3048)
			(end 0.67945 0.3048)
			(stroke
				(width 0.1)
				(type default)
			)
			(layer "F.Fab")
		)
		(fp_line
			(start 0.67945 0.3048)
			(end 0.120396 0.3048)
			(stroke
				(width 0.1)
				(type default)
			)
			(layer "F.Fab")
		)
		(pad "1" smd circle
			(at -0.40005 0)
			(size 0 0)
			(layers "F.Cu" "F.Mask" "F.Paste")
			(net "HP_LVC3_OCP_V3_2_PWRGD_R2")
		)
		(pad "2" smd circle
			(at 0.40005 0)
			(size 0 0)
			(layers "F.Cu" "F.Mask" "F.Paste")
			(net "OCP_V3_2_P3V3_R3_PWRGD")
		)
	)
	(footprint ""
		(layer "F.Cu")
		(at 156.30779 -101.638862 -90)
		(property "Reference" "R3297"
			(at 0 0 270)
			(layer "F.SilkS")
			(hide yes)
			(effects
				(font
					(size 1.27 1.27)
				)
			)
		)
		(property "Value" ""
			(at 0 0 270)
			(layer "F.Fab")
			(effects
				(font
					(size 1.27 1.27)
				)
			)
		)
		(duplicate_pad_numbers_are_jumpers no)
		(fp_line
			(start -0.7874 0.4064)
			(end -0.7874 -0.4064)
			(stroke
				(width 0.1524)
				(type default)
			)
			(layer "F.SilkS")
		)
		(fp_line
			(start 0.7874 0.4064)
			(end -0.7874 0.4064)
			(stroke
				(width 0.1524)
				(type default)
			)
			(layer "F.SilkS")
		)
		(fp_line
			(start -0.7874 -0.4064)
			(end 0.7874 -0.4064)
			(stroke
				(width 0.1524)
				(type default)
			)
			(layer "F.SilkS")
		)
		(fp_line
			(start 0.7874 -0.4064)
			(end 0.7874 0.4064)
			(stroke
				(width 0.1524)
				(type default)
			)
			(layer "F.SilkS")
		)
		(fp_line
			(start -0.67945 0.3048)
			(end -0.67945 -0.305054)
			(stroke
				(width 0.1)
				(type default)
			)
			(layer "F.Fab")
		)
		(fp_line
			(start -0.12065 0.3048)
			(end -0.67945 0.3048)
			(stroke
				(width 0.1)
				(type default)
			)
			(layer "F.Fab")
		)
		(fp_line
			(start 0.120396 0.3048)
			(end 0.120396 0.2794)
			(stroke
				(width 0.1)
				(type default)
			)
			(layer "F.Fab")
		)
		(fp_line
			(start 0.67945 0.3048)
			(end 0.120396 0.3048)
			(stroke
				(width 0.1)
				(type default)
			)
			(layer "F.Fab")
		)
		(fp_line
			(start -0.12065 0.2794)
			(end -0.12065 0.3048)
			(stroke
				(width 0.1)
				(type default)
			)
			(layer "F.Fab")
		)
		(fp_line
			(start 0.120396 0.2794)
			(end -0.12065 0.2794)
			(stroke
				(width 0.1)
				(type default)
			)
			(layer "F.Fab")
		)
		(fp_line
			(start -0.12065 -0.2794)
			(end 0.12065 -0.2794)
			(stroke
				(width 0.1)
				(type default)
			)
			(layer "F.Fab")
		)
		(fp_line
			(start 0.12065 -0.2794)
			(end 0.12065 -0.3048)
			(stroke
				(width 0.1)
				(type default)
			)
			(layer "F.Fab")
		)
		(fp_line
			(start 0.12065 -0.3048)
			(end 0.67945 -0.3048)
			(stroke
				(width 0.1)
				(type default)
			)
			(layer "F.Fab")
		)
		(fp_line
			(start 0.67945 -0.3048)
			(end 0.67945 0.3048)
			(stroke
				(width 0.1)
				(type default)
			)
			(layer "F.Fab")
		)
		(fp_line
			(start -0.67945 -0.305054)
			(end -0.12065 -0.305054)
			(stroke
				(width 0.1)
				(type default)
			)
			(layer "F.Fab")
		)
		(fp_line
			(start -0.12065 -0.305054)
			(end -0.12065 -0.2794)
			(stroke
				(width 0.1)
				(type default)
			)
			(layer "F.Fab")
		)
		(pad "1" smd circle
			(at -0.40005 0 270)
			(size 0 0)
			(layers "F.Cu" "F.Mask" "F.Paste")
			(net "LED_HDD_ACTIVITY_B_N")
		)
		(pad "2" smd circle
			(at 0.40005 0 270)
			(size 0 0)
			(layers "F.Cu" "F.Mask" "F.Paste")
			(net "GND")
		)
	)
	(footprint ""
		(layer "F.Cu")
		(at 348.9325 -15.924276 90)
		(property "Reference" "D46"
			(at -3.12674 0.141732 90)
			(unlocked yes)
			(layer "F.SilkS")
			(effects
				(font
					(size 0.7874 0.5842)
					(thickness 0.1524)
				)
				(justify left)
			)
		)
		(property "Value" ""
			(at 0 0 90)
			(layer "F.Fab")
			(effects
				(font
					(size 1.27 1.27)
				)
			)
		)
		(duplicate_pad_numbers_are_jumpers no)
		(fp_line
			(start 1.16078 -0.4826)
			(end 1.16078 0.4826)
			(stroke
				(width 0.1524)
				(type default)
			)
			(layer "F.SilkS")
		)
		(fp_line
			(start 1.03378 -0.4826)
			(end 1.03378 0.4826)
			(stroke
				(width 0.1524)
				(type default)
			)
			(layer "F.SilkS")
		)
		(fp_line
			(start 0.90678 -0.4826)
			(end 0.90678 0.4826)
			(stroke
				(width 0.1524)
				(type default)
			)
			(layer "F.SilkS")
		)
		(fp_line
			(start -0.64008 -0.4826)
			(end 1.16078 -0.4826)
			(stroke
				(width 0.1524)
				(type default)
			)
			(layer "F.SilkS")
		)
		(fp_line
			(start -0.79248 -0.4826)
			(end 1.03378 -0.4826)
			(stroke
				(width 0.1524)
				(type default)
			)
			(layer "F.SilkS")
		)
		(fp_line
			(start -0.89408 -0.4826)
			(end 0.90678 -0.4826)
			(stroke
				(width 0.1524)
				(type default)
			)
			(layer "F.SilkS")
		)
		(fp_line
			(start 1.16078 0.4826)
			(end -0.64008 0.4826)
			(stroke
				(width 0.1524)
				(type default)
			)
			(layer "F.SilkS")
		)
		(fp_line
			(start 1.03378 0.4826)
			(end -0.79248 0.4826)
			(stroke
				(width 0.1524)
				(type default)
			)
			(layer "F.SilkS")
		)
		(fp_line
			(start 0.90678 0.4826)
			(end -0.90678 0.4826)
			(stroke
				(width 0.1524)
				(type default)
			)
			(layer "F.SilkS")
		)
		(fp_line
			(start -0.90678 0.4826)
			(end -0.90678 -0.4699)
			(stroke
				(width 0.1524)
				(type default)
			)
			(layer "F.SilkS")
		)
		(fp_line
			(start 0.499872 -0.249936)
			(end 0.499872 0.249936)
			(stroke
				(width 0.1)
				(type default)
			)
			(layer "F.Fab")
		)
		(fp_line
			(start -0.499872 -0.249936)
			(end 0.499872 -0.249936)
			(stroke
				(width 0.1)
				(type default)
			)
			(layer "F.Fab")
		)
		(fp_line
			(start 0.499872 0.249936)
			(end -0.499872 0.249936)
			(stroke
				(width 0.1)
				(type default)
			)
			(layer "F.Fab")
		)
		(fp_line
			(start -0.499872 0.249936)
			(end -0.499872 -0.249936)
			(stroke
				(width 0.1)
				(type default)
			)
			(layer "F.Fab")
		)
		(pad "A" smd rect
			(at -0.47498 0 90)
			(size 0.6096 0.7112)
			(layers "F.Cu" "F.Mask" "F.Paste")
			(net "PU_P12V_ALL_PWROK_LED")
		)
		(pad "C" smd rect
			(at 0.47498 0 90)
			(size 0.6096 0.7112)
			(layers "F.Cu" "F.Mask" "F.Paste")
			(net "P12V_ALL_PWROK_N")
		)
	)
	(footprint ""
		(layer "F.Cu")
		(at 252.961648 -56.193182)
		(property "Reference" "PR3953"
			(at 0 0 0)
			(layer "F.SilkS")
			(hide yes)
			(effects
				(font
					(size 1.27 1.27)
				)
			)
		)
		(property "Value" ""
			(at 0 0 0)
			(layer "F.Fab")
			(effects
				(font
					(size 1.27 1.27)
				)
			)
		)
		(duplicate_pad_numbers_are_jumpers no)
		(fp_line
			(start -0.7874 -0.4064)
			(end 0.7874 -0.4064)
			(stroke
				(width 0.1524)
				(type default)
			)
			(layer "F.SilkS")
		)
		(fp_line
			(start -0.7874 0.4064)
			(end -0.7874 -0.4064)
			(stroke
				(width 0.1524)
				(type default)
			)
			(layer "F.SilkS")
		)
		(fp_line
			(start 0.7874 -0.4064)
			(end 0.7874 0.4064)
			(stroke
				(width 0.1524)
				(type default)
			)
			(layer "F.SilkS")
		)
		(fp_line
			(start 0.7874 0.4064)
			(end -0.7874 0.4064)
			(stroke
				(width 0.1524)
				(type default)
			)
			(layer "F.SilkS")
		)
		(fp_line
			(start -0.67945 -0.305054)
			(end -0.12065 -0.305054)
			(stroke
				(width 0.1)
				(type default)
			)
			(layer "F.Fab")
		)
		(fp_line
			(start -0.67945 0.3048)
			(end -0.67945 -0.305054)
			(stroke
				(width 0.1)
				(type default)
			)
			(layer "F.Fab")
		)
		(fp_line
			(start -0.12065 -0.305054)
			(end -0.12065 -0.2794)
			(stroke
				(width 0.1)
				(type default)
			)
			(layer "F.Fab")
		)
		(fp_line
			(start -0.12065 -0.2794)
			(end 0.12065 -0.2794)
			(stroke
				(width 0.1)
				(type default)
			)
			(layer "F.Fab")
		)
		(fp_line
			(start -0.12065 0.2794)
			(end -0.12065 0.3048)
			(stroke
				(width 0.1)
				(type default)
			)
			(layer "F.Fab")
		)
		(fp_line
			(start -0.12065 0.3048)
			(end -0.67945 0.3048)
			(stroke
				(width 0.1)
				(type default)
			)
			(layer "F.Fab")
		)
		(fp_line
			(start 0.120396 0.2794)
			(end -0.12065 0.2794)
			(stroke
				(width 0.1)
				(type default)
			)
			(layer "F.Fab")
		)
		(fp_line
			(start 0.120396 0.3048)
			(end 0.120396 0.2794)
			(stroke
				(width 0.1)
				(type default)
			)
			(layer "F.Fab")
		)
		(fp_line
			(start 0.12065 -0.3048)
			(end 0.67945 -0.3048)
			(stroke
				(width 0.1)
				(type default)
			)
			(layer "F.Fab")
		)
		(fp_line
			(start 0.12065 -0.2794)
			(end 0.12065 -0.3048)
			(stroke
				(width 0.1)
				(type default)
			)
			(layer "F.Fab")
		)
		(fp_line
			(start 0.67945 -0.3048)
			(end 0.67945 0.3048)
			(stroke
				(width 0.1)
				(type default)
			)
			(layer "F.Fab")
		)
		(fp_line
			(start 0.67945 0.3048)
			(end 0.120396 0.3048)
			(stroke
				(width 0.1)
				(type default)
			)
			(layer "F.Fab")
		)
		(pad "1" smd circle
			(at -0.40005 0)
			(size 0 0)
			(layers "F.Cu" "F.Mask" "F.Paste")
			(net "P12V_AUX")
		)
		(pad "2" smd circle
			(at 0.40005 0)
			(size 0 0)
			(layers "F.Cu" "F.Mask" "F.Paste")
			(net "P12V_E1S_OV_FB_0")
		)
	)
	(footprint ""
		(layer "F.Cu")
		(at 448.717924 -397.399002 -90)
		(property "Reference" "PC6554_1"
			(at 0 0 270)
			(layer "F.SilkS")
			(hide yes)
			(effects
				(font
					(size 1.27 1.27)
				)
			)
		)
		(property "Value" ""
			(at 0 0 270)
			(layer "F.Fab")
			(effects
				(font
					(size 1.27 1.27)
				)
			)
		)
		(duplicate_pad_numbers_are_jumpers no)
		(fp_line
			(start -0.7874 0.4064)
			(end -0.7874 -0.4064)
			(stroke
				(width 0.1524)
				(type default)
			)
			(layer "F.SilkS")
		)
		(fp_line
			(start 0.7874 0.4064)
			(end -0.7874 0.4064)
			(stroke
				(width 0.1524)
				(type default)
			)
			(layer "F.SilkS")
		)
		(fp_line
			(start -0.7874 -0.4064)
			(end 0.7874 -0.4064)
			(stroke
				(width 0.1524)
				(type default)
			)
			(layer "F.SilkS")
		)
		(fp_line
			(start 0.7874 -0.4064)
			(end 0.7874 0.4064)
			(stroke
				(width 0.1524)
				(type default)
			)
			(layer "F.SilkS")
		)
		(fp_line
			(start -0.67945 0.3048)
			(end -0.67945 -0.305054)
			(stroke
				(width 0.1)
				(type default)
			)
			(layer "F.Fab")
		)
		(fp_line
			(start -0.12065 0.3048)
			(end -0.67945 0.3048)
			(stroke
				(width 0.1)
				(type default)
			)
			(layer "F.Fab")
		)
		(fp_line
			(start 0.120396 0.3048)
			(end 0.120396 0.2794)
			(stroke
				(width 0.1)
				(type default)
			)
			(layer "F.Fab")
		)
		(fp_line
			(start 0.67945 0.3048)
			(end 0.120396 0.3048)
			(stroke
				(width 0.1)
				(type default)
			)
			(layer "F.Fab")
		)
		(fp_line
			(start -0.12065 0.2794)
			(end -0.12065 0.3048)
			(stroke
				(width 0.1)
				(type default)
			)
			(layer "F.Fab")
		)
		(fp_line
			(start 0.120396 0.2794)
			(end -0.12065 0.2794)
			(stroke
				(width 0.1)
				(type default)
			)
			(layer "F.Fab")
		)
		(fp_line
			(start -0.12065 -0.2794)
			(end 0.12065 -0.2794)
			(stroke
				(width 0.1)
				(type default)
			)
			(layer "F.Fab")
		)
		(fp_line
			(start 0.12065 -0.2794)
			(end 0.12065 -0.3048)
			(stroke
				(width 0.1)
				(type default)
			)
			(layer "F.Fab")
		)
		(fp_line
			(start 0.12065 -0.3048)
			(end 0.67945 -0.3048)
			(stroke
				(width 0.1)
				(type default)
			)
			(layer "F.Fab")
		)
		(fp_line
			(start 0.67945 -0.3048)
			(end 0.67945 0.3048)
			(stroke
				(width 0.1)
				(type default)
			)
			(layer "F.Fab")
		)
		(fp_line
			(start -0.67945 -0.305054)
			(end -0.12065 -0.305054)
			(stroke
				(width 0.1)
				(type default)
			)
			(layer "F.Fab")
		)
		(fp_line
			(start -0.12065 -0.305054)
			(end -0.12065 -0.2794)
			(stroke
				(width 0.1)
				(type default)
			)
			(layer "F.Fab")
		)
		(pad "1" smd circle
			(at -0.40005 0 270)
			(size 0 0)
			(layers "F.Cu" "F.Mask" "F.Paste")
			(net "SW_P12V_AUX_P0V9_RETIMER_CPU0_FLT")
		)
		(pad "2" smd circle
			(at 0.40005 0 270)
			(size 0 0)
			(layers "F.Cu" "F.Mask" "F.Paste")
			(net "GND")
		)
	)
	(footprint ""
		(layer "F.Cu")
		(at 166.3192 -433.878736 180)
		(property "Reference" "R3106"
			(at 0 0 180)
			(layer "F.SilkS")
			(hide yes)
			(effects
				(font
					(size 1.27 1.27)
				)
			)
		)
		(property "Value" ""
			(at 0 0 180)
			(layer "F.Fab")
			(effects
				(font
					(size 1.27 1.27)
				)
			)
		)
		(duplicate_pad_numbers_are_jumpers no)
		(fp_line
			(start 0.7874 0.4064)
			(end -0.7874 0.4064)
			(stroke
				(width 0.1524)
				(type default)
			)
			(layer "F.SilkS")
		)
		(fp_line
			(start 0.7874 -0.4064)
			(end 0.7874 0.4064)
			(stroke
				(width 0.1524)
				(type default)
			)
			(layer "F.SilkS")
		)
		(fp_line
			(start -0.7874 0.4064)
			(end -0.7874 -0.4064)
			(stroke
				(width 0.1524)
				(type default)
			)
			(layer "F.SilkS")
		)
		(fp_line
			(start -0.7874 -0.4064)
			(end 0.7874 -0.4064)
			(stroke
				(width 0.1524)
				(type default)
			)
			(layer "F.SilkS")
		)
		(fp_line
			(start 0.67945 0.3048)
			(end 0.120396 0.3048)
			(stroke
				(width 0.1)
				(type default)
			)
			(layer "F.Fab")
		)
		(fp_line
			(start 0.67945 -0.3048)
			(end 0.67945 0.3048)
			(stroke
				(width 0.1)
				(type default)
			)
			(layer "F.Fab")
		)
		(fp_line
			(start 0.12065 -0.2794)
			(end 0.12065 -0.3048)
			(stroke
				(width 0.1)
				(type default)
			)
			(layer "F.Fab")
		)
		(fp_line
			(start 0.12065 -0.3048)
			(end 0.67945 -0.3048)
			(stroke
				(width 0.1)
				(type default)
			)
			(layer "F.Fab")
		)
		(fp_line
			(start 0.120396 0.3048)
			(end 0.120396 0.2794)
			(stroke
				(width 0.1)
				(type default)
			)
			(layer "F.Fab")
		)
		(fp_line
			(start 0.120396 0.2794)
			(end -0.12065 0.2794)
			(stroke
				(width 0.1)
				(type default)
			)
			(layer "F.Fab")
		)
		(fp_line
			(start -0.12065 0.3048)
			(end -0.67945 0.3048)
			(stroke
				(width 0.1)
				(type default)
			)
			(layer "F.Fab")
		)
		(fp_line
			(start -0.12065 0.2794)
			(end -0.12065 0.3048)
			(stroke
				(width 0.1)
				(type default)
			)
			(layer "F.Fab")
		)
		(fp_line
			(start -0.12065 -0.2794)
			(end 0.12065 -0.2794)
			(stroke
				(width 0.1)
				(type default)
			)
			(layer "F.Fab")
		)
		(fp_line
			(start -0.12065 -0.305054)
			(end -0.12065 -0.2794)
			(stroke
				(width 0.1)
				(type default)
			)
			(layer "F.Fab")
		)
		(fp_line
			(start -0.67945 0.3048)
			(end -0.67945 -0.305054)
			(stroke
				(width 0.1)
				(type default)
			)
			(layer "F.Fab")
		)
		(fp_line
			(start -0.67945 -0.305054)
			(end -0.12065 -0.305054)
			(stroke
				(width 0.1)
				(type default)
			)
			(layer "F.Fab")
		)
		(pad "1" smd circle
			(at -0.40005 0 180)
			(size 0 0)
			(layers "F.Cu" "F.Mask" "F.Paste")
			(net "SMB_BMC_SWB_SDA")
		)
		(pad "2" smd circle
			(at 0.40005 0 180)
			(size 0 0)
			(layers "F.Cu" "F.Mask" "F.Paste")
			(net "SMB_BMC_SWB_R_SDA")
		)
	)
	(footprint ""
		(layer "F.Cu")
		(at 332.071472 -396.412974 90)
		(property "Reference" "R630"
			(at 0 0 90)
			(layer "F.SilkS")
			(hide yes)
			(effects
				(font
					(size 1.27 1.27)
				)
			)
		)
		(property "Value" ""
			(at 0 0 90)
			(layer "F.Fab")
			(effects
				(font
					(size 1.27 1.27)
				)
			)
		)
		(duplicate_pad_numbers_are_jumpers no)
		(fp_line
			(start 0.32512 -0.175006)
			(end 0.32512 0.175006)
			(stroke
				(width 0.1)
				(type default)
			)
			(layer "F.Fab")
		)
		(fp_line
			(start -0.32512 -0.175006)
			(end 0.32512 -0.175006)
			(stroke
				(width 0.1)
				(type default)
			)
			(layer "F.Fab")
		)
		(fp_line
			(start 0.32512 0.175006)
			(end -0.32512 0.175006)
			(stroke
				(width 0.1)
				(type default)
			)
			(layer "F.Fab")
		)
		(fp_line
			(start -0.32512 0.175006)
			(end -0.32512 -0.175006)
			(stroke
				(width 0.1)
				(type default)
			)
			(layer "F.Fab")
		)
		(pad "1" smd rect
			(at -0.2667 0 90)
			(size 0.3048 0.381)
			(layers "F.Cu" "F.Mask" "F.Paste")
			(net "CLK_100M_RETIMER_CPU0_P1_DP")
		)
		(pad "2" smd rect
			(at 0.2667 0 270)
			(size 0.3048 0.381)
			(layers "F.Cu" "F.Mask" "F.Paste")
			(net "GND")
		)
	)
	(footprint ""
		(layer "F.Cu")
		(at 437.240172 -32.173418 90)
		(property "Reference" "R3871"
			(at 0 0 90)
			(layer "F.SilkS")
			(hide yes)
			(effects
				(font
					(size 1.27 1.27)
				)
			)
		)
		(property "Value" ""
			(at 0 0 90)
			(layer "F.Fab")
			(effects
				(font
					(size 1.27 1.27)
				)
			)
		)
		(duplicate_pad_numbers_are_jumpers no)
		(fp_line
			(start 0.7874 -0.4064)
			(end 0.7874 0.4064)
			(stroke
				(width 0.1524)
				(type default)
			)
			(layer "F.SilkS")
		)
		(fp_line
			(start -0.7874 -0.4064)
			(end 0.7874 -0.4064)
			(stroke
				(width 0.1524)
				(type default)
			)
			(layer "F.SilkS")
		)
		(fp_line
			(start 0.7874 0.4064)
			(end -0.7874 0.4064)
			(stroke
				(width 0.1524)
				(type default)
			)
			(layer "F.SilkS")
		)
		(fp_line
			(start -0.7874 0.4064)
			(end -0.7874 -0.4064)
			(stroke
				(width 0.1524)
				(type default)
			)
			(layer "F.SilkS")
		)
		(fp_line
			(start -0.12065 -0.305054)
			(end -0.12065 -0.2794)
			(stroke
				(width 0.1)
				(type default)
			)
			(layer "F.Fab")
		)
		(fp_line
			(start -0.67945 -0.305054)
			(end -0.12065 -0.305054)
			(stroke
				(width 0.1)
				(type default)
			)
			(layer "F.Fab")
		)
		(fp_line
			(start 0.67945 -0.3048)
			(end 0.67945 0.3048)
			(stroke
				(width 0.1)
				(type default)
			)
			(layer "F.Fab")
		)
		(fp_line
			(start 0.12065 -0.3048)
			(end 0.67945 -0.3048)
			(stroke
				(width 0.1)
				(type default)
			)
			(layer "F.Fab")
		)
		(fp_line
			(start 0.12065 -0.2794)
			(end 0.12065 -0.3048)
			(stroke
				(width 0.1)
				(type default)
			)
			(layer "F.Fab")
		)
		(fp_line
			(start -0.12065 -0.2794)
			(end 0.12065 -0.2794)
			(stroke
				(width 0.1)
				(type default)
			)
			(layer "F.Fab")
		)
		(fp_line
			(start 0.120396 0.2794)
			(end -0.12065 0.2794)
			(stroke
				(width 0.1)
				(type default)
			)
			(layer "F.Fab")
		)
		(fp_line
			(start -0.12065 0.2794)
			(end -0.12065 0.3048)
			(stroke
				(width 0.1)
				(type default)
			)
			(layer "F.Fab")
		)
		(fp_line
			(start 0.67945 0.3048)
			(end 0.120396 0.3048)
			(stroke
				(width 0.1)
				(type default)
			)
			(layer "F.Fab")
		)
		(fp_line
			(start 0.120396 0.3048)
			(end 0.120396 0.2794)
			(stroke
				(width 0.1)
				(type default)
			)
			(layer "F.Fab")
		)
		(fp_line
			(start -0.12065 0.3048)
			(end -0.67945 0.3048)
			(stroke
				(width 0.1)
				(type default)
			)
			(layer "F.Fab")
		)
		(fp_line
			(start -0.67945 0.3048)
			(end -0.67945 -0.305054)
			(stroke
				(width 0.1)
				(type default)
			)
			(layer "F.Fab")
		)
		(pad "1" smd circle
			(at -0.40005 0 90)
			(size 0 0)
			(layers "F.Cu" "F.Mask" "F.Paste")
			(net "P12V_OCP_IMON_1")
		)
		(pad "2" smd circle
			(at 0.40005 0 90)
			(size 0 0)
			(layers "F.Cu" "F.Mask" "F.Paste")
			(net "P12V_OCP_SFF_ISENSE_MPS_MAM")
		)
	)
	(footprint ""
		(layer "F.Cu")
		(at 150.339044 -373.03583 -90)
		(property "Reference" "C762"
			(at 0 0 270)
			(layer "F.SilkS")
			(hide yes)
			(effects
				(font
					(size 1.27 1.27)
				)
			)
		)
		(property "Value" ""
			(at 0 0 270)
			(layer "F.Fab")
			(effects
				(font
					(size 1.27 1.27)
				)
			)
		)
		(duplicate_pad_numbers_are_jumpers no)
		(fp_line
			(start -0.299974 0.150114)
			(end -0.299974 -0.150114)
			(stroke
				(width 0.1)
				(type default)
			)
			(layer "F.Fab")
		)
		(fp_line
			(start 0.299974 0.150114)
			(end -0.299974 0.150114)
			(stroke
				(width 0.1)
				(type default)
			)
			(layer "F.Fab")
		)
		(fp_line
			(start -0.299974 -0.150114)
			(end 0.299974 -0.150114)
			(stroke
				(width 0.1)
				(type default)
			)
			(layer "F.Fab")
		)
		(fp_line
			(start 0.299974 -0.150114)
			(end 0.299974 0.150114)
			(stroke
				(width 0.1)
				(type default)
			)
			(layer "F.Fab")
		)
		(pad "1" smd rect
			(at -0.2667 0 270)
			(size 0.3048 0.381)
			(layers "F.Cu" "F.Mask" "F.Paste")
			(net "P5E_CPU1_P2_TX_C_DN<5>")
		)
		(pad "2" smd rect
			(at 0.2667 0 270)
			(size 0.3048 0.381)
			(layers "F.Cu" "F.Mask" "F.Paste")
			(net "P5E_CPU1_P2_TX_DN<5>")
		)
	)
	(footprint ""
		(layer "F.Cu")
		(at 16.645382 -105.56621 90)
		(property "Reference" "R2791"
			(at 0 0 90)
			(layer "F.SilkS")
			(hide yes)
			(effects
				(font
					(size 1.27 1.27)
				)
			)
		)
		(property "Value" ""
			(at 0 0 90)
			(layer "F.Fab")
			(effects
				(font
					(size 1.27 1.27)
				)
			)
		)
		(duplicate_pad_numbers_are_jumpers no)
		(fp_line
			(start 0.7874 -0.4064)
			(end 0.7874 0.4064)
			(stroke
				(width 0.1524)
				(type default)
			)
			(layer "F.SilkS")
		)
		(fp_line
			(start -0.7874 -0.4064)
			(end 0.7874 -0.4064)
			(stroke
				(width 0.1524)
				(type default)
			)
			(layer "F.SilkS")
		)
		(fp_line
			(start 0.7874 0.4064)
			(end -0.7874 0.4064)
			(stroke
				(width 0.1524)
				(type default)
			)
			(layer "F.SilkS")
		)
		(fp_line
			(start -0.7874 0.4064)
			(end -0.7874 -0.4064)
			(stroke
				(width 0.1524)
				(type default)
			)
			(layer "F.SilkS")
		)
		(fp_line
			(start -0.12065 -0.305054)
			(end -0.12065 -0.2794)
			(stroke
				(width 0.1)
				(type default)
			)
			(layer "F.Fab")
		)
		(fp_line
			(start -0.67945 -0.305054)
			(end -0.12065 -0.305054)
			(stroke
				(width 0.1)
				(type default)
			)
			(layer "F.Fab")
		)
		(fp_line
			(start 0.67945 -0.3048)
			(end 0.67945 0.3048)
			(stroke
				(width 0.1)
				(type default)
			)
			(layer "F.Fab")
		)
		(fp_line
			(start 0.12065 -0.3048)
			(end 0.67945 -0.3048)
			(stroke
				(width 0.1)
				(type default)
			)
			(layer "F.Fab")
		)
		(fp_line
			(start 0.12065 -0.2794)
			(end 0.12065 -0.3048)
			(stroke
				(width 0.1)
				(type default)
			)
			(layer "F.Fab")
		)
		(fp_line
			(start -0.12065 -0.2794)
			(end 0.12065 -0.2794)
			(stroke
				(width 0.1)
				(type default)
			)
			(layer "F.Fab")
		)
		(fp_line
			(start 0.120396 0.2794)
			(end -0.12065 0.2794)
			(stroke
				(width 0.1)
				(type default)
			)
			(layer "F.Fab")
		)
		(fp_line
			(start -0.12065 0.2794)
			(end -0.12065 0.3048)
			(stroke
				(width 0.1)
				(type default)
			)
			(layer "F.Fab")
		)
		(fp_line
			(start 0.67945 0.3048)
			(end 0.120396 0.3048)
			(stroke
				(width 0.1)
				(type default)
			)
			(layer "F.Fab")
		)
		(fp_line
			(start 0.120396 0.3048)
			(end 0.120396 0.2794)
			(stroke
				(width 0.1)
				(type default)
			)
			(layer "F.Fab")
		)
		(fp_line
			(start -0.12065 0.3048)
			(end -0.67945 0.3048)
			(stroke
				(width 0.1)
				(type default)
			)
			(layer "F.Fab")
		)
		(fp_line
			(start -0.67945 0.3048)
			(end -0.67945 -0.305054)
			(stroke
				(width 0.1)
				(type default)
			)
			(layer "F.Fab")
		)
		(pad "1" smd rect
			(at -0.40005 0 270)
			(size 0.4572 0.508)
			(layers "F.Cu" "F.Mask" "F.Paste")
			(net "USB2_HOST_BMC_B_DN")
		)
		(pad "2" smd rect
			(at 0.40005 0 270)
			(size 0.4572 0.508)
			(layers "F.Cu" "F.Mask" "F.Paste")
			(net "USB2_HOST_BMC_B_BUF_DN")
		)
	)
	(footprint ""
		(layer "F.Cu")
		(at 72.194928 -339.651848 -90)
		(property "Reference" "PC414"
			(at 0 0 270)
			(layer "F.SilkS")
			(hide yes)
			(effects
				(font
					(size 1.27 1.27)
				)
			)
		)
		(property "Value" ""
			(at 0 0 270)
			(layer "F.Fab")
			(effects
				(font
					(size 1.27 1.27)
				)
			)
		)
		(duplicate_pad_numbers_are_jumpers no)
		(fp_line
			(start -0.7874 0.4064)
			(end -0.7874 -0.4064)
			(stroke
				(width 0.1524)
				(type default)
			)
			(layer "F.SilkS")
		)
		(fp_line
			(start 0.7874 0.4064)
			(end -0.7874 0.4064)
			(stroke
				(width 0.1524)
				(type default)
			)
			(layer "F.SilkS")
		)
		(fp_line
			(start -0.7874 -0.4064)
			(end 0.7874 -0.4064)
			(stroke
				(width 0.1524)
				(type default)
			)
			(layer "F.SilkS")
		)
		(fp_line
			(start 0.7874 -0.4064)
			(end 0.7874 0.4064)
			(stroke
				(width 0.1524)
				(type default)
			)
			(layer "F.SilkS")
		)
		(fp_line
			(start -0.67945 0.3048)
			(end -0.67945 -0.305054)
			(stroke
				(width 0.1)
				(type default)
			)
			(layer "F.Fab")
		)
		(fp_line
			(start -0.12065 0.3048)
			(end -0.67945 0.3048)
			(stroke
				(width 0.1)
				(type default)
			)
			(layer "F.Fab")
		)
		(fp_line
			(start 0.120396 0.3048)
			(end 0.120396 0.2794)
			(stroke
				(width 0.1)
				(type default)
			)
			(layer "F.Fab")
		)
		(fp_line
			(start 0.67945 0.3048)
			(end 0.120396 0.3048)
			(stroke
				(width 0.1)
				(type default)
			)
			(layer "F.Fab")
		)
		(fp_line
			(start -0.12065 0.2794)
			(end -0.12065 0.3048)
			(stroke
				(width 0.1)
				(type default)
			)
			(layer "F.Fab")
		)
		(fp_line
			(start 0.120396 0.2794)
			(end -0.12065 0.2794)
			(stroke
				(width 0.1)
				(type default)
			)
			(layer "F.Fab")
		)
		(fp_line
			(start -0.12065 -0.2794)
			(end 0.12065 -0.2794)
			(stroke
				(width 0.1)
				(type default)
			)
			(layer "F.Fab")
		)
		(fp_line
			(start 0.12065 -0.2794)
			(end 0.12065 -0.3048)
			(stroke
				(width 0.1)
				(type default)
			)
			(layer "F.Fab")
		)
		(fp_line
			(start 0.12065 -0.3048)
			(end 0.67945 -0.3048)
			(stroke
				(width 0.1)
				(type default)
			)
			(layer "F.Fab")
		)
		(fp_line
			(start 0.67945 -0.3048)
			(end 0.67945 0.3048)
			(stroke
				(width 0.1)
				(type default)
			)
			(layer "F.Fab")
		)
		(fp_line
			(start -0.67945 -0.305054)
			(end -0.12065 -0.305054)
			(stroke
				(width 0.1)
				(type default)
			)
			(layer "F.Fab")
		)
		(fp_line
			(start -0.12065 -0.305054)
			(end -0.12065 -0.2794)
			(stroke
				(width 0.1)
				(type default)
			)
			(layer "F.Fab")
		)
		(pad "1" smd circle
			(at -0.40005 0 270)
			(size 0 0)
			(layers "F.Cu" "F.Mask" "F.Paste")
			(net "SW_PVDDCR_CPU1_P1_BOOT3_R")
		)
		(pad "2" smd circle
			(at 0.40005 0 270)
			(size 0 0)
			(layers "F.Cu" "F.Mask" "F.Paste")
			(net "SW_PVDDCR_CPU1_P1_BOOTR3")
		)
	)
	(footprint ""
		(layer "F.Cu")
		(at 439.821066 -389.9535)
		(property "Reference" "PR6532"
			(at 0 0 0)
			(layer "F.SilkS")
			(hide yes)
			(effects
				(font
					(size 1.27 1.27)
				)
			)
		)
		(property "Value" ""
			(at 0 0 0)
			(layer "F.Fab")
			(effects
				(font
					(size 1.27 1.27)
				)
			)
		)
		(duplicate_pad_numbers_are_jumpers no)
		(fp_line
			(start -0.7874 -0.4064)
			(end 0.7874 -0.4064)
			(stroke
				(width 0.1524)
				(type default)
			)
			(layer "F.SilkS")
		)
		(fp_line
			(start -0.7874 0.4064)
			(end -0.7874 -0.4064)
			(stroke
				(width 0.1524)
				(type default)
			)
			(layer "F.SilkS")
		)
		(fp_line
			(start 0.7874 -0.4064)
			(end 0.7874 0.4064)
			(stroke
				(width 0.1524)
				(type default)
			)
			(layer "F.SilkS")
		)
		(fp_line
			(start 0.7874 0.4064)
			(end -0.7874 0.4064)
			(stroke
				(width 0.1524)
				(type default)
			)
			(layer "F.SilkS")
		)
		(fp_line
			(start -0.67945 -0.305054)
			(end -0.12065 -0.305054)
			(stroke
				(width 0.1)
				(type default)
			)
			(layer "F.Fab")
		)
		(fp_line
			(start -0.67945 0.3048)
			(end -0.67945 -0.305054)
			(stroke
				(width 0.1)
				(type default)
			)
			(layer "F.Fab")
		)
		(fp_line
			(start -0.12065 -0.305054)
			(end -0.12065 -0.2794)
			(stroke
				(width 0.1)
				(type default)
			)
			(layer "F.Fab")
		)
		(fp_line
			(start -0.12065 -0.2794)
			(end 0.12065 -0.2794)
			(stroke
				(width 0.1)
				(type default)
			)
			(layer "F.Fab")
		)
		(fp_line
			(start -0.12065 0.2794)
			(end -0.12065 0.3048)
			(stroke
				(width 0.1)
				(type default)
			)
			(layer "F.Fab")
		)
		(fp_line
			(start -0.12065 0.3048)
			(end -0.67945 0.3048)
			(stroke
				(width 0.1)
				(type default)
			)
			(layer "F.Fab")
		)
		(fp_line
			(start 0.120396 0.2794)
			(end -0.12065 0.2794)
			(stroke
				(width 0.1)
				(type default)
			)
			(layer "F.Fab")
		)
		(fp_line
			(start 0.120396 0.3048)
			(end 0.120396 0.2794)
			(stroke
				(width 0.1)
				(type default)
			)
			(layer "F.Fab")
		)
		(fp_line
			(start 0.12065 -0.3048)
			(end 0.67945 -0.3048)
			(stroke
				(width 0.1)
				(type default)
			)
			(layer "F.Fab")
		)
		(fp_line
			(start 0.12065 -0.2794)
			(end 0.12065 -0.3048)
			(stroke
				(width 0.1)
				(type default)
			)
			(layer "F.Fab")
		)
		(fp_line
			(start 0.67945 -0.3048)
			(end 0.67945 0.3048)
			(stroke
				(width 0.1)
				(type default)
			)
			(layer "F.Fab")
		)
		(fp_line
			(start 0.67945 0.3048)
			(end 0.120396 0.3048)
			(stroke
				(width 0.1)
				(type default)
			)
			(layer "F.Fab")
		)
		(pad "1" smd circle
			(at -0.40005 0)
			(size 0 0)
			(layers "F.Cu" "F.Mask" "F.Paste")
			(net "P0V9_RETIMER_CPU0_SENSE_SH_N")
		)
		(pad "2" smd circle
			(at 0.40005 0)
			(size 0 0)
			(layers "F.Cu" "F.Mask" "F.Paste")
			(net "GND")
		)
	)
	(footprint ""
		(layer "F.Cu")
		(at 245.52275 -50.335434 180)
		(property "Reference" "R1283"
			(at 0 0 180)
			(layer "F.SilkS")
			(hide yes)
			(effects
				(font
					(size 1.27 1.27)
				)
			)
		)
		(property "Value" ""
			(at 0 0 180)
			(layer "F.Fab")
			(effects
				(font
					(size 1.27 1.27)
				)
			)
		)
		(duplicate_pad_numbers_are_jumpers no)
		(fp_line
			(start 0.7874 0.4064)
			(end -0.7874 0.4064)
			(stroke
				(width 0.1524)
				(type default)
			)
			(layer "F.SilkS")
		)
		(fp_line
			(start 0.7874 -0.4064)
			(end 0.7874 0.4064)
			(stroke
				(width 0.1524)
				(type default)
			)
			(layer "F.SilkS")
		)
		(fp_line
			(start -0.7874 0.4064)
			(end -0.7874 -0.4064)
			(stroke
				(width 0.1524)
				(type default)
			)
			(layer "F.SilkS")
		)
		(fp_line
			(start -0.7874 -0.4064)
			(end 0.7874 -0.4064)
			(stroke
				(width 0.1524)
				(type default)
			)
			(layer "F.SilkS")
		)
		(fp_line
			(start 0.67945 0.3048)
			(end 0.120396 0.3048)
			(stroke
				(width 0.1)
				(type default)
			)
			(layer "F.Fab")
		)
		(fp_line
			(start 0.67945 -0.3048)
			(end 0.67945 0.3048)
			(stroke
				(width 0.1)
				(type default)
			)
			(layer "F.Fab")
		)
		(fp_line
			(start 0.12065 -0.2794)
			(end 0.12065 -0.3048)
			(stroke
				(width 0.1)
				(type default)
			)
			(layer "F.Fab")
		)
		(fp_line
			(start 0.12065 -0.3048)
			(end 0.67945 -0.3048)
			(stroke
				(width 0.1)
				(type default)
			)
			(layer "F.Fab")
		)
		(fp_line
			(start 0.120396 0.3048)
			(end 0.120396 0.2794)
			(stroke
				(width 0.1)
				(type default)
			)
			(layer "F.Fab")
		)
		(fp_line
			(start 0.120396 0.2794)
			(end -0.12065 0.2794)
			(stroke
				(width 0.1)
				(type default)
			)
			(layer "F.Fab")
		)
		(fp_line
			(start -0.12065 0.3048)
			(end -0.67945 0.3048)
			(stroke
				(width 0.1)
				(type default)
			)
			(layer "F.Fab")
		)
		(fp_line
			(start -0.12065 0.2794)
			(end -0.12065 0.3048)
			(stroke
				(width 0.1)
				(type default)
			)
			(layer "F.Fab")
		)
		(fp_line
			(start -0.12065 -0.2794)
			(end 0.12065 -0.2794)
			(stroke
				(width 0.1)
				(type default)
			)
			(layer "F.Fab")
		)
		(fp_line
			(start -0.12065 -0.305054)
			(end -0.12065 -0.2794)
			(stroke
				(width 0.1)
				(type default)
			)
			(layer "F.Fab")
		)
		(fp_line
			(start -0.67945 0.3048)
			(end -0.67945 -0.305054)
			(stroke
				(width 0.1)
				(type default)
			)
			(layer "F.Fab")
		)
		(fp_line
			(start -0.67945 -0.305054)
			(end -0.12065 -0.305054)
			(stroke
				(width 0.1)
				(type default)
			)
			(layer "F.Fab")
		)
		(pad "1" smd circle
			(at -0.40005 0 180)
			(size 0 0)
			(layers "F.Cu" "F.Mask" "F.Paste")
			(net "P12V_E1S_0")
		)
		(pad "2" smd circle
			(at 0.40005 0 180)
			(size 0 0)
			(layers "F.Cu" "F.Mask" "F.Paste")
			(net "VSENSE_P12V_INA230_8_INP")
		)
	)
	(footprint ""
		(layer "F.Cu")
		(at 399.171668 -395.066774 -90)
		(property "Reference" "R631"
			(at 0 0 270)
			(layer "F.SilkS")
			(hide yes)
			(effects
				(font
					(size 1.27 1.27)
				)
			)
		)
		(property "Value" ""
			(at 0 0 270)
			(layer "F.Fab")
			(effects
				(font
					(size 1.27 1.27)
				)
			)
		)
		(duplicate_pad_numbers_are_jumpers no)
		(fp_line
			(start -0.32512 0.175006)
			(end -0.32512 -0.175006)
			(stroke
				(width 0.1)
				(type default)
			)
			(layer "F.Fab")
		)
		(fp_line
			(start 0.32512 0.175006)
			(end -0.32512 0.175006)
			(stroke
				(width 0.1)
				(type default)
			)
			(layer "F.Fab")
		)
		(fp_line
			(start -0.32512 -0.175006)
			(end 0.32512 -0.175006)
			(stroke
				(width 0.1)
				(type default)
			)
			(layer "F.Fab")
		)
		(fp_line
			(start 0.32512 -0.175006)
			(end 0.32512 0.175006)
			(stroke
				(width 0.1)
				(type default)
			)
			(layer "F.Fab")
		)
		(pad "1" smd rect
			(at -0.2667 0 270)
			(size 0.3048 0.381)
			(layers "F.Cu" "F.Mask" "F.Paste")
			(net "CLK_100M_RETIMER_CPU0_P2_DN")
		)
		(pad "2" smd rect
			(at 0.2667 0 90)
			(size 0.3048 0.381)
			(layers "F.Cu" "F.Mask" "F.Paste")
			(net "GND")
		)
	)
	(footprint ""
		(layer "F.Cu")
		(at 64.614298 -24.798782 180)
		(property "Reference" "PC1320"
			(at 0 0 180)
			(layer "F.SilkS")
			(hide yes)
			(effects
				(font
					(size 1.27 1.27)
				)
			)
		)
		(property "Value" ""
			(at 0 0 180)
			(layer "F.Fab")
			(effects
				(font
					(size 1.27 1.27)
				)
			)
		)
		(duplicate_pad_numbers_are_jumpers no)
		(fp_line
			(start 1.2954 0.5842)
			(end -1.2954 0.5842)
			(stroke
				(width 0.1524)
				(type default)
			)
			(layer "F.SilkS")
		)
		(fp_line
			(start 1.2954 -0.5842)
			(end 1.2954 0.5842)
			(stroke
				(width 0.1524)
				(type default)
			)
			(layer "F.SilkS")
		)
		(fp_line
			(start -1.2954 0.5842)
			(end -1.2954 -0.5842)
			(stroke
				(width 0.1524)
				(type default)
			)
			(layer "F.SilkS")
		)
		(fp_line
			(start -1.2954 -0.5842)
			(end 1.2954 -0.5842)
			(stroke
				(width 0.1524)
				(type default)
			)
			(layer "F.SilkS")
		)
		(fp_line
			(start 1.1938 0.4064)
			(end 0.8636 0.4064)
			(stroke
				(width 0.1)
				(type default)
			)
			(layer "F.Fab")
		)
		(fp_line
			(start 1.1938 -0.4064)
			(end 1.1938 0.4064)
			(stroke
				(width 0.1)
				(type default)
			)
			(layer "F.Fab")
		)
		(fp_line
			(start 0.8636 0.4572)
			(end -0.8636 0.4572)
			(stroke
				(width 0.1)
				(type default)
			)
			(layer "F.Fab")
		)
		(fp_line
			(start 0.8636 0.4064)
			(end 0.8636 0.4572)
			(stroke
				(width 0.1)
				(type default)
			)
			(layer "F.Fab")
		)
		(fp_line
			(start 0.8636 -0.4064)
			(end 1.1938 -0.4064)
			(stroke
				(width 0.1)
				(type default)
			)
			(layer "F.Fab")
		)
		(fp_line
			(start 0.8636 -0.4572)
			(end 0.8636 -0.4064)
			(stroke
				(width 0.1)
				(type default)
			)
			(layer "F.Fab")
		)
		(fp_line
			(start -0.8636 0.4572)
			(end -0.8636 0.4064)
			(stroke
				(width 0.1)
				(type default)
			)
			(layer "F.Fab")
		)
		(fp_line
			(start -0.8636 0.4064)
			(end -1.1938 0.4064)
			(stroke
				(width 0.1)
				(type default)
			)
			(layer "F.Fab")
		)
		(fp_line
			(start -0.8636 -0.4064)
			(end -0.8636 -0.4572)
			(stroke
				(width 0.1)
				(type default)
			)
			(layer "F.Fab")
		)
		(fp_line
			(start -0.8636 -0.4572)
			(end 0.8636 -0.4572)
			(stroke
				(width 0.1)
				(type default)
			)
			(layer "F.Fab")
		)
		(fp_line
			(start -1.1938 0.4064)
			(end -1.1938 -0.4064)
			(stroke
				(width 0.1)
				(type default)
			)
			(layer "F.Fab")
		)
		(fp_line
			(start -1.1938 -0.4064)
			(end -0.8636 -0.4064)
			(stroke
				(width 0.1)
				(type default)
			)
			(layer "F.Fab")
		)
		(pad "1" smd rect
			(at -0.7366 0 90)
			(size 0.7112 0.8128)
			(layers "F.Cu" "F.Mask" "F.Paste")
			(net "P12V_OCP_AVIN_PD_2")
		)
		(pad "2" smd rect
			(at 0.7366 0 90)
			(size 0.7112 0.8128)
			(layers "F.Cu" "F.Mask" "F.Paste")
			(net "GND")
		)
	)
	(footprint ""
		(layer "F.Cu")
		(at 118.491 -423.672)
		(property "Reference" "R3392"
			(at 0 0 0)
			(layer "F.SilkS")
			(hide yes)
			(effects
				(font
					(size 1.27 1.27)
				)
			)
		)
		(property "Value" ""
			(at 0 0 0)
			(layer "F.Fab")
			(effects
				(font
					(size 1.27 1.27)
				)
			)
		)
		(duplicate_pad_numbers_are_jumpers no)
		(fp_line
			(start -0.7874 -0.4064)
			(end 0.7874 -0.4064)
			(stroke
				(width 0.1524)
				(type default)
			)
			(layer "F.SilkS")
		)
		(fp_line
			(start -0.7874 0.4064)
			(end -0.7874 -0.4064)
			(stroke
				(width 0.1524)
				(type default)
			)
			(layer "F.SilkS")
		)
		(fp_line
			(start 0.7874 -0.4064)
			(end 0.7874 0.4064)
			(stroke
				(width 0.1524)
				(type default)
			)
			(layer "F.SilkS")
		)
		(fp_line
			(start 0.7874 0.4064)
			(end -0.7874 0.4064)
			(stroke
				(width 0.1524)
				(type default)
			)
			(layer "F.SilkS")
		)
		(fp_line
			(start -0.67945 -0.305054)
			(end -0.12065 -0.305054)
			(stroke
				(width 0.1)
				(type default)
			)
			(layer "F.Fab")
		)
		(fp_line
			(start -0.67945 0.3048)
			(end -0.67945 -0.305054)
			(stroke
				(width 0.1)
				(type default)
			)
			(layer "F.Fab")
		)
		(fp_line
			(start -0.12065 -0.305054)
			(end -0.12065 -0.2794)
			(stroke
				(width 0.1)
				(type default)
			)
			(layer "F.Fab")
		)
		(fp_line
			(start -0.12065 -0.2794)
			(end 0.12065 -0.2794)
			(stroke
				(width 0.1)
				(type default)
			)
			(layer "F.Fab")
		)
		(fp_line
			(start -0.12065 0.2794)
			(end -0.12065 0.3048)
			(stroke
				(width 0.1)
				(type default)
			)
			(layer "F.Fab")
		)
		(fp_line
			(start -0.12065 0.3048)
			(end -0.67945 0.3048)
			(stroke
				(width 0.1)
				(type default)
			)
			(layer "F.Fab")
		)
		(fp_line
			(start 0.120396 0.2794)
			(end -0.12065 0.2794)
			(stroke
				(width 0.1)
				(type default)
			)
			(layer "F.Fab")
		)
		(fp_line
			(start 0.120396 0.3048)
			(end 0.120396 0.2794)
			(stroke
				(width 0.1)
				(type default)
			)
			(layer "F.Fab")
		)
		(fp_line
			(start 0.12065 -0.3048)
			(end 0.67945 -0.3048)
			(stroke
				(width 0.1)
				(type default)
			)
			(layer "F.Fab")
		)
		(fp_line
			(start 0.12065 -0.2794)
			(end 0.12065 -0.3048)
			(stroke
				(width 0.1)
				(type default)
			)
			(layer "F.Fab")
		)
		(fp_line
			(start 0.67945 -0.3048)
			(end 0.67945 0.3048)
			(stroke
				(width 0.1)
				(type default)
			)
			(layer "F.Fab")
		)
		(fp_line
			(start 0.67945 0.3048)
			(end 0.120396 0.3048)
			(stroke
				(width 0.1)
				(type default)
			)
			(layer "F.Fab")
		)
		(pad "1" smd circle
			(at -0.40005 0)
			(size 0 0)
			(layers "F.Cu" "F.Mask" "F.Paste")
			(net "GPU_BASE_STBY_EN_BUF_R")
		)
		(pad "2" smd circle
			(at 0.40005 0)
			(size 0 0)
			(layers "F.Cu" "F.Mask" "F.Paste")
			(net "GPU_BASE_STBY_EN_BUF")
		)
	)
	(footprint ""
		(layer "F.Cu")
		(at 271.744948 -344.982038 90)
		(property "Reference" "PR291"
			(at 0 0 90)
			(layer "F.SilkS")
			(hide yes)
			(effects
				(font
					(size 1.27 1.27)
				)
			)
		)
		(property "Value" ""
			(at 0 0 90)
			(layer "F.Fab")
			(effects
				(font
					(size 1.27 1.27)
				)
			)
		)
		(duplicate_pad_numbers_are_jumpers no)
		(fp_line
			(start 0.7874 -0.4064)
			(end 0.7874 0.4064)
			(stroke
				(width 0.1524)
				(type default)
			)
			(layer "F.SilkS")
		)
		(fp_line
			(start -0.7874 -0.4064)
			(end 0.7874 -0.4064)
			(stroke
				(width 0.1524)
				(type default)
			)
			(layer "F.SilkS")
		)
		(fp_line
			(start 0.7874 0.4064)
			(end -0.7874 0.4064)
			(stroke
				(width 0.1524)
				(type default)
			)
			(layer "F.SilkS")
		)
		(fp_line
			(start -0.7874 0.4064)
			(end -0.7874 -0.4064)
			(stroke
				(width 0.1524)
				(type default)
			)
			(layer "F.SilkS")
		)
		(fp_line
			(start -0.12065 -0.305054)
			(end -0.12065 -0.2794)
			(stroke
				(width 0.1)
				(type default)
			)
			(layer "F.Fab")
		)
		(fp_line
			(start -0.67945 -0.305054)
			(end -0.12065 -0.305054)
			(stroke
				(width 0.1)
				(type default)
			)
			(layer "F.Fab")
		)
		(fp_line
			(start 0.67945 -0.3048)
			(end 0.67945 0.3048)
			(stroke
				(width 0.1)
				(type default)
			)
			(layer "F.Fab")
		)
		(fp_line
			(start 0.12065 -0.3048)
			(end 0.67945 -0.3048)
			(stroke
				(width 0.1)
				(type default)
			)
			(layer "F.Fab")
		)
		(fp_line
			(start 0.12065 -0.2794)
			(end 0.12065 -0.3048)
			(stroke
				(width 0.1)
				(type default)
			)
			(layer "F.Fab")
		)
		(fp_line
			(start -0.12065 -0.2794)
			(end 0.12065 -0.2794)
			(stroke
				(width 0.1)
				(type default)
			)
			(layer "F.Fab")
		)
		(fp_line
			(start 0.120396 0.2794)
			(end -0.12065 0.2794)
			(stroke
				(width 0.1)
				(type default)
			)
			(layer "F.Fab")
		)
		(fp_line
			(start -0.12065 0.2794)
			(end -0.12065 0.3048)
			(stroke
				(width 0.1)
				(type default)
			)
			(layer "F.Fab")
		)
		(fp_line
			(start 0.67945 0.3048)
			(end 0.120396 0.3048)
			(stroke
				(width 0.1)
				(type default)
			)
			(layer "F.Fab")
		)
		(fp_line
			(start 0.120396 0.3048)
			(end 0.120396 0.2794)
			(stroke
				(width 0.1)
				(type default)
			)
			(layer "F.Fab")
		)
		(fp_line
			(start -0.12065 0.3048)
			(end -0.67945 0.3048)
			(stroke
				(width 0.1)
				(type default)
			)
			(layer "F.Fab")
		)
		(fp_line
			(start -0.67945 0.3048)
			(end -0.67945 -0.305054)
			(stroke
				(width 0.1)
				(type default)
			)
			(layer "F.Fab")
		)
		(pad "1" smd circle
			(at -0.40005 0 90)
			(size 0 0)
			(layers "F.Cu" "F.Mask" "F.Paste")
			(net "SW_PVDDIO_P0_SW4_RC")
		)
		(pad "2" smd circle
			(at 0.40005 0 90)
			(size 0 0)
			(layers "F.Cu" "F.Mask" "F.Paste")
			(net "GND")
		)
	)
	(footprint ""
		(layer "F.Cu")
		(at 152.849834 -321.715892)
		(property "Reference" "C5024"
			(at 0 0 0)
			(layer "F.SilkS")
			(hide yes)
			(effects
				(font
					(size 1.27 1.27)
				)
			)
		)
		(property "Value" ""
			(at 0 0 0)
			(layer "F.Fab")
			(effects
				(font
					(size 1.27 1.27)
				)
			)
		)
		(duplicate_pad_numbers_are_jumpers no)
		(fp_line
			(start -0.7874 -0.4064)
			(end 0.7874 -0.4064)
			(stroke
				(width 0.1524)
				(type default)
			)
			(layer "F.SilkS")
		)
		(fp_line
			(start -0.7874 0.4064)
			(end -0.7874 -0.4064)
			(stroke
				(width 0.1524)
				(type default)
			)
			(layer "F.SilkS")
		)
		(fp_line
			(start 0.7874 -0.4064)
			(end 0.7874 0.4064)
			(stroke
				(width 0.1524)
				(type default)
			)
			(layer "F.SilkS")
		)
		(fp_line
			(start 0.7874 0.4064)
			(end -0.7874 0.4064)
			(stroke
				(width 0.1524)
				(type default)
			)
			(layer "F.SilkS")
		)
		(fp_line
			(start -0.67945 -0.305054)
			(end -0.12065 -0.305054)
			(stroke
				(width 0.1)
				(type default)
			)
			(layer "F.Fab")
		)
		(fp_line
			(start -0.67945 0.3048)
			(end -0.67945 -0.305054)
			(stroke
				(width 0.1)
				(type default)
			)
			(layer "F.Fab")
		)
		(fp_line
			(start -0.12065 -0.305054)
			(end -0.12065 -0.2794)
			(stroke
				(width 0.1)
				(type default)
			)
			(layer "F.Fab")
		)
		(fp_line
			(start -0.12065 -0.2794)
			(end 0.12065 -0.2794)
			(stroke
				(width 0.1)
				(type default)
			)
			(layer "F.Fab")
		)
		(fp_line
			(start -0.12065 0.2794)
			(end -0.12065 0.3048)
			(stroke
				(width 0.1)
				(type default)
			)
			(layer "F.Fab")
		)
		(fp_line
			(start -0.12065 0.3048)
			(end -0.67945 0.3048)
			(stroke
				(width 0.1)
				(type default)
			)
			(layer "F.Fab")
		)
		(fp_line
			(start 0.120396 0.2794)
			(end -0.12065 0.2794)
			(stroke
				(width 0.1)
				(type default)
			)
			(layer "F.Fab")
		)
		(fp_line
			(start 0.120396 0.3048)
			(end 0.120396 0.2794)
			(stroke
				(width 0.1)
				(type default)
			)
			(layer "F.Fab")
		)
		(fp_line
			(start 0.12065 -0.3048)
			(end 0.67945 -0.3048)
			(stroke
				(width 0.1)
				(type default)
			)
			(layer "F.Fab")
		)
		(fp_line
			(start 0.12065 -0.2794)
			(end 0.12065 -0.3048)
			(stroke
				(width 0.1)
				(type default)
			)
			(layer "F.Fab")
		)
		(fp_line
			(start 0.67945 -0.3048)
			(end 0.67945 0.3048)
			(stroke
				(width 0.1)
				(type default)
			)
			(layer "F.Fab")
		)
		(fp_line
			(start 0.67945 0.3048)
			(end 0.120396 0.3048)
			(stroke
				(width 0.1)
				(type default)
			)
			(layer "F.Fab")
		)
		(pad "1" smd circle
			(at -0.40005 0)
			(size 0 0)
			(layers "F.Cu" "F.Mask" "F.Paste")
			(net "RST_CPU1_RSMRST_N")
		)
		(pad "2" smd circle
			(at 0.40005 0)
			(size 0 0)
			(layers "F.Cu" "F.Mask" "F.Paste")
			(net "GND")
		)
	)
	(footprint ""
		(layer "F.Cu")
		(at 182.710836 -92.674948 -90)
		(property "Reference" "R6151"
			(at 0 0 270)
			(layer "F.SilkS")
			(hide yes)
			(effects
				(font
					(size 1.27 1.27)
				)
			)
		)
		(property "Value" ""
			(at 0 0 270)
			(layer "F.Fab")
			(effects
				(font
					(size 1.27 1.27)
				)
			)
		)
		(duplicate_pad_numbers_are_jumpers no)
		(fp_line
			(start -0.7874 0.4064)
			(end -0.7874 -0.4064)
			(stroke
				(width 0.1524)
				(type default)
			)
			(layer "F.SilkS")
		)
		(fp_line
			(start 0.7874 0.4064)
			(end -0.7874 0.4064)
			(stroke
				(width 0.1524)
				(type default)
			)
			(layer "F.SilkS")
		)
		(fp_line
			(start -0.7874 -0.4064)
			(end 0.7874 -0.4064)
			(stroke
				(width 0.1524)
				(type default)
			)
			(layer "F.SilkS")
		)
		(fp_line
			(start 0.7874 -0.4064)
			(end 0.7874 0.4064)
			(stroke
				(width 0.1524)
				(type default)
			)
			(layer "F.SilkS")
		)
		(fp_line
			(start -0.67945 0.3048)
			(end -0.67945 -0.305054)
			(stroke
				(width 0.1)
				(type default)
			)
			(layer "F.Fab")
		)
		(fp_line
			(start -0.12065 0.3048)
			(end -0.67945 0.3048)
			(stroke
				(width 0.1)
				(type default)
			)
			(layer "F.Fab")
		)
		(fp_line
			(start 0.120396 0.3048)
			(end 0.120396 0.2794)
			(stroke
				(width 0.1)
				(type default)
			)
			(layer "F.Fab")
		)
		(fp_line
			(start 0.67945 0.3048)
			(end 0.120396 0.3048)
			(stroke
				(width 0.1)
				(type default)
			)
			(layer "F.Fab")
		)
		(fp_line
			(start -0.12065 0.2794)
			(end -0.12065 0.3048)
			(stroke
				(width 0.1)
				(type default)
			)
			(layer "F.Fab")
		)
		(fp_line
			(start 0.120396 0.2794)
			(end -0.12065 0.2794)
			(stroke
				(width 0.1)
				(type default)
			)
			(layer "F.Fab")
		)
		(fp_line
			(start -0.12065 -0.2794)
			(end 0.12065 -0.2794)
			(stroke
				(width 0.1)
				(type default)
			)
			(layer "F.Fab")
		)
		(fp_line
			(start 0.12065 -0.2794)
			(end 0.12065 -0.3048)
			(stroke
				(width 0.1)
				(type default)
			)
			(layer "F.Fab")
		)
		(fp_line
			(start 0.12065 -0.3048)
			(end 0.67945 -0.3048)
			(stroke
				(width 0.1)
				(type default)
			)
			(layer "F.Fab")
		)
		(fp_line
			(start 0.67945 -0.3048)
			(end 0.67945 0.3048)
			(stroke
				(width 0.1)
				(type default)
			)
			(layer "F.Fab")
		)
		(fp_line
			(start -0.67945 -0.305054)
			(end -0.12065 -0.305054)
			(stroke
				(width 0.1)
				(type default)
			)
			(layer "F.Fab")
		)
		(fp_line
			(start -0.12065 -0.305054)
			(end -0.12065 -0.2794)
			(stroke
				(width 0.1)
				(type default)
			)
			(layer "F.Fab")
		)
		(pad "1" smd circle
			(at -0.40005 0 270)
			(size 0 0)
			(layers "F.Cu" "F.Mask" "F.Paste")
			(net "FAB_BMC_REV_ID0")
		)
		(pad "2" smd circle
			(at 0.40005 0 270)
			(size 0 0)
			(layers "F.Cu" "F.Mask" "F.Paste")
			(net "GND")
		)
	)
	(footprint ""
		(layer "F.Cu")
		(at 75.070716 -331.988668 180)
		(property "Reference" "PC202"
			(at 0 0 180)
			(layer "F.SilkS")
			(hide yes)
			(effects
				(font
					(size 1.27 1.27)
				)
			)
		)
		(property "Value" ""
			(at 0 0 180)
			(layer "F.Fab")
			(effects
				(font
					(size 1.27 1.27)
				)
			)
		)
		(duplicate_pad_numbers_are_jumpers no)
		(fp_line
			(start 0.7874 0.4064)
			(end -0.7874 0.4064)
			(stroke
				(width 0.1524)
				(type default)
			)
			(layer "F.SilkS")
		)
		(fp_line
			(start 0.7874 -0.4064)
			(end 0.7874 0.4064)
			(stroke
				(width 0.1524)
				(type default)
			)
			(layer "F.SilkS")
		)
		(fp_line
			(start -0.7874 0.4064)
			(end -0.7874 -0.4064)
			(stroke
				(width 0.1524)
				(type default)
			)
			(layer "F.SilkS")
		)
		(fp_line
			(start -0.7874 -0.4064)
			(end 0.7874 -0.4064)
			(stroke
				(width 0.1524)
				(type default)
			)
			(layer "F.SilkS")
		)
		(fp_line
			(start 0.67945 0.3048)
			(end 0.120396 0.3048)
			(stroke
				(width 0.1)
				(type default)
			)
			(layer "F.Fab")
		)
		(fp_line
			(start 0.67945 -0.3048)
			(end 0.67945 0.3048)
			(stroke
				(width 0.1)
				(type default)
			)
			(layer "F.Fab")
		)
		(fp_line
			(start 0.12065 -0.2794)
			(end 0.12065 -0.3048)
			(stroke
				(width 0.1)
				(type default)
			)
			(layer "F.Fab")
		)
		(fp_line
			(start 0.12065 -0.3048)
			(end 0.67945 -0.3048)
			(stroke
				(width 0.1)
				(type default)
			)
			(layer "F.Fab")
		)
		(fp_line
			(start 0.120396 0.3048)
			(end 0.120396 0.2794)
			(stroke
				(width 0.1)
				(type default)
			)
			(layer "F.Fab")
		)
		(fp_line
			(start 0.120396 0.2794)
			(end -0.12065 0.2794)
			(stroke
				(width 0.1)
				(type default)
			)
			(layer "F.Fab")
		)
		(fp_line
			(start -0.12065 0.3048)
			(end -0.67945 0.3048)
			(stroke
				(width 0.1)
				(type default)
			)
			(layer "F.Fab")
		)
		(fp_line
			(start -0.12065 0.2794)
			(end -0.12065 0.3048)
			(stroke
				(width 0.1)
				(type default)
			)
			(layer "F.Fab")
		)
		(fp_line
			(start -0.12065 -0.2794)
			(end 0.12065 -0.2794)
			(stroke
				(width 0.1)
				(type default)
			)
			(layer "F.Fab")
		)
		(fp_line
			(start -0.12065 -0.305054)
			(end -0.12065 -0.2794)
			(stroke
				(width 0.1)
				(type default)
			)
			(layer "F.Fab")
		)
		(fp_line
			(start -0.67945 0.3048)
			(end -0.67945 -0.305054)
			(stroke
				(width 0.1)
				(type default)
			)
			(layer "F.Fab")
		)
		(fp_line
			(start -0.67945 -0.305054)
			(end -0.12065 -0.305054)
			(stroke
				(width 0.1)
				(type default)
			)
			(layer "F.Fab")
		)
		(pad "1" smd circle
			(at -0.40005 0 180)
			(size 0 0)
			(layers "F.Cu" "F.Mask" "F.Paste")
			(net "SW_PVDDCR_CPU1_P1_SW2")
		)
		(pad "2" smd circle
			(at 0.40005 0 180)
			(size 0 0)
			(layers "F.Cu" "F.Mask" "F.Paste")
			(net "SW_PVDDCR_CPU1_P1_SW2_RC")
		)
	)
	(footprint ""
		(layer "F.Cu")
		(at 236.650022 -192.499996)
		(property "Reference" "H99"
			(at -3.30454 -6.229604 0)
			(unlocked yes)
			(layer "F.SilkS")
			(effects
				(font
					(size 0.7874 0.5842)
					(thickness 0.1524)
				)
				(justify left)
			)
		)
		(property "Value" ""
			(at 0 0 0)
			(layer "F.Fab")
			(effects
				(font
					(size 1.27 1.27)
				)
			)
		)
		(duplicate_pad_numbers_are_jumpers no)
		(pad "1" thru_hole circle
			(at 0 0)
			(size 10.0076 10.0076)
			(drill 5.6134)
			(layers "*.Cu" "*.Mask")
			(remove_unused_layers no)
			(net "GND")
			(clearance -1.9431)
		)
	)
	(footprint ""
		(layer "F.Cu")
		(at 162.251644 -375.49963 -90)
		(property "Reference" "C752"
			(at 0 0 270)
			(layer "F.SilkS")
			(hide yes)
			(effects
				(font
					(size 1.27 1.27)
				)
			)
		)
		(property "Value" ""
			(at 0 0 270)
			(layer "F.Fab")
			(effects
				(font
					(size 1.27 1.27)
				)
			)
		)
		(duplicate_pad_numbers_are_jumpers no)
		(fp_line
			(start -0.299974 0.150114)
			(end -0.299974 -0.150114)
			(stroke
				(width 0.1)
				(type default)
			)
			(layer "F.Fab")
		)
		(fp_line
			(start 0.299974 0.150114)
			(end -0.299974 0.150114)
			(stroke
				(width 0.1)
				(type default)
			)
			(layer "F.Fab")
		)
		(fp_line
			(start -0.299974 -0.150114)
			(end 0.299974 -0.150114)
			(stroke
				(width 0.1)
				(type default)
			)
			(layer "F.Fab")
		)
		(fp_line
			(start 0.299974 -0.150114)
			(end 0.299974 0.150114)
			(stroke
				(width 0.1)
				(type default)
			)
			(layer "F.Fab")
		)
		(pad "1" smd rect
			(at -0.2667 0 270)
			(size 0.3048 0.381)
			(layers "F.Cu" "F.Mask" "F.Paste")
			(net "P5E_CPU1_P2_TX_C_DN<10>")
		)
		(pad "2" smd rect
			(at 0.2667 0 270)
			(size 0.3048 0.381)
			(layers "F.Cu" "F.Mask" "F.Paste")
			(net "P5E_CPU1_P2_TX_DN<10>")
		)
	)
	(footprint ""
		(layer "F.Cu")
		(at 78.028546 -395.436852 -90)
		(property "Reference" "R793"
			(at 0 0 270)
			(layer "F.SilkS")
			(hide yes)
			(effects
				(font
					(size 1.27 1.27)
				)
			)
		)
		(property "Value" ""
			(at 0 0 270)
			(layer "F.Fab")
			(effects
				(font
					(size 1.27 1.27)
				)
			)
		)
		(duplicate_pad_numbers_are_jumpers no)
		(fp_line
			(start -0.32512 0.175006)
			(end -0.32512 -0.175006)
			(stroke
				(width 0.1)
				(type default)
			)
			(layer "F.Fab")
		)
		(fp_line
			(start 0.32512 0.175006)
			(end -0.32512 0.175006)
			(stroke
				(width 0.1)
				(type default)
			)
			(layer "F.Fab")
		)
		(fp_line
			(start -0.32512 -0.175006)
			(end 0.32512 -0.175006)
			(stroke
				(width 0.1)
				(type default)
			)
			(layer "F.Fab")
		)
		(fp_line
			(start 0.32512 -0.175006)
			(end 0.32512 0.175006)
			(stroke
				(width 0.1)
				(type default)
			)
			(layer "F.Fab")
		)
		(pad "1" smd rect
			(at -0.2667 0 270)
			(size 0.3048 0.381)
			(layers "F.Cu" "F.Mask" "F.Paste")
			(net "P1V8_CPU1_RT_1D")
		)
		(pad "2" smd rect
			(at 0.2667 0 90)
			(size 0.3048 0.381)
			(layers "F.Cu" "F.Mask" "F.Paste")
			(net "MODE_RT_CPU1_P1")
		)
	)
	(footprint ""
		(layer "F.Cu")
		(at 186.804046 -94.876112 -90)
		(property "Reference" "R397"
			(at 0 0 270)
			(layer "F.SilkS")
			(hide yes)
			(effects
				(font
					(size 1.27 1.27)
				)
			)
		)
		(property "Value" ""
			(at 0 0 270)
			(layer "F.Fab")
			(effects
				(font
					(size 1.27 1.27)
				)
			)
		)
		(duplicate_pad_numbers_are_jumpers no)
		(fp_line
			(start -0.7874 0.4064)
			(end -0.7874 -0.4064)
			(stroke
				(width 0.1524)
				(type default)
			)
			(layer "F.SilkS")
		)
		(fp_line
			(start 0.7874 0.4064)
			(end -0.7874 0.4064)
			(stroke
				(width 0.1524)
				(type default)
			)
			(layer "F.SilkS")
		)
		(fp_line
			(start -0.7874 -0.4064)
			(end 0.7874 -0.4064)
			(stroke
				(width 0.1524)
				(type default)
			)
			(layer "F.SilkS")
		)
		(fp_line
			(start 0.7874 -0.4064)
			(end 0.7874 0.4064)
			(stroke
				(width 0.1524)
				(type default)
			)
			(layer "F.SilkS")
		)
		(fp_line
			(start -0.67945 0.3048)
			(end -0.67945 -0.305054)
			(stroke
				(width 0.1)
				(type default)
			)
			(layer "F.Fab")
		)
		(fp_line
			(start -0.12065 0.3048)
			(end -0.67945 0.3048)
			(stroke
				(width 0.1)
				(type default)
			)
			(layer "F.Fab")
		)
		(fp_line
			(start 0.120396 0.3048)
			(end 0.120396 0.2794)
			(stroke
				(width 0.1)
				(type default)
			)
			(layer "F.Fab")
		)
		(fp_line
			(start 0.67945 0.3048)
			(end 0.120396 0.3048)
			(stroke
				(width 0.1)
				(type default)
			)
			(layer "F.Fab")
		)
		(fp_line
			(start -0.12065 0.2794)
			(end -0.12065 0.3048)
			(stroke
				(width 0.1)
				(type default)
			)
			(layer "F.Fab")
		)
		(fp_line
			(start 0.120396 0.2794)
			(end -0.12065 0.2794)
			(stroke
				(width 0.1)
				(type default)
			)
			(layer "F.Fab")
		)
		(fp_line
			(start -0.12065 -0.2794)
			(end 0.12065 -0.2794)
			(stroke
				(width 0.1)
				(type default)
			)
			(layer "F.Fab")
		)
		(fp_line
			(start 0.12065 -0.2794)
			(end 0.12065 -0.3048)
			(stroke
				(width 0.1)
				(type default)
			)
			(layer "F.Fab")
		)
		(fp_line
			(start 0.12065 -0.3048)
			(end 0.67945 -0.3048)
			(stroke
				(width 0.1)
				(type default)
			)
			(layer "F.Fab")
		)
		(fp_line
			(start 0.67945 -0.3048)
			(end 0.67945 0.3048)
			(stroke
				(width 0.1)
				(type default)
			)
			(layer "F.Fab")
		)
		(fp_line
			(start -0.67945 -0.305054)
			(end -0.12065 -0.305054)
			(stroke
				(width 0.1)
				(type default)
			)
			(layer "F.Fab")
		)
		(fp_line
			(start -0.12065 -0.305054)
			(end -0.12065 -0.2794)
			(stroke
				(width 0.1)
				(type default)
			)
			(layer "F.Fab")
		)
		(pad "1" smd circle
			(at -0.40005 0 270)
			(size 0 0)
			(layers "F.Cu" "F.Mask" "F.Paste")
			(net "P3V3_AUX")
		)
		(pad "2" smd circle
			(at 0.40005 0 270)
			(size 0 0)
			(layers "F.Cu" "F.Mask" "F.Paste")
			(net "CPU0_SP5R1")
		)
	)
	(footprint ""
		(layer "F.Cu")
		(at 259.89788 -47.650146 90)
		(property "Reference" "PC2198"
			(at 0 0 90)
			(layer "F.SilkS")
			(hide yes)
			(effects
				(font
					(size 1.27 1.27)
				)
			)
		)
		(property "Value" ""
			(at 0 0 90)
			(layer "F.Fab")
			(effects
				(font
					(size 1.27 1.27)
				)
			)
		)
		(duplicate_pad_numbers_are_jumpers no)
		(fp_line
			(start 0.7874 -0.4064)
			(end 0.7874 0.4064)
			(stroke
				(width 0.1524)
				(type default)
			)
			(layer "F.SilkS")
		)
		(fp_line
			(start -0.7874 -0.4064)
			(end 0.7874 -0.4064)
			(stroke
				(width 0.1524)
				(type default)
			)
			(layer "F.SilkS")
		)
		(fp_line
			(start 0.7874 0.4064)
			(end -0.7874 0.4064)
			(stroke
				(width 0.1524)
				(type default)
			)
			(layer "F.SilkS")
		)
		(fp_line
			(start -0.7874 0.4064)
			(end -0.7874 -0.4064)
			(stroke
				(width 0.1524)
				(type default)
			)
			(layer "F.SilkS")
		)
		(fp_line
			(start -0.12065 -0.305054)
			(end -0.12065 -0.2794)
			(stroke
				(width 0.1)
				(type default)
			)
			(layer "F.Fab")
		)
		(fp_line
			(start -0.67945 -0.305054)
			(end -0.12065 -0.305054)
			(stroke
				(width 0.1)
				(type default)
			)
			(layer "F.Fab")
		)
		(fp_line
			(start 0.67945 -0.3048)
			(end 0.67945 0.3048)
			(stroke
				(width 0.1)
				(type default)
			)
			(layer "F.Fab")
		)
		(fp_line
			(start 0.12065 -0.3048)
			(end 0.67945 -0.3048)
			(stroke
				(width 0.1)
				(type default)
			)
			(layer "F.Fab")
		)
		(fp_line
			(start 0.12065 -0.2794)
			(end 0.12065 -0.3048)
			(stroke
				(width 0.1)
				(type default)
			)
			(layer "F.Fab")
		)
		(fp_line
			(start -0.12065 -0.2794)
			(end 0.12065 -0.2794)
			(stroke
				(width 0.1)
				(type default)
			)
			(layer "F.Fab")
		)
		(fp_line
			(start 0.120396 0.2794)
			(end -0.12065 0.2794)
			(stroke
				(width 0.1)
				(type default)
			)
			(layer "F.Fab")
		)
		(fp_line
			(start -0.12065 0.2794)
			(end -0.12065 0.3048)
			(stroke
				(width 0.1)
				(type default)
			)
			(layer "F.Fab")
		)
		(fp_line
			(start 0.67945 0.3048)
			(end 0.120396 0.3048)
			(stroke
				(width 0.1)
				(type default)
			)
			(layer "F.Fab")
		)
		(fp_line
			(start 0.120396 0.3048)
			(end 0.120396 0.2794)
			(stroke
				(width 0.1)
				(type default)
			)
			(layer "F.Fab")
		)
		(fp_line
			(start -0.12065 0.3048)
			(end -0.67945 0.3048)
			(stroke
				(width 0.1)
				(type default)
			)
			(layer "F.Fab")
		)
		(fp_line
			(start -0.67945 0.3048)
			(end -0.67945 -0.305054)
			(stroke
				(width 0.1)
				(type default)
			)
			(layer "F.Fab")
		)
		(pad "1" smd circle
			(at -0.40005 0 90)
			(size 0 0)
			(layers "F.Cu" "F.Mask" "F.Paste")
			(net "P12V_AUX")
		)
		(pad "2" smd circle
			(at 0.40005 0 90)
			(size 0 0)
			(layers "F.Cu" "F.Mask" "F.Paste")
			(net "GND")
		)
	)
	(footprint ""
		(layer "F.Cu")
		(at 4.747514 -44.106592 90)
		(property "Reference" "R932"
			(at 0 0 90)
			(layer "F.SilkS")
			(hide yes)
			(effects
				(font
					(size 1.27 1.27)
				)
			)
		)
		(property "Value" ""
			(at 0 0 90)
			(layer "F.Fab")
			(effects
				(font
					(size 1.27 1.27)
				)
			)
		)
		(duplicate_pad_numbers_are_jumpers no)
		(fp_line
			(start 0.7874 -0.4064)
			(end 0.7874 0.4064)
			(stroke
				(width 0.1524)
				(type default)
			)
			(layer "F.SilkS")
		)
		(fp_line
			(start -0.7874 -0.4064)
			(end 0.7874 -0.4064)
			(stroke
				(width 0.1524)
				(type default)
			)
			(layer "F.SilkS")
		)
		(fp_line
			(start 0.7874 0.4064)
			(end -0.7874 0.4064)
			(stroke
				(width 0.1524)
				(type default)
			)
			(layer "F.SilkS")
		)
		(fp_line
			(start -0.7874 0.4064)
			(end -0.7874 -0.4064)
			(stroke
				(width 0.1524)
				(type default)
			)
			(layer "F.SilkS")
		)
		(fp_line
			(start -0.12065 -0.305054)
			(end -0.12065 -0.2794)
			(stroke
				(width 0.1)
				(type default)
			)
			(layer "F.Fab")
		)
		(fp_line
			(start -0.67945 -0.305054)
			(end -0.12065 -0.305054)
			(stroke
				(width 0.1)
				(type default)
			)
			(layer "F.Fab")
		)
		(fp_line
			(start 0.67945 -0.3048)
			(end 0.67945 0.3048)
			(stroke
				(width 0.1)
				(type default)
			)
			(layer "F.Fab")
		)
		(fp_line
			(start 0.12065 -0.3048)
			(end 0.67945 -0.3048)
			(stroke
				(width 0.1)
				(type default)
			)
			(layer "F.Fab")
		)
		(fp_line
			(start 0.12065 -0.2794)
			(end 0.12065 -0.3048)
			(stroke
				(width 0.1)
				(type default)
			)
			(layer "F.Fab")
		)
		(fp_line
			(start -0.12065 -0.2794)
			(end 0.12065 -0.2794)
			(stroke
				(width 0.1)
				(type default)
			)
			(layer "F.Fab")
		)
		(fp_line
			(start 0.120396 0.2794)
			(end -0.12065 0.2794)
			(stroke
				(width 0.1)
				(type default)
			)
			(layer "F.Fab")
		)
		(fp_line
			(start -0.12065 0.2794)
			(end -0.12065 0.3048)
			(stroke
				(width 0.1)
				(type default)
			)
			(layer "F.Fab")
		)
		(fp_line
			(start 0.67945 0.3048)
			(end 0.120396 0.3048)
			(stroke
				(width 0.1)
				(type default)
			)
			(layer "F.Fab")
		)
		(fp_line
			(start 0.120396 0.3048)
			(end 0.120396 0.2794)
			(stroke
				(width 0.1)
				(type default)
			)
			(layer "F.Fab")
		)
		(fp_line
			(start -0.12065 0.3048)
			(end -0.67945 0.3048)
			(stroke
				(width 0.1)
				(type default)
			)
			(layer "F.Fab")
		)
		(fp_line
			(start -0.67945 0.3048)
			(end -0.67945 -0.305054)
			(stroke
				(width 0.1)
				(type default)
			)
			(layer "F.Fab")
		)
		(pad "1" smd circle
			(at -0.40005 0 90)
			(size 0 0)
			(layers "F.Cu" "F.Mask" "F.Paste")
			(net "CPU1_XTRIG_L7")
		)
		(pad "2" smd circle
			(at 0.40005 0 90)
			(size 0 0)
			(layers "F.Cu" "F.Mask" "F.Paste")
			(net "CPU1_XTRIG_R1_L7")
		)
	)
	(footprint ""
		(layer "F.Cu")
		(at 117.895624 -260.305296 180)
		(property "Reference" "C2286"
			(at 0 0 180)
			(layer "F.SilkS")
			(hide yes)
			(effects
				(font
					(size 1.27 1.27)
				)
			)
		)
		(property "Value" ""
			(at 0 0 180)
			(layer "F.Fab")
			(effects
				(font
					(size 1.27 1.27)
				)
			)
		)
		(duplicate_pad_numbers_are_jumpers no)
		(fp_line
			(start 0.7874 0.4064)
			(end -0.7874 0.4064)
			(stroke
				(width 0.1524)
				(type default)
			)
			(layer "F.SilkS")
		)
		(fp_line
			(start 0.7874 -0.4064)
			(end 0.7874 0.4064)
			(stroke
				(width 0.1524)
				(type default)
			)
			(layer "F.SilkS")
		)
		(fp_line
			(start -0.7874 0.4064)
			(end -0.7874 -0.4064)
			(stroke
				(width 0.1524)
				(type default)
			)
			(layer "F.SilkS")
		)
		(fp_line
			(start -0.7874 -0.4064)
			(end 0.7874 -0.4064)
			(stroke
				(width 0.1524)
				(type default)
			)
			(layer "F.SilkS")
		)
		(fp_line
			(start 0.67945 0.3048)
			(end 0.120396 0.3048)
			(stroke
				(width 0.1)
				(type default)
			)
			(layer "F.Fab")
		)
		(fp_line
			(start 0.67945 -0.3048)
			(end 0.67945 0.3048)
			(stroke
				(width 0.1)
				(type default)
			)
			(layer "F.Fab")
		)
		(fp_line
			(start 0.12065 -0.2794)
			(end 0.12065 -0.3048)
			(stroke
				(width 0.1)
				(type default)
			)
			(layer "F.Fab")
		)
		(fp_line
			(start 0.12065 -0.3048)
			(end 0.67945 -0.3048)
			(stroke
				(width 0.1)
				(type default)
			)
			(layer "F.Fab")
		)
		(fp_line
			(start 0.120396 0.3048)
			(end 0.120396 0.2794)
			(stroke
				(width 0.1)
				(type default)
			)
			(layer "F.Fab")
		)
		(fp_line
			(start 0.120396 0.2794)
			(end -0.12065 0.2794)
			(stroke
				(width 0.1)
				(type default)
			)
			(layer "F.Fab")
		)
		(fp_line
			(start -0.12065 0.3048)
			(end -0.67945 0.3048)
			(stroke
				(width 0.1)
				(type default)
			)
			(layer "F.Fab")
		)
		(fp_line
			(start -0.12065 0.2794)
			(end -0.12065 0.3048)
			(stroke
				(width 0.1)
				(type default)
			)
			(layer "F.Fab")
		)
		(fp_line
			(start -0.12065 -0.2794)
			(end 0.12065 -0.2794)
			(stroke
				(width 0.1)
				(type default)
			)
			(layer "F.Fab")
		)
		(fp_line
			(start -0.12065 -0.305054)
			(end -0.12065 -0.2794)
			(stroke
				(width 0.1)
				(type default)
			)
			(layer "F.Fab")
		)
		(fp_line
			(start -0.67945 0.3048)
			(end -0.67945 -0.305054)
			(stroke
				(width 0.1)
				(type default)
			)
			(layer "F.Fab")
		)
		(fp_line
			(start -0.67945 -0.305054)
			(end -0.12065 -0.305054)
			(stroke
				(width 0.1)
				(type default)
			)
			(layer "F.Fab")
		)
		(pad "1" smd circle
			(at -0.40005 0 180)
			(size 0 0)
			(layers "F.Cu" "F.Mask" "F.Paste")
			(net "PVDDCR_SOC_P1")
		)
		(pad "2" smd circle
			(at 0.40005 0 180)
			(size 0 0)
			(layers "F.Cu" "F.Mask" "F.Paste")
			(net "GND")
		)
	)
	(footprint ""
		(layer "F.Cu")
		(at 245.589298 -242.048538)
		(property "Reference" "ME11"
			(at 0 0 0)
			(layer "F.SilkS")
			(hide yes)
			(effects
				(font
					(size 1.27 1.27)
				)
			)
		)
		(property "Value" ""
			(at 0 0 0)
			(layer "F.Fab")
			(effects
				(font
					(size 1.27 1.27)
				)
			)
		)
		(duplicate_pad_numbers_are_jumpers no)
		(zone
			(layer "F.Cu")
			(hatch none 0.5)
			(connect_pads
				(clearance 0)
			)
			(min_thickness 0.25)
			(keepout
				(tracks allowed)
				(vias allowed)
				(pads allowed)
				(copperpour allowed)
				(footprints not_allowed)
			)
			(placement
				(enabled no)
				(sheetname "")
			)
			(fill
				(thermal_gap 0.5)
				(thermal_bridge_width 0.5)
				(island_removal_mode 0)
			)
			(polygon
				(pts
					(arc
						(start 255.589278 -242.048538)
						(mid 235.589318 -242.048538)
						(end 255.589278 -242.048538)
					)
				)
			)
		)
	)
	(footprint ""
		(layer "F.Cu")
		(at 326.701404 -334.988154)
		(property "Reference" "PU2"
			(at 0.450596 -7.631176 0)
			(unlocked yes)
			(layer "F.SilkS")
			(effects
				(font
					(size 0.7874 0.5842)
					(thickness 0.1524)
				)
				(justify left)
			)
		)
		(property "Value" ""
			(at 0 0 0)
			(layer "F.Fab")
			(effects
				(font
					(size 1.27 1.27)
				)
			)
		)
		(duplicate_pad_numbers_are_jumpers no)
		(fp_line
			(start -2.500122 -2.999994)
			(end -2.24409 -2.999994)
			(stroke
				(width 0.1524)
				(type default)
			)
			(layer "F.SilkS")
		)
		(fp_line
			(start -2.500122 -2.529078)
			(end -2.500122 -2.999994)
			(stroke
				(width 0.1524)
				(type default)
			)
			(layer "F.SilkS")
		)
		(fp_line
			(start -2.500122 0.6604)
			(end -2.500122 0.229108)
			(stroke
				(width 0.1524)
				(type default)
			)
			(layer "F.SilkS")
		)
		(fp_line
			(start -2.500122 2.999994)
			(end -2.500122 2.339594)
			(stroke
				(width 0.1524)
				(type default)
			)
			(layer "F.SilkS")
		)
		(fp_line
			(start -2.2987 2.999994)
			(end -2.500122 2.999994)
			(stroke
				(width 0.1524)
				(type default)
			)
			(layer "F.SilkS")
		)
		(fp_line
			(start 2.31394 -2.999994)
			(end 2.500122 -2.999994)
			(stroke
				(width 0.1524)
				(type default)
			)
			(layer "F.SilkS")
		)
		(fp_line
			(start 2.500122 -2.999994)
			(end 2.500122 -2.44348)
			(stroke
				(width 0.1524)
				(type default)
			)
			(layer "F.SilkS")
		)
		(fp_line
			(start 2.500122 2.339594)
			(end 2.500122 2.999994)
			(stroke
				(width 0.1524)
				(type default)
			)
			(layer "F.SilkS")
		)
		(fp_line
			(start 2.500122 2.999994)
			(end 2.2987 2.999994)
			(stroke
				(width 0.1524)
				(type default)
			)
			(layer "F.SilkS")
		)
		(fp_poly
			(pts
				(xy -2.774442 -2.272284) (xy -3.409442 -1.954784) (xy -3.409442 -2.589784)
			)
			(stroke
				(width 0)
				(type default)
			)
			(fill yes)
			(layer "F.SilkS")
		)
		(fp_line
			(start -2.500122 -2.999994)
			(end 2.500122 -2.999994)
			(stroke
				(width 0.1)
				(type default)
			)
			(layer "F.Fab")
		)
		(fp_line
			(start -2.500122 2.999994)
			(end -2.500122 -2.999994)
			(stroke
				(width 0.1)
				(type default)
			)
			(layer "F.Fab")
		)
		(fp_line
			(start 2.500122 -2.999994)
			(end 2.500122 2.999994)
			(stroke
				(width 0.1)
				(type default)
			)
			(layer "F.Fab")
		)
		(fp_line
			(start 2.500122 2.999994)
			(end -2.500122 2.999994)
			(stroke
				(width 0.1)
				(type default)
			)
			(layer "F.Fab")
		)
		(fp_poly
			(pts
				(xy -4.218432 -2.783078) (xy -4.218432 -1.767078) (xy -3.202432 -2.275078)
			)
			(stroke
				(width 0)
				(type default)
			)
			(fill yes)
			(layer "F.Fab")
		)
		(pad "1" smd rect
			(at -2.400046 -2.275078 90)
			(size 0.2286 0.6096)
			(layers "F.Cu" "F.Mask" "F.Paste")
			(net "PVDDCR_CPU1_P0_VOS2")
		)
		(pad "2" smd rect
			(at -2.400046 -1.82499 90)
			(size 0.2286 0.6096)
			(layers "F.Cu" "F.Mask" "F.Paste")
			(net "GND")
		)
		(pad "3" smd rect
			(at -2.400046 -1.374902 90)
			(size 0.2286 0.6096)
			(layers "F.Cu" "F.Mask" "F.Paste")
			(net "PVDDCR_CPU1_P0_VCC2")
		)
		(pad "4" smd rect
			(at -2.400046 -0.925068 90)
			(size 0.2286 0.6096)
			(layers "F.Cu" "F.Mask" "F.Paste")
			(net "PVDDCR_CPU1_P0_PVCC")
		)
		(pad "5" smd rect
			(at -2.400046 -0.47498 90)
			(size 0.2286 0.6096)
			(layers "F.Cu" "F.Mask" "F.Paste")
			(net "GND")
		)
		(pad "6" smd rect
			(at -2.400046 -0.024892 90)
			(size 0.2286 0.6096)
			(layers "F.Cu" "F.Mask" "F.Paste")
			(net "NC_PVDDCR_CPU1_P0_GL1_2")
		)
		(pad "7_9-20_24" smd circle
			(at 0 1.150112 90)
			(size 0 0)
			(layers "F.Cu" "F.Mask" "F.Paste")
			(net "GND")
		)
		(pad "10_19" smd rect
			(at 0 2.899918 90)
			(size 0.6096 4.318)
			(layers "F.Cu" "F.Mask" "F.Paste")
			(net "SW_PVDDCR_CPU1_P0_SW2")
		)
		(pad "25_29" smd rect
			(at 1.549908 -1.279906 270)
			(size 2.0574 2.3114)
			(layers "F.Cu" "F.Mask" "F.Paste")
			(net "SW_P12V_AUX_PVDDCR_CPU1_P0_FLT")
		)
		(pad "30" smd rect
			(at 2.05994 -2.899918)
			(size 0.2286 0.6096)
			(layers "F.Cu" "F.Mask" "F.Paste")
			(net "SW_P12V_AUX_PVDDCR_CPU1_P0_FLT")
		)
		(pad "31" smd rect
			(at 1.610106 -2.899918)
			(size 0.2286 0.6096)
			(layers "F.Cu" "F.Mask" "F.Paste")
			(net "NC_PVDDCR_CPU1_P0_DNC2")
		)
		(pad "32" smd rect
			(at 1.160018 -2.899918)
			(size 0.2286 0.6096)
			(layers "F.Cu" "F.Mask" "F.Paste")
			(net "SW_PVDDCR_CPU1_P0_BOOTR2")
		)
		(pad "33" smd rect
			(at 0.70993 -2.899918)
			(size 0.2286 0.6096)
			(layers "F.Cu" "F.Mask" "F.Paste")
			(net "SW_PVDDCR_CPU1_P0_BOOT2")
		)
		(pad "34" smd rect
			(at 0.260096 -2.899918)
			(size 0.2286 0.6096)
			(layers "F.Cu" "F.Mask" "F.Paste")
			(net "PVDDCR_CPU1_P0_PWM2")
		)
		(pad "35" smd rect
			(at -0.189992 -2.899918)
			(size 0.2286 0.6096)
			(layers "F.Cu" "F.Mask" "F.Paste")
			(net "PVDDCR_CPU1_P0_VCC2")
		)
		(pad "36" smd rect
			(at -0.64008 -2.899918)
			(size 0.2286 0.6096)
			(layers "F.Cu" "F.Mask" "F.Paste")
			(net "PVDDCR_CPU1_P0_TEMP0")
		)
		(pad "37" smd rect
			(at -1.089914 -2.899918)
			(size 0.2286 0.6096)
			(layers "F.Cu" "F.Mask" "F.Paste")
			(net "PVDDCR_CPU1_P0_LSET2")
		)
		(pad "38" smd rect
			(at -1.540002 -2.899918)
			(size 0.2286 0.6096)
			(layers "F.Cu" "F.Mask" "F.Paste")
			(net "PVDDCR_CPU1_P0_IMON2")
		)
		(pad "39" smd rect
			(at -1.99009 -2.899918)
			(size 0.2286 0.6096)
			(layers "F.Cu" "F.Mask" "F.Paste")
			(net "PVDDCR_CPU1_P0_VCCS")
		)
		(pad "40" smd rect
			(at -0.87503 -1.27508)
			(size 1.7526 1.9558)
			(layers "F.Cu" "F.Mask" "F.Paste")
			(net "GND")
		)
		(pad "41" smd rect
			(at -1.525016 0.249936 270)
			(size 0.3048 0.4572)
			(layers "F.Cu" "F.Mask" "F.Paste")
			(net "NC_PVDDCR_CPU1_P0_GL2_2")
		)
		(zone
			(layer "F.Cu")
			(hatch none 0.5)
			(connect_pads
				(clearance 0)
			)
			(min_thickness 0.25)
			(keepout
				(tracks not_allowed)
				(vias allowed)
				(pads allowed)
				(copperpour not_allowed)
				(footprints allowed)
			)
			(placement
				(enabled no)
				(sheetname "")
			)
			(fill
				(thermal_gap 0.5)
				(thermal_bridge_width 0.5)
				(island_removal_mode 0)
			)
			(polygon
				(pts
					(xy 324.201282 -332.418182) (xy 324.201282 -332.73746) (xy 329.201526 -332.73746) (xy 329.201526 -332.406498)
					(xy 328.911204 -332.406498) (xy 328.911204 -332.443836) (xy 324.491604 -332.443836) (xy 324.491604 -332.418182)
				)
			)
		)
		(zone
			(layer "F.Cu")
			(hatch none 0.5)
			(connect_pads
				(clearance 0)
			)
			(min_thickness 0.25)
			(keepout
				(tracks not_allowed)
				(vias allowed)
				(pads allowed)
				(copperpour not_allowed)
				(footprints allowed)
			)
			(placement
				(enabled no)
				(sheetname "")
			)
			(fill
				(thermal_gap 0.5)
				(thermal_bridge_width 0.5)
				(island_removal_mode 0)
			)
			(polygon
				(pts
					(xy 326.753474 -335.234534) (xy 326.753474 -337.291934) (xy 324.899274 -337.291934) (xy 324.899274 -337.050888)
					(xy 324.656958 -337.050888) (xy 324.656958 -337.532472) (xy 328.471022 -337.532472) (xy 328.471022 -337.34756)
					(xy 327.044812 -337.34756) (xy 327.044812 -335.18856) (xy 329.201526 -335.18856) (xy 329.201526 -334.938878)
					(xy 327.04913 -334.938878)
				)
			)
		)
	)
	(footprint ""
		(layer "F.Cu")
		(at 403.682962 -58.2295 180)
		(property "Reference" "R1621"
			(at 0 0 180)
			(layer "F.SilkS")
			(hide yes)
			(effects
				(font
					(size 1.27 1.27)
				)
			)
		)
		(property "Value" ""
			(at 0 0 180)
			(layer "F.Fab")
			(effects
				(font
					(size 1.27 1.27)
				)
			)
		)
		(duplicate_pad_numbers_are_jumpers no)
		(fp_line
			(start 0.7874 0.4064)
			(end -0.7874 0.4064)
			(stroke
				(width 0.1524)
				(type default)
			)
			(layer "F.SilkS")
		)
		(fp_line
			(start 0.7874 -0.4064)
			(end 0.7874 0.4064)
			(stroke
				(width 0.1524)
				(type default)
			)
			(layer "F.SilkS")
		)
		(fp_line
			(start -0.7874 0.4064)
			(end -0.7874 -0.4064)
			(stroke
				(width 0.1524)
				(type default)
			)
			(layer "F.SilkS")
		)
		(fp_line
			(start -0.7874 -0.4064)
			(end 0.7874 -0.4064)
			(stroke
				(width 0.1524)
				(type default)
			)
			(layer "F.SilkS")
		)
		(fp_line
			(start 0.67945 0.3048)
			(end 0.120396 0.3048)
			(stroke
				(width 0.1)
				(type default)
			)
			(layer "F.Fab")
		)
		(fp_line
			(start 0.67945 -0.3048)
			(end 0.67945 0.3048)
			(stroke
				(width 0.1)
				(type default)
			)
			(layer "F.Fab")
		)
		(fp_line
			(start 0.12065 -0.2794)
			(end 0.12065 -0.3048)
			(stroke
				(width 0.1)
				(type default)
			)
			(layer "F.Fab")
		)
		(fp_line
			(start 0.12065 -0.3048)
			(end 0.67945 -0.3048)
			(stroke
				(width 0.1)
				(type default)
			)
			(layer "F.Fab")
		)
		(fp_line
			(start 0.120396 0.3048)
			(end 0.120396 0.2794)
			(stroke
				(width 0.1)
				(type default)
			)
			(layer "F.Fab")
		)
		(fp_line
			(start 0.120396 0.2794)
			(end -0.12065 0.2794)
			(stroke
				(width 0.1)
				(type default)
			)
			(layer "F.Fab")
		)
		(fp_line
			(start -0.12065 0.3048)
			(end -0.67945 0.3048)
			(stroke
				(width 0.1)
				(type default)
			)
			(layer "F.Fab")
		)
		(fp_line
			(start -0.12065 0.2794)
			(end -0.12065 0.3048)
			(stroke
				(width 0.1)
				(type default)
			)
			(layer "F.Fab")
		)
		(fp_line
			(start -0.12065 -0.2794)
			(end 0.12065 -0.2794)
			(stroke
				(width 0.1)
				(type default)
			)
			(layer "F.Fab")
		)
		(fp_line
			(start -0.12065 -0.305054)
			(end -0.12065 -0.2794)
			(stroke
				(width 0.1)
				(type default)
			)
			(layer "F.Fab")
		)
		(fp_line
			(start -0.67945 0.3048)
			(end -0.67945 -0.305054)
			(stroke
				(width 0.1)
				(type default)
			)
			(layer "F.Fab")
		)
		(fp_line
			(start -0.67945 -0.305054)
			(end -0.12065 -0.305054)
			(stroke
				(width 0.1)
				(type default)
			)
			(layer "F.Fab")
		)
		(pad "1" smd circle
			(at -0.40005 0 180)
			(size 0 0)
			(layers "F.Cu" "F.Mask" "F.Paste")
			(net "PVDD18_S5_P0")
		)
		(pad "2" smd circle
			(at 0.40005 0 180)
			(size 0 0)
			(layers "F.Cu" "F.Mask" "F.Paste")
			(net "HDT_HDR_TRST_N_R")
		)
	)
	(footprint ""
		(layer "F.Cu")
		(at 200.939908 -112.609376 180)
		(property "Reference" "R218"
			(at 0 0 180)
			(layer "F.SilkS")
			(hide yes)
			(effects
				(font
					(size 1.27 1.27)
				)
			)
		)
		(property "Value" ""
			(at 0 0 180)
			(layer "F.Fab")
			(effects
				(font
					(size 1.27 1.27)
				)
			)
		)
		(duplicate_pad_numbers_are_jumpers no)
		(fp_line
			(start 0.7874 0.4064)
			(end -0.7874 0.4064)
			(stroke
				(width 0.1524)
				(type default)
			)
			(layer "F.SilkS")
		)
		(fp_line
			(start 0.7874 -0.4064)
			(end 0.7874 0.4064)
			(stroke
				(width 0.1524)
				(type default)
			)
			(layer "F.SilkS")
		)
		(fp_line
			(start -0.7874 0.4064)
			(end -0.7874 -0.4064)
			(stroke
				(width 0.1524)
				(type default)
			)
			(layer "F.SilkS")
		)
		(fp_line
			(start -0.7874 -0.4064)
			(end 0.7874 -0.4064)
			(stroke
				(width 0.1524)
				(type default)
			)
			(layer "F.SilkS")
		)
		(fp_line
			(start 0.67945 0.3048)
			(end 0.120396 0.3048)
			(stroke
				(width 0.1)
				(type default)
			)
			(layer "F.Fab")
		)
		(fp_line
			(start 0.67945 -0.3048)
			(end 0.67945 0.3048)
			(stroke
				(width 0.1)
				(type default)
			)
			(layer "F.Fab")
		)
		(fp_line
			(start 0.12065 -0.2794)
			(end 0.12065 -0.3048)
			(stroke
				(width 0.1)
				(type default)
			)
			(layer "F.Fab")
		)
		(fp_line
			(start 0.12065 -0.3048)
			(end 0.67945 -0.3048)
			(stroke
				(width 0.1)
				(type default)
			)
			(layer "F.Fab")
		)
		(fp_line
			(start 0.120396 0.3048)
			(end 0.120396 0.2794)
			(stroke
				(width 0.1)
				(type default)
			)
			(layer "F.Fab")
		)
		(fp_line
			(start 0.120396 0.2794)
			(end -0.12065 0.2794)
			(stroke
				(width 0.1)
				(type default)
			)
			(layer "F.Fab")
		)
		(fp_line
			(start -0.12065 0.3048)
			(end -0.67945 0.3048)
			(stroke
				(width 0.1)
				(type default)
			)
			(layer "F.Fab")
		)
		(fp_line
			(start -0.12065 0.2794)
			(end -0.12065 0.3048)
			(stroke
				(width 0.1)
				(type default)
			)
			(layer "F.Fab")
		)
		(fp_line
			(start -0.12065 -0.2794)
			(end 0.12065 -0.2794)
			(stroke
				(width 0.1)
				(type default)
			)
			(layer "F.Fab")
		)
		(fp_line
			(start -0.12065 -0.305054)
			(end -0.12065 -0.2794)
			(stroke
				(width 0.1)
				(type default)
			)
			(layer "F.Fab")
		)
		(fp_line
			(start -0.67945 0.3048)
			(end -0.67945 -0.305054)
			(stroke
				(width 0.1)
				(type default)
			)
			(layer "F.Fab")
		)
		(fp_line
			(start -0.67945 -0.305054)
			(end -0.12065 -0.305054)
			(stroke
				(width 0.1)
				(type default)
			)
			(layer "F.Fab")
		)
		(pad "1" smd circle
			(at -0.40005 0 180)
			(size 0 0)
			(layers "F.Cu" "F.Mask" "F.Paste")
			(net "CPU0_PWR_GOOD")
		)
		(pad "2" smd circle
			(at 0.40005 0 180)
			(size 0 0)
			(layers "F.Cu" "F.Mask" "F.Paste")
			(net "FM_CPU0_PWR_GOOD")
		)
	)
	(footprint ""
		(layer "F.Cu")
		(at 401.23364 -378.95403 -90)
		(property "Reference" "C862"
			(at 0 0 270)
			(layer "F.SilkS")
			(hide yes)
			(effects
				(font
					(size 1.27 1.27)
				)
			)
		)
		(property "Value" ""
			(at 0 0 270)
			(layer "F.Fab")
			(effects
				(font
					(size 1.27 1.27)
				)
			)
		)
		(duplicate_pad_numbers_are_jumpers no)
		(fp_line
			(start -0.299974 0.150114)
			(end -0.299974 -0.150114)
			(stroke
				(width 0.1)
				(type default)
			)
			(layer "F.Fab")
		)
		(fp_line
			(start 0.299974 0.150114)
			(end -0.299974 0.150114)
			(stroke
				(width 0.1)
				(type default)
			)
			(layer "F.Fab")
		)
		(fp_line
			(start -0.299974 -0.150114)
			(end 0.299974 -0.150114)
			(stroke
				(width 0.1)
				(type default)
			)
			(layer "F.Fab")
		)
		(fp_line
			(start 0.299974 -0.150114)
			(end 0.299974 0.150114)
			(stroke
				(width 0.1)
				(type default)
			)
			(layer "F.Fab")
		)
		(pad "1" smd rect
			(at -0.2667 0 270)
			(size 0.3048 0.381)
			(layers "F.Cu" "F.Mask" "F.Paste")
			(net "P5E_CPU0_P2_TX_C_DN<3>")
		)
		(pad "2" smd rect
			(at 0.2667 0 270)
			(size 0.3048 0.381)
			(layers "F.Cu" "F.Mask" "F.Paste")
			(net "P5E_CPU0_P2_TX_DN<3>")
		)
	)
	(footprint ""
		(layer "F.Cu")
		(at 365.518446 -28.306522 90)
		(property "Reference" "R825"
			(at 0 0 90)
			(layer "F.SilkS")
			(hide yes)
			(effects
				(font
					(size 1.27 1.27)
				)
			)
		)
		(property "Value" ""
			(at 0 0 90)
			(layer "F.Fab")
			(effects
				(font
					(size 1.27 1.27)
				)
			)
		)
		(duplicate_pad_numbers_are_jumpers no)
		(fp_line
			(start 0.7874 -0.4064)
			(end 0.7874 0.4064)
			(stroke
				(width 0.1524)
				(type default)
			)
			(layer "F.SilkS")
		)
		(fp_line
			(start -0.7874 -0.4064)
			(end 0.7874 -0.4064)
			(stroke
				(width 0.1524)
				(type default)
			)
			(layer "F.SilkS")
		)
		(fp_line
			(start 0.7874 0.4064)
			(end -0.7874 0.4064)
			(stroke
				(width 0.1524)
				(type default)
			)
			(layer "F.SilkS")
		)
		(fp_line
			(start -0.7874 0.4064)
			(end -0.7874 -0.4064)
			(stroke
				(width 0.1524)
				(type default)
			)
			(layer "F.SilkS")
		)
		(fp_line
			(start -0.12065 -0.305054)
			(end -0.12065 -0.2794)
			(stroke
				(width 0.1)
				(type default)
			)
			(layer "F.Fab")
		)
		(fp_line
			(start -0.67945 -0.305054)
			(end -0.12065 -0.305054)
			(stroke
				(width 0.1)
				(type default)
			)
			(layer "F.Fab")
		)
		(fp_line
			(start 0.67945 -0.3048)
			(end 0.67945 0.3048)
			(stroke
				(width 0.1)
				(type default)
			)
			(layer "F.Fab")
		)
		(fp_line
			(start 0.12065 -0.3048)
			(end 0.67945 -0.3048)
			(stroke
				(width 0.1)
				(type default)
			)
			(layer "F.Fab")
		)
		(fp_line
			(start 0.12065 -0.2794)
			(end 0.12065 -0.3048)
			(stroke
				(width 0.1)
				(type default)
			)
			(layer "F.Fab")
		)
		(fp_line
			(start -0.12065 -0.2794)
			(end 0.12065 -0.2794)
			(stroke
				(width 0.1)
				(type default)
			)
			(layer "F.Fab")
		)
		(fp_line
			(start 0.120396 0.2794)
			(end -0.12065 0.2794)
			(stroke
				(width 0.1)
				(type default)
			)
			(layer "F.Fab")
		)
		(fp_line
			(start -0.12065 0.2794)
			(end -0.12065 0.3048)
			(stroke
				(width 0.1)
				(type default)
			)
			(layer "F.Fab")
		)
		(fp_line
			(start 0.67945 0.3048)
			(end 0.120396 0.3048)
			(stroke
				(width 0.1)
				(type default)
			)
			(layer "F.Fab")
		)
		(fp_line
			(start 0.120396 0.3048)
			(end 0.120396 0.2794)
			(stroke
				(width 0.1)
				(type default)
			)
			(layer "F.Fab")
		)
		(fp_line
			(start -0.12065 0.3048)
			(end -0.67945 0.3048)
			(stroke
				(width 0.1)
				(type default)
			)
			(layer "F.Fab")
		)
		(fp_line
			(start -0.67945 0.3048)
			(end -0.67945 -0.305054)
			(stroke
				(width 0.1)
				(type default)
			)
			(layer "F.Fab")
		)
		(pad "1" smd circle
			(at -0.40005 0 90)
			(size 0 0)
			(layers "F.Cu" "F.Mask" "F.Paste")
			(net "P3V3_AUX")
		)
		(pad "2" smd circle
			(at 0.40005 0 90)
			(size 0 0)
			(layers "F.Cu" "F.Mask" "F.Paste")
			(net "UART_CPU0_LVC3_UART0_RX")
		)
	)
	(footprint ""
		(layer "F.Cu")
		(at 382.391158 -323.186552 90)
		(property "Reference" "R939"
			(at 0 0 90)
			(layer "F.SilkS")
			(hide yes)
			(effects
				(font
					(size 1.27 1.27)
				)
			)
		)
		(property "Value" ""
			(at 0 0 90)
			(layer "F.Fab")
			(effects
				(font
					(size 1.27 1.27)
				)
			)
		)
		(duplicate_pad_numbers_are_jumpers no)
		(fp_line
			(start 0.7874 -0.4064)
			(end 0.7874 0.4064)
			(stroke
				(width 0.1524)
				(type default)
			)
			(layer "F.SilkS")
		)
		(fp_line
			(start -0.7874 -0.4064)
			(end 0.7874 -0.4064)
			(stroke
				(width 0.1524)
				(type default)
			)
			(layer "F.SilkS")
		)
		(fp_line
			(start 0.7874 0.4064)
			(end -0.7874 0.4064)
			(stroke
				(width 0.1524)
				(type default)
			)
			(layer "F.SilkS")
		)
		(fp_line
			(start -0.7874 0.4064)
			(end -0.7874 -0.4064)
			(stroke
				(width 0.1524)
				(type default)
			)
			(layer "F.SilkS")
		)
		(fp_line
			(start -0.12065 -0.305054)
			(end -0.12065 -0.2794)
			(stroke
				(width 0.1)
				(type default)
			)
			(layer "F.Fab")
		)
		(fp_line
			(start -0.67945 -0.305054)
			(end -0.12065 -0.305054)
			(stroke
				(width 0.1)
				(type default)
			)
			(layer "F.Fab")
		)
		(fp_line
			(start 0.67945 -0.3048)
			(end 0.67945 0.3048)
			(stroke
				(width 0.1)
				(type default)
			)
			(layer "F.Fab")
		)
		(fp_line
			(start 0.12065 -0.3048)
			(end 0.67945 -0.3048)
			(stroke
				(width 0.1)
				(type default)
			)
			(layer "F.Fab")
		)
		(fp_line
			(start 0.12065 -0.2794)
			(end 0.12065 -0.3048)
			(stroke
				(width 0.1)
				(type default)
			)
			(layer "F.Fab")
		)
		(fp_line
			(start -0.12065 -0.2794)
			(end 0.12065 -0.2794)
			(stroke
				(width 0.1)
				(type default)
			)
			(layer "F.Fab")
		)
		(fp_line
			(start 0.120396 0.2794)
			(end -0.12065 0.2794)
			(stroke
				(width 0.1)
				(type default)
			)
			(layer "F.Fab")
		)
		(fp_line
			(start -0.12065 0.2794)
			(end -0.12065 0.3048)
			(stroke
				(width 0.1)
				(type default)
			)
			(layer "F.Fab")
		)
		(fp_line
			(start 0.67945 0.3048)
			(end 0.120396 0.3048)
			(stroke
				(width 0.1)
				(type default)
			)
			(layer "F.Fab")
		)
		(fp_line
			(start 0.120396 0.3048)
			(end 0.120396 0.2794)
			(stroke
				(width 0.1)
				(type default)
			)
			(layer "F.Fab")
		)
		(fp_line
			(start -0.12065 0.3048)
			(end -0.67945 0.3048)
			(stroke
				(width 0.1)
				(type default)
			)
			(layer "F.Fab")
		)
		(fp_line
			(start -0.67945 0.3048)
			(end -0.67945 -0.305054)
			(stroke
				(width 0.1)
				(type default)
			)
			(layer "F.Fab")
		)
		(pad "1" smd circle
			(at -0.40005 0 90)
			(size 0 0)
			(layers "F.Cu" "F.Mask" "F.Paste")
			(net "FM_BIOS_POST_CMPLT_R_N")
		)
		(pad "2" smd circle
			(at 0.40005 0 90)
			(size 0 0)
			(layers "F.Cu" "F.Mask" "F.Paste")
			(net "FM_BIOS_POST_CMPLT_N")
		)
	)
	(footprint ""
		(layer "F.Cu")
		(at 167.900096 -160.50006)
		(property "Reference" "H89"
			(at -5.028184 -6.468618 0)
			(unlocked yes)
			(layer "F.SilkS")
			(effects
				(font
					(size 0.7874 0.5842)
					(thickness 0.1524)
				)
				(justify left)
			)
		)
		(property "Value" ""
			(at 0 0 0)
			(layer "F.Fab")
			(effects
				(font
					(size 1.27 1.27)
				)
			)
		)
		(duplicate_pad_numbers_are_jumpers no)
		(pad "1" thru_hole circle
			(at 0 0)
			(size 10.0076 10.0076)
			(drill 5.6134)
			(layers "*.Cu" "*.Mask")
			(remove_unused_layers no)
			(net "GND")
			(clearance -1.9431)
		)
	)
	(footprint ""
		(layer "F.Cu")
		(at 323.637148 -41.160954)
		(property "Reference" "R3681"
			(at 0 0 0)
			(layer "F.SilkS")
			(hide yes)
			(effects
				(font
					(size 1.27 1.27)
				)
			)
		)
		(property "Value" ""
			(at 0 0 0)
			(layer "F.Fab")
			(effects
				(font
					(size 1.27 1.27)
				)
			)
		)
		(duplicate_pad_numbers_are_jumpers no)
		(fp_line
			(start -0.7874 -0.4064)
			(end 0.7874 -0.4064)
			(stroke
				(width 0.1524)
				(type default)
			)
			(layer "F.SilkS")
		)
		(fp_line
			(start -0.7874 0.4064)
			(end -0.7874 -0.4064)
			(stroke
				(width 0.1524)
				(type default)
			)
			(layer "F.SilkS")
		)
		(fp_line
			(start 0.7874 -0.4064)
			(end 0.7874 0.4064)
			(stroke
				(width 0.1524)
				(type default)
			)
			(layer "F.SilkS")
		)
		(fp_line
			(start 0.7874 0.4064)
			(end -0.7874 0.4064)
			(stroke
				(width 0.1524)
				(type default)
			)
			(layer "F.SilkS")
		)
		(fp_line
			(start -0.67945 -0.305054)
			(end -0.12065 -0.305054)
			(stroke
				(width 0.1)
				(type default)
			)
			(layer "F.Fab")
		)
		(fp_line
			(start -0.67945 0.3048)
			(end -0.67945 -0.305054)
			(stroke
				(width 0.1)
				(type default)
			)
			(layer "F.Fab")
		)
		(fp_line
			(start -0.12065 -0.305054)
			(end -0.12065 -0.2794)
			(stroke
				(width 0.1)
				(type default)
			)
			(layer "F.Fab")
		)
		(fp_line
			(start -0.12065 -0.2794)
			(end 0.12065 -0.2794)
			(stroke
				(width 0.1)
				(type default)
			)
			(layer "F.Fab")
		)
		(fp_line
			(start -0.12065 0.2794)
			(end -0.12065 0.3048)
			(stroke
				(width 0.1)
				(type default)
			)
			(layer "F.Fab")
		)
		(fp_line
			(start -0.12065 0.3048)
			(end -0.67945 0.3048)
			(stroke
				(width 0.1)
				(type default)
			)
			(layer "F.Fab")
		)
		(fp_line
			(start 0.120396 0.2794)
			(end -0.12065 0.2794)
			(stroke
				(width 0.1)
				(type default)
			)
			(layer "F.Fab")
		)
		(fp_line
			(start 0.120396 0.3048)
			(end 0.120396 0.2794)
			(stroke
				(width 0.1)
				(type default)
			)
			(layer "F.Fab")
		)
		(fp_line
			(start 0.12065 -0.3048)
			(end 0.67945 -0.3048)
			(stroke
				(width 0.1)
				(type default)
			)
			(layer "F.Fab")
		)
		(fp_line
			(start 0.12065 -0.2794)
			(end 0.12065 -0.3048)
			(stroke
				(width 0.1)
				(type default)
			)
			(layer "F.Fab")
		)
		(fp_line
			(start 0.67945 -0.3048)
			(end 0.67945 0.3048)
			(stroke
				(width 0.1)
				(type default)
			)
			(layer "F.Fab")
		)
		(fp_line
			(start 0.67945 0.3048)
			(end 0.120396 0.3048)
			(stroke
				(width 0.1)
				(type default)
			)
			(layer "F.Fab")
		)
		(pad "1" smd rect
			(at -0.40005 0 180)
			(size 0.4572 0.508)
			(layers "F.Cu" "F.Mask" "F.Paste")
			(net "P3V3_AUX_ADC")
		)
		(pad "2" smd rect
			(at 0.40005 0 180)
			(size 0.4572 0.508)
			(layers "F.Cu" "F.Mask" "F.Paste")
			(net "P3V3_AUX_ADC_MAM")
		)
	)
	(footprint ""
		(layer "F.Cu")
		(at 328.868024 -140.245338)
		(property "Reference" "PC6005"
			(at 0 0 0)
			(layer "F.SilkS")
			(hide yes)
			(effects
				(font
					(size 1.27 1.27)
				)
			)
		)
		(property "Value" ""
			(at 0 0 0)
			(layer "F.Fab")
			(effects
				(font
					(size 1.27 1.27)
				)
			)
		)
		(duplicate_pad_numbers_are_jumpers no)
		(fp_line
			(start -0.7874 -0.4064)
			(end 0.7874 -0.4064)
			(stroke
				(width 0.1524)
				(type default)
			)
			(layer "F.SilkS")
		)
		(fp_line
			(start -0.7874 0.4064)
			(end -0.7874 -0.4064)
			(stroke
				(width 0.1524)
				(type default)
			)
			(layer "F.SilkS")
		)
		(fp_line
			(start 0.7874 -0.4064)
			(end 0.7874 0.4064)
			(stroke
				(width 0.1524)
				(type default)
			)
			(layer "F.SilkS")
		)
		(fp_line
			(start 0.7874 0.4064)
			(end -0.7874 0.4064)
			(stroke
				(width 0.1524)
				(type default)
			)
			(layer "F.SilkS")
		)
		(fp_line
			(start -0.67945 -0.305054)
			(end -0.12065 -0.305054)
			(stroke
				(width 0.1)
				(type default)
			)
			(layer "F.Fab")
		)
		(fp_line
			(start -0.67945 0.3048)
			(end -0.67945 -0.305054)
			(stroke
				(width 0.1)
				(type default)
			)
			(layer "F.Fab")
		)
		(fp_line
			(start -0.12065 -0.305054)
			(end -0.12065 -0.2794)
			(stroke
				(width 0.1)
				(type default)
			)
			(layer "F.Fab")
		)
		(fp_line
			(start -0.12065 -0.2794)
			(end 0.12065 -0.2794)
			(stroke
				(width 0.1)
				(type default)
			)
			(layer "F.Fab")
		)
		(fp_line
			(start -0.12065 0.2794)
			(end -0.12065 0.3048)
			(stroke
				(width 0.1)
				(type default)
			)
			(layer "F.Fab")
		)
		(fp_line
			(start -0.12065 0.3048)
			(end -0.67945 0.3048)
			(stroke
				(width 0.1)
				(type default)
			)
			(layer "F.Fab")
		)
		(fp_line
			(start 0.120396 0.2794)
			(end -0.12065 0.2794)
			(stroke
				(width 0.1)
				(type default)
			)
			(layer "F.Fab")
		)
		(fp_line
			(start 0.120396 0.3048)
			(end 0.120396 0.2794)
			(stroke
				(width 0.1)
				(type default)
			)
			(layer "F.Fab")
		)
		(fp_line
			(start 0.12065 -0.3048)
			(end 0.67945 -0.3048)
			(stroke
				(width 0.1)
				(type default)
			)
			(layer "F.Fab")
		)
		(fp_line
			(start 0.12065 -0.2794)
			(end 0.12065 -0.3048)
			(stroke
				(width 0.1)
				(type default)
			)
			(layer "F.Fab")
		)
		(fp_line
			(start 0.67945 -0.3048)
			(end 0.67945 0.3048)
			(stroke
				(width 0.1)
				(type default)
			)
			(layer "F.Fab")
		)
		(fp_line
			(start 0.67945 0.3048)
			(end 0.120396 0.3048)
			(stroke
				(width 0.1)
				(type default)
			)
			(layer "F.Fab")
		)
		(pad "1" smd circle
			(at -0.40005 0)
			(size 0 0)
			(layers "F.Cu" "F.Mask" "F.Paste")
			(net "PVDD18_S5_P0_FB_RC")
		)
		(pad "2" smd circle
			(at 0.40005 0)
			(size 0 0)
			(layers "F.Cu" "F.Mask" "F.Paste")
			(net "PVDD18_S5_P0_RGND")
		)
	)
	(footprint ""
		(layer "F.Cu")
		(at 200.939908 -106.513376 180)
		(property "Reference" "R228"
			(at 0 0 180)
			(layer "F.SilkS")
			(hide yes)
			(effects
				(font
					(size 1.27 1.27)
				)
			)
		)
		(property "Value" ""
			(at 0 0 180)
			(layer "F.Fab")
			(effects
				(font
					(size 1.27 1.27)
				)
			)
		)
		(duplicate_pad_numbers_are_jumpers no)
		(fp_line
			(start 0.7874 0.4064)
			(end -0.7874 0.4064)
			(stroke
				(width 0.1524)
				(type default)
			)
			(layer "F.SilkS")
		)
		(fp_line
			(start 0.7874 -0.4064)
			(end 0.7874 0.4064)
			(stroke
				(width 0.1524)
				(type default)
			)
			(layer "F.SilkS")
		)
		(fp_line
			(start -0.7874 0.4064)
			(end -0.7874 -0.4064)
			(stroke
				(width 0.1524)
				(type default)
			)
			(layer "F.SilkS")
		)
		(fp_line
			(start -0.7874 -0.4064)
			(end 0.7874 -0.4064)
			(stroke
				(width 0.1524)
				(type default)
			)
			(layer "F.SilkS")
		)
		(fp_line
			(start 0.67945 0.3048)
			(end 0.120396 0.3048)
			(stroke
				(width 0.1)
				(type default)
			)
			(layer "F.Fab")
		)
		(fp_line
			(start 0.67945 -0.3048)
			(end 0.67945 0.3048)
			(stroke
				(width 0.1)
				(type default)
			)
			(layer "F.Fab")
		)
		(fp_line
			(start 0.12065 -0.2794)
			(end 0.12065 -0.3048)
			(stroke
				(width 0.1)
				(type default)
			)
			(layer "F.Fab")
		)
		(fp_line
			(start 0.12065 -0.3048)
			(end 0.67945 -0.3048)
			(stroke
				(width 0.1)
				(type default)
			)
			(layer "F.Fab")
		)
		(fp_line
			(start 0.120396 0.3048)
			(end 0.120396 0.2794)
			(stroke
				(width 0.1)
				(type default)
			)
			(layer "F.Fab")
		)
		(fp_line
			(start 0.120396 0.2794)
			(end -0.12065 0.2794)
			(stroke
				(width 0.1)
				(type default)
			)
			(layer "F.Fab")
		)
		(fp_line
			(start -0.12065 0.3048)
			(end -0.67945 0.3048)
			(stroke
				(width 0.1)
				(type default)
			)
			(layer "F.Fab")
		)
		(fp_line
			(start -0.12065 0.2794)
			(end -0.12065 0.3048)
			(stroke
				(width 0.1)
				(type default)
			)
			(layer "F.Fab")
		)
		(fp_line
			(start -0.12065 -0.2794)
			(end 0.12065 -0.2794)
			(stroke
				(width 0.1)
				(type default)
			)
			(layer "F.Fab")
		)
		(fp_line
			(start -0.12065 -0.305054)
			(end -0.12065 -0.2794)
			(stroke
				(width 0.1)
				(type default)
			)
			(layer "F.Fab")
		)
		(fp_line
			(start -0.67945 0.3048)
			(end -0.67945 -0.305054)
			(stroke
				(width 0.1)
				(type default)
			)
			(layer "F.Fab")
		)
		(fp_line
			(start -0.67945 -0.305054)
			(end -0.12065 -0.305054)
			(stroke
				(width 0.1)
				(type default)
			)
			(layer "F.Fab")
		)
		(pad "1" smd circle
			(at -0.40005 0 180)
			(size 0 0)
			(layers "F.Cu" "F.Mask" "F.Paste")
			(net "PWRGD_PVDD11_S3_P0")
		)
		(pad "2" smd circle
			(at 0.40005 0 180)
			(size 0 0)
			(layers "F.Cu" "F.Mask" "F.Paste")
			(net "FM_PWRGD_PVDD11_S3_P0")
		)
	)
	(footprint ""
		(layer "F.Cu")
		(at 188.552582 -356.178358 90)
		(property "Reference" "PC504_2"
			(at 0 0 90)
			(layer "F.SilkS")
			(hide yes)
			(effects
				(font
					(size 1.27 1.27)
				)
			)
		)
		(property "Value" ""
			(at 0 0 90)
			(layer "F.Fab")
			(effects
				(font
					(size 1.27 1.27)
				)
			)
		)
		(duplicate_pad_numbers_are_jumpers no)
		(fp_line
			(start 0.7874 -0.4064)
			(end 0.7874 0.4064)
			(stroke
				(width 0.1524)
				(type default)
			)
			(layer "F.SilkS")
		)
		(fp_line
			(start -0.7874 -0.4064)
			(end 0.7874 -0.4064)
			(stroke
				(width 0.1524)
				(type default)
			)
			(layer "F.SilkS")
		)
		(fp_line
			(start 0.7874 0.4064)
			(end -0.7874 0.4064)
			(stroke
				(width 0.1524)
				(type default)
			)
			(layer "F.SilkS")
		)
		(fp_line
			(start -0.7874 0.4064)
			(end -0.7874 -0.4064)
			(stroke
				(width 0.1524)
				(type default)
			)
			(layer "F.SilkS")
		)
		(fp_line
			(start -0.12065 -0.305054)
			(end -0.12065 -0.2794)
			(stroke
				(width 0.1)
				(type default)
			)
			(layer "F.Fab")
		)
		(fp_line
			(start -0.67945 -0.305054)
			(end -0.12065 -0.305054)
			(stroke
				(width 0.1)
				(type default)
			)
			(layer "F.Fab")
		)
		(fp_line
			(start 0.67945 -0.3048)
			(end 0.67945 0.3048)
			(stroke
				(width 0.1)
				(type default)
			)
			(layer "F.Fab")
		)
		(fp_line
			(start 0.12065 -0.3048)
			(end 0.67945 -0.3048)
			(stroke
				(width 0.1)
				(type default)
			)
			(layer "F.Fab")
		)
		(fp_line
			(start 0.12065 -0.2794)
			(end 0.12065 -0.3048)
			(stroke
				(width 0.1)
				(type default)
			)
			(layer "F.Fab")
		)
		(fp_line
			(start -0.12065 -0.2794)
			(end 0.12065 -0.2794)
			(stroke
				(width 0.1)
				(type default)
			)
			(layer "F.Fab")
		)
		(fp_line
			(start 0.120396 0.2794)
			(end -0.12065 0.2794)
			(stroke
				(width 0.1)
				(type default)
			)
			(layer "F.Fab")
		)
		(fp_line
			(start -0.12065 0.2794)
			(end -0.12065 0.3048)
			(stroke
				(width 0.1)
				(type default)
			)
			(layer "F.Fab")
		)
		(fp_line
			(start 0.67945 0.3048)
			(end 0.120396 0.3048)
			(stroke
				(width 0.1)
				(type default)
			)
			(layer "F.Fab")
		)
		(fp_line
			(start 0.120396 0.3048)
			(end 0.120396 0.2794)
			(stroke
				(width 0.1)
				(type default)
			)
			(layer "F.Fab")
		)
		(fp_line
			(start -0.12065 0.3048)
			(end -0.67945 0.3048)
			(stroke
				(width 0.1)
				(type default)
			)
			(layer "F.Fab")
		)
		(fp_line
			(start -0.67945 0.3048)
			(end -0.67945 -0.305054)
			(stroke
				(width 0.1)
				(type default)
			)
			(layer "F.Fab")
		)
		(pad "1" smd circle
			(at -0.40005 0 90)
			(size 0 0)
			(layers "F.Cu" "F.Mask" "F.Paste")
			(net "PVDD11_S3_P1_VCCS")
		)
		(pad "2" smd circle
			(at 0.40005 0 90)
			(size 0 0)
			(layers "F.Cu" "F.Mask" "F.Paste")
			(net "GND")
		)
	)
	(footprint ""
		(layer "F.Cu")
		(at 153.277824 -191.358266 -90)
		(property "Reference" "R3354"
			(at 0 0 270)
			(layer "F.SilkS")
			(hide yes)
			(effects
				(font
					(size 1.27 1.27)
				)
			)
		)
		(property "Value" ""
			(at 0 0 270)
			(layer "F.Fab")
			(effects
				(font
					(size 1.27 1.27)
				)
			)
		)
		(duplicate_pad_numbers_are_jumpers no)
		(fp_line
			(start -0.7874 0.4064)
			(end -0.7874 -0.061976)
			(stroke
				(width 0.1524)
				(type default)
			)
			(layer "F.SilkS")
		)
		(fp_line
			(start 0.7874 0.4064)
			(end -0.7874 0.4064)
			(stroke
				(width 0.1524)
				(type default)
			)
			(layer "F.SilkS")
		)
		(fp_line
			(start 0.7874 -0.061976)
			(end 0.7874 0.4064)
			(stroke
				(width 0.1524)
				(type default)
			)
			(layer "F.SilkS")
		)
		(fp_line
			(start -0.386334 -0.4064)
			(end 0.324866 -0.4064)
			(stroke
				(width 0.1524)
				(type default)
			)
			(layer "F.SilkS")
		)
		(fp_line
			(start -0.67945 0.3048)
			(end -0.67945 -0.305054)
			(stroke
				(width 0.1)
				(type default)
			)
			(layer "F.Fab")
		)
		(fp_line
			(start -0.12065 0.3048)
			(end -0.67945 0.3048)
			(stroke
				(width 0.1)
				(type default)
			)
			(layer "F.Fab")
		)
		(fp_line
			(start 0.120396 0.3048)
			(end 0.120396 0.2794)
			(stroke
				(width 0.1)
				(type default)
			)
			(layer "F.Fab")
		)
		(fp_line
			(start 0.67945 0.3048)
			(end 0.120396 0.3048)
			(stroke
				(width 0.1)
				(type default)
			)
			(layer "F.Fab")
		)
		(fp_line
			(start -0.12065 0.2794)
			(end -0.12065 0.3048)
			(stroke
				(width 0.1)
				(type default)
			)
			(layer "F.Fab")
		)
		(fp_line
			(start 0.120396 0.2794)
			(end -0.12065 0.2794)
			(stroke
				(width 0.1)
				(type default)
			)
			(layer "F.Fab")
		)
		(fp_line
			(start -0.12065 -0.2794)
			(end 0.12065 -0.2794)
			(stroke
				(width 0.1)
				(type default)
			)
			(layer "F.Fab")
		)
		(fp_line
			(start 0.12065 -0.2794)
			(end 0.12065 -0.3048)
			(stroke
				(width 0.1)
				(type default)
			)
			(layer "F.Fab")
		)
		(fp_line
			(start 0.12065 -0.3048)
			(end 0.67945 -0.3048)
			(stroke
				(width 0.1)
				(type default)
			)
			(layer "F.Fab")
		)
		(fp_line
			(start 0.67945 -0.3048)
			(end 0.67945 0.3048)
			(stroke
				(width 0.1)
				(type default)
			)
			(layer "F.Fab")
		)
		(fp_line
			(start -0.67945 -0.305054)
			(end -0.12065 -0.305054)
			(stroke
				(width 0.1)
				(type default)
			)
			(layer "F.Fab")
		)
		(fp_line
			(start -0.12065 -0.305054)
			(end -0.12065 -0.2794)
			(stroke
				(width 0.1)
				(type default)
			)
			(layer "F.Fab")
		)
		(pad "1" smd circle
			(at -0.40005 0 270)
			(size 0 0)
			(layers "F.Cu" "F.Mask" "F.Paste")
			(net "CLK_100M_CPU1_CLK01_R_DP")
		)
		(pad "2" smd circle
			(at 0.40005 0 270)
			(size 0 0)
			(layers "F.Cu" "F.Mask" "F.Paste")
			(net "CLK_100M_CPU1_CLK01_DP")
		)
	)
	(footprint ""
		(layer "F.Cu")
		(at 163.734496 -117.310662 180)
		(property "Reference" "R6142"
			(at 0 0 180)
			(layer "F.SilkS")
			(hide yes)
			(effects
				(font
					(size 1.27 1.27)
				)
			)
		)
		(property "Value" ""
			(at 0 0 180)
			(layer "F.Fab")
			(effects
				(font
					(size 1.27 1.27)
				)
			)
		)
		(duplicate_pad_numbers_are_jumpers no)
		(fp_line
			(start 0.7874 0.4064)
			(end -0.7874 0.4064)
			(stroke
				(width 0.1524)
				(type default)
			)
			(layer "F.SilkS")
		)
		(fp_line
			(start 0.7874 -0.4064)
			(end 0.7874 0.4064)
			(stroke
				(width 0.1524)
				(type default)
			)
			(layer "F.SilkS")
		)
		(fp_line
			(start -0.7874 0.4064)
			(end -0.7874 -0.4064)
			(stroke
				(width 0.1524)
				(type default)
			)
			(layer "F.SilkS")
		)
		(fp_line
			(start -0.7874 -0.4064)
			(end 0.7874 -0.4064)
			(stroke
				(width 0.1524)
				(type default)
			)
			(layer "F.SilkS")
		)
		(fp_line
			(start 0.67945 0.3048)
			(end 0.120396 0.3048)
			(stroke
				(width 0.1)
				(type default)
			)
			(layer "F.Fab")
		)
		(fp_line
			(start 0.67945 -0.3048)
			(end 0.67945 0.3048)
			(stroke
				(width 0.1)
				(type default)
			)
			(layer "F.Fab")
		)
		(fp_line
			(start 0.12065 -0.2794)
			(end 0.12065 -0.3048)
			(stroke
				(width 0.1)
				(type default)
			)
			(layer "F.Fab")
		)
		(fp_line
			(start 0.12065 -0.3048)
			(end 0.67945 -0.3048)
			(stroke
				(width 0.1)
				(type default)
			)
			(layer "F.Fab")
		)
		(fp_line
			(start 0.120396 0.3048)
			(end 0.120396 0.2794)
			(stroke
				(width 0.1)
				(type default)
			)
			(layer "F.Fab")
		)
		(fp_line
			(start 0.120396 0.2794)
			(end -0.12065 0.2794)
			(stroke
				(width 0.1)
				(type default)
			)
			(layer "F.Fab")
		)
		(fp_line
			(start -0.12065 0.3048)
			(end -0.67945 0.3048)
			(stroke
				(width 0.1)
				(type default)
			)
			(layer "F.Fab")
		)
		(fp_line
			(start -0.12065 0.2794)
			(end -0.12065 0.3048)
			(stroke
				(width 0.1)
				(type default)
			)
			(layer "F.Fab")
		)
		(fp_line
			(start -0.12065 -0.2794)
			(end 0.12065 -0.2794)
			(stroke
				(width 0.1)
				(type default)
			)
			(layer "F.Fab")
		)
		(fp_line
			(start -0.12065 -0.305054)
			(end -0.12065 -0.2794)
			(stroke
				(width 0.1)
				(type default)
			)
			(layer "F.Fab")
		)
		(fp_line
			(start -0.67945 0.3048)
			(end -0.67945 -0.305054)
			(stroke
				(width 0.1)
				(type default)
			)
			(layer "F.Fab")
		)
		(fp_line
			(start -0.67945 -0.305054)
			(end -0.12065 -0.305054)
			(stroke
				(width 0.1)
				(type default)
			)
			(layer "F.Fab")
		)
		(pad "1" smd circle
			(at -0.40005 0 180)
			(size 0 0)
			(layers "F.Cu" "F.Mask" "F.Paste")
			(net "FM_BOARD_BMC_SKU_ID3")
		)
		(pad "2" smd circle
			(at 0.40005 0 180)
			(size 0 0)
			(layers "F.Cu" "F.Mask" "F.Paste")
			(net "GND")
		)
	)
	(footprint ""
		(layer "F.Cu")
		(at 441.863226 -19.059906)
		(property "Reference" "R1324"
			(at 0.350774 2.703576 0)
			(unlocked yes)
			(layer "F.SilkS")
			(effects
				(font
					(size 0.7874 0.5842)
					(thickness 0.1524)
				)
				(justify left)
			)
		)
		(property "Value" ""
			(at 0 0 0)
			(layer "F.Fab")
			(effects
				(font
					(size 1.27 1.27)
				)
			)
		)
		(duplicate_pad_numbers_are_jumpers no)
		(fp_line
			(start -3.937508 -1.8796)
			(end -3.937508 1.8796)
			(stroke
				(width 0.1524)
				(type default)
			)
			(layer "F.SilkS")
		)
		(fp_line
			(start -3.937508 1.8796)
			(end 3.937508 1.8796)
			(stroke
				(width 0.1524)
				(type default)
			)
			(layer "F.SilkS")
		)
		(fp_line
			(start 3.937508 -1.8796)
			(end -3.937508 -1.8796)
			(stroke
				(width 0.1524)
				(type default)
			)
			(layer "F.SilkS")
		)
		(fp_line
			(start 3.937508 1.8796)
			(end 3.937508 -1.8796)
			(stroke
				(width 0.1524)
				(type default)
			)
			(layer "F.SilkS")
		)
		(fp_line
			(start -3.275076 -1.674876)
			(end -3.275076 1.674876)
			(stroke
				(width 0.1)
				(type default)
			)
			(layer "F.Fab")
		)
		(fp_line
			(start -3.275076 1.674876)
			(end 3.275076 1.674876)
			(stroke
				(width 0.1)
				(type default)
			)
			(layer "F.Fab")
		)
		(fp_line
			(start 3.275076 -1.674876)
			(end -3.275076 -1.674876)
			(stroke
				(width 0.1)
				(type default)
			)
			(layer "F.Fab")
		)
		(fp_line
			(start 3.275076 1.674876)
			(end 3.275076 -1.674876)
			(stroke
				(width 0.1)
				(type default)
			)
			(layer "F.Fab")
		)
		(pad "1" smd rect
			(at -2.350008 0)
			(size 2.921 3.5052)
			(layers "F.Cu" "F.Mask" "F.Paste")
			(net "P12V_OCP_SFF_R")
		)
		(pad "2" smd rect
			(at 2.350008 0)
			(size 2.921 3.5052)
			(layers "F.Cu" "F.Mask" "F.Paste")
			(net "P12V_OCP_SFF")
		)
	)
	(footprint ""
		(layer "F.Cu")
		(at 371.921278 -136.608058 180)
		(property "Reference" "C5017"
			(at 0 0 180)
			(layer "F.SilkS")
			(hide yes)
			(effects
				(font
					(size 1.27 1.27)
				)
			)
		)
		(property "Value" ""
			(at 0 0 180)
			(layer "F.Fab")
			(effects
				(font
					(size 1.27 1.27)
				)
			)
		)
		(duplicate_pad_numbers_are_jumpers no)
		(fp_line
			(start 0.7874 0.4064)
			(end -0.7874 0.4064)
			(stroke
				(width 0.1524)
				(type default)
			)
			(layer "F.SilkS")
		)
		(fp_line
			(start 0.7874 -0.4064)
			(end 0.7874 0.4064)
			(stroke
				(width 0.1524)
				(type default)
			)
			(layer "F.SilkS")
		)
		(fp_line
			(start -0.7874 0.4064)
			(end -0.7874 -0.4064)
			(stroke
				(width 0.1524)
				(type default)
			)
			(layer "F.SilkS")
		)
		(fp_line
			(start -0.7874 -0.4064)
			(end 0.7874 -0.4064)
			(stroke
				(width 0.1524)
				(type default)
			)
			(layer "F.SilkS")
		)
		(fp_line
			(start 0.67945 0.3048)
			(end 0.120396 0.3048)
			(stroke
				(width 0.1)
				(type default)
			)
			(layer "F.Fab")
		)
		(fp_line
			(start 0.67945 -0.3048)
			(end 0.67945 0.3048)
			(stroke
				(width 0.1)
				(type default)
			)
			(layer "F.Fab")
		)
		(fp_line
			(start 0.12065 -0.2794)
			(end 0.12065 -0.3048)
			(stroke
				(width 0.1)
				(type default)
			)
			(layer "F.Fab")
		)
		(fp_line
			(start 0.12065 -0.3048)
			(end 0.67945 -0.3048)
			(stroke
				(width 0.1)
				(type default)
			)
			(layer "F.Fab")
		)
		(fp_line
			(start 0.120396 0.3048)
			(end 0.120396 0.2794)
			(stroke
				(width 0.1)
				(type default)
			)
			(layer "F.Fab")
		)
		(fp_line
			(start 0.120396 0.2794)
			(end -0.12065 0.2794)
			(stroke
				(width 0.1)
				(type default)
			)
			(layer "F.Fab")
		)
		(fp_line
			(start -0.12065 0.3048)
			(end -0.67945 0.3048)
			(stroke
				(width 0.1)
				(type default)
			)
			(layer "F.Fab")
		)
		(fp_line
			(start -0.12065 0.2794)
			(end -0.12065 0.3048)
			(stroke
				(width 0.1)
				(type default)
			)
			(layer "F.Fab")
		)
		(fp_line
			(start -0.12065 -0.2794)
			(end 0.12065 -0.2794)
			(stroke
				(width 0.1)
				(type default)
			)
			(layer "F.Fab")
		)
		(fp_line
			(start -0.12065 -0.305054)
			(end -0.12065 -0.2794)
			(stroke
				(width 0.1)
				(type default)
			)
			(layer "F.Fab")
		)
		(fp_line
			(start -0.67945 0.3048)
			(end -0.67945 -0.305054)
			(stroke
				(width 0.1)
				(type default)
			)
			(layer "F.Fab")
		)
		(fp_line
			(start -0.67945 -0.305054)
			(end -0.12065 -0.305054)
			(stroke
				(width 0.1)
				(type default)
			)
			(layer "F.Fab")
		)
		(pad "1" smd circle
			(at -0.40005 0 180)
			(size 0 0)
			(layers "F.Cu" "F.Mask" "F.Paste")
			(net "GND")
		)
		(pad "2" smd circle
			(at 0.40005 0 180)
			(size 0 0)
			(layers "F.Cu" "F.Mask" "F.Paste")
			(net "PWRGD_PVDDCR_CPU0_P0")
		)
	)
	(footprint ""
		(layer "F.Cu")
		(at 70.21576 -344.814906)
		(property "Reference" "H13"
			(at -2.6416 -4.08813 0)
			(unlocked yes)
			(layer "F.SilkS")
			(effects
				(font
					(size 0.7874 0.5842)
					(thickness 0.1524)
				)
				(justify left)
			)
		)
		(property "Value" ""
			(at 0 0 0)
			(layer "F.Fab")
			(effects
				(font
					(size 1.27 1.27)
				)
			)
		)
		(duplicate_pad_numbers_are_jumpers no)
		(pad "1" thru_hole circle
			(at 0 0)
			(size 6.1976 6.1976)
			(drill 3.7338)
			(layers "*.Cu" "*.Mask")
			(remove_unused_layers no)
			(net "GND")
			(clearance -0.9779)
			(padstack
				(mode front_inner_back)
				(layer "Inner"
					(shape circle)
					(size 5.5372 5.5372)
					(clearance -0.6477)
				)
				(layer "B.Cu"
					(shape circle)
					(size 6.1976 6.1976)
					(clearance -0.9779)
				)
			)
		)
	)
	(footprint ""
		(layer "F.Cu")
		(at 66.952114 -163.71697)
		(property "Reference" "PR423"
			(at 0 0 0)
			(layer "F.SilkS")
			(hide yes)
			(effects
				(font
					(size 1.27 1.27)
				)
			)
		)
		(property "Value" ""
			(at 0 0 0)
			(layer "F.Fab")
			(effects
				(font
					(size 1.27 1.27)
				)
			)
		)
		(duplicate_pad_numbers_are_jumpers no)
		(fp_line
			(start -0.7874 -0.4064)
			(end 0.7874 -0.4064)
			(stroke
				(width 0.1524)
				(type default)
			)
			(layer "F.SilkS")
		)
		(fp_line
			(start -0.7874 0.4064)
			(end -0.7874 -0.4064)
			(stroke
				(width 0.1524)
				(type default)
			)
			(layer "F.SilkS")
		)
		(fp_line
			(start 0.7874 -0.4064)
			(end 0.7874 0.4064)
			(stroke
				(width 0.1524)
				(type default)
			)
			(layer "F.SilkS")
		)
		(fp_line
			(start 0.7874 0.4064)
			(end -0.7874 0.4064)
			(stroke
				(width 0.1524)
				(type default)
			)
			(layer "F.SilkS")
		)
		(fp_line
			(start -0.67945 -0.305054)
			(end -0.12065 -0.305054)
			(stroke
				(width 0.1)
				(type default)
			)
			(layer "F.Fab")
		)
		(fp_line
			(start -0.67945 0.3048)
			(end -0.67945 -0.305054)
			(stroke
				(width 0.1)
				(type default)
			)
			(layer "F.Fab")
		)
		(fp_line
			(start -0.12065 -0.305054)
			(end -0.12065 -0.2794)
			(stroke
				(width 0.1)
				(type default)
			)
			(layer "F.Fab")
		)
		(fp_line
			(start -0.12065 -0.2794)
			(end 0.12065 -0.2794)
			(stroke
				(width 0.1)
				(type default)
			)
			(layer "F.Fab")
		)
		(fp_line
			(start -0.12065 0.2794)
			(end -0.12065 0.3048)
			(stroke
				(width 0.1)
				(type default)
			)
			(layer "F.Fab")
		)
		(fp_line
			(start -0.12065 0.3048)
			(end -0.67945 0.3048)
			(stroke
				(width 0.1)
				(type default)
			)
			(layer "F.Fab")
		)
		(fp_line
			(start 0.120396 0.2794)
			(end -0.12065 0.2794)
			(stroke
				(width 0.1)
				(type default)
			)
			(layer "F.Fab")
		)
		(fp_line
			(start 0.120396 0.3048)
			(end 0.120396 0.2794)
			(stroke
				(width 0.1)
				(type default)
			)
			(layer "F.Fab")
		)
		(fp_line
			(start 0.12065 -0.3048)
			(end 0.67945 -0.3048)
			(stroke
				(width 0.1)
				(type default)
			)
			(layer "F.Fab")
		)
		(fp_line
			(start 0.12065 -0.2794)
			(end 0.12065 -0.3048)
			(stroke
				(width 0.1)
				(type default)
			)
			(layer "F.Fab")
		)
		(fp_line
			(start 0.67945 -0.3048)
			(end 0.67945 0.3048)
			(stroke
				(width 0.1)
				(type default)
			)
			(layer "F.Fab")
		)
		(fp_line
			(start 0.67945 0.3048)
			(end 0.120396 0.3048)
			(stroke
				(width 0.1)
				(type default)
			)
			(layer "F.Fab")
		)
		(pad "1" smd circle
			(at -0.40005 0)
			(size 0 0)
			(layers "F.Cu" "F.Mask" "F.Paste")
			(net "GND")
		)
		(pad "2" smd circle
			(at 0.40005 0)
			(size 0 0)
			(layers "F.Cu" "F.Mask" "F.Paste")
			(net "PVDDCR_CPU0_P1_LSET6")
		)
	)
	(footprint ""
		(layer "F.Cu")
		(at 309.455312 -351.368106 90)
		(property "Reference" "PR89"
			(at 0 0 90)
			(layer "F.SilkS")
			(hide yes)
			(effects
				(font
					(size 1.27 1.27)
				)
			)
		)
		(property "Value" ""
			(at 0 0 90)
			(layer "F.Fab")
			(effects
				(font
					(size 1.27 1.27)
				)
			)
		)
		(duplicate_pad_numbers_are_jumpers no)
		(fp_line
			(start 0.7874 -0.4064)
			(end 0.7874 0.4064)
			(stroke
				(width 0.1524)
				(type default)
			)
			(layer "F.SilkS")
		)
		(fp_line
			(start -0.7874 -0.4064)
			(end 0.7874 -0.4064)
			(stroke
				(width 0.1524)
				(type default)
			)
			(layer "F.SilkS")
		)
		(fp_line
			(start 0.7874 0.4064)
			(end -0.7874 0.4064)
			(stroke
				(width 0.1524)
				(type default)
			)
			(layer "F.SilkS")
		)
		(fp_line
			(start -0.7874 0.4064)
			(end -0.7874 -0.4064)
			(stroke
				(width 0.1524)
				(type default)
			)
			(layer "F.SilkS")
		)
		(fp_line
			(start -0.12065 -0.305054)
			(end -0.12065 -0.2794)
			(stroke
				(width 0.1)
				(type default)
			)
			(layer "F.Fab")
		)
		(fp_line
			(start -0.67945 -0.305054)
			(end -0.12065 -0.305054)
			(stroke
				(width 0.1)
				(type default)
			)
			(layer "F.Fab")
		)
		(fp_line
			(start 0.67945 -0.3048)
			(end 0.67945 0.3048)
			(stroke
				(width 0.1)
				(type default)
			)
			(layer "F.Fab")
		)
		(fp_line
			(start 0.12065 -0.3048)
			(end 0.67945 -0.3048)
			(stroke
				(width 0.1)
				(type default)
			)
			(layer "F.Fab")
		)
		(fp_line
			(start 0.12065 -0.2794)
			(end 0.12065 -0.3048)
			(stroke
				(width 0.1)
				(type default)
			)
			(layer "F.Fab")
		)
		(fp_line
			(start -0.12065 -0.2794)
			(end 0.12065 -0.2794)
			(stroke
				(width 0.1)
				(type default)
			)
			(layer "F.Fab")
		)
		(fp_line
			(start 0.120396 0.2794)
			(end -0.12065 0.2794)
			(stroke
				(width 0.1)
				(type default)
			)
			(layer "F.Fab")
		)
		(fp_line
			(start -0.12065 0.2794)
			(end -0.12065 0.3048)
			(stroke
				(width 0.1)
				(type default)
			)
			(layer "F.Fab")
		)
		(fp_line
			(start 0.67945 0.3048)
			(end 0.120396 0.3048)
			(stroke
				(width 0.1)
				(type default)
			)
			(layer "F.Fab")
		)
		(fp_line
			(start 0.120396 0.3048)
			(end 0.120396 0.2794)
			(stroke
				(width 0.1)
				(type default)
			)
			(layer "F.Fab")
		)
		(fp_line
			(start -0.12065 0.3048)
			(end -0.67945 0.3048)
			(stroke
				(width 0.1)
				(type default)
			)
			(layer "F.Fab")
		)
		(fp_line
			(start -0.67945 0.3048)
			(end -0.67945 -0.305054)
			(stroke
				(width 0.1)
				(type default)
			)
			(layer "F.Fab")
		)
		(pad "1" smd circle
			(at -0.40005 0 90)
			(size 0 0)
			(layers "F.Cu" "F.Mask" "F.Paste")
			(net "SW_PVDDCR_CPU1_P0_BOOT4")
		)
		(pad "2" smd circle
			(at 0.40005 0 90)
			(size 0 0)
			(layers "F.Cu" "F.Mask" "F.Paste")
			(net "SW_PVDDCR_CPU1_P0_BOOT4_R")
		)
	)
	(footprint ""
		(layer "F.Cu")
		(at 178.764946 -413.815022 -90)
		(property "Reference" "R2694"
			(at 0 0 270)
			(layer "F.SilkS")
			(hide yes)
			(effects
				(font
					(size 1.27 1.27)
				)
			)
		)
		(property "Value" ""
			(at 0 0 270)
			(layer "F.Fab")
			(effects
				(font
					(size 1.27 1.27)
				)
			)
		)
		(duplicate_pad_numbers_are_jumpers no)
		(fp_line
			(start -0.7874 0.4064)
			(end -0.7874 -0.4064)
			(stroke
				(width 0.1524)
				(type default)
			)
			(layer "F.SilkS")
		)
		(fp_line
			(start 0.7874 0.4064)
			(end -0.7874 0.4064)
			(stroke
				(width 0.1524)
				(type default)
			)
			(layer "F.SilkS")
		)
		(fp_line
			(start -0.7874 -0.4064)
			(end 0.7874 -0.4064)
			(stroke
				(width 0.1524)
				(type default)
			)
			(layer "F.SilkS")
		)
		(fp_line
			(start 0.7874 -0.4064)
			(end 0.7874 0.4064)
			(stroke
				(width 0.1524)
				(type default)
			)
			(layer "F.SilkS")
		)
		(fp_line
			(start -0.67945 0.3048)
			(end -0.67945 -0.305054)
			(stroke
				(width 0.1)
				(type default)
			)
			(layer "F.Fab")
		)
		(fp_line
			(start -0.12065 0.3048)
			(end -0.67945 0.3048)
			(stroke
				(width 0.1)
				(type default)
			)
			(layer "F.Fab")
		)
		(fp_line
			(start 0.120396 0.3048)
			(end 0.120396 0.2794)
			(stroke
				(width 0.1)
				(type default)
			)
			(layer "F.Fab")
		)
		(fp_line
			(start 0.67945 0.3048)
			(end 0.120396 0.3048)
			(stroke
				(width 0.1)
				(type default)
			)
			(layer "F.Fab")
		)
		(fp_line
			(start -0.12065 0.2794)
			(end -0.12065 0.3048)
			(stroke
				(width 0.1)
				(type default)
			)
			(layer "F.Fab")
		)
		(fp_line
			(start 0.120396 0.2794)
			(end -0.12065 0.2794)
			(stroke
				(width 0.1)
				(type default)
			)
			(layer "F.Fab")
		)
		(fp_line
			(start -0.12065 -0.2794)
			(end 0.12065 -0.2794)
			(stroke
				(width 0.1)
				(type default)
			)
			(layer "F.Fab")
		)
		(fp_line
			(start 0.12065 -0.2794)
			(end 0.12065 -0.3048)
			(stroke
				(width 0.1)
				(type default)
			)
			(layer "F.Fab")
		)
		(fp_line
			(start 0.12065 -0.3048)
			(end 0.67945 -0.3048)
			(stroke
				(width 0.1)
				(type default)
			)
			(layer "F.Fab")
		)
		(fp_line
			(start 0.67945 -0.3048)
			(end 0.67945 0.3048)
			(stroke
				(width 0.1)
				(type default)
			)
			(layer "F.Fab")
		)
		(fp_line
			(start -0.67945 -0.305054)
			(end -0.12065 -0.305054)
			(stroke
				(width 0.1)
				(type default)
			)
			(layer "F.Fab")
		)
		(fp_line
			(start -0.12065 -0.305054)
			(end -0.12065 -0.2794)
			(stroke
				(width 0.1)
				(type default)
			)
			(layer "F.Fab")
		)
		(pad "1" smd circle
			(at -0.40005 0 270)
			(size 0 0)
			(layers "F.Cu" "F.Mask" "F.Paste")
			(net "TCA9539_0_ADD1")
		)
		(pad "2" smd circle
			(at 0.40005 0 270)
			(size 0 0)
			(layers "F.Cu" "F.Mask" "F.Paste")
			(net "GND")
		)
	)
	(footprint ""
		(layer "F.Cu")
		(at 180.074062 -32.935672 -90)
		(property "Reference" "R3998"
			(at 0 0 270)
			(layer "F.SilkS")
			(hide yes)
			(effects
				(font
					(size 1.27 1.27)
				)
			)
		)
		(property "Value" ""
			(at 0 0 270)
			(layer "F.Fab")
			(effects
				(font
					(size 1.27 1.27)
				)
			)
		)
		(duplicate_pad_numbers_are_jumpers no)
		(fp_line
			(start -0.7874 0.4064)
			(end -0.7874 -0.4064)
			(stroke
				(width 0.1524)
				(type default)
			)
			(layer "F.SilkS")
		)
		(fp_line
			(start 0.7874 0.4064)
			(end -0.7874 0.4064)
			(stroke
				(width 0.1524)
				(type default)
			)
			(layer "F.SilkS")
		)
		(fp_line
			(start -0.7874 -0.4064)
			(end 0.7874 -0.4064)
			(stroke
				(width 0.1524)
				(type default)
			)
			(layer "F.SilkS")
		)
		(fp_line
			(start 0.7874 -0.4064)
			(end 0.7874 0.4064)
			(stroke
				(width 0.1524)
				(type default)
			)
			(layer "F.SilkS")
		)
		(fp_line
			(start -0.67945 0.3048)
			(end -0.67945 -0.305054)
			(stroke
				(width 0.1)
				(type default)
			)
			(layer "F.Fab")
		)
		(fp_line
			(start -0.12065 0.3048)
			(end -0.67945 0.3048)
			(stroke
				(width 0.1)
				(type default)
			)
			(layer "F.Fab")
		)
		(fp_line
			(start 0.120396 0.3048)
			(end 0.120396 0.2794)
			(stroke
				(width 0.1)
				(type default)
			)
			(layer "F.Fab")
		)
		(fp_line
			(start 0.67945 0.3048)
			(end 0.120396 0.3048)
			(stroke
				(width 0.1)
				(type default)
			)
			(layer "F.Fab")
		)
		(fp_line
			(start -0.12065 0.2794)
			(end -0.12065 0.3048)
			(stroke
				(width 0.1)
				(type default)
			)
			(layer "F.Fab")
		)
		(fp_line
			(start 0.120396 0.2794)
			(end -0.12065 0.2794)
			(stroke
				(width 0.1)
				(type default)
			)
			(layer "F.Fab")
		)
		(fp_line
			(start -0.12065 -0.2794)
			(end 0.12065 -0.2794)
			(stroke
				(width 0.1)
				(type default)
			)
			(layer "F.Fab")
		)
		(fp_line
			(start 0.12065 -0.2794)
			(end 0.12065 -0.3048)
			(stroke
				(width 0.1)
				(type default)
			)
			(layer "F.Fab")
		)
		(fp_line
			(start 0.12065 -0.3048)
			(end 0.67945 -0.3048)
			(stroke
				(width 0.1)
				(type default)
			)
			(layer "F.Fab")
		)
		(fp_line
			(start 0.67945 -0.3048)
			(end 0.67945 0.3048)
			(stroke
				(width 0.1)
				(type default)
			)
			(layer "F.Fab")
		)
		(fp_line
			(start -0.67945 -0.305054)
			(end -0.12065 -0.305054)
			(stroke
				(width 0.1)
				(type default)
			)
			(layer "F.Fab")
		)
		(fp_line
			(start -0.12065 -0.305054)
			(end -0.12065 -0.2794)
			(stroke
				(width 0.1)
				(type default)
			)
			(layer "F.Fab")
		)
		(pad "1" smd circle
			(at -0.40005 0 270)
			(size 0 0)
			(layers "F.Cu" "F.Mask" "F.Paste")
			(net "P12V_SCM_EN")
		)
		(pad "2" smd circle
			(at 0.40005 0 270)
			(size 0 0)
			(layers "F.Cu" "F.Mask" "F.Paste")
			(net "P12V_SCM_EN_R2")
		)
	)
	(footprint ""
		(layer "F.Cu")
		(at 96.0628 -417.2204 180)
		(property "Reference" "R1454"
			(at 0 0 180)
			(layer "F.SilkS")
			(hide yes)
			(effects
				(font
					(size 1.27 1.27)
				)
			)
		)
		(property "Value" ""
			(at 0 0 180)
			(layer "F.Fab")
			(effects
				(font
					(size 1.27 1.27)
				)
			)
		)
		(duplicate_pad_numbers_are_jumpers no)
		(fp_line
			(start 0.32512 0.175006)
			(end -0.32512 0.175006)
			(stroke
				(width 0.1)
				(type default)
			)
			(layer "F.Fab")
		)
		(fp_line
			(start 0.32512 -0.175006)
			(end 0.32512 0.175006)
			(stroke
				(width 0.1)
				(type default)
			)
			(layer "F.Fab")
		)
		(fp_line
			(start -0.32512 0.175006)
			(end -0.32512 -0.175006)
			(stroke
				(width 0.1)
				(type default)
			)
			(layer "F.Fab")
		)
		(fp_line
			(start -0.32512 -0.175006)
			(end 0.32512 -0.175006)
			(stroke
				(width 0.1)
				(type default)
			)
			(layer "F.Fab")
		)
		(pad "1" smd rect
			(at -0.2667 0 180)
			(size 0.3048 0.381)
			(layers "F.Cu" "F.Mask" "F.Paste")
			(net "P1V8_CPU1_RT_1D")
		)
		(pad "2" smd rect
			(at 0.2667 0)
			(size 0.3048 0.381)
			(layers "F.Cu" "F.Mask" "F.Paste")
			(net "JTAG_TDI_RT_CPU1_P1")
		)
	)
	(footprint ""
		(layer "F.Cu")
		(at 194.31 -137.632948 90)
		(property "Reference" "R252"
			(at 0 0 90)
			(layer "F.SilkS")
			(hide yes)
			(effects
				(font
					(size 1.27 1.27)
				)
			)
		)
		(property "Value" ""
			(at 0 0 90)
			(layer "F.Fab")
			(effects
				(font
					(size 1.27 1.27)
				)
			)
		)
		(duplicate_pad_numbers_are_jumpers no)
		(fp_line
			(start 0.7874 -0.4064)
			(end 0.7874 0.4064)
			(stroke
				(width 0.1524)
				(type default)
			)
			(layer "F.SilkS")
		)
		(fp_line
			(start -0.7874 -0.4064)
			(end 0.7874 -0.4064)
			(stroke
				(width 0.1524)
				(type default)
			)
			(layer "F.SilkS")
		)
		(fp_line
			(start 0.7874 0.4064)
			(end -0.7874 0.4064)
			(stroke
				(width 0.1524)
				(type default)
			)
			(layer "F.SilkS")
		)
		(fp_line
			(start -0.7874 0.4064)
			(end -0.7874 -0.4064)
			(stroke
				(width 0.1524)
				(type default)
			)
			(layer "F.SilkS")
		)
		(fp_line
			(start -0.12065 -0.305054)
			(end -0.12065 -0.2794)
			(stroke
				(width 0.1)
				(type default)
			)
			(layer "F.Fab")
		)
		(fp_line
			(start -0.67945 -0.305054)
			(end -0.12065 -0.305054)
			(stroke
				(width 0.1)
				(type default)
			)
			(layer "F.Fab")
		)
		(fp_line
			(start 0.67945 -0.3048)
			(end 0.67945 0.3048)
			(stroke
				(width 0.1)
				(type default)
			)
			(layer "F.Fab")
		)
		(fp_line
			(start 0.12065 -0.3048)
			(end 0.67945 -0.3048)
			(stroke
				(width 0.1)
				(type default)
			)
			(layer "F.Fab")
		)
		(fp_line
			(start 0.12065 -0.2794)
			(end 0.12065 -0.3048)
			(stroke
				(width 0.1)
				(type default)
			)
			(layer "F.Fab")
		)
		(fp_line
			(start -0.12065 -0.2794)
			(end 0.12065 -0.2794)
			(stroke
				(width 0.1)
				(type default)
			)
			(layer "F.Fab")
		)
		(fp_line
			(start 0.120396 0.2794)
			(end -0.12065 0.2794)
			(stroke
				(width 0.1)
				(type default)
			)
			(layer "F.Fab")
		)
		(fp_line
			(start -0.12065 0.2794)
			(end -0.12065 0.3048)
			(stroke
				(width 0.1)
				(type default)
			)
			(layer "F.Fab")
		)
		(fp_line
			(start 0.67945 0.3048)
			(end 0.120396 0.3048)
			(stroke
				(width 0.1)
				(type default)
			)
			(layer "F.Fab")
		)
		(fp_line
			(start 0.120396 0.3048)
			(end 0.120396 0.2794)
			(stroke
				(width 0.1)
				(type default)
			)
			(layer "F.Fab")
		)
		(fp_line
			(start -0.12065 0.3048)
			(end -0.67945 0.3048)
			(stroke
				(width 0.1)
				(type default)
			)
			(layer "F.Fab")
		)
		(fp_line
			(start -0.67945 0.3048)
			(end -0.67945 -0.305054)
			(stroke
				(width 0.1)
				(type default)
			)
			(layer "F.Fab")
		)
		(pad "1" smd circle
			(at -0.40005 0 90)
			(size 0 0)
			(layers "F.Cu" "F.Mask" "F.Paste")
			(net "FM_CPU1_PWR_GD_IN")
		)
		(pad "2" smd circle
			(at 0.40005 0 90)
			(size 0 0)
			(layers "F.Cu" "F.Mask" "F.Paste")
			(net "CPU1_PWR_GD_IN")
		)
	)
	(footprint ""
		(layer "F.Cu")
		(at 398.595088 -384.32486 180)
		(property "Reference" "C867"
			(at 0 0 180)
			(layer "F.SilkS")
			(hide yes)
			(effects
				(font
					(size 1.27 1.27)
				)
			)
		)
		(property "Value" ""
			(at 0 0 180)
			(layer "F.Fab")
			(effects
				(font
					(size 1.27 1.27)
				)
			)
		)
		(duplicate_pad_numbers_are_jumpers no)
		(fp_line
			(start 0.299974 0.150114)
			(end -0.299974 0.150114)
			(stroke
				(width 0.1)
				(type default)
			)
			(layer "F.Fab")
		)
		(fp_line
			(start 0.299974 -0.150114)
			(end 0.299974 0.150114)
			(stroke
				(width 0.1)
				(type default)
			)
			(layer "F.Fab")
		)
		(fp_line
			(start -0.299974 0.150114)
			(end -0.299974 -0.150114)
			(stroke
				(width 0.1)
				(type default)
			)
			(layer "F.Fab")
		)
		(fp_line
			(start -0.299974 -0.150114)
			(end 0.299974 -0.150114)
			(stroke
				(width 0.1)
				(type default)
			)
			(layer "F.Fab")
		)
		(pad "1" smd rect
			(at -0.2667 0 180)
			(size 0.3048 0.381)
			(layers "F.Cu" "F.Mask" "F.Paste")
			(net "P5E_CPU0_P2_TX_C_DP<1>")
		)
		(pad "2" smd rect
			(at 0.2667 0 180)
			(size 0.3048 0.381)
			(layers "F.Cu" "F.Mask" "F.Paste")
			(net "P5E_CPU0_P2_TX_DP<1>")
		)
	)
	(footprint ""
		(layer "F.Cu")
		(at 236.650022 -352.49993)
		(property "Reference" "H105"
			(at -5.01269 -6.23189 0)
			(unlocked yes)
			(layer "F.SilkS")
			(effects
				(font
					(size 0.7874 0.5842)
					(thickness 0.1524)
				)
				(justify left)
			)
		)
		(property "Value" ""
			(at 0 0 0)
			(layer "F.Fab")
			(effects
				(font
					(size 1.27 1.27)
				)
			)
		)
		(duplicate_pad_numbers_are_jumpers no)
		(pad "1" thru_hole circle
			(at 0 0)
			(size 10.0076 10.0076)
			(drill 5.6134)
			(layers "*.Cu" "*.Mask")
			(remove_unused_layers no)
			(net "GND")
			(clearance -1.9431)
		)
	)
	(footprint ""
		(layer "F.Cu")
		(at 237.720378 -315.95568 90)
		(property "Reference" "PC6514"
			(at 0 0 90)
			(layer "F.SilkS")
			(hide yes)
			(effects
				(font
					(size 1.27 1.27)
				)
			)
		)
		(property "Value" ""
			(at 0 0 90)
			(layer "F.Fab")
			(effects
				(font
					(size 1.27 1.27)
				)
			)
		)
		(duplicate_pad_numbers_are_jumpers no)
		(fp_line
			(start 0.7874 -0.4064)
			(end 0.7874 0.4064)
			(stroke
				(width 0.1524)
				(type default)
			)
			(layer "F.SilkS")
		)
		(fp_line
			(start -0.7874 -0.4064)
			(end 0.7874 -0.4064)
			(stroke
				(width 0.1524)
				(type default)
			)
			(layer "F.SilkS")
		)
		(fp_line
			(start 0.7874 0.4064)
			(end -0.7874 0.4064)
			(stroke
				(width 0.1524)
				(type default)
			)
			(layer "F.SilkS")
		)
		(fp_line
			(start -0.7874 0.4064)
			(end -0.7874 -0.4064)
			(stroke
				(width 0.1524)
				(type default)
			)
			(layer "F.SilkS")
		)
		(fp_line
			(start -0.12065 -0.305054)
			(end -0.12065 -0.2794)
			(stroke
				(width 0.1)
				(type default)
			)
			(layer "F.Fab")
		)
		(fp_line
			(start -0.67945 -0.305054)
			(end -0.12065 -0.305054)
			(stroke
				(width 0.1)
				(type default)
			)
			(layer "F.Fab")
		)
		(fp_line
			(start 0.67945 -0.3048)
			(end 0.67945 0.3048)
			(stroke
				(width 0.1)
				(type default)
			)
			(layer "F.Fab")
		)
		(fp_line
			(start 0.12065 -0.3048)
			(end 0.67945 -0.3048)
			(stroke
				(width 0.1)
				(type default)
			)
			(layer "F.Fab")
		)
		(fp_line
			(start 0.12065 -0.2794)
			(end 0.12065 -0.3048)
			(stroke
				(width 0.1)
				(type default)
			)
			(layer "F.Fab")
		)
		(fp_line
			(start -0.12065 -0.2794)
			(end 0.12065 -0.2794)
			(stroke
				(width 0.1)
				(type default)
			)
			(layer "F.Fab")
		)
		(fp_line
			(start 0.120396 0.2794)
			(end -0.12065 0.2794)
			(stroke
				(width 0.1)
				(type default)
			)
			(layer "F.Fab")
		)
		(fp_line
			(start -0.12065 0.2794)
			(end -0.12065 0.3048)
			(stroke
				(width 0.1)
				(type default)
			)
			(layer "F.Fab")
		)
		(fp_line
			(start 0.67945 0.3048)
			(end 0.120396 0.3048)
			(stroke
				(width 0.1)
				(type default)
			)
			(layer "F.Fab")
		)
		(fp_line
			(start 0.120396 0.3048)
			(end 0.120396 0.2794)
			(stroke
				(width 0.1)
				(type default)
			)
			(layer "F.Fab")
		)
		(fp_line
			(start -0.12065 0.3048)
			(end -0.67945 0.3048)
			(stroke
				(width 0.1)
				(type default)
			)
			(layer "F.Fab")
		)
		(fp_line
			(start -0.67945 0.3048)
			(end -0.67945 -0.305054)
			(stroke
				(width 0.1)
				(type default)
			)
			(layer "F.Fab")
		)
		(pad "1" smd circle
			(at -0.40005 0 90)
			(size 0 0)
			(layers "F.Cu" "F.Mask" "F.Paste")
			(net "P1V8_CPU0_RT_1D")
		)
		(pad "2" smd circle
			(at 0.40005 0 90)
			(size 0 0)
			(layers "F.Cu" "F.Mask" "F.Paste")
			(net "GND")
		)
	)
	(footprint ""
		(layer "F.Cu")
		(at 363.215936 -256.012188 90)
		(property "Reference" "C2161"
			(at 0 0 90)
			(layer "F.SilkS")
			(hide yes)
			(effects
				(font
					(size 1.27 1.27)
				)
			)
		)
		(property "Value" ""
			(at 0 0 90)
			(layer "F.Fab")
			(effects
				(font
					(size 1.27 1.27)
				)
			)
		)
		(duplicate_pad_numbers_are_jumpers no)
		(fp_line
			(start 0.7874 -0.4064)
			(end 0.7874 0.4064)
			(stroke
				(width 0.1524)
				(type default)
			)
			(layer "F.SilkS")
		)
		(fp_line
			(start -0.7874 -0.4064)
			(end 0.7874 -0.4064)
			(stroke
				(width 0.1524)
				(type default)
			)
			(layer "F.SilkS")
		)
		(fp_line
			(start 0.7874 0.4064)
			(end -0.7874 0.4064)
			(stroke
				(width 0.1524)
				(type default)
			)
			(layer "F.SilkS")
		)
		(fp_line
			(start -0.7874 0.4064)
			(end -0.7874 -0.4064)
			(stroke
				(width 0.1524)
				(type default)
			)
			(layer "F.SilkS")
		)
		(fp_line
			(start -0.12065 -0.305054)
			(end -0.12065 -0.2794)
			(stroke
				(width 0.1)
				(type default)
			)
			(layer "F.Fab")
		)
		(fp_line
			(start -0.67945 -0.305054)
			(end -0.12065 -0.305054)
			(stroke
				(width 0.1)
				(type default)
			)
			(layer "F.Fab")
		)
		(fp_line
			(start 0.67945 -0.3048)
			(end 0.67945 0.3048)
			(stroke
				(width 0.1)
				(type default)
			)
			(layer "F.Fab")
		)
		(fp_line
			(start 0.12065 -0.3048)
			(end 0.67945 -0.3048)
			(stroke
				(width 0.1)
				(type default)
			)
			(layer "F.Fab")
		)
		(fp_line
			(start 0.12065 -0.2794)
			(end 0.12065 -0.3048)
			(stroke
				(width 0.1)
				(type default)
			)
			(layer "F.Fab")
		)
		(fp_line
			(start -0.12065 -0.2794)
			(end 0.12065 -0.2794)
			(stroke
				(width 0.1)
				(type default)
			)
			(layer "F.Fab")
		)
		(fp_line
			(start 0.120396 0.2794)
			(end -0.12065 0.2794)
			(stroke
				(width 0.1)
				(type default)
			)
			(layer "F.Fab")
		)
		(fp_line
			(start -0.12065 0.2794)
			(end -0.12065 0.3048)
			(stroke
				(width 0.1)
				(type default)
			)
			(layer "F.Fab")
		)
		(fp_line
			(start 0.67945 0.3048)
			(end 0.120396 0.3048)
			(stroke
				(width 0.1)
				(type default)
			)
			(layer "F.Fab")
		)
		(fp_line
			(start 0.120396 0.3048)
			(end 0.120396 0.2794)
			(stroke
				(width 0.1)
				(type default)
			)
			(layer "F.Fab")
		)
		(fp_line
			(start -0.12065 0.3048)
			(end -0.67945 0.3048)
			(stroke
				(width 0.1)
				(type default)
			)
			(layer "F.Fab")
		)
		(fp_line
			(start -0.67945 0.3048)
			(end -0.67945 -0.305054)
			(stroke
				(width 0.1)
				(type default)
			)
			(layer "F.Fab")
		)
		(pad "1" smd circle
			(at -0.40005 0 90)
			(size 0 0)
			(layers "F.Cu" "F.Mask" "F.Paste")
			(net "PVDDCR_SOC_P0")
		)
		(pad "2" smd circle
			(at 0.40005 0 90)
			(size 0 0)
			(layers "F.Cu" "F.Mask" "F.Paste")
			(net "GND")
		)
	)
	(footprint ""
		(layer "F.Cu")
		(at 135.616696 -370.57203 -90)
		(property "Reference" "C53"
			(at 0 0 270)
			(layer "F.SilkS")
			(hide yes)
			(effects
				(font
					(size 1.27 1.27)
				)
			)
		)
		(property "Value" ""
			(at 0 0 270)
			(layer "F.Fab")
			(effects
				(font
					(size 1.27 1.27)
				)
			)
		)
		(duplicate_pad_numbers_are_jumpers no)
		(fp_line
			(start -0.299974 0.150114)
			(end -0.299974 -0.150114)
			(stroke
				(width 0.1)
				(type default)
			)
			(layer "F.Fab")
		)
		(fp_line
			(start 0.299974 0.150114)
			(end -0.299974 0.150114)
			(stroke
				(width 0.1)
				(type default)
			)
			(layer "F.Fab")
		)
		(fp_line
			(start -0.299974 -0.150114)
			(end 0.299974 -0.150114)
			(stroke
				(width 0.1)
				(type default)
			)
			(layer "F.Fab")
		)
		(fp_line
			(start 0.299974 -0.150114)
			(end 0.299974 0.150114)
			(stroke
				(width 0.1)
				(type default)
			)
			(layer "F.Fab")
		)
		(pad "1" smd rect
			(at -0.2667 0 270)
			(size 0.3048 0.381)
			(layers "F.Cu" "F.Mask" "F.Paste")
			(net "P5E_CPU1_P3_TX_C_DP<13>")
		)
		(pad "2" smd rect
			(at 0.2667 0 270)
			(size 0.3048 0.381)
			(layers "F.Cu" "F.Mask" "F.Paste")
			(net "P5E_CPU1_P3_TX_DP<13>")
		)
	)
	(footprint ""
		(layer "F.Cu")
		(at 190.4238 -42.554398)
		(property "Reference" "R4071"
			(at 0 0 0)
			(layer "F.SilkS")
			(hide yes)
			(effects
				(font
					(size 1.27 1.27)
				)
			)
		)
		(property "Value" ""
			(at 0 0 0)
			(layer "F.Fab")
			(effects
				(font
					(size 1.27 1.27)
				)
			)
		)
		(duplicate_pad_numbers_are_jumpers no)
		(fp_line
			(start -0.7874 -0.4064)
			(end 0.7874 -0.4064)
			(stroke
				(width 0.1524)
				(type default)
			)
			(layer "F.SilkS")
		)
		(fp_line
			(start -0.7874 0.4064)
			(end -0.7874 -0.4064)
			(stroke
				(width 0.1524)
				(type default)
			)
			(layer "F.SilkS")
		)
		(fp_line
			(start 0.7874 -0.4064)
			(end 0.7874 0.4064)
			(stroke
				(width 0.1524)
				(type default)
			)
			(layer "F.SilkS")
		)
		(fp_line
			(start 0.7874 0.4064)
			(end -0.7874 0.4064)
			(stroke
				(width 0.1524)
				(type default)
			)
			(layer "F.SilkS")
		)
		(fp_line
			(start -0.67945 -0.305054)
			(end -0.12065 -0.305054)
			(stroke
				(width 0.1)
				(type default)
			)
			(layer "F.Fab")
		)
		(fp_line
			(start -0.67945 0.3048)
			(end -0.67945 -0.305054)
			(stroke
				(width 0.1)
				(type default)
			)
			(layer "F.Fab")
		)
		(fp_line
			(start -0.12065 -0.305054)
			(end -0.12065 -0.2794)
			(stroke
				(width 0.1)
				(type default)
			)
			(layer "F.Fab")
		)
		(fp_line
			(start -0.12065 -0.2794)
			(end 0.12065 -0.2794)
			(stroke
				(width 0.1)
				(type default)
			)
			(layer "F.Fab")
		)
		(fp_line
			(start -0.12065 0.2794)
			(end -0.12065 0.3048)
			(stroke
				(width 0.1)
				(type default)
			)
			(layer "F.Fab")
		)
		(fp_line
			(start -0.12065 0.3048)
			(end -0.67945 0.3048)
			(stroke
				(width 0.1)
				(type default)
			)
			(layer "F.Fab")
		)
		(fp_line
			(start 0.120396 0.2794)
			(end -0.12065 0.2794)
			(stroke
				(width 0.1)
				(type default)
			)
			(layer "F.Fab")
		)
		(fp_line
			(start 0.120396 0.3048)
			(end 0.120396 0.2794)
			(stroke
				(width 0.1)
				(type default)
			)
			(layer "F.Fab")
		)
		(fp_line
			(start 0.12065 -0.3048)
			(end 0.67945 -0.3048)
			(stroke
				(width 0.1)
				(type default)
			)
			(layer "F.Fab")
		)
		(fp_line
			(start 0.12065 -0.2794)
			(end 0.12065 -0.3048)
			(stroke
				(width 0.1)
				(type default)
			)
			(layer "F.Fab")
		)
		(fp_line
			(start 0.67945 -0.3048)
			(end 0.67945 0.3048)
			(stroke
				(width 0.1)
				(type default)
			)
			(layer "F.Fab")
		)
		(fp_line
			(start 0.67945 0.3048)
			(end 0.120396 0.3048)
			(stroke
				(width 0.1)
				(type default)
			)
			(layer "F.Fab")
		)
		(pad "1" smd circle
			(at -0.40005 0)
			(size 0 0)
			(layers "F.Cu" "F.Mask" "F.Paste")
			(net "P12V_AUX")
		)
		(pad "2" smd circle
			(at 0.40005 0)
			(size 0 0)
			(layers "F.Cu" "F.Mask" "F.Paste")
			(net "P12V_SCM_EN_G")
		)
	)
	(footprint ""
		(layer "F.Cu")
		(at 319.940178 -41.668954)
		(property "Reference" "C2047"
			(at 0 0 0)
			(layer "F.SilkS")
			(hide yes)
			(effects
				(font
					(size 1.27 1.27)
				)
			)
		)
		(property "Value" ""
			(at 0 0 0)
			(layer "F.Fab")
			(effects
				(font
					(size 1.27 1.27)
				)
			)
		)
		(duplicate_pad_numbers_are_jumpers no)
		(fp_line
			(start -0.7874 -0.4064)
			(end 0.7874 -0.4064)
			(stroke
				(width 0.1524)
				(type default)
			)
			(layer "F.SilkS")
		)
		(fp_line
			(start -0.7874 0.4064)
			(end -0.7874 -0.4064)
			(stroke
				(width 0.1524)
				(type default)
			)
			(layer "F.SilkS")
		)
		(fp_line
			(start 0.7874 -0.4064)
			(end 0.7874 0.4064)
			(stroke
				(width 0.1524)
				(type default)
			)
			(layer "F.SilkS")
		)
		(fp_line
			(start 0.7874 0.4064)
			(end -0.7874 0.4064)
			(stroke
				(width 0.1524)
				(type default)
			)
			(layer "F.SilkS")
		)
		(fp_line
			(start -0.67945 -0.305054)
			(end -0.12065 -0.305054)
			(stroke
				(width 0.1)
				(type default)
			)
			(layer "F.Fab")
		)
		(fp_line
			(start -0.67945 0.3048)
			(end -0.67945 -0.305054)
			(stroke
				(width 0.1)
				(type default)
			)
			(layer "F.Fab")
		)
		(fp_line
			(start -0.12065 -0.305054)
			(end -0.12065 -0.2794)
			(stroke
				(width 0.1)
				(type default)
			)
			(layer "F.Fab")
		)
		(fp_line
			(start -0.12065 -0.2794)
			(end 0.12065 -0.2794)
			(stroke
				(width 0.1)
				(type default)
			)
			(layer "F.Fab")
		)
		(fp_line
			(start -0.12065 0.2794)
			(end -0.12065 0.3048)
			(stroke
				(width 0.1)
				(type default)
			)
			(layer "F.Fab")
		)
		(fp_line
			(start -0.12065 0.3048)
			(end -0.67945 0.3048)
			(stroke
				(width 0.1)
				(type default)
			)
			(layer "F.Fab")
		)
		(fp_line
			(start 0.120396 0.2794)
			(end -0.12065 0.2794)
			(stroke
				(width 0.1)
				(type default)
			)
			(layer "F.Fab")
		)
		(fp_line
			(start 0.120396 0.3048)
			(end 0.120396 0.2794)
			(stroke
				(width 0.1)
				(type default)
			)
			(layer "F.Fab")
		)
		(fp_line
			(start 0.12065 -0.3048)
			(end 0.67945 -0.3048)
			(stroke
				(width 0.1)
				(type default)
			)
			(layer "F.Fab")
		)
		(fp_line
			(start 0.12065 -0.2794)
			(end 0.12065 -0.3048)
			(stroke
				(width 0.1)
				(type default)
			)
			(layer "F.Fab")
		)
		(fp_line
			(start 0.67945 -0.3048)
			(end 0.67945 0.3048)
			(stroke
				(width 0.1)
				(type default)
			)
			(layer "F.Fab")
		)
		(fp_line
			(start 0.67945 0.3048)
			(end 0.120396 0.3048)
			(stroke
				(width 0.1)
				(type default)
			)
			(layer "F.Fab")
		)
		(pad "1" smd circle
			(at -0.40005 0)
			(size 0 0)
			(layers "F.Cu" "F.Mask" "F.Paste")
			(net "P3V3_AUX_ADC_TIC")
		)
		(pad "2" smd circle
			(at 0.40005 0)
			(size 0 0)
			(layers "F.Cu" "F.Mask" "F.Paste")
			(net "GND")
		)
	)
	(footprint ""
		(layer "F.Cu")
		(at 320.153538 -116.632228 180)
		(property "Reference" "R26"
			(at 0 0 180)
			(layer "F.SilkS")
			(hide yes)
			(effects
				(font
					(size 1.27 1.27)
				)
			)
		)
		(property "Value" ""
			(at 0 0 180)
			(layer "F.Fab")
			(effects
				(font
					(size 1.27 1.27)
				)
			)
		)
		(duplicate_pad_numbers_are_jumpers no)
		(fp_line
			(start 0.7874 0.4064)
			(end -0.7874 0.4064)
			(stroke
				(width 0.1524)
				(type default)
			)
			(layer "F.SilkS")
		)
		(fp_line
			(start 0.7874 -0.4064)
			(end 0.7874 0.4064)
			(stroke
				(width 0.1524)
				(type default)
			)
			(layer "F.SilkS")
		)
		(fp_line
			(start -0.7874 0.4064)
			(end -0.7874 -0.4064)
			(stroke
				(width 0.1524)
				(type default)
			)
			(layer "F.SilkS")
		)
		(fp_line
			(start -0.7874 -0.4064)
			(end 0.7874 -0.4064)
			(stroke
				(width 0.1524)
				(type default)
			)
			(layer "F.SilkS")
		)
		(fp_line
			(start 0.67945 0.3048)
			(end 0.120396 0.3048)
			(stroke
				(width 0.1)
				(type default)
			)
			(layer "F.Fab")
		)
		(fp_line
			(start 0.67945 -0.3048)
			(end 0.67945 0.3048)
			(stroke
				(width 0.1)
				(type default)
			)
			(layer "F.Fab")
		)
		(fp_line
			(start 0.12065 -0.2794)
			(end 0.12065 -0.3048)
			(stroke
				(width 0.1)
				(type default)
			)
			(layer "F.Fab")
		)
		(fp_line
			(start 0.12065 -0.3048)
			(end 0.67945 -0.3048)
			(stroke
				(width 0.1)
				(type default)
			)
			(layer "F.Fab")
		)
		(fp_line
			(start 0.120396 0.3048)
			(end 0.120396 0.2794)
			(stroke
				(width 0.1)
				(type default)
			)
			(layer "F.Fab")
		)
		(fp_line
			(start 0.120396 0.2794)
			(end -0.12065 0.2794)
			(stroke
				(width 0.1)
				(type default)
			)
			(layer "F.Fab")
		)
		(fp_line
			(start -0.12065 0.3048)
			(end -0.67945 0.3048)
			(stroke
				(width 0.1)
				(type default)
			)
			(layer "F.Fab")
		)
		(fp_line
			(start -0.12065 0.2794)
			(end -0.12065 0.3048)
			(stroke
				(width 0.1)
				(type default)
			)
			(layer "F.Fab")
		)
		(fp_line
			(start -0.12065 -0.2794)
			(end 0.12065 -0.2794)
			(stroke
				(width 0.1)
				(type default)
			)
			(layer "F.Fab")
		)
		(fp_line
			(start -0.12065 -0.305054)
			(end -0.12065 -0.2794)
			(stroke
				(width 0.1)
				(type default)
			)
			(layer "F.Fab")
		)
		(fp_line
			(start -0.67945 0.3048)
			(end -0.67945 -0.305054)
			(stroke
				(width 0.1)
				(type default)
			)
			(layer "F.Fab")
		)
		(fp_line
			(start -0.67945 -0.305054)
			(end -0.12065 -0.305054)
			(stroke
				(width 0.1)
				(type default)
			)
			(layer "F.Fab")
		)
		(pad "1" smd circle
			(at -0.40005 0 180)
			(size 0 0)
			(layers "F.Cu" "F.Mask" "F.Paste")
			(net "P3V3_AUX")
		)
		(pad "2" smd circle
			(at 0.40005 0 180)
			(size 0 0)
			(layers "F.Cu" "F.Mask" "F.Paste")
			(net "SMB_FRU_3V3AUX_R1_SCL")
		)
	)
	(footprint ""
		(layer "F.Cu")
		(at 17.190974 -92.687648 90)
		(property "Reference" "R3662"
			(at 0 0 90)
			(layer "F.SilkS")
			(hide yes)
			(effects
				(font
					(size 1.27 1.27)
				)
			)
		)
		(property "Value" ""
			(at 0 0 90)
			(layer "F.Fab")
			(effects
				(font
					(size 1.27 1.27)
				)
			)
		)
		(duplicate_pad_numbers_are_jumpers no)
		(fp_line
			(start 0.7874 -0.4064)
			(end 0.7874 0.4064)
			(stroke
				(width 0.1524)
				(type default)
			)
			(layer "F.SilkS")
		)
		(fp_line
			(start -0.7874 -0.4064)
			(end 0.7874 -0.4064)
			(stroke
				(width 0.1524)
				(type default)
			)
			(layer "F.SilkS")
		)
		(fp_line
			(start 0.7874 0.4064)
			(end -0.7874 0.4064)
			(stroke
				(width 0.1524)
				(type default)
			)
			(layer "F.SilkS")
		)
		(fp_line
			(start -0.7874 0.4064)
			(end -0.7874 -0.4064)
			(stroke
				(width 0.1524)
				(type default)
			)
			(layer "F.SilkS")
		)
		(fp_line
			(start -0.12065 -0.305054)
			(end -0.12065 -0.2794)
			(stroke
				(width 0.1)
				(type default)
			)
			(layer "F.Fab")
		)
		(fp_line
			(start -0.67945 -0.305054)
			(end -0.12065 -0.305054)
			(stroke
				(width 0.1)
				(type default)
			)
			(layer "F.Fab")
		)
		(fp_line
			(start 0.67945 -0.3048)
			(end 0.67945 0.3048)
			(stroke
				(width 0.1)
				(type default)
			)
			(layer "F.Fab")
		)
		(fp_line
			(start 0.12065 -0.3048)
			(end 0.67945 -0.3048)
			(stroke
				(width 0.1)
				(type default)
			)
			(layer "F.Fab")
		)
		(fp_line
			(start 0.12065 -0.2794)
			(end 0.12065 -0.3048)
			(stroke
				(width 0.1)
				(type default)
			)
			(layer "F.Fab")
		)
		(fp_line
			(start -0.12065 -0.2794)
			(end 0.12065 -0.2794)
			(stroke
				(width 0.1)
				(type default)
			)
			(layer "F.Fab")
		)
		(fp_line
			(start 0.120396 0.2794)
			(end -0.12065 0.2794)
			(stroke
				(width 0.1)
				(type default)
			)
			(layer "F.Fab")
		)
		(fp_line
			(start -0.12065 0.2794)
			(end -0.12065 0.3048)
			(stroke
				(width 0.1)
				(type default)
			)
			(layer "F.Fab")
		)
		(fp_line
			(start 0.67945 0.3048)
			(end 0.120396 0.3048)
			(stroke
				(width 0.1)
				(type default)
			)
			(layer "F.Fab")
		)
		(fp_line
			(start 0.120396 0.3048)
			(end 0.120396 0.2794)
			(stroke
				(width 0.1)
				(type default)
			)
			(layer "F.Fab")
		)
		(fp_line
			(start -0.12065 0.3048)
			(end -0.67945 0.3048)
			(stroke
				(width 0.1)
				(type default)
			)
			(layer "F.Fab")
		)
		(fp_line
			(start -0.67945 0.3048)
			(end -0.67945 -0.305054)
			(stroke
				(width 0.1)
				(type default)
			)
			(layer "F.Fab")
		)
		(pad "1" smd circle
			(at -0.40005 0 90)
			(size 0 0)
			(layers "F.Cu" "F.Mask" "F.Paste")
			(net "P3V3_AUX_USB_HUB")
		)
		(pad "2" smd circle
			(at 0.40005 0 90)
			(size 0 0)
			(layers "F.Cu" "F.Mask" "F.Paste")
			(net "USB_HUB_DVDD")
		)
	)
	(footprint ""
		(layer "F.Cu")
		(at 291.259006 -398.60855 90)
		(property "Reference" "R679"
			(at 0 0 90)
			(layer "F.SilkS")
			(hide yes)
			(effects
				(font
					(size 1.27 1.27)
				)
			)
		)
		(property "Value" ""
			(at 0 0 90)
			(layer "F.Fab")
			(effects
				(font
					(size 1.27 1.27)
				)
			)
		)
		(duplicate_pad_numbers_are_jumpers no)
		(fp_line
			(start 0.32512 -0.175006)
			(end 0.32512 0.175006)
			(stroke
				(width 0.1)
				(type default)
			)
			(layer "F.Fab")
		)
		(fp_line
			(start -0.32512 -0.175006)
			(end 0.32512 -0.175006)
			(stroke
				(width 0.1)
				(type default)
			)
			(layer "F.Fab")
		)
		(fp_line
			(start 0.32512 0.175006)
			(end -0.32512 0.175006)
			(stroke
				(width 0.1)
				(type default)
			)
			(layer "F.Fab")
		)
		(fp_line
			(start -0.32512 0.175006)
			(end -0.32512 -0.175006)
			(stroke
				(width 0.1)
				(type default)
			)
			(layer "F.Fab")
		)
		(pad "1" smd rect
			(at -0.2667 0 90)
			(size 0.3048 0.381)
			(layers "F.Cu" "F.Mask" "F.Paste")
			(net "SMB_RT_CPU0_P1_ROM_R_SDA")
		)
		(pad "2" smd rect
			(at 0.2667 0 270)
			(size 0.3048 0.381)
			(layers "F.Cu" "F.Mask" "F.Paste")
			(net "SMB_RT_CPU0_P1_ROM_SDA")
		)
	)
	(footprint ""
		(layer "F.Cu")
		(at 186.111642 -413.64408 90)
		(property "Reference" "R9001"
			(at 0 0 90)
			(layer "F.SilkS")
			(hide yes)
			(effects
				(font
					(size 1.27 1.27)
				)
			)
		)
		(property "Value" ""
			(at 0 0 90)
			(layer "F.Fab")
			(effects
				(font
					(size 1.27 1.27)
				)
			)
		)
		(duplicate_pad_numbers_are_jumpers no)
		(fp_line
			(start 0.7874 -0.4064)
			(end 0.7874 0.4064)
			(stroke
				(width 0.1524)
				(type default)
			)
			(layer "F.SilkS")
		)
		(fp_line
			(start -0.7874 -0.4064)
			(end 0.7874 -0.4064)
			(stroke
				(width 0.1524)
				(type default)
			)
			(layer "F.SilkS")
		)
		(fp_line
			(start 0.7874 0.4064)
			(end -0.7874 0.4064)
			(stroke
				(width 0.1524)
				(type default)
			)
			(layer "F.SilkS")
		)
		(fp_line
			(start -0.7874 0.4064)
			(end -0.7874 -0.4064)
			(stroke
				(width 0.1524)
				(type default)
			)
			(layer "F.SilkS")
		)
		(fp_line
			(start -0.12065 -0.305054)
			(end -0.12065 -0.2794)
			(stroke
				(width 0.1)
				(type default)
			)
			(layer "F.Fab")
		)
		(fp_line
			(start -0.67945 -0.305054)
			(end -0.12065 -0.305054)
			(stroke
				(width 0.1)
				(type default)
			)
			(layer "F.Fab")
		)
		(fp_line
			(start 0.67945 -0.3048)
			(end 0.67945 0.3048)
			(stroke
				(width 0.1)
				(type default)
			)
			(layer "F.Fab")
		)
		(fp_line
			(start 0.12065 -0.3048)
			(end 0.67945 -0.3048)
			(stroke
				(width 0.1)
				(type default)
			)
			(layer "F.Fab")
		)
		(fp_line
			(start 0.12065 -0.2794)
			(end 0.12065 -0.3048)
			(stroke
				(width 0.1)
				(type default)
			)
			(layer "F.Fab")
		)
		(fp_line
			(start -0.12065 -0.2794)
			(end 0.12065 -0.2794)
			(stroke
				(width 0.1)
				(type default)
			)
			(layer "F.Fab")
		)
		(fp_line
			(start 0.120396 0.2794)
			(end -0.12065 0.2794)
			(stroke
				(width 0.1)
				(type default)
			)
			(layer "F.Fab")
		)
		(fp_line
			(start -0.12065 0.2794)
			(end -0.12065 0.3048)
			(stroke
				(width 0.1)
				(type default)
			)
			(layer "F.Fab")
		)
		(fp_line
			(start 0.67945 0.3048)
			(end 0.120396 0.3048)
			(stroke
				(width 0.1)
				(type default)
			)
			(layer "F.Fab")
		)
		(fp_line
			(start 0.120396 0.3048)
			(end 0.120396 0.2794)
			(stroke
				(width 0.1)
				(type default)
			)
			(layer "F.Fab")
		)
		(fp_line
			(start -0.12065 0.3048)
			(end -0.67945 0.3048)
			(stroke
				(width 0.1)
				(type default)
			)
			(layer "F.Fab")
		)
		(fp_line
			(start -0.67945 0.3048)
			(end -0.67945 -0.305054)
			(stroke
				(width 0.1)
				(type default)
			)
			(layer "F.Fab")
		)
		(pad "1" smd circle
			(at -0.40005 0 90)
			(size 0 0)
			(layers "F.Cu" "F.Mask" "F.Paste")
			(net "GPU_PRSNT_N_ISO")
		)
		(pad "2" smd circle
			(at 0.40005 0 90)
			(size 0 0)
			(layers "F.Cu" "F.Mask" "F.Paste")
			(net "GPU_PRSNT_N_ISO_R1")
		)
	)
	(footprint ""
		(layer "F.Cu")
		(at 9.379458 -423.821098)
		(property "Reference" "R6171"
			(at 0 0 0)
			(layer "F.SilkS")
			(hide yes)
			(effects
				(font
					(size 1.27 1.27)
				)
			)
		)
		(property "Value" ""
			(at 0 0 0)
			(layer "F.Fab")
			(effects
				(font
					(size 1.27 1.27)
				)
			)
		)
		(duplicate_pad_numbers_are_jumpers no)
		(fp_line
			(start -0.7874 -0.4064)
			(end 0.7874 -0.4064)
			(stroke
				(width 0.1524)
				(type default)
			)
			(layer "F.SilkS")
		)
		(fp_line
			(start -0.7874 0.4064)
			(end -0.7874 -0.4064)
			(stroke
				(width 0.1524)
				(type default)
			)
			(layer "F.SilkS")
		)
		(fp_line
			(start 0.7874 -0.4064)
			(end 0.7874 0.4064)
			(stroke
				(width 0.1524)
				(type default)
			)
			(layer "F.SilkS")
		)
		(fp_line
			(start 0.7874 0.4064)
			(end -0.7874 0.4064)
			(stroke
				(width 0.1524)
				(type default)
			)
			(layer "F.SilkS")
		)
		(fp_line
			(start -0.67945 -0.305054)
			(end -0.12065 -0.305054)
			(stroke
				(width 0.1)
				(type default)
			)
			(layer "F.Fab")
		)
		(fp_line
			(start -0.67945 0.3048)
			(end -0.67945 -0.305054)
			(stroke
				(width 0.1)
				(type default)
			)
			(layer "F.Fab")
		)
		(fp_line
			(start -0.12065 -0.305054)
			(end -0.12065 -0.2794)
			(stroke
				(width 0.1)
				(type default)
			)
			(layer "F.Fab")
		)
		(fp_line
			(start -0.12065 -0.2794)
			(end 0.12065 -0.2794)
			(stroke
				(width 0.1)
				(type default)
			)
			(layer "F.Fab")
		)
		(fp_line
			(start -0.12065 0.2794)
			(end -0.12065 0.3048)
			(stroke
				(width 0.1)
				(type default)
			)
			(layer "F.Fab")
		)
		(fp_line
			(start -0.12065 0.3048)
			(end -0.67945 0.3048)
			(stroke
				(width 0.1)
				(type default)
			)
			(layer "F.Fab")
		)
		(fp_line
			(start 0.120396 0.2794)
			(end -0.12065 0.2794)
			(stroke
				(width 0.1)
				(type default)
			)
			(layer "F.Fab")
		)
		(fp_line
			(start 0.120396 0.3048)
			(end 0.120396 0.2794)
			(stroke
				(width 0.1)
				(type default)
			)
			(layer "F.Fab")
		)
		(fp_line
			(start 0.12065 -0.3048)
			(end 0.67945 -0.3048)
			(stroke
				(width 0.1)
				(type default)
			)
			(layer "F.Fab")
		)
		(fp_line
			(start 0.12065 -0.2794)
			(end 0.12065 -0.3048)
			(stroke
				(width 0.1)
				(type default)
			)
			(layer "F.Fab")
		)
		(fp_line
			(start 0.67945 -0.3048)
			(end 0.67945 0.3048)
			(stroke
				(width 0.1)
				(type default)
			)
			(layer "F.Fab")
		)
		(fp_line
			(start 0.67945 0.3048)
			(end 0.120396 0.3048)
			(stroke
				(width 0.1)
				(type default)
			)
			(layer "F.Fab")
		)
		(pad "1" smd circle
			(at -0.40005 0)
			(size 0 0)
			(layers "F.Cu" "F.Mask" "F.Paste")
			(net "P3V3_AUX")
		)
		(pad "2" smd circle
			(at 0.40005 0)
			(size 0 0)
			(layers "F.Cu" "F.Mask" "F.Paste")
			(net "FM_P2E_BUF2_EQA1")
		)
	)
	(footprint ""
		(layer "F.Cu")
		(at 193.167 -133.568948 90)
		(property "Reference" "R372"
			(at 0 0 90)
			(layer "F.SilkS")
			(hide yes)
			(effects
				(font
					(size 1.27 1.27)
				)
			)
		)
		(property "Value" ""
			(at 0 0 90)
			(layer "F.Fab")
			(effects
				(font
					(size 1.27 1.27)
				)
			)
		)
		(duplicate_pad_numbers_are_jumpers no)
		(fp_line
			(start 0.7874 -0.4064)
			(end 0.7874 0.4064)
			(stroke
				(width 0.1524)
				(type default)
			)
			(layer "F.SilkS")
		)
		(fp_line
			(start -0.7874 -0.4064)
			(end 0.7874 -0.4064)
			(stroke
				(width 0.1524)
				(type default)
			)
			(layer "F.SilkS")
		)
		(fp_line
			(start 0.7874 0.4064)
			(end -0.7874 0.4064)
			(stroke
				(width 0.1524)
				(type default)
			)
			(layer "F.SilkS")
		)
		(fp_line
			(start -0.7874 0.4064)
			(end -0.7874 -0.4064)
			(stroke
				(width 0.1524)
				(type default)
			)
			(layer "F.SilkS")
		)
		(fp_line
			(start -0.12065 -0.305054)
			(end -0.12065 -0.2794)
			(stroke
				(width 0.1)
				(type default)
			)
			(layer "F.Fab")
		)
		(fp_line
			(start -0.67945 -0.305054)
			(end -0.12065 -0.305054)
			(stroke
				(width 0.1)
				(type default)
			)
			(layer "F.Fab")
		)
		(fp_line
			(start 0.67945 -0.3048)
			(end 0.67945 0.3048)
			(stroke
				(width 0.1)
				(type default)
			)
			(layer "F.Fab")
		)
		(fp_line
			(start 0.12065 -0.3048)
			(end 0.67945 -0.3048)
			(stroke
				(width 0.1)
				(type default)
			)
			(layer "F.Fab")
		)
		(fp_line
			(start 0.12065 -0.2794)
			(end 0.12065 -0.3048)
			(stroke
				(width 0.1)
				(type default)
			)
			(layer "F.Fab")
		)
		(fp_line
			(start -0.12065 -0.2794)
			(end 0.12065 -0.2794)
			(stroke
				(width 0.1)
				(type default)
			)
			(layer "F.Fab")
		)
		(fp_line
			(start 0.120396 0.2794)
			(end -0.12065 0.2794)
			(stroke
				(width 0.1)
				(type default)
			)
			(layer "F.Fab")
		)
		(fp_line
			(start -0.12065 0.2794)
			(end -0.12065 0.3048)
			(stroke
				(width 0.1)
				(type default)
			)
			(layer "F.Fab")
		)
		(fp_line
			(start 0.67945 0.3048)
			(end 0.120396 0.3048)
			(stroke
				(width 0.1)
				(type default)
			)
			(layer "F.Fab")
		)
		(fp_line
			(start 0.120396 0.3048)
			(end 0.120396 0.2794)
			(stroke
				(width 0.1)
				(type default)
			)
			(layer "F.Fab")
		)
		(fp_line
			(start -0.12065 0.3048)
			(end -0.67945 0.3048)
			(stroke
				(width 0.1)
				(type default)
			)
			(layer "F.Fab")
		)
		(fp_line
			(start -0.67945 0.3048)
			(end -0.67945 -0.305054)
			(stroke
				(width 0.1)
				(type default)
			)
			(layer "F.Fab")
		)
		(pad "1" smd circle
			(at -0.40005 0 90)
			(size 0 0)
			(layers "F.Cu" "F.Mask" "F.Paste")
			(net "P12V_ALL_PWROK_R")
		)
		(pad "2" smd circle
			(at 0.40005 0 90)
			(size 0 0)
			(layers "F.Cu" "F.Mask" "F.Paste")
			(net "P12V_ALL_PWROK")
		)
	)
	(footprint ""
		(layer "F.Cu")
		(at 244.63375 -51.332384 180)
		(property "Reference" "C1110"
			(at 0 0 180)
			(layer "F.SilkS")
			(hide yes)
			(effects
				(font
					(size 1.27 1.27)
				)
			)
		)
		(property "Value" ""
			(at 0 0 180)
			(layer "F.Fab")
			(effects
				(font
					(size 1.27 1.27)
				)
			)
		)
		(duplicate_pad_numbers_are_jumpers no)
		(fp_line
			(start 0.7874 0.4064)
			(end -0.7874 0.4064)
			(stroke
				(width 0.1524)
				(type default)
			)
			(layer "F.SilkS")
		)
		(fp_line
			(start 0.7874 -0.4064)
			(end 0.7874 0.4064)
			(stroke
				(width 0.1524)
				(type default)
			)
			(layer "F.SilkS")
		)
		(fp_line
			(start -0.7874 0.4064)
			(end -0.7874 -0.4064)
			(stroke
				(width 0.1524)
				(type default)
			)
			(layer "F.SilkS")
		)
		(fp_line
			(start -0.7874 -0.4064)
			(end 0.7874 -0.4064)
			(stroke
				(width 0.1524)
				(type default)
			)
			(layer "F.SilkS")
		)
		(fp_line
			(start 0.67945 0.3048)
			(end 0.120396 0.3048)
			(stroke
				(width 0.1)
				(type default)
			)
			(layer "F.Fab")
		)
		(fp_line
			(start 0.67945 -0.3048)
			(end 0.67945 0.3048)
			(stroke
				(width 0.1)
				(type default)
			)
			(layer "F.Fab")
		)
		(fp_line
			(start 0.12065 -0.2794)
			(end 0.12065 -0.3048)
			(stroke
				(width 0.1)
				(type default)
			)
			(layer "F.Fab")
		)
		(fp_line
			(start 0.12065 -0.3048)
			(end 0.67945 -0.3048)
			(stroke
				(width 0.1)
				(type default)
			)
			(layer "F.Fab")
		)
		(fp_line
			(start 0.120396 0.3048)
			(end 0.120396 0.2794)
			(stroke
				(width 0.1)
				(type default)
			)
			(layer "F.Fab")
		)
		(fp_line
			(start 0.120396 0.2794)
			(end -0.12065 0.2794)
			(stroke
				(width 0.1)
				(type default)
			)
			(layer "F.Fab")
		)
		(fp_line
			(start -0.12065 0.3048)
			(end -0.67945 0.3048)
			(stroke
				(width 0.1)
				(type default)
			)
			(layer "F.Fab")
		)
		(fp_line
			(start -0.12065 0.2794)
			(end -0.12065 0.3048)
			(stroke
				(width 0.1)
				(type default)
			)
			(layer "F.Fab")
		)
		(fp_line
			(start -0.12065 -0.2794)
			(end 0.12065 -0.2794)
			(stroke
				(width 0.1)
				(type default)
			)
			(layer "F.Fab")
		)
		(fp_line
			(start -0.12065 -0.305054)
			(end -0.12065 -0.2794)
			(stroke
				(width 0.1)
				(type default)
			)
			(layer "F.Fab")
		)
		(fp_line
			(start -0.67945 0.3048)
			(end -0.67945 -0.305054)
			(stroke
				(width 0.1)
				(type default)
			)
			(layer "F.Fab")
		)
		(fp_line
			(start -0.67945 -0.305054)
			(end -0.12065 -0.305054)
			(stroke
				(width 0.1)
				(type default)
			)
			(layer "F.Fab")
		)
		(pad "1" smd circle
			(at -0.40005 0 180)
			(size 0 0)
			(layers "F.Cu" "F.Mask" "F.Paste")
			(net "VSENSE_P12V_INA230_8_INP")
		)
		(pad "2" smd circle
			(at 0.40005 0 180)
			(size 0 0)
			(layers "F.Cu" "F.Mask" "F.Paste")
			(net "VSENSE_P12V_INA230_8_INN")
		)
	)
	(footprint ""
		(layer "F.Cu")
		(at 320.981324 -192.09766 -90)
		(property "Reference" "R2310"
			(at 0 0 270)
			(layer "F.SilkS")
			(hide yes)
			(effects
				(font
					(size 1.27 1.27)
				)
			)
		)
		(property "Value" ""
			(at 0 0 270)
			(layer "F.Fab")
			(effects
				(font
					(size 1.27 1.27)
				)
			)
		)
		(duplicate_pad_numbers_are_jumpers no)
		(fp_line
			(start -0.7874 0.4064)
			(end -0.7874 -0.4064)
			(stroke
				(width 0.1524)
				(type default)
			)
			(layer "F.SilkS")
		)
		(fp_line
			(start 0.7874 0.4064)
			(end -0.7874 0.4064)
			(stroke
				(width 0.1524)
				(type default)
			)
			(layer "F.SilkS")
		)
		(fp_line
			(start -0.7874 -0.4064)
			(end 0.7874 -0.4064)
			(stroke
				(width 0.1524)
				(type default)
			)
			(layer "F.SilkS")
		)
		(fp_line
			(start 0.7874 -0.4064)
			(end 0.7874 0.4064)
			(stroke
				(width 0.1524)
				(type default)
			)
			(layer "F.SilkS")
		)
		(fp_line
			(start -0.67945 0.3048)
			(end -0.67945 -0.305054)
			(stroke
				(width 0.1)
				(type default)
			)
			(layer "F.Fab")
		)
		(fp_line
			(start -0.12065 0.3048)
			(end -0.67945 0.3048)
			(stroke
				(width 0.1)
				(type default)
			)
			(layer "F.Fab")
		)
		(fp_line
			(start 0.120396 0.3048)
			(end 0.120396 0.2794)
			(stroke
				(width 0.1)
				(type default)
			)
			(layer "F.Fab")
		)
		(fp_line
			(start 0.67945 0.3048)
			(end 0.120396 0.3048)
			(stroke
				(width 0.1)
				(type default)
			)
			(layer "F.Fab")
		)
		(fp_line
			(start -0.12065 0.2794)
			(end -0.12065 0.3048)
			(stroke
				(width 0.1)
				(type default)
			)
			(layer "F.Fab")
		)
		(fp_line
			(start 0.120396 0.2794)
			(end -0.12065 0.2794)
			(stroke
				(width 0.1)
				(type default)
			)
			(layer "F.Fab")
		)
		(fp_line
			(start -0.12065 -0.2794)
			(end 0.12065 -0.2794)
			(stroke
				(width 0.1)
				(type default)
			)
			(layer "F.Fab")
		)
		(fp_line
			(start 0.12065 -0.2794)
			(end 0.12065 -0.3048)
			(stroke
				(width 0.1)
				(type default)
			)
			(layer "F.Fab")
		)
		(fp_line
			(start 0.12065 -0.3048)
			(end 0.67945 -0.3048)
			(stroke
				(width 0.1)
				(type default)
			)
			(layer "F.Fab")
		)
		(fp_line
			(start 0.67945 -0.3048)
			(end 0.67945 0.3048)
			(stroke
				(width 0.1)
				(type default)
			)
			(layer "F.Fab")
		)
		(fp_line
			(start -0.67945 -0.305054)
			(end -0.12065 -0.305054)
			(stroke
				(width 0.1)
				(type default)
			)
			(layer "F.Fab")
		)
		(fp_line
			(start -0.12065 -0.305054)
			(end -0.12065 -0.2794)
			(stroke
				(width 0.1)
				(type default)
			)
			(layer "F.Fab")
		)
		(pad "1" smd rect
			(at -0.40005 0 90)
			(size 0.4572 0.508)
			(layers "F.Cu" "F.Mask" "F.Paste")
			(net "I3C_0_SPD_DDRAF_CPU0_R_SCL")
		)
		(pad "2" smd rect
			(at 0.40005 0 90)
			(size 0.4572 0.508)
			(layers "F.Cu" "F.Mask" "F.Paste")
			(net "I3C_SPD_DDRAF_CPU0_BYPASS_SCL")
		)
	)
	(footprint ""
		(layer "F.Cu")
		(at 319.940178 -45.859954)
		(property "Reference" "C37"
			(at 0 0 0)
			(layer "F.SilkS")
			(hide yes)
			(effects
				(font
					(size 1.27 1.27)
				)
			)
		)
		(property "Value" ""
			(at 0 0 0)
			(layer "F.Fab")
			(effects
				(font
					(size 1.27 1.27)
				)
			)
		)
		(duplicate_pad_numbers_are_jumpers no)
		(fp_line
			(start -0.7874 -0.4064)
			(end 0.7874 -0.4064)
			(stroke
				(width 0.1524)
				(type default)
			)
			(layer "F.SilkS")
		)
		(fp_line
			(start -0.7874 0.4064)
			(end -0.7874 -0.4064)
			(stroke
				(width 0.1524)
				(type default)
			)
			(layer "F.SilkS")
		)
		(fp_line
			(start 0.7874 -0.4064)
			(end 0.7874 0.4064)
			(stroke
				(width 0.1524)
				(type default)
			)
			(layer "F.SilkS")
		)
		(fp_line
			(start 0.7874 0.4064)
			(end -0.7874 0.4064)
			(stroke
				(width 0.1524)
				(type default)
			)
			(layer "F.SilkS")
		)
		(fp_line
			(start -0.67945 -0.305054)
			(end -0.12065 -0.305054)
			(stroke
				(width 0.1)
				(type default)
			)
			(layer "F.Fab")
		)
		(fp_line
			(start -0.67945 0.3048)
			(end -0.67945 -0.305054)
			(stroke
				(width 0.1)
				(type default)
			)
			(layer "F.Fab")
		)
		(fp_line
			(start -0.12065 -0.305054)
			(end -0.12065 -0.2794)
			(stroke
				(width 0.1)
				(type default)
			)
			(layer "F.Fab")
		)
		(fp_line
			(start -0.12065 -0.2794)
			(end 0.12065 -0.2794)
			(stroke
				(width 0.1)
				(type default)
			)
			(layer "F.Fab")
		)
		(fp_line
			(start -0.12065 0.2794)
			(end -0.12065 0.3048)
			(stroke
				(width 0.1)
				(type default)
			)
			(layer "F.Fab")
		)
		(fp_line
			(start -0.12065 0.3048)
			(end -0.67945 0.3048)
			(stroke
				(width 0.1)
				(type default)
			)
			(layer "F.Fab")
		)
		(fp_line
			(start 0.120396 0.2794)
			(end -0.12065 0.2794)
			(stroke
				(width 0.1)
				(type default)
			)
			(layer "F.Fab")
		)
		(fp_line
			(start 0.120396 0.3048)
			(end 0.120396 0.2794)
			(stroke
				(width 0.1)
				(type default)
			)
			(layer "F.Fab")
		)
		(fp_line
			(start 0.12065 -0.3048)
			(end 0.67945 -0.3048)
			(stroke
				(width 0.1)
				(type default)
			)
			(layer "F.Fab")
		)
		(fp_line
			(start 0.12065 -0.2794)
			(end 0.12065 -0.3048)
			(stroke
				(width 0.1)
				(type default)
			)
			(layer "F.Fab")
		)
		(fp_line
			(start 0.67945 -0.3048)
			(end 0.67945 0.3048)
			(stroke
				(width 0.1)
				(type default)
			)
			(layer "F.Fab")
		)
		(fp_line
			(start 0.67945 0.3048)
			(end 0.120396 0.3048)
			(stroke
				(width 0.1)
				(type default)
			)
			(layer "F.Fab")
		)
		(pad "1" smd circle
			(at -0.40005 0)
			(size 0 0)
			(layers "F.Cu" "F.Mask" "F.Paste")
			(net "P12V_OCP_SFF_ISENSE_TIC")
		)
		(pad "2" smd circle
			(at 0.40005 0)
			(size 0 0)
			(layers "F.Cu" "F.Mask" "F.Paste")
			(net "GND")
		)
	)
	(footprint ""
		(layer "F.Cu")
		(at 429.506126 -255.560068 180)
		(property "Reference" "J18"
			(at 0.484632 -81.752948 0)
			(unlocked yes)
			(layer "F.SilkS")
			(effects
				(font
					(size 0.7874 0.5842)
					(thickness 0.1524)
				)
			)
		)
		(property "Value" ""
			(at 0 0 180)
			(layer "F.Fab")
			(effects
				(font
					(size 1.27 1.27)
				)
			)
		)
		(duplicate_pad_numbers_are_jumpers no)
		(fp_line
			(start 3.24993 -81.000092)
			(end 3.24993 72.861932)
			(stroke
				(width 0.1524)
				(type default)
			)
			(layer "F.SilkS")
		)
		(fp_line
			(start 1.389126 81.000092)
			(end -1.912874 81.000092)
			(stroke
				(width 0.1524)
				(type default)
			)
			(layer "F.SilkS")
		)
		(fp_line
			(start -3.24993 72.861932)
			(end -3.24993 -81.000092)
			(stroke
				(width 0.1524)
				(type default)
			)
			(layer "F.SilkS")
		)
		(fp_line
			(start -3.24993 72.499982)
			(end 3.24993 72.499982)
			(stroke
				(width 0.1524)
				(type default)
			)
			(layer "F.SilkS")
		)
		(fp_line
			(start -3.24993 -72.499982)
			(end 3.24993 -72.499982)
			(stroke
				(width 0.1524)
				(type default)
			)
			(layer "F.SilkS")
		)
		(fp_line
			(start -3.24993 -81.000092)
			(end 3.24993 -81.000092)
			(stroke
				(width 0.1524)
				(type default)
			)
			(layer "F.SilkS")
		)
		(fp_poly
			(pts
				(xy -3.792728 -64.502538) (xy -3.374136 -63.929006) (xy -4.084066 -63.938404)
			)
			(stroke
				(width 0)
				(type default)
			)
			(fill yes)
			(layer "F.SilkS")
		)
		(fp_line
			(start 3.24993 81.000092)
			(end -3.24993 81.000092)
			(stroke
				(width 0.1)
				(type default)
			)
			(layer "F.Fab")
		)
		(fp_line
			(start 3.24993 -81.000092)
			(end 3.24993 81.000092)
			(stroke
				(width 0.1)
				(type default)
			)
			(layer "F.Fab")
		)
		(fp_line
			(start -3.24993 81.000092)
			(end -3.24993 -81.000092)
			(stroke
				(width 0.1)
				(type default)
			)
			(layer "F.Fab")
		)
		(fp_line
			(start -3.24993 72.499982)
			(end 3.24993 72.499982)
			(stroke
				(width 0.1)
				(type default)
			)
			(layer "F.Fab")
		)
		(fp_line
			(start -3.24993 71.000112)
			(end 3.24993 71.000112)
			(stroke
				(width 0.1)
				(type default)
			)
			(layer "F.Fab")
		)
		(fp_line
			(start -3.24993 -71.000112)
			(end 3.24993 -71.000112)
			(stroke
				(width 0.1)
				(type default)
			)
			(layer "F.Fab")
		)
		(fp_line
			(start -3.24993 -72.499982)
			(end 3.24993 -72.499982)
			(stroke
				(width 0.1)
				(type default)
			)
			(layer "F.Fab")
		)
		(fp_line
			(start -3.24993 -81.000092)
			(end 3.24993 -81.000092)
			(stroke
				(width 0.1)
				(type default)
			)
			(layer "F.Fab")
		)
		(fp_poly
			(pts
				(xy -3.41503 -63.324994) (xy -4.43103 -62.816994) (xy -4.43103 -63.832994)
			)
			(stroke
				(width 0)
				(type default)
			)
			(fill yes)
			(layer "F.Fab")
		)
		(pad "1" smd rect
			(at -2.050034 -63.324994 90)
			(size 0.519938 1.4986)
			(layers "F.Cu" "F.Mask" "F.Paste")
			(net "P12V_MEM_CPU0")
		)
		(pad "2" smd rect
			(at -2.050034 -62.47511 90)
			(size 0.519938 1.4986)
			(layers "F.Cu" "F.Mask" "F.Paste")
			(net "Net_2361")
		)
		(pad "3" smd rect
			(at -2.050034 -61.624972 90)
			(size 0.519938 1.4986)
			(layers "F.Cu" "F.Mask" "F.Paste")
			(net "P3V3_AUX")
		)
		(pad "4" smd rect
			(at -2.050034 -60.775088 90)
			(size 0.519938 1.4986)
			(layers "F.Cu" "F.Mask" "F.Paste")
			(net "I3C_SPD_DDRI_CPU0_SCL")
		)
		(pad "5" smd rect
			(at -2.050034 -59.92495 90)
			(size 0.519938 1.4986)
			(layers "F.Cu" "F.Mask" "F.Paste")
			(net "I3C_SPD_DDRI_CPU0_SDA")
		)
		(pad "6" smd rect
			(at -2.050034 -59.075066 90)
			(size 0.519938 1.4986)
			(layers "F.Cu" "F.Mask" "F.Paste")
			(net "GND")
		)
		(pad "7" smd rect
			(at -2.050034 -58.224928 90)
			(size 0.519938 1.4986)
			(layers "F.Cu" "F.Mask" "F.Paste")
			(net "M_I_CPU0_SA_DQ<0>")
		)
		(pad "8" smd rect
			(at -2.050034 -57.375044 90)
			(size 0.519938 1.4986)
			(layers "F.Cu" "F.Mask" "F.Paste")
			(net "GND")
		)
		(pad "9" smd rect
			(at -2.050034 -56.524906 90)
			(size 0.519938 1.4986)
			(layers "F.Cu" "F.Mask" "F.Paste")
			(net "M_I_CPU0_SA_DQ<1>")
		)
		(pad "10" smd rect
			(at -2.050034 -55.675022 90)
			(size 0.519938 1.4986)
			(layers "F.Cu" "F.Mask" "F.Paste")
			(net "GND")
		)
		(pad "11" smd rect
			(at -2.050034 -54.824884 90)
			(size 0.519938 1.4986)
			(layers "F.Cu" "F.Mask" "F.Paste")
			(net "M_I_CPU0_SA_DQS_DP<0>")
		)
		(pad "12" smd rect
			(at -2.050034 -53.975 90)
			(size 0.519938 1.4986)
			(layers "F.Cu" "F.Mask" "F.Paste")
			(net "M_I_CPU0_SA_DQS_DN<0>")
		)
		(pad "13" smd rect
			(at -2.050034 -53.125116 90)
			(size 0.519938 1.4986)
			(layers "F.Cu" "F.Mask" "F.Paste")
			(net "GND")
		)
		(pad "14" smd rect
			(at -2.050034 -52.274978 90)
			(size 0.519938 1.4986)
			(layers "F.Cu" "F.Mask" "F.Paste")
			(net "M_I_CPU0_SA_DQ<4>")
		)
		(pad "15" smd rect
			(at -2.050034 -51.425094 90)
			(size 0.519938 1.4986)
			(layers "F.Cu" "F.Mask" "F.Paste")
			(net "GND")
		)
		(pad "16" smd rect
			(at -2.050034 -50.574956 90)
			(size 0.519938 1.4986)
			(layers "F.Cu" "F.Mask" "F.Paste")
			(net "M_I_CPU0_SA_DQ<5>")
		)
		(pad "17" smd rect
			(at -2.050034 -49.725072 90)
			(size 0.519938 1.4986)
			(layers "F.Cu" "F.Mask" "F.Paste")
			(net "GND")
		)
		(pad "18" smd rect
			(at -2.050034 -48.874934 90)
			(size 0.519938 1.4986)
			(layers "F.Cu" "F.Mask" "F.Paste")
			(net "M_I_CPU0_SA_DQ<8>")
		)
		(pad "19" smd rect
			(at -2.050034 -48.02505 90)
			(size 0.519938 1.4986)
			(layers "F.Cu" "F.Mask" "F.Paste")
			(net "GND")
		)
		(pad "20" smd rect
			(at -2.050034 -47.174912 90)
			(size 0.519938 1.4986)
			(layers "F.Cu" "F.Mask" "F.Paste")
			(net "M_I_CPU0_SA_DQ<9>")
		)
		(pad "21" smd rect
			(at -2.050034 -46.325028 90)
			(size 0.519938 1.4986)
			(layers "F.Cu" "F.Mask" "F.Paste")
			(net "GND")
		)
		(pad "22" smd rect
			(at -2.050034 -45.47489 90)
			(size 0.519938 1.4986)
			(layers "F.Cu" "F.Mask" "F.Paste")
			(net "M_I_CPU0_SA_DQS_DP<1>")
		)
		(pad "23" smd rect
			(at -2.050034 -44.625006 90)
			(size 0.519938 1.4986)
			(layers "F.Cu" "F.Mask" "F.Paste")
			(net "M_I_CPU0_SA_DQS_DN<1>")
		)
		(pad "24" smd rect
			(at -2.050034 -43.775122 90)
			(size 0.519938 1.4986)
			(layers "F.Cu" "F.Mask" "F.Paste")
			(net "GND")
		)
		(pad "25" smd rect
			(at -2.050034 -42.924984 90)
			(size 0.519938 1.4986)
			(layers "F.Cu" "F.Mask" "F.Paste")
			(net "M_I_CPU0_SA_DQ<12>")
		)
		(pad "26" smd rect
			(at -2.050034 -42.0751 90)
			(size 0.519938 1.4986)
			(layers "F.Cu" "F.Mask" "F.Paste")
			(net "GND")
		)
		(pad "27" smd rect
			(at -2.050034 -41.224962 90)
			(size 0.519938 1.4986)
			(layers "F.Cu" "F.Mask" "F.Paste")
			(net "M_I_CPU0_SA_DQ<13>")
		)
		(pad "28" smd rect
			(at -2.050034 -40.375078 90)
			(size 0.519938 1.4986)
			(layers "F.Cu" "F.Mask" "F.Paste")
			(net "GND")
		)
		(pad "29" smd rect
			(at -2.050034 -39.52494 90)
			(size 0.519938 1.4986)
			(layers "F.Cu" "F.Mask" "F.Paste")
			(net "M_I_CPU0_SA_DQ<16>")
		)
		(pad "30" smd rect
			(at -2.050034 -38.675056 90)
			(size 0.519938 1.4986)
			(layers "F.Cu" "F.Mask" "F.Paste")
			(net "GND")
		)
		(pad "31" smd rect
			(at -2.050034 -37.824918 90)
			(size 0.519938 1.4986)
			(layers "F.Cu" "F.Mask" "F.Paste")
			(net "M_I_CPU0_SA_DQ<17>")
		)
		(pad "32" smd rect
			(at -2.050034 -36.975034 90)
			(size 0.519938 1.4986)
			(layers "F.Cu" "F.Mask" "F.Paste")
			(net "GND")
		)
		(pad "33" smd rect
			(at -2.050034 -36.124896 90)
			(size 0.519938 1.4986)
			(layers "F.Cu" "F.Mask" "F.Paste")
			(net "M_I_CPU0_SA_DQS_DP<2>")
		)
		(pad "34" smd rect
			(at -2.050034 -35.275012 90)
			(size 0.519938 1.4986)
			(layers "F.Cu" "F.Mask" "F.Paste")
			(net "M_I_CPU0_SA_DQS_DN<2>")
		)
		(pad "35" smd rect
			(at -2.050034 -34.425128 90)
			(size 0.519938 1.4986)
			(layers "F.Cu" "F.Mask" "F.Paste")
			(net "GND")
		)
		(pad "36" smd rect
			(at -2.050034 -33.57499 90)
			(size 0.519938 1.4986)
			(layers "F.Cu" "F.Mask" "F.Paste")
			(net "M_I_CPU0_SA_DQ<20>")
		)
		(pad "37" smd rect
			(at -2.050034 -32.725106 90)
			(size 0.519938 1.4986)
			(layers "F.Cu" "F.Mask" "F.Paste")
			(net "GND")
		)
		(pad "38" smd rect
			(at -2.050034 -31.874968 90)
			(size 0.519938 1.4986)
			(layers "F.Cu" "F.Mask" "F.Paste")
			(net "M_I_CPU0_SA_DQ<21>")
		)
		(pad "39" smd rect
			(at -2.050034 -31.025084 90)
			(size 0.519938 1.4986)
			(layers "F.Cu" "F.Mask" "F.Paste")
			(net "GND")
		)
		(pad "40" smd rect
			(at -2.050034 -30.174946 90)
			(size 0.519938 1.4986)
			(layers "F.Cu" "F.Mask" "F.Paste")
			(net "M_I_CPU0_SA_DQ<24>")
		)
		(pad "41" smd rect
			(at -2.050034 -29.325062 90)
			(size 0.519938 1.4986)
			(layers "F.Cu" "F.Mask" "F.Paste")
			(net "GND")
		)
		(pad "42" smd rect
			(at -2.050034 -28.474924 90)
			(size 0.519938 1.4986)
			(layers "F.Cu" "F.Mask" "F.Paste")
			(net "M_I_CPU0_SA_DQ<25>")
		)
		(pad "43" smd rect
			(at -2.050034 -27.62504 90)
			(size 0.519938 1.4986)
			(layers "F.Cu" "F.Mask" "F.Paste")
			(net "GND")
		)
		(pad "44" smd rect
			(at -2.050034 -26.774902 90)
			(size 0.519938 1.4986)
			(layers "F.Cu" "F.Mask" "F.Paste")
			(net "M_I_CPU0_SA_DQS_DP<3>")
		)
		(pad "45" smd rect
			(at -2.050034 -25.925018 90)
			(size 0.519938 1.4986)
			(layers "F.Cu" "F.Mask" "F.Paste")
			(net "M_I_CPU0_SA_DQS_DN<3>")
		)
		(pad "46" smd rect
			(at -2.050034 -25.07488 90)
			(size 0.519938 1.4986)
			(layers "F.Cu" "F.Mask" "F.Paste")
			(net "GND")
		)
		(pad "47" smd rect
			(at -2.050034 -24.224996 90)
			(size 0.519938 1.4986)
			(layers "F.Cu" "F.Mask" "F.Paste")
			(net "M_I_CPU0_SA_DQ<28>")
		)
		(pad "48" smd rect
			(at -2.050034 -23.375112 90)
			(size 0.519938 1.4986)
			(layers "F.Cu" "F.Mask" "F.Paste")
			(net "GND")
		)
		(pad "49" smd rect
			(at -2.050034 -22.524974 90)
			(size 0.519938 1.4986)
			(layers "F.Cu" "F.Mask" "F.Paste")
			(net "M_I_CPU0_SA_DQ<29>")
		)
		(pad "50" smd rect
			(at -2.050034 -21.67509 90)
			(size 0.519938 1.4986)
			(layers "F.Cu" "F.Mask" "F.Paste")
			(net "GND")
		)
		(pad "51" smd rect
			(at -2.050034 -20.824952 90)
			(size 0.519938 1.4986)
			(layers "F.Cu" "F.Mask" "F.Paste")
			(net "M_I_CPU0_SA_CB<0>")
		)
		(pad "52" smd rect
			(at -2.050034 -19.975068 90)
			(size 0.519938 1.4986)
			(layers "F.Cu" "F.Mask" "F.Paste")
			(net "GND")
		)
		(pad "53" smd rect
			(at -2.050034 -19.12493 90)
			(size 0.519938 1.4986)
			(layers "F.Cu" "F.Mask" "F.Paste")
			(net "M_I_CPU0_SA_CB<1>")
		)
		(pad "54" smd rect
			(at -2.050034 -18.275046 90)
			(size 0.519938 1.4986)
			(layers "F.Cu" "F.Mask" "F.Paste")
			(net "GND")
		)
		(pad "55" smd rect
			(at -2.050034 -17.424908 90)
			(size 0.519938 1.4986)
			(layers "F.Cu" "F.Mask" "F.Paste")
			(net "M_I_CPU0_SA_DQS_DP<4>")
		)
		(pad "56" smd rect
			(at -2.050034 -16.575024 90)
			(size 0.519938 1.4986)
			(layers "F.Cu" "F.Mask" "F.Paste")
			(net "M_I_CPU0_SA_DQS_DN<4>")
		)
		(pad "57" smd rect
			(at -2.050034 -15.724886 90)
			(size 0.519938 1.4986)
			(layers "F.Cu" "F.Mask" "F.Paste")
			(net "GND")
		)
		(pad "58" smd rect
			(at -2.050034 -14.875002 90)
			(size 0.519938 1.4986)
			(layers "F.Cu" "F.Mask" "F.Paste")
			(net "M_I_CPU0_SA_CB<4>")
		)
		(pad "59" smd rect
			(at -2.050034 -14.025118 90)
			(size 0.519938 1.4986)
			(layers "F.Cu" "F.Mask" "F.Paste")
			(net "GND")
		)
		(pad "60" smd rect
			(at -2.050034 -13.17498 90)
			(size 0.519938 1.4986)
			(layers "F.Cu" "F.Mask" "F.Paste")
			(net "M_I_CPU0_SA_CB<5>")
		)
		(pad "61" smd rect
			(at -2.050034 -12.325096 90)
			(size 0.519938 1.4986)
			(layers "F.Cu" "F.Mask" "F.Paste")
			(net "GND")
		)
		(pad "62" smd rect
			(at -2.050034 -11.474958 90)
			(size 0.519938 1.4986)
			(layers "F.Cu" "F.Mask" "F.Paste")
			(net "M_I_CPU0_ALERT_N")
		)
		(pad "63" smd rect
			(at -2.050034 -10.625074 90)
			(size 0.519938 1.4986)
			(layers "F.Cu" "F.Mask" "F.Paste")
			(net "GND")
		)
		(pad "64" smd rect
			(at -2.050034 -9.774936 90)
			(size 0.519938 1.4986)
			(layers "F.Cu" "F.Mask" "F.Paste")
			(net "M_I_CPU0_SA_CS_N<0>")
		)
		(pad "65" smd rect
			(at -2.050034 -8.925052 90)
			(size 0.519938 1.4986)
			(layers "F.Cu" "F.Mask" "F.Paste")
			(net "GND")
		)
		(pad "66" smd rect
			(at -2.050034 -8.074914 90)
			(size 0.519938 1.4986)
			(layers "F.Cu" "F.Mask" "F.Paste")
			(net "M_I_CPU0_SA_CA<0>")
		)
		(pad "67" smd rect
			(at -2.050034 -7.22503 90)
			(size 0.519938 1.4986)
			(layers "F.Cu" "F.Mask" "F.Paste")
			(net "GND")
		)
		(pad "68" smd rect
			(at -2.050034 -6.374892 90)
			(size 0.519938 1.4986)
			(layers "F.Cu" "F.Mask" "F.Paste")
			(net "M_I_CPU0_SA_CA<2>")
		)
		(pad "69" smd rect
			(at -2.050034 -5.525008 90)
			(size 0.519938 1.4986)
			(layers "F.Cu" "F.Mask" "F.Paste")
			(net "GND")
		)
		(pad "70" smd rect
			(at -2.050034 -4.675124 90)
			(size 0.519938 1.4986)
			(layers "F.Cu" "F.Mask" "F.Paste")
			(net "M_I_CPU0_SA_CA<4>")
		)
		(pad "71" smd rect
			(at -2.050034 -3.824986 90)
			(size 0.519938 1.4986)
			(layers "F.Cu" "F.Mask" "F.Paste")
			(net "GND")
		)
		(pad "72" smd rect
			(at -2.050034 -2.975102 90)
			(size 0.519938 1.4986)
			(layers "F.Cu" "F.Mask" "F.Paste")
			(net "M_I_CPU0_SA_CA<6>")
		)
		(pad "73" smd rect
			(at -2.050034 -2.124964 90)
			(size 0.519938 1.4986)
			(layers "F.Cu" "F.Mask" "F.Paste")
			(net "GND")
		)
		(pad "74" smd rect
			(at -2.050034 -1.27508 90)
			(size 0.519938 1.4986)
			(layers "F.Cu" "F.Mask" "F.Paste")
			(net "M_I_CPU0_SA_PAR")
		)
		(pad "75" smd rect
			(at -2.050034 -0.424942 90)
			(size 0.519938 1.4986)
			(layers "F.Cu" "F.Mask" "F.Paste")
			(net "GND")
		)
		(pad "76" smd rect
			(at -2.050034 5.525008 90)
			(size 0.519938 1.4986)
			(layers "F.Cu" "F.Mask" "F.Paste")
			(net "M_I_CPU0_SB_CA<0>")
		)
		(pad "77" smd rect
			(at -2.050034 6.374892 90)
			(size 0.519938 1.4986)
			(layers "F.Cu" "F.Mask" "F.Paste")
			(net "GND")
		)
		(pad "78" smd rect
			(at -2.050034 7.22503 90)
			(size 0.519938 1.4986)
			(layers "F.Cu" "F.Mask" "F.Paste")
			(net "M_I_CPU0_SB_CA<2>")
		)
		(pad "79" smd rect
			(at -2.050034 8.074914 90)
			(size 0.519938 1.4986)
			(layers "F.Cu" "F.Mask" "F.Paste")
			(net "GND")
		)
		(pad "80" smd rect
			(at -2.050034 8.925052 90)
			(size 0.519938 1.4986)
			(layers "F.Cu" "F.Mask" "F.Paste")
			(net "M_I_CPU0_SB_CA<4>")
		)
		(pad "81" smd rect
			(at -2.050034 9.774936 90)
			(size 0.519938 1.4986)
			(layers "F.Cu" "F.Mask" "F.Paste")
			(net "GND")
		)
		(pad "82" smd rect
			(at -2.050034 10.625074 90)
			(size 0.519938 1.4986)
			(layers "F.Cu" "F.Mask" "F.Paste")
			(net "M_I_CPU0_SB_CA<6>")
		)
		(pad "83" smd rect
			(at -2.050034 11.474958 90)
			(size 0.519938 1.4986)
			(layers "F.Cu" "F.Mask" "F.Paste")
			(net "GND")
		)
		(pad "84" smd rect
			(at -2.050034 12.325096 90)
			(size 0.519938 1.4986)
			(layers "F.Cu" "F.Mask" "F.Paste")
			(net "M_I_CPU0_SB_CS_N<0>")
		)
		(pad "85" smd rect
			(at -2.050034 13.17498 90)
			(size 0.519938 1.4986)
			(layers "F.Cu" "F.Mask" "F.Paste")
			(net "GND")
		)
		(pad "86" smd rect
			(at -2.050034 14.025118 90)
			(size 0.519938 1.4986)
			(layers "F.Cu" "F.Mask" "F.Paste")
			(net "M_I_CPU0_SA_RSP<0>")
		)
		(pad "87" smd rect
			(at -2.050034 14.875002 90)
			(size 0.519938 1.4986)
			(layers "F.Cu" "F.Mask" "F.Paste")
			(net "M_I_CPU0_SB_RSP<0>")
		)
		(pad "88" smd rect
			(at -2.050034 15.724886 90)
			(size 0.519938 1.4986)
			(layers "F.Cu" "F.Mask" "F.Paste")
			(net "GND")
		)
		(pad "89" smd rect
			(at -2.050034 16.575024 90)
			(size 0.519938 1.4986)
			(layers "F.Cu" "F.Mask" "F.Paste")
			(net "M_I_CPU0_SB_CB<4>")
		)
		(pad "90" smd rect
			(at -2.050034 17.424908 90)
			(size 0.519938 1.4986)
			(layers "F.Cu" "F.Mask" "F.Paste")
			(net "GND")
		)
		(pad "91" smd rect
			(at -2.050034 18.275046 90)
			(size 0.519938 1.4986)
			(layers "F.Cu" "F.Mask" "F.Paste")
			(net "M_I_CPU0_SB_CB<5>")
		)
		(pad "92" smd rect
			(at -2.050034 19.12493 90)
			(size 0.519938 1.4986)
			(layers "F.Cu" "F.Mask" "F.Paste")
			(net "GND")
		)
		(pad "93" smd rect
			(at -2.050034 19.975068 90)
			(size 0.519938 1.4986)
			(layers "F.Cu" "F.Mask" "F.Paste")
			(net "M_I_CPU0_SB_DQS_DP<9>")
		)
		(pad "94" smd rect
			(at -2.050034 20.824952 90)
			(size 0.519938 1.4986)
			(layers "F.Cu" "F.Mask" "F.Paste")
			(net "M_I_CPU0_SB_DQS_DN<9>")
		)
		(pad "95" smd rect
			(at -2.050034 21.67509 90)
			(size 0.519938 1.4986)
			(layers "F.Cu" "F.Mask" "F.Paste")
			(net "GND")
		)
		(pad "96" smd rect
			(at -2.050034 22.524974 90)
			(size 0.519938 1.4986)
			(layers "F.Cu" "F.Mask" "F.Paste")
			(net "M_I_CPU0_SB_CB<0>")
		)
		(pad "97" smd rect
			(at -2.050034 23.375112 90)
			(size 0.519938 1.4986)
			(layers "F.Cu" "F.Mask" "F.Paste")
			(net "GND")
		)
		(pad "98" smd rect
			(at -2.050034 24.224996 90)
			(size 0.519938 1.4986)
			(layers "F.Cu" "F.Mask" "F.Paste")
			(net "M_I_CPU0_SB_CB<1>")
		)
		(pad "99" smd rect
			(at -2.050034 25.07488 90)
			(size 0.519938 1.4986)
			(layers "F.Cu" "F.Mask" "F.Paste")
			(net "GND")
		)
		(pad "100" smd rect
			(at -2.050034 25.925018 90)
			(size 0.519938 1.4986)
			(layers "F.Cu" "F.Mask" "F.Paste")
			(net "M_I_CPU0_SB_DQ<0>")
		)
		(pad "101" smd rect
			(at -2.050034 26.774902 90)
			(size 0.519938 1.4986)
			(layers "F.Cu" "F.Mask" "F.Paste")
			(net "GND")
		)
		(pad "102" smd rect
			(at -2.050034 27.62504 90)
			(size 0.519938 1.4986)
			(layers "F.Cu" "F.Mask" "F.Paste")
			(net "M_I_CPU0_SB_DQ<1>")
		)
		(pad "103" smd rect
			(at -2.050034 28.474924 90)
			(size 0.519938 1.4986)
			(layers "F.Cu" "F.Mask" "F.Paste")
			(net "GND")
		)
		(pad "104" smd rect
			(at -2.050034 29.325062 90)
			(size 0.519938 1.4986)
			(layers "F.Cu" "F.Mask" "F.Paste")
			(net "M_I_CPU0_SB_DQS_DP<0>")
		)
		(pad "105" smd rect
			(at -2.050034 30.174946 90)
			(size 0.519938 1.4986)
			(layers "F.Cu" "F.Mask" "F.Paste")
			(net "M_I_CPU0_SB_DQS_DN<0>")
		)
		(pad "106" smd rect
			(at -2.050034 31.025084 90)
			(size 0.519938 1.4986)
			(layers "F.Cu" "F.Mask" "F.Paste")
			(net "GND")
		)
		(pad "107" smd rect
			(at -2.050034 31.874968 90)
			(size 0.519938 1.4986)
			(layers "F.Cu" "F.Mask" "F.Paste")
			(net "M_I_CPU0_SB_DQ<4>")
		)
		(pad "108" smd rect
			(at -2.050034 32.725106 90)
			(size 0.519938 1.4986)
			(layers "F.Cu" "F.Mask" "F.Paste")
			(net "GND")
		)
		(pad "109" smd rect
			(at -2.050034 33.57499 90)
			(size 0.519938 1.4986)
			(layers "F.Cu" "F.Mask" "F.Paste")
			(net "M_I_CPU0_SB_DQ<5>")
		)
		(pad "110" smd rect
			(at -2.050034 34.425128 90)
			(size 0.519938 1.4986)
			(layers "F.Cu" "F.Mask" "F.Paste")
			(net "GND")
		)
		(pad "111" smd rect
			(at -2.050034 35.275012 90)
			(size 0.519938 1.4986)
			(layers "F.Cu" "F.Mask" "F.Paste")
			(net "M_I_CPU0_SB_DQ<8>")
		)
		(pad "112" smd rect
			(at -2.050034 36.124896 90)
			(size 0.519938 1.4986)
			(layers "F.Cu" "F.Mask" "F.Paste")
			(net "GND")
		)
		(pad "113" smd rect
			(at -2.050034 36.975034 90)
			(size 0.519938 1.4986)
			(layers "F.Cu" "F.Mask" "F.Paste")
			(net "M_I_CPU0_SB_DQ<9>")
		)
		(pad "114" smd rect
			(at -2.050034 37.824918 90)
			(size 0.519938 1.4986)
			(layers "F.Cu" "F.Mask" "F.Paste")
			(net "GND")
		)
		(pad "115" smd rect
			(at -2.050034 38.675056 90)
			(size 0.519938 1.4986)
			(layers "F.Cu" "F.Mask" "F.Paste")
			(net "M_I_CPU0_SB_DQS_DP<1>")
		)
		(pad "116" smd rect
			(at -2.050034 39.52494 90)
			(size 0.519938 1.4986)
			(layers "F.Cu" "F.Mask" "F.Paste")
			(net "M_I_CPU0_SB_DQS_DN<1>")
		)
		(pad "117" smd rect
			(at -2.050034 40.375078 90)
			(size 0.519938 1.4986)
			(layers "F.Cu" "F.Mask" "F.Paste")
			(net "GND")
		)
		(pad "118" smd rect
			(at -2.050034 41.224962 90)
			(size 0.519938 1.4986)
			(layers "F.Cu" "F.Mask" "F.Paste")
			(net "M_I_CPU0_SB_DQ<12>")
		)
		(pad "119" smd rect
			(at -2.050034 42.0751 90)
			(size 0.519938 1.4986)
			(layers "F.Cu" "F.Mask" "F.Paste")
			(net "GND")
		)
		(pad "120" smd rect
			(at -2.050034 42.924984 90)
			(size 0.519938 1.4986)
			(layers "F.Cu" "F.Mask" "F.Paste")
			(net "M_I_CPU0_SB_DQ<13>")
		)
		(pad "121" smd rect
			(at -2.050034 43.775122 90)
			(size 0.519938 1.4986)
			(layers "F.Cu" "F.Mask" "F.Paste")
			(net "GND")
		)
		(pad "122" smd rect
			(at -2.050034 44.625006 90)
			(size 0.519938 1.4986)
			(layers "F.Cu" "F.Mask" "F.Paste")
			(net "M_I_CPU0_SB_DQ<16>")
		)
		(pad "123" smd rect
			(at -2.050034 45.47489 90)
			(size 0.519938 1.4986)
			(layers "F.Cu" "F.Mask" "F.Paste")
			(net "GND")
		)
		(pad "124" smd rect
			(at -2.050034 46.325028 90)
			(size 0.519938 1.4986)
			(layers "F.Cu" "F.Mask" "F.Paste")
			(net "M_I_CPU0_SB_DQ<17>")
		)
		(pad "125" smd rect
			(at -2.050034 47.174912 90)
			(size 0.519938 1.4986)
			(layers "F.Cu" "F.Mask" "F.Paste")
			(net "GND")
		)
		(pad "126" smd rect
			(at -2.050034 48.02505 90)
			(size 0.519938 1.4986)
			(layers "F.Cu" "F.Mask" "F.Paste")
			(net "M_I_CPU0_SB_DQS_DP<2>")
		)
		(pad "127" smd rect
			(at -2.050034 48.874934 90)
			(size 0.519938 1.4986)
			(layers "F.Cu" "F.Mask" "F.Paste")
			(net "M_I_CPU0_SB_DQS_DN<2>")
		)
		(pad "128" smd rect
			(at -2.050034 49.725072 90)
			(size 0.519938 1.4986)
			(layers "F.Cu" "F.Mask" "F.Paste")
			(net "GND")
		)
		(pad "129" smd rect
			(at -2.050034 50.574956 90)
			(size 0.519938 1.4986)
			(layers "F.Cu" "F.Mask" "F.Paste")
			(net "M_I_CPU0_SB_DQ<20>")
		)
		(pad "130" smd rect
			(at -2.050034 51.425094 90)
			(size 0.519938 1.4986)
			(layers "F.Cu" "F.Mask" "F.Paste")
			(net "GND")
		)
		(pad "131" smd rect
			(at -2.050034 52.274978 90)
			(size 0.519938 1.4986)
			(layers "F.Cu" "F.Mask" "F.Paste")
			(net "M_I_CPU0_SB_DQ<21>")
		)
		(pad "132" smd rect
			(at -2.050034 53.125116 90)
			(size 0.519938 1.4986)
			(layers "F.Cu" "F.Mask" "F.Paste")
			(net "GND")
		)
		(pad "133" smd rect
			(at -2.050034 53.975 90)
			(size 0.519938 1.4986)
			(layers "F.Cu" "F.Mask" "F.Paste")
			(net "M_I_CPU0_SB_DQ<24>")
		)
		(pad "134" smd rect
			(at -2.050034 54.824884 90)
			(size 0.519938 1.4986)
			(layers "F.Cu" "F.Mask" "F.Paste")
			(net "GND")
		)
		(pad "135" smd rect
			(at -2.050034 55.675022 90)
			(size 0.519938 1.4986)
			(layers "F.Cu" "F.Mask" "F.Paste")
			(net "M_I_CPU0_SB_DQ<25>")
		)
		(pad "136" smd rect
			(at -2.050034 56.524906 90)
			(size 0.519938 1.4986)
			(layers "F.Cu" "F.Mask" "F.Paste")
			(net "GND")
		)
		(pad "137" smd rect
			(at -2.050034 57.375044 90)
			(size 0.519938 1.4986)
			(layers "F.Cu" "F.Mask" "F.Paste")
			(net "M_I_CPU0_SB_DQS_DP<3>")
		)
		(pad "138" smd rect
			(at -2.050034 58.224928 90)
			(size 0.519938 1.4986)
			(layers "F.Cu" "F.Mask" "F.Paste")
			(net "M_I_CPU0_SB_DQS_DN<3>")
		)
		(pad "139" smd rect
			(at -2.050034 59.075066 90)
			(size 0.519938 1.4986)
			(layers "F.Cu" "F.Mask" "F.Paste")
			(net "GND")
		)
		(pad "140" smd rect
			(at -2.050034 59.92495 90)
			(size 0.519938 1.4986)
			(layers "F.Cu" "F.Mask" "F.Paste")
			(net "M_I_CPU0_SB_DQ<28>")
		)
		(pad "141" smd rect
			(at -2.050034 60.775088 90)
			(size 0.519938 1.4986)
			(layers "F.Cu" "F.Mask" "F.Paste")
			(net "GND")
		)
		(pad "142" smd rect
			(at -2.050034 61.624972 90)
			(size 0.519938 1.4986)
			(layers "F.Cu" "F.Mask" "F.Paste")
			(net "M_I_CPU0_SB_DQ<29>")
		)
		(pad "143" smd rect
			(at -2.050034 62.47511 90)
			(size 0.519938 1.4986)
			(layers "F.Cu" "F.Mask" "F.Paste")
			(net "GND")
		)
		(pad "144" smd rect
			(at -2.050034 63.324994 90)
			(size 0.519938 1.4986)
			(layers "F.Cu" "F.Mask" "F.Paste")
			(net "Net_2362")
		)
		(pad "145" smd rect
			(at 2.050034 -63.324994 90)
			(size 0.519938 1.4986)
			(layers "F.Cu" "F.Mask" "F.Paste")
			(net "P12V_MEM_CPU0")
		)
		(pad "146" smd rect
			(at 2.050034 -62.47511 90)
			(size 0.519938 1.4986)
			(layers "F.Cu" "F.Mask" "F.Paste")
			(net "P12V_MEM_CPU0")
		)
		(pad "147" smd rect
			(at 2.050034 -61.624972 90)
			(size 0.519938 1.4986)
			(layers "F.Cu" "F.Mask" "F.Paste")
			(net "PWRGD_CHI_CPU0_DIMM")
		)
		(pad "148" smd rect
			(at 2.050034 -60.775088 90)
			(size 0.519938 1.4986)
			(layers "F.Cu" "F.Mask" "F.Paste")
			(net "PD_CHI_CPU0_DIMM_SAA")
		)
		(pad "149" smd rect
			(at 2.050034 -59.92495 90)
			(size 0.519938 1.4986)
			(layers "F.Cu" "F.Mask" "F.Paste")
			(net "Net_2363")
		)
		(pad "150" smd rect
			(at 2.050034 -59.075066 90)
			(size 0.519938 1.4986)
			(layers "F.Cu" "F.Mask" "F.Paste")
			(net "Net_2364")
		)
		(pad "151" smd rect
			(at 2.050034 -58.224928 90)
			(size 0.519938 1.4986)
			(layers "F.Cu" "F.Mask" "F.Paste")
			(net "GND")
		)
		(pad "152" smd rect
			(at 2.050034 -57.375044 90)
			(size 0.519938 1.4986)
			(layers "F.Cu" "F.Mask" "F.Paste")
			(net "M_I_CPU0_SA_DQ<2>")
		)
		(pad "153" smd rect
			(at 2.050034 -56.524906 90)
			(size 0.519938 1.4986)
			(layers "F.Cu" "F.Mask" "F.Paste")
			(net "GND")
		)
		(pad "154" smd rect
			(at 2.050034 -55.675022 90)
			(size 0.519938 1.4986)
			(layers "F.Cu" "F.Mask" "F.Paste")
			(net "M_I_CPU0_SA_DQ<3>")
		)
		(pad "155" smd rect
			(at 2.050034 -54.824884 90)
			(size 0.519938 1.4986)
			(layers "F.Cu" "F.Mask" "F.Paste")
			(net "GND")
		)
		(pad "156" smd rect
			(at 2.050034 -53.975 90)
			(size 0.519938 1.4986)
			(layers "F.Cu" "F.Mask" "F.Paste")
			(net "M_I_CPU0_SA_DQS_DN<5>")
		)
		(pad "157" smd rect
			(at 2.050034 -53.125116 90)
			(size 0.519938 1.4986)
			(layers "F.Cu" "F.Mask" "F.Paste")
			(net "M_I_CPU0_SA_DQS_DP<5>")
		)
		(pad "158" smd rect
			(at 2.050034 -52.274978 90)
			(size 0.519938 1.4986)
			(layers "F.Cu" "F.Mask" "F.Paste")
			(net "GND")
		)
		(pad "159" smd rect
			(at 2.050034 -51.425094 90)
			(size 0.519938 1.4986)
			(layers "F.Cu" "F.Mask" "F.Paste")
			(net "M_I_CPU0_SA_DQ<6>")
		)
		(pad "160" smd rect
			(at 2.050034 -50.574956 90)
			(size 0.519938 1.4986)
			(layers "F.Cu" "F.Mask" "F.Paste")
			(net "GND")
		)
		(pad "161" smd rect
			(at 2.050034 -49.725072 90)
			(size 0.519938 1.4986)
			(layers "F.Cu" "F.Mask" "F.Paste")
			(net "M_I_CPU0_SA_DQ<7>")
		)
		(pad "162" smd rect
			(at 2.050034 -48.874934 90)
			(size 0.519938 1.4986)
			(layers "F.Cu" "F.Mask" "F.Paste")
			(net "GND")
		)
		(pad "163" smd rect
			(at 2.050034 -48.02505 90)
			(size 0.519938 1.4986)
			(layers "F.Cu" "F.Mask" "F.Paste")
			(net "M_I_CPU0_SA_DQ<10>")
		)
		(pad "164" smd rect
			(at 2.050034 -47.174912 90)
			(size 0.519938 1.4986)
			(layers "F.Cu" "F.Mask" "F.Paste")
			(net "GND")
		)
		(pad "165" smd rect
			(at 2.050034 -46.325028 90)
			(size 0.519938 1.4986)
			(layers "F.Cu" "F.Mask" "F.Paste")
			(net "M_I_CPU0_SA_DQ<11>")
		)
		(pad "166" smd rect
			(at 2.050034 -45.47489 90)
			(size 0.519938 1.4986)
			(layers "F.Cu" "F.Mask" "F.Paste")
			(net "GND")
		)
		(pad "167" smd rect
			(at 2.050034 -44.625006 90)
			(size 0.519938 1.4986)
			(layers "F.Cu" "F.Mask" "F.Paste")
			(net "M_I_CPU0_SA_DQS_DN<6>")
		)
		(pad "168" smd rect
			(at 2.050034 -43.775122 90)
			(size 0.519938 1.4986)
			(layers "F.Cu" "F.Mask" "F.Paste")
			(net "M_I_CPU0_SA_DQS_DP<6>")
		)
		(pad "169" smd rect
			(at 2.050034 -42.924984 90)
			(size 0.519938 1.4986)
			(layers "F.Cu" "F.Mask" "F.Paste")
			(net "GND")
		)
		(pad "170" smd rect
			(at 2.050034 -42.0751 90)
			(size 0.519938 1.4986)
			(layers "F.Cu" "F.Mask" "F.Paste")
			(net "M_I_CPU0_SA_DQ<14>")
		)
		(pad "171" smd rect
			(at 2.050034 -41.224962 90)
			(size 0.519938 1.4986)
			(layers "F.Cu" "F.Mask" "F.Paste")
			(net "GND")
		)
		(pad "172" smd rect
			(at 2.050034 -40.375078 90)
			(size 0.519938 1.4986)
			(layers "F.Cu" "F.Mask" "F.Paste")
			(net "M_I_CPU0_SA_DQ<15>")
		)
		(pad "173" smd rect
			(at 2.050034 -39.52494 90)
			(size 0.519938 1.4986)
			(layers "F.Cu" "F.Mask" "F.Paste")
			(net "GND")
		)
		(pad "174" smd rect
			(at 2.050034 -38.675056 90)
			(size 0.519938 1.4986)
			(layers "F.Cu" "F.Mask" "F.Paste")
			(net "M_I_CPU0_SA_DQ<18>")
		)
		(pad "175" smd rect
			(at 2.050034 -37.824918 90)
			(size 0.519938 1.4986)
			(layers "F.Cu" "F.Mask" "F.Paste")
			(net "GND")
		)
		(pad "176" smd rect
			(at 2.050034 -36.975034 90)
			(size 0.519938 1.4986)
			(layers "F.Cu" "F.Mask" "F.Paste")
			(net "M_I_CPU0_SA_DQ<19>")
		)
		(pad "177" smd rect
			(at 2.050034 -36.124896 90)
			(size 0.519938 1.4986)
			(layers "F.Cu" "F.Mask" "F.Paste")
			(net "GND")
		)
		(pad "178" smd rect
			(at 2.050034 -35.275012 90)
			(size 0.519938 1.4986)
			(layers "F.Cu" "F.Mask" "F.Paste")
			(net "M_I_CPU0_SA_DQS_DN<7>")
		)
		(pad "179" smd rect
			(at 2.050034 -34.425128 90)
			(size 0.519938 1.4986)
			(layers "F.Cu" "F.Mask" "F.Paste")
			(net "M_I_CPU0_SA_DQS_DP<7>")
		)
		(pad "180" smd rect
			(at 2.050034 -33.57499 90)
			(size 0.519938 1.4986)
			(layers "F.Cu" "F.Mask" "F.Paste")
			(net "GND")
		)
		(pad "181" smd rect
			(at 2.050034 -32.725106 90)
			(size 0.519938 1.4986)
			(layers "F.Cu" "F.Mask" "F.Paste")
			(net "M_I_CPU0_SA_DQ<22>")
		)
		(pad "182" smd rect
			(at 2.050034 -31.874968 90)
			(size 0.519938 1.4986)
			(layers "F.Cu" "F.Mask" "F.Paste")
			(net "GND")
		)
		(pad "183" smd rect
			(at 2.050034 -31.025084 90)
			(size 0.519938 1.4986)
			(layers "F.Cu" "F.Mask" "F.Paste")
			(net "M_I_CPU0_SA_DQ<23>")
		)
		(pad "184" smd rect
			(at 2.050034 -30.174946 90)
			(size 0.519938 1.4986)
			(layers "F.Cu" "F.Mask" "F.Paste")
			(net "GND")
		)
		(pad "185" smd rect
			(at 2.050034 -29.325062 90)
			(size 0.519938 1.4986)
			(layers "F.Cu" "F.Mask" "F.Paste")
			(net "M_I_CPU0_SA_DQ<26>")
		)
		(pad "186" smd rect
			(at 2.050034 -28.474924 90)
			(size 0.519938 1.4986)
			(layers "F.Cu" "F.Mask" "F.Paste")
			(net "GND")
		)
		(pad "187" smd rect
			(at 2.050034 -27.62504 90)
			(size 0.519938 1.4986)
			(layers "F.Cu" "F.Mask" "F.Paste")
			(net "M_I_CPU0_SA_DQ<27>")
		)
		(pad "188" smd rect
			(at 2.050034 -26.774902 90)
			(size 0.519938 1.4986)
			(layers "F.Cu" "F.Mask" "F.Paste")
			(net "GND")
		)
		(pad "189" smd rect
			(at 2.050034 -25.925018 90)
			(size 0.519938 1.4986)
			(layers "F.Cu" "F.Mask" "F.Paste")
			(net "M_I_CPU0_SA_DQS_DN<8>")
		)
		(pad "190" smd rect
			(at 2.050034 -25.07488 90)
			(size 0.519938 1.4986)
			(layers "F.Cu" "F.Mask" "F.Paste")
			(net "M_I_CPU0_SA_DQS_DP<8>")
		)
		(pad "191" smd rect
			(at 2.050034 -24.224996 90)
			(size 0.519938 1.4986)
			(layers "F.Cu" "F.Mask" "F.Paste")
			(net "GND")
		)
		(pad "192" smd rect
			(at 2.050034 -23.375112 90)
			(size 0.519938 1.4986)
			(layers "F.Cu" "F.Mask" "F.Paste")
			(net "M_I_CPU0_SA_DQ<30>")
		)
		(pad "193" smd rect
			(at 2.050034 -22.524974 90)
			(size 0.519938 1.4986)
			(layers "F.Cu" "F.Mask" "F.Paste")
			(net "GND")
		)
		(pad "194" smd rect
			(at 2.050034 -21.67509 90)
			(size 0.519938 1.4986)
			(layers "F.Cu" "F.Mask" "F.Paste")
			(net "M_I_CPU0_SA_DQ<31>")
		)
		(pad "195" smd rect
			(at 2.050034 -20.824952 90)
			(size 0.519938 1.4986)
			(layers "F.Cu" "F.Mask" "F.Paste")
			(net "GND")
		)
		(pad "196" smd rect
			(at 2.050034 -19.975068 90)
			(size 0.519938 1.4986)
			(layers "F.Cu" "F.Mask" "F.Paste")
			(net "M_I_CPU0_SA_CB<2>")
		)
		(pad "197" smd rect
			(at 2.050034 -19.12493 90)
			(size 0.519938 1.4986)
			(layers "F.Cu" "F.Mask" "F.Paste")
			(net "GND")
		)
		(pad "198" smd rect
			(at 2.050034 -18.275046 90)
			(size 0.519938 1.4986)
			(layers "F.Cu" "F.Mask" "F.Paste")
			(net "M_I_CPU0_SA_CB<3>")
		)
		(pad "199" smd rect
			(at 2.050034 -17.424908 90)
			(size 0.519938 1.4986)
			(layers "F.Cu" "F.Mask" "F.Paste")
			(net "GND")
		)
		(pad "200" smd rect
			(at 2.050034 -16.575024 90)
			(size 0.519938 1.4986)
			(layers "F.Cu" "F.Mask" "F.Paste")
			(net "M_I_CPU0_SA_DQS_DN<9>")
		)
		(pad "201" smd rect
			(at 2.050034 -15.724886 90)
			(size 0.519938 1.4986)
			(layers "F.Cu" "F.Mask" "F.Paste")
			(net "M_I_CPU0_SA_DQS_DP<9>")
		)
		(pad "202" smd rect
			(at 2.050034 -14.875002 90)
			(size 0.519938 1.4986)
			(layers "F.Cu" "F.Mask" "F.Paste")
			(net "GND")
		)
		(pad "203" smd rect
			(at 2.050034 -14.025118 90)
			(size 0.519938 1.4986)
			(layers "F.Cu" "F.Mask" "F.Paste")
			(net "M_I_CPU0_SA_CB<6>")
		)
		(pad "204" smd rect
			(at 2.050034 -13.17498 90)
			(size 0.519938 1.4986)
			(layers "F.Cu" "F.Mask" "F.Paste")
			(net "GND")
		)
		(pad "205" smd rect
			(at 2.050034 -12.325096 90)
			(size 0.519938 1.4986)
			(layers "F.Cu" "F.Mask" "F.Paste")
			(net "M_I_CPU0_SA_CB<7>")
		)
		(pad "206" smd rect
			(at 2.050034 -11.474958 90)
			(size 0.519938 1.4986)
			(layers "F.Cu" "F.Mask" "F.Paste")
			(net "GND")
		)
		(pad "207" smd rect
			(at 2.050034 -10.625074 90)
			(size 0.519938 1.4986)
			(layers "F.Cu" "F.Mask" "F.Paste")
			(net "M_I_CPU0_RESET_N")
		)
		(pad "208" smd rect
			(at 2.050034 -9.774936 90)
			(size 0.519938 1.4986)
			(layers "F.Cu" "F.Mask" "F.Paste")
			(net "GND")
		)
		(pad "209" smd rect
			(at 2.050034 -8.925052 90)
			(size 0.519938 1.4986)
			(layers "F.Cu" "F.Mask" "F.Paste")
			(net "M_I_CPU0_SA_CS_N<1>")
		)
		(pad "210" smd rect
			(at 2.050034 -8.074914 90)
			(size 0.519938 1.4986)
			(layers "F.Cu" "F.Mask" "F.Paste")
			(net "GND")
		)
		(pad "211" smd rect
			(at 2.050034 -7.22503 90)
			(size 0.519938 1.4986)
			(layers "F.Cu" "F.Mask" "F.Paste")
			(net "M_I_CPU0_SA_CA<1>")
		)
		(pad "212" smd rect
			(at 2.050034 -6.374892 90)
			(size 0.519938 1.4986)
			(layers "F.Cu" "F.Mask" "F.Paste")
			(net "GND")
		)
		(pad "213" smd rect
			(at 2.050034 -5.525008 90)
			(size 0.519938 1.4986)
			(layers "F.Cu" "F.Mask" "F.Paste")
			(net "M_I_CPU0_SA_CA<3>")
		)
		(pad "214" smd rect
			(at 2.050034 -4.675124 90)
			(size 0.519938 1.4986)
			(layers "F.Cu" "F.Mask" "F.Paste")
			(net "GND")
		)
		(pad "215" smd rect
			(at 2.050034 -3.824986 90)
			(size 0.519938 1.4986)
			(layers "F.Cu" "F.Mask" "F.Paste")
			(net "M_I_CPU0_SA_CA<5>")
		)
		(pad "216" smd rect
			(at 2.050034 -2.975102 90)
			(size 0.519938 1.4986)
			(layers "F.Cu" "F.Mask" "F.Paste")
			(net "GND")
		)
		(pad "217" smd rect
			(at 2.050034 -2.124964 90)
			(size 0.519938 1.4986)
			(layers "F.Cu" "F.Mask" "F.Paste")
			(net "M_I_CPU0_CLK_DP<0>")
		)
		(pad "218" smd rect
			(at 2.050034 -1.27508 90)
			(size 0.519938 1.4986)
			(layers "F.Cu" "F.Mask" "F.Paste")
			(net "M_I_CPU0_CLK_DN<0>")
		)
		(pad "219" smd rect
			(at 2.050034 -0.424942 90)
			(size 0.519938 1.4986)
			(layers "F.Cu" "F.Mask" "F.Paste")
			(net "GND")
		)
		(pad "220" smd rect
			(at 2.050034 5.525008 90)
			(size 0.519938 1.4986)
			(layers "F.Cu" "F.Mask" "F.Paste")
			(net "Net_2365")
		)
		(pad "221" smd rect
			(at 2.050034 6.374892 90)
			(size 0.519938 1.4986)
			(layers "F.Cu" "F.Mask" "F.Paste")
			(net "M_I_CPU0_SB_CA<1>")
		)
		(pad "222" smd rect
			(at 2.050034 7.22503 90)
			(size 0.519938 1.4986)
			(layers "F.Cu" "F.Mask" "F.Paste")
			(net "GND")
		)
		(pad "223" smd rect
			(at 2.050034 8.074914 90)
			(size 0.519938 1.4986)
			(layers "F.Cu" "F.Mask" "F.Paste")
			(net "M_I_CPU0_SB_CA<3>")
		)
		(pad "224" smd rect
			(at 2.050034 8.925052 90)
			(size 0.519938 1.4986)
			(layers "F.Cu" "F.Mask" "F.Paste")
			(net "GND")
		)
		(pad "225" smd rect
			(at 2.050034 9.774936 90)
			(size 0.519938 1.4986)
			(layers "F.Cu" "F.Mask" "F.Paste")
			(net "M_I_CPU0_SB_CA<5>")
		)
		(pad "226" smd rect
			(at 2.050034 10.625074 90)
			(size 0.519938 1.4986)
			(layers "F.Cu" "F.Mask" "F.Paste")
			(net "GND")
		)
		(pad "227" smd rect
			(at 2.050034 11.474958 90)
			(size 0.519938 1.4986)
			(layers "F.Cu" "F.Mask" "F.Paste")
			(net "M_I_CPU0_SB_PAR")
		)
		(pad "228" smd rect
			(at 2.050034 12.325096 90)
			(size 0.519938 1.4986)
			(layers "F.Cu" "F.Mask" "F.Paste")
			(net "GND")
		)
		(pad "229" smd rect
			(at 2.050034 13.17498 90)
			(size 0.519938 1.4986)
			(layers "F.Cu" "F.Mask" "F.Paste")
			(net "M_I_CPU0_SB_CS_N<1>")
		)
		(pad "230" smd rect
			(at 2.050034 14.025118 90)
			(size 0.519938 1.4986)
			(layers "F.Cu" "F.Mask" "F.Paste")
			(net "GND")
		)
		(pad "231" smd rect
			(at 2.050034 14.875002 90)
			(size 0.519938 1.4986)
			(layers "F.Cu" "F.Mask" "F.Paste")
			(net "Net_2366")
		)
		(pad "232" smd rect
			(at 2.050034 15.724886 90)
			(size 0.519938 1.4986)
			(layers "F.Cu" "F.Mask" "F.Paste")
			(net "Net_2367")
		)
		(pad "233" smd rect
			(at 2.050034 16.575024 90)
			(size 0.519938 1.4986)
			(layers "F.Cu" "F.Mask" "F.Paste")
			(net "GND")
		)
		(pad "234" smd rect
			(at 2.050034 17.424908 90)
			(size 0.519938 1.4986)
			(layers "F.Cu" "F.Mask" "F.Paste")
			(net "M_I_CPU0_SB_CB<6>")
		)
		(pad "235" smd rect
			(at 2.050034 18.275046 90)
			(size 0.519938 1.4986)
			(layers "F.Cu" "F.Mask" "F.Paste")
			(net "GND")
		)
		(pad "236" smd rect
			(at 2.050034 19.12493 90)
			(size 0.519938 1.4986)
			(layers "F.Cu" "F.Mask" "F.Paste")
			(net "M_I_CPU0_SB_CB<7>")
		)
		(pad "237" smd rect
			(at 2.050034 19.975068 90)
			(size 0.519938 1.4986)
			(layers "F.Cu" "F.Mask" "F.Paste")
			(net "GND")
		)
		(pad "238" smd rect
			(at 2.050034 20.824952 90)
			(size 0.519938 1.4986)
			(layers "F.Cu" "F.Mask" "F.Paste")
			(net "M_I_CPU0_SB_DQS_DN<4>")
		)
		(pad "239" smd rect
			(at 2.050034 21.67509 90)
			(size 0.519938 1.4986)
			(layers "F.Cu" "F.Mask" "F.Paste")
			(net "M_I_CPU0_SB_DQS_DP<4>")
		)
		(pad "240" smd rect
			(at 2.050034 22.524974 90)
			(size 0.519938 1.4986)
			(layers "F.Cu" "F.Mask" "F.Paste")
			(net "GND")
		)
		(pad "241" smd rect
			(at 2.050034 23.375112 90)
			(size 0.519938 1.4986)
			(layers "F.Cu" "F.Mask" "F.Paste")
			(net "M_I_CPU0_SB_CB<2>")
		)
		(pad "242" smd rect
			(at 2.050034 24.224996 90)
			(size 0.519938 1.4986)
			(layers "F.Cu" "F.Mask" "F.Paste")
			(net "GND")
		)
		(pad "243" smd rect
			(at 2.050034 25.07488 90)
			(size 0.519938 1.4986)
			(layers "F.Cu" "F.Mask" "F.Paste")
			(net "M_I_CPU0_SB_CB<3>")
		)
		(pad "244" smd rect
			(at 2.050034 25.925018 90)
			(size 0.519938 1.4986)
			(layers "F.Cu" "F.Mask" "F.Paste")
			(net "GND")
		)
		(pad "245" smd rect
			(at 2.050034 26.774902 90)
			(size 0.519938 1.4986)
			(layers "F.Cu" "F.Mask" "F.Paste")
			(net "M_I_CPU0_SB_DQ<2>")
		)
		(pad "246" smd rect
			(at 2.050034 27.62504 90)
			(size 0.519938 1.4986)
			(layers "F.Cu" "F.Mask" "F.Paste")
			(net "GND")
		)
		(pad "247" smd rect
			(at 2.050034 28.474924 90)
			(size 0.519938 1.4986)
			(layers "F.Cu" "F.Mask" "F.Paste")
			(net "M_I_CPU0_SB_DQ<3>")
		)
		(pad "248" smd rect
			(at 2.050034 29.325062 90)
			(size 0.519938 1.4986)
			(layers "F.Cu" "F.Mask" "F.Paste")
			(net "GND")
		)
		(pad "249" smd rect
			(at 2.050034 30.174946 90)
			(size 0.519938 1.4986)
			(layers "F.Cu" "F.Mask" "F.Paste")
			(net "M_I_CPU0_SB_DQS_DN<5>")
		)
		(pad "250" smd rect
			(at 2.050034 31.025084 90)
			(size 0.519938 1.4986)
			(layers "F.Cu" "F.Mask" "F.Paste")
			(net "M_I_CPU0_SB_DQS_DP<5>")
		)
		(pad "251" smd rect
			(at 2.050034 31.874968 90)
			(size 0.519938 1.4986)
			(layers "F.Cu" "F.Mask" "F.Paste")
			(net "GND")
		)
		(pad "252" smd rect
			(at 2.050034 32.725106 90)
			(size 0.519938 1.4986)
			(layers "F.Cu" "F.Mask" "F.Paste")
			(net "M_I_CPU0_SB_DQ<6>")
		)
		(pad "253" smd rect
			(at 2.050034 33.57499 90)
			(size 0.519938 1.4986)
			(layers "F.Cu" "F.Mask" "F.Paste")
			(net "GND")
		)
		(pad "254" smd rect
			(at 2.050034 34.425128 90)
			(size 0.519938 1.4986)
			(layers "F.Cu" "F.Mask" "F.Paste")
			(net "M_I_CPU0_SB_DQ<7>")
		)
		(pad "255" smd rect
			(at 2.050034 35.275012 90)
			(size 0.519938 1.4986)
			(layers "F.Cu" "F.Mask" "F.Paste")
			(net "GND")
		)
		(pad "256" smd rect
			(at 2.050034 36.124896 90)
			(size 0.519938 1.4986)
			(layers "F.Cu" "F.Mask" "F.Paste")
			(net "M_I_CPU0_SB_DQ<10>")
		)
		(pad "257" smd rect
			(at 2.050034 36.975034 90)
			(size 0.519938 1.4986)
			(layers "F.Cu" "F.Mask" "F.Paste")
			(net "GND")
		)
		(pad "258" smd rect
			(at 2.050034 37.824918 90)
			(size 0.519938 1.4986)
			(layers "F.Cu" "F.Mask" "F.Paste")
			(net "M_I_CPU0_SB_DQ<11>")
		)
		(pad "259" smd rect
			(at 2.050034 38.675056 90)
			(size 0.519938 1.4986)
			(layers "F.Cu" "F.Mask" "F.Paste")
			(net "GND")
		)
		(pad "260" smd rect
			(at 2.050034 39.52494 90)
			(size 0.519938 1.4986)
			(layers "F.Cu" "F.Mask" "F.Paste")
			(net "M_I_CPU0_SB_DQS_DN<6>")
		)
		(pad "261" smd rect
			(at 2.050034 40.375078 90)
			(size 0.519938 1.4986)
			(layers "F.Cu" "F.Mask" "F.Paste")
			(net "M_I_CPU0_SB_DQS_DP<6>")
		)
		(pad "262" smd rect
			(at 2.050034 41.224962 90)
			(size 0.519938 1.4986)
			(layers "F.Cu" "F.Mask" "F.Paste")
			(net "GND")
		)
		(pad "263" smd rect
			(at 2.050034 42.0751 90)
			(size 0.519938 1.4986)
			(layers "F.Cu" "F.Mask" "F.Paste")
			(net "M_I_CPU0_SB_DQ<14>")
		)
		(pad "264" smd rect
			(at 2.050034 42.924984 90)
			(size 0.519938 1.4986)
			(layers "F.Cu" "F.Mask" "F.Paste")
			(net "GND")
		)
		(pad "265" smd rect
			(at 2.050034 43.775122 90)
			(size 0.519938 1.4986)
			(layers "F.Cu" "F.Mask" "F.Paste")
			(net "M_I_CPU0_SB_DQ<15>")
		)
		(pad "266" smd rect
			(at 2.050034 44.625006 90)
			(size 0.519938 1.4986)
			(layers "F.Cu" "F.Mask" "F.Paste")
			(net "GND")
		)
		(pad "267" smd rect
			(at 2.050034 45.47489 90)
			(size 0.519938 1.4986)
			(layers "F.Cu" "F.Mask" "F.Paste")
			(net "M_I_CPU0_SB_DQ<18>")
		)
		(pad "268" smd rect
			(at 2.050034 46.325028 90)
			(size 0.519938 1.4986)
			(layers "F.Cu" "F.Mask" "F.Paste")
			(net "GND")
		)
		(pad "269" smd rect
			(at 2.050034 47.174912 90)
			(size 0.519938 1.4986)
			(layers "F.Cu" "F.Mask" "F.Paste")
			(net "M_I_CPU0_SB_DQ<19>")
		)
		(pad "270" smd rect
			(at 2.050034 48.02505 90)
			(size 0.519938 1.4986)
			(layers "F.Cu" "F.Mask" "F.Paste")
			(net "GND")
		)
		(pad "271" smd rect
			(at 2.050034 48.874934 90)
			(size 0.519938 1.4986)
			(layers "F.Cu" "F.Mask" "F.Paste")
			(net "M_I_CPU0_SB_DQS_DN<7>")
		)
		(pad "272" smd rect
			(at 2.050034 49.725072 90)
			(size 0.519938 1.4986)
			(layers "F.Cu" "F.Mask" "F.Paste")
			(net "M_I_CPU0_SB_DQS_DP<7>")
		)
		(pad "273" smd rect
			(at 2.050034 50.574956 90)
			(size 0.519938 1.4986)
			(layers "F.Cu" "F.Mask" "F.Paste")
			(net "GND")
		)
		(pad "274" smd rect
			(at 2.050034 51.425094 90)
			(size 0.519938 1.4986)
			(layers "F.Cu" "F.Mask" "F.Paste")
			(net "M_I_CPU0_SB_DQ<22>")
		)
		(pad "275" smd rect
			(at 2.050034 52.274978 90)
			(size 0.519938 1.4986)
			(layers "F.Cu" "F.Mask" "F.Paste")
			(net "GND")
		)
		(pad "276" smd rect
			(at 2.050034 53.125116 90)
			(size 0.519938 1.4986)
			(layers "F.Cu" "F.Mask" "F.Paste")
			(net "M_I_CPU0_SB_DQ<23>")
		)
		(pad "277" smd rect
			(at 2.050034 53.975 90)
			(size 0.519938 1.4986)
			(layers "F.Cu" "F.Mask" "F.Paste")
			(net "GND")
		)
		(pad "278" smd rect
			(at 2.050034 54.824884 90)
			(size 0.519938 1.4986)
			(layers "F.Cu" "F.Mask" "F.Paste")
			(net "M_I_CPU0_SB_DQ<26>")
		)
		(pad "279" smd rect
			(at 2.050034 55.675022 90)
			(size 0.519938 1.4986)
			(layers "F.Cu" "F.Mask" "F.Paste")
			(net "GND")
		)
		(pad "280" smd rect
			(at 2.050034 56.524906 90)
			(size 0.519938 1.4986)
			(layers "F.Cu" "F.Mask" "F.Paste")
			(net "M_I_CPU0_SB_DQ<27>")
		)
		(pad "281" smd rect
			(at 2.050034 57.375044 90)
			(size 0.519938 1.4986)
			(layers "F.Cu" "F.Mask" "F.Paste")
			(net "GND")
		)
		(pad "282" smd rect
			(at 2.050034 58.224928 90)
			(size 0.519938 1.4986)
			(layers "F.Cu" "F.Mask" "F.Paste")
			(net "M_I_CPU0_SB_DQS_DN<8>")
		)
		(pad "283" smd rect
			(at 2.050034 59.075066 90)
			(size 0.519938 1.4986)
			(layers "F.Cu" "F.Mask" "F.Paste")
			(net "M_I_CPU0_SB_DQS_DP<8>")
		)
		(pad "284" smd rect
			(at 2.050034 59.92495 90)
			(size 0.519938 1.4986)
			(layers "F.Cu" "F.Mask" "F.Paste")
			(net "GND")
		)
		(pad "285" smd rect
			(at 2.050034 60.775088 90)
			(size 0.519938 1.4986)
			(layers "F.Cu" "F.Mask" "F.Paste")
			(net "M_I_CPU0_SB_DQ<30>")
		)
		(pad "286" smd rect
			(at 2.050034 61.624972 90)
			(size 0.519938 1.4986)
			(layers "F.Cu" "F.Mask" "F.Paste")
			(net "GND")
		)
		(pad "287" smd rect
			(at 2.050034 62.47511 90)
			(size 0.519938 1.4986)
			(layers "F.Cu" "F.Mask" "F.Paste")
			(net "M_I_CPU0_SB_DQ<31>")
		)
		(pad "288" smd rect
			(at 2.050034 63.324994 90)
			(size 0.519938 1.4986)
			(layers "F.Cu" "F.Mask" "F.Paste")
			(net "GND")
		)
		(pad "G1" thru_hole oval
			(at 0 -68.97497 90)
			(size 1.7272 3.4798)
			(drill oval 1.2192 2.4638)
			(layers "*.Cu" "*.Mask")
			(remove_unused_layers no)
			(net "GND")
			(clearance 0.127)
			(thermal_gap 0.127)
		)
		(pad "G2" thru_hole oval
			(at 0 3.875024 90)
			(size 1.7272 3.4798)
			(drill oval 1.2192 2.4638)
			(layers "*.Cu" "*.Mask")
			(remove_unused_layers no)
			(net "GND")
			(clearance 0.127)
			(thermal_gap 0.127)
		)
		(pad "G3" thru_hole oval
			(at 0 68.97497 90)
			(size 1.7272 3.4798)
			(drill oval 1.2192 2.4638)
			(layers "*.Cu" "*.Mask")
			(remove_unused_layers no)
			(net "GND")
			(clearance 0.127)
			(thermal_gap 0.127)
		)
	)
	(footprint ""
		(layer "F.Cu")
		(at 57.88914 -400.755612)
		(property "Reference" "C7037"
			(at -5.0038 4.043172 0)
			(unlocked yes)
			(layer "F.SilkS")
			(effects
				(font
					(size 0.7874 0.5842)
					(thickness 0.1524)
				)
				(justify left)
			)
		)
		(property "Value" ""
			(at 0 0 0)
			(layer "F.Fab")
			(effects
				(font
					(size 1.27 1.27)
				)
			)
		)
		(duplicate_pad_numbers_are_jumpers no)
		(fp_line
			(start -4.84378 -2.150618)
			(end -4.842256 2.163064)
			(stroke
				(width 0.1524)
				(type default)
			)
			(layer "F.SilkS")
		)
		(fp_line
			(start -4.84378 -2.150618)
			(end -4.53898 -2.150618)
			(stroke
				(width 0.1524)
				(type default)
			)
			(layer "F.SilkS")
		)
		(fp_line
			(start -4.83108 2.150364)
			(end -4.447794 2.149348)
			(stroke
				(width 0.1524)
				(type default)
			)
			(layer "F.SilkS")
		)
		(fp_line
			(start -4.69138 -2.150618)
			(end -4.692396 2.161032)
			(stroke
				(width 0.1524)
				(type default)
			)
			(layer "F.SilkS")
		)
		(fp_line
			(start -4.53898 -2.150618)
			(end -4.539742 2.152142)
			(stroke
				(width 0.1524)
				(type default)
			)
			(layer "F.SilkS")
		)
		(fp_line
			(start -4.53898 -2.15011)
			(end 4.53898 -2.15011)
			(stroke
				(width 0.1524)
				(type default)
			)
			(layer "F.SilkS")
		)
		(fp_line
			(start -4.53898 2.15011)
			(end -4.53898 -2.15011)
			(stroke
				(width 0.1524)
				(type default)
			)
			(layer "F.SilkS")
		)
		(fp_line
			(start 4.53898 -2.15011)
			(end 4.53898 2.15011)
			(stroke
				(width 0.1524)
				(type default)
			)
			(layer "F.SilkS")
		)
		(fp_line
			(start 4.53898 2.15011)
			(end -4.53898 2.15011)
			(stroke
				(width 0.1524)
				(type default)
			)
			(layer "F.SilkS")
		)
		(fp_line
			(start -3.64998 -2.15011)
			(end 3.64998 -2.15011)
			(stroke
				(width 0.1)
				(type default)
			)
			(layer "F.Fab")
		)
		(fp_line
			(start -3.64998 2.15011)
			(end -3.64998 -2.15011)
			(stroke
				(width 0.1)
				(type default)
			)
			(layer "F.Fab")
		)
		(fp_line
			(start 3.64998 -2.15011)
			(end 3.64998 2.15011)
			(stroke
				(width 0.1)
				(type default)
			)
			(layer "F.Fab")
		)
		(fp_line
			(start 3.64998 2.15011)
			(end -3.64998 2.15011)
			(stroke
				(width 0.1)
				(type default)
			)
			(layer "F.Fab")
		)
		(fp_text user "+"
			(at -4.754372 2.619502 0)
			(unlocked yes)
			(layer "F.SilkS")
			(effects
				(font
					(size 1.905 1.4224)
					(thickness 0.1524)
				)
				(justify left)
			)
		)
		(fp_text user "-"
			(at 3.096514 -2.753868 0)
			(unlocked yes)
			(layer "F.SilkS")
			(effects
				(font
					(size 1.905 1.4224)
					(thickness 0.1524)
				)
				(justify left)
			)
		)
		(fp_text user "+"
			(at -6.214872 -0.337058 0)
			(unlocked yes)
			(layer "F.Fab")
			(effects
				(font
					(size 1.905 1.4224)
					(thickness 0.1524)
				)
				(justify left)
			)
		)
		(fp_text user "-"
			(at 4.313174 -0.094488 0)
			(unlocked yes)
			(layer "F.Fab")
			(effects
				(font
					(size 1.905 1.4224)
					(thickness 0.1524)
				)
				(justify left)
			)
		)
		(pad "1" smd rect
			(at -3.199892 0)
			(size 2.413 2.8194)
			(layers "F.Cu" "F.Mask" "F.Paste")
			(net "P0V9_CPU1_RT_2D")
		)
		(pad "2" smd rect
			(at 3.199892 0)
			(size 2.413 2.8194)
			(layers "F.Cu" "F.Mask" "F.Paste")
			(net "GND")
		)
	)
	(footprint ""
		(layer "F.Cu")
		(at 257.242056 -124.115068 180)
		(property "Reference" "R3707"
			(at 0 0 180)
			(layer "F.SilkS")
			(hide yes)
			(effects
				(font
					(size 1.27 1.27)
				)
			)
		)
		(property "Value" ""
			(at 0 0 180)
			(layer "F.Fab")
			(effects
				(font
					(size 1.27 1.27)
				)
			)
		)
		(duplicate_pad_numbers_are_jumpers no)
		(fp_line
			(start 0.7874 0.4064)
			(end -0.7874 0.4064)
			(stroke
				(width 0.1524)
				(type default)
			)
			(layer "F.SilkS")
		)
		(fp_line
			(start 0.7874 -0.4064)
			(end 0.7874 0.4064)
			(stroke
				(width 0.1524)
				(type default)
			)
			(layer "F.SilkS")
		)
		(fp_line
			(start -0.7874 0.4064)
			(end -0.7874 -0.4064)
			(stroke
				(width 0.1524)
				(type default)
			)
			(layer "F.SilkS")
		)
		(fp_line
			(start -0.7874 -0.4064)
			(end 0.7874 -0.4064)
			(stroke
				(width 0.1524)
				(type default)
			)
			(layer "F.SilkS")
		)
		(fp_line
			(start 0.67945 0.3048)
			(end 0.120396 0.3048)
			(stroke
				(width 0.1)
				(type default)
			)
			(layer "F.Fab")
		)
		(fp_line
			(start 0.67945 -0.3048)
			(end 0.67945 0.3048)
			(stroke
				(width 0.1)
				(type default)
			)
			(layer "F.Fab")
		)
		(fp_line
			(start 0.12065 -0.2794)
			(end 0.12065 -0.3048)
			(stroke
				(width 0.1)
				(type default)
			)
			(layer "F.Fab")
		)
		(fp_line
			(start 0.12065 -0.3048)
			(end 0.67945 -0.3048)
			(stroke
				(width 0.1)
				(type default)
			)
			(layer "F.Fab")
		)
		(fp_line
			(start 0.120396 0.3048)
			(end 0.120396 0.2794)
			(stroke
				(width 0.1)
				(type default)
			)
			(layer "F.Fab")
		)
		(fp_line
			(start 0.120396 0.2794)
			(end -0.12065 0.2794)
			(stroke
				(width 0.1)
				(type default)
			)
			(layer "F.Fab")
		)
		(fp_line
			(start -0.12065 0.3048)
			(end -0.67945 0.3048)
			(stroke
				(width 0.1)
				(type default)
			)
			(layer "F.Fab")
		)
		(fp_line
			(start -0.12065 0.2794)
			(end -0.12065 0.3048)
			(stroke
				(width 0.1)
				(type default)
			)
			(layer "F.Fab")
		)
		(fp_line
			(start -0.12065 -0.2794)
			(end 0.12065 -0.2794)
			(stroke
				(width 0.1)
				(type default)
			)
			(layer "F.Fab")
		)
		(fp_line
			(start -0.12065 -0.305054)
			(end -0.12065 -0.2794)
			(stroke
				(width 0.1)
				(type default)
			)
			(layer "F.Fab")
		)
		(fp_line
			(start -0.67945 0.3048)
			(end -0.67945 -0.305054)
			(stroke
				(width 0.1)
				(type default)
			)
			(layer "F.Fab")
		)
		(fp_line
			(start -0.67945 -0.305054)
			(end -0.12065 -0.305054)
			(stroke
				(width 0.1)
				(type default)
			)
			(layer "F.Fab")
		)
		(pad "1" smd circle
			(at -0.40005 0 180)
			(size 0 0)
			(layers "F.Cu" "F.Mask" "F.Paste")
			(net "PCA9548_PCIE0_ADDR1")
		)
		(pad "2" smd circle
			(at 0.40005 0 180)
			(size 0 0)
			(layers "F.Cu" "F.Mask" "F.Paste")
			(net "GND")
		)
	)
	(footprint ""
		(layer "F.Cu")
		(at 368.0079 -180.77561)
		(property "Reference" "PC178"
			(at 0 0 0)
			(layer "F.SilkS")
			(hide yes)
			(effects
				(font
					(size 1.27 1.27)
				)
			)
		)
		(property "Value" ""
			(at 0 0 0)
			(layer "F.Fab")
			(effects
				(font
					(size 1.27 1.27)
				)
			)
		)
		(duplicate_pad_numbers_are_jumpers no)
		(fp_line
			(start -0.7874 -0.4064)
			(end 0.7874 -0.4064)
			(stroke
				(width 0.1524)
				(type default)
			)
			(layer "F.SilkS")
		)
		(fp_line
			(start -0.7874 0.4064)
			(end -0.7874 -0.4064)
			(stroke
				(width 0.1524)
				(type default)
			)
			(layer "F.SilkS")
		)
		(fp_line
			(start 0.7874 -0.4064)
			(end 0.7874 0.4064)
			(stroke
				(width 0.1524)
				(type default)
			)
			(layer "F.SilkS")
		)
		(fp_line
			(start 0.7874 0.4064)
			(end -0.7874 0.4064)
			(stroke
				(width 0.1524)
				(type default)
			)
			(layer "F.SilkS")
		)
		(fp_line
			(start -0.67945 -0.305054)
			(end -0.12065 -0.305054)
			(stroke
				(width 0.1)
				(type default)
			)
			(layer "F.Fab")
		)
		(fp_line
			(start -0.67945 0.3048)
			(end -0.67945 -0.305054)
			(stroke
				(width 0.1)
				(type default)
			)
			(layer "F.Fab")
		)
		(fp_line
			(start -0.12065 -0.305054)
			(end -0.12065 -0.2794)
			(stroke
				(width 0.1)
				(type default)
			)
			(layer "F.Fab")
		)
		(fp_line
			(start -0.12065 -0.2794)
			(end 0.12065 -0.2794)
			(stroke
				(width 0.1)
				(type default)
			)
			(layer "F.Fab")
		)
		(fp_line
			(start -0.12065 0.2794)
			(end -0.12065 0.3048)
			(stroke
				(width 0.1)
				(type default)
			)
			(layer "F.Fab")
		)
		(fp_line
			(start -0.12065 0.3048)
			(end -0.67945 0.3048)
			(stroke
				(width 0.1)
				(type default)
			)
			(layer "F.Fab")
		)
		(fp_line
			(start 0.120396 0.2794)
			(end -0.12065 0.2794)
			(stroke
				(width 0.1)
				(type default)
			)
			(layer "F.Fab")
		)
		(fp_line
			(start 0.120396 0.3048)
			(end 0.120396 0.2794)
			(stroke
				(width 0.1)
				(type default)
			)
			(layer "F.Fab")
		)
		(fp_line
			(start 0.12065 -0.3048)
			(end 0.67945 -0.3048)
			(stroke
				(width 0.1)
				(type default)
			)
			(layer "F.Fab")
		)
		(fp_line
			(start 0.12065 -0.2794)
			(end 0.12065 -0.3048)
			(stroke
				(width 0.1)
				(type default)
			)
			(layer "F.Fab")
		)
		(fp_line
			(start 0.67945 -0.3048)
			(end 0.67945 0.3048)
			(stroke
				(width 0.1)
				(type default)
			)
			(layer "F.Fab")
		)
		(fp_line
			(start 0.67945 0.3048)
			(end 0.120396 0.3048)
			(stroke
				(width 0.1)
				(type default)
			)
			(layer "F.Fab")
		)
		(pad "1" smd circle
			(at -0.40005 0)
			(size 0 0)
			(layers "F.Cu" "F.Mask" "F.Paste")
			(net "SW_PVDDCR_CPU0_P0_SW1")
		)
		(pad "2" smd circle
			(at 0.40005 0)
			(size 0 0)
			(layers "F.Cu" "F.Mask" "F.Paste")
			(net "SW_PVDDCR_CPU0_P0_SW1_RC")
		)
	)
	(footprint ""
		(layer "F.Cu")
		(at 24.765 -367.919)
		(property "Reference" "R8249"
			(at 0 0 0)
			(layer "F.SilkS")
			(hide yes)
			(effects
				(font
					(size 1.27 1.27)
				)
			)
		)
		(property "Value" ""
			(at 0 0 0)
			(layer "F.Fab")
			(effects
				(font
					(size 1.27 1.27)
				)
			)
		)
		(duplicate_pad_numbers_are_jumpers no)
		(fp_line
			(start -0.7874 -0.4064)
			(end 0.7874 -0.4064)
			(stroke
				(width 0.1524)
				(type default)
			)
			(layer "F.SilkS")
		)
		(fp_line
			(start -0.7874 0.4064)
			(end -0.7874 -0.4064)
			(stroke
				(width 0.1524)
				(type default)
			)
			(layer "F.SilkS")
		)
		(fp_line
			(start 0.7874 -0.4064)
			(end 0.7874 0.4064)
			(stroke
				(width 0.1524)
				(type default)
			)
			(layer "F.SilkS")
		)
		(fp_line
			(start 0.7874 0.4064)
			(end -0.7874 0.4064)
			(stroke
				(width 0.1524)
				(type default)
			)
			(layer "F.SilkS")
		)
		(fp_line
			(start -0.67945 -0.305054)
			(end -0.12065 -0.305054)
			(stroke
				(width 0.1)
				(type default)
			)
			(layer "F.Fab")
		)
		(fp_line
			(start -0.67945 0.3048)
			(end -0.67945 -0.305054)
			(stroke
				(width 0.1)
				(type default)
			)
			(layer "F.Fab")
		)
		(fp_line
			(start -0.12065 -0.305054)
			(end -0.12065 -0.2794)
			(stroke
				(width 0.1)
				(type default)
			)
			(layer "F.Fab")
		)
		(fp_line
			(start -0.12065 -0.2794)
			(end 0.12065 -0.2794)
			(stroke
				(width 0.1)
				(type default)
			)
			(layer "F.Fab")
		)
		(fp_line
			(start -0.12065 0.2794)
			(end -0.12065 0.3048)
			(stroke
				(width 0.1)
				(type default)
			)
			(layer "F.Fab")
		)
		(fp_line
			(start -0.12065 0.3048)
			(end -0.67945 0.3048)
			(stroke
				(width 0.1)
				(type default)
			)
			(layer "F.Fab")
		)
		(fp_line
			(start 0.120396 0.2794)
			(end -0.12065 0.2794)
			(stroke
				(width 0.1)
				(type default)
			)
			(layer "F.Fab")
		)
		(fp_line
			(start 0.120396 0.3048)
			(end 0.120396 0.2794)
			(stroke
				(width 0.1)
				(type default)
			)
			(layer "F.Fab")
		)
		(fp_line
			(start 0.12065 -0.3048)
			(end 0.67945 -0.3048)
			(stroke
				(width 0.1)
				(type default)
			)
			(layer "F.Fab")
		)
		(fp_line
			(start 0.12065 -0.2794)
			(end 0.12065 -0.3048)
			(stroke
				(width 0.1)
				(type default)
			)
			(layer "F.Fab")
		)
		(fp_line
			(start 0.67945 -0.3048)
			(end 0.67945 0.3048)
			(stroke
				(width 0.1)
				(type default)
			)
			(layer "F.Fab")
		)
		(fp_line
			(start 0.67945 0.3048)
			(end 0.120396 0.3048)
			(stroke
				(width 0.1)
				(type default)
			)
			(layer "F.Fab")
		)
		(pad "1" smd circle
			(at -0.40005 0)
			(size 0 0)
			(layers "F.Cu" "F.Mask" "F.Paste")
			(net "SMB_SCM_2_R1_SDA")
		)
		(pad "2" smd circle
			(at 0.40005 0)
			(size 0 0)
			(layers "F.Cu" "F.Mask" "F.Paste")
			(net "SMB_DIO_PVDDCR_CPU1_P1_R")
		)
	)
	(footprint ""
		(layer "F.Cu")
		(at 117.931946 -408.517344 -90)
		(property "Reference" "C6696"
			(at 0 0 270)
			(layer "F.SilkS")
			(hide yes)
			(effects
				(font
					(size 1.27 1.27)
				)
			)
		)
		(property "Value" ""
			(at 0 0 270)
			(layer "F.Fab")
			(effects
				(font
					(size 1.27 1.27)
				)
			)
		)
		(duplicate_pad_numbers_are_jumpers no)
		(fp_line
			(start -0.299974 0.150114)
			(end -0.299974 -0.150114)
			(stroke
				(width 0.1)
				(type default)
			)
			(layer "F.Fab")
		)
		(fp_line
			(start 0.299974 0.150114)
			(end -0.299974 0.150114)
			(stroke
				(width 0.1)
				(type default)
			)
			(layer "F.Fab")
		)
		(fp_line
			(start -0.299974 -0.150114)
			(end 0.299974 -0.150114)
			(stroke
				(width 0.1)
				(type default)
			)
			(layer "F.Fab")
		)
		(fp_line
			(start 0.299974 -0.150114)
			(end 0.299974 0.150114)
			(stroke
				(width 0.1)
				(type default)
			)
			(layer "F.Fab")
		)
		(pad "1" smd rect
			(at -0.2667 0 270)
			(size 0.3048 0.381)
			(layers "F.Cu" "F.Mask" "F.Paste")
			(net "P5E_CPU1_P2_TX_BUF_C_DN<1>")
		)
		(pad "2" smd rect
			(at 0.2667 0 270)
			(size 0.3048 0.381)
			(layers "F.Cu" "F.Mask" "F.Paste")
			(net "P5E_CPU1_P2_TX_BUF_DN<1>")
		)
	)
	(footprint ""
		(layer "F.Cu")
		(at 193.03238 -355.924358 -90)
		(property "Reference" "PC520"
			(at 0 0 270)
			(layer "F.SilkS")
			(hide yes)
			(effects
				(font
					(size 1.27 1.27)
				)
			)
		)
		(property "Value" ""
			(at 0 0 270)
			(layer "F.Fab")
			(effects
				(font
					(size 1.27 1.27)
				)
			)
		)
		(duplicate_pad_numbers_are_jumpers no)
		(fp_line
			(start -0.7874 0.4064)
			(end -0.7874 -0.4064)
			(stroke
				(width 0.1524)
				(type default)
			)
			(layer "F.SilkS")
		)
		(fp_line
			(start 0.7874 0.4064)
			(end -0.7874 0.4064)
			(stroke
				(width 0.1524)
				(type default)
			)
			(layer "F.SilkS")
		)
		(fp_line
			(start -0.7874 -0.4064)
			(end 0.7874 -0.4064)
			(stroke
				(width 0.1524)
				(type default)
			)
			(layer "F.SilkS")
		)
		(fp_line
			(start 0.7874 -0.4064)
			(end 0.7874 0.4064)
			(stroke
				(width 0.1524)
				(type default)
			)
			(layer "F.SilkS")
		)
		(fp_line
			(start -0.67945 0.3048)
			(end -0.67945 -0.305054)
			(stroke
				(width 0.1)
				(type default)
			)
			(layer "F.Fab")
		)
		(fp_line
			(start -0.12065 0.3048)
			(end -0.67945 0.3048)
			(stroke
				(width 0.1)
				(type default)
			)
			(layer "F.Fab")
		)
		(fp_line
			(start 0.120396 0.3048)
			(end 0.120396 0.2794)
			(stroke
				(width 0.1)
				(type default)
			)
			(layer "F.Fab")
		)
		(fp_line
			(start 0.67945 0.3048)
			(end 0.120396 0.3048)
			(stroke
				(width 0.1)
				(type default)
			)
			(layer "F.Fab")
		)
		(fp_line
			(start -0.12065 0.2794)
			(end -0.12065 0.3048)
			(stroke
				(width 0.1)
				(type default)
			)
			(layer "F.Fab")
		)
		(fp_line
			(start 0.120396 0.2794)
			(end -0.12065 0.2794)
			(stroke
				(width 0.1)
				(type default)
			)
			(layer "F.Fab")
		)
		(fp_line
			(start -0.12065 -0.2794)
			(end 0.12065 -0.2794)
			(stroke
				(width 0.1)
				(type default)
			)
			(layer "F.Fab")
		)
		(fp_line
			(start 0.12065 -0.2794)
			(end 0.12065 -0.3048)
			(stroke
				(width 0.1)
				(type default)
			)
			(layer "F.Fab")
		)
		(fp_line
			(start 0.12065 -0.3048)
			(end 0.67945 -0.3048)
			(stroke
				(width 0.1)
				(type default)
			)
			(layer "F.Fab")
		)
		(fp_line
			(start 0.67945 -0.3048)
			(end 0.67945 0.3048)
			(stroke
				(width 0.1)
				(type default)
			)
			(layer "F.Fab")
		)
		(fp_line
			(start -0.67945 -0.305054)
			(end -0.12065 -0.305054)
			(stroke
				(width 0.1)
				(type default)
			)
			(layer "F.Fab")
		)
		(fp_line
			(start -0.12065 -0.305054)
			(end -0.12065 -0.2794)
			(stroke
				(width 0.1)
				(type default)
			)
			(layer "F.Fab")
		)
		(pad "1" smd circle
			(at -0.40005 0 270)
			(size 0 0)
			(layers "F.Cu" "F.Mask" "F.Paste")
			(net "SW_PVDD11_S3_P1_BOOT2_RC")
		)
		(pad "2" smd circle
			(at 0.40005 0 270)
			(size 0 0)
			(layers "F.Cu" "F.Mask" "F.Paste")
			(net "SW_PVDD11_S3_P1_PH2")
		)
	)
	(footprint ""
		(layer "F.Cu")
		(at 185.027316 -428.372016 90)
		(property "Reference" "R3443"
			(at 0 0 90)
			(layer "F.SilkS")
			(hide yes)
			(effects
				(font
					(size 1.27 1.27)
				)
			)
		)
		(property "Value" ""
			(at 0 0 90)
			(layer "F.Fab")
			(effects
				(font
					(size 1.27 1.27)
				)
			)
		)
		(duplicate_pad_numbers_are_jumpers no)
		(fp_line
			(start 0.7874 -0.4064)
			(end 0.7874 0.4064)
			(stroke
				(width 0.1524)
				(type default)
			)
			(layer "F.SilkS")
		)
		(fp_line
			(start -0.7874 -0.4064)
			(end 0.7874 -0.4064)
			(stroke
				(width 0.1524)
				(type default)
			)
			(layer "F.SilkS")
		)
		(fp_line
			(start 0.7874 0.4064)
			(end -0.7874 0.4064)
			(stroke
				(width 0.1524)
				(type default)
			)
			(layer "F.SilkS")
		)
		(fp_line
			(start -0.7874 0.4064)
			(end -0.7874 -0.4064)
			(stroke
				(width 0.1524)
				(type default)
			)
			(layer "F.SilkS")
		)
		(fp_line
			(start -0.12065 -0.305054)
			(end -0.12065 -0.2794)
			(stroke
				(width 0.1)
				(type default)
			)
			(layer "F.Fab")
		)
		(fp_line
			(start -0.67945 -0.305054)
			(end -0.12065 -0.305054)
			(stroke
				(width 0.1)
				(type default)
			)
			(layer "F.Fab")
		)
		(fp_line
			(start 0.67945 -0.3048)
			(end 0.67945 0.3048)
			(stroke
				(width 0.1)
				(type default)
			)
			(layer "F.Fab")
		)
		(fp_line
			(start 0.12065 -0.3048)
			(end 0.67945 -0.3048)
			(stroke
				(width 0.1)
				(type default)
			)
			(layer "F.Fab")
		)
		(fp_line
			(start 0.12065 -0.2794)
			(end 0.12065 -0.3048)
			(stroke
				(width 0.1)
				(type default)
			)
			(layer "F.Fab")
		)
		(fp_line
			(start -0.12065 -0.2794)
			(end 0.12065 -0.2794)
			(stroke
				(width 0.1)
				(type default)
			)
			(layer "F.Fab")
		)
		(fp_line
			(start 0.120396 0.2794)
			(end -0.12065 0.2794)
			(stroke
				(width 0.1)
				(type default)
			)
			(layer "F.Fab")
		)
		(fp_line
			(start -0.12065 0.2794)
			(end -0.12065 0.3048)
			(stroke
				(width 0.1)
				(type default)
			)
			(layer "F.Fab")
		)
		(fp_line
			(start 0.67945 0.3048)
			(end 0.120396 0.3048)
			(stroke
				(width 0.1)
				(type default)
			)
			(layer "F.Fab")
		)
		(fp_line
			(start 0.120396 0.3048)
			(end 0.120396 0.2794)
			(stroke
				(width 0.1)
				(type default)
			)
			(layer "F.Fab")
		)
		(fp_line
			(start -0.12065 0.3048)
			(end -0.67945 0.3048)
			(stroke
				(width 0.1)
				(type default)
			)
			(layer "F.Fab")
		)
		(fp_line
			(start -0.67945 0.3048)
			(end -0.67945 -0.305054)
			(stroke
				(width 0.1)
				(type default)
			)
			(layer "F.Fab")
		)
		(pad "1" smd circle
			(at -0.40005 0 90)
			(size 0 0)
			(layers "F.Cu" "F.Mask" "F.Paste")
			(net "GPU_PEX_STRAP1")
		)
		(pad "2" smd circle
			(at 0.40005 0 90)
			(size 0 0)
			(layers "F.Cu" "F.Mask" "F.Paste")
			(net "GND")
		)
	)
	(footprint ""
		(layer "F.Cu")
		(at 188.28258 -29.758386 -90)
		(property "Reference" "PR4003"
			(at 0 0 270)
			(layer "F.SilkS")
			(hide yes)
			(effects
				(font
					(size 1.27 1.27)
				)
			)
		)
		(property "Value" ""
			(at 0 0 270)
			(layer "F.Fab")
			(effects
				(font
					(size 1.27 1.27)
				)
			)
		)
		(duplicate_pad_numbers_are_jumpers no)
		(fp_line
			(start -0.7874 0.4064)
			(end -0.7874 -0.4064)
			(stroke
				(width 0.1524)
				(type default)
			)
			(layer "F.SilkS")
		)
		(fp_line
			(start 0.7874 0.4064)
			(end -0.7874 0.4064)
			(stroke
				(width 0.1524)
				(type default)
			)
			(layer "F.SilkS")
		)
		(fp_line
			(start -0.7874 -0.4064)
			(end 0.7874 -0.4064)
			(stroke
				(width 0.1524)
				(type default)
			)
			(layer "F.SilkS")
		)
		(fp_line
			(start 0.7874 -0.4064)
			(end 0.7874 0.4064)
			(stroke
				(width 0.1524)
				(type default)
			)
			(layer "F.SilkS")
		)
		(fp_line
			(start -0.67945 0.3048)
			(end -0.67945 -0.305054)
			(stroke
				(width 0.1)
				(type default)
			)
			(layer "F.Fab")
		)
		(fp_line
			(start -0.12065 0.3048)
			(end -0.67945 0.3048)
			(stroke
				(width 0.1)
				(type default)
			)
			(layer "F.Fab")
		)
		(fp_line
			(start 0.120396 0.3048)
			(end 0.120396 0.2794)
			(stroke
				(width 0.1)
				(type default)
			)
			(layer "F.Fab")
		)
		(fp_line
			(start 0.67945 0.3048)
			(end 0.120396 0.3048)
			(stroke
				(width 0.1)
				(type default)
			)
			(layer "F.Fab")
		)
		(fp_line
			(start -0.12065 0.2794)
			(end -0.12065 0.3048)
			(stroke
				(width 0.1)
				(type default)
			)
			(layer "F.Fab")
		)
		(fp_line
			(start 0.120396 0.2794)
			(end -0.12065 0.2794)
			(stroke
				(width 0.1)
				(type default)
			)
			(layer "F.Fab")
		)
		(fp_line
			(start -0.12065 -0.2794)
			(end 0.12065 -0.2794)
			(stroke
				(width 0.1)
				(type default)
			)
			(layer "F.Fab")
		)
		(fp_line
			(start 0.12065 -0.2794)
			(end 0.12065 -0.3048)
			(stroke
				(width 0.1)
				(type default)
			)
			(layer "F.Fab")
		)
		(fp_line
			(start 0.12065 -0.3048)
			(end 0.67945 -0.3048)
			(stroke
				(width 0.1)
				(type default)
			)
			(layer "F.Fab")
		)
		(fp_line
			(start 0.67945 -0.3048)
			(end 0.67945 0.3048)
			(stroke
				(width 0.1)
				(type default)
			)
			(layer "F.Fab")
		)
		(fp_line
			(start -0.67945 -0.305054)
			(end -0.12065 -0.305054)
			(stroke
				(width 0.1)
				(type default)
			)
			(layer "F.Fab")
		)
		(fp_line
			(start -0.12065 -0.305054)
			(end -0.12065 -0.2794)
			(stroke
				(width 0.1)
				(type default)
			)
			(layer "F.Fab")
		)
		(pad "1" smd circle
			(at -0.40005 0 270)
			(size 0 0)
			(layers "F.Cu" "F.Mask" "F.Paste")
			(net "P12V_AUX")
		)
		(pad "2" smd circle
			(at 0.40005 0 270)
			(size 0 0)
			(layers "F.Cu" "F.Mask" "F.Paste")
			(net "P12V_SCM_VCC")
		)
	)
	(footprint ""
		(layer "F.Cu")
		(at 441.430156 -397.435578 -90)
		(property "Reference" "PC6550_09P0_1"
			(at 0 0 270)
			(layer "F.SilkS")
			(hide yes)
			(effects
				(font
					(size 1.27 1.27)
				)
			)
		)
		(property "Value" ""
			(at 0 0 270)
			(layer "F.Fab")
			(effects
				(font
					(size 1.27 1.27)
				)
			)
		)
		(duplicate_pad_numbers_are_jumpers no)
		(fp_line
			(start -0.7874 0.4064)
			(end -0.7874 -0.4064)
			(stroke
				(width 0.1524)
				(type default)
			)
			(layer "F.SilkS")
		)
		(fp_line
			(start 0.7874 0.4064)
			(end -0.7874 0.4064)
			(stroke
				(width 0.1524)
				(type default)
			)
			(layer "F.SilkS")
		)
		(fp_line
			(start -0.7874 -0.4064)
			(end 0.7874 -0.4064)
			(stroke
				(width 0.1524)
				(type default)
			)
			(layer "F.SilkS")
		)
		(fp_line
			(start 0.7874 -0.4064)
			(end 0.7874 0.4064)
			(stroke
				(width 0.1524)
				(type default)
			)
			(layer "F.SilkS")
		)
		(fp_line
			(start -0.67945 0.3048)
			(end -0.67945 -0.305054)
			(stroke
				(width 0.1)
				(type default)
			)
			(layer "F.Fab")
		)
		(fp_line
			(start -0.12065 0.3048)
			(end -0.67945 0.3048)
			(stroke
				(width 0.1)
				(type default)
			)
			(layer "F.Fab")
		)
		(fp_line
			(start 0.120396 0.3048)
			(end 0.120396 0.2794)
			(stroke
				(width 0.1)
				(type default)
			)
			(layer "F.Fab")
		)
		(fp_line
			(start 0.67945 0.3048)
			(end 0.120396 0.3048)
			(stroke
				(width 0.1)
				(type default)
			)
			(layer "F.Fab")
		)
		(fp_line
			(start -0.12065 0.2794)
			(end -0.12065 0.3048)
			(stroke
				(width 0.1)
				(type default)
			)
			(layer "F.Fab")
		)
		(fp_line
			(start 0.120396 0.2794)
			(end -0.12065 0.2794)
			(stroke
				(width 0.1)
				(type default)
			)
			(layer "F.Fab")
		)
		(fp_line
			(start -0.12065 -0.2794)
			(end 0.12065 -0.2794)
			(stroke
				(width 0.1)
				(type default)
			)
			(layer "F.Fab")
		)
		(fp_line
			(start 0.12065 -0.2794)
			(end 0.12065 -0.3048)
			(stroke
				(width 0.1)
				(type default)
			)
			(layer "F.Fab")
		)
		(fp_line
			(start 0.12065 -0.3048)
			(end 0.67945 -0.3048)
			(stroke
				(width 0.1)
				(type default)
			)
			(layer "F.Fab")
		)
		(fp_line
			(start 0.67945 -0.3048)
			(end 0.67945 0.3048)
			(stroke
				(width 0.1)
				(type default)
			)
			(layer "F.Fab")
		)
		(fp_line
			(start -0.67945 -0.305054)
			(end -0.12065 -0.305054)
			(stroke
				(width 0.1)
				(type default)
			)
			(layer "F.Fab")
		)
		(fp_line
			(start -0.12065 -0.305054)
			(end -0.12065 -0.2794)
			(stroke
				(width 0.1)
				(type default)
			)
			(layer "F.Fab")
		)
		(pad "1" smd circle
			(at -0.40005 0 270)
			(size 0 0)
			(layers "F.Cu" "F.Mask" "F.Paste")
			(net "P0V9_RETIMER_CPU0_PVCC")
		)
		(pad "2" smd circle
			(at 0.40005 0 270)
			(size 0 0)
			(layers "F.Cu" "F.Mask" "F.Paste")
			(net "GND")
		)
	)
	(footprint ""
		(layer "F.Cu")
		(at 118.718584 -59.884056 180)
		(property "Reference" "R1734"
			(at 0 0 180)
			(layer "F.SilkS")
			(hide yes)
			(effects
				(font
					(size 1.27 1.27)
				)
			)
		)
		(property "Value" ""
			(at 0 0 180)
			(layer "F.Fab")
			(effects
				(font
					(size 1.27 1.27)
				)
			)
		)
		(duplicate_pad_numbers_are_jumpers no)
		(fp_line
			(start 0.7874 0.4064)
			(end -0.7874 0.4064)
			(stroke
				(width 0.1524)
				(type default)
			)
			(layer "F.SilkS")
		)
		(fp_line
			(start 0.7874 -0.4064)
			(end 0.7874 0.4064)
			(stroke
				(width 0.1524)
				(type default)
			)
			(layer "F.SilkS")
		)
		(fp_line
			(start -0.7874 0.4064)
			(end -0.7874 -0.4064)
			(stroke
				(width 0.1524)
				(type default)
			)
			(layer "F.SilkS")
		)
		(fp_line
			(start -0.7874 -0.4064)
			(end 0.7874 -0.4064)
			(stroke
				(width 0.1524)
				(type default)
			)
			(layer "F.SilkS")
		)
		(fp_line
			(start 0.67945 0.3048)
			(end 0.120396 0.3048)
			(stroke
				(width 0.1)
				(type default)
			)
			(layer "F.Fab")
		)
		(fp_line
			(start 0.67945 -0.3048)
			(end 0.67945 0.3048)
			(stroke
				(width 0.1)
				(type default)
			)
			(layer "F.Fab")
		)
		(fp_line
			(start 0.12065 -0.2794)
			(end 0.12065 -0.3048)
			(stroke
				(width 0.1)
				(type default)
			)
			(layer "F.Fab")
		)
		(fp_line
			(start 0.12065 -0.3048)
			(end 0.67945 -0.3048)
			(stroke
				(width 0.1)
				(type default)
			)
			(layer "F.Fab")
		)
		(fp_line
			(start 0.120396 0.3048)
			(end 0.120396 0.2794)
			(stroke
				(width 0.1)
				(type default)
			)
			(layer "F.Fab")
		)
		(fp_line
			(start 0.120396 0.2794)
			(end -0.12065 0.2794)
			(stroke
				(width 0.1)
				(type default)
			)
			(layer "F.Fab")
		)
		(fp_line
			(start -0.12065 0.3048)
			(end -0.67945 0.3048)
			(stroke
				(width 0.1)
				(type default)
			)
			(layer "F.Fab")
		)
		(fp_line
			(start -0.12065 0.2794)
			(end -0.12065 0.3048)
			(stroke
				(width 0.1)
				(type default)
			)
			(layer "F.Fab")
		)
		(fp_line
			(start -0.12065 -0.2794)
			(end 0.12065 -0.2794)
			(stroke
				(width 0.1)
				(type default)
			)
			(layer "F.Fab")
		)
		(fp_line
			(start -0.12065 -0.305054)
			(end -0.12065 -0.2794)
			(stroke
				(width 0.1)
				(type default)
			)
			(layer "F.Fab")
		)
		(fp_line
			(start -0.67945 0.3048)
			(end -0.67945 -0.305054)
			(stroke
				(width 0.1)
				(type default)
			)
			(layer "F.Fab")
		)
		(fp_line
			(start -0.67945 -0.305054)
			(end -0.12065 -0.305054)
			(stroke
				(width 0.1)
				(type default)
			)
			(layer "F.Fab")
		)
		(pad "1" smd circle
			(at -0.40005 0 180)
			(size 0 0)
			(layers "F.Cu" "F.Mask" "F.Paste")
			(net "P3V3_AUX")
		)
		(pad "2" smd circle
			(at 0.40005 0 180)
			(size 0 0)
			(layers "F.Cu" "F.Mask" "F.Paste")
			(net "JTAG_SCM_TCK")
		)
	)
	(footprint ""
		(layer "F.Cu")
		(at 144.4752 -75.557126 180)
		(property "Reference" "PC384"
			(at 0 0 180)
			(layer "F.SilkS")
			(hide yes)
			(effects
				(font
					(size 1.27 1.27)
				)
			)
		)
		(property "Value" ""
			(at 0 0 180)
			(layer "F.Fab")
			(effects
				(font
					(size 1.27 1.27)
				)
			)
		)
		(duplicate_pad_numbers_are_jumpers no)
		(fp_line
			(start 0.7874 0.4064)
			(end -0.7874 0.4064)
			(stroke
				(width 0.1524)
				(type default)
			)
			(layer "F.SilkS")
		)
		(fp_line
			(start 0.7874 -0.4064)
			(end 0.7874 0.4064)
			(stroke
				(width 0.1524)
				(type default)
			)
			(layer "F.SilkS")
		)
		(fp_line
			(start -0.7874 0.4064)
			(end -0.7874 -0.4064)
			(stroke
				(width 0.1524)
				(type default)
			)
			(layer "F.SilkS")
		)
		(fp_line
			(start -0.7874 -0.4064)
			(end 0.7874 -0.4064)
			(stroke
				(width 0.1524)
				(type default)
			)
			(layer "F.SilkS")
		)
		(fp_line
			(start 0.67945 0.3048)
			(end 0.120396 0.3048)
			(stroke
				(width 0.1)
				(type default)
			)
			(layer "F.Fab")
		)
		(fp_line
			(start 0.67945 -0.3048)
			(end 0.67945 0.3048)
			(stroke
				(width 0.1)
				(type default)
			)
			(layer "F.Fab")
		)
		(fp_line
			(start 0.12065 -0.2794)
			(end 0.12065 -0.3048)
			(stroke
				(width 0.1)
				(type default)
			)
			(layer "F.Fab")
		)
		(fp_line
			(start 0.12065 -0.3048)
			(end 0.67945 -0.3048)
			(stroke
				(width 0.1)
				(type default)
			)
			(layer "F.Fab")
		)
		(fp_line
			(start 0.120396 0.3048)
			(end 0.120396 0.2794)
			(stroke
				(width 0.1)
				(type default)
			)
			(layer "F.Fab")
		)
		(fp_line
			(start 0.120396 0.2794)
			(end -0.12065 0.2794)
			(stroke
				(width 0.1)
				(type default)
			)
			(layer "F.Fab")
		)
		(fp_line
			(start -0.12065 0.3048)
			(end -0.67945 0.3048)
			(stroke
				(width 0.1)
				(type default)
			)
			(layer "F.Fab")
		)
		(fp_line
			(start -0.12065 0.2794)
			(end -0.12065 0.3048)
			(stroke
				(width 0.1)
				(type default)
			)
			(layer "F.Fab")
		)
		(fp_line
			(start -0.12065 -0.2794)
			(end 0.12065 -0.2794)
			(stroke
				(width 0.1)
				(type default)
			)
			(layer "F.Fab")
		)
		(fp_line
			(start -0.12065 -0.305054)
			(end -0.12065 -0.2794)
			(stroke
				(width 0.1)
				(type default)
			)
			(layer "F.Fab")
		)
		(fp_line
			(start -0.67945 0.3048)
			(end -0.67945 -0.305054)
			(stroke
				(width 0.1)
				(type default)
			)
			(layer "F.Fab")
		)
		(fp_line
			(start -0.67945 -0.305054)
			(end -0.12065 -0.305054)
			(stroke
				(width 0.1)
				(type default)
			)
			(layer "F.Fab")
		)
		(pad "1" smd circle
			(at -0.40005 0 180)
			(size 0 0)
			(layers "F.Cu" "F.Mask" "F.Paste")
			(net "P1V8_AUX_REF")
		)
		(pad "2" smd circle
			(at 0.40005 0 180)
			(size 0 0)
			(layers "F.Cu" "F.Mask" "F.Paste")
			(net "GND")
		)
	)
	(footprint ""
		(layer "F.Cu")
		(at 296.385742 -398.78 90)
		(property "Reference" "R998"
			(at 0 0 90)
			(layer "F.SilkS")
			(hide yes)
			(effects
				(font
					(size 1.27 1.27)
				)
			)
		)
		(property "Value" ""
			(at 0 0 90)
			(layer "F.Fab")
			(effects
				(font
					(size 1.27 1.27)
				)
			)
		)
		(duplicate_pad_numbers_are_jumpers no)
		(fp_line
			(start 0.32512 -0.175006)
			(end 0.32512 0.175006)
			(stroke
				(width 0.1)
				(type default)
			)
			(layer "F.Fab")
		)
		(fp_line
			(start -0.32512 -0.175006)
			(end 0.32512 -0.175006)
			(stroke
				(width 0.1)
				(type default)
			)
			(layer "F.Fab")
		)
		(fp_line
			(start 0.32512 0.175006)
			(end -0.32512 0.175006)
			(stroke
				(width 0.1)
				(type default)
			)
			(layer "F.Fab")
		)
		(fp_line
			(start -0.32512 0.175006)
			(end -0.32512 -0.175006)
			(stroke
				(width 0.1)
				(type default)
			)
			(layer "F.Fab")
		)
		(pad "1" smd rect
			(at -0.2667 0 90)
			(size 0.3048 0.381)
			(layers "F.Cu" "F.Mask" "F.Paste")
			(net "P1V8_CPU0_RT_1D")
		)
		(pad "2" smd rect
			(at 0.2667 0 270)
			(size 0.3048 0.381)
			(layers "F.Cu" "F.Mask" "F.Paste")
			(net "MODE_RT_CPU0_P0")
		)
	)
	(footprint ""
		(layer "F.Cu")
		(at 178.69408 -92.685616 90)
		(property "Reference" "R6742"
			(at 0 0 90)
			(layer "F.SilkS")
			(hide yes)
			(effects
				(font
					(size 1.27 1.27)
				)
			)
		)
		(property "Value" ""
			(at 0 0 90)
			(layer "F.Fab")
			(effects
				(font
					(size 1.27 1.27)
				)
			)
		)
		(duplicate_pad_numbers_are_jumpers no)
		(fp_line
			(start 0.7874 -0.4064)
			(end 0.7874 0.4064)
			(stroke
				(width 0.1524)
				(type default)
			)
			(layer "F.SilkS")
		)
		(fp_line
			(start -0.7874 -0.4064)
			(end 0.7874 -0.4064)
			(stroke
				(width 0.1524)
				(type default)
			)
			(layer "F.SilkS")
		)
		(fp_line
			(start 0.7874 0.4064)
			(end -0.7874 0.4064)
			(stroke
				(width 0.1524)
				(type default)
			)
			(layer "F.SilkS")
		)
		(fp_line
			(start -0.7874 0.4064)
			(end -0.7874 -0.4064)
			(stroke
				(width 0.1524)
				(type default)
			)
			(layer "F.SilkS")
		)
		(fp_line
			(start -0.12065 -0.305054)
			(end -0.12065 -0.2794)
			(stroke
				(width 0.1)
				(type default)
			)
			(layer "F.Fab")
		)
		(fp_line
			(start -0.67945 -0.305054)
			(end -0.12065 -0.305054)
			(stroke
				(width 0.1)
				(type default)
			)
			(layer "F.Fab")
		)
		(fp_line
			(start 0.67945 -0.3048)
			(end 0.67945 0.3048)
			(stroke
				(width 0.1)
				(type default)
			)
			(layer "F.Fab")
		)
		(fp_line
			(start 0.12065 -0.3048)
			(end 0.67945 -0.3048)
			(stroke
				(width 0.1)
				(type default)
			)
			(layer "F.Fab")
		)
		(fp_line
			(start 0.12065 -0.2794)
			(end 0.12065 -0.3048)
			(stroke
				(width 0.1)
				(type default)
			)
			(layer "F.Fab")
		)
		(fp_line
			(start -0.12065 -0.2794)
			(end 0.12065 -0.2794)
			(stroke
				(width 0.1)
				(type default)
			)
			(layer "F.Fab")
		)
		(fp_line
			(start 0.120396 0.2794)
			(end -0.12065 0.2794)
			(stroke
				(width 0.1)
				(type default)
			)
			(layer "F.Fab")
		)
		(fp_line
			(start -0.12065 0.2794)
			(end -0.12065 0.3048)
			(stroke
				(width 0.1)
				(type default)
			)
			(layer "F.Fab")
		)
		(fp_line
			(start 0.67945 0.3048)
			(end 0.120396 0.3048)
			(stroke
				(width 0.1)
				(type default)
			)
			(layer "F.Fab")
		)
		(fp_line
			(start 0.120396 0.3048)
			(end 0.120396 0.2794)
			(stroke
				(width 0.1)
				(type default)
			)
			(layer "F.Fab")
		)
		(fp_line
			(start -0.12065 0.3048)
			(end -0.67945 0.3048)
			(stroke
				(width 0.1)
				(type default)
			)
			(layer "F.Fab")
		)
		(fp_line
			(start -0.67945 0.3048)
			(end -0.67945 -0.305054)
			(stroke
				(width 0.1)
				(type default)
			)
			(layer "F.Fab")
		)
		(pad "1" smd circle
			(at -0.40005 0 90)
			(size 0 0)
			(layers "F.Cu" "F.Mask" "F.Paste")
			(net "P1V8_AUX")
		)
		(pad "2" smd circle
			(at 0.40005 0 90)
			(size 0 0)
			(layers "F.Cu" "F.Mask" "F.Paste")
			(net "RT_BOARD_ID_ID1")
		)
	)
	(footprint ""
		(layer "F.Cu")
		(at 305.082448 -147.940522 180)
		(property "Reference" "R5014"
			(at 0 0 180)
			(layer "F.SilkS")
			(hide yes)
			(effects
				(font
					(size 1.27 1.27)
				)
			)
		)
		(property "Value" ""
			(at 0 0 180)
			(layer "F.Fab")
			(effects
				(font
					(size 1.27 1.27)
				)
			)
		)
		(duplicate_pad_numbers_are_jumpers no)
		(fp_line
			(start 0.7874 0.4064)
			(end -0.7874 0.4064)
			(stroke
				(width 0.1524)
				(type default)
			)
			(layer "F.SilkS")
		)
		(fp_line
			(start 0.7874 -0.4064)
			(end 0.7874 0.4064)
			(stroke
				(width 0.1524)
				(type default)
			)
			(layer "F.SilkS")
		)
		(fp_line
			(start -0.7874 0.4064)
			(end -0.7874 -0.4064)
			(stroke
				(width 0.1524)
				(type default)
			)
			(layer "F.SilkS")
		)
		(fp_line
			(start -0.7874 -0.4064)
			(end 0.7874 -0.4064)
			(stroke
				(width 0.1524)
				(type default)
			)
			(layer "F.SilkS")
		)
		(fp_line
			(start 0.67945 0.3048)
			(end 0.120396 0.3048)
			(stroke
				(width 0.1)
				(type default)
			)
			(layer "F.Fab")
		)
		(fp_line
			(start 0.67945 -0.3048)
			(end 0.67945 0.3048)
			(stroke
				(width 0.1)
				(type default)
			)
			(layer "F.Fab")
		)
		(fp_line
			(start 0.12065 -0.2794)
			(end 0.12065 -0.3048)
			(stroke
				(width 0.1)
				(type default)
			)
			(layer "F.Fab")
		)
		(fp_line
			(start 0.12065 -0.3048)
			(end 0.67945 -0.3048)
			(stroke
				(width 0.1)
				(type default)
			)
			(layer "F.Fab")
		)
		(fp_line
			(start 0.120396 0.3048)
			(end 0.120396 0.2794)
			(stroke
				(width 0.1)
				(type default)
			)
			(layer "F.Fab")
		)
		(fp_line
			(start 0.120396 0.2794)
			(end -0.12065 0.2794)
			(stroke
				(width 0.1)
				(type default)
			)
			(layer "F.Fab")
		)
		(fp_line
			(start -0.12065 0.3048)
			(end -0.67945 0.3048)
			(stroke
				(width 0.1)
				(type default)
			)
			(layer "F.Fab")
		)
		(fp_line
			(start -0.12065 0.2794)
			(end -0.12065 0.3048)
			(stroke
				(width 0.1)
				(type default)
			)
			(layer "F.Fab")
		)
		(fp_line
			(start -0.12065 -0.2794)
			(end 0.12065 -0.2794)
			(stroke
				(width 0.1)
				(type default)
			)
			(layer "F.Fab")
		)
		(fp_line
			(start -0.12065 -0.305054)
			(end -0.12065 -0.2794)
			(stroke
				(width 0.1)
				(type default)
			)
			(layer "F.Fab")
		)
		(fp_line
			(start -0.67945 0.3048)
			(end -0.67945 -0.305054)
			(stroke
				(width 0.1)
				(type default)
			)
			(layer "F.Fab")
		)
		(fp_line
			(start -0.67945 -0.305054)
			(end -0.12065 -0.305054)
			(stroke
				(width 0.1)
				(type default)
			)
			(layer "F.Fab")
		)
		(pad "1" smd circle
			(at -0.40005 0 180)
			(size 0 0)
			(layers "F.Cu" "F.Mask" "F.Paste")
			(net "PVDD11_S3_P0")
		)
		(pad "2" smd circle
			(at 0.40005 0 180)
			(size 0 0)
			(layers "F.Cu" "F.Mask" "F.Paste")
			(net "I3C_SCM_0_R_SCL")
		)
	)
	(footprint ""
		(layer "F.Cu")
		(at 109.918754 -326.566276 180)
		(property "Reference" "PR228"
			(at 0 0 180)
			(layer "F.SilkS")
			(hide yes)
			(effects
				(font
					(size 1.27 1.27)
				)
			)
		)
		(property "Value" ""
			(at 0 0 180)
			(layer "F.Fab")
			(effects
				(font
					(size 1.27 1.27)
				)
			)
		)
		(duplicate_pad_numbers_are_jumpers no)
		(fp_line
			(start 0.7874 0.4064)
			(end -0.7874 0.4064)
			(stroke
				(width 0.1524)
				(type default)
			)
			(layer "F.SilkS")
		)
		(fp_line
			(start 0.7874 -0.4064)
			(end 0.7874 0.4064)
			(stroke
				(width 0.1524)
				(type default)
			)
			(layer "F.SilkS")
		)
		(fp_line
			(start -0.7874 0.4064)
			(end -0.7874 -0.4064)
			(stroke
				(width 0.1524)
				(type default)
			)
			(layer "F.SilkS")
		)
		(fp_line
			(start -0.7874 -0.4064)
			(end 0.7874 -0.4064)
			(stroke
				(width 0.1524)
				(type default)
			)
			(layer "F.SilkS")
		)
		(fp_line
			(start 0.67945 0.3048)
			(end 0.120396 0.3048)
			(stroke
				(width 0.1)
				(type default)
			)
			(layer "F.Fab")
		)
		(fp_line
			(start 0.67945 -0.3048)
			(end 0.67945 0.3048)
			(stroke
				(width 0.1)
				(type default)
			)
			(layer "F.Fab")
		)
		(fp_line
			(start 0.12065 -0.2794)
			(end 0.12065 -0.3048)
			(stroke
				(width 0.1)
				(type default)
			)
			(layer "F.Fab")
		)
		(fp_line
			(start 0.12065 -0.3048)
			(end 0.67945 -0.3048)
			(stroke
				(width 0.1)
				(type default)
			)
			(layer "F.Fab")
		)
		(fp_line
			(start 0.120396 0.3048)
			(end 0.120396 0.2794)
			(stroke
				(width 0.1)
				(type default)
			)
			(layer "F.Fab")
		)
		(fp_line
			(start 0.120396 0.2794)
			(end -0.12065 0.2794)
			(stroke
				(width 0.1)
				(type default)
			)
			(layer "F.Fab")
		)
		(fp_line
			(start -0.12065 0.3048)
			(end -0.67945 0.3048)
			(stroke
				(width 0.1)
				(type default)
			)
			(layer "F.Fab")
		)
		(fp_line
			(start -0.12065 0.2794)
			(end -0.12065 0.3048)
			(stroke
				(width 0.1)
				(type default)
			)
			(layer "F.Fab")
		)
		(fp_line
			(start -0.12065 -0.2794)
			(end 0.12065 -0.2794)
			(stroke
				(width 0.1)
				(type default)
			)
			(layer "F.Fab")
		)
		(fp_line
			(start -0.12065 -0.305054)
			(end -0.12065 -0.2794)
			(stroke
				(width 0.1)
				(type default)
			)
			(layer "F.Fab")
		)
		(fp_line
			(start -0.67945 0.3048)
			(end -0.67945 -0.305054)
			(stroke
				(width 0.1)
				(type default)
			)
			(layer "F.Fab")
		)
		(fp_line
			(start -0.67945 -0.305054)
			(end -0.12065 -0.305054)
			(stroke
				(width 0.1)
				(type default)
			)
			(layer "F.Fab")
		)
		(pad "1" smd circle
			(at -0.40005 0 180)
			(size 0 0)
			(layers "F.Cu" "F.Mask" "F.Paste")
			(net "VSENSE_PVDDCR_CPU1_P1_DP")
		)
		(pad "2" smd circle
			(at 0.40005 0 180)
			(size 0 0)
			(layers "F.Cu" "F.Mask" "F.Paste")
			(net "PVDDCR_CPU1_P1")
		)
	)
	(footprint ""
		(layer "F.Cu")
		(at 177.40757 -425.304966)
		(property "Reference" "R2982"
			(at 0 0 0)
			(layer "F.SilkS")
			(hide yes)
			(effects
				(font
					(size 1.27 1.27)
				)
			)
		)
		(property "Value" ""
			(at 0 0 0)
			(layer "F.Fab")
			(effects
				(font
					(size 1.27 1.27)
				)
			)
		)
		(duplicate_pad_numbers_are_jumpers no)
		(fp_line
			(start -0.7874 -0.4064)
			(end 0.7874 -0.4064)
			(stroke
				(width 0.1524)
				(type default)
			)
			(layer "F.SilkS")
		)
		(fp_line
			(start -0.7874 0.4064)
			(end -0.7874 -0.4064)
			(stroke
				(width 0.1524)
				(type default)
			)
			(layer "F.SilkS")
		)
		(fp_line
			(start 0.7874 -0.4064)
			(end 0.7874 0.4064)
			(stroke
				(width 0.1524)
				(type default)
			)
			(layer "F.SilkS")
		)
		(fp_line
			(start 0.7874 0.4064)
			(end -0.7874 0.4064)
			(stroke
				(width 0.1524)
				(type default)
			)
			(layer "F.SilkS")
		)
		(fp_line
			(start -0.67945 -0.305054)
			(end -0.12065 -0.305054)
			(stroke
				(width 0.1)
				(type default)
			)
			(layer "F.Fab")
		)
		(fp_line
			(start -0.67945 0.3048)
			(end -0.67945 -0.305054)
			(stroke
				(width 0.1)
				(type default)
			)
			(layer "F.Fab")
		)
		(fp_line
			(start -0.12065 -0.305054)
			(end -0.12065 -0.2794)
			(stroke
				(width 0.1)
				(type default)
			)
			(layer "F.Fab")
		)
		(fp_line
			(start -0.12065 -0.2794)
			(end 0.12065 -0.2794)
			(stroke
				(width 0.1)
				(type default)
			)
			(layer "F.Fab")
		)
		(fp_line
			(start -0.12065 0.2794)
			(end -0.12065 0.3048)
			(stroke
				(width 0.1)
				(type default)
			)
			(layer "F.Fab")
		)
		(fp_line
			(start -0.12065 0.3048)
			(end -0.67945 0.3048)
			(stroke
				(width 0.1)
				(type default)
			)
			(layer "F.Fab")
		)
		(fp_line
			(start 0.120396 0.2794)
			(end -0.12065 0.2794)
			(stroke
				(width 0.1)
				(type default)
			)
			(layer "F.Fab")
		)
		(fp_line
			(start 0.120396 0.3048)
			(end 0.120396 0.2794)
			(stroke
				(width 0.1)
				(type default)
			)
			(layer "F.Fab")
		)
		(fp_line
			(start 0.12065 -0.3048)
			(end 0.67945 -0.3048)
			(stroke
				(width 0.1)
				(type default)
			)
			(layer "F.Fab")
		)
		(fp_line
			(start 0.12065 -0.2794)
			(end 0.12065 -0.3048)
			(stroke
				(width 0.1)
				(type default)
			)
			(layer "F.Fab")
		)
		(fp_line
			(start 0.67945 -0.3048)
			(end 0.67945 0.3048)
			(stroke
				(width 0.1)
				(type default)
			)
			(layer "F.Fab")
		)
		(fp_line
			(start 0.67945 0.3048)
			(end 0.120396 0.3048)
			(stroke
				(width 0.1)
				(type default)
			)
			(layer "F.Fab")
		)
		(pad "1" smd circle
			(at -0.40005 0)
			(size 0 0)
			(layers "F.Cu" "F.Mask" "F.Paste")
			(net "SMB_IOEXP_3V3AUX_SCL")
		)
		(pad "2" smd circle
			(at 0.40005 0)
			(size 0 0)
			(layers "F.Cu" "F.Mask" "F.Paste")
			(net "SMB_IOEXP_3V3AUX_SCL_R1")
		)
	)
	(footprint ""
		(layer "F.Cu")
		(at 75.7936 -383.7432)
		(property "Reference" "R791"
			(at 0 0 0)
			(layer "F.SilkS")
			(hide yes)
			(effects
				(font
					(size 1.27 1.27)
				)
			)
		)
		(property "Value" ""
			(at 0 0 0)
			(layer "F.Fab")
			(effects
				(font
					(size 1.27 1.27)
				)
			)
		)
		(duplicate_pad_numbers_are_jumpers no)
		(fp_line
			(start -0.32512 -0.175006)
			(end 0.32512 -0.175006)
			(stroke
				(width 0.1)
				(type default)
			)
			(layer "F.Fab")
		)
		(fp_line
			(start -0.32512 0.175006)
			(end -0.32512 -0.175006)
			(stroke
				(width 0.1)
				(type default)
			)
			(layer "F.Fab")
		)
		(fp_line
			(start 0.32512 -0.175006)
			(end 0.32512 0.175006)
			(stroke
				(width 0.1)
				(type default)
			)
			(layer "F.Fab")
		)
		(fp_line
			(start 0.32512 0.175006)
			(end -0.32512 0.175006)
			(stroke
				(width 0.1)
				(type default)
			)
			(layer "F.Fab")
		)
		(pad "1" smd rect
			(at -0.2667 0)
			(size 0.3048 0.381)
			(layers "F.Cu" "F.Mask" "F.Paste")
			(net "TEST2_RT_CPU1_P1")
		)
		(pad "2" smd rect
			(at 0.2667 0 180)
			(size 0.3048 0.381)
			(layers "F.Cu" "F.Mask" "F.Paste")
			(net "GND")
		)
	)
	(footprint ""
		(layer "F.Cu")
		(at 205.214982 -116.673376 180)
		(property "Reference" "R4557"
			(at 0 0 180)
			(layer "F.SilkS")
			(hide yes)
			(effects
				(font
					(size 1.27 1.27)
				)
			)
		)
		(property "Value" ""
			(at 0 0 180)
			(layer "F.Fab")
			(effects
				(font
					(size 1.27 1.27)
				)
			)
		)
		(duplicate_pad_numbers_are_jumpers no)
		(fp_line
			(start 0.7874 0.4064)
			(end -0.7874 0.4064)
			(stroke
				(width 0.1524)
				(type default)
			)
			(layer "F.SilkS")
		)
		(fp_line
			(start 0.7874 -0.4064)
			(end 0.7874 0.4064)
			(stroke
				(width 0.1524)
				(type default)
			)
			(layer "F.SilkS")
		)
		(fp_line
			(start -0.7874 0.4064)
			(end -0.7874 -0.4064)
			(stroke
				(width 0.1524)
				(type default)
			)
			(layer "F.SilkS")
		)
		(fp_line
			(start -0.7874 -0.4064)
			(end 0.7874 -0.4064)
			(stroke
				(width 0.1524)
				(type default)
			)
			(layer "F.SilkS")
		)
		(fp_line
			(start 0.67945 0.3048)
			(end 0.120396 0.3048)
			(stroke
				(width 0.1)
				(type default)
			)
			(layer "F.Fab")
		)
		(fp_line
			(start 0.67945 -0.3048)
			(end 0.67945 0.3048)
			(stroke
				(width 0.1)
				(type default)
			)
			(layer "F.Fab")
		)
		(fp_line
			(start 0.12065 -0.2794)
			(end 0.12065 -0.3048)
			(stroke
				(width 0.1)
				(type default)
			)
			(layer "F.Fab")
		)
		(fp_line
			(start 0.12065 -0.3048)
			(end 0.67945 -0.3048)
			(stroke
				(width 0.1)
				(type default)
			)
			(layer "F.Fab")
		)
		(fp_line
			(start 0.120396 0.3048)
			(end 0.120396 0.2794)
			(stroke
				(width 0.1)
				(type default)
			)
			(layer "F.Fab")
		)
		(fp_line
			(start 0.120396 0.2794)
			(end -0.12065 0.2794)
			(stroke
				(width 0.1)
				(type default)
			)
			(layer "F.Fab")
		)
		(fp_line
			(start -0.12065 0.3048)
			(end -0.67945 0.3048)
			(stroke
				(width 0.1)
				(type default)
			)
			(layer "F.Fab")
		)
		(fp_line
			(start -0.12065 0.2794)
			(end -0.12065 0.3048)
			(stroke
				(width 0.1)
				(type default)
			)
			(layer "F.Fab")
		)
		(fp_line
			(start -0.12065 -0.2794)
			(end 0.12065 -0.2794)
			(stroke
				(width 0.1)
				(type default)
			)
			(layer "F.Fab")
		)
		(fp_line
			(start -0.12065 -0.305054)
			(end -0.12065 -0.2794)
			(stroke
				(width 0.1)
				(type default)
			)
			(layer "F.Fab")
		)
		(fp_line
			(start -0.67945 0.3048)
			(end -0.67945 -0.305054)
			(stroke
				(width 0.1)
				(type default)
			)
			(layer "F.Fab")
		)
		(fp_line
			(start -0.67945 -0.305054)
			(end -0.12065 -0.305054)
			(stroke
				(width 0.1)
				(type default)
			)
			(layer "F.Fab")
		)
		(pad "1" smd circle
			(at -0.40005 0 180)
			(size 0 0)
			(layers "F.Cu" "F.Mask" "F.Paste")
			(net "HPDB_HSC_PWRGD_ISO")
		)
		(pad "2" smd circle
			(at 0.40005 0 180)
			(size 0 0)
			(layers "F.Cu" "F.Mask" "F.Paste")
			(net "HPDB_HSC_PWRGD_ISO_R")
		)
	)
	(footprint ""
		(layer "F.Cu")
		(at 330.374244 -335.129632 -90)
		(property "Reference" "PC88_2"
			(at 0 0 270)
			(layer "F.SilkS")
			(hide yes)
			(effects
				(font
					(size 1.27 1.27)
				)
			)
		)
		(property "Value" ""
			(at 0 0 270)
			(layer "F.Fab")
			(effects
				(font
					(size 1.27 1.27)
				)
			)
		)
		(duplicate_pad_numbers_are_jumpers no)
		(fp_line
			(start -0.7874 0.4064)
			(end -0.7874 -0.4064)
			(stroke
				(width 0.1524)
				(type default)
			)
			(layer "F.SilkS")
		)
		(fp_line
			(start 0.7874 0.4064)
			(end -0.7874 0.4064)
			(stroke
				(width 0.1524)
				(type default)
			)
			(layer "F.SilkS")
		)
		(fp_line
			(start -0.7874 -0.4064)
			(end 0.7874 -0.4064)
			(stroke
				(width 0.1524)
				(type default)
			)
			(layer "F.SilkS")
		)
		(fp_line
			(start 0.7874 -0.4064)
			(end 0.7874 0.4064)
			(stroke
				(width 0.1524)
				(type default)
			)
			(layer "F.SilkS")
		)
		(fp_line
			(start -0.67945 0.3048)
			(end -0.67945 -0.305054)
			(stroke
				(width 0.1)
				(type default)
			)
			(layer "F.Fab")
		)
		(fp_line
			(start -0.12065 0.3048)
			(end -0.67945 0.3048)
			(stroke
				(width 0.1)
				(type default)
			)
			(layer "F.Fab")
		)
		(fp_line
			(start 0.120396 0.3048)
			(end 0.120396 0.2794)
			(stroke
				(width 0.1)
				(type default)
			)
			(layer "F.Fab")
		)
		(fp_line
			(start 0.67945 0.3048)
			(end 0.120396 0.3048)
			(stroke
				(width 0.1)
				(type default)
			)
			(layer "F.Fab")
		)
		(fp_line
			(start -0.12065 0.2794)
			(end -0.12065 0.3048)
			(stroke
				(width 0.1)
				(type default)
			)
			(layer "F.Fab")
		)
		(fp_line
			(start 0.120396 0.2794)
			(end -0.12065 0.2794)
			(stroke
				(width 0.1)
				(type default)
			)
			(layer "F.Fab")
		)
		(fp_line
			(start -0.12065 -0.2794)
			(end 0.12065 -0.2794)
			(stroke
				(width 0.1)
				(type default)
			)
			(layer "F.Fab")
		)
		(fp_line
			(start 0.12065 -0.2794)
			(end 0.12065 -0.3048)
			(stroke
				(width 0.1)
				(type default)
			)
			(layer "F.Fab")
		)
		(fp_line
			(start 0.12065 -0.3048)
			(end 0.67945 -0.3048)
			(stroke
				(width 0.1)
				(type default)
			)
			(layer "F.Fab")
		)
		(fp_line
			(start 0.67945 -0.3048)
			(end 0.67945 0.3048)
			(stroke
				(width 0.1)
				(type default)
			)
			(layer "F.Fab")
		)
		(fp_line
			(start -0.67945 -0.305054)
			(end -0.12065 -0.305054)
			(stroke
				(width 0.1)
				(type default)
			)
			(layer "F.Fab")
		)
		(fp_line
			(start -0.12065 -0.305054)
			(end -0.12065 -0.2794)
			(stroke
				(width 0.1)
				(type default)
			)
			(layer "F.Fab")
		)
		(pad "1" smd circle
			(at -0.40005 0 270)
			(size 0 0)
			(layers "F.Cu" "F.Mask" "F.Paste")
			(net "SW_P12V_AUX_PVDDCR_CPU1_P0_FLT")
		)
		(pad "2" smd circle
			(at 0.40005 0 270)
			(size 0 0)
			(layers "F.Cu" "F.Mask" "F.Paste")
			(net "GND")
		)
	)
	(footprint ""
		(layer "F.Cu")
		(at 437.542432 -27.275536 90)
		(property "Reference" "PR3841"
			(at 0 0 90)
			(layer "F.SilkS")
			(hide yes)
			(effects
				(font
					(size 1.27 1.27)
				)
			)
		)
		(property "Value" ""
			(at 0 0 90)
			(layer "F.Fab")
			(effects
				(font
					(size 1.27 1.27)
				)
			)
		)
		(duplicate_pad_numbers_are_jumpers no)
		(fp_line
			(start 0.7874 -0.4064)
			(end 0.7874 0.4064)
			(stroke
				(width 0.1524)
				(type default)
			)
			(layer "F.SilkS")
		)
		(fp_line
			(start -0.7874 -0.4064)
			(end 0.7874 -0.4064)
			(stroke
				(width 0.1524)
				(type default)
			)
			(layer "F.SilkS")
		)
		(fp_line
			(start 0.7874 0.4064)
			(end -0.7874 0.4064)
			(stroke
				(width 0.1524)
				(type default)
			)
			(layer "F.SilkS")
		)
		(fp_line
			(start -0.7874 0.4064)
			(end -0.7874 -0.4064)
			(stroke
				(width 0.1524)
				(type default)
			)
			(layer "F.SilkS")
		)
		(fp_line
			(start -0.12065 -0.305054)
			(end -0.12065 -0.2794)
			(stroke
				(width 0.1)
				(type default)
			)
			(layer "F.Fab")
		)
		(fp_line
			(start -0.67945 -0.305054)
			(end -0.12065 -0.305054)
			(stroke
				(width 0.1)
				(type default)
			)
			(layer "F.Fab")
		)
		(fp_line
			(start 0.67945 -0.3048)
			(end 0.67945 0.3048)
			(stroke
				(width 0.1)
				(type default)
			)
			(layer "F.Fab")
		)
		(fp_line
			(start 0.12065 -0.3048)
			(end 0.67945 -0.3048)
			(stroke
				(width 0.1)
				(type default)
			)
			(layer "F.Fab")
		)
		(fp_line
			(start 0.12065 -0.2794)
			(end 0.12065 -0.3048)
			(stroke
				(width 0.1)
				(type default)
			)
			(layer "F.Fab")
		)
		(fp_line
			(start -0.12065 -0.2794)
			(end 0.12065 -0.2794)
			(stroke
				(width 0.1)
				(type default)
			)
			(layer "F.Fab")
		)
		(fp_line
			(start 0.120396 0.2794)
			(end -0.12065 0.2794)
			(stroke
				(width 0.1)
				(type default)
			)
			(layer "F.Fab")
		)
		(fp_line
			(start -0.12065 0.2794)
			(end -0.12065 0.3048)
			(stroke
				(width 0.1)
				(type default)
			)
			(layer "F.Fab")
		)
		(fp_line
			(start 0.67945 0.3048)
			(end 0.120396 0.3048)
			(stroke
				(width 0.1)
				(type default)
			)
			(layer "F.Fab")
		)
		(fp_line
			(start 0.120396 0.3048)
			(end 0.120396 0.2794)
			(stroke
				(width 0.1)
				(type default)
			)
			(layer "F.Fab")
		)
		(fp_line
			(start -0.12065 0.3048)
			(end -0.67945 0.3048)
			(stroke
				(width 0.1)
				(type default)
			)
			(layer "F.Fab")
		)
		(fp_line
			(start -0.67945 0.3048)
			(end -0.67945 -0.305054)
			(stroke
				(width 0.1)
				(type default)
			)
			(layer "F.Fab")
		)
		(pad "1" smd circle
			(at -0.40005 0 90)
			(size 0 0)
			(layers "F.Cu" "F.Mask" "F.Paste")
			(net "P12V_AUX")
		)
		(pad "2" smd circle
			(at 0.40005 0 90)
			(size 0 0)
			(layers "F.Cu" "F.Mask" "F.Paste")
			(net "P12V_OCP_OV_FB_1")
		)
	)
	(footprint ""
		(layer "F.Cu")
		(at 89.131902 -373.03583 -90)
		(property "Reference" "C725"
			(at 0 0 270)
			(layer "F.SilkS")
			(hide yes)
			(effects
				(font
					(size 1.27 1.27)
				)
			)
		)
		(property "Value" ""
			(at 0 0 270)
			(layer "F.Fab")
			(effects
				(font
					(size 1.27 1.27)
				)
			)
		)
		(duplicate_pad_numbers_are_jumpers no)
		(fp_line
			(start -0.299974 0.150114)
			(end -0.299974 -0.150114)
			(stroke
				(width 0.1)
				(type default)
			)
			(layer "F.Fab")
		)
		(fp_line
			(start 0.299974 0.150114)
			(end -0.299974 0.150114)
			(stroke
				(width 0.1)
				(type default)
			)
			(layer "F.Fab")
		)
		(fp_line
			(start -0.299974 -0.150114)
			(end 0.299974 -0.150114)
			(stroke
				(width 0.1)
				(type default)
			)
			(layer "F.Fab")
		)
		(fp_line
			(start 0.299974 -0.150114)
			(end 0.299974 0.150114)
			(stroke
				(width 0.1)
				(type default)
			)
			(layer "F.Fab")
		)
		(pad "1" smd rect
			(at -0.2667 0 270)
			(size 0.3048 0.381)
			(layers "F.Cu" "F.Mask" "F.Paste")
			(net "P5E_CPU1_P1_TX_C_DP<8>")
		)
		(pad "2" smd rect
			(at 0.2667 0 270)
			(size 0.3048 0.381)
			(layers "F.Cu" "F.Mask" "F.Paste")
			(net "P5E_CPU1_P1_TX_DP<8>")
		)
	)
	(footprint ""
		(layer "F.Cu")
		(at 184.079642 -413.64408 -90)
		(property "Reference" "R2848"
			(at 0 0 270)
			(layer "F.SilkS")
			(hide yes)
			(effects
				(font
					(size 1.27 1.27)
				)
			)
		)
		(property "Value" ""
			(at 0 0 270)
			(layer "F.Fab")
			(effects
				(font
					(size 1.27 1.27)
				)
			)
		)
		(duplicate_pad_numbers_are_jumpers no)
		(fp_line
			(start -0.7874 0.4064)
			(end -0.7874 -0.4064)
			(stroke
				(width 0.1524)
				(type default)
			)
			(layer "F.SilkS")
		)
		(fp_line
			(start 0.7874 0.4064)
			(end -0.7874 0.4064)
			(stroke
				(width 0.1524)
				(type default)
			)
			(layer "F.SilkS")
		)
		(fp_line
			(start -0.7874 -0.4064)
			(end 0.7874 -0.4064)
			(stroke
				(width 0.1524)
				(type default)
			)
			(layer "F.SilkS")
		)
		(fp_line
			(start 0.7874 -0.4064)
			(end 0.7874 0.4064)
			(stroke
				(width 0.1524)
				(type default)
			)
			(layer "F.SilkS")
		)
		(fp_line
			(start -0.67945 0.3048)
			(end -0.67945 -0.305054)
			(stroke
				(width 0.1)
				(type default)
			)
			(layer "F.Fab")
		)
		(fp_line
			(start -0.12065 0.3048)
			(end -0.67945 0.3048)
			(stroke
				(width 0.1)
				(type default)
			)
			(layer "F.Fab")
		)
		(fp_line
			(start 0.120396 0.3048)
			(end 0.120396 0.2794)
			(stroke
				(width 0.1)
				(type default)
			)
			(layer "F.Fab")
		)
		(fp_line
			(start 0.67945 0.3048)
			(end 0.120396 0.3048)
			(stroke
				(width 0.1)
				(type default)
			)
			(layer "F.Fab")
		)
		(fp_line
			(start -0.12065 0.2794)
			(end -0.12065 0.3048)
			(stroke
				(width 0.1)
				(type default)
			)
			(layer "F.Fab")
		)
		(fp_line
			(start 0.120396 0.2794)
			(end -0.12065 0.2794)
			(stroke
				(width 0.1)
				(type default)
			)
			(layer "F.Fab")
		)
		(fp_line
			(start -0.12065 -0.2794)
			(end 0.12065 -0.2794)
			(stroke
				(width 0.1)
				(type default)
			)
			(layer "F.Fab")
		)
		(fp_line
			(start 0.12065 -0.2794)
			(end 0.12065 -0.3048)
			(stroke
				(width 0.1)
				(type default)
			)
			(layer "F.Fab")
		)
		(fp_line
			(start 0.12065 -0.3048)
			(end 0.67945 -0.3048)
			(stroke
				(width 0.1)
				(type default)
			)
			(layer "F.Fab")
		)
		(fp_line
			(start 0.67945 -0.3048)
			(end 0.67945 0.3048)
			(stroke
				(width 0.1)
				(type default)
			)
			(layer "F.Fab")
		)
		(fp_line
			(start -0.67945 -0.305054)
			(end -0.12065 -0.305054)
			(stroke
				(width 0.1)
				(type default)
			)
			(layer "F.Fab")
		)
		(fp_line
			(start -0.12065 -0.305054)
			(end -0.12065 -0.2794)
			(stroke
				(width 0.1)
				(type default)
			)
			(layer "F.Fab")
		)
		(pad "1" smd circle
			(at -0.40005 0 270)
			(size 0 0)
			(layers "F.Cu" "F.Mask" "F.Paste")
			(net "RST_SWB_BIC_N")
		)
		(pad "2" smd circle
			(at 0.40005 0 270)
			(size 0 0)
			(layers "F.Cu" "F.Mask" "F.Paste")
			(net "RST_SWB_BIC_R_N")
		)
	)
	(footprint ""
		(layer "F.Cu")
		(at 443.717172 -32.173418 90)
		(property "Reference" "PC2153"
			(at 0 0 90)
			(layer "F.SilkS")
			(hide yes)
			(effects
				(font
					(size 1.27 1.27)
				)
			)
		)
		(property "Value" ""
			(at 0 0 90)
			(layer "F.Fab")
			(effects
				(font
					(size 1.27 1.27)
				)
			)
		)
		(duplicate_pad_numbers_are_jumpers no)
		(fp_line
			(start 0.7874 -0.4064)
			(end 0.7874 0.4064)
			(stroke
				(width 0.1524)
				(type default)
			)
			(layer "F.SilkS")
		)
		(fp_line
			(start -0.7874 -0.4064)
			(end 0.7874 -0.4064)
			(stroke
				(width 0.1524)
				(type default)
			)
			(layer "F.SilkS")
		)
		(fp_line
			(start 0.7874 0.4064)
			(end -0.7874 0.4064)
			(stroke
				(width 0.1524)
				(type default)
			)
			(layer "F.SilkS")
		)
		(fp_line
			(start -0.7874 0.4064)
			(end -0.7874 -0.4064)
			(stroke
				(width 0.1524)
				(type default)
			)
			(layer "F.SilkS")
		)
		(fp_line
			(start -0.12065 -0.305054)
			(end -0.12065 -0.2794)
			(stroke
				(width 0.1)
				(type default)
			)
			(layer "F.Fab")
		)
		(fp_line
			(start -0.67945 -0.305054)
			(end -0.12065 -0.305054)
			(stroke
				(width 0.1)
				(type default)
			)
			(layer "F.Fab")
		)
		(fp_line
			(start 0.67945 -0.3048)
			(end 0.67945 0.3048)
			(stroke
				(width 0.1)
				(type default)
			)
			(layer "F.Fab")
		)
		(fp_line
			(start 0.12065 -0.3048)
			(end 0.67945 -0.3048)
			(stroke
				(width 0.1)
				(type default)
			)
			(layer "F.Fab")
		)
		(fp_line
			(start 0.12065 -0.2794)
			(end 0.12065 -0.3048)
			(stroke
				(width 0.1)
				(type default)
			)
			(layer "F.Fab")
		)
		(fp_line
			(start -0.12065 -0.2794)
			(end 0.12065 -0.2794)
			(stroke
				(width 0.1)
				(type default)
			)
			(layer "F.Fab")
		)
		(fp_line
			(start 0.120396 0.2794)
			(end -0.12065 0.2794)
			(stroke
				(width 0.1)
				(type default)
			)
			(layer "F.Fab")
		)
		(fp_line
			(start -0.12065 0.2794)
			(end -0.12065 0.3048)
			(stroke
				(width 0.1)
				(type default)
			)
			(layer "F.Fab")
		)
		(fp_line
			(start 0.67945 0.3048)
			(end 0.120396 0.3048)
			(stroke
				(width 0.1)
				(type default)
			)
			(layer "F.Fab")
		)
		(fp_line
			(start 0.120396 0.3048)
			(end 0.120396 0.2794)
			(stroke
				(width 0.1)
				(type default)
			)
			(layer "F.Fab")
		)
		(fp_line
			(start -0.12065 0.3048)
			(end -0.67945 0.3048)
			(stroke
				(width 0.1)
				(type default)
			)
			(layer "F.Fab")
		)
		(fp_line
			(start -0.67945 0.3048)
			(end -0.67945 -0.305054)
			(stroke
				(width 0.1)
				(type default)
			)
			(layer "F.Fab")
		)
		(pad "1" smd circle
			(at -0.40005 0 90)
			(size 0 0)
			(layers "F.Cu" "F.Mask" "F.Paste")
			(net "P12V_OCP_TIMER_1")
		)
		(pad "2" smd circle
			(at 0.40005 0 90)
			(size 0 0)
			(layers "F.Cu" "F.Mask" "F.Paste")
			(net "GND")
		)
	)
	(footprint ""
		(layer "F.Cu")
		(at 165.14064 -78.000606 180)
		(property "Reference" "R1009"
			(at 0 0 180)
			(layer "F.SilkS")
			(hide yes)
			(effects
				(font
					(size 1.27 1.27)
				)
			)
		)
		(property "Value" ""
			(at 0 0 180)
			(layer "F.Fab")
			(effects
				(font
					(size 1.27 1.27)
				)
			)
		)
		(duplicate_pad_numbers_are_jumpers no)
		(fp_line
			(start 0.7874 0.4064)
			(end -0.7874 0.4064)
			(stroke
				(width 0.1524)
				(type default)
			)
			(layer "F.SilkS")
		)
		(fp_line
			(start 0.7874 -0.4064)
			(end 0.7874 0.4064)
			(stroke
				(width 0.1524)
				(type default)
			)
			(layer "F.SilkS")
		)
		(fp_line
			(start -0.7874 0.4064)
			(end -0.7874 -0.4064)
			(stroke
				(width 0.1524)
				(type default)
			)
			(layer "F.SilkS")
		)
		(fp_line
			(start -0.7874 -0.4064)
			(end 0.7874 -0.4064)
			(stroke
				(width 0.1524)
				(type default)
			)
			(layer "F.SilkS")
		)
		(fp_line
			(start 0.67945 0.3048)
			(end 0.120396 0.3048)
			(stroke
				(width 0.1)
				(type default)
			)
			(layer "F.Fab")
		)
		(fp_line
			(start 0.67945 -0.3048)
			(end 0.67945 0.3048)
			(stroke
				(width 0.1)
				(type default)
			)
			(layer "F.Fab")
		)
		(fp_line
			(start 0.12065 -0.2794)
			(end 0.12065 -0.3048)
			(stroke
				(width 0.1)
				(type default)
			)
			(layer "F.Fab")
		)
		(fp_line
			(start 0.12065 -0.3048)
			(end 0.67945 -0.3048)
			(stroke
				(width 0.1)
				(type default)
			)
			(layer "F.Fab")
		)
		(fp_line
			(start 0.120396 0.3048)
			(end 0.120396 0.2794)
			(stroke
				(width 0.1)
				(type default)
			)
			(layer "F.Fab")
		)
		(fp_line
			(start 0.120396 0.2794)
			(end -0.12065 0.2794)
			(stroke
				(width 0.1)
				(type default)
			)
			(layer "F.Fab")
		)
		(fp_line
			(start -0.12065 0.3048)
			(end -0.67945 0.3048)
			(stroke
				(width 0.1)
				(type default)
			)
			(layer "F.Fab")
		)
		(fp_line
			(start -0.12065 0.2794)
			(end -0.12065 0.3048)
			(stroke
				(width 0.1)
				(type default)
			)
			(layer "F.Fab")
		)
		(fp_line
			(start -0.12065 -0.2794)
			(end 0.12065 -0.2794)
			(stroke
				(width 0.1)
				(type default)
			)
			(layer "F.Fab")
		)
		(fp_line
			(start -0.12065 -0.305054)
			(end -0.12065 -0.2794)
			(stroke
				(width 0.1)
				(type default)
			)
			(layer "F.Fab")
		)
		(fp_line
			(start -0.67945 0.3048)
			(end -0.67945 -0.305054)
			(stroke
				(width 0.1)
				(type default)
			)
			(layer "F.Fab")
		)
		(fp_line
			(start -0.67945 -0.305054)
			(end -0.12065 -0.305054)
			(stroke
				(width 0.1)
				(type default)
			)
			(layer "F.Fab")
		)
		(pad "1" smd circle
			(at -0.40005 0 180)
			(size 0 0)
			(layers "F.Cu" "F.Mask" "F.Paste")
			(net "P3V3_AUX")
		)
		(pad "2" smd circle
			(at 0.40005 0 180)
			(size 0 0)
			(layers "F.Cu" "F.Mask" "F.Paste")
			(net "IRQ_LVC3_WAKE")
		)
	)
	(footprint ""
		(layer "F.Cu")
		(at 303.653952 -22.7457 90)
		(property "Reference" "R1779"
			(at 0 0 90)
			(layer "F.SilkS")
			(hide yes)
			(effects
				(font
					(size 1.27 1.27)
				)
			)
		)
		(property "Value" ""
			(at 0 0 90)
			(layer "F.Fab")
			(effects
				(font
					(size 1.27 1.27)
				)
			)
		)
		(duplicate_pad_numbers_are_jumpers no)
		(fp_line
			(start 0.7874 -0.4064)
			(end 0.7874 0.4064)
			(stroke
				(width 0.1524)
				(type default)
			)
			(layer "F.SilkS")
		)
		(fp_line
			(start -0.7874 -0.4064)
			(end 0.7874 -0.4064)
			(stroke
				(width 0.1524)
				(type default)
			)
			(layer "F.SilkS")
		)
		(fp_line
			(start 0.7874 0.4064)
			(end -0.7874 0.4064)
			(stroke
				(width 0.1524)
				(type default)
			)
			(layer "F.SilkS")
		)
		(fp_line
			(start -0.7874 0.4064)
			(end -0.7874 -0.4064)
			(stroke
				(width 0.1524)
				(type default)
			)
			(layer "F.SilkS")
		)
		(fp_line
			(start -0.12065 -0.305054)
			(end -0.12065 -0.2794)
			(stroke
				(width 0.1)
				(type default)
			)
			(layer "F.Fab")
		)
		(fp_line
			(start -0.67945 -0.305054)
			(end -0.12065 -0.305054)
			(stroke
				(width 0.1)
				(type default)
			)
			(layer "F.Fab")
		)
		(fp_line
			(start 0.67945 -0.3048)
			(end 0.67945 0.3048)
			(stroke
				(width 0.1)
				(type default)
			)
			(layer "F.Fab")
		)
		(fp_line
			(start 0.12065 -0.3048)
			(end 0.67945 -0.3048)
			(stroke
				(width 0.1)
				(type default)
			)
			(layer "F.Fab")
		)
		(fp_line
			(start 0.12065 -0.2794)
			(end 0.12065 -0.3048)
			(stroke
				(width 0.1)
				(type default)
			)
			(layer "F.Fab")
		)
		(fp_line
			(start -0.12065 -0.2794)
			(end 0.12065 -0.2794)
			(stroke
				(width 0.1)
				(type default)
			)
			(layer "F.Fab")
		)
		(fp_line
			(start 0.120396 0.2794)
			(end -0.12065 0.2794)
			(stroke
				(width 0.1)
				(type default)
			)
			(layer "F.Fab")
		)
		(fp_line
			(start -0.12065 0.2794)
			(end -0.12065 0.3048)
			(stroke
				(width 0.1)
				(type default)
			)
			(layer "F.Fab")
		)
		(fp_line
			(start 0.67945 0.3048)
			(end 0.120396 0.3048)
			(stroke
				(width 0.1)
				(type default)
			)
			(layer "F.Fab")
		)
		(fp_line
			(start 0.120396 0.3048)
			(end 0.120396 0.2794)
			(stroke
				(width 0.1)
				(type default)
			)
			(layer "F.Fab")
		)
		(fp_line
			(start -0.12065 0.3048)
			(end -0.67945 0.3048)
			(stroke
				(width 0.1)
				(type default)
			)
			(layer "F.Fab")
		)
		(fp_line
			(start -0.67945 0.3048)
			(end -0.67945 -0.305054)
			(stroke
				(width 0.1)
				(type default)
			)
			(layer "F.Fab")
		)
		(pad "1" smd circle
			(at -0.40005 0 90)
			(size 0 0)
			(layers "F.Cu" "F.Mask" "F.Paste")
			(net "CLR_CMOS_N")
		)
		(pad "2" smd circle
			(at 0.40005 0 90)
			(size 0 0)
			(layers "F.Cu" "F.Mask" "F.Paste")
			(net "P1V5_BAT")
		)
	)
	(footprint ""
		(layer "F.Cu")
		(at 384.755136 -184.478168 -90)
		(property "Reference" "PR498"
			(at 0 0 270)
			(layer "F.SilkS")
			(hide yes)
			(effects
				(font
					(size 1.27 1.27)
				)
			)
		)
		(property "Value" ""
			(at 0 0 270)
			(layer "F.Fab")
			(effects
				(font
					(size 1.27 1.27)
				)
			)
		)
		(duplicate_pad_numbers_are_jumpers no)
		(fp_line
			(start -0.7874 0.4064)
			(end -0.7874 -0.4064)
			(stroke
				(width 0.1524)
				(type default)
			)
			(layer "F.SilkS")
		)
		(fp_line
			(start 0.7874 0.4064)
			(end -0.7874 0.4064)
			(stroke
				(width 0.1524)
				(type default)
			)
			(layer "F.SilkS")
		)
		(fp_line
			(start -0.7874 -0.4064)
			(end 0.7874 -0.4064)
			(stroke
				(width 0.1524)
				(type default)
			)
			(layer "F.SilkS")
		)
		(fp_line
			(start 0.7874 -0.4064)
			(end 0.7874 0.4064)
			(stroke
				(width 0.1524)
				(type default)
			)
			(layer "F.SilkS")
		)
		(fp_line
			(start -0.67945 0.3048)
			(end -0.67945 -0.305054)
			(stroke
				(width 0.1)
				(type default)
			)
			(layer "F.Fab")
		)
		(fp_line
			(start -0.12065 0.3048)
			(end -0.67945 0.3048)
			(stroke
				(width 0.1)
				(type default)
			)
			(layer "F.Fab")
		)
		(fp_line
			(start 0.120396 0.3048)
			(end 0.120396 0.2794)
			(stroke
				(width 0.1)
				(type default)
			)
			(layer "F.Fab")
		)
		(fp_line
			(start 0.67945 0.3048)
			(end 0.120396 0.3048)
			(stroke
				(width 0.1)
				(type default)
			)
			(layer "F.Fab")
		)
		(fp_line
			(start -0.12065 0.2794)
			(end -0.12065 0.3048)
			(stroke
				(width 0.1)
				(type default)
			)
			(layer "F.Fab")
		)
		(fp_line
			(start 0.120396 0.2794)
			(end -0.12065 0.2794)
			(stroke
				(width 0.1)
				(type default)
			)
			(layer "F.Fab")
		)
		(fp_line
			(start -0.12065 -0.2794)
			(end 0.12065 -0.2794)
			(stroke
				(width 0.1)
				(type default)
			)
			(layer "F.Fab")
		)
		(fp_line
			(start 0.12065 -0.2794)
			(end 0.12065 -0.3048)
			(stroke
				(width 0.1)
				(type default)
			)
			(layer "F.Fab")
		)
		(fp_line
			(start 0.12065 -0.3048)
			(end 0.67945 -0.3048)
			(stroke
				(width 0.1)
				(type default)
			)
			(layer "F.Fab")
		)
		(fp_line
			(start 0.67945 -0.3048)
			(end 0.67945 0.3048)
			(stroke
				(width 0.1)
				(type default)
			)
			(layer "F.Fab")
		)
		(fp_line
			(start -0.67945 -0.305054)
			(end -0.12065 -0.305054)
			(stroke
				(width 0.1)
				(type default)
			)
			(layer "F.Fab")
		)
		(fp_line
			(start -0.12065 -0.305054)
			(end -0.12065 -0.2794)
			(stroke
				(width 0.1)
				(type default)
			)
			(layer "F.Fab")
		)
		(pad "1" smd circle
			(at -0.40005 0 270)
			(size 0 0)
			(layers "F.Cu" "F.Mask" "F.Paste")
			(net "SW_PVDDCR_CPU0_P0_SW3_RC")
		)
		(pad "2" smd circle
			(at 0.40005 0 270)
			(size 0 0)
			(layers "F.Cu" "F.Mask" "F.Paste")
			(net "GND")
		)
	)
	(footprint ""
		(layer "F.Cu")
		(at 191.806322 -20.126452 180)
		(property "Reference" "PD116"
			(at -2.53746 2.96545 0)
			(unlocked yes)
			(layer "F.SilkS")
			(effects
				(font
					(size 0.7874 0.5842)
					(thickness 0.1524)
				)
				(justify left)
			)
		)
		(property "Value" ""
			(at 0 0 180)
			(layer "F.Fab")
			(effects
				(font
					(size 1.27 1.27)
				)
			)
		)
		(duplicate_pad_numbers_are_jumpers no)
		(fp_line
			(start 4.107942 1.459992)
			(end -3.400044 1.459992)
			(stroke
				(width 0.1524)
				(type default)
			)
			(layer "F.SilkS")
		)
		(fp_line
			(start 4.107942 -1.459992)
			(end 4.107942 1.459992)
			(stroke
				(width 0.1524)
				(type default)
			)
			(layer "F.SilkS")
		)
		(fp_line
			(start -3.400044 1.459992)
			(end -3.400044 -1.459992)
			(stroke
				(width 0.1524)
				(type default)
			)
			(layer "F.SilkS")
		)
		(fp_line
			(start -3.400044 -1.459992)
			(end 4.107942 -1.459992)
			(stroke
				(width 0.1524)
				(type default)
			)
			(layer "F.SilkS")
		)
		(fp_rect
			(start 4.107942 -1.459992)
			(end 3.308096 1.459992)
			(stroke
				(width 0)
				(type default)
			)
			(fill yes)
			(layer "F.SilkS")
		)
		(fp_line
			(start 2.29997 1.459992)
			(end -2.29997 1.459992)
			(stroke
				(width 0.1)
				(type default)
			)
			(layer "F.Fab")
		)
		(fp_line
			(start 2.29997 -1.459992)
			(end 2.29997 1.459992)
			(stroke
				(width 0.1)
				(type default)
			)
			(layer "F.Fab")
		)
		(fp_line
			(start -2.29997 1.459992)
			(end -2.29997 -1.459992)
			(stroke
				(width 0.1)
				(type default)
			)
			(layer "F.Fab")
		)
		(fp_line
			(start -2.29997 -1.459992)
			(end 2.29997 -1.459992)
			(stroke
				(width 0.1)
				(type default)
			)
			(layer "F.Fab")
		)
		(fp_text user "-"
			(at 5.50418 1.00203 0)
			(unlocked yes)
			(layer "F.SilkS")
			(effects
				(font
					(size 1.905 1.4224)
					(thickness 0.1524)
				)
				(justify left)
			)
		)
		(fp_text user "+"
			(at -5.283962 -0.182118 180)
			(unlocked yes)
			(layer "F.SilkS")
			(effects
				(font
					(size 1.905 1.4224)
					(thickness 0.1524)
				)
				(justify left)
			)
		)
		(fp_text user "-"
			(at 5.4102 0.29845 0)
			(unlocked yes)
			(layer "F.Fab")
			(effects
				(font
					(size 1.905 1.4224)
					(thickness 0.1524)
				)
				(justify left)
			)
		)
		(fp_text user "+"
			(at -4.7752 -0.12065 180)
			(unlocked yes)
			(layer "F.Fab")
			(effects
				(font
					(size 1.905 1.4224)
					(thickness 0.1524)
				)
				(justify left)
			)
		)
		(pad "A" smd rect
			(at -1.999996 0 270)
			(size 1.7018 2.5146)
			(layers "F.Cu" "F.Mask" "F.Paste")
			(net "GND")
		)
		(pad "C" smd rect
			(at 1.999996 0 270)
			(size 1.7018 2.5146)
			(layers "F.Cu" "F.Mask" "F.Paste")
			(net "P12V_SCM_R")
		)
	)
	(footprint ""
		(layer "F.Cu")
		(at 141.233652 -79.029052 90)
		(property "Reference" "PC6010"
			(at 0 0 90)
			(layer "F.SilkS")
			(hide yes)
			(effects
				(font
					(size 1.27 1.27)
				)
			)
		)
		(property "Value" ""
			(at 0 0 90)
			(layer "F.Fab")
			(effects
				(font
					(size 1.27 1.27)
				)
			)
		)
		(duplicate_pad_numbers_are_jumpers no)
		(fp_line
			(start 0.7874 -0.4064)
			(end 0.7874 0.4064)
			(stroke
				(width 0.1524)
				(type default)
			)
			(layer "F.SilkS")
		)
		(fp_line
			(start -0.7874 -0.4064)
			(end 0.7874 -0.4064)
			(stroke
				(width 0.1524)
				(type default)
			)
			(layer "F.SilkS")
		)
		(fp_line
			(start 0.7874 0.4064)
			(end -0.7874 0.4064)
			(stroke
				(width 0.1524)
				(type default)
			)
			(layer "F.SilkS")
		)
		(fp_line
			(start -0.7874 0.4064)
			(end -0.7874 -0.4064)
			(stroke
				(width 0.1524)
				(type default)
			)
			(layer "F.SilkS")
		)
		(fp_line
			(start -0.12065 -0.305054)
			(end -0.12065 -0.2794)
			(stroke
				(width 0.1)
				(type default)
			)
			(layer "F.Fab")
		)
		(fp_line
			(start -0.67945 -0.305054)
			(end -0.12065 -0.305054)
			(stroke
				(width 0.1)
				(type default)
			)
			(layer "F.Fab")
		)
		(fp_line
			(start 0.67945 -0.3048)
			(end 0.67945 0.3048)
			(stroke
				(width 0.1)
				(type default)
			)
			(layer "F.Fab")
		)
		(fp_line
			(start 0.12065 -0.3048)
			(end 0.67945 -0.3048)
			(stroke
				(width 0.1)
				(type default)
			)
			(layer "F.Fab")
		)
		(fp_line
			(start 0.12065 -0.2794)
			(end 0.12065 -0.3048)
			(stroke
				(width 0.1)
				(type default)
			)
			(layer "F.Fab")
		)
		(fp_line
			(start -0.12065 -0.2794)
			(end 0.12065 -0.2794)
			(stroke
				(width 0.1)
				(type default)
			)
			(layer "F.Fab")
		)
		(fp_line
			(start 0.120396 0.2794)
			(end -0.12065 0.2794)
			(stroke
				(width 0.1)
				(type default)
			)
			(layer "F.Fab")
		)
		(fp_line
			(start -0.12065 0.2794)
			(end -0.12065 0.3048)
			(stroke
				(width 0.1)
				(type default)
			)
			(layer "F.Fab")
		)
		(fp_line
			(start 0.67945 0.3048)
			(end 0.120396 0.3048)
			(stroke
				(width 0.1)
				(type default)
			)
			(layer "F.Fab")
		)
		(fp_line
			(start 0.120396 0.3048)
			(end 0.120396 0.2794)
			(stroke
				(width 0.1)
				(type default)
			)
			(layer "F.Fab")
		)
		(fp_line
			(start -0.12065 0.3048)
			(end -0.67945 0.3048)
			(stroke
				(width 0.1)
				(type default)
			)
			(layer "F.Fab")
		)
		(fp_line
			(start -0.67945 0.3048)
			(end -0.67945 -0.305054)
			(stroke
				(width 0.1)
				(type default)
			)
			(layer "F.Fab")
		)
		(pad "1" smd circle
			(at -0.40005 0 90)
			(size 0 0)
			(layers "F.Cu" "F.Mask" "F.Paste")
			(net "SW_P12V_AUX_P1V8_AUX_FLT")
		)
		(pad "2" smd circle
			(at 0.40005 0 90)
			(size 0 0)
			(layers "F.Cu" "F.Mask" "F.Paste")
			(net "GND")
		)
	)
	(footprint ""
		(layer "F.Cu")
		(at 140.661898 -160.403794 90)
		(property "Reference" "PL34"
			(at 3.955796 -3.199384 0)
			(unlocked yes)
			(layer "F.SilkS")
			(effects
				(font
					(size 0.7874 0.5842)
					(thickness 0.1524)
				)
				(justify left)
			)
		)
		(property "Value" ""
			(at 0 0 90)
			(layer "F.Fab")
			(effects
				(font
					(size 1.27 1.27)
				)
			)
		)
		(duplicate_pad_numbers_are_jumpers no)
		(fp_line
			(start 3.24993 -3.24993)
			(end 3.24993 -2.2352)
			(stroke
				(width 0.1524)
				(type default)
			)
			(layer "F.SilkS")
		)
		(fp_line
			(start -3.24993 -3.24993)
			(end 3.24993 -3.24993)
			(stroke
				(width 0.1524)
				(type default)
			)
			(layer "F.SilkS")
		)
		(fp_line
			(start -3.24993 -2.2352)
			(end -3.24993 -3.24993)
			(stroke
				(width 0.1524)
				(type default)
			)
			(layer "F.SilkS")
		)
		(fp_line
			(start 3.24993 2.2352)
			(end 3.24993 3.24993)
			(stroke
				(width 0.1524)
				(type default)
			)
			(layer "F.SilkS")
		)
		(fp_line
			(start 3.24993 3.24993)
			(end -3.24993 3.24993)
			(stroke
				(width 0.1524)
				(type default)
			)
			(layer "F.SilkS")
		)
		(fp_line
			(start -3.24993 3.24993)
			(end -3.24993 2.2352)
			(stroke
				(width 0.1524)
				(type default)
			)
			(layer "F.SilkS")
		)
		(fp_line
			(start 3.24993 -3.24993)
			(end 3.24993 3.24993)
			(stroke
				(width 0.1)
				(type default)
			)
			(layer "F.Fab")
		)
		(fp_line
			(start -3.24993 -3.24993)
			(end 3.24993 -3.24993)
			(stroke
				(width 0.1)
				(type default)
			)
			(layer "F.Fab")
		)
		(fp_line
			(start 3.24993 3.24993)
			(end -3.24993 3.24993)
			(stroke
				(width 0.1)
				(type default)
			)
			(layer "F.Fab")
		)
		(fp_line
			(start -3.24993 3.24993)
			(end -3.24993 -3.24993)
			(stroke
				(width 0.1)
				(type default)
			)
			(layer "F.Fab")
		)
		(pad "1" smd rect
			(at -2.29997 0 90)
			(size 2.0066 4.2164)
			(layers "F.Cu" "F.Mask" "F.Paste")
			(net "GND")
		)
		(pad "2" smd rect
			(at 2.29997 0 90)
			(size 2.0066 4.2164)
			(layers "F.Cu" "F.Mask" "F.Paste")
			(net "IND_SOC_P1_CPL0")
		)
	)
	(footprint ""
		(layer "F.Cu")
		(at 406.461976 -177.910998 180)
		(property "Reference" "PL64"
			(at -0.472694 5.858002 90)
			(unlocked yes)
			(layer "F.SilkS")
			(effects
				(font
					(size 0.7874 0.5842)
					(thickness 0.1524)
				)
				(justify left)
			)
		)
		(property "Value" ""
			(at 0 0 180)
			(layer "F.Fab")
			(effects
				(font
					(size 1.27 1.27)
				)
			)
		)
		(duplicate_pad_numbers_are_jumpers no)
		(fp_line
			(start 3.750056 5.500116)
			(end 3.750056 -5.500116)
			(stroke
				(width 0.1524)
				(type default)
			)
			(layer "F.SilkS")
		)
		(fp_line
			(start 3.750056 -5.500116)
			(end 2.393442 -5.500116)
			(stroke
				(width 0.1524)
				(type default)
			)
			(layer "F.SilkS")
		)
		(fp_line
			(start 2.393442 5.500116)
			(end 3.750056 5.500116)
			(stroke
				(width 0.1524)
				(type default)
			)
			(layer "F.SilkS")
		)
		(fp_line
			(start -2.393442 5.500116)
			(end -3.750056 5.500116)
			(stroke
				(width 0.1524)
				(type default)
			)
			(layer "F.SilkS")
		)
		(fp_line
			(start -3.750056 5.500116)
			(end -3.750056 -5.500116)
			(stroke
				(width 0.1524)
				(type default)
			)
			(layer "F.SilkS")
		)
		(fp_line
			(start -3.750056 -5.500116)
			(end -2.393442 -5.500116)
			(stroke
				(width 0.1524)
				(type default)
			)
			(layer "F.SilkS")
		)
		(fp_poly
			(pts
				(xy -3.9116 -4.249928) (xy -4.383024 -4.014216) (xy -4.383024 -4.48564)
			)
			(stroke
				(width 0)
				(type default)
			)
			(fill yes)
			(layer "F.SilkS")
		)
		(fp_line
			(start 3.750056 5.500116)
			(end 3.750056 -5.500116)
			(stroke
				(width 0.1)
				(type default)
			)
			(layer "F.Fab")
		)
		(fp_line
			(start 3.750056 -5.500116)
			(end -3.750056 -5.500116)
			(stroke
				(width 0.1)
				(type default)
			)
			(layer "F.Fab")
		)
		(fp_line
			(start -3.750056 5.500116)
			(end 3.750056 5.500116)
			(stroke
				(width 0.1)
				(type default)
			)
			(layer "F.Fab")
		)
		(fp_line
			(start -3.750056 -5.500116)
			(end -3.750056 5.500116)
			(stroke
				(width 0.1)
				(type default)
			)
			(layer "F.Fab")
		)
		(fp_poly
			(pts
				(xy -4.9276 -4.757928) (xy -4.9276 -3.741928) (xy -3.9116 -4.249928)
			)
			(stroke
				(width 0)
				(type default)
			)
			(fill yes)
			(layer "F.Fab")
		)
		(pad "1" smd rect
			(at 0 -4.249928 90)
			(size 2.413 4.5212)
			(layers "F.Cu" "F.Mask" "F.Paste")
			(net "SW_PVDDCR_SOC_P0_SW2")
		)
		(pad "2" smd rect
			(at 0 -1.175004 90)
			(size 1.3716 4.5212)
			(layers "F.Cu" "F.Mask" "F.Paste")
			(net "IND_SOC_P0_CPL3")
		)
		(pad "3" smd rect
			(at 0 1.175004 90)
			(size 1.3716 4.5212)
			(layers "F.Cu" "F.Mask" "F.Paste")
			(net "IND_SOC_P0_CPL2")
		)
		(pad "4" smd rect
			(at 0 4.249928 90)
			(size 2.413 4.5212)
			(layers "F.Cu" "F.Mask" "F.Paste")
			(net "PVDDCR_SOC_P0")
		)
	)
	(footprint ""
		(layer "F.Cu")
		(at 108.841794 -383.7432)
		(property "Reference" "R922"
			(at 0 0 0)
			(layer "F.SilkS")
			(hide yes)
			(effects
				(font
					(size 1.27 1.27)
				)
			)
		)
		(property "Value" ""
			(at 0 0 0)
			(layer "F.Fab")
			(effects
				(font
					(size 1.27 1.27)
				)
			)
		)
		(duplicate_pad_numbers_are_jumpers no)
		(fp_line
			(start -0.32512 -0.175006)
			(end 0.32512 -0.175006)
			(stroke
				(width 0.1)
				(type default)
			)
			(layer "F.Fab")
		)
		(fp_line
			(start -0.32512 0.175006)
			(end -0.32512 -0.175006)
			(stroke
				(width 0.1)
				(type default)
			)
			(layer "F.Fab")
		)
		(fp_line
			(start 0.32512 -0.175006)
			(end 0.32512 0.175006)
			(stroke
				(width 0.1)
				(type default)
			)
			(layer "F.Fab")
		)
		(fp_line
			(start 0.32512 0.175006)
			(end -0.32512 0.175006)
			(stroke
				(width 0.1)
				(type default)
			)
			(layer "F.Fab")
		)
		(pad "1" smd rect
			(at -0.2667 0)
			(size 0.3048 0.381)
			(layers "F.Cu" "F.Mask" "F.Paste")
			(net "P1V8_CPU1_RT_1D")
		)
		(pad "2" smd rect
			(at 0.2667 0 180)
			(size 0.3048 0.381)
			(layers "F.Cu" "F.Mask" "F.Paste")
			(net "TEST2_RT_CPU1_P3")
		)
	)
	(footprint ""
		(layer "F.Cu")
		(at 354.555044 -378.95403 -90)
		(property "Reference" "C940"
			(at 0 0 270)
			(layer "F.SilkS")
			(hide yes)
			(effects
				(font
					(size 1.27 1.27)
				)
			)
		)
		(property "Value" ""
			(at 0 0 270)
			(layer "F.Fab")
			(effects
				(font
					(size 1.27 1.27)
				)
			)
		)
		(duplicate_pad_numbers_are_jumpers no)
		(fp_line
			(start -0.299974 0.150114)
			(end -0.299974 -0.150114)
			(stroke
				(width 0.1)
				(type default)
			)
			(layer "F.Fab")
		)
		(fp_line
			(start 0.299974 0.150114)
			(end -0.299974 0.150114)
			(stroke
				(width 0.1)
				(type default)
			)
			(layer "F.Fab")
		)
		(fp_line
			(start -0.299974 -0.150114)
			(end 0.299974 -0.150114)
			(stroke
				(width 0.1)
				(type default)
			)
			(layer "F.Fab")
		)
		(fp_line
			(start 0.299974 -0.150114)
			(end 0.299974 0.150114)
			(stroke
				(width 0.1)
				(type default)
			)
			(layer "F.Fab")
		)
		(pad "1" smd rect
			(at -0.2667 0 270)
			(size 0.3048 0.381)
			(layers "F.Cu" "F.Mask" "F.Paste")
			(net "P5E_CPU0_P1_TX_C_DN<12>")
		)
		(pad "2" smd rect
			(at 0.2667 0 270)
			(size 0.3048 0.381)
			(layers "F.Cu" "F.Mask" "F.Paste")
			(net "P5E_CPU0_P1_TX_DN<12>")
		)
	)
	(footprint ""
		(layer "F.Cu")
		(at 413.14624 -381.41783 -90)
		(property "Reference" "C852"
			(at 0 0 270)
			(layer "F.SilkS")
			(hide yes)
			(effects
				(font
					(size 1.27 1.27)
				)
			)
		)
		(property "Value" ""
			(at 0 0 270)
			(layer "F.Fab")
			(effects
				(font
					(size 1.27 1.27)
				)
			)
		)
		(duplicate_pad_numbers_are_jumpers no)
		(fp_line
			(start -0.299974 0.150114)
			(end -0.299974 -0.150114)
			(stroke
				(width 0.1)
				(type default)
			)
			(layer "F.Fab")
		)
		(fp_line
			(start 0.299974 0.150114)
			(end -0.299974 0.150114)
			(stroke
				(width 0.1)
				(type default)
			)
			(layer "F.Fab")
		)
		(fp_line
			(start -0.299974 -0.150114)
			(end 0.299974 -0.150114)
			(stroke
				(width 0.1)
				(type default)
			)
			(layer "F.Fab")
		)
		(fp_line
			(start 0.299974 -0.150114)
			(end 0.299974 0.150114)
			(stroke
				(width 0.1)
				(type default)
			)
			(layer "F.Fab")
		)
		(pad "1" smd rect
			(at -0.2667 0 270)
			(size 0.3048 0.381)
			(layers "F.Cu" "F.Mask" "F.Paste")
			(net "P5E_CPU0_P2_TX_C_DN<8>")
		)
		(pad "2" smd rect
			(at 0.2667 0 270)
			(size 0.3048 0.381)
			(layers "F.Cu" "F.Mask" "F.Paste")
			(net "P5E_CPU0_P2_TX_DN<8>")
		)
	)
	(footprint ""
		(layer "F.Cu")
		(at 319.940178 -40.652954)
		(property "Reference" "C2050"
			(at 0 0 0)
			(layer "F.SilkS")
			(hide yes)
			(effects
				(font
					(size 1.27 1.27)
				)
			)
		)
		(property "Value" ""
			(at 0 0 0)
			(layer "F.Fab")
			(effects
				(font
					(size 1.27 1.27)
				)
			)
		)
		(duplicate_pad_numbers_are_jumpers no)
		(fp_line
			(start -0.7874 -0.4064)
			(end 0.7874 -0.4064)
			(stroke
				(width 0.1524)
				(type default)
			)
			(layer "F.SilkS")
		)
		(fp_line
			(start -0.7874 0.4064)
			(end -0.7874 -0.4064)
			(stroke
				(width 0.1524)
				(type default)
			)
			(layer "F.SilkS")
		)
		(fp_line
			(start 0.7874 -0.4064)
			(end 0.7874 0.4064)
			(stroke
				(width 0.1524)
				(type default)
			)
			(layer "F.SilkS")
		)
		(fp_line
			(start 0.7874 0.4064)
			(end -0.7874 0.4064)
			(stroke
				(width 0.1524)
				(type default)
			)
			(layer "F.SilkS")
		)
		(fp_line
			(start -0.67945 -0.305054)
			(end -0.12065 -0.305054)
			(stroke
				(width 0.1)
				(type default)
			)
			(layer "F.Fab")
		)
		(fp_line
			(start -0.67945 0.3048)
			(end -0.67945 -0.305054)
			(stroke
				(width 0.1)
				(type default)
			)
			(layer "F.Fab")
		)
		(fp_line
			(start -0.12065 -0.305054)
			(end -0.12065 -0.2794)
			(stroke
				(width 0.1)
				(type default)
			)
			(layer "F.Fab")
		)
		(fp_line
			(start -0.12065 -0.2794)
			(end 0.12065 -0.2794)
			(stroke
				(width 0.1)
				(type default)
			)
			(layer "F.Fab")
		)
		(fp_line
			(start -0.12065 0.2794)
			(end -0.12065 0.3048)
			(stroke
				(width 0.1)
				(type default)
			)
			(layer "F.Fab")
		)
		(fp_line
			(start -0.12065 0.3048)
			(end -0.67945 0.3048)
			(stroke
				(width 0.1)
				(type default)
			)
			(layer "F.Fab")
		)
		(fp_line
			(start 0.120396 0.2794)
			(end -0.12065 0.2794)
			(stroke
				(width 0.1)
				(type default)
			)
			(layer "F.Fab")
		)
		(fp_line
			(start 0.120396 0.3048)
			(end 0.120396 0.2794)
			(stroke
				(width 0.1)
				(type default)
			)
			(layer "F.Fab")
		)
		(fp_line
			(start 0.12065 -0.3048)
			(end 0.67945 -0.3048)
			(stroke
				(width 0.1)
				(type default)
			)
			(layer "F.Fab")
		)
		(fp_line
			(start 0.12065 -0.2794)
			(end 0.12065 -0.3048)
			(stroke
				(width 0.1)
				(type default)
			)
			(layer "F.Fab")
		)
		(fp_line
			(start 0.67945 -0.3048)
			(end 0.67945 0.3048)
			(stroke
				(width 0.1)
				(type default)
			)
			(layer "F.Fab")
		)
		(fp_line
			(start 0.67945 0.3048)
			(end 0.120396 0.3048)
			(stroke
				(width 0.1)
				(type default)
			)
			(layer "F.Fab")
		)
		(pad "1" smd circle
			(at -0.40005 0)
			(size 0 0)
			(layers "F.Cu" "F.Mask" "F.Paste")
			(net "P3V3_PDB_AUX_ADC_TIC")
		)
		(pad "2" smd circle
			(at 0.40005 0)
			(size 0 0)
			(layers "F.Cu" "F.Mask" "F.Paste")
			(net "GND")
		)
	)
	(footprint ""
		(layer "F.Cu")
		(at 161.097976 -129.295652 -90)
		(property "Reference" "R552"
			(at 0 0 270)
			(layer "F.SilkS")
			(hide yes)
			(effects
				(font
					(size 1.27 1.27)
				)
			)
		)
		(property "Value" ""
			(at 0 0 270)
			(layer "F.Fab")
			(effects
				(font
					(size 1.27 1.27)
				)
			)
		)
		(duplicate_pad_numbers_are_jumpers no)
		(fp_line
			(start -0.7874 0.4064)
			(end -0.7874 -0.4064)
			(stroke
				(width 0.1524)
				(type default)
			)
			(layer "F.SilkS")
		)
		(fp_line
			(start 0.7874 0.4064)
			(end -0.7874 0.4064)
			(stroke
				(width 0.1524)
				(type default)
			)
			(layer "F.SilkS")
		)
		(fp_line
			(start -0.7874 -0.4064)
			(end 0.7874 -0.4064)
			(stroke
				(width 0.1524)
				(type default)
			)
			(layer "F.SilkS")
		)
		(fp_line
			(start 0.7874 -0.4064)
			(end 0.7874 0.4064)
			(stroke
				(width 0.1524)
				(type default)
			)
			(layer "F.SilkS")
		)
		(fp_line
			(start -0.67945 0.3048)
			(end -0.67945 -0.305054)
			(stroke
				(width 0.1)
				(type default)
			)
			(layer "F.Fab")
		)
		(fp_line
			(start -0.12065 0.3048)
			(end -0.67945 0.3048)
			(stroke
				(width 0.1)
				(type default)
			)
			(layer "F.Fab")
		)
		(fp_line
			(start 0.120396 0.3048)
			(end 0.120396 0.2794)
			(stroke
				(width 0.1)
				(type default)
			)
			(layer "F.Fab")
		)
		(fp_line
			(start 0.67945 0.3048)
			(end 0.120396 0.3048)
			(stroke
				(width 0.1)
				(type default)
			)
			(layer "F.Fab")
		)
		(fp_line
			(start -0.12065 0.2794)
			(end -0.12065 0.3048)
			(stroke
				(width 0.1)
				(type default)
			)
			(layer "F.Fab")
		)
		(fp_line
			(start 0.120396 0.2794)
			(end -0.12065 0.2794)
			(stroke
				(width 0.1)
				(type default)
			)
			(layer "F.Fab")
		)
		(fp_line
			(start -0.12065 -0.2794)
			(end 0.12065 -0.2794)
			(stroke
				(width 0.1)
				(type default)
			)
			(layer "F.Fab")
		)
		(fp_line
			(start 0.12065 -0.2794)
			(end 0.12065 -0.3048)
			(stroke
				(width 0.1)
				(type default)
			)
			(layer "F.Fab")
		)
		(fp_line
			(start 0.12065 -0.3048)
			(end 0.67945 -0.3048)
			(stroke
				(width 0.1)
				(type default)
			)
			(layer "F.Fab")
		)
		(fp_line
			(start 0.67945 -0.3048)
			(end 0.67945 0.3048)
			(stroke
				(width 0.1)
				(type default)
			)
			(layer "F.Fab")
		)
		(fp_line
			(start -0.67945 -0.305054)
			(end -0.12065 -0.305054)
			(stroke
				(width 0.1)
				(type default)
			)
			(layer "F.Fab")
		)
		(fp_line
			(start -0.12065 -0.305054)
			(end -0.12065 -0.2794)
			(stroke
				(width 0.1)
				(type default)
			)
			(layer "F.Fab")
		)
		(pad "1" smd circle
			(at -0.40005 0 270)
			(size 0 0)
			(layers "F.Cu" "F.Mask" "F.Paste")
			(net "P3V3_AUX")
		)
		(pad "2" smd circle
			(at 0.40005 0 270)
			(size 0 0)
			(layers "F.Cu" "F.Mask" "F.Paste")
			(net "PWRGD_P5V_R2")
		)
	)
	(footprint ""
		(layer "F.Cu")
		(at 224.074482 -57.386982 90)
		(property "Reference" "R3767"
			(at 4.689348 -1.951482 0)
			(unlocked yes)
			(layer "F.SilkS")
			(effects
				(font
					(size 0.7874 0.5842)
					(thickness 0.1524)
				)
				(justify left)
			)
		)
		(property "Value" ""
			(at 0 0 90)
			(layer "F.Fab")
			(effects
				(font
					(size 1.27 1.27)
				)
			)
		)
		(duplicate_pad_numbers_are_jumpers no)
		(fp_line
			(start 3.937508 -1.8796)
			(end -3.937508 -1.8796)
			(stroke
				(width 0.1524)
				(type default)
			)
			(layer "F.SilkS")
		)
		(fp_line
			(start -3.937508 -1.8796)
			(end -3.937508 1.8796)
			(stroke
				(width 0.1524)
				(type default)
			)
			(layer "F.SilkS")
		)
		(fp_line
			(start 3.937508 1.8796)
			(end 3.937508 -1.8796)
			(stroke
				(width 0.1524)
				(type default)
			)
			(layer "F.SilkS")
		)
		(fp_line
			(start -3.937508 1.8796)
			(end 3.937508 1.8796)
			(stroke
				(width 0.1524)
				(type default)
			)
			(layer "F.SilkS")
		)
		(fp_line
			(start 3.275076 -1.674876)
			(end -3.275076 -1.674876)
			(stroke
				(width 0.1)
				(type default)
			)
			(layer "F.Fab")
		)
		(fp_line
			(start -3.275076 -1.674876)
			(end -3.275076 1.674876)
			(stroke
				(width 0.1)
				(type default)
			)
			(layer "F.Fab")
		)
		(fp_line
			(start 3.275076 1.674876)
			(end 3.275076 -1.674876)
			(stroke
				(width 0.1)
				(type default)
			)
			(layer "F.Fab")
		)
		(fp_line
			(start -3.275076 1.674876)
			(end 3.275076 1.674876)
			(stroke
				(width 0.1)
				(type default)
			)
			(layer "F.Fab")
		)
		(pad "1" smd rect
			(at -2.350008 0 90)
			(size 2.921 3.5052)
			(layers "F.Cu" "F.Mask" "F.Paste")
			(net "P3V3_E1S_0")
		)
		(pad "2" smd rect
			(at 2.350008 0 90)
			(size 2.921 3.5052)
			(layers "F.Cu" "F.Mask" "F.Paste")
			(net "P3V3_E1S_0_R")
		)
	)
	(footprint ""
		(layer "F.Cu")
		(at 448.271392 -47.506382 -90)
		(property "Reference" "PC576"
			(at 0 0 270)
			(layer "F.SilkS")
			(hide yes)
			(effects
				(font
					(size 1.27 1.27)
				)
			)
		)
		(property "Value" ""
			(at 0 0 270)
			(layer "F.Fab")
			(effects
				(font
					(size 1.27 1.27)
				)
			)
		)
		(duplicate_pad_numbers_are_jumpers no)
		(fp_line
			(start -1.524 0.762)
			(end -1.524 -0.762)
			(stroke
				(width 0.1524)
				(type default)
			)
			(layer "F.SilkS")
		)
		(fp_line
			(start 1.524 0.762)
			(end -1.524 0.762)
			(stroke
				(width 0.1524)
				(type default)
			)
			(layer "F.SilkS")
		)
		(fp_line
			(start -1.524 -0.762)
			(end 1.524 -0.762)
			(stroke
				(width 0.1524)
				(type default)
			)
			(layer "F.SilkS")
		)
		(fp_line
			(start 1.524 -0.762)
			(end 1.524 0.762)
			(stroke
				(width 0.1524)
				(type default)
			)
			(layer "F.SilkS")
		)
		(fp_line
			(start -1.1049 0.724916)
			(end 1.1049 0.724916)
			(stroke
				(width 0.1)
				(type default)
			)
			(layer "F.Fab")
		)
		(fp_line
			(start 1.1049 0.724916)
			(end 1.1049 -0.724916)
			(stroke
				(width 0.1)
				(type default)
			)
			(layer "F.Fab")
		)
		(fp_line
			(start -1.1049 -0.724916)
			(end -1.1049 0.724916)
			(stroke
				(width 0.1)
				(type default)
			)
			(layer "F.Fab")
		)
		(fp_line
			(start 1.1049 -0.724916)
			(end -1.1049 -0.724916)
			(stroke
				(width 0.1)
				(type default)
			)
			(layer "F.Fab")
		)
		(pad "1" smd rect
			(at -0.889 0 90)
			(size 1.016 1.27)
			(layers "F.Cu" "F.Mask" "F.Paste")
			(net "SW_P3V3_AUX_FLT")
		)
		(pad "2" smd rect
			(at 0.889 0 90)
			(size 1.016 1.27)
			(layers "F.Cu" "F.Mask" "F.Paste")
			(net "GND")
		)
	)
	(footprint ""
		(layer "F.Cu")
		(at 441.951872 -351.415858)
		(property "Reference" "H34"
			(at -1.7272 -4.177792 0)
			(unlocked yes)
			(layer "F.SilkS")
			(effects
				(font
					(size 0.7874 0.5842)
					(thickness 0.1524)
				)
				(justify left)
			)
		)
		(property "Value" ""
			(at 0 0 0)
			(layer "F.Fab")
			(effects
				(font
					(size 1.27 1.27)
				)
			)
		)
		(duplicate_pad_numbers_are_jumpers no)
		(pad "1" thru_hole circle
			(at 0 0)
			(size 6.1976 6.1976)
			(drill 3.7338)
			(layers "*.Cu" "*.Mask")
			(remove_unused_layers no)
			(net "GND")
			(clearance -0.9779)
			(padstack
				(mode front_inner_back)
				(layer "Inner"
					(shape circle)
					(size 5.5372 5.5372)
					(clearance -0.6477)
				)
				(layer "B.Cu"
					(shape circle)
					(size 6.1976 6.1976)
					(clearance -0.9779)
				)
			)
		)
	)
	(footprint ""
		(layer "F.Cu")
		(at 308.420516 -437.498744 -90)
		(property "Reference" "R4134"
			(at 0 0 270)
			(layer "F.SilkS")
			(hide yes)
			(effects
				(font
					(size 1.27 1.27)
				)
			)
		)
		(property "Value" ""
			(at 0 0 270)
			(layer "F.Fab")
			(effects
				(font
					(size 1.27 1.27)
				)
			)
		)
		(duplicate_pad_numbers_are_jumpers no)
		(fp_line
			(start -0.7874 0.4064)
			(end -0.7874 -0.4064)
			(stroke
				(width 0.1524)
				(type default)
			)
			(layer "F.SilkS")
		)
		(fp_line
			(start 0.7874 0.4064)
			(end -0.7874 0.4064)
			(stroke
				(width 0.1524)
				(type default)
			)
			(layer "F.SilkS")
		)
		(fp_line
			(start -0.7874 -0.4064)
			(end 0.7874 -0.4064)
			(stroke
				(width 0.1524)
				(type default)
			)
			(layer "F.SilkS")
		)
		(fp_line
			(start 0.7874 -0.4064)
			(end 0.7874 0.4064)
			(stroke
				(width 0.1524)
				(type default)
			)
			(layer "F.SilkS")
		)
		(fp_line
			(start -0.67945 0.3048)
			(end -0.67945 -0.305054)
			(stroke
				(width 0.1)
				(type default)
			)
			(layer "F.Fab")
		)
		(fp_line
			(start -0.12065 0.3048)
			(end -0.67945 0.3048)
			(stroke
				(width 0.1)
				(type default)
			)
			(layer "F.Fab")
		)
		(fp_line
			(start 0.120396 0.3048)
			(end 0.120396 0.2794)
			(stroke
				(width 0.1)
				(type default)
			)
			(layer "F.Fab")
		)
		(fp_line
			(start 0.67945 0.3048)
			(end 0.120396 0.3048)
			(stroke
				(width 0.1)
				(type default)
			)
			(layer "F.Fab")
		)
		(fp_line
			(start -0.12065 0.2794)
			(end -0.12065 0.3048)
			(stroke
				(width 0.1)
				(type default)
			)
			(layer "F.Fab")
		)
		(fp_line
			(start 0.120396 0.2794)
			(end -0.12065 0.2794)
			(stroke
				(width 0.1)
				(type default)
			)
			(layer "F.Fab")
		)
		(fp_line
			(start -0.12065 -0.2794)
			(end 0.12065 -0.2794)
			(stroke
				(width 0.1)
				(type default)
			)
			(layer "F.Fab")
		)
		(fp_line
			(start 0.12065 -0.2794)
			(end 0.12065 -0.3048)
			(stroke
				(width 0.1)
				(type default)
			)
			(layer "F.Fab")
		)
		(fp_line
			(start 0.12065 -0.3048)
			(end 0.67945 -0.3048)
			(stroke
				(width 0.1)
				(type default)
			)
			(layer "F.Fab")
		)
		(fp_line
			(start 0.67945 -0.3048)
			(end 0.67945 0.3048)
			(stroke
				(width 0.1)
				(type default)
			)
			(layer "F.Fab")
		)
		(fp_line
			(start -0.67945 -0.305054)
			(end -0.12065 -0.305054)
			(stroke
				(width 0.1)
				(type default)
			)
			(layer "F.Fab")
		)
		(fp_line
			(start -0.12065 -0.305054)
			(end -0.12065 -0.2794)
			(stroke
				(width 0.1)
				(type default)
			)
			(layer "F.Fab")
		)
		(pad "1" smd circle
			(at -0.40005 0 270)
			(size 0 0)
			(layers "F.Cu" "F.Mask" "F.Paste")
			(net "GPU_3V3IO_RSVD5_FFU")
		)
		(pad "2" smd circle
			(at 0.40005 0 270)
			(size 0 0)
			(layers "F.Cu" "F.Mask" "F.Paste")
			(net "GND")
		)
	)
	(footprint ""
		(layer "F.Cu")
		(at 363.793278 -171.64431)
		(property "Reference" "PC479_1"
			(at 0 0 0)
			(layer "F.SilkS")
			(hide yes)
			(effects
				(font
					(size 1.27 1.27)
				)
			)
		)
		(property "Value" ""
			(at 0 0 0)
			(layer "F.Fab")
			(effects
				(font
					(size 1.27 1.27)
				)
			)
		)
		(duplicate_pad_numbers_are_jumpers no)
		(fp_line
			(start -0.7874 -0.4064)
			(end 0.7874 -0.4064)
			(stroke
				(width 0.1524)
				(type default)
			)
			(layer "F.SilkS")
		)
		(fp_line
			(start -0.7874 0.4064)
			(end -0.7874 -0.4064)
			(stroke
				(width 0.1524)
				(type default)
			)
			(layer "F.SilkS")
		)
		(fp_line
			(start 0.7874 -0.4064)
			(end 0.7874 0.4064)
			(stroke
				(width 0.1524)
				(type default)
			)
			(layer "F.SilkS")
		)
		(fp_line
			(start 0.7874 0.4064)
			(end -0.7874 0.4064)
			(stroke
				(width 0.1524)
				(type default)
			)
			(layer "F.SilkS")
		)
		(fp_line
			(start -0.67945 -0.305054)
			(end -0.12065 -0.305054)
			(stroke
				(width 0.1)
				(type default)
			)
			(layer "F.Fab")
		)
		(fp_line
			(start -0.67945 0.3048)
			(end -0.67945 -0.305054)
			(stroke
				(width 0.1)
				(type default)
			)
			(layer "F.Fab")
		)
		(fp_line
			(start -0.12065 -0.305054)
			(end -0.12065 -0.2794)
			(stroke
				(width 0.1)
				(type default)
			)
			(layer "F.Fab")
		)
		(fp_line
			(start -0.12065 -0.2794)
			(end 0.12065 -0.2794)
			(stroke
				(width 0.1)
				(type default)
			)
			(layer "F.Fab")
		)
		(fp_line
			(start -0.12065 0.2794)
			(end -0.12065 0.3048)
			(stroke
				(width 0.1)
				(type default)
			)
			(layer "F.Fab")
		)
		(fp_line
			(start -0.12065 0.3048)
			(end -0.67945 0.3048)
			(stroke
				(width 0.1)
				(type default)
			)
			(layer "F.Fab")
		)
		(fp_line
			(start 0.120396 0.2794)
			(end -0.12065 0.2794)
			(stroke
				(width 0.1)
				(type default)
			)
			(layer "F.Fab")
		)
		(fp_line
			(start 0.120396 0.3048)
			(end 0.120396 0.2794)
			(stroke
				(width 0.1)
				(type default)
			)
			(layer "F.Fab")
		)
		(fp_line
			(start 0.12065 -0.3048)
			(end 0.67945 -0.3048)
			(stroke
				(width 0.1)
				(type default)
			)
			(layer "F.Fab")
		)
		(fp_line
			(start 0.12065 -0.2794)
			(end 0.12065 -0.3048)
			(stroke
				(width 0.1)
				(type default)
			)
			(layer "F.Fab")
		)
		(fp_line
			(start 0.67945 -0.3048)
			(end 0.67945 0.3048)
			(stroke
				(width 0.1)
				(type default)
			)
			(layer "F.Fab")
		)
		(fp_line
			(start 0.67945 0.3048)
			(end 0.120396 0.3048)
			(stroke
				(width 0.1)
				(type default)
			)
			(layer "F.Fab")
		)
		(pad "1" smd circle
			(at -0.40005 0)
			(size 0 0)
			(layers "F.Cu" "F.Mask" "F.Paste")
			(net "SW_P12V_AUX_PVDDCR_CPU0_P0_FLT")
		)
		(pad "2" smd circle
			(at 0.40005 0)
			(size 0 0)
			(layers "F.Cu" "F.Mask" "F.Paste")
			(net "GND")
		)
	)
	(footprint ""
		(layer "F.Cu")
		(at 126.58979 -27.863546 -90)
		(property "Reference" "C91"
			(at 0 0 270)
			(layer "F.SilkS")
			(hide yes)
			(effects
				(font
					(size 1.27 1.27)
				)
			)
		)
		(property "Value" ""
			(at 0 0 270)
			(layer "F.Fab")
			(effects
				(font
					(size 1.27 1.27)
				)
			)
		)
		(duplicate_pad_numbers_are_jumpers no)
		(fp_line
			(start -0.7874 0.4064)
			(end -0.7874 -0.4064)
			(stroke
				(width 0.1524)
				(type default)
			)
			(layer "F.SilkS")
		)
		(fp_line
			(start 0.7874 0.4064)
			(end -0.7874 0.4064)
			(stroke
				(width 0.1524)
				(type default)
			)
			(layer "F.SilkS")
		)
		(fp_line
			(start -0.7874 -0.4064)
			(end 0.7874 -0.4064)
			(stroke
				(width 0.1524)
				(type default)
			)
			(layer "F.SilkS")
		)
		(fp_line
			(start 0.7874 -0.4064)
			(end 0.7874 0.4064)
			(stroke
				(width 0.1524)
				(type default)
			)
			(layer "F.SilkS")
		)
		(fp_line
			(start -0.67945 0.3048)
			(end -0.67945 -0.305054)
			(stroke
				(width 0.1)
				(type default)
			)
			(layer "F.Fab")
		)
		(fp_line
			(start -0.12065 0.3048)
			(end -0.67945 0.3048)
			(stroke
				(width 0.1)
				(type default)
			)
			(layer "F.Fab")
		)
		(fp_line
			(start 0.120396 0.3048)
			(end 0.120396 0.2794)
			(stroke
				(width 0.1)
				(type default)
			)
			(layer "F.Fab")
		)
		(fp_line
			(start 0.67945 0.3048)
			(end 0.120396 0.3048)
			(stroke
				(width 0.1)
				(type default)
			)
			(layer "F.Fab")
		)
		(fp_line
			(start -0.12065 0.2794)
			(end -0.12065 0.3048)
			(stroke
				(width 0.1)
				(type default)
			)
			(layer "F.Fab")
		)
		(fp_line
			(start 0.120396 0.2794)
			(end -0.12065 0.2794)
			(stroke
				(width 0.1)
				(type default)
			)
			(layer "F.Fab")
		)
		(fp_line
			(start -0.12065 -0.2794)
			(end 0.12065 -0.2794)
			(stroke
				(width 0.1)
				(type default)
			)
			(layer "F.Fab")
		)
		(fp_line
			(start 0.12065 -0.2794)
			(end 0.12065 -0.3048)
			(stroke
				(width 0.1)
				(type default)
			)
			(layer "F.Fab")
		)
		(fp_line
			(start 0.12065 -0.3048)
			(end 0.67945 -0.3048)
			(stroke
				(width 0.1)
				(type default)
			)
			(layer "F.Fab")
		)
		(fp_line
			(start 0.67945 -0.3048)
			(end 0.67945 0.3048)
			(stroke
				(width 0.1)
				(type default)
			)
			(layer "F.Fab")
		)
		(fp_line
			(start -0.67945 -0.305054)
			(end -0.12065 -0.305054)
			(stroke
				(width 0.1)
				(type default)
			)
			(layer "F.Fab")
		)
		(fp_line
			(start -0.12065 -0.305054)
			(end -0.12065 -0.2794)
			(stroke
				(width 0.1)
				(type default)
			)
			(layer "F.Fab")
		)
		(pad "1" smd circle
			(at -0.40005 0 270)
			(size 0 0)
			(layers "F.Cu" "F.Mask" "F.Paste")
			(net "XTAL_USB_CPU0_HUB1_XIN")
		)
		(pad "2" smd circle
			(at 0.40005 0 270)
			(size 0 0)
			(layers "F.Cu" "F.Mask" "F.Paste")
			(net "GND")
		)
	)
	(footprint ""
		(layer "F.Cu")
		(at 163.4236 -438.912)
		(property "Reference" "R2920"
			(at 0 0 0)
			(layer "F.SilkS")
			(hide yes)
			(effects
				(font
					(size 1.27 1.27)
				)
			)
		)
		(property "Value" ""
			(at 0 0 0)
			(layer "F.Fab")
			(effects
				(font
					(size 1.27 1.27)
				)
			)
		)
		(duplicate_pad_numbers_are_jumpers no)
		(fp_line
			(start -0.7874 -0.4064)
			(end 0.7874 -0.4064)
			(stroke
				(width 0.1524)
				(type default)
			)
			(layer "F.SilkS")
		)
		(fp_line
			(start -0.7874 0.4064)
			(end -0.7874 -0.4064)
			(stroke
				(width 0.1524)
				(type default)
			)
			(layer "F.SilkS")
		)
		(fp_line
			(start 0.7874 -0.4064)
			(end 0.7874 0.4064)
			(stroke
				(width 0.1524)
				(type default)
			)
			(layer "F.SilkS")
		)
		(fp_line
			(start 0.7874 0.4064)
			(end -0.7874 0.4064)
			(stroke
				(width 0.1524)
				(type default)
			)
			(layer "F.SilkS")
		)
		(fp_line
			(start -0.67945 -0.305054)
			(end -0.12065 -0.305054)
			(stroke
				(width 0.1)
				(type default)
			)
			(layer "F.Fab")
		)
		(fp_line
			(start -0.67945 0.3048)
			(end -0.67945 -0.305054)
			(stroke
				(width 0.1)
				(type default)
			)
			(layer "F.Fab")
		)
		(fp_line
			(start -0.12065 -0.305054)
			(end -0.12065 -0.2794)
			(stroke
				(width 0.1)
				(type default)
			)
			(layer "F.Fab")
		)
		(fp_line
			(start -0.12065 -0.2794)
			(end 0.12065 -0.2794)
			(stroke
				(width 0.1)
				(type default)
			)
			(layer "F.Fab")
		)
		(fp_line
			(start -0.12065 0.2794)
			(end -0.12065 0.3048)
			(stroke
				(width 0.1)
				(type default)
			)
			(layer "F.Fab")
		)
		(fp_line
			(start -0.12065 0.3048)
			(end -0.67945 0.3048)
			(stroke
				(width 0.1)
				(type default)
			)
			(layer "F.Fab")
		)
		(fp_line
			(start 0.120396 0.2794)
			(end -0.12065 0.2794)
			(stroke
				(width 0.1)
				(type default)
			)
			(layer "F.Fab")
		)
		(fp_line
			(start 0.120396 0.3048)
			(end 0.120396 0.2794)
			(stroke
				(width 0.1)
				(type default)
			)
			(layer "F.Fab")
		)
		(fp_line
			(start 0.12065 -0.3048)
			(end 0.67945 -0.3048)
			(stroke
				(width 0.1)
				(type default)
			)
			(layer "F.Fab")
		)
		(fp_line
			(start 0.12065 -0.2794)
			(end 0.12065 -0.3048)
			(stroke
				(width 0.1)
				(type default)
			)
			(layer "F.Fab")
		)
		(fp_line
			(start 0.67945 -0.3048)
			(end 0.67945 0.3048)
			(stroke
				(width 0.1)
				(type default)
			)
			(layer "F.Fab")
		)
		(fp_line
			(start 0.67945 0.3048)
			(end 0.120396 0.3048)
			(stroke
				(width 0.1)
				(type default)
			)
			(layer "F.Fab")
		)
		(pad "1" smd circle
			(at -0.40005 0)
			(size 0 0)
			(layers "F.Cu" "F.Mask" "F.Paste")
			(net "P3V3_AUX")
		)
		(pad "2" smd circle
			(at 0.40005 0)
			(size 0 0)
			(layers "F.Cu" "F.Mask" "F.Paste")
			(net "BIC_MONITER_ISO")
		)
	)
	(footprint ""
		(layer "F.Cu")
		(at 425.79163 -389.802116 -90)
		(property "Reference" "R1404"
			(at 0 0 270)
			(layer "F.SilkS")
			(hide yes)
			(effects
				(font
					(size 1.27 1.27)
				)
			)
		)
		(property "Value" ""
			(at 0 0 270)
			(layer "F.Fab")
			(effects
				(font
					(size 1.27 1.27)
				)
			)
		)
		(duplicate_pad_numbers_are_jumpers no)
		(fp_line
			(start -0.32512 0.175006)
			(end -0.32512 -0.175006)
			(stroke
				(width 0.1)
				(type default)
			)
			(layer "F.Fab")
		)
		(fp_line
			(start 0.32512 0.175006)
			(end -0.32512 0.175006)
			(stroke
				(width 0.1)
				(type default)
			)
			(layer "F.Fab")
		)
		(fp_line
			(start -0.32512 -0.175006)
			(end 0.32512 -0.175006)
			(stroke
				(width 0.1)
				(type default)
			)
			(layer "F.Fab")
		)
		(fp_line
			(start 0.32512 -0.175006)
			(end 0.32512 0.175006)
			(stroke
				(width 0.1)
				(type default)
			)
			(layer "F.Fab")
		)
		(pad "1" smd rect
			(at -0.2667 0 270)
			(size 0.3048 0.381)
			(layers "F.Cu" "F.Mask" "F.Paste")
			(net "CLKREQ_RT_CPU0_P2_N")
		)
		(pad "2" smd rect
			(at 0.2667 0 90)
			(size 0.3048 0.381)
			(layers "F.Cu" "F.Mask" "F.Paste")
			(net "GND")
		)
	)
	(footprint ""
		(layer "F.Cu")
		(at 34.665158 -171.52366)
		(property "Reference" "R5010"
			(at 0 0 0)
			(layer "F.SilkS")
			(hide yes)
			(effects
				(font
					(size 1.27 1.27)
				)
			)
		)
		(property "Value" ""
			(at 0 0 0)
			(layer "F.Fab")
			(effects
				(font
					(size 1.27 1.27)
				)
			)
		)
		(duplicate_pad_numbers_are_jumpers no)
		(fp_line
			(start -0.7874 -0.4064)
			(end 0.7874 -0.4064)
			(stroke
				(width 0.1524)
				(type default)
			)
			(layer "F.SilkS")
		)
		(fp_line
			(start -0.7874 0.4064)
			(end -0.7874 -0.4064)
			(stroke
				(width 0.1524)
				(type default)
			)
			(layer "F.SilkS")
		)
		(fp_line
			(start 0.7874 -0.4064)
			(end 0.7874 0.4064)
			(stroke
				(width 0.1524)
				(type default)
			)
			(layer "F.SilkS")
		)
		(fp_line
			(start 0.7874 0.4064)
			(end -0.7874 0.4064)
			(stroke
				(width 0.1524)
				(type default)
			)
			(layer "F.SilkS")
		)
		(fp_line
			(start -0.67945 -0.305054)
			(end -0.12065 -0.305054)
			(stroke
				(width 0.1)
				(type default)
			)
			(layer "F.Fab")
		)
		(fp_line
			(start -0.67945 0.3048)
			(end -0.67945 -0.305054)
			(stroke
				(width 0.1)
				(type default)
			)
			(layer "F.Fab")
		)
		(fp_line
			(start -0.12065 -0.305054)
			(end -0.12065 -0.2794)
			(stroke
				(width 0.1)
				(type default)
			)
			(layer "F.Fab")
		)
		(fp_line
			(start -0.12065 -0.2794)
			(end 0.12065 -0.2794)
			(stroke
				(width 0.1)
				(type default)
			)
			(layer "F.Fab")
		)
		(fp_line
			(start -0.12065 0.2794)
			(end -0.12065 0.3048)
			(stroke
				(width 0.1)
				(type default)
			)
			(layer "F.Fab")
		)
		(fp_line
			(start -0.12065 0.3048)
			(end -0.67945 0.3048)
			(stroke
				(width 0.1)
				(type default)
			)
			(layer "F.Fab")
		)
		(fp_line
			(start 0.120396 0.2794)
			(end -0.12065 0.2794)
			(stroke
				(width 0.1)
				(type default)
			)
			(layer "F.Fab")
		)
		(fp_line
			(start 0.120396 0.3048)
			(end 0.120396 0.2794)
			(stroke
				(width 0.1)
				(type default)
			)
			(layer "F.Fab")
		)
		(fp_line
			(start 0.12065 -0.3048)
			(end 0.67945 -0.3048)
			(stroke
				(width 0.1)
				(type default)
			)
			(layer "F.Fab")
		)
		(fp_line
			(start 0.12065 -0.2794)
			(end 0.12065 -0.3048)
			(stroke
				(width 0.1)
				(type default)
			)
			(layer "F.Fab")
		)
		(fp_line
			(start 0.67945 -0.3048)
			(end 0.67945 0.3048)
			(stroke
				(width 0.1)
				(type default)
			)
			(layer "F.Fab")
		)
		(fp_line
			(start 0.67945 0.3048)
			(end 0.120396 0.3048)
			(stroke
				(width 0.1)
				(type default)
			)
			(layer "F.Fab")
		)
		(pad "1" smd circle
			(at -0.40005 0)
			(size 0 0)
			(layers "F.Cu" "F.Mask" "F.Paste")
			(net "PVDD11_S3_P1")
		)
		(pad "2" smd circle
			(at 0.40005 0)
			(size 0 0)
			(layers "F.Cu" "F.Mask" "F.Paste")
			(net "I3C_SPD_DDRAF_CPU1_LVC1_SCL")
		)
	)
	(footprint ""
		(layer "F.Cu")
		(at 323.637148 -42.176954)
		(property "Reference" "R3683"
			(at 0 0 0)
			(layer "F.SilkS")
			(hide yes)
			(effects
				(font
					(size 1.27 1.27)
				)
			)
		)
		(property "Value" ""
			(at 0 0 0)
			(layer "F.Fab")
			(effects
				(font
					(size 1.27 1.27)
				)
			)
		)
		(duplicate_pad_numbers_are_jumpers no)
		(fp_line
			(start -0.7874 -0.4064)
			(end 0.7874 -0.4064)
			(stroke
				(width 0.1524)
				(type default)
			)
			(layer "F.SilkS")
		)
		(fp_line
			(start -0.7874 0.4064)
			(end -0.7874 -0.4064)
			(stroke
				(width 0.1524)
				(type default)
			)
			(layer "F.SilkS")
		)
		(fp_line
			(start 0.7874 -0.4064)
			(end 0.7874 0.4064)
			(stroke
				(width 0.1524)
				(type default)
			)
			(layer "F.SilkS")
		)
		(fp_line
			(start 0.7874 0.4064)
			(end -0.7874 0.4064)
			(stroke
				(width 0.1524)
				(type default)
			)
			(layer "F.SilkS")
		)
		(fp_line
			(start -0.67945 -0.305054)
			(end -0.12065 -0.305054)
			(stroke
				(width 0.1)
				(type default)
			)
			(layer "F.Fab")
		)
		(fp_line
			(start -0.67945 0.3048)
			(end -0.67945 -0.305054)
			(stroke
				(width 0.1)
				(type default)
			)
			(layer "F.Fab")
		)
		(fp_line
			(start -0.12065 -0.305054)
			(end -0.12065 -0.2794)
			(stroke
				(width 0.1)
				(type default)
			)
			(layer "F.Fab")
		)
		(fp_line
			(start -0.12065 -0.2794)
			(end 0.12065 -0.2794)
			(stroke
				(width 0.1)
				(type default)
			)
			(layer "F.Fab")
		)
		(fp_line
			(start -0.12065 0.2794)
			(end -0.12065 0.3048)
			(stroke
				(width 0.1)
				(type default)
			)
			(layer "F.Fab")
		)
		(fp_line
			(start -0.12065 0.3048)
			(end -0.67945 0.3048)
			(stroke
				(width 0.1)
				(type default)
			)
			(layer "F.Fab")
		)
		(fp_line
			(start 0.120396 0.2794)
			(end -0.12065 0.2794)
			(stroke
				(width 0.1)
				(type default)
			)
			(layer "F.Fab")
		)
		(fp_line
			(start 0.120396 0.3048)
			(end 0.120396 0.2794)
			(stroke
				(width 0.1)
				(type default)
			)
			(layer "F.Fab")
		)
		(fp_line
			(start 0.12065 -0.3048)
			(end 0.67945 -0.3048)
			(stroke
				(width 0.1)
				(type default)
			)
			(layer "F.Fab")
		)
		(fp_line
			(start 0.12065 -0.2794)
			(end 0.12065 -0.3048)
			(stroke
				(width 0.1)
				(type default)
			)
			(layer "F.Fab")
		)
		(fp_line
			(start 0.67945 -0.3048)
			(end 0.67945 0.3048)
			(stroke
				(width 0.1)
				(type default)
			)
			(layer "F.Fab")
		)
		(fp_line
			(start 0.67945 0.3048)
			(end 0.120396 0.3048)
			(stroke
				(width 0.1)
				(type default)
			)
			(layer "F.Fab")
		)
		(pad "1" smd rect
			(at -0.40005 0 180)
			(size 0.4572 0.508)
			(layers "F.Cu" "F.Mask" "F.Paste")
			(net "P3V3_ADC")
		)
		(pad "2" smd rect
			(at 0.40005 0 180)
			(size 0.4572 0.508)
			(layers "F.Cu" "F.Mask" "F.Paste")
			(net "P3V3_ADC_MAM")
		)
	)
	(footprint ""
		(layer "F.Cu")
		(at 116.227098 -261.748016 -90)
		(property "Reference" "C2508"
			(at 0 0 270)
			(layer "F.SilkS")
			(hide yes)
			(effects
				(font
					(size 1.27 1.27)
				)
			)
		)
		(property "Value" ""
			(at 0 0 270)
			(layer "F.Fab")
			(effects
				(font
					(size 1.27 1.27)
				)
			)
		)
		(duplicate_pad_numbers_are_jumpers no)
		(fp_line
			(start -0.7874 0.4064)
			(end -0.7874 -0.4064)
			(stroke
				(width 0.1524)
				(type default)
			)
			(layer "F.SilkS")
		)
		(fp_line
			(start 0.7874 0.4064)
			(end -0.7874 0.4064)
			(stroke
				(width 0.1524)
				(type default)
			)
			(layer "F.SilkS")
		)
		(fp_line
			(start -0.7874 -0.4064)
			(end 0.7874 -0.4064)
			(stroke
				(width 0.1524)
				(type default)
			)
			(layer "F.SilkS")
		)
		(fp_line
			(start 0.7874 -0.4064)
			(end 0.7874 0.4064)
			(stroke
				(width 0.1524)
				(type default)
			)
			(layer "F.SilkS")
		)
		(fp_line
			(start -0.67945 0.3048)
			(end -0.67945 -0.305054)
			(stroke
				(width 0.1)
				(type default)
			)
			(layer "F.Fab")
		)
		(fp_line
			(start -0.12065 0.3048)
			(end -0.67945 0.3048)
			(stroke
				(width 0.1)
				(type default)
			)
			(layer "F.Fab")
		)
		(fp_line
			(start 0.120396 0.3048)
			(end 0.120396 0.2794)
			(stroke
				(width 0.1)
				(type default)
			)
			(layer "F.Fab")
		)
		(fp_line
			(start 0.67945 0.3048)
			(end 0.120396 0.3048)
			(stroke
				(width 0.1)
				(type default)
			)
			(layer "F.Fab")
		)
		(fp_line
			(start -0.12065 0.2794)
			(end -0.12065 0.3048)
			(stroke
				(width 0.1)
				(type default)
			)
			(layer "F.Fab")
		)
		(fp_line
			(start 0.120396 0.2794)
			(end -0.12065 0.2794)
			(stroke
				(width 0.1)
				(type default)
			)
			(layer "F.Fab")
		)
		(fp_line
			(start -0.12065 -0.2794)
			(end 0.12065 -0.2794)
			(stroke
				(width 0.1)
				(type default)
			)
			(layer "F.Fab")
		)
		(fp_line
			(start 0.12065 -0.2794)
			(end 0.12065 -0.3048)
			(stroke
				(width 0.1)
				(type default)
			)
			(layer "F.Fab")
		)
		(fp_line
			(start 0.12065 -0.3048)
			(end 0.67945 -0.3048)
			(stroke
				(width 0.1)
				(type default)
			)
			(layer "F.Fab")
		)
		(fp_line
			(start 0.67945 -0.3048)
			(end 0.67945 0.3048)
			(stroke
				(width 0.1)
				(type default)
			)
			(layer "F.Fab")
		)
		(fp_line
			(start -0.67945 -0.305054)
			(end -0.12065 -0.305054)
			(stroke
				(width 0.1)
				(type default)
			)
			(layer "F.Fab")
		)
		(fp_line
			(start -0.12065 -0.305054)
			(end -0.12065 -0.2794)
			(stroke
				(width 0.1)
				(type default)
			)
			(layer "F.Fab")
		)
		(pad "1" smd circle
			(at -0.40005 0 270)
			(size 0 0)
			(layers "F.Cu" "F.Mask" "F.Paste")
			(net "PVDD11_S3_P1")
		)
		(pad "2" smd circle
			(at 0.40005 0 270)
			(size 0 0)
			(layers "F.Cu" "F.Mask" "F.Paste")
			(net "GND")
		)
	)
	(footprint ""
		(layer "F.Cu")
		(at 150.368762 -119.098822)
		(property "Reference" "R2221"
			(at 0 0 0)
			(layer "F.SilkS")
			(hide yes)
			(effects
				(font
					(size 1.27 1.27)
				)
			)
		)
		(property "Value" ""
			(at 0 0 0)
			(layer "F.Fab")
			(effects
				(font
					(size 1.27 1.27)
				)
			)
		)
		(duplicate_pad_numbers_are_jumpers no)
		(fp_line
			(start -0.7874 -0.4064)
			(end 0.7874 -0.4064)
			(stroke
				(width 0.1524)
				(type default)
			)
			(layer "F.SilkS")
		)
		(fp_line
			(start -0.7874 0.4064)
			(end -0.7874 -0.4064)
			(stroke
				(width 0.1524)
				(type default)
			)
			(layer "F.SilkS")
		)
		(fp_line
			(start 0.7874 -0.4064)
			(end 0.7874 0.4064)
			(stroke
				(width 0.1524)
				(type default)
			)
			(layer "F.SilkS")
		)
		(fp_line
			(start 0.7874 0.4064)
			(end -0.7874 0.4064)
			(stroke
				(width 0.1524)
				(type default)
			)
			(layer "F.SilkS")
		)
		(fp_line
			(start -0.67945 -0.305054)
			(end -0.12065 -0.305054)
			(stroke
				(width 0.1)
				(type default)
			)
			(layer "F.Fab")
		)
		(fp_line
			(start -0.67945 0.3048)
			(end -0.67945 -0.305054)
			(stroke
				(width 0.1)
				(type default)
			)
			(layer "F.Fab")
		)
		(fp_line
			(start -0.12065 -0.305054)
			(end -0.12065 -0.2794)
			(stroke
				(width 0.1)
				(type default)
			)
			(layer "F.Fab")
		)
		(fp_line
			(start -0.12065 -0.2794)
			(end 0.12065 -0.2794)
			(stroke
				(width 0.1)
				(type default)
			)
			(layer "F.Fab")
		)
		(fp_line
			(start -0.12065 0.2794)
			(end -0.12065 0.3048)
			(stroke
				(width 0.1)
				(type default)
			)
			(layer "F.Fab")
		)
		(fp_line
			(start -0.12065 0.3048)
			(end -0.67945 0.3048)
			(stroke
				(width 0.1)
				(type default)
			)
			(layer "F.Fab")
		)
		(fp_line
			(start 0.120396 0.2794)
			(end -0.12065 0.2794)
			(stroke
				(width 0.1)
				(type default)
			)
			(layer "F.Fab")
		)
		(fp_line
			(start 0.120396 0.3048)
			(end 0.120396 0.2794)
			(stroke
				(width 0.1)
				(type default)
			)
			(layer "F.Fab")
		)
		(fp_line
			(start 0.12065 -0.3048)
			(end 0.67945 -0.3048)
			(stroke
				(width 0.1)
				(type default)
			)
			(layer "F.Fab")
		)
		(fp_line
			(start 0.12065 -0.2794)
			(end 0.12065 -0.3048)
			(stroke
				(width 0.1)
				(type default)
			)
			(layer "F.Fab")
		)
		(fp_line
			(start 0.67945 -0.3048)
			(end 0.67945 0.3048)
			(stroke
				(width 0.1)
				(type default)
			)
			(layer "F.Fab")
		)
		(fp_line
			(start 0.67945 0.3048)
			(end 0.120396 0.3048)
			(stroke
				(width 0.1)
				(type default)
			)
			(layer "F.Fab")
		)
		(pad "1" smd circle
			(at -0.40005 0)
			(size 0 0)
			(layers "F.Cu" "F.Mask" "F.Paste")
			(net "P12V_AUX")
		)
		(pad "2" smd circle
			(at 0.40005 0)
			(size 0 0)
			(layers "F.Cu" "F.Mask" "F.Paste")
			(net "A_P12V_STBY_FP_TRIGGER")
		)
	)
	(footprint ""
		(layer "F.Cu")
		(at 439.295032 -24.009858)
		(property "Reference" "PR3843"
			(at 0 0 0)
			(layer "F.SilkS")
			(hide yes)
			(effects
				(font
					(size 1.27 1.27)
				)
			)
		)
		(property "Value" ""
			(at 0 0 0)
			(layer "F.Fab")
			(effects
				(font
					(size 1.27 1.27)
				)
			)
		)
		(duplicate_pad_numbers_are_jumpers no)
		(fp_line
			(start -1.2954 -0.5842)
			(end 1.2954 -0.5842)
			(stroke
				(width 0.1524)
				(type default)
			)
			(layer "F.SilkS")
		)
		(fp_line
			(start -1.2954 0.5842)
			(end -1.2954 -0.5842)
			(stroke
				(width 0.1524)
				(type default)
			)
			(layer "F.SilkS")
		)
		(fp_line
			(start 1.2954 -0.5842)
			(end 1.2954 0.5842)
			(stroke
				(width 0.1524)
				(type default)
			)
			(layer "F.SilkS")
		)
		(fp_line
			(start 1.2954 0.5842)
			(end -1.2954 0.5842)
			(stroke
				(width 0.1524)
				(type default)
			)
			(layer "F.SilkS")
		)
		(fp_line
			(start -1.1938 -0.406654)
			(end -0.8636 -0.406654)
			(stroke
				(width 0.1)
				(type default)
			)
			(layer "F.Fab")
		)
		(fp_line
			(start -1.1938 0.4064)
			(end -1.1938 -0.406654)
			(stroke
				(width 0.1)
				(type default)
			)
			(layer "F.Fab")
		)
		(fp_line
			(start -0.8636 -0.4572)
			(end 0.8636 -0.4572)
			(stroke
				(width 0.1)
				(type default)
			)
			(layer "F.Fab")
		)
		(fp_line
			(start -0.8636 -0.406654)
			(end -0.8636 -0.4572)
			(stroke
				(width 0.1)
				(type default)
			)
			(layer "F.Fab")
		)
		(fp_line
			(start -0.8636 0.4064)
			(end -1.1938 0.4064)
			(stroke
				(width 0.1)
				(type default)
			)
			(layer "F.Fab")
		)
		(fp_line
			(start -0.8636 0.4318)
			(end -0.8636 0.4064)
			(stroke
				(width 0.1)
				(type default)
			)
			(layer "F.Fab")
		)
		(fp_line
			(start -0.8636 0.4572)
			(end -0.8636 0.4318)
			(stroke
				(width 0.1)
				(type default)
			)
			(layer "F.Fab")
		)
		(fp_line
			(start 0.8636 -0.4572)
			(end 0.8636 -0.406654)
			(stroke
				(width 0.1)
				(type default)
			)
			(layer "F.Fab")
		)
		(fp_line
			(start 0.8636 -0.406654)
			(end 1.1938 -0.406654)
			(stroke
				(width 0.1)
				(type default)
			)
			(layer "F.Fab")
		)
		(fp_line
			(start 0.8636 0.4064)
			(end 0.8636 0.4572)
			(stroke
				(width 0.1)
				(type default)
			)
			(layer "F.Fab")
		)
		(fp_line
			(start 0.8636 0.4572)
			(end -0.8636 0.4572)
			(stroke
				(width 0.1)
				(type default)
			)
			(layer "F.Fab")
		)
		(fp_line
			(start 1.1938 -0.406654)
			(end 1.1938 0.4064)
			(stroke
				(width 0.1)
				(type default)
			)
			(layer "F.Fab")
		)
		(fp_line
			(start 1.1938 0.4064)
			(end 0.8636 0.4064)
			(stroke
				(width 0.1)
				(type default)
			)
			(layer "F.Fab")
		)
		(pad "1" smd rect
			(at -0.7366 0 270)
			(size 0.7112 0.8128)
			(layers "F.Cu" "F.Mask" "F.Paste")
			(net "P12V_AUX")
		)
		(pad "2" smd rect
			(at 0.7366 0 270)
			(size 0.7112 0.8128)
			(layers "F.Cu" "F.Mask" "F.Paste")
			(net "P12V_OCP_AVIN_PD_1")
		)
	)
	(footprint ""
		(layer "F.Cu")
		(at 63.25616 -56.98998)
		(property "Reference" "R1525"
			(at 0 0 0)
			(layer "F.SilkS")
			(hide yes)
			(effects
				(font
					(size 1.27 1.27)
				)
			)
		)
		(property "Value" ""
			(at 0 0 0)
			(layer "F.Fab")
			(effects
				(font
					(size 1.27 1.27)
				)
			)
		)
		(duplicate_pad_numbers_are_jumpers no)
		(fp_line
			(start -0.7874 -0.4064)
			(end 0.7874 -0.4064)
			(stroke
				(width 0.1524)
				(type default)
			)
			(layer "F.SilkS")
		)
		(fp_line
			(start -0.7874 0.4064)
			(end -0.7874 -0.4064)
			(stroke
				(width 0.1524)
				(type default)
			)
			(layer "F.SilkS")
		)
		(fp_line
			(start 0.7874 -0.4064)
			(end 0.7874 0.4064)
			(stroke
				(width 0.1524)
				(type default)
			)
			(layer "F.SilkS")
		)
		(fp_line
			(start 0.7874 0.4064)
			(end -0.7874 0.4064)
			(stroke
				(width 0.1524)
				(type default)
			)
			(layer "F.SilkS")
		)
		(fp_line
			(start -0.67945 -0.305054)
			(end -0.12065 -0.305054)
			(stroke
				(width 0.1)
				(type default)
			)
			(layer "F.Fab")
		)
		(fp_line
			(start -0.67945 0.3048)
			(end -0.67945 -0.305054)
			(stroke
				(width 0.1)
				(type default)
			)
			(layer "F.Fab")
		)
		(fp_line
			(start -0.12065 -0.305054)
			(end -0.12065 -0.2794)
			(stroke
				(width 0.1)
				(type default)
			)
			(layer "F.Fab")
		)
		(fp_line
			(start -0.12065 -0.2794)
			(end 0.12065 -0.2794)
			(stroke
				(width 0.1)
				(type default)
			)
			(layer "F.Fab")
		)
		(fp_line
			(start -0.12065 0.2794)
			(end -0.12065 0.3048)
			(stroke
				(width 0.1)
				(type default)
			)
			(layer "F.Fab")
		)
		(fp_line
			(start -0.12065 0.3048)
			(end -0.67945 0.3048)
			(stroke
				(width 0.1)
				(type default)
			)
			(layer "F.Fab")
		)
		(fp_line
			(start 0.120396 0.2794)
			(end -0.12065 0.2794)
			(stroke
				(width 0.1)
				(type default)
			)
			(layer "F.Fab")
		)
		(fp_line
			(start 0.120396 0.3048)
			(end 0.120396 0.2794)
			(stroke
				(width 0.1)
				(type default)
			)
			(layer "F.Fab")
		)
		(fp_line
			(start 0.12065 -0.3048)
			(end 0.67945 -0.3048)
			(stroke
				(width 0.1)
				(type default)
			)
			(layer "F.Fab")
		)
		(fp_line
			(start 0.12065 -0.2794)
			(end 0.12065 -0.3048)
			(stroke
				(width 0.1)
				(type default)
			)
			(layer "F.Fab")
		)
		(fp_line
			(start 0.67945 -0.3048)
			(end 0.67945 0.3048)
			(stroke
				(width 0.1)
				(type default)
			)
			(layer "F.Fab")
		)
		(fp_line
			(start 0.67945 0.3048)
			(end 0.120396 0.3048)
			(stroke
				(width 0.1)
				(type default)
			)
			(layer "F.Fab")
		)
		(pad "1" smd circle
			(at -0.40005 0)
			(size 0 0)
			(layers "F.Cu" "F.Mask" "F.Paste")
			(net "OCP_V3_2_P3V3_PWRGD")
		)
		(pad "2" smd circle
			(at 0.40005 0)
			(size 0 0)
			(layers "F.Cu" "F.Mask" "F.Paste")
			(net "OCP_V3_2_P3V3_R3_PWRGD")
		)
	)
	(footprint ""
		(layer "F.Cu")
		(at 277.352252 -117.50167)
		(property "Reference" "R3582"
			(at 0 0 0)
			(layer "F.SilkS")
			(hide yes)
			(effects
				(font
					(size 1.27 1.27)
				)
			)
		)
		(property "Value" ""
			(at 0 0 0)
			(layer "F.Fab")
			(effects
				(font
					(size 1.27 1.27)
				)
			)
		)
		(duplicate_pad_numbers_are_jumpers no)
		(fp_line
			(start -0.7874 -0.4064)
			(end 0.7874 -0.4064)
			(stroke
				(width 0.1524)
				(type default)
			)
			(layer "F.SilkS")
		)
		(fp_line
			(start -0.7874 0.4064)
			(end -0.7874 -0.4064)
			(stroke
				(width 0.1524)
				(type default)
			)
			(layer "F.SilkS")
		)
		(fp_line
			(start 0.7874 -0.4064)
			(end 0.7874 0.4064)
			(stroke
				(width 0.1524)
				(type default)
			)
			(layer "F.SilkS")
		)
		(fp_line
			(start 0.7874 0.4064)
			(end -0.7874 0.4064)
			(stroke
				(width 0.1524)
				(type default)
			)
			(layer "F.SilkS")
		)
		(fp_line
			(start -0.67945 -0.305054)
			(end -0.12065 -0.305054)
			(stroke
				(width 0.1)
				(type default)
			)
			(layer "F.Fab")
		)
		(fp_line
			(start -0.67945 0.3048)
			(end -0.67945 -0.305054)
			(stroke
				(width 0.1)
				(type default)
			)
			(layer "F.Fab")
		)
		(fp_line
			(start -0.12065 -0.305054)
			(end -0.12065 -0.2794)
			(stroke
				(width 0.1)
				(type default)
			)
			(layer "F.Fab")
		)
		(fp_line
			(start -0.12065 -0.2794)
			(end 0.12065 -0.2794)
			(stroke
				(width 0.1)
				(type default)
			)
			(layer "F.Fab")
		)
		(fp_line
			(start -0.12065 0.2794)
			(end -0.12065 0.3048)
			(stroke
				(width 0.1)
				(type default)
			)
			(layer "F.Fab")
		)
		(fp_line
			(start -0.12065 0.3048)
			(end -0.67945 0.3048)
			(stroke
				(width 0.1)
				(type default)
			)
			(layer "F.Fab")
		)
		(fp_line
			(start 0.120396 0.2794)
			(end -0.12065 0.2794)
			(stroke
				(width 0.1)
				(type default)
			)
			(layer "F.Fab")
		)
		(fp_line
			(start 0.120396 0.3048)
			(end 0.120396 0.2794)
			(stroke
				(width 0.1)
				(type default)
			)
			(layer "F.Fab")
		)
		(fp_line
			(start 0.12065 -0.3048)
			(end 0.67945 -0.3048)
			(stroke
				(width 0.1)
				(type default)
			)
			(layer "F.Fab")
		)
		(fp_line
			(start 0.12065 -0.2794)
			(end 0.12065 -0.3048)
			(stroke
				(width 0.1)
				(type default)
			)
			(layer "F.Fab")
		)
		(fp_line
			(start 0.67945 -0.3048)
			(end 0.67945 0.3048)
			(stroke
				(width 0.1)
				(type default)
			)
			(layer "F.Fab")
		)
		(fp_line
			(start 0.67945 0.3048)
			(end 0.120396 0.3048)
			(stroke
				(width 0.1)
				(type default)
			)
			(layer "F.Fab")
		)
		(pad "1" smd circle
			(at -0.40005 0)
			(size 0 0)
			(layers "F.Cu" "F.Mask" "F.Paste")
			(net "P3V3_AUX")
		)
		(pad "2" smd circle
			(at 0.40005 0)
			(size 0 0)
			(layers "F.Cu" "F.Mask" "F.Paste")
			(net "SMB_IOEXP_3V3AUX_SCL")
		)
	)
	(footprint ""
		(layer "F.Cu")
		(at 163.953444 -373.03583 -90)
		(property "Reference" "C750"
			(at 0 0 270)
			(layer "F.SilkS")
			(hide yes)
			(effects
				(font
					(size 1.27 1.27)
				)
			)
		)
		(property "Value" ""
			(at 0 0 270)
			(layer "F.Fab")
			(effects
				(font
					(size 1.27 1.27)
				)
			)
		)
		(duplicate_pad_numbers_are_jumpers no)
		(fp_line
			(start -0.299974 0.150114)
			(end -0.299974 -0.150114)
			(stroke
				(width 0.1)
				(type default)
			)
			(layer "F.Fab")
		)
		(fp_line
			(start 0.299974 0.150114)
			(end -0.299974 0.150114)
			(stroke
				(width 0.1)
				(type default)
			)
			(layer "F.Fab")
		)
		(fp_line
			(start -0.299974 -0.150114)
			(end 0.299974 -0.150114)
			(stroke
				(width 0.1)
				(type default)
			)
			(layer "F.Fab")
		)
		(fp_line
			(start 0.299974 -0.150114)
			(end 0.299974 0.150114)
			(stroke
				(width 0.1)
				(type default)
			)
			(layer "F.Fab")
		)
		(pad "1" smd rect
			(at -0.2667 0 270)
			(size 0.3048 0.381)
			(layers "F.Cu" "F.Mask" "F.Paste")
			(net "P5E_CPU1_P2_TX_C_DN<11>")
		)
		(pad "2" smd rect
			(at 0.2667 0 270)
			(size 0.3048 0.381)
			(layers "F.Cu" "F.Mask" "F.Paste")
			(net "P5E_CPU1_P2_TX_DN<11>")
		)
	)
	(footprint ""
		(layer "F.Cu")
		(at 442.233558 -169.726864 180)
		(property "Reference" "R5017"
			(at 0 0 180)
			(layer "F.SilkS")
			(hide yes)
			(effects
				(font
					(size 1.27 1.27)
				)
			)
		)
		(property "Value" ""
			(at 0 0 180)
			(layer "F.Fab")
			(effects
				(font
					(size 1.27 1.27)
				)
			)
		)
		(duplicate_pad_numbers_are_jumpers no)
		(fp_line
			(start 0.7874 0.4064)
			(end -0.7874 0.4064)
			(stroke
				(width 0.1524)
				(type default)
			)
			(layer "F.SilkS")
		)
		(fp_line
			(start 0.7874 -0.4064)
			(end 0.7874 0.4064)
			(stroke
				(width 0.1524)
				(type default)
			)
			(layer "F.SilkS")
		)
		(fp_line
			(start -0.7874 0.4064)
			(end -0.7874 -0.4064)
			(stroke
				(width 0.1524)
				(type default)
			)
			(layer "F.SilkS")
		)
		(fp_line
			(start -0.7874 -0.4064)
			(end 0.7874 -0.4064)
			(stroke
				(width 0.1524)
				(type default)
			)
			(layer "F.SilkS")
		)
		(fp_line
			(start 0.67945 0.3048)
			(end 0.120396 0.3048)
			(stroke
				(width 0.1)
				(type default)
			)
			(layer "F.Fab")
		)
		(fp_line
			(start 0.67945 -0.3048)
			(end 0.67945 0.3048)
			(stroke
				(width 0.1)
				(type default)
			)
			(layer "F.Fab")
		)
		(fp_line
			(start 0.12065 -0.2794)
			(end 0.12065 -0.3048)
			(stroke
				(width 0.1)
				(type default)
			)
			(layer "F.Fab")
		)
		(fp_line
			(start 0.12065 -0.3048)
			(end 0.67945 -0.3048)
			(stroke
				(width 0.1)
				(type default)
			)
			(layer "F.Fab")
		)
		(fp_line
			(start 0.120396 0.3048)
			(end 0.120396 0.2794)
			(stroke
				(width 0.1)
				(type default)
			)
			(layer "F.Fab")
		)
		(fp_line
			(start 0.120396 0.2794)
			(end -0.12065 0.2794)
			(stroke
				(width 0.1)
				(type default)
			)
			(layer "F.Fab")
		)
		(fp_line
			(start -0.12065 0.3048)
			(end -0.67945 0.3048)
			(stroke
				(width 0.1)
				(type default)
			)
			(layer "F.Fab")
		)
		(fp_line
			(start -0.12065 0.2794)
			(end -0.12065 0.3048)
			(stroke
				(width 0.1)
				(type default)
			)
			(layer "F.Fab")
		)
		(fp_line
			(start -0.12065 -0.2794)
			(end 0.12065 -0.2794)
			(stroke
				(width 0.1)
				(type default)
			)
			(layer "F.Fab")
		)
		(fp_line
			(start -0.12065 -0.305054)
			(end -0.12065 -0.2794)
			(stroke
				(width 0.1)
				(type default)
			)
			(layer "F.Fab")
		)
		(fp_line
			(start -0.67945 0.3048)
			(end -0.67945 -0.305054)
			(stroke
				(width 0.1)
				(type default)
			)
			(layer "F.Fab")
		)
		(fp_line
			(start -0.67945 -0.305054)
			(end -0.12065 -0.305054)
			(stroke
				(width 0.1)
				(type default)
			)
			(layer "F.Fab")
		)
		(pad "1" smd circle
			(at -0.40005 0 180)
			(size 0 0)
			(layers "F.Cu" "F.Mask" "F.Paste")
			(net "PVDD11_S3_P0")
		)
		(pad "2" smd circle
			(at 0.40005 0 180)
			(size 0 0)
			(layers "F.Cu" "F.Mask" "F.Paste")
			(net "I3C_SCM_1_R_SDA")
		)
	)
	(footprint ""
		(layer "F.Cu")
		(at 277.352252 -125.638814)
		(property "Reference" "R320"
			(at 0 0 0)
			(layer "F.SilkS")
			(hide yes)
			(effects
				(font
					(size 1.27 1.27)
				)
			)
		)
		(property "Value" ""
			(at 0 0 0)
			(layer "F.Fab")
			(effects
				(font
					(size 1.27 1.27)
				)
			)
		)
		(duplicate_pad_numbers_are_jumpers no)
		(fp_line
			(start -0.7874 -0.4064)
			(end 0.7874 -0.4064)
			(stroke
				(width 0.1524)
				(type default)
			)
			(layer "F.SilkS")
		)
		(fp_line
			(start -0.7874 0.4064)
			(end -0.7874 -0.4064)
			(stroke
				(width 0.1524)
				(type default)
			)
			(layer "F.SilkS")
		)
		(fp_line
			(start 0.7874 -0.4064)
			(end 0.7874 0.4064)
			(stroke
				(width 0.1524)
				(type default)
			)
			(layer "F.SilkS")
		)
		(fp_line
			(start 0.7874 0.4064)
			(end -0.7874 0.4064)
			(stroke
				(width 0.1524)
				(type default)
			)
			(layer "F.SilkS")
		)
		(fp_line
			(start -0.67945 -0.305054)
			(end -0.12065 -0.305054)
			(stroke
				(width 0.1)
				(type default)
			)
			(layer "F.Fab")
		)
		(fp_line
			(start -0.67945 0.3048)
			(end -0.67945 -0.305054)
			(stroke
				(width 0.1)
				(type default)
			)
			(layer "F.Fab")
		)
		(fp_line
			(start -0.12065 -0.305054)
			(end -0.12065 -0.2794)
			(stroke
				(width 0.1)
				(type default)
			)
			(layer "F.Fab")
		)
		(fp_line
			(start -0.12065 -0.2794)
			(end 0.12065 -0.2794)
			(stroke
				(width 0.1)
				(type default)
			)
			(layer "F.Fab")
		)
		(fp_line
			(start -0.12065 0.2794)
			(end -0.12065 0.3048)
			(stroke
				(width 0.1)
				(type default)
			)
			(layer "F.Fab")
		)
		(fp_line
			(start -0.12065 0.3048)
			(end -0.67945 0.3048)
			(stroke
				(width 0.1)
				(type default)
			)
			(layer "F.Fab")
		)
		(fp_line
			(start 0.120396 0.2794)
			(end -0.12065 0.2794)
			(stroke
				(width 0.1)
				(type default)
			)
			(layer "F.Fab")
		)
		(fp_line
			(start 0.120396 0.3048)
			(end 0.120396 0.2794)
			(stroke
				(width 0.1)
				(type default)
			)
			(layer "F.Fab")
		)
		(fp_line
			(start 0.12065 -0.3048)
			(end 0.67945 -0.3048)
			(stroke
				(width 0.1)
				(type default)
			)
			(layer "F.Fab")
		)
		(fp_line
			(start 0.12065 -0.2794)
			(end 0.12065 -0.3048)
			(stroke
				(width 0.1)
				(type default)
			)
			(layer "F.Fab")
		)
		(fp_line
			(start 0.67945 -0.3048)
			(end 0.67945 0.3048)
			(stroke
				(width 0.1)
				(type default)
			)
			(layer "F.Fab")
		)
		(fp_line
			(start 0.67945 0.3048)
			(end 0.120396 0.3048)
			(stroke
				(width 0.1)
				(type default)
			)
			(layer "F.Fab")
		)
		(pad "1" smd circle
			(at -0.40005 0)
			(size 0 0)
			(layers "F.Cu" "F.Mask" "F.Paste")
			(net "P3V3_AUX")
		)
		(pad "2" smd circle
			(at 0.40005 0)
			(size 0 0)
			(layers "F.Cu" "F.Mask" "F.Paste")
			(net "PCA9548_PCIE3_ADDR0")
		)
	)
	(footprint ""
		(layer "F.Cu")
		(at 102.811834 -176.438052 90)
		(property "Reference" "PC293_4"
			(at 0 0 90)
			(layer "F.SilkS")
			(hide yes)
			(effects
				(font
					(size 1.27 1.27)
				)
			)
		)
		(property "Value" ""
			(at 0 0 90)
			(layer "F.Fab")
			(effects
				(font
					(size 1.27 1.27)
				)
			)
		)
		(duplicate_pad_numbers_are_jumpers no)
		(fp_line
			(start 0.7874 -0.4064)
			(end 0.7874 0.4064)
			(stroke
				(width 0.1524)
				(type default)
			)
			(layer "F.SilkS")
		)
		(fp_line
			(start -0.7874 -0.4064)
			(end 0.7874 -0.4064)
			(stroke
				(width 0.1524)
				(type default)
			)
			(layer "F.SilkS")
		)
		(fp_line
			(start 0.7874 0.4064)
			(end -0.7874 0.4064)
			(stroke
				(width 0.1524)
				(type default)
			)
			(layer "F.SilkS")
		)
		(fp_line
			(start -0.7874 0.4064)
			(end -0.7874 -0.4064)
			(stroke
				(width 0.1524)
				(type default)
			)
			(layer "F.SilkS")
		)
		(fp_line
			(start -0.12065 -0.305054)
			(end -0.12065 -0.2794)
			(stroke
				(width 0.1)
				(type default)
			)
			(layer "F.Fab")
		)
		(fp_line
			(start -0.67945 -0.305054)
			(end -0.12065 -0.305054)
			(stroke
				(width 0.1)
				(type default)
			)
			(layer "F.Fab")
		)
		(fp_line
			(start 0.67945 -0.3048)
			(end 0.67945 0.3048)
			(stroke
				(width 0.1)
				(type default)
			)
			(layer "F.Fab")
		)
		(fp_line
			(start 0.12065 -0.3048)
			(end 0.67945 -0.3048)
			(stroke
				(width 0.1)
				(type default)
			)
			(layer "F.Fab")
		)
		(fp_line
			(start 0.12065 -0.2794)
			(end 0.12065 -0.3048)
			(stroke
				(width 0.1)
				(type default)
			)
			(layer "F.Fab")
		)
		(fp_line
			(start -0.12065 -0.2794)
			(end 0.12065 -0.2794)
			(stroke
				(width 0.1)
				(type default)
			)
			(layer "F.Fab")
		)
		(fp_line
			(start 0.120396 0.2794)
			(end -0.12065 0.2794)
			(stroke
				(width 0.1)
				(type default)
			)
			(layer "F.Fab")
		)
		(fp_line
			(start -0.12065 0.2794)
			(end -0.12065 0.3048)
			(stroke
				(width 0.1)
				(type default)
			)
			(layer "F.Fab")
		)
		(fp_line
			(start 0.67945 0.3048)
			(end 0.120396 0.3048)
			(stroke
				(width 0.1)
				(type default)
			)
			(layer "F.Fab")
		)
		(fp_line
			(start 0.120396 0.3048)
			(end 0.120396 0.2794)
			(stroke
				(width 0.1)
				(type default)
			)
			(layer "F.Fab")
		)
		(fp_line
			(start -0.12065 0.3048)
			(end -0.67945 0.3048)
			(stroke
				(width 0.1)
				(type default)
			)
			(layer "F.Fab")
		)
		(fp_line
			(start -0.67945 0.3048)
			(end -0.67945 -0.305054)
			(stroke
				(width 0.1)
				(type default)
			)
			(layer "F.Fab")
		)
		(pad "1" smd circle
			(at -0.40005 0 90)
			(size 0 0)
			(layers "F.Cu" "F.Mask" "F.Paste")
			(net "SW_P12V_AUX_PVDDCR_CPU0_P1_FLT")
		)
		(pad "2" smd circle
			(at 0.40005 0 90)
			(size 0 0)
			(layers "F.Cu" "F.Mask" "F.Paste")
			(net "GND")
		)
	)
	(footprint ""
		(layer "F.Cu")
		(at 19.216878 -17.623536 90)
		(property "Reference" "C681"
			(at 0 0 90)
			(layer "F.SilkS")
			(hide yes)
			(effects
				(font
					(size 1.27 1.27)
				)
			)
		)
		(property "Value" ""
			(at 0 0 90)
			(layer "F.Fab")
			(effects
				(font
					(size 1.27 1.27)
				)
			)
		)
		(duplicate_pad_numbers_are_jumpers no)
		(fp_line
			(start 0.299974 -0.150114)
			(end 0.299974 0.150114)
			(stroke
				(width 0.1)
				(type default)
			)
			(layer "F.Fab")
		)
		(fp_line
			(start -0.299974 -0.150114)
			(end 0.299974 -0.150114)
			(stroke
				(width 0.1)
				(type default)
			)
			(layer "F.Fab")
		)
		(fp_line
			(start 0.299974 0.150114)
			(end -0.299974 0.150114)
			(stroke
				(width 0.1)
				(type default)
			)
			(layer "F.Fab")
		)
		(fp_line
			(start -0.299974 0.150114)
			(end -0.299974 -0.150114)
			(stroke
				(width 0.1)
				(type default)
			)
			(layer "F.Fab")
		)
		(pad "1" smd rect
			(at -0.2667 0 90)
			(size 0.3048 0.381)
			(layers "F.Cu" "F.Mask" "F.Paste")
			(net "P5E_CPU1_G1_TX_C_DP<14>")
		)
		(pad "2" smd rect
			(at 0.2667 0 90)
			(size 0.3048 0.381)
			(layers "F.Cu" "F.Mask" "F.Paste")
			(net "P5E_CPU1_G1_TX_DP<14>")
		)
	)
	(footprint ""
		(layer "F.Cu")
		(at 305.162458 -116.891308)
		(property "Reference" "R713"
			(at 0 0 0)
			(layer "F.SilkS")
			(hide yes)
			(effects
				(font
					(size 1.27 1.27)
				)
			)
		)
		(property "Value" ""
			(at 0 0 0)
			(layer "F.Fab")
			(effects
				(font
					(size 1.27 1.27)
				)
			)
		)
		(duplicate_pad_numbers_are_jumpers no)
		(fp_line
			(start -0.7874 -0.4064)
			(end 0.7874 -0.4064)
			(stroke
				(width 0.1524)
				(type default)
			)
			(layer "F.SilkS")
		)
		(fp_line
			(start -0.7874 0.4064)
			(end -0.7874 -0.4064)
			(stroke
				(width 0.1524)
				(type default)
			)
			(layer "F.SilkS")
		)
		(fp_line
			(start 0.7874 -0.4064)
			(end 0.7874 0.4064)
			(stroke
				(width 0.1524)
				(type default)
			)
			(layer "F.SilkS")
		)
		(fp_line
			(start 0.7874 0.4064)
			(end -0.7874 0.4064)
			(stroke
				(width 0.1524)
				(type default)
			)
			(layer "F.SilkS")
		)
		(fp_line
			(start -0.67945 -0.305054)
			(end -0.12065 -0.305054)
			(stroke
				(width 0.1)
				(type default)
			)
			(layer "F.Fab")
		)
		(fp_line
			(start -0.67945 0.3048)
			(end -0.67945 -0.305054)
			(stroke
				(width 0.1)
				(type default)
			)
			(layer "F.Fab")
		)
		(fp_line
			(start -0.12065 -0.305054)
			(end -0.12065 -0.2794)
			(stroke
				(width 0.1)
				(type default)
			)
			(layer "F.Fab")
		)
		(fp_line
			(start -0.12065 -0.2794)
			(end 0.12065 -0.2794)
			(stroke
				(width 0.1)
				(type default)
			)
			(layer "F.Fab")
		)
		(fp_line
			(start -0.12065 0.2794)
			(end -0.12065 0.3048)
			(stroke
				(width 0.1)
				(type default)
			)
			(layer "F.Fab")
		)
		(fp_line
			(start -0.12065 0.3048)
			(end -0.67945 0.3048)
			(stroke
				(width 0.1)
				(type default)
			)
			(layer "F.Fab")
		)
		(fp_line
			(start 0.120396 0.2794)
			(end -0.12065 0.2794)
			(stroke
				(width 0.1)
				(type default)
			)
			(layer "F.Fab")
		)
		(fp_line
			(start 0.120396 0.3048)
			(end 0.120396 0.2794)
			(stroke
				(width 0.1)
				(type default)
			)
			(layer "F.Fab")
		)
		(fp_line
			(start 0.12065 -0.3048)
			(end 0.67945 -0.3048)
			(stroke
				(width 0.1)
				(type default)
			)
			(layer "F.Fab")
		)
		(fp_line
			(start 0.12065 -0.2794)
			(end 0.12065 -0.3048)
			(stroke
				(width 0.1)
				(type default)
			)
			(layer "F.Fab")
		)
		(fp_line
			(start 0.67945 -0.3048)
			(end 0.67945 0.3048)
			(stroke
				(width 0.1)
				(type default)
			)
			(layer "F.Fab")
		)
		(fp_line
			(start 0.67945 0.3048)
			(end 0.120396 0.3048)
			(stroke
				(width 0.1)
				(type default)
			)
			(layer "F.Fab")
		)
		(pad "1" smd circle
			(at -0.40005 0)
			(size 0 0)
			(layers "F.Cu" "F.Mask" "F.Paste")
			(net "P3V3_AUX")
		)
		(pad "2" smd circle
			(at 0.40005 0)
			(size 0 0)
			(layers "F.Cu" "F.Mask" "F.Paste")
			(net "MB_FRU_ADDR2")
		)
	)
	(footprint ""
		(layer "F.Cu")
		(at 93.375734 -177.818288 -90)
		(property "Reference" "PC255_2"
			(at 0 0 270)
			(layer "F.SilkS")
			(hide yes)
			(effects
				(font
					(size 1.27 1.27)
				)
			)
		)
		(property "Value" ""
			(at 0 0 270)
			(layer "F.Fab")
			(effects
				(font
					(size 1.27 1.27)
				)
			)
		)
		(duplicate_pad_numbers_are_jumpers no)
		(fp_line
			(start -0.7874 0.4064)
			(end -0.7874 -0.4064)
			(stroke
				(width 0.1524)
				(type default)
			)
			(layer "F.SilkS")
		)
		(fp_line
			(start 0.7874 0.4064)
			(end -0.7874 0.4064)
			(stroke
				(width 0.1524)
				(type default)
			)
			(layer "F.SilkS")
		)
		(fp_line
			(start -0.7874 -0.4064)
			(end 0.7874 -0.4064)
			(stroke
				(width 0.1524)
				(type default)
			)
			(layer "F.SilkS")
		)
		(fp_line
			(start 0.7874 -0.4064)
			(end 0.7874 0.4064)
			(stroke
				(width 0.1524)
				(type default)
			)
			(layer "F.SilkS")
		)
		(fp_line
			(start -0.67945 0.3048)
			(end -0.67945 -0.305054)
			(stroke
				(width 0.1)
				(type default)
			)
			(layer "F.Fab")
		)
		(fp_line
			(start -0.12065 0.3048)
			(end -0.67945 0.3048)
			(stroke
				(width 0.1)
				(type default)
			)
			(layer "F.Fab")
		)
		(fp_line
			(start 0.120396 0.3048)
			(end 0.120396 0.2794)
			(stroke
				(width 0.1)
				(type default)
			)
			(layer "F.Fab")
		)
		(fp_line
			(start 0.67945 0.3048)
			(end 0.120396 0.3048)
			(stroke
				(width 0.1)
				(type default)
			)
			(layer "F.Fab")
		)
		(fp_line
			(start -0.12065 0.2794)
			(end -0.12065 0.3048)
			(stroke
				(width 0.1)
				(type default)
			)
			(layer "F.Fab")
		)
		(fp_line
			(start 0.120396 0.2794)
			(end -0.12065 0.2794)
			(stroke
				(width 0.1)
				(type default)
			)
			(layer "F.Fab")
		)
		(fp_line
			(start -0.12065 -0.2794)
			(end 0.12065 -0.2794)
			(stroke
				(width 0.1)
				(type default)
			)
			(layer "F.Fab")
		)
		(fp_line
			(start 0.12065 -0.2794)
			(end 0.12065 -0.3048)
			(stroke
				(width 0.1)
				(type default)
			)
			(layer "F.Fab")
		)
		(fp_line
			(start 0.12065 -0.3048)
			(end 0.67945 -0.3048)
			(stroke
				(width 0.1)
				(type default)
			)
			(layer "F.Fab")
		)
		(fp_line
			(start 0.67945 -0.3048)
			(end 0.67945 0.3048)
			(stroke
				(width 0.1)
				(type default)
			)
			(layer "F.Fab")
		)
		(fp_line
			(start -0.67945 -0.305054)
			(end -0.12065 -0.305054)
			(stroke
				(width 0.1)
				(type default)
			)
			(layer "F.Fab")
		)
		(fp_line
			(start -0.12065 -0.305054)
			(end -0.12065 -0.2794)
			(stroke
				(width 0.1)
				(type default)
			)
			(layer "F.Fab")
		)
		(pad "1" smd circle
			(at -0.40005 0 270)
			(size 0 0)
			(layers "F.Cu" "F.Mask" "F.Paste")
			(net "PVDDCR_CPU0_P1_VCCS")
		)
		(pad "2" smd circle
			(at 0.40005 0 270)
			(size 0 0)
			(layers "F.Cu" "F.Mask" "F.Paste")
			(net "GND")
		)
	)
	(footprint ""
		(layer "F.Cu")
		(at 359.190036 -392.48588 180)
		(property "Reference" "R1008"
			(at 0 0 180)
			(layer "F.SilkS")
			(hide yes)
			(effects
				(font
					(size 1.27 1.27)
				)
			)
		)
		(property "Value" ""
			(at 0 0 180)
			(layer "F.Fab")
			(effects
				(font
					(size 1.27 1.27)
				)
			)
		)
		(duplicate_pad_numbers_are_jumpers no)
		(fp_line
			(start 0.7874 0.4064)
			(end -0.7874 0.4064)
			(stroke
				(width 0.1524)
				(type default)
			)
			(layer "F.SilkS")
		)
		(fp_line
			(start 0.7874 -0.4064)
			(end 0.7874 0.4064)
			(stroke
				(width 0.1524)
				(type default)
			)
			(layer "F.SilkS")
		)
		(fp_line
			(start -0.7874 0.4064)
			(end -0.7874 -0.4064)
			(stroke
				(width 0.1524)
				(type default)
			)
			(layer "F.SilkS")
		)
		(fp_line
			(start -0.7874 -0.4064)
			(end 0.7874 -0.4064)
			(stroke
				(width 0.1524)
				(type default)
			)
			(layer "F.SilkS")
		)
		(fp_line
			(start 0.67945 0.3048)
			(end 0.120396 0.3048)
			(stroke
				(width 0.1)
				(type default)
			)
			(layer "F.Fab")
		)
		(fp_line
			(start 0.67945 -0.3048)
			(end 0.67945 0.3048)
			(stroke
				(width 0.1)
				(type default)
			)
			(layer "F.Fab")
		)
		(fp_line
			(start 0.12065 -0.2794)
			(end 0.12065 -0.3048)
			(stroke
				(width 0.1)
				(type default)
			)
			(layer "F.Fab")
		)
		(fp_line
			(start 0.12065 -0.3048)
			(end 0.67945 -0.3048)
			(stroke
				(width 0.1)
				(type default)
			)
			(layer "F.Fab")
		)
		(fp_line
			(start 0.120396 0.3048)
			(end 0.120396 0.2794)
			(stroke
				(width 0.1)
				(type default)
			)
			(layer "F.Fab")
		)
		(fp_line
			(start 0.120396 0.2794)
			(end -0.12065 0.2794)
			(stroke
				(width 0.1)
				(type default)
			)
			(layer "F.Fab")
		)
		(fp_line
			(start -0.12065 0.3048)
			(end -0.67945 0.3048)
			(stroke
				(width 0.1)
				(type default)
			)
			(layer "F.Fab")
		)
		(fp_line
			(start -0.12065 0.2794)
			(end -0.12065 0.3048)
			(stroke
				(width 0.1)
				(type default)
			)
			(layer "F.Fab")
		)
		(fp_line
			(start -0.12065 -0.2794)
			(end 0.12065 -0.2794)
			(stroke
				(width 0.1)
				(type default)
			)
			(layer "F.Fab")
		)
		(fp_line
			(start -0.12065 -0.305054)
			(end -0.12065 -0.2794)
			(stroke
				(width 0.1)
				(type default)
			)
			(layer "F.Fab")
		)
		(fp_line
			(start -0.67945 0.3048)
			(end -0.67945 -0.305054)
			(stroke
				(width 0.1)
				(type default)
			)
			(layer "F.Fab")
		)
		(fp_line
			(start -0.67945 -0.305054)
			(end -0.12065 -0.305054)
			(stroke
				(width 0.1)
				(type default)
			)
			(layer "F.Fab")
		)
		(pad "1" smd rect
			(at -0.40005 0)
			(size 0.4572 0.508)
			(layers "F.Cu" "F.Mask" "F.Paste")
			(net "P1V8_CPU0_RT_1D")
		)
		(pad "2" smd rect
			(at 0.40005 0)
			(size 0.4572 0.508)
			(layers "F.Cu" "F.Mask" "F.Paste")
			(net "P1V8_CPU0_RT1_1A_1D")
		)
	)
	(footprint ""
		(layer "F.Cu")
		(at 113.613946 -54.882034 -90)
		(property "Reference" "R6303"
			(at 0 0 270)
			(layer "F.SilkS")
			(hide yes)
			(effects
				(font
					(size 1.27 1.27)
				)
			)
		)
		(property "Value" ""
			(at 0 0 270)
			(layer "F.Fab")
			(effects
				(font
					(size 1.27 1.27)
				)
			)
		)
		(duplicate_pad_numbers_are_jumpers no)
		(fp_line
			(start -0.7874 0.4064)
			(end -0.7874 -0.4064)
			(stroke
				(width 0.1524)
				(type default)
			)
			(layer "F.SilkS")
		)
		(fp_line
			(start 0.7874 0.4064)
			(end -0.7874 0.4064)
			(stroke
				(width 0.1524)
				(type default)
			)
			(layer "F.SilkS")
		)
		(fp_line
			(start -0.7874 -0.4064)
			(end 0.7874 -0.4064)
			(stroke
				(width 0.1524)
				(type default)
			)
			(layer "F.SilkS")
		)
		(fp_line
			(start 0.7874 -0.4064)
			(end 0.7874 0.4064)
			(stroke
				(width 0.1524)
				(type default)
			)
			(layer "F.SilkS")
		)
		(fp_line
			(start -0.67945 0.3048)
			(end -0.67945 -0.305054)
			(stroke
				(width 0.1)
				(type default)
			)
			(layer "F.Fab")
		)
		(fp_line
			(start -0.12065 0.3048)
			(end -0.67945 0.3048)
			(stroke
				(width 0.1)
				(type default)
			)
			(layer "F.Fab")
		)
		(fp_line
			(start 0.120396 0.3048)
			(end 0.120396 0.2794)
			(stroke
				(width 0.1)
				(type default)
			)
			(layer "F.Fab")
		)
		(fp_line
			(start 0.67945 0.3048)
			(end 0.120396 0.3048)
			(stroke
				(width 0.1)
				(type default)
			)
			(layer "F.Fab")
		)
		(fp_line
			(start -0.12065 0.2794)
			(end -0.12065 0.3048)
			(stroke
				(width 0.1)
				(type default)
			)
			(layer "F.Fab")
		)
		(fp_line
			(start 0.120396 0.2794)
			(end -0.12065 0.2794)
			(stroke
				(width 0.1)
				(type default)
			)
			(layer "F.Fab")
		)
		(fp_line
			(start -0.12065 -0.2794)
			(end 0.12065 -0.2794)
			(stroke
				(width 0.1)
				(type default)
			)
			(layer "F.Fab")
		)
		(fp_line
			(start 0.12065 -0.2794)
			(end 0.12065 -0.3048)
			(stroke
				(width 0.1)
				(type default)
			)
			(layer "F.Fab")
		)
		(fp_line
			(start 0.12065 -0.3048)
			(end 0.67945 -0.3048)
			(stroke
				(width 0.1)
				(type default)
			)
			(layer "F.Fab")
		)
		(fp_line
			(start 0.67945 -0.3048)
			(end 0.67945 0.3048)
			(stroke
				(width 0.1)
				(type default)
			)
			(layer "F.Fab")
		)
		(fp_line
			(start -0.67945 -0.305054)
			(end -0.12065 -0.305054)
			(stroke
				(width 0.1)
				(type default)
			)
			(layer "F.Fab")
		)
		(fp_line
			(start -0.12065 -0.305054)
			(end -0.12065 -0.2794)
			(stroke
				(width 0.1)
				(type default)
			)
			(layer "F.Fab")
		)
		(pad "1" smd circle
			(at -0.40005 0 270)
			(size 0 0)
			(layers "F.Cu" "F.Mask" "F.Paste")
			(net "P3V3_AUX")
		)
		(pad "2" smd circle
			(at 0.40005 0 270)
			(size 0 0)
			(layers "F.Cu" "F.Mask" "F.Paste")
			(net "USB_HUB2_MRP_CFG_BC_EN")
		)
	)
	(footprint ""
		(layer "F.Cu")
		(at 119.761 -426.72)
		(property "Reference" "C1958"
			(at 0 0 0)
			(layer "F.SilkS")
			(hide yes)
			(effects
				(font
					(size 1.27 1.27)
				)
			)
		)
		(property "Value" ""
			(at 0 0 0)
			(layer "F.Fab")
			(effects
				(font
					(size 1.27 1.27)
				)
			)
		)
		(duplicate_pad_numbers_are_jumpers no)
		(fp_line
			(start -0.7874 -0.4064)
			(end 0.7874 -0.4064)
			(stroke
				(width 0.1524)
				(type default)
			)
			(layer "F.SilkS")
		)
		(fp_line
			(start -0.7874 0.4064)
			(end -0.7874 -0.4064)
			(stroke
				(width 0.1524)
				(type default)
			)
			(layer "F.SilkS")
		)
		(fp_line
			(start 0.7874 -0.4064)
			(end 0.7874 0.4064)
			(stroke
				(width 0.1524)
				(type default)
			)
			(layer "F.SilkS")
		)
		(fp_line
			(start 0.7874 0.4064)
			(end -0.7874 0.4064)
			(stroke
				(width 0.1524)
				(type default)
			)
			(layer "F.SilkS")
		)
		(fp_line
			(start -0.67945 -0.305054)
			(end -0.12065 -0.305054)
			(stroke
				(width 0.1)
				(type default)
			)
			(layer "F.Fab")
		)
		(fp_line
			(start -0.67945 0.3048)
			(end -0.67945 -0.305054)
			(stroke
				(width 0.1)
				(type default)
			)
			(layer "F.Fab")
		)
		(fp_line
			(start -0.12065 -0.305054)
			(end -0.12065 -0.2794)
			(stroke
				(width 0.1)
				(type default)
			)
			(layer "F.Fab")
		)
		(fp_line
			(start -0.12065 -0.2794)
			(end 0.12065 -0.2794)
			(stroke
				(width 0.1)
				(type default)
			)
			(layer "F.Fab")
		)
		(fp_line
			(start -0.12065 0.2794)
			(end -0.12065 0.3048)
			(stroke
				(width 0.1)
				(type default)
			)
			(layer "F.Fab")
		)
		(fp_line
			(start -0.12065 0.3048)
			(end -0.67945 0.3048)
			(stroke
				(width 0.1)
				(type default)
			)
			(layer "F.Fab")
		)
		(fp_line
			(start 0.120396 0.2794)
			(end -0.12065 0.2794)
			(stroke
				(width 0.1)
				(type default)
			)
			(layer "F.Fab")
		)
		(fp_line
			(start 0.120396 0.3048)
			(end 0.120396 0.2794)
			(stroke
				(width 0.1)
				(type default)
			)
			(layer "F.Fab")
		)
		(fp_line
			(start 0.12065 -0.3048)
			(end 0.67945 -0.3048)
			(stroke
				(width 0.1)
				(type default)
			)
			(layer "F.Fab")
		)
		(fp_line
			(start 0.12065 -0.2794)
			(end 0.12065 -0.3048)
			(stroke
				(width 0.1)
				(type default)
			)
			(layer "F.Fab")
		)
		(fp_line
			(start 0.67945 -0.3048)
			(end 0.67945 0.3048)
			(stroke
				(width 0.1)
				(type default)
			)
			(layer "F.Fab")
		)
		(fp_line
			(start 0.67945 0.3048)
			(end 0.120396 0.3048)
			(stroke
				(width 0.1)
				(type default)
			)
			(layer "F.Fab")
		)
		(pad "1" smd circle
			(at -0.40005 0)
			(size 0 0)
			(layers "F.Cu" "F.Mask" "F.Paste")
			(net "P3V3_AUX")
		)
		(pad "2" smd circle
			(at 0.40005 0)
			(size 0 0)
			(layers "F.Cu" "F.Mask" "F.Paste")
			(net "GND")
		)
	)
	(footprint ""
		(layer "F.Cu")
		(at 292.126162 -337.399122)
		(property "Reference" "PL18"
			(at -2.439162 -15.888208 0)
			(unlocked yes)
			(layer "F.SilkS")
			(effects
				(font
					(size 0.7874 0.5842)
					(thickness 0.1524)
				)
				(justify left)
			)
		)
		(property "Value" ""
			(at 0 0 0)
			(layer "F.Fab")
			(effects
				(font
					(size 1.27 1.27)
				)
			)
		)
		(duplicate_pad_numbers_are_jumpers no)
		(fp_line
			(start -3.750056 -5.500116)
			(end -2.393442 -5.500116)
			(stroke
				(width 0.1524)
				(type default)
			)
			(layer "F.SilkS")
		)
		(fp_line
			(start -3.750056 5.500116)
			(end -3.750056 -5.500116)
			(stroke
				(width 0.1524)
				(type default)
			)
			(layer "F.SilkS")
		)
		(fp_line
			(start -2.393442 5.500116)
			(end -3.750056 5.500116)
			(stroke
				(width 0.1524)
				(type default)
			)
			(layer "F.SilkS")
		)
		(fp_line
			(start 2.393442 5.500116)
			(end 3.750056 5.500116)
			(stroke
				(width 0.1524)
				(type default)
			)
			(layer "F.SilkS")
		)
		(fp_line
			(start 3.750056 -5.500116)
			(end 2.393442 -5.500116)
			(stroke
				(width 0.1524)
				(type default)
			)
			(layer "F.SilkS")
		)
		(fp_line
			(start 3.750056 5.500116)
			(end 3.750056 -5.500116)
			(stroke
				(width 0.1524)
				(type default)
			)
			(layer "F.SilkS")
		)
		(fp_poly
			(pts
				(xy -3.9116 -4.249928) (xy -4.3434 -4.034028) (xy -4.3434 -4.465828)
			)
			(stroke
				(width 0)
				(type default)
			)
			(fill yes)
			(layer "F.SilkS")
		)
		(fp_line
			(start -3.750056 -5.500116)
			(end -3.750056 5.500116)
			(stroke
				(width 0.1)
				(type default)
			)
			(layer "F.Fab")
		)
		(fp_line
			(start -3.750056 5.500116)
			(end 3.750056 5.500116)
			(stroke
				(width 0.1)
				(type default)
			)
			(layer "F.Fab")
		)
		(fp_line
			(start 3.750056 -5.500116)
			(end -3.750056 -5.500116)
			(stroke
				(width 0.1)
				(type default)
			)
			(layer "F.Fab")
		)
		(fp_line
			(start 3.750056 5.500116)
			(end 3.750056 -5.500116)
			(stroke
				(width 0.1)
				(type default)
			)
			(layer "F.Fab")
		)
		(fp_poly
			(pts
				(xy -4.9276 -4.757928) (xy -4.9276 -3.741928) (xy -3.9116 -4.249928)
			)
			(stroke
				(width 0)
				(type default)
			)
			(fill yes)
			(layer "F.Fab")
		)
		(pad "1" smd rect
			(at 0 -4.249928 270)
			(size 2.413 4.5212)
			(layers "F.Cu" "F.Mask" "F.Paste")
			(net "SW_PVDDIO_P0_SW2")
		)
		(pad "2" smd rect
			(at 0 -1.175004 270)
			(size 1.3716 4.5212)
			(layers "F.Cu" "F.Mask" "F.Paste")
			(net "IND_PVDDIO_P0_CPL3")
		)
		(pad "3" smd rect
			(at 0 1.175004 270)
			(size 1.3716 4.5212)
			(layers "F.Cu" "F.Mask" "F.Paste")
			(net "IND_PVDDIO_P0_CPL2")
		)
		(pad "4" smd rect
			(at 0 4.249928 270)
			(size 2.413 4.5212)
			(layers "F.Cu" "F.Mask" "F.Paste")
			(net "PVDDIO_P0")
		)
	)
	(footprint ""
		(layer "F.Cu")
		(at 188.296804 -428.069248 90)
		(property "Reference" "R3440"
			(at 0 0 90)
			(layer "F.SilkS")
			(hide yes)
			(effects
				(font
					(size 1.27 1.27)
				)
			)
		)
		(property "Value" ""
			(at 0 0 90)
			(layer "F.Fab")
			(effects
				(font
					(size 1.27 1.27)
				)
			)
		)
		(duplicate_pad_numbers_are_jumpers no)
		(fp_line
			(start 0.7874 -0.4064)
			(end 0.7874 0.4064)
			(stroke
				(width 0.1524)
				(type default)
			)
			(layer "F.SilkS")
		)
		(fp_line
			(start -0.7874 -0.4064)
			(end 0.7874 -0.4064)
			(stroke
				(width 0.1524)
				(type default)
			)
			(layer "F.SilkS")
		)
		(fp_line
			(start 0.7874 0.4064)
			(end -0.7874 0.4064)
			(stroke
				(width 0.1524)
				(type default)
			)
			(layer "F.SilkS")
		)
		(fp_line
			(start -0.7874 0.4064)
			(end -0.7874 -0.4064)
			(stroke
				(width 0.1524)
				(type default)
			)
			(layer "F.SilkS")
		)
		(fp_line
			(start -0.12065 -0.305054)
			(end -0.12065 -0.2794)
			(stroke
				(width 0.1)
				(type default)
			)
			(layer "F.Fab")
		)
		(fp_line
			(start -0.67945 -0.305054)
			(end -0.12065 -0.305054)
			(stroke
				(width 0.1)
				(type default)
			)
			(layer "F.Fab")
		)
		(fp_line
			(start 0.67945 -0.3048)
			(end 0.67945 0.3048)
			(stroke
				(width 0.1)
				(type default)
			)
			(layer "F.Fab")
		)
		(fp_line
			(start 0.12065 -0.3048)
			(end 0.67945 -0.3048)
			(stroke
				(width 0.1)
				(type default)
			)
			(layer "F.Fab")
		)
		(fp_line
			(start 0.12065 -0.2794)
			(end 0.12065 -0.3048)
			(stroke
				(width 0.1)
				(type default)
			)
			(layer "F.Fab")
		)
		(fp_line
			(start -0.12065 -0.2794)
			(end 0.12065 -0.2794)
			(stroke
				(width 0.1)
				(type default)
			)
			(layer "F.Fab")
		)
		(fp_line
			(start 0.120396 0.2794)
			(end -0.12065 0.2794)
			(stroke
				(width 0.1)
				(type default)
			)
			(layer "F.Fab")
		)
		(fp_line
			(start -0.12065 0.2794)
			(end -0.12065 0.3048)
			(stroke
				(width 0.1)
				(type default)
			)
			(layer "F.Fab")
		)
		(fp_line
			(start 0.67945 0.3048)
			(end 0.120396 0.3048)
			(stroke
				(width 0.1)
				(type default)
			)
			(layer "F.Fab")
		)
		(fp_line
			(start 0.120396 0.3048)
			(end 0.120396 0.2794)
			(stroke
				(width 0.1)
				(type default)
			)
			(layer "F.Fab")
		)
		(fp_line
			(start -0.12065 0.3048)
			(end -0.67945 0.3048)
			(stroke
				(width 0.1)
				(type default)
			)
			(layer "F.Fab")
		)
		(fp_line
			(start -0.67945 0.3048)
			(end -0.67945 -0.305054)
			(stroke
				(width 0.1)
				(type default)
			)
			(layer "F.Fab")
		)
		(pad "1" smd circle
			(at -0.40005 0 90)
			(size 0 0)
			(layers "F.Cu" "F.Mask" "F.Paste")
			(net "GPU_BASE_ID0")
		)
		(pad "2" smd circle
			(at 0.40005 0 90)
			(size 0 0)
			(layers "F.Cu" "F.Mask" "F.Paste")
			(net "GND")
		)
	)
	(footprint ""
		(layer "F.Cu")
		(at 110.565946 -52.86248 -90)
		(property "Reference" "R6304"
			(at 0 0 270)
			(layer "F.SilkS")
			(hide yes)
			(effects
				(font
					(size 1.27 1.27)
				)
			)
		)
		(property "Value" ""
			(at 0 0 270)
			(layer "F.Fab")
			(effects
				(font
					(size 1.27 1.27)
				)
			)
		)
		(duplicate_pad_numbers_are_jumpers no)
		(fp_line
			(start -0.7874 0.4064)
			(end -0.7874 -0.4064)
			(stroke
				(width 0.1524)
				(type default)
			)
			(layer "F.SilkS")
		)
		(fp_line
			(start 0.7874 0.4064)
			(end -0.7874 0.4064)
			(stroke
				(width 0.1524)
				(type default)
			)
			(layer "F.SilkS")
		)
		(fp_line
			(start -0.7874 -0.4064)
			(end 0.7874 -0.4064)
			(stroke
				(width 0.1524)
				(type default)
			)
			(layer "F.SilkS")
		)
		(fp_line
			(start 0.7874 -0.4064)
			(end 0.7874 0.4064)
			(stroke
				(width 0.1524)
				(type default)
			)
			(layer "F.SilkS")
		)
		(fp_line
			(start -0.67945 0.3048)
			(end -0.67945 -0.305054)
			(stroke
				(width 0.1)
				(type default)
			)
			(layer "F.Fab")
		)
		(fp_line
			(start -0.12065 0.3048)
			(end -0.67945 0.3048)
			(stroke
				(width 0.1)
				(type default)
			)
			(layer "F.Fab")
		)
		(fp_line
			(start 0.120396 0.3048)
			(end 0.120396 0.2794)
			(stroke
				(width 0.1)
				(type default)
			)
			(layer "F.Fab")
		)
		(fp_line
			(start 0.67945 0.3048)
			(end 0.120396 0.3048)
			(stroke
				(width 0.1)
				(type default)
			)
			(layer "F.Fab")
		)
		(fp_line
			(start -0.12065 0.2794)
			(end -0.12065 0.3048)
			(stroke
				(width 0.1)
				(type default)
			)
			(layer "F.Fab")
		)
		(fp_line
			(start 0.120396 0.2794)
			(end -0.12065 0.2794)
			(stroke
				(width 0.1)
				(type default)
			)
			(layer "F.Fab")
		)
		(fp_line
			(start -0.12065 -0.2794)
			(end 0.12065 -0.2794)
			(stroke
				(width 0.1)
				(type default)
			)
			(layer "F.Fab")
		)
		(fp_line
			(start 0.12065 -0.2794)
			(end 0.12065 -0.3048)
			(stroke
				(width 0.1)
				(type default)
			)
			(layer "F.Fab")
		)
		(fp_line
			(start 0.12065 -0.3048)
			(end 0.67945 -0.3048)
			(stroke
				(width 0.1)
				(type default)
			)
			(layer "F.Fab")
		)
		(fp_line
			(start 0.67945 -0.3048)
			(end 0.67945 0.3048)
			(stroke
				(width 0.1)
				(type default)
			)
			(layer "F.Fab")
		)
		(fp_line
			(start -0.67945 -0.305054)
			(end -0.12065 -0.305054)
			(stroke
				(width 0.1)
				(type default)
			)
			(layer "F.Fab")
		)
		(fp_line
			(start -0.12065 -0.305054)
			(end -0.12065 -0.2794)
			(stroke
				(width 0.1)
				(type default)
			)
			(layer "F.Fab")
		)
		(pad "1" smd circle
			(at -0.40005 0 270)
			(size 0 0)
			(layers "F.Cu" "F.Mask" "F.Paste")
			(net "USB_HUB2_TI_HS_SUSPEND")
		)
		(pad "2" smd circle
			(at 0.40005 0 270)
			(size 0 0)
			(layers "F.Cu" "F.Mask" "F.Paste")
			(net "USB_HUB2_TI_HS_SUSPEND_MRP_CFG_NON_REM")
		)
	)
	(footprint ""
		(layer "F.Cu")
		(at 144.36344 -31.58744 90)
		(property "Reference" "C6004"
			(at 0 0 90)
			(layer "F.SilkS")
			(hide yes)
			(effects
				(font
					(size 1.27 1.27)
				)
			)
		)
		(property "Value" ""
			(at 0 0 90)
			(layer "F.Fab")
			(effects
				(font
					(size 1.27 1.27)
				)
			)
		)
		(duplicate_pad_numbers_are_jumpers no)
		(fp_line
			(start 0.7874 -0.4064)
			(end 0.7874 0.4064)
			(stroke
				(width 0.1524)
				(type default)
			)
			(layer "F.SilkS")
		)
		(fp_line
			(start -0.7874 -0.4064)
			(end 0.7874 -0.4064)
			(stroke
				(width 0.1524)
				(type default)
			)
			(layer "F.SilkS")
		)
		(fp_line
			(start 0.7874 0.4064)
			(end -0.7874 0.4064)
			(stroke
				(width 0.1524)
				(type default)
			)
			(layer "F.SilkS")
		)
		(fp_line
			(start -0.7874 0.4064)
			(end -0.7874 -0.4064)
			(stroke
				(width 0.1524)
				(type default)
			)
			(layer "F.SilkS")
		)
		(fp_line
			(start 0.6858 -0.3048)
			(end 0.6858 0.3048)
			(stroke
				(width 0.1)
				(type default)
			)
			(layer "F.Fab")
		)
		(fp_line
			(start 0.1016 -0.3048)
			(end 0.6858 -0.3048)
			(stroke
				(width 0.1)
				(type default)
			)
			(layer "F.Fab")
		)
		(fp_line
			(start -0.1016 -0.3048)
			(end -0.1016 -0.2794)
			(stroke
				(width 0.1)
				(type default)
			)
			(layer "F.Fab")
		)
		(fp_line
			(start -0.6858 -0.3048)
			(end -0.1016 -0.3048)
			(stroke
				(width 0.1)
				(type default)
			)
			(layer "F.Fab")
		)
		(fp_line
			(start 0.1016 -0.2794)
			(end 0.1016 -0.3048)
			(stroke
				(width 0.1)
				(type default)
			)
			(layer "F.Fab")
		)
		(fp_line
			(start -0.1016 -0.2794)
			(end 0.1016 -0.2794)
			(stroke
				(width 0.1)
				(type default)
			)
			(layer "F.Fab")
		)
		(fp_line
			(start 0.1016 0.2794)
			(end -0.1016 0.2794)
			(stroke
				(width 0.1)
				(type default)
			)
			(layer "F.Fab")
		)
		(fp_line
			(start -0.1016 0.2794)
			(end -0.1016 0.3048)
			(stroke
				(width 0.1)
				(type default)
			)
			(layer "F.Fab")
		)
		(fp_line
			(start 0.6858 0.3048)
			(end 0.1016 0.3048)
			(stroke
				(width 0.1)
				(type default)
			)
			(layer "F.Fab")
		)
		(fp_line
			(start 0.1016 0.3048)
			(end 0.1016 0.2794)
			(stroke
				(width 0.1)
				(type default)
			)
			(layer "F.Fab")
		)
		(fp_line
			(start -0.1016 0.3048)
			(end -0.6858 0.3048)
			(stroke
				(width 0.1)
				(type default)
			)
			(layer "F.Fab")
		)
		(fp_line
			(start -0.6858 0.3048)
			(end -0.6858 -0.3048)
			(stroke
				(width 0.1)
				(type default)
			)
			(layer "F.Fab")
		)
		(pad "1" smd rect
			(at -0.40005 0 270)
			(size 0.4572 0.508)
			(layers "F.Cu" "F.Mask" "F.Paste")
			(net "USB3_CPU0_BMC_TX_DN")
		)
		(pad "2" smd rect
			(at 0.40005 0 270)
			(size 0.4572 0.508)
			(layers "F.Cu" "F.Mask" "F.Paste")
			(net "USB3_CPU0_BMC_TX_C1_DN")
		)
	)
	(footprint ""
		(layer "F.Cu")
		(at 59.8678 -36.083748 180)
		(property "Reference" "R4065"
			(at 0 0 180)
			(layer "F.SilkS")
			(hide yes)
			(effects
				(font
					(size 1.27 1.27)
				)
			)
		)
		(property "Value" ""
			(at 0 0 180)
			(layer "F.Fab")
			(effects
				(font
					(size 1.27 1.27)
				)
			)
		)
		(duplicate_pad_numbers_are_jumpers no)
		(fp_line
			(start 0.7874 0.4064)
			(end -0.7874 0.4064)
			(stroke
				(width 0.1524)
				(type default)
			)
			(layer "F.SilkS")
		)
		(fp_line
			(start 0.7874 -0.4064)
			(end 0.7874 0.4064)
			(stroke
				(width 0.1524)
				(type default)
			)
			(layer "F.SilkS")
		)
		(fp_line
			(start -0.7874 0.4064)
			(end -0.7874 -0.4064)
			(stroke
				(width 0.1524)
				(type default)
			)
			(layer "F.SilkS")
		)
		(fp_line
			(start -0.7874 -0.4064)
			(end 0.7874 -0.4064)
			(stroke
				(width 0.1524)
				(type default)
			)
			(layer "F.SilkS")
		)
		(fp_line
			(start 0.67945 0.3048)
			(end 0.120396 0.3048)
			(stroke
				(width 0.1)
				(type default)
			)
			(layer "F.Fab")
		)
		(fp_line
			(start 0.67945 -0.3048)
			(end 0.67945 0.3048)
			(stroke
				(width 0.1)
				(type default)
			)
			(layer "F.Fab")
		)
		(fp_line
			(start 0.12065 -0.2794)
			(end 0.12065 -0.3048)
			(stroke
				(width 0.1)
				(type default)
			)
			(layer "F.Fab")
		)
		(fp_line
			(start 0.12065 -0.3048)
			(end 0.67945 -0.3048)
			(stroke
				(width 0.1)
				(type default)
			)
			(layer "F.Fab")
		)
		(fp_line
			(start 0.120396 0.3048)
			(end 0.120396 0.2794)
			(stroke
				(width 0.1)
				(type default)
			)
			(layer "F.Fab")
		)
		(fp_line
			(start 0.120396 0.2794)
			(end -0.12065 0.2794)
			(stroke
				(width 0.1)
				(type default)
			)
			(layer "F.Fab")
		)
		(fp_line
			(start -0.12065 0.3048)
			(end -0.67945 0.3048)
			(stroke
				(width 0.1)
				(type default)
			)
			(layer "F.Fab")
		)
		(fp_line
			(start -0.12065 0.2794)
			(end -0.12065 0.3048)
			(stroke
				(width 0.1)
				(type default)
			)
			(layer "F.Fab")
		)
		(fp_line
			(start -0.12065 -0.2794)
			(end 0.12065 -0.2794)
			(stroke
				(width 0.1)
				(type default)
			)
			(layer "F.Fab")
		)
		(fp_line
			(start -0.12065 -0.305054)
			(end -0.12065 -0.2794)
			(stroke
				(width 0.1)
				(type default)
			)
			(layer "F.Fab")
		)
		(fp_line
			(start -0.67945 0.3048)
			(end -0.67945 -0.305054)
			(stroke
				(width 0.1)
				(type default)
			)
			(layer "F.Fab")
		)
		(fp_line
			(start -0.67945 -0.305054)
			(end -0.12065 -0.305054)
			(stroke
				(width 0.1)
				(type default)
			)
			(layer "F.Fab")
		)
		(pad "1" smd circle
			(at -0.40005 0 180)
			(size 0 0)
			(layers "F.Cu" "F.Mask" "F.Paste")
			(net "P12V_AUX")
		)
		(pad "2" smd circle
			(at 0.40005 0 180)
			(size 0 0)
			(layers "F.Cu" "F.Mask" "F.Paste")
			(net "P12V_OCP_2_EN_G")
		)
	)
	(footprint ""
		(layer "F.Cu")
		(at 145.501106 -408.517344 -90)
		(property "Reference" "C6714"
			(at 0 0 270)
			(layer "F.SilkS")
			(hide yes)
			(effects
				(font
					(size 1.27 1.27)
				)
			)
		)
		(property "Value" ""
			(at 0 0 270)
			(layer "F.Fab")
			(effects
				(font
					(size 1.27 1.27)
				)
			)
		)
		(duplicate_pad_numbers_are_jumpers no)
		(fp_line
			(start -0.299974 0.150114)
			(end -0.299974 -0.150114)
			(stroke
				(width 0.1)
				(type default)
			)
			(layer "F.Fab")
		)
		(fp_line
			(start 0.299974 0.150114)
			(end -0.299974 0.150114)
			(stroke
				(width 0.1)
				(type default)
			)
			(layer "F.Fab")
		)
		(fp_line
			(start -0.299974 -0.150114)
			(end 0.299974 -0.150114)
			(stroke
				(width 0.1)
				(type default)
			)
			(layer "F.Fab")
		)
		(fp_line
			(start 0.299974 -0.150114)
			(end 0.299974 0.150114)
			(stroke
				(width 0.1)
				(type default)
			)
			(layer "F.Fab")
		)
		(pad "1" smd rect
			(at -0.2667 0 270)
			(size 0.3048 0.381)
			(layers "F.Cu" "F.Mask" "F.Paste")
			(net "P5E_CPU1_P2_TX_BUF_C_DN<10>")
		)
		(pad "2" smd rect
			(at 0.2667 0 270)
			(size 0.3048 0.381)
			(layers "F.Cu" "F.Mask" "F.Paste")
			(net "P5E_CPU1_P2_TX_BUF_DN<10>")
		)
	)
	(footprint ""
		(layer "F.Cu")
		(at 101.770942 -145.377662 -90)
		(property "Reference" "R8180"
			(at 0 0 270)
			(layer "F.SilkS")
			(hide yes)
			(effects
				(font
					(size 1.27 1.27)
				)
			)
		)
		(property "Value" ""
			(at 0 0 270)
			(layer "F.Fab")
			(effects
				(font
					(size 1.27 1.27)
				)
			)
		)
		(duplicate_pad_numbers_are_jumpers no)
		(fp_line
			(start -0.7874 0.4064)
			(end -0.7874 -0.4064)
			(stroke
				(width 0.1524)
				(type default)
			)
			(layer "F.SilkS")
		)
		(fp_line
			(start 0.7874 0.4064)
			(end -0.7874 0.4064)
			(stroke
				(width 0.1524)
				(type default)
			)
			(layer "F.SilkS")
		)
		(fp_line
			(start -0.7874 -0.4064)
			(end 0.7874 -0.4064)
			(stroke
				(width 0.1524)
				(type default)
			)
			(layer "F.SilkS")
		)
		(fp_line
			(start 0.7874 -0.4064)
			(end 0.7874 0.4064)
			(stroke
				(width 0.1524)
				(type default)
			)
			(layer "F.SilkS")
		)
		(fp_line
			(start -0.67945 0.3048)
			(end -0.67945 -0.305054)
			(stroke
				(width 0.1)
				(type default)
			)
			(layer "F.Fab")
		)
		(fp_line
			(start -0.12065 0.3048)
			(end -0.67945 0.3048)
			(stroke
				(width 0.1)
				(type default)
			)
			(layer "F.Fab")
		)
		(fp_line
			(start 0.120396 0.3048)
			(end 0.120396 0.2794)
			(stroke
				(width 0.1)
				(type default)
			)
			(layer "F.Fab")
		)
		(fp_line
			(start 0.67945 0.3048)
			(end 0.120396 0.3048)
			(stroke
				(width 0.1)
				(type default)
			)
			(layer "F.Fab")
		)
		(fp_line
			(start -0.12065 0.2794)
			(end -0.12065 0.3048)
			(stroke
				(width 0.1)
				(type default)
			)
			(layer "F.Fab")
		)
		(fp_line
			(start 0.120396 0.2794)
			(end -0.12065 0.2794)
			(stroke
				(width 0.1)
				(type default)
			)
			(layer "F.Fab")
		)
		(fp_line
			(start -0.12065 -0.2794)
			(end 0.12065 -0.2794)
			(stroke
				(width 0.1)
				(type default)
			)
			(layer "F.Fab")
		)
		(fp_line
			(start 0.12065 -0.2794)
			(end 0.12065 -0.3048)
			(stroke
				(width 0.1)
				(type default)
			)
			(layer "F.Fab")
		)
		(fp_line
			(start 0.12065 -0.3048)
			(end 0.67945 -0.3048)
			(stroke
				(width 0.1)
				(type default)
			)
			(layer "F.Fab")
		)
		(fp_line
			(start 0.67945 -0.3048)
			(end 0.67945 0.3048)
			(stroke
				(width 0.1)
				(type default)
			)
			(layer "F.Fab")
		)
		(fp_line
			(start -0.67945 -0.305054)
			(end -0.12065 -0.305054)
			(stroke
				(width 0.1)
				(type default)
			)
			(layer "F.Fab")
		)
		(fp_line
			(start -0.12065 -0.305054)
			(end -0.12065 -0.2794)
			(stroke
				(width 0.1)
				(type default)
			)
			(layer "F.Fab")
		)
		(pad "1" smd circle
			(at -0.40005 0 270)
			(size 0 0)
			(layers "F.Cu" "F.Mask" "F.Paste")
			(net "PVDD18_S5_P1")
		)
		(pad "2" smd circle
			(at 0.40005 0 270)
			(size 0 0)
			(layers "F.Cu" "F.Mask" "F.Paste")
			(net "PVDDCR_CPU0_P1_OCP_N_R")
		)
	)
	(footprint ""
		(layer "F.Cu")
		(at 163.705794 -116.267484 180)
		(property "Reference" "R6141"
			(at 0 0 180)
			(layer "F.SilkS")
			(hide yes)
			(effects
				(font
					(size 1.27 1.27)
				)
			)
		)
		(property "Value" ""
			(at 0 0 180)
			(layer "F.Fab")
			(effects
				(font
					(size 1.27 1.27)
				)
			)
		)
		(duplicate_pad_numbers_are_jumpers no)
		(fp_line
			(start 0.7874 0.4064)
			(end -0.7874 0.4064)
			(stroke
				(width 0.1524)
				(type default)
			)
			(layer "F.SilkS")
		)
		(fp_line
			(start 0.7874 -0.4064)
			(end 0.7874 0.4064)
			(stroke
				(width 0.1524)
				(type default)
			)
			(layer "F.SilkS")
		)
		(fp_line
			(start -0.7874 0.4064)
			(end -0.7874 -0.4064)
			(stroke
				(width 0.1524)
				(type default)
			)
			(layer "F.SilkS")
		)
		(fp_line
			(start -0.7874 -0.4064)
			(end 0.7874 -0.4064)
			(stroke
				(width 0.1524)
				(type default)
			)
			(layer "F.SilkS")
		)
		(fp_line
			(start 0.67945 0.3048)
			(end 0.120396 0.3048)
			(stroke
				(width 0.1)
				(type default)
			)
			(layer "F.Fab")
		)
		(fp_line
			(start 0.67945 -0.3048)
			(end 0.67945 0.3048)
			(stroke
				(width 0.1)
				(type default)
			)
			(layer "F.Fab")
		)
		(fp_line
			(start 0.12065 -0.2794)
			(end 0.12065 -0.3048)
			(stroke
				(width 0.1)
				(type default)
			)
			(layer "F.Fab")
		)
		(fp_line
			(start 0.12065 -0.3048)
			(end 0.67945 -0.3048)
			(stroke
				(width 0.1)
				(type default)
			)
			(layer "F.Fab")
		)
		(fp_line
			(start 0.120396 0.3048)
			(end 0.120396 0.2794)
			(stroke
				(width 0.1)
				(type default)
			)
			(layer "F.Fab")
		)
		(fp_line
			(start 0.120396 0.2794)
			(end -0.12065 0.2794)
			(stroke
				(width 0.1)
				(type default)
			)
			(layer "F.Fab")
		)
		(fp_line
			(start -0.12065 0.3048)
			(end -0.67945 0.3048)
			(stroke
				(width 0.1)
				(type default)
			)
			(layer "F.Fab")
		)
		(fp_line
			(start -0.12065 0.2794)
			(end -0.12065 0.3048)
			(stroke
				(width 0.1)
				(type default)
			)
			(layer "F.Fab")
		)
		(fp_line
			(start -0.12065 -0.2794)
			(end 0.12065 -0.2794)
			(stroke
				(width 0.1)
				(type default)
			)
			(layer "F.Fab")
		)
		(fp_line
			(start -0.12065 -0.305054)
			(end -0.12065 -0.2794)
			(stroke
				(width 0.1)
				(type default)
			)
			(layer "F.Fab")
		)
		(fp_line
			(start -0.67945 0.3048)
			(end -0.67945 -0.305054)
			(stroke
				(width 0.1)
				(type default)
			)
			(layer "F.Fab")
		)
		(fp_line
			(start -0.67945 -0.305054)
			(end -0.12065 -0.305054)
			(stroke
				(width 0.1)
				(type default)
			)
			(layer "F.Fab")
		)
		(pad "1" smd circle
			(at -0.40005 0 180)
			(size 0 0)
			(layers "F.Cu" "F.Mask" "F.Paste")
			(net "FM_BOARD_BMC_SKU_ID4")
		)
		(pad "2" smd circle
			(at 0.40005 0 180)
			(size 0 0)
			(layers "F.Cu" "F.Mask" "F.Paste")
			(net "GND")
		)
	)
	(footprint ""
		(layer "F.Cu")
		(at 314.567316 -112.58677)
		(property "Reference" "R44"
			(at 0 0 0)
			(layer "F.SilkS")
			(hide yes)
			(effects
				(font
					(size 1.27 1.27)
				)
			)
		)
		(property "Value" ""
			(at 0 0 0)
			(layer "F.Fab")
			(effects
				(font
					(size 1.27 1.27)
				)
			)
		)
		(duplicate_pad_numbers_are_jumpers no)
		(fp_line
			(start -0.7874 -0.4064)
			(end 0.7874 -0.4064)
			(stroke
				(width 0.1524)
				(type default)
			)
			(layer "F.SilkS")
		)
		(fp_line
			(start -0.7874 0.4064)
			(end -0.7874 -0.4064)
			(stroke
				(width 0.1524)
				(type default)
			)
			(layer "F.SilkS")
		)
		(fp_line
			(start 0.7874 -0.4064)
			(end 0.7874 0.4064)
			(stroke
				(width 0.1524)
				(type default)
			)
			(layer "F.SilkS")
		)
		(fp_line
			(start 0.7874 0.4064)
			(end -0.7874 0.4064)
			(stroke
				(width 0.1524)
				(type default)
			)
			(layer "F.SilkS")
		)
		(fp_line
			(start -0.67945 -0.305054)
			(end -0.12065 -0.305054)
			(stroke
				(width 0.1)
				(type default)
			)
			(layer "F.Fab")
		)
		(fp_line
			(start -0.67945 0.3048)
			(end -0.67945 -0.305054)
			(stroke
				(width 0.1)
				(type default)
			)
			(layer "F.Fab")
		)
		(fp_line
			(start -0.12065 -0.305054)
			(end -0.12065 -0.2794)
			(stroke
				(width 0.1)
				(type default)
			)
			(layer "F.Fab")
		)
		(fp_line
			(start -0.12065 -0.2794)
			(end 0.12065 -0.2794)
			(stroke
				(width 0.1)
				(type default)
			)
			(layer "F.Fab")
		)
		(fp_line
			(start -0.12065 0.2794)
			(end -0.12065 0.3048)
			(stroke
				(width 0.1)
				(type default)
			)
			(layer "F.Fab")
		)
		(fp_line
			(start -0.12065 0.3048)
			(end -0.67945 0.3048)
			(stroke
				(width 0.1)
				(type default)
			)
			(layer "F.Fab")
		)
		(fp_line
			(start 0.120396 0.2794)
			(end -0.12065 0.2794)
			(stroke
				(width 0.1)
				(type default)
			)
			(layer "F.Fab")
		)
		(fp_line
			(start 0.120396 0.3048)
			(end 0.120396 0.2794)
			(stroke
				(width 0.1)
				(type default)
			)
			(layer "F.Fab")
		)
		(fp_line
			(start 0.12065 -0.3048)
			(end 0.67945 -0.3048)
			(stroke
				(width 0.1)
				(type default)
			)
			(layer "F.Fab")
		)
		(fp_line
			(start 0.12065 -0.2794)
			(end 0.12065 -0.3048)
			(stroke
				(width 0.1)
				(type default)
			)
			(layer "F.Fab")
		)
		(fp_line
			(start 0.67945 -0.3048)
			(end 0.67945 0.3048)
			(stroke
				(width 0.1)
				(type default)
			)
			(layer "F.Fab")
		)
		(fp_line
			(start 0.67945 0.3048)
			(end 0.120396 0.3048)
			(stroke
				(width 0.1)
				(type default)
			)
			(layer "F.Fab")
		)
		(pad "1" smd circle
			(at -0.40005 0)
			(size 0 0)
			(layers "F.Cu" "F.Mask" "F.Paste")
			(net "PD_CPU_FRU_WP")
		)
		(pad "2" smd circle
			(at 0.40005 0)
			(size 0 0)
			(layers "F.Cu" "F.Mask" "F.Paste")
			(net "GND")
		)
	)
	(footprint ""
		(layer "F.Cu")
		(at 171.196 -118.328948)
		(property "Reference" "R211"
			(at 0 0 0)
			(layer "F.SilkS")
			(hide yes)
			(effects
				(font
					(size 1.27 1.27)
				)
			)
		)
		(property "Value" ""
			(at 0 0 0)
			(layer "F.Fab")
			(effects
				(font
					(size 1.27 1.27)
				)
			)
		)
		(duplicate_pad_numbers_are_jumpers no)
		(fp_line
			(start -0.7874 -0.4064)
			(end 0.7874 -0.4064)
			(stroke
				(width 0.1524)
				(type default)
			)
			(layer "F.SilkS")
		)
		(fp_line
			(start -0.7874 0.4064)
			(end -0.7874 -0.4064)
			(stroke
				(width 0.1524)
				(type default)
			)
			(layer "F.SilkS")
		)
		(fp_line
			(start 0.7874 -0.4064)
			(end 0.7874 0.4064)
			(stroke
				(width 0.1524)
				(type default)
			)
			(layer "F.SilkS")
		)
		(fp_line
			(start 0.7874 0.4064)
			(end -0.7874 0.4064)
			(stroke
				(width 0.1524)
				(type default)
			)
			(layer "F.SilkS")
		)
		(fp_line
			(start -0.67945 -0.305054)
			(end -0.12065 -0.305054)
			(stroke
				(width 0.1)
				(type default)
			)
			(layer "F.Fab")
		)
		(fp_line
			(start -0.67945 0.3048)
			(end -0.67945 -0.305054)
			(stroke
				(width 0.1)
				(type default)
			)
			(layer "F.Fab")
		)
		(fp_line
			(start -0.12065 -0.305054)
			(end -0.12065 -0.2794)
			(stroke
				(width 0.1)
				(type default)
			)
			(layer "F.Fab")
		)
		(fp_line
			(start -0.12065 -0.2794)
			(end 0.12065 -0.2794)
			(stroke
				(width 0.1)
				(type default)
			)
			(layer "F.Fab")
		)
		(fp_line
			(start -0.12065 0.2794)
			(end -0.12065 0.3048)
			(stroke
				(width 0.1)
				(type default)
			)
			(layer "F.Fab")
		)
		(fp_line
			(start -0.12065 0.3048)
			(end -0.67945 0.3048)
			(stroke
				(width 0.1)
				(type default)
			)
			(layer "F.Fab")
		)
		(fp_line
			(start 0.120396 0.2794)
			(end -0.12065 0.2794)
			(stroke
				(width 0.1)
				(type default)
			)
			(layer "F.Fab")
		)
		(fp_line
			(start 0.120396 0.3048)
			(end 0.120396 0.2794)
			(stroke
				(width 0.1)
				(type default)
			)
			(layer "F.Fab")
		)
		(fp_line
			(start 0.12065 -0.3048)
			(end 0.67945 -0.3048)
			(stroke
				(width 0.1)
				(type default)
			)
			(layer "F.Fab")
		)
		(fp_line
			(start 0.12065 -0.2794)
			(end 0.12065 -0.3048)
			(stroke
				(width 0.1)
				(type default)
			)
			(layer "F.Fab")
		)
		(fp_line
			(start 0.67945 -0.3048)
			(end 0.67945 0.3048)
			(stroke
				(width 0.1)
				(type default)
			)
			(layer "F.Fab")
		)
		(fp_line
			(start 0.67945 0.3048)
			(end 0.120396 0.3048)
			(stroke
				(width 0.1)
				(type default)
			)
			(layer "F.Fab")
		)
		(pad "1" smd circle
			(at -0.40005 0)
			(size 0 0)
			(layers "F.Cu" "F.Mask" "F.Paste")
			(net "SMB_2_PLD_3V3AUX_SDA_R1")
		)
		(pad "2" smd circle
			(at 0.40005 0)
			(size 0 0)
			(layers "F.Cu" "F.Mask" "F.Paste")
			(net "SMB_2_PLD_3V3AUX_SDA_R2")
		)
	)
	(footprint ""
		(layer "F.Cu")
		(at 428.287688 -353.80549 90)
		(property "Reference" "PC204"
			(at 0 0 90)
			(layer "F.SilkS")
			(hide yes)
			(effects
				(font
					(size 1.27 1.27)
				)
			)
		)
		(property "Value" ""
			(at 0 0 90)
			(layer "F.Fab")
			(effects
				(font
					(size 1.27 1.27)
				)
			)
		)
		(duplicate_pad_numbers_are_jumpers no)
		(fp_line
			(start 0.7874 -0.4064)
			(end 0.7874 0.4064)
			(stroke
				(width 0.1524)
				(type default)
			)
			(layer "F.SilkS")
		)
		(fp_line
			(start -0.7874 -0.4064)
			(end 0.7874 -0.4064)
			(stroke
				(width 0.1524)
				(type default)
			)
			(layer "F.SilkS")
		)
		(fp_line
			(start 0.7874 0.4064)
			(end 0.44831 0.4064)
			(stroke
				(width 0.1524)
				(type default)
			)
			(layer "F.SilkS")
		)
		(fp_line
			(start -0.23749 0.4064)
			(end -0.7874 0.4064)
			(stroke
				(width 0.1524)
				(type default)
			)
			(layer "F.SilkS")
		)
		(fp_line
			(start -0.7874 0.4064)
			(end -0.7874 -0.4064)
			(stroke
				(width 0.1524)
				(type default)
			)
			(layer "F.SilkS")
		)
		(fp_line
			(start -0.12065 -0.305054)
			(end -0.12065 -0.2794)
			(stroke
				(width 0.1)
				(type default)
			)
			(layer "F.Fab")
		)
		(fp_line
			(start -0.67945 -0.305054)
			(end -0.12065 -0.305054)
			(stroke
				(width 0.1)
				(type default)
			)
			(layer "F.Fab")
		)
		(fp_line
			(start 0.67945 -0.3048)
			(end 0.67945 0.3048)
			(stroke
				(width 0.1)
				(type default)
			)
			(layer "F.Fab")
		)
		(fp_line
			(start 0.12065 -0.3048)
			(end 0.67945 -0.3048)
			(stroke
				(width 0.1)
				(type default)
			)
			(layer "F.Fab")
		)
		(fp_line
			(start 0.12065 -0.2794)
			(end 0.12065 -0.3048)
			(stroke
				(width 0.1)
				(type default)
			)
			(layer "F.Fab")
		)
		(fp_line
			(start -0.12065 -0.2794)
			(end 0.12065 -0.2794)
			(stroke
				(width 0.1)
				(type default)
			)
			(layer "F.Fab")
		)
		(fp_line
			(start 0.120396 0.2794)
			(end -0.12065 0.2794)
			(stroke
				(width 0.1)
				(type default)
			)
			(layer "F.Fab")
		)
		(fp_line
			(start -0.12065 0.2794)
			(end -0.12065 0.3048)
			(stroke
				(width 0.1)
				(type default)
			)
			(layer "F.Fab")
		)
		(fp_line
			(start 0.67945 0.3048)
			(end 0.120396 0.3048)
			(stroke
				(width 0.1)
				(type default)
			)
			(layer "F.Fab")
		)
		(fp_line
			(start 0.120396 0.3048)
			(end 0.120396 0.2794)
			(stroke
				(width 0.1)
				(type default)
			)
			(layer "F.Fab")
		)
		(fp_line
			(start -0.12065 0.3048)
			(end -0.67945 0.3048)
			(stroke
				(width 0.1)
				(type default)
			)
			(layer "F.Fab")
		)
		(fp_line
			(start -0.67945 0.3048)
			(end -0.67945 -0.305054)
			(stroke
				(width 0.1)
				(type default)
			)
			(layer "F.Fab")
		)
		(pad "1" smd circle
			(at -0.40005 0 90)
			(size 0 0)
			(layers "F.Cu" "F.Mask" "F.Paste")
			(net "PVDD11_S3_P0_VCC2")
		)
		(pad "2" smd circle
			(at 0.40005 0 90)
			(size 0 0)
			(layers "F.Cu" "F.Mask" "F.Paste")
			(net "GND")
		)
	)
	(footprint ""
		(layer "F.Cu")
		(at 307.404516 -437.498744 90)
		(property "Reference" "R4133"
			(at 0 0 90)
			(layer "F.SilkS")
			(hide yes)
			(effects
				(font
					(size 1.27 1.27)
				)
			)
		)
		(property "Value" ""
			(at 0 0 90)
			(layer "F.Fab")
			(effects
				(font
					(size 1.27 1.27)
				)
			)
		)
		(duplicate_pad_numbers_are_jumpers no)
		(fp_line
			(start 0.7874 -0.4064)
			(end 0.7874 0.4064)
			(stroke
				(width 0.1524)
				(type default)
			)
			(layer "F.SilkS")
		)
		(fp_line
			(start -0.7874 -0.4064)
			(end 0.7874 -0.4064)
			(stroke
				(width 0.1524)
				(type default)
			)
			(layer "F.SilkS")
		)
		(fp_line
			(start 0.7874 0.4064)
			(end -0.7874 0.4064)
			(stroke
				(width 0.1524)
				(type default)
			)
			(layer "F.SilkS")
		)
		(fp_line
			(start -0.7874 0.4064)
			(end -0.7874 -0.4064)
			(stroke
				(width 0.1524)
				(type default)
			)
			(layer "F.SilkS")
		)
		(fp_line
			(start -0.12065 -0.305054)
			(end -0.12065 -0.2794)
			(stroke
				(width 0.1)
				(type default)
			)
			(layer "F.Fab")
		)
		(fp_line
			(start -0.67945 -0.305054)
			(end -0.12065 -0.305054)
			(stroke
				(width 0.1)
				(type default)
			)
			(layer "F.Fab")
		)
		(fp_line
			(start 0.67945 -0.3048)
			(end 0.67945 0.3048)
			(stroke
				(width 0.1)
				(type default)
			)
			(layer "F.Fab")
		)
		(fp_line
			(start 0.12065 -0.3048)
			(end 0.67945 -0.3048)
			(stroke
				(width 0.1)
				(type default)
			)
			(layer "F.Fab")
		)
		(fp_line
			(start 0.12065 -0.2794)
			(end 0.12065 -0.3048)
			(stroke
				(width 0.1)
				(type default)
			)
			(layer "F.Fab")
		)
		(fp_line
			(start -0.12065 -0.2794)
			(end 0.12065 -0.2794)
			(stroke
				(width 0.1)
				(type default)
			)
			(layer "F.Fab")
		)
		(fp_line
			(start 0.120396 0.2794)
			(end -0.12065 0.2794)
			(stroke
				(width 0.1)
				(type default)
			)
			(layer "F.Fab")
		)
		(fp_line
			(start -0.12065 0.2794)
			(end -0.12065 0.3048)
			(stroke
				(width 0.1)
				(type default)
			)
			(layer "F.Fab")
		)
		(fp_line
			(start 0.67945 0.3048)
			(end 0.120396 0.3048)
			(stroke
				(width 0.1)
				(type default)
			)
			(layer "F.Fab")
		)
		(fp_line
			(start 0.120396 0.3048)
			(end 0.120396 0.2794)
			(stroke
				(width 0.1)
				(type default)
			)
			(layer "F.Fab")
		)
		(fp_line
			(start -0.12065 0.3048)
			(end -0.67945 0.3048)
			(stroke
				(width 0.1)
				(type default)
			)
			(layer "F.Fab")
		)
		(fp_line
			(start -0.67945 0.3048)
			(end -0.67945 -0.305054)
			(stroke
				(width 0.1)
				(type default)
			)
			(layer "F.Fab")
		)
		(pad "1" smd circle
			(at -0.40005 0 90)
			(size 0 0)
			(layers "F.Cu" "F.Mask" "F.Paste")
			(net "P3V3_AUX")
		)
		(pad "2" smd circle
			(at 0.40005 0 90)
			(size 0 0)
			(layers "F.Cu" "F.Mask" "F.Paste")
			(net "GPU_3V3IO_RSVD5_FFU")
		)
	)
	(footprint ""
		(layer "F.Cu")
		(at 108.760514 -172.960284)
		(property "Reference" "PR196"
			(at 0 0 0)
			(layer "F.SilkS")
			(hide yes)
			(effects
				(font
					(size 1.27 1.27)
				)
			)
		)
		(property "Value" ""
			(at 0 0 0)
			(layer "F.Fab")
			(effects
				(font
					(size 1.27 1.27)
				)
			)
		)
		(duplicate_pad_numbers_are_jumpers no)
		(fp_line
			(start -0.7874 -0.4064)
			(end 0.7874 -0.4064)
			(stroke
				(width 0.1524)
				(type default)
			)
			(layer "F.SilkS")
		)
		(fp_line
			(start -0.7874 0.4064)
			(end -0.7874 -0.4064)
			(stroke
				(width 0.1524)
				(type default)
			)
			(layer "F.SilkS")
		)
		(fp_line
			(start 0.7874 -0.4064)
			(end 0.7874 0.4064)
			(stroke
				(width 0.1524)
				(type default)
			)
			(layer "F.SilkS")
		)
		(fp_line
			(start 0.7874 0.4064)
			(end -0.7874 0.4064)
			(stroke
				(width 0.1524)
				(type default)
			)
			(layer "F.SilkS")
		)
		(fp_line
			(start -0.67945 -0.305054)
			(end -0.12065 -0.305054)
			(stroke
				(width 0.1)
				(type default)
			)
			(layer "F.Fab")
		)
		(fp_line
			(start -0.67945 0.3048)
			(end -0.67945 -0.305054)
			(stroke
				(width 0.1)
				(type default)
			)
			(layer "F.Fab")
		)
		(fp_line
			(start -0.12065 -0.305054)
			(end -0.12065 -0.2794)
			(stroke
				(width 0.1)
				(type default)
			)
			(layer "F.Fab")
		)
		(fp_line
			(start -0.12065 -0.2794)
			(end 0.12065 -0.2794)
			(stroke
				(width 0.1)
				(type default)
			)
			(layer "F.Fab")
		)
		(fp_line
			(start -0.12065 0.2794)
			(end -0.12065 0.3048)
			(stroke
				(width 0.1)
				(type default)
			)
			(layer "F.Fab")
		)
		(fp_line
			(start -0.12065 0.3048)
			(end -0.67945 0.3048)
			(stroke
				(width 0.1)
				(type default)
			)
			(layer "F.Fab")
		)
		(fp_line
			(start 0.120396 0.2794)
			(end -0.12065 0.2794)
			(stroke
				(width 0.1)
				(type default)
			)
			(layer "F.Fab")
		)
		(fp_line
			(start 0.120396 0.3048)
			(end 0.120396 0.2794)
			(stroke
				(width 0.1)
				(type default)
			)
			(layer "F.Fab")
		)
		(fp_line
			(start 0.12065 -0.3048)
			(end 0.67945 -0.3048)
			(stroke
				(width 0.1)
				(type default)
			)
			(layer "F.Fab")
		)
		(fp_line
			(start 0.12065 -0.2794)
			(end 0.12065 -0.3048)
			(stroke
				(width 0.1)
				(type default)
			)
			(layer "F.Fab")
		)
		(fp_line
			(start 0.67945 -0.3048)
			(end 0.67945 0.3048)
			(stroke
				(width 0.1)
				(type default)
			)
			(layer "F.Fab")
		)
		(fp_line
			(start 0.67945 0.3048)
			(end 0.120396 0.3048)
			(stroke
				(width 0.1)
				(type default)
			)
			(layer "F.Fab")
		)
		(pad "1" smd circle
			(at -0.40005 0)
			(size 0 0)
			(layers "F.Cu" "F.Mask" "F.Paste")
			(net "GND")
		)
		(pad "2" smd circle
			(at 0.40005 0)
			(size 0 0)
			(layers "F.Cu" "F.Mask" "F.Paste")
			(net "PVDDCR_CPU0_P1_LSET4")
		)
	)
	(footprint ""
		(layer "F.Cu")
		(at 328.274426 -416.899344 -90)
		(property "Reference" "C6518"
			(at 0 0 270)
			(layer "F.SilkS")
			(hide yes)
			(effects
				(font
					(size 1.27 1.27)
				)
			)
		)
		(property "Value" ""
			(at 0 0 270)
			(layer "F.Fab")
			(effects
				(font
					(size 1.27 1.27)
				)
			)
		)
		(duplicate_pad_numbers_are_jumpers no)
		(fp_line
			(start -0.299974 0.150114)
			(end -0.299974 -0.150114)
			(stroke
				(width 0.1)
				(type default)
			)
			(layer "F.Fab")
		)
		(fp_line
			(start 0.299974 0.150114)
			(end -0.299974 0.150114)
			(stroke
				(width 0.1)
				(type default)
			)
			(layer "F.Fab")
		)
		(fp_line
			(start -0.299974 -0.150114)
			(end 0.299974 -0.150114)
			(stroke
				(width 0.1)
				(type default)
			)
			(layer "F.Fab")
		)
		(fp_line
			(start 0.299974 -0.150114)
			(end 0.299974 0.150114)
			(stroke
				(width 0.1)
				(type default)
			)
			(layer "F.Fab")
		)
		(pad "1" smd rect
			(at -0.2667 0 270)
			(size 0.3048 0.381)
			(layers "F.Cu" "F.Mask" "F.Paste")
			(net "P5E_CPU0_P0_TX_BUF_C_DN<8>")
		)
		(pad "2" smd rect
			(at 0.2667 0 270)
			(size 0.3048 0.381)
			(layers "F.Cu" "F.Mask" "F.Paste")
			(net "P5E_CPU0_P0_TX_BUF_DN<8>")
		)
	)
	(footprint ""
		(layer "F.Cu")
		(at 279.570942 -380.66853)
		(property "Reference" "PR2538"
			(at 0 0 0)
			(layer "F.SilkS")
			(hide yes)
			(effects
				(font
					(size 1.27 1.27)
				)
			)
		)
		(property "Value" ""
			(at 0 0 0)
			(layer "F.Fab")
			(effects
				(font
					(size 1.27 1.27)
				)
			)
		)
		(duplicate_pad_numbers_are_jumpers no)
		(fp_line
			(start -0.7874 -0.4064)
			(end 0.7874 -0.4064)
			(stroke
				(width 0.1524)
				(type default)
			)
			(layer "F.SilkS")
		)
		(fp_line
			(start -0.7874 0.4064)
			(end -0.7874 -0.4064)
			(stroke
				(width 0.1524)
				(type default)
			)
			(layer "F.SilkS")
		)
		(fp_line
			(start 0.7874 -0.4064)
			(end 0.7874 0.4064)
			(stroke
				(width 0.1524)
				(type default)
			)
			(layer "F.SilkS")
		)
		(fp_line
			(start 0.7874 0.4064)
			(end -0.7874 0.4064)
			(stroke
				(width 0.1524)
				(type default)
			)
			(layer "F.SilkS")
		)
		(fp_line
			(start -0.67945 -0.305054)
			(end -0.12065 -0.305054)
			(stroke
				(width 0.1)
				(type default)
			)
			(layer "F.Fab")
		)
		(fp_line
			(start -0.67945 0.3048)
			(end -0.67945 -0.305054)
			(stroke
				(width 0.1)
				(type default)
			)
			(layer "F.Fab")
		)
		(fp_line
			(start -0.12065 -0.305054)
			(end -0.12065 -0.2794)
			(stroke
				(width 0.1)
				(type default)
			)
			(layer "F.Fab")
		)
		(fp_line
			(start -0.12065 -0.2794)
			(end 0.12065 -0.2794)
			(stroke
				(width 0.1)
				(type default)
			)
			(layer "F.Fab")
		)
		(fp_line
			(start -0.12065 0.2794)
			(end -0.12065 0.3048)
			(stroke
				(width 0.1)
				(type default)
			)
			(layer "F.Fab")
		)
		(fp_line
			(start -0.12065 0.3048)
			(end -0.67945 0.3048)
			(stroke
				(width 0.1)
				(type default)
			)
			(layer "F.Fab")
		)
		(fp_line
			(start 0.120396 0.2794)
			(end -0.12065 0.2794)
			(stroke
				(width 0.1)
				(type default)
			)
			(layer "F.Fab")
		)
		(fp_line
			(start 0.120396 0.3048)
			(end 0.120396 0.2794)
			(stroke
				(width 0.1)
				(type default)
			)
			(layer "F.Fab")
		)
		(fp_line
			(start 0.12065 -0.3048)
			(end 0.67945 -0.3048)
			(stroke
				(width 0.1)
				(type default)
			)
			(layer "F.Fab")
		)
		(fp_line
			(start 0.12065 -0.2794)
			(end 0.12065 -0.3048)
			(stroke
				(width 0.1)
				(type default)
			)
			(layer "F.Fab")
		)
		(fp_line
			(start 0.67945 -0.3048)
			(end 0.67945 0.3048)
			(stroke
				(width 0.1)
				(type default)
			)
			(layer "F.Fab")
		)
		(fp_line
			(start 0.67945 0.3048)
			(end 0.120396 0.3048)
			(stroke
				(width 0.1)
				(type default)
			)
			(layer "F.Fab")
		)
		(pad "1" smd circle
			(at -0.40005 0)
			(size 0 0)
			(layers "F.Cu" "F.Mask" "F.Paste")
			(net "MB0_CM_GATE_G0")
		)
		(pad "2" smd circle
			(at 0.40005 0)
			(size 0 0)
			(layers "F.Cu" "F.Mask" "F.Paste")
			(net "P12V_HSC_GATE1")
		)
	)
	(footprint ""
		(layer "F.Cu")
		(at 252.08484 -92.719144 -90)
		(property "Reference" "R1640"
			(at 0 0 270)
			(layer "F.SilkS")
			(hide yes)
			(effects
				(font
					(size 1.27 1.27)
				)
			)
		)
		(property "Value" ""
			(at 0 0 270)
			(layer "F.Fab")
			(effects
				(font
					(size 1.27 1.27)
				)
			)
		)
		(duplicate_pad_numbers_are_jumpers no)
		(fp_line
			(start -0.7874 0.4064)
			(end -0.7874 -0.4064)
			(stroke
				(width 0.1524)
				(type default)
			)
			(layer "F.SilkS")
		)
		(fp_line
			(start 0.7874 0.4064)
			(end -0.7874 0.4064)
			(stroke
				(width 0.1524)
				(type default)
			)
			(layer "F.SilkS")
		)
		(fp_line
			(start -0.7874 -0.4064)
			(end 0.7874 -0.4064)
			(stroke
				(width 0.1524)
				(type default)
			)
			(layer "F.SilkS")
		)
		(fp_line
			(start 0.7874 -0.4064)
			(end 0.7874 0.4064)
			(stroke
				(width 0.1524)
				(type default)
			)
			(layer "F.SilkS")
		)
		(fp_line
			(start -0.67945 0.3048)
			(end -0.67945 -0.305054)
			(stroke
				(width 0.1)
				(type default)
			)
			(layer "F.Fab")
		)
		(fp_line
			(start -0.12065 0.3048)
			(end -0.67945 0.3048)
			(stroke
				(width 0.1)
				(type default)
			)
			(layer "F.Fab")
		)
		(fp_line
			(start 0.120396 0.3048)
			(end 0.120396 0.2794)
			(stroke
				(width 0.1)
				(type default)
			)
			(layer "F.Fab")
		)
		(fp_line
			(start 0.67945 0.3048)
			(end 0.120396 0.3048)
			(stroke
				(width 0.1)
				(type default)
			)
			(layer "F.Fab")
		)
		(fp_line
			(start -0.12065 0.2794)
			(end -0.12065 0.3048)
			(stroke
				(width 0.1)
				(type default)
			)
			(layer "F.Fab")
		)
		(fp_line
			(start 0.120396 0.2794)
			(end -0.12065 0.2794)
			(stroke
				(width 0.1)
				(type default)
			)
			(layer "F.Fab")
		)
		(fp_line
			(start -0.12065 -0.2794)
			(end 0.12065 -0.2794)
			(stroke
				(width 0.1)
				(type default)
			)
			(layer "F.Fab")
		)
		(fp_line
			(start 0.12065 -0.2794)
			(end 0.12065 -0.3048)
			(stroke
				(width 0.1)
				(type default)
			)
			(layer "F.Fab")
		)
		(fp_line
			(start 0.12065 -0.3048)
			(end 0.67945 -0.3048)
			(stroke
				(width 0.1)
				(type default)
			)
			(layer "F.Fab")
		)
		(fp_line
			(start 0.67945 -0.3048)
			(end 0.67945 0.3048)
			(stroke
				(width 0.1)
				(type default)
			)
			(layer "F.Fab")
		)
		(fp_line
			(start -0.67945 -0.305054)
			(end -0.12065 -0.305054)
			(stroke
				(width 0.1)
				(type default)
			)
			(layer "F.Fab")
		)
		(fp_line
			(start -0.12065 -0.305054)
			(end -0.12065 -0.2794)
			(stroke
				(width 0.1)
				(type default)
			)
			(layer "F.Fab")
		)
		(pad "1" smd circle
			(at -0.40005 0 270)
			(size 0 0)
			(layers "F.Cu" "F.Mask" "F.Paste")
			(net "JTAG_P0_R_TRST_N")
		)
		(pad "2" smd circle
			(at 0.40005 0 270)
			(size 0 0)
			(layers "F.Cu" "F.Mask" "F.Paste")
			(net "JTAG_CPU0_TRST_N")
		)
	)
	(footprint ""
		(layer "F.Cu")
		(at 345.131644 -381.41783 -90)
		(property "Reference" "C949"
			(at 0 0 270)
			(layer "F.SilkS")
			(hide yes)
			(effects
				(font
					(size 1.27 1.27)
				)
			)
		)
		(property "Value" ""
			(at 0 0 270)
			(layer "F.Fab")
			(effects
				(font
					(size 1.27 1.27)
				)
			)
		)
		(duplicate_pad_numbers_are_jumpers no)
		(fp_line
			(start -0.299974 0.150114)
			(end -0.299974 -0.150114)
			(stroke
				(width 0.1)
				(type default)
			)
			(layer "F.Fab")
		)
		(fp_line
			(start 0.299974 0.150114)
			(end -0.299974 0.150114)
			(stroke
				(width 0.1)
				(type default)
			)
			(layer "F.Fab")
		)
		(fp_line
			(start -0.299974 -0.150114)
			(end 0.299974 -0.150114)
			(stroke
				(width 0.1)
				(type default)
			)
			(layer "F.Fab")
		)
		(fp_line
			(start 0.299974 -0.150114)
			(end 0.299974 0.150114)
			(stroke
				(width 0.1)
				(type default)
			)
			(layer "F.Fab")
		)
		(pad "1" smd rect
			(at -0.2667 0 270)
			(size 0.3048 0.381)
			(layers "F.Cu" "F.Mask" "F.Paste")
			(net "P5E_CPU0_P1_TX_C_DP<8>")
		)
		(pad "2" smd rect
			(at 0.2667 0 270)
			(size 0.3048 0.381)
			(layers "F.Cu" "F.Mask" "F.Paste")
			(net "P5E_CPU0_P1_TX_DP<8>")
		)
	)
	(footprint ""
		(layer "F.Cu")
		(at 254.592836 -120.31345)
		(property "Reference" "R3726"
			(at 0 0 0)
			(layer "F.SilkS")
			(hide yes)
			(effects
				(font
					(size 1.27 1.27)
				)
			)
		)
		(property "Value" ""
			(at 0 0 0)
			(layer "F.Fab")
			(effects
				(font
					(size 1.27 1.27)
				)
			)
		)
		(duplicate_pad_numbers_are_jumpers no)
		(fp_line
			(start -0.7874 -0.4064)
			(end 0.7874 -0.4064)
			(stroke
				(width 0.1524)
				(type default)
			)
			(layer "F.SilkS")
		)
		(fp_line
			(start -0.7874 0.4064)
			(end -0.7874 -0.4064)
			(stroke
				(width 0.1524)
				(type default)
			)
			(layer "F.SilkS")
		)
		(fp_line
			(start 0.7874 -0.4064)
			(end 0.7874 0.4064)
			(stroke
				(width 0.1524)
				(type default)
			)
			(layer "F.SilkS")
		)
		(fp_line
			(start 0.7874 0.4064)
			(end -0.7874 0.4064)
			(stroke
				(width 0.1524)
				(type default)
			)
			(layer "F.SilkS")
		)
		(fp_line
			(start -0.67945 -0.305054)
			(end -0.12065 -0.305054)
			(stroke
				(width 0.1)
				(type default)
			)
			(layer "F.Fab")
		)
		(fp_line
			(start -0.67945 0.3048)
			(end -0.67945 -0.305054)
			(stroke
				(width 0.1)
				(type default)
			)
			(layer "F.Fab")
		)
		(fp_line
			(start -0.12065 -0.305054)
			(end -0.12065 -0.2794)
			(stroke
				(width 0.1)
				(type default)
			)
			(layer "F.Fab")
		)
		(fp_line
			(start -0.12065 -0.2794)
			(end 0.12065 -0.2794)
			(stroke
				(width 0.1)
				(type default)
			)
			(layer "F.Fab")
		)
		(fp_line
			(start -0.12065 0.2794)
			(end -0.12065 0.3048)
			(stroke
				(width 0.1)
				(type default)
			)
			(layer "F.Fab")
		)
		(fp_line
			(start -0.12065 0.3048)
			(end -0.67945 0.3048)
			(stroke
				(width 0.1)
				(type default)
			)
			(layer "F.Fab")
		)
		(fp_line
			(start 0.120396 0.2794)
			(end -0.12065 0.2794)
			(stroke
				(width 0.1)
				(type default)
			)
			(layer "F.Fab")
		)
		(fp_line
			(start 0.120396 0.3048)
			(end 0.120396 0.2794)
			(stroke
				(width 0.1)
				(type default)
			)
			(layer "F.Fab")
		)
		(fp_line
			(start 0.12065 -0.3048)
			(end 0.67945 -0.3048)
			(stroke
				(width 0.1)
				(type default)
			)
			(layer "F.Fab")
		)
		(fp_line
			(start 0.12065 -0.2794)
			(end 0.12065 -0.3048)
			(stroke
				(width 0.1)
				(type default)
			)
			(layer "F.Fab")
		)
		(fp_line
			(start 0.67945 -0.3048)
			(end 0.67945 0.3048)
			(stroke
				(width 0.1)
				(type default)
			)
			(layer "F.Fab")
		)
		(fp_line
			(start 0.67945 0.3048)
			(end 0.120396 0.3048)
			(stroke
				(width 0.1)
				(type default)
			)
			(layer "F.Fab")
		)
		(pad "1" smd circle
			(at -0.40005 0)
			(size 0 0)
			(layers "F.Cu" "F.Mask" "F.Paste")
			(net "P3V3_AUX")
		)
		(pad "2" smd circle
			(at 0.40005 0)
			(size 0 0)
			(layers "F.Cu" "F.Mask" "F.Paste")
			(net "SMB_LM75_0_3V3AUX_SDA")
		)
	)
	(footprint ""
		(layer "F.Cu")
		(at 369.455446 -30.084522 -90)
		(property "Reference" "R1425"
			(at 0 0 270)
			(layer "F.SilkS")
			(hide yes)
			(effects
				(font
					(size 1.27 1.27)
				)
			)
		)
		(property "Value" ""
			(at 0 0 270)
			(layer "F.Fab")
			(effects
				(font
					(size 1.27 1.27)
				)
			)
		)
		(duplicate_pad_numbers_are_jumpers no)
		(fp_line
			(start -0.7874 0.4064)
			(end -0.7874 -0.4064)
			(stroke
				(width 0.1524)
				(type default)
			)
			(layer "F.SilkS")
		)
		(fp_line
			(start 0.7874 0.4064)
			(end -0.7874 0.4064)
			(stroke
				(width 0.1524)
				(type default)
			)
			(layer "F.SilkS")
		)
		(fp_line
			(start -0.7874 -0.4064)
			(end 0.7874 -0.4064)
			(stroke
				(width 0.1524)
				(type default)
			)
			(layer "F.SilkS")
		)
		(fp_line
			(start 0.7874 -0.4064)
			(end 0.7874 0.4064)
			(stroke
				(width 0.1524)
				(type default)
			)
			(layer "F.SilkS")
		)
		(fp_line
			(start -0.67945 0.3048)
			(end -0.67945 -0.305054)
			(stroke
				(width 0.1)
				(type default)
			)
			(layer "F.Fab")
		)
		(fp_line
			(start -0.12065 0.3048)
			(end -0.67945 0.3048)
			(stroke
				(width 0.1)
				(type default)
			)
			(layer "F.Fab")
		)
		(fp_line
			(start 0.120396 0.3048)
			(end 0.120396 0.2794)
			(stroke
				(width 0.1)
				(type default)
			)
			(layer "F.Fab")
		)
		(fp_line
			(start 0.67945 0.3048)
			(end 0.120396 0.3048)
			(stroke
				(width 0.1)
				(type default)
			)
			(layer "F.Fab")
		)
		(fp_line
			(start -0.12065 0.2794)
			(end -0.12065 0.3048)
			(stroke
				(width 0.1)
				(type default)
			)
			(layer "F.Fab")
		)
		(fp_line
			(start 0.120396 0.2794)
			(end -0.12065 0.2794)
			(stroke
				(width 0.1)
				(type default)
			)
			(layer "F.Fab")
		)
		(fp_line
			(start -0.12065 -0.2794)
			(end 0.12065 -0.2794)
			(stroke
				(width 0.1)
				(type default)
			)
			(layer "F.Fab")
		)
		(fp_line
			(start 0.12065 -0.2794)
			(end 0.12065 -0.3048)
			(stroke
				(width 0.1)
				(type default)
			)
			(layer "F.Fab")
		)
		(fp_line
			(start 0.12065 -0.3048)
			(end 0.67945 -0.3048)
			(stroke
				(width 0.1)
				(type default)
			)
			(layer "F.Fab")
		)
		(fp_line
			(start 0.67945 -0.3048)
			(end 0.67945 0.3048)
			(stroke
				(width 0.1)
				(type default)
			)
			(layer "F.Fab")
		)
		(fp_line
			(start -0.67945 -0.305054)
			(end -0.12065 -0.305054)
			(stroke
				(width 0.1)
				(type default)
			)
			(layer "F.Fab")
		)
		(fp_line
			(start -0.12065 -0.305054)
			(end -0.12065 -0.2794)
			(stroke
				(width 0.1)
				(type default)
			)
			(layer "F.Fab")
		)
		(pad "1" smd circle
			(at -0.40005 0 270)
			(size 0 0)
			(layers "F.Cu" "F.Mask" "F.Paste")
			(net "UART_CPU0_SCM_LVC3_UART1_R_TX")
		)
		(pad "2" smd circle
			(at 0.40005 0 270)
			(size 0 0)
			(layers "F.Cu" "F.Mask" "F.Paste")
			(net "UART_CPU0_SCM_LVC3_UART1_TX")
		)
	)
	(footprint ""
		(layer "F.Cu")
		(at 417.623752 -159.310324)
		(property "Reference" "PC605_9"
			(at 0 0 0)
			(layer "F.SilkS")
			(hide yes)
			(effects
				(font
					(size 1.27 1.27)
				)
			)
		)
		(property "Value" ""
			(at 0 0 0)
			(layer "F.Fab")
			(effects
				(font
					(size 1.27 1.27)
				)
			)
		)
		(duplicate_pad_numbers_are_jumpers no)
		(fp_line
			(start -0.7874 -0.4064)
			(end 0.7874 -0.4064)
			(stroke
				(width 0.1524)
				(type default)
			)
			(layer "F.SilkS")
		)
		(fp_line
			(start -0.7874 0.4064)
			(end -0.7874 -0.4064)
			(stroke
				(width 0.1524)
				(type default)
			)
			(layer "F.SilkS")
		)
		(fp_line
			(start 0.7874 -0.4064)
			(end 0.7874 0.4064)
			(stroke
				(width 0.1524)
				(type default)
			)
			(layer "F.SilkS")
		)
		(fp_line
			(start 0.7874 0.4064)
			(end -0.7874 0.4064)
			(stroke
				(width 0.1524)
				(type default)
			)
			(layer "F.SilkS")
		)
		(fp_line
			(start -0.67945 -0.305054)
			(end -0.12065 -0.305054)
			(stroke
				(width 0.1)
				(type default)
			)
			(layer "F.Fab")
		)
		(fp_line
			(start -0.67945 0.3048)
			(end -0.67945 -0.305054)
			(stroke
				(width 0.1)
				(type default)
			)
			(layer "F.Fab")
		)
		(fp_line
			(start -0.12065 -0.305054)
			(end -0.12065 -0.2794)
			(stroke
				(width 0.1)
				(type default)
			)
			(layer "F.Fab")
		)
		(fp_line
			(start -0.12065 -0.2794)
			(end 0.12065 -0.2794)
			(stroke
				(width 0.1)
				(type default)
			)
			(layer "F.Fab")
		)
		(fp_line
			(start -0.12065 0.2794)
			(end -0.12065 0.3048)
			(stroke
				(width 0.1)
				(type default)
			)
			(layer "F.Fab")
		)
		(fp_line
			(start -0.12065 0.3048)
			(end -0.67945 0.3048)
			(stroke
				(width 0.1)
				(type default)
			)
			(layer "F.Fab")
		)
		(fp_line
			(start 0.120396 0.2794)
			(end -0.12065 0.2794)
			(stroke
				(width 0.1)
				(type default)
			)
			(layer "F.Fab")
		)
		(fp_line
			(start 0.120396 0.3048)
			(end 0.120396 0.2794)
			(stroke
				(width 0.1)
				(type default)
			)
			(layer "F.Fab")
		)
		(fp_line
			(start 0.12065 -0.3048)
			(end 0.67945 -0.3048)
			(stroke
				(width 0.1)
				(type default)
			)
			(layer "F.Fab")
		)
		(fp_line
			(start 0.12065 -0.2794)
			(end 0.12065 -0.3048)
			(stroke
				(width 0.1)
				(type default)
			)
			(layer "F.Fab")
		)
		(fp_line
			(start 0.67945 -0.3048)
			(end 0.67945 0.3048)
			(stroke
				(width 0.1)
				(type default)
			)
			(layer "F.Fab")
		)
		(fp_line
			(start 0.67945 0.3048)
			(end 0.120396 0.3048)
			(stroke
				(width 0.1)
				(type default)
			)
			(layer "F.Fab")
		)
		(pad "1" smd circle
			(at -0.40005 0)
			(size 0 0)
			(layers "F.Cu" "F.Mask" "F.Paste")
			(net "PVDDCR_CPU0_P0_VCCS")
		)
		(pad "2" smd circle
			(at 0.40005 0)
			(size 0 0)
			(layers "F.Cu" "F.Mask" "F.Paste")
			(net "GND")
		)
	)
	(footprint ""
		(layer "F.Cu")
		(at 427.30166 -351.20326 -90)
		(property "Reference" "PC209_1"
			(at 0 0 270)
			(layer "F.SilkS")
			(hide yes)
			(effects
				(font
					(size 1.27 1.27)
				)
			)
		)
		(property "Value" ""
			(at 0 0 270)
			(layer "F.Fab")
			(effects
				(font
					(size 1.27 1.27)
				)
			)
		)
		(duplicate_pad_numbers_are_jumpers no)
		(fp_line
			(start -0.7874 0.4064)
			(end -0.7874 -0.4064)
			(stroke
				(width 0.1524)
				(type default)
			)
			(layer "F.SilkS")
		)
		(fp_line
			(start 0.7874 0.4064)
			(end -0.7874 0.4064)
			(stroke
				(width 0.1524)
				(type default)
			)
			(layer "F.SilkS")
		)
		(fp_line
			(start -0.7874 -0.4064)
			(end 0.7874 -0.4064)
			(stroke
				(width 0.1524)
				(type default)
			)
			(layer "F.SilkS")
		)
		(fp_line
			(start 0.7874 -0.4064)
			(end 0.7874 0.4064)
			(stroke
				(width 0.1524)
				(type default)
			)
			(layer "F.SilkS")
		)
		(fp_line
			(start -0.67945 0.3048)
			(end -0.67945 -0.305054)
			(stroke
				(width 0.1)
				(type default)
			)
			(layer "F.Fab")
		)
		(fp_line
			(start -0.12065 0.3048)
			(end -0.67945 0.3048)
			(stroke
				(width 0.1)
				(type default)
			)
			(layer "F.Fab")
		)
		(fp_line
			(start 0.120396 0.3048)
			(end 0.120396 0.2794)
			(stroke
				(width 0.1)
				(type default)
			)
			(layer "F.Fab")
		)
		(fp_line
			(start 0.67945 0.3048)
			(end 0.120396 0.3048)
			(stroke
				(width 0.1)
				(type default)
			)
			(layer "F.Fab")
		)
		(fp_line
			(start -0.12065 0.2794)
			(end -0.12065 0.3048)
			(stroke
				(width 0.1)
				(type default)
			)
			(layer "F.Fab")
		)
		(fp_line
			(start 0.120396 0.2794)
			(end -0.12065 0.2794)
			(stroke
				(width 0.1)
				(type default)
			)
			(layer "F.Fab")
		)
		(fp_line
			(start -0.12065 -0.2794)
			(end 0.12065 -0.2794)
			(stroke
				(width 0.1)
				(type default)
			)
			(layer "F.Fab")
		)
		(fp_line
			(start 0.12065 -0.2794)
			(end 0.12065 -0.3048)
			(stroke
				(width 0.1)
				(type default)
			)
			(layer "F.Fab")
		)
		(fp_line
			(start 0.12065 -0.3048)
			(end 0.67945 -0.3048)
			(stroke
				(width 0.1)
				(type default)
			)
			(layer "F.Fab")
		)
		(fp_line
			(start 0.67945 -0.3048)
			(end 0.67945 0.3048)
			(stroke
				(width 0.1)
				(type default)
			)
			(layer "F.Fab")
		)
		(fp_line
			(start -0.67945 -0.305054)
			(end -0.12065 -0.305054)
			(stroke
				(width 0.1)
				(type default)
			)
			(layer "F.Fab")
		)
		(fp_line
			(start -0.12065 -0.305054)
			(end -0.12065 -0.2794)
			(stroke
				(width 0.1)
				(type default)
			)
			(layer "F.Fab")
		)
		(pad "1" smd circle
			(at -0.40005 0 270)
			(size 0 0)
			(layers "F.Cu" "F.Mask" "F.Paste")
			(net "SW_P12V_AUX_PVDD11_S3_P0_FLT")
		)
		(pad "2" smd circle
			(at 0.40005 0 270)
			(size 0 0)
			(layers "F.Cu" "F.Mask" "F.Paste")
			(net "GND")
		)
	)
	(footprint ""
		(layer "F.Cu")
		(at 280.019506 -346.714572 -90)
		(property "Reference" "PC174_IOP0_3"
			(at 0 0 270)
			(layer "F.SilkS")
			(hide yes)
			(effects
				(font
					(size 1.27 1.27)
				)
			)
		)
		(property "Value" ""
			(at 0 0 270)
			(layer "F.Fab")
			(effects
				(font
					(size 1.27 1.27)
				)
			)
		)
		(duplicate_pad_numbers_are_jumpers no)
		(fp_line
			(start -0.7874 0.4064)
			(end -0.7874 -0.4064)
			(stroke
				(width 0.1524)
				(type default)
			)
			(layer "F.SilkS")
		)
		(fp_line
			(start 0.7874 0.4064)
			(end -0.7874 0.4064)
			(stroke
				(width 0.1524)
				(type default)
			)
			(layer "F.SilkS")
		)
		(fp_line
			(start -0.7874 -0.4064)
			(end 0.7874 -0.4064)
			(stroke
				(width 0.1524)
				(type default)
			)
			(layer "F.SilkS")
		)
		(fp_line
			(start 0.7874 -0.4064)
			(end 0.7874 0.4064)
			(stroke
				(width 0.1524)
				(type default)
			)
			(layer "F.SilkS")
		)
		(fp_line
			(start -0.67945 0.3048)
			(end -0.67945 -0.305054)
			(stroke
				(width 0.1)
				(type default)
			)
			(layer "F.Fab")
		)
		(fp_line
			(start -0.12065 0.3048)
			(end -0.67945 0.3048)
			(stroke
				(width 0.1)
				(type default)
			)
			(layer "F.Fab")
		)
		(fp_line
			(start 0.120396 0.3048)
			(end 0.120396 0.2794)
			(stroke
				(width 0.1)
				(type default)
			)
			(layer "F.Fab")
		)
		(fp_line
			(start 0.67945 0.3048)
			(end 0.120396 0.3048)
			(stroke
				(width 0.1)
				(type default)
			)
			(layer "F.Fab")
		)
		(fp_line
			(start -0.12065 0.2794)
			(end -0.12065 0.3048)
			(stroke
				(width 0.1)
				(type default)
			)
			(layer "F.Fab")
		)
		(fp_line
			(start 0.120396 0.2794)
			(end -0.12065 0.2794)
			(stroke
				(width 0.1)
				(type default)
			)
			(layer "F.Fab")
		)
		(fp_line
			(start -0.12065 -0.2794)
			(end 0.12065 -0.2794)
			(stroke
				(width 0.1)
				(type default)
			)
			(layer "F.Fab")
		)
		(fp_line
			(start 0.12065 -0.2794)
			(end 0.12065 -0.3048)
			(stroke
				(width 0.1)
				(type default)
			)
			(layer "F.Fab")
		)
		(fp_line
			(start 0.12065 -0.3048)
			(end 0.67945 -0.3048)
			(stroke
				(width 0.1)
				(type default)
			)
			(layer "F.Fab")
		)
		(fp_line
			(start 0.67945 -0.3048)
			(end 0.67945 0.3048)
			(stroke
				(width 0.1)
				(type default)
			)
			(layer "F.Fab")
		)
		(fp_line
			(start -0.67945 -0.305054)
			(end -0.12065 -0.305054)
			(stroke
				(width 0.1)
				(type default)
			)
			(layer "F.Fab")
		)
		(fp_line
			(start -0.12065 -0.305054)
			(end -0.12065 -0.2794)
			(stroke
				(width 0.1)
				(type default)
			)
			(layer "F.Fab")
		)
		(pad "1" smd circle
			(at -0.40005 0 270)
			(size 0 0)
			(layers "F.Cu" "F.Mask" "F.Paste")
			(net "PVDDCR_CPU1_P0_PVCC")
		)
		(pad "2" smd circle
			(at 0.40005 0 270)
			(size 0 0)
			(layers "F.Cu" "F.Mask" "F.Paste")
			(net "GND")
		)
	)
	(footprint ""
		(layer "F.Cu")
		(at 466.8901 -51.289966)
		(property "Reference" "H6001"
			(at -2.5146 -4.17957 0)
			(unlocked yes)
			(layer "F.SilkS")
			(effects
				(font
					(size 0.7874 0.5842)
					(thickness 0.1524)
				)
				(justify left)
			)
		)
		(property "Value" ""
			(at 0 0 0)
			(layer "F.Fab")
			(effects
				(font
					(size 1.27 1.27)
				)
			)
		)
		(duplicate_pad_numbers_are_jumpers no)
		(pad "1" thru_hole circle
			(at 0 0)
			(size 6.1976 6.1976)
			(drill 3.7338)
			(layers "*.Cu" "*.Mask")
			(remove_unused_layers no)
			(net "GND")
			(clearance -0.9779)
			(padstack
				(mode front_inner_back)
				(layer "Inner"
					(shape circle)
					(size 5.5372 5.5372)
					(clearance -0.6477)
				)
				(layer "B.Cu"
					(shape circle)
					(size 6.1976 6.1976)
					(clearance -0.9779)
				)
			)
		)
	)
	(footprint ""
		(layer "F.Cu")
		(at 127.64897 -162.527234 -90)
		(property "Reference" "PC320"
			(at 0 0 270)
			(layer "F.SilkS")
			(hide yes)
			(effects
				(font
					(size 1.27 1.27)
				)
			)
		)
		(property "Value" ""
			(at 0 0 270)
			(layer "F.Fab")
			(effects
				(font
					(size 1.27 1.27)
				)
			)
		)
		(duplicate_pad_numbers_are_jumpers no)
		(fp_line
			(start -0.7874 0.4064)
			(end -0.7874 -0.4064)
			(stroke
				(width 0.1524)
				(type default)
			)
			(layer "F.SilkS")
		)
		(fp_line
			(start -0.286766 0.4064)
			(end -0.7874 0.4064)
			(stroke
				(width 0.1524)
				(type default)
			)
			(layer "F.SilkS")
		)
		(fp_line
			(start 0.7874 0.4064)
			(end 0.348234 0.4064)
			(stroke
				(width 0.1524)
				(type default)
			)
			(layer "F.SilkS")
		)
		(fp_line
			(start -0.7874 -0.4064)
			(end 0.7874 -0.4064)
			(stroke
				(width 0.1524)
				(type default)
			)
			(layer "F.SilkS")
		)
		(fp_line
			(start 0.7874 -0.4064)
			(end 0.7874 0.4064)
			(stroke
				(width 0.1524)
				(type default)
			)
			(layer "F.SilkS")
		)
		(fp_line
			(start -0.67945 0.3048)
			(end -0.67945 -0.305054)
			(stroke
				(width 0.1)
				(type default)
			)
			(layer "F.Fab")
		)
		(fp_line
			(start -0.12065 0.3048)
			(end -0.67945 0.3048)
			(stroke
				(width 0.1)
				(type default)
			)
			(layer "F.Fab")
		)
		(fp_line
			(start 0.120396 0.3048)
			(end 0.120396 0.2794)
			(stroke
				(width 0.1)
				(type default)
			)
			(layer "F.Fab")
		)
		(fp_line
			(start 0.67945 0.3048)
			(end 0.120396 0.3048)
			(stroke
				(width 0.1)
				(type default)
			)
			(layer "F.Fab")
		)
		(fp_line
			(start -0.12065 0.2794)
			(end -0.12065 0.3048)
			(stroke
				(width 0.1)
				(type default)
			)
			(layer "F.Fab")
		)
		(fp_line
			(start 0.120396 0.2794)
			(end -0.12065 0.2794)
			(stroke
				(width 0.1)
				(type default)
			)
			(layer "F.Fab")
		)
		(fp_line
			(start -0.12065 -0.2794)
			(end 0.12065 -0.2794)
			(stroke
				(width 0.1)
				(type default)
			)
			(layer "F.Fab")
		)
		(fp_line
			(start 0.12065 -0.2794)
			(end 0.12065 -0.3048)
			(stroke
				(width 0.1)
				(type default)
			)
			(layer "F.Fab")
		)
		(fp_line
			(start 0.12065 -0.3048)
			(end 0.67945 -0.3048)
			(stroke
				(width 0.1)
				(type default)
			)
			(layer "F.Fab")
		)
		(fp_line
			(start 0.67945 -0.3048)
			(end 0.67945 0.3048)
			(stroke
				(width 0.1)
				(type default)
			)
			(layer "F.Fab")
		)
		(fp_line
			(start -0.67945 -0.305054)
			(end -0.12065 -0.305054)
			(stroke
				(width 0.1)
				(type default)
			)
			(layer "F.Fab")
		)
		(fp_line
			(start -0.12065 -0.305054)
			(end -0.12065 -0.2794)
			(stroke
				(width 0.1)
				(type default)
			)
			(layer "F.Fab")
		)
		(pad "1" smd circle
			(at -0.40005 0 270)
			(size 0 0)
			(layers "F.Cu" "F.Mask" "F.Paste")
			(net "PVDDCR_SOC_P1_VCC2")
		)
		(pad "2" smd circle
			(at 0.40005 0 270)
			(size 0 0)
			(layers "F.Cu" "F.Mask" "F.Paste")
			(net "GND")
		)
	)
	(footprint ""
		(layer "F.Cu")
		(at 254.592836 -126.91745)
		(property "Reference" "R3708"
			(at 0 0 0)
			(layer "F.SilkS")
			(hide yes)
			(effects
				(font
					(size 1.27 1.27)
				)
			)
		)
		(property "Value" ""
			(at 0 0 0)
			(layer "F.Fab")
			(effects
				(font
					(size 1.27 1.27)
				)
			)
		)
		(duplicate_pad_numbers_are_jumpers no)
		(fp_line
			(start -0.7874 -0.4064)
			(end 0.7874 -0.4064)
			(stroke
				(width 0.1524)
				(type default)
			)
			(layer "F.SilkS")
		)
		(fp_line
			(start -0.7874 0.4064)
			(end -0.7874 -0.4064)
			(stroke
				(width 0.1524)
				(type default)
			)
			(layer "F.SilkS")
		)
		(fp_line
			(start 0.7874 -0.4064)
			(end 0.7874 0.4064)
			(stroke
				(width 0.1524)
				(type default)
			)
			(layer "F.SilkS")
		)
		(fp_line
			(start 0.7874 0.4064)
			(end -0.7874 0.4064)
			(stroke
				(width 0.1524)
				(type default)
			)
			(layer "F.SilkS")
		)
		(fp_line
			(start -0.67945 -0.305054)
			(end -0.12065 -0.305054)
			(stroke
				(width 0.1)
				(type default)
			)
			(layer "F.Fab")
		)
		(fp_line
			(start -0.67945 0.3048)
			(end -0.67945 -0.305054)
			(stroke
				(width 0.1)
				(type default)
			)
			(layer "F.Fab")
		)
		(fp_line
			(start -0.12065 -0.305054)
			(end -0.12065 -0.2794)
			(stroke
				(width 0.1)
				(type default)
			)
			(layer "F.Fab")
		)
		(fp_line
			(start -0.12065 -0.2794)
			(end 0.12065 -0.2794)
			(stroke
				(width 0.1)
				(type default)
			)
			(layer "F.Fab")
		)
		(fp_line
			(start -0.12065 0.2794)
			(end -0.12065 0.3048)
			(stroke
				(width 0.1)
				(type default)
			)
			(layer "F.Fab")
		)
		(fp_line
			(start -0.12065 0.3048)
			(end -0.67945 0.3048)
			(stroke
				(width 0.1)
				(type default)
			)
			(layer "F.Fab")
		)
		(fp_line
			(start 0.120396 0.2794)
			(end -0.12065 0.2794)
			(stroke
				(width 0.1)
				(type default)
			)
			(layer "F.Fab")
		)
		(fp_line
			(start 0.120396 0.3048)
			(end 0.120396 0.2794)
			(stroke
				(width 0.1)
				(type default)
			)
			(layer "F.Fab")
		)
		(fp_line
			(start 0.12065 -0.3048)
			(end 0.67945 -0.3048)
			(stroke
				(width 0.1)
				(type default)
			)
			(layer "F.Fab")
		)
		(fp_line
			(start 0.12065 -0.2794)
			(end 0.12065 -0.3048)
			(stroke
				(width 0.1)
				(type default)
			)
			(layer "F.Fab")
		)
		(fp_line
			(start 0.67945 -0.3048)
			(end 0.67945 0.3048)
			(stroke
				(width 0.1)
				(type default)
			)
			(layer "F.Fab")
		)
		(fp_line
			(start 0.67945 0.3048)
			(end 0.120396 0.3048)
			(stroke
				(width 0.1)
				(type default)
			)
			(layer "F.Fab")
		)
		(pad "1" smd circle
			(at -0.40005 0)
			(size 0 0)
			(layers "F.Cu" "F.Mask" "F.Paste")
			(net "P3V3_AUX")
		)
		(pad "2" smd circle
			(at 0.40005 0)
			(size 0 0)
			(layers "F.Cu" "F.Mask" "F.Paste")
			(net "PCA9548_PCIE0_ADDR0")
		)
	)
	(footprint ""
		(layer "F.Cu")
		(at 234.739688 -148.948648 180)
		(property "Reference" "U153"
			(at -3.725164 -3.332988 0)
			(unlocked yes)
			(layer "F.SilkS")
			(effects
				(font
					(size 0.7874 0.5842)
					(thickness 0.1524)
				)
				(justify left)
			)
		)
		(property "Value" ""
			(at 0 0 180)
			(layer "F.Fab")
			(effects
				(font
					(size 1.27 1.27)
				)
			)
		)
		(duplicate_pad_numbers_are_jumpers no)
		(fp_line
			(start 1.0414 1.575054)
			(end -1.0414 1.575054)
			(stroke
				(width 0.1524)
				(type default)
			)
			(layer "F.SilkS")
		)
		(fp_line
			(start 1.0414 -1.575054)
			(end 1.0414 1.575054)
			(stroke
				(width 0.1524)
				(type default)
			)
			(layer "F.SilkS")
		)
		(fp_line
			(start 0.254 -1.575054)
			(end 1.0414 -1.575054)
			(stroke
				(width 0.1524)
				(type default)
			)
			(layer "F.SilkS")
		)
		(fp_line
			(start 0.2286 -1.575054)
			(end 0 -1.272032)
			(stroke
				(width 0.1524)
				(type default)
			)
			(layer "F.SilkS")
		)
		(fp_line
			(start 0 -1.272032)
			(end -0.254 -1.575054)
			(stroke
				(width 0.1524)
				(type default)
			)
			(layer "F.SilkS")
		)
		(fp_line
			(start -1.0414 1.575054)
			(end -1.0414 -1.575054)
			(stroke
				(width 0.1524)
				(type default)
			)
			(layer "F.SilkS")
		)
		(fp_line
			(start -1.0414 -1.575054)
			(end -0.254 -1.575054)
			(stroke
				(width 0.1524)
				(type default)
			)
			(layer "F.SilkS")
		)
		(fp_poly
			(pts
				(xy -3.960876 -2.091182) (xy -3.242564 -2.809748) (xy -2.883154 -1.732026)
			)
			(stroke
				(width 0)
				(type default)
			)
			(fill yes)
			(layer "F.SilkS")
		)
		(fp_line
			(start 2.5654 1.2192)
			(end 1.4478 1.2192)
			(stroke
				(width 0.1)
				(type default)
			)
			(layer "F.Fab")
		)
		(fp_line
			(start 2.5654 -1.2192)
			(end 2.5654 1.2192)
			(stroke
				(width 0.1)
				(type default)
			)
			(layer "F.Fab")
		)
		(fp_line
			(start 1.4478 1.5748)
			(end -1.4478 1.5748)
			(stroke
				(width 0.1)
				(type default)
			)
			(layer "F.Fab")
		)
		(fp_line
			(start 1.4478 1.2192)
			(end 1.4478 1.5748)
			(stroke
				(width 0.1)
				(type default)
			)
			(layer "F.Fab")
		)
		(fp_line
			(start 1.4478 -1.2192)
			(end 2.5654 -1.2192)
			(stroke
				(width 0.1)
				(type default)
			)
			(layer "F.Fab")
		)
		(fp_line
			(start 1.4478 -1.5748)
			(end 1.4478 -1.2192)
			(stroke
				(width 0.1)
				(type default)
			)
			(layer "F.Fab")
		)
		(fp_line
			(start -1.4478 1.5748)
			(end -1.4478 1.2192)
			(stroke
				(width 0.1)
				(type default)
			)
			(layer "F.Fab")
		)
		(fp_line
			(start -1.4478 1.2192)
			(end -2.5654 1.2192)
			(stroke
				(width 0.1)
				(type default)
			)
			(layer "F.Fab")
		)
		(fp_line
			(start -1.4478 -1.2192)
			(end -1.4478 -1.5748)
			(stroke
				(width 0.1)
				(type default)
			)
			(layer "F.Fab")
		)
		(fp_line
			(start -1.4478 -1.5748)
			(end 1.4478 -1.5748)
			(stroke
				(width 0.1)
				(type default)
			)
			(layer "F.Fab")
		)
		(fp_line
			(start -2.5654 1.2192)
			(end -2.5654 -1.2192)
			(stroke
				(width 0.1)
				(type default)
			)
			(layer "F.Fab")
		)
		(fp_line
			(start -2.5654 -1.2192)
			(end -1.4478 -1.2192)
			(stroke
				(width 0.1)
				(type default)
			)
			(layer "F.Fab")
		)
		(fp_poly
			(pts
				(xy -2.710688 -0.975106) (xy -3.726688 -1.483106) (xy -3.726688 -0.467106)
			)
			(stroke
				(width 0)
				(type default)
			)
			(fill yes)
			(layer "F.Fab")
		)
		(pad "1" smd rect
			(at -1.849882 -0.975106 90)
			(size 0.3556 1.3208)
			(layers "F.Cu" "F.Mask" "F.Paste")
			(net "JTAG_CPUX_TDI")
		)
		(pad "2" smd rect
			(at -1.849882 -0.32512 90)
			(size 0.3556 1.3208)
			(layers "F.Cu" "F.Mask" "F.Paste")
			(net "JTAG_CPU0_R_TDI")
		)
		(pad "3" smd rect
			(at -1.849882 0.32512 90)
			(size 0.3556 1.3208)
			(layers "F.Cu" "F.Mask" "F.Paste")
			(net "FM_PLD_CPU0_PRSNT_HDT_N")
		)
		(pad "4" smd rect
			(at -1.849882 0.975106 90)
			(size 0.3556 1.3208)
			(layers "F.Cu" "F.Mask" "F.Paste")
			(net "GND")
		)
		(pad "5" smd rect
			(at 1.849882 0.975106 90)
			(size 0.3556 1.3208)
			(layers "F.Cu" "F.Mask" "F.Paste")
			(net "JTAG_CPUX_TDI")
		)
		(pad "6" smd rect
			(at 1.849882 0.32512 90)
			(size 0.3556 1.3208)
			(layers "F.Cu" "F.Mask" "F.Paste")
			(net "JTAG_CPU0_BYPASS")
		)
		(pad "7" smd rect
			(at 1.849882 -0.32512 90)
			(size 0.3556 1.3208)
			(layers "F.Cu" "F.Mask" "F.Paste")
			(net "CPU0_HDT_BYPASS_SEL")
		)
		(pad "8" smd rect
			(at 1.849882 -0.975106 90)
			(size 0.3556 1.3208)
			(layers "F.Cu" "F.Mask" "F.Paste")
			(net "PVDD18_S5_P0")
		)
	)
	(footprint ""
		(layer "F.Cu")
		(at 163.59632 -102.00132 180)
		(property "Reference" "R6188"
			(at 0 0 180)
			(layer "F.SilkS")
			(hide yes)
			(effects
				(font
					(size 1.27 1.27)
				)
			)
		)
		(property "Value" ""
			(at 0 0 180)
			(layer "F.Fab")
			(effects
				(font
					(size 1.27 1.27)
				)
			)
		)
		(duplicate_pad_numbers_are_jumpers no)
		(fp_line
			(start 0.7874 0.4064)
			(end -0.7874 0.4064)
			(stroke
				(width 0.1524)
				(type default)
			)
			(layer "F.SilkS")
		)
		(fp_line
			(start 0.7874 -0.4064)
			(end 0.7874 0.4064)
			(stroke
				(width 0.1524)
				(type default)
			)
			(layer "F.SilkS")
		)
		(fp_line
			(start -0.7874 0.4064)
			(end -0.7874 -0.4064)
			(stroke
				(width 0.1524)
				(type default)
			)
			(layer "F.SilkS")
		)
		(fp_line
			(start -0.7874 -0.4064)
			(end 0.7874 -0.4064)
			(stroke
				(width 0.1524)
				(type default)
			)
			(layer "F.SilkS")
		)
		(fp_line
			(start 0.67945 0.3048)
			(end 0.120396 0.3048)
			(stroke
				(width 0.1)
				(type default)
			)
			(layer "F.Fab")
		)
		(fp_line
			(start 0.67945 -0.3048)
			(end 0.67945 0.3048)
			(stroke
				(width 0.1)
				(type default)
			)
			(layer "F.Fab")
		)
		(fp_line
			(start 0.12065 -0.2794)
			(end 0.12065 -0.3048)
			(stroke
				(width 0.1)
				(type default)
			)
			(layer "F.Fab")
		)
		(fp_line
			(start 0.12065 -0.3048)
			(end 0.67945 -0.3048)
			(stroke
				(width 0.1)
				(type default)
			)
			(layer "F.Fab")
		)
		(fp_line
			(start 0.120396 0.3048)
			(end 0.120396 0.2794)
			(stroke
				(width 0.1)
				(type default)
			)
			(layer "F.Fab")
		)
		(fp_line
			(start 0.120396 0.2794)
			(end -0.12065 0.2794)
			(stroke
				(width 0.1)
				(type default)
			)
			(layer "F.Fab")
		)
		(fp_line
			(start -0.12065 0.3048)
			(end -0.67945 0.3048)
			(stroke
				(width 0.1)
				(type default)
			)
			(layer "F.Fab")
		)
		(fp_line
			(start -0.12065 0.2794)
			(end -0.12065 0.3048)
			(stroke
				(width 0.1)
				(type default)
			)
			(layer "F.Fab")
		)
		(fp_line
			(start -0.12065 -0.2794)
			(end 0.12065 -0.2794)
			(stroke
				(width 0.1)
				(type default)
			)
			(layer "F.Fab")
		)
		(fp_line
			(start -0.12065 -0.305054)
			(end -0.12065 -0.2794)
			(stroke
				(width 0.1)
				(type default)
			)
			(layer "F.Fab")
		)
		(fp_line
			(start -0.67945 0.3048)
			(end -0.67945 -0.305054)
			(stroke
				(width 0.1)
				(type default)
			)
			(layer "F.Fab")
		)
		(fp_line
			(start -0.67945 -0.305054)
			(end -0.12065 -0.305054)
			(stroke
				(width 0.1)
				(type default)
			)
			(layer "F.Fab")
		)
		(pad "1" smd circle
			(at -0.40005 0 180)
			(size 0 0)
			(layers "F.Cu" "F.Mask" "F.Paste")
			(net "FM_SEC_MUX_SEL")
		)
		(pad "2" smd circle
			(at 0.40005 0 180)
			(size 0 0)
			(layers "F.Cu" "F.Mask" "F.Paste")
			(net "P3V3_AUX")
		)
	)
	(footprint ""
		(layer "F.Cu")
		(at 300.691296 -378.95403 -90)
		(property "Reference" "C927"
			(at 0 0 270)
			(layer "F.SilkS")
			(hide yes)
			(effects
				(font
					(size 1.27 1.27)
				)
			)
		)
		(property "Value" ""
			(at 0 0 270)
			(layer "F.Fab")
			(effects
				(font
					(size 1.27 1.27)
				)
			)
		)
		(duplicate_pad_numbers_are_jumpers no)
		(fp_line
			(start -0.299974 0.150114)
			(end -0.299974 -0.150114)
			(stroke
				(width 0.1)
				(type default)
			)
			(layer "F.Fab")
		)
		(fp_line
			(start 0.299974 0.150114)
			(end -0.299974 0.150114)
			(stroke
				(width 0.1)
				(type default)
			)
			(layer "F.Fab")
		)
		(fp_line
			(start -0.299974 -0.150114)
			(end 0.299974 -0.150114)
			(stroke
				(width 0.1)
				(type default)
			)
			(layer "F.Fab")
		)
		(fp_line
			(start 0.299974 -0.150114)
			(end 0.299974 0.150114)
			(stroke
				(width 0.1)
				(type default)
			)
			(layer "F.Fab")
		)
		(pad "1" smd rect
			(at -0.2667 0 270)
			(size 0.3048 0.381)
			(layers "F.Cu" "F.Mask" "F.Paste")
			(net "P5E_CPU0_P0_TX_C_DP<3>")
		)
		(pad "2" smd rect
			(at 0.2667 0 270)
			(size 0.3048 0.381)
			(layers "F.Cu" "F.Mask" "F.Paste")
			(net "P5E_CPU0_P0_TX_DP<3>")
		)
	)
	(footprint ""
		(layer "F.Cu")
		(at 418.253164 -16.100298 90)
		(property "Reference" "C1568"
			(at 0 0 90)
			(layer "F.SilkS")
			(hide yes)
			(effects
				(font
					(size 1.27 1.27)
				)
			)
		)
		(property "Value" ""
			(at 0 0 90)
			(layer "F.Fab")
			(effects
				(font
					(size 1.27 1.27)
				)
			)
		)
		(duplicate_pad_numbers_are_jumpers no)
		(fp_line
			(start 0.299974 -0.150114)
			(end 0.299974 0.150114)
			(stroke
				(width 0.1)
				(type default)
			)
			(layer "F.Fab")
		)
		(fp_line
			(start -0.299974 -0.150114)
			(end 0.299974 -0.150114)
			(stroke
				(width 0.1)
				(type default)
			)
			(layer "F.Fab")
		)
		(fp_line
			(start 0.299974 0.150114)
			(end -0.299974 0.150114)
			(stroke
				(width 0.1)
				(type default)
			)
			(layer "F.Fab")
		)
		(fp_line
			(start -0.299974 0.150114)
			(end -0.299974 -0.150114)
			(stroke
				(width 0.1)
				(type default)
			)
			(layer "F.Fab")
		)
		(pad "1" smd rect
			(at -0.2667 0 90)
			(size 0.3048 0.381)
			(layers "F.Cu" "F.Mask" "F.Paste")
			(net "P5E_CPU0_G3_TX_C_DN<5>")
		)
		(pad "2" smd rect
			(at 0.2667 0 90)
			(size 0.3048 0.381)
			(layers "F.Cu" "F.Mask" "F.Paste")
			(net "P5E_CPU0_G3_TX_DN<5>")
		)
	)
	(footprint ""
		(layer "F.Cu")
		(at 325.314056 -23.826216 -90)
		(property "Reference" "R5054"
			(at 0 0 270)
			(layer "F.SilkS")
			(hide yes)
			(effects
				(font
					(size 1.27 1.27)
				)
			)
		)
		(property "Value" ""
			(at 0 0 270)
			(layer "F.Fab")
			(effects
				(font
					(size 1.27 1.27)
				)
			)
		)
		(duplicate_pad_numbers_are_jumpers no)
		(fp_line
			(start -0.7874 0.4064)
			(end -0.7874 -0.4064)
			(stroke
				(width 0.1524)
				(type default)
			)
			(layer "F.SilkS")
		)
		(fp_line
			(start 0.7874 0.4064)
			(end -0.7874 0.4064)
			(stroke
				(width 0.1524)
				(type default)
			)
			(layer "F.SilkS")
		)
		(fp_line
			(start -0.7874 -0.4064)
			(end 0.7874 -0.4064)
			(stroke
				(width 0.1524)
				(type default)
			)
			(layer "F.SilkS")
		)
		(fp_line
			(start 0.7874 -0.4064)
			(end 0.7874 0.4064)
			(stroke
				(width 0.1524)
				(type default)
			)
			(layer "F.SilkS")
		)
		(fp_line
			(start -0.67945 0.3048)
			(end -0.67945 -0.305054)
			(stroke
				(width 0.1)
				(type default)
			)
			(layer "F.Fab")
		)
		(fp_line
			(start -0.12065 0.3048)
			(end -0.67945 0.3048)
			(stroke
				(width 0.1)
				(type default)
			)
			(layer "F.Fab")
		)
		(fp_line
			(start 0.120396 0.3048)
			(end 0.120396 0.2794)
			(stroke
				(width 0.1)
				(type default)
			)
			(layer "F.Fab")
		)
		(fp_line
			(start 0.67945 0.3048)
			(end 0.120396 0.3048)
			(stroke
				(width 0.1)
				(type default)
			)
			(layer "F.Fab")
		)
		(fp_line
			(start -0.12065 0.2794)
			(end -0.12065 0.3048)
			(stroke
				(width 0.1)
				(type default)
			)
			(layer "F.Fab")
		)
		(fp_line
			(start 0.120396 0.2794)
			(end -0.12065 0.2794)
			(stroke
				(width 0.1)
				(type default)
			)
			(layer "F.Fab")
		)
		(fp_line
			(start -0.12065 -0.2794)
			(end 0.12065 -0.2794)
			(stroke
				(width 0.1)
				(type default)
			)
			(layer "F.Fab")
		)
		(fp_line
			(start 0.12065 -0.2794)
			(end 0.12065 -0.3048)
			(stroke
				(width 0.1)
				(type default)
			)
			(layer "F.Fab")
		)
		(fp_line
			(start 0.12065 -0.3048)
			(end 0.67945 -0.3048)
			(stroke
				(width 0.1)
				(type default)
			)
			(layer "F.Fab")
		)
		(fp_line
			(start 0.67945 -0.3048)
			(end 0.67945 0.3048)
			(stroke
				(width 0.1)
				(type default)
			)
			(layer "F.Fab")
		)
		(fp_line
			(start -0.67945 -0.305054)
			(end -0.12065 -0.305054)
			(stroke
				(width 0.1)
				(type default)
			)
			(layer "F.Fab")
		)
		(fp_line
			(start -0.12065 -0.305054)
			(end -0.12065 -0.2794)
			(stroke
				(width 0.1)
				(type default)
			)
			(layer "F.Fab")
		)
		(pad "1" smd circle
			(at -0.40005 0 270)
			(size 0 0)
			(layers "F.Cu" "F.Mask" "F.Paste")
			(net "P3V3_RTC_AUX_R")
		)
		(pad "2" smd circle
			(at 0.40005 0 270)
			(size 0 0)
			(layers "F.Cu" "F.Mask" "F.Paste")
			(net "P1V5_BAT_OUT_R")
		)
	)
	(footprint ""
		(layer "F.Cu")
		(at 172.540422 -417.551616)
		(property "Reference" "R9006"
			(at 0 0 0)
			(layer "F.SilkS")
			(hide yes)
			(effects
				(font
					(size 1.27 1.27)
				)
			)
		)
		(property "Value" ""
			(at 0 0 0)
			(layer "F.Fab")
			(effects
				(font
					(size 1.27 1.27)
				)
			)
		)
		(duplicate_pad_numbers_are_jumpers no)
		(fp_line
			(start -0.7874 -0.4064)
			(end 0.7874 -0.4064)
			(stroke
				(width 0.1524)
				(type default)
			)
			(layer "F.SilkS")
		)
		(fp_line
			(start -0.7874 0.4064)
			(end -0.7874 -0.4064)
			(stroke
				(width 0.1524)
				(type default)
			)
			(layer "F.SilkS")
		)
		(fp_line
			(start 0.7874 -0.4064)
			(end 0.7874 0.4064)
			(stroke
				(width 0.1524)
				(type default)
			)
			(layer "F.SilkS")
		)
		(fp_line
			(start 0.7874 0.4064)
			(end -0.7874 0.4064)
			(stroke
				(width 0.1524)
				(type default)
			)
			(layer "F.SilkS")
		)
		(fp_line
			(start -0.67945 -0.305054)
			(end -0.12065 -0.305054)
			(stroke
				(width 0.1)
				(type default)
			)
			(layer "F.Fab")
		)
		(fp_line
			(start -0.67945 0.3048)
			(end -0.67945 -0.305054)
			(stroke
				(width 0.1)
				(type default)
			)
			(layer "F.Fab")
		)
		(fp_line
			(start -0.12065 -0.305054)
			(end -0.12065 -0.2794)
			(stroke
				(width 0.1)
				(type default)
			)
			(layer "F.Fab")
		)
		(fp_line
			(start -0.12065 -0.2794)
			(end 0.12065 -0.2794)
			(stroke
				(width 0.1)
				(type default)
			)
			(layer "F.Fab")
		)
		(fp_line
			(start -0.12065 0.2794)
			(end -0.12065 0.3048)
			(stroke
				(width 0.1)
				(type default)
			)
			(layer "F.Fab")
		)
		(fp_line
			(start -0.12065 0.3048)
			(end -0.67945 0.3048)
			(stroke
				(width 0.1)
				(type default)
			)
			(layer "F.Fab")
		)
		(fp_line
			(start 0.120396 0.2794)
			(end -0.12065 0.2794)
			(stroke
				(width 0.1)
				(type default)
			)
			(layer "F.Fab")
		)
		(fp_line
			(start 0.120396 0.3048)
			(end 0.120396 0.2794)
			(stroke
				(width 0.1)
				(type default)
			)
			(layer "F.Fab")
		)
		(fp_line
			(start 0.12065 -0.3048)
			(end 0.67945 -0.3048)
			(stroke
				(width 0.1)
				(type default)
			)
			(layer "F.Fab")
		)
		(fp_line
			(start 0.12065 -0.2794)
			(end 0.12065 -0.3048)
			(stroke
				(width 0.1)
				(type default)
			)
			(layer "F.Fab")
		)
		(fp_line
			(start 0.67945 -0.3048)
			(end 0.67945 0.3048)
			(stroke
				(width 0.1)
				(type default)
			)
			(layer "F.Fab")
		)
		(fp_line
			(start 0.67945 0.3048)
			(end 0.120396 0.3048)
			(stroke
				(width 0.1)
				(type default)
			)
			(layer "F.Fab")
		)
		(pad "1" smd circle
			(at -0.40005 0)
			(size 0 0)
			(layers "F.Cu" "F.Mask" "F.Paste")
			(net "P3V3_AUX")
		)
		(pad "2" smd circle
			(at 0.40005 0)
			(size 0 0)
			(layers "F.Cu" "F.Mask" "F.Paste")
			(net "PRSNT_CABLE_SWB_B2_N")
		)
	)
	(footprint ""
		(layer "F.Cu")
		(at 149.990048 -26.68778 -90)
		(property "Reference" "R6024"
			(at 0 0 270)
			(layer "F.SilkS")
			(hide yes)
			(effects
				(font
					(size 1.27 1.27)
				)
			)
		)
		(property "Value" ""
			(at 0 0 270)
			(layer "F.Fab")
			(effects
				(font
					(size 1.27 1.27)
				)
			)
		)
		(duplicate_pad_numbers_are_jumpers no)
		(fp_line
			(start -0.7874 0.4064)
			(end -0.7874 -0.4064)
			(stroke
				(width 0.1524)
				(type default)
			)
			(layer "F.SilkS")
		)
		(fp_line
			(start 0.7874 0.4064)
			(end -0.7874 0.4064)
			(stroke
				(width 0.1524)
				(type default)
			)
			(layer "F.SilkS")
		)
		(fp_line
			(start -0.7874 -0.4064)
			(end 0.7874 -0.4064)
			(stroke
				(width 0.1524)
				(type default)
			)
			(layer "F.SilkS")
		)
		(fp_line
			(start 0.7874 -0.4064)
			(end 0.7874 0.4064)
			(stroke
				(width 0.1524)
				(type default)
			)
			(layer "F.SilkS")
		)
		(fp_line
			(start -0.67945 0.3048)
			(end -0.67945 -0.305054)
			(stroke
				(width 0.1)
				(type default)
			)
			(layer "F.Fab")
		)
		(fp_line
			(start -0.12065 0.3048)
			(end -0.67945 0.3048)
			(stroke
				(width 0.1)
				(type default)
			)
			(layer "F.Fab")
		)
		(fp_line
			(start 0.120396 0.3048)
			(end 0.120396 0.2794)
			(stroke
				(width 0.1)
				(type default)
			)
			(layer "F.Fab")
		)
		(fp_line
			(start 0.67945 0.3048)
			(end 0.120396 0.3048)
			(stroke
				(width 0.1)
				(type default)
			)
			(layer "F.Fab")
		)
		(fp_line
			(start -0.12065 0.2794)
			(end -0.12065 0.3048)
			(stroke
				(width 0.1)
				(type default)
			)
			(layer "F.Fab")
		)
		(fp_line
			(start 0.120396 0.2794)
			(end -0.12065 0.2794)
			(stroke
				(width 0.1)
				(type default)
			)
			(layer "F.Fab")
		)
		(fp_line
			(start -0.12065 -0.2794)
			(end 0.12065 -0.2794)
			(stroke
				(width 0.1)
				(type default)
			)
			(layer "F.Fab")
		)
		(fp_line
			(start 0.12065 -0.2794)
			(end 0.12065 -0.3048)
			(stroke
				(width 0.1)
				(type default)
			)
			(layer "F.Fab")
		)
		(fp_line
			(start 0.12065 -0.3048)
			(end 0.67945 -0.3048)
			(stroke
				(width 0.1)
				(type default)
			)
			(layer "F.Fab")
		)
		(fp_line
			(start 0.67945 -0.3048)
			(end 0.67945 0.3048)
			(stroke
				(width 0.1)
				(type default)
			)
			(layer "F.Fab")
		)
		(fp_line
			(start -0.67945 -0.305054)
			(end -0.12065 -0.305054)
			(stroke
				(width 0.1)
				(type default)
			)
			(layer "F.Fab")
		)
		(fp_line
			(start -0.12065 -0.305054)
			(end -0.12065 -0.2794)
			(stroke
				(width 0.1)
				(type default)
			)
			(layer "F.Fab")
		)
		(pad "1" smd circle
			(at -0.40005 0 270)
			(size 0 0)
			(layers "F.Cu" "F.Mask" "F.Paste")
			(net "P3V3_AUX")
		)
		(pad "2" smd circle
			(at 0.40005 0 270)
			(size 0 0)
			(layers "F.Cu" "F.Mask" "F.Paste")
			(net "SGPIO_SCM_INTR_N")
		)
	)
	(footprint ""
		(layer "F.Cu")
		(at 330.96962 -397.726154 180)
		(property "Reference" "R1369"
			(at 0 0 180)
			(layer "F.SilkS")
			(hide yes)
			(effects
				(font
					(size 1.27 1.27)
				)
			)
		)
		(property "Value" ""
			(at 0 0 180)
			(layer "F.Fab")
			(effects
				(font
					(size 1.27 1.27)
				)
			)
		)
		(duplicate_pad_numbers_are_jumpers no)
		(fp_line
			(start 0.32512 0.175006)
			(end -0.32512 0.175006)
			(stroke
				(width 0.1)
				(type default)
			)
			(layer "F.Fab")
		)
		(fp_line
			(start 0.32512 -0.175006)
			(end 0.32512 0.175006)
			(stroke
				(width 0.1)
				(type default)
			)
			(layer "F.Fab")
		)
		(fp_line
			(start -0.32512 0.175006)
			(end -0.32512 -0.175006)
			(stroke
				(width 0.1)
				(type default)
			)
			(layer "F.Fab")
		)
		(fp_line
			(start -0.32512 -0.175006)
			(end 0.32512 -0.175006)
			(stroke
				(width 0.1)
				(type default)
			)
			(layer "F.Fab")
		)
		(pad "1" smd rect
			(at -0.2667 0 180)
			(size 0.3048 0.381)
			(layers "F.Cu" "F.Mask" "F.Paste")
			(net "P1V8_CPU0_RT_1D")
		)
		(pad "2" smd rect
			(at 0.2667 0)
			(size 0.3048 0.381)
			(layers "F.Cu" "F.Mask" "F.Paste")
			(net "RXDET_BYP_RT_CPU0_P0")
		)
	)
	(footprint ""
		(layer "F.Cu")
		(at 302.133 -354.711 180)
		(property "Reference" "PR40"
			(at 0 0 180)
			(layer "F.SilkS")
			(hide yes)
			(effects
				(font
					(size 1.27 1.27)
				)
			)
		)
		(property "Value" ""
			(at 0 0 180)
			(layer "F.Fab")
			(effects
				(font
					(size 1.27 1.27)
				)
			)
		)
		(duplicate_pad_numbers_are_jumpers no)
		(fp_line
			(start 0.7874 0.4064)
			(end -0.7874 0.4064)
			(stroke
				(width 0.1524)
				(type default)
			)
			(layer "F.SilkS")
		)
		(fp_line
			(start 0.7874 -0.4064)
			(end 0.7874 0.4064)
			(stroke
				(width 0.1524)
				(type default)
			)
			(layer "F.SilkS")
		)
		(fp_line
			(start -0.7874 0.4064)
			(end -0.7874 -0.4064)
			(stroke
				(width 0.1524)
				(type default)
			)
			(layer "F.SilkS")
		)
		(fp_line
			(start -0.7874 -0.4064)
			(end 0.7874 -0.4064)
			(stroke
				(width 0.1524)
				(type default)
			)
			(layer "F.SilkS")
		)
		(fp_line
			(start 0.67945 0.3048)
			(end 0.120396 0.3048)
			(stroke
				(width 0.1)
				(type default)
			)
			(layer "F.Fab")
		)
		(fp_line
			(start 0.67945 -0.3048)
			(end 0.67945 0.3048)
			(stroke
				(width 0.1)
				(type default)
			)
			(layer "F.Fab")
		)
		(fp_line
			(start 0.12065 -0.2794)
			(end 0.12065 -0.3048)
			(stroke
				(width 0.1)
				(type default)
			)
			(layer "F.Fab")
		)
		(fp_line
			(start 0.12065 -0.3048)
			(end 0.67945 -0.3048)
			(stroke
				(width 0.1)
				(type default)
			)
			(layer "F.Fab")
		)
		(fp_line
			(start 0.120396 0.3048)
			(end 0.120396 0.2794)
			(stroke
				(width 0.1)
				(type default)
			)
			(layer "F.Fab")
		)
		(fp_line
			(start 0.120396 0.2794)
			(end -0.12065 0.2794)
			(stroke
				(width 0.1)
				(type default)
			)
			(layer "F.Fab")
		)
		(fp_line
			(start -0.12065 0.3048)
			(end -0.67945 0.3048)
			(stroke
				(width 0.1)
				(type default)
			)
			(layer "F.Fab")
		)
		(fp_line
			(start -0.12065 0.2794)
			(end -0.12065 0.3048)
			(stroke
				(width 0.1)
				(type default)
			)
			(layer "F.Fab")
		)
		(fp_line
			(start -0.12065 -0.2794)
			(end 0.12065 -0.2794)
			(stroke
				(width 0.1)
				(type default)
			)
			(layer "F.Fab")
		)
		(fp_line
			(start -0.12065 -0.305054)
			(end -0.12065 -0.2794)
			(stroke
				(width 0.1)
				(type default)
			)
			(layer "F.Fab")
		)
		(fp_line
			(start -0.67945 0.3048)
			(end -0.67945 -0.305054)
			(stroke
				(width 0.1)
				(type default)
			)
			(layer "F.Fab")
		)
		(fp_line
			(start -0.67945 -0.305054)
			(end -0.12065 -0.305054)
			(stroke
				(width 0.1)
				(type default)
			)
			(layer "F.Fab")
		)
		(pad "1" smd circle
			(at -0.40005 0 180)
			(size 0 0)
			(layers "F.Cu" "F.Mask" "F.Paste")
			(net "SVID_PVDDCR_CPU1_P0_SVTI")
		)
		(pad "2" smd circle
			(at 0.40005 0 180)
			(size 0 0)
			(layers "F.Cu" "F.Mask" "F.Paste")
			(net "GND")
		)
	)
	(footprint ""
		(layer "F.Cu")
		(at 131.099306 -408.517344 -90)
		(property "Reference" "C6703"
			(at 0 0 270)
			(layer "F.SilkS")
			(hide yes)
			(effects
				(font
					(size 1.27 1.27)
				)
			)
		)
		(property "Value" ""
			(at 0 0 270)
			(layer "F.Fab")
			(effects
				(font
					(size 1.27 1.27)
				)
			)
		)
		(duplicate_pad_numbers_are_jumpers no)
		(fp_line
			(start -0.299974 0.150114)
			(end -0.299974 -0.150114)
			(stroke
				(width 0.1)
				(type default)
			)
			(layer "F.Fab")
		)
		(fp_line
			(start 0.299974 0.150114)
			(end -0.299974 0.150114)
			(stroke
				(width 0.1)
				(type default)
			)
			(layer "F.Fab")
		)
		(fp_line
			(start -0.299974 -0.150114)
			(end 0.299974 -0.150114)
			(stroke
				(width 0.1)
				(type default)
			)
			(layer "F.Fab")
		)
		(fp_line
			(start 0.299974 -0.150114)
			(end 0.299974 0.150114)
			(stroke
				(width 0.1)
				(type default)
			)
			(layer "F.Fab")
		)
		(pad "1" smd rect
			(at -0.2667 0 270)
			(size 0.3048 0.381)
			(layers "F.Cu" "F.Mask" "F.Paste")
			(net "P5E_CPU1_P2_TX_BUF_C_DP<5>")
		)
		(pad "2" smd rect
			(at 0.2667 0 270)
			(size 0.3048 0.381)
			(layers "F.Cu" "F.Mask" "F.Paste")
			(net "P5E_CPU1_P2_TX_BUF_DP<5>")
		)
	)
	(footprint ""
		(layer "F.Cu")
		(at 388.213092 -378.95403 -90)
		(property "Reference" "C877"
			(at 0 0 270)
			(layer "F.SilkS")
			(hide yes)
			(effects
				(font
					(size 1.27 1.27)
				)
			)
		)
		(property "Value" ""
			(at 0 0 270)
			(layer "F.Fab")
			(effects
				(font
					(size 1.27 1.27)
				)
			)
		)
		(duplicate_pad_numbers_are_jumpers no)
		(fp_line
			(start -0.299974 0.150114)
			(end -0.299974 -0.150114)
			(stroke
				(width 0.1)
				(type default)
			)
			(layer "F.Fab")
		)
		(fp_line
			(start 0.299974 0.150114)
			(end -0.299974 0.150114)
			(stroke
				(width 0.1)
				(type default)
			)
			(layer "F.Fab")
		)
		(fp_line
			(start -0.299974 -0.150114)
			(end 0.299974 -0.150114)
			(stroke
				(width 0.1)
				(type default)
			)
			(layer "F.Fab")
		)
		(fp_line
			(start 0.299974 -0.150114)
			(end 0.299974 0.150114)
			(stroke
				(width 0.1)
				(type default)
			)
			(layer "F.Fab")
		)
		(pad "1" smd rect
			(at -0.2667 0 270)
			(size 0.3048 0.381)
			(layers "F.Cu" "F.Mask" "F.Paste")
			(net "P5E_CPU0_P3_TX_C_DP<12>")
		)
		(pad "2" smd rect
			(at 0.2667 0 270)
			(size 0.3048 0.381)
			(layers "F.Cu" "F.Mask" "F.Paste")
			(net "P5E_CPU0_P3_TX_DP<12>")
		)
	)
	(footprint ""
		(layer "F.Cu")
		(at 66.369438 -31.887922 90)
		(property "Reference" "PC2166"
			(at 0 0 90)
			(layer "F.SilkS")
			(hide yes)
			(effects
				(font
					(size 1.27 1.27)
				)
			)
		)
		(property "Value" ""
			(at 0 0 90)
			(layer "F.Fab")
			(effects
				(font
					(size 1.27 1.27)
				)
			)
		)
		(duplicate_pad_numbers_are_jumpers no)
		(fp_line
			(start 0.7874 -0.4064)
			(end 0.7874 0.4064)
			(stroke
				(width 0.1524)
				(type default)
			)
			(layer "F.SilkS")
		)
		(fp_line
			(start -0.7874 -0.4064)
			(end 0.7874 -0.4064)
			(stroke
				(width 0.1524)
				(type default)
			)
			(layer "F.SilkS")
		)
		(fp_line
			(start 0.7874 0.4064)
			(end -0.7874 0.4064)
			(stroke
				(width 0.1524)
				(type default)
			)
			(layer "F.SilkS")
		)
		(fp_line
			(start -0.7874 0.4064)
			(end -0.7874 -0.4064)
			(stroke
				(width 0.1524)
				(type default)
			)
			(layer "F.SilkS")
		)
		(fp_line
			(start -0.12065 -0.305054)
			(end -0.12065 -0.2794)
			(stroke
				(width 0.1)
				(type default)
			)
			(layer "F.Fab")
		)
		(fp_line
			(start -0.67945 -0.305054)
			(end -0.12065 -0.305054)
			(stroke
				(width 0.1)
				(type default)
			)
			(layer "F.Fab")
		)
		(fp_line
			(start 0.67945 -0.3048)
			(end 0.67945 0.3048)
			(stroke
				(width 0.1)
				(type default)
			)
			(layer "F.Fab")
		)
		(fp_line
			(start 0.12065 -0.3048)
			(end 0.67945 -0.3048)
			(stroke
				(width 0.1)
				(type default)
			)
			(layer "F.Fab")
		)
		(fp_line
			(start 0.12065 -0.2794)
			(end 0.12065 -0.3048)
			(stroke
				(width 0.1)
				(type default)
			)
			(layer "F.Fab")
		)
		(fp_line
			(start -0.12065 -0.2794)
			(end 0.12065 -0.2794)
			(stroke
				(width 0.1)
				(type default)
			)
			(layer "F.Fab")
		)
		(fp_line
			(start 0.120396 0.2794)
			(end -0.12065 0.2794)
			(stroke
				(width 0.1)
				(type default)
			)
			(layer "F.Fab")
		)
		(fp_line
			(start -0.12065 0.2794)
			(end -0.12065 0.3048)
			(stroke
				(width 0.1)
				(type default)
			)
			(layer "F.Fab")
		)
		(fp_line
			(start 0.67945 0.3048)
			(end 0.120396 0.3048)
			(stroke
				(width 0.1)
				(type default)
			)
			(layer "F.Fab")
		)
		(fp_line
			(start 0.120396 0.3048)
			(end 0.120396 0.2794)
			(stroke
				(width 0.1)
				(type default)
			)
			(layer "F.Fab")
		)
		(fp_line
			(start -0.12065 0.3048)
			(end -0.67945 0.3048)
			(stroke
				(width 0.1)
				(type default)
			)
			(layer "F.Fab")
		)
		(fp_line
			(start -0.67945 0.3048)
			(end -0.67945 -0.305054)
			(stroke
				(width 0.1)
				(type default)
			)
			(layer "F.Fab")
		)
		(pad "1" smd circle
			(at -0.40005 0 90)
			(size 0 0)
			(layers "F.Cu" "F.Mask" "F.Paste")
			(net "P12V_OCP_SS_2")
		)
		(pad "2" smd circle
			(at 0.40005 0 90)
			(size 0 0)
			(layers "F.Cu" "F.Mask" "F.Paste")
			(net "GND")
		)
	)
	(footprint ""
		(layer "F.Cu")
		(at 447.557652 -18.449798)
		(property "Reference" "PR3786"
			(at 0 0 0)
			(layer "F.SilkS")
			(hide yes)
			(effects
				(font
					(size 1.27 1.27)
				)
			)
		)
		(property "Value" ""
			(at 0 0 0)
			(layer "F.Fab")
			(effects
				(font
					(size 1.27 1.27)
				)
			)
		)
		(duplicate_pad_numbers_are_jumpers no)
		(fp_line
			(start -0.7874 -0.4064)
			(end 0.7874 -0.4064)
			(stroke
				(width 0.1524)
				(type default)
			)
			(layer "F.SilkS")
		)
		(fp_line
			(start -0.7874 0.4064)
			(end -0.7874 -0.4064)
			(stroke
				(width 0.1524)
				(type default)
			)
			(layer "F.SilkS")
		)
		(fp_line
			(start 0.7874 -0.4064)
			(end 0.7874 0.4064)
			(stroke
				(width 0.1524)
				(type default)
			)
			(layer "F.SilkS")
		)
		(fp_line
			(start 0.7874 0.4064)
			(end -0.7874 0.4064)
			(stroke
				(width 0.1524)
				(type default)
			)
			(layer "F.SilkS")
		)
		(fp_line
			(start -0.67945 -0.305054)
			(end -0.12065 -0.305054)
			(stroke
				(width 0.1)
				(type default)
			)
			(layer "F.Fab")
		)
		(fp_line
			(start -0.67945 0.3048)
			(end -0.67945 -0.305054)
			(stroke
				(width 0.1)
				(type default)
			)
			(layer "F.Fab")
		)
		(fp_line
			(start -0.12065 -0.305054)
			(end -0.12065 -0.2794)
			(stroke
				(width 0.1)
				(type default)
			)
			(layer "F.Fab")
		)
		(fp_line
			(start -0.12065 -0.2794)
			(end 0.12065 -0.2794)
			(stroke
				(width 0.1)
				(type default)
			)
			(layer "F.Fab")
		)
		(fp_line
			(start -0.12065 0.2794)
			(end -0.12065 0.3048)
			(stroke
				(width 0.1)
				(type default)
			)
			(layer "F.Fab")
		)
		(fp_line
			(start -0.12065 0.3048)
			(end -0.67945 0.3048)
			(stroke
				(width 0.1)
				(type default)
			)
			(layer "F.Fab")
		)
		(fp_line
			(start 0.120396 0.2794)
			(end -0.12065 0.2794)
			(stroke
				(width 0.1)
				(type default)
			)
			(layer "F.Fab")
		)
		(fp_line
			(start 0.120396 0.3048)
			(end 0.120396 0.2794)
			(stroke
				(width 0.1)
				(type default)
			)
			(layer "F.Fab")
		)
		(fp_line
			(start 0.12065 -0.3048)
			(end 0.67945 -0.3048)
			(stroke
				(width 0.1)
				(type default)
			)
			(layer "F.Fab")
		)
		(fp_line
			(start 0.12065 -0.2794)
			(end 0.12065 -0.3048)
			(stroke
				(width 0.1)
				(type default)
			)
			(layer "F.Fab")
		)
		(fp_line
			(start 0.67945 -0.3048)
			(end 0.67945 0.3048)
			(stroke
				(width 0.1)
				(type default)
			)
			(layer "F.Fab")
		)
		(fp_line
			(start 0.67945 0.3048)
			(end 0.120396 0.3048)
			(stroke
				(width 0.1)
				(type default)
			)
			(layer "F.Fab")
		)
		(pad "1" smd circle
			(at -0.40005 0)
			(size 0 0)
			(layers "F.Cu" "F.Mask" "F.Paste")
			(net "P12V_AUX")
		)
		(pad "2" smd circle
			(at 0.40005 0)
			(size 0 0)
			(layers "F.Cu" "F.Mask" "F.Paste")
			(net "P12V_OCP_UV_1")
		)
	)
	(footprint ""
		(layer "F.Cu")
		(at 239.152684 -54.736238)
		(property "Reference" "C1994"
			(at 0 0 0)
			(layer "F.SilkS")
			(hide yes)
			(effects
				(font
					(size 1.27 1.27)
				)
			)
		)
		(property "Value" ""
			(at 0 0 0)
			(layer "F.Fab")
			(effects
				(font
					(size 1.27 1.27)
				)
			)
		)
		(duplicate_pad_numbers_are_jumpers no)
		(fp_line
			(start -0.299974 -0.150114)
			(end 0.299974 -0.150114)
			(stroke
				(width 0.1)
				(type default)
			)
			(layer "F.Fab")
		)
		(fp_line
			(start -0.299974 0.150114)
			(end -0.299974 -0.150114)
			(stroke
				(width 0.1)
				(type default)
			)
			(layer "F.Fab")
		)
		(fp_line
			(start 0.299974 -0.150114)
			(end 0.299974 0.150114)
			(stroke
				(width 0.1)
				(type default)
			)
			(layer "F.Fab")
		)
		(fp_line
			(start 0.299974 0.150114)
			(end -0.299974 0.150114)
			(stroke
				(width 0.1)
				(type default)
			)
			(layer "F.Fab")
		)
		(pad "1" smd rect
			(at -0.2667 0)
			(size 0.3048 0.381)
			(layers "F.Cu" "F.Mask" "F.Paste")
			(net "P3E_CPU0_P4_TX_C_DN<1>")
		)
		(pad "2" smd rect
			(at 0.2667 0)
			(size 0.3048 0.381)
			(layers "F.Cu" "F.Mask" "F.Paste")
			(net "P3E_CPU0_P4_TX_DN<1>")
		)
	)
	(footprint ""
		(layer "F.Cu")
		(at 99.07397 -182.693056 180)
		(property "Reference" "PU27"
			(at 0.78994 -6.592062 0)
			(unlocked yes)
			(layer "F.SilkS")
			(effects
				(font
					(size 0.7874 0.5842)
					(thickness 0.1524)
				)
				(justify left)
			)
		)
		(property "Value" ""
			(at 0 0 180)
			(layer "F.Fab")
			(effects
				(font
					(size 1.27 1.27)
				)
			)
		)
		(duplicate_pad_numbers_are_jumpers no)
		(fp_line
			(start 2.500122 2.999994)
			(end 2.2987 2.999994)
			(stroke
				(width 0.1524)
				(type default)
			)
			(layer "F.SilkS")
		)
		(fp_line
			(start 2.500122 2.339594)
			(end 2.500122 2.999994)
			(stroke
				(width 0.1524)
				(type default)
			)
			(layer "F.SilkS")
		)
		(fp_line
			(start 2.500122 -2.999994)
			(end 2.500122 -2.44348)
			(stroke
				(width 0.1524)
				(type default)
			)
			(layer "F.SilkS")
		)
		(fp_line
			(start 2.31394 -2.999994)
			(end 2.500122 -2.999994)
			(stroke
				(width 0.1524)
				(type default)
			)
			(layer "F.SilkS")
		)
		(fp_line
			(start -2.2987 2.999994)
			(end -2.500122 2.999994)
			(stroke
				(width 0.1524)
				(type default)
			)
			(layer "F.SilkS")
		)
		(fp_line
			(start -2.500122 2.999994)
			(end -2.500122 2.339594)
			(stroke
				(width 0.1524)
				(type default)
			)
			(layer "F.SilkS")
		)
		(fp_line
			(start -2.500122 0.6604)
			(end -2.500122 0.229108)
			(stroke
				(width 0.1524)
				(type default)
			)
			(layer "F.SilkS")
		)
		(fp_line
			(start -2.500122 -2.529078)
			(end -2.500122 -2.999994)
			(stroke
				(width 0.1524)
				(type default)
			)
			(layer "F.SilkS")
		)
		(fp_line
			(start -2.500122 -2.999994)
			(end -2.24409 -2.999994)
			(stroke
				(width 0.1524)
				(type default)
			)
			(layer "F.SilkS")
		)
		(fp_poly
			(pts
				(xy -2.770632 -2.436368) (xy -3.443986 -2.660904) (xy -2.995168 -3.109722)
			)
			(stroke
				(width 0)
				(type default)
			)
			(fill yes)
			(layer "F.SilkS")
		)
		(fp_line
			(start 2.500122 2.999994)
			(end -2.500122 2.999994)
			(stroke
				(width 0.1)
				(type default)
			)
			(layer "F.Fab")
		)
		(fp_line
			(start 2.500122 -2.999994)
			(end 2.500122 2.999994)
			(stroke
				(width 0.1)
				(type default)
			)
			(layer "F.Fab")
		)
		(fp_line
			(start -2.500122 2.999994)
			(end -2.500122 -2.999994)
			(stroke
				(width 0.1)
				(type default)
			)
			(layer "F.Fab")
		)
		(fp_line
			(start -2.500122 -2.999994)
			(end 2.500122 -2.999994)
			(stroke
				(width 0.1)
				(type default)
			)
			(layer "F.Fab")
		)
		(fp_poly
			(pts
				(xy -4.218432 -2.783078) (xy -4.218432 -1.767078) (xy -3.202432 -2.275078)
			)
			(stroke
				(width 0)
				(type default)
			)
			(fill yes)
			(layer "F.Fab")
		)
		(pad "1" smd rect
			(at -2.400046 -2.275078 270)
			(size 0.2286 0.6096)
			(layers "F.Cu" "F.Mask" "F.Paste")
			(net "PVDDCR_CPU0_P1_VOS3")
		)
		(pad "2" smd rect
			(at -2.400046 -1.82499 270)
			(size 0.2286 0.6096)
			(layers "F.Cu" "F.Mask" "F.Paste")
			(net "GND")
		)
		(pad "3" smd rect
			(at -2.400046 -1.374902 270)
			(size 0.2286 0.6096)
			(layers "F.Cu" "F.Mask" "F.Paste")
			(net "PVDDCR_CPU0_P1_VCC3")
		)
		(pad "4" smd rect
			(at -2.400046 -0.925068 270)
			(size 0.2286 0.6096)
			(layers "F.Cu" "F.Mask" "F.Paste")
			(net "PVDDCR_CPU0_P1_PVCC")
		)
		(pad "5" smd rect
			(at -2.400046 -0.47498 270)
			(size 0.2286 0.6096)
			(layers "F.Cu" "F.Mask" "F.Paste")
			(net "GND")
		)
		(pad "6" smd rect
			(at -2.400046 -0.024892 270)
			(size 0.2286 0.6096)
			(layers "F.Cu" "F.Mask" "F.Paste")
			(net "NC_PVDDCR_CPU0_P1_GL1_3")
		)
		(pad "7_9-20_24" smd circle
			(at 0 1.150112 270)
			(size 0 0)
			(layers "F.Cu" "F.Mask" "F.Paste")
			(net "GND")
		)
		(pad "10_19" smd rect
			(at 0 2.899918 270)
			(size 0.6096 4.318)
			(layers "F.Cu" "F.Mask" "F.Paste")
			(net "SW_PVDDCR_CPU0_P1_SW3")
		)
		(pad "25_29" smd rect
			(at 1.549908 -1.279906 90)
			(size 2.0574 2.3114)
			(layers "F.Cu" "F.Mask" "F.Paste")
			(net "SW_P12V_AUX_PVDDCR_CPU0_P1_FLT")
		)
		(pad "30" smd rect
			(at 2.05994 -2.899918 180)
			(size 0.2286 0.6096)
			(layers "F.Cu" "F.Mask" "F.Paste")
			(net "SW_P12V_AUX_PVDDCR_CPU0_P1_FLT")
		)
		(pad "31" smd rect
			(at 1.610106 -2.899918 180)
			(size 0.2286 0.6096)
			(layers "F.Cu" "F.Mask" "F.Paste")
			(net "NC_PVDDCR_CPU0_P1_DNC3")
		)
		(pad "32" smd rect
			(at 1.160018 -2.899918 180)
			(size 0.2286 0.6096)
			(layers "F.Cu" "F.Mask" "F.Paste")
			(net "SW_PVDDCR_CPU0_P1_PH3")
		)
		(pad "33" smd rect
			(at 0.70993 -2.899918 180)
			(size 0.2286 0.6096)
			(layers "F.Cu" "F.Mask" "F.Paste")
			(net "SW_PVDDCR_CPU0_P1_BOOT3")
		)
		(pad "34" smd rect
			(at 0.260096 -2.899918 180)
			(size 0.2286 0.6096)
			(layers "F.Cu" "F.Mask" "F.Paste")
			(net "PVDDCR_CPU0_P1_PWM3")
		)
		(pad "35" smd rect
			(at -0.189992 -2.899918 180)
			(size 0.2286 0.6096)
			(layers "F.Cu" "F.Mask" "F.Paste")
			(net "PVDDCR_CPU0_P1_VCC3")
		)
		(pad "36" smd rect
			(at -0.64008 -2.899918 180)
			(size 0.2286 0.6096)
			(layers "F.Cu" "F.Mask" "F.Paste")
			(net "PVDDCR_CPU0_P1_TEMP0")
		)
		(pad "37" smd rect
			(at -1.089914 -2.899918 180)
			(size 0.2286 0.6096)
			(layers "F.Cu" "F.Mask" "F.Paste")
			(net "PVDDCR_CPU0_P1_LSET3")
		)
		(pad "38" smd rect
			(at -1.540002 -2.899918 180)
			(size 0.2286 0.6096)
			(layers "F.Cu" "F.Mask" "F.Paste")
			(net "PVDDCR_CPU0_P1_IMON3")
		)
		(pad "39" smd rect
			(at -1.99009 -2.899918 180)
			(size 0.2286 0.6096)
			(layers "F.Cu" "F.Mask" "F.Paste")
			(net "PVDDCR_CPU0_P1_VCCS")
		)
		(pad "40" smd rect
			(at -0.87503 -1.27508 180)
			(size 1.7526 1.9558)
			(layers "F.Cu" "F.Mask" "F.Paste")
			(net "GND")
		)
		(pad "41" smd rect
			(at -1.525016 0.249936 90)
			(size 0.3048 0.4572)
			(layers "F.Cu" "F.Mask" "F.Paste")
			(net "NC_PVDDCR_CPU0_P1_GL2_3")
		)
		(zone
			(layer "F.Cu")
			(hatch none 0.5)
			(connect_pads
				(clearance 0)
			)
			(min_thickness 0.25)
			(keepout
				(tracks not_allowed)
				(vias allowed)
				(pads allowed)
				(copperpour not_allowed)
				(footprints allowed)
			)
			(placement
				(enabled no)
				(sheetname "")
			)
			(fill
				(thermal_gap 0.5)
				(thermal_bridge_width 0.5)
				(island_removal_mode 0)
			)
			(polygon
				(pts
					(xy 101.574092 -185.237374) (xy 101.574092 -184.94375) (xy 96.573848 -184.94375) (xy 96.573848 -185.237374)
					(xy 96.86417 -185.237374) (xy 101.28377 -185.237374)
				)
			)
		)
		(zone
			(layer "F.Cu")
			(hatch none 0.5)
			(connect_pads
				(clearance 0)
			)
			(min_thickness 0.25)
			(keepout
				(tracks not_allowed)
				(vias allowed)
				(pads allowed)
				(copperpour not_allowed)
				(footprints allowed)
			)
			(placement
				(enabled no)
				(sheetname "")
			)
			(fill
				(thermal_gap 0.5)
				(thermal_bridge_width 0.5)
				(island_removal_mode 0)
			)
			(polygon
				(pts
					(xy 99.0219 -182.446676) (xy 99.0219 -180.389276) (xy 100.8761 -180.389276) (xy 100.8761 -180.630322)
					(xy 101.118416 -180.630322) (xy 101.118416 -180.148738) (xy 97.178368 -180.148738) (xy 97.178368 -180.33365)
					(xy 98.730562 -180.33365) (xy 98.730562 -182.49265) (xy 96.573848 -182.49265) (xy 96.573848 -182.742332)
					(xy 98.726244 -182.742332)
				)
			)
		)
	)
	(footprint ""
		(layer "F.Cu")
		(at 127.381 -106.934 90)
		(property "Reference" "R8113"
			(at 0 0 90)
			(layer "F.SilkS")
			(hide yes)
			(effects
				(font
					(size 1.27 1.27)
				)
			)
		)
		(property "Value" ""
			(at 0 0 90)
			(layer "F.Fab")
			(effects
				(font
					(size 1.27 1.27)
				)
			)
		)
		(duplicate_pad_numbers_are_jumpers no)
		(fp_line
			(start 0.7874 -0.4064)
			(end 0.7874 0.4064)
			(stroke
				(width 0.1524)
				(type default)
			)
			(layer "F.SilkS")
		)
		(fp_line
			(start -0.7874 -0.4064)
			(end 0.7874 -0.4064)
			(stroke
				(width 0.1524)
				(type default)
			)
			(layer "F.SilkS")
		)
		(fp_line
			(start 0.7874 0.4064)
			(end -0.7874 0.4064)
			(stroke
				(width 0.1524)
				(type default)
			)
			(layer "F.SilkS")
		)
		(fp_line
			(start -0.7874 0.4064)
			(end -0.7874 -0.4064)
			(stroke
				(width 0.1524)
				(type default)
			)
			(layer "F.SilkS")
		)
		(fp_line
			(start -0.12065 -0.305054)
			(end -0.12065 -0.2794)
			(stroke
				(width 0.1)
				(type default)
			)
			(layer "F.Fab")
		)
		(fp_line
			(start -0.67945 -0.305054)
			(end -0.12065 -0.305054)
			(stroke
				(width 0.1)
				(type default)
			)
			(layer "F.Fab")
		)
		(fp_line
			(start 0.67945 -0.3048)
			(end 0.67945 0.3048)
			(stroke
				(width 0.1)
				(type default)
			)
			(layer "F.Fab")
		)
		(fp_line
			(start 0.12065 -0.3048)
			(end 0.67945 -0.3048)
			(stroke
				(width 0.1)
				(type default)
			)
			(layer "F.Fab")
		)
		(fp_line
			(start 0.12065 -0.2794)
			(end 0.12065 -0.3048)
			(stroke
				(width 0.1)
				(type default)
			)
			(layer "F.Fab")
		)
		(fp_line
			(start -0.12065 -0.2794)
			(end 0.12065 -0.2794)
			(stroke
				(width 0.1)
				(type default)
			)
			(layer "F.Fab")
		)
		(fp_line
			(start 0.120396 0.2794)
			(end -0.12065 0.2794)
			(stroke
				(width 0.1)
				(type default)
			)
			(layer "F.Fab")
		)
		(fp_line
			(start -0.12065 0.2794)
			(end -0.12065 0.3048)
			(stroke
				(width 0.1)
				(type default)
			)
			(layer "F.Fab")
		)
		(fp_line
			(start 0.67945 0.3048)
			(end 0.120396 0.3048)
			(stroke
				(width 0.1)
				(type default)
			)
			(layer "F.Fab")
		)
		(fp_line
			(start 0.120396 0.3048)
			(end 0.120396 0.2794)
			(stroke
				(width 0.1)
				(type default)
			)
			(layer "F.Fab")
		)
		(fp_line
			(start -0.12065 0.3048)
			(end -0.67945 0.3048)
			(stroke
				(width 0.1)
				(type default)
			)
			(layer "F.Fab")
		)
		(fp_line
			(start -0.67945 0.3048)
			(end -0.67945 -0.305054)
			(stroke
				(width 0.1)
				(type default)
			)
			(layer "F.Fab")
		)
		(pad "1" smd circle
			(at -0.40005 0 90)
			(size 0 0)
			(layers "F.Cu" "F.Mask" "F.Paste")
			(net "P3V3_AUX")
		)
		(pad "2" smd circle
			(at 0.40005 0 90)
			(size 0 0)
			(layers "F.Cu" "F.Mask" "F.Paste")
			(net "UV_ADR_P2V5_COMP")
		)
	)
	(footprint ""
		(layer "F.Cu")
		(at 110.152942 -19.9898 90)
		(property "Reference" "R6273"
			(at 0 0 90)
			(layer "F.SilkS")
			(hide yes)
			(effects
				(font
					(size 1.27 1.27)
				)
			)
		)
		(property "Value" ""
			(at 0 0 90)
			(layer "F.Fab")
			(effects
				(font
					(size 1.27 1.27)
				)
			)
		)
		(duplicate_pad_numbers_are_jumpers no)
		(fp_line
			(start 0.7874 -0.4064)
			(end 0.7874 0.4064)
			(stroke
				(width 0.1524)
				(type default)
			)
			(layer "F.SilkS")
		)
		(fp_line
			(start -0.7874 -0.4064)
			(end 0.7874 -0.4064)
			(stroke
				(width 0.1524)
				(type default)
			)
			(layer "F.SilkS")
		)
		(fp_line
			(start 0.7874 0.4064)
			(end -0.7874 0.4064)
			(stroke
				(width 0.1524)
				(type default)
			)
			(layer "F.SilkS")
		)
		(fp_line
			(start -0.7874 0.4064)
			(end -0.7874 -0.4064)
			(stroke
				(width 0.1524)
				(type default)
			)
			(layer "F.SilkS")
		)
		(fp_line
			(start -0.12065 -0.305054)
			(end -0.12065 -0.2794)
			(stroke
				(width 0.1)
				(type default)
			)
			(layer "F.Fab")
		)
		(fp_line
			(start -0.67945 -0.305054)
			(end -0.12065 -0.305054)
			(stroke
				(width 0.1)
				(type default)
			)
			(layer "F.Fab")
		)
		(fp_line
			(start 0.67945 -0.3048)
			(end 0.67945 0.3048)
			(stroke
				(width 0.1)
				(type default)
			)
			(layer "F.Fab")
		)
		(fp_line
			(start 0.12065 -0.3048)
			(end 0.67945 -0.3048)
			(stroke
				(width 0.1)
				(type default)
			)
			(layer "F.Fab")
		)
		(fp_line
			(start 0.12065 -0.2794)
			(end 0.12065 -0.3048)
			(stroke
				(width 0.1)
				(type default)
			)
			(layer "F.Fab")
		)
		(fp_line
			(start -0.12065 -0.2794)
			(end 0.12065 -0.2794)
			(stroke
				(width 0.1)
				(type default)
			)
			(layer "F.Fab")
		)
		(fp_line
			(start 0.120396 0.2794)
			(end -0.12065 0.2794)
			(stroke
				(width 0.1)
				(type default)
			)
			(layer "F.Fab")
		)
		(fp_line
			(start -0.12065 0.2794)
			(end -0.12065 0.3048)
			(stroke
				(width 0.1)
				(type default)
			)
			(layer "F.Fab")
		)
		(fp_line
			(start 0.67945 0.3048)
			(end 0.120396 0.3048)
			(stroke
				(width 0.1)
				(type default)
			)
			(layer "F.Fab")
		)
		(fp_line
			(start 0.120396 0.3048)
			(end 0.120396 0.2794)
			(stroke
				(width 0.1)
				(type default)
			)
			(layer "F.Fab")
		)
		(fp_line
			(start -0.12065 0.3048)
			(end -0.67945 0.3048)
			(stroke
				(width 0.1)
				(type default)
			)
			(layer "F.Fab")
		)
		(fp_line
			(start -0.67945 0.3048)
			(end -0.67945 -0.305054)
			(stroke
				(width 0.1)
				(type default)
			)
			(layer "F.Fab")
		)
		(pad "1" smd circle
			(at -0.40005 0 90)
			(size 0 0)
			(layers "F.Cu" "F.Mask" "F.Paste")
			(net "P3V3_AUX")
		)
		(pad "2" smd circle
			(at 0.40005 0 90)
			(size 0 0)
			(layers "F.Cu" "F.Mask" "F.Paste")
			(net "USB_HUB2_MRP_CFG_STRAP")
		)
	)
	(footprint ""
		(layer "F.Cu")
		(at 102.437946 -52.86248 -90)
		(property "Reference" "R6317"
			(at 0 0 270)
			(layer "F.SilkS")
			(hide yes)
			(effects
				(font
					(size 1.27 1.27)
				)
			)
		)
		(property "Value" ""
			(at 0 0 270)
			(layer "F.Fab")
			(effects
				(font
					(size 1.27 1.27)
				)
			)
		)
		(duplicate_pad_numbers_are_jumpers no)
		(fp_line
			(start -0.7874 0.4064)
			(end -0.7874 -0.4064)
			(stroke
				(width 0.1524)
				(type default)
			)
			(layer "F.SilkS")
		)
		(fp_line
			(start 0.7874 0.4064)
			(end -0.7874 0.4064)
			(stroke
				(width 0.1524)
				(type default)
			)
			(layer "F.SilkS")
		)
		(fp_line
			(start -0.7874 -0.4064)
			(end 0.7874 -0.4064)
			(stroke
				(width 0.1524)
				(type default)
			)
			(layer "F.SilkS")
		)
		(fp_line
			(start 0.7874 -0.4064)
			(end 0.7874 0.4064)
			(stroke
				(width 0.1524)
				(type default)
			)
			(layer "F.SilkS")
		)
		(fp_line
			(start -0.67945 0.3048)
			(end -0.67945 -0.305054)
			(stroke
				(width 0.1)
				(type default)
			)
			(layer "F.Fab")
		)
		(fp_line
			(start -0.12065 0.3048)
			(end -0.67945 0.3048)
			(stroke
				(width 0.1)
				(type default)
			)
			(layer "F.Fab")
		)
		(fp_line
			(start 0.120396 0.3048)
			(end 0.120396 0.2794)
			(stroke
				(width 0.1)
				(type default)
			)
			(layer "F.Fab")
		)
		(fp_line
			(start 0.67945 0.3048)
			(end 0.120396 0.3048)
			(stroke
				(width 0.1)
				(type default)
			)
			(layer "F.Fab")
		)
		(fp_line
			(start -0.12065 0.2794)
			(end -0.12065 0.3048)
			(stroke
				(width 0.1)
				(type default)
			)
			(layer "F.Fab")
		)
		(fp_line
			(start 0.120396 0.2794)
			(end -0.12065 0.2794)
			(stroke
				(width 0.1)
				(type default)
			)
			(layer "F.Fab")
		)
		(fp_line
			(start -0.12065 -0.2794)
			(end 0.12065 -0.2794)
			(stroke
				(width 0.1)
				(type default)
			)
			(layer "F.Fab")
		)
		(fp_line
			(start 0.12065 -0.2794)
			(end 0.12065 -0.3048)
			(stroke
				(width 0.1)
				(type default)
			)
			(layer "F.Fab")
		)
		(fp_line
			(start 0.12065 -0.3048)
			(end 0.67945 -0.3048)
			(stroke
				(width 0.1)
				(type default)
			)
			(layer "F.Fab")
		)
		(fp_line
			(start 0.67945 -0.3048)
			(end 0.67945 0.3048)
			(stroke
				(width 0.1)
				(type default)
			)
			(layer "F.Fab")
		)
		(fp_line
			(start -0.67945 -0.305054)
			(end -0.12065 -0.305054)
			(stroke
				(width 0.1)
				(type default)
			)
			(layer "F.Fab")
		)
		(fp_line
			(start -0.12065 -0.305054)
			(end -0.12065 -0.2794)
			(stroke
				(width 0.1)
				(type default)
			)
			(layer "F.Fab")
		)
		(pad "1" smd circle
			(at -0.40005 0 270)
			(size 0 0)
			(layers "F.Cu" "F.Mask" "F.Paste")
			(net "USB_HUB2_MRP_RESET_N")
		)
		(pad "2" smd circle
			(at 0.40005 0 270)
			(size 0 0)
			(layers "F.Cu" "F.Mask" "F.Paste")
			(net "USB_HUB2_TI_USB_VBUS_MRP_RESET_N")
		)
	)
	(footprint ""
		(layer "F.Cu")
		(at 192.53962 -422.804082 -90)
		(property "Reference" "R2946"
			(at 0 0 270)
			(layer "F.SilkS")
			(hide yes)
			(effects
				(font
					(size 1.27 1.27)
				)
			)
		)
		(property "Value" ""
			(at 0 0 270)
			(layer "F.Fab")
			(effects
				(font
					(size 1.27 1.27)
				)
			)
		)
		(duplicate_pad_numbers_are_jumpers no)
		(fp_line
			(start -0.7874 0.4064)
			(end -0.7874 -0.4064)
			(stroke
				(width 0.1524)
				(type default)
			)
			(layer "F.SilkS")
		)
		(fp_line
			(start 0.7874 0.4064)
			(end -0.7874 0.4064)
			(stroke
				(width 0.1524)
				(type default)
			)
			(layer "F.SilkS")
		)
		(fp_line
			(start -0.7874 -0.4064)
			(end 0.7874 -0.4064)
			(stroke
				(width 0.1524)
				(type default)
			)
			(layer "F.SilkS")
		)
		(fp_line
			(start 0.7874 -0.4064)
			(end 0.7874 0.4064)
			(stroke
				(width 0.1524)
				(type default)
			)
			(layer "F.SilkS")
		)
		(fp_line
			(start -0.67945 0.3048)
			(end -0.67945 -0.305054)
			(stroke
				(width 0.1)
				(type default)
			)
			(layer "F.Fab")
		)
		(fp_line
			(start -0.12065 0.3048)
			(end -0.67945 0.3048)
			(stroke
				(width 0.1)
				(type default)
			)
			(layer "F.Fab")
		)
		(fp_line
			(start 0.120396 0.3048)
			(end 0.120396 0.2794)
			(stroke
				(width 0.1)
				(type default)
			)
			(layer "F.Fab")
		)
		(fp_line
			(start 0.67945 0.3048)
			(end 0.120396 0.3048)
			(stroke
				(width 0.1)
				(type default)
			)
			(layer "F.Fab")
		)
		(fp_line
			(start -0.12065 0.2794)
			(end -0.12065 0.3048)
			(stroke
				(width 0.1)
				(type default)
			)
			(layer "F.Fab")
		)
		(fp_line
			(start 0.120396 0.2794)
			(end -0.12065 0.2794)
			(stroke
				(width 0.1)
				(type default)
			)
			(layer "F.Fab")
		)
		(fp_line
			(start -0.12065 -0.2794)
			(end 0.12065 -0.2794)
			(stroke
				(width 0.1)
				(type default)
			)
			(layer "F.Fab")
		)
		(fp_line
			(start 0.12065 -0.2794)
			(end 0.12065 -0.3048)
			(stroke
				(width 0.1)
				(type default)
			)
			(layer "F.Fab")
		)
		(fp_line
			(start 0.12065 -0.3048)
			(end 0.67945 -0.3048)
			(stroke
				(width 0.1)
				(type default)
			)
			(layer "F.Fab")
		)
		(fp_line
			(start 0.67945 -0.3048)
			(end 0.67945 0.3048)
			(stroke
				(width 0.1)
				(type default)
			)
			(layer "F.Fab")
		)
		(fp_line
			(start -0.67945 -0.305054)
			(end -0.12065 -0.305054)
			(stroke
				(width 0.1)
				(type default)
			)
			(layer "F.Fab")
		)
		(fp_line
			(start -0.12065 -0.305054)
			(end -0.12065 -0.2794)
			(stroke
				(width 0.1)
				(type default)
			)
			(layer "F.Fab")
		)
		(pad "1" smd circle
			(at -0.40005 0 270)
			(size 0 0)
			(layers "F.Cu" "F.Mask" "F.Paste")
			(net "P3V3_AUX")
		)
		(pad "2" smd circle
			(at 0.40005 0 270)
			(size 0 0)
			(layers "F.Cu" "F.Mask" "F.Paste")
			(net "FM_GPU_HSC_EN_BUF_R")
		)
	)
	(footprint ""
		(layer "F.Cu")
		(at 15.58417 -70.194678)
		(property "Reference" "R3142"
			(at 0 0 0)
			(layer "F.SilkS")
			(hide yes)
			(effects
				(font
					(size 1.27 1.27)
				)
			)
		)
		(property "Value" ""
			(at 0 0 0)
			(layer "F.Fab")
			(effects
				(font
					(size 1.27 1.27)
				)
			)
		)
		(duplicate_pad_numbers_are_jumpers no)
		(fp_line
			(start -0.7874 -0.4064)
			(end 0.7874 -0.4064)
			(stroke
				(width 0.1524)
				(type default)
			)
			(layer "F.SilkS")
		)
		(fp_line
			(start -0.7874 0.4064)
			(end -0.7874 -0.4064)
			(stroke
				(width 0.1524)
				(type default)
			)
			(layer "F.SilkS")
		)
		(fp_line
			(start 0.7874 -0.4064)
			(end 0.7874 0.4064)
			(stroke
				(width 0.1524)
				(type default)
			)
			(layer "F.SilkS")
		)
		(fp_line
			(start 0.7874 0.4064)
			(end -0.7874 0.4064)
			(stroke
				(width 0.1524)
				(type default)
			)
			(layer "F.SilkS")
		)
		(fp_line
			(start -0.67945 -0.305054)
			(end -0.12065 -0.305054)
			(stroke
				(width 0.1)
				(type default)
			)
			(layer "F.Fab")
		)
		(fp_line
			(start -0.67945 0.3048)
			(end -0.67945 -0.305054)
			(stroke
				(width 0.1)
				(type default)
			)
			(layer "F.Fab")
		)
		(fp_line
			(start -0.12065 -0.305054)
			(end -0.12065 -0.2794)
			(stroke
				(width 0.1)
				(type default)
			)
			(layer "F.Fab")
		)
		(fp_line
			(start -0.12065 -0.2794)
			(end 0.12065 -0.2794)
			(stroke
				(width 0.1)
				(type default)
			)
			(layer "F.Fab")
		)
		(fp_line
			(start -0.12065 0.2794)
			(end -0.12065 0.3048)
			(stroke
				(width 0.1)
				(type default)
			)
			(layer "F.Fab")
		)
		(fp_line
			(start -0.12065 0.3048)
			(end -0.67945 0.3048)
			(stroke
				(width 0.1)
				(type default)
			)
			(layer "F.Fab")
		)
		(fp_line
			(start 0.120396 0.2794)
			(end -0.12065 0.2794)
			(stroke
				(width 0.1)
				(type default)
			)
			(layer "F.Fab")
		)
		(fp_line
			(start 0.120396 0.3048)
			(end 0.120396 0.2794)
			(stroke
				(width 0.1)
				(type default)
			)
			(layer "F.Fab")
		)
		(fp_line
			(start 0.12065 -0.3048)
			(end 0.67945 -0.3048)
			(stroke
				(width 0.1)
				(type default)
			)
			(layer "F.Fab")
		)
		(fp_line
			(start 0.12065 -0.2794)
			(end 0.12065 -0.3048)
			(stroke
				(width 0.1)
				(type default)
			)
			(layer "F.Fab")
		)
		(fp_line
			(start 0.67945 -0.3048)
			(end 0.67945 0.3048)
			(stroke
				(width 0.1)
				(type default)
			)
			(layer "F.Fab")
		)
		(fp_line
			(start 0.67945 0.3048)
			(end 0.120396 0.3048)
			(stroke
				(width 0.1)
				(type default)
			)
			(layer "F.Fab")
		)
		(pad "1" smd circle
			(at -0.40005 0)
			(size 0 0)
			(layers "F.Cu" "F.Mask" "F.Paste")
			(net "HP_LVC3_OCP_V3_2_PRSNT2_N_R")
		)
		(pad "2" smd circle
			(at 0.40005 0)
			(size 0 0)
			(layers "F.Cu" "F.Mask" "F.Paste")
			(net "HP_LVC3_OCP_V3_2_PRSNT2_PLD_N")
		)
	)
	(footprint ""
		(layer "F.Cu")
		(at 17.432782 -414.120584 180)
		(property "Reference" "PC6600"
			(at 0 0 180)
			(layer "F.SilkS")
			(hide yes)
			(effects
				(font
					(size 1.27 1.27)
				)
			)
		)
		(property "Value" ""
			(at 0 0 180)
			(layer "F.Fab")
			(effects
				(font
					(size 1.27 1.27)
				)
			)
		)
		(duplicate_pad_numbers_are_jumpers no)
		(fp_line
			(start 0.7874 0.4064)
			(end -0.7874 0.4064)
			(stroke
				(width 0.1524)
				(type default)
			)
			(layer "F.SilkS")
		)
		(fp_line
			(start 0.7874 -0.4064)
			(end 0.7874 0.4064)
			(stroke
				(width 0.1524)
				(type default)
			)
			(layer "F.SilkS")
		)
		(fp_line
			(start -0.7874 0.4064)
			(end -0.7874 -0.4064)
			(stroke
				(width 0.1524)
				(type default)
			)
			(layer "F.SilkS")
		)
		(fp_line
			(start -0.7874 -0.4064)
			(end 0.7874 -0.4064)
			(stroke
				(width 0.1524)
				(type default)
			)
			(layer "F.SilkS")
		)
		(fp_line
			(start 0.67945 0.3048)
			(end 0.120396 0.3048)
			(stroke
				(width 0.1)
				(type default)
			)
			(layer "F.Fab")
		)
		(fp_line
			(start 0.67945 -0.3048)
			(end 0.67945 0.3048)
			(stroke
				(width 0.1)
				(type default)
			)
			(layer "F.Fab")
		)
		(fp_line
			(start 0.12065 -0.2794)
			(end 0.12065 -0.3048)
			(stroke
				(width 0.1)
				(type default)
			)
			(layer "F.Fab")
		)
		(fp_line
			(start 0.12065 -0.3048)
			(end 0.67945 -0.3048)
			(stroke
				(width 0.1)
				(type default)
			)
			(layer "F.Fab")
		)
		(fp_line
			(start 0.120396 0.3048)
			(end 0.120396 0.2794)
			(stroke
				(width 0.1)
				(type default)
			)
			(layer "F.Fab")
		)
		(fp_line
			(start 0.120396 0.2794)
			(end -0.12065 0.2794)
			(stroke
				(width 0.1)
				(type default)
			)
			(layer "F.Fab")
		)
		(fp_line
			(start -0.12065 0.3048)
			(end -0.67945 0.3048)
			(stroke
				(width 0.1)
				(type default)
			)
			(layer "F.Fab")
		)
		(fp_line
			(start -0.12065 0.2794)
			(end -0.12065 0.3048)
			(stroke
				(width 0.1)
				(type default)
			)
			(layer "F.Fab")
		)
		(fp_line
			(start -0.12065 -0.2794)
			(end 0.12065 -0.2794)
			(stroke
				(width 0.1)
				(type default)
			)
			(layer "F.Fab")
		)
		(fp_line
			(start -0.12065 -0.305054)
			(end -0.12065 -0.2794)
			(stroke
				(width 0.1)
				(type default)
			)
			(layer "F.Fab")
		)
		(fp_line
			(start -0.67945 0.3048)
			(end -0.67945 -0.305054)
			(stroke
				(width 0.1)
				(type default)
			)
			(layer "F.Fab")
		)
		(fp_line
			(start -0.67945 -0.305054)
			(end -0.12065 -0.305054)
			(stroke
				(width 0.1)
				(type default)
			)
			(layer "F.Fab")
		)
		(pad "1" smd circle
			(at -0.40005 0 180)
			(size 0 0)
			(layers "F.Cu" "F.Mask" "F.Paste")
			(net "P0V9_RETIMER_CPU1_SENSE_R_P")
		)
		(pad "2" smd circle
			(at 0.40005 0 180)
			(size 0 0)
			(layers "F.Cu" "F.Mask" "F.Paste")
			(net "P0V9_RETIMER_CPU1_SENSE_SH_N")
		)
	)
	(footprint ""
		(layer "F.Cu")
		(at 458.346302 -405.972264)
		(property "Reference" "PC6581_2"
			(at 0 0 0)
			(layer "F.SilkS")
			(hide yes)
			(effects
				(font
					(size 1.27 1.27)
				)
			)
		)
		(property "Value" ""
			(at 0 0 0)
			(layer "F.Fab")
			(effects
				(font
					(size 1.27 1.27)
				)
			)
		)
		(duplicate_pad_numbers_are_jumpers no)
		(fp_line
			(start -1.524 -0.762)
			(end 1.524 -0.762)
			(stroke
				(width 0.1524)
				(type default)
			)
			(layer "F.SilkS")
		)
		(fp_line
			(start -1.524 0.762)
			(end -1.524 -0.762)
			(stroke
				(width 0.1524)
				(type default)
			)
			(layer "F.SilkS")
		)
		(fp_line
			(start 1.524 -0.762)
			(end 1.524 0.762)
			(stroke
				(width 0.1524)
				(type default)
			)
			(layer "F.SilkS")
		)
		(fp_line
			(start 1.524 0.762)
			(end -1.524 0.762)
			(stroke
				(width 0.1524)
				(type default)
			)
			(layer "F.SilkS")
		)
		(fp_line
			(start -1.1049 -0.724916)
			(end -1.1049 0.724916)
			(stroke
				(width 0.1)
				(type default)
			)
			(layer "F.Fab")
		)
		(fp_line
			(start -1.1049 0.724916)
			(end 1.1049 0.724916)
			(stroke
				(width 0.1)
				(type default)
			)
			(layer "F.Fab")
		)
		(fp_line
			(start 1.1049 -0.724916)
			(end -1.1049 -0.724916)
			(stroke
				(width 0.1)
				(type default)
			)
			(layer "F.Fab")
		)
		(fp_line
			(start 1.1049 0.724916)
			(end 1.1049 -0.724916)
			(stroke
				(width 0.1)
				(type default)
			)
			(layer "F.Fab")
		)
		(pad "1" smd rect
			(at -0.889 0 180)
			(size 1.016 1.27)
			(layers "F.Cu" "F.Mask" "F.Paste")
			(net "SW_P12V_AUX_P0V9_RETIMER_CPU0_FLT")
		)
		(pad "2" smd rect
			(at 0.889 0 180)
			(size 1.016 1.27)
			(layers "F.Cu" "F.Mask" "F.Paste")
			(net "GND")
		)
	)
	(footprint ""
		(layer "F.Cu")
		(at 180.528468 -48.053498)
		(property "Reference" "C9103"
			(at 0 0 0)
			(layer "F.SilkS")
			(hide yes)
			(effects
				(font
					(size 1.27 1.27)
				)
			)
		)
		(property "Value" ""
			(at 0 0 0)
			(layer "F.Fab")
			(effects
				(font
					(size 1.27 1.27)
				)
			)
		)
		(duplicate_pad_numbers_are_jumpers no)
		(fp_line
			(start -0.299974 -0.150114)
			(end 0.299974 -0.150114)
			(stroke
				(width 0.1)
				(type default)
			)
			(layer "F.Fab")
		)
		(fp_line
			(start -0.299974 0.150114)
			(end -0.299974 -0.150114)
			(stroke
				(width 0.1)
				(type default)
			)
			(layer "F.Fab")
		)
		(fp_line
			(start 0.299974 -0.150114)
			(end 0.299974 0.150114)
			(stroke
				(width 0.1)
				(type default)
			)
			(layer "F.Fab")
		)
		(fp_line
			(start 0.299974 0.150114)
			(end -0.299974 0.150114)
			(stroke
				(width 0.1)
				(type default)
			)
			(layer "F.Fab")
		)
		(pad "1" smd rect
			(at -0.2667 0)
			(size 0.3048 0.381)
			(layers "F.Cu" "F.Mask" "F.Paste")
			(net "P3E_CPU1_P4_TX_C_DN<1>")
		)
		(pad "2" smd rect
			(at 0.2667 0)
			(size 0.3048 0.381)
			(layers "F.Cu" "F.Mask" "F.Paste")
			(net "P3E_CPU1_P4_TX_DN<1>")
		)
	)
	(footprint ""
		(layer "F.Cu")
		(at 25.331166 -78.805024 -90)
		(property "Reference" "JP6001"
			(at -3.135122 6.727444 0)
			(unlocked yes)
			(layer "F.SilkS")
			(effects
				(font
					(size 0.7874 0.5842)
					(thickness 0.1524)
				)
				(justify left)
			)
		)
		(property "Value" ""
			(at 0 0 270)
			(layer "F.Fab")
			(effects
				(font
					(size 1.27 1.27)
				)
			)
		)
		(duplicate_pad_numbers_are_jumpers no)
		(fp_line
			(start -1.249934 6.400038)
			(end -1.249934 -1.320038)
			(stroke
				(width 0.1524)
				(type default)
			)
			(layer "F.SilkS")
		)
		(fp_line
			(start 1.249934 6.400038)
			(end -1.249934 6.400038)
			(stroke
				(width 0.1524)
				(type default)
			)
			(layer "F.SilkS")
		)
		(fp_line
			(start -1.249934 -1.320038)
			(end 1.249934 -1.320038)
			(stroke
				(width 0.1524)
				(type default)
			)
			(layer "F.SilkS")
		)
		(fp_line
			(start 1.249934 -1.320038)
			(end 1.249934 6.400038)
			(stroke
				(width 0.1524)
				(type default)
			)
			(layer "F.SilkS")
		)
		(fp_poly
			(pts
				(xy -2.5654 -0.556514) (xy -1.452372 0) (xy -2.5654 0.556514)
			)
			(stroke
				(width 0)
				(type default)
			)
			(fill yes)
			(layer "F.SilkS")
		)
		(fp_line
			(start -1.249934 6.400038)
			(end -1.249934 -1.320038)
			(stroke
				(width 0.1)
				(type default)
			)
			(layer "F.Fab")
		)
		(fp_line
			(start 1.249934 6.400038)
			(end -1.249934 6.400038)
			(stroke
				(width 0.1)
				(type default)
			)
			(layer "F.Fab")
		)
		(fp_line
			(start -1.249934 -1.320038)
			(end 1.249934 -1.320038)
			(stroke
				(width 0.1)
				(type default)
			)
			(layer "F.Fab")
		)
		(fp_line
			(start 1.249934 -1.320038)
			(end 1.249934 6.400038)
			(stroke
				(width 0.1)
				(type default)
			)
			(layer "F.Fab")
		)
		(fp_poly
			(pts
				(xy -2.5654 -0.556514) (xy -1.452372 0) (xy -2.5654 0.556514)
			)
			(stroke
				(width 0)
				(type default)
			)
			(fill yes)
			(layer "F.Fab")
		)
		(fp_text user "3"
			(at -1.778 5.13207 270)
			(unlocked yes)
			(layer "F.SilkS")
			(effects
				(font
					(size 0.7874 0.5842)
					(thickness 0.1524)
				)
			)
		)
		(fp_text user "3"
			(at -1.1557 5.18287 270)
			(unlocked yes)
			(layer "B.SilkS")
			(effects
				(font
					(size 0.7874 0.5842)
					(thickness 0.1524)
				)
				(justify mirror)
			)
		)
		(fp_text user "1"
			(at -1.143 0.02667 270)
			(unlocked yes)
			(layer "B.SilkS")
			(effects
				(font
					(size 0.7874 0.5842)
					(thickness 0.1524)
				)
				(justify mirror)
			)
		)
		(fp_text user "3"
			(at -1.1557 5.18287 270)
			(unlocked yes)
			(layer "B.Fab")
			(effects
				(font
					(size 0.7874 0.5842)
					(thickness 0.1524)
				)
				(justify mirror)
			)
		)
		(fp_text user "1"
			(at -1.143 0.02667 270)
			(unlocked yes)
			(layer "B.Fab")
			(effects
				(font
					(size 0.7874 0.5842)
					(thickness 0.1524)
				)
				(justify mirror)
			)
		)
		(fp_text user "3"
			(at -1.778 5.13207 270)
			(unlocked yes)
			(layer "F.Fab")
			(effects
				(font
					(size 0.7874 0.5842)
					(thickness 0.1524)
				)
			)
		)
		(pad "1" thru_hole rect
			(at 0 0 270)
			(size 1.5494 1.5494)
			(drill 1.0414)
			(layers "*.Cu" "*.Mask")
			(remove_unused_layers no)
			(net "PU_U160_EN_N")
			(clearance 0)
			(padstack
				(mode front_inner_back)
				(layer "Inner"
					(shape circle)
					(size 1.5494 1.5494)
					(clearance 0)
				)
				(layer "B.Cu"
					(shape rect)
					(size 1.5494 1.5494)
					(clearance 0)
				)
			)
		)
		(pad "2" thru_hole circle
			(at 0 2.54 270)
			(size 1.5494 1.5494)
			(drill 1.0414)
			(layers "*.Cu" "*.Mask")
			(remove_unused_layers no)
			(net "U160_EN_N")
			(clearance 0)
		)
		(pad "3" thru_hole circle
			(at 0 5.08 270)
			(size 1.5494 1.5494)
			(drill 1.0414)
			(layers "*.Cu" "*.Mask")
			(remove_unused_layers no)
			(net "PD_U160_EN_N")
			(clearance 0)
		)
	)
	(footprint ""
		(layer "F.Cu")
		(at 422.129712 -57.447688 -90)
		(property "Reference" "R733"
			(at 0 0 270)
			(layer "F.SilkS")
			(hide yes)
			(effects
				(font
					(size 1.27 1.27)
				)
			)
		)
		(property "Value" ""
			(at 0 0 270)
			(layer "F.Fab")
			(effects
				(font
					(size 1.27 1.27)
				)
			)
		)
		(duplicate_pad_numbers_are_jumpers no)
		(fp_line
			(start -0.7874 0.4064)
			(end -0.7874 -0.4064)
			(stroke
				(width 0.1524)
				(type default)
			)
			(layer "F.SilkS")
		)
		(fp_line
			(start 0.7874 0.4064)
			(end -0.7874 0.4064)
			(stroke
				(width 0.1524)
				(type default)
			)
			(layer "F.SilkS")
		)
		(fp_line
			(start -0.7874 -0.4064)
			(end 0.7874 -0.4064)
			(stroke
				(width 0.1524)
				(type default)
			)
			(layer "F.SilkS")
		)
		(fp_line
			(start 0.7874 -0.4064)
			(end 0.7874 0.4064)
			(stroke
				(width 0.1524)
				(type default)
			)
			(layer "F.SilkS")
		)
		(fp_line
			(start -0.67945 0.3048)
			(end -0.67945 -0.305054)
			(stroke
				(width 0.1)
				(type default)
			)
			(layer "F.Fab")
		)
		(fp_line
			(start -0.12065 0.3048)
			(end -0.67945 0.3048)
			(stroke
				(width 0.1)
				(type default)
			)
			(layer "F.Fab")
		)
		(fp_line
			(start 0.120396 0.3048)
			(end 0.120396 0.2794)
			(stroke
				(width 0.1)
				(type default)
			)
			(layer "F.Fab")
		)
		(fp_line
			(start 0.67945 0.3048)
			(end 0.120396 0.3048)
			(stroke
				(width 0.1)
				(type default)
			)
			(layer "F.Fab")
		)
		(fp_line
			(start -0.12065 0.2794)
			(end -0.12065 0.3048)
			(stroke
				(width 0.1)
				(type default)
			)
			(layer "F.Fab")
		)
		(fp_line
			(start 0.120396 0.2794)
			(end -0.12065 0.2794)
			(stroke
				(width 0.1)
				(type default)
			)
			(layer "F.Fab")
		)
		(fp_line
			(start -0.12065 -0.2794)
			(end 0.12065 -0.2794)
			(stroke
				(width 0.1)
				(type default)
			)
			(layer "F.Fab")
		)
		(fp_line
			(start 0.12065 -0.2794)
			(end 0.12065 -0.3048)
			(stroke
				(width 0.1)
				(type default)
			)
			(layer "F.Fab")
		)
		(fp_line
			(start 0.12065 -0.3048)
			(end 0.67945 -0.3048)
			(stroke
				(width 0.1)
				(type default)
			)
			(layer "F.Fab")
		)
		(fp_line
			(start 0.67945 -0.3048)
			(end 0.67945 0.3048)
			(stroke
				(width 0.1)
				(type default)
			)
			(layer "F.Fab")
		)
		(fp_line
			(start -0.67945 -0.305054)
			(end -0.12065 -0.305054)
			(stroke
				(width 0.1)
				(type default)
			)
			(layer "F.Fab")
		)
		(fp_line
			(start -0.12065 -0.305054)
			(end -0.12065 -0.2794)
			(stroke
				(width 0.1)
				(type default)
			)
			(layer "F.Fab")
		)
		(pad "1" smd circle
			(at -0.40005 0 270)
			(size 0 0)
			(layers "F.Cu" "F.Mask" "F.Paste")
			(net "P1V8_AUX")
		)
		(pad "2" smd circle
			(at 0.40005 0 270)
			(size 0 0)
			(layers "F.Cu" "F.Mask" "F.Paste")
			(net "FM_JTAG_BMC_R_OE")
		)
	)
	(footprint ""
		(layer "F.Cu")
		(at 115.010946 -52.48148 180)
		(property "Reference" "R6295"
			(at 0 0 180)
			(layer "F.SilkS")
			(hide yes)
			(effects
				(font
					(size 1.27 1.27)
				)
			)
		)
		(property "Value" ""
			(at 0 0 180)
			(layer "F.Fab")
			(effects
				(font
					(size 1.27 1.27)
				)
			)
		)
		(duplicate_pad_numbers_are_jumpers no)
		(fp_line
			(start 0.7874 0.4064)
			(end -0.7874 0.4064)
			(stroke
				(width 0.1524)
				(type default)
			)
			(layer "F.SilkS")
		)
		(fp_line
			(start 0.7874 -0.4064)
			(end 0.7874 0.4064)
			(stroke
				(width 0.1524)
				(type default)
			)
			(layer "F.SilkS")
		)
		(fp_line
			(start -0.7874 0.4064)
			(end -0.7874 -0.4064)
			(stroke
				(width 0.1524)
				(type default)
			)
			(layer "F.SilkS")
		)
		(fp_line
			(start -0.7874 -0.4064)
			(end 0.7874 -0.4064)
			(stroke
				(width 0.1524)
				(type default)
			)
			(layer "F.SilkS")
		)
		(fp_line
			(start 0.67945 0.3048)
			(end 0.120396 0.3048)
			(stroke
				(width 0.1)
				(type default)
			)
			(layer "F.Fab")
		)
		(fp_line
			(start 0.67945 -0.3048)
			(end 0.67945 0.3048)
			(stroke
				(width 0.1)
				(type default)
			)
			(layer "F.Fab")
		)
		(fp_line
			(start 0.12065 -0.2794)
			(end 0.12065 -0.3048)
			(stroke
				(width 0.1)
				(type default)
			)
			(layer "F.Fab")
		)
		(fp_line
			(start 0.12065 -0.3048)
			(end 0.67945 -0.3048)
			(stroke
				(width 0.1)
				(type default)
			)
			(layer "F.Fab")
		)
		(fp_line
			(start 0.120396 0.3048)
			(end 0.120396 0.2794)
			(stroke
				(width 0.1)
				(type default)
			)
			(layer "F.Fab")
		)
		(fp_line
			(start 0.120396 0.2794)
			(end -0.12065 0.2794)
			(stroke
				(width 0.1)
				(type default)
			)
			(layer "F.Fab")
		)
		(fp_line
			(start -0.12065 0.3048)
			(end -0.67945 0.3048)
			(stroke
				(width 0.1)
				(type default)
			)
			(layer "F.Fab")
		)
		(fp_line
			(start -0.12065 0.2794)
			(end -0.12065 0.3048)
			(stroke
				(width 0.1)
				(type default)
			)
			(layer "F.Fab")
		)
		(fp_line
			(start -0.12065 -0.2794)
			(end 0.12065 -0.2794)
			(stroke
				(width 0.1)
				(type default)
			)
			(layer "F.Fab")
		)
		(fp_line
			(start -0.12065 -0.305054)
			(end -0.12065 -0.2794)
			(stroke
				(width 0.1)
				(type default)
			)
			(layer "F.Fab")
		)
		(fp_line
			(start -0.67945 0.3048)
			(end -0.67945 -0.305054)
			(stroke
				(width 0.1)
				(type default)
			)
			(layer "F.Fab")
		)
		(fp_line
			(start -0.67945 -0.305054)
			(end -0.12065 -0.305054)
			(stroke
				(width 0.1)
				(type default)
			)
			(layer "F.Fab")
		)
		(pad "1" smd circle
			(at -0.40005 0 180)
			(size 0 0)
			(layers "F.Cu" "F.Mask" "F.Paste")
			(net "USB_HUB2_TI_OVERCCUR4")
		)
		(pad "2" smd circle
			(at 0.40005 0 180)
			(size 0 0)
			(layers "F.Cu" "F.Mask" "F.Paste")
			(net "USB_HUB2_TI_OVERCUR4_MRP_I2C_SLV_CFG1")
		)
	)
	(footprint ""
		(layer "F.Cu")
		(at 250.465336 -75.092814)
		(property "Reference" "R3775"
			(at 0 0 0)
			(layer "F.SilkS")
			(hide yes)
			(effects
				(font
					(size 1.27 1.27)
				)
			)
		)
		(property "Value" ""
			(at 0 0 0)
			(layer "F.Fab")
			(effects
				(font
					(size 1.27 1.27)
				)
			)
		)
		(duplicate_pad_numbers_are_jumpers no)
		(fp_line
			(start -0.7874 -0.4064)
			(end 0.7874 -0.4064)
			(stroke
				(width 0.1524)
				(type default)
			)
			(layer "F.SilkS")
		)
		(fp_line
			(start -0.7874 0.4064)
			(end -0.7874 -0.4064)
			(stroke
				(width 0.1524)
				(type default)
			)
			(layer "F.SilkS")
		)
		(fp_line
			(start 0.7874 -0.4064)
			(end 0.7874 0.4064)
			(stroke
				(width 0.1524)
				(type default)
			)
			(layer "F.SilkS")
		)
		(fp_line
			(start 0.7874 0.4064)
			(end -0.7874 0.4064)
			(stroke
				(width 0.1524)
				(type default)
			)
			(layer "F.SilkS")
		)
		(fp_line
			(start -0.67945 -0.305054)
			(end -0.12065 -0.305054)
			(stroke
				(width 0.1)
				(type default)
			)
			(layer "F.Fab")
		)
		(fp_line
			(start -0.67945 0.3048)
			(end -0.67945 -0.305054)
			(stroke
				(width 0.1)
				(type default)
			)
			(layer "F.Fab")
		)
		(fp_line
			(start -0.12065 -0.305054)
			(end -0.12065 -0.2794)
			(stroke
				(width 0.1)
				(type default)
			)
			(layer "F.Fab")
		)
		(fp_line
			(start -0.12065 -0.2794)
			(end 0.12065 -0.2794)
			(stroke
				(width 0.1)
				(type default)
			)
			(layer "F.Fab")
		)
		(fp_line
			(start -0.12065 0.2794)
			(end -0.12065 0.3048)
			(stroke
				(width 0.1)
				(type default)
			)
			(layer "F.Fab")
		)
		(fp_line
			(start -0.12065 0.3048)
			(end -0.67945 0.3048)
			(stroke
				(width 0.1)
				(type default)
			)
			(layer "F.Fab")
		)
		(fp_line
			(start 0.120396 0.2794)
			(end -0.12065 0.2794)
			(stroke
				(width 0.1)
				(type default)
			)
			(layer "F.Fab")
		)
		(fp_line
			(start 0.120396 0.3048)
			(end 0.120396 0.2794)
			(stroke
				(width 0.1)
				(type default)
			)
			(layer "F.Fab")
		)
		(fp_line
			(start 0.12065 -0.3048)
			(end 0.67945 -0.3048)
			(stroke
				(width 0.1)
				(type default)
			)
			(layer "F.Fab")
		)
		(fp_line
			(start 0.12065 -0.2794)
			(end 0.12065 -0.3048)
			(stroke
				(width 0.1)
				(type default)
			)
			(layer "F.Fab")
		)
		(fp_line
			(start 0.67945 -0.3048)
			(end 0.67945 0.3048)
			(stroke
				(width 0.1)
				(type default)
			)
			(layer "F.Fab")
		)
		(fp_line
			(start 0.67945 0.3048)
			(end 0.120396 0.3048)
			(stroke
				(width 0.1)
				(type default)
			)
			(layer "F.Fab")
		)
		(pad "1" smd circle
			(at -0.40005 0)
			(size 0 0)
			(layers "F.Cu" "F.Mask" "F.Paste")
			(net "FM_SMB_RST_E1S_0_R_N")
		)
		(pad "2" smd circle
			(at 0.40005 0)
			(size 0 0)
			(layers "F.Cu" "F.Mask" "F.Paste")
			(net "RST_SMB_E1S_N")
		)
	)
	(footprint ""
		(layer "F.Cu")
		(at 90.046302 -373.03583 -90)
		(property "Reference" "C724"
			(at 0 0 270)
			(layer "F.SilkS")
			(hide yes)
			(effects
				(font
					(size 1.27 1.27)
				)
			)
		)
		(property "Value" ""
			(at 0 0 270)
			(layer "F.Fab")
			(effects
				(font
					(size 1.27 1.27)
				)
			)
		)
		(duplicate_pad_numbers_are_jumpers no)
		(fp_line
			(start -0.299974 0.150114)
			(end -0.299974 -0.150114)
			(stroke
				(width 0.1)
				(type default)
			)
			(layer "F.Fab")
		)
		(fp_line
			(start 0.299974 0.150114)
			(end -0.299974 0.150114)
			(stroke
				(width 0.1)
				(type default)
			)
			(layer "F.Fab")
		)
		(fp_line
			(start -0.299974 -0.150114)
			(end 0.299974 -0.150114)
			(stroke
				(width 0.1)
				(type default)
			)
			(layer "F.Fab")
		)
		(fp_line
			(start 0.299974 -0.150114)
			(end 0.299974 0.150114)
			(stroke
				(width 0.1)
				(type default)
			)
			(layer "F.Fab")
		)
		(pad "1" smd rect
			(at -0.2667 0 270)
			(size 0.3048 0.381)
			(layers "F.Cu" "F.Mask" "F.Paste")
			(net "P5E_CPU1_P1_TX_C_DN<8>")
		)
		(pad "2" smd rect
			(at 0.2667 0 270)
			(size 0.3048 0.381)
			(layers "F.Cu" "F.Mask" "F.Paste")
			(net "P5E_CPU1_P1_TX_DN<8>")
		)
	)
	(footprint ""
		(layer "F.Cu")
		(at 163.195 -106.807 90)
		(property "Reference" "R9028"
			(at 0 0 90)
			(layer "F.SilkS")
			(hide yes)
			(effects
				(font
					(size 1.27 1.27)
				)
			)
		)
		(property "Value" ""
			(at 0 0 90)
			(layer "F.Fab")
			(effects
				(font
					(size 1.27 1.27)
				)
			)
		)
		(duplicate_pad_numbers_are_jumpers no)
		(fp_line
			(start 0.7874 -0.4064)
			(end 0.7874 0.4064)
			(stroke
				(width 0.1524)
				(type default)
			)
			(layer "F.SilkS")
		)
		(fp_line
			(start -0.7874 -0.4064)
			(end 0.7874 -0.4064)
			(stroke
				(width 0.1524)
				(type default)
			)
			(layer "F.SilkS")
		)
		(fp_line
			(start 0.7874 0.4064)
			(end -0.7874 0.4064)
			(stroke
				(width 0.1524)
				(type default)
			)
			(layer "F.SilkS")
		)
		(fp_line
			(start -0.7874 0.4064)
			(end -0.7874 -0.4064)
			(stroke
				(width 0.1524)
				(type default)
			)
			(layer "F.SilkS")
		)
		(fp_line
			(start -0.12065 -0.305054)
			(end -0.12065 -0.2794)
			(stroke
				(width 0.1)
				(type default)
			)
			(layer "F.Fab")
		)
		(fp_line
			(start -0.67945 -0.305054)
			(end -0.12065 -0.305054)
			(stroke
				(width 0.1)
				(type default)
			)
			(layer "F.Fab")
		)
		(fp_line
			(start 0.67945 -0.3048)
			(end 0.67945 0.3048)
			(stroke
				(width 0.1)
				(type default)
			)
			(layer "F.Fab")
		)
		(fp_line
			(start 0.12065 -0.3048)
			(end 0.67945 -0.3048)
			(stroke
				(width 0.1)
				(type default)
			)
			(layer "F.Fab")
		)
		(fp_line
			(start 0.12065 -0.2794)
			(end 0.12065 -0.3048)
			(stroke
				(width 0.1)
				(type default)
			)
			(layer "F.Fab")
		)
		(fp_line
			(start -0.12065 -0.2794)
			(end 0.12065 -0.2794)
			(stroke
				(width 0.1)
				(type default)
			)
			(layer "F.Fab")
		)
		(fp_line
			(start 0.120396 0.2794)
			(end -0.12065 0.2794)
			(stroke
				(width 0.1)
				(type default)
			)
			(layer "F.Fab")
		)
		(fp_line
			(start -0.12065 0.2794)
			(end -0.12065 0.3048)
			(stroke
				(width 0.1)
				(type default)
			)
			(layer "F.Fab")
		)
		(fp_line
			(start 0.67945 0.3048)
			(end 0.120396 0.3048)
			(stroke
				(width 0.1)
				(type default)
			)
			(layer "F.Fab")
		)
		(fp_line
			(start 0.120396 0.3048)
			(end 0.120396 0.2794)
			(stroke
				(width 0.1)
				(type default)
			)
			(layer "F.Fab")
		)
		(fp_line
			(start -0.12065 0.3048)
			(end -0.67945 0.3048)
			(stroke
				(width 0.1)
				(type default)
			)
			(layer "F.Fab")
		)
		(fp_line
			(start -0.67945 0.3048)
			(end -0.67945 -0.305054)
			(stroke
				(width 0.1)
				(type default)
			)
			(layer "F.Fab")
		)
		(pad "1" smd circle
			(at -0.40005 0 90)
			(size 0 0)
			(layers "F.Cu" "F.Mask" "F.Paste")
			(net "IRQ_HSC_FAULT_N")
		)
		(pad "2" smd circle
			(at 0.40005 0 90)
			(size 0 0)
			(layers "F.Cu" "F.Mask" "F.Paste")
			(net "IRQ_HSC_FAULT_BUF_N")
		)
	)
	(footprint ""
		(layer "F.Cu")
		(at 279.513792 -121.75617)
		(property "Reference" "R2268"
			(at 0 0 0)
			(layer "F.SilkS")
			(hide yes)
			(effects
				(font
					(size 1.27 1.27)
				)
			)
		)
		(property "Value" ""
			(at 0 0 0)
			(layer "F.Fab")
			(effects
				(font
					(size 1.27 1.27)
				)
			)
		)
		(duplicate_pad_numbers_are_jumpers no)
		(fp_line
			(start -0.7874 -0.4064)
			(end 0.7874 -0.4064)
			(stroke
				(width 0.1524)
				(type default)
			)
			(layer "F.SilkS")
		)
		(fp_line
			(start -0.7874 0.4064)
			(end -0.7874 -0.4064)
			(stroke
				(width 0.1524)
				(type default)
			)
			(layer "F.SilkS")
		)
		(fp_line
			(start 0.7874 -0.4064)
			(end 0.7874 0.4064)
			(stroke
				(width 0.1524)
				(type default)
			)
			(layer "F.SilkS")
		)
		(fp_line
			(start 0.7874 0.4064)
			(end -0.7874 0.4064)
			(stroke
				(width 0.1524)
				(type default)
			)
			(layer "F.SilkS")
		)
		(fp_line
			(start -0.67945 -0.305054)
			(end -0.12065 -0.305054)
			(stroke
				(width 0.1)
				(type default)
			)
			(layer "F.Fab")
		)
		(fp_line
			(start -0.67945 0.3048)
			(end -0.67945 -0.305054)
			(stroke
				(width 0.1)
				(type default)
			)
			(layer "F.Fab")
		)
		(fp_line
			(start -0.12065 -0.305054)
			(end -0.12065 -0.2794)
			(stroke
				(width 0.1)
				(type default)
			)
			(layer "F.Fab")
		)
		(fp_line
			(start -0.12065 -0.2794)
			(end 0.12065 -0.2794)
			(stroke
				(width 0.1)
				(type default)
			)
			(layer "F.Fab")
		)
		(fp_line
			(start -0.12065 0.2794)
			(end -0.12065 0.3048)
			(stroke
				(width 0.1)
				(type default)
			)
			(layer "F.Fab")
		)
		(fp_line
			(start -0.12065 0.3048)
			(end -0.67945 0.3048)
			(stroke
				(width 0.1)
				(type default)
			)
			(layer "F.Fab")
		)
		(fp_line
			(start 0.120396 0.2794)
			(end -0.12065 0.2794)
			(stroke
				(width 0.1)
				(type default)
			)
			(layer "F.Fab")
		)
		(fp_line
			(start 0.120396 0.3048)
			(end 0.120396 0.2794)
			(stroke
				(width 0.1)
				(type default)
			)
			(layer "F.Fab")
		)
		(fp_line
			(start 0.12065 -0.3048)
			(end 0.67945 -0.3048)
			(stroke
				(width 0.1)
				(type default)
			)
			(layer "F.Fab")
		)
		(fp_line
			(start 0.12065 -0.2794)
			(end 0.12065 -0.3048)
			(stroke
				(width 0.1)
				(type default)
			)
			(layer "F.Fab")
		)
		(fp_line
			(start 0.67945 -0.3048)
			(end 0.67945 0.3048)
			(stroke
				(width 0.1)
				(type default)
			)
			(layer "F.Fab")
		)
		(fp_line
			(start 0.67945 0.3048)
			(end 0.120396 0.3048)
			(stroke
				(width 0.1)
				(type default)
			)
			(layer "F.Fab")
		)
		(pad "1" smd circle
			(at -0.40005 0)
			(size 0 0)
			(layers "F.Cu" "F.Mask" "F.Paste")
			(net "RST_SMB_SWITCH_N")
		)
		(pad "2" smd circle
			(at 0.40005 0)
			(size 0 0)
			(layers "F.Cu" "F.Mask" "F.Paste")
			(net "PU_RST_SMB_PCIE0_N")
		)
	)
	(footprint ""
		(layer "F.Cu")
		(at 334.133444 -378.95403 -90)
		(property "Reference" "C958"
			(at 0 0 270)
			(layer "F.SilkS")
			(hide yes)
			(effects
				(font
					(size 1.27 1.27)
				)
			)
		)
		(property "Value" ""
			(at 0 0 270)
			(layer "F.Fab")
			(effects
				(font
					(size 1.27 1.27)
				)
			)
		)
		(duplicate_pad_numbers_are_jumpers no)
		(fp_line
			(start -0.299974 0.150114)
			(end -0.299974 -0.150114)
			(stroke
				(width 0.1)
				(type default)
			)
			(layer "F.Fab")
		)
		(fp_line
			(start 0.299974 0.150114)
			(end -0.299974 0.150114)
			(stroke
				(width 0.1)
				(type default)
			)
			(layer "F.Fab")
		)
		(fp_line
			(start -0.299974 -0.150114)
			(end 0.299974 -0.150114)
			(stroke
				(width 0.1)
				(type default)
			)
			(layer "F.Fab")
		)
		(fp_line
			(start 0.299974 -0.150114)
			(end 0.299974 0.150114)
			(stroke
				(width 0.1)
				(type default)
			)
			(layer "F.Fab")
		)
		(pad "1" smd rect
			(at -0.2667 0 270)
			(size 0.3048 0.381)
			(layers "F.Cu" "F.Mask" "F.Paste")
			(net "P5E_CPU0_P1_TX_C_DN<3>")
		)
		(pad "2" smd rect
			(at 0.2667 0 270)
			(size 0.3048 0.381)
			(layers "F.Cu" "F.Mask" "F.Paste")
			(net "P5E_CPU0_P1_TX_DN<3>")
		)
	)
	(footprint ""
		(layer "F.Cu")
		(at 112.672876 -418.090858 -90)
		(property "Reference" "R3029"
			(at 0 0 270)
			(layer "F.SilkS")
			(hide yes)
			(effects
				(font
					(size 1.27 1.27)
				)
			)
		)
		(property "Value" ""
			(at 0 0 270)
			(layer "F.Fab")
			(effects
				(font
					(size 1.27 1.27)
				)
			)
		)
		(duplicate_pad_numbers_are_jumpers no)
		(fp_line
			(start -0.7874 0.4064)
			(end -0.7874 -0.4064)
			(stroke
				(width 0.1524)
				(type default)
			)
			(layer "F.SilkS")
		)
		(fp_line
			(start 0.7874 0.4064)
			(end -0.7874 0.4064)
			(stroke
				(width 0.1524)
				(type default)
			)
			(layer "F.SilkS")
		)
		(fp_line
			(start -0.7874 -0.4064)
			(end 0.7874 -0.4064)
			(stroke
				(width 0.1524)
				(type default)
			)
			(layer "F.SilkS")
		)
		(fp_line
			(start 0.7874 -0.4064)
			(end 0.7874 0.4064)
			(stroke
				(width 0.1524)
				(type default)
			)
			(layer "F.SilkS")
		)
		(fp_line
			(start -0.67945 0.3048)
			(end -0.67945 -0.305054)
			(stroke
				(width 0.1)
				(type default)
			)
			(layer "F.Fab")
		)
		(fp_line
			(start -0.12065 0.3048)
			(end -0.67945 0.3048)
			(stroke
				(width 0.1)
				(type default)
			)
			(layer "F.Fab")
		)
		(fp_line
			(start 0.120396 0.3048)
			(end 0.120396 0.2794)
			(stroke
				(width 0.1)
				(type default)
			)
			(layer "F.Fab")
		)
		(fp_line
			(start 0.67945 0.3048)
			(end 0.120396 0.3048)
			(stroke
				(width 0.1)
				(type default)
			)
			(layer "F.Fab")
		)
		(fp_line
			(start -0.12065 0.2794)
			(end -0.12065 0.3048)
			(stroke
				(width 0.1)
				(type default)
			)
			(layer "F.Fab")
		)
		(fp_line
			(start 0.120396 0.2794)
			(end -0.12065 0.2794)
			(stroke
				(width 0.1)
				(type default)
			)
			(layer "F.Fab")
		)
		(fp_line
			(start -0.12065 -0.2794)
			(end 0.12065 -0.2794)
			(stroke
				(width 0.1)
				(type default)
			)
			(layer "F.Fab")
		)
		(fp_line
			(start 0.12065 -0.2794)
			(end 0.12065 -0.3048)
			(stroke
				(width 0.1)
				(type default)
			)
			(layer "F.Fab")
		)
		(fp_line
			(start 0.12065 -0.3048)
			(end 0.67945 -0.3048)
			(stroke
				(width 0.1)
				(type default)
			)
			(layer "F.Fab")
		)
		(fp_line
			(start 0.67945 -0.3048)
			(end 0.67945 0.3048)
			(stroke
				(width 0.1)
				(type default)
			)
			(layer "F.Fab")
		)
		(fp_line
			(start -0.67945 -0.305054)
			(end -0.12065 -0.305054)
			(stroke
				(width 0.1)
				(type default)
			)
			(layer "F.Fab")
		)
		(fp_line
			(start -0.12065 -0.305054)
			(end -0.12065 -0.2794)
			(stroke
				(width 0.1)
				(type default)
			)
			(layer "F.Fab")
		)
		(pad "1" smd circle
			(at -0.40005 0 270)
			(size 0 0)
			(layers "F.Cu" "F.Mask" "F.Paste")
			(net "P3V3_AUX")
		)
		(pad "2" smd circle
			(at 0.40005 0 270)
			(size 0 0)
			(layers "F.Cu" "F.Mask" "F.Paste")
			(net "FM_SMB_1_ALERT_GPU")
		)
	)
	(footprint ""
		(layer "F.Cu")
		(at 142.367 -120.269 180)
		(property "Reference" "R8123"
			(at 0 0 180)
			(layer "F.SilkS")
			(hide yes)
			(effects
				(font
					(size 1.27 1.27)
				)
			)
		)
		(property "Value" ""
			(at 0 0 180)
			(layer "F.Fab")
			(effects
				(font
					(size 1.27 1.27)
				)
			)
		)
		(duplicate_pad_numbers_are_jumpers no)
		(fp_line
			(start 0.7874 0.4064)
			(end -0.7874 0.4064)
			(stroke
				(width 0.1524)
				(type default)
			)
			(layer "F.SilkS")
		)
		(fp_line
			(start 0.7874 -0.4064)
			(end 0.7874 0.4064)
			(stroke
				(width 0.1524)
				(type default)
			)
			(layer "F.SilkS")
		)
		(fp_line
			(start -0.7874 0.4064)
			(end -0.7874 -0.4064)
			(stroke
				(width 0.1524)
				(type default)
			)
			(layer "F.SilkS")
		)
		(fp_line
			(start -0.7874 -0.4064)
			(end 0.7874 -0.4064)
			(stroke
				(width 0.1524)
				(type default)
			)
			(layer "F.SilkS")
		)
		(fp_line
			(start 0.67945 0.3048)
			(end 0.120396 0.3048)
			(stroke
				(width 0.1)
				(type default)
			)
			(layer "F.Fab")
		)
		(fp_line
			(start 0.67945 -0.3048)
			(end 0.67945 0.3048)
			(stroke
				(width 0.1)
				(type default)
			)
			(layer "F.Fab")
		)
		(fp_line
			(start 0.12065 -0.2794)
			(end 0.12065 -0.3048)
			(stroke
				(width 0.1)
				(type default)
			)
			(layer "F.Fab")
		)
		(fp_line
			(start 0.12065 -0.3048)
			(end 0.67945 -0.3048)
			(stroke
				(width 0.1)
				(type default)
			)
			(layer "F.Fab")
		)
		(fp_line
			(start 0.120396 0.3048)
			(end 0.120396 0.2794)
			(stroke
				(width 0.1)
				(type default)
			)
			(layer "F.Fab")
		)
		(fp_line
			(start 0.120396 0.2794)
			(end -0.12065 0.2794)
			(stroke
				(width 0.1)
				(type default)
			)
			(layer "F.Fab")
		)
		(fp_line
			(start -0.12065 0.3048)
			(end -0.67945 0.3048)
			(stroke
				(width 0.1)
				(type default)
			)
			(layer "F.Fab")
		)
		(fp_line
			(start -0.12065 0.2794)
			(end -0.12065 0.3048)
			(stroke
				(width 0.1)
				(type default)
			)
			(layer "F.Fab")
		)
		(fp_line
			(start -0.12065 -0.2794)
			(end 0.12065 -0.2794)
			(stroke
				(width 0.1)
				(type default)
			)
			(layer "F.Fab")
		)
		(fp_line
			(start -0.12065 -0.305054)
			(end -0.12065 -0.2794)
			(stroke
				(width 0.1)
				(type default)
			)
			(layer "F.Fab")
		)
		(fp_line
			(start -0.67945 0.3048)
			(end -0.67945 -0.305054)
			(stroke
				(width 0.1)
				(type default)
			)
			(layer "F.Fab")
		)
		(fp_line
			(start -0.67945 -0.305054)
			(end -0.12065 -0.305054)
			(stroke
				(width 0.1)
				(type default)
			)
			(layer "F.Fab")
		)
		(pad "1" smd circle
			(at -0.40005 0 180)
			(size 0 0)
			(layers "F.Cu" "F.Mask" "F.Paste")
			(net "P12V_AUX_UV_TRIGGER")
		)
		(pad "2" smd circle
			(at 0.40005 0 180)
			(size 0 0)
			(layers "F.Cu" "F.Mask" "F.Paste")
			(net "IRQ_UV_DETECT_R2_N")
		)
	)
	(footprint ""
		(layer "F.Cu")
		(at 118.618 -432.054 180)
		(property "Reference" "R3452"
			(at 0 0 180)
			(layer "F.SilkS")
			(hide yes)
			(effects
				(font
					(size 1.27 1.27)
				)
			)
		)
		(property "Value" ""
			(at 0 0 180)
			(layer "F.Fab")
			(effects
				(font
					(size 1.27 1.27)
				)
			)
		)
		(duplicate_pad_numbers_are_jumpers no)
		(fp_line
			(start 0.7874 0.4064)
			(end -0.7874 0.4064)
			(stroke
				(width 0.1524)
				(type default)
			)
			(layer "F.SilkS")
		)
		(fp_line
			(start 0.7874 -0.4064)
			(end 0.7874 0.4064)
			(stroke
				(width 0.1524)
				(type default)
			)
			(layer "F.SilkS")
		)
		(fp_line
			(start -0.7874 0.4064)
			(end -0.7874 -0.4064)
			(stroke
				(width 0.1524)
				(type default)
			)
			(layer "F.SilkS")
		)
		(fp_line
			(start -0.7874 -0.4064)
			(end 0.7874 -0.4064)
			(stroke
				(width 0.1524)
				(type default)
			)
			(layer "F.SilkS")
		)
		(fp_line
			(start 0.67945 0.3048)
			(end 0.120396 0.3048)
			(stroke
				(width 0.1)
				(type default)
			)
			(layer "F.Fab")
		)
		(fp_line
			(start 0.67945 -0.3048)
			(end 0.67945 0.3048)
			(stroke
				(width 0.1)
				(type default)
			)
			(layer "F.Fab")
		)
		(fp_line
			(start 0.12065 -0.2794)
			(end 0.12065 -0.3048)
			(stroke
				(width 0.1)
				(type default)
			)
			(layer "F.Fab")
		)
		(fp_line
			(start 0.12065 -0.3048)
			(end 0.67945 -0.3048)
			(stroke
				(width 0.1)
				(type default)
			)
			(layer "F.Fab")
		)
		(fp_line
			(start 0.120396 0.3048)
			(end 0.120396 0.2794)
			(stroke
				(width 0.1)
				(type default)
			)
			(layer "F.Fab")
		)
		(fp_line
			(start 0.120396 0.2794)
			(end -0.12065 0.2794)
			(stroke
				(width 0.1)
				(type default)
			)
			(layer "F.Fab")
		)
		(fp_line
			(start -0.12065 0.3048)
			(end -0.67945 0.3048)
			(stroke
				(width 0.1)
				(type default)
			)
			(layer "F.Fab")
		)
		(fp_line
			(start -0.12065 0.2794)
			(end -0.12065 0.3048)
			(stroke
				(width 0.1)
				(type default)
			)
			(layer "F.Fab")
		)
		(fp_line
			(start -0.12065 -0.2794)
			(end 0.12065 -0.2794)
			(stroke
				(width 0.1)
				(type default)
			)
			(layer "F.Fab")
		)
		(fp_line
			(start -0.12065 -0.305054)
			(end -0.12065 -0.2794)
			(stroke
				(width 0.1)
				(type default)
			)
			(layer "F.Fab")
		)
		(fp_line
			(start -0.67945 0.3048)
			(end -0.67945 -0.305054)
			(stroke
				(width 0.1)
				(type default)
			)
			(layer "F.Fab")
		)
		(fp_line
			(start -0.67945 -0.305054)
			(end -0.12065 -0.305054)
			(stroke
				(width 0.1)
				(type default)
			)
			(layer "F.Fab")
		)
		(pad "1" smd circle
			(at -0.40005 0 180)
			(size 0 0)
			(layers "F.Cu" "F.Mask" "F.Paste")
			(net "GPU_BASE_STBY_EN")
		)
		(pad "2" smd circle
			(at 0.40005 0 180)
			(size 0 0)
			(layers "F.Cu" "F.Mask" "F.Paste")
			(net "GND")
		)
	)
	(footprint ""
		(layer "F.Cu")
		(at 411.605222 -416.899344 -90)
		(property "Reference" "C6591"
			(at 0 0 270)
			(layer "F.SilkS")
			(hide yes)
			(effects
				(font
					(size 1.27 1.27)
				)
			)
		)
		(property "Value" ""
			(at 0 0 270)
			(layer "F.Fab")
			(effects
				(font
					(size 1.27 1.27)
				)
			)
		)
		(duplicate_pad_numbers_are_jumpers no)
		(fp_line
			(start -0.299974 0.150114)
			(end -0.299974 -0.150114)
			(stroke
				(width 0.1)
				(type default)
			)
			(layer "F.Fab")
		)
		(fp_line
			(start 0.299974 0.150114)
			(end -0.299974 0.150114)
			(stroke
				(width 0.1)
				(type default)
			)
			(layer "F.Fab")
		)
		(fp_line
			(start -0.299974 -0.150114)
			(end 0.299974 -0.150114)
			(stroke
				(width 0.1)
				(type default)
			)
			(layer "F.Fab")
		)
		(fp_line
			(start 0.299974 -0.150114)
			(end 0.299974 0.150114)
			(stroke
				(width 0.1)
				(type default)
			)
			(layer "F.Fab")
		)
		(pad "1" smd rect
			(at -0.2667 0 270)
			(size 0.3048 0.381)
			(layers "F.Cu" "F.Mask" "F.Paste")
			(net "P5E_CPU0_P2_TX_BUF_C_DP<13>")
		)
		(pad "2" smd rect
			(at 0.2667 0 270)
			(size 0.3048 0.381)
			(layers "F.Cu" "F.Mask" "F.Paste")
			(net "P5E_CPU0_P2_TX_BUF_DP<13>")
		)
	)
	(footprint ""
		(layer "F.Cu")
		(at 297.554142 -400.177)
		(property "Reference" "R997"
			(at 0 0 0)
			(layer "F.SilkS")
			(hide yes)
			(effects
				(font
					(size 1.27 1.27)
				)
			)
		)
		(property "Value" ""
			(at 0 0 0)
			(layer "F.Fab")
			(effects
				(font
					(size 1.27 1.27)
				)
			)
		)
		(duplicate_pad_numbers_are_jumpers no)
		(fp_line
			(start -0.32512 -0.175006)
			(end 0.32512 -0.175006)
			(stroke
				(width 0.1)
				(type default)
			)
			(layer "F.Fab")
		)
		(fp_line
			(start -0.32512 0.175006)
			(end -0.32512 -0.175006)
			(stroke
				(width 0.1)
				(type default)
			)
			(layer "F.Fab")
		)
		(fp_line
			(start 0.32512 -0.175006)
			(end 0.32512 0.175006)
			(stroke
				(width 0.1)
				(type default)
			)
			(layer "F.Fab")
		)
		(fp_line
			(start 0.32512 0.175006)
			(end -0.32512 0.175006)
			(stroke
				(width 0.1)
				(type default)
			)
			(layer "F.Fab")
		)
		(pad "1" smd rect
			(at -0.2667 0)
			(size 0.3048 0.381)
			(layers "F.Cu" "F.Mask" "F.Paste")
			(net "JTAG_TEST_MODE_RT_CPU0_P0")
		)
		(pad "2" smd rect
			(at 0.2667 0 180)
			(size 0.3048 0.381)
			(layers "F.Cu" "F.Mask" "F.Paste")
			(net "GND")
		)
	)
	(footprint ""
		(layer "F.Cu")
		(at 453.719946 -108.059728)
		(property "Reference" "R1905"
			(at 0 0 0)
			(layer "F.SilkS")
			(hide yes)
			(effects
				(font
					(size 1.27 1.27)
				)
			)
		)
		(property "Value" ""
			(at 0 0 0)
			(layer "F.Fab")
			(effects
				(font
					(size 1.27 1.27)
				)
			)
		)
		(duplicate_pad_numbers_are_jumpers no)
		(fp_line
			(start -0.7874 -0.4064)
			(end 0.7874 -0.4064)
			(stroke
				(width 0.1524)
				(type default)
			)
			(layer "F.SilkS")
		)
		(fp_line
			(start -0.7874 0.4064)
			(end -0.7874 -0.4064)
			(stroke
				(width 0.1524)
				(type default)
			)
			(layer "F.SilkS")
		)
		(fp_line
			(start 0.7874 -0.4064)
			(end 0.7874 0.4064)
			(stroke
				(width 0.1524)
				(type default)
			)
			(layer "F.SilkS")
		)
		(fp_line
			(start 0.7874 0.4064)
			(end -0.7874 0.4064)
			(stroke
				(width 0.1524)
				(type default)
			)
			(layer "F.SilkS")
		)
		(fp_line
			(start -0.67945 -0.305054)
			(end -0.12065 -0.305054)
			(stroke
				(width 0.1)
				(type default)
			)
			(layer "F.Fab")
		)
		(fp_line
			(start -0.67945 0.3048)
			(end -0.67945 -0.305054)
			(stroke
				(width 0.1)
				(type default)
			)
			(layer "F.Fab")
		)
		(fp_line
			(start -0.12065 -0.305054)
			(end -0.12065 -0.2794)
			(stroke
				(width 0.1)
				(type default)
			)
			(layer "F.Fab")
		)
		(fp_line
			(start -0.12065 -0.2794)
			(end 0.12065 -0.2794)
			(stroke
				(width 0.1)
				(type default)
			)
			(layer "F.Fab")
		)
		(fp_line
			(start -0.12065 0.2794)
			(end -0.12065 0.3048)
			(stroke
				(width 0.1)
				(type default)
			)
			(layer "F.Fab")
		)
		(fp_line
			(start -0.12065 0.3048)
			(end -0.67945 0.3048)
			(stroke
				(width 0.1)
				(type default)
			)
			(layer "F.Fab")
		)
		(fp_line
			(start 0.120396 0.2794)
			(end -0.12065 0.2794)
			(stroke
				(width 0.1)
				(type default)
			)
			(layer "F.Fab")
		)
		(fp_line
			(start 0.120396 0.3048)
			(end 0.120396 0.2794)
			(stroke
				(width 0.1)
				(type default)
			)
			(layer "F.Fab")
		)
		(fp_line
			(start 0.12065 -0.3048)
			(end 0.67945 -0.3048)
			(stroke
				(width 0.1)
				(type default)
			)
			(layer "F.Fab")
		)
		(fp_line
			(start 0.12065 -0.2794)
			(end 0.12065 -0.3048)
			(stroke
				(width 0.1)
				(type default)
			)
			(layer "F.Fab")
		)
		(fp_line
			(start 0.67945 -0.3048)
			(end 0.67945 0.3048)
			(stroke
				(width 0.1)
				(type default)
			)
			(layer "F.Fab")
		)
		(fp_line
			(start 0.67945 0.3048)
			(end 0.120396 0.3048)
			(stroke
				(width 0.1)
				(type default)
			)
			(layer "F.Fab")
		)
		(pad "1" smd circle
			(at -0.40005 0)
			(size 0 0)
			(layers "F.Cu" "F.Mask" "F.Paste")
			(net "P3V3_AUX")
		)
		(pad "2" smd circle
			(at 0.40005 0)
			(size 0 0)
			(layers "F.Cu" "F.Mask" "F.Paste")
			(net "OCP_SFF_PRSNT0_R_N")
		)
	)
	(footprint ""
		(layer "F.Cu")
		(at 180.721 -100.294948 90)
		(property "Reference" "R189"
			(at 0 0 90)
			(layer "F.SilkS")
			(hide yes)
			(effects
				(font
					(size 1.27 1.27)
				)
			)
		)
		(property "Value" ""
			(at 0 0 90)
			(layer "F.Fab")
			(effects
				(font
					(size 1.27 1.27)
				)
			)
		)
		(duplicate_pad_numbers_are_jumpers no)
		(fp_line
			(start 0.7874 -0.4064)
			(end 0.7874 0.4064)
			(stroke
				(width 0.1524)
				(type default)
			)
			(layer "F.SilkS")
		)
		(fp_line
			(start -0.7874 -0.4064)
			(end 0.7874 -0.4064)
			(stroke
				(width 0.1524)
				(type default)
			)
			(layer "F.SilkS")
		)
		(fp_line
			(start 0.7874 0.4064)
			(end -0.7874 0.4064)
			(stroke
				(width 0.1524)
				(type default)
			)
			(layer "F.SilkS")
		)
		(fp_line
			(start -0.7874 0.4064)
			(end -0.7874 -0.4064)
			(stroke
				(width 0.1524)
				(type default)
			)
			(layer "F.SilkS")
		)
		(fp_line
			(start -0.12065 -0.305054)
			(end -0.12065 -0.2794)
			(stroke
				(width 0.1)
				(type default)
			)
			(layer "F.Fab")
		)
		(fp_line
			(start -0.67945 -0.305054)
			(end -0.12065 -0.305054)
			(stroke
				(width 0.1)
				(type default)
			)
			(layer "F.Fab")
		)
		(fp_line
			(start 0.67945 -0.3048)
			(end 0.67945 0.3048)
			(stroke
				(width 0.1)
				(type default)
			)
			(layer "F.Fab")
		)
		(fp_line
			(start 0.12065 -0.3048)
			(end 0.67945 -0.3048)
			(stroke
				(width 0.1)
				(type default)
			)
			(layer "F.Fab")
		)
		(fp_line
			(start 0.12065 -0.2794)
			(end 0.12065 -0.3048)
			(stroke
				(width 0.1)
				(type default)
			)
			(layer "F.Fab")
		)
		(fp_line
			(start -0.12065 -0.2794)
			(end 0.12065 -0.2794)
			(stroke
				(width 0.1)
				(type default)
			)
			(layer "F.Fab")
		)
		(fp_line
			(start 0.120396 0.2794)
			(end -0.12065 0.2794)
			(stroke
				(width 0.1)
				(type default)
			)
			(layer "F.Fab")
		)
		(fp_line
			(start -0.12065 0.2794)
			(end -0.12065 0.3048)
			(stroke
				(width 0.1)
				(type default)
			)
			(layer "F.Fab")
		)
		(fp_line
			(start 0.67945 0.3048)
			(end 0.120396 0.3048)
			(stroke
				(width 0.1)
				(type default)
			)
			(layer "F.Fab")
		)
		(fp_line
			(start 0.120396 0.3048)
			(end 0.120396 0.2794)
			(stroke
				(width 0.1)
				(type default)
			)
			(layer "F.Fab")
		)
		(fp_line
			(start -0.12065 0.3048)
			(end -0.67945 0.3048)
			(stroke
				(width 0.1)
				(type default)
			)
			(layer "F.Fab")
		)
		(fp_line
			(start -0.67945 0.3048)
			(end -0.67945 -0.305054)
			(stroke
				(width 0.1)
				(type default)
			)
			(layer "F.Fab")
		)
		(pad "1" smd circle
			(at -0.40005 0 90)
			(size 0 0)
			(layers "F.Cu" "F.Mask" "F.Paste")
			(net "FM_BMC_TPM_PRES_N")
		)
		(pad "2" smd circle
			(at 0.40005 0 90)
			(size 0 0)
			(layers "F.Cu" "F.Mask" "F.Paste")
			(net "FM_BMC_TPM_PRES_N_R")
		)
	)
	(footprint ""
		(layer "F.Cu")
		(at 374.598692 -378.95403 -90)
		(property "Reference" "C889"
			(at 0 0 270)
			(layer "F.SilkS")
			(hide yes)
			(effects
				(font
					(size 1.27 1.27)
				)
			)
		)
		(property "Value" ""
			(at 0 0 270)
			(layer "F.Fab")
			(effects
				(font
					(size 1.27 1.27)
				)
			)
		)
		(duplicate_pad_numbers_are_jumpers no)
		(fp_line
			(start -0.299974 0.150114)
			(end -0.299974 -0.150114)
			(stroke
				(width 0.1)
				(type default)
			)
			(layer "F.Fab")
		)
		(fp_line
			(start 0.299974 0.150114)
			(end -0.299974 0.150114)
			(stroke
				(width 0.1)
				(type default)
			)
			(layer "F.Fab")
		)
		(fp_line
			(start -0.299974 -0.150114)
			(end 0.299974 -0.150114)
			(stroke
				(width 0.1)
				(type default)
			)
			(layer "F.Fab")
		)
		(fp_line
			(start 0.299974 -0.150114)
			(end 0.299974 0.150114)
			(stroke
				(width 0.1)
				(type default)
			)
			(layer "F.Fab")
		)
		(pad "1" smd rect
			(at -0.2667 0 270)
			(size 0.3048 0.381)
			(layers "F.Cu" "F.Mask" "F.Paste")
			(net "P5E_CPU0_P3_TX_C_DP<6>")
		)
		(pad "2" smd rect
			(at 0.2667 0 270)
			(size 0.3048 0.381)
			(layers "F.Cu" "F.Mask" "F.Paste")
			(net "P5E_CPU0_P3_TX_DP<6>")
		)
	)
	(footprint ""
		(layer "F.Cu")
		(at 39.842694 -423.21734)
		(property "Reference" "R6155"
			(at 0 0 0)
			(layer "F.SilkS")
			(hide yes)
			(effects
				(font
					(size 1.27 1.27)
				)
			)
		)
		(property "Value" ""
			(at 0 0 0)
			(layer "F.Fab")
			(effects
				(font
					(size 1.27 1.27)
				)
			)
		)
		(duplicate_pad_numbers_are_jumpers no)
		(fp_line
			(start -0.32512 -0.175006)
			(end 0.32512 -0.175006)
			(stroke
				(width 0.1)
				(type default)
			)
			(layer "F.Fab")
		)
		(fp_line
			(start -0.32512 0.175006)
			(end -0.32512 -0.175006)
			(stroke
				(width 0.1)
				(type default)
			)
			(layer "F.Fab")
		)
		(fp_line
			(start 0.32512 -0.175006)
			(end 0.32512 0.175006)
			(stroke
				(width 0.1)
				(type default)
			)
			(layer "F.Fab")
		)
		(fp_line
			(start 0.32512 0.175006)
			(end -0.32512 0.175006)
			(stroke
				(width 0.1)
				(type default)
			)
			(layer "F.Fab")
		)
		(pad "1" smd rect
			(at -0.2667 0)
			(size 0.3048 0.381)
			(layers "F.Cu" "F.Mask" "F.Paste")
			(net "P2E_MB_BMC_TX_C_DN<0>")
		)
		(pad "2" smd rect
			(at 0.2667 0 180)
			(size 0.3048 0.381)
			(layers "F.Cu" "F.Mask" "F.Paste")
			(net "P2E_MB_BMC_TX_C_R2_DN<0>")
		)
	)
	(footprint ""
		(layer "F.Cu")
		(at 222.738442 -315.95568 90)
		(property "Reference" "PC6533"
			(at 0 0 90)
			(layer "F.SilkS")
			(hide yes)
			(effects
				(font
					(size 1.27 1.27)
				)
			)
		)
		(property "Value" ""
			(at 0 0 90)
			(layer "F.Fab")
			(effects
				(font
					(size 1.27 1.27)
				)
			)
		)
		(duplicate_pad_numbers_are_jumpers no)
		(fp_line
			(start 0.7874 -0.4064)
			(end 0.7874 0.4064)
			(stroke
				(width 0.1524)
				(type default)
			)
			(layer "F.SilkS")
		)
		(fp_line
			(start -0.7874 -0.4064)
			(end 0.7874 -0.4064)
			(stroke
				(width 0.1524)
				(type default)
			)
			(layer "F.SilkS")
		)
		(fp_line
			(start 0.7874 0.4064)
			(end -0.7874 0.4064)
			(stroke
				(width 0.1524)
				(type default)
			)
			(layer "F.SilkS")
		)
		(fp_line
			(start -0.7874 0.4064)
			(end -0.7874 -0.4064)
			(stroke
				(width 0.1524)
				(type default)
			)
			(layer "F.SilkS")
		)
		(fp_line
			(start -0.12065 -0.305054)
			(end -0.12065 -0.2794)
			(stroke
				(width 0.1)
				(type default)
			)
			(layer "F.Fab")
		)
		(fp_line
			(start -0.67945 -0.305054)
			(end -0.12065 -0.305054)
			(stroke
				(width 0.1)
				(type default)
			)
			(layer "F.Fab")
		)
		(fp_line
			(start 0.67945 -0.3048)
			(end 0.67945 0.3048)
			(stroke
				(width 0.1)
				(type default)
			)
			(layer "F.Fab")
		)
		(fp_line
			(start 0.12065 -0.3048)
			(end 0.67945 -0.3048)
			(stroke
				(width 0.1)
				(type default)
			)
			(layer "F.Fab")
		)
		(fp_line
			(start 0.12065 -0.2794)
			(end 0.12065 -0.3048)
			(stroke
				(width 0.1)
				(type default)
			)
			(layer "F.Fab")
		)
		(fp_line
			(start -0.12065 -0.2794)
			(end 0.12065 -0.2794)
			(stroke
				(width 0.1)
				(type default)
			)
			(layer "F.Fab")
		)
		(fp_line
			(start 0.120396 0.2794)
			(end -0.12065 0.2794)
			(stroke
				(width 0.1)
				(type default)
			)
			(layer "F.Fab")
		)
		(fp_line
			(start -0.12065 0.2794)
			(end -0.12065 0.3048)
			(stroke
				(width 0.1)
				(type default)
			)
			(layer "F.Fab")
		)
		(fp_line
			(start 0.67945 0.3048)
			(end 0.120396 0.3048)
			(stroke
				(width 0.1)
				(type default)
			)
			(layer "F.Fab")
		)
		(fp_line
			(start 0.120396 0.3048)
			(end 0.120396 0.2794)
			(stroke
				(width 0.1)
				(type default)
			)
			(layer "F.Fab")
		)
		(fp_line
			(start -0.12065 0.3048)
			(end -0.67945 0.3048)
			(stroke
				(width 0.1)
				(type default)
			)
			(layer "F.Fab")
		)
		(fp_line
			(start -0.67945 0.3048)
			(end -0.67945 -0.305054)
			(stroke
				(width 0.1)
				(type default)
			)
			(layer "F.Fab")
		)
		(pad "1" smd circle
			(at -0.40005 0 90)
			(size 0 0)
			(layers "F.Cu" "F.Mask" "F.Paste")
			(net "P1V8_CPU1_RT_1D")
		)
		(pad "2" smd circle
			(at 0.40005 0 90)
			(size 0 0)
			(layers "F.Cu" "F.Mask" "F.Paste")
			(net "GND")
		)
	)
	(footprint ""
		(layer "F.Cu")
		(at 80.223106 -58.890154 180)
		(property "Reference" "R3570"
			(at 0 0 180)
			(layer "F.SilkS")
			(hide yes)
			(effects
				(font
					(size 1.27 1.27)
				)
			)
		)
		(property "Value" ""
			(at 0 0 180)
			(layer "F.Fab")
			(effects
				(font
					(size 1.27 1.27)
				)
			)
		)
		(duplicate_pad_numbers_are_jumpers no)
		(fp_line
			(start 0.7874 0.4064)
			(end -0.7874 0.4064)
			(stroke
				(width 0.1524)
				(type default)
			)
			(layer "F.SilkS")
		)
		(fp_line
			(start 0.7874 -0.4064)
			(end 0.7874 0.4064)
			(stroke
				(width 0.1524)
				(type default)
			)
			(layer "F.SilkS")
		)
		(fp_line
			(start -0.7874 0.4064)
			(end -0.7874 -0.4064)
			(stroke
				(width 0.1524)
				(type default)
			)
			(layer "F.SilkS")
		)
		(fp_line
			(start -0.7874 -0.4064)
			(end 0.7874 -0.4064)
			(stroke
				(width 0.1524)
				(type default)
			)
			(layer "F.SilkS")
		)
		(fp_line
			(start 0.67945 0.3048)
			(end 0.120396 0.3048)
			(stroke
				(width 0.1)
				(type default)
			)
			(layer "F.Fab")
		)
		(fp_line
			(start 0.67945 -0.3048)
			(end 0.67945 0.3048)
			(stroke
				(width 0.1)
				(type default)
			)
			(layer "F.Fab")
		)
		(fp_line
			(start 0.12065 -0.2794)
			(end 0.12065 -0.3048)
			(stroke
				(width 0.1)
				(type default)
			)
			(layer "F.Fab")
		)
		(fp_line
			(start 0.12065 -0.3048)
			(end 0.67945 -0.3048)
			(stroke
				(width 0.1)
				(type default)
			)
			(layer "F.Fab")
		)
		(fp_line
			(start 0.120396 0.3048)
			(end 0.120396 0.2794)
			(stroke
				(width 0.1)
				(type default)
			)
			(layer "F.Fab")
		)
		(fp_line
			(start 0.120396 0.2794)
			(end -0.12065 0.2794)
			(stroke
				(width 0.1)
				(type default)
			)
			(layer "F.Fab")
		)
		(fp_line
			(start -0.12065 0.3048)
			(end -0.67945 0.3048)
			(stroke
				(width 0.1)
				(type default)
			)
			(layer "F.Fab")
		)
		(fp_line
			(start -0.12065 0.2794)
			(end -0.12065 0.3048)
			(stroke
				(width 0.1)
				(type default)
			)
			(layer "F.Fab")
		)
		(fp_line
			(start -0.12065 -0.2794)
			(end 0.12065 -0.2794)
			(stroke
				(width 0.1)
				(type default)
			)
			(layer "F.Fab")
		)
		(fp_line
			(start -0.12065 -0.305054)
			(end -0.12065 -0.2794)
			(stroke
				(width 0.1)
				(type default)
			)
			(layer "F.Fab")
		)
		(fp_line
			(start -0.67945 0.3048)
			(end -0.67945 -0.305054)
			(stroke
				(width 0.1)
				(type default)
			)
			(layer "F.Fab")
		)
		(fp_line
			(start -0.67945 -0.305054)
			(end -0.12065 -0.305054)
			(stroke
				(width 0.1)
				(type default)
			)
			(layer "F.Fab")
		)
		(pad "1" smd circle
			(at -0.40005 0 180)
			(size 0 0)
			(layers "F.Cu" "F.Mask" "F.Paste")
			(net "P3V3_OCP_V3_2_R")
		)
		(pad "2" smd circle
			(at 0.40005 0 180)
			(size 0 0)
			(layers "F.Cu" "F.Mask" "F.Paste")
			(net "VSENSE_P12V_INA230_3_INP")
		)
	)
	(footprint ""
		(layer "F.Cu")
		(at 160.817306 -408.517344 -90)
		(property "Reference" "C6724"
			(at 0 0 270)
			(layer "F.SilkS")
			(hide yes)
			(effects
				(font
					(size 1.27 1.27)
				)
			)
		)
		(property "Value" ""
			(at 0 0 270)
			(layer "F.Fab")
			(effects
				(font
					(size 1.27 1.27)
				)
			)
		)
		(duplicate_pad_numbers_are_jumpers no)
		(fp_line
			(start -0.299974 0.150114)
			(end -0.299974 -0.150114)
			(stroke
				(width 0.1)
				(type default)
			)
			(layer "F.Fab")
		)
		(fp_line
			(start 0.299974 0.150114)
			(end -0.299974 0.150114)
			(stroke
				(width 0.1)
				(type default)
			)
			(layer "F.Fab")
		)
		(fp_line
			(start -0.299974 -0.150114)
			(end 0.299974 -0.150114)
			(stroke
				(width 0.1)
				(type default)
			)
			(layer "F.Fab")
		)
		(fp_line
			(start 0.299974 -0.150114)
			(end 0.299974 0.150114)
			(stroke
				(width 0.1)
				(type default)
			)
			(layer "F.Fab")
		)
		(pad "1" smd rect
			(at -0.2667 0 270)
			(size 0.3048 0.381)
			(layers "F.Cu" "F.Mask" "F.Paste")
			(net "P5E_CPU1_P2_TX_BUF_C_DN<15>")
		)
		(pad "2" smd rect
			(at 0.2667 0 270)
			(size 0.3048 0.381)
			(layers "F.Cu" "F.Mask" "F.Paste")
			(net "P5E_CPU1_P2_TX_BUF_DN<15>")
		)
	)
	(footprint ""
		(layer "F.Cu")
		(at 310.134 -360.68 -90)
		(property "Reference" "PU12"
			(at -6.05409 1.856232 0)
			(unlocked yes)
			(layer "F.SilkS")
			(effects
				(font
					(size 0.7874 0.5842)
					(thickness 0.1524)
				)
			)
		)
		(property "Value" ""
			(at 0 0 270)
			(layer "F.Fab")
			(effects
				(font
					(size 1.27 1.27)
				)
			)
		)
		(duplicate_pad_numbers_are_jumpers no)
		(fp_line
			(start -3.024886 3.024886)
			(end -3.024886 2.428494)
			(stroke
				(width 0.1524)
				(type default)
			)
			(layer "F.SilkS")
		)
		(fp_line
			(start -2.428494 3.024886)
			(end -3.024886 3.024886)
			(stroke
				(width 0.1524)
				(type default)
			)
			(layer "F.SilkS")
		)
		(fp_line
			(start 3.024886 3.024886)
			(end 2.428494 3.024886)
			(stroke
				(width 0.1524)
				(type default)
			)
			(layer "F.SilkS")
		)
		(fp_line
			(start 3.024886 2.428494)
			(end 3.024886 3.024886)
			(stroke
				(width 0.1524)
				(type default)
			)
			(layer "F.SilkS")
		)
		(fp_line
			(start -3.024886 -2.428494)
			(end -3.024886 -3.024886)
			(stroke
				(width 0.1524)
				(type default)
			)
			(layer "F.SilkS")
		)
		(fp_line
			(start -3.024886 -3.024886)
			(end -2.428494 -3.024886)
			(stroke
				(width 0.1524)
				(type default)
			)
			(layer "F.SilkS")
		)
		(fp_line
			(start 2.428494 -3.024886)
			(end 3.024886 -3.024886)
			(stroke
				(width 0.1524)
				(type default)
			)
			(layer "F.SilkS")
		)
		(fp_line
			(start 3.024886 -3.024886)
			(end 3.024886 -2.428494)
			(stroke
				(width 0.1524)
				(type default)
			)
			(layer "F.SilkS")
		)
		(fp_poly
			(pts
				(xy -4.832096 -2.695448) (xy -4.832096 -1.679448) (xy -3.816096 -2.187448)
			)
			(stroke
				(width 0)
				(type default)
			)
			(fill yes)
			(layer "F.SilkS")
		)
		(fp_line
			(start -3.024886 3.024886)
			(end -3.024886 -3.024886)
			(stroke
				(width 0.1)
				(type default)
			)
			(layer "F.Fab")
		)
		(fp_line
			(start 3.024886 3.024886)
			(end -3.024886 3.024886)
			(stroke
				(width 0.1)
				(type default)
			)
			(layer "F.Fab")
		)
		(fp_line
			(start -3.024886 -3.024886)
			(end 3.024886 -3.024886)
			(stroke
				(width 0.1)
				(type default)
			)
			(layer "F.Fab")
		)
		(fp_line
			(start 3.024886 -3.024886)
			(end 3.024886 3.024886)
			(stroke
				(width 0.1)
				(type default)
			)
			(layer "F.Fab")
		)
		(fp_poly
			(pts
				(xy -3.332226 -2.199894) (xy -4.348226 -1.691894) (xy -4.348226 -2.707894)
			)
			(stroke
				(width 0)
				(type default)
			)
			(fill yes)
			(layer "F.Fab")
		)
		(pad "1" smd rect
			(at -2.875026 -2.199894 180)
			(size 0.1778 0.6604)
			(layers "F.Cu" "F.Mask" "F.Paste")
			(net "PVDDIO_P0_PWM1")
		)
		(pad "2" smd rect
			(at -2.875026 -1.800098 180)
			(size 0.1778 0.6604)
			(layers "F.Cu" "F.Mask" "F.Paste")
			(net "PVDDIO_P0_PWM2")
		)
		(pad "3" smd rect
			(at -2.875026 -1.400048 180)
			(size 0.1778 0.6604)
			(layers "F.Cu" "F.Mask" "F.Paste")
			(net "PVDDIO_P0_PWM3")
		)
		(pad "4" smd rect
			(at -2.875026 -0.999998 180)
			(size 0.1778 0.6604)
			(layers "F.Cu" "F.Mask" "F.Paste")
			(net "PVDDIO_P0_PWM4")
		)
		(pad "5" smd rect
			(at -2.875026 -0.599948 180)
			(size 0.1778 0.6604)
			(layers "F.Cu" "F.Mask" "F.Paste")
			(net "NC_PVDDCR_CPU1_P0_PWM8")
		)
		(pad "6" smd rect
			(at -2.875026 -0.199898 180)
			(size 0.1778 0.6604)
			(layers "F.Cu" "F.Mask" "F.Paste")
			(net "NC_PVDDCR_CPU1_P0_PWM7")
		)
		(pad "7" smd rect
			(at -2.875026 0.199898 180)
			(size 0.1778 0.6604)
			(layers "F.Cu" "F.Mask" "F.Paste")
			(net "PVDDCR_CPU1_P0_PWM6")
		)
		(pad "8" smd rect
			(at -2.875026 0.599948 180)
			(size 0.1778 0.6604)
			(layers "F.Cu" "F.Mask" "F.Paste")
			(net "PVDDCR_CPU1_P0_PWM5")
		)
		(pad "9" smd rect
			(at -2.875026 0.999998 180)
			(size 0.1778 0.6604)
			(layers "F.Cu" "F.Mask" "F.Paste")
			(net "PVDDCR_CPU1_P0_PWM4")
		)
		(pad "10" smd rect
			(at -2.875026 1.400048 180)
			(size 0.1778 0.6604)
			(layers "F.Cu" "F.Mask" "F.Paste")
			(net "PVDDCR_CPU1_P0_PWM3")
		)
		(pad "11" smd rect
			(at -2.875026 1.800098 180)
			(size 0.1778 0.6604)
			(layers "F.Cu" "F.Mask" "F.Paste")
			(net "PVDDCR_CPU1_P0_PWM2")
		)
		(pad "12" smd rect
			(at -2.875026 2.199894 180)
			(size 0.1778 0.6604)
			(layers "F.Cu" "F.Mask" "F.Paste")
			(net "PVDDCR_CPU1_P0_PWM1")
		)
		(pad "13" smd rect
			(at -2.199894 2.875026 270)
			(size 0.1778 0.6604)
			(layers "F.Cu" "F.Mask" "F.Paste")
			(net "SMB_DIO_PVDDCR_CPU1_P0_R")
		)
		(pad "14" smd rect
			(at -1.800098 2.875026 270)
			(size 0.1778 0.6604)
			(layers "F.Cu" "F.Mask" "F.Paste")
			(net "SMB_CLK_PVDDCR_CPU1_P0_R")
		)
		(pad "15" smd rect
			(at -1.400048 2.875026 270)
			(size 0.1778 0.6604)
			(layers "F.Cu" "F.Mask" "F.Paste")
			(net "PVDDCR_CPU1_P0_SMB_ALERT_R")
		)
		(pad "16" smd rect
			(at -0.999998 2.875026 270)
			(size 0.1778 0.6604)
			(layers "F.Cu" "F.Mask" "F.Paste")
			(net "PWRGD_PVDDCR_CPU1_P0_R")
		)
		(pad "17" smd rect
			(at -0.599948 2.875026 270)
			(size 0.1778 0.6604)
			(layers "F.Cu" "F.Mask" "F.Paste")
			(net "PVDDCR_CPU1_P0_EN_R")
		)
		(pad "18" smd rect
			(at -0.199898 2.875026 270)
			(size 0.1778 0.6604)
			(layers "F.Cu" "F.Mask" "F.Paste")
			(net "PVDDCR_CPU1_P0_RESET_N_R")
		)
		(pad "19" smd rect
			(at 0.199898 2.875026 270)
			(size 0.1778 0.6604)
			(layers "F.Cu" "F.Mask" "F.Paste")
			(net "PVDD18_S5_P0")
		)
		(pad "20" smd rect
			(at 0.599948 2.875026 270)
			(size 0.1778 0.6604)
			(layers "F.Cu" "F.Mask" "F.Paste")
			(net "PWRGD_PVDDIO_P0_R")
		)
		(pad "21" smd rect
			(at 0.999998 2.875026 270)
			(size 0.1778 0.6604)
			(layers "F.Cu" "F.Mask" "F.Paste")
			(net "SVID_PVDDCR_CPU1_P0_SVD_R1")
		)
		(pad "22" smd rect
			(at 1.400048 2.875026 270)
			(size 0.1778 0.6604)
			(layers "F.Cu" "F.Mask" "F.Paste")
			(net "SVID_PVDDCR_CPU1_P0_SVC_R1")
		)
		(pad "23" smd rect
			(at 1.800098 2.875026 270)
			(size 0.1778 0.6604)
			(layers "F.Cu" "F.Mask" "F.Paste")
			(net "SVID_PVDDCR_CPU1_P0_SVTO_R")
		)
		(pad "24" smd rect
			(at 2.199894 2.875026 270)
			(size 0.1778 0.6604)
			(layers "F.Cu" "F.Mask" "F.Paste")
			(net "SVID_PVDDCR_CPU1_P0_SVTI_R")
		)
		(pad "25" smd rect
			(at 2.875026 2.199894 180)
			(size 0.1778 0.6604)
			(layers "F.Cu" "F.Mask" "F.Paste")
			(net "VSENSE_PVDDCR_CPU1_P0_VSEN0")
		)
		(pad "26" smd rect
			(at 2.875026 1.800098 180)
			(size 0.1778 0.6604)
			(layers "F.Cu" "F.Mask" "F.Paste")
			(net "VSENSE_VSS_SENSE_C_P0")
		)
		(pad "27" smd rect
			(at 2.875026 1.400048 180)
			(size 0.1778 0.6604)
			(layers "F.Cu" "F.Mask" "F.Paste")
			(net "PVDDCR_CPU1_P0_IMON1")
		)
		(pad "28" smd rect
			(at 2.875026 0.999998 180)
			(size 0.1778 0.6604)
			(layers "F.Cu" "F.Mask" "F.Paste")
			(net "PVDDCR_CPU1_P0_IMON2")
		)
		(pad "29" smd rect
			(at 2.875026 0.599948 180)
			(size 0.1778 0.6604)
			(layers "F.Cu" "F.Mask" "F.Paste")
			(net "PVDDCR_CPU1_P0_IMON3")
		)
		(pad "30" smd rect
			(at 2.875026 0.199898 180)
			(size 0.1778 0.6604)
			(layers "F.Cu" "F.Mask" "F.Paste")
			(net "PVDDCR_CPU1_P0_IMON4")
		)
		(pad "31" smd rect
			(at 2.875026 -0.199898 180)
			(size 0.1778 0.6604)
			(layers "F.Cu" "F.Mask" "F.Paste")
			(net "PVDDCR_CPU1_P0_IMON5")
		)
		(pad "32" smd rect
			(at 2.875026 -0.599948 180)
			(size 0.1778 0.6604)
			(layers "F.Cu" "F.Mask" "F.Paste")
			(net "PVDDCR_CPU1_P0_IMON6")
		)
		(pad "33" smd rect
			(at 2.875026 -0.999998 180)
			(size 0.1778 0.6604)
			(layers "F.Cu" "F.Mask" "F.Paste")
			(net "NC_PVDDCR_CPU1_P0_IMON7")
		)
		(pad "34" smd rect
			(at 2.875026 -1.400048 180)
			(size 0.1778 0.6604)
			(layers "F.Cu" "F.Mask" "F.Paste")
			(net "NC_PVDDCR_CPU1_P0_IMON8")
		)
		(pad "35" smd rect
			(at 2.875026 -1.800098 180)
			(size 0.1778 0.6604)
			(layers "F.Cu" "F.Mask" "F.Paste")
			(net "PVDDIO_P0_IMON4")
		)
		(pad "36" smd rect
			(at 2.875026 -2.199894 180)
			(size 0.1778 0.6604)
			(layers "F.Cu" "F.Mask" "F.Paste")
			(net "PVDDIO_P0_IMON3")
		)
		(pad "37" smd rect
			(at 2.199894 -2.875026 270)
			(size 0.1778 0.6604)
			(layers "F.Cu" "F.Mask" "F.Paste")
			(net "PVDDIO_P0_IMON2")
		)
		(pad "38" smd rect
			(at 1.800098 -2.875026 270)
			(size 0.1778 0.6604)
			(layers "F.Cu" "F.Mask" "F.Paste")
			(net "PVDDIO_P0_IMON1")
		)
		(pad "39" smd rect
			(at 1.400048 -2.875026 270)
			(size 0.1778 0.6604)
			(layers "F.Cu" "F.Mask" "F.Paste")
			(net "VSENSE_VSS_SENSE_B_P0")
		)
		(pad "40" smd rect
			(at 0.999998 -2.875026 270)
			(size 0.1778 0.6604)
			(layers "F.Cu" "F.Mask" "F.Paste")
			(net "VSENSE_PVDDIO_P0_VSEN1")
		)
		(pad "41" smd rect
			(at 0.599948 -2.875026 270)
			(size 0.1778 0.6604)
			(layers "F.Cu" "F.Mask" "F.Paste")
			(net "PVDDCR_CPU1_P0_OCP_N_R")
		)
		(pad "42" smd rect
			(at 0.199898 -2.875026 270)
			(size 0.1778 0.6604)
			(layers "F.Cu" "F.Mask" "F.Paste")
			(net "PVDDCR_CPU1_P0_EN1_ADDR_CFG")
		)
		(pad "43" smd rect
			(at -0.199898 -2.875026 270)
			(size 0.1778 0.6604)
			(layers "F.Cu" "F.Mask" "F.Paste")
			(net "PVDDIO_P0_TEMP1")
		)
		(pad "44" smd rect
			(at -0.599948 -2.875026 270)
			(size 0.1778 0.6604)
			(layers "F.Cu" "F.Mask" "F.Paste")
			(net "PVDDCR_CPU1_P0_TEMP0")
		)
		(pad "45" smd rect
			(at -0.999998 -2.875026 270)
			(size 0.1778 0.6604)
			(layers "F.Cu" "F.Mask" "F.Paste")
			(net "PVDDCR_CPU1_P0_VMON")
		)
		(pad "46" smd rect
			(at -1.400048 -2.875026 270)
			(size 0.1778 0.6604)
			(layers "F.Cu" "F.Mask" "F.Paste")
			(net "PVDDCR_CPU1_P0_VINSEN")
		)
		(pad "47" smd rect
			(at -1.800098 -2.875026 270)
			(size 0.1778 0.6604)
			(layers "F.Cu" "F.Mask" "F.Paste")
			(net "PVDDCR_CPU1_P0_VCC")
		)
		(pad "48" smd rect
			(at -2.199894 -2.875026 270)
			(size 0.1778 0.6604)
			(layers "F.Cu" "F.Mask" "F.Paste")
			(net "PVDDCR_CPU1_P0_VCCS")
		)
		(pad "TH" smd rect
			(at 0 0 270)
			(size 4.4196 4.4196)
			(layers "F.Cu" "F.Mask" "F.Paste")
			(net "GND")
		)
		(zone
			(layer "F.Cu")
			(hatch none 0.5)
			(connect_pads
				(clearance 0)
			)
			(min_thickness 0.25)
			(keepout
				(tracks not_allowed)
				(vias allowed)
				(pads allowed)
				(copperpour not_allowed)
				(footprints allowed)
			)
			(placement
				(enabled no)
				(sheetname "")
			)
			(fill
				(thermal_gap 0.5)
				(thermal_bridge_width 0.5)
				(island_removal_mode 0)
			)
			(polygon
				(pts
					(xy 310.1594 -363.174026) (xy 312.628026 -363.174026) (xy 312.628026 -358.185974) (xy 307.639974 -358.185974)
					(xy 307.639974 -363.174026) (xy 310.134 -363.174026) (xy 310.134 -362.9406) (xy 307.8734 -362.9406)
					(xy 307.8734 -358.4194) (xy 312.3946 -358.4194) (xy 312.3946 -362.9406) (xy 310.1594 -362.9406)
				)
			)
		)
	)
	(footprint ""
		(layer "F.Cu")
		(at 140.02512 -31.62681 -90)
		(property "Reference" "C6016"
			(at 0 0 270)
			(layer "F.SilkS")
			(hide yes)
			(effects
				(font
					(size 1.27 1.27)
				)
			)
		)
		(property "Value" ""
			(at 0 0 270)
			(layer "F.Fab")
			(effects
				(font
					(size 1.27 1.27)
				)
			)
		)
		(duplicate_pad_numbers_are_jumpers no)
		(fp_line
			(start 0.40005 0.4064)
			(end -0.40005 0.4064)
			(stroke
				(width 0.1524)
				(type default)
			)
			(layer "F.SilkS")
		)
		(fp_line
			(start -0.6858 0.3048)
			(end -0.6858 -0.3048)
			(stroke
				(width 0.1)
				(type default)
			)
			(layer "F.Fab")
		)
		(fp_line
			(start -0.1016 0.3048)
			(end -0.6858 0.3048)
			(stroke
				(width 0.1)
				(type default)
			)
			(layer "F.Fab")
		)
		(fp_line
			(start 0.1016 0.3048)
			(end 0.1016 0.2794)
			(stroke
				(width 0.1)
				(type default)
			)
			(layer "F.Fab")
		)
		(fp_line
			(start 0.6858 0.3048)
			(end 0.1016 0.3048)
			(stroke
				(width 0.1)
				(type default)
			)
			(layer "F.Fab")
		)
		(fp_line
			(start -0.1016 0.2794)
			(end -0.1016 0.3048)
			(stroke
				(width 0.1)
				(type default)
			)
			(layer "F.Fab")
		)
		(fp_line
			(start 0.1016 0.2794)
			(end -0.1016 0.2794)
			(stroke
				(width 0.1)
				(type default)
			)
			(layer "F.Fab")
		)
		(fp_line
			(start -0.1016 -0.2794)
			(end 0.1016 -0.2794)
			(stroke
				(width 0.1)
				(type default)
			)
			(layer "F.Fab")
		)
		(fp_line
			(start 0.1016 -0.2794)
			(end 0.1016 -0.3048)
			(stroke
				(width 0.1)
				(type default)
			)
			(layer "F.Fab")
		)
		(fp_line
			(start -0.6858 -0.3048)
			(end -0.1016 -0.3048)
			(stroke
				(width 0.1)
				(type default)
			)
			(layer "F.Fab")
		)
		(fp_line
			(start -0.1016 -0.3048)
			(end -0.1016 -0.2794)
			(stroke
				(width 0.1)
				(type default)
			)
			(layer "F.Fab")
		)
		(fp_line
			(start 0.1016 -0.3048)
			(end 0.6858 -0.3048)
			(stroke
				(width 0.1)
				(type default)
			)
			(layer "F.Fab")
		)
		(fp_line
			(start 0.6858 -0.3048)
			(end 0.6858 0.3048)
			(stroke
				(width 0.1)
				(type default)
			)
			(layer "F.Fab")
		)
		(pad "1" smd rect
			(at -0.40005 0 90)
			(size 0.4572 0.508)
			(layers "F.Cu" "F.Mask" "F.Paste")
			(net "USB3_CPU0_BMC_RX_HUB1_DN")
		)
		(pad "2" smd rect
			(at 0.40005 0 90)
			(size 0.4572 0.508)
			(layers "F.Cu" "F.Mask" "F.Paste")
			(net "USB3_CPU0_BMC_RX_HUB_C_DN")
		)
	)
	(footprint ""
		(layer "F.Cu")
		(at 93.996256 -61.248544 90)
		(property "Reference" "PR3829"
			(at 0 0 90)
			(layer "F.SilkS")
			(hide yes)
			(effects
				(font
					(size 1.27 1.27)
				)
			)
		)
		(property "Value" ""
			(at 0 0 90)
			(layer "F.Fab")
			(effects
				(font
					(size 1.27 1.27)
				)
			)
		)
		(duplicate_pad_numbers_are_jumpers no)
		(fp_line
			(start 0.7874 -0.4064)
			(end 0.7874 0.4064)
			(stroke
				(width 0.1524)
				(type default)
			)
			(layer "F.SilkS")
		)
		(fp_line
			(start -0.7874 -0.4064)
			(end 0.7874 -0.4064)
			(stroke
				(width 0.1524)
				(type default)
			)
			(layer "F.SilkS")
		)
		(fp_line
			(start 0.7874 0.4064)
			(end -0.7874 0.4064)
			(stroke
				(width 0.1524)
				(type default)
			)
			(layer "F.SilkS")
		)
		(fp_line
			(start -0.7874 0.4064)
			(end -0.7874 -0.4064)
			(stroke
				(width 0.1524)
				(type default)
			)
			(layer "F.SilkS")
		)
		(fp_line
			(start -0.12065 -0.305054)
			(end -0.12065 -0.2794)
			(stroke
				(width 0.1)
				(type default)
			)
			(layer "F.Fab")
		)
		(fp_line
			(start -0.67945 -0.305054)
			(end -0.12065 -0.305054)
			(stroke
				(width 0.1)
				(type default)
			)
			(layer "F.Fab")
		)
		(fp_line
			(start 0.67945 -0.3048)
			(end 0.67945 0.3048)
			(stroke
				(width 0.1)
				(type default)
			)
			(layer "F.Fab")
		)
		(fp_line
			(start 0.12065 -0.3048)
			(end 0.67945 -0.3048)
			(stroke
				(width 0.1)
				(type default)
			)
			(layer "F.Fab")
		)
		(fp_line
			(start 0.12065 -0.2794)
			(end 0.12065 -0.3048)
			(stroke
				(width 0.1)
				(type default)
			)
			(layer "F.Fab")
		)
		(fp_line
			(start -0.12065 -0.2794)
			(end 0.12065 -0.2794)
			(stroke
				(width 0.1)
				(type default)
			)
			(layer "F.Fab")
		)
		(fp_line
			(start 0.120396 0.2794)
			(end -0.12065 0.2794)
			(stroke
				(width 0.1)
				(type default)
			)
			(layer "F.Fab")
		)
		(fp_line
			(start -0.12065 0.2794)
			(end -0.12065 0.3048)
			(stroke
				(width 0.1)
				(type default)
			)
			(layer "F.Fab")
		)
		(fp_line
			(start 0.67945 0.3048)
			(end 0.120396 0.3048)
			(stroke
				(width 0.1)
				(type default)
			)
			(layer "F.Fab")
		)
		(fp_line
			(start 0.120396 0.3048)
			(end 0.120396 0.2794)
			(stroke
				(width 0.1)
				(type default)
			)
			(layer "F.Fab")
		)
		(fp_line
			(start -0.12065 0.3048)
			(end -0.67945 0.3048)
			(stroke
				(width 0.1)
				(type default)
			)
			(layer "F.Fab")
		)
		(fp_line
			(start -0.67945 0.3048)
			(end -0.67945 -0.305054)
			(stroke
				(width 0.1)
				(type default)
			)
			(layer "F.Fab")
		)
		(pad "1" smd circle
			(at -0.40005 0 90)
			(size 0 0)
			(layers "F.Cu" "F.Mask" "F.Paste")
			(net "P3V3_OCP_UV_2")
		)
		(pad "2" smd circle
			(at 0.40005 0 90)
			(size 0 0)
			(layers "F.Cu" "F.Mask" "F.Paste")
			(net "P3V3_OCP_OV_2")
		)
	)
	(footprint ""
		(layer "F.Cu")
		(at 303.374298 -14.48181)
		(property "Reference" "R4197"
			(at 0 0 0)
			(layer "F.SilkS")
			(hide yes)
			(effects
				(font
					(size 1.27 1.27)
				)
			)
		)
		(property "Value" ""
			(at 0 0 0)
			(layer "F.Fab")
			(effects
				(font
					(size 1.27 1.27)
				)
			)
		)
		(duplicate_pad_numbers_are_jumpers no)
		(fp_line
			(start -0.7874 -0.4064)
			(end 0.7874 -0.4064)
			(stroke
				(width 0.1524)
				(type default)
			)
			(layer "F.SilkS")
		)
		(fp_line
			(start -0.7874 0.4064)
			(end -0.7874 -0.4064)
			(stroke
				(width 0.1524)
				(type default)
			)
			(layer "F.SilkS")
		)
		(fp_line
			(start 0.7874 -0.4064)
			(end 0.7874 0.4064)
			(stroke
				(width 0.1524)
				(type default)
			)
			(layer "F.SilkS")
		)
		(fp_line
			(start 0.7874 0.4064)
			(end -0.7874 0.4064)
			(stroke
				(width 0.1524)
				(type default)
			)
			(layer "F.SilkS")
		)
		(fp_line
			(start -0.67945 -0.305054)
			(end -0.12065 -0.305054)
			(stroke
				(width 0.1)
				(type default)
			)
			(layer "F.Fab")
		)
		(fp_line
			(start -0.67945 0.3048)
			(end -0.67945 -0.305054)
			(stroke
				(width 0.1)
				(type default)
			)
			(layer "F.Fab")
		)
		(fp_line
			(start -0.12065 -0.305054)
			(end -0.12065 -0.2794)
			(stroke
				(width 0.1)
				(type default)
			)
			(layer "F.Fab")
		)
		(fp_line
			(start -0.12065 -0.2794)
			(end 0.12065 -0.2794)
			(stroke
				(width 0.1)
				(type default)
			)
			(layer "F.Fab")
		)
		(fp_line
			(start -0.12065 0.2794)
			(end -0.12065 0.3048)
			(stroke
				(width 0.1)
				(type default)
			)
			(layer "F.Fab")
		)
		(fp_line
			(start -0.12065 0.3048)
			(end -0.67945 0.3048)
			(stroke
				(width 0.1)
				(type default)
			)
			(layer "F.Fab")
		)
		(fp_line
			(start 0.120396 0.2794)
			(end -0.12065 0.2794)
			(stroke
				(width 0.1)
				(type default)
			)
			(layer "F.Fab")
		)
		(fp_line
			(start 0.120396 0.3048)
			(end 0.120396 0.2794)
			(stroke
				(width 0.1)
				(type default)
			)
			(layer "F.Fab")
		)
		(fp_line
			(start 0.12065 -0.3048)
			(end 0.67945 -0.3048)
			(stroke
				(width 0.1)
				(type default)
			)
			(layer "F.Fab")
		)
		(fp_line
			(start 0.12065 -0.2794)
			(end 0.12065 -0.3048)
			(stroke
				(width 0.1)
				(type default)
			)
			(layer "F.Fab")
		)
		(fp_line
			(start 0.67945 -0.3048)
			(end 0.67945 0.3048)
			(stroke
				(width 0.1)
				(type default)
			)
			(layer "F.Fab")
		)
		(fp_line
			(start 0.67945 0.3048)
			(end 0.120396 0.3048)
			(stroke
				(width 0.1)
				(type default)
			)
			(layer "F.Fab")
		)
		(pad "1" smd circle
			(at -0.40005 0)
			(size 0 0)
			(layers "F.Cu" "F.Mask" "F.Paste")
			(net "U271_1_ADD1")
		)
		(pad "2" smd circle
			(at 0.40005 0)
			(size 0 0)
			(layers "F.Cu" "F.Mask" "F.Paste")
			(net "GND")
		)
	)
	(footprint ""
		(layer "F.Cu")
		(at 99.614736 -127.787654 -90)
		(property "Reference" "R1458"
			(at 0 0 270)
			(layer "F.SilkS")
			(hide yes)
			(effects
				(font
					(size 1.27 1.27)
				)
			)
		)
		(property "Value" ""
			(at 0 0 270)
			(layer "F.Fab")
			(effects
				(font
					(size 1.27 1.27)
				)
			)
		)
		(duplicate_pad_numbers_are_jumpers no)
		(fp_line
			(start -0.7874 0.4064)
			(end -0.7874 -0.4064)
			(stroke
				(width 0.1524)
				(type default)
			)
			(layer "F.SilkS")
		)
		(fp_line
			(start 0.7874 0.4064)
			(end -0.7874 0.4064)
			(stroke
				(width 0.1524)
				(type default)
			)
			(layer "F.SilkS")
		)
		(fp_line
			(start -0.7874 -0.4064)
			(end 0.7874 -0.4064)
			(stroke
				(width 0.1524)
				(type default)
			)
			(layer "F.SilkS")
		)
		(fp_line
			(start 0.7874 -0.4064)
			(end 0.7874 0.4064)
			(stroke
				(width 0.1524)
				(type default)
			)
			(layer "F.SilkS")
		)
		(fp_line
			(start -0.67945 0.3048)
			(end -0.67945 -0.305054)
			(stroke
				(width 0.1)
				(type default)
			)
			(layer "F.Fab")
		)
		(fp_line
			(start -0.12065 0.3048)
			(end -0.67945 0.3048)
			(stroke
				(width 0.1)
				(type default)
			)
			(layer "F.Fab")
		)
		(fp_line
			(start 0.120396 0.3048)
			(end 0.120396 0.2794)
			(stroke
				(width 0.1)
				(type default)
			)
			(layer "F.Fab")
		)
		(fp_line
			(start 0.67945 0.3048)
			(end 0.120396 0.3048)
			(stroke
				(width 0.1)
				(type default)
			)
			(layer "F.Fab")
		)
		(fp_line
			(start -0.12065 0.2794)
			(end -0.12065 0.3048)
			(stroke
				(width 0.1)
				(type default)
			)
			(layer "F.Fab")
		)
		(fp_line
			(start 0.120396 0.2794)
			(end -0.12065 0.2794)
			(stroke
				(width 0.1)
				(type default)
			)
			(layer "F.Fab")
		)
		(fp_line
			(start -0.12065 -0.2794)
			(end 0.12065 -0.2794)
			(stroke
				(width 0.1)
				(type default)
			)
			(layer "F.Fab")
		)
		(fp_line
			(start 0.12065 -0.2794)
			(end 0.12065 -0.3048)
			(stroke
				(width 0.1)
				(type default)
			)
			(layer "F.Fab")
		)
		(fp_line
			(start 0.12065 -0.3048)
			(end 0.67945 -0.3048)
			(stroke
				(width 0.1)
				(type default)
			)
			(layer "F.Fab")
		)
		(fp_line
			(start 0.67945 -0.3048)
			(end 0.67945 0.3048)
			(stroke
				(width 0.1)
				(type default)
			)
			(layer "F.Fab")
		)
		(fp_line
			(start -0.67945 -0.305054)
			(end -0.12065 -0.305054)
			(stroke
				(width 0.1)
				(type default)
			)
			(layer "F.Fab")
		)
		(fp_line
			(start -0.12065 -0.305054)
			(end -0.12065 -0.2794)
			(stroke
				(width 0.1)
				(type default)
			)
			(layer "F.Fab")
		)
		(pad "1" smd circle
			(at -0.40005 0 270)
			(size 0 0)
			(layers "F.Cu" "F.Mask" "F.Paste")
			(net "PWRGD_P12V_MEM_CPU0")
		)
		(pad "2" smd circle
			(at 0.40005 0 270)
			(size 0 0)
			(layers "F.Cu" "F.Mask" "F.Paste")
			(net "PWRGD_P12V_MEM_CPU0_R")
		)
	)
	(footprint ""
		(layer "F.Cu")
		(at 293.720012 -34.001964 -90)
		(property "Reference" "BT2"
			(at 5.553964 1.243076 0)
			(unlocked yes)
			(layer "F.SilkS")
			(effects
				(font
					(size 0.7874 0.5842)
					(thickness 0.1524)
				)
				(justify left)
			)
		)
		(property "Value" ""
			(at 0 0 270)
			(layer "F.Fab")
			(effects
				(font
					(size 1.27 1.27)
				)
			)
		)
		(duplicate_pad_numbers_are_jumpers no)
		(fp_line
			(start 3.666236 22.820122)
			(end -3.666236 22.820122)
			(stroke
				(width 0.1524)
				(type default)
			)
			(layer "F.SilkS")
		)
		(fp_line
			(start -4.012692 22.800056)
			(end -3.724148 22.800056)
			(stroke
				(width 0.1524)
				(type default)
			)
			(layer "F.SilkS")
		)
		(fp_line
			(start 3.724148 22.800056)
			(end 4.012692 22.800056)
			(stroke
				(width 0.1524)
				(type default)
			)
			(layer "F.SilkS")
		)
		(fp_line
			(start -3.800094 1.807464)
			(end -3.800094 -1.180084)
			(stroke
				(width 0.1524)
				(type default)
			)
			(layer "F.SilkS")
		)
		(fp_line
			(start 3.899916 1.737614)
			(end 3.899916 -1.260094)
			(stroke
				(width 0.1524)
				(type default)
			)
			(layer "F.SilkS")
		)
		(fp_line
			(start -3.800094 -1.180084)
			(end 3.800094 -1.180084)
			(stroke
				(width 0.1524)
				(type default)
			)
			(layer "F.SilkS")
		)
		(fp_line
			(start 3.800094 -1.180084)
			(end 3.800094 1.807464)
			(stroke
				(width 0.1524)
				(type default)
			)
			(layer "F.SilkS")
		)
		(fp_line
			(start -3.899916 -1.260094)
			(end -3.899916 1.737614)
			(stroke
				(width 0.1524)
				(type default)
			)
			(layer "F.SilkS")
		)
		(fp_line
			(start 3.899916 -1.260094)
			(end -3.899916 -1.260094)
			(stroke
				(width 0.1524)
				(type default)
			)
			(layer "F.SilkS")
		)
		(fp_arc
			(start -3.666236 22.820122)
			(mid -11.149833 12.361061)
			(end -3.800094 1.807464)
			(stroke
				(width 0.1524)
				(type default)
			)
			(layer "F.SilkS")
		)
		(fp_arc
			(start -4.012692 22.800056)
			(mid -11.249872 12.229778)
			(end -3.899916 1.737614)
			(stroke
				(width 0.1524)
				(type default)
			)
			(layer "F.SilkS")
		)
		(fp_arc
			(start 3.800094 1.807464)
			(mid 11.149895 12.361062)
			(end 3.666236 22.820122)
			(stroke
				(width 0.1524)
				(type default)
			)
			(layer "F.SilkS")
		)
		(fp_arc
			(start 3.899916 1.737614)
			(mid 11.249813 12.229779)
			(end 4.012692 22.800056)
			(stroke
				(width 0.1524)
				(type default)
			)
			(layer "F.SilkS")
		)
		(fp_line
			(start 3.666236 22.820122)
			(end -3.666236 22.820122)
			(stroke
				(width 0.1)
				(type default)
			)
			(layer "F.Fab")
		)
		(fp_line
			(start -3.800094 1.807464)
			(end -3.800094 -1.180084)
			(stroke
				(width 0.1)
				(type default)
			)
			(layer "F.Fab")
		)
		(fp_line
			(start -3.800094 -1.180084)
			(end 3.800094 -1.180084)
			(stroke
				(width 0.1)
				(type default)
			)
			(layer "F.Fab")
		)
		(fp_line
			(start 3.800094 -1.180084)
			(end 3.800094 1.807464)
			(stroke
				(width 0.1)
				(type default)
			)
			(layer "F.Fab")
		)
		(fp_arc
			(start -3.666236 22.820122)
			(mid -11.149833 12.361061)
			(end -3.800094 1.807464)
			(stroke
				(width 0.1)
				(type default)
			)
			(layer "F.Fab")
		)
		(fp_arc
			(start 3.800094 1.807464)
			(mid 11.149895 12.361062)
			(end 3.666236 22.820122)
			(stroke
				(width 0.1)
				(type default)
			)
			(layer "F.Fab")
		)
		(fp_text user "-"
			(at 0.26035 22.7076 180)
			(unlocked yes)
			(layer "F.Fab")
			(effects
				(font
					(size 1.905 1.4224)
					(thickness 0.1524)
				)
				(justify left)
			)
		)
		(fp_text user "+"
			(at 0.20955 -2.5908 180)
			(unlocked yes)
			(layer "F.Fab")
			(effects
				(font
					(size 1.905 1.4224)
					(thickness 0.1524)
				)
				(justify left)
			)
		)
		(pad "1" thru_hole rect
			(at 0 0 270)
			(size 1.6256 1.6256)
			(drill 1.1176)
			(layers "*.Cu" "*.Mask")
			(remove_unused_layers no)
			(net "P3V_BAT")
			(clearance 0)
			(padstack
				(mode front_inner_back)
				(layer "Inner"
					(shape circle)
					(size 1.6256 1.6256)
					(clearance 0)
				)
				(layer "B.Cu"
					(shape rect)
					(size 1.6256 1.6256)
					(clearance 0)
				)
			)
		)
		(pad "2" thru_hole circle
			(at 0 19.99996 270)
			(size 1.524 1.524)
			(drill 1.016)
			(layers "*.Cu" "*.Mask")
			(remove_unused_layers no)
			(net "GND")
			(clearance 0)
		)
	)
	(footprint ""
		(layer "F.Cu")
		(at 430.022 -58.42 -90)
		(property "Reference" "R8017"
			(at 0 0 270)
			(layer "F.SilkS")
			(hide yes)
			(effects
				(font
					(size 1.27 1.27)
				)
			)
		)
		(property "Value" ""
			(at 0 0 270)
			(layer "F.Fab")
			(effects
				(font
					(size 1.27 1.27)
				)
			)
		)
		(duplicate_pad_numbers_are_jumpers no)
		(fp_line
			(start -0.7874 0.4064)
			(end -0.7874 -0.4064)
			(stroke
				(width 0.1524)
				(type default)
			)
			(layer "F.SilkS")
		)
		(fp_line
			(start 0.7874 0.4064)
			(end -0.7874 0.4064)
			(stroke
				(width 0.1524)
				(type default)
			)
			(layer "F.SilkS")
		)
		(fp_line
			(start -0.7874 -0.4064)
			(end 0.7874 -0.4064)
			(stroke
				(width 0.1524)
				(type default)
			)
			(layer "F.SilkS")
		)
		(fp_line
			(start 0.7874 -0.4064)
			(end 0.7874 0.4064)
			(stroke
				(width 0.1524)
				(type default)
			)
			(layer "F.SilkS")
		)
		(fp_line
			(start -0.67945 0.3048)
			(end -0.67945 -0.305054)
			(stroke
				(width 0.1)
				(type default)
			)
			(layer "F.Fab")
		)
		(fp_line
			(start -0.12065 0.3048)
			(end -0.67945 0.3048)
			(stroke
				(width 0.1)
				(type default)
			)
			(layer "F.Fab")
		)
		(fp_line
			(start 0.120396 0.3048)
			(end 0.120396 0.2794)
			(stroke
				(width 0.1)
				(type default)
			)
			(layer "F.Fab")
		)
		(fp_line
			(start 0.67945 0.3048)
			(end 0.120396 0.3048)
			(stroke
				(width 0.1)
				(type default)
			)
			(layer "F.Fab")
		)
		(fp_line
			(start -0.12065 0.2794)
			(end -0.12065 0.3048)
			(stroke
				(width 0.1)
				(type default)
			)
			(layer "F.Fab")
		)
		(fp_line
			(start 0.120396 0.2794)
			(end -0.12065 0.2794)
			(stroke
				(width 0.1)
				(type default)
			)
			(layer "F.Fab")
		)
		(fp_line
			(start -0.12065 -0.2794)
			(end 0.12065 -0.2794)
			(stroke
				(width 0.1)
				(type default)
			)
			(layer "F.Fab")
		)
		(fp_line
			(start 0.12065 -0.2794)
			(end 0.12065 -0.3048)
			(stroke
				(width 0.1)
				(type default)
			)
			(layer "F.Fab")
		)
		(fp_line
			(start 0.12065 -0.3048)
			(end 0.67945 -0.3048)
			(stroke
				(width 0.1)
				(type default)
			)
			(layer "F.Fab")
		)
		(fp_line
			(start 0.67945 -0.3048)
			(end 0.67945 0.3048)
			(stroke
				(width 0.1)
				(type default)
			)
			(layer "F.Fab")
		)
		(fp_line
			(start -0.67945 -0.305054)
			(end -0.12065 -0.305054)
			(stroke
				(width 0.1)
				(type default)
			)
			(layer "F.Fab")
		)
		(fp_line
			(start -0.12065 -0.305054)
			(end -0.12065 -0.2794)
			(stroke
				(width 0.1)
				(type default)
			)
			(layer "F.Fab")
		)
		(pad "1" smd circle
			(at -0.40005 0 270)
			(size 0 0)
			(layers "F.Cu" "F.Mask" "F.Paste")
			(net "P3V3_AUX")
		)
		(pad "2" smd circle
			(at 0.40005 0 270)
			(size 0 0)
			(layers "F.Cu" "F.Mask" "F.Paste")
			(net "U124_VCC")
		)
	)
	(footprint ""
		(layer "F.Cu")
		(at 134.474712 -400.76882 180)
		(property "Reference" "C7005"
			(at -1.133856 -2.910332 0)
			(unlocked yes)
			(layer "F.SilkS")
			(effects
				(font
					(size 0.7874 0.5842)
					(thickness 0.1524)
				)
				(justify left)
			)
		)
		(property "Value" ""
			(at 0 0 180)
			(layer "F.Fab")
			(effects
				(font
					(size 1.27 1.27)
				)
			)
		)
		(duplicate_pad_numbers_are_jumpers no)
		(fp_line
			(start 4.53898 2.15011)
			(end -4.53898 2.15011)
			(stroke
				(width 0.1524)
				(type default)
			)
			(layer "F.SilkS")
		)
		(fp_line
			(start 4.53898 -2.15011)
			(end 4.53898 2.15011)
			(stroke
				(width 0.1524)
				(type default)
			)
			(layer "F.SilkS")
		)
		(fp_line
			(start -4.53898 2.15011)
			(end -4.53898 -2.15011)
			(stroke
				(width 0.1524)
				(type default)
			)
			(layer "F.SilkS")
		)
		(fp_line
			(start -4.53898 -2.15011)
			(end 4.53898 -2.15011)
			(stroke
				(width 0.1524)
				(type default)
			)
			(layer "F.SilkS")
		)
		(fp_line
			(start -4.53898 -2.150618)
			(end -4.539742 2.152142)
			(stroke
				(width 0.1524)
				(type default)
			)
			(layer "F.SilkS")
		)
		(fp_line
			(start -4.69138 -2.150618)
			(end -4.692396 2.161032)
			(stroke
				(width 0.1524)
				(type default)
			)
			(layer "F.SilkS")
		)
		(fp_line
			(start -4.83108 2.150364)
			(end -4.447794 2.149348)
			(stroke
				(width 0.1524)
				(type default)
			)
			(layer "F.SilkS")
		)
		(fp_line
			(start -4.84378 -2.150618)
			(end -4.53898 -2.150618)
			(stroke
				(width 0.1524)
				(type default)
			)
			(layer "F.SilkS")
		)
		(fp_line
			(start -4.84378 -2.150618)
			(end -4.842256 2.163064)
			(stroke
				(width 0.1524)
				(type default)
			)
			(layer "F.SilkS")
		)
		(fp_line
			(start 3.64998 2.15011)
			(end -3.64998 2.15011)
			(stroke
				(width 0.1)
				(type default)
			)
			(layer "F.Fab")
		)
		(fp_line
			(start 3.64998 -2.15011)
			(end 3.64998 2.15011)
			(stroke
				(width 0.1)
				(type default)
			)
			(layer "F.Fab")
		)
		(fp_line
			(start -3.64998 2.15011)
			(end -3.64998 -2.15011)
			(stroke
				(width 0.1)
				(type default)
			)
			(layer "F.Fab")
		)
		(fp_line
			(start -3.64998 -2.15011)
			(end 3.64998 -2.15011)
			(stroke
				(width 0.1)
				(type default)
			)
			(layer "F.Fab")
		)
		(fp_text user "-"
			(at 4.869434 -0.582168 180)
			(unlocked yes)
			(layer "F.SilkS")
			(effects
				(font
					(size 1.905 1.4224)
					(thickness 0.1524)
				)
				(justify left)
			)
		)
		(fp_text user "+"
			(at -6.075172 -1.660398 180)
			(unlocked yes)
			(layer "F.SilkS")
			(effects
				(font
					(size 1.905 1.4224)
					(thickness 0.1524)
				)
				(justify left)
			)
		)
		(fp_text user "-"
			(at 4.313174 -0.094488 180)
			(unlocked yes)
			(layer "F.Fab")
			(effects
				(font
					(size 1.905 1.4224)
					(thickness 0.1524)
				)
				(justify left)
			)
		)
		(fp_text user "+"
			(at -6.214872 -0.337058 180)
			(unlocked yes)
			(layer "F.Fab")
			(effects
				(font
					(size 1.905 1.4224)
					(thickness 0.1524)
				)
				(justify left)
			)
		)
		(pad "1" smd rect
			(at -3.199892 0 180)
			(size 2.413 2.8194)
			(layers "F.Cu" "F.Mask" "F.Paste")
			(net "P0V9_CPU1_RT_2D")
		)
		(pad "2" smd rect
			(at 3.199892 0 180)
			(size 2.413 2.8194)
			(layers "F.Cu" "F.Mask" "F.Paste")
			(net "GND")
		)
	)
	(footprint ""
		(layer "F.Cu")
		(at 79.248 -61.214 180)
		(property "Reference" "C8009"
			(at 0 0 180)
			(layer "F.SilkS")
			(hide yes)
			(effects
				(font
					(size 1.27 1.27)
				)
			)
		)
		(property "Value" ""
			(at 0 0 180)
			(layer "F.Fab")
			(effects
				(font
					(size 1.27 1.27)
				)
			)
		)
		(duplicate_pad_numbers_are_jumpers no)
		(fp_line
			(start 0.7874 0.4064)
			(end -0.7874 0.4064)
			(stroke
				(width 0.1524)
				(type default)
			)
			(layer "F.SilkS")
		)
		(fp_line
			(start 0.7874 -0.4064)
			(end 0.7874 0.4064)
			(stroke
				(width 0.1524)
				(type default)
			)
			(layer "F.SilkS")
		)
		(fp_line
			(start -0.7874 0.4064)
			(end -0.7874 -0.4064)
			(stroke
				(width 0.1524)
				(type default)
			)
			(layer "F.SilkS")
		)
		(fp_line
			(start -0.7874 -0.4064)
			(end 0.7874 -0.4064)
			(stroke
				(width 0.1524)
				(type default)
			)
			(layer "F.SilkS")
		)
		(fp_line
			(start 0.67945 0.3048)
			(end 0.120396 0.3048)
			(stroke
				(width 0.1)
				(type default)
			)
			(layer "F.Fab")
		)
		(fp_line
			(start 0.67945 -0.3048)
			(end 0.67945 0.3048)
			(stroke
				(width 0.1)
				(type default)
			)
			(layer "F.Fab")
		)
		(fp_line
			(start 0.12065 -0.2794)
			(end 0.12065 -0.3048)
			(stroke
				(width 0.1)
				(type default)
			)
			(layer "F.Fab")
		)
		(fp_line
			(start 0.12065 -0.3048)
			(end 0.67945 -0.3048)
			(stroke
				(width 0.1)
				(type default)
			)
			(layer "F.Fab")
		)
		(fp_line
			(start 0.120396 0.3048)
			(end 0.120396 0.2794)
			(stroke
				(width 0.1)
				(type default)
			)
			(layer "F.Fab")
		)
		(fp_line
			(start 0.120396 0.2794)
			(end -0.12065 0.2794)
			(stroke
				(width 0.1)
				(type default)
			)
			(layer "F.Fab")
		)
		(fp_line
			(start -0.12065 0.3048)
			(end -0.67945 0.3048)
			(stroke
				(width 0.1)
				(type default)
			)
			(layer "F.Fab")
		)
		(fp_line
			(start -0.12065 0.2794)
			(end -0.12065 0.3048)
			(stroke
				(width 0.1)
				(type default)
			)
			(layer "F.Fab")
		)
		(fp_line
			(start -0.12065 -0.2794)
			(end 0.12065 -0.2794)
			(stroke
				(width 0.1)
				(type default)
			)
			(layer "F.Fab")
		)
		(fp_line
			(start -0.12065 -0.305054)
			(end -0.12065 -0.2794)
			(stroke
				(width 0.1)
				(type default)
			)
			(layer "F.Fab")
		)
		(fp_line
			(start -0.67945 0.3048)
			(end -0.67945 -0.305054)
			(stroke
				(width 0.1)
				(type default)
			)
			(layer "F.Fab")
		)
		(fp_line
			(start -0.67945 -0.305054)
			(end -0.12065 -0.305054)
			(stroke
				(width 0.1)
				(type default)
			)
			(layer "F.Fab")
		)
		(pad "1" smd circle
			(at -0.40005 0 180)
			(size 0 0)
			(layers "F.Cu" "F.Mask" "F.Paste")
			(net "P3V3_OCP_V3_2_R")
		)
		(pad "2" smd circle
			(at 0.40005 0 180)
			(size 0 0)
			(layers "F.Cu" "F.Mask" "F.Paste")
			(net "GND")
		)
	)
	(footprint ""
		(layer "F.Cu")
		(at 105.191814 -37.6682)
		(property "Reference" "R6324"
			(at 0 0 0)
			(layer "F.SilkS")
			(hide yes)
			(effects
				(font
					(size 1.27 1.27)
				)
			)
		)
		(property "Value" ""
			(at 0 0 0)
			(layer "F.Fab")
			(effects
				(font
					(size 1.27 1.27)
				)
			)
		)
		(duplicate_pad_numbers_are_jumpers no)
		(fp_line
			(start -0.7874 -0.4064)
			(end 0.7874 -0.4064)
			(stroke
				(width 0.1524)
				(type default)
			)
			(layer "F.SilkS")
		)
		(fp_line
			(start -0.7874 0.4064)
			(end -0.7874 -0.4064)
			(stroke
				(width 0.1524)
				(type default)
			)
			(layer "F.SilkS")
		)
		(fp_line
			(start 0.7874 -0.4064)
			(end 0.7874 0.4064)
			(stroke
				(width 0.1524)
				(type default)
			)
			(layer "F.SilkS")
		)
		(fp_line
			(start 0.7874 0.4064)
			(end -0.7874 0.4064)
			(stroke
				(width 0.1524)
				(type default)
			)
			(layer "F.SilkS")
		)
		(fp_line
			(start -0.67945 -0.305054)
			(end -0.12065 -0.305054)
			(stroke
				(width 0.1)
				(type default)
			)
			(layer "F.Fab")
		)
		(fp_line
			(start -0.67945 0.3048)
			(end -0.67945 -0.305054)
			(stroke
				(width 0.1)
				(type default)
			)
			(layer "F.Fab")
		)
		(fp_line
			(start -0.12065 -0.305054)
			(end -0.12065 -0.2794)
			(stroke
				(width 0.1)
				(type default)
			)
			(layer "F.Fab")
		)
		(fp_line
			(start -0.12065 -0.2794)
			(end 0.12065 -0.2794)
			(stroke
				(width 0.1)
				(type default)
			)
			(layer "F.Fab")
		)
		(fp_line
			(start -0.12065 0.2794)
			(end -0.12065 0.3048)
			(stroke
				(width 0.1)
				(type default)
			)
			(layer "F.Fab")
		)
		(fp_line
			(start -0.12065 0.3048)
			(end -0.67945 0.3048)
			(stroke
				(width 0.1)
				(type default)
			)
			(layer "F.Fab")
		)
		(fp_line
			(start 0.120396 0.2794)
			(end -0.12065 0.2794)
			(stroke
				(width 0.1)
				(type default)
			)
			(layer "F.Fab")
		)
		(fp_line
			(start 0.120396 0.3048)
			(end 0.120396 0.2794)
			(stroke
				(width 0.1)
				(type default)
			)
			(layer "F.Fab")
		)
		(fp_line
			(start 0.12065 -0.3048)
			(end 0.67945 -0.3048)
			(stroke
				(width 0.1)
				(type default)
			)
			(layer "F.Fab")
		)
		(fp_line
			(start 0.12065 -0.2794)
			(end 0.12065 -0.3048)
			(stroke
				(width 0.1)
				(type default)
			)
			(layer "F.Fab")
		)
		(fp_line
			(start 0.67945 -0.3048)
			(end 0.67945 0.3048)
			(stroke
				(width 0.1)
				(type default)
			)
			(layer "F.Fab")
		)
		(fp_line
			(start 0.67945 0.3048)
			(end 0.120396 0.3048)
			(stroke
				(width 0.1)
				(type default)
			)
			(layer "F.Fab")
		)
		(pad "1" smd circle
			(at -0.40005 0)
			(size 0 0)
			(layers "F.Cu" "F.Mask" "F.Paste")
			(net "USB_HUB2_MRP_PROG_FUNC6")
		)
		(pad "2" smd circle
			(at 0.40005 0)
			(size 0 0)
			(layers "F.Cu" "F.Mask" "F.Paste")
			(net "USB_HUB2_TI_TEST_MRP_PROG_FUNC6")
		)
	)
	(footprint ""
		(layer "F.Cu")
		(at 318.226186 -361.061 -90)
		(property "Reference" "PR54"
			(at 0 0 270)
			(layer "F.SilkS")
			(hide yes)
			(effects
				(font
					(size 1.27 1.27)
				)
			)
		)
		(property "Value" ""
			(at 0 0 270)
			(layer "F.Fab")
			(effects
				(font
					(size 1.27 1.27)
				)
			)
		)
		(duplicate_pad_numbers_are_jumpers no)
		(fp_line
			(start -0.7874 0.4064)
			(end -0.7874 -0.4064)
			(stroke
				(width 0.1524)
				(type default)
			)
			(layer "F.SilkS")
		)
		(fp_line
			(start 0.7874 0.4064)
			(end -0.7874 0.4064)
			(stroke
				(width 0.1524)
				(type default)
			)
			(layer "F.SilkS")
		)
		(fp_line
			(start -0.7874 -0.4064)
			(end 0.7874 -0.4064)
			(stroke
				(width 0.1524)
				(type default)
			)
			(layer "F.SilkS")
		)
		(fp_line
			(start 0.7874 -0.4064)
			(end 0.7874 0.4064)
			(stroke
				(width 0.1524)
				(type default)
			)
			(layer "F.SilkS")
		)
		(fp_line
			(start -0.67945 0.3048)
			(end -0.67945 -0.305054)
			(stroke
				(width 0.1)
				(type default)
			)
			(layer "F.Fab")
		)
		(fp_line
			(start -0.12065 0.3048)
			(end -0.67945 0.3048)
			(stroke
				(width 0.1)
				(type default)
			)
			(layer "F.Fab")
		)
		(fp_line
			(start 0.120396 0.3048)
			(end 0.120396 0.2794)
			(stroke
				(width 0.1)
				(type default)
			)
			(layer "F.Fab")
		)
		(fp_line
			(start 0.67945 0.3048)
			(end 0.120396 0.3048)
			(stroke
				(width 0.1)
				(type default)
			)
			(layer "F.Fab")
		)
		(fp_line
			(start -0.12065 0.2794)
			(end -0.12065 0.3048)
			(stroke
				(width 0.1)
				(type default)
			)
			(layer "F.Fab")
		)
		(fp_line
			(start 0.120396 0.2794)
			(end -0.12065 0.2794)
			(stroke
				(width 0.1)
				(type default)
			)
			(layer "F.Fab")
		)
		(fp_line
			(start -0.12065 -0.2794)
			(end 0.12065 -0.2794)
			(stroke
				(width 0.1)
				(type default)
			)
			(layer "F.Fab")
		)
		(fp_line
			(start 0.12065 -0.2794)
			(end 0.12065 -0.3048)
			(stroke
				(width 0.1)
				(type default)
			)
			(layer "F.Fab")
		)
		(fp_line
			(start 0.12065 -0.3048)
			(end 0.67945 -0.3048)
			(stroke
				(width 0.1)
				(type default)
			)
			(layer "F.Fab")
		)
		(fp_line
			(start 0.67945 -0.3048)
			(end 0.67945 0.3048)
			(stroke
				(width 0.1)
				(type default)
			)
			(layer "F.Fab")
		)
		(fp_line
			(start -0.67945 -0.305054)
			(end -0.12065 -0.305054)
			(stroke
				(width 0.1)
				(type default)
			)
			(layer "F.Fab")
		)
		(fp_line
			(start -0.12065 -0.305054)
			(end -0.12065 -0.2794)
			(stroke
				(width 0.1)
				(type default)
			)
			(layer "F.Fab")
		)
		(pad "1" smd circle
			(at -0.40005 0 270)
			(size 0 0)
			(layers "F.Cu" "F.Mask" "F.Paste")
			(net "PVDDCR_CPU1_P0_VMON")
		)
		(pad "2" smd circle
			(at 0.40005 0 270)
			(size 0 0)
			(layers "F.Cu" "F.Mask" "F.Paste")
			(net "GND")
		)
	)
	(footprint ""
		(layer "F.Cu")
		(at 110.067344 -381.48006 180)
		(property "Reference" "C1546"
			(at 0 0 180)
			(layer "F.SilkS")
			(hide yes)
			(effects
				(font
					(size 1.27 1.27)
				)
			)
		)
		(property "Value" ""
			(at 0 0 180)
			(layer "F.Fab")
			(effects
				(font
					(size 1.27 1.27)
				)
			)
		)
		(duplicate_pad_numbers_are_jumpers no)
		(fp_line
			(start 0.299974 0.150114)
			(end -0.299974 0.150114)
			(stroke
				(width 0.1)
				(type default)
			)
			(layer "F.Fab")
		)
		(fp_line
			(start 0.299974 -0.150114)
			(end 0.299974 0.150114)
			(stroke
				(width 0.1)
				(type default)
			)
			(layer "F.Fab")
		)
		(fp_line
			(start -0.299974 0.150114)
			(end -0.299974 -0.150114)
			(stroke
				(width 0.1)
				(type default)
			)
			(layer "F.Fab")
		)
		(fp_line
			(start -0.299974 -0.150114)
			(end 0.299974 -0.150114)
			(stroke
				(width 0.1)
				(type default)
			)
			(layer "F.Fab")
		)
		(pad "1" smd rect
			(at -0.2667 0 180)
			(size 0.3048 0.381)
			(layers "F.Cu" "F.Mask" "F.Paste")
			(net "P5E_CPU1_P3_TX_C_DN<0>")
		)
		(pad "2" smd rect
			(at 0.2667 0 180)
			(size 0.3048 0.381)
			(layers "F.Cu" "F.Mask" "F.Paste")
			(net "P5E_CPU1_P3_TX_DN<0>")
		)
	)
	(footprint ""
		(layer "F.Cu")
		(at 171.20743 -102.993952)
		(property "Reference" "R6183"
			(at 0 0 0)
			(layer "F.SilkS")
			(hide yes)
			(effects
				(font
					(size 1.27 1.27)
				)
			)
		)
		(property "Value" ""
			(at 0 0 0)
			(layer "F.Fab")
			(effects
				(font
					(size 1.27 1.27)
				)
			)
		)
		(duplicate_pad_numbers_are_jumpers no)
		(fp_line
			(start -0.7874 -0.4064)
			(end 0.7874 -0.4064)
			(stroke
				(width 0.1524)
				(type default)
			)
			(layer "F.SilkS")
		)
		(fp_line
			(start -0.7874 0.4064)
			(end -0.7874 -0.4064)
			(stroke
				(width 0.1524)
				(type default)
			)
			(layer "F.SilkS")
		)
		(fp_line
			(start 0.7874 -0.4064)
			(end 0.7874 0.4064)
			(stroke
				(width 0.1524)
				(type default)
			)
			(layer "F.SilkS")
		)
		(fp_line
			(start 0.7874 0.4064)
			(end -0.7874 0.4064)
			(stroke
				(width 0.1524)
				(type default)
			)
			(layer "F.SilkS")
		)
		(fp_line
			(start -0.67945 -0.305054)
			(end -0.12065 -0.305054)
			(stroke
				(width 0.1)
				(type default)
			)
			(layer "F.Fab")
		)
		(fp_line
			(start -0.67945 0.3048)
			(end -0.67945 -0.305054)
			(stroke
				(width 0.1)
				(type default)
			)
			(layer "F.Fab")
		)
		(fp_line
			(start -0.12065 -0.305054)
			(end -0.12065 -0.2794)
			(stroke
				(width 0.1)
				(type default)
			)
			(layer "F.Fab")
		)
		(fp_line
			(start -0.12065 -0.2794)
			(end 0.12065 -0.2794)
			(stroke
				(width 0.1)
				(type default)
			)
			(layer "F.Fab")
		)
		(fp_line
			(start -0.12065 0.2794)
			(end -0.12065 0.3048)
			(stroke
				(width 0.1)
				(type default)
			)
			(layer "F.Fab")
		)
		(fp_line
			(start -0.12065 0.3048)
			(end -0.67945 0.3048)
			(stroke
				(width 0.1)
				(type default)
			)
			(layer "F.Fab")
		)
		(fp_line
			(start 0.120396 0.2794)
			(end -0.12065 0.2794)
			(stroke
				(width 0.1)
				(type default)
			)
			(layer "F.Fab")
		)
		(fp_line
			(start 0.120396 0.3048)
			(end 0.120396 0.2794)
			(stroke
				(width 0.1)
				(type default)
			)
			(layer "F.Fab")
		)
		(fp_line
			(start 0.12065 -0.3048)
			(end 0.67945 -0.3048)
			(stroke
				(width 0.1)
				(type default)
			)
			(layer "F.Fab")
		)
		(fp_line
			(start 0.12065 -0.2794)
			(end 0.12065 -0.3048)
			(stroke
				(width 0.1)
				(type default)
			)
			(layer "F.Fab")
		)
		(fp_line
			(start 0.67945 -0.3048)
			(end 0.67945 0.3048)
			(stroke
				(width 0.1)
				(type default)
			)
			(layer "F.Fab")
		)
		(fp_line
			(start 0.67945 0.3048)
			(end 0.120396 0.3048)
			(stroke
				(width 0.1)
				(type default)
			)
			(layer "F.Fab")
		)
		(pad "1" smd circle
			(at -0.40005 0)
			(size 0 0)
			(layers "F.Cu" "F.Mask" "F.Paste")
			(net "FM_SEC_MUX_OE_N")
		)
		(pad "2" smd circle
			(at 0.40005 0)
			(size 0 0)
			(layers "F.Cu" "F.Mask" "F.Paste")
			(net "FM_SEC_MUX_OE_R_N")
		)
	)
	(footprint ""
		(layer "F.Cu")
		(at 56.858408 -37.7825)
		(property "Reference" "R1168"
			(at 0 0 0)
			(layer "F.SilkS")
			(hide yes)
			(effects
				(font
					(size 1.27 1.27)
				)
			)
		)
		(property "Value" ""
			(at 0 0 0)
			(layer "F.Fab")
			(effects
				(font
					(size 1.27 1.27)
				)
			)
		)
		(duplicate_pad_numbers_are_jumpers no)
		(fp_line
			(start -0.7874 -0.4064)
			(end 0.7874 -0.4064)
			(stroke
				(width 0.1524)
				(type default)
			)
			(layer "F.SilkS")
		)
		(fp_line
			(start -0.7874 0.4064)
			(end -0.7874 -0.4064)
			(stroke
				(width 0.1524)
				(type default)
			)
			(layer "F.SilkS")
		)
		(fp_line
			(start 0.7874 -0.4064)
			(end 0.7874 0.4064)
			(stroke
				(width 0.1524)
				(type default)
			)
			(layer "F.SilkS")
		)
		(fp_line
			(start 0.7874 0.4064)
			(end -0.7874 0.4064)
			(stroke
				(width 0.1524)
				(type default)
			)
			(layer "F.SilkS")
		)
		(fp_line
			(start -0.67945 -0.305054)
			(end -0.12065 -0.305054)
			(stroke
				(width 0.1)
				(type default)
			)
			(layer "F.Fab")
		)
		(fp_line
			(start -0.67945 0.3048)
			(end -0.67945 -0.305054)
			(stroke
				(width 0.1)
				(type default)
			)
			(layer "F.Fab")
		)
		(fp_line
			(start -0.12065 -0.305054)
			(end -0.12065 -0.2794)
			(stroke
				(width 0.1)
				(type default)
			)
			(layer "F.Fab")
		)
		(fp_line
			(start -0.12065 -0.2794)
			(end 0.12065 -0.2794)
			(stroke
				(width 0.1)
				(type default)
			)
			(layer "F.Fab")
		)
		(fp_line
			(start -0.12065 0.2794)
			(end -0.12065 0.3048)
			(stroke
				(width 0.1)
				(type default)
			)
			(layer "F.Fab")
		)
		(fp_line
			(start -0.12065 0.3048)
			(end -0.67945 0.3048)
			(stroke
				(width 0.1)
				(type default)
			)
			(layer "F.Fab")
		)
		(fp_line
			(start 0.120396 0.2794)
			(end -0.12065 0.2794)
			(stroke
				(width 0.1)
				(type default)
			)
			(layer "F.Fab")
		)
		(fp_line
			(start 0.120396 0.3048)
			(end 0.120396 0.2794)
			(stroke
				(width 0.1)
				(type default)
			)
			(layer "F.Fab")
		)
		(fp_line
			(start 0.12065 -0.3048)
			(end 0.67945 -0.3048)
			(stroke
				(width 0.1)
				(type default)
			)
			(layer "F.Fab")
		)
		(fp_line
			(start 0.12065 -0.2794)
			(end 0.12065 -0.3048)
			(stroke
				(width 0.1)
				(type default)
			)
			(layer "F.Fab")
		)
		(fp_line
			(start 0.67945 -0.3048)
			(end 0.67945 0.3048)
			(stroke
				(width 0.1)
				(type default)
			)
			(layer "F.Fab")
		)
		(fp_line
			(start 0.67945 0.3048)
			(end 0.120396 0.3048)
			(stroke
				(width 0.1)
				(type default)
			)
			(layer "F.Fab")
		)
		(pad "1" smd circle
			(at -0.40005 0)
			(size 0 0)
			(layers "F.Cu" "F.Mask" "F.Paste")
			(net "P12V_OCP_V3_2_BUF_EN")
		)
		(pad "2" smd circle
			(at 0.40005 0)
			(size 0 0)
			(layers "F.Cu" "F.Mask" "F.Paste")
			(net "P12V_OCP_V3_2_BUF_EN_R")
		)
	)
	(footprint ""
		(layer "F.Cu")
		(at 22.07768 -433.453794 180)
		(property "Reference" "R2897"
			(at 0 0 180)
			(layer "F.SilkS")
			(hide yes)
			(effects
				(font
					(size 1.27 1.27)
				)
			)
		)
		(property "Value" ""
			(at 0 0 180)
			(layer "F.Fab")
			(effects
				(font
					(size 1.27 1.27)
				)
			)
		)
		(duplicate_pad_numbers_are_jumpers no)
		(fp_line
			(start 0.7874 0.4064)
			(end -0.7874 0.4064)
			(stroke
				(width 0.1524)
				(type default)
			)
			(layer "F.SilkS")
		)
		(fp_line
			(start 0.7874 -0.4064)
			(end 0.7874 0.4064)
			(stroke
				(width 0.1524)
				(type default)
			)
			(layer "F.SilkS")
		)
		(fp_line
			(start -0.7874 0.4064)
			(end -0.7874 -0.4064)
			(stroke
				(width 0.1524)
				(type default)
			)
			(layer "F.SilkS")
		)
		(fp_line
			(start -0.7874 -0.4064)
			(end 0.7874 -0.4064)
			(stroke
				(width 0.1524)
				(type default)
			)
			(layer "F.SilkS")
		)
		(fp_line
			(start 0.67945 0.3048)
			(end 0.120396 0.3048)
			(stroke
				(width 0.1)
				(type default)
			)
			(layer "F.Fab")
		)
		(fp_line
			(start 0.67945 -0.3048)
			(end 0.67945 0.3048)
			(stroke
				(width 0.1)
				(type default)
			)
			(layer "F.Fab")
		)
		(fp_line
			(start 0.12065 -0.2794)
			(end 0.12065 -0.3048)
			(stroke
				(width 0.1)
				(type default)
			)
			(layer "F.Fab")
		)
		(fp_line
			(start 0.12065 -0.3048)
			(end 0.67945 -0.3048)
			(stroke
				(width 0.1)
				(type default)
			)
			(layer "F.Fab")
		)
		(fp_line
			(start 0.120396 0.3048)
			(end 0.120396 0.2794)
			(stroke
				(width 0.1)
				(type default)
			)
			(layer "F.Fab")
		)
		(fp_line
			(start 0.120396 0.2794)
			(end -0.12065 0.2794)
			(stroke
				(width 0.1)
				(type default)
			)
			(layer "F.Fab")
		)
		(fp_line
			(start -0.12065 0.3048)
			(end -0.67945 0.3048)
			(stroke
				(width 0.1)
				(type default)
			)
			(layer "F.Fab")
		)
		(fp_line
			(start -0.12065 0.2794)
			(end -0.12065 0.3048)
			(stroke
				(width 0.1)
				(type default)
			)
			(layer "F.Fab")
		)
		(fp_line
			(start -0.12065 -0.2794)
			(end 0.12065 -0.2794)
			(stroke
				(width 0.1)
				(type default)
			)
			(layer "F.Fab")
		)
		(fp_line
			(start -0.12065 -0.305054)
			(end -0.12065 -0.2794)
			(stroke
				(width 0.1)
				(type default)
			)
			(layer "F.Fab")
		)
		(fp_line
			(start -0.67945 0.3048)
			(end -0.67945 -0.305054)
			(stroke
				(width 0.1)
				(type default)
			)
			(layer "F.Fab")
		)
		(fp_line
			(start -0.67945 -0.305054)
			(end -0.12065 -0.305054)
			(stroke
				(width 0.1)
				(type default)
			)
			(layer "F.Fab")
		)
		(pad "1" smd circle
			(at -0.40005 0 180)
			(size 0 0)
			(layers "F.Cu" "F.Mask" "F.Paste")
			(net "SMB_1_BMC_GPU_BUF_R_SCL")
		)
		(pad "2" smd circle
			(at 0.40005 0 180)
			(size 0 0)
			(layers "F.Cu" "F.Mask" "F.Paste")
			(net "SMB_1_BMC_GPU_BUF_SCL")
		)
	)
	(footprint ""
		(layer "F.Cu")
		(at 376.809 -426.339 180)
		(property "Reference" "R1206"
			(at 0 0 180)
			(layer "F.SilkS")
			(hide yes)
			(effects
				(font
					(size 1.27 1.27)
				)
			)
		)
		(property "Value" ""
			(at 0 0 180)
			(layer "F.Fab")
			(effects
				(font
					(size 1.27 1.27)
				)
			)
		)
		(duplicate_pad_numbers_are_jumpers no)
		(fp_line
			(start 0.32512 0.175006)
			(end -0.32512 0.175006)
			(stroke
				(width 0.1)
				(type default)
			)
			(layer "F.Fab")
		)
		(fp_line
			(start 0.32512 -0.175006)
			(end 0.32512 0.175006)
			(stroke
				(width 0.1)
				(type default)
			)
			(layer "F.Fab")
		)
		(fp_line
			(start -0.32512 0.175006)
			(end -0.32512 -0.175006)
			(stroke
				(width 0.1)
				(type default)
			)
			(layer "F.Fab")
		)
		(fp_line
			(start -0.32512 -0.175006)
			(end 0.32512 -0.175006)
			(stroke
				(width 0.1)
				(type default)
			)
			(layer "F.Fab")
		)
		(pad "1" smd rect
			(at -0.2667 0 180)
			(size 0.3048 0.381)
			(layers "F.Cu" "F.Mask" "F.Paste")
			(net "RST_SMB_RT_ROM_R1_N")
		)
		(pad "2" smd rect
			(at 0.2667 0)
			(size 0.3048 0.381)
			(layers "F.Cu" "F.Mask" "F.Paste")
			(net "FM_SMB_RT_ROM_MUX7_SEL")
		)
	)
	(footprint ""
		(layer "F.Cu")
		(at 412.472886 -74.864468 180)
		(property "Reference" "R3501"
			(at 0 0 180)
			(layer "F.SilkS")
			(hide yes)
			(effects
				(font
					(size 1.27 1.27)
				)
			)
		)
		(property "Value" ""
			(at 0 0 180)
			(layer "F.Fab")
			(effects
				(font
					(size 1.27 1.27)
				)
			)
		)
		(duplicate_pad_numbers_are_jumpers no)
		(fp_line
			(start 0.7874 0.4064)
			(end -0.7874 0.4064)
			(stroke
				(width 0.1524)
				(type default)
			)
			(layer "F.SilkS")
		)
		(fp_line
			(start 0.7874 -0.4064)
			(end 0.7874 0.4064)
			(stroke
				(width 0.1524)
				(type default)
			)
			(layer "F.SilkS")
		)
		(fp_line
			(start -0.7874 0.4064)
			(end -0.7874 -0.4064)
			(stroke
				(width 0.1524)
				(type default)
			)
			(layer "F.SilkS")
		)
		(fp_line
			(start -0.7874 -0.4064)
			(end 0.7874 -0.4064)
			(stroke
				(width 0.1524)
				(type default)
			)
			(layer "F.SilkS")
		)
		(fp_line
			(start 0.67945 0.3048)
			(end 0.120396 0.3048)
			(stroke
				(width 0.1)
				(type default)
			)
			(layer "F.Fab")
		)
		(fp_line
			(start 0.67945 -0.3048)
			(end 0.67945 0.3048)
			(stroke
				(width 0.1)
				(type default)
			)
			(layer "F.Fab")
		)
		(fp_line
			(start 0.12065 -0.2794)
			(end 0.12065 -0.3048)
			(stroke
				(width 0.1)
				(type default)
			)
			(layer "F.Fab")
		)
		(fp_line
			(start 0.12065 -0.3048)
			(end 0.67945 -0.3048)
			(stroke
				(width 0.1)
				(type default)
			)
			(layer "F.Fab")
		)
		(fp_line
			(start 0.120396 0.3048)
			(end 0.120396 0.2794)
			(stroke
				(width 0.1)
				(type default)
			)
			(layer "F.Fab")
		)
		(fp_line
			(start 0.120396 0.2794)
			(end -0.12065 0.2794)
			(stroke
				(width 0.1)
				(type default)
			)
			(layer "F.Fab")
		)
		(fp_line
			(start -0.12065 0.3048)
			(end -0.67945 0.3048)
			(stroke
				(width 0.1)
				(type default)
			)
			(layer "F.Fab")
		)
		(fp_line
			(start -0.12065 0.2794)
			(end -0.12065 0.3048)
			(stroke
				(width 0.1)
				(type default)
			)
			(layer "F.Fab")
		)
		(fp_line
			(start -0.12065 -0.2794)
			(end 0.12065 -0.2794)
			(stroke
				(width 0.1)
				(type default)
			)
			(layer "F.Fab")
		)
		(fp_line
			(start -0.12065 -0.305054)
			(end -0.12065 -0.2794)
			(stroke
				(width 0.1)
				(type default)
			)
			(layer "F.Fab")
		)
		(fp_line
			(start -0.67945 0.3048)
			(end -0.67945 -0.305054)
			(stroke
				(width 0.1)
				(type default)
			)
			(layer "F.Fab")
		)
		(fp_line
			(start -0.67945 -0.305054)
			(end -0.12065 -0.305054)
			(stroke
				(width 0.1)
				(type default)
			)
			(layer "F.Fab")
		)
		(pad "1" smd circle
			(at -0.40005 0 180)
			(size 0 0)
			(layers "F.Cu" "F.Mask" "F.Paste")
			(net "P3V3_OCP_SFF")
		)
		(pad "2" smd circle
			(at 0.40005 0 180)
			(size 0 0)
			(layers "F.Cu" "F.Mask" "F.Paste")
			(net "SMB_OCP_SFF_3V3AUX_BUF_SDA")
		)
	)
	(footprint ""
		(layer "F.Cu")
		(at 150.400258 -116.449094)
		(property "Reference" "R2230"
			(at 0 0 0)
			(layer "F.SilkS")
			(hide yes)
			(effects
				(font
					(size 1.27 1.27)
				)
			)
		)
		(property "Value" ""
			(at 0 0 0)
			(layer "F.Fab")
			(effects
				(font
					(size 1.27 1.27)
				)
			)
		)
		(duplicate_pad_numbers_are_jumpers no)
		(fp_line
			(start -0.7874 -0.4064)
			(end 0.7874 -0.4064)
			(stroke
				(width 0.1524)
				(type default)
			)
			(layer "F.SilkS")
		)
		(fp_line
			(start -0.7874 0.4064)
			(end -0.7874 -0.4064)
			(stroke
				(width 0.1524)
				(type default)
			)
			(layer "F.SilkS")
		)
		(fp_line
			(start 0.7874 -0.4064)
			(end 0.7874 0.4064)
			(stroke
				(width 0.1524)
				(type default)
			)
			(layer "F.SilkS")
		)
		(fp_line
			(start 0.7874 0.4064)
			(end -0.7874 0.4064)
			(stroke
				(width 0.1524)
				(type default)
			)
			(layer "F.SilkS")
		)
		(fp_line
			(start -0.67945 -0.305054)
			(end -0.12065 -0.305054)
			(stroke
				(width 0.1)
				(type default)
			)
			(layer "F.Fab")
		)
		(fp_line
			(start -0.67945 0.3048)
			(end -0.67945 -0.305054)
			(stroke
				(width 0.1)
				(type default)
			)
			(layer "F.Fab")
		)
		(fp_line
			(start -0.12065 -0.305054)
			(end -0.12065 -0.2794)
			(stroke
				(width 0.1)
				(type default)
			)
			(layer "F.Fab")
		)
		(fp_line
			(start -0.12065 -0.2794)
			(end 0.12065 -0.2794)
			(stroke
				(width 0.1)
				(type default)
			)
			(layer "F.Fab")
		)
		(fp_line
			(start -0.12065 0.2794)
			(end -0.12065 0.3048)
			(stroke
				(width 0.1)
				(type default)
			)
			(layer "F.Fab")
		)
		(fp_line
			(start -0.12065 0.3048)
			(end -0.67945 0.3048)
			(stroke
				(width 0.1)
				(type default)
			)
			(layer "F.Fab")
		)
		(fp_line
			(start 0.120396 0.2794)
			(end -0.12065 0.2794)
			(stroke
				(width 0.1)
				(type default)
			)
			(layer "F.Fab")
		)
		(fp_line
			(start 0.120396 0.3048)
			(end 0.120396 0.2794)
			(stroke
				(width 0.1)
				(type default)
			)
			(layer "F.Fab")
		)
		(fp_line
			(start 0.12065 -0.3048)
			(end 0.67945 -0.3048)
			(stroke
				(width 0.1)
				(type default)
			)
			(layer "F.Fab")
		)
		(fp_line
			(start 0.12065 -0.2794)
			(end 0.12065 -0.3048)
			(stroke
				(width 0.1)
				(type default)
			)
			(layer "F.Fab")
		)
		(fp_line
			(start 0.67945 -0.3048)
			(end 0.67945 0.3048)
			(stroke
				(width 0.1)
				(type default)
			)
			(layer "F.Fab")
		)
		(fp_line
			(start 0.67945 0.3048)
			(end 0.120396 0.3048)
			(stroke
				(width 0.1)
				(type default)
			)
			(layer "F.Fab")
		)
		(pad "1" smd circle
			(at -0.40005 0)
			(size 0 0)
			(layers "F.Cu" "F.Mask" "F.Paste")
			(net "P3V3_AUX")
		)
		(pad "2" smd circle
			(at 0.40005 0)
			(size 0 0)
			(layers "F.Cu" "F.Mask" "F.Paste")
			(net "A_P12V_STBY_FPH_GATE")
		)
	)
	(footprint ""
		(layer "F.Cu")
		(at 230.675688 -158.981648 180)
		(property "Reference" "C1523"
			(at 0 0 180)
			(layer "F.SilkS")
			(hide yes)
			(effects
				(font
					(size 1.27 1.27)
				)
			)
		)
		(property "Value" ""
			(at 0 0 180)
			(layer "F.Fab")
			(effects
				(font
					(size 1.27 1.27)
				)
			)
		)
		(duplicate_pad_numbers_are_jumpers no)
		(fp_line
			(start 0.7874 0.4064)
			(end -0.7874 0.4064)
			(stroke
				(width 0.1524)
				(type default)
			)
			(layer "F.SilkS")
		)
		(fp_line
			(start 0.7874 -0.4064)
			(end 0.7874 0.4064)
			(stroke
				(width 0.1524)
				(type default)
			)
			(layer "F.SilkS")
		)
		(fp_line
			(start -0.7874 0.4064)
			(end -0.7874 -0.4064)
			(stroke
				(width 0.1524)
				(type default)
			)
			(layer "F.SilkS")
		)
		(fp_line
			(start -0.7874 -0.4064)
			(end 0.7874 -0.4064)
			(stroke
				(width 0.1524)
				(type default)
			)
			(layer "F.SilkS")
		)
		(fp_line
			(start 0.67945 0.3048)
			(end 0.120396 0.3048)
			(stroke
				(width 0.1)
				(type default)
			)
			(layer "F.Fab")
		)
		(fp_line
			(start 0.67945 -0.3048)
			(end 0.67945 0.3048)
			(stroke
				(width 0.1)
				(type default)
			)
			(layer "F.Fab")
		)
		(fp_line
			(start 0.12065 -0.2794)
			(end 0.12065 -0.3048)
			(stroke
				(width 0.1)
				(type default)
			)
			(layer "F.Fab")
		)
		(fp_line
			(start 0.12065 -0.3048)
			(end 0.67945 -0.3048)
			(stroke
				(width 0.1)
				(type default)
			)
			(layer "F.Fab")
		)
		(fp_line
			(start 0.120396 0.3048)
			(end 0.120396 0.2794)
			(stroke
				(width 0.1)
				(type default)
			)
			(layer "F.Fab")
		)
		(fp_line
			(start 0.120396 0.2794)
			(end -0.12065 0.2794)
			(stroke
				(width 0.1)
				(type default)
			)
			(layer "F.Fab")
		)
		(fp_line
			(start -0.12065 0.3048)
			(end -0.67945 0.3048)
			(stroke
				(width 0.1)
				(type default)
			)
			(layer "F.Fab")
		)
		(fp_line
			(start -0.12065 0.2794)
			(end -0.12065 0.3048)
			(stroke
				(width 0.1)
				(type default)
			)
			(layer "F.Fab")
		)
		(fp_line
			(start -0.12065 -0.2794)
			(end 0.12065 -0.2794)
			(stroke
				(width 0.1)
				(type default)
			)
			(layer "F.Fab")
		)
		(fp_line
			(start -0.12065 -0.305054)
			(end -0.12065 -0.2794)
			(stroke
				(width 0.1)
				(type default)
			)
			(layer "F.Fab")
		)
		(fp_line
			(start -0.67945 0.3048)
			(end -0.67945 -0.305054)
			(stroke
				(width 0.1)
				(type default)
			)
			(layer "F.Fab")
		)
		(fp_line
			(start -0.67945 -0.305054)
			(end -0.12065 -0.305054)
			(stroke
				(width 0.1)
				(type default)
			)
			(layer "F.Fab")
		)
		(pad "1" smd circle
			(at -0.40005 0 180)
			(size 0 0)
			(layers "F.Cu" "F.Mask" "F.Paste")
			(net "PVDD18_S5_P0")
		)
		(pad "2" smd circle
			(at 0.40005 0 180)
			(size 0 0)
			(layers "F.Cu" "F.Mask" "F.Paste")
			(net "GND")
		)
	)
	(footprint ""
		(layer "F.Cu")
		(at 22.49297 -332.104746)
		(property "Reference" "PR227"
			(at 0 0 0)
			(layer "F.SilkS")
			(hide yes)
			(effects
				(font
					(size 1.27 1.27)
				)
			)
		)
		(property "Value" ""
			(at 0 0 0)
			(layer "F.Fab")
			(effects
				(font
					(size 1.27 1.27)
				)
			)
		)
		(duplicate_pad_numbers_are_jumpers no)
		(fp_line
			(start -0.7874 -0.4064)
			(end 0.7874 -0.4064)
			(stroke
				(width 0.1524)
				(type default)
			)
			(layer "F.SilkS")
		)
		(fp_line
			(start -0.7874 0.4064)
			(end -0.7874 -0.4064)
			(stroke
				(width 0.1524)
				(type default)
			)
			(layer "F.SilkS")
		)
		(fp_line
			(start 0.7874 -0.4064)
			(end 0.7874 0.4064)
			(stroke
				(width 0.1524)
				(type default)
			)
			(layer "F.SilkS")
		)
		(fp_line
			(start 0.7874 0.4064)
			(end -0.7874 0.4064)
			(stroke
				(width 0.1524)
				(type default)
			)
			(layer "F.SilkS")
		)
		(fp_line
			(start -0.67945 -0.305054)
			(end -0.12065 -0.305054)
			(stroke
				(width 0.1)
				(type default)
			)
			(layer "F.Fab")
		)
		(fp_line
			(start -0.67945 0.3048)
			(end -0.67945 -0.305054)
			(stroke
				(width 0.1)
				(type default)
			)
			(layer "F.Fab")
		)
		(fp_line
			(start -0.12065 -0.305054)
			(end -0.12065 -0.2794)
			(stroke
				(width 0.1)
				(type default)
			)
			(layer "F.Fab")
		)
		(fp_line
			(start -0.12065 -0.2794)
			(end 0.12065 -0.2794)
			(stroke
				(width 0.1)
				(type default)
			)
			(layer "F.Fab")
		)
		(fp_line
			(start -0.12065 0.2794)
			(end -0.12065 0.3048)
			(stroke
				(width 0.1)
				(type default)
			)
			(layer "F.Fab")
		)
		(fp_line
			(start -0.12065 0.3048)
			(end -0.67945 0.3048)
			(stroke
				(width 0.1)
				(type default)
			)
			(layer "F.Fab")
		)
		(fp_line
			(start 0.120396 0.2794)
			(end -0.12065 0.2794)
			(stroke
				(width 0.1)
				(type default)
			)
			(layer "F.Fab")
		)
		(fp_line
			(start 0.120396 0.3048)
			(end 0.120396 0.2794)
			(stroke
				(width 0.1)
				(type default)
			)
			(layer "F.Fab")
		)
		(fp_line
			(start 0.12065 -0.3048)
			(end 0.67945 -0.3048)
			(stroke
				(width 0.1)
				(type default)
			)
			(layer "F.Fab")
		)
		(fp_line
			(start 0.12065 -0.2794)
			(end 0.12065 -0.3048)
			(stroke
				(width 0.1)
				(type default)
			)
			(layer "F.Fab")
		)
		(fp_line
			(start 0.67945 -0.3048)
			(end 0.67945 0.3048)
			(stroke
				(width 0.1)
				(type default)
			)
			(layer "F.Fab")
		)
		(fp_line
			(start 0.67945 0.3048)
			(end 0.120396 0.3048)
			(stroke
				(width 0.1)
				(type default)
			)
			(layer "F.Fab")
		)
		(pad "1" smd circle
			(at -0.40005 0)
			(size 0 0)
			(layers "F.Cu" "F.Mask" "F.Paste")
			(net "VSENSE_PVDDIO_P1_DP")
		)
		(pad "2" smd circle
			(at 0.40005 0)
			(size 0 0)
			(layers "F.Cu" "F.Mask" "F.Paste")
			(net "PVDDIO_P1")
		)
	)
	(footprint ""
		(layer "F.Cu")
		(at 98.222562 -31.835598 -90)
		(property "Reference" "C6089"
			(at 0 0 270)
			(layer "F.SilkS")
			(hide yes)
			(effects
				(font
					(size 1.27 1.27)
				)
			)
		)
		(property "Value" ""
			(at 0 0 270)
			(layer "F.Fab")
			(effects
				(font
					(size 1.27 1.27)
				)
			)
		)
		(duplicate_pad_numbers_are_jumpers no)
		(fp_line
			(start -0.7874 0.4064)
			(end -0.7874 -0.4064)
			(stroke
				(width 0.1524)
				(type default)
			)
			(layer "F.SilkS")
		)
		(fp_line
			(start 0.7874 0.4064)
			(end -0.7874 0.4064)
			(stroke
				(width 0.1524)
				(type default)
			)
			(layer "F.SilkS")
		)
		(fp_line
			(start -0.7874 -0.4064)
			(end 0.7874 -0.4064)
			(stroke
				(width 0.1524)
				(type default)
			)
			(layer "F.SilkS")
		)
		(fp_line
			(start 0.7874 -0.4064)
			(end 0.7874 0.4064)
			(stroke
				(width 0.1524)
				(type default)
			)
			(layer "F.SilkS")
		)
		(fp_line
			(start -0.67945 0.3048)
			(end -0.67945 -0.305054)
			(stroke
				(width 0.1)
				(type default)
			)
			(layer "F.Fab")
		)
		(fp_line
			(start -0.12065 0.3048)
			(end -0.67945 0.3048)
			(stroke
				(width 0.1)
				(type default)
			)
			(layer "F.Fab")
		)
		(fp_line
			(start 0.120396 0.3048)
			(end 0.120396 0.2794)
			(stroke
				(width 0.1)
				(type default)
			)
			(layer "F.Fab")
		)
		(fp_line
			(start 0.67945 0.3048)
			(end 0.120396 0.3048)
			(stroke
				(width 0.1)
				(type default)
			)
			(layer "F.Fab")
		)
		(fp_line
			(start -0.12065 0.2794)
			(end -0.12065 0.3048)
			(stroke
				(width 0.1)
				(type default)
			)
			(layer "F.Fab")
		)
		(fp_line
			(start 0.120396 0.2794)
			(end -0.12065 0.2794)
			(stroke
				(width 0.1)
				(type default)
			)
			(layer "F.Fab")
		)
		(fp_line
			(start -0.12065 -0.2794)
			(end 0.12065 -0.2794)
			(stroke
				(width 0.1)
				(type default)
			)
			(layer "F.Fab")
		)
		(fp_line
			(start 0.12065 -0.2794)
			(end 0.12065 -0.3048)
			(stroke
				(width 0.1)
				(type default)
			)
			(layer "F.Fab")
		)
		(fp_line
			(start 0.12065 -0.3048)
			(end 0.67945 -0.3048)
			(stroke
				(width 0.1)
				(type default)
			)
			(layer "F.Fab")
		)
		(fp_line
			(start 0.67945 -0.3048)
			(end 0.67945 0.3048)
			(stroke
				(width 0.1)
				(type default)
			)
			(layer "F.Fab")
		)
		(fp_line
			(start -0.67945 -0.305054)
			(end -0.12065 -0.305054)
			(stroke
				(width 0.1)
				(type default)
			)
			(layer "F.Fab")
		)
		(fp_line
			(start -0.12065 -0.305054)
			(end -0.12065 -0.2794)
			(stroke
				(width 0.1)
				(type default)
			)
			(layer "F.Fab")
		)
		(pad "1" smd circle
			(at -0.40005 0 270)
			(size 0 0)
			(layers "F.Cu" "F.Mask" "F.Paste")
			(net "USB_HUB2_TI_GRSTZ_MRP_PROG_FUNC1")
		)
		(pad "2" smd circle
			(at 0.40005 0 270)
			(size 0 0)
			(layers "F.Cu" "F.Mask" "F.Paste")
			(net "GND")
		)
	)
	(footprint ""
		(layer "F.Cu")
		(at 368.06378 -427.411388 -90)
		(property "Reference" "R4198"
			(at 0 0 270)
			(layer "F.SilkS")
			(hide yes)
			(effects
				(font
					(size 1.27 1.27)
				)
			)
		)
		(property "Value" ""
			(at 0 0 270)
			(layer "F.Fab")
			(effects
				(font
					(size 1.27 1.27)
				)
			)
		)
		(duplicate_pad_numbers_are_jumpers no)
		(fp_line
			(start -0.7874 0.4064)
			(end -0.7874 -0.4064)
			(stroke
				(width 0.1524)
				(type default)
			)
			(layer "F.SilkS")
		)
		(fp_line
			(start 0.7874 0.4064)
			(end -0.7874 0.4064)
			(stroke
				(width 0.1524)
				(type default)
			)
			(layer "F.SilkS")
		)
		(fp_line
			(start -0.7874 -0.4064)
			(end 0.7874 -0.4064)
			(stroke
				(width 0.1524)
				(type default)
			)
			(layer "F.SilkS")
		)
		(fp_line
			(start 0.7874 -0.4064)
			(end 0.7874 0.4064)
			(stroke
				(width 0.1524)
				(type default)
			)
			(layer "F.SilkS")
		)
		(fp_line
			(start -0.67945 0.3048)
			(end -0.67945 -0.305054)
			(stroke
				(width 0.1)
				(type default)
			)
			(layer "F.Fab")
		)
		(fp_line
			(start -0.12065 0.3048)
			(end -0.67945 0.3048)
			(stroke
				(width 0.1)
				(type default)
			)
			(layer "F.Fab")
		)
		(fp_line
			(start 0.120396 0.3048)
			(end 0.120396 0.2794)
			(stroke
				(width 0.1)
				(type default)
			)
			(layer "F.Fab")
		)
		(fp_line
			(start 0.67945 0.3048)
			(end 0.120396 0.3048)
			(stroke
				(width 0.1)
				(type default)
			)
			(layer "F.Fab")
		)
		(fp_line
			(start -0.12065 0.2794)
			(end -0.12065 0.3048)
			(stroke
				(width 0.1)
				(type default)
			)
			(layer "F.Fab")
		)
		(fp_line
			(start 0.120396 0.2794)
			(end -0.12065 0.2794)
			(stroke
				(width 0.1)
				(type default)
			)
			(layer "F.Fab")
		)
		(fp_line
			(start -0.12065 -0.2794)
			(end 0.12065 -0.2794)
			(stroke
				(width 0.1)
				(type default)
			)
			(layer "F.Fab")
		)
		(fp_line
			(start 0.12065 -0.2794)
			(end 0.12065 -0.3048)
			(stroke
				(width 0.1)
				(type default)
			)
			(layer "F.Fab")
		)
		(fp_line
			(start 0.12065 -0.3048)
			(end 0.67945 -0.3048)
			(stroke
				(width 0.1)
				(type default)
			)
			(layer "F.Fab")
		)
		(fp_line
			(start 0.67945 -0.3048)
			(end 0.67945 0.3048)
			(stroke
				(width 0.1)
				(type default)
			)
			(layer "F.Fab")
		)
		(fp_line
			(start -0.67945 -0.305054)
			(end -0.12065 -0.305054)
			(stroke
				(width 0.1)
				(type default)
			)
			(layer "F.Fab")
		)
		(fp_line
			(start -0.12065 -0.305054)
			(end -0.12065 -0.2794)
			(stroke
				(width 0.1)
				(type default)
			)
			(layer "F.Fab")
		)
		(pad "1" smd circle
			(at -0.40005 0 270)
			(size 0 0)
			(layers "F.Cu" "F.Mask" "F.Paste")
			(net "P3V3_AUX")
		)
		(pad "2" smd circle
			(at 0.40005 0 270)
			(size 0 0)
			(layers "F.Cu" "F.Mask" "F.Paste")
			(net "U270_0_ADD1")
		)
	)
	(footprint ""
		(layer "F.Cu")
		(at 449.443602 -420.99611 180)
		(property "Reference" "R652"
			(at 0 0 180)
			(layer "F.SilkS")
			(hide yes)
			(effects
				(font
					(size 1.27 1.27)
				)
			)
		)
		(property "Value" ""
			(at 0 0 180)
			(layer "F.Fab")
			(effects
				(font
					(size 1.27 1.27)
				)
			)
		)
		(duplicate_pad_numbers_are_jumpers no)
		(fp_line
			(start 0.7874 0.4064)
			(end -0.7874 0.4064)
			(stroke
				(width 0.1524)
				(type default)
			)
			(layer "F.SilkS")
		)
		(fp_line
			(start 0.7874 -0.4064)
			(end 0.7874 0.4064)
			(stroke
				(width 0.1524)
				(type default)
			)
			(layer "F.SilkS")
		)
		(fp_line
			(start -0.7874 0.4064)
			(end -0.7874 -0.4064)
			(stroke
				(width 0.1524)
				(type default)
			)
			(layer "F.SilkS")
		)
		(fp_line
			(start -0.7874 -0.4064)
			(end 0.7874 -0.4064)
			(stroke
				(width 0.1524)
				(type default)
			)
			(layer "F.SilkS")
		)
		(fp_line
			(start 0.67945 0.3048)
			(end 0.120396 0.3048)
			(stroke
				(width 0.1)
				(type default)
			)
			(layer "F.Fab")
		)
		(fp_line
			(start 0.67945 -0.3048)
			(end 0.67945 0.3048)
			(stroke
				(width 0.1)
				(type default)
			)
			(layer "F.Fab")
		)
		(fp_line
			(start 0.12065 -0.2794)
			(end 0.12065 -0.3048)
			(stroke
				(width 0.1)
				(type default)
			)
			(layer "F.Fab")
		)
		(fp_line
			(start 0.12065 -0.3048)
			(end 0.67945 -0.3048)
			(stroke
				(width 0.1)
				(type default)
			)
			(layer "F.Fab")
		)
		(fp_line
			(start 0.120396 0.3048)
			(end 0.120396 0.2794)
			(stroke
				(width 0.1)
				(type default)
			)
			(layer "F.Fab")
		)
		(fp_line
			(start 0.120396 0.2794)
			(end -0.12065 0.2794)
			(stroke
				(width 0.1)
				(type default)
			)
			(layer "F.Fab")
		)
		(fp_line
			(start -0.12065 0.3048)
			(end -0.67945 0.3048)
			(stroke
				(width 0.1)
				(type default)
			)
			(layer "F.Fab")
		)
		(fp_line
			(start -0.12065 0.2794)
			(end -0.12065 0.3048)
			(stroke
				(width 0.1)
				(type default)
			)
			(layer "F.Fab")
		)
		(fp_line
			(start -0.12065 -0.2794)
			(end 0.12065 -0.2794)
			(stroke
				(width 0.1)
				(type default)
			)
			(layer "F.Fab")
		)
		(fp_line
			(start -0.12065 -0.305054)
			(end -0.12065 -0.2794)
			(stroke
				(width 0.1)
				(type default)
			)
			(layer "F.Fab")
		)
		(fp_line
			(start -0.67945 0.3048)
			(end -0.67945 -0.305054)
			(stroke
				(width 0.1)
				(type default)
			)
			(layer "F.Fab")
		)
		(fp_line
			(start -0.67945 -0.305054)
			(end -0.12065 -0.305054)
			(stroke
				(width 0.1)
				(type default)
			)
			(layer "F.Fab")
		)
		(pad "1" smd circle
			(at -0.40005 0 180)
			(size 0 0)
			(layers "F.Cu" "F.Mask" "F.Paste")
			(net "P3V3_AUX")
		)
		(pad "2" smd circle
			(at 0.40005 0 180)
			(size 0 0)
			(layers "F.Cu" "F.Mask" "F.Paste")
			(net "P0V9_RETIMER_CPU0_CFP")
		)
	)
	(footprint ""
		(layer "F.Cu")
		(at 407.452322 -163.382198)
		(property "Reference" "PR359"
			(at 0 0 0)
			(layer "F.SilkS")
			(hide yes)
			(effects
				(font
					(size 1.27 1.27)
				)
			)
		)
		(property "Value" ""
			(at 0 0 0)
			(layer "F.Fab")
			(effects
				(font
					(size 1.27 1.27)
				)
			)
		)
		(duplicate_pad_numbers_are_jumpers no)
		(fp_line
			(start -0.7874 -0.4064)
			(end 0.7874 -0.4064)
			(stroke
				(width 0.1524)
				(type default)
			)
			(layer "F.SilkS")
		)
		(fp_line
			(start -0.7874 0.4064)
			(end -0.7874 -0.4064)
			(stroke
				(width 0.1524)
				(type default)
			)
			(layer "F.SilkS")
		)
		(fp_line
			(start 0.7874 -0.4064)
			(end 0.7874 0.4064)
			(stroke
				(width 0.1524)
				(type default)
			)
			(layer "F.SilkS")
		)
		(fp_line
			(start 0.7874 0.4064)
			(end -0.7874 0.4064)
			(stroke
				(width 0.1524)
				(type default)
			)
			(layer "F.SilkS")
		)
		(fp_line
			(start -0.67945 -0.305054)
			(end -0.12065 -0.305054)
			(stroke
				(width 0.1)
				(type default)
			)
			(layer "F.Fab")
		)
		(fp_line
			(start -0.67945 0.3048)
			(end -0.67945 -0.305054)
			(stroke
				(width 0.1)
				(type default)
			)
			(layer "F.Fab")
		)
		(fp_line
			(start -0.12065 -0.305054)
			(end -0.12065 -0.2794)
			(stroke
				(width 0.1)
				(type default)
			)
			(layer "F.Fab")
		)
		(fp_line
			(start -0.12065 -0.2794)
			(end 0.12065 -0.2794)
			(stroke
				(width 0.1)
				(type default)
			)
			(layer "F.Fab")
		)
		(fp_line
			(start -0.12065 0.2794)
			(end -0.12065 0.3048)
			(stroke
				(width 0.1)
				(type default)
			)
			(layer "F.Fab")
		)
		(fp_line
			(start -0.12065 0.3048)
			(end -0.67945 0.3048)
			(stroke
				(width 0.1)
				(type default)
			)
			(layer "F.Fab")
		)
		(fp_line
			(start 0.120396 0.2794)
			(end -0.12065 0.2794)
			(stroke
				(width 0.1)
				(type default)
			)
			(layer "F.Fab")
		)
		(fp_line
			(start 0.120396 0.3048)
			(end 0.120396 0.2794)
			(stroke
				(width 0.1)
				(type default)
			)
			(layer "F.Fab")
		)
		(fp_line
			(start 0.12065 -0.3048)
			(end 0.67945 -0.3048)
			(stroke
				(width 0.1)
				(type default)
			)
			(layer "F.Fab")
		)
		(fp_line
			(start 0.12065 -0.2794)
			(end 0.12065 -0.3048)
			(stroke
				(width 0.1)
				(type default)
			)
			(layer "F.Fab")
		)
		(fp_line
			(start 0.67945 -0.3048)
			(end 0.67945 0.3048)
			(stroke
				(width 0.1)
				(type default)
			)
			(layer "F.Fab")
		)
		(fp_line
			(start 0.67945 0.3048)
			(end 0.120396 0.3048)
			(stroke
				(width 0.1)
				(type default)
			)
			(layer "F.Fab")
		)
		(pad "1" smd circle
			(at -0.40005 0)
			(size 0 0)
			(layers "F.Cu" "F.Mask" "F.Paste")
			(net "GND")
		)
		(pad "2" smd circle
			(at 0.40005 0)
			(size 0 0)
			(layers "F.Cu" "F.Mask" "F.Paste")
			(net "PVDDCR_SOC_P0_LSET2")
		)
	)
	(footprint ""
		(layer "F.Cu")
		(at 149.649434 -321.733672 180)
		(property "Reference" "R373"
			(at 0 0 180)
			(layer "F.SilkS")
			(hide yes)
			(effects
				(font
					(size 1.27 1.27)
				)
			)
		)
		(property "Value" ""
			(at 0 0 180)
			(layer "F.Fab")
			(effects
				(font
					(size 1.27 1.27)
				)
			)
		)
		(duplicate_pad_numbers_are_jumpers no)
		(fp_line
			(start 0.7874 0.4064)
			(end -0.7874 0.4064)
			(stroke
				(width 0.1524)
				(type default)
			)
			(layer "F.SilkS")
		)
		(fp_line
			(start 0.7874 -0.4064)
			(end 0.7874 0.4064)
			(stroke
				(width 0.1524)
				(type default)
			)
			(layer "F.SilkS")
		)
		(fp_line
			(start -0.7874 0.4064)
			(end -0.7874 -0.4064)
			(stroke
				(width 0.1524)
				(type default)
			)
			(layer "F.SilkS")
		)
		(fp_line
			(start -0.7874 -0.4064)
			(end 0.7874 -0.4064)
			(stroke
				(width 0.1524)
				(type default)
			)
			(layer "F.SilkS")
		)
		(fp_line
			(start 0.67945 0.3048)
			(end 0.120396 0.3048)
			(stroke
				(width 0.1)
				(type default)
			)
			(layer "F.Fab")
		)
		(fp_line
			(start 0.67945 -0.3048)
			(end 0.67945 0.3048)
			(stroke
				(width 0.1)
				(type default)
			)
			(layer "F.Fab")
		)
		(fp_line
			(start 0.12065 -0.2794)
			(end 0.12065 -0.3048)
			(stroke
				(width 0.1)
				(type default)
			)
			(layer "F.Fab")
		)
		(fp_line
			(start 0.12065 -0.3048)
			(end 0.67945 -0.3048)
			(stroke
				(width 0.1)
				(type default)
			)
			(layer "F.Fab")
		)
		(fp_line
			(start 0.120396 0.3048)
			(end 0.120396 0.2794)
			(stroke
				(width 0.1)
				(type default)
			)
			(layer "F.Fab")
		)
		(fp_line
			(start 0.120396 0.2794)
			(end -0.12065 0.2794)
			(stroke
				(width 0.1)
				(type default)
			)
			(layer "F.Fab")
		)
		(fp_line
			(start -0.12065 0.3048)
			(end -0.67945 0.3048)
			(stroke
				(width 0.1)
				(type default)
			)
			(layer "F.Fab")
		)
		(fp_line
			(start -0.12065 0.2794)
			(end -0.12065 0.3048)
			(stroke
				(width 0.1)
				(type default)
			)
			(layer "F.Fab")
		)
		(fp_line
			(start -0.12065 -0.2794)
			(end 0.12065 -0.2794)
			(stroke
				(width 0.1)
				(type default)
			)
			(layer "F.Fab")
		)
		(fp_line
			(start -0.12065 -0.305054)
			(end -0.12065 -0.2794)
			(stroke
				(width 0.1)
				(type default)
			)
			(layer "F.Fab")
		)
		(fp_line
			(start -0.67945 0.3048)
			(end -0.67945 -0.305054)
			(stroke
				(width 0.1)
				(type default)
			)
			(layer "F.Fab")
		)
		(fp_line
			(start -0.67945 -0.305054)
			(end -0.12065 -0.305054)
			(stroke
				(width 0.1)
				(type default)
			)
			(layer "F.Fab")
		)
		(pad "1" smd circle
			(at -0.40005 0 180)
			(size 0 0)
			(layers "F.Cu" "F.Mask" "F.Paste")
			(net "P1V5_BAT")
		)
		(pad "2" smd circle
			(at 0.40005 0 180)
			(size 0 0)
			(layers "F.Cu" "F.Mask" "F.Paste")
			(net "CPU1_VDDBT_RTC_G")
		)
	)
	(footprint ""
		(layer "F.Cu")
		(at 174.635922 -24.601932)
		(property "Reference" "PR4014"
			(at 0 0 0)
			(layer "F.SilkS")
			(hide yes)
			(effects
				(font
					(size 1.27 1.27)
				)
			)
		)
		(property "Value" ""
			(at 0 0 0)
			(layer "F.Fab")
			(effects
				(font
					(size 1.27 1.27)
				)
			)
		)
		(duplicate_pad_numbers_are_jumpers no)
		(fp_line
			(start -1.2954 -0.5842)
			(end 1.2954 -0.5842)
			(stroke
				(width 0.1524)
				(type default)
			)
			(layer "F.SilkS")
		)
		(fp_line
			(start -1.2954 0.5842)
			(end -1.2954 -0.5842)
			(stroke
				(width 0.1524)
				(type default)
			)
			(layer "F.SilkS")
		)
		(fp_line
			(start 1.2954 -0.5842)
			(end 1.2954 0.5842)
			(stroke
				(width 0.1524)
				(type default)
			)
			(layer "F.SilkS")
		)
		(fp_line
			(start 1.2954 0.5842)
			(end -1.2954 0.5842)
			(stroke
				(width 0.1524)
				(type default)
			)
			(layer "F.SilkS")
		)
		(fp_line
			(start -1.1938 -0.406654)
			(end -0.8636 -0.406654)
			(stroke
				(width 0.1)
				(type default)
			)
			(layer "F.Fab")
		)
		(fp_line
			(start -1.1938 0.4064)
			(end -1.1938 -0.406654)
			(stroke
				(width 0.1)
				(type default)
			)
			(layer "F.Fab")
		)
		(fp_line
			(start -0.8636 -0.4572)
			(end 0.8636 -0.4572)
			(stroke
				(width 0.1)
				(type default)
			)
			(layer "F.Fab")
		)
		(fp_line
			(start -0.8636 -0.406654)
			(end -0.8636 -0.4572)
			(stroke
				(width 0.1)
				(type default)
			)
			(layer "F.Fab")
		)
		(fp_line
			(start -0.8636 0.4064)
			(end -1.1938 0.4064)
			(stroke
				(width 0.1)
				(type default)
			)
			(layer "F.Fab")
		)
		(fp_line
			(start -0.8636 0.4318)
			(end -0.8636 0.4064)
			(stroke
				(width 0.1)
				(type default)
			)
			(layer "F.Fab")
		)
		(fp_line
			(start -0.8636 0.4572)
			(end -0.8636 0.4318)
			(stroke
				(width 0.1)
				(type default)
			)
			(layer "F.Fab")
		)
		(fp_line
			(start 0.8636 -0.4572)
			(end 0.8636 -0.406654)
			(stroke
				(width 0.1)
				(type default)
			)
			(layer "F.Fab")
		)
		(fp_line
			(start 0.8636 -0.406654)
			(end 1.1938 -0.406654)
			(stroke
				(width 0.1)
				(type default)
			)
			(layer "F.Fab")
		)
		(fp_line
			(start 0.8636 0.4064)
			(end 0.8636 0.4572)
			(stroke
				(width 0.1)
				(type default)
			)
			(layer "F.Fab")
		)
		(fp_line
			(start 0.8636 0.4572)
			(end -0.8636 0.4572)
			(stroke
				(width 0.1)
				(type default)
			)
			(layer "F.Fab")
		)
		(fp_line
			(start 1.1938 -0.406654)
			(end 1.1938 0.4064)
			(stroke
				(width 0.1)
				(type default)
			)
			(layer "F.Fab")
		)
		(fp_line
			(start 1.1938 0.4064)
			(end 0.8636 0.4064)
			(stroke
				(width 0.1)
				(type default)
			)
			(layer "F.Fab")
		)
		(pad "1" smd rect
			(at -0.7366 0 270)
			(size 0.7112 0.8128)
			(layers "F.Cu" "F.Mask" "F.Paste")
			(net "P12V_AUX")
		)
		(pad "2" smd rect
			(at 0.7366 0 270)
			(size 0.7112 0.8128)
			(layers "F.Cu" "F.Mask" "F.Paste")
			(net "P12V_SCM_AVIN_PD")
		)
	)
	(footprint ""
		(layer "F.Cu")
		(at 170.2308 -386.3848)
		(property "Reference" "C367"
			(at 0 0 0)
			(layer "F.SilkS")
			(hide yes)
			(effects
				(font
					(size 1.27 1.27)
				)
			)
		)
		(property "Value" ""
			(at 0 0 0)
			(layer "F.Fab")
			(effects
				(font
					(size 1.27 1.27)
				)
			)
		)
		(duplicate_pad_numbers_are_jumpers no)
		(fp_line
			(start -1.524 -0.762)
			(end 1.524 -0.762)
			(stroke
				(width 0.1524)
				(type default)
			)
			(layer "F.SilkS")
		)
		(fp_line
			(start -1.524 0.762)
			(end -1.524 -0.762)
			(stroke
				(width 0.1524)
				(type default)
			)
			(layer "F.SilkS")
		)
		(fp_line
			(start 1.524 -0.762)
			(end 1.524 0.762)
			(stroke
				(width 0.1524)
				(type default)
			)
			(layer "F.SilkS")
		)
		(fp_line
			(start 1.524 0.762)
			(end -1.524 0.762)
			(stroke
				(width 0.1524)
				(type default)
			)
			(layer "F.SilkS")
		)
		(fp_line
			(start -1.1049 -0.724916)
			(end -1.1049 0.724916)
			(stroke
				(width 0.1)
				(type default)
			)
			(layer "F.Fab")
		)
		(fp_line
			(start -1.1049 0.724916)
			(end 1.1049 0.724916)
			(stroke
				(width 0.1)
				(type default)
			)
			(layer "F.Fab")
		)
		(fp_line
			(start 1.1049 -0.724916)
			(end -1.1049 -0.724916)
			(stroke
				(width 0.1)
				(type default)
			)
			(layer "F.Fab")
		)
		(fp_line
			(start 1.1049 0.724916)
			(end 1.1049 -0.724916)
			(stroke
				(width 0.1)
				(type default)
			)
			(layer "F.Fab")
		)
		(pad "1" smd rect
			(at -0.889 0 180)
			(size 1.016 1.27)
			(layers "F.Cu" "F.Mask" "F.Paste")
			(net "P1V8_CPU1_RT2_1A")
		)
		(pad "2" smd rect
			(at 0.889 0 180)
			(size 1.016 1.27)
			(layers "F.Cu" "F.Mask" "F.Paste")
			(net "GND")
		)
	)
	(footprint ""
		(layer "F.Cu")
		(at 120.396 -435.483)
		(property "Reference" "R3495"
			(at 0 0 0)
			(layer "F.SilkS")
			(hide yes)
			(effects
				(font
					(size 1.27 1.27)
				)
			)
		)
		(property "Value" ""
			(at 0 0 0)
			(layer "F.Fab")
			(effects
				(font
					(size 1.27 1.27)
				)
			)
		)
		(duplicate_pad_numbers_are_jumpers no)
		(fp_line
			(start -0.7874 -0.4064)
			(end 0.7874 -0.4064)
			(stroke
				(width 0.1524)
				(type default)
			)
			(layer "F.SilkS")
		)
		(fp_line
			(start -0.7874 0.4064)
			(end -0.7874 -0.4064)
			(stroke
				(width 0.1524)
				(type default)
			)
			(layer "F.SilkS")
		)
		(fp_line
			(start 0.7874 -0.4064)
			(end 0.7874 0.4064)
			(stroke
				(width 0.1524)
				(type default)
			)
			(layer "F.SilkS")
		)
		(fp_line
			(start 0.7874 0.4064)
			(end -0.7874 0.4064)
			(stroke
				(width 0.1524)
				(type default)
			)
			(layer "F.SilkS")
		)
		(fp_line
			(start -0.67945 -0.305054)
			(end -0.12065 -0.305054)
			(stroke
				(width 0.1)
				(type default)
			)
			(layer "F.Fab")
		)
		(fp_line
			(start -0.67945 0.3048)
			(end -0.67945 -0.305054)
			(stroke
				(width 0.1)
				(type default)
			)
			(layer "F.Fab")
		)
		(fp_line
			(start -0.12065 -0.305054)
			(end -0.12065 -0.2794)
			(stroke
				(width 0.1)
				(type default)
			)
			(layer "F.Fab")
		)
		(fp_line
			(start -0.12065 -0.2794)
			(end 0.12065 -0.2794)
			(stroke
				(width 0.1)
				(type default)
			)
			(layer "F.Fab")
		)
		(fp_line
			(start -0.12065 0.2794)
			(end -0.12065 0.3048)
			(stroke
				(width 0.1)
				(type default)
			)
			(layer "F.Fab")
		)
		(fp_line
			(start -0.12065 0.3048)
			(end -0.67945 0.3048)
			(stroke
				(width 0.1)
				(type default)
			)
			(layer "F.Fab")
		)
		(fp_line
			(start 0.120396 0.2794)
			(end -0.12065 0.2794)
			(stroke
				(width 0.1)
				(type default)
			)
			(layer "F.Fab")
		)
		(fp_line
			(start 0.120396 0.3048)
			(end 0.120396 0.2794)
			(stroke
				(width 0.1)
				(type default)
			)
			(layer "F.Fab")
		)
		(fp_line
			(start 0.12065 -0.3048)
			(end 0.67945 -0.3048)
			(stroke
				(width 0.1)
				(type default)
			)
			(layer "F.Fab")
		)
		(fp_line
			(start 0.12065 -0.2794)
			(end 0.12065 -0.3048)
			(stroke
				(width 0.1)
				(type default)
			)
			(layer "F.Fab")
		)
		(fp_line
			(start 0.67945 -0.3048)
			(end 0.67945 0.3048)
			(stroke
				(width 0.1)
				(type default)
			)
			(layer "F.Fab")
		)
		(fp_line
			(start 0.67945 0.3048)
			(end 0.120396 0.3048)
			(stroke
				(width 0.1)
				(type default)
			)
			(layer "F.Fab")
		)
		(pad "1" smd circle
			(at -0.40005 0)
			(size 0 0)
			(layers "F.Cu" "F.Mask" "F.Paste")
			(net "GPU_FPGA_EROT_RECOV_BUF_R_N")
		)
		(pad "2" smd circle
			(at 0.40005 0)
			(size 0 0)
			(layers "F.Cu" "F.Mask" "F.Paste")
			(net "GND")
		)
	)
	(footprint ""
		(layer "F.Cu")
		(at 296.385742 -397.4084 -90)
		(property "Reference" "R974"
			(at 0 0 270)
			(layer "F.SilkS")
			(hide yes)
			(effects
				(font
					(size 1.27 1.27)
				)
			)
		)
		(property "Value" ""
			(at 0 0 270)
			(layer "F.Fab")
			(effects
				(font
					(size 1.27 1.27)
				)
			)
		)
		(duplicate_pad_numbers_are_jumpers no)
		(fp_line
			(start -0.32512 0.175006)
			(end -0.32512 -0.175006)
			(stroke
				(width 0.1)
				(type default)
			)
			(layer "F.Fab")
		)
		(fp_line
			(start 0.32512 0.175006)
			(end -0.32512 0.175006)
			(stroke
				(width 0.1)
				(type default)
			)
			(layer "F.Fab")
		)
		(fp_line
			(start -0.32512 -0.175006)
			(end 0.32512 -0.175006)
			(stroke
				(width 0.1)
				(type default)
			)
			(layer "F.Fab")
		)
		(fp_line
			(start 0.32512 -0.175006)
			(end 0.32512 0.175006)
			(stroke
				(width 0.1)
				(type default)
			)
			(layer "F.Fab")
		)
		(pad "1" smd rect
			(at -0.2667 0 270)
			(size 0.3048 0.381)
			(layers "F.Cu" "F.Mask" "F.Paste")
			(net "P1V8_CPU0_RT_1D")
		)
		(pad "2" smd rect
			(at 0.2667 0 90)
			(size 0.3048 0.381)
			(layers "F.Cu" "F.Mask" "F.Paste")
			(net "RST_RT_CPU0_P0_RESET_R_N")
		)
	)
	(footprint ""
		(layer "F.Cu")
		(at 279.670256 -430.791366 180)
		(property "Reference" "R4264"
			(at 0 0 180)
			(layer "F.SilkS")
			(hide yes)
			(effects
				(font
					(size 1.27 1.27)
				)
			)
		)
		(property "Value" ""
			(at 0 0 180)
			(layer "F.Fab")
			(effects
				(font
					(size 1.27 1.27)
				)
			)
		)
		(duplicate_pad_numbers_are_jumpers no)
		(fp_line
			(start 0.7874 0.4064)
			(end -0.7874 0.4064)
			(stroke
				(width 0.1524)
				(type default)
			)
			(layer "F.SilkS")
		)
		(fp_line
			(start 0.7874 -0.4064)
			(end 0.7874 0.4064)
			(stroke
				(width 0.1524)
				(type default)
			)
			(layer "F.SilkS")
		)
		(fp_line
			(start -0.7874 0.4064)
			(end -0.7874 -0.4064)
			(stroke
				(width 0.1524)
				(type default)
			)
			(layer "F.SilkS")
		)
		(fp_line
			(start -0.7874 -0.4064)
			(end 0.7874 -0.4064)
			(stroke
				(width 0.1524)
				(type default)
			)
			(layer "F.SilkS")
		)
		(fp_line
			(start 0.67945 0.3048)
			(end 0.120396 0.3048)
			(stroke
				(width 0.1)
				(type default)
			)
			(layer "F.Fab")
		)
		(fp_line
			(start 0.67945 -0.3048)
			(end 0.67945 0.3048)
			(stroke
				(width 0.1)
				(type default)
			)
			(layer "F.Fab")
		)
		(fp_line
			(start 0.12065 -0.2794)
			(end 0.12065 -0.3048)
			(stroke
				(width 0.1)
				(type default)
			)
			(layer "F.Fab")
		)
		(fp_line
			(start 0.12065 -0.3048)
			(end 0.67945 -0.3048)
			(stroke
				(width 0.1)
				(type default)
			)
			(layer "F.Fab")
		)
		(fp_line
			(start 0.120396 0.3048)
			(end 0.120396 0.2794)
			(stroke
				(width 0.1)
				(type default)
			)
			(layer "F.Fab")
		)
		(fp_line
			(start 0.120396 0.2794)
			(end -0.12065 0.2794)
			(stroke
				(width 0.1)
				(type default)
			)
			(layer "F.Fab")
		)
		(fp_line
			(start -0.12065 0.3048)
			(end -0.67945 0.3048)
			(stroke
				(width 0.1)
				(type default)
			)
			(layer "F.Fab")
		)
		(fp_line
			(start -0.12065 0.2794)
			(end -0.12065 0.3048)
			(stroke
				(width 0.1)
				(type default)
			)
			(layer "F.Fab")
		)
		(fp_line
			(start -0.12065 -0.2794)
			(end 0.12065 -0.2794)
			(stroke
				(width 0.1)
				(type default)
			)
			(layer "F.Fab")
		)
		(fp_line
			(start -0.12065 -0.305054)
			(end -0.12065 -0.2794)
			(stroke
				(width 0.1)
				(type default)
			)
			(layer "F.Fab")
		)
		(fp_line
			(start -0.67945 0.3048)
			(end -0.67945 -0.305054)
			(stroke
				(width 0.1)
				(type default)
			)
			(layer "F.Fab")
		)
		(fp_line
			(start -0.67945 -0.305054)
			(end -0.12065 -0.305054)
			(stroke
				(width 0.1)
				(type default)
			)
			(layer "F.Fab")
		)
		(pad "1" smd circle
			(at -0.40005 0 180)
			(size 0 0)
			(layers "F.Cu" "F.Mask" "F.Paste")
			(net "P3V3_AUX")
		)
		(pad "2" smd circle
			(at 0.40005 0 180)
			(size 0 0)
			(layers "F.Cu" "F.Mask" "F.Paste")
			(net "PWRGD_P3V3_AUX_PDB_BUF_R")
		)
	)
	(footprint ""
		(layer "F.Cu")
		(at 308.420516 -433.942744 -90)
		(property "Reference" "R3430"
			(at 0 0 270)
			(layer "F.SilkS")
			(hide yes)
			(effects
				(font
					(size 1.27 1.27)
				)
			)
		)
		(property "Value" ""
			(at 0 0 270)
			(layer "F.Fab")
			(effects
				(font
					(size 1.27 1.27)
				)
			)
		)
		(duplicate_pad_numbers_are_jumpers no)
		(fp_line
			(start -0.7874 0.4064)
			(end -0.7874 -0.4064)
			(stroke
				(width 0.1524)
				(type default)
			)
			(layer "F.SilkS")
		)
		(fp_line
			(start 0.7874 0.4064)
			(end -0.7874 0.4064)
			(stroke
				(width 0.1524)
				(type default)
			)
			(layer "F.SilkS")
		)
		(fp_line
			(start -0.7874 -0.4064)
			(end 0.7874 -0.4064)
			(stroke
				(width 0.1524)
				(type default)
			)
			(layer "F.SilkS")
		)
		(fp_line
			(start 0.7874 -0.4064)
			(end 0.7874 0.4064)
			(stroke
				(width 0.1524)
				(type default)
			)
			(layer "F.SilkS")
		)
		(fp_line
			(start -0.67945 0.3048)
			(end -0.67945 -0.305054)
			(stroke
				(width 0.1)
				(type default)
			)
			(layer "F.Fab")
		)
		(fp_line
			(start -0.12065 0.3048)
			(end -0.67945 0.3048)
			(stroke
				(width 0.1)
				(type default)
			)
			(layer "F.Fab")
		)
		(fp_line
			(start 0.120396 0.3048)
			(end 0.120396 0.2794)
			(stroke
				(width 0.1)
				(type default)
			)
			(layer "F.Fab")
		)
		(fp_line
			(start 0.67945 0.3048)
			(end 0.120396 0.3048)
			(stroke
				(width 0.1)
				(type default)
			)
			(layer "F.Fab")
		)
		(fp_line
			(start -0.12065 0.2794)
			(end -0.12065 0.3048)
			(stroke
				(width 0.1)
				(type default)
			)
			(layer "F.Fab")
		)
		(fp_line
			(start 0.120396 0.2794)
			(end -0.12065 0.2794)
			(stroke
				(width 0.1)
				(type default)
			)
			(layer "F.Fab")
		)
		(fp_line
			(start -0.12065 -0.2794)
			(end 0.12065 -0.2794)
			(stroke
				(width 0.1)
				(type default)
			)
			(layer "F.Fab")
		)
		(fp_line
			(start 0.12065 -0.2794)
			(end 0.12065 -0.3048)
			(stroke
				(width 0.1)
				(type default)
			)
			(layer "F.Fab")
		)
		(fp_line
			(start 0.12065 -0.3048)
			(end 0.67945 -0.3048)
			(stroke
				(width 0.1)
				(type default)
			)
			(layer "F.Fab")
		)
		(fp_line
			(start 0.67945 -0.3048)
			(end 0.67945 0.3048)
			(stroke
				(width 0.1)
				(type default)
			)
			(layer "F.Fab")
		)
		(fp_line
			(start -0.67945 -0.305054)
			(end -0.12065 -0.305054)
			(stroke
				(width 0.1)
				(type default)
			)
			(layer "F.Fab")
		)
		(fp_line
			(start -0.12065 -0.305054)
			(end -0.12065 -0.2794)
			(stroke
				(width 0.1)
				(type default)
			)
			(layer "F.Fab")
		)
		(pad "1" smd circle
			(at -0.40005 0 270)
			(size 0 0)
			(layers "F.Cu" "F.Mask" "F.Paste")
			(net "GPU_FPGA_OVERT_N")
		)
		(pad "2" smd circle
			(at 0.40005 0 270)
			(size 0 0)
			(layers "F.Cu" "F.Mask" "F.Paste")
			(net "GND")
		)
	)
	(footprint ""
		(layer "F.Cu")
		(at 145.63344 -30.78734 -90)
		(property "Reference" "C6013"
			(at 0 0 270)
			(layer "F.SilkS")
			(hide yes)
			(effects
				(font
					(size 1.27 1.27)
				)
			)
		)
		(property "Value" ""
			(at 0 0 270)
			(layer "F.Fab")
			(effects
				(font
					(size 1.27 1.27)
				)
			)
		)
		(duplicate_pad_numbers_are_jumpers no)
		(fp_line
			(start -0.7874 0.4064)
			(end -0.7874 -0.4064)
			(stroke
				(width 0.1524)
				(type default)
			)
			(layer "F.SilkS")
		)
		(fp_line
			(start 0.7874 0.4064)
			(end -0.7874 0.4064)
			(stroke
				(width 0.1524)
				(type default)
			)
			(layer "F.SilkS")
		)
		(fp_line
			(start -0.7874 -0.4064)
			(end 0.7874 -0.4064)
			(stroke
				(width 0.1524)
				(type default)
			)
			(layer "F.SilkS")
		)
		(fp_line
			(start 0.7874 -0.4064)
			(end 0.7874 0.4064)
			(stroke
				(width 0.1524)
				(type default)
			)
			(layer "F.SilkS")
		)
		(fp_line
			(start -0.6858 0.3048)
			(end -0.6858 -0.3048)
			(stroke
				(width 0.1)
				(type default)
			)
			(layer "F.Fab")
		)
		(fp_line
			(start -0.1016 0.3048)
			(end -0.6858 0.3048)
			(stroke
				(width 0.1)
				(type default)
			)
			(layer "F.Fab")
		)
		(fp_line
			(start 0.1016 0.3048)
			(end 0.1016 0.2794)
			(stroke
				(width 0.1)
				(type default)
			)
			(layer "F.Fab")
		)
		(fp_line
			(start 0.6858 0.3048)
			(end 0.1016 0.3048)
			(stroke
				(width 0.1)
				(type default)
			)
			(layer "F.Fab")
		)
		(fp_line
			(start -0.1016 0.2794)
			(end -0.1016 0.3048)
			(stroke
				(width 0.1)
				(type default)
			)
			(layer "F.Fab")
		)
		(fp_line
			(start 0.1016 0.2794)
			(end -0.1016 0.2794)
			(stroke
				(width 0.1)
				(type default)
			)
			(layer "F.Fab")
		)
		(fp_line
			(start -0.1016 -0.2794)
			(end 0.1016 -0.2794)
			(stroke
				(width 0.1)
				(type default)
			)
			(layer "F.Fab")
		)
		(fp_line
			(start 0.1016 -0.2794)
			(end 0.1016 -0.3048)
			(stroke
				(width 0.1)
				(type default)
			)
			(layer "F.Fab")
		)
		(fp_line
			(start -0.6858 -0.3048)
			(end -0.1016 -0.3048)
			(stroke
				(width 0.1)
				(type default)
			)
			(layer "F.Fab")
		)
		(fp_line
			(start -0.1016 -0.3048)
			(end -0.1016 -0.2794)
			(stroke
				(width 0.1)
				(type default)
			)
			(layer "F.Fab")
		)
		(fp_line
			(start 0.1016 -0.3048)
			(end 0.6858 -0.3048)
			(stroke
				(width 0.1)
				(type default)
			)
			(layer "F.Fab")
		)
		(fp_line
			(start 0.6858 -0.3048)
			(end 0.6858 0.3048)
			(stroke
				(width 0.1)
				(type default)
			)
			(layer "F.Fab")
		)
		(pad "1" smd rect
			(at -0.40005 0 90)
			(size 0.4572 0.508)
			(layers "F.Cu" "F.Mask" "F.Paste")
			(net "USB3_CPU0_BMC_TX_DP")
		)
		(pad "2" smd rect
			(at 0.40005 0 90)
			(size 0.4572 0.508)
			(layers "F.Cu" "F.Mask" "F.Paste")
			(net "USB3_CPU0_BMC_TX_C2_DP")
		)
	)
	(footprint ""
		(layer "F.Cu")
		(at 47.401988 -5.569966 -90)
		(property "Reference" "J35"
			(at -8.0772 -20.659598 0)
			(unlocked yes)
			(layer "F.SilkS")
			(effects
				(font
					(size 0.7874 0.5842)
					(thickness 0.1524)
				)
				(justify left)
			)
		)
		(property "Value" ""
			(at 0 0 270)
			(layer "F.Fab")
			(effects
				(font
					(size 1.27 1.27)
				)
			)
		)
		(duplicate_pad_numbers_are_jumpers no)
		(fp_line
			(start -6.495034 34.360104)
			(end 6.210046 34.360104)
			(stroke
				(width 0.1524)
				(type default)
			)
			(layer "F.SilkS")
		)
		(fp_line
			(start 6.210046 34.360104)
			(end 6.210046 -34.360104)
			(stroke
				(width 0.1524)
				(type default)
			)
			(layer "F.SilkS")
		)
		(fp_line
			(start -5.5499 33.8201)
			(end 5.5499 33.8201)
			(stroke
				(width 0.1524)
				(type default)
			)
			(layer "F.SilkS")
		)
		(fp_line
			(start 5.5499 33.8201)
			(end 5.5499 -33.8201)
			(stroke
				(width 0.1524)
				(type default)
			)
			(layer "F.SilkS")
		)
		(fp_line
			(start -5.5499 30.97784)
			(end -5.5499 33.8201)
			(stroke
				(width 0.1524)
				(type default)
			)
			(layer "F.SilkS")
		)
		(fp_line
			(start -7.420102 29.494988)
			(end -7.420102 33.304988)
			(stroke
				(width 0.1524)
				(type default)
			)
			(layer "F.SilkS")
		)
		(fp_line
			(start -7.420102 27.081988)
			(end -7.420102 27.716988)
			(stroke
				(width 0.1524)
				(type default)
			)
			(layer "F.SilkS")
		)
		(fp_line
			(start -7.420102 25.049988)
			(end -7.420102 25.811988)
			(stroke
				(width 0.1524)
				(type default)
			)
			(layer "F.SilkS")
		)
		(fp_line
			(start -7.420102 23.144988)
			(end -7.420102 24.033988)
			(stroke
				(width 0.1524)
				(type default)
			)
			(layer "F.SilkS")
		)
		(fp_line
			(start -7.420102 21.366988)
			(end -7.420102 22.001988)
			(stroke
				(width 0.1524)
				(type default)
			)
			(layer "F.SilkS")
		)
		(fp_line
			(start -7.420102 19.461988)
			(end -7.420102 19.969988)
			(stroke
				(width 0.1524)
				(type default)
			)
			(layer "F.SilkS")
		)
		(fp_line
			(start -7.420102 17.429988)
			(end -7.420102 18.064988)
			(stroke
				(width 0.1524)
				(type default)
			)
			(layer "F.SilkS")
		)
		(fp_line
			(start -7.420102 15.651988)
			(end -7.420102 16.159988)
			(stroke
				(width 0.1524)
				(type default)
			)
			(layer "F.SilkS")
		)
		(fp_line
			(start -5.5499 9.8806)
			(end -5.5499 14.13256)
			(stroke
				(width 0.1524)
				(type default)
			)
			(layer "F.SilkS")
		)
		(fp_line
			(start -7.420102 8.920988)
			(end -7.420102 14.381988)
			(stroke
				(width 0.1524)
				(type default)
			)
			(layer "F.SilkS")
		)
		(fp_line
			(start -7.420102 7.015988)
			(end -7.420102 7.396988)
			(stroke
				(width 0.1524)
				(type default)
			)
			(layer "F.SilkS")
		)
		(fp_line
			(start -7.420102 4.983988)
			(end -7.420102 5.618988)
			(stroke
				(width 0.1524)
				(type default)
			)
			(layer "F.SilkS")
		)
		(fp_line
			(start -7.420102 3.205988)
			(end -7.420102 3.586988)
			(stroke
				(width 0.1524)
				(type default)
			)
			(layer "F.SilkS")
		)
		(fp_line
			(start -5.5499 -1.9304)
			(end -5.5499 1.4224)
			(stroke
				(width 0.1524)
				(type default)
			)
			(layer "F.SilkS")
		)
		(fp_line
			(start -7.420102 -2.382012)
			(end -7.420102 1.300988)
			(stroke
				(width 0.1524)
				(type default)
			)
			(layer "F.SilkS")
		)
		(fp_line
			(start -7.420102 -4.414012)
			(end -7.420102 -3.652012)
			(stroke
				(width 0.1524)
				(type default)
			)
			(layer "F.SilkS")
		)
		(fp_line
			(start -7.420102 -6.446012)
			(end -7.420102 -5.430012)
			(stroke
				(width 0.1524)
				(type default)
			)
			(layer "F.SilkS")
		)
		(fp_line
			(start -7.420102 -8.351012)
			(end -7.420102 -7.589012)
			(stroke
				(width 0.1524)
				(type default)
			)
			(layer "F.SilkS")
		)
		(fp_line
			(start -5.5499 -22.5425)
			(end -5.5499 -18.7833)
			(stroke
				(width 0.1524)
				(type default)
			)
			(layer "F.SilkS")
		)
		(fp_line
			(start -7.420102 -23.210012)
			(end -7.420102 -11.272012)
			(stroke
				(width 0.1524)
				(type default)
			)
			(layer "F.SilkS")
		)
		(fp_line
			(start -5.5499 -33.8201)
			(end -5.5499 -30.988)
			(stroke
				(width 0.1524)
				(type default)
			)
			(layer "F.SilkS")
		)
		(fp_line
			(start 5.5499 -33.8201)
			(end -5.5499 -33.8201)
			(stroke
				(width 0.1524)
				(type default)
			)
			(layer "F.SilkS")
		)
		(fp_line
			(start -7.420102 -34.360104)
			(end -7.420102 -25.369012)
			(stroke
				(width 0.1524)
				(type default)
			)
			(layer "F.SilkS")
		)
		(fp_line
			(start 6.210046 -34.360104)
			(end -7.420102 -34.360104)
			(stroke
				(width 0.1524)
				(type default)
			)
			(layer "F.SilkS")
		)
		(fp_poly
			(pts
				(xy 3.3274 -18.312638) (xy 4.3434 -18.820638) (xy 4.3434 -17.804638)
			)
			(stroke
				(width 0)
				(type default)
			)
			(fill yes)
			(layer "F.SilkS")
		)
		(fp_line
			(start -5.5499 33.8201)
			(end 5.5499 33.8201)
			(stroke
				(width 0.1)
				(type default)
			)
			(layer "F.Fab")
		)
		(fp_line
			(start 5.5499 33.8201)
			(end 5.5499 -33.8201)
			(stroke
				(width 0.1)
				(type default)
			)
			(layer "F.Fab")
		)
		(fp_line
			(start -5.5499 -33.8201)
			(end -5.5499 33.8201)
			(stroke
				(width 0.1)
				(type default)
			)
			(layer "F.Fab")
		)
		(fp_line
			(start 5.5499 -33.8201)
			(end -5.5499 -33.8201)
			(stroke
				(width 0.1)
				(type default)
			)
			(layer "F.Fab")
		)
		(fp_poly
			(pts
				(xy 7.4168 -17.957038) (xy 7.4168 -18.973038) (xy 6.4008 -18.465038)
			)
			(stroke
				(width 0)
				(type default)
			)
			(fill yes)
			(layer "F.Fab")
		)
		(pad "" np_thru_hole circle
			(at -0.599948 -32.079946 180)
			(size 1.1176 1.1176)
			(drill 1.1176)
			(layers "*.Cu" "*.Mask")
			(clearance 0.381)
			(thermal_gap 0.381)
		)
		(pad "" np_thru_hole circle
			(at 0.40005 32.085026 180)
			(size 1.1176 1.1176)
			(drill 1.1176)
			(layers "*.Cu" "*.Mask")
			(clearance 0.381)
			(thermal_gap 0.381)
		)
		(pad "A1" smd rect
			(at -2.750058 -18.465038 180)
			(size 0.381 1.4478)
			(layers "F.Cu" "F.Mask" "F.Paste")
			(net "GND")
		)
		(pad "A2" smd rect
			(at -2.750058 -17.86509 180)
			(size 0.381 1.4478)
			(layers "F.Cu" "F.Mask" "F.Paste")
			(net "GND")
		)
		(pad "A3" smd rect
			(at -2.750058 -17.264888 180)
			(size 0.381 1.4478)
			(layers "F.Cu" "F.Mask" "F.Paste")
			(net "GND")
		)
		(pad "A4" smd rect
			(at -2.750058 -16.66494 180)
			(size 0.381 1.4478)
			(layers "F.Cu" "F.Mask" "F.Paste")
			(net "GND")
		)
		(pad "A5" smd rect
			(at -2.750058 -16.064992 180)
			(size 0.381 1.4478)
			(layers "F.Cu" "F.Mask" "F.Paste")
			(net "GND")
		)
		(pad "A6" smd rect
			(at -2.750058 -15.465044 180)
			(size 0.381 1.4478)
			(layers "F.Cu" "F.Mask" "F.Paste")
			(net "GND")
		)
		(pad "A7" smd rect
			(at -2.750058 -14.865096 180)
			(size 0.381 1.4478)
			(layers "F.Cu" "F.Mask" "F.Paste")
			(net "SMB_OCP_V3_2_3V3AUX_BUF_R_SCL")
		)
		(pad "A8" smd rect
			(at -2.750058 -14.264894 180)
			(size 0.381 1.4478)
			(layers "F.Cu" "F.Mask" "F.Paste")
			(net "SMB_OCP_V3_2_3V3AUX_BUF_R_SDA")
		)
		(pad "A9" smd rect
			(at -2.750058 -13.664946 180)
			(size 0.381 1.4478)
			(layers "F.Cu" "F.Mask" "F.Paste")
			(net "RST_SMB_OCP_V3_2_N")
		)
		(pad "A10" smd rect
			(at -2.750058 -13.064998 180)
			(size 0.381 1.4478)
			(layers "F.Cu" "F.Mask" "F.Paste")
			(net "OCP_V3_2_PRSNTA_R_N")
		)
		(pad "A11" smd rect
			(at -2.750058 -12.46505 180)
			(size 0.381 1.4478)
			(layers "F.Cu" "F.Mask" "F.Paste")
			(net "RST_PERST1_OCP_V3_2_N")
		)
		(pad "A12" smd rect
			(at -2.750058 -11.865102 180)
			(size 0.381 1.4478)
			(layers "F.Cu" "F.Mask" "F.Paste")
			(net "OCP_V3_2_PRSNT2_R_N")
		)
		(pad "A13" smd rect
			(at -2.750058 -11.2649 180)
			(size 0.381 1.4478)
			(layers "F.Cu" "F.Mask" "F.Paste")
			(net "GND")
		)
		(pad "A14" smd rect
			(at -2.750058 -10.664952 180)
			(size 0.381 1.4478)
			(layers "F.Cu" "F.Mask" "F.Paste")
			(net "CLK_100M_CPU1_CLK03_DN")
		)
		(pad "A15" smd rect
			(at -2.750058 -10.065004 180)
			(size 0.381 1.4478)
			(layers "F.Cu" "F.Mask" "F.Paste")
			(net "CLK_100M_CPU1_CLK03_DP")
		)
		(pad "A16" smd rect
			(at -2.750058 -9.465056 180)
			(size 0.381 1.4478)
			(layers "F.Cu" "F.Mask" "F.Paste")
			(net "GND")
		)
		(pad "A17" smd rect
			(at -2.750058 -8.865108 180)
			(size 0.381 1.4478)
			(layers "F.Cu" "F.Mask" "F.Paste")
			(net "P5E_CPU1_G1_RX_DN<0>")
		)
		(pad "A18" smd rect
			(at -2.750058 -8.264906 180)
			(size 0.381 1.4478)
			(layers "F.Cu" "F.Mask" "F.Paste")
			(net "P5E_CPU1_G1_RX_DP<0>")
		)
		(pad "A19" smd rect
			(at -2.750058 -7.664958 180)
			(size 0.381 1.4478)
			(layers "F.Cu" "F.Mask" "F.Paste")
			(net "GND")
		)
		(pad "A20" smd rect
			(at -2.750058 -7.06501 180)
			(size 0.381 1.4478)
			(layers "F.Cu" "F.Mask" "F.Paste")
			(net "P5E_CPU1_G1_RX_DN<1>")
		)
		(pad "A21" smd rect
			(at -2.750058 -6.465062 180)
			(size 0.381 1.4478)
			(layers "F.Cu" "F.Mask" "F.Paste")
			(net "P5E_CPU1_G1_RX_DP<1>")
		)
		(pad "A22" smd rect
			(at -2.750058 -5.865114 180)
			(size 0.381 1.4478)
			(layers "F.Cu" "F.Mask" "F.Paste")
			(net "GND")
		)
		(pad "A23" smd rect
			(at -2.750058 -5.264912 180)
			(size 0.381 1.4478)
			(layers "F.Cu" "F.Mask" "F.Paste")
			(net "P5E_CPU1_G1_RX_DN<2>")
		)
		(pad "A24" smd rect
			(at -2.750058 -4.664964 180)
			(size 0.381 1.4478)
			(layers "F.Cu" "F.Mask" "F.Paste")
			(net "P5E_CPU1_G1_RX_DP<2>")
		)
		(pad "A25" smd rect
			(at -2.750058 -4.065016 180)
			(size 0.381 1.4478)
			(layers "F.Cu" "F.Mask" "F.Paste")
			(net "GND")
		)
		(pad "A26" smd rect
			(at -2.750058 -3.465068 180)
			(size 0.381 1.4478)
			(layers "F.Cu" "F.Mask" "F.Paste")
			(net "P5E_CPU1_G1_RX_DN<3>")
		)
		(pad "A27" smd rect
			(at -2.750058 -2.86512 180)
			(size 0.381 1.4478)
			(layers "F.Cu" "F.Mask" "F.Paste")
			(net "P5E_CPU1_G1_RX_DP<3>")
		)
		(pad "A28" smd rect
			(at -2.750058 -2.264918 180)
			(size 0.381 1.4478)
			(layers "F.Cu" "F.Mask" "F.Paste")
			(net "GND")
		)
		(pad "A29" smd rect
			(at -2.750058 1.74498 180)
			(size 0.381 1.4478)
			(layers "F.Cu" "F.Mask" "F.Paste")
			(net "GND")
		)
		(pad "A30" smd rect
			(at -2.750058 2.344928 180)
			(size 0.381 1.4478)
			(layers "F.Cu" "F.Mask" "F.Paste")
			(net "P5E_CPU1_G1_RX_DN<4>")
		)
		(pad "A31" smd rect
			(at -2.750058 2.944876 180)
			(size 0.381 1.4478)
			(layers "F.Cu" "F.Mask" "F.Paste")
			(net "P5E_CPU1_G1_RX_DP<4>")
		)
		(pad "A32" smd rect
			(at -2.750058 3.545078 180)
			(size 0.381 1.4478)
			(layers "F.Cu" "F.Mask" "F.Paste")
			(net "GND")
		)
		(pad "A33" smd rect
			(at -2.750058 4.145026 180)
			(size 0.381 1.4478)
			(layers "F.Cu" "F.Mask" "F.Paste")
			(net "P5E_CPU1_G1_RX_DN<5>")
		)
		(pad "A34" smd rect
			(at -2.750058 4.744974 180)
			(size 0.381 1.4478)
			(layers "F.Cu" "F.Mask" "F.Paste")
			(net "P5E_CPU1_G1_RX_DP<5>")
		)
		(pad "A35" smd rect
			(at -2.750058 5.344922 180)
			(size 0.381 1.4478)
			(layers "F.Cu" "F.Mask" "F.Paste")
			(net "GND")
		)
		(pad "A36" smd rect
			(at -2.750058 5.945124 180)
			(size 0.381 1.4478)
			(layers "F.Cu" "F.Mask" "F.Paste")
			(net "P5E_CPU1_G1_RX_DN<6>")
		)
		(pad "A37" smd rect
			(at -2.750058 6.545072 180)
			(size 0.381 1.4478)
			(layers "F.Cu" "F.Mask" "F.Paste")
			(net "P5E_CPU1_G1_RX_DP<6>")
		)
		(pad "A38" smd rect
			(at -2.750058 7.14502 180)
			(size 0.381 1.4478)
			(layers "F.Cu" "F.Mask" "F.Paste")
			(net "GND")
		)
		(pad "A39" smd rect
			(at -2.750058 7.744968 180)
			(size 0.381 1.4478)
			(layers "F.Cu" "F.Mask" "F.Paste")
			(net "P5E_CPU1_G1_RX_DN<7>")
		)
		(pad "A40" smd rect
			(at -2.750058 8.344916 180)
			(size 0.381 1.4478)
			(layers "F.Cu" "F.Mask" "F.Paste")
			(net "P5E_CPU1_G1_RX_DP<7>")
		)
		(pad "A41" smd rect
			(at -2.750058 8.945118 180)
			(size 0.381 1.4478)
			(layers "F.Cu" "F.Mask" "F.Paste")
			(net "GND")
		)
		(pad "A42" smd rect
			(at -2.750058 9.545066 180)
			(size 0.381 1.4478)
			(layers "F.Cu" "F.Mask" "F.Paste")
			(net "OCP_V3_2_PRSNT1_R_N")
		)
		(pad "A43" smd rect
			(at -2.750058 14.454886 180)
			(size 0.381 1.4478)
			(layers "F.Cu" "F.Mask" "F.Paste")
			(net "GND")
		)
		(pad "A44" smd rect
			(at -2.750058 15.055088 180)
			(size 0.381 1.4478)
			(layers "F.Cu" "F.Mask" "F.Paste")
			(net "P5E_CPU1_G1_RX_DN<8>")
		)
		(pad "A45" smd rect
			(at -2.750058 15.655036 180)
			(size 0.381 1.4478)
			(layers "F.Cu" "F.Mask" "F.Paste")
			(net "P5E_CPU1_G1_RX_DP<8>")
		)
		(pad "A46" smd rect
			(at -2.750058 16.254984 180)
			(size 0.381 1.4478)
			(layers "F.Cu" "F.Mask" "F.Paste")
			(net "GND")
		)
		(pad "A47" smd rect
			(at -2.750058 16.854932 180)
			(size 0.381 1.4478)
			(layers "F.Cu" "F.Mask" "F.Paste")
			(net "P5E_CPU1_G1_RX_DN<9>")
		)
		(pad "A48" smd rect
			(at -2.750058 17.45488 180)
			(size 0.381 1.4478)
			(layers "F.Cu" "F.Mask" "F.Paste")
			(net "P5E_CPU1_G1_RX_DP<9>")
		)
		(pad "A49" smd rect
			(at -2.750058 18.055082 180)
			(size 0.381 1.4478)
			(layers "F.Cu" "F.Mask" "F.Paste")
			(net "GND")
		)
		(pad "A50" smd rect
			(at -2.750058 18.65503 180)
			(size 0.381 1.4478)
			(layers "F.Cu" "F.Mask" "F.Paste")
			(net "P5E_CPU1_G1_RX_DN<10>")
		)
		(pad "A51" smd rect
			(at -2.750058 19.254978 180)
			(size 0.381 1.4478)
			(layers "F.Cu" "F.Mask" "F.Paste")
			(net "P5E_CPU1_G1_RX_DP<10>")
		)
		(pad "A52" smd rect
			(at -2.750058 19.854926 180)
			(size 0.381 1.4478)
			(layers "F.Cu" "F.Mask" "F.Paste")
			(net "GND")
		)
		(pad "A53" smd rect
			(at -2.750058 20.455128 180)
			(size 0.381 1.4478)
			(layers "F.Cu" "F.Mask" "F.Paste")
			(net "P5E_CPU1_G1_RX_DN<11>")
		)
		(pad "A54" smd rect
			(at -2.750058 21.055076 180)
			(size 0.381 1.4478)
			(layers "F.Cu" "F.Mask" "F.Paste")
			(net "P5E_CPU1_G1_RX_DP<11>")
		)
		(pad "A55" smd rect
			(at -2.750058 21.655024 180)
			(size 0.381 1.4478)
			(layers "F.Cu" "F.Mask" "F.Paste")
			(net "GND")
		)
		(pad "A56" smd rect
			(at -2.750058 22.254972 180)
			(size 0.381 1.4478)
			(layers "F.Cu" "F.Mask" "F.Paste")
			(net "P5E_CPU1_G1_RX_DN<12>")
		)
		(pad "A57" smd rect
			(at -2.750058 22.85492 180)
			(size 0.381 1.4478)
			(layers "F.Cu" "F.Mask" "F.Paste")
			(net "P5E_CPU1_G1_RX_DP<12>")
		)
		(pad "A58" smd rect
			(at -2.750058 23.455122 180)
			(size 0.381 1.4478)
			(layers "F.Cu" "F.Mask" "F.Paste")
			(net "GND")
		)
		(pad "A59" smd rect
			(at -2.750058 24.05507 180)
			(size 0.381 1.4478)
			(layers "F.Cu" "F.Mask" "F.Paste")
			(net "P5E_CPU1_G1_RX_DN<13>")
		)
		(pad "A60" smd rect
			(at -2.750058 24.655018 180)
			(size 0.381 1.4478)
			(layers "F.Cu" "F.Mask" "F.Paste")
			(net "P5E_CPU1_G1_RX_DP<13>")
		)
		(pad "A61" smd rect
			(at -2.750058 25.254966 180)
			(size 0.381 1.4478)
			(layers "F.Cu" "F.Mask" "F.Paste")
			(net "GND")
		)
		(pad "A62" smd rect
			(at -2.750058 25.854914 180)
			(size 0.381 1.4478)
			(layers "F.Cu" "F.Mask" "F.Paste")
			(net "P5E_CPU1_G1_RX_DN<14>")
		)
		(pad "A63" smd rect
			(at -2.750058 26.455116 180)
			(size 0.381 1.4478)
			(layers "F.Cu" "F.Mask" "F.Paste")
			(net "P5E_CPU1_G1_RX_DP<14>")
		)
		(pad "A64" smd rect
			(at -2.750058 27.055064 180)
			(size 0.381 1.4478)
			(layers "F.Cu" "F.Mask" "F.Paste")
			(net "GND")
		)
		(pad "A65" smd rect
			(at -2.750058 27.655012 180)
			(size 0.381 1.4478)
			(layers "F.Cu" "F.Mask" "F.Paste")
			(net "P5E_CPU1_G1_RX_DN<15>")
		)
		(pad "A66" smd rect
			(at -2.750058 28.25496 180)
			(size 0.381 1.4478)
			(layers "F.Cu" "F.Mask" "F.Paste")
			(net "P5E_CPU1_G1_RX_DP<15>")
		)
		(pad "A67" smd rect
			(at -2.750058 28.854908 180)
			(size 0.381 1.4478)
			(layers "F.Cu" "F.Mask" "F.Paste")
			(net "GND")
		)
		(pad "A68" smd rect
			(at -2.750058 29.45511 180)
			(size 0.381 1.4478)
			(layers "F.Cu" "F.Mask" "F.Paste")
			(net "USB2_P10_DN")
		)
		(pad "A69" smd rect
			(at -2.750058 30.055058 180)
			(size 0.381 1.4478)
			(layers "F.Cu" "F.Mask" "F.Paste")
			(net "USB2_P10_DP")
		)
		(pad "A70" smd rect
			(at -2.750058 30.655006 180)
			(size 0.381 1.4478)
			(layers "F.Cu" "F.Mask" "F.Paste")
			(net "OCP_V3_2_PWRBRK_N")
		)
		(pad "B1" smd rect
			(at -5.700014 -18.465038 180)
			(size 0.381 1.4478)
			(layers "F.Cu" "F.Mask" "F.Paste")
			(net "P12V_OCP_V3_2_R")
		)
		(pad "B2" smd rect
			(at -5.700014 -17.86509 180)
			(size 0.381 1.4478)
			(layers "F.Cu" "F.Mask" "F.Paste")
			(net "P12V_OCP_V3_2_R")
		)
		(pad "B3" smd rect
			(at -5.700014 -17.264888 180)
			(size 0.381 1.4478)
			(layers "F.Cu" "F.Mask" "F.Paste")
			(net "P12V_OCP_V3_2_R")
		)
		(pad "B4" smd rect
			(at -5.700014 -16.66494 180)
			(size 0.381 1.4478)
			(layers "F.Cu" "F.Mask" "F.Paste")
			(net "P12V_OCP_V3_2_R")
		)
		(pad "B5" smd rect
			(at -5.700014 -16.064992 180)
			(size 0.381 1.4478)
			(layers "F.Cu" "F.Mask" "F.Paste")
			(net "P12V_OCP_V3_2_R")
		)
		(pad "B6" smd rect
			(at -5.700014 -15.465044 180)
			(size 0.381 1.4478)
			(layers "F.Cu" "F.Mask" "F.Paste")
			(net "P12V_OCP_V3_2_R")
		)
		(pad "B7" smd rect
			(at -5.700014 -14.865096 180)
			(size 0.381 1.4478)
			(layers "F.Cu" "F.Mask" "F.Paste")
			(net "OCP_V3_2_BIF0_R_N")
		)
		(pad "B8" smd rect
			(at -5.700014 -14.264894 180)
			(size 0.381 1.4478)
			(layers "F.Cu" "F.Mask" "F.Paste")
			(net "OCP_V3_2_BIF1_R_N")
		)
		(pad "B9" smd rect
			(at -5.700014 -13.664946 180)
			(size 0.381 1.4478)
			(layers "F.Cu" "F.Mask" "F.Paste")
			(net "OCP_V3_2_BIF2_R_N")
		)
		(pad "B10" smd rect
			(at -5.700014 -13.064998 180)
			(size 0.381 1.4478)
			(layers "F.Cu" "F.Mask" "F.Paste")
			(net "RST_PERST0_OCP_V3_2_N")
		)
		(pad "B11" smd rect
			(at -5.700014 -12.46505 180)
			(size 0.381 1.4478)
			(layers "F.Cu" "F.Mask" "F.Paste")
			(net "P3V3_OCP_V3_2")
		)
		(pad "B12" smd rect
			(at -5.700014 -11.865102 180)
			(size 0.381 1.4478)
			(layers "F.Cu" "F.Mask" "F.Paste")
			(net "OCP_V3_2_AUX_PWR_EN_R")
		)
		(pad "B13" smd rect
			(at -5.700014 -11.2649 180)
			(size 0.381 1.4478)
			(layers "F.Cu" "F.Mask" "F.Paste")
			(net "GND")
		)
		(pad "B14" smd rect
			(at -5.700014 -10.664952 180)
			(size 0.381 1.4478)
			(layers "F.Cu" "F.Mask" "F.Paste")
			(net "CLK_100M_CPU1_CLK02_DN")
		)
		(pad "B15" smd rect
			(at -5.700014 -10.065004 180)
			(size 0.381 1.4478)
			(layers "F.Cu" "F.Mask" "F.Paste")
			(net "CLK_100M_CPU1_CLK02_DP")
		)
		(pad "B16" smd rect
			(at -5.700014 -9.465056 180)
			(size 0.381 1.4478)
			(layers "F.Cu" "F.Mask" "F.Paste")
			(net "GND")
		)
		(pad "B17" smd rect
			(at -5.700014 -8.865108 180)
			(size 0.381 1.4478)
			(layers "F.Cu" "F.Mask" "F.Paste")
			(net "P5E_CPU1_G1_TX_C_DP<0>")
		)
		(pad "B18" smd rect
			(at -5.700014 -8.264906 180)
			(size 0.381 1.4478)
			(layers "F.Cu" "F.Mask" "F.Paste")
			(net "P5E_CPU1_G1_TX_C_DN<0>")
		)
		(pad "B19" smd rect
			(at -5.700014 -7.664958 180)
			(size 0.381 1.4478)
			(layers "F.Cu" "F.Mask" "F.Paste")
			(net "GND")
		)
		(pad "B20" smd rect
			(at -5.700014 -7.06501 180)
			(size 0.381 1.4478)
			(layers "F.Cu" "F.Mask" "F.Paste")
			(net "P5E_CPU1_G1_TX_C_DP<1>")
		)
		(pad "B21" smd rect
			(at -5.700014 -6.465062 180)
			(size 0.381 1.4478)
			(layers "F.Cu" "F.Mask" "F.Paste")
			(net "P5E_CPU1_G1_TX_C_DN<1>")
		)
		(pad "B22" smd rect
			(at -5.700014 -5.865114 180)
			(size 0.381 1.4478)
			(layers "F.Cu" "F.Mask" "F.Paste")
			(net "GND")
		)
		(pad "B23" smd rect
			(at -5.700014 -5.264912 180)
			(size 0.381 1.4478)
			(layers "F.Cu" "F.Mask" "F.Paste")
			(net "P5E_CPU1_G1_TX_C_DP<2>")
		)
		(pad "B24" smd rect
			(at -5.700014 -4.664964 180)
			(size 0.381 1.4478)
			(layers "F.Cu" "F.Mask" "F.Paste")
			(net "P5E_CPU1_G1_TX_C_DN<2>")
		)
		(pad "B25" smd rect
			(at -5.700014 -4.065016 180)
			(size 0.381 1.4478)
			(layers "F.Cu" "F.Mask" "F.Paste")
			(net "GND")
		)
		(pad "B26" smd rect
			(at -5.700014 -3.465068 180)
			(size 0.381 1.4478)
			(layers "F.Cu" "F.Mask" "F.Paste")
			(net "P5E_CPU1_G1_TX_C_DP<3>")
		)
		(pad "B27" smd rect
			(at -5.700014 -2.86512 180)
			(size 0.381 1.4478)
			(layers "F.Cu" "F.Mask" "F.Paste")
			(net "P5E_CPU1_G1_TX_C_DN<3>")
		)
		(pad "B28" smd rect
			(at -5.700014 -2.264918 180)
			(size 0.381 1.4478)
			(layers "F.Cu" "F.Mask" "F.Paste")
			(net "GND")
		)
		(pad "B29" smd rect
			(at -5.700014 1.74498 180)
			(size 0.381 1.4478)
			(layers "F.Cu" "F.Mask" "F.Paste")
			(net "GND")
		)
		(pad "B30" smd rect
			(at -5.700014 2.344928 180)
			(size 0.381 1.4478)
			(layers "F.Cu" "F.Mask" "F.Paste")
			(net "P5E_CPU1_G1_TX_C_DP<4>")
		)
		(pad "B31" smd rect
			(at -5.700014 2.944876 180)
			(size 0.381 1.4478)
			(layers "F.Cu" "F.Mask" "F.Paste")
			(net "P5E_CPU1_G1_TX_C_DN<4>")
		)
		(pad "B32" smd rect
			(at -5.700014 3.545078 180)
			(size 0.381 1.4478)
			(layers "F.Cu" "F.Mask" "F.Paste")
			(net "GND")
		)
		(pad "B33" smd rect
			(at -5.700014 4.145026 180)
			(size 0.381 1.4478)
			(layers "F.Cu" "F.Mask" "F.Paste")
			(net "P5E_CPU1_G1_TX_C_DP<5>")
		)
		(pad "B34" smd rect
			(at -5.700014 4.744974 180)
			(size 0.381 1.4478)
			(layers "F.Cu" "F.Mask" "F.Paste")
			(net "P5E_CPU1_G1_TX_C_DN<5>")
		)
		(pad "B35" smd rect
			(at -5.700014 5.344922 180)
			(size 0.381 1.4478)
			(layers "F.Cu" "F.Mask" "F.Paste")
			(net "GND")
		)
		(pad "B36" smd rect
			(at -5.700014 5.945124 180)
			(size 0.381 1.4478)
			(layers "F.Cu" "F.Mask" "F.Paste")
			(net "P5E_CPU1_G1_TX_C_DP<6>")
		)
		(pad "B37" smd rect
			(at -5.700014 6.545072 180)
			(size 0.381 1.4478)
			(layers "F.Cu" "F.Mask" "F.Paste")
			(net "P5E_CPU1_G1_TX_C_DN<6>")
		)
		(pad "B38" smd rect
			(at -5.700014 7.14502 180)
			(size 0.381 1.4478)
			(layers "F.Cu" "F.Mask" "F.Paste")
			(net "GND")
		)
		(pad "B39" smd rect
			(at -5.700014 7.744968 180)
			(size 0.381 1.4478)
			(layers "F.Cu" "F.Mask" "F.Paste")
			(net "P5E_CPU1_G1_TX_C_DP<7>")
		)
		(pad "B40" smd rect
			(at -5.700014 8.344916 180)
			(size 0.381 1.4478)
			(layers "F.Cu" "F.Mask" "F.Paste")
			(net "P5E_CPU1_G1_TX_C_DN<7>")
		)
		(pad "B41" smd rect
			(at -5.700014 8.945118 180)
			(size 0.381 1.4478)
			(layers "F.Cu" "F.Mask" "F.Paste")
			(net "GND")
		)
		(pad "B42" smd rect
			(at -5.700014 9.545066 180)
			(size 0.381 1.4478)
			(layers "F.Cu" "F.Mask" "F.Paste")
			(net "OCP_V3_2_PRSNT0_R_N")
		)
		(pad "B43" smd rect
			(at -5.700014 14.454886 180)
			(size 0.381 1.4478)
			(layers "F.Cu" "F.Mask" "F.Paste")
			(net "GND")
		)
		(pad "B44" smd rect
			(at -5.700014 15.055088 180)
			(size 0.381 1.4478)
			(layers "F.Cu" "F.Mask" "F.Paste")
			(net "P5E_CPU1_G1_TX_C_DP<8>")
		)
		(pad "B45" smd rect
			(at -5.700014 15.655036 180)
			(size 0.381 1.4478)
			(layers "F.Cu" "F.Mask" "F.Paste")
			(net "P5E_CPU1_G1_TX_C_DN<8>")
		)
		(pad "B46" smd rect
			(at -5.700014 16.254984 180)
			(size 0.381 1.4478)
			(layers "F.Cu" "F.Mask" "F.Paste")
			(net "GND")
		)
		(pad "B47" smd rect
			(at -5.700014 16.854932 180)
			(size 0.381 1.4478)
			(layers "F.Cu" "F.Mask" "F.Paste")
			(net "P5E_CPU1_G1_TX_C_DP<9>")
		)
		(pad "B48" smd rect
			(at -5.700014 17.45488 180)
			(size 0.381 1.4478)
			(layers "F.Cu" "F.Mask" "F.Paste")
			(net "P5E_CPU1_G1_TX_C_DN<9>")
		)
		(pad "B49" smd rect
			(at -5.700014 18.055082 180)
			(size 0.381 1.4478)
			(layers "F.Cu" "F.Mask" "F.Paste")
			(net "GND")
		)
		(pad "B50" smd rect
			(at -5.700014 18.65503 180)
			(size 0.381 1.4478)
			(layers "F.Cu" "F.Mask" "F.Paste")
			(net "P5E_CPU1_G1_TX_C_DP<10>")
		)
		(pad "B51" smd rect
			(at -5.700014 19.254978 180)
			(size 0.381 1.4478)
			(layers "F.Cu" "F.Mask" "F.Paste")
			(net "P5E_CPU1_G1_TX_C_DN<10>")
		)
		(pad "B52" smd rect
			(at -5.700014 19.854926 180)
			(size 0.381 1.4478)
			(layers "F.Cu" "F.Mask" "F.Paste")
			(net "GND")
		)
		(pad "B53" smd rect
			(at -5.700014 20.455128 180)
			(size 0.381 1.4478)
			(layers "F.Cu" "F.Mask" "F.Paste")
			(net "P5E_CPU1_G1_TX_C_DP<11>")
		)
		(pad "B54" smd rect
			(at -5.700014 21.055076 180)
			(size 0.381 1.4478)
			(layers "F.Cu" "F.Mask" "F.Paste")
			(net "P5E_CPU1_G1_TX_C_DN<11>")
		)
		(pad "B55" smd rect
			(at -5.700014 21.655024 180)
			(size 0.381 1.4478)
			(layers "F.Cu" "F.Mask" "F.Paste")
			(net "GND")
		)
		(pad "B56" smd rect
			(at -5.700014 22.254972 180)
			(size 0.381 1.4478)
			(layers "F.Cu" "F.Mask" "F.Paste")
			(net "P5E_CPU1_G1_TX_C_DP<12>")
		)
		(pad "B57" smd rect
			(at -5.700014 22.85492 180)
			(size 0.381 1.4478)
			(layers "F.Cu" "F.Mask" "F.Paste")
			(net "P5E_CPU1_G1_TX_C_DN<12>")
		)
		(pad "B58" smd rect
			(at -5.700014 23.455122 180)
			(size 0.381 1.4478)
			(layers "F.Cu" "F.Mask" "F.Paste")
			(net "GND")
		)
		(pad "B59" smd rect
			(at -5.700014 24.05507 180)
			(size 0.381 1.4478)
			(layers "F.Cu" "F.Mask" "F.Paste")
			(net "P5E_CPU1_G1_TX_C_DP<13>")
		)
		(pad "B60" smd rect
			(at -5.700014 24.655018 180)
			(size 0.381 1.4478)
			(layers "F.Cu" "F.Mask" "F.Paste")
			(net "P5E_CPU1_G1_TX_C_DN<13>")
		)
		(pad "B61" smd rect
			(at -5.700014 25.254966 180)
			(size 0.381 1.4478)
			(layers "F.Cu" "F.Mask" "F.Paste")
			(net "GND")
		)
		(pad "B62" smd rect
			(at -5.700014 25.854914 180)
			(size 0.381 1.4478)
			(layers "F.Cu" "F.Mask" "F.Paste")
			(net "P5E_CPU1_G1_TX_C_DP<14>")
		)
		(pad "B63" smd rect
			(at -5.700014 26.455116 180)
			(size 0.381 1.4478)
			(layers "F.Cu" "F.Mask" "F.Paste")
			(net "P5E_CPU1_G1_TX_C_DN<14>")
		)
		(pad "B64" smd rect
			(at -5.700014 27.055064 180)
			(size 0.381 1.4478)
			(layers "F.Cu" "F.Mask" "F.Paste")
			(net "GND")
		)
		(pad "B65" smd rect
			(at -5.700014 27.655012 180)
			(size 0.381 1.4478)
			(layers "F.Cu" "F.Mask" "F.Paste")
			(net "P5E_CPU1_G1_TX_C_DP<15>")
		)
		(pad "B66" smd rect
			(at -5.700014 28.25496 180)
			(size 0.381 1.4478)
			(layers "F.Cu" "F.Mask" "F.Paste")
			(net "P5E_CPU1_G1_TX_C_DN<15>")
		)
		(pad "B67" smd rect
			(at -5.700014 28.854908 180)
			(size 0.381 1.4478)
			(layers "F.Cu" "F.Mask" "F.Paste")
			(net "GND")
		)
		(pad "B68" smd rect
			(at -5.700014 29.45511 180)
			(size 0.381 1.4478)
			(layers "F.Cu" "F.Mask" "F.Paste")
			(net "TP_OCP_V3_2_B68")
		)
		(pad "B69" smd rect
			(at -5.700014 30.055058 180)
			(size 0.381 1.4478)
			(layers "F.Cu" "F.Mask" "F.Paste")
			(net "TP_OCP_V3_2_B69")
		)
		(pad "B70" smd rect
			(at -5.700014 30.655006 180)
			(size 0.381 1.4478)
			(layers "F.Cu" "F.Mask" "F.Paste")
			(net "OCP_V3_2_PRSNT3_R_N")
		)
		(pad "G1" thru_hole circle
			(at 2.400046 -32.759904 180)
			(size 1.6256 1.6256)
			(drill 1.1176)
			(layers "*.Cu" "*.Mask")
			(remove_unused_layers no)
			(net "GND")
			(clearance 0)
		)
		(pad "G2" thru_hole circle
			(at 2.400046 -20.379944 180)
			(size 1.6256 1.6256)
			(drill 1.1176)
			(layers "*.Cu" "*.Mask")
			(remove_unused_layers no)
			(net "GND")
			(clearance 0)
		)
		(pad "G3" thru_hole circle
			(at 2.400046 0 180)
			(size 1.6256 1.6256)
			(drill 1.1176)
			(layers "*.Cu" "*.Mask")
			(remove_unused_layers no)
			(net "GND")
			(clearance 0)
		)
		(pad "G4" thru_hole circle
			(at 2.400046 12.5349 180)
			(size 1.6256 1.6256)
			(drill 1.1176)
			(layers "*.Cu" "*.Mask")
			(remove_unused_layers no)
			(net "GND")
			(clearance 0)
		)
		(pad "G5" thru_hole circle
			(at 2.400046 32.759904 180)
			(size 1.6256 1.6256)
			(drill 1.1176)
			(layers "*.Cu" "*.Mask")
			(remove_unused_layers no)
			(net "GND")
			(clearance 0)
		)
		(pad "OA1" smd rect
			(at -2.750058 -30.660086 180)
			(size 0.381 1.4478)
			(layers "F.Cu" "F.Mask" "F.Paste")
			(net "RST_PERST2_OCP_V3_2_N")
		)
		(pad "OA2" smd rect
			(at -2.750058 -30.059884 180)
			(size 0.381 1.4478)
			(layers "F.Cu" "F.Mask" "F.Paste")
			(net "RST_PERST3_OCP_V3_2_N")
		)
		(pad "OA3" smd rect
			(at -2.750058 -29.459936 180)
			(size 0.381 1.4478)
			(layers "F.Cu" "F.Mask" "F.Paste")
			(net "IRQ_LVC3_OCP_V3_2_WAKE_N")
		)
		(pad "OA4" smd rect
			(at -2.750058 -28.859988 180)
			(size 0.381 1.4478)
			(layers "F.Cu" "F.Mask" "F.Paste")
			(net "OCP_V3_2_ISO1_RBT_ARB_IN")
		)
		(pad "OA5" smd rect
			(at -2.750058 -28.26004 180)
			(size 0.381 1.4478)
			(layers "F.Cu" "F.Mask" "F.Paste")
			(net "OCP_V3_2_ISO2_RBT_ARB_OUT")
		)
		(pad "OA6" smd rect
			(at -2.750058 -27.660092 180)
			(size 0.381 1.4478)
			(layers "F.Cu" "F.Mask" "F.Paste")
			(net "OCP_V3_2_ID1")
		)
		(pad "OA7" smd rect
			(at -2.750058 -27.05989 180)
			(size 0.381 1.4478)
			(layers "F.Cu" "F.Mask" "F.Paste")
			(net "NCSI_OCP_V3_2_TX_EN")
		)
		(pad "OA8" smd rect
			(at -2.750058 -26.459942 180)
			(size 0.381 1.4478)
			(layers "F.Cu" "F.Mask" "F.Paste")
			(net "NCSI_OCP_V3_2_TXD1")
		)
		(pad "OA9" smd rect
			(at -2.750058 -25.859994 180)
			(size 0.381 1.4478)
			(layers "F.Cu" "F.Mask" "F.Paste")
			(net "NCSI_OCP_V3_2_TXD0")
		)
		(pad "OA10" smd rect
			(at -2.750058 -25.260046 180)
			(size 0.381 1.4478)
			(layers "F.Cu" "F.Mask" "F.Paste")
			(net "GND")
		)
		(pad "OA11" smd rect
			(at -2.750058 -24.660098 180)
			(size 0.381 1.4478)
			(layers "F.Cu" "F.Mask" "F.Paste")
			(net "CLK_100M_CPU1_CLK05_DN")
		)
		(pad "OA12" smd rect
			(at -2.750058 -24.059896 180)
			(size 0.381 1.4478)
			(layers "F.Cu" "F.Mask" "F.Paste")
			(net "CLK_100M_CPU1_CLK05_DP")
		)
		(pad "OA13" smd rect
			(at -2.750058 -23.459948 180)
			(size 0.381 1.4478)
			(layers "F.Cu" "F.Mask" "F.Paste")
			(net "GND")
		)
		(pad "OA14" smd rect
			(at -2.750058 -22.86 180)
			(size 0.381 1.4478)
			(layers "F.Cu" "F.Mask" "F.Paste")
			(net "CLK_50M_NCSI_OCP_V3_2_ISO")
		)
		(pad "OB1" smd rect
			(at -5.700014 -30.660086 180)
			(size 0.381 1.4478)
			(layers "F.Cu" "F.Mask" "F.Paste")
			(net "FM_OCP_V3_2_PWR_GOOD")
		)
		(pad "OB2" smd rect
			(at -5.700014 -30.059884 180)
			(size 0.381 1.4478)
			(layers "F.Cu" "F.Mask" "F.Paste")
			(net "OCP_V3_2_MAIN_PWR_EN_R")
		)
		(pad "OB3" smd rect
			(at -5.700014 -29.459936 180)
			(size 0.381 1.4478)
			(layers "F.Cu" "F.Mask" "F.Paste")
			(net "SGPIO_OCP_V3_2_LD_N")
		)
		(pad "OB4" smd rect
			(at -5.700014 -28.859988 180)
			(size 0.381 1.4478)
			(layers "F.Cu" "F.Mask" "F.Paste")
			(net "SGPIO_OCP_V3_2_DATAIN")
		)
		(pad "OB5" smd rect
			(at -5.700014 -28.26004 180)
			(size 0.381 1.4478)
			(layers "F.Cu" "F.Mask" "F.Paste")
			(net "SGPIO_OCP_V3_2_DATAOUT")
		)
		(pad "OB6" smd rect
			(at -5.700014 -27.660092 180)
			(size 0.381 1.4478)
			(layers "F.Cu" "F.Mask" "F.Paste")
			(net "SGPIO_OCP_V3_2_CLK")
		)
		(pad "OB7" smd rect
			(at -5.700014 -27.05989 180)
			(size 0.381 1.4478)
			(layers "F.Cu" "F.Mask" "F.Paste")
			(net "OCP_V3_2_ID0")
		)
		(pad "OB8" smd rect
			(at -5.700014 -26.459942 180)
			(size 0.381 1.4478)
			(layers "F.Cu" "F.Mask" "F.Paste")
			(net "NCSI_OCP_V3_2_RXD1")
		)
		(pad "OB9" smd rect
			(at -5.700014 -25.859994 180)
			(size 0.381 1.4478)
			(layers "F.Cu" "F.Mask" "F.Paste")
			(net "NCSI_OCP_V3_2_RXD0")
		)
		(pad "OB10" smd rect
			(at -5.700014 -25.260046 180)
			(size 0.381 1.4478)
			(layers "F.Cu" "F.Mask" "F.Paste")
			(net "GND")
		)
		(pad "OB11" smd rect
			(at -5.700014 -24.660098 180)
			(size 0.381 1.4478)
			(layers "F.Cu" "F.Mask" "F.Paste")
			(net "CLK_100M_CPU1_CLK04_DN")
		)
		(pad "OB12" smd rect
			(at -5.700014 -24.059896 180)
			(size 0.381 1.4478)
			(layers "F.Cu" "F.Mask" "F.Paste")
			(net "CLK_100M_CPU1_CLK04_DP")
		)
		(pad "OB13" smd rect
			(at -5.700014 -23.459948 180)
			(size 0.381 1.4478)
			(layers "F.Cu" "F.Mask" "F.Paste")
			(net "GND")
		)
		(pad "OB14" smd rect
			(at -5.700014 -22.86 180)
			(size 0.381 1.4478)
			(layers "F.Cu" "F.Mask" "F.Paste")
			(net "NCSI_OCP_V3_2_CRS_DV")
		)
		(zone
			(layers "F.Cu" "B.Cu" "In1.Cu" "In2.Cu" "In3.Cu" "In4.Cu" "In5.Cu" "In6.Cu"
				"In7.Cu" "In8.Cu" "In9.Cu" "In10.Cu" "In11.Cu" "In12.Cu" "In13.Cu" "In14.Cu"
				"In15.Cu" "In16.Cu"
			)
			(hatch none 0.5)
			(connect_pads
				(clearance 0)
			)
			(min_thickness 0.25)
			(keepout
				(tracks not_allowed)
				(vias allowed)
				(pads allowed)
				(copperpour not_allowed)
				(footprints allowed)
			)
			(placement
				(enabled no)
				(sheetname "")
			)
			(fill
				(thermal_gap 0.5)
				(thermal_bridge_width 0.5)
				(island_removal_mode 0)
			)
			(polygon
				(pts
					(arc
						(start 16.282162 -5.169916)
						(mid 14.351762 -5.169916)
						(end 16.282162 -5.169916)
					)
				)
			)
		)
		(zone
			(layers "F.Cu" "B.Cu" "In1.Cu" "In2.Cu" "In3.Cu" "In4.Cu" "In5.Cu" "In6.Cu"
				"In7.Cu" "In8.Cu" "In9.Cu" "In10.Cu" "In11.Cu" "In12.Cu" "In13.Cu" "In14.Cu"
				"In15.Cu" "In16.Cu"
			)
			(hatch none 0.5)
			(connect_pads
				(clearance 0)
			)
			(min_thickness 0.25)
			(keepout
				(tracks not_allowed)
				(vias allowed)
				(pads allowed)
				(copperpour not_allowed)
				(footprints allowed)
			)
			(placement
				(enabled no)
				(sheetname "")
			)
			(fill
				(thermal_gap 0.5)
				(thermal_bridge_width 0.5)
				(island_removal_mode 0)
			)
			(polygon
				(pts
					(arc
						(start 80.447134 -6.169914)
						(mid 78.516734 -6.169914)
						(end 80.447134 -6.169914)
					)
				)
			)
		)
	)
	(footprint ""
		(layer "F.Cu")
		(at 195.888864 -351.409254 -90)
		(property "Reference" "PC510_2"
			(at 0 0 270)
			(layer "F.SilkS")
			(hide yes)
			(effects
				(font
					(size 1.27 1.27)
				)
			)
		)
		(property "Value" ""
			(at 0 0 270)
			(layer "F.Fab")
			(effects
				(font
					(size 1.27 1.27)
				)
			)
		)
		(duplicate_pad_numbers_are_jumpers no)
		(fp_line
			(start -0.7874 0.4064)
			(end -0.7874 -0.4064)
			(stroke
				(width 0.1524)
				(type default)
			)
			(layer "F.SilkS")
		)
		(fp_line
			(start 0.7874 0.4064)
			(end -0.7874 0.4064)
			(stroke
				(width 0.1524)
				(type default)
			)
			(layer "F.SilkS")
		)
		(fp_line
			(start -0.7874 -0.4064)
			(end 0.7874 -0.4064)
			(stroke
				(width 0.1524)
				(type default)
			)
			(layer "F.SilkS")
		)
		(fp_line
			(start 0.7874 -0.4064)
			(end 0.7874 0.4064)
			(stroke
				(width 0.1524)
				(type default)
			)
			(layer "F.SilkS")
		)
		(fp_line
			(start -0.67945 0.3048)
			(end -0.67945 -0.305054)
			(stroke
				(width 0.1)
				(type default)
			)
			(layer "F.Fab")
		)
		(fp_line
			(start -0.12065 0.3048)
			(end -0.67945 0.3048)
			(stroke
				(width 0.1)
				(type default)
			)
			(layer "F.Fab")
		)
		(fp_line
			(start 0.120396 0.3048)
			(end 0.120396 0.2794)
			(stroke
				(width 0.1)
				(type default)
			)
			(layer "F.Fab")
		)
		(fp_line
			(start 0.67945 0.3048)
			(end 0.120396 0.3048)
			(stroke
				(width 0.1)
				(type default)
			)
			(layer "F.Fab")
		)
		(fp_line
			(start -0.12065 0.2794)
			(end -0.12065 0.3048)
			(stroke
				(width 0.1)
				(type default)
			)
			(layer "F.Fab")
		)
		(fp_line
			(start 0.120396 0.2794)
			(end -0.12065 0.2794)
			(stroke
				(width 0.1)
				(type default)
			)
			(layer "F.Fab")
		)
		(fp_line
			(start -0.12065 -0.2794)
			(end 0.12065 -0.2794)
			(stroke
				(width 0.1)
				(type default)
			)
			(layer "F.Fab")
		)
		(fp_line
			(start 0.12065 -0.2794)
			(end 0.12065 -0.3048)
			(stroke
				(width 0.1)
				(type default)
			)
			(layer "F.Fab")
		)
		(fp_line
			(start 0.12065 -0.3048)
			(end 0.67945 -0.3048)
			(stroke
				(width 0.1)
				(type default)
			)
			(layer "F.Fab")
		)
		(fp_line
			(start 0.67945 -0.3048)
			(end 0.67945 0.3048)
			(stroke
				(width 0.1)
				(type default)
			)
			(layer "F.Fab")
		)
		(fp_line
			(start -0.67945 -0.305054)
			(end -0.12065 -0.305054)
			(stroke
				(width 0.1)
				(type default)
			)
			(layer "F.Fab")
		)
		(fp_line
			(start -0.12065 -0.305054)
			(end -0.12065 -0.2794)
			(stroke
				(width 0.1)
				(type default)
			)
			(layer "F.Fab")
		)
		(pad "1" smd circle
			(at -0.40005 0 270)
			(size 0 0)
			(layers "F.Cu" "F.Mask" "F.Paste")
			(net "SW_P12V_AUX_PVDD11_S3_P1_FLT")
		)
		(pad "2" smd circle
			(at 0.40005 0 270)
			(size 0 0)
			(layers "F.Cu" "F.Mask" "F.Paste")
			(net "GND")
		)
	)
	(footprint ""
		(layer "F.Cu")
		(at 320.571876 -70.098412 90)
		(property "Reference" "D96"
			(at -3.934714 -0.691642 90)
			(unlocked yes)
			(layer "F.SilkS")
			(effects
				(font
					(size 0.7874 0.5842)
					(thickness 0.1524)
				)
				(justify left)
			)
		)
		(property "Value" ""
			(at 0 0 90)
			(layer "F.Fab")
			(effects
				(font
					(size 1.27 1.27)
				)
			)
		)
		(duplicate_pad_numbers_are_jumpers no)
		(fp_line
			(start 1.16078 -0.4826)
			(end 1.16078 0.4826)
			(stroke
				(width 0.1524)
				(type default)
			)
			(layer "F.SilkS")
		)
		(fp_line
			(start 1.03378 -0.4826)
			(end 1.03378 0.4826)
			(stroke
				(width 0.1524)
				(type default)
			)
			(layer "F.SilkS")
		)
		(fp_line
			(start 0.90678 -0.4826)
			(end 0.90678 0.4826)
			(stroke
				(width 0.1524)
				(type default)
			)
			(layer "F.SilkS")
		)
		(fp_line
			(start -0.64008 -0.4826)
			(end 1.16078 -0.4826)
			(stroke
				(width 0.1524)
				(type default)
			)
			(layer "F.SilkS")
		)
		(fp_line
			(start -0.79248 -0.4826)
			(end 1.03378 -0.4826)
			(stroke
				(width 0.1524)
				(type default)
			)
			(layer "F.SilkS")
		)
		(fp_line
			(start -0.89408 -0.4826)
			(end 0.90678 -0.4826)
			(stroke
				(width 0.1524)
				(type default)
			)
			(layer "F.SilkS")
		)
		(fp_line
			(start 1.16078 0.4826)
			(end -0.64008 0.4826)
			(stroke
				(width 0.1524)
				(type default)
			)
			(layer "F.SilkS")
		)
		(fp_line
			(start 1.03378 0.4826)
			(end -0.79248 0.4826)
			(stroke
				(width 0.1524)
				(type default)
			)
			(layer "F.SilkS")
		)
		(fp_line
			(start 0.90678 0.4826)
			(end -0.90678 0.4826)
			(stroke
				(width 0.1524)
				(type default)
			)
			(layer "F.SilkS")
		)
		(fp_line
			(start -0.90678 0.4826)
			(end -0.90678 -0.4699)
			(stroke
				(width 0.1524)
				(type default)
			)
			(layer "F.SilkS")
		)
		(fp_line
			(start 0.499872 -0.249936)
			(end 0.499872 0.249936)
			(stroke
				(width 0.1)
				(type default)
			)
			(layer "F.Fab")
		)
		(fp_line
			(start -0.499872 -0.249936)
			(end 0.499872 -0.249936)
			(stroke
				(width 0.1)
				(type default)
			)
			(layer "F.Fab")
		)
		(fp_line
			(start 0.499872 0.249936)
			(end -0.499872 0.249936)
			(stroke
				(width 0.1)
				(type default)
			)
			(layer "F.Fab")
		)
		(fp_line
			(start -0.499872 0.249936)
			(end -0.499872 -0.249936)
			(stroke
				(width 0.1)
				(type default)
			)
			(layer "F.Fab")
		)
		(pad "A" smd rect
			(at -0.47498 0 90)
			(size 0.6096 0.7112)
			(layers "F.Cu" "F.Mask" "F.Paste")
			(net "LED_PWRGD_PS_PWROK_PLD")
		)
		(pad "C" smd rect
			(at 0.47498 0 90)
			(size 0.6096 0.7112)
			(layers "F.Cu" "F.Mask" "F.Paste")
			(net "LED_PWRGD_PS_PWROK_PLD_D")
		)
	)
	(footprint ""
		(layer "F.Cu")
		(at 170.970702 -439.740294 90)
		(property "Reference" "R2835"
			(at 0 0 90)
			(layer "F.SilkS")
			(hide yes)
			(effects
				(font
					(size 1.27 1.27)
				)
			)
		)
		(property "Value" ""
			(at 0 0 90)
			(layer "F.Fab")
			(effects
				(font
					(size 1.27 1.27)
				)
			)
		)
		(duplicate_pad_numbers_are_jumpers no)
		(fp_line
			(start 0.7874 -0.4064)
			(end 0.7874 0.4064)
			(stroke
				(width 0.1524)
				(type default)
			)
			(layer "F.SilkS")
		)
		(fp_line
			(start -0.7874 -0.4064)
			(end 0.7874 -0.4064)
			(stroke
				(width 0.1524)
				(type default)
			)
			(layer "F.SilkS")
		)
		(fp_line
			(start 0.7874 0.4064)
			(end -0.7874 0.4064)
			(stroke
				(width 0.1524)
				(type default)
			)
			(layer "F.SilkS")
		)
		(fp_line
			(start -0.7874 0.4064)
			(end -0.7874 -0.4064)
			(stroke
				(width 0.1524)
				(type default)
			)
			(layer "F.SilkS")
		)
		(fp_line
			(start -0.12065 -0.305054)
			(end -0.12065 -0.2794)
			(stroke
				(width 0.1)
				(type default)
			)
			(layer "F.Fab")
		)
		(fp_line
			(start -0.67945 -0.305054)
			(end -0.12065 -0.305054)
			(stroke
				(width 0.1)
				(type default)
			)
			(layer "F.Fab")
		)
		(fp_line
			(start 0.67945 -0.3048)
			(end 0.67945 0.3048)
			(stroke
				(width 0.1)
				(type default)
			)
			(layer "F.Fab")
		)
		(fp_line
			(start 0.12065 -0.3048)
			(end 0.67945 -0.3048)
			(stroke
				(width 0.1)
				(type default)
			)
			(layer "F.Fab")
		)
		(fp_line
			(start 0.12065 -0.2794)
			(end 0.12065 -0.3048)
			(stroke
				(width 0.1)
				(type default)
			)
			(layer "F.Fab")
		)
		(fp_line
			(start -0.12065 -0.2794)
			(end 0.12065 -0.2794)
			(stroke
				(width 0.1)
				(type default)
			)
			(layer "F.Fab")
		)
		(fp_line
			(start 0.120396 0.2794)
			(end -0.12065 0.2794)
			(stroke
				(width 0.1)
				(type default)
			)
			(layer "F.Fab")
		)
		(fp_line
			(start -0.12065 0.2794)
			(end -0.12065 0.3048)
			(stroke
				(width 0.1)
				(type default)
			)
			(layer "F.Fab")
		)
		(fp_line
			(start 0.67945 0.3048)
			(end 0.120396 0.3048)
			(stroke
				(width 0.1)
				(type default)
			)
			(layer "F.Fab")
		)
		(fp_line
			(start 0.120396 0.3048)
			(end 0.120396 0.2794)
			(stroke
				(width 0.1)
				(type default)
			)
			(layer "F.Fab")
		)
		(fp_line
			(start -0.12065 0.3048)
			(end -0.67945 0.3048)
			(stroke
				(width 0.1)
				(type default)
			)
			(layer "F.Fab")
		)
		(fp_line
			(start -0.67945 0.3048)
			(end -0.67945 -0.305054)
			(stroke
				(width 0.1)
				(type default)
			)
			(layer "F.Fab")
		)
		(pad "1" smd circle
			(at -0.40005 0 90)
			(size 0 0)
			(layers "F.Cu" "F.Mask" "F.Paste")
			(net "P3V3_AUX")
		)
		(pad "2" smd circle
			(at 0.40005 0 90)
			(size 0 0)
			(layers "F.Cu" "F.Mask" "F.Paste")
			(net "BIC_MONITER_N")
		)
	)
	(footprint ""
		(layer "F.Cu")
		(at 158.668466 -408.517344 -90)
		(property "Reference" "C6721"
			(at 0 0 270)
			(layer "F.SilkS")
			(hide yes)
			(effects
				(font
					(size 1.27 1.27)
				)
			)
		)
		(property "Value" ""
			(at 0 0 270)
			(layer "F.Fab")
			(effects
				(font
					(size 1.27 1.27)
				)
			)
		)
		(duplicate_pad_numbers_are_jumpers no)
		(fp_line
			(start -0.299974 0.150114)
			(end -0.299974 -0.150114)
			(stroke
				(width 0.1)
				(type default)
			)
			(layer "F.Fab")
		)
		(fp_line
			(start 0.299974 0.150114)
			(end -0.299974 0.150114)
			(stroke
				(width 0.1)
				(type default)
			)
			(layer "F.Fab")
		)
		(fp_line
			(start -0.299974 -0.150114)
			(end 0.299974 -0.150114)
			(stroke
				(width 0.1)
				(type default)
			)
			(layer "F.Fab")
		)
		(fp_line
			(start 0.299974 -0.150114)
			(end 0.299974 0.150114)
			(stroke
				(width 0.1)
				(type default)
			)
			(layer "F.Fab")
		)
		(pad "1" smd rect
			(at -0.2667 0 270)
			(size 0.3048 0.381)
			(layers "F.Cu" "F.Mask" "F.Paste")
			(net "P5E_CPU1_P2_TX_BUF_C_DP<14>")
		)
		(pad "2" smd rect
			(at 0.2667 0 270)
			(size 0.3048 0.381)
			(layers "F.Cu" "F.Mask" "F.Paste")
			(net "P5E_CPU1_P2_TX_BUF_DP<14>")
		)
	)
	(footprint ""
		(layer "F.Cu")
		(at 392.593576 -394.82268 90)
		(property "Reference" "C993"
			(at 0 0 90)
			(layer "F.SilkS")
			(hide yes)
			(effects
				(font
					(size 1.27 1.27)
				)
			)
		)
		(property "Value" ""
			(at 0 0 90)
			(layer "F.Fab")
			(effects
				(font
					(size 1.27 1.27)
				)
			)
		)
		(duplicate_pad_numbers_are_jumpers no)
		(fp_line
			(start 0.7874 -0.4064)
			(end 0.7874 0.4064)
			(stroke
				(width 0.1524)
				(type default)
			)
			(layer "F.SilkS")
		)
		(fp_line
			(start -0.7874 -0.4064)
			(end 0.7874 -0.4064)
			(stroke
				(width 0.1524)
				(type default)
			)
			(layer "F.SilkS")
		)
		(fp_line
			(start 0.7874 0.4064)
			(end -0.7874 0.4064)
			(stroke
				(width 0.1524)
				(type default)
			)
			(layer "F.SilkS")
		)
		(fp_line
			(start -0.7874 0.4064)
			(end -0.7874 -0.4064)
			(stroke
				(width 0.1524)
				(type default)
			)
			(layer "F.SilkS")
		)
		(fp_line
			(start -0.12065 -0.305054)
			(end -0.12065 -0.2794)
			(stroke
				(width 0.1)
				(type default)
			)
			(layer "F.Fab")
		)
		(fp_line
			(start -0.67945 -0.305054)
			(end -0.12065 -0.305054)
			(stroke
				(width 0.1)
				(type default)
			)
			(layer "F.Fab")
		)
		(fp_line
			(start 0.67945 -0.3048)
			(end 0.67945 0.3048)
			(stroke
				(width 0.1)
				(type default)
			)
			(layer "F.Fab")
		)
		(fp_line
			(start 0.12065 -0.3048)
			(end 0.67945 -0.3048)
			(stroke
				(width 0.1)
				(type default)
			)
			(layer "F.Fab")
		)
		(fp_line
			(start 0.12065 -0.2794)
			(end 0.12065 -0.3048)
			(stroke
				(width 0.1)
				(type default)
			)
			(layer "F.Fab")
		)
		(fp_line
			(start -0.12065 -0.2794)
			(end 0.12065 -0.2794)
			(stroke
				(width 0.1)
				(type default)
			)
			(layer "F.Fab")
		)
		(fp_line
			(start 0.120396 0.2794)
			(end -0.12065 0.2794)
			(stroke
				(width 0.1)
				(type default)
			)
			(layer "F.Fab")
		)
		(fp_line
			(start -0.12065 0.2794)
			(end -0.12065 0.3048)
			(stroke
				(width 0.1)
				(type default)
			)
			(layer "F.Fab")
		)
		(fp_line
			(start 0.67945 0.3048)
			(end 0.120396 0.3048)
			(stroke
				(width 0.1)
				(type default)
			)
			(layer "F.Fab")
		)
		(fp_line
			(start 0.120396 0.3048)
			(end 0.120396 0.2794)
			(stroke
				(width 0.1)
				(type default)
			)
			(layer "F.Fab")
		)
		(fp_line
			(start -0.12065 0.3048)
			(end -0.67945 0.3048)
			(stroke
				(width 0.1)
				(type default)
			)
			(layer "F.Fab")
		)
		(fp_line
			(start -0.67945 0.3048)
			(end -0.67945 -0.305054)
			(stroke
				(width 0.1)
				(type default)
			)
			(layer "F.Fab")
		)
		(pad "1" smd circle
			(at -0.40005 0 90)
			(size 0 0)
			(layers "F.Cu" "F.Mask" "F.Paste")
			(net "P1V8_CPU0_RT3_1A")
		)
		(pad "2" smd circle
			(at 0.40005 0 90)
			(size 0 0)
			(layers "F.Cu" "F.Mask" "F.Paste")
			(net "GND")
		)
	)
	(footprint ""
		(layer "F.Cu")
		(at 91.759532 -332.02499 180)
		(property "Reference" "PC207"
			(at 0 0 180)
			(layer "F.SilkS")
			(hide yes)
			(effects
				(font
					(size 1.27 1.27)
				)
			)
		)
		(property "Value" ""
			(at 0 0 180)
			(layer "F.Fab")
			(effects
				(font
					(size 1.27 1.27)
				)
			)
		)
		(duplicate_pad_numbers_are_jumpers no)
		(fp_line
			(start 0.7874 0.4064)
			(end -0.7874 0.4064)
			(stroke
				(width 0.1524)
				(type default)
			)
			(layer "F.SilkS")
		)
		(fp_line
			(start 0.7874 -0.4064)
			(end 0.7874 0.4064)
			(stroke
				(width 0.1524)
				(type default)
			)
			(layer "F.SilkS")
		)
		(fp_line
			(start -0.7874 0.4064)
			(end -0.7874 -0.4064)
			(stroke
				(width 0.1524)
				(type default)
			)
			(layer "F.SilkS")
		)
		(fp_line
			(start -0.7874 -0.4064)
			(end 0.7874 -0.4064)
			(stroke
				(width 0.1524)
				(type default)
			)
			(layer "F.SilkS")
		)
		(fp_line
			(start 0.67945 0.3048)
			(end 0.120396 0.3048)
			(stroke
				(width 0.1)
				(type default)
			)
			(layer "F.Fab")
		)
		(fp_line
			(start 0.67945 -0.3048)
			(end 0.67945 0.3048)
			(stroke
				(width 0.1)
				(type default)
			)
			(layer "F.Fab")
		)
		(fp_line
			(start 0.12065 -0.2794)
			(end 0.12065 -0.3048)
			(stroke
				(width 0.1)
				(type default)
			)
			(layer "F.Fab")
		)
		(fp_line
			(start 0.12065 -0.3048)
			(end 0.67945 -0.3048)
			(stroke
				(width 0.1)
				(type default)
			)
			(layer "F.Fab")
		)
		(fp_line
			(start 0.120396 0.3048)
			(end 0.120396 0.2794)
			(stroke
				(width 0.1)
				(type default)
			)
			(layer "F.Fab")
		)
		(fp_line
			(start 0.120396 0.2794)
			(end -0.12065 0.2794)
			(stroke
				(width 0.1)
				(type default)
			)
			(layer "F.Fab")
		)
		(fp_line
			(start -0.12065 0.3048)
			(end -0.67945 0.3048)
			(stroke
				(width 0.1)
				(type default)
			)
			(layer "F.Fab")
		)
		(fp_line
			(start -0.12065 0.2794)
			(end -0.12065 0.3048)
			(stroke
				(width 0.1)
				(type default)
			)
			(layer "F.Fab")
		)
		(fp_line
			(start -0.12065 -0.2794)
			(end 0.12065 -0.2794)
			(stroke
				(width 0.1)
				(type default)
			)
			(layer "F.Fab")
		)
		(fp_line
			(start -0.12065 -0.305054)
			(end -0.12065 -0.2794)
			(stroke
				(width 0.1)
				(type default)
			)
			(layer "F.Fab")
		)
		(fp_line
			(start -0.67945 0.3048)
			(end -0.67945 -0.305054)
			(stroke
				(width 0.1)
				(type default)
			)
			(layer "F.Fab")
		)
		(fp_line
			(start -0.67945 -0.305054)
			(end -0.12065 -0.305054)
			(stroke
				(width 0.1)
				(type default)
			)
			(layer "F.Fab")
		)
		(pad "1" smd circle
			(at -0.40005 0 180)
			(size 0 0)
			(layers "F.Cu" "F.Mask" "F.Paste")
			(net "SW_PVDDCR_CPU1_P1_SW5")
		)
		(pad "2" smd circle
			(at 0.40005 0 180)
			(size 0 0)
			(layers "F.Cu" "F.Mask" "F.Paste")
			(net "SW_PVDDCR_CPU1_P1_SW5_RC")
		)
	)
	(footprint ""
		(layer "F.Cu")
		(at 383.121662 -416.899344 -90)
		(property "Reference" "C6574"
			(at 0 0 270)
			(layer "F.SilkS")
			(hide yes)
			(effects
				(font
					(size 1.27 1.27)
				)
			)
		)
		(property "Value" ""
			(at 0 0 270)
			(layer "F.Fab")
			(effects
				(font
					(size 1.27 1.27)
				)
			)
		)
		(duplicate_pad_numbers_are_jumpers no)
		(fp_line
			(start -0.299974 0.150114)
			(end -0.299974 -0.150114)
			(stroke
				(width 0.1)
				(type default)
			)
			(layer "F.Fab")
		)
		(fp_line
			(start 0.299974 0.150114)
			(end -0.299974 0.150114)
			(stroke
				(width 0.1)
				(type default)
			)
			(layer "F.Fab")
		)
		(fp_line
			(start -0.299974 -0.150114)
			(end 0.299974 -0.150114)
			(stroke
				(width 0.1)
				(type default)
			)
			(layer "F.Fab")
		)
		(fp_line
			(start 0.299974 -0.150114)
			(end 0.299974 0.150114)
			(stroke
				(width 0.1)
				(type default)
			)
			(layer "F.Fab")
		)
		(pad "1" smd rect
			(at -0.2667 0 270)
			(size 0.3048 0.381)
			(layers "F.Cu" "F.Mask" "F.Paste")
			(net "P5E_CPU0_P2_TX_BUF_C_DN<4>")
		)
		(pad "2" smd rect
			(at 0.2667 0 270)
			(size 0.3048 0.381)
			(layers "F.Cu" "F.Mask" "F.Paste")
			(net "P5E_CPU0_P2_TX_BUF_DN<4>")
		)
	)
	(footprint ""
		(layer "F.Cu")
		(at 258.275836 -72.976994)
		(property "Reference" "R2114"
			(at 0 0 0)
			(layer "F.SilkS")
			(hide yes)
			(effects
				(font
					(size 1.27 1.27)
				)
			)
		)
		(property "Value" ""
			(at 0 0 0)
			(layer "F.Fab")
			(effects
				(font
					(size 1.27 1.27)
				)
			)
		)
		(duplicate_pad_numbers_are_jumpers no)
		(fp_line
			(start -0.7874 -0.4064)
			(end 0.7874 -0.4064)
			(stroke
				(width 0.1524)
				(type default)
			)
			(layer "F.SilkS")
		)
		(fp_line
			(start -0.7874 0.4064)
			(end -0.7874 -0.4064)
			(stroke
				(width 0.1524)
				(type default)
			)
			(layer "F.SilkS")
		)
		(fp_line
			(start 0.7874 -0.4064)
			(end 0.7874 0.4064)
			(stroke
				(width 0.1524)
				(type default)
			)
			(layer "F.SilkS")
		)
		(fp_line
			(start 0.7874 0.4064)
			(end -0.7874 0.4064)
			(stroke
				(width 0.1524)
				(type default)
			)
			(layer "F.SilkS")
		)
		(fp_line
			(start -0.67945 -0.305054)
			(end -0.12065 -0.305054)
			(stroke
				(width 0.1)
				(type default)
			)
			(layer "F.Fab")
		)
		(fp_line
			(start -0.67945 0.3048)
			(end -0.67945 -0.305054)
			(stroke
				(width 0.1)
				(type default)
			)
			(layer "F.Fab")
		)
		(fp_line
			(start -0.12065 -0.305054)
			(end -0.12065 -0.2794)
			(stroke
				(width 0.1)
				(type default)
			)
			(layer "F.Fab")
		)
		(fp_line
			(start -0.12065 -0.2794)
			(end 0.12065 -0.2794)
			(stroke
				(width 0.1)
				(type default)
			)
			(layer "F.Fab")
		)
		(fp_line
			(start -0.12065 0.2794)
			(end -0.12065 0.3048)
			(stroke
				(width 0.1)
				(type default)
			)
			(layer "F.Fab")
		)
		(fp_line
			(start -0.12065 0.3048)
			(end -0.67945 0.3048)
			(stroke
				(width 0.1)
				(type default)
			)
			(layer "F.Fab")
		)
		(fp_line
			(start 0.120396 0.2794)
			(end -0.12065 0.2794)
			(stroke
				(width 0.1)
				(type default)
			)
			(layer "F.Fab")
		)
		(fp_line
			(start 0.120396 0.3048)
			(end 0.120396 0.2794)
			(stroke
				(width 0.1)
				(type default)
			)
			(layer "F.Fab")
		)
		(fp_line
			(start 0.12065 -0.3048)
			(end 0.67945 -0.3048)
			(stroke
				(width 0.1)
				(type default)
			)
			(layer "F.Fab")
		)
		(fp_line
			(start 0.12065 -0.2794)
			(end 0.12065 -0.3048)
			(stroke
				(width 0.1)
				(type default)
			)
			(layer "F.Fab")
		)
		(fp_line
			(start 0.67945 -0.3048)
			(end 0.67945 0.3048)
			(stroke
				(width 0.1)
				(type default)
			)
			(layer "F.Fab")
		)
		(fp_line
			(start 0.67945 0.3048)
			(end 0.120396 0.3048)
			(stroke
				(width 0.1)
				(type default)
			)
			(layer "F.Fab")
		)
		(pad "1" smd circle
			(at -0.40005 0)
			(size 0 0)
			(layers "F.Cu" "F.Mask" "F.Paste")
			(net "SMB_PCIE_E1S_ISO_EN_R2")
		)
		(pad "2" smd circle
			(at 0.40005 0)
			(size 0 0)
			(layers "F.Cu" "F.Mask" "F.Paste")
			(net "SMB_PCIE_E1S_ISO_EN")
		)
	)
	(footprint ""
		(layer "F.Cu")
		(at 52.705 -38.735)
		(property "Reference" "U31"
			(at -0.882142 -2.608072 0)
			(unlocked yes)
			(layer "F.SilkS")
			(effects
				(font
					(size 0.7874 0.5842)
					(thickness 0.1524)
				)
				(justify left)
			)
		)
		(property "Value" ""
			(at 0 0 0)
			(layer "F.Fab")
			(effects
				(font
					(size 1.27 1.27)
				)
			)
		)
		(duplicate_pad_numbers_are_jumpers no)
		(fp_line
			(start -1.733296 -1.549908)
			(end -1.733296 1.549908)
			(stroke
				(width 0.1524)
				(type default)
			)
			(layer "F.SilkS")
		)
		(fp_line
			(start -1.733296 1.549908)
			(end 1.733296 1.549908)
			(stroke
				(width 0.1524)
				(type default)
			)
			(layer "F.SilkS")
		)
		(fp_line
			(start -0.660908 -1.549908)
			(end -1.733296 -1.549908)
			(stroke
				(width 0.1524)
				(type default)
			)
			(layer "F.SilkS")
		)
		(fp_line
			(start 0 -0.889)
			(end -0.660908 -1.549908)
			(stroke
				(width 0.1524)
				(type default)
			)
			(layer "F.SilkS")
		)
		(fp_line
			(start 0.660908 -1.549908)
			(end 0 -0.889)
			(stroke
				(width 0.1524)
				(type default)
			)
			(layer "F.SilkS")
		)
		(fp_line
			(start 1.733296 -1.549908)
			(end 0.660908 -1.549908)
			(stroke
				(width 0.1524)
				(type default)
			)
			(layer "F.SilkS")
		)
		(fp_line
			(start 1.733296 1.549908)
			(end 1.733296 -1.549908)
			(stroke
				(width 0.1524)
				(type default)
			)
			(layer "F.SilkS")
		)
		(fp_poly
			(pts
				(xy -1.556512 -2.49555) (xy -2.005076 -2.257298) (xy -1.542542 -1.92786)
			)
			(stroke
				(width 0)
				(type default)
			)
			(fill yes)
			(layer "F.SilkS")
		)
		(fp_line
			(start -0.849884 -1.549908)
			(end -0.849884 1.549908)
			(stroke
				(width 0.1)
				(type default)
			)
			(layer "F.Fab")
		)
		(fp_line
			(start -0.849884 1.549908)
			(end 0.849884 1.549908)
			(stroke
				(width 0.1)
				(type default)
			)
			(layer "F.Fab")
		)
		(fp_line
			(start 0.849884 -1.549908)
			(end -0.849884 -1.549908)
			(stroke
				(width 0.1)
				(type default)
			)
			(layer "F.Fab")
		)
		(fp_line
			(start 0.849884 1.549908)
			(end 0.849884 -1.549908)
			(stroke
				(width 0.1)
				(type default)
			)
			(layer "F.Fab")
		)
		(fp_poly
			(pts
				(xy -2.4384 -1.20396) (xy -2.4384 -0.69596) (xy -1.9304 -0.94996)
			)
			(stroke
				(width 0)
				(type default)
			)
			(fill yes)
			(layer "F.Fab")
		)
		(pad "1" smd rect
			(at -1.199896 -0.94996 270)
			(size 0.5588 0.8128)
			(layers "F.Cu" "F.Mask" "F.Paste")
			(net "P12V_OCP_V3_2_EN_R3")
		)
		(pad "2" smd rect
			(at -1.199896 0 270)
			(size 0.5588 0.8128)
			(layers "F.Cu" "F.Mask" "F.Paste")
			(net "HP_LVC3_OCP_V3_2_PRSNT2")
		)
		(pad "3" smd rect
			(at -1.199896 0.94996 270)
			(size 0.5588 0.8128)
			(layers "F.Cu" "F.Mask" "F.Paste")
			(net "GND")
		)
		(pad "4" smd rect
			(at 1.199896 0.94996 270)
			(size 0.5588 0.8128)
			(layers "F.Cu" "F.Mask" "F.Paste")
			(net "P12V_OCP_V3_2_BUF_EN")
		)
		(pad "5" smd rect
			(at 1.199896 -0.94996 270)
			(size 0.5588 0.8128)
			(layers "F.Cu" "F.Mask" "F.Paste")
			(net "P3V3_AUX")
		)
	)
	(footprint ""
		(layer "F.Cu")
		(at 366.06734 -385.23926 180)
		(property "Reference" "C898"
			(at 0 0 180)
			(layer "F.SilkS")
			(hide yes)
			(effects
				(font
					(size 1.27 1.27)
				)
			)
		)
		(property "Value" ""
			(at 0 0 180)
			(layer "F.Fab")
			(effects
				(font
					(size 1.27 1.27)
				)
			)
		)
		(duplicate_pad_numbers_are_jumpers no)
		(fp_line
			(start 0.299974 0.150114)
			(end -0.299974 0.150114)
			(stroke
				(width 0.1)
				(type default)
			)
			(layer "F.Fab")
		)
		(fp_line
			(start 0.299974 -0.150114)
			(end 0.299974 0.150114)
			(stroke
				(width 0.1)
				(type default)
			)
			(layer "F.Fab")
		)
		(fp_line
			(start -0.299974 0.150114)
			(end -0.299974 -0.150114)
			(stroke
				(width 0.1)
				(type default)
			)
			(layer "F.Fab")
		)
		(fp_line
			(start -0.299974 -0.150114)
			(end 0.299974 -0.150114)
			(stroke
				(width 0.1)
				(type default)
			)
			(layer "F.Fab")
		)
		(pad "1" smd rect
			(at -0.2667 0 180)
			(size 0.3048 0.381)
			(layers "F.Cu" "F.Mask" "F.Paste")
			(net "P5E_CPU0_P3_TX_C_DN<1>")
		)
		(pad "2" smd rect
			(at 0.2667 0 180)
			(size 0.3048 0.381)
			(layers "F.Cu" "F.Mask" "F.Paste")
			(net "P5E_CPU0_P3_TX_DN<1>")
		)
	)
	(footprint ""
		(layer "F.Cu")
		(at 33.291272 -434.173884)
		(property "Reference" "C1766"
			(at 0 0 0)
			(layer "F.SilkS")
			(hide yes)
			(effects
				(font
					(size 1.27 1.27)
				)
			)
		)
		(property "Value" ""
			(at 0 0 0)
			(layer "F.Fab")
			(effects
				(font
					(size 1.27 1.27)
				)
			)
		)
		(duplicate_pad_numbers_are_jumpers no)
		(fp_line
			(start -0.7874 -0.4064)
			(end 0.7874 -0.4064)
			(stroke
				(width 0.1524)
				(type default)
			)
			(layer "F.SilkS")
		)
		(fp_line
			(start -0.7874 0.4064)
			(end -0.7874 -0.4064)
			(stroke
				(width 0.1524)
				(type default)
			)
			(layer "F.SilkS")
		)
		(fp_line
			(start 0.7874 -0.4064)
			(end 0.7874 0.4064)
			(stroke
				(width 0.1524)
				(type default)
			)
			(layer "F.SilkS")
		)
		(fp_line
			(start 0.7874 0.4064)
			(end -0.7874 0.4064)
			(stroke
				(width 0.1524)
				(type default)
			)
			(layer "F.SilkS")
		)
		(fp_line
			(start -0.67945 -0.305054)
			(end -0.12065 -0.305054)
			(stroke
				(width 0.1)
				(type default)
			)
			(layer "F.Fab")
		)
		(fp_line
			(start -0.67945 0.3048)
			(end -0.67945 -0.305054)
			(stroke
				(width 0.1)
				(type default)
			)
			(layer "F.Fab")
		)
		(fp_line
			(start -0.12065 -0.305054)
			(end -0.12065 -0.2794)
			(stroke
				(width 0.1)
				(type default)
			)
			(layer "F.Fab")
		)
		(fp_line
			(start -0.12065 -0.2794)
			(end 0.12065 -0.2794)
			(stroke
				(width 0.1)
				(type default)
			)
			(layer "F.Fab")
		)
		(fp_line
			(start -0.12065 0.2794)
			(end -0.12065 0.3048)
			(stroke
				(width 0.1)
				(type default)
			)
			(layer "F.Fab")
		)
		(fp_line
			(start -0.12065 0.3048)
			(end -0.67945 0.3048)
			(stroke
				(width 0.1)
				(type default)
			)
			(layer "F.Fab")
		)
		(fp_line
			(start 0.120396 0.2794)
			(end -0.12065 0.2794)
			(stroke
				(width 0.1)
				(type default)
			)
			(layer "F.Fab")
		)
		(fp_line
			(start 0.120396 0.3048)
			(end 0.120396 0.2794)
			(stroke
				(width 0.1)
				(type default)
			)
			(layer "F.Fab")
		)
		(fp_line
			(start 0.12065 -0.3048)
			(end 0.67945 -0.3048)
			(stroke
				(width 0.1)
				(type default)
			)
			(layer "F.Fab")
		)
		(fp_line
			(start 0.12065 -0.2794)
			(end 0.12065 -0.3048)
			(stroke
				(width 0.1)
				(type default)
			)
			(layer "F.Fab")
		)
		(fp_line
			(start 0.67945 -0.3048)
			(end 0.67945 0.3048)
			(stroke
				(width 0.1)
				(type default)
			)
			(layer "F.Fab")
		)
		(fp_line
			(start 0.67945 0.3048)
			(end 0.120396 0.3048)
			(stroke
				(width 0.1)
				(type default)
			)
			(layer "F.Fab")
		)
		(pad "1" smd circle
			(at -0.40005 0)
			(size 0 0)
			(layers "F.Cu" "F.Mask" "F.Paste")
			(net "P3V3_AUX")
		)
		(pad "2" smd circle
			(at 0.40005 0)
			(size 0 0)
			(layers "F.Cu" "F.Mask" "F.Paste")
			(net "GND")
		)
	)
	(footprint ""
		(layer "F.Cu")
		(at 166.47795 -255.560322 180)
		(property "Reference" "J102"
			(at -2.7178 -81.857088 0)
			(unlocked yes)
			(layer "F.SilkS")
			(effects
				(font
					(size 0.7874 0.5842)
					(thickness 0.1524)
				)
			)
		)
		(property "Value" ""
			(at 0 0 180)
			(layer "F.Fab")
			(effects
				(font
					(size 1.27 1.27)
				)
			)
		)
		(duplicate_pad_numbers_are_jumpers no)
		(fp_line
			(start 3.24993 81.000092)
			(end -3.24993 81.000092)
			(stroke
				(width 0.1524)
				(type default)
			)
			(layer "F.SilkS")
		)
		(fp_line
			(start 3.24993 62.447678)
			(end 3.24993 81.000092)
			(stroke
				(width 0.1524)
				(type default)
			)
			(layer "F.SilkS")
		)
		(fp_line
			(start 3.24993 -0.925322)
			(end 3.24993 4.789678)
			(stroke
				(width 0.1524)
				(type default)
			)
			(layer "F.SilkS")
		)
		(fp_line
			(start 3.24993 -81.000092)
			(end 3.24993 -58.075322)
			(stroke
				(width 0.1524)
				(type default)
			)
			(layer "F.SilkS")
		)
		(fp_line
			(start -3.24993 81.000092)
			(end -3.24993 -81.000092)
			(stroke
				(width 0.1524)
				(type default)
			)
			(layer "F.SilkS")
		)
		(fp_line
			(start -3.24993 72.499982)
			(end 3.24993 72.499982)
			(stroke
				(width 0.1524)
				(type default)
			)
			(layer "F.SilkS")
		)
		(fp_line
			(start -3.24993 -72.499982)
			(end 3.24993 -72.499982)
			(stroke
				(width 0.1524)
				(type default)
			)
			(layer "F.SilkS")
		)
		(fp_line
			(start -3.24993 -81.000092)
			(end 3.24993 -81.000092)
			(stroke
				(width 0.1524)
				(type default)
			)
			(layer "F.SilkS")
		)
		(fp_poly
			(pts
				(xy -3.7465 -64.824864) (xy -3.082036 -63.903352) (xy -4.217924 -63.924688)
			)
			(stroke
				(width 0)
				(type default)
			)
			(fill yes)
			(layer "F.SilkS")
		)
		(fp_line
			(start 3.24993 81.000092)
			(end -3.24993 81.000092)
			(stroke
				(width 0.1)
				(type default)
			)
			(layer "F.Fab")
		)
		(fp_line
			(start 3.24993 -81.000092)
			(end 3.24993 81.000092)
			(stroke
				(width 0.1)
				(type default)
			)
			(layer "F.Fab")
		)
		(fp_line
			(start -3.24993 81.000092)
			(end -3.24993 -81.000092)
			(stroke
				(width 0.1)
				(type default)
			)
			(layer "F.Fab")
		)
		(fp_line
			(start -3.24993 72.499982)
			(end 3.24993 72.499982)
			(stroke
				(width 0.1)
				(type default)
			)
			(layer "F.Fab")
		)
		(fp_line
			(start -3.24993 71.000112)
			(end 3.24993 71.000112)
			(stroke
				(width 0.1)
				(type default)
			)
			(layer "F.Fab")
		)
		(fp_line
			(start -3.24993 -71.000112)
			(end 3.24993 -71.000112)
			(stroke
				(width 0.1)
				(type default)
			)
			(layer "F.Fab")
		)
		(fp_line
			(start -3.24993 -72.499982)
			(end 3.24993 -72.499982)
			(stroke
				(width 0.1)
				(type default)
			)
			(layer "F.Fab")
		)
		(fp_line
			(start -3.24993 -81.000092)
			(end 3.24993 -81.000092)
			(stroke
				(width 0.1)
				(type default)
			)
			(layer "F.Fab")
		)
		(fp_poly
			(pts
				(xy -3.41503 -63.324994) (xy -4.43103 -62.816994) (xy -4.43103 -63.832994)
			)
			(stroke
				(width 0)
				(type default)
			)
			(fill yes)
			(layer "F.Fab")
		)
		(pad "1" smd rect
			(at -2.050034 -63.324994 90)
			(size 0.519938 1.4986)
			(layers "F.Cu" "F.Mask" "F.Paste")
			(net "P12V_MEM_CPU1")
		)
		(pad "2" smd rect
			(at -2.050034 -62.47511 90)
			(size 0.519938 1.4986)
			(layers "F.Cu" "F.Mask" "F.Paste")
			(net "Net_2340")
		)
		(pad "3" smd rect
			(at -2.050034 -61.624972 90)
			(size 0.519938 1.4986)
			(layers "F.Cu" "F.Mask" "F.Paste")
			(net "P3V3_AUX")
		)
		(pad "4" smd rect
			(at -2.050034 -60.775088 90)
			(size 0.519938 1.4986)
			(layers "F.Cu" "F.Mask" "F.Paste")
			(net "I3C_SPD_DDRG_CPU1_SCL")
		)
		(pad "5" smd rect
			(at -2.050034 -59.92495 90)
			(size 0.519938 1.4986)
			(layers "F.Cu" "F.Mask" "F.Paste")
			(net "I3C_SPD_DDRG_CPU1_SDA")
		)
		(pad "6" smd rect
			(at -2.050034 -59.075066 90)
			(size 0.519938 1.4986)
			(layers "F.Cu" "F.Mask" "F.Paste")
			(net "GND")
		)
		(pad "7" smd rect
			(at -2.050034 -58.224928 90)
			(size 0.519938 1.4986)
			(layers "F.Cu" "F.Mask" "F.Paste")
			(net "M_G_CPU1_SA_DQ<0>")
		)
		(pad "8" smd rect
			(at -2.050034 -57.375044 90)
			(size 0.519938 1.4986)
			(layers "F.Cu" "F.Mask" "F.Paste")
			(net "GND")
		)
		(pad "9" smd rect
			(at -2.050034 -56.524906 90)
			(size 0.519938 1.4986)
			(layers "F.Cu" "F.Mask" "F.Paste")
			(net "M_G_CPU1_SA_DQ<1>")
		)
		(pad "10" smd rect
			(at -2.050034 -55.675022 90)
			(size 0.519938 1.4986)
			(layers "F.Cu" "F.Mask" "F.Paste")
			(net "GND")
		)
		(pad "11" smd rect
			(at -2.050034 -54.824884 90)
			(size 0.519938 1.4986)
			(layers "F.Cu" "F.Mask" "F.Paste")
			(net "M_G_CPU1_SA_DQS_DP<0>")
		)
		(pad "12" smd rect
			(at -2.050034 -53.975 90)
			(size 0.519938 1.4986)
			(layers "F.Cu" "F.Mask" "F.Paste")
			(net "M_G_CPU1_SA_DQS_DN<0>")
		)
		(pad "13" smd rect
			(at -2.050034 -53.125116 90)
			(size 0.519938 1.4986)
			(layers "F.Cu" "F.Mask" "F.Paste")
			(net "GND")
		)
		(pad "14" smd rect
			(at -2.050034 -52.274978 90)
			(size 0.519938 1.4986)
			(layers "F.Cu" "F.Mask" "F.Paste")
			(net "M_G_CPU1_SA_DQ<4>")
		)
		(pad "15" smd rect
			(at -2.050034 -51.425094 90)
			(size 0.519938 1.4986)
			(layers "F.Cu" "F.Mask" "F.Paste")
			(net "GND")
		)
		(pad "16" smd rect
			(at -2.050034 -50.574956 90)
			(size 0.519938 1.4986)
			(layers "F.Cu" "F.Mask" "F.Paste")
			(net "M_G_CPU1_SA_DQ<5>")
		)
		(pad "17" smd rect
			(at -2.050034 -49.725072 90)
			(size 0.519938 1.4986)
			(layers "F.Cu" "F.Mask" "F.Paste")
			(net "GND")
		)
		(pad "18" smd rect
			(at -2.050034 -48.874934 90)
			(size 0.519938 1.4986)
			(layers "F.Cu" "F.Mask" "F.Paste")
			(net "M_G_CPU1_SA_DQ<8>")
		)
		(pad "19" smd rect
			(at -2.050034 -48.02505 90)
			(size 0.519938 1.4986)
			(layers "F.Cu" "F.Mask" "F.Paste")
			(net "GND")
		)
		(pad "20" smd rect
			(at -2.050034 -47.174912 90)
			(size 0.519938 1.4986)
			(layers "F.Cu" "F.Mask" "F.Paste")
			(net "M_G_CPU1_SA_DQ<9>")
		)
		(pad "21" smd rect
			(at -2.050034 -46.325028 90)
			(size 0.519938 1.4986)
			(layers "F.Cu" "F.Mask" "F.Paste")
			(net "GND")
		)
		(pad "22" smd rect
			(at -2.050034 -45.47489 90)
			(size 0.519938 1.4986)
			(layers "F.Cu" "F.Mask" "F.Paste")
			(net "M_G_CPU1_SA_DQS_DP<1>")
		)
		(pad "23" smd rect
			(at -2.050034 -44.625006 90)
			(size 0.519938 1.4986)
			(layers "F.Cu" "F.Mask" "F.Paste")
			(net "M_G_CPU1_SA_DQS_DN<1>")
		)
		(pad "24" smd rect
			(at -2.050034 -43.775122 90)
			(size 0.519938 1.4986)
			(layers "F.Cu" "F.Mask" "F.Paste")
			(net "GND")
		)
		(pad "25" smd rect
			(at -2.050034 -42.924984 90)
			(size 0.519938 1.4986)
			(layers "F.Cu" "F.Mask" "F.Paste")
			(net "M_G_CPU1_SA_DQ<12>")
		)
		(pad "26" smd rect
			(at -2.050034 -42.0751 90)
			(size 0.519938 1.4986)
			(layers "F.Cu" "F.Mask" "F.Paste")
			(net "GND")
		)
		(pad "27" smd rect
			(at -2.050034 -41.224962 90)
			(size 0.519938 1.4986)
			(layers "F.Cu" "F.Mask" "F.Paste")
			(net "M_G_CPU1_SA_DQ<13>")
		)
		(pad "28" smd rect
			(at -2.050034 -40.375078 90)
			(size 0.519938 1.4986)
			(layers "F.Cu" "F.Mask" "F.Paste")
			(net "GND")
		)
		(pad "29" smd rect
			(at -2.050034 -39.52494 90)
			(size 0.519938 1.4986)
			(layers "F.Cu" "F.Mask" "F.Paste")
			(net "M_G_CPU1_SA_DQ<16>")
		)
		(pad "30" smd rect
			(at -2.050034 -38.675056 90)
			(size 0.519938 1.4986)
			(layers "F.Cu" "F.Mask" "F.Paste")
			(net "GND")
		)
		(pad "31" smd rect
			(at -2.050034 -37.824918 90)
			(size 0.519938 1.4986)
			(layers "F.Cu" "F.Mask" "F.Paste")
			(net "M_G_CPU1_SA_DQ<17>")
		)
		(pad "32" smd rect
			(at -2.050034 -36.975034 90)
			(size 0.519938 1.4986)
			(layers "F.Cu" "F.Mask" "F.Paste")
			(net "GND")
		)
		(pad "33" smd rect
			(at -2.050034 -36.124896 90)
			(size 0.519938 1.4986)
			(layers "F.Cu" "F.Mask" "F.Paste")
			(net "M_G_CPU1_SA_DQS_DP<2>")
		)
		(pad "34" smd rect
			(at -2.050034 -35.275012 90)
			(size 0.519938 1.4986)
			(layers "F.Cu" "F.Mask" "F.Paste")
			(net "M_G_CPU1_SA_DQS_DN<2>")
		)
		(pad "35" smd rect
			(at -2.050034 -34.425128 90)
			(size 0.519938 1.4986)
			(layers "F.Cu" "F.Mask" "F.Paste")
			(net "GND")
		)
		(pad "36" smd rect
			(at -2.050034 -33.57499 90)
			(size 0.519938 1.4986)
			(layers "F.Cu" "F.Mask" "F.Paste")
			(net "M_G_CPU1_SA_DQ<20>")
		)
		(pad "37" smd rect
			(at -2.050034 -32.725106 90)
			(size 0.519938 1.4986)
			(layers "F.Cu" "F.Mask" "F.Paste")
			(net "GND")
		)
		(pad "38" smd rect
			(at -2.050034 -31.874968 90)
			(size 0.519938 1.4986)
			(layers "F.Cu" "F.Mask" "F.Paste")
			(net "M_G_CPU1_SA_DQ<21>")
		)
		(pad "39" smd rect
			(at -2.050034 -31.025084 90)
			(size 0.519938 1.4986)
			(layers "F.Cu" "F.Mask" "F.Paste")
			(net "GND")
		)
		(pad "40" smd rect
			(at -2.050034 -30.174946 90)
			(size 0.519938 1.4986)
			(layers "F.Cu" "F.Mask" "F.Paste")
			(net "M_G_CPU1_SA_DQ<24>")
		)
		(pad "41" smd rect
			(at -2.050034 -29.325062 90)
			(size 0.519938 1.4986)
			(layers "F.Cu" "F.Mask" "F.Paste")
			(net "GND")
		)
		(pad "42" smd rect
			(at -2.050034 -28.474924 90)
			(size 0.519938 1.4986)
			(layers "F.Cu" "F.Mask" "F.Paste")
			(net "M_G_CPU1_SA_DQ<25>")
		)
		(pad "43" smd rect
			(at -2.050034 -27.62504 90)
			(size 0.519938 1.4986)
			(layers "F.Cu" "F.Mask" "F.Paste")
			(net "GND")
		)
		(pad "44" smd rect
			(at -2.050034 -26.774902 90)
			(size 0.519938 1.4986)
			(layers "F.Cu" "F.Mask" "F.Paste")
			(net "M_G_CPU1_SA_DQS_DP<3>")
		)
		(pad "45" smd rect
			(at -2.050034 -25.925018 90)
			(size 0.519938 1.4986)
			(layers "F.Cu" "F.Mask" "F.Paste")
			(net "M_G_CPU1_SA_DQS_DN<3>")
		)
		(pad "46" smd rect
			(at -2.050034 -25.07488 90)
			(size 0.519938 1.4986)
			(layers "F.Cu" "F.Mask" "F.Paste")
			(net "GND")
		)
		(pad "47" smd rect
			(at -2.050034 -24.224996 90)
			(size 0.519938 1.4986)
			(layers "F.Cu" "F.Mask" "F.Paste")
			(net "M_G_CPU1_SA_DQ<28>")
		)
		(pad "48" smd rect
			(at -2.050034 -23.375112 90)
			(size 0.519938 1.4986)
			(layers "F.Cu" "F.Mask" "F.Paste")
			(net "GND")
		)
		(pad "49" smd rect
			(at -2.050034 -22.524974 90)
			(size 0.519938 1.4986)
			(layers "F.Cu" "F.Mask" "F.Paste")
			(net "M_G_CPU1_SA_DQ<29>")
		)
		(pad "50" smd rect
			(at -2.050034 -21.67509 90)
			(size 0.519938 1.4986)
			(layers "F.Cu" "F.Mask" "F.Paste")
			(net "GND")
		)
		(pad "51" smd rect
			(at -2.050034 -20.824952 90)
			(size 0.519938 1.4986)
			(layers "F.Cu" "F.Mask" "F.Paste")
			(net "M_G_CPU1_SA_CB<0>")
		)
		(pad "52" smd rect
			(at -2.050034 -19.975068 90)
			(size 0.519938 1.4986)
			(layers "F.Cu" "F.Mask" "F.Paste")
			(net "GND")
		)
		(pad "53" smd rect
			(at -2.050034 -19.12493 90)
			(size 0.519938 1.4986)
			(layers "F.Cu" "F.Mask" "F.Paste")
			(net "M_G_CPU1_SA_CB<1>")
		)
		(pad "54" smd rect
			(at -2.050034 -18.275046 90)
			(size 0.519938 1.4986)
			(layers "F.Cu" "F.Mask" "F.Paste")
			(net "GND")
		)
		(pad "55" smd rect
			(at -2.050034 -17.424908 90)
			(size 0.519938 1.4986)
			(layers "F.Cu" "F.Mask" "F.Paste")
			(net "M_G_CPU1_SA_DQS_DP<4>")
		)
		(pad "56" smd rect
			(at -2.050034 -16.575024 90)
			(size 0.519938 1.4986)
			(layers "F.Cu" "F.Mask" "F.Paste")
			(net "M_G_CPU1_SA_DQS_DN<4>")
		)
		(pad "57" smd rect
			(at -2.050034 -15.724886 90)
			(size 0.519938 1.4986)
			(layers "F.Cu" "F.Mask" "F.Paste")
			(net "GND")
		)
		(pad "58" smd rect
			(at -2.050034 -14.875002 90)
			(size 0.519938 1.4986)
			(layers "F.Cu" "F.Mask" "F.Paste")
			(net "M_G_CPU1_SA_CB<4>")
		)
		(pad "59" smd rect
			(at -2.050034 -14.025118 90)
			(size 0.519938 1.4986)
			(layers "F.Cu" "F.Mask" "F.Paste")
			(net "GND")
		)
		(pad "60" smd rect
			(at -2.050034 -13.17498 90)
			(size 0.519938 1.4986)
			(layers "F.Cu" "F.Mask" "F.Paste")
			(net "M_G_CPU1_SA_CB<5>")
		)
		(pad "61" smd rect
			(at -2.050034 -12.325096 90)
			(size 0.519938 1.4986)
			(layers "F.Cu" "F.Mask" "F.Paste")
			(net "GND")
		)
		(pad "62" smd rect
			(at -2.050034 -11.474958 90)
			(size 0.519938 1.4986)
			(layers "F.Cu" "F.Mask" "F.Paste")
			(net "M_G_CPU1_ALERT_N")
		)
		(pad "63" smd rect
			(at -2.050034 -10.625074 90)
			(size 0.519938 1.4986)
			(layers "F.Cu" "F.Mask" "F.Paste")
			(net "GND")
		)
		(pad "64" smd rect
			(at -2.050034 -9.774936 90)
			(size 0.519938 1.4986)
			(layers "F.Cu" "F.Mask" "F.Paste")
			(net "M_G_CPU1_SA_CS_N<0>")
		)
		(pad "65" smd rect
			(at -2.050034 -8.925052 90)
			(size 0.519938 1.4986)
			(layers "F.Cu" "F.Mask" "F.Paste")
			(net "GND")
		)
		(pad "66" smd rect
			(at -2.050034 -8.074914 90)
			(size 0.519938 1.4986)
			(layers "F.Cu" "F.Mask" "F.Paste")
			(net "M_G_CPU1_SA_CA<0>")
		)
		(pad "67" smd rect
			(at -2.050034 -7.22503 90)
			(size 0.519938 1.4986)
			(layers "F.Cu" "F.Mask" "F.Paste")
			(net "GND")
		)
		(pad "68" smd rect
			(at -2.050034 -6.374892 90)
			(size 0.519938 1.4986)
			(layers "F.Cu" "F.Mask" "F.Paste")
			(net "M_G_CPU1_SA_CA<2>")
		)
		(pad "69" smd rect
			(at -2.050034 -5.525008 90)
			(size 0.519938 1.4986)
			(layers "F.Cu" "F.Mask" "F.Paste")
			(net "GND")
		)
		(pad "70" smd rect
			(at -2.050034 -4.675124 90)
			(size 0.519938 1.4986)
			(layers "F.Cu" "F.Mask" "F.Paste")
			(net "M_G_CPU1_SA_CA<4>")
		)
		(pad "71" smd rect
			(at -2.050034 -3.824986 90)
			(size 0.519938 1.4986)
			(layers "F.Cu" "F.Mask" "F.Paste")
			(net "GND")
		)
		(pad "72" smd rect
			(at -2.050034 -2.975102 90)
			(size 0.519938 1.4986)
			(layers "F.Cu" "F.Mask" "F.Paste")
			(net "M_G_CPU1_SA_CA<6>")
		)
		(pad "73" smd rect
			(at -2.050034 -2.124964 90)
			(size 0.519938 1.4986)
			(layers "F.Cu" "F.Mask" "F.Paste")
			(net "GND")
		)
		(pad "74" smd rect
			(at -2.050034 -1.27508 90)
			(size 0.519938 1.4986)
			(layers "F.Cu" "F.Mask" "F.Paste")
			(net "M_G_CPU1_SA_PAR")
		)
		(pad "75" smd rect
			(at -2.050034 -0.424942 90)
			(size 0.519938 1.4986)
			(layers "F.Cu" "F.Mask" "F.Paste")
			(net "GND")
		)
		(pad "76" smd rect
			(at -2.050034 5.525008 90)
			(size 0.519938 1.4986)
			(layers "F.Cu" "F.Mask" "F.Paste")
			(net "M_G_CPU1_SB_CA<0>")
		)
		(pad "77" smd rect
			(at -2.050034 6.374892 90)
			(size 0.519938 1.4986)
			(layers "F.Cu" "F.Mask" "F.Paste")
			(net "GND")
		)
		(pad "78" smd rect
			(at -2.050034 7.22503 90)
			(size 0.519938 1.4986)
			(layers "F.Cu" "F.Mask" "F.Paste")
			(net "M_G_CPU1_SB_CA<2>")
		)
		(pad "79" smd rect
			(at -2.050034 8.074914 90)
			(size 0.519938 1.4986)
			(layers "F.Cu" "F.Mask" "F.Paste")
			(net "GND")
		)
		(pad "80" smd rect
			(at -2.050034 8.925052 90)
			(size 0.519938 1.4986)
			(layers "F.Cu" "F.Mask" "F.Paste")
			(net "M_G_CPU1_SB_CA<4>")
		)
		(pad "81" smd rect
			(at -2.050034 9.774936 90)
			(size 0.519938 1.4986)
			(layers "F.Cu" "F.Mask" "F.Paste")
			(net "GND")
		)
		(pad "82" smd rect
			(at -2.050034 10.625074 90)
			(size 0.519938 1.4986)
			(layers "F.Cu" "F.Mask" "F.Paste")
			(net "M_G_CPU1_SB_CA<6>")
		)
		(pad "83" smd rect
			(at -2.050034 11.474958 90)
			(size 0.519938 1.4986)
			(layers "F.Cu" "F.Mask" "F.Paste")
			(net "GND")
		)
		(pad "84" smd rect
			(at -2.050034 12.325096 90)
			(size 0.519938 1.4986)
			(layers "F.Cu" "F.Mask" "F.Paste")
			(net "M_G_CPU1_SB_CS_N<0>")
		)
		(pad "85" smd rect
			(at -2.050034 13.17498 90)
			(size 0.519938 1.4986)
			(layers "F.Cu" "F.Mask" "F.Paste")
			(net "GND")
		)
		(pad "86" smd rect
			(at -2.050034 14.025118 90)
			(size 0.519938 1.4986)
			(layers "F.Cu" "F.Mask" "F.Paste")
			(net "M_G_CPU1_SA_RSP<0>")
		)
		(pad "87" smd rect
			(at -2.050034 14.875002 90)
			(size 0.519938 1.4986)
			(layers "F.Cu" "F.Mask" "F.Paste")
			(net "M_G_CPU1_SB_RSP<0>")
		)
		(pad "88" smd rect
			(at -2.050034 15.724886 90)
			(size 0.519938 1.4986)
			(layers "F.Cu" "F.Mask" "F.Paste")
			(net "GND")
		)
		(pad "89" smd rect
			(at -2.050034 16.575024 90)
			(size 0.519938 1.4986)
			(layers "F.Cu" "F.Mask" "F.Paste")
			(net "M_G_CPU1_SB_CB<4>")
		)
		(pad "90" smd rect
			(at -2.050034 17.424908 90)
			(size 0.519938 1.4986)
			(layers "F.Cu" "F.Mask" "F.Paste")
			(net "GND")
		)
		(pad "91" smd rect
			(at -2.050034 18.275046 90)
			(size 0.519938 1.4986)
			(layers "F.Cu" "F.Mask" "F.Paste")
			(net "M_G_CPU1_SB_CB<5>")
		)
		(pad "92" smd rect
			(at -2.050034 19.12493 90)
			(size 0.519938 1.4986)
			(layers "F.Cu" "F.Mask" "F.Paste")
			(net "GND")
		)
		(pad "93" smd rect
			(at -2.050034 19.975068 90)
			(size 0.519938 1.4986)
			(layers "F.Cu" "F.Mask" "F.Paste")
			(net "M_G_CPU1_SB_DQS_DP<9>")
		)
		(pad "94" smd rect
			(at -2.050034 20.824952 90)
			(size 0.519938 1.4986)
			(layers "F.Cu" "F.Mask" "F.Paste")
			(net "M_G_CPU1_SB_DQS_DN<9>")
		)
		(pad "95" smd rect
			(at -2.050034 21.67509 90)
			(size 0.519938 1.4986)
			(layers "F.Cu" "F.Mask" "F.Paste")
			(net "GND")
		)
		(pad "96" smd rect
			(at -2.050034 22.524974 90)
			(size 0.519938 1.4986)
			(layers "F.Cu" "F.Mask" "F.Paste")
			(net "M_G_CPU1_SB_CB<0>")
		)
		(pad "97" smd rect
			(at -2.050034 23.375112 90)
			(size 0.519938 1.4986)
			(layers "F.Cu" "F.Mask" "F.Paste")
			(net "GND")
		)
		(pad "98" smd rect
			(at -2.050034 24.224996 90)
			(size 0.519938 1.4986)
			(layers "F.Cu" "F.Mask" "F.Paste")
			(net "M_G_CPU1_SB_CB<1>")
		)
		(pad "99" smd rect
			(at -2.050034 25.07488 90)
			(size 0.519938 1.4986)
			(layers "F.Cu" "F.Mask" "F.Paste")
			(net "GND")
		)
		(pad "100" smd rect
			(at -2.050034 25.925018 90)
			(size 0.519938 1.4986)
			(layers "F.Cu" "F.Mask" "F.Paste")
			(net "M_G_CPU1_SB_DQ<0>")
		)
		(pad "101" smd rect
			(at -2.050034 26.774902 90)
			(size 0.519938 1.4986)
			(layers "F.Cu" "F.Mask" "F.Paste")
			(net "GND")
		)
		(pad "102" smd rect
			(at -2.050034 27.62504 90)
			(size 0.519938 1.4986)
			(layers "F.Cu" "F.Mask" "F.Paste")
			(net "M_G_CPU1_SB_DQ<1>")
		)
		(pad "103" smd rect
			(at -2.050034 28.474924 90)
			(size 0.519938 1.4986)
			(layers "F.Cu" "F.Mask" "F.Paste")
			(net "GND")
		)
		(pad "104" smd rect
			(at -2.050034 29.325062 90)
			(size 0.519938 1.4986)
			(layers "F.Cu" "F.Mask" "F.Paste")
			(net "M_G_CPU1_SB_DQS_DP<0>")
		)
		(pad "105" smd rect
			(at -2.050034 30.174946 90)
			(size 0.519938 1.4986)
			(layers "F.Cu" "F.Mask" "F.Paste")
			(net "M_G_CPU1_SB_DQS_DN<0>")
		)
		(pad "106" smd rect
			(at -2.050034 31.025084 90)
			(size 0.519938 1.4986)
			(layers "F.Cu" "F.Mask" "F.Paste")
			(net "GND")
		)
		(pad "107" smd rect
			(at -2.050034 31.874968 90)
			(size 0.519938 1.4986)
			(layers "F.Cu" "F.Mask" "F.Paste")
			(net "M_G_CPU1_SB_DQ<4>")
		)
		(pad "108" smd rect
			(at -2.050034 32.725106 90)
			(size 0.519938 1.4986)
			(layers "F.Cu" "F.Mask" "F.Paste")
			(net "GND")
		)
		(pad "109" smd rect
			(at -2.050034 33.57499 90)
			(size 0.519938 1.4986)
			(layers "F.Cu" "F.Mask" "F.Paste")
			(net "M_G_CPU1_SB_DQ<5>")
		)
		(pad "110" smd rect
			(at -2.050034 34.425128 90)
			(size 0.519938 1.4986)
			(layers "F.Cu" "F.Mask" "F.Paste")
			(net "GND")
		)
		(pad "111" smd rect
			(at -2.050034 35.275012 90)
			(size 0.519938 1.4986)
			(layers "F.Cu" "F.Mask" "F.Paste")
			(net "M_G_CPU1_SB_DQ<8>")
		)
		(pad "112" smd rect
			(at -2.050034 36.124896 90)
			(size 0.519938 1.4986)
			(layers "F.Cu" "F.Mask" "F.Paste")
			(net "GND")
		)
		(pad "113" smd rect
			(at -2.050034 36.975034 90)
			(size 0.519938 1.4986)
			(layers "F.Cu" "F.Mask" "F.Paste")
			(net "M_G_CPU1_SB_DQ<9>")
		)
		(pad "114" smd rect
			(at -2.050034 37.824918 90)
			(size 0.519938 1.4986)
			(layers "F.Cu" "F.Mask" "F.Paste")
			(net "GND")
		)
		(pad "115" smd rect
			(at -2.050034 38.675056 90)
			(size 0.519938 1.4986)
			(layers "F.Cu" "F.Mask" "F.Paste")
			(net "M_G_CPU1_SB_DQS_DP<1>")
		)
		(pad "116" smd rect
			(at -2.050034 39.52494 90)
			(size 0.519938 1.4986)
			(layers "F.Cu" "F.Mask" "F.Paste")
			(net "M_G_CPU1_SB_DQS_DN<1>")
		)
		(pad "117" smd rect
			(at -2.050034 40.375078 90)
			(size 0.519938 1.4986)
			(layers "F.Cu" "F.Mask" "F.Paste")
			(net "GND")
		)
		(pad "118" smd rect
			(at -2.050034 41.224962 90)
			(size 0.519938 1.4986)
			(layers "F.Cu" "F.Mask" "F.Paste")
			(net "M_G_CPU1_SB_DQ<12>")
		)
		(pad "119" smd rect
			(at -2.050034 42.0751 90)
			(size 0.519938 1.4986)
			(layers "F.Cu" "F.Mask" "F.Paste")
			(net "GND")
		)
		(pad "120" smd rect
			(at -2.050034 42.924984 90)
			(size 0.519938 1.4986)
			(layers "F.Cu" "F.Mask" "F.Paste")
			(net "M_G_CPU1_SB_DQ<13>")
		)
		(pad "121" smd rect
			(at -2.050034 43.775122 90)
			(size 0.519938 1.4986)
			(layers "F.Cu" "F.Mask" "F.Paste")
			(net "GND")
		)
		(pad "122" smd rect
			(at -2.050034 44.625006 90)
			(size 0.519938 1.4986)
			(layers "F.Cu" "F.Mask" "F.Paste")
			(net "M_G_CPU1_SB_DQ<16>")
		)
		(pad "123" smd rect
			(at -2.050034 45.47489 90)
			(size 0.519938 1.4986)
			(layers "F.Cu" "F.Mask" "F.Paste")
			(net "GND")
		)
		(pad "124" smd rect
			(at -2.050034 46.325028 90)
			(size 0.519938 1.4986)
			(layers "F.Cu" "F.Mask" "F.Paste")
			(net "M_G_CPU1_SB_DQ<17>")
		)
		(pad "125" smd rect
			(at -2.050034 47.174912 90)
			(size 0.519938 1.4986)
			(layers "F.Cu" "F.Mask" "F.Paste")
			(net "GND")
		)
		(pad "126" smd rect
			(at -2.050034 48.02505 90)
			(size 0.519938 1.4986)
			(layers "F.Cu" "F.Mask" "F.Paste")
			(net "M_G_CPU1_SB_DQS_DP<2>")
		)
		(pad "127" smd rect
			(at -2.050034 48.874934 90)
			(size 0.519938 1.4986)
			(layers "F.Cu" "F.Mask" "F.Paste")
			(net "M_G_CPU1_SB_DQS_DN<2>")
		)
		(pad "128" smd rect
			(at -2.050034 49.725072 90)
			(size 0.519938 1.4986)
			(layers "F.Cu" "F.Mask" "F.Paste")
			(net "GND")
		)
		(pad "129" smd rect
			(at -2.050034 50.574956 90)
			(size 0.519938 1.4986)
			(layers "F.Cu" "F.Mask" "F.Paste")
			(net "M_G_CPU1_SB_DQ<20>")
		)
		(pad "130" smd rect
			(at -2.050034 51.425094 90)
			(size 0.519938 1.4986)
			(layers "F.Cu" "F.Mask" "F.Paste")
			(net "GND")
		)
		(pad "131" smd rect
			(at -2.050034 52.274978 90)
			(size 0.519938 1.4986)
			(layers "F.Cu" "F.Mask" "F.Paste")
			(net "M_G_CPU1_SB_DQ<21>")
		)
		(pad "132" smd rect
			(at -2.050034 53.125116 90)
			(size 0.519938 1.4986)
			(layers "F.Cu" "F.Mask" "F.Paste")
			(net "GND")
		)
		(pad "133" smd rect
			(at -2.050034 53.975 90)
			(size 0.519938 1.4986)
			(layers "F.Cu" "F.Mask" "F.Paste")
			(net "M_G_CPU1_SB_DQ<24>")
		)
		(pad "134" smd rect
			(at -2.050034 54.824884 90)
			(size 0.519938 1.4986)
			(layers "F.Cu" "F.Mask" "F.Paste")
			(net "GND")
		)
		(pad "135" smd rect
			(at -2.050034 55.675022 90)
			(size 0.519938 1.4986)
			(layers "F.Cu" "F.Mask" "F.Paste")
			(net "M_G_CPU1_SB_DQ<25>")
		)
		(pad "136" smd rect
			(at -2.050034 56.524906 90)
			(size 0.519938 1.4986)
			(layers "F.Cu" "F.Mask" "F.Paste")
			(net "GND")
		)
		(pad "137" smd rect
			(at -2.050034 57.375044 90)
			(size 0.519938 1.4986)
			(layers "F.Cu" "F.Mask" "F.Paste")
			(net "M_G_CPU1_SB_DQS_DP<3>")
		)
		(pad "138" smd rect
			(at -2.050034 58.224928 90)
			(size 0.519938 1.4986)
			(layers "F.Cu" "F.Mask" "F.Paste")
			(net "M_G_CPU1_SB_DQS_DN<3>")
		)
		(pad "139" smd rect
			(at -2.050034 59.075066 90)
			(size 0.519938 1.4986)
			(layers "F.Cu" "F.Mask" "F.Paste")
			(net "GND")
		)
		(pad "140" smd rect
			(at -2.050034 59.92495 90)
			(size 0.519938 1.4986)
			(layers "F.Cu" "F.Mask" "F.Paste")
			(net "M_G_CPU1_SB_DQ<28>")
		)
		(pad "141" smd rect
			(at -2.050034 60.775088 90)
			(size 0.519938 1.4986)
			(layers "F.Cu" "F.Mask" "F.Paste")
			(net "GND")
		)
		(pad "142" smd rect
			(at -2.050034 61.624972 90)
			(size 0.519938 1.4986)
			(layers "F.Cu" "F.Mask" "F.Paste")
			(net "M_G_CPU1_SB_DQ<29>")
		)
		(pad "143" smd rect
			(at -2.050034 62.47511 90)
			(size 0.519938 1.4986)
			(layers "F.Cu" "F.Mask" "F.Paste")
			(net "GND")
		)
		(pad "144" smd rect
			(at -2.050034 63.324994 90)
			(size 0.519938 1.4986)
			(layers "F.Cu" "F.Mask" "F.Paste")
			(net "Net_2341")
		)
		(pad "145" smd rect
			(at 2.050034 -63.324994 90)
			(size 0.519938 1.4986)
			(layers "F.Cu" "F.Mask" "F.Paste")
			(net "P12V_MEM_CPU1")
		)
		(pad "146" smd rect
			(at 2.050034 -62.47511 90)
			(size 0.519938 1.4986)
			(layers "F.Cu" "F.Mask" "F.Paste")
			(net "P12V_MEM_CPU1")
		)
		(pad "147" smd rect
			(at 2.050034 -61.624972 90)
			(size 0.519938 1.4986)
			(layers "F.Cu" "F.Mask" "F.Paste")
			(net "PWRGD_CHG_CPU1_DIMM0")
		)
		(pad "148" smd rect
			(at 2.050034 -60.775088 90)
			(size 0.519938 1.4986)
			(layers "F.Cu" "F.Mask" "F.Paste")
			(net "PD_CHG_CPU1_DIMM0_SAA")
		)
		(pad "149" smd rect
			(at 2.050034 -59.92495 90)
			(size 0.519938 1.4986)
			(layers "F.Cu" "F.Mask" "F.Paste")
			(net "Net_2342")
		)
		(pad "150" smd rect
			(at 2.050034 -59.075066 90)
			(size 0.519938 1.4986)
			(layers "F.Cu" "F.Mask" "F.Paste")
			(net "Net_2343")
		)
		(pad "151" smd rect
			(at 2.050034 -58.224928 90)
			(size 0.519938 1.4986)
			(layers "F.Cu" "F.Mask" "F.Paste")
			(net "GND")
		)
		(pad "152" smd rect
			(at 2.050034 -57.375044 90)
			(size 0.519938 1.4986)
			(layers "F.Cu" "F.Mask" "F.Paste")
			(net "M_G_CPU1_SA_DQ<2>")
		)
		(pad "153" smd rect
			(at 2.050034 -56.524906 90)
			(size 0.519938 1.4986)
			(layers "F.Cu" "F.Mask" "F.Paste")
			(net "GND")
		)
		(pad "154" smd rect
			(at 2.050034 -55.675022 90)
			(size 0.519938 1.4986)
			(layers "F.Cu" "F.Mask" "F.Paste")
			(net "M_G_CPU1_SA_DQ<3>")
		)
		(pad "155" smd rect
			(at 2.050034 -54.824884 90)
			(size 0.519938 1.4986)
			(layers "F.Cu" "F.Mask" "F.Paste")
			(net "GND")
		)
		(pad "156" smd rect
			(at 2.050034 -53.975 90)
			(size 0.519938 1.4986)
			(layers "F.Cu" "F.Mask" "F.Paste")
			(net "M_G_CPU1_SA_DQS_DN<5>")
		)
		(pad "157" smd rect
			(at 2.050034 -53.125116 90)
			(size 0.519938 1.4986)
			(layers "F.Cu" "F.Mask" "F.Paste")
			(net "M_G_CPU1_SA_DQS_DP<5>")
		)
		(pad "158" smd rect
			(at 2.050034 -52.274978 90)
			(size 0.519938 1.4986)
			(layers "F.Cu" "F.Mask" "F.Paste")
			(net "GND")
		)
		(pad "159" smd rect
			(at 2.050034 -51.425094 90)
			(size 0.519938 1.4986)
			(layers "F.Cu" "F.Mask" "F.Paste")
			(net "M_G_CPU1_SA_DQ<6>")
		)
		(pad "160" smd rect
			(at 2.050034 -50.574956 90)
			(size 0.519938 1.4986)
			(layers "F.Cu" "F.Mask" "F.Paste")
			(net "GND")
		)
		(pad "161" smd rect
			(at 2.050034 -49.725072 90)
			(size 0.519938 1.4986)
			(layers "F.Cu" "F.Mask" "F.Paste")
			(net "M_G_CPU1_SA_DQ<7>")
		)
		(pad "162" smd rect
			(at 2.050034 -48.874934 90)
			(size 0.519938 1.4986)
			(layers "F.Cu" "F.Mask" "F.Paste")
			(net "GND")
		)
		(pad "163" smd rect
			(at 2.050034 -48.02505 90)
			(size 0.519938 1.4986)
			(layers "F.Cu" "F.Mask" "F.Paste")
			(net "M_G_CPU1_SA_DQ<10>")
		)
		(pad "164" smd rect
			(at 2.050034 -47.174912 90)
			(size 0.519938 1.4986)
			(layers "F.Cu" "F.Mask" "F.Paste")
			(net "GND")
		)
		(pad "165" smd rect
			(at 2.050034 -46.325028 90)
			(size 0.519938 1.4986)
			(layers "F.Cu" "F.Mask" "F.Paste")
			(net "M_G_CPU1_SA_DQ<11>")
		)
		(pad "166" smd rect
			(at 2.050034 -45.47489 90)
			(size 0.519938 1.4986)
			(layers "F.Cu" "F.Mask" "F.Paste")
			(net "GND")
		)
		(pad "167" smd rect
			(at 2.050034 -44.625006 90)
			(size 0.519938 1.4986)
			(layers "F.Cu" "F.Mask" "F.Paste")
			(net "M_G_CPU1_SA_DQS_DN<6>")
		)
		(pad "168" smd rect
			(at 2.050034 -43.775122 90)
			(size 0.519938 1.4986)
			(layers "F.Cu" "F.Mask" "F.Paste")
			(net "M_G_CPU1_SA_DQS_DP<6>")
		)
		(pad "169" smd rect
			(at 2.050034 -42.924984 90)
			(size 0.519938 1.4986)
			(layers "F.Cu" "F.Mask" "F.Paste")
			(net "GND")
		)
		(pad "170" smd rect
			(at 2.050034 -42.0751 90)
			(size 0.519938 1.4986)
			(layers "F.Cu" "F.Mask" "F.Paste")
			(net "M_G_CPU1_SA_DQ<14>")
		)
		(pad "171" smd rect
			(at 2.050034 -41.224962 90)
			(size 0.519938 1.4986)
			(layers "F.Cu" "F.Mask" "F.Paste")
			(net "GND")
		)
		(pad "172" smd rect
			(at 2.050034 -40.375078 90)
			(size 0.519938 1.4986)
			(layers "F.Cu" "F.Mask" "F.Paste")
			(net "M_G_CPU1_SA_DQ<15>")
		)
		(pad "173" smd rect
			(at 2.050034 -39.52494 90)
			(size 0.519938 1.4986)
			(layers "F.Cu" "F.Mask" "F.Paste")
			(net "GND")
		)
		(pad "174" smd rect
			(at 2.050034 -38.675056 90)
			(size 0.519938 1.4986)
			(layers "F.Cu" "F.Mask" "F.Paste")
			(net "M_G_CPU1_SA_DQ<18>")
		)
		(pad "175" smd rect
			(at 2.050034 -37.824918 90)
			(size 0.519938 1.4986)
			(layers "F.Cu" "F.Mask" "F.Paste")
			(net "GND")
		)
		(pad "176" smd rect
			(at 2.050034 -36.975034 90)
			(size 0.519938 1.4986)
			(layers "F.Cu" "F.Mask" "F.Paste")
			(net "M_G_CPU1_SA_DQ<19>")
		)
		(pad "177" smd rect
			(at 2.050034 -36.124896 90)
			(size 0.519938 1.4986)
			(layers "F.Cu" "F.Mask" "F.Paste")
			(net "GND")
		)
		(pad "178" smd rect
			(at 2.050034 -35.275012 90)
			(size 0.519938 1.4986)
			(layers "F.Cu" "F.Mask" "F.Paste")
			(net "M_G_CPU1_SA_DQS_DN<7>")
		)
		(pad "179" smd rect
			(at 2.050034 -34.425128 90)
			(size 0.519938 1.4986)
			(layers "F.Cu" "F.Mask" "F.Paste")
			(net "M_G_CPU1_SA_DQS_DP<7>")
		)
		(pad "180" smd rect
			(at 2.050034 -33.57499 90)
			(size 0.519938 1.4986)
			(layers "F.Cu" "F.Mask" "F.Paste")
			(net "GND")
		)
		(pad "181" smd rect
			(at 2.050034 -32.725106 90)
			(size 0.519938 1.4986)
			(layers "F.Cu" "F.Mask" "F.Paste")
			(net "M_G_CPU1_SA_DQ<22>")
		)
		(pad "182" smd rect
			(at 2.050034 -31.874968 90)
			(size 0.519938 1.4986)
			(layers "F.Cu" "F.Mask" "F.Paste")
			(net "GND")
		)
		(pad "183" smd rect
			(at 2.050034 -31.025084 90)
			(size 0.519938 1.4986)
			(layers "F.Cu" "F.Mask" "F.Paste")
			(net "M_G_CPU1_SA_DQ<23>")
		)
		(pad "184" smd rect
			(at 2.050034 -30.174946 90)
			(size 0.519938 1.4986)
			(layers "F.Cu" "F.Mask" "F.Paste")
			(net "GND")
		)
		(pad "185" smd rect
			(at 2.050034 -29.325062 90)
			(size 0.519938 1.4986)
			(layers "F.Cu" "F.Mask" "F.Paste")
			(net "M_G_CPU1_SA_DQ<26>")
		)
		(pad "186" smd rect
			(at 2.050034 -28.474924 90)
			(size 0.519938 1.4986)
			(layers "F.Cu" "F.Mask" "F.Paste")
			(net "GND")
		)
		(pad "187" smd rect
			(at 2.050034 -27.62504 90)
			(size 0.519938 1.4986)
			(layers "F.Cu" "F.Mask" "F.Paste")
			(net "M_G_CPU1_SA_DQ<27>")
		)
		(pad "188" smd rect
			(at 2.050034 -26.774902 90)
			(size 0.519938 1.4986)
			(layers "F.Cu" "F.Mask" "F.Paste")
			(net "GND")
		)
		(pad "189" smd rect
			(at 2.050034 -25.925018 90)
			(size 0.519938 1.4986)
			(layers "F.Cu" "F.Mask" "F.Paste")
			(net "M_G_CPU1_SA_DQS_DN<8>")
		)
		(pad "190" smd rect
			(at 2.050034 -25.07488 90)
			(size 0.519938 1.4986)
			(layers "F.Cu" "F.Mask" "F.Paste")
			(net "M_G_CPU1_SA_DQS_DP<8>")
		)
		(pad "191" smd rect
			(at 2.050034 -24.224996 90)
			(size 0.519938 1.4986)
			(layers "F.Cu" "F.Mask" "F.Paste")
			(net "GND")
		)
		(pad "192" smd rect
			(at 2.050034 -23.375112 90)
			(size 0.519938 1.4986)
			(layers "F.Cu" "F.Mask" "F.Paste")
			(net "M_G_CPU1_SA_DQ<30>")
		)
		(pad "193" smd rect
			(at 2.050034 -22.524974 90)
			(size 0.519938 1.4986)
			(layers "F.Cu" "F.Mask" "F.Paste")
			(net "GND")
		)
		(pad "194" smd rect
			(at 2.050034 -21.67509 90)
			(size 0.519938 1.4986)
			(layers "F.Cu" "F.Mask" "F.Paste")
			(net "M_G_CPU1_SA_DQ<31>")
		)
		(pad "195" smd rect
			(at 2.050034 -20.824952 90)
			(size 0.519938 1.4986)
			(layers "F.Cu" "F.Mask" "F.Paste")
			(net "GND")
		)
		(pad "196" smd rect
			(at 2.050034 -19.975068 90)
			(size 0.519938 1.4986)
			(layers "F.Cu" "F.Mask" "F.Paste")
			(net "M_G_CPU1_SA_CB<2>")
		)
		(pad "197" smd rect
			(at 2.050034 -19.12493 90)
			(size 0.519938 1.4986)
			(layers "F.Cu" "F.Mask" "F.Paste")
			(net "GND")
		)
		(pad "198" smd rect
			(at 2.050034 -18.275046 90)
			(size 0.519938 1.4986)
			(layers "F.Cu" "F.Mask" "F.Paste")
			(net "M_G_CPU1_SA_CB<3>")
		)
		(pad "199" smd rect
			(at 2.050034 -17.424908 90)
			(size 0.519938 1.4986)
			(layers "F.Cu" "F.Mask" "F.Paste")
			(net "GND")
		)
		(pad "200" smd rect
			(at 2.050034 -16.575024 90)
			(size 0.519938 1.4986)
			(layers "F.Cu" "F.Mask" "F.Paste")
			(net "M_G_CPU1_SA_DQS_DN<9>")
		)
		(pad "201" smd rect
			(at 2.050034 -15.724886 90)
			(size 0.519938 1.4986)
			(layers "F.Cu" "F.Mask" "F.Paste")
			(net "M_G_CPU1_SA_DQS_DP<9>")
		)
		(pad "202" smd rect
			(at 2.050034 -14.875002 90)
			(size 0.519938 1.4986)
			(layers "F.Cu" "F.Mask" "F.Paste")
			(net "GND")
		)
		(pad "203" smd rect
			(at 2.050034 -14.025118 90)
			(size 0.519938 1.4986)
			(layers "F.Cu" "F.Mask" "F.Paste")
			(net "M_G_CPU1_SA_CB<6>")
		)
		(pad "204" smd rect
			(at 2.050034 -13.17498 90)
			(size 0.519938 1.4986)
			(layers "F.Cu" "F.Mask" "F.Paste")
			(net "GND")
		)
		(pad "205" smd rect
			(at 2.050034 -12.325096 90)
			(size 0.519938 1.4986)
			(layers "F.Cu" "F.Mask" "F.Paste")
			(net "M_G_CPU1_SA_CB<7>")
		)
		(pad "206" smd rect
			(at 2.050034 -11.474958 90)
			(size 0.519938 1.4986)
			(layers "F.Cu" "F.Mask" "F.Paste")
			(net "GND")
		)
		(pad "207" smd rect
			(at 2.050034 -10.625074 90)
			(size 0.519938 1.4986)
			(layers "F.Cu" "F.Mask" "F.Paste")
			(net "M_G_CPU1_RESET_N")
		)
		(pad "208" smd rect
			(at 2.050034 -9.774936 90)
			(size 0.519938 1.4986)
			(layers "F.Cu" "F.Mask" "F.Paste")
			(net "GND")
		)
		(pad "209" smd rect
			(at 2.050034 -8.925052 90)
			(size 0.519938 1.4986)
			(layers "F.Cu" "F.Mask" "F.Paste")
			(net "M_G_CPU1_SA_CS_N<1>")
		)
		(pad "210" smd rect
			(at 2.050034 -8.074914 90)
			(size 0.519938 1.4986)
			(layers "F.Cu" "F.Mask" "F.Paste")
			(net "GND")
		)
		(pad "211" smd rect
			(at 2.050034 -7.22503 90)
			(size 0.519938 1.4986)
			(layers "F.Cu" "F.Mask" "F.Paste")
			(net "M_G_CPU1_SA_CA<1>")
		)
		(pad "212" smd rect
			(at 2.050034 -6.374892 90)
			(size 0.519938 1.4986)
			(layers "F.Cu" "F.Mask" "F.Paste")
			(net "GND")
		)
		(pad "213" smd rect
			(at 2.050034 -5.525008 90)
			(size 0.519938 1.4986)
			(layers "F.Cu" "F.Mask" "F.Paste")
			(net "M_G_CPU1_SA_CA<3>")
		)
		(pad "214" smd rect
			(at 2.050034 -4.675124 90)
			(size 0.519938 1.4986)
			(layers "F.Cu" "F.Mask" "F.Paste")
			(net "GND")
		)
		(pad "215" smd rect
			(at 2.050034 -3.824986 90)
			(size 0.519938 1.4986)
			(layers "F.Cu" "F.Mask" "F.Paste")
			(net "M_G_CPU1_SA_CA<5>")
		)
		(pad "216" smd rect
			(at 2.050034 -2.975102 90)
			(size 0.519938 1.4986)
			(layers "F.Cu" "F.Mask" "F.Paste")
			(net "GND")
		)
		(pad "217" smd rect
			(at 2.050034 -2.124964 90)
			(size 0.519938 1.4986)
			(layers "F.Cu" "F.Mask" "F.Paste")
			(net "M_G_CPU1_CLK_DP<0>")
		)
		(pad "218" smd rect
			(at 2.050034 -1.27508 90)
			(size 0.519938 1.4986)
			(layers "F.Cu" "F.Mask" "F.Paste")
			(net "M_G_CPU1_CLK_DN<0>")
		)
		(pad "219" smd rect
			(at 2.050034 -0.424942 90)
			(size 0.519938 1.4986)
			(layers "F.Cu" "F.Mask" "F.Paste")
			(net "GND")
		)
		(pad "220" smd rect
			(at 2.050034 5.525008 90)
			(size 0.519938 1.4986)
			(layers "F.Cu" "F.Mask" "F.Paste")
			(net "Net_2344")
		)
		(pad "221" smd rect
			(at 2.050034 6.374892 90)
			(size 0.519938 1.4986)
			(layers "F.Cu" "F.Mask" "F.Paste")
			(net "M_G_CPU1_SB_CA<1>")
		)
		(pad "222" smd rect
			(at 2.050034 7.22503 90)
			(size 0.519938 1.4986)
			(layers "F.Cu" "F.Mask" "F.Paste")
			(net "GND")
		)
		(pad "223" smd rect
			(at 2.050034 8.074914 90)
			(size 0.519938 1.4986)
			(layers "F.Cu" "F.Mask" "F.Paste")
			(net "M_G_CPU1_SB_CA<3>")
		)
		(pad "224" smd rect
			(at 2.050034 8.925052 90)
			(size 0.519938 1.4986)
			(layers "F.Cu" "F.Mask" "F.Paste")
			(net "GND")
		)
		(pad "225" smd rect
			(at 2.050034 9.774936 90)
			(size 0.519938 1.4986)
			(layers "F.Cu" "F.Mask" "F.Paste")
			(net "M_G_CPU1_SB_CA<5>")
		)
		(pad "226" smd rect
			(at 2.050034 10.625074 90)
			(size 0.519938 1.4986)
			(layers "F.Cu" "F.Mask" "F.Paste")
			(net "GND")
		)
		(pad "227" smd rect
			(at 2.050034 11.474958 90)
			(size 0.519938 1.4986)
			(layers "F.Cu" "F.Mask" "F.Paste")
			(net "M_G_CPU1_SB_PAR")
		)
		(pad "228" smd rect
			(at 2.050034 12.325096 90)
			(size 0.519938 1.4986)
			(layers "F.Cu" "F.Mask" "F.Paste")
			(net "GND")
		)
		(pad "229" smd rect
			(at 2.050034 13.17498 90)
			(size 0.519938 1.4986)
			(layers "F.Cu" "F.Mask" "F.Paste")
			(net "M_G_CPU1_SB_CS_N<1>")
		)
		(pad "230" smd rect
			(at 2.050034 14.025118 90)
			(size 0.519938 1.4986)
			(layers "F.Cu" "F.Mask" "F.Paste")
			(net "GND")
		)
		(pad "231" smd rect
			(at 2.050034 14.875002 90)
			(size 0.519938 1.4986)
			(layers "F.Cu" "F.Mask" "F.Paste")
			(net "Net_2345")
		)
		(pad "232" smd rect
			(at 2.050034 15.724886 90)
			(size 0.519938 1.4986)
			(layers "F.Cu" "F.Mask" "F.Paste")
			(net "Net_2346")
		)
		(pad "233" smd rect
			(at 2.050034 16.575024 90)
			(size 0.519938 1.4986)
			(layers "F.Cu" "F.Mask" "F.Paste")
			(net "GND")
		)
		(pad "234" smd rect
			(at 2.050034 17.424908 90)
			(size 0.519938 1.4986)
			(layers "F.Cu" "F.Mask" "F.Paste")
			(net "M_G_CPU1_SB_CB<6>")
		)
		(pad "235" smd rect
			(at 2.050034 18.275046 90)
			(size 0.519938 1.4986)
			(layers "F.Cu" "F.Mask" "F.Paste")
			(net "GND")
		)
		(pad "236" smd rect
			(at 2.050034 19.12493 90)
			(size 0.519938 1.4986)
			(layers "F.Cu" "F.Mask" "F.Paste")
			(net "M_G_CPU1_SB_CB<7>")
		)
		(pad "237" smd rect
			(at 2.050034 19.975068 90)
			(size 0.519938 1.4986)
			(layers "F.Cu" "F.Mask" "F.Paste")
			(net "GND")
		)
		(pad "238" smd rect
			(at 2.050034 20.824952 90)
			(size 0.519938 1.4986)
			(layers "F.Cu" "F.Mask" "F.Paste")
			(net "M_G_CPU1_SB_DQS_DN<4>")
		)
		(pad "239" smd rect
			(at 2.050034 21.67509 90)
			(size 0.519938 1.4986)
			(layers "F.Cu" "F.Mask" "F.Paste")
			(net "M_G_CPU1_SB_DQS_DP<4>")
		)
		(pad "240" smd rect
			(at 2.050034 22.524974 90)
			(size 0.519938 1.4986)
			(layers "F.Cu" "F.Mask" "F.Paste")
			(net "GND")
		)
		(pad "241" smd rect
			(at 2.050034 23.375112 90)
			(size 0.519938 1.4986)
			(layers "F.Cu" "F.Mask" "F.Paste")
			(net "M_G_CPU1_SB_CB<2>")
		)
		(pad "242" smd rect
			(at 2.050034 24.224996 90)
			(size 0.519938 1.4986)
			(layers "F.Cu" "F.Mask" "F.Paste")
			(net "GND")
		)
		(pad "243" smd rect
			(at 2.050034 25.07488 90)
			(size 0.519938 1.4986)
			(layers "F.Cu" "F.Mask" "F.Paste")
			(net "M_G_CPU1_SB_CB<3>")
		)
		(pad "244" smd rect
			(at 2.050034 25.925018 90)
			(size 0.519938 1.4986)
			(layers "F.Cu" "F.Mask" "F.Paste")
			(net "GND")
		)
		(pad "245" smd rect
			(at 2.050034 26.774902 90)
			(size 0.519938 1.4986)
			(layers "F.Cu" "F.Mask" "F.Paste")
			(net "M_G_CPU1_SB_DQ<2>")
		)
		(pad "246" smd rect
			(at 2.050034 27.62504 90)
			(size 0.519938 1.4986)
			(layers "F.Cu" "F.Mask" "F.Paste")
			(net "GND")
		)
		(pad "247" smd rect
			(at 2.050034 28.474924 90)
			(size 0.519938 1.4986)
			(layers "F.Cu" "F.Mask" "F.Paste")
			(net "M_G_CPU1_SB_DQ<3>")
		)
		(pad "248" smd rect
			(at 2.050034 29.325062 90)
			(size 0.519938 1.4986)
			(layers "F.Cu" "F.Mask" "F.Paste")
			(net "GND")
		)
		(pad "249" smd rect
			(at 2.050034 30.174946 90)
			(size 0.519938 1.4986)
			(layers "F.Cu" "F.Mask" "F.Paste")
			(net "M_G_CPU1_SB_DQS_DN<5>")
		)
		(pad "250" smd rect
			(at 2.050034 31.025084 90)
			(size 0.519938 1.4986)
			(layers "F.Cu" "F.Mask" "F.Paste")
			(net "M_G_CPU1_SB_DQS_DP<5>")
		)
		(pad "251" smd rect
			(at 2.050034 31.874968 90)
			(size 0.519938 1.4986)
			(layers "F.Cu" "F.Mask" "F.Paste")
			(net "GND")
		)
		(pad "252" smd rect
			(at 2.050034 32.725106 90)
			(size 0.519938 1.4986)
			(layers "F.Cu" "F.Mask" "F.Paste")
			(net "M_G_CPU1_SB_DQ<6>")
		)
		(pad "253" smd rect
			(at 2.050034 33.57499 90)
			(size 0.519938 1.4986)
			(layers "F.Cu" "F.Mask" "F.Paste")
			(net "GND")
		)
		(pad "254" smd rect
			(at 2.050034 34.425128 90)
			(size 0.519938 1.4986)
			(layers "F.Cu" "F.Mask" "F.Paste")
			(net "M_G_CPU1_SB_DQ<7>")
		)
		(pad "255" smd rect
			(at 2.050034 35.275012 90)
			(size 0.519938 1.4986)
			(layers "F.Cu" "F.Mask" "F.Paste")
			(net "GND")
		)
		(pad "256" smd rect
			(at 2.050034 36.124896 90)
			(size 0.519938 1.4986)
			(layers "F.Cu" "F.Mask" "F.Paste")
			(net "M_G_CPU1_SB_DQ<10>")
		)
		(pad "257" smd rect
			(at 2.050034 36.975034 90)
			(size 0.519938 1.4986)
			(layers "F.Cu" "F.Mask" "F.Paste")
			(net "GND")
		)
		(pad "258" smd rect
			(at 2.050034 37.824918 90)
			(size 0.519938 1.4986)
			(layers "F.Cu" "F.Mask" "F.Paste")
			(net "M_G_CPU1_SB_DQ<11>")
		)
		(pad "259" smd rect
			(at 2.050034 38.675056 90)
			(size 0.519938 1.4986)
			(layers "F.Cu" "F.Mask" "F.Paste")
			(net "GND")
		)
		(pad "260" smd rect
			(at 2.050034 39.52494 90)
			(size 0.519938 1.4986)
			(layers "F.Cu" "F.Mask" "F.Paste")
			(net "M_G_CPU1_SB_DQS_DN<6>")
		)
		(pad "261" smd rect
			(at 2.050034 40.375078 90)
			(size 0.519938 1.4986)
			(layers "F.Cu" "F.Mask" "F.Paste")
			(net "M_G_CPU1_SB_DQS_DP<6>")
		)
		(pad "262" smd rect
			(at 2.050034 41.224962 90)
			(size 0.519938 1.4986)
			(layers "F.Cu" "F.Mask" "F.Paste")
			(net "GND")
		)
		(pad "263" smd rect
			(at 2.050034 42.0751 90)
			(size 0.519938 1.4986)
			(layers "F.Cu" "F.Mask" "F.Paste")
			(net "M_G_CPU1_SB_DQ<14>")
		)
		(pad "264" smd rect
			(at 2.050034 42.924984 90)
			(size 0.519938 1.4986)
			(layers "F.Cu" "F.Mask" "F.Paste")
			(net "GND")
		)
		(pad "265" smd rect
			(at 2.050034 43.775122 90)
			(size 0.519938 1.4986)
			(layers "F.Cu" "F.Mask" "F.Paste")
			(net "M_G_CPU1_SB_DQ<15>")
		)
		(pad "266" smd rect
			(at 2.050034 44.625006 90)
			(size 0.519938 1.4986)
			(layers "F.Cu" "F.Mask" "F.Paste")
			(net "GND")
		)
		(pad "267" smd rect
			(at 2.050034 45.47489 90)
			(size 0.519938 1.4986)
			(layers "F.Cu" "F.Mask" "F.Paste")
			(net "M_G_CPU1_SB_DQ<18>")
		)
		(pad "268" smd rect
			(at 2.050034 46.325028 90)
			(size 0.519938 1.4986)
			(layers "F.Cu" "F.Mask" "F.Paste")
			(net "GND")
		)
		(pad "269" smd rect
			(at 2.050034 47.174912 90)
			(size 0.519938 1.4986)
			(layers "F.Cu" "F.Mask" "F.Paste")
			(net "M_G_CPU1_SB_DQ<19>")
		)
		(pad "270" smd rect
			(at 2.050034 48.02505 90)
			(size 0.519938 1.4986)
			(layers "F.Cu" "F.Mask" "F.Paste")
			(net "GND")
		)
		(pad "271" smd rect
			(at 2.050034 48.874934 90)
			(size 0.519938 1.4986)
			(layers "F.Cu" "F.Mask" "F.Paste")
			(net "M_G_CPU1_SB_DQS_DN<7>")
		)
		(pad "272" smd rect
			(at 2.050034 49.725072 90)
			(size 0.519938 1.4986)
			(layers "F.Cu" "F.Mask" "F.Paste")
			(net "M_G_CPU1_SB_DQS_DP<7>")
		)
		(pad "273" smd rect
			(at 2.050034 50.574956 90)
			(size 0.519938 1.4986)
			(layers "F.Cu" "F.Mask" "F.Paste")
			(net "GND")
		)
		(pad "274" smd rect
			(at 2.050034 51.425094 90)
			(size 0.519938 1.4986)
			(layers "F.Cu" "F.Mask" "F.Paste")
			(net "M_G_CPU1_SB_DQ<22>")
		)
		(pad "275" smd rect
			(at 2.050034 52.274978 90)
			(size 0.519938 1.4986)
			(layers "F.Cu" "F.Mask" "F.Paste")
			(net "GND")
		)
		(pad "276" smd rect
			(at 2.050034 53.125116 90)
			(size 0.519938 1.4986)
			(layers "F.Cu" "F.Mask" "F.Paste")
			(net "M_G_CPU1_SB_DQ<23>")
		)
		(pad "277" smd rect
			(at 2.050034 53.975 90)
			(size 0.519938 1.4986)
			(layers "F.Cu" "F.Mask" "F.Paste")
			(net "GND")
		)
		(pad "278" smd rect
			(at 2.050034 54.824884 90)
			(size 0.519938 1.4986)
			(layers "F.Cu" "F.Mask" "F.Paste")
			(net "M_G_CPU1_SB_DQ<26>")
		)
		(pad "279" smd rect
			(at 2.050034 55.675022 90)
			(size 0.519938 1.4986)
			(layers "F.Cu" "F.Mask" "F.Paste")
			(net "GND")
		)
		(pad "280" smd rect
			(at 2.050034 56.524906 90)
			(size 0.519938 1.4986)
			(layers "F.Cu" "F.Mask" "F.Paste")
			(net "M_G_CPU1_SB_DQ<27>")
		)
		(pad "281" smd rect
			(at 2.050034 57.375044 90)
			(size 0.519938 1.4986)
			(layers "F.Cu" "F.Mask" "F.Paste")
			(net "GND")
		)
		(pad "282" smd rect
			(at 2.050034 58.224928 90)
			(size 0.519938 1.4986)
			(layers "F.Cu" "F.Mask" "F.Paste")
			(net "M_G_CPU1_SB_DQS_DN<8>")
		)
		(pad "283" smd rect
			(at 2.050034 59.075066 90)
			(size 0.519938 1.4986)
			(layers "F.Cu" "F.Mask" "F.Paste")
			(net "M_G_CPU1_SB_DQS_DP<8>")
		)
		(pad "284" smd rect
			(at 2.050034 59.92495 90)
			(size 0.519938 1.4986)
			(layers "F.Cu" "F.Mask" "F.Paste")
			(net "GND")
		)
		(pad "285" smd rect
			(at 2.050034 60.775088 90)
			(size 0.519938 1.4986)
			(layers "F.Cu" "F.Mask" "F.Paste")
			(net "M_G_CPU1_SB_DQ<30>")
		)
		(pad "286" smd rect
			(at 2.050034 61.624972 90)
			(size 0.519938 1.4986)
			(layers "F.Cu" "F.Mask" "F.Paste")
			(net "GND")
		)
		(pad "287" smd rect
			(at 2.050034 62.47511 90)
			(size 0.519938 1.4986)
			(layers "F.Cu" "F.Mask" "F.Paste")
			(net "M_G_CPU1_SB_DQ<31>")
		)
		(pad "288" smd rect
			(at 2.050034 63.324994 90)
			(size 0.519938 1.4986)
			(layers "F.Cu" "F.Mask" "F.Paste")
			(net "GND")
		)
		(pad "G1" thru_hole oval
			(at 0 -68.97497 90)
			(size 1.7272 3.4798)
			(drill oval 1.2192 2.4638)
			(layers "*.Cu" "*.Mask")
			(remove_unused_layers no)
			(net "GND")
			(clearance 0.127)
			(thermal_gap 0.127)
		)
		(pad "G2" thru_hole oval
			(at 0 3.875024 90)
			(size 1.7272 3.4798)
			(drill oval 1.2192 2.4638)
			(layers "*.Cu" "*.Mask")
			(remove_unused_layers no)
			(net "GND")
			(clearance 0.127)
			(thermal_gap 0.127)
		)
		(pad "G3" thru_hole oval
			(at 0 68.97497 90)
			(size 1.7272 3.4798)
			(drill oval 1.2192 2.4638)
			(layers "*.Cu" "*.Mask")
			(remove_unused_layers no)
			(net "GND")
			(clearance 0.127)
			(thermal_gap 0.127)
		)
	)
	(footprint ""
		(layer "B.Cu")
		(at 213.617302 -328.110088)
		(property "Reference" "R1242"
			(at 0 0 0)
			(layer "B.SilkS")
			(hide yes)
			(effects
				(font
					(size 1.27 1.27)
				)
				(justify mirror)
			)
		)
		(property "Value" ""
			(at 0 0 0)
			(layer "B.Fab")
			(effects
				(font
					(size 1.27 1.27)
				)
				(justify mirror)
			)
		)
		(duplicate_pad_numbers_are_jumpers no)
		(fp_line
			(start -0.7874 -0.4064)
			(end -0.7874 0.4064)
			(stroke
				(width 0.1524)
				(type default)
			)
			(layer "B.SilkS")
		)
		(fp_line
			(start -0.7874 0.4064)
			(end 0.7874 0.4064)
			(stroke
				(width 0.1524)
				(type default)
			)
			(layer "B.SilkS")
		)
		(fp_line
			(start 0.7874 -0.4064)
			(end -0.7874 -0.4064)
			(stroke
				(width 0.1524)
				(type default)
			)
			(layer "B.SilkS")
		)
		(fp_line
			(start 0.7874 0.4064)
			(end 0.7874 -0.4064)
			(stroke
				(width 0.1524)
				(type default)
			)
			(layer "B.SilkS")
		)
		(fp_line
			(start -0.67945 -0.3048)
			(end -0.67945 0.3048)
			(stroke
				(width 0.1)
				(type default)
			)
			(layer "B.Fab")
		)
		(fp_line
			(start -0.67945 0.3048)
			(end -0.120396 0.3048)
			(stroke
				(width 0.1)
				(type default)
			)
			(layer "B.Fab")
		)
		(fp_line
			(start -0.12065 -0.3048)
			(end -0.67945 -0.3048)
			(stroke
				(width 0.1)
				(type default)
			)
			(layer "B.Fab")
		)
		(fp_line
			(start -0.12065 -0.2794)
			(end -0.12065 -0.3048)
			(stroke
				(width 0.1)
				(type default)
			)
			(layer "B.Fab")
		)
		(fp_line
			(start -0.120396 0.2794)
			(end 0.12065 0.2794)
			(stroke
				(width 0.1)
				(type default)
			)
			(layer "B.Fab")
		)
		(fp_line
			(start -0.120396 0.3048)
			(end -0.120396 0.2794)
			(stroke
				(width 0.1)
				(type default)
			)
			(layer "B.Fab")
		)
		(fp_line
			(start 0.12065 -0.305054)
			(end 0.12065 -0.2794)
			(stroke
				(width 0.1)
				(type default)
			)
			(layer "B.Fab")
		)
		(fp_line
			(start 0.12065 -0.2794)
			(end -0.12065 -0.2794)
			(stroke
				(width 0.1)
				(type default)
			)
			(layer "B.Fab")
		)
		(fp_line
			(start 0.12065 0.2794)
			(end 0.12065 0.3048)
			(stroke
				(width 0.1)
				(type default)
			)
			(layer "B.Fab")
		)
		(fp_line
			(start 0.12065 0.3048)
			(end 0.67945 0.3048)
			(stroke
				(width 0.1)
				(type default)
			)
			(layer "B.Fab")
		)
		(fp_line
			(start 0.67945 -0.305054)
			(end 0.12065 -0.305054)
			(stroke
				(width 0.1)
				(type default)
			)
			(layer "B.Fab")
		)
		(fp_line
			(start 0.67945 0.3048)
			(end 0.67945 -0.305054)
			(stroke
				(width 0.1)
				(type default)
			)
			(layer "B.Fab")
		)
		(pad "1" smd circle
			(at 0.40005 0 180)
			(size 0 0)
			(layers "B.Cu" "B.Mask" "B.Paste")
			(net "ADC128_2_A0")
		)
		(pad "2" smd circle
			(at -0.40005 0 180)
			(size 0 0)
			(layers "B.Cu" "B.Mask" "B.Paste")
			(net "GND")
		)
	)
	(footprint ""
		(layer "B.Cu")
		(at 87.246206 -388.011162 -90)
		(property "Reference" "C204"
			(at 0 0 90)
			(layer "B.SilkS")
			(hide yes)
			(effects
				(font
					(size 1.27 1.27)
				)
				(justify mirror)
			)
		)
		(property "Value" ""
			(at 0 0 90)
			(layer "B.Fab")
			(effects
				(font
					(size 1.27 1.27)
				)
				(justify mirror)
			)
		)
		(duplicate_pad_numbers_are_jumpers no)
		(fp_line
			(start -0.299974 0.150114)
			(end 0.299974 0.150114)
			(stroke
				(width 0.1)
				(type default)
			)
			(layer "B.Fab")
		)
		(fp_line
			(start 0.299974 0.150114)
			(end 0.299974 -0.150114)
			(stroke
				(width 0.1)
				(type default)
			)
			(layer "B.Fab")
		)
		(fp_line
			(start -0.299974 -0.150114)
			(end -0.299974 0.150114)
			(stroke
				(width 0.1)
				(type default)
			)
			(layer "B.Fab")
		)
		(fp_line
			(start 0.299974 -0.150114)
			(end -0.299974 -0.150114)
			(stroke
				(width 0.1)
				(type default)
			)
			(layer "B.Fab")
		)
		(pad "1" smd rect
			(at 0.2667 0 90)
			(size 0.3048 0.381)
			(layers "B.Cu" "B.Mask" "B.Paste")
			(net "P1V8_CPU1_RT1_1A")
		)
		(pad "2" smd rect
			(at -0.2667 0 90)
			(size 0.3048 0.381)
			(layers "B.Cu" "B.Mask" "B.Paste")
			(net "GND")
		)
	)
	(footprint ""
		(layer "B.Cu")
		(at 361.391454 -246.44731 -60)
		(property "Reference" "C2171"
			(at 0 0 120)
			(layer "B.SilkS")
			(hide yes)
			(effects
				(font
					(size 1.27 1.27)
				)
				(justify mirror)
			)
		)
		(property "Value" ""
			(at 0 0 120)
			(layer "B.Fab")
			(effects
				(font
					(size 1.27 1.27)
				)
				(justify mirror)
			)
		)
		(duplicate_pad_numbers_are_jumpers no)
		(fp_line
			(start -0.787516 0.406438)
			(end 0.787425 0.40652)
			(stroke
				(width 0.1524)
				(type default)
			)
			(layer "B.SilkS")
		)
		(fp_line
			(start -0.787425 -0.40652)
			(end -0.787516 0.406438)
			(stroke
				(width 0.1524)
				(type default)
			)
			(layer "B.SilkS")
		)
		(fp_line
			(start 0.787425 0.40652)
			(end 0.787516 -0.406438)
			(stroke
				(width 0.1524)
				(type default)
			)
			(layer "B.SilkS")
		)
		(fp_line
			(start 0.787516 -0.406438)
			(end -0.787425 -0.40652)
			(stroke
				(width 0.1524)
				(type default)
			)
			(layer "B.SilkS")
		)
		(fp_line
			(start -0.679568 0.304811)
			(end -0.120258 0.304812)
			(stroke
				(width 0.1)
				(type default)
			)
			(layer "B.Fab")
		)
		(fp_line
			(start -0.120258 0.304812)
			(end -0.120334 0.279545)
			(stroke
				(width 0.1)
				(type default)
			)
			(layer "B.Fab")
		)
		(fp_line
			(start -0.120334 0.279545)
			(end 0.120587 0.279326)
			(stroke
				(width 0.1)
				(type default)
			)
			(layer "B.Fab")
		)
		(fp_line
			(start 0.120536 0.304813)
			(end 0.6795 0.304908)
			(stroke
				(width 0.1)
				(type default)
			)
			(layer "B.Fab")
		)
		(fp_line
			(start 0.120587 0.279326)
			(end 0.120536 0.304813)
			(stroke
				(width 0.1)
				(type default)
			)
			(layer "B.Fab")
		)
		(fp_line
			(start -0.6795 -0.304908)
			(end -0.679568 0.304811)
			(stroke
				(width 0.1)
				(type default)
			)
			(layer "B.Fab")
		)
		(fp_line
			(start 0.6795 0.304908)
			(end 0.679475 -0.305158)
			(stroke
				(width 0.1)
				(type default)
			)
			(layer "B.Fab")
		)
		(fp_line
			(start -0.120587 -0.279326)
			(end -0.120536 -0.304813)
			(stroke
				(width 0.1)
				(type default)
			)
			(layer "B.Fab")
		)
		(fp_line
			(start -0.120536 -0.304813)
			(end -0.6795 -0.304908)
			(stroke
				(width 0.1)
				(type default)
			)
			(layer "B.Fab")
		)
		(fp_line
			(start 0.120554 -0.279418)
			(end -0.120587 -0.279326)
			(stroke
				(width 0.1)
				(type default)
			)
			(layer "B.Fab")
		)
		(fp_line
			(start 0.120732 -0.305125)
			(end 0.120554 -0.279418)
			(stroke
				(width 0.1)
				(type default)
			)
			(layer "B.Fab")
		)
		(fp_line
			(start 0.679475 -0.305158)
			(end 0.120732 -0.305125)
			(stroke
				(width 0.1)
				(type default)
			)
			(layer "B.Fab")
		)
		(pad "1" smd circle
			(at 0.40005 0 120)
			(size 0 0)
			(layers "B.Cu" "B.Mask" "B.Paste")
			(net "PVDDCR_CPU0_P0")
		)
		(pad "2" smd circle
			(at -0.40005 0 120)
			(size 0 0)
			(layers "B.Cu" "B.Mask" "B.Paste")
			(net "GND")
		)
	)
	(footprint ""
		(layer "B.Cu")
		(at 276.436582 -193.99631)
		(property "Reference" "C104"
			(at 0 0 0)
			(layer "B.SilkS")
			(hide yes)
			(effects
				(font
					(size 1.27 1.27)
				)
				(justify mirror)
			)
		)
		(property "Value" ""
			(at 0 0 0)
			(layer "B.Fab")
			(effects
				(font
					(size 1.27 1.27)
				)
				(justify mirror)
			)
		)
		(duplicate_pad_numbers_are_jumpers no)
		(fp_line
			(start -0.7874 -0.4064)
			(end -0.7874 0.4064)
			(stroke
				(width 0.1524)
				(type default)
			)
			(layer "B.SilkS")
		)
		(fp_line
			(start -0.7874 0.4064)
			(end 0.7874 0.4064)
			(stroke
				(width 0.1524)
				(type default)
			)
			(layer "B.SilkS")
		)
		(fp_line
			(start 0.7874 -0.4064)
			(end -0.7874 -0.4064)
			(stroke
				(width 0.1524)
				(type default)
			)
			(layer "B.SilkS")
		)
		(fp_line
			(start 0.7874 0.4064)
			(end 0.7874 -0.4064)
			(stroke
				(width 0.1524)
				(type default)
			)
			(layer "B.SilkS")
		)
		(fp_line
			(start -0.67945 -0.3048)
			(end -0.67945 0.3048)
			(stroke
				(width 0.1)
				(type default)
			)
			(layer "B.Fab")
		)
		(fp_line
			(start -0.67945 0.3048)
			(end -0.120396 0.3048)
			(stroke
				(width 0.1)
				(type default)
			)
			(layer "B.Fab")
		)
		(fp_line
			(start -0.12065 -0.3048)
			(end -0.67945 -0.3048)
			(stroke
				(width 0.1)
				(type default)
			)
			(layer "B.Fab")
		)
		(fp_line
			(start -0.12065 -0.2794)
			(end -0.12065 -0.3048)
			(stroke
				(width 0.1)
				(type default)
			)
			(layer "B.Fab")
		)
		(fp_line
			(start -0.120396 0.2794)
			(end 0.12065 0.2794)
			(stroke
				(width 0.1)
				(type default)
			)
			(layer "B.Fab")
		)
		(fp_line
			(start -0.120396 0.3048)
			(end -0.120396 0.2794)
			(stroke
				(width 0.1)
				(type default)
			)
			(layer "B.Fab")
		)
		(fp_line
			(start 0.12065 -0.305054)
			(end 0.12065 -0.2794)
			(stroke
				(width 0.1)
				(type default)
			)
			(layer "B.Fab")
		)
		(fp_line
			(start 0.12065 -0.2794)
			(end -0.12065 -0.2794)
			(stroke
				(width 0.1)
				(type default)
			)
			(layer "B.Fab")
		)
		(fp_line
			(start 0.12065 0.2794)
			(end 0.12065 0.3048)
			(stroke
				(width 0.1)
				(type default)
			)
			(layer "B.Fab")
		)
		(fp_line
			(start 0.12065 0.3048)
			(end 0.67945 0.3048)
			(stroke
				(width 0.1)
				(type default)
			)
			(layer "B.Fab")
		)
		(fp_line
			(start 0.67945 -0.305054)
			(end 0.12065 -0.305054)
			(stroke
				(width 0.1)
				(type default)
			)
			(layer "B.Fab")
		)
		(fp_line
			(start 0.67945 0.3048)
			(end 0.67945 -0.305054)
			(stroke
				(width 0.1)
				(type default)
			)
			(layer "B.Fab")
		)
		(pad "1" smd circle
			(at 0.40005 0 180)
			(size 0 0)
			(layers "B.Cu" "B.Mask" "B.Paste")
			(net "P3V3_AUX")
		)
		(pad "2" smd circle
			(at -0.40005 0 180)
			(size 0 0)
			(layers "B.Cu" "B.Mask" "B.Paste")
			(net "GND")
		)
	)
	(footprint ""
		(layer "B.Cu")
		(at 95.506286 -386.766562 90)
		(property "Reference" "C307"
			(at 0 0 90)
			(layer "B.SilkS")
			(hide yes)
			(effects
				(font
					(size 1.27 1.27)
				)
				(justify mirror)
			)
		)
		(property "Value" ""
			(at 0 0 90)
			(layer "B.Fab")
			(effects
				(font
					(size 1.27 1.27)
				)
				(justify mirror)
			)
		)
		(duplicate_pad_numbers_are_jumpers no)
		(fp_line
			(start 0.299974 -0.150114)
			(end -0.299974 -0.150114)
			(stroke
				(width 0.1)
				(type default)
			)
			(layer "B.Fab")
		)
		(fp_line
			(start -0.299974 -0.150114)
			(end -0.299974 0.150114)
			(stroke
				(width 0.1)
				(type default)
			)
			(layer "B.Fab")
		)
		(fp_line
			(start 0.299974 0.150114)
			(end 0.299974 -0.150114)
			(stroke
				(width 0.1)
				(type default)
			)
			(layer "B.Fab")
		)
		(fp_line
			(start -0.299974 0.150114)
			(end 0.299974 0.150114)
			(stroke
				(width 0.1)
				(type default)
			)
			(layer "B.Fab")
		)
		(pad "1" smd rect
			(at 0.2667 0 270)
			(size 0.3048 0.381)
			(layers "B.Cu" "B.Mask" "B.Paste")
			(net "P0V9_CPU1_RT1_2A")
		)
		(pad "2" smd rect
			(at -0.2667 0 270)
			(size 0.3048 0.381)
			(layers "B.Cu" "B.Mask" "B.Paste")
			(net "GND")
		)
	)
	(footprint ""
		(layer "B.Cu")
		(at 64.911732 -338.086954 -90)
		(property "Reference" "PC418_4"
			(at 0 0 90)
			(layer "B.SilkS")
			(hide yes)
			(effects
				(font
					(size 1.27 1.27)
				)
				(justify mirror)
			)
		)
		(property "Value" ""
			(at 0 0 90)
			(layer "B.Fab")
			(effects
				(font
					(size 1.27 1.27)
				)
				(justify mirror)
			)
		)
		(duplicate_pad_numbers_are_jumpers no)
		(fp_line
			(start -1.524 0.762)
			(end 1.524 0.762)
			(stroke
				(width 0.1524)
				(type default)
			)
			(layer "B.SilkS")
		)
		(fp_line
			(start 1.524 0.762)
			(end 1.524 -0.762)
			(stroke
				(width 0.1524)
				(type default)
			)
			(layer "B.SilkS")
		)
		(fp_line
			(start -1.524 -0.762)
			(end -1.524 0.762)
			(stroke
				(width 0.1524)
				(type default)
			)
			(layer "B.SilkS")
		)
		(fp_line
			(start 1.524 -0.762)
			(end -1.524 -0.762)
			(stroke
				(width 0.1524)
				(type default)
			)
			(layer "B.SilkS")
		)
		(fp_line
			(start -1.1049 0.724916)
			(end -1.1049 -0.724916)
			(stroke
				(width 0.1)
				(type default)
			)
			(layer "B.Fab")
		)
		(fp_line
			(start 1.1049 0.724916)
			(end -1.1049 0.724916)
			(stroke
				(width 0.1)
				(type default)
			)
			(layer "B.Fab")
		)
		(fp_line
			(start -1.1049 -0.724916)
			(end 1.1049 -0.724916)
			(stroke
				(width 0.1)
				(type default)
			)
			(layer "B.Fab")
		)
		(fp_line
			(start 1.1049 -0.724916)
			(end 1.1049 0.724916)
			(stroke
				(width 0.1)
				(type default)
			)
			(layer "B.Fab")
		)
		(pad "1" smd rect
			(at 0.889 0 270)
			(size 1.016 1.27)
			(layers "B.Cu" "B.Mask" "B.Paste")
			(net "PVDDCR_CPU1_P1")
		)
		(pad "2" smd rect
			(at -0.889 0 270)
			(size 1.016 1.27)
			(layers "B.Cu" "B.Mask" "B.Paste")
			(net "GND")
		)
	)
	(footprint ""
		(layer "B.Cu")
		(at 247.264682 -336.846164 180)
		(property "Reference" "U22"
			(at -1.699768 -5.606796 0)
			(unlocked yes)
			(layer "B.SilkS")
			(effects
				(font
					(size 0.7874 0.5842)
					(thickness 0.1524)
				)
				(justify left mirror)
			)
		)
		(property "Value" ""
			(at 0 0 0)
			(layer "B.Fab")
			(effects
				(font
					(size 1.27 1.27)
				)
				(justify mirror)
			)
		)
		(duplicate_pad_numbers_are_jumpers no)
		(fp_line
			(start 1.8542 3.949954)
			(end -1.8542 3.949954)
			(stroke
				(width 0.1524)
				(type default)
			)
			(layer "B.SilkS")
		)
		(fp_line
			(start 1.8542 -3.949954)
			(end 1.8542 3.949954)
			(stroke
				(width 0.1524)
				(type default)
			)
			(layer "B.SilkS")
		)
		(fp_line
			(start 1.282954 -3.949954)
			(end 1.8542 -3.949954)
			(stroke
				(width 0.1524)
				(type default)
			)
			(layer "B.SilkS")
		)
		(fp_line
			(start 0 -2.667)
			(end 1.282954 -3.949954)
			(stroke
				(width 0.1524)
				(type default)
			)
			(layer "B.SilkS")
		)
		(fp_line
			(start -1.282954 -3.949954)
			(end 0 -2.667)
			(stroke
				(width 0.1524)
				(type default)
			)
			(layer "B.SilkS")
		)
		(fp_line
			(start -1.8542 3.949954)
			(end -1.8542 -3.949954)
			(stroke
				(width 0.1524)
				(type default)
			)
			(layer "B.SilkS")
		)
		(fp_line
			(start -1.8542 -3.949954)
			(end -1.282954 -3.949954)
			(stroke
				(width 0.1524)
				(type default)
			)
			(layer "B.SilkS")
		)
		(fp_poly
			(pts
				(xy 2.334514 -5.227066) (xy 3.348482 -5.29209) (xy 2.906522 -4.24561)
			)
			(stroke
				(width 0)
				(type default)
			)
			(fill yes)
			(layer "B.SilkS")
		)
		(fp_line
			(start 2.249932 3.949954)
			(end -2.249932 3.949954)
			(stroke
				(width 0.1)
				(type default)
			)
			(layer "B.Fab")
		)
		(fp_line
			(start 2.249932 -3.949954)
			(end 2.249932 3.949954)
			(stroke
				(width 0.1)
				(type default)
			)
			(layer "B.Fab")
		)
		(fp_line
			(start -2.249932 3.949954)
			(end -2.249932 -3.949954)
			(stroke
				(width 0.1)
				(type default)
			)
			(layer "B.Fab")
		)
		(fp_line
			(start -2.249932 -3.949954)
			(end 2.249932 -3.949954)
			(stroke
				(width 0.1)
				(type default)
			)
			(layer "B.Fab")
		)
		(fp_poly
			(pts
				(xy 4.8006 -4.08305) (xy 4.8006 -3.06705) (xy 3.7846 -3.57505)
			)
			(stroke
				(width 0)
				(type default)
			)
			(fill yes)
			(layer "B.Fab")
		)
		(pad "1" smd rect
			(at 2.800096 -3.57505 90)
			(size 0.3048 1.6002)
			(layers "B.Cu" "B.Mask" "B.Paste")
			(net "RT_ROM_SMB_MUX_ADDR0")
		)
		(pad "2" smd rect
			(at 2.800096 -2.925064 90)
			(size 0.3048 1.6002)
			(layers "B.Cu" "B.Mask" "B.Paste")
			(net "RT_ROM_SMB_MUX_ADDR1")
		)
		(pad "3" smd rect
			(at 2.800096 -2.275078 90)
			(size 0.3048 1.6002)
			(layers "B.Cu" "B.Mask" "B.Paste")
			(net "RST_SMB_RT_ROM_N")
		)
		(pad "4" smd rect
			(at 2.800096 -1.625092 90)
			(size 0.3048 1.6002)
			(layers "B.Cu" "B.Mask" "B.Paste")
			(net "SMB_RT_CPU1_P0_ROM_MUX_2D_R_SDA")
		)
		(pad "5" smd rect
			(at 2.800096 -0.975106 90)
			(size 0.3048 1.6002)
			(layers "B.Cu" "B.Mask" "B.Paste")
			(net "SMB_RT_CPU1_P0_ROM_MUX_2D_R_SCL")
		)
		(pad "6" smd rect
			(at 2.800096 -0.32512 90)
			(size 0.3048 1.6002)
			(layers "B.Cu" "B.Mask" "B.Paste")
			(net "SMB_RT_CPU1_P1_ROM_MUX_2D_R_SDA")
		)
		(pad "7" smd rect
			(at 2.800096 0.32512 90)
			(size 0.3048 1.6002)
			(layers "B.Cu" "B.Mask" "B.Paste")
			(net "SMB_RT_CPU1_P1_ROM_MUX_2D_R_SCL")
		)
		(pad "8" smd rect
			(at 2.800096 0.975106 90)
			(size 0.3048 1.6002)
			(layers "B.Cu" "B.Mask" "B.Paste")
			(net "SMB_RT_CPU1_P3_ROM_MUX_2D_R_SDA")
		)
		(pad "9" smd rect
			(at 2.800096 1.625092 90)
			(size 0.3048 1.6002)
			(layers "B.Cu" "B.Mask" "B.Paste")
			(net "SMB_RT_CPU1_P3_ROM_MUX_2D_R_SCL")
		)
		(pad "10" smd rect
			(at 2.800096 2.275078 90)
			(size 0.3048 1.6002)
			(layers "B.Cu" "B.Mask" "B.Paste")
			(net "SMB_RT_CPU1_P2_ROM_MUX_2D_R_SDA")
		)
		(pad "11" smd rect
			(at 2.800096 2.925064 90)
			(size 0.3048 1.6002)
			(layers "B.Cu" "B.Mask" "B.Paste")
			(net "SMB_RT_CPU1_P2_ROM_MUX_2D_R_SCL")
		)
		(pad "12" smd rect
			(at 2.800096 3.57505 90)
			(size 0.3048 1.6002)
			(layers "B.Cu" "B.Mask" "B.Paste")
			(net "GND")
		)
		(pad "13" smd rect
			(at -2.800096 3.57505 90)
			(size 0.3048 1.6002)
			(layers "B.Cu" "B.Mask" "B.Paste")
			(net "SMB_RT_CPU0_P0_ROM_MUX_2D_R_SDA")
		)
		(pad "14" smd rect
			(at -2.800096 2.925064 90)
			(size 0.3048 1.6002)
			(layers "B.Cu" "B.Mask" "B.Paste")
			(net "SMB_RT_CPU0_P0_ROM_MUX_2D_R_SCL")
		)
		(pad "15" smd rect
			(at -2.800096 2.275078 90)
			(size 0.3048 1.6002)
			(layers "B.Cu" "B.Mask" "B.Paste")
			(net "SMB_RT_CPU0_P1_ROM_MUX_2D_R_SDA")
		)
		(pad "16" smd rect
			(at -2.800096 1.625092 90)
			(size 0.3048 1.6002)
			(layers "B.Cu" "B.Mask" "B.Paste")
			(net "SMB_RT_CPU0_P1_ROM_MUX_2D_R_SCL")
		)
		(pad "17" smd rect
			(at -2.800096 0.975106 90)
			(size 0.3048 1.6002)
			(layers "B.Cu" "B.Mask" "B.Paste")
			(net "SMB_RT_CPU0_P3_ROM_MUX_2D_R_SDA")
		)
		(pad "18" smd rect
			(at -2.800096 0.32512 90)
			(size 0.3048 1.6002)
			(layers "B.Cu" "B.Mask" "B.Paste")
			(net "SMB_RT_CPU0_P3_ROM_MUX_2D_R_SCL")
		)
		(pad "19" smd rect
			(at -2.800096 -0.32512 90)
			(size 0.3048 1.6002)
			(layers "B.Cu" "B.Mask" "B.Paste")
			(net "SMB_RT_CPU0_P2_ROM_MUX_2D_R_SDA")
		)
		(pad "20" smd rect
			(at -2.800096 -0.975106 90)
			(size 0.3048 1.6002)
			(layers "B.Cu" "B.Mask" "B.Paste")
			(net "SMB_RT_CPU0_P2_ROM_MUX_2D_R_SCL")
		)
		(pad "21" smd rect
			(at -2.800096 -1.625092 90)
			(size 0.3048 1.6002)
			(layers "B.Cu" "B.Mask" "B.Paste")
			(net "RT_ROM_SMB_MUX_ADDR2")
		)
		(pad "22" smd rect
			(at -2.800096 -2.275078 90)
			(size 0.3048 1.6002)
			(layers "B.Cu" "B.Mask" "B.Paste")
			(net "SMB_MUX_RT_ROM_SCL")
		)
		(pad "23" smd rect
			(at -2.800096 -2.925064 90)
			(size 0.3048 1.6002)
			(layers "B.Cu" "B.Mask" "B.Paste")
			(net "SMB_MUX_RT_ROM_SDA")
		)
		(pad "24" smd rect
			(at -2.800096 -3.57505 90)
			(size 0.3048 1.6002)
			(layers "B.Cu" "B.Mask" "B.Paste")
			(net "P1V8_AUX")
		)
	)
	(footprint ""
		(layer "B.Cu")
		(at 285.299912 -420.350442 90)
		(property "Reference" "C2339"
			(at 0 0 90)
			(layer "B.SilkS")
			(hide yes)
			(effects
				(font
					(size 1.27 1.27)
				)
				(justify mirror)
			)
		)
		(property "Value" ""
			(at 0 0 90)
			(layer "B.Fab")
			(effects
				(font
					(size 1.27 1.27)
				)
				(justify mirror)
			)
		)
		(duplicate_pad_numbers_are_jumpers no)
		(fp_line
			(start 0.7874 -0.4064)
			(end -0.7874 -0.4064)
			(stroke
				(width 0.1524)
				(type default)
			)
			(layer "B.SilkS")
		)
		(fp_line
			(start -0.7874 -0.4064)
			(end -0.7874 0.4064)
			(stroke
				(width 0.1524)
				(type default)
			)
			(layer "B.SilkS")
		)
		(fp_line
			(start 0.7874 0.4064)
			(end 0.7874 -0.4064)
			(stroke
				(width 0.1524)
				(type default)
			)
			(layer "B.SilkS")
		)
		(fp_line
			(start -0.7874 0.4064)
			(end 0.7874 0.4064)
			(stroke
				(width 0.1524)
				(type default)
			)
			(layer "B.SilkS")
		)
		(fp_line
			(start 0.67945 -0.305054)
			(end 0.12065 -0.305054)
			(stroke
				(width 0.1)
				(type default)
			)
			(layer "B.Fab")
		)
		(fp_line
			(start 0.12065 -0.305054)
			(end 0.12065 -0.2794)
			(stroke
				(width 0.1)
				(type default)
			)
			(layer "B.Fab")
		)
		(fp_line
			(start -0.12065 -0.3048)
			(end -0.67945 -0.3048)
			(stroke
				(width 0.1)
				(type default)
			)
			(layer "B.Fab")
		)
		(fp_line
			(start -0.67945 -0.3048)
			(end -0.67945 0.3048)
			(stroke
				(width 0.1)
				(type default)
			)
			(layer "B.Fab")
		)
		(fp_line
			(start 0.12065 -0.2794)
			(end -0.12065 -0.2794)
			(stroke
				(width 0.1)
				(type default)
			)
			(layer "B.Fab")
		)
		(fp_line
			(start -0.12065 -0.2794)
			(end -0.12065 -0.3048)
			(stroke
				(width 0.1)
				(type default)
			)
			(layer "B.Fab")
		)
		(fp_line
			(start 0.12065 0.2794)
			(end 0.12065 0.3048)
			(stroke
				(width 0.1)
				(type default)
			)
			(layer "B.Fab")
		)
		(fp_line
			(start -0.120396 0.2794)
			(end 0.12065 0.2794)
			(stroke
				(width 0.1)
				(type default)
			)
			(layer "B.Fab")
		)
		(fp_line
			(start 0.67945 0.3048)
			(end 0.67945 -0.305054)
			(stroke
				(width 0.1)
				(type default)
			)
			(layer "B.Fab")
		)
		(fp_line
			(start 0.12065 0.3048)
			(end 0.67945 0.3048)
			(stroke
				(width 0.1)
				(type default)
			)
			(layer "B.Fab")
		)
		(fp_line
			(start -0.120396 0.3048)
			(end -0.120396 0.2794)
			(stroke
				(width 0.1)
				(type default)
			)
			(layer "B.Fab")
		)
		(fp_line
			(start -0.67945 0.3048)
			(end -0.120396 0.3048)
			(stroke
				(width 0.1)
				(type default)
			)
			(layer "B.Fab")
		)
		(pad "1" smd circle
			(at 0.40005 0 270)
			(size 0 0)
			(layers "B.Cu" "B.Mask" "B.Paste")
			(net "P3V3_9ZXL045_P0_VDD")
		)
		(pad "2" smd circle
			(at -0.40005 0 270)
			(size 0 0)
			(layers "B.Cu" "B.Mask" "B.Paste")
			(net "GND")
		)
	)
	(footprint ""
		(layer "B.Cu")
		(at 197.225158 -77.192632)
		(property "Reference" "U67"
			(at 2.032 -3.27533 0)
			(unlocked yes)
			(layer "B.SilkS")
			(effects
				(font
					(size 0.7874 0.5842)
					(thickness 0.1524)
				)
				(justify left mirror)
			)
		)
		(property "Value" ""
			(at 0 0 0)
			(layer "B.Fab")
			(effects
				(font
					(size 1.27 1.27)
				)
				(justify mirror)
			)
		)
		(duplicate_pad_numbers_are_jumpers no)
		(fp_line
			(start -2.0066 -2.5527)
			(end -2.0066 2.5527)
			(stroke
				(width 0.1524)
				(type default)
			)
			(layer "B.SilkS")
		)
		(fp_line
			(start -2.0066 2.5527)
			(end 2.0066 2.5527)
			(stroke
				(width 0.1524)
				(type default)
			)
			(layer "B.SilkS")
		)
		(fp_line
			(start -0.5715 -2.5527)
			(end -2.0066 -2.5527)
			(stroke
				(width 0.1524)
				(type default)
			)
			(layer "B.SilkS")
		)
		(fp_line
			(start 0 -1.9812)
			(end -0.5715 -2.5527)
			(stroke
				(width 0.1524)
				(type default)
			)
			(layer "B.SilkS")
		)
		(fp_line
			(start 0.5715 -2.5527)
			(end 0 -1.9812)
			(stroke
				(width 0.1524)
				(type default)
			)
			(layer "B.SilkS")
		)
		(fp_line
			(start 2.0066 -2.5527)
			(end 0.5715 -2.5527)
			(stroke
				(width 0.1524)
				(type default)
			)
			(layer "B.SilkS")
		)
		(fp_line
			(start 2.0066 2.5527)
			(end 2.0066 -2.5527)
			(stroke
				(width 0.1524)
				(type default)
			)
			(layer "B.SilkS")
		)
		(fp_poly
			(pts
				(xy 3.793236 -2.006092) (xy 4.346956 -2.33426) (xy 4.346956 -1.70942)
			)
			(stroke
				(width 0)
				(type default)
			)
			(fill yes)
			(layer "B.SilkS")
		)
		(fp_line
			(start -2.249932 -2.549906)
			(end -2.249932 2.549906)
			(stroke
				(width 0.1)
				(type default)
			)
			(layer "B.Fab")
		)
		(fp_line
			(start -2.249932 2.549906)
			(end 2.249932 2.549906)
			(stroke
				(width 0.1)
				(type default)
			)
			(layer "B.Fab")
		)
		(fp_line
			(start 2.249932 -2.549906)
			(end -2.249932 -2.549906)
			(stroke
				(width 0.1)
				(type default)
			)
			(layer "B.Fab")
		)
		(fp_line
			(start 2.249932 2.549906)
			(end 2.249932 -2.549906)
			(stroke
				(width 0.1)
				(type default)
			)
			(layer "B.Fab")
		)
		(fp_poly
			(pts
				(xy 4.36372 -1.608328) (xy 4.36372 -2.233168) (xy 3.81 -1.905)
			)
			(stroke
				(width 0)
				(type default)
			)
			(fill yes)
			(layer "B.Fab")
		)
		(pad "1" smd rect
			(at 2.921 -1.949958 270)
			(size 0.3556 1.4986)
			(layers "B.Cu" "B.Mask" "B.Paste")
			(net "FB_BMC_ISOLATE")
		)
		(pad "2" smd rect
			(at 2.921 -1.299972 270)
			(size 0.3556 1.4986)
			(layers "B.Cu" "B.Mask" "B.Paste")
			(net "NCSI_BMC_RXD1_R")
		)
		(pad "3" smd rect
			(at 2.921 -0.649986 270)
			(size 0.3556 1.4986)
			(layers "B.Cu" "B.Mask" "B.Paste")
			(net "NCSI_OCP_SFF_RXD1")
		)
		(pad "4" smd rect
			(at 2.921 0 270)
			(size 0.3556 1.4986)
			(layers "B.Cu" "B.Mask" "B.Paste")
			(net "FB_BMC_ISOLATE")
		)
		(pad "5" smd rect
			(at 2.921 0.649986 270)
			(size 0.3556 1.4986)
			(layers "B.Cu" "B.Mask" "B.Paste")
			(net "NCSI_BMC_RXD0_R")
		)
		(pad "6" smd rect
			(at 2.921 1.299972 270)
			(size 0.3556 1.4986)
			(layers "B.Cu" "B.Mask" "B.Paste")
			(net "NCSI_OCP_SFF_RXD0")
		)
		(pad "7" smd rect
			(at 2.921 1.949958 270)
			(size 0.3556 1.4986)
			(layers "B.Cu" "B.Mask" "B.Paste")
			(net "GND")
		)
		(pad "8" smd rect
			(at -2.921 1.949958 270)
			(size 0.3556 1.4986)
			(layers "B.Cu" "B.Mask" "B.Paste")
			(net "NCSI_OCP_SFF_CRS_DV")
		)
		(pad "9" smd rect
			(at -2.921 1.299972 270)
			(size 0.3556 1.4986)
			(layers "B.Cu" "B.Mask" "B.Paste")
			(net "NCSI_BMC_CRS_DV_R")
		)
		(pad "10" smd rect
			(at -2.921 0.649986 270)
			(size 0.3556 1.4986)
			(layers "B.Cu" "B.Mask" "B.Paste")
			(net "FB_BMC_ISOLATE")
		)
		(pad "11" smd rect
			(at -2.921 0 270)
			(size 0.3556 1.4986)
			(layers "B.Cu" "B.Mask" "B.Paste")
			(net "OCP_SFF_ISO1_RBT_ARB_IN")
		)
		(pad "12" smd rect
			(at -2.921 -0.649986 270)
			(size 0.3556 1.4986)
			(layers "B.Cu" "B.Mask" "B.Paste")
			(net "OCP_SFF_RBT_ARB_IN_R")
		)
		(pad "13" smd rect
			(at -2.921 -1.299972 270)
			(size 0.3556 1.4986)
			(layers "B.Cu" "B.Mask" "B.Paste")
			(net "FB_BMC_ISOLATE")
		)
		(pad "14" smd rect
			(at -2.921 -1.949958 270)
			(size 0.3556 1.4986)
			(layers "B.Cu" "B.Mask" "B.Paste")
			(net "P3V3_AUX")
		)
	)
	(footprint ""
		(layer "B.Cu")
		(at 74.940668 -388.846568)
		(property "Reference" "C324"
			(at 0 0 0)
			(layer "B.SilkS")
			(hide yes)
			(effects
				(font
					(size 1.27 1.27)
				)
				(justify mirror)
			)
		)
		(property "Value" ""
			(at 0 0 0)
			(layer "B.Fab")
			(effects
				(font
					(size 1.27 1.27)
				)
				(justify mirror)
			)
		)
		(duplicate_pad_numbers_are_jumpers no)
		(fp_line
			(start -1.524 -0.762)
			(end -1.524 0.762)
			(stroke
				(width 0.1524)
				(type default)
			)
			(layer "B.SilkS")
		)
		(fp_line
			(start -1.524 0.762)
			(end 1.524 0.762)
			(stroke
				(width 0.1524)
				(type default)
			)
			(layer "B.SilkS")
		)
		(fp_line
			(start 1.524 -0.762)
			(end -1.524 -0.762)
			(stroke
				(width 0.1524)
				(type default)
			)
			(layer "B.SilkS")
		)
		(fp_line
			(start 1.524 0.762)
			(end 1.524 -0.762)
			(stroke
				(width 0.1524)
				(type default)
			)
			(layer "B.SilkS")
		)
		(fp_line
			(start -1.1049 -0.724916)
			(end 1.1049 -0.724916)
			(stroke
				(width 0.1)
				(type default)
			)
			(layer "B.Fab")
		)
		(fp_line
			(start -1.1049 0.724916)
			(end -1.1049 -0.724916)
			(stroke
				(width 0.1)
				(type default)
			)
			(layer "B.Fab")
		)
		(fp_line
			(start 1.1049 -0.724916)
			(end 1.1049 0.724916)
			(stroke
				(width 0.1)
				(type default)
			)
			(layer "B.Fab")
		)
		(fp_line
			(start 1.1049 0.724916)
			(end -1.1049 0.724916)
			(stroke
				(width 0.1)
				(type default)
			)
			(layer "B.Fab")
		)
		(pad "1" smd rect
			(at 0.889 0)
			(size 1.016 1.27)
			(layers "B.Cu" "B.Mask" "B.Paste")
			(net "P0V9_CPU1_RT1_2A")
		)
		(pad "2" smd rect
			(at -0.889 0)
			(size 1.016 1.27)
			(layers "B.Cu" "B.Mask" "B.Paste")
			(net "GND")
		)
	)
	(footprint ""
		(layer "B.Cu")
		(at 356.057454 -253.43231)
		(property "Reference" "C2549"
			(at 0 0 0)
			(layer "B.SilkS")
			(hide yes)
			(effects
				(font
					(size 1.27 1.27)
				)
				(justify mirror)
			)
		)
		(property "Value" ""
			(at 0 0 0)
			(layer "B.Fab")
			(effects
				(font
					(size 1.27 1.27)
				)
				(justify mirror)
			)
		)
		(duplicate_pad_numbers_are_jumpers no)
		(fp_line
			(start -0.7874 -0.4064)
			(end -0.7874 0.4064)
			(stroke
				(width 0.1524)
				(type default)
			)
			(layer "B.SilkS")
		)
		(fp_line
			(start -0.7874 0.4064)
			(end 0.7874 0.4064)
			(stroke
				(width 0.1524)
				(type default)
			)
			(layer "B.SilkS")
		)
		(fp_line
			(start 0.7874 -0.4064)
			(end -0.7874 -0.4064)
			(stroke
				(width 0.1524)
				(type default)
			)
			(layer "B.SilkS")
		)
		(fp_line
			(start 0.7874 0.4064)
			(end 0.7874 -0.4064)
			(stroke
				(width 0.1524)
				(type default)
			)
			(layer "B.SilkS")
		)
		(fp_line
			(start -0.67945 -0.3048)
			(end -0.67945 0.3048)
			(stroke
				(width 0.1)
				(type default)
			)
			(layer "B.Fab")
		)
		(fp_line
			(start -0.67945 0.3048)
			(end -0.120396 0.3048)
			(stroke
				(width 0.1)
				(type default)
			)
			(layer "B.Fab")
		)
		(fp_line
			(start -0.12065 -0.3048)
			(end -0.67945 -0.3048)
			(stroke
				(width 0.1)
				(type default)
			)
			(layer "B.Fab")
		)
		(fp_line
			(start -0.12065 -0.2794)
			(end -0.12065 -0.3048)
			(stroke
				(width 0.1)
				(type default)
			)
			(layer "B.Fab")
		)
		(fp_line
			(start -0.120396 0.2794)
			(end 0.12065 0.2794)
			(stroke
				(width 0.1)
				(type default)
			)
			(layer "B.Fab")
		)
		(fp_line
			(start -0.120396 0.3048)
			(end -0.120396 0.2794)
			(stroke
				(width 0.1)
				(type default)
			)
			(layer "B.Fab")
		)
		(fp_line
			(start 0.12065 -0.305054)
			(end 0.12065 -0.2794)
			(stroke
				(width 0.1)
				(type default)
			)
			(layer "B.Fab")
		)
		(fp_line
			(start 0.12065 -0.2794)
			(end -0.12065 -0.2794)
			(stroke
				(width 0.1)
				(type default)
			)
			(layer "B.Fab")
		)
		(fp_line
			(start 0.12065 0.2794)
			(end 0.12065 0.3048)
			(stroke
				(width 0.1)
				(type default)
			)
			(layer "B.Fab")
		)
		(fp_line
			(start 0.12065 0.3048)
			(end 0.67945 0.3048)
			(stroke
				(width 0.1)
				(type default)
			)
			(layer "B.Fab")
		)
		(fp_line
			(start 0.67945 -0.305054)
			(end 0.12065 -0.305054)
			(stroke
				(width 0.1)
				(type default)
			)
			(layer "B.Fab")
		)
		(fp_line
			(start 0.67945 0.3048)
			(end 0.67945 -0.305054)
			(stroke
				(width 0.1)
				(type default)
			)
			(layer "B.Fab")
		)
		(pad "1" smd circle
			(at 0.40005 0 180)
			(size 0 0)
			(layers "B.Cu" "B.Mask" "B.Paste")
			(net "PVDDCR_SOC_P0")
		)
		(pad "2" smd circle
			(at -0.40005 0 180)
			(size 0 0)
			(layers "B.Cu" "B.Mask" "B.Paste")
			(net "GND")
		)
	)
	(footprint ""
		(layer "B.Cu")
		(at 375.456958 -208.530952 90)
		(property "Reference" "C209"
			(at 0 0 90)
			(layer "B.SilkS")
			(hide yes)
			(effects
				(font
					(size 1.27 1.27)
				)
				(justify mirror)
			)
		)
		(property "Value" ""
			(at 0 0 90)
			(layer "B.Fab")
			(effects
				(font
					(size 1.27 1.27)
				)
				(justify mirror)
			)
		)
		(duplicate_pad_numbers_are_jumpers no)
		(fp_line
			(start 0.7874 -0.4064)
			(end -0.7874 -0.4064)
			(stroke
				(width 0.1524)
				(type default)
			)
			(layer "B.SilkS")
		)
		(fp_line
			(start -0.7874 -0.4064)
			(end -0.7874 0.4064)
			(stroke
				(width 0.1524)
				(type default)
			)
			(layer "B.SilkS")
		)
		(fp_line
			(start 0.7874 0.4064)
			(end 0.7874 -0.4064)
			(stroke
				(width 0.1524)
				(type default)
			)
			(layer "B.SilkS")
		)
		(fp_line
			(start -0.7874 0.4064)
			(end 0.7874 0.4064)
			(stroke
				(width 0.1524)
				(type default)
			)
			(layer "B.SilkS")
		)
		(fp_line
			(start 0.67945 -0.305054)
			(end 0.12065 -0.305054)
			(stroke
				(width 0.1)
				(type default)
			)
			(layer "B.Fab")
		)
		(fp_line
			(start 0.12065 -0.305054)
			(end 0.12065 -0.2794)
			(stroke
				(width 0.1)
				(type default)
			)
			(layer "B.Fab")
		)
		(fp_line
			(start -0.12065 -0.3048)
			(end -0.67945 -0.3048)
			(stroke
				(width 0.1)
				(type default)
			)
			(layer "B.Fab")
		)
		(fp_line
			(start -0.67945 -0.3048)
			(end -0.67945 0.3048)
			(stroke
				(width 0.1)
				(type default)
			)
			(layer "B.Fab")
		)
		(fp_line
			(start 0.12065 -0.2794)
			(end -0.12065 -0.2794)
			(stroke
				(width 0.1)
				(type default)
			)
			(layer "B.Fab")
		)
		(fp_line
			(start -0.12065 -0.2794)
			(end -0.12065 -0.3048)
			(stroke
				(width 0.1)
				(type default)
			)
			(layer "B.Fab")
		)
		(fp_line
			(start 0.12065 0.2794)
			(end 0.12065 0.3048)
			(stroke
				(width 0.1)
				(type default)
			)
			(layer "B.Fab")
		)
		(fp_line
			(start -0.120396 0.2794)
			(end 0.12065 0.2794)
			(stroke
				(width 0.1)
				(type default)
			)
			(layer "B.Fab")
		)
		(fp_line
			(start 0.67945 0.3048)
			(end 0.67945 -0.305054)
			(stroke
				(width 0.1)
				(type default)
			)
			(layer "B.Fab")
		)
		(fp_line
			(start 0.12065 0.3048)
			(end 0.67945 0.3048)
			(stroke
				(width 0.1)
				(type default)
			)
			(layer "B.Fab")
		)
		(fp_line
			(start -0.120396 0.3048)
			(end -0.120396 0.2794)
			(stroke
				(width 0.1)
				(type default)
			)
			(layer "B.Fab")
		)
		(fp_line
			(start -0.67945 0.3048)
			(end -0.120396 0.3048)
			(stroke
				(width 0.1)
				(type default)
			)
			(layer "B.Fab")
		)
		(pad "1" smd circle
			(at 0.40005 0 270)
			(size 0 0)
			(layers "B.Cu" "B.Mask" "B.Paste")
			(net "JTAG_CPU0_TRST_N")
		)
		(pad "2" smd circle
			(at -0.40005 0 270)
			(size 0 0)
			(layers "B.Cu" "B.Mask" "B.Paste")
			(net "GND")
		)
	)
	(footprint ""
		(layer "B.Cu")
		(at 88.319102 -390.560052 90)
		(property "Reference" "C195"
			(at 0 0 90)
			(layer "B.SilkS")
			(hide yes)
			(effects
				(font
					(size 1.27 1.27)
				)
				(justify mirror)
			)
		)
		(property "Value" ""
			(at 0 0 90)
			(layer "B.Fab")
			(effects
				(font
					(size 1.27 1.27)
				)
				(justify mirror)
			)
		)
		(duplicate_pad_numbers_are_jumpers no)
		(fp_line
			(start 0.7874 -0.4064)
			(end -0.7874 -0.4064)
			(stroke
				(width 0.1524)
				(type default)
			)
			(layer "B.SilkS")
		)
		(fp_line
			(start -0.7874 -0.4064)
			(end -0.7874 0.4064)
			(stroke
				(width 0.1524)
				(type default)
			)
			(layer "B.SilkS")
		)
		(fp_line
			(start 0.7874 0.4064)
			(end 0.7874 -0.4064)
			(stroke
				(width 0.1524)
				(type default)
			)
			(layer "B.SilkS")
		)
		(fp_line
			(start -0.7874 0.4064)
			(end 0.7874 0.4064)
			(stroke
				(width 0.1524)
				(type default)
			)
			(layer "B.SilkS")
		)
		(fp_line
			(start 0.67945 -0.305054)
			(end 0.12065 -0.305054)
			(stroke
				(width 0.1)
				(type default)
			)
			(layer "B.Fab")
		)
		(fp_line
			(start 0.12065 -0.305054)
			(end 0.12065 -0.2794)
			(stroke
				(width 0.1)
				(type default)
			)
			(layer "B.Fab")
		)
		(fp_line
			(start -0.12065 -0.3048)
			(end -0.67945 -0.3048)
			(stroke
				(width 0.1)
				(type default)
			)
			(layer "B.Fab")
		)
		(fp_line
			(start -0.67945 -0.3048)
			(end -0.67945 0.3048)
			(stroke
				(width 0.1)
				(type default)
			)
			(layer "B.Fab")
		)
		(fp_line
			(start 0.12065 -0.2794)
			(end -0.12065 -0.2794)
			(stroke
				(width 0.1)
				(type default)
			)
			(layer "B.Fab")
		)
		(fp_line
			(start -0.12065 -0.2794)
			(end -0.12065 -0.3048)
			(stroke
				(width 0.1)
				(type default)
			)
			(layer "B.Fab")
		)
		(fp_line
			(start 0.12065 0.2794)
			(end 0.12065 0.3048)
			(stroke
				(width 0.1)
				(type default)
			)
			(layer "B.Fab")
		)
		(fp_line
			(start -0.120396 0.2794)
			(end 0.12065 0.2794)
			(stroke
				(width 0.1)
				(type default)
			)
			(layer "B.Fab")
		)
		(fp_line
			(start 0.67945 0.3048)
			(end 0.67945 -0.305054)
			(stroke
				(width 0.1)
				(type default)
			)
			(layer "B.Fab")
		)
		(fp_line
			(start 0.12065 0.3048)
			(end 0.67945 0.3048)
			(stroke
				(width 0.1)
				(type default)
			)
			(layer "B.Fab")
		)
		(fp_line
			(start -0.120396 0.3048)
			(end -0.120396 0.2794)
			(stroke
				(width 0.1)
				(type default)
			)
			(layer "B.Fab")
		)
		(fp_line
			(start -0.67945 0.3048)
			(end -0.120396 0.3048)
			(stroke
				(width 0.1)
				(type default)
			)
			(layer "B.Fab")
		)
		(pad "1" smd circle
			(at 0.40005 0 270)
			(size 0 0)
			(layers "B.Cu" "B.Mask" "B.Paste")
			(net "P1V8_CPU1_RT1_1A")
		)
		(pad "2" smd circle
			(at -0.40005 0 270)
			(size 0 0)
			(layers "B.Cu" "B.Mask" "B.Paste")
			(net "GND")
		)
	)
	(footprint ""
		(layer "B.Cu")
		(at 25.313386 -190.948564 180)
		(property "Reference" "R307"
			(at 0 0 0)
			(layer "B.SilkS")
			(hide yes)
			(effects
				(font
					(size 1.27 1.27)
				)
				(justify mirror)
			)
		)
		(property "Value" ""
			(at 0 0 0)
			(layer "B.Fab")
			(effects
				(font
					(size 1.27 1.27)
				)
				(justify mirror)
			)
		)
		(duplicate_pad_numbers_are_jumpers no)
		(fp_line
			(start 0.7874 0.4064)
			(end 0.7874 -0.4064)
			(stroke
				(width 0.1524)
				(type default)
			)
			(layer "B.SilkS")
		)
		(fp_line
			(start 0.7874 -0.4064)
			(end -0.7874 -0.4064)
			(stroke
				(width 0.1524)
				(type default)
			)
			(layer "B.SilkS")
		)
		(fp_line
			(start -0.7874 0.4064)
			(end 0.7874 0.4064)
			(stroke
				(width 0.1524)
				(type default)
			)
			(layer "B.SilkS")
		)
		(fp_line
			(start -0.7874 -0.4064)
			(end -0.7874 0.4064)
			(stroke
				(width 0.1524)
				(type default)
			)
			(layer "B.SilkS")
		)
		(fp_line
			(start 0.67945 0.3048)
			(end 0.67945 -0.305054)
			(stroke
				(width 0.1)
				(type default)
			)
			(layer "B.Fab")
		)
		(fp_line
			(start 0.67945 -0.305054)
			(end 0.12065 -0.305054)
			(stroke
				(width 0.1)
				(type default)
			)
			(layer "B.Fab")
		)
		(fp_line
			(start 0.12065 0.3048)
			(end 0.67945 0.3048)
			(stroke
				(width 0.1)
				(type default)
			)
			(layer "B.Fab")
		)
		(fp_line
			(start 0.12065 0.2794)
			(end 0.12065 0.3048)
			(stroke
				(width 0.1)
				(type default)
			)
			(layer "B.Fab")
		)
		(fp_line
			(start 0.12065 -0.2794)
			(end -0.12065 -0.2794)
			(stroke
				(width 0.1)
				(type default)
			)
			(layer "B.Fab")
		)
		(fp_line
			(start 0.12065 -0.305054)
			(end 0.12065 -0.2794)
			(stroke
				(width 0.1)
				(type default)
			)
			(layer "B.Fab")
		)
		(fp_line
			(start -0.120396 0.3048)
			(end -0.120396 0.2794)
			(stroke
				(width 0.1)
				(type default)
			)
			(layer "B.Fab")
		)
		(fp_line
			(start -0.120396 0.2794)
			(end 0.12065 0.2794)
			(stroke
				(width 0.1)
				(type default)
			)
			(layer "B.Fab")
		)
		(fp_line
			(start -0.12065 -0.2794)
			(end -0.12065 -0.3048)
			(stroke
				(width 0.1)
				(type default)
			)
			(layer "B.Fab")
		)
		(fp_line
			(start -0.12065 -0.3048)
			(end -0.67945 -0.3048)
			(stroke
				(width 0.1)
				(type default)
			)
			(layer "B.Fab")
		)
		(fp_line
			(start -0.67945 0.3048)
			(end -0.120396 0.3048)
			(stroke
				(width 0.1)
				(type default)
			)
			(layer "B.Fab")
		)
		(fp_line
			(start -0.67945 -0.3048)
			(end -0.67945 0.3048)
			(stroke
				(width 0.1)
				(type default)
			)
			(layer "B.Fab")
		)
		(pad "1" smd circle
			(at 0.40005 0)
			(size 0 0)
			(layers "B.Cu" "B.Mask" "B.Paste")
			(net "PWRGD_CHE_CPU1_DIMM")
		)
		(pad "2" smd circle
			(at -0.40005 0)
			(size 0 0)
			(layers "B.Cu" "B.Mask" "B.Paste")
			(net "PWRGD_CHAF_CPU1")
		)
	)
	(footprint ""
		(layer "B.Cu")
		(at 248.539 -332.105)
		(property "Reference" "C365"
			(at 0 0 0)
			(layer "B.SilkS")
			(hide yes)
			(effects
				(font
					(size 1.27 1.27)
				)
				(justify mirror)
			)
		)
		(property "Value" ""
			(at 0 0 0)
			(layer "B.Fab")
			(effects
				(font
					(size 1.27 1.27)
				)
				(justify mirror)
			)
		)
		(duplicate_pad_numbers_are_jumpers no)
		(fp_line
			(start -0.299974 -0.150114)
			(end -0.299974 0.150114)
			(stroke
				(width 0.1)
				(type default)
			)
			(layer "B.Fab")
		)
		(fp_line
			(start -0.299974 0.150114)
			(end 0.299974 0.150114)
			(stroke
				(width 0.1)
				(type default)
			)
			(layer "B.Fab")
		)
		(fp_line
			(start 0.299974 -0.150114)
			(end -0.299974 -0.150114)
			(stroke
				(width 0.1)
				(type default)
			)
			(layer "B.Fab")
		)
		(fp_line
			(start 0.299974 0.150114)
			(end 0.299974 -0.150114)
			(stroke
				(width 0.1)
				(type default)
			)
			(layer "B.Fab")
		)
		(pad "1" smd rect
			(at 0.2667 0 180)
			(size 0.3048 0.381)
			(layers "B.Cu" "B.Mask" "B.Paste")
			(net "P1V8_AUX")
		)
		(pad "2" smd rect
			(at -0.2667 0 180)
			(size 0.3048 0.381)
			(layers "B.Cu" "B.Mask" "B.Paste")
			(net "GND")
		)
	)
	(footprint ""
		(layer "B.Cu")
		(at 114.086386 -249.368564)
		(property "Reference" "C2338"
			(at 0 0 0)
			(layer "B.SilkS")
			(hide yes)
			(effects
				(font
					(size 1.27 1.27)
				)
				(justify mirror)
			)
		)
		(property "Value" ""
			(at 0 0 0)
			(layer "B.Fab")
			(effects
				(font
					(size 1.27 1.27)
				)
				(justify mirror)
			)
		)
		(duplicate_pad_numbers_are_jumpers no)
		(fp_line
			(start -0.7874 -0.4064)
			(end -0.7874 0.4064)
			(stroke
				(width 0.1524)
				(type default)
			)
			(layer "B.SilkS")
		)
		(fp_line
			(start -0.7874 0.4064)
			(end 0.7874 0.4064)
			(stroke
				(width 0.1524)
				(type default)
			)
			(layer "B.SilkS")
		)
		(fp_line
			(start 0.7874 -0.4064)
			(end -0.7874 -0.4064)
			(stroke
				(width 0.1524)
				(type default)
			)
			(layer "B.SilkS")
		)
		(fp_line
			(start 0.7874 0.4064)
			(end 0.7874 -0.4064)
			(stroke
				(width 0.1524)
				(type default)
			)
			(layer "B.SilkS")
		)
		(fp_line
			(start -0.67945 -0.3048)
			(end -0.67945 0.3048)
			(stroke
				(width 0.1)
				(type default)
			)
			(layer "B.Fab")
		)
		(fp_line
			(start -0.67945 0.3048)
			(end -0.120396 0.3048)
			(stroke
				(width 0.1)
				(type default)
			)
			(layer "B.Fab")
		)
		(fp_line
			(start -0.12065 -0.3048)
			(end -0.67945 -0.3048)
			(stroke
				(width 0.1)
				(type default)
			)
			(layer "B.Fab")
		)
		(fp_line
			(start -0.12065 -0.2794)
			(end -0.12065 -0.3048)
			(stroke
				(width 0.1)
				(type default)
			)
			(layer "B.Fab")
		)
		(fp_line
			(start -0.120396 0.2794)
			(end 0.12065 0.2794)
			(stroke
				(width 0.1)
				(type default)
			)
			(layer "B.Fab")
		)
		(fp_line
			(start -0.120396 0.3048)
			(end -0.120396 0.2794)
			(stroke
				(width 0.1)
				(type default)
			)
			(layer "B.Fab")
		)
		(fp_line
			(start 0.12065 -0.305054)
			(end 0.12065 -0.2794)
			(stroke
				(width 0.1)
				(type default)
			)
			(layer "B.Fab")
		)
		(fp_line
			(start 0.12065 -0.2794)
			(end -0.12065 -0.2794)
			(stroke
				(width 0.1)
				(type default)
			)
			(layer "B.Fab")
		)
		(fp_line
			(start 0.12065 0.2794)
			(end 0.12065 0.3048)
			(stroke
				(width 0.1)
				(type default)
			)
			(layer "B.Fab")
		)
		(fp_line
			(start 0.12065 0.3048)
			(end 0.67945 0.3048)
			(stroke
				(width 0.1)
				(type default)
			)
			(layer "B.Fab")
		)
		(fp_line
			(start 0.67945 -0.305054)
			(end 0.12065 -0.305054)
			(stroke
				(width 0.1)
				(type default)
			)
			(layer "B.Fab")
		)
		(fp_line
			(start 0.67945 0.3048)
			(end 0.67945 -0.305054)
			(stroke
				(width 0.1)
				(type default)
			)
			(layer "B.Fab")
		)
		(pad "1" smd circle
			(at 0.40005 0 180)
			(size 0 0)
			(layers "B.Cu" "B.Mask" "B.Paste")
			(net "PVDDCR_CPU0_P1")
		)
		(pad "2" smd circle
			(at -0.40005 0 180)
			(size 0 0)
			(layers "B.Cu" "B.Mask" "B.Paste")
			(net "GND")
		)
	)
	(footprint ""
		(layer "B.Cu")
		(at 23.577804 -338.08797 -90)
		(property "Reference" "PR378"
			(at 0 0 90)
			(layer "B.SilkS")
			(hide yes)
			(effects
				(font
					(size 1.27 1.27)
				)
				(justify mirror)
			)
		)
		(property "Value" ""
			(at 0 0 90)
			(layer "B.Fab")
			(effects
				(font
					(size 1.27 1.27)
				)
				(justify mirror)
			)
		)
		(duplicate_pad_numbers_are_jumpers no)
		(fp_line
			(start -0.7874 0.4064)
			(end 0.7874 0.4064)
			(stroke
				(width 0.1524)
				(type default)
			)
			(layer "B.SilkS")
		)
		(fp_line
			(start 0.7874 0.4064)
			(end 0.7874 -0.4064)
			(stroke
				(width 0.1524)
				(type default)
			)
			(layer "B.SilkS")
		)
		(fp_line
			(start -0.7874 -0.4064)
			(end -0.7874 0.4064)
			(stroke
				(width 0.1524)
				(type default)
			)
			(layer "B.SilkS")
		)
		(fp_line
			(start 0.7874 -0.4064)
			(end -0.7874 -0.4064)
			(stroke
				(width 0.1524)
				(type default)
			)
			(layer "B.SilkS")
		)
		(fp_line
			(start -0.67945 0.3048)
			(end -0.120396 0.3048)
			(stroke
				(width 0.1)
				(type default)
			)
			(layer "B.Fab")
		)
		(fp_line
			(start -0.120396 0.3048)
			(end -0.120396 0.2794)
			(stroke
				(width 0.1)
				(type default)
			)
			(layer "B.Fab")
		)
		(fp_line
			(start 0.12065 0.3048)
			(end 0.67945 0.3048)
			(stroke
				(width 0.1)
				(type default)
			)
			(layer "B.Fab")
		)
		(fp_line
			(start 0.67945 0.3048)
			(end 0.67945 -0.305054)
			(stroke
				(width 0.1)
				(type default)
			)
			(layer "B.Fab")
		)
		(fp_line
			(start -0.120396 0.2794)
			(end 0.12065 0.2794)
			(stroke
				(width 0.1)
				(type default)
			)
			(layer "B.Fab")
		)
		(fp_line
			(start 0.12065 0.2794)
			(end 0.12065 0.3048)
			(stroke
				(width 0.1)
				(type default)
			)
			(layer "B.Fab")
		)
		(fp_line
			(start -0.12065 -0.2794)
			(end -0.12065 -0.3048)
			(stroke
				(width 0.1)
				(type default)
			)
			(layer "B.Fab")
		)
		(fp_line
			(start 0.12065 -0.2794)
			(end -0.12065 -0.2794)
			(stroke
				(width 0.1)
				(type default)
			)
			(layer "B.Fab")
		)
		(fp_line
			(start -0.67945 -0.3048)
			(end -0.67945 0.3048)
			(stroke
				(width 0.1)
				(type default)
			)
			(layer "B.Fab")
		)
		(fp_line
			(start -0.12065 -0.3048)
			(end -0.67945 -0.3048)
			(stroke
				(width 0.1)
				(type default)
			)
			(layer "B.Fab")
		)
		(fp_line
			(start 0.12065 -0.305054)
			(end 0.12065 -0.2794)
			(stroke
				(width 0.1)
				(type default)
			)
			(layer "B.Fab")
		)
		(fp_line
			(start 0.67945 -0.305054)
			(end 0.12065 -0.305054)
			(stroke
				(width 0.1)
				(type default)
			)
			(layer "B.Fab")
		)
		(pad "1" smd circle
			(at 0.40005 0 90)
			(size 0 0)
			(layers "B.Cu" "B.Mask" "B.Paste")
			(net "PVDDIO_P1")
		)
		(pad "2" smd circle
			(at -0.40005 0 90)
			(size 0 0)
			(layers "B.Cu" "B.Mask" "B.Paste")
			(net "GND")
		)
	)
	(footprint ""
		(layer "B.Cu")
		(at 176.432972 -414.435544 180)
		(property "Reference" "U195"
			(at -2.873502 -2.892298 0)
			(unlocked yes)
			(layer "B.SilkS")
			(effects
				(font
					(size 0.7874 0.5842)
					(thickness 0.1524)
				)
				(justify left mirror)
			)
		)
		(property "Value" ""
			(at 0 0 0)
			(layer "B.Fab")
			(effects
				(font
					(size 1.27 1.27)
				)
				(justify mirror)
			)
		)
		(duplicate_pad_numbers_are_jumpers no)
		(fp_line
			(start 1.3462 1.100074)
			(end 1.3462 -1.100074)
			(stroke
				(width 0.1524)
				(type default)
			)
			(layer "B.SilkS")
		)
		(fp_line
			(start 1.3462 -1.100074)
			(end 0.670052 -1.100074)
			(stroke
				(width 0.1524)
				(type default)
			)
			(layer "B.SilkS")
		)
		(fp_line
			(start 0.670052 -1.100074)
			(end 0 -0.381)
			(stroke
				(width 0.1524)
				(type default)
			)
			(layer "B.SilkS")
		)
		(fp_line
			(start 0 -0.381)
			(end -0.670052 -1.100074)
			(stroke
				(width 0.1524)
				(type default)
			)
			(layer "B.SilkS")
		)
		(fp_line
			(start -0.670052 -1.100074)
			(end -1.3462 -1.100074)
			(stroke
				(width 0.1524)
				(type default)
			)
			(layer "B.SilkS")
		)
		(fp_line
			(start -1.3462 1.100074)
			(end 1.3462 1.100074)
			(stroke
				(width 0.1524)
				(type default)
			)
			(layer "B.SilkS")
		)
		(fp_line
			(start -1.3462 -1.100074)
			(end -1.3462 1.100074)
			(stroke
				(width 0.1524)
				(type default)
			)
			(layer "B.SilkS")
		)
		(fp_poly
			(pts
				(xy 3.007868 -0.33909) (xy 2.990088 -1.100836) (xy 2.237232 -0.702056)
			)
			(stroke
				(width 0)
				(type default)
			)
			(fill yes)
			(layer "B.SilkS")
		)
		(fp_line
			(start 1.100074 0.8001)
			(end 1.100074 -0.8001)
			(stroke
				(width 0.1)
				(type default)
			)
			(layer "B.Fab")
		)
		(fp_line
			(start 1.100074 -0.8001)
			(end 0.670052 -0.8001)
			(stroke
				(width 0.1)
				(type default)
			)
			(layer "B.Fab")
		)
		(fp_line
			(start 0.670052 1.100074)
			(end 0.670052 0.8001)
			(stroke
				(width 0.1)
				(type default)
			)
			(layer "B.Fab")
		)
		(fp_line
			(start 0.670052 0.8001)
			(end 1.100074 0.8001)
			(stroke
				(width 0.1)
				(type default)
			)
			(layer "B.Fab")
		)
		(fp_line
			(start 0.670052 0.8001)
			(end 0.670052 -0.8001)
			(stroke
				(width 0.1)
				(type default)
			)
			(layer "B.Fab")
		)
		(fp_line
			(start 0.670052 -0.8001)
			(end 0.670052 -1.100074)
			(stroke
				(width 0.1)
				(type default)
			)
			(layer "B.Fab")
		)
		(fp_line
			(start 0.670052 -1.100074)
			(end -0.670052 -1.100074)
			(stroke
				(width 0.1)
				(type default)
			)
			(layer "B.Fab")
		)
		(fp_line
			(start -0.670052 1.100074)
			(end 0.670052 1.100074)
			(stroke
				(width 0.1)
				(type default)
			)
			(layer "B.Fab")
		)
		(fp_line
			(start -0.670052 0.8001)
			(end -0.670052 1.100074)
			(stroke
				(width 0.1)
				(type default)
			)
			(layer "B.Fab")
		)
		(fp_line
			(start -0.670052 -0.8001)
			(end -0.670052 0.8001)
			(stroke
				(width 0.1)
				(type default)
			)
			(layer "B.Fab")
		)
		(fp_line
			(start -0.670052 -0.8001)
			(end -1.100074 -0.8001)
			(stroke
				(width 0.1)
				(type default)
			)
			(layer "B.Fab")
		)
		(fp_line
			(start -0.670052 -1.100074)
			(end -0.670052 -0.8001)
			(stroke
				(width 0.1)
				(type default)
			)
			(layer "B.Fab")
		)
		(fp_line
			(start -1.100074 0.8001)
			(end -0.670052 0.8001)
			(stroke
				(width 0.1)
				(type default)
			)
			(layer "B.Fab")
		)
		(fp_line
			(start -1.100074 -0.8001)
			(end -1.100074 0.8001)
			(stroke
				(width 0.1)
				(type default)
			)
			(layer "B.Fab")
		)
		(fp_poly
			(pts
				(xy 1.524 -0.649986) (xy 2.286 -1.030986) (xy 2.286 -0.268986)
			)
			(stroke
				(width 0)
				(type default)
			)
			(fill yes)
			(layer "B.Fab")
		)
		(pad "1" smd rect
			(at 0.94996 -0.649986 90)
			(size 0.4064 0.508)
			(layers "B.Cu" "B.Mask" "B.Paste")
			(net "BMC_MONITER_R")
		)
		(pad "2" smd rect
			(at 0.94996 0 90)
			(size 0.4064 0.508)
			(layers "B.Cu" "B.Mask" "B.Paste")
			(net "GND")
		)
		(pad "3" smd rect
			(at 0.94996 0.649986 90)
			(size 0.4064 0.508)
			(layers "B.Cu" "B.Mask" "B.Paste")
			(net "RST_SWB_BIC_R_N")
		)
		(pad "4" smd rect
			(at -0.94996 0.649986 90)
			(size 0.4064 0.508)
			(layers "B.Cu" "B.Mask" "B.Paste")
			(net "RST_SWB_BIC_BUF_R_N")
		)
		(pad "5" smd rect
			(at -0.94996 0 90)
			(size 0.4064 0.508)
			(layers "B.Cu" "B.Mask" "B.Paste")
			(net "P3V3_AUX")
		)
		(pad "6" smd rect
			(at -0.94996 -0.649986 90)
			(size 0.4064 0.508)
			(layers "B.Cu" "B.Mask" "B.Paste")
			(net "BMC_MONITER_BUF_R")
		)
	)
	(footprint ""
		(layer "B.Cu")
		(at 449.494402 -424.93311 180)
		(property "Reference" "PR6607"
			(at 0 0 0)
			(layer "B.SilkS")
			(hide yes)
			(effects
				(font
					(size 1.27 1.27)
				)
				(justify mirror)
			)
		)
		(property "Value" ""
			(at 0 0 0)
			(layer "B.Fab")
			(effects
				(font
					(size 1.27 1.27)
				)
				(justify mirror)
			)
		)
		(duplicate_pad_numbers_are_jumpers no)
		(fp_line
			(start 0.7874 0.4064)
			(end 0.7874 -0.4064)
			(stroke
				(width 0.1524)
				(type default)
			)
			(layer "B.SilkS")
		)
		(fp_line
			(start 0.7874 -0.4064)
			(end -0.7874 -0.4064)
			(stroke
				(width 0.1524)
				(type default)
			)
			(layer "B.SilkS")
		)
		(fp_line
			(start -0.7874 0.4064)
			(end 0.7874 0.4064)
			(stroke
				(width 0.1524)
				(type default)
			)
			(layer "B.SilkS")
		)
		(fp_line
			(start -0.7874 -0.4064)
			(end -0.7874 0.4064)
			(stroke
				(width 0.1524)
				(type default)
			)
			(layer "B.SilkS")
		)
		(fp_line
			(start 0.67945 0.3048)
			(end 0.67945 -0.305054)
			(stroke
				(width 0.1)
				(type default)
			)
			(layer "B.Fab")
		)
		(fp_line
			(start 0.67945 -0.305054)
			(end 0.12065 -0.305054)
			(stroke
				(width 0.1)
				(type default)
			)
			(layer "B.Fab")
		)
		(fp_line
			(start 0.12065 0.3048)
			(end 0.67945 0.3048)
			(stroke
				(width 0.1)
				(type default)
			)
			(layer "B.Fab")
		)
		(fp_line
			(start 0.12065 0.2794)
			(end 0.12065 0.3048)
			(stroke
				(width 0.1)
				(type default)
			)
			(layer "B.Fab")
		)
		(fp_line
			(start 0.12065 -0.2794)
			(end -0.12065 -0.2794)
			(stroke
				(width 0.1)
				(type default)
			)
			(layer "B.Fab")
		)
		(fp_line
			(start 0.12065 -0.305054)
			(end 0.12065 -0.2794)
			(stroke
				(width 0.1)
				(type default)
			)
			(layer "B.Fab")
		)
		(fp_line
			(start -0.120396 0.3048)
			(end -0.120396 0.2794)
			(stroke
				(width 0.1)
				(type default)
			)
			(layer "B.Fab")
		)
		(fp_line
			(start -0.120396 0.2794)
			(end 0.12065 0.2794)
			(stroke
				(width 0.1)
				(type default)
			)
			(layer "B.Fab")
		)
		(fp_line
			(start -0.12065 -0.2794)
			(end -0.12065 -0.3048)
			(stroke
				(width 0.1)
				(type default)
			)
			(layer "B.Fab")
		)
		(fp_line
			(start -0.12065 -0.3048)
			(end -0.67945 -0.3048)
			(stroke
				(width 0.1)
				(type default)
			)
			(layer "B.Fab")
		)
		(fp_line
			(start -0.67945 0.3048)
			(end -0.120396 0.3048)
			(stroke
				(width 0.1)
				(type default)
			)
			(layer "B.Fab")
		)
		(fp_line
			(start -0.67945 -0.3048)
			(end -0.67945 0.3048)
			(stroke
				(width 0.1)
				(type default)
			)
			(layer "B.Fab")
		)
		(pad "1" smd circle
			(at 0.40005 0)
			(size 0 0)
			(layers "B.Cu" "B.Mask" "B.Paste")
			(net "P0V9_RETIMER_CPU0_VINSEN")
		)
		(pad "2" smd circle
			(at -0.40005 0)
			(size 0 0)
			(layers "B.Cu" "B.Mask" "B.Paste")
			(net "GND")
		)
	)
	(footprint ""
		(layer "B.Cu")
		(at 84.71916 -390.560052 90)
		(property "Reference" "C318"
			(at 0 0 90)
			(layer "B.SilkS")
			(hide yes)
			(effects
				(font
					(size 1.27 1.27)
				)
				(justify mirror)
			)
		)
		(property "Value" ""
			(at 0 0 90)
			(layer "B.Fab")
			(effects
				(font
					(size 1.27 1.27)
				)
				(justify mirror)
			)
		)
		(duplicate_pad_numbers_are_jumpers no)
		(fp_line
			(start 0.7874 -0.4064)
			(end -0.7874 -0.4064)
			(stroke
				(width 0.1524)
				(type default)
			)
			(layer "B.SilkS")
		)
		(fp_line
			(start -0.7874 -0.4064)
			(end -0.7874 0.4064)
			(stroke
				(width 0.1524)
				(type default)
			)
			(layer "B.SilkS")
		)
		(fp_line
			(start 0.7874 0.4064)
			(end 0.7874 -0.4064)
			(stroke
				(width 0.1524)
				(type default)
			)
			(layer "B.SilkS")
		)
		(fp_line
			(start -0.7874 0.4064)
			(end 0.7874 0.4064)
			(stroke
				(width 0.1524)
				(type default)
			)
			(layer "B.SilkS")
		)
		(fp_line
			(start 0.67945 -0.305054)
			(end 0.12065 -0.305054)
			(stroke
				(width 0.1)
				(type default)
			)
			(layer "B.Fab")
		)
		(fp_line
			(start 0.12065 -0.305054)
			(end 0.12065 -0.2794)
			(stroke
				(width 0.1)
				(type default)
			)
			(layer "B.Fab")
		)
		(fp_line
			(start -0.12065 -0.3048)
			(end -0.67945 -0.3048)
			(stroke
				(width 0.1)
				(type default)
			)
			(layer "B.Fab")
		)
		(fp_line
			(start -0.67945 -0.3048)
			(end -0.67945 0.3048)
			(stroke
				(width 0.1)
				(type default)
			)
			(layer "B.Fab")
		)
		(fp_line
			(start 0.12065 -0.2794)
			(end -0.12065 -0.2794)
			(stroke
				(width 0.1)
				(type default)
			)
			(layer "B.Fab")
		)
		(fp_line
			(start -0.12065 -0.2794)
			(end -0.12065 -0.3048)
			(stroke
				(width 0.1)
				(type default)
			)
			(layer "B.Fab")
		)
		(fp_line
			(start 0.12065 0.2794)
			(end 0.12065 0.3048)
			(stroke
				(width 0.1)
				(type default)
			)
			(layer "B.Fab")
		)
		(fp_line
			(start -0.120396 0.2794)
			(end 0.12065 0.2794)
			(stroke
				(width 0.1)
				(type default)
			)
			(layer "B.Fab")
		)
		(fp_line
			(start 0.67945 0.3048)
			(end 0.67945 -0.305054)
			(stroke
				(width 0.1)
				(type default)
			)
			(layer "B.Fab")
		)
		(fp_line
			(start 0.12065 0.3048)
			(end 0.67945 0.3048)
			(stroke
				(width 0.1)
				(type default)
			)
			(layer "B.Fab")
		)
		(fp_line
			(start -0.120396 0.3048)
			(end -0.120396 0.2794)
			(stroke
				(width 0.1)
				(type default)
			)
			(layer "B.Fab")
		)
		(fp_line
			(start -0.67945 0.3048)
			(end -0.120396 0.3048)
			(stroke
				(width 0.1)
				(type default)
			)
			(layer "B.Fab")
		)
		(pad "1" smd circle
			(at 0.40005 0 270)
			(size 0 0)
			(layers "B.Cu" "B.Mask" "B.Paste")
			(net "P0V9_CPU1_RT1_2A")
		)
		(pad "2" smd circle
			(at -0.40005 0 270)
			(size 0 0)
			(layers "B.Cu" "B.Mask" "B.Paste")
			(net "GND")
		)
	)
	(footprint ""
		(layer "B.Cu")
		(at 228.525578 -289.066732 90)
		(property "Reference" "R645"
			(at 0 0 90)
			(layer "B.SilkS")
			(hide yes)
			(effects
				(font
					(size 1.27 1.27)
				)
				(justify mirror)
			)
		)
		(property "Value" ""
			(at 0 0 90)
			(layer "B.Fab")
			(effects
				(font
					(size 1.27 1.27)
				)
				(justify mirror)
			)
		)
		(duplicate_pad_numbers_are_jumpers no)
		(fp_line
			(start 0.7874 -0.4064)
			(end -0.7874 -0.4064)
			(stroke
				(width 0.1524)
				(type default)
			)
			(layer "B.SilkS")
		)
		(fp_line
			(start -0.7874 -0.4064)
			(end -0.7874 0.4064)
			(stroke
				(width 0.1524)
				(type default)
			)
			(layer "B.SilkS")
		)
		(fp_line
			(start 0.7874 0.4064)
			(end 0.7874 -0.4064)
			(stroke
				(width 0.1524)
				(type default)
			)
			(layer "B.SilkS")
		)
		(fp_line
			(start -0.7874 0.4064)
			(end 0.7874 0.4064)
			(stroke
				(width 0.1524)
				(type default)
			)
			(layer "B.SilkS")
		)
		(fp_line
			(start 0.67945 -0.305054)
			(end 0.12065 -0.305054)
			(stroke
				(width 0.1)
				(type default)
			)
			(layer "B.Fab")
		)
		(fp_line
			(start 0.12065 -0.305054)
			(end 0.12065 -0.2794)
			(stroke
				(width 0.1)
				(type default)
			)
			(layer "B.Fab")
		)
		(fp_line
			(start -0.12065 -0.3048)
			(end -0.67945 -0.3048)
			(stroke
				(width 0.1)
				(type default)
			)
			(layer "B.Fab")
		)
		(fp_line
			(start -0.67945 -0.3048)
			(end -0.67945 0.3048)
			(stroke
				(width 0.1)
				(type default)
			)
			(layer "B.Fab")
		)
		(fp_line
			(start 0.12065 -0.2794)
			(end -0.12065 -0.2794)
			(stroke
				(width 0.1)
				(type default)
			)
			(layer "B.Fab")
		)
		(fp_line
			(start -0.12065 -0.2794)
			(end -0.12065 -0.3048)
			(stroke
				(width 0.1)
				(type default)
			)
			(layer "B.Fab")
		)
		(fp_line
			(start 0.12065 0.2794)
			(end 0.12065 0.3048)
			(stroke
				(width 0.1)
				(type default)
			)
			(layer "B.Fab")
		)
		(fp_line
			(start -0.120396 0.2794)
			(end 0.12065 0.2794)
			(stroke
				(width 0.1)
				(type default)
			)
			(layer "B.Fab")
		)
		(fp_line
			(start 0.67945 0.3048)
			(end 0.67945 -0.305054)
			(stroke
				(width 0.1)
				(type default)
			)
			(layer "B.Fab")
		)
		(fp_line
			(start 0.12065 0.3048)
			(end 0.67945 0.3048)
			(stroke
				(width 0.1)
				(type default)
			)
			(layer "B.Fab")
		)
		(fp_line
			(start -0.120396 0.3048)
			(end -0.120396 0.2794)
			(stroke
				(width 0.1)
				(type default)
			)
			(layer "B.Fab")
		)
		(fp_line
			(start -0.67945 0.3048)
			(end -0.120396 0.3048)
			(stroke
				(width 0.1)
				(type default)
			)
			(layer "B.Fab")
		)
		(pad "1" smd circle
			(at 0.40005 0 270)
			(size 0 0)
			(layers "B.Cu" "B.Mask" "B.Paste")
			(net "PWRGD_P1V8_RETIMER_CPU1")
		)
		(pad "2" smd circle
			(at -0.40005 0 270)
			(size 0 0)
			(layers "B.Cu" "B.Mask" "B.Paste")
			(net "FM_PWRGD_P1V8_RETIMER_CPU1")
		)
	)
	(footprint ""
		(layer "B.Cu")
		(at 123.357386 -266.005564)
		(property "Reference" "C3919"
			(at 0 0 0)
			(layer "B.SilkS")
			(hide yes)
			(effects
				(font
					(size 1.27 1.27)
				)
				(justify mirror)
			)
		)
		(property "Value" ""
			(at 0 0 0)
			(layer "B.Fab")
			(effects
				(font
					(size 1.27 1.27)
				)
				(justify mirror)
			)
		)
		(duplicate_pad_numbers_are_jumpers no)
		(fp_line
			(start -0.7874 -0.4064)
			(end -0.7874 0.4064)
			(stroke
				(width 0.1524)
				(type default)
			)
			(layer "B.SilkS")
		)
		(fp_line
			(start -0.7874 0.4064)
			(end 0.7874 0.4064)
			(stroke
				(width 0.1524)
				(type default)
			)
			(layer "B.SilkS")
		)
		(fp_line
			(start 0.7874 -0.4064)
			(end -0.7874 -0.4064)
			(stroke
				(width 0.1524)
				(type default)
			)
			(layer "B.SilkS")
		)
		(fp_line
			(start 0.7874 0.4064)
			(end 0.7874 -0.4064)
			(stroke
				(width 0.1524)
				(type default)
			)
			(layer "B.SilkS")
		)
		(fp_line
			(start -0.67945 -0.3048)
			(end -0.67945 0.3048)
			(stroke
				(width 0.1)
				(type default)
			)
			(layer "B.Fab")
		)
		(fp_line
			(start -0.67945 0.3048)
			(end -0.120396 0.3048)
			(stroke
				(width 0.1)
				(type default)
			)
			(layer "B.Fab")
		)
		(fp_line
			(start -0.12065 -0.3048)
			(end -0.67945 -0.3048)
			(stroke
				(width 0.1)
				(type default)
			)
			(layer "B.Fab")
		)
		(fp_line
			(start -0.12065 -0.2794)
			(end -0.12065 -0.3048)
			(stroke
				(width 0.1)
				(type default)
			)
			(layer "B.Fab")
		)
		(fp_line
			(start -0.120396 0.2794)
			(end 0.12065 0.2794)
			(stroke
				(width 0.1)
				(type default)
			)
			(layer "B.Fab")
		)
		(fp_line
			(start -0.120396 0.3048)
			(end -0.120396 0.2794)
			(stroke
				(width 0.1)
				(type default)
			)
			(layer "B.Fab")
		)
		(fp_line
			(start 0.12065 -0.305054)
			(end 0.12065 -0.2794)
			(stroke
				(width 0.1)
				(type default)
			)
			(layer "B.Fab")
		)
		(fp_line
			(start 0.12065 -0.2794)
			(end -0.12065 -0.2794)
			(stroke
				(width 0.1)
				(type default)
			)
			(layer "B.Fab")
		)
		(fp_line
			(start 0.12065 0.2794)
			(end 0.12065 0.3048)
			(stroke
				(width 0.1)
				(type default)
			)
			(layer "B.Fab")
		)
		(fp_line
			(start 0.12065 0.3048)
			(end 0.67945 0.3048)
			(stroke
				(width 0.1)
				(type default)
			)
			(layer "B.Fab")
		)
		(fp_line
			(start 0.67945 -0.305054)
			(end 0.12065 -0.305054)
			(stroke
				(width 0.1)
				(type default)
			)
			(layer "B.Fab")
		)
		(fp_line
			(start 0.67945 0.3048)
			(end 0.67945 -0.305054)
			(stroke
				(width 0.1)
				(type default)
			)
			(layer "B.Fab")
		)
		(pad "1" smd circle
			(at 0.40005 0 180)
			(size 0 0)
			(layers "B.Cu" "B.Mask" "B.Paste")
			(net "PVDD11_S3_P1")
		)
		(pad "2" smd circle
			(at -0.40005 0 180)
			(size 0 0)
			(layers "B.Cu" "B.Mask" "B.Paste")
			(net "GND")
		)
	)
	(footprint ""
		(layer "B.Cu")
		(at 359.539794 -419.027864 180)
		(property "Reference" "R2838"
			(at 0 0 0)
			(layer "B.SilkS")
			(hide yes)
			(effects
				(font
					(size 1.27 1.27)
				)
				(justify mirror)
			)
		)
		(property "Value" ""
			(at 0 0 0)
			(layer "B.Fab")
			(effects
				(font
					(size 1.27 1.27)
				)
				(justify mirror)
			)
		)
		(duplicate_pad_numbers_are_jumpers no)
		(fp_line
			(start 0.7874 0.4064)
			(end 0.7874 -0.4064)
			(stroke
				(width 0.1524)
				(type default)
			)
			(layer "B.SilkS")
		)
		(fp_line
			(start 0.7874 -0.4064)
			(end -0.7874 -0.4064)
			(stroke
				(width 0.1524)
				(type default)
			)
			(layer "B.SilkS")
		)
		(fp_line
			(start -0.7874 0.4064)
			(end 0.7874 0.4064)
			(stroke
				(width 0.1524)
				(type default)
			)
			(layer "B.SilkS")
		)
		(fp_line
			(start -0.7874 -0.4064)
			(end -0.7874 0.4064)
			(stroke
				(width 0.1524)
				(type default)
			)
			(layer "B.SilkS")
		)
		(fp_line
			(start 0.67945 0.3048)
			(end 0.67945 -0.305054)
			(stroke
				(width 0.1)
				(type default)
			)
			(layer "B.Fab")
		)
		(fp_line
			(start 0.67945 -0.305054)
			(end 0.12065 -0.305054)
			(stroke
				(width 0.1)
				(type default)
			)
			(layer "B.Fab")
		)
		(fp_line
			(start 0.12065 0.3048)
			(end 0.67945 0.3048)
			(stroke
				(width 0.1)
				(type default)
			)
			(layer "B.Fab")
		)
		(fp_line
			(start 0.12065 0.2794)
			(end 0.12065 0.3048)
			(stroke
				(width 0.1)
				(type default)
			)
			(layer "B.Fab")
		)
		(fp_line
			(start 0.12065 -0.2794)
			(end -0.12065 -0.2794)
			(stroke
				(width 0.1)
				(type default)
			)
			(layer "B.Fab")
		)
		(fp_line
			(start 0.12065 -0.305054)
			(end 0.12065 -0.2794)
			(stroke
				(width 0.1)
				(type default)
			)
			(layer "B.Fab")
		)
		(fp_line
			(start -0.120396 0.3048)
			(end -0.120396 0.2794)
			(stroke
				(width 0.1)
				(type default)
			)
			(layer "B.Fab")
		)
		(fp_line
			(start -0.120396 0.2794)
			(end 0.12065 0.2794)
			(stroke
				(width 0.1)
				(type default)
			)
			(layer "B.Fab")
		)
		(fp_line
			(start -0.12065 -0.2794)
			(end -0.12065 -0.3048)
			(stroke
				(width 0.1)
				(type default)
			)
			(layer "B.Fab")
		)
		(fp_line
			(start -0.12065 -0.3048)
			(end -0.67945 -0.3048)
			(stroke
				(width 0.1)
				(type default)
			)
			(layer "B.Fab")
		)
		(fp_line
			(start -0.67945 0.3048)
			(end -0.120396 0.3048)
			(stroke
				(width 0.1)
				(type default)
			)
			(layer "B.Fab")
		)
		(fp_line
			(start -0.67945 -0.3048)
			(end -0.67945 0.3048)
			(stroke
				(width 0.1)
				(type default)
			)
			(layer "B.Fab")
		)
		(pad "1" smd circle
			(at 0.40005 0)
			(size 0 0)
			(layers "B.Cu" "B.Mask" "B.Paste")
			(net "FM_SWB_PWRGD")
		)
		(pad "2" smd circle
			(at -0.40005 0)
			(size 0 0)
			(layers "B.Cu" "B.Mask" "B.Paste")
			(net "GND")
		)
	)
	(footprint ""
		(layer "B.Cu")
		(at 58.418476 -338.086954 -90)
		(property "Reference" "PC419_3"
			(at 0 0 90)
			(layer "B.SilkS")
			(hide yes)
			(effects
				(font
					(size 1.27 1.27)
				)
				(justify mirror)
			)
		)
		(property "Value" ""
			(at 0 0 90)
			(layer "B.Fab")
			(effects
				(font
					(size 1.27 1.27)
				)
				(justify mirror)
			)
		)
		(duplicate_pad_numbers_are_jumpers no)
		(fp_line
			(start -1.524 0.762)
			(end 1.524 0.762)
			(stroke
				(width 0.1524)
				(type default)
			)
			(layer "B.SilkS")
		)
		(fp_line
			(start 1.524 0.762)
			(end 1.524 -0.762)
			(stroke
				(width 0.1524)
				(type default)
			)
			(layer "B.SilkS")
		)
		(fp_line
			(start -1.524 -0.762)
			(end -1.524 0.762)
			(stroke
				(width 0.1524)
				(type default)
			)
			(layer "B.SilkS")
		)
		(fp_line
			(start 1.524 -0.762)
			(end -1.524 -0.762)
			(stroke
				(width 0.1524)
				(type default)
			)
			(layer "B.SilkS")
		)
		(fp_line
			(start -1.1049 0.724916)
			(end -1.1049 -0.724916)
			(stroke
				(width 0.1)
				(type default)
			)
			(layer "B.Fab")
		)
		(fp_line
			(start 1.1049 0.724916)
			(end -1.1049 0.724916)
			(stroke
				(width 0.1)
				(type default)
			)
			(layer "B.Fab")
		)
		(fp_line
			(start -1.1049 -0.724916)
			(end 1.1049 -0.724916)
			(stroke
				(width 0.1)
				(type default)
			)
			(layer "B.Fab")
		)
		(fp_line
			(start 1.1049 -0.724916)
			(end 1.1049 0.724916)
			(stroke
				(width 0.1)
				(type default)
			)
			(layer "B.Fab")
		)
		(pad "1" smd rect
			(at 0.889 0 270)
			(size 1.016 1.27)
			(layers "B.Cu" "B.Mask" "B.Paste")
			(net "PVDDCR_CPU1_P1")
		)
		(pad "2" smd rect
			(at -0.889 0 270)
			(size 1.016 1.27)
			(layers "B.Cu" "B.Mask" "B.Paste")
			(net "GND")
		)
	)
	(footprint ""
		(layer "B.Cu")
		(at 386.350256 -182.867554 -90)
		(property "Reference" "PC559_4"
			(at 0 0 90)
			(layer "B.SilkS")
			(hide yes)
			(effects
				(font
					(size 1.27 1.27)
				)
				(justify mirror)
			)
		)
		(property "Value" ""
			(at 0 0 90)
			(layer "B.Fab")
			(effects
				(font
					(size 1.27 1.27)
				)
				(justify mirror)
			)
		)
		(duplicate_pad_numbers_are_jumpers no)
		(fp_line
			(start -1.524 0.762)
			(end 1.524 0.762)
			(stroke
				(width 0.1524)
				(type default)
			)
			(layer "B.SilkS")
		)
		(fp_line
			(start 1.524 0.762)
			(end 1.524 -0.762)
			(stroke
				(width 0.1524)
				(type default)
			)
			(layer "B.SilkS")
		)
		(fp_line
			(start -1.524 -0.762)
			(end -1.524 0.762)
			(stroke
				(width 0.1524)
				(type default)
			)
			(layer "B.SilkS")
		)
		(fp_line
			(start 1.524 -0.762)
			(end -1.524 -0.762)
			(stroke
				(width 0.1524)
				(type default)
			)
			(layer "B.SilkS")
		)
		(fp_line
			(start -1.1049 0.724916)
			(end -1.1049 -0.724916)
			(stroke
				(width 0.1)
				(type default)
			)
			(layer "B.Fab")
		)
		(fp_line
			(start 1.1049 0.724916)
			(end -1.1049 0.724916)
			(stroke
				(width 0.1)
				(type default)
			)
			(layer "B.Fab")
		)
		(fp_line
			(start -1.1049 -0.724916)
			(end 1.1049 -0.724916)
			(stroke
				(width 0.1)
				(type default)
			)
			(layer "B.Fab")
		)
		(fp_line
			(start 1.1049 -0.724916)
			(end 1.1049 0.724916)
			(stroke
				(width 0.1)
				(type default)
			)
			(layer "B.Fab")
		)
		(pad "1" smd rect
			(at 0.889 0 270)
			(size 1.016 1.27)
			(layers "B.Cu" "B.Mask" "B.Paste")
			(net "SW_P12V_AUX_PVDDCR_CPU0_P0_FLT")
		)
		(pad "2" smd rect
			(at -0.889 0 270)
			(size 1.016 1.27)
			(layers "B.Cu" "B.Mask" "B.Paste")
			(net "GND")
		)
	)
	(footprint ""
		(layer "B.Cu")
		(at 99.128834 -250.892564 180)
		(property "Reference" "C2669"
			(at 0 0 0)
			(layer "B.SilkS")
			(hide yes)
			(effects
				(font
					(size 1.27 1.27)
				)
				(justify mirror)
			)
		)
		(property "Value" ""
			(at 0 0 0)
			(layer "B.Fab")
			(effects
				(font
					(size 1.27 1.27)
				)
				(justify mirror)
			)
		)
		(duplicate_pad_numbers_are_jumpers no)
		(fp_line
			(start 0.7874 0.4064)
			(end 0.7874 -0.4064)
			(stroke
				(width 0.1524)
				(type default)
			)
			(layer "B.SilkS")
		)
		(fp_line
			(start 0.7874 -0.4064)
			(end -0.7874 -0.4064)
			(stroke
				(width 0.1524)
				(type default)
			)
			(layer "B.SilkS")
		)
		(fp_line
			(start -0.7874 0.4064)
			(end 0.7874 0.4064)
			(stroke
				(width 0.1524)
				(type default)
			)
			(layer "B.SilkS")
		)
		(fp_line
			(start -0.7874 -0.4064)
			(end -0.7874 0.4064)
			(stroke
				(width 0.1524)
				(type default)
			)
			(layer "B.SilkS")
		)
		(fp_line
			(start 0.67945 0.3048)
			(end 0.67945 -0.305054)
			(stroke
				(width 0.1)
				(type default)
			)
			(layer "B.Fab")
		)
		(fp_line
			(start 0.67945 -0.305054)
			(end 0.12065 -0.305054)
			(stroke
				(width 0.1)
				(type default)
			)
			(layer "B.Fab")
		)
		(fp_line
			(start 0.12065 0.3048)
			(end 0.67945 0.3048)
			(stroke
				(width 0.1)
				(type default)
			)
			(layer "B.Fab")
		)
		(fp_line
			(start 0.12065 0.2794)
			(end 0.12065 0.3048)
			(stroke
				(width 0.1)
				(type default)
			)
			(layer "B.Fab")
		)
		(fp_line
			(start 0.12065 -0.2794)
			(end -0.12065 -0.2794)
			(stroke
				(width 0.1)
				(type default)
			)
			(layer "B.Fab")
		)
		(fp_line
			(start 0.12065 -0.305054)
			(end 0.12065 -0.2794)
			(stroke
				(width 0.1)
				(type default)
			)
			(layer "B.Fab")
		)
		(fp_line
			(start -0.120396 0.3048)
			(end -0.120396 0.2794)
			(stroke
				(width 0.1)
				(type default)
			)
			(layer "B.Fab")
		)
		(fp_line
			(start -0.120396 0.2794)
			(end 0.12065 0.2794)
			(stroke
				(width 0.1)
				(type default)
			)
			(layer "B.Fab")
		)
		(fp_line
			(start -0.12065 -0.2794)
			(end -0.12065 -0.3048)
			(stroke
				(width 0.1)
				(type default)
			)
			(layer "B.Fab")
		)
		(fp_line
			(start -0.12065 -0.3048)
			(end -0.67945 -0.3048)
			(stroke
				(width 0.1)
				(type default)
			)
			(layer "B.Fab")
		)
		(fp_line
			(start -0.67945 0.3048)
			(end -0.120396 0.3048)
			(stroke
				(width 0.1)
				(type default)
			)
			(layer "B.Fab")
		)
		(fp_line
			(start -0.67945 -0.3048)
			(end -0.67945 0.3048)
			(stroke
				(width 0.1)
				(type default)
			)
			(layer "B.Fab")
		)
		(pad "1" smd circle
			(at 0.40005 0)
			(size 0 0)
			(layers "B.Cu" "B.Mask" "B.Paste")
			(net "PVDD18_S5_P1")
		)
		(pad "2" smd circle
			(at -0.40005 0)
			(size 0 0)
			(layers "B.Cu" "B.Mask" "B.Paste")
			(net "GND")
		)
	)
	(footprint ""
		(layer "B.Cu")
		(at 98.464878 -139.93241 90)
		(property "Reference" "PC11"
			(at 0 0 90)
			(layer "B.SilkS")
			(hide yes)
			(effects
				(font
					(size 1.27 1.27)
				)
				(justify mirror)
			)
		)
		(property "Value" ""
			(at 0 0 90)
			(layer "B.Fab")
			(effects
				(font
					(size 1.27 1.27)
				)
				(justify mirror)
			)
		)
		(duplicate_pad_numbers_are_jumpers no)
		(fp_line
			(start 0.7874 -0.4064)
			(end -0.7874 -0.4064)
			(stroke
				(width 0.1524)
				(type default)
			)
			(layer "B.SilkS")
		)
		(fp_line
			(start -0.7874 -0.4064)
			(end -0.7874 0.4064)
			(stroke
				(width 0.1524)
				(type default)
			)
			(layer "B.SilkS")
		)
		(fp_line
			(start 0.7874 0.4064)
			(end 0.7874 -0.4064)
			(stroke
				(width 0.1524)
				(type default)
			)
			(layer "B.SilkS")
		)
		(fp_line
			(start -0.7874 0.4064)
			(end 0.7874 0.4064)
			(stroke
				(width 0.1524)
				(type default)
			)
			(layer "B.SilkS")
		)
		(fp_line
			(start 0.67945 -0.305054)
			(end 0.12065 -0.305054)
			(stroke
				(width 0.1)
				(type default)
			)
			(layer "B.Fab")
		)
		(fp_line
			(start 0.12065 -0.305054)
			(end 0.12065 -0.2794)
			(stroke
				(width 0.1)
				(type default)
			)
			(layer "B.Fab")
		)
		(fp_line
			(start -0.12065 -0.3048)
			(end -0.67945 -0.3048)
			(stroke
				(width 0.1)
				(type default)
			)
			(layer "B.Fab")
		)
		(fp_line
			(start -0.67945 -0.3048)
			(end -0.67945 0.3048)
			(stroke
				(width 0.1)
				(type default)
			)
			(layer "B.Fab")
		)
		(fp_line
			(start 0.12065 -0.2794)
			(end -0.12065 -0.2794)
			(stroke
				(width 0.1)
				(type default)
			)
			(layer "B.Fab")
		)
		(fp_line
			(start -0.12065 -0.2794)
			(end -0.12065 -0.3048)
			(stroke
				(width 0.1)
				(type default)
			)
			(layer "B.Fab")
		)
		(fp_line
			(start 0.12065 0.2794)
			(end 0.12065 0.3048)
			(stroke
				(width 0.1)
				(type default)
			)
			(layer "B.Fab")
		)
		(fp_line
			(start -0.120396 0.2794)
			(end 0.12065 0.2794)
			(stroke
				(width 0.1)
				(type default)
			)
			(layer "B.Fab")
		)
		(fp_line
			(start 0.67945 0.3048)
			(end 0.67945 -0.305054)
			(stroke
				(width 0.1)
				(type default)
			)
			(layer "B.Fab")
		)
		(fp_line
			(start 0.12065 0.3048)
			(end 0.67945 0.3048)
			(stroke
				(width 0.1)
				(type default)
			)
			(layer "B.Fab")
		)
		(fp_line
			(start -0.120396 0.3048)
			(end -0.120396 0.2794)
			(stroke
				(width 0.1)
				(type default)
			)
			(layer "B.Fab")
		)
		(fp_line
			(start -0.67945 0.3048)
			(end -0.120396 0.3048)
			(stroke
				(width 0.1)
				(type default)
			)
			(layer "B.Fab")
		)
		(pad "1" smd circle
			(at 0.40005 0 270)
			(size 0 0)
			(layers "B.Cu" "B.Mask" "B.Paste")
			(net "PVDDCR_CPU0_P1_VCCS")
		)
		(pad "2" smd circle
			(at -0.40005 0 270)
			(size 0 0)
			(layers "B.Cu" "B.Mask" "B.Paste")
			(net "GND")
		)
	)
	(footprint ""
		(layer "B.Cu")
		(at 120.618504 -388.011162 -90)
		(property "Reference" "C451"
			(at 0 0 90)
			(layer "B.SilkS")
			(hide yes)
			(effects
				(font
					(size 1.27 1.27)
				)
				(justify mirror)
			)
		)
		(property "Value" ""
			(at 0 0 90)
			(layer "B.Fab")
			(effects
				(font
					(size 1.27 1.27)
				)
				(justify mirror)
			)
		)
		(duplicate_pad_numbers_are_jumpers no)
		(fp_line
			(start -0.299974 0.150114)
			(end 0.299974 0.150114)
			(stroke
				(width 0.1)
				(type default)
			)
			(layer "B.Fab")
		)
		(fp_line
			(start 0.299974 0.150114)
			(end 0.299974 -0.150114)
			(stroke
				(width 0.1)
				(type default)
			)
			(layer "B.Fab")
		)
		(fp_line
			(start -0.299974 -0.150114)
			(end -0.299974 0.150114)
			(stroke
				(width 0.1)
				(type default)
			)
			(layer "B.Fab")
		)
		(fp_line
			(start 0.299974 -0.150114)
			(end -0.299974 -0.150114)
			(stroke
				(width 0.1)
				(type default)
			)
			(layer "B.Fab")
		)
		(pad "1" smd rect
			(at 0.2667 0 90)
			(size 0.3048 0.381)
			(layers "B.Cu" "B.Mask" "B.Paste")
			(net "P0V9_CPU1_RT_2D")
		)
		(pad "2" smd rect
			(at -0.2667 0 90)
			(size 0.3048 0.381)
			(layers "B.Cu" "B.Mask" "B.Paste")
			(net "GND")
		)
	)
	(footprint ""
		(layer "B.Cu")
		(at 9.181338 -383.051558 -90)
		(property "Reference" "PC6624_1"
			(at 0 0 90)
			(layer "B.SilkS")
			(hide yes)
			(effects
				(font
					(size 1.27 1.27)
				)
				(justify mirror)
			)
		)
		(property "Value" ""
			(at 0 0 90)
			(layer "B.Fab")
			(effects
				(font
					(size 1.27 1.27)
				)
				(justify mirror)
			)
		)
		(duplicate_pad_numbers_are_jumpers no)
		(fp_line
			(start -1.524 0.762)
			(end 1.524 0.762)
			(stroke
				(width 0.1524)
				(type default)
			)
			(layer "B.SilkS")
		)
		(fp_line
			(start 1.524 0.762)
			(end 1.524 -0.762)
			(stroke
				(width 0.1524)
				(type default)
			)
			(layer "B.SilkS")
		)
		(fp_line
			(start -1.524 -0.762)
			(end -1.524 0.762)
			(stroke
				(width 0.1524)
				(type default)
			)
			(layer "B.SilkS")
		)
		(fp_line
			(start 1.524 -0.762)
			(end -1.524 -0.762)
			(stroke
				(width 0.1524)
				(type default)
			)
			(layer "B.SilkS")
		)
		(fp_line
			(start -1.1049 0.724916)
			(end -1.1049 -0.724916)
			(stroke
				(width 0.1)
				(type default)
			)
			(layer "B.Fab")
		)
		(fp_line
			(start 1.1049 0.724916)
			(end -1.1049 0.724916)
			(stroke
				(width 0.1)
				(type default)
			)
			(layer "B.Fab")
		)
		(fp_line
			(start -1.1049 -0.724916)
			(end 1.1049 -0.724916)
			(stroke
				(width 0.1)
				(type default)
			)
			(layer "B.Fab")
		)
		(fp_line
			(start 1.1049 -0.724916)
			(end 1.1049 0.724916)
			(stroke
				(width 0.1)
				(type default)
			)
			(layer "B.Fab")
		)
		(pad "1" smd rect
			(at 0.889 0 270)
			(size 1.016 1.27)
			(layers "B.Cu" "B.Mask" "B.Paste")
			(net "P0V9_CPU1_RT_2D")
		)
		(pad "2" smd rect
			(at -0.889 0 270)
			(size 1.016 1.27)
			(layers "B.Cu" "B.Mask" "B.Paste")
			(net "GND")
		)
	)
	(footprint ""
		(layer "B.Cu")
		(at 161.546286 -388.011162 -90)
		(property "Reference" "C427"
			(at 0 0 90)
			(layer "B.SilkS")
			(hide yes)
			(effects
				(font
					(size 1.27 1.27)
				)
				(justify mirror)
			)
		)
		(property "Value" ""
			(at 0 0 90)
			(layer "B.Fab")
			(effects
				(font
					(size 1.27 1.27)
				)
				(justify mirror)
			)
		)
		(duplicate_pad_numbers_are_jumpers no)
		(fp_line
			(start -0.299974 0.150114)
			(end 0.299974 0.150114)
			(stroke
				(width 0.1)
				(type default)
			)
			(layer "B.Fab")
		)
		(fp_line
			(start 0.299974 0.150114)
			(end 0.299974 -0.150114)
			(stroke
				(width 0.1)
				(type default)
			)
			(layer "B.Fab")
		)
		(fp_line
			(start -0.299974 -0.150114)
			(end -0.299974 0.150114)
			(stroke
				(width 0.1)
				(type default)
			)
			(layer "B.Fab")
		)
		(fp_line
			(start 0.299974 -0.150114)
			(end -0.299974 -0.150114)
			(stroke
				(width 0.1)
				(type default)
			)
			(layer "B.Fab")
		)
		(pad "1" smd rect
			(at 0.2667 0 90)
			(size 0.3048 0.381)
			(layers "B.Cu" "B.Mask" "B.Paste")
			(net "P0V9_CPU1_RT2_2A")
		)
		(pad "2" smd rect
			(at -0.2667 0 90)
			(size 0.3048 0.381)
			(layers "B.Cu" "B.Mask" "B.Paste")
			(net "GND")
		)
	)
	(footprint ""
		(layer "B.Cu")
		(at 103.924354 -186.811412 90)
		(property "Reference" "PC303_4"
			(at 0 0 90)
			(layer "B.SilkS")
			(hide yes)
			(effects
				(font
					(size 1.27 1.27)
				)
				(justify mirror)
			)
		)
		(property "Value" ""
			(at 0 0 90)
			(layer "B.Fab")
			(effects
				(font
					(size 1.27 1.27)
				)
				(justify mirror)
			)
		)
		(duplicate_pad_numbers_are_jumpers no)
		(fp_line
			(start 1.524 -0.762)
			(end -1.524 -0.762)
			(stroke
				(width 0.1524)
				(type default)
			)
			(layer "B.SilkS")
		)
		(fp_line
			(start -1.524 -0.762)
			(end -1.524 0.762)
			(stroke
				(width 0.1524)
				(type default)
			)
			(layer "B.SilkS")
		)
		(fp_line
			(start 1.524 0.762)
			(end 1.524 -0.762)
			(stroke
				(width 0.1524)
				(type default)
			)
			(layer "B.SilkS")
		)
		(fp_line
			(start -1.524 0.762)
			(end 1.524 0.762)
			(stroke
				(width 0.1524)
				(type default)
			)
			(layer "B.SilkS")
		)
		(fp_line
			(start 1.1049 -0.724916)
			(end 1.1049 0.724916)
			(stroke
				(width 0.1)
				(type default)
			)
			(layer "B.Fab")
		)
		(fp_line
			(start -1.1049 -0.724916)
			(end 1.1049 -0.724916)
			(stroke
				(width 0.1)
				(type default)
			)
			(layer "B.Fab")
		)
		(fp_line
			(start 1.1049 0.724916)
			(end -1.1049 0.724916)
			(stroke
				(width 0.1)
				(type default)
			)
			(layer "B.Fab")
		)
		(fp_line
			(start -1.1049 0.724916)
			(end -1.1049 -0.724916)
			(stroke
				(width 0.1)
				(type default)
			)
			(layer "B.Fab")
		)
		(pad "1" smd rect
			(at 0.889 0 90)
			(size 1.016 1.27)
			(layers "B.Cu" "B.Mask" "B.Paste")
			(net "PVDDCR_CPU0_P1")
		)
		(pad "2" smd rect
			(at -0.889 0 90)
			(size 1.016 1.27)
			(layers "B.Cu" "B.Mask" "B.Paste")
			(net "GND")
		)
	)
	(footprint ""
		(layer "B.Cu")
		(at 276.520402 -76.110084 180)
		(property "Reference" ""
			(at 0 0 0)
			(layer "B.SilkS")
			(hide yes)
			(effects
				(font
					(size 1.27 1.27)
				)
				(justify mirror)
			)
		)
		(property "Value" ""
			(at 0 0 0)
			(layer "B.Fab")
			(effects
				(font
					(size 1.27 1.27)
				)
				(justify mirror)
			)
		)
		(duplicate_pad_numbers_are_jumpers no)
		(pad "1" smd circle
			(at 0 0)
			(size 0.9906 0.9906)
			(layers "B.Cu" "B.Mask" "B.Paste")
			(net "Net_2235")
		)
		(zone
			(layer "B.Cu")
			(hatch none 0.5)
			(connect_pads
				(clearance 0)
			)
			(min_thickness 0.25)
			(keepout
				(tracks not_allowed)
				(vias allowed)
				(pads allowed)
				(copperpour not_allowed)
				(footprints allowed)
			)
			(placement
				(enabled no)
				(sheetname "")
			)
			(fill
				(thermal_gap 0.5)
				(thermal_bridge_width 0.5)
				(island_removal_mode 0)
			)
			(polygon
				(pts
					(arc
						(start 278.146002 -76.110084)
						(mid 274.894802 -76.110084)
						(end 278.146002 -76.110084)
					)
				)
			)
		)
	)
	(footprint ""
		(layer "B.Cu")
		(at 452.957184 -65.768982 90)
		(property "Reference" "PC1868"
			(at 0 0 90)
			(layer "B.SilkS")
			(hide yes)
			(effects
				(font
					(size 1.27 1.27)
				)
				(justify mirror)
			)
		)
		(property "Value" ""
			(at 0 0 90)
			(layer "B.Fab")
			(effects
				(font
					(size 1.27 1.27)
				)
				(justify mirror)
			)
		)
		(duplicate_pad_numbers_are_jumpers no)
		(fp_line
			(start 1.524 -0.762)
			(end -1.524 -0.762)
			(stroke
				(width 0.1524)
				(type default)
			)
			(layer "B.SilkS")
		)
		(fp_line
			(start -1.524 -0.762)
			(end -1.524 0.762)
			(stroke
				(width 0.1524)
				(type default)
			)
			(layer "B.SilkS")
		)
		(fp_line
			(start 1.524 0.762)
			(end 1.524 -0.762)
			(stroke
				(width 0.1524)
				(type default)
			)
			(layer "B.SilkS")
		)
		(fp_line
			(start -1.524 0.762)
			(end 1.524 0.762)
			(stroke
				(width 0.1524)
				(type default)
			)
			(layer "B.SilkS")
		)
		(fp_line
			(start 1.1049 -0.724916)
			(end 1.1049 0.724916)
			(stroke
				(width 0.1)
				(type default)
			)
			(layer "B.Fab")
		)
		(fp_line
			(start -1.1049 -0.724916)
			(end 1.1049 -0.724916)
			(stroke
				(width 0.1)
				(type default)
			)
			(layer "B.Fab")
		)
		(fp_line
			(start 1.1049 0.724916)
			(end -1.1049 0.724916)
			(stroke
				(width 0.1)
				(type default)
			)
			(layer "B.Fab")
		)
		(fp_line
			(start -1.1049 0.724916)
			(end -1.1049 -0.724916)
			(stroke
				(width 0.1)
				(type default)
			)
			(layer "B.Fab")
		)
		(pad "1" smd rect
			(at 0.889 0 90)
			(size 1.016 1.27)
			(layers "B.Cu" "B.Mask" "B.Paste")
			(net "P3V3_AUX")
		)
		(pad "2" smd rect
			(at -0.889 0 90)
			(size 1.016 1.27)
			(layers "B.Cu" "B.Mask" "B.Paste")
			(net "GND")
		)
	)
	(footprint ""
		(layer "B.Cu")
		(at 101.073204 -424.885358 180)
		(property "Reference" "Q8000"
			(at -1.528826 -2.694686 0)
			(unlocked yes)
			(layer "B.SilkS")
			(effects
				(font
					(size 0.7874 0.5842)
					(thickness 0.1524)
				)
				(justify left mirror)
			)
		)
		(property "Value" ""
			(at 0 0 0)
			(layer "B.Fab")
			(effects
				(font
					(size 1.27 1.27)
				)
				(justify mirror)
			)
		)
		(duplicate_pad_numbers_are_jumpers no)
		(fp_line
			(start 1.332738 1.100074)
			(end 1.332738 -1.100074)
			(stroke
				(width 0.1524)
				(type default)
			)
			(layer "B.SilkS")
		)
		(fp_line
			(start 1.332738 -1.100074)
			(end 0.4826 -1.100074)
			(stroke
				(width 0.1524)
				(type default)
			)
			(layer "B.SilkS")
		)
		(fp_line
			(start 0.4826 -1.100074)
			(end 0 -0.541274)
			(stroke
				(width 0.1524)
				(type default)
			)
			(layer "B.SilkS")
		)
		(fp_line
			(start 0 -0.541274)
			(end -0.4826 -1.100074)
			(stroke
				(width 0.1524)
				(type default)
			)
			(layer "B.SilkS")
		)
		(fp_line
			(start -0.4826 -1.100074)
			(end -1.332738 -1.100074)
			(stroke
				(width 0.1524)
				(type default)
			)
			(layer "B.SilkS")
		)
		(fp_line
			(start -1.332738 1.100074)
			(end 1.332738 1.100074)
			(stroke
				(width 0.1524)
				(type default)
			)
			(layer "B.SilkS")
		)
		(fp_line
			(start -1.332738 -1.100074)
			(end -1.332738 1.100074)
			(stroke
				(width 0.1524)
				(type default)
			)
			(layer "B.SilkS")
		)
		(fp_poly
			(pts
				(xy 2.2352 -0.298958) (xy 2.2352 -1.001014) (xy 1.533144 -0.649986)
			)
			(stroke
				(width 0)
				(type default)
			)
			(fill yes)
			(layer "B.SilkS")
		)
		(fp_line
			(start 0.674878 1.100074)
			(end 0.674878 -1.100074)
			(stroke
				(width 0.1)
				(type default)
			)
			(layer "B.Fab")
		)
		(fp_line
			(start 0.674878 -1.100074)
			(end -0.674878 -1.100074)
			(stroke
				(width 0.1)
				(type default)
			)
			(layer "B.Fab")
		)
		(fp_line
			(start -0.674878 1.100074)
			(end 0.674878 1.100074)
			(stroke
				(width 0.1)
				(type default)
			)
			(layer "B.Fab")
		)
		(fp_line
			(start -0.674878 -1.100074)
			(end -0.674878 1.100074)
			(stroke
				(width 0.1)
				(type default)
			)
			(layer "B.Fab")
		)
		(fp_poly
			(pts
				(xy 2.2352 -0.298958) (xy 2.2352 -1.001014) (xy 1.533144 -0.649986)
			)
			(stroke
				(width 0)
				(type default)
			)
			(fill yes)
			(layer "B.Fab")
		)
		(pad "1" smd rect
			(at 0.94996 -0.649986 270)
			(size 0.4318 0.508)
			(layers "B.Cu" "B.Mask" "B.Paste")
			(net "GND")
		)
		(pad "2" smd rect
			(at 0.94996 0 270)
			(size 0.4318 0.508)
			(layers "B.Cu" "B.Mask" "B.Paste")
			(net "PRSNT_SWB_N")
		)
		(pad "3" smd rect
			(at 0.94996 0.649986 270)
			(size 0.4318 0.508)
			(layers "B.Cu" "B.Mask" "B.Paste")
			(net "PRSNT_SWB_ISO_N")
		)
		(pad "4" smd rect
			(at -0.94996 0.649986 270)
			(size 0.4318 0.508)
			(layers "B.Cu" "B.Mask" "B.Paste")
			(net "GND")
		)
		(pad "5" smd rect
			(at -0.94996 0 270)
			(size 0.4318 0.508)
			(layers "B.Cu" "B.Mask" "B.Paste")
			(net "PRSNT_SWB")
		)
		(pad "6" smd rect
			(at -0.94996 -0.649986 270)
			(size 0.4318 0.508)
			(layers "B.Cu" "B.Mask" "B.Paste")
			(net "PRSNT_SWB")
		)
	)
	(footprint ""
		(layer "B.Cu")
		(at 276.436582 -194.893946 180)
		(property "Reference" "R1572"
			(at 0 0 0)
			(layer "B.SilkS")
			(hide yes)
			(effects
				(font
					(size 1.27 1.27)
				)
				(justify mirror)
			)
		)
		(property "Value" ""
			(at 0 0 0)
			(layer "B.Fab")
			(effects
				(font
					(size 1.27 1.27)
				)
				(justify mirror)
			)
		)
		(duplicate_pad_numbers_are_jumpers no)
		(fp_line
			(start 0.7874 0.4064)
			(end 0.7874 -0.4064)
			(stroke
				(width 0.1524)
				(type default)
			)
			(layer "B.SilkS")
		)
		(fp_line
			(start 0.7874 -0.4064)
			(end -0.7874 -0.4064)
			(stroke
				(width 0.1524)
				(type default)
			)
			(layer "B.SilkS")
		)
		(fp_line
			(start -0.7874 0.4064)
			(end 0.7874 0.4064)
			(stroke
				(width 0.1524)
				(type default)
			)
			(layer "B.SilkS")
		)
		(fp_line
			(start -0.7874 -0.4064)
			(end -0.7874 0.4064)
			(stroke
				(width 0.1524)
				(type default)
			)
			(layer "B.SilkS")
		)
		(fp_line
			(start 0.67945 0.3048)
			(end 0.67945 -0.305054)
			(stroke
				(width 0.1)
				(type default)
			)
			(layer "B.Fab")
		)
		(fp_line
			(start 0.67945 -0.305054)
			(end 0.12065 -0.305054)
			(stroke
				(width 0.1)
				(type default)
			)
			(layer "B.Fab")
		)
		(fp_line
			(start 0.12065 0.3048)
			(end 0.67945 0.3048)
			(stroke
				(width 0.1)
				(type default)
			)
			(layer "B.Fab")
		)
		(fp_line
			(start 0.12065 0.2794)
			(end 0.12065 0.3048)
			(stroke
				(width 0.1)
				(type default)
			)
			(layer "B.Fab")
		)
		(fp_line
			(start 0.12065 -0.2794)
			(end -0.12065 -0.2794)
			(stroke
				(width 0.1)
				(type default)
			)
			(layer "B.Fab")
		)
		(fp_line
			(start 0.12065 -0.305054)
			(end 0.12065 -0.2794)
			(stroke
				(width 0.1)
				(type default)
			)
			(layer "B.Fab")
		)
		(fp_line
			(start -0.120396 0.3048)
			(end -0.120396 0.2794)
			(stroke
				(width 0.1)
				(type default)
			)
			(layer "B.Fab")
		)
		(fp_line
			(start -0.120396 0.2794)
			(end 0.12065 0.2794)
			(stroke
				(width 0.1)
				(type default)
			)
			(layer "B.Fab")
		)
		(fp_line
			(start -0.12065 -0.2794)
			(end -0.12065 -0.3048)
			(stroke
				(width 0.1)
				(type default)
			)
			(layer "B.Fab")
		)
		(fp_line
			(start -0.12065 -0.3048)
			(end -0.67945 -0.3048)
			(stroke
				(width 0.1)
				(type default)
			)
			(layer "B.Fab")
		)
		(fp_line
			(start -0.67945 0.3048)
			(end -0.120396 0.3048)
			(stroke
				(width 0.1)
				(type default)
			)
			(layer "B.Fab")
		)
		(fp_line
			(start -0.67945 -0.3048)
			(end -0.67945 0.3048)
			(stroke
				(width 0.1)
				(type default)
			)
			(layer "B.Fab")
		)
		(pad "1" smd circle
			(at 0.40005 0)
			(size 0 0)
			(layers "B.Cu" "B.Mask" "B.Paste")
			(net "I3C_SPD_DDRAF_CPU0_SCL")
		)
		(pad "2" smd circle
			(at -0.40005 0)
			(size 0 0)
			(layers "B.Cu" "B.Mask" "B.Paste")
			(net "I3C_SPD_DDRE_CPU0_SCL")
		)
	)
	(footprint ""
		(layer "B.Cu")
		(at 33.44545 -426.850302 180)
		(property "Reference" "C1866"
			(at 0 0 0)
			(layer "B.SilkS")
			(hide yes)
			(effects
				(font
					(size 1.27 1.27)
				)
				(justify mirror)
			)
		)
		(property "Value" ""
			(at 0 0 0)
			(layer "B.Fab")
			(effects
				(font
					(size 1.27 1.27)
				)
				(justify mirror)
			)
		)
		(duplicate_pad_numbers_are_jumpers no)
		(fp_line
			(start 0.7874 0.4064)
			(end 0.7874 -0.4064)
			(stroke
				(width 0.1524)
				(type default)
			)
			(layer "B.SilkS")
		)
		(fp_line
			(start 0.7874 -0.4064)
			(end -0.7874 -0.4064)
			(stroke
				(width 0.1524)
				(type default)
			)
			(layer "B.SilkS")
		)
		(fp_line
			(start -0.7874 0.4064)
			(end 0.7874 0.4064)
			(stroke
				(width 0.1524)
				(type default)
			)
			(layer "B.SilkS")
		)
		(fp_line
			(start -0.7874 -0.4064)
			(end -0.7874 0.4064)
			(stroke
				(width 0.1524)
				(type default)
			)
			(layer "B.SilkS")
		)
		(fp_line
			(start 0.67945 0.3048)
			(end 0.67945 -0.305054)
			(stroke
				(width 0.1)
				(type default)
			)
			(layer "B.Fab")
		)
		(fp_line
			(start 0.67945 -0.305054)
			(end 0.12065 -0.305054)
			(stroke
				(width 0.1)
				(type default)
			)
			(layer "B.Fab")
		)
		(fp_line
			(start 0.12065 0.3048)
			(end 0.67945 0.3048)
			(stroke
				(width 0.1)
				(type default)
			)
			(layer "B.Fab")
		)
		(fp_line
			(start 0.12065 0.2794)
			(end 0.12065 0.3048)
			(stroke
				(width 0.1)
				(type default)
			)
			(layer "B.Fab")
		)
		(fp_line
			(start 0.12065 -0.2794)
			(end -0.12065 -0.2794)
			(stroke
				(width 0.1)
				(type default)
			)
			(layer "B.Fab")
		)
		(fp_line
			(start 0.12065 -0.305054)
			(end 0.12065 -0.2794)
			(stroke
				(width 0.1)
				(type default)
			)
			(layer "B.Fab")
		)
		(fp_line
			(start -0.120396 0.3048)
			(end -0.120396 0.2794)
			(stroke
				(width 0.1)
				(type default)
			)
			(layer "B.Fab")
		)
		(fp_line
			(start -0.120396 0.2794)
			(end 0.12065 0.2794)
			(stroke
				(width 0.1)
				(type default)
			)
			(layer "B.Fab")
		)
		(fp_line
			(start -0.12065 -0.2794)
			(end -0.12065 -0.3048)
			(stroke
				(width 0.1)
				(type default)
			)
			(layer "B.Fab")
		)
		(fp_line
			(start -0.12065 -0.3048)
			(end -0.67945 -0.3048)
			(stroke
				(width 0.1)
				(type default)
			)
			(layer "B.Fab")
		)
		(fp_line
			(start -0.67945 0.3048)
			(end -0.120396 0.3048)
			(stroke
				(width 0.1)
				(type default)
			)
			(layer "B.Fab")
		)
		(fp_line
			(start -0.67945 -0.3048)
			(end -0.67945 0.3048)
			(stroke
				(width 0.1)
				(type default)
			)
			(layer "B.Fab")
		)
		(pad "1" smd circle
			(at 0.40005 0)
			(size 0 0)
			(layers "B.Cu" "B.Mask" "B.Paste")
			(net "P3V3_AUX")
		)
		(pad "2" smd circle
			(at -0.40005 0)
			(size 0 0)
			(layers "B.Cu" "B.Mask" "B.Paste")
			(net "GND")
		)
	)
	(footprint ""
		(layer "B.Cu")
		(at 244.099842 -382.936242 90)
		(property "Reference" "PC1751"
			(at 0 0 90)
			(layer "B.SilkS")
			(hide yes)
			(effects
				(font
					(size 1.27 1.27)
				)
				(justify mirror)
			)
		)
		(property "Value" ""
			(at 0 0 90)
			(layer "B.Fab")
			(effects
				(font
					(size 1.27 1.27)
				)
				(justify mirror)
			)
		)
		(duplicate_pad_numbers_are_jumpers no)
		(fp_line
			(start 0.7874 -0.4064)
			(end -0.7874 -0.4064)
			(stroke
				(width 0.1524)
				(type default)
			)
			(layer "B.SilkS")
		)
		(fp_line
			(start -0.7874 -0.4064)
			(end -0.7874 0.4064)
			(stroke
				(width 0.1524)
				(type default)
			)
			(layer "B.SilkS")
		)
		(fp_line
			(start 0.7874 0.4064)
			(end 0.7874 -0.4064)
			(stroke
				(width 0.1524)
				(type default)
			)
			(layer "B.SilkS")
		)
		(fp_line
			(start -0.7874 0.4064)
			(end 0.7874 0.4064)
			(stroke
				(width 0.1524)
				(type default)
			)
			(layer "B.SilkS")
		)
		(fp_line
			(start 0.67945 -0.305054)
			(end 0.12065 -0.305054)
			(stroke
				(width 0.1)
				(type default)
			)
			(layer "B.Fab")
		)
		(fp_line
			(start 0.12065 -0.305054)
			(end 0.12065 -0.2794)
			(stroke
				(width 0.1)
				(type default)
			)
			(layer "B.Fab")
		)
		(fp_line
			(start -0.12065 -0.3048)
			(end -0.67945 -0.3048)
			(stroke
				(width 0.1)
				(type default)
			)
			(layer "B.Fab")
		)
		(fp_line
			(start -0.67945 -0.3048)
			(end -0.67945 0.3048)
			(stroke
				(width 0.1)
				(type default)
			)
			(layer "B.Fab")
		)
		(fp_line
			(start 0.12065 -0.2794)
			(end -0.12065 -0.2794)
			(stroke
				(width 0.1)
				(type default)
			)
			(layer "B.Fab")
		)
		(fp_line
			(start -0.12065 -0.2794)
			(end -0.12065 -0.3048)
			(stroke
				(width 0.1)
				(type default)
			)
			(layer "B.Fab")
		)
		(fp_line
			(start 0.12065 0.2794)
			(end 0.12065 0.3048)
			(stroke
				(width 0.1)
				(type default)
			)
			(layer "B.Fab")
		)
		(fp_line
			(start -0.120396 0.2794)
			(end 0.12065 0.2794)
			(stroke
				(width 0.1)
				(type default)
			)
			(layer "B.Fab")
		)
		(fp_line
			(start 0.67945 0.3048)
			(end 0.67945 -0.305054)
			(stroke
				(width 0.1)
				(type default)
			)
			(layer "B.Fab")
		)
		(fp_line
			(start 0.12065 0.3048)
			(end 0.67945 0.3048)
			(stroke
				(width 0.1)
				(type default)
			)
			(layer "B.Fab")
		)
		(fp_line
			(start -0.120396 0.3048)
			(end -0.120396 0.2794)
			(stroke
				(width 0.1)
				(type default)
			)
			(layer "B.Fab")
		)
		(fp_line
			(start -0.67945 0.3048)
			(end -0.120396 0.3048)
			(stroke
				(width 0.1)
				(type default)
			)
			(layer "B.Fab")
		)
		(pad "1" smd circle
			(at 0.40005 0 270)
			(size 0 0)
			(layers "B.Cu" "B.Mask" "B.Paste")
			(net "P12V_HSC_GATE_RC")
		)
		(pad "2" smd circle
			(at -0.40005 0 270)
			(size 0 0)
			(layers "B.Cu" "B.Mask" "B.Paste")
			(net "P12V_HSC_GATE2")
		)
	)
	(footprint ""
		(layer "B.Cu")
		(at 231.775 -243.2431 -90)
		(property "Reference" "R325"
			(at 0 0 90)
			(layer "B.SilkS")
			(hide yes)
			(effects
				(font
					(size 1.27 1.27)
				)
				(justify mirror)
			)
		)
		(property "Value" ""
			(at 0 0 90)
			(layer "B.Fab")
			(effects
				(font
					(size 1.27 1.27)
				)
				(justify mirror)
			)
		)
		(duplicate_pad_numbers_are_jumpers no)
		(fp_line
			(start -0.7874 0.4064)
			(end 0.7874 0.4064)
			(stroke
				(width 0.1524)
				(type default)
			)
			(layer "B.SilkS")
		)
		(fp_line
			(start 0.7874 0.4064)
			(end 0.7874 -0.4064)
			(stroke
				(width 0.1524)
				(type default)
			)
			(layer "B.SilkS")
		)
		(fp_line
			(start -0.7874 -0.4064)
			(end -0.7874 0.4064)
			(stroke
				(width 0.1524)
				(type default)
			)
			(layer "B.SilkS")
		)
		(fp_line
			(start 0.7874 -0.4064)
			(end -0.7874 -0.4064)
			(stroke
				(width 0.1524)
				(type default)
			)
			(layer "B.SilkS")
		)
		(fp_line
			(start -0.67945 0.3048)
			(end -0.120396 0.3048)
			(stroke
				(width 0.1)
				(type default)
			)
			(layer "B.Fab")
		)
		(fp_line
			(start -0.120396 0.3048)
			(end -0.120396 0.2794)
			(stroke
				(width 0.1)
				(type default)
			)
			(layer "B.Fab")
		)
		(fp_line
			(start 0.12065 0.3048)
			(end 0.67945 0.3048)
			(stroke
				(width 0.1)
				(type default)
			)
			(layer "B.Fab")
		)
		(fp_line
			(start 0.67945 0.3048)
			(end 0.67945 -0.305054)
			(stroke
				(width 0.1)
				(type default)
			)
			(layer "B.Fab")
		)
		(fp_line
			(start -0.120396 0.2794)
			(end 0.12065 0.2794)
			(stroke
				(width 0.1)
				(type default)
			)
			(layer "B.Fab")
		)
		(fp_line
			(start 0.12065 0.2794)
			(end 0.12065 0.3048)
			(stroke
				(width 0.1)
				(type default)
			)
			(layer "B.Fab")
		)
		(fp_line
			(start -0.12065 -0.2794)
			(end -0.12065 -0.3048)
			(stroke
				(width 0.1)
				(type default)
			)
			(layer "B.Fab")
		)
		(fp_line
			(start 0.12065 -0.2794)
			(end -0.12065 -0.2794)
			(stroke
				(width 0.1)
				(type default)
			)
			(layer "B.Fab")
		)
		(fp_line
			(start -0.67945 -0.3048)
			(end -0.67945 0.3048)
			(stroke
				(width 0.1)
				(type default)
			)
			(layer "B.Fab")
		)
		(fp_line
			(start -0.12065 -0.3048)
			(end -0.67945 -0.3048)
			(stroke
				(width 0.1)
				(type default)
			)
			(layer "B.Fab")
		)
		(fp_line
			(start 0.12065 -0.305054)
			(end 0.12065 -0.2794)
			(stroke
				(width 0.1)
				(type default)
			)
			(layer "B.Fab")
		)
		(fp_line
			(start 0.67945 -0.305054)
			(end 0.12065 -0.305054)
			(stroke
				(width 0.1)
				(type default)
			)
			(layer "B.Fab")
		)
		(pad "1" smd rect
			(at 0.40005 0 270)
			(size 0.4572 0.508)
			(layers "B.Cu" "B.Mask" "B.Paste")
			(net "SMB_CPU0_CPU1_APML_SCL_R2")
		)
		(pad "2" smd rect
			(at -0.40005 0 270)
			(size 0.4572 0.508)
			(layers "B.Cu" "B.Mask" "B.Paste")
			(net "SMB_CPU0_CPU1_APML_MUX2_SCL")
		)
	)
	(footprint ""
		(layer "B.Cu")
		(at 403.032722 -416.899344 90)
		(property "Reference" "C6618"
			(at 0 0 90)
			(layer "B.SilkS")
			(hide yes)
			(effects
				(font
					(size 1.27 1.27)
				)
				(justify mirror)
			)
		)
		(property "Value" ""
			(at 0 0 90)
			(layer "B.Fab")
			(effects
				(font
					(size 1.27 1.27)
				)
				(justify mirror)
			)
		)
		(duplicate_pad_numbers_are_jumpers no)
		(fp_line
			(start 0.299974 -0.150114)
			(end -0.299974 -0.150114)
			(stroke
				(width 0.1)
				(type default)
			)
			(layer "B.Fab")
		)
		(fp_line
			(start -0.299974 -0.150114)
			(end -0.299974 0.150114)
			(stroke
				(width 0.1)
				(type default)
			)
			(layer "B.Fab")
		)
		(fp_line
			(start 0.299974 0.150114)
			(end 0.299974 -0.150114)
			(stroke
				(width 0.1)
				(type default)
			)
			(layer "B.Fab")
		)
		(fp_line
			(start -0.299974 0.150114)
			(end 0.299974 0.150114)
			(stroke
				(width 0.1)
				(type default)
			)
			(layer "B.Fab")
		)
		(pad "1" smd rect
			(at 0.2667 0 270)
			(size 0.3048 0.381)
			(layers "B.Cu" "B.Mask" "B.Paste")
			(net "P5E_CPU0_P3_TX_BUF_C_DN<10>")
		)
		(pad "2" smd rect
			(at -0.2667 0 270)
			(size 0.3048 0.381)
			(layers "B.Cu" "B.Mask" "B.Paste")
			(net "P5E_CPU0_P3_TX_BUF_DN<10>")
		)
	)
	(footprint ""
		(layer "B.Cu")
		(at 367.595658 -145.495772 -90)
		(property "Reference" "PQ13"
			(at 1.50114 2.67335 270)
			(unlocked yes)
			(layer "B.SilkS")
			(effects
				(font
					(size 0.7874 0.5842)
					(thickness 0.1524)
				)
				(justify left mirror)
			)
		)
		(property "Value" ""
			(at 0 0 90)
			(layer "B.Fab")
			(effects
				(font
					(size 1.27 1.27)
				)
				(justify mirror)
			)
		)
		(duplicate_pad_numbers_are_jumpers no)
		(fp_line
			(start -1.603248 1.500124)
			(end 1.603248 1.500124)
			(stroke
				(width 0.1524)
				(type default)
			)
			(layer "B.SilkS")
		)
		(fp_line
			(start 1.603248 1.500124)
			(end 1.603248 -1.500124)
			(stroke
				(width 0.1524)
				(type default)
			)
			(layer "B.SilkS")
		)
		(fp_line
			(start -1.603248 -1.500124)
			(end -1.603248 1.500124)
			(stroke
				(width 0.1524)
				(type default)
			)
			(layer "B.SilkS")
		)
		(fp_line
			(start 1.603248 -1.500124)
			(end -1.603248 -1.500124)
			(stroke
				(width 0.1524)
				(type default)
			)
			(layer "B.SilkS")
		)
		(fp_line
			(start -0.700024 1.500124)
			(end -0.700024 0.219964)
			(stroke
				(width 0.1)
				(type default)
			)
			(layer "B.Fab")
		)
		(fp_line
			(start 0.700024 1.500124)
			(end -0.700024 1.500124)
			(stroke
				(width 0.1)
				(type default)
			)
			(layer "B.Fab")
		)
		(fp_line
			(start 0.700024 1.169924)
			(end 0.700024 1.500124)
			(stroke
				(width 0.1)
				(type default)
			)
			(layer "B.Fab")
		)
		(fp_line
			(start 1.249934 1.169924)
			(end 0.700024 1.169924)
			(stroke
				(width 0.1)
				(type default)
			)
			(layer "B.Fab")
		)
		(fp_line
			(start 0.6985 0.729996)
			(end 1.249934 0.729996)
			(stroke
				(width 0.1)
				(type default)
			)
			(layer "B.Fab")
		)
		(fp_line
			(start 1.249934 0.729996)
			(end 1.249934 1.169924)
			(stroke
				(width 0.1)
				(type default)
			)
			(layer "B.Fab")
		)
		(fp_line
			(start -1.249934 0.219964)
			(end -1.249934 -0.219964)
			(stroke
				(width 0.1)
				(type default)
			)
			(layer "B.Fab")
		)
		(fp_line
			(start -0.700024 0.219964)
			(end -1.249934 0.219964)
			(stroke
				(width 0.1)
				(type default)
			)
			(layer "B.Fab")
		)
		(fp_line
			(start -1.249934 -0.219964)
			(end -0.700024 -0.219964)
			(stroke
				(width 0.1)
				(type default)
			)
			(layer "B.Fab")
		)
		(fp_line
			(start -0.700024 -0.219964)
			(end -0.700024 -1.500124)
			(stroke
				(width 0.1)
				(type default)
			)
			(layer "B.Fab")
		)
		(fp_line
			(start 0.6985 -0.729996)
			(end 0.6985 0.729996)
			(stroke
				(width 0.1)
				(type default)
			)
			(layer "B.Fab")
		)
		(fp_line
			(start 1.249934 -0.729996)
			(end 0.6985 -0.729996)
			(stroke
				(width 0.1)
				(type default)
			)
			(layer "B.Fab")
		)
		(fp_line
			(start 0.700024 -1.169924)
			(end 1.249934 -1.169924)
			(stroke
				(width 0.1)
				(type default)
			)
			(layer "B.Fab")
		)
		(fp_line
			(start 1.249934 -1.169924)
			(end 1.249934 -0.729996)
			(stroke
				(width 0.1)
				(type default)
			)
			(layer "B.Fab")
		)
		(fp_line
			(start -0.700024 -1.500124)
			(end 0.700024 -1.500124)
			(stroke
				(width 0.1)
				(type default)
			)
			(layer "B.Fab")
		)
		(fp_line
			(start 0.700024 -1.500124)
			(end 0.700024 -1.169924)
			(stroke
				(width 0.1)
				(type default)
			)
			(layer "B.Fab")
		)
		(fp_rect
			(start 0.700024 1.500124)
			(end -0.700024 -1.500124)
			(stroke
				(width 0)
				(type default)
			)
			(fill no)
			(layer "B.Fab")
		)
		(pad "D" smd rect
			(at -0.999998 0 180)
			(size 0.8128 0.9144)
			(layers "B.Cu" "B.Mask" "B.Paste")
			(net "PVDDCR_SOC_P0_EN//ADDR_CFG")
		)
		(pad "G" smd rect
			(at 0.999998 -0.94996 180)
			(size 0.8128 0.9144)
			(layers "B.Cu" "B.Mask" "B.Paste")
			(net "PVDDCR_SOC_P0_EN_GD")
		)
		(pad "S" smd rect
			(at 0.999998 0.94996 180)
			(size 0.8128 0.9144)
			(layers "B.Cu" "B.Mask" "B.Paste")
			(net "P3V3_AUX")
		)
	)
	(footprint ""
		(layer "B.Cu")
		(at 435.029102 -351.058226 90)
		(property "Reference" "PC212_2"
			(at 0 0 90)
			(layer "B.SilkS")
			(hide yes)
			(effects
				(font
					(size 1.27 1.27)
				)
				(justify mirror)
			)
		)
		(property "Value" ""
			(at 0 0 90)
			(layer "B.Fab")
			(effects
				(font
					(size 1.27 1.27)
				)
				(justify mirror)
			)
		)
		(duplicate_pad_numbers_are_jumpers no)
		(fp_line
			(start 1.524 -0.762)
			(end -1.524 -0.762)
			(stroke
				(width 0.1524)
				(type default)
			)
			(layer "B.SilkS")
		)
		(fp_line
			(start -1.524 -0.762)
			(end -1.524 0.762)
			(stroke
				(width 0.1524)
				(type default)
			)
			(layer "B.SilkS")
		)
		(fp_line
			(start 1.524 0.762)
			(end 1.524 -0.762)
			(stroke
				(width 0.1524)
				(type default)
			)
			(layer "B.SilkS")
		)
		(fp_line
			(start -1.524 0.762)
			(end 1.524 0.762)
			(stroke
				(width 0.1524)
				(type default)
			)
			(layer "B.SilkS")
		)
		(fp_line
			(start 1.1049 -0.724916)
			(end 1.1049 0.724916)
			(stroke
				(width 0.1)
				(type default)
			)
			(layer "B.Fab")
		)
		(fp_line
			(start -1.1049 -0.724916)
			(end 1.1049 -0.724916)
			(stroke
				(width 0.1)
				(type default)
			)
			(layer "B.Fab")
		)
		(fp_line
			(start 1.1049 0.724916)
			(end -1.1049 0.724916)
			(stroke
				(width 0.1)
				(type default)
			)
			(layer "B.Fab")
		)
		(fp_line
			(start -1.1049 0.724916)
			(end -1.1049 -0.724916)
			(stroke
				(width 0.1)
				(type default)
			)
			(layer "B.Fab")
		)
		(pad "1" smd rect
			(at 0.889 0 90)
			(size 1.016 1.27)
			(layers "B.Cu" "B.Mask" "B.Paste")
			(net "SW_P12V_AUX_PVDD11_S3_P0_FLT")
		)
		(pad "2" smd rect
			(at -0.889 0 90)
			(size 1.016 1.27)
			(layers "B.Cu" "B.Mask" "B.Paste")
			(net "GND")
		)
	)
	(footprint ""
		(layer "B.Cu")
		(at 38.002718 -350.660716 -90)
		(property "Reference" "PC628_3"
			(at 0 0 90)
			(layer "B.SilkS")
			(hide yes)
			(effects
				(font
					(size 1.27 1.27)
				)
				(justify mirror)
			)
		)
		(property "Value" ""
			(at 0 0 90)
			(layer "B.Fab")
			(effects
				(font
					(size 1.27 1.27)
				)
				(justify mirror)
			)
		)
		(duplicate_pad_numbers_are_jumpers no)
		(fp_line
			(start -1.524 0.762)
			(end 1.524 0.762)
			(stroke
				(width 0.1524)
				(type default)
			)
			(layer "B.SilkS")
		)
		(fp_line
			(start 1.524 0.762)
			(end 1.524 -0.762)
			(stroke
				(width 0.1524)
				(type default)
			)
			(layer "B.SilkS")
		)
		(fp_line
			(start -1.524 -0.762)
			(end -1.524 0.762)
			(stroke
				(width 0.1524)
				(type default)
			)
			(layer "B.SilkS")
		)
		(fp_line
			(start 1.524 -0.762)
			(end -1.524 -0.762)
			(stroke
				(width 0.1524)
				(type default)
			)
			(layer "B.SilkS")
		)
		(fp_line
			(start -1.1049 0.724916)
			(end -1.1049 -0.724916)
			(stroke
				(width 0.1)
				(type default)
			)
			(layer "B.Fab")
		)
		(fp_line
			(start 1.1049 0.724916)
			(end -1.1049 0.724916)
			(stroke
				(width 0.1)
				(type default)
			)
			(layer "B.Fab")
		)
		(fp_line
			(start -1.1049 -0.724916)
			(end 1.1049 -0.724916)
			(stroke
				(width 0.1)
				(type default)
			)
			(layer "B.Fab")
		)
		(fp_line
			(start 1.1049 -0.724916)
			(end 1.1049 0.724916)
			(stroke
				(width 0.1)
				(type default)
			)
			(layer "B.Fab")
		)
		(pad "1" smd rect
			(at 0.889 0 270)
			(size 1.016 1.27)
			(layers "B.Cu" "B.Mask" "B.Paste")
			(net "SW_P12V_AUX_PVDDIO_P1_FLT")
		)
		(pad "2" smd rect
			(at -0.889 0 270)
			(size 1.016 1.27)
			(layers "B.Cu" "B.Mask" "B.Paste")
			(net "GND")
		)
	)
	(footprint ""
		(layer "B.Cu")
		(at 330.94041 -397.228568)
		(property "Reference" "C637"
			(at 0 0 0)
			(layer "B.SilkS")
			(hide yes)
			(effects
				(font
					(size 1.27 1.27)
				)
				(justify mirror)
			)
		)
		(property "Value" ""
			(at 0 0 0)
			(layer "B.Fab")
			(effects
				(font
					(size 1.27 1.27)
				)
				(justify mirror)
			)
		)
		(duplicate_pad_numbers_are_jumpers no)
		(fp_line
			(start -1.524 -0.762)
			(end -1.524 0.762)
			(stroke
				(width 0.1524)
				(type default)
			)
			(layer "B.SilkS")
		)
		(fp_line
			(start -1.524 0.762)
			(end 1.524 0.762)
			(stroke
				(width 0.1524)
				(type default)
			)
			(layer "B.SilkS")
		)
		(fp_line
			(start 1.524 -0.762)
			(end -1.524 -0.762)
			(stroke
				(width 0.1524)
				(type default)
			)
			(layer "B.SilkS")
		)
		(fp_line
			(start 1.524 0.762)
			(end 1.524 -0.762)
			(stroke
				(width 0.1524)
				(type default)
			)
			(layer "B.SilkS")
		)
		(fp_line
			(start -1.1049 -0.724916)
			(end 1.1049 -0.724916)
			(stroke
				(width 0.1)
				(type default)
			)
			(layer "B.Fab")
		)
		(fp_line
			(start -1.1049 0.724916)
			(end -1.1049 -0.724916)
			(stroke
				(width 0.1)
				(type default)
			)
			(layer "B.Fab")
		)
		(fp_line
			(start 1.1049 -0.724916)
			(end 1.1049 0.724916)
			(stroke
				(width 0.1)
				(type default)
			)
			(layer "B.Fab")
		)
		(fp_line
			(start 1.1049 0.724916)
			(end -1.1049 0.724916)
			(stroke
				(width 0.1)
				(type default)
			)
			(layer "B.Fab")
		)
		(pad "1" smd rect
			(at 0.889 0)
			(size 1.016 1.27)
			(layers "B.Cu" "B.Mask" "B.Paste")
			(net "P0V9_CPU0_RT1_2A")
		)
		(pad "2" smd rect
			(at -0.889 0)
			(size 1.016 1.27)
			(layers "B.Cu" "B.Mask" "B.Paste")
			(net "GND")
		)
	)
	(footprint ""
		(layer "B.Cu")
		(at 371.553486 -182.676038 -90)
		(property "Reference" "PC488_2"
			(at 0 0 90)
			(layer "B.SilkS")
			(hide yes)
			(effects
				(font
					(size 1.27 1.27)
				)
				(justify mirror)
			)
		)
		(property "Value" ""
			(at 0 0 90)
			(layer "B.Fab")
			(effects
				(font
					(size 1.27 1.27)
				)
				(justify mirror)
			)
		)
		(duplicate_pad_numbers_are_jumpers no)
		(fp_line
			(start -1.524 0.762)
			(end 1.524 0.762)
			(stroke
				(width 0.1524)
				(type default)
			)
			(layer "B.SilkS")
		)
		(fp_line
			(start 1.524 0.762)
			(end 1.524 -0.762)
			(stroke
				(width 0.1524)
				(type default)
			)
			(layer "B.SilkS")
		)
		(fp_line
			(start -1.524 -0.762)
			(end -1.524 0.762)
			(stroke
				(width 0.1524)
				(type default)
			)
			(layer "B.SilkS")
		)
		(fp_line
			(start 1.524 -0.762)
			(end -1.524 -0.762)
			(stroke
				(width 0.1524)
				(type default)
			)
			(layer "B.SilkS")
		)
		(fp_line
			(start -1.1049 0.724916)
			(end -1.1049 -0.724916)
			(stroke
				(width 0.1)
				(type default)
			)
			(layer "B.Fab")
		)
		(fp_line
			(start 1.1049 0.724916)
			(end -1.1049 0.724916)
			(stroke
				(width 0.1)
				(type default)
			)
			(layer "B.Fab")
		)
		(fp_line
			(start -1.1049 -0.724916)
			(end 1.1049 -0.724916)
			(stroke
				(width 0.1)
				(type default)
			)
			(layer "B.Fab")
		)
		(fp_line
			(start 1.1049 -0.724916)
			(end 1.1049 0.724916)
			(stroke
				(width 0.1)
				(type default)
			)
			(layer "B.Fab")
		)
		(pad "1" smd rect
			(at 0.889 0 270)
			(size 1.016 1.27)
			(layers "B.Cu" "B.Mask" "B.Paste")
			(net "SW_P12V_AUX_PVDDCR_CPU0_P0_FLT")
		)
		(pad "2" smd rect
			(at -0.889 0 270)
			(size 1.016 1.27)
			(layers "B.Cu" "B.Mask" "B.Paste")
			(net "GND")
		)
	)
	(footprint ""
		(layer "B.Cu")
		(at 156.67101 -16.851122 -90)
		(property "Reference" "R2999"
			(at 0 0 90)
			(layer "B.SilkS")
			(hide yes)
			(effects
				(font
					(size 1.27 1.27)
				)
				(justify mirror)
			)
		)
		(property "Value" ""
			(at 0 0 90)
			(layer "B.Fab")
			(effects
				(font
					(size 1.27 1.27)
				)
				(justify mirror)
			)
		)
		(duplicate_pad_numbers_are_jumpers no)
		(fp_line
			(start -0.7874 0.4064)
			(end 0.7874 0.4064)
			(stroke
				(width 0.1524)
				(type default)
			)
			(layer "B.SilkS")
		)
		(fp_line
			(start 0.7874 0.4064)
			(end 0.7874 -0.4064)
			(stroke
				(width 0.1524)
				(type default)
			)
			(layer "B.SilkS")
		)
		(fp_line
			(start -0.7874 -0.4064)
			(end -0.7874 0.4064)
			(stroke
				(width 0.1524)
				(type default)
			)
			(layer "B.SilkS")
		)
		(fp_line
			(start 0.7874 -0.4064)
			(end -0.7874 -0.4064)
			(stroke
				(width 0.1524)
				(type default)
			)
			(layer "B.SilkS")
		)
		(fp_line
			(start -0.67945 0.3048)
			(end -0.120396 0.3048)
			(stroke
				(width 0.1)
				(type default)
			)
			(layer "B.Fab")
		)
		(fp_line
			(start -0.120396 0.3048)
			(end -0.120396 0.2794)
			(stroke
				(width 0.1)
				(type default)
			)
			(layer "B.Fab")
		)
		(fp_line
			(start 0.12065 0.3048)
			(end 0.67945 0.3048)
			(stroke
				(width 0.1)
				(type default)
			)
			(layer "B.Fab")
		)
		(fp_line
			(start 0.67945 0.3048)
			(end 0.67945 -0.305054)
			(stroke
				(width 0.1)
				(type default)
			)
			(layer "B.Fab")
		)
		(fp_line
			(start -0.120396 0.2794)
			(end 0.12065 0.2794)
			(stroke
				(width 0.1)
				(type default)
			)
			(layer "B.Fab")
		)
		(fp_line
			(start 0.12065 0.2794)
			(end 0.12065 0.3048)
			(stroke
				(width 0.1)
				(type default)
			)
			(layer "B.Fab")
		)
		(fp_line
			(start -0.12065 -0.2794)
			(end -0.12065 -0.3048)
			(stroke
				(width 0.1)
				(type default)
			)
			(layer "B.Fab")
		)
		(fp_line
			(start 0.12065 -0.2794)
			(end -0.12065 -0.2794)
			(stroke
				(width 0.1)
				(type default)
			)
			(layer "B.Fab")
		)
		(fp_line
			(start -0.67945 -0.3048)
			(end -0.67945 0.3048)
			(stroke
				(width 0.1)
				(type default)
			)
			(layer "B.Fab")
		)
		(fp_line
			(start -0.12065 -0.3048)
			(end -0.67945 -0.3048)
			(stroke
				(width 0.1)
				(type default)
			)
			(layer "B.Fab")
		)
		(fp_line
			(start 0.12065 -0.305054)
			(end 0.12065 -0.2794)
			(stroke
				(width 0.1)
				(type default)
			)
			(layer "B.Fab")
		)
		(fp_line
			(start 0.67945 -0.305054)
			(end 0.12065 -0.305054)
			(stroke
				(width 0.1)
				(type default)
			)
			(layer "B.Fab")
		)
		(pad "1" smd circle
			(at 0.40005 0 90)
			(size 0 0)
			(layers "B.Cu" "B.Mask" "B.Paste")
			(net "SMB_2_BMC_GPU_SCL")
		)
		(pad "2" smd circle
			(at -0.40005 0 90)
			(size 0 0)
			(layers "B.Cu" "B.Mask" "B.Paste")
			(net "P3V3_AUX")
		)
	)
	(footprint ""
		(layer "B.Cu")
		(at 61.778642 -386.766562 90)
		(property "Reference" "C190"
			(at 0 0 90)
			(layer "B.SilkS")
			(hide yes)
			(effects
				(font
					(size 1.27 1.27)
				)
				(justify mirror)
			)
		)
		(property "Value" ""
			(at 0 0 90)
			(layer "B.Fab")
			(effects
				(font
					(size 1.27 1.27)
				)
				(justify mirror)
			)
		)
		(duplicate_pad_numbers_are_jumpers no)
		(fp_line
			(start 0.299974 -0.150114)
			(end -0.299974 -0.150114)
			(stroke
				(width 0.1)
				(type default)
			)
			(layer "B.Fab")
		)
		(fp_line
			(start -0.299974 -0.150114)
			(end -0.299974 0.150114)
			(stroke
				(width 0.1)
				(type default)
			)
			(layer "B.Fab")
		)
		(fp_line
			(start 0.299974 0.150114)
			(end 0.299974 -0.150114)
			(stroke
				(width 0.1)
				(type default)
			)
			(layer "B.Fab")
		)
		(fp_line
			(start -0.299974 0.150114)
			(end 0.299974 0.150114)
			(stroke
				(width 0.1)
				(type default)
			)
			(layer "B.Fab")
		)
		(pad "1" smd rect
			(at 0.2667 0 270)
			(size 0.3048 0.381)
			(layers "B.Cu" "B.Mask" "B.Paste")
			(net "P0V9_CPU1_RT0_2A")
		)
		(pad "2" smd rect
			(at -0.2667 0 270)
			(size 0.3048 0.381)
			(layers "B.Cu" "B.Mask" "B.Paste")
			(net "GND")
		)
	)
	(footprint ""
		(layer "B.Cu")
		(at 382.504442 -416.899344 90)
		(property "Reference" "C6603"
			(at 0 0 90)
			(layer "B.SilkS")
			(hide yes)
			(effects
				(font
					(size 1.27 1.27)
				)
				(justify mirror)
			)
		)
		(property "Value" ""
			(at 0 0 90)
			(layer "B.Fab")
			(effects
				(font
					(size 1.27 1.27)
				)
				(justify mirror)
			)
		)
		(duplicate_pad_numbers_are_jumpers no)
		(fp_line
			(start 0.299974 -0.150114)
			(end -0.299974 -0.150114)
			(stroke
				(width 0.1)
				(type default)
			)
			(layer "B.Fab")
		)
		(fp_line
			(start -0.299974 -0.150114)
			(end -0.299974 0.150114)
			(stroke
				(width 0.1)
				(type default)
			)
			(layer "B.Fab")
		)
		(fp_line
			(start 0.299974 0.150114)
			(end 0.299974 -0.150114)
			(stroke
				(width 0.1)
				(type default)
			)
			(layer "B.Fab")
		)
		(fp_line
			(start -0.299974 0.150114)
			(end 0.299974 0.150114)
			(stroke
				(width 0.1)
				(type default)
			)
			(layer "B.Fab")
		)
		(pad "1" smd rect
			(at 0.2667 0 270)
			(size 0.3048 0.381)
			(layers "B.Cu" "B.Mask" "B.Paste")
			(net "P5E_CPU0_P3_TX_BUF_C_DP<3>")
		)
		(pad "2" smd rect
			(at -0.2667 0 270)
			(size 0.3048 0.381)
			(layers "B.Cu" "B.Mask" "B.Paste")
			(net "P5E_CPU0_P3_TX_BUF_DP<3>")
		)
	)
	(footprint ""
		(layer "B.Cu")
		(at 136.040114 -36.882578)
		(property "Reference" "C6036"
			(at 0 0 0)
			(layer "B.SilkS")
			(hide yes)
			(effects
				(font
					(size 1.27 1.27)
				)
				(justify mirror)
			)
		)
		(property "Value" ""
			(at 0 0 0)
			(layer "B.Fab")
			(effects
				(font
					(size 1.27 1.27)
				)
				(justify mirror)
			)
		)
		(duplicate_pad_numbers_are_jumpers no)
		(fp_line
			(start -0.7874 -0.4064)
			(end -0.7874 0.4064)
			(stroke
				(width 0.1524)
				(type default)
			)
			(layer "B.SilkS")
		)
		(fp_line
			(start -0.7874 0.4064)
			(end 0.7874 0.4064)
			(stroke
				(width 0.1524)
				(type default)
			)
			(layer "B.SilkS")
		)
		(fp_line
			(start 0.7874 -0.4064)
			(end -0.7874 -0.4064)
			(stroke
				(width 0.1524)
				(type default)
			)
			(layer "B.SilkS")
		)
		(fp_line
			(start 0.7874 0.4064)
			(end 0.7874 -0.4064)
			(stroke
				(width 0.1524)
				(type default)
			)
			(layer "B.SilkS")
		)
		(fp_line
			(start -0.67945 -0.3048)
			(end -0.67945 0.3048)
			(stroke
				(width 0.1)
				(type default)
			)
			(layer "B.Fab")
		)
		(fp_line
			(start -0.67945 0.3048)
			(end -0.120396 0.3048)
			(stroke
				(width 0.1)
				(type default)
			)
			(layer "B.Fab")
		)
		(fp_line
			(start -0.12065 -0.3048)
			(end -0.67945 -0.3048)
			(stroke
				(width 0.1)
				(type default)
			)
			(layer "B.Fab")
		)
		(fp_line
			(start -0.12065 -0.2794)
			(end -0.12065 -0.3048)
			(stroke
				(width 0.1)
				(type default)
			)
			(layer "B.Fab")
		)
		(fp_line
			(start -0.120396 0.2794)
			(end 0.12065 0.2794)
			(stroke
				(width 0.1)
				(type default)
			)
			(layer "B.Fab")
		)
		(fp_line
			(start -0.120396 0.3048)
			(end -0.120396 0.2794)
			(stroke
				(width 0.1)
				(type default)
			)
			(layer "B.Fab")
		)
		(fp_line
			(start 0.12065 -0.305054)
			(end 0.12065 -0.2794)
			(stroke
				(width 0.1)
				(type default)
			)
			(layer "B.Fab")
		)
		(fp_line
			(start 0.12065 -0.2794)
			(end -0.12065 -0.2794)
			(stroke
				(width 0.1)
				(type default)
			)
			(layer "B.Fab")
		)
		(fp_line
			(start 0.12065 0.2794)
			(end 0.12065 0.3048)
			(stroke
				(width 0.1)
				(type default)
			)
			(layer "B.Fab")
		)
		(fp_line
			(start 0.12065 0.3048)
			(end 0.67945 0.3048)
			(stroke
				(width 0.1)
				(type default)
			)
			(layer "B.Fab")
		)
		(fp_line
			(start 0.67945 -0.305054)
			(end 0.12065 -0.305054)
			(stroke
				(width 0.1)
				(type default)
			)
			(layer "B.Fab")
		)
		(fp_line
			(start 0.67945 0.3048)
			(end 0.67945 -0.305054)
			(stroke
				(width 0.1)
				(type default)
			)
			(layer "B.Fab")
		)
		(pad "1" smd circle
			(at 0.40005 0 180)
			(size 0 0)
			(layers "B.Cu" "B.Mask" "B.Paste")
			(net "P1V2_CPU0_USB_DVDD12")
		)
		(pad "2" smd circle
			(at -0.40005 0 180)
			(size 0 0)
			(layers "B.Cu" "B.Mask" "B.Paste")
			(net "GND")
		)
	)
	(footprint ""
		(layer "B.Cu")
		(at 115.864386 -266.005564)
		(property "Reference" "C2118"
			(at 0 0 0)
			(layer "B.SilkS")
			(hide yes)
			(effects
				(font
					(size 1.27 1.27)
				)
				(justify mirror)
			)
		)
		(property "Value" ""
			(at 0 0 0)
			(layer "B.Fab")
			(effects
				(font
					(size 1.27 1.27)
				)
				(justify mirror)
			)
		)
		(duplicate_pad_numbers_are_jumpers no)
		(fp_line
			(start -0.7874 -0.4064)
			(end -0.7874 0.4064)
			(stroke
				(width 0.1524)
				(type default)
			)
			(layer "B.SilkS")
		)
		(fp_line
			(start -0.7874 0.4064)
			(end 0.7874 0.4064)
			(stroke
				(width 0.1524)
				(type default)
			)
			(layer "B.SilkS")
		)
		(fp_line
			(start 0.7874 -0.4064)
			(end -0.7874 -0.4064)
			(stroke
				(width 0.1524)
				(type default)
			)
			(layer "B.SilkS")
		)
		(fp_line
			(start 0.7874 0.4064)
			(end 0.7874 -0.4064)
			(stroke
				(width 0.1524)
				(type default)
			)
			(layer "B.SilkS")
		)
		(fp_line
			(start -0.67945 -0.3048)
			(end -0.67945 0.3048)
			(stroke
				(width 0.1)
				(type default)
			)
			(layer "B.Fab")
		)
		(fp_line
			(start -0.67945 0.3048)
			(end -0.120396 0.3048)
			(stroke
				(width 0.1)
				(type default)
			)
			(layer "B.Fab")
		)
		(fp_line
			(start -0.12065 -0.3048)
			(end -0.67945 -0.3048)
			(stroke
				(width 0.1)
				(type default)
			)
			(layer "B.Fab")
		)
		(fp_line
			(start -0.12065 -0.2794)
			(end -0.12065 -0.3048)
			(stroke
				(width 0.1)
				(type default)
			)
			(layer "B.Fab")
		)
		(fp_line
			(start -0.120396 0.2794)
			(end 0.12065 0.2794)
			(stroke
				(width 0.1)
				(type default)
			)
			(layer "B.Fab")
		)
		(fp_line
			(start -0.120396 0.3048)
			(end -0.120396 0.2794)
			(stroke
				(width 0.1)
				(type default)
			)
			(layer "B.Fab")
		)
		(fp_line
			(start 0.12065 -0.305054)
			(end 0.12065 -0.2794)
			(stroke
				(width 0.1)
				(type default)
			)
			(layer "B.Fab")
		)
		(fp_line
			(start 0.12065 -0.2794)
			(end -0.12065 -0.2794)
			(stroke
				(width 0.1)
				(type default)
			)
			(layer "B.Fab")
		)
		(fp_line
			(start 0.12065 0.2794)
			(end 0.12065 0.3048)
			(stroke
				(width 0.1)
				(type default)
			)
			(layer "B.Fab")
		)
		(fp_line
			(start 0.12065 0.3048)
			(end 0.67945 0.3048)
			(stroke
				(width 0.1)
				(type default)
			)
			(layer "B.Fab")
		)
		(fp_line
			(start 0.67945 -0.305054)
			(end 0.12065 -0.305054)
			(stroke
				(width 0.1)
				(type default)
			)
			(layer "B.Fab")
		)
		(fp_line
			(start 0.67945 0.3048)
			(end 0.67945 -0.305054)
			(stroke
				(width 0.1)
				(type default)
			)
			(layer "B.Fab")
		)
		(pad "1" smd circle
			(at 0.40005 0 180)
			(size 0 0)
			(layers "B.Cu" "B.Mask" "B.Paste")
			(net "PVDD11_S3_P1")
		)
		(pad "2" smd circle
			(at -0.40005 0 180)
			(size 0 0)
			(layers "B.Cu" "B.Mask" "B.Paste")
			(net "GND")
		)
	)
	(footprint ""
		(layer "B.Cu")
		(at 351.612454 -261.17931 180)
		(property "Reference" "C2596"
			(at 0 0 0)
			(layer "B.SilkS")
			(hide yes)
			(effects
				(font
					(size 1.27 1.27)
				)
				(justify mirror)
			)
		)
		(property "Value" ""
			(at 0 0 0)
			(layer "B.Fab")
			(effects
				(font
					(size 1.27 1.27)
				)
				(justify mirror)
			)
		)
		(duplicate_pad_numbers_are_jumpers no)
		(fp_line
			(start 0.7874 0.4064)
			(end 0.7874 -0.4064)
			(stroke
				(width 0.1524)
				(type default)
			)
			(layer "B.SilkS")
		)
		(fp_line
			(start 0.7874 -0.4064)
			(end -0.7874 -0.4064)
			(stroke
				(width 0.1524)
				(type default)
			)
			(layer "B.SilkS")
		)
		(fp_line
			(start -0.7874 0.4064)
			(end 0.7874 0.4064)
			(stroke
				(width 0.1524)
				(type default)
			)
			(layer "B.SilkS")
		)
		(fp_line
			(start -0.7874 -0.4064)
			(end -0.7874 0.4064)
			(stroke
				(width 0.1524)
				(type default)
			)
			(layer "B.SilkS")
		)
		(fp_line
			(start 0.67945 0.3048)
			(end 0.67945 -0.305054)
			(stroke
				(width 0.1)
				(type default)
			)
			(layer "B.Fab")
		)
		(fp_line
			(start 0.67945 -0.305054)
			(end 0.12065 -0.305054)
			(stroke
				(width 0.1)
				(type default)
			)
			(layer "B.Fab")
		)
		(fp_line
			(start 0.12065 0.3048)
			(end 0.67945 0.3048)
			(stroke
				(width 0.1)
				(type default)
			)
			(layer "B.Fab")
		)
		(fp_line
			(start 0.12065 0.2794)
			(end 0.12065 0.3048)
			(stroke
				(width 0.1)
				(type default)
			)
			(layer "B.Fab")
		)
		(fp_line
			(start 0.12065 -0.2794)
			(end -0.12065 -0.2794)
			(stroke
				(width 0.1)
				(type default)
			)
			(layer "B.Fab")
		)
		(fp_line
			(start 0.12065 -0.305054)
			(end 0.12065 -0.2794)
			(stroke
				(width 0.1)
				(type default)
			)
			(layer "B.Fab")
		)
		(fp_line
			(start -0.120396 0.3048)
			(end -0.120396 0.2794)
			(stroke
				(width 0.1)
				(type default)
			)
			(layer "B.Fab")
		)
		(fp_line
			(start -0.120396 0.2794)
			(end 0.12065 0.2794)
			(stroke
				(width 0.1)
				(type default)
			)
			(layer "B.Fab")
		)
		(fp_line
			(start -0.12065 -0.2794)
			(end -0.12065 -0.3048)
			(stroke
				(width 0.1)
				(type default)
			)
			(layer "B.Fab")
		)
		(fp_line
			(start -0.12065 -0.3048)
			(end -0.67945 -0.3048)
			(stroke
				(width 0.1)
				(type default)
			)
			(layer "B.Fab")
		)
		(fp_line
			(start -0.67945 0.3048)
			(end -0.120396 0.3048)
			(stroke
				(width 0.1)
				(type default)
			)
			(layer "B.Fab")
		)
		(fp_line
			(start -0.67945 -0.3048)
			(end -0.67945 0.3048)
			(stroke
				(width 0.1)
				(type default)
			)
			(layer "B.Fab")
		)
		(pad "1" smd circle
			(at 0.40005 0)
			(size 0 0)
			(layers "B.Cu" "B.Mask" "B.Paste")
			(net "PVDDCR_SOC_P0")
		)
		(pad "2" smd circle
			(at -0.40005 0)
			(size 0 0)
			(layers "B.Cu" "B.Mask" "B.Paste")
			(net "GND")
		)
	)
	(footprint ""
		(layer "B.Cu")
		(at 124.218446 -388.011162 -90)
		(property "Reference" "C447"
			(at 0 0 90)
			(layer "B.SilkS")
			(hide yes)
			(effects
				(font
					(size 1.27 1.27)
				)
				(justify mirror)
			)
		)
		(property "Value" ""
			(at 0 0 90)
			(layer "B.Fab")
			(effects
				(font
					(size 1.27 1.27)
				)
				(justify mirror)
			)
		)
		(duplicate_pad_numbers_are_jumpers no)
		(fp_line
			(start -0.299974 0.150114)
			(end 0.299974 0.150114)
			(stroke
				(width 0.1)
				(type default)
			)
			(layer "B.Fab")
		)
		(fp_line
			(start 0.299974 0.150114)
			(end 0.299974 -0.150114)
			(stroke
				(width 0.1)
				(type default)
			)
			(layer "B.Fab")
		)
		(fp_line
			(start -0.299974 -0.150114)
			(end -0.299974 0.150114)
			(stroke
				(width 0.1)
				(type default)
			)
			(layer "B.Fab")
		)
		(fp_line
			(start 0.299974 -0.150114)
			(end -0.299974 -0.150114)
			(stroke
				(width 0.1)
				(type default)
			)
			(layer "B.Fab")
		)
		(pad "1" smd rect
			(at 0.2667 0 90)
			(size 0.3048 0.381)
			(layers "B.Cu" "B.Mask" "B.Paste")
			(net "P1V8_CPU1_RT3_1A")
		)
		(pad "2" smd rect
			(at -0.2667 0 90)
			(size 0.3048 0.381)
			(layers "B.Cu" "B.Mask" "B.Paste")
			(net "GND")
		)
	)
	(footprint ""
		(layer "B.Cu")
		(at 358.796082 -257.744976 180)
		(property "Reference" "C3889"
			(at 0 0 0)
			(layer "B.SilkS")
			(hide yes)
			(effects
				(font
					(size 1.27 1.27)
				)
				(justify mirror)
			)
		)
		(property "Value" ""
			(at 0 0 0)
			(layer "B.Fab")
			(effects
				(font
					(size 1.27 1.27)
				)
				(justify mirror)
			)
		)
		(duplicate_pad_numbers_are_jumpers no)
		(fp_line
			(start 0.7874 0.4064)
			(end 0.7874 -0.4064)
			(stroke
				(width 0.1524)
				(type default)
			)
			(layer "B.SilkS")
		)
		(fp_line
			(start 0.7874 -0.4064)
			(end -0.7874 -0.4064)
			(stroke
				(width 0.1524)
				(type default)
			)
			(layer "B.SilkS")
		)
		(fp_line
			(start -0.7874 0.4064)
			(end 0.7874 0.4064)
			(stroke
				(width 0.1524)
				(type default)
			)
			(layer "B.SilkS")
		)
		(fp_line
			(start -0.7874 -0.4064)
			(end -0.7874 0.4064)
			(stroke
				(width 0.1524)
				(type default)
			)
			(layer "B.SilkS")
		)
		(fp_line
			(start 0.67945 0.3048)
			(end 0.67945 -0.305054)
			(stroke
				(width 0.1)
				(type default)
			)
			(layer "B.Fab")
		)
		(fp_line
			(start 0.67945 -0.305054)
			(end 0.12065 -0.305054)
			(stroke
				(width 0.1)
				(type default)
			)
			(layer "B.Fab")
		)
		(fp_line
			(start 0.12065 0.3048)
			(end 0.67945 0.3048)
			(stroke
				(width 0.1)
				(type default)
			)
			(layer "B.Fab")
		)
		(fp_line
			(start 0.12065 0.2794)
			(end 0.12065 0.3048)
			(stroke
				(width 0.1)
				(type default)
			)
			(layer "B.Fab")
		)
		(fp_line
			(start 0.12065 -0.2794)
			(end -0.12065 -0.2794)
			(stroke
				(width 0.1)
				(type default)
			)
			(layer "B.Fab")
		)
		(fp_line
			(start 0.12065 -0.305054)
			(end 0.12065 -0.2794)
			(stroke
				(width 0.1)
				(type default)
			)
			(layer "B.Fab")
		)
		(fp_line
			(start -0.120396 0.3048)
			(end -0.120396 0.2794)
			(stroke
				(width 0.1)
				(type default)
			)
			(layer "B.Fab")
		)
		(fp_line
			(start -0.120396 0.2794)
			(end 0.12065 0.2794)
			(stroke
				(width 0.1)
				(type default)
			)
			(layer "B.Fab")
		)
		(fp_line
			(start -0.12065 -0.2794)
			(end -0.12065 -0.3048)
			(stroke
				(width 0.1)
				(type default)
			)
			(layer "B.Fab")
		)
		(fp_line
			(start -0.12065 -0.3048)
			(end -0.67945 -0.3048)
			(stroke
				(width 0.1)
				(type default)
			)
			(layer "B.Fab")
		)
		(fp_line
			(start -0.67945 0.3048)
			(end -0.120396 0.3048)
			(stroke
				(width 0.1)
				(type default)
			)
			(layer "B.Fab")
		)
		(fp_line
			(start -0.67945 -0.3048)
			(end -0.67945 0.3048)
			(stroke
				(width 0.1)
				(type default)
			)
			(layer "B.Fab")
		)
		(pad "1" smd circle
			(at 0.40005 0)
			(size 0 0)
			(layers "B.Cu" "B.Mask" "B.Paste")
			(net "PVDDCR_SOC_P0")
		)
		(pad "2" smd circle
			(at -0.40005 0)
			(size 0 0)
			(layers "B.Cu" "B.Mask" "B.Paste")
			(net "GND")
		)
	)
	(footprint ""
		(layer "B.Cu")
		(at 408.316684 -332.118462 180)
		(property "Reference" "R5026"
			(at 0 0 0)
			(layer "B.SilkS")
			(hide yes)
			(effects
				(font
					(size 1.27 1.27)
				)
				(justify mirror)
			)
		)
		(property "Value" ""
			(at 0 0 0)
			(layer "B.Fab")
			(effects
				(font
					(size 1.27 1.27)
				)
				(justify mirror)
			)
		)
		(duplicate_pad_numbers_are_jumpers no)
		(fp_line
			(start 0.7874 0.4064)
			(end 0.7874 -0.4064)
			(stroke
				(width 0.1524)
				(type default)
			)
			(layer "B.SilkS")
		)
		(fp_line
			(start 0.7874 -0.4064)
			(end -0.7874 -0.4064)
			(stroke
				(width 0.1524)
				(type default)
			)
			(layer "B.SilkS")
		)
		(fp_line
			(start -0.7874 0.4064)
			(end 0.7874 0.4064)
			(stroke
				(width 0.1524)
				(type default)
			)
			(layer "B.SilkS")
		)
		(fp_line
			(start -0.7874 -0.4064)
			(end -0.7874 0.4064)
			(stroke
				(width 0.1524)
				(type default)
			)
			(layer "B.SilkS")
		)
		(fp_line
			(start 0.67945 0.3048)
			(end 0.67945 -0.305054)
			(stroke
				(width 0.1)
				(type default)
			)
			(layer "B.Fab")
		)
		(fp_line
			(start 0.67945 -0.305054)
			(end 0.12065 -0.305054)
			(stroke
				(width 0.1)
				(type default)
			)
			(layer "B.Fab")
		)
		(fp_line
			(start 0.12065 0.3048)
			(end 0.67945 0.3048)
			(stroke
				(width 0.1)
				(type default)
			)
			(layer "B.Fab")
		)
		(fp_line
			(start 0.12065 0.2794)
			(end 0.12065 0.3048)
			(stroke
				(width 0.1)
				(type default)
			)
			(layer "B.Fab")
		)
		(fp_line
			(start 0.12065 -0.2794)
			(end -0.12065 -0.2794)
			(stroke
				(width 0.1)
				(type default)
			)
			(layer "B.Fab")
		)
		(fp_line
			(start 0.12065 -0.305054)
			(end 0.12065 -0.2794)
			(stroke
				(width 0.1)
				(type default)
			)
			(layer "B.Fab")
		)
		(fp_line
			(start -0.120396 0.3048)
			(end -0.120396 0.2794)
			(stroke
				(width 0.1)
				(type default)
			)
			(layer "B.Fab")
		)
		(fp_line
			(start -0.120396 0.2794)
			(end 0.12065 0.2794)
			(stroke
				(width 0.1)
				(type default)
			)
			(layer "B.Fab")
		)
		(fp_line
			(start -0.12065 -0.2794)
			(end -0.12065 -0.3048)
			(stroke
				(width 0.1)
				(type default)
			)
			(layer "B.Fab")
		)
		(fp_line
			(start -0.12065 -0.3048)
			(end -0.67945 -0.3048)
			(stroke
				(width 0.1)
				(type default)
			)
			(layer "B.Fab")
		)
		(fp_line
			(start -0.67945 0.3048)
			(end -0.120396 0.3048)
			(stroke
				(width 0.1)
				(type default)
			)
			(layer "B.Fab")
		)
		(fp_line
			(start -0.67945 -0.3048)
			(end -0.67945 0.3048)
			(stroke
				(width 0.1)
				(type default)
			)
			(layer "B.Fab")
		)
		(pad "1" smd circle
			(at 0.40005 0)
			(size 0 0)
			(layers "B.Cu" "B.Mask" "B.Paste")
			(net "GND")
		)
		(pad "2" smd circle
			(at -0.40005 0)
			(size 0 0)
			(layers "B.Cu" "B.Mask" "B.Paste")
			(net "FM_SMM_CRASHDUMP")
		)
	)
	(footprint ""
		(layer "B.Cu")
		(at 96.886522 -150.698962 -90)
		(property "Reference" "PR530"
			(at 0 0 90)
			(layer "B.SilkS")
			(hide yes)
			(effects
				(font
					(size 1.27 1.27)
				)
				(justify mirror)
			)
		)
		(property "Value" ""
			(at 0 0 90)
			(layer "B.Fab")
			(effects
				(font
					(size 1.27 1.27)
				)
				(justify mirror)
			)
		)
		(duplicate_pad_numbers_are_jumpers no)
		(fp_line
			(start -0.7874 0.4064)
			(end 0.7874 0.4064)
			(stroke
				(width 0.1524)
				(type default)
			)
			(layer "B.SilkS")
		)
		(fp_line
			(start 0.7874 0.4064)
			(end 0.7874 -0.4064)
			(stroke
				(width 0.1524)
				(type default)
			)
			(layer "B.SilkS")
		)
		(fp_line
			(start -0.7874 -0.4064)
			(end -0.7874 0.4064)
			(stroke
				(width 0.1524)
				(type default)
			)
			(layer "B.SilkS")
		)
		(fp_line
			(start 0.7874 -0.4064)
			(end -0.7874 -0.4064)
			(stroke
				(width 0.1524)
				(type default)
			)
			(layer "B.SilkS")
		)
		(fp_line
			(start -0.67945 0.3048)
			(end -0.120396 0.3048)
			(stroke
				(width 0.1)
				(type default)
			)
			(layer "B.Fab")
		)
		(fp_line
			(start -0.120396 0.3048)
			(end -0.120396 0.2794)
			(stroke
				(width 0.1)
				(type default)
			)
			(layer "B.Fab")
		)
		(fp_line
			(start 0.12065 0.3048)
			(end 0.67945 0.3048)
			(stroke
				(width 0.1)
				(type default)
			)
			(layer "B.Fab")
		)
		(fp_line
			(start 0.67945 0.3048)
			(end 0.67945 -0.305054)
			(stroke
				(width 0.1)
				(type default)
			)
			(layer "B.Fab")
		)
		(fp_line
			(start -0.120396 0.2794)
			(end 0.12065 0.2794)
			(stroke
				(width 0.1)
				(type default)
			)
			(layer "B.Fab")
		)
		(fp_line
			(start 0.12065 0.2794)
			(end 0.12065 0.3048)
			(stroke
				(width 0.1)
				(type default)
			)
			(layer "B.Fab")
		)
		(fp_line
			(start -0.12065 -0.2794)
			(end -0.12065 -0.3048)
			(stroke
				(width 0.1)
				(type default)
			)
			(layer "B.Fab")
		)
		(fp_line
			(start 0.12065 -0.2794)
			(end -0.12065 -0.2794)
			(stroke
				(width 0.1)
				(type default)
			)
			(layer "B.Fab")
		)
		(fp_line
			(start -0.67945 -0.3048)
			(end -0.67945 0.3048)
			(stroke
				(width 0.1)
				(type default)
			)
			(layer "B.Fab")
		)
		(fp_line
			(start -0.12065 -0.3048)
			(end -0.67945 -0.3048)
			(stroke
				(width 0.1)
				(type default)
			)
			(layer "B.Fab")
		)
		(fp_line
			(start 0.12065 -0.305054)
			(end 0.12065 -0.2794)
			(stroke
				(width 0.1)
				(type default)
			)
			(layer "B.Fab")
		)
		(fp_line
			(start 0.67945 -0.305054)
			(end 0.12065 -0.305054)
			(stroke
				(width 0.1)
				(type default)
			)
			(layer "B.Fab")
		)
		(pad "1" smd circle
			(at 0.40005 0 90)
			(size 0 0)
			(layers "B.Cu" "B.Mask" "B.Paste")
			(net "NC_PVDDCR_CPU0_P1_IMON7")
		)
		(pad "2" smd circle
			(at -0.40005 0 90)
			(size 0 0)
			(layers "B.Cu" "B.Mask" "B.Paste")
			(net "GND")
		)
	)
	(footprint ""
		(layer "B.Cu")
		(at 418.618924 -398.942052 90)
		(property "Reference" "C969"
			(at 0 0 90)
			(layer "B.SilkS")
			(hide yes)
			(effects
				(font
					(size 1.27 1.27)
				)
				(justify mirror)
			)
		)
		(property "Value" ""
			(at 0 0 90)
			(layer "B.Fab")
			(effects
				(font
					(size 1.27 1.27)
				)
				(justify mirror)
			)
		)
		(duplicate_pad_numbers_are_jumpers no)
		(fp_line
			(start 0.7874 -0.4064)
			(end -0.7874 -0.4064)
			(stroke
				(width 0.1524)
				(type default)
			)
			(layer "B.SilkS")
		)
		(fp_line
			(start -0.7874 -0.4064)
			(end -0.7874 0.4064)
			(stroke
				(width 0.1524)
				(type default)
			)
			(layer "B.SilkS")
		)
		(fp_line
			(start 0.7874 0.4064)
			(end 0.7874 -0.4064)
			(stroke
				(width 0.1524)
				(type default)
			)
			(layer "B.SilkS")
		)
		(fp_line
			(start -0.7874 0.4064)
			(end 0.7874 0.4064)
			(stroke
				(width 0.1524)
				(type default)
			)
			(layer "B.SilkS")
		)
		(fp_line
			(start 0.67945 -0.305054)
			(end 0.12065 -0.305054)
			(stroke
				(width 0.1)
				(type default)
			)
			(layer "B.Fab")
		)
		(fp_line
			(start 0.12065 -0.305054)
			(end 0.12065 -0.2794)
			(stroke
				(width 0.1)
				(type default)
			)
			(layer "B.Fab")
		)
		(fp_line
			(start -0.12065 -0.3048)
			(end -0.67945 -0.3048)
			(stroke
				(width 0.1)
				(type default)
			)
			(layer "B.Fab")
		)
		(fp_line
			(start -0.67945 -0.3048)
			(end -0.67945 0.3048)
			(stroke
				(width 0.1)
				(type default)
			)
			(layer "B.Fab")
		)
		(fp_line
			(start 0.12065 -0.2794)
			(end -0.12065 -0.2794)
			(stroke
				(width 0.1)
				(type default)
			)
			(layer "B.Fab")
		)
		(fp_line
			(start -0.12065 -0.2794)
			(end -0.12065 -0.3048)
			(stroke
				(width 0.1)
				(type default)
			)
			(layer "B.Fab")
		)
		(fp_line
			(start 0.12065 0.2794)
			(end 0.12065 0.3048)
			(stroke
				(width 0.1)
				(type default)
			)
			(layer "B.Fab")
		)
		(fp_line
			(start -0.120396 0.2794)
			(end 0.12065 0.2794)
			(stroke
				(width 0.1)
				(type default)
			)
			(layer "B.Fab")
		)
		(fp_line
			(start 0.67945 0.3048)
			(end 0.67945 -0.305054)
			(stroke
				(width 0.1)
				(type default)
			)
			(layer "B.Fab")
		)
		(fp_line
			(start 0.12065 0.3048)
			(end 0.67945 0.3048)
			(stroke
				(width 0.1)
				(type default)
			)
			(layer "B.Fab")
		)
		(fp_line
			(start -0.120396 0.3048)
			(end -0.120396 0.2794)
			(stroke
				(width 0.1)
				(type default)
			)
			(layer "B.Fab")
		)
		(fp_line
			(start -0.67945 0.3048)
			(end -0.120396 0.3048)
			(stroke
				(width 0.1)
				(type default)
			)
			(layer "B.Fab")
		)
		(pad "1" smd circle
			(at 0.40005 0 270)
			(size 0 0)
			(layers "B.Cu" "B.Mask" "B.Paste")
			(net "P0V9_CPU0_RT2_2A")
		)
		(pad "2" smd circle
			(at -0.40005 0 270)
			(size 0 0)
			(layers "B.Cu" "B.Mask" "B.Paste")
			(net "GND")
		)
	)
	(footprint ""
		(layer "B.Cu")
		(at 322.4149 -326.227186 -90)
		(property "Reference" "PC108_2"
			(at 0 0 90)
			(layer "B.SilkS")
			(hide yes)
			(effects
				(font
					(size 1.27 1.27)
				)
				(justify mirror)
			)
		)
		(property "Value" ""
			(at 0 0 90)
			(layer "B.Fab")
			(effects
				(font
					(size 1.27 1.27)
				)
				(justify mirror)
			)
		)
		(duplicate_pad_numbers_are_jumpers no)
		(fp_line
			(start -1.524 0.762)
			(end 1.524 0.762)
			(stroke
				(width 0.1524)
				(type default)
			)
			(layer "B.SilkS")
		)
		(fp_line
			(start 1.524 0.762)
			(end 1.524 -0.762)
			(stroke
				(width 0.1524)
				(type default)
			)
			(layer "B.SilkS")
		)
		(fp_line
			(start -1.524 -0.762)
			(end -1.524 0.762)
			(stroke
				(width 0.1524)
				(type default)
			)
			(layer "B.SilkS")
		)
		(fp_line
			(start 1.524 -0.762)
			(end -1.524 -0.762)
			(stroke
				(width 0.1524)
				(type default)
			)
			(layer "B.SilkS")
		)
		(fp_line
			(start -1.1049 0.724916)
			(end -1.1049 -0.724916)
			(stroke
				(width 0.1)
				(type default)
			)
			(layer "B.Fab")
		)
		(fp_line
			(start 1.1049 0.724916)
			(end -1.1049 0.724916)
			(stroke
				(width 0.1)
				(type default)
			)
			(layer "B.Fab")
		)
		(fp_line
			(start -1.1049 -0.724916)
			(end 1.1049 -0.724916)
			(stroke
				(width 0.1)
				(type default)
			)
			(layer "B.Fab")
		)
		(fp_line
			(start 1.1049 -0.724916)
			(end 1.1049 0.724916)
			(stroke
				(width 0.1)
				(type default)
			)
			(layer "B.Fab")
		)
		(pad "1" smd rect
			(at 0.889 0 270)
			(size 1.016 1.27)
			(layers "B.Cu" "B.Mask" "B.Paste")
			(net "PVDDCR_CPU1_P0")
		)
		(pad "2" smd rect
			(at -0.889 0 270)
			(size 1.016 1.27)
			(layers "B.Cu" "B.Mask" "B.Paste")
			(net "GND")
		)
	)
	(footprint ""
		(layer "B.Cu")
		(at 364.820454 -269.30731)
		(property "Reference" "C2254"
			(at 0 0 0)
			(layer "B.SilkS")
			(hide yes)
			(effects
				(font
					(size 1.27 1.27)
				)
				(justify mirror)
			)
		)
		(property "Value" ""
			(at 0 0 0)
			(layer "B.Fab")
			(effects
				(font
					(size 1.27 1.27)
				)
				(justify mirror)
			)
		)
		(duplicate_pad_numbers_are_jumpers no)
		(fp_line
			(start -0.7874 -0.4064)
			(end -0.7874 0.4064)
			(stroke
				(width 0.1524)
				(type default)
			)
			(layer "B.SilkS")
		)
		(fp_line
			(start -0.7874 0.4064)
			(end 0.7874 0.4064)
			(stroke
				(width 0.1524)
				(type default)
			)
			(layer "B.SilkS")
		)
		(fp_line
			(start 0.7874 -0.4064)
			(end -0.7874 -0.4064)
			(stroke
				(width 0.1524)
				(type default)
			)
			(layer "B.SilkS")
		)
		(fp_line
			(start 0.7874 0.4064)
			(end 0.7874 -0.4064)
			(stroke
				(width 0.1524)
				(type default)
			)
			(layer "B.SilkS")
		)
		(fp_line
			(start -0.67945 -0.3048)
			(end -0.67945 0.3048)
			(stroke
				(width 0.1)
				(type default)
			)
			(layer "B.Fab")
		)
		(fp_line
			(start -0.67945 0.3048)
			(end -0.120396 0.3048)
			(stroke
				(width 0.1)
				(type default)
			)
			(layer "B.Fab")
		)
		(fp_line
			(start -0.12065 -0.3048)
			(end -0.67945 -0.3048)
			(stroke
				(width 0.1)
				(type default)
			)
			(layer "B.Fab")
		)
		(fp_line
			(start -0.12065 -0.2794)
			(end -0.12065 -0.3048)
			(stroke
				(width 0.1)
				(type default)
			)
			(layer "B.Fab")
		)
		(fp_line
			(start -0.120396 0.2794)
			(end 0.12065 0.2794)
			(stroke
				(width 0.1)
				(type default)
			)
			(layer "B.Fab")
		)
		(fp_line
			(start -0.120396 0.3048)
			(end -0.120396 0.2794)
			(stroke
				(width 0.1)
				(type default)
			)
			(layer "B.Fab")
		)
		(fp_line
			(start 0.12065 -0.305054)
			(end 0.12065 -0.2794)
			(stroke
				(width 0.1)
				(type default)
			)
			(layer "B.Fab")
		)
		(fp_line
			(start 0.12065 -0.2794)
			(end -0.12065 -0.2794)
			(stroke
				(width 0.1)
				(type default)
			)
			(layer "B.Fab")
		)
		(fp_line
			(start 0.12065 0.2794)
			(end 0.12065 0.3048)
			(stroke
				(width 0.1)
				(type default)
			)
			(layer "B.Fab")
		)
		(fp_line
			(start 0.12065 0.3048)
			(end 0.67945 0.3048)
			(stroke
				(width 0.1)
				(type default)
			)
			(layer "B.Fab")
		)
		(fp_line
			(start 0.67945 -0.305054)
			(end 0.12065 -0.305054)
			(stroke
				(width 0.1)
				(type default)
			)
			(layer "B.Fab")
		)
		(fp_line
			(start 0.67945 0.3048)
			(end 0.67945 -0.305054)
			(stroke
				(width 0.1)
				(type default)
			)
			(layer "B.Fab")
		)
		(pad "1" smd circle
			(at 0.40005 0 180)
			(size 0 0)
			(layers "B.Cu" "B.Mask" "B.Paste")
			(net "PVDDCR_CPU1_P0")
		)
		(pad "2" smd circle
			(at -0.40005 0 180)
			(size 0 0)
			(layers "B.Cu" "B.Mask" "B.Paste")
			(net "GND")
		)
	)
	(footprint ""
		(layer "B.Cu")
		(at 11.961114 -98.296222 180)
		(property "Reference" "C2034"
			(at 0 0 0)
			(layer "B.SilkS")
			(hide yes)
			(effects
				(font
					(size 1.27 1.27)
				)
				(justify mirror)
			)
		)
		(property "Value" ""
			(at 0 0 0)
			(layer "B.Fab")
			(effects
				(font
					(size 1.27 1.27)
				)
				(justify mirror)
			)
		)
		(duplicate_pad_numbers_are_jumpers no)
		(fp_line
			(start 0.7874 0.4064)
			(end 0.7874 -0.4064)
			(stroke
				(width 0.1524)
				(type default)
			)
			(layer "B.SilkS")
		)
		(fp_line
			(start 0.7874 -0.4064)
			(end -0.7874 -0.4064)
			(stroke
				(width 0.1524)
				(type default)
			)
			(layer "B.SilkS")
		)
		(fp_line
			(start -0.7874 0.4064)
			(end 0.7874 0.4064)
			(stroke
				(width 0.1524)
				(type default)
			)
			(layer "B.SilkS")
		)
		(fp_line
			(start -0.7874 -0.4064)
			(end -0.7874 0.4064)
			(stroke
				(width 0.1524)
				(type default)
			)
			(layer "B.SilkS")
		)
		(fp_line
			(start 0.67945 0.3048)
			(end 0.67945 -0.305054)
			(stroke
				(width 0.1)
				(type default)
			)
			(layer "B.Fab")
		)
		(fp_line
			(start 0.67945 -0.305054)
			(end 0.12065 -0.305054)
			(stroke
				(width 0.1)
				(type default)
			)
			(layer "B.Fab")
		)
		(fp_line
			(start 0.12065 0.3048)
			(end 0.67945 0.3048)
			(stroke
				(width 0.1)
				(type default)
			)
			(layer "B.Fab")
		)
		(fp_line
			(start 0.12065 0.2794)
			(end 0.12065 0.3048)
			(stroke
				(width 0.1)
				(type default)
			)
			(layer "B.Fab")
		)
		(fp_line
			(start 0.12065 -0.2794)
			(end -0.12065 -0.2794)
			(stroke
				(width 0.1)
				(type default)
			)
			(layer "B.Fab")
		)
		(fp_line
			(start 0.12065 -0.305054)
			(end 0.12065 -0.2794)
			(stroke
				(width 0.1)
				(type default)
			)
			(layer "B.Fab")
		)
		(fp_line
			(start -0.120396 0.3048)
			(end -0.120396 0.2794)
			(stroke
				(width 0.1)
				(type default)
			)
			(layer "B.Fab")
		)
		(fp_line
			(start -0.120396 0.2794)
			(end 0.12065 0.2794)
			(stroke
				(width 0.1)
				(type default)
			)
			(layer "B.Fab")
		)
		(fp_line
			(start -0.12065 -0.2794)
			(end -0.12065 -0.3048)
			(stroke
				(width 0.1)
				(type default)
			)
			(layer "B.Fab")
		)
		(fp_line
			(start -0.12065 -0.3048)
			(end -0.67945 -0.3048)
			(stroke
				(width 0.1)
				(type default)
			)
			(layer "B.Fab")
		)
		(fp_line
			(start -0.67945 0.3048)
			(end -0.120396 0.3048)
			(stroke
				(width 0.1)
				(type default)
			)
			(layer "B.Fab")
		)
		(fp_line
			(start -0.67945 -0.3048)
			(end -0.67945 0.3048)
			(stroke
				(width 0.1)
				(type default)
			)
			(layer "B.Fab")
		)
		(pad "1" smd circle
			(at 0.40005 0)
			(size 0 0)
			(layers "B.Cu" "B.Mask" "B.Paste")
			(net "P3V3_AUX_USB_HUB")
		)
		(pad "2" smd circle
			(at -0.40005 0)
			(size 0 0)
			(layers "B.Cu" "B.Mask" "B.Paste")
			(net "GND")
		)
	)
	(footprint ""
		(layer "B.Cu")
		(at 435.145942 -8.316976 -90)
		(property "Reference" "R1895"
			(at 0 0 90)
			(layer "B.SilkS")
			(hide yes)
			(effects
				(font
					(size 1.27 1.27)
				)
				(justify mirror)
			)
		)
		(property "Value" ""
			(at 0 0 90)
			(layer "B.Fab")
			(effects
				(font
					(size 1.27 1.27)
				)
				(justify mirror)
			)
		)
		(duplicate_pad_numbers_are_jumpers no)
		(fp_line
			(start -0.7874 0.4064)
			(end 0.7874 0.4064)
			(stroke
				(width 0.1524)
				(type default)
			)
			(layer "B.SilkS")
		)
		(fp_line
			(start 0.7874 0.4064)
			(end 0.7874 -0.4064)
			(stroke
				(width 0.1524)
				(type default)
			)
			(layer "B.SilkS")
		)
		(fp_line
			(start -0.7874 -0.4064)
			(end -0.7874 0.4064)
			(stroke
				(width 0.1524)
				(type default)
			)
			(layer "B.SilkS")
		)
		(fp_line
			(start 0.7874 -0.4064)
			(end -0.7874 -0.4064)
			(stroke
				(width 0.1524)
				(type default)
			)
			(layer "B.SilkS")
		)
		(fp_line
			(start -0.67945 0.3048)
			(end -0.120396 0.3048)
			(stroke
				(width 0.1)
				(type default)
			)
			(layer "B.Fab")
		)
		(fp_line
			(start -0.120396 0.3048)
			(end -0.120396 0.2794)
			(stroke
				(width 0.1)
				(type default)
			)
			(layer "B.Fab")
		)
		(fp_line
			(start 0.12065 0.3048)
			(end 0.67945 0.3048)
			(stroke
				(width 0.1)
				(type default)
			)
			(layer "B.Fab")
		)
		(fp_line
			(start 0.67945 0.3048)
			(end 0.67945 -0.305054)
			(stroke
				(width 0.1)
				(type default)
			)
			(layer "B.Fab")
		)
		(fp_line
			(start -0.120396 0.2794)
			(end 0.12065 0.2794)
			(stroke
				(width 0.1)
				(type default)
			)
			(layer "B.Fab")
		)
		(fp_line
			(start 0.12065 0.2794)
			(end 0.12065 0.3048)
			(stroke
				(width 0.1)
				(type default)
			)
			(layer "B.Fab")
		)
		(fp_line
			(start -0.12065 -0.2794)
			(end -0.12065 -0.3048)
			(stroke
				(width 0.1)
				(type default)
			)
			(layer "B.Fab")
		)
		(fp_line
			(start 0.12065 -0.2794)
			(end -0.12065 -0.2794)
			(stroke
				(width 0.1)
				(type default)
			)
			(layer "B.Fab")
		)
		(fp_line
			(start -0.67945 -0.3048)
			(end -0.67945 0.3048)
			(stroke
				(width 0.1)
				(type default)
			)
			(layer "B.Fab")
		)
		(fp_line
			(start -0.12065 -0.3048)
			(end -0.67945 -0.3048)
			(stroke
				(width 0.1)
				(type default)
			)
			(layer "B.Fab")
		)
		(fp_line
			(start 0.12065 -0.305054)
			(end 0.12065 -0.2794)
			(stroke
				(width 0.1)
				(type default)
			)
			(layer "B.Fab")
		)
		(fp_line
			(start 0.67945 -0.305054)
			(end 0.12065 -0.305054)
			(stroke
				(width 0.1)
				(type default)
			)
			(layer "B.Fab")
		)
		(pad "1" smd circle
			(at 0.40005 0 90)
			(size 0 0)
			(layers "B.Cu" "B.Mask" "B.Paste")
			(net "OCP_SFF_PRSNTA_R_N")
		)
		(pad "2" smd circle
			(at -0.40005 0 90)
			(size 0 0)
			(layers "B.Cu" "B.Mask" "B.Paste")
			(net "GND")
		)
	)
	(footprint ""
		(layer "B.Cu")
		(at 123.611386 -252.543564)
		(property "Reference" "C2429"
			(at 0 0 0)
			(layer "B.SilkS")
			(hide yes)
			(effects
				(font
					(size 1.27 1.27)
				)
				(justify mirror)
			)
		)
		(property "Value" ""
			(at 0 0 0)
			(layer "B.Fab")
			(effects
				(font
					(size 1.27 1.27)
				)
				(justify mirror)
			)
		)
		(duplicate_pad_numbers_are_jumpers no)
		(fp_line
			(start -0.7874 -0.4064)
			(end -0.7874 0.4064)
			(stroke
				(width 0.1524)
				(type default)
			)
			(layer "B.SilkS")
		)
		(fp_line
			(start -0.7874 0.4064)
			(end 0.7874 0.4064)
			(stroke
				(width 0.1524)
				(type default)
			)
			(layer "B.SilkS")
		)
		(fp_line
			(start 0.7874 -0.4064)
			(end -0.7874 -0.4064)
			(stroke
				(width 0.1524)
				(type default)
			)
			(layer "B.SilkS")
		)
		(fp_line
			(start 0.7874 0.4064)
			(end 0.7874 -0.4064)
			(stroke
				(width 0.1524)
				(type default)
			)
			(layer "B.SilkS")
		)
		(fp_line
			(start -0.67945 -0.3048)
			(end -0.67945 0.3048)
			(stroke
				(width 0.1)
				(type default)
			)
			(layer "B.Fab")
		)
		(fp_line
			(start -0.67945 0.3048)
			(end -0.120396 0.3048)
			(stroke
				(width 0.1)
				(type default)
			)
			(layer "B.Fab")
		)
		(fp_line
			(start -0.12065 -0.3048)
			(end -0.67945 -0.3048)
			(stroke
				(width 0.1)
				(type default)
			)
			(layer "B.Fab")
		)
		(fp_line
			(start -0.12065 -0.2794)
			(end -0.12065 -0.3048)
			(stroke
				(width 0.1)
				(type default)
			)
			(layer "B.Fab")
		)
		(fp_line
			(start -0.120396 0.2794)
			(end 0.12065 0.2794)
			(stroke
				(width 0.1)
				(type default)
			)
			(layer "B.Fab")
		)
		(fp_line
			(start -0.120396 0.3048)
			(end -0.120396 0.2794)
			(stroke
				(width 0.1)
				(type default)
			)
			(layer "B.Fab")
		)
		(fp_line
			(start 0.12065 -0.305054)
			(end 0.12065 -0.2794)
			(stroke
				(width 0.1)
				(type default)
			)
			(layer "B.Fab")
		)
		(fp_line
			(start 0.12065 -0.2794)
			(end -0.12065 -0.2794)
			(stroke
				(width 0.1)
				(type default)
			)
			(layer "B.Fab")
		)
		(fp_line
			(start 0.12065 0.2794)
			(end 0.12065 0.3048)
			(stroke
				(width 0.1)
				(type default)
			)
			(layer "B.Fab")
		)
		(fp_line
			(start 0.12065 0.3048)
			(end 0.67945 0.3048)
			(stroke
				(width 0.1)
				(type default)
			)
			(layer "B.Fab")
		)
		(fp_line
			(start 0.67945 -0.305054)
			(end 0.12065 -0.305054)
			(stroke
				(width 0.1)
				(type default)
			)
			(layer "B.Fab")
		)
		(fp_line
			(start 0.67945 0.3048)
			(end 0.67945 -0.305054)
			(stroke
				(width 0.1)
				(type default)
			)
			(layer "B.Fab")
		)
		(pad "1" smd circle
			(at 0.40005 0 180)
			(size 0 0)
			(layers "B.Cu" "B.Mask" "B.Paste")
			(net "PVDDCR_SOC_P1")
		)
		(pad "2" smd circle
			(at -0.40005 0 180)
			(size 0 0)
			(layers "B.Cu" "B.Mask" "B.Paste")
			(net "GND")
		)
	)
	(footprint ""
		(layer "B.Cu")
		(at 208.461356 -381.222504)
		(property "Reference" "PR2517"
			(at 0 0 0)
			(layer "B.SilkS")
			(hide yes)
			(effects
				(font
					(size 1.27 1.27)
				)
				(justify mirror)
			)
		)
		(property "Value" ""
			(at 0 0 0)
			(layer "B.Fab")
			(effects
				(font
					(size 1.27 1.27)
				)
				(justify mirror)
			)
		)
		(duplicate_pad_numbers_are_jumpers no)
		(fp_line
			(start -0.7874 -0.4064)
			(end -0.7874 0.4064)
			(stroke
				(width 0.1524)
				(type default)
			)
			(layer "B.SilkS")
		)
		(fp_line
			(start -0.7874 0.4064)
			(end 0.7874 0.4064)
			(stroke
				(width 0.1524)
				(type default)
			)
			(layer "B.SilkS")
		)
		(fp_line
			(start 0.7874 -0.4064)
			(end -0.7874 -0.4064)
			(stroke
				(width 0.1524)
				(type default)
			)
			(layer "B.SilkS")
		)
		(fp_line
			(start 0.7874 0.4064)
			(end 0.7874 -0.4064)
			(stroke
				(width 0.1524)
				(type default)
			)
			(layer "B.SilkS")
		)
		(fp_line
			(start -0.67945 -0.3048)
			(end -0.67945 0.3048)
			(stroke
				(width 0.1)
				(type default)
			)
			(layer "B.Fab")
		)
		(fp_line
			(start -0.67945 0.3048)
			(end -0.120396 0.3048)
			(stroke
				(width 0.1)
				(type default)
			)
			(layer "B.Fab")
		)
		(fp_line
			(start -0.12065 -0.3048)
			(end -0.67945 -0.3048)
			(stroke
				(width 0.1)
				(type default)
			)
			(layer "B.Fab")
		)
		(fp_line
			(start -0.12065 -0.2794)
			(end -0.12065 -0.3048)
			(stroke
				(width 0.1)
				(type default)
			)
			(layer "B.Fab")
		)
		(fp_line
			(start -0.120396 0.2794)
			(end 0.12065 0.2794)
			(stroke
				(width 0.1)
				(type default)
			)
			(layer "B.Fab")
		)
		(fp_line
			(start -0.120396 0.3048)
			(end -0.120396 0.2794)
			(stroke
				(width 0.1)
				(type default)
			)
			(layer "B.Fab")
		)
		(fp_line
			(start 0.12065 -0.305054)
			(end 0.12065 -0.2794)
			(stroke
				(width 0.1)
				(type default)
			)
			(layer "B.Fab")
		)
		(fp_line
			(start 0.12065 -0.2794)
			(end -0.12065 -0.2794)
			(stroke
				(width 0.1)
				(type default)
			)
			(layer "B.Fab")
		)
		(fp_line
			(start 0.12065 0.2794)
			(end 0.12065 0.3048)
			(stroke
				(width 0.1)
				(type default)
			)
			(layer "B.Fab")
		)
		(fp_line
			(start 0.12065 0.3048)
			(end 0.67945 0.3048)
			(stroke
				(width 0.1)
				(type default)
			)
			(layer "B.Fab")
		)
		(fp_line
			(start 0.67945 -0.305054)
			(end 0.12065 -0.305054)
			(stroke
				(width 0.1)
				(type default)
			)
			(layer "B.Fab")
		)
		(fp_line
			(start 0.67945 0.3048)
			(end 0.67945 -0.305054)
			(stroke
				(width 0.1)
				(type default)
			)
			(layer "B.Fab")
		)
		(pad "1" smd circle
			(at 0.40005 0 180)
			(size 0 0)
			(layers "B.Cu" "B.Mask" "B.Paste")
			(net "P12V_HSC_ADC_N")
		)
		(pad "2" smd circle
			(at -0.40005 0 180)
			(size 0 0)
			(layers "B.Cu" "B.Mask" "B.Paste")
			(net "P12V_HSC_SENSE2_R3_N")
		)
	)
	(footprint ""
		(layer "B.Cu")
		(at 73.248774 -184.343548 90)
		(property "Reference" "PC279"
			(at 5.811012 0.851916 270)
			(unlocked yes)
			(layer "B.SilkS")
			(effects
				(font
					(size 0.7874 0.5842)
					(thickness 0.1524)
				)
				(justify left mirror)
			)
		)
		(property "Value" ""
			(at 0 0 90)
			(layer "B.Fab")
			(effects
				(font
					(size 1.27 1.27)
				)
				(justify mirror)
			)
		)
		(duplicate_pad_numbers_are_jumpers no)
		(fp_line
			(start 4.533392 -2.249932)
			(end -4.533392 -2.249932)
			(stroke
				(width 0.1524)
				(type default)
			)
			(layer "B.SilkS")
		)
		(fp_line
			(start -4.533392 -2.249932)
			(end -4.533392 2.249932)
			(stroke
				(width 0.1524)
				(type default)
			)
			(layer "B.SilkS")
		)
		(fp_line
			(start 4.533392 2.249932)
			(end 4.533392 -2.249932)
			(stroke
				(width 0.1524)
				(type default)
			)
			(layer "B.SilkS")
		)
		(fp_line
			(start -4.533392 2.249932)
			(end 4.533392 2.249932)
			(stroke
				(width 0.1524)
				(type default)
			)
			(layer "B.SilkS")
		)
		(fp_rect
			(start 4.533392 -2.326132)
			(end 5.39242 2.326132)
			(stroke
				(width 0)
				(type default)
			)
			(fill yes)
			(layer "B.SilkS")
		)
		(fp_line
			(start 3.750056 -2.249932)
			(end -3.750056 -2.249932)
			(stroke
				(width 0.1)
				(type default)
			)
			(layer "B.Fab")
		)
		(fp_line
			(start -3.750056 -2.249932)
			(end -3.750056 2.249932)
			(stroke
				(width 0.1)
				(type default)
			)
			(layer "B.Fab")
		)
		(fp_line
			(start 3.750056 2.249932)
			(end 3.750056 -2.249932)
			(stroke
				(width 0.1)
				(type default)
			)
			(layer "B.Fab")
		)
		(fp_line
			(start -3.750056 2.249932)
			(end 3.750056 2.249932)
			(stroke
				(width 0.1)
				(type default)
			)
			(layer "B.Fab")
		)
		(fp_text user "+"
			(at 6.322314 0.786384 0)
			(unlocked yes)
			(layer "B.SilkS")
			(effects
				(font
					(size 1.905 1.4224)
					(thickness 0.1524)
				)
				(justify left mirror)
			)
		)
		(fp_text user "-"
			(at -4.83997 0.996696 90)
			(unlocked yes)
			(layer "B.SilkS")
			(effects
				(font
					(size 1.905 1.4224)
					(thickness 0.1524)
				)
				(justify left mirror)
			)
		)
		(fp_text user "-"
			(at -4.8514 -0.14605 90)
			(unlocked yes)
			(layer "B.Fab")
			(effects
				(font
					(size 1.905 1.4224)
					(thickness 0.1524)
				)
				(justify left mirror)
			)
		)
		(fp_text user "+"
			(at 6.322314 0.786384 0)
			(unlocked yes)
			(layer "B.Fab")
			(effects
				(font
					(size 1.905 1.4224)
					(thickness 0.1524)
				)
				(justify left mirror)
			)
		)
		(pad "1" smd rect
			(at 3.199892 0 270)
			(size 2.413 2.8194)
			(layers "B.Cu" "B.Mask" "B.Paste")
			(net "PVDDCR_CPU0_P1")
		)
		(pad "2" smd rect
			(at -3.199892 0 270)
			(size 2.413 2.8194)
			(layers "B.Cu" "B.Mask" "B.Paste")
			(net "GND")
		)
	)
	(footprint ""
		(layer "B.Cu")
		(at 233.807 -332.74 180)
		(property "Reference" "R6773"
			(at 0 0 0)
			(layer "B.SilkS")
			(hide yes)
			(effects
				(font
					(size 1.27 1.27)
				)
				(justify mirror)
			)
		)
		(property "Value" ""
			(at 0 0 0)
			(layer "B.Fab")
			(effects
				(font
					(size 1.27 1.27)
				)
				(justify mirror)
			)
		)
		(duplicate_pad_numbers_are_jumpers no)
		(fp_line
			(start 0.32512 0.175006)
			(end 0.32512 -0.175006)
			(stroke
				(width 0.1)
				(type default)
			)
			(layer "B.Fab")
		)
		(fp_line
			(start 0.32512 -0.175006)
			(end -0.32512 -0.175006)
			(stroke
				(width 0.1)
				(type default)
			)
			(layer "B.Fab")
		)
		(fp_line
			(start -0.32512 0.175006)
			(end 0.32512 0.175006)
			(stroke
				(width 0.1)
				(type default)
			)
			(layer "B.Fab")
		)
		(fp_line
			(start -0.32512 -0.175006)
			(end -0.32512 0.175006)
			(stroke
				(width 0.1)
				(type default)
			)
			(layer "B.Fab")
		)
		(pad "1" smd rect
			(at 0.2667 0)
			(size 0.3048 0.381)
			(layers "B.Cu" "B.Mask" "B.Paste")
			(net "RT_SMB_MUX_ADDR2")
		)
		(pad "2" smd rect
			(at -0.2667 0 180)
			(size 0.3048 0.381)
			(layers "B.Cu" "B.Mask" "B.Paste")
			(net "GND")
		)
	)
	(footprint ""
		(layer "B.Cu")
		(at 273.253454 -190.94831 180)
		(property "Reference" "R295"
			(at 0 0 0)
			(layer "B.SilkS")
			(hide yes)
			(effects
				(font
					(size 1.27 1.27)
				)
				(justify mirror)
			)
		)
		(property "Value" ""
			(at 0 0 0)
			(layer "B.Fab")
			(effects
				(font
					(size 1.27 1.27)
				)
				(justify mirror)
			)
		)
		(duplicate_pad_numbers_are_jumpers no)
		(fp_line
			(start 0.7874 0.4064)
			(end 0.7874 -0.4064)
			(stroke
				(width 0.1524)
				(type default)
			)
			(layer "B.SilkS")
		)
		(fp_line
			(start 0.7874 -0.4064)
			(end -0.7874 -0.4064)
			(stroke
				(width 0.1524)
				(type default)
			)
			(layer "B.SilkS")
		)
		(fp_line
			(start -0.7874 0.4064)
			(end 0.7874 0.4064)
			(stroke
				(width 0.1524)
				(type default)
			)
			(layer "B.SilkS")
		)
		(fp_line
			(start -0.7874 -0.4064)
			(end -0.7874 0.4064)
			(stroke
				(width 0.1524)
				(type default)
			)
			(layer "B.SilkS")
		)
		(fp_line
			(start 0.67945 0.3048)
			(end 0.67945 -0.305054)
			(stroke
				(width 0.1)
				(type default)
			)
			(layer "B.Fab")
		)
		(fp_line
			(start 0.67945 -0.305054)
			(end 0.12065 -0.305054)
			(stroke
				(width 0.1)
				(type default)
			)
			(layer "B.Fab")
		)
		(fp_line
			(start 0.12065 0.3048)
			(end 0.67945 0.3048)
			(stroke
				(width 0.1)
				(type default)
			)
			(layer "B.Fab")
		)
		(fp_line
			(start 0.12065 0.2794)
			(end 0.12065 0.3048)
			(stroke
				(width 0.1)
				(type default)
			)
			(layer "B.Fab")
		)
		(fp_line
			(start 0.12065 -0.2794)
			(end -0.12065 -0.2794)
			(stroke
				(width 0.1)
				(type default)
			)
			(layer "B.Fab")
		)
		(fp_line
			(start 0.12065 -0.305054)
			(end 0.12065 -0.2794)
			(stroke
				(width 0.1)
				(type default)
			)
			(layer "B.Fab")
		)
		(fp_line
			(start -0.120396 0.3048)
			(end -0.120396 0.2794)
			(stroke
				(width 0.1)
				(type default)
			)
			(layer "B.Fab")
		)
		(fp_line
			(start -0.120396 0.2794)
			(end 0.12065 0.2794)
			(stroke
				(width 0.1)
				(type default)
			)
			(layer "B.Fab")
		)
		(fp_line
			(start -0.12065 -0.2794)
			(end -0.12065 -0.3048)
			(stroke
				(width 0.1)
				(type default)
			)
			(layer "B.Fab")
		)
		(fp_line
			(start -0.12065 -0.3048)
			(end -0.67945 -0.3048)
			(stroke
				(width 0.1)
				(type default)
			)
			(layer "B.Fab")
		)
		(fp_line
			(start -0.67945 0.3048)
			(end -0.120396 0.3048)
			(stroke
				(width 0.1)
				(type default)
			)
			(layer "B.Fab")
		)
		(fp_line
			(start -0.67945 -0.3048)
			(end -0.67945 0.3048)
			(stroke
				(width 0.1)
				(type default)
			)
			(layer "B.Fab")
		)
		(pad "1" smd circle
			(at 0.40005 0)
			(size 0 0)
			(layers "B.Cu" "B.Mask" "B.Paste")
			(net "PWRGD_CHE_CPU0_DIMM")
		)
		(pad "2" smd circle
			(at -0.40005 0)
			(size 0 0)
			(layers "B.Cu" "B.Mask" "B.Paste")
			(net "PWRGD_CHAF_CPU0")
		)
	)
	(footprint ""
		(layer "B.Cu")
		(at 111.125 -413.004)
		(property "Reference" "R585"
			(at 0 0 0)
			(layer "B.SilkS")
			(hide yes)
			(effects
				(font
					(size 1.27 1.27)
				)
				(justify mirror)
			)
		)
		(property "Value" ""
			(at 0 0 0)
			(layer "B.Fab")
			(effects
				(font
					(size 1.27 1.27)
				)
				(justify mirror)
			)
		)
		(duplicate_pad_numbers_are_jumpers no)
		(fp_line
			(start -0.7874 -0.4064)
			(end -0.7874 0.4064)
			(stroke
				(width 0.1524)
				(type default)
			)
			(layer "B.SilkS")
		)
		(fp_line
			(start -0.7874 0.4064)
			(end 0.7874 0.4064)
			(stroke
				(width 0.1524)
				(type default)
			)
			(layer "B.SilkS")
		)
		(fp_line
			(start 0.7874 -0.4064)
			(end -0.7874 -0.4064)
			(stroke
				(width 0.1524)
				(type default)
			)
			(layer "B.SilkS")
		)
		(fp_line
			(start 0.7874 0.4064)
			(end 0.7874 -0.4064)
			(stroke
				(width 0.1524)
				(type default)
			)
			(layer "B.SilkS")
		)
		(fp_line
			(start -0.67945 -0.3048)
			(end -0.67945 0.3048)
			(stroke
				(width 0.1)
				(type default)
			)
			(layer "B.Fab")
		)
		(fp_line
			(start -0.67945 0.3048)
			(end -0.120396 0.3048)
			(stroke
				(width 0.1)
				(type default)
			)
			(layer "B.Fab")
		)
		(fp_line
			(start -0.12065 -0.3048)
			(end -0.67945 -0.3048)
			(stroke
				(width 0.1)
				(type default)
			)
			(layer "B.Fab")
		)
		(fp_line
			(start -0.12065 -0.2794)
			(end -0.12065 -0.3048)
			(stroke
				(width 0.1)
				(type default)
			)
			(layer "B.Fab")
		)
		(fp_line
			(start -0.120396 0.2794)
			(end 0.12065 0.2794)
			(stroke
				(width 0.1)
				(type default)
			)
			(layer "B.Fab")
		)
		(fp_line
			(start -0.120396 0.3048)
			(end -0.120396 0.2794)
			(stroke
				(width 0.1)
				(type default)
			)
			(layer "B.Fab")
		)
		(fp_line
			(start 0.12065 -0.305054)
			(end 0.12065 -0.2794)
			(stroke
				(width 0.1)
				(type default)
			)
			(layer "B.Fab")
		)
		(fp_line
			(start 0.12065 -0.2794)
			(end -0.12065 -0.2794)
			(stroke
				(width 0.1)
				(type default)
			)
			(layer "B.Fab")
		)
		(fp_line
			(start 0.12065 0.2794)
			(end 0.12065 0.3048)
			(stroke
				(width 0.1)
				(type default)
			)
			(layer "B.Fab")
		)
		(fp_line
			(start 0.12065 0.3048)
			(end 0.67945 0.3048)
			(stroke
				(width 0.1)
				(type default)
			)
			(layer "B.Fab")
		)
		(fp_line
			(start 0.67945 -0.305054)
			(end 0.12065 -0.305054)
			(stroke
				(width 0.1)
				(type default)
			)
			(layer "B.Fab")
		)
		(fp_line
			(start 0.67945 0.3048)
			(end 0.67945 -0.305054)
			(stroke
				(width 0.1)
				(type default)
			)
			(layer "B.Fab")
		)
		(pad "1" smd circle
			(at 0.40005 0 180)
			(size 0 0)
			(layers "B.Cu" "B.Mask" "B.Paste")
			(net "CLK_9ZXL045_P1_HIBW")
		)
		(pad "2" smd circle
			(at -0.40005 0 180)
			(size 0 0)
			(layers "B.Cu" "B.Mask" "B.Paste")
			(net "GND")
		)
	)
	(footprint ""
		(layer "B.Cu")
		(at 346.518992 -257.930142 180)
		(property "Reference" "C2618"
			(at 0 0 0)
			(layer "B.SilkS")
			(hide yes)
			(effects
				(font
					(size 1.27 1.27)
				)
				(justify mirror)
			)
		)
		(property "Value" ""
			(at 0 0 0)
			(layer "B.Fab")
			(effects
				(font
					(size 1.27 1.27)
				)
				(justify mirror)
			)
		)
		(duplicate_pad_numbers_are_jumpers no)
		(fp_line
			(start 0.7874 0.4064)
			(end 0.7874 -0.4064)
			(stroke
				(width 0.1524)
				(type default)
			)
			(layer "B.SilkS")
		)
		(fp_line
			(start 0.7874 -0.4064)
			(end -0.7874 -0.4064)
			(stroke
				(width 0.1524)
				(type default)
			)
			(layer "B.SilkS")
		)
		(fp_line
			(start -0.7874 0.4064)
			(end 0.7874 0.4064)
			(stroke
				(width 0.1524)
				(type default)
			)
			(layer "B.SilkS")
		)
		(fp_line
			(start -0.7874 -0.4064)
			(end -0.7874 0.4064)
			(stroke
				(width 0.1524)
				(type default)
			)
			(layer "B.SilkS")
		)
		(fp_line
			(start 0.67945 0.3048)
			(end 0.67945 -0.305054)
			(stroke
				(width 0.1)
				(type default)
			)
			(layer "B.Fab")
		)
		(fp_line
			(start 0.67945 -0.305054)
			(end 0.12065 -0.305054)
			(stroke
				(width 0.1)
				(type default)
			)
			(layer "B.Fab")
		)
		(fp_line
			(start 0.12065 0.3048)
			(end 0.67945 0.3048)
			(stroke
				(width 0.1)
				(type default)
			)
			(layer "B.Fab")
		)
		(fp_line
			(start 0.12065 0.2794)
			(end 0.12065 0.3048)
			(stroke
				(width 0.1)
				(type default)
			)
			(layer "B.Fab")
		)
		(fp_line
			(start 0.12065 -0.2794)
			(end -0.12065 -0.2794)
			(stroke
				(width 0.1)
				(type default)
			)
			(layer "B.Fab")
		)
		(fp_line
			(start 0.12065 -0.305054)
			(end 0.12065 -0.2794)
			(stroke
				(width 0.1)
				(type default)
			)
			(layer "B.Fab")
		)
		(fp_line
			(start -0.120396 0.3048)
			(end -0.120396 0.2794)
			(stroke
				(width 0.1)
				(type default)
			)
			(layer "B.Fab")
		)
		(fp_line
			(start -0.120396 0.2794)
			(end 0.12065 0.2794)
			(stroke
				(width 0.1)
				(type default)
			)
			(layer "B.Fab")
		)
		(fp_line
			(start -0.12065 -0.2794)
			(end -0.12065 -0.3048)
			(stroke
				(width 0.1)
				(type default)
			)
			(layer "B.Fab")
		)
		(fp_line
			(start -0.12065 -0.3048)
			(end -0.67945 -0.3048)
			(stroke
				(width 0.1)
				(type default)
			)
			(layer "B.Fab")
		)
		(fp_line
			(start -0.67945 0.3048)
			(end -0.120396 0.3048)
			(stroke
				(width 0.1)
				(type default)
			)
			(layer "B.Fab")
		)
		(fp_line
			(start -0.67945 -0.3048)
			(end -0.67945 0.3048)
			(stroke
				(width 0.1)
				(type default)
			)
			(layer "B.Fab")
		)
		(pad "1" smd circle
			(at 0.40005 0)
			(size 0 0)
			(layers "B.Cu" "B.Mask" "B.Paste")
			(net "PVDDIO_P0")
		)
		(pad "2" smd circle
			(at -0.40005 0)
			(size 0 0)
			(layers "B.Cu" "B.Mask" "B.Paste")
			(net "GND")
		)
	)
	(footprint ""
		(layer "B.Cu")
		(at 83.50631 -386.766562 90)
		(property "Reference" "C294"
			(at 0 0 90)
			(layer "B.SilkS")
			(hide yes)
			(effects
				(font
					(size 1.27 1.27)
				)
				(justify mirror)
			)
		)
		(property "Value" ""
			(at 0 0 90)
			(layer "B.Fab")
			(effects
				(font
					(size 1.27 1.27)
				)
				(justify mirror)
			)
		)
		(duplicate_pad_numbers_are_jumpers no)
		(fp_line
			(start 0.299974 -0.150114)
			(end -0.299974 -0.150114)
			(stroke
				(width 0.1)
				(type default)
			)
			(layer "B.Fab")
		)
		(fp_line
			(start -0.299974 -0.150114)
			(end -0.299974 0.150114)
			(stroke
				(width 0.1)
				(type default)
			)
			(layer "B.Fab")
		)
		(fp_line
			(start 0.299974 0.150114)
			(end 0.299974 -0.150114)
			(stroke
				(width 0.1)
				(type default)
			)
			(layer "B.Fab")
		)
		(fp_line
			(start -0.299974 0.150114)
			(end 0.299974 0.150114)
			(stroke
				(width 0.1)
				(type default)
			)
			(layer "B.Fab")
		)
		(pad "1" smd rect
			(at 0.2667 0 270)
			(size 0.3048 0.381)
			(layers "B.Cu" "B.Mask" "B.Paste")
			(net "P0V9_CPU1_RT1_2A")
		)
		(pad "2" smd rect
			(at -0.2667 0 270)
			(size 0.3048 0.381)
			(layers "B.Cu" "B.Mask" "B.Paste")
			(net "GND")
		)
	)
	(footprint ""
		(layer "B.Cu")
		(at 189.865 -100.294948 90)
		(property "Reference" "R221"
			(at 0 0 90)
			(layer "B.SilkS")
			(hide yes)
			(effects
				(font
					(size 1.27 1.27)
				)
				(justify mirror)
			)
		)
		(property "Value" ""
			(at 0 0 90)
			(layer "B.Fab")
			(effects
				(font
					(size 1.27 1.27)
				)
				(justify mirror)
			)
		)
		(duplicate_pad_numbers_are_jumpers no)
		(fp_line
			(start 0.7874 -0.4064)
			(end -0.7874 -0.4064)
			(stroke
				(width 0.1524)
				(type default)
			)
			(layer "B.SilkS")
		)
		(fp_line
			(start -0.7874 -0.4064)
			(end -0.7874 0.4064)
			(stroke
				(width 0.1524)
				(type default)
			)
			(layer "B.SilkS")
		)
		(fp_line
			(start 0.7874 0.4064)
			(end 0.7874 -0.4064)
			(stroke
				(width 0.1524)
				(type default)
			)
			(layer "B.SilkS")
		)
		(fp_line
			(start -0.7874 0.4064)
			(end 0.7874 0.4064)
			(stroke
				(width 0.1524)
				(type default)
			)
			(layer "B.SilkS")
		)
		(fp_line
			(start 0.67945 -0.305054)
			(end 0.12065 -0.305054)
			(stroke
				(width 0.1)
				(type default)
			)
			(layer "B.Fab")
		)
		(fp_line
			(start 0.12065 -0.305054)
			(end 0.12065 -0.2794)
			(stroke
				(width 0.1)
				(type default)
			)
			(layer "B.Fab")
		)
		(fp_line
			(start -0.12065 -0.3048)
			(end -0.67945 -0.3048)
			(stroke
				(width 0.1)
				(type default)
			)
			(layer "B.Fab")
		)
		(fp_line
			(start -0.67945 -0.3048)
			(end -0.67945 0.3048)
			(stroke
				(width 0.1)
				(type default)
			)
			(layer "B.Fab")
		)
		(fp_line
			(start 0.12065 -0.2794)
			(end -0.12065 -0.2794)
			(stroke
				(width 0.1)
				(type default)
			)
			(layer "B.Fab")
		)
		(fp_line
			(start -0.12065 -0.2794)
			(end -0.12065 -0.3048)
			(stroke
				(width 0.1)
				(type default)
			)
			(layer "B.Fab")
		)
		(fp_line
			(start 0.12065 0.2794)
			(end 0.12065 0.3048)
			(stroke
				(width 0.1)
				(type default)
			)
			(layer "B.Fab")
		)
		(fp_line
			(start -0.120396 0.2794)
			(end 0.12065 0.2794)
			(stroke
				(width 0.1)
				(type default)
			)
			(layer "B.Fab")
		)
		(fp_line
			(start 0.67945 0.3048)
			(end 0.67945 -0.305054)
			(stroke
				(width 0.1)
				(type default)
			)
			(layer "B.Fab")
		)
		(fp_line
			(start 0.12065 0.3048)
			(end 0.67945 0.3048)
			(stroke
				(width 0.1)
				(type default)
			)
			(layer "B.Fab")
		)
		(fp_line
			(start -0.120396 0.3048)
			(end -0.120396 0.2794)
			(stroke
				(width 0.1)
				(type default)
			)
			(layer "B.Fab")
		)
		(fp_line
			(start -0.67945 0.3048)
			(end -0.120396 0.3048)
			(stroke
				(width 0.1)
				(type default)
			)
			(layer "B.Fab")
		)
		(pad "1" smd circle
			(at 0.40005 0 270)
			(size 0 0)
			(layers "B.Cu" "B.Mask" "B.Paste")
			(net "FM_CPU0_SA1")
		)
		(pad "2" smd circle
			(at -0.40005 0 270)
			(size 0 0)
			(layers "B.Cu" "B.Mask" "B.Paste")
			(net "CPU0_SA1")
		)
	)
	(footprint ""
		(layer "B.Cu")
		(at 136.459468 -41.028112 90)
		(property "Reference" "C6030"
			(at 0 0 90)
			(layer "B.SilkS")
			(hide yes)
			(effects
				(font
					(size 1.27 1.27)
				)
				(justify mirror)
			)
		)
		(property "Value" ""
			(at 0 0 90)
			(layer "B.Fab")
			(effects
				(font
					(size 1.27 1.27)
				)
				(justify mirror)
			)
		)
		(duplicate_pad_numbers_are_jumpers no)
		(fp_line
			(start 1.2954 -0.5842)
			(end -1.2954 -0.5842)
			(stroke
				(width 0.1524)
				(type default)
			)
			(layer "B.SilkS")
		)
		(fp_line
			(start -1.2954 -0.5842)
			(end -1.2954 0.5842)
			(stroke
				(width 0.1524)
				(type default)
			)
			(layer "B.SilkS")
		)
		(fp_line
			(start 1.2954 0.5842)
			(end 1.2954 -0.5842)
			(stroke
				(width 0.1524)
				(type default)
			)
			(layer "B.SilkS")
		)
		(fp_line
			(start -1.2954 0.5842)
			(end 1.2954 0.5842)
			(stroke
				(width 0.1524)
				(type default)
			)
			(layer "B.SilkS")
		)
		(fp_line
			(start 0.8636 -0.4572)
			(end -0.8636 -0.4572)
			(stroke
				(width 0.1)
				(type default)
			)
			(layer "B.Fab")
		)
		(fp_line
			(start -0.8636 -0.4572)
			(end -0.8636 -0.4064)
			(stroke
				(width 0.1)
				(type default)
			)
			(layer "B.Fab")
		)
		(fp_line
			(start 1.1938 -0.4064)
			(end 0.8636 -0.4064)
			(stroke
				(width 0.1)
				(type default)
			)
			(layer "B.Fab")
		)
		(fp_line
			(start 0.8636 -0.4064)
			(end 0.8636 -0.4572)
			(stroke
				(width 0.1)
				(type default)
			)
			(layer "B.Fab")
		)
		(fp_line
			(start -0.8636 -0.4064)
			(end -1.1938 -0.4064)
			(stroke
				(width 0.1)
				(type default)
			)
			(layer "B.Fab")
		)
		(fp_line
			(start -1.1938 -0.4064)
			(end -1.1938 0.4064)
			(stroke
				(width 0.1)
				(type default)
			)
			(layer "B.Fab")
		)
		(fp_line
			(start 1.1938 0.4064)
			(end 1.1938 -0.4064)
			(stroke
				(width 0.1)
				(type default)
			)
			(layer "B.Fab")
		)
		(fp_line
			(start 0.8636 0.4064)
			(end 1.1938 0.4064)
			(stroke
				(width 0.1)
				(type default)
			)
			(layer "B.Fab")
		)
		(fp_line
			(start -0.8636 0.4064)
			(end -0.8636 0.4572)
			(stroke
				(width 0.1)
				(type default)
			)
			(layer "B.Fab")
		)
		(fp_line
			(start -1.1938 0.4064)
			(end -0.8636 0.4064)
			(stroke
				(width 0.1)
				(type default)
			)
			(layer "B.Fab")
		)
		(fp_line
			(start 0.8636 0.4572)
			(end 0.8636 0.4064)
			(stroke
				(width 0.1)
				(type default)
			)
			(layer "B.Fab")
		)
		(fp_line
			(start -0.8636 0.4572)
			(end 0.8636 0.4572)
			(stroke
				(width 0.1)
				(type default)
			)
			(layer "B.Fab")
		)
		(pad "1" smd rect
			(at 0.7366 0)
			(size 0.7112 0.8128)
			(layers "B.Cu" "B.Mask" "B.Paste")
			(net "P1V2_CPU0_USB_DVDD12")
		)
		(pad "2" smd rect
			(at -0.7366 0)
			(size 0.7112 0.8128)
			(layers "B.Cu" "B.Mask" "B.Paste")
			(net "GND")
		)
	)
	(footprint ""
		(layer "B.Cu")
		(at 172.72762 -194.885564 180)
		(property "Reference" "R774"
			(at 0 0 0)
			(layer "B.SilkS")
			(hide yes)
			(effects
				(font
					(size 1.27 1.27)
				)
				(justify mirror)
			)
		)
		(property "Value" ""
			(at 0 0 0)
			(layer "B.Fab")
			(effects
				(font
					(size 1.27 1.27)
				)
				(justify mirror)
			)
		)
		(duplicate_pad_numbers_are_jumpers no)
		(fp_line
			(start 0.7874 0.4064)
			(end 0.7874 -0.4064)
			(stroke
				(width 0.1524)
				(type default)
			)
			(layer "B.SilkS")
		)
		(fp_line
			(start 0.7874 -0.4064)
			(end -0.7874 -0.4064)
			(stroke
				(width 0.1524)
				(type default)
			)
			(layer "B.SilkS")
		)
		(fp_line
			(start -0.7874 0.4064)
			(end 0.7874 0.4064)
			(stroke
				(width 0.1524)
				(type default)
			)
			(layer "B.SilkS")
		)
		(fp_line
			(start -0.7874 -0.4064)
			(end -0.7874 0.4064)
			(stroke
				(width 0.1524)
				(type default)
			)
			(layer "B.SilkS")
		)
		(fp_line
			(start 0.67945 0.3048)
			(end 0.67945 -0.305054)
			(stroke
				(width 0.1)
				(type default)
			)
			(layer "B.Fab")
		)
		(fp_line
			(start 0.67945 -0.305054)
			(end 0.12065 -0.305054)
			(stroke
				(width 0.1)
				(type default)
			)
			(layer "B.Fab")
		)
		(fp_line
			(start 0.12065 0.3048)
			(end 0.67945 0.3048)
			(stroke
				(width 0.1)
				(type default)
			)
			(layer "B.Fab")
		)
		(fp_line
			(start 0.12065 0.2794)
			(end 0.12065 0.3048)
			(stroke
				(width 0.1)
				(type default)
			)
			(layer "B.Fab")
		)
		(fp_line
			(start 0.12065 -0.2794)
			(end -0.12065 -0.2794)
			(stroke
				(width 0.1)
				(type default)
			)
			(layer "B.Fab")
		)
		(fp_line
			(start 0.12065 -0.305054)
			(end 0.12065 -0.2794)
			(stroke
				(width 0.1)
				(type default)
			)
			(layer "B.Fab")
		)
		(fp_line
			(start -0.120396 0.3048)
			(end -0.120396 0.2794)
			(stroke
				(width 0.1)
				(type default)
			)
			(layer "B.Fab")
		)
		(fp_line
			(start -0.120396 0.2794)
			(end 0.12065 0.2794)
			(stroke
				(width 0.1)
				(type default)
			)
			(layer "B.Fab")
		)
		(fp_line
			(start -0.12065 -0.2794)
			(end -0.12065 -0.3048)
			(stroke
				(width 0.1)
				(type default)
			)
			(layer "B.Fab")
		)
		(fp_line
			(start -0.12065 -0.3048)
			(end -0.67945 -0.3048)
			(stroke
				(width 0.1)
				(type default)
			)
			(layer "B.Fab")
		)
		(fp_line
			(start -0.67945 0.3048)
			(end -0.120396 0.3048)
			(stroke
				(width 0.1)
				(type default)
			)
			(layer "B.Fab")
		)
		(fp_line
			(start -0.67945 -0.3048)
			(end -0.67945 0.3048)
			(stroke
				(width 0.1)
				(type default)
			)
			(layer "B.Fab")
		)
		(pad "1" smd circle
			(at 0.40005 0)
			(size 0 0)
			(layers "B.Cu" "B.Mask" "B.Paste")
			(net "PD_CHH_CPU1_DIMM_SAA")
		)
		(pad "2" smd circle
			(at -0.40005 0)
			(size 0 0)
			(layers "B.Cu" "B.Mask" "B.Paste")
			(net "GND")
		)
	)
	(footprint ""
		(layer "B.Cu")
		(at 307.34127 -194.98691 180)
		(property "Reference" "R1568"
			(at 0 0 0)
			(layer "B.SilkS")
			(hide yes)
			(effects
				(font
					(size 1.27 1.27)
				)
				(justify mirror)
			)
		)
		(property "Value" ""
			(at 0 0 0)
			(layer "B.Fab")
			(effects
				(font
					(size 1.27 1.27)
				)
				(justify mirror)
			)
		)
		(duplicate_pad_numbers_are_jumpers no)
		(fp_line
			(start 0.7874 0.4064)
			(end 0.7874 -0.4064)
			(stroke
				(width 0.1524)
				(type default)
			)
			(layer "B.SilkS")
		)
		(fp_line
			(start 0.7874 -0.4064)
			(end -0.7874 -0.4064)
			(stroke
				(width 0.1524)
				(type default)
			)
			(layer "B.SilkS")
		)
		(fp_line
			(start -0.7874 0.4064)
			(end 0.7874 0.4064)
			(stroke
				(width 0.1524)
				(type default)
			)
			(layer "B.SilkS")
		)
		(fp_line
			(start -0.7874 -0.4064)
			(end -0.7874 0.4064)
			(stroke
				(width 0.1524)
				(type default)
			)
			(layer "B.SilkS")
		)
		(fp_line
			(start 0.67945 0.3048)
			(end 0.67945 -0.305054)
			(stroke
				(width 0.1)
				(type default)
			)
			(layer "B.Fab")
		)
		(fp_line
			(start 0.67945 -0.305054)
			(end 0.12065 -0.305054)
			(stroke
				(width 0.1)
				(type default)
			)
			(layer "B.Fab")
		)
		(fp_line
			(start 0.12065 0.3048)
			(end 0.67945 0.3048)
			(stroke
				(width 0.1)
				(type default)
			)
			(layer "B.Fab")
		)
		(fp_line
			(start 0.12065 0.2794)
			(end 0.12065 0.3048)
			(stroke
				(width 0.1)
				(type default)
			)
			(layer "B.Fab")
		)
		(fp_line
			(start 0.12065 -0.2794)
			(end -0.12065 -0.2794)
			(stroke
				(width 0.1)
				(type default)
			)
			(layer "B.Fab")
		)
		(fp_line
			(start 0.12065 -0.305054)
			(end 0.12065 -0.2794)
			(stroke
				(width 0.1)
				(type default)
			)
			(layer "B.Fab")
		)
		(fp_line
			(start -0.120396 0.3048)
			(end -0.120396 0.2794)
			(stroke
				(width 0.1)
				(type default)
			)
			(layer "B.Fab")
		)
		(fp_line
			(start -0.120396 0.2794)
			(end 0.12065 0.2794)
			(stroke
				(width 0.1)
				(type default)
			)
			(layer "B.Fab")
		)
		(fp_line
			(start -0.12065 -0.2794)
			(end -0.12065 -0.3048)
			(stroke
				(width 0.1)
				(type default)
			)
			(layer "B.Fab")
		)
		(fp_line
			(start -0.12065 -0.3048)
			(end -0.67945 -0.3048)
			(stroke
				(width 0.1)
				(type default)
			)
			(layer "B.Fab")
		)
		(fp_line
			(start -0.67945 0.3048)
			(end -0.120396 0.3048)
			(stroke
				(width 0.1)
				(type default)
			)
			(layer "B.Fab")
		)
		(fp_line
			(start -0.67945 -0.3048)
			(end -0.67945 0.3048)
			(stroke
				(width 0.1)
				(type default)
			)
			(layer "B.Fab")
		)
		(pad "1" smd circle
			(at 0.40005 0)
			(size 0 0)
			(layers "B.Cu" "B.Mask" "B.Paste")
			(net "I3C_SPD_DDRAF_CPU0_SCL")
		)
		(pad "2" smd circle
			(at -0.40005 0)
			(size 0 0)
			(layers "B.Cu" "B.Mask" "B.Paste")
			(net "I3C_SPD_DDRA_CPU0_SCL")
		)
	)
	(footprint ""
		(layer "B.Cu")
		(at 453.432418 -195.92671 180)
		(property "Reference" "R1686"
			(at 0 0 0)
			(layer "B.SilkS")
			(hide yes)
			(effects
				(font
					(size 1.27 1.27)
				)
				(justify mirror)
			)
		)
		(property "Value" ""
			(at 0 0 0)
			(layer "B.Fab")
			(effects
				(font
					(size 1.27 1.27)
				)
				(justify mirror)
			)
		)
		(duplicate_pad_numbers_are_jumpers no)
		(fp_line
			(start 0.7874 0.4064)
			(end 0.7874 -0.4064)
			(stroke
				(width 0.1524)
				(type default)
			)
			(layer "B.SilkS")
		)
		(fp_line
			(start 0.7874 -0.4064)
			(end -0.7874 -0.4064)
			(stroke
				(width 0.1524)
				(type default)
			)
			(layer "B.SilkS")
		)
		(fp_line
			(start -0.7874 0.4064)
			(end 0.7874 0.4064)
			(stroke
				(width 0.1524)
				(type default)
			)
			(layer "B.SilkS")
		)
		(fp_line
			(start -0.7874 -0.4064)
			(end -0.7874 0.4064)
			(stroke
				(width 0.1524)
				(type default)
			)
			(layer "B.SilkS")
		)
		(fp_line
			(start 0.67945 0.3048)
			(end 0.67945 -0.305054)
			(stroke
				(width 0.1)
				(type default)
			)
			(layer "B.Fab")
		)
		(fp_line
			(start 0.67945 -0.305054)
			(end 0.12065 -0.305054)
			(stroke
				(width 0.1)
				(type default)
			)
			(layer "B.Fab")
		)
		(fp_line
			(start 0.12065 0.3048)
			(end 0.67945 0.3048)
			(stroke
				(width 0.1)
				(type default)
			)
			(layer "B.Fab")
		)
		(fp_line
			(start 0.12065 0.2794)
			(end 0.12065 0.3048)
			(stroke
				(width 0.1)
				(type default)
			)
			(layer "B.Fab")
		)
		(fp_line
			(start 0.12065 -0.2794)
			(end -0.12065 -0.2794)
			(stroke
				(width 0.1)
				(type default)
			)
			(layer "B.Fab")
		)
		(fp_line
			(start 0.12065 -0.305054)
			(end 0.12065 -0.2794)
			(stroke
				(width 0.1)
				(type default)
			)
			(layer "B.Fab")
		)
		(fp_line
			(start -0.120396 0.3048)
			(end -0.120396 0.2794)
			(stroke
				(width 0.1)
				(type default)
			)
			(layer "B.Fab")
		)
		(fp_line
			(start -0.120396 0.2794)
			(end 0.12065 0.2794)
			(stroke
				(width 0.1)
				(type default)
			)
			(layer "B.Fab")
		)
		(fp_line
			(start -0.12065 -0.2794)
			(end -0.12065 -0.3048)
			(stroke
				(width 0.1)
				(type default)
			)
			(layer "B.Fab")
		)
		(fp_line
			(start -0.12065 -0.3048)
			(end -0.67945 -0.3048)
			(stroke
				(width 0.1)
				(type default)
			)
			(layer "B.Fab")
		)
		(fp_line
			(start -0.67945 0.3048)
			(end -0.120396 0.3048)
			(stroke
				(width 0.1)
				(type default)
			)
			(layer "B.Fab")
		)
		(fp_line
			(start -0.67945 -0.3048)
			(end -0.67945 0.3048)
			(stroke
				(width 0.1)
				(type default)
			)
			(layer "B.Fab")
		)
		(pad "1" smd circle
			(at 0.40005 0)
			(size 0 0)
			(layers "B.Cu" "B.Mask" "B.Paste")
			(net "I3C_SPD_DDRGL_CPU0_SDA")
		)
		(pad "2" smd circle
			(at -0.40005 0)
			(size 0 0)
			(layers "B.Cu" "B.Mask" "B.Paste")
			(net "I3C_SPD_DDRL_CPU0_SDA")
		)
	)
	(footprint ""
		(layer "B.Cu")
		(at 102.214934 -252.234192 60)
		(property "Reference" "C2409"
			(at 0 0 60)
			(layer "B.SilkS")
			(hide yes)
			(effects
				(font
					(size 1.27 1.27)
				)
				(justify mirror)
			)
		)
		(property "Value" ""
			(at 0 0 60)
			(layer "B.Fab")
			(effects
				(font
					(size 1.27 1.27)
				)
				(justify mirror)
			)
		)
		(duplicate_pad_numbers_are_jumpers no)
		(fp_line
			(start -0.787516 -0.406438)
			(end -0.787425 0.40652)
			(stroke
				(width 0.1524)
				(type default)
			)
			(layer "B.SilkS")
		)
		(fp_line
			(start -0.787425 0.40652)
			(end 0.787516 0.406438)
			(stroke
				(width 0.1524)
				(type default)
			)
			(layer "B.SilkS")
		)
		(fp_line
			(start 0.787425 -0.40652)
			(end -0.787516 -0.406438)
			(stroke
				(width 0.1524)
				(type default)
			)
			(layer "B.SilkS")
		)
		(fp_line
			(start 0.787516 0.406438)
			(end 0.787425 -0.40652)
			(stroke
				(width 0.1524)
				(type default)
			)
			(layer "B.SilkS")
		)
		(fp_line
			(start -0.679568 -0.304811)
			(end -0.6795 0.304908)
			(stroke
				(width 0.1)
				(type default)
			)
			(layer "B.Fab")
		)
		(fp_line
			(start -0.120605 -0.304905)
			(end -0.679568 -0.304811)
			(stroke
				(width 0.1)
				(type default)
			)
			(layer "B.Fab")
		)
		(fp_line
			(start -0.120554 -0.279418)
			(end -0.120605 -0.304905)
			(stroke
				(width 0.1)
				(type default)
			)
			(layer "B.Fab")
		)
		(fp_line
			(start 0.120629 -0.30516)
			(end 0.120587 -0.279326)
			(stroke
				(width 0.1)
				(type default)
			)
			(layer "B.Fab")
		)
		(fp_line
			(start 0.120587 -0.279326)
			(end -0.120554 -0.279418)
			(stroke
				(width 0.1)
				(type default)
			)
			(layer "B.Fab")
		)
		(fp_line
			(start -0.6795 0.304908)
			(end -0.120316 0.304686)
			(stroke
				(width 0.1)
				(type default)
			)
			(layer "B.Fab")
		)
		(fp_line
			(start 0.679373 -0.305128)
			(end 0.120629 -0.30516)
			(stroke
				(width 0.1)
				(type default)
			)
			(layer "B.Fab")
		)
		(fp_line
			(start -0.12024 0.279419)
			(end 0.120554 0.279418)
			(stroke
				(width 0.1)
				(type default)
			)
			(layer "B.Fab")
		)
		(fp_line
			(start -0.120316 0.304686)
			(end -0.12024 0.279419)
			(stroke
				(width 0.1)
				(type default)
			)
			(layer "B.Fab")
		)
		(fp_line
			(start 0.120554 0.279418)
			(end 0.120605 0.304905)
			(stroke
				(width 0.1)
				(type default)
			)
			(layer "B.Fab")
		)
		(fp_line
			(start 0.120605 0.304905)
			(end 0.679568 0.304811)
			(stroke
				(width 0.1)
				(type default)
			)
			(layer "B.Fab")
		)
		(fp_line
			(start 0.679568 0.304811)
			(end 0.679373 -0.305128)
			(stroke
				(width 0.1)
				(type default)
			)
			(layer "B.Fab")
		)
		(pad "1" smd circle
			(at 0.40005 0 240)
			(size 0 0)
			(layers "B.Cu" "B.Mask" "B.Paste")
			(net "PVDDCR_SOC_P1")
		)
		(pad "2" smd circle
			(at -0.40005 0 240)
			(size 0 0)
			(layers "B.Cu" "B.Mask" "B.Paste")
			(net "GND")
		)
	)
	(footprint ""
		(layer "B.Cu")
		(at 49.300384 -408.517344 90)
		(property "Reference" "C6662"
			(at 0 0 90)
			(layer "B.SilkS")
			(hide yes)
			(effects
				(font
					(size 1.27 1.27)
				)
				(justify mirror)
			)
		)
		(property "Value" ""
			(at 0 0 90)
			(layer "B.Fab")
			(effects
				(font
					(size 1.27 1.27)
				)
				(justify mirror)
			)
		)
		(duplicate_pad_numbers_are_jumpers no)
		(fp_line
			(start 0.299974 -0.150114)
			(end -0.299974 -0.150114)
			(stroke
				(width 0.1)
				(type default)
			)
			(layer "B.Fab")
		)
		(fp_line
			(start -0.299974 -0.150114)
			(end -0.299974 0.150114)
			(stroke
				(width 0.1)
				(type default)
			)
			(layer "B.Fab")
		)
		(fp_line
			(start 0.299974 0.150114)
			(end 0.299974 -0.150114)
			(stroke
				(width 0.1)
				(type default)
			)
			(layer "B.Fab")
		)
		(fp_line
			(start -0.299974 0.150114)
			(end 0.299974 0.150114)
			(stroke
				(width 0.1)
				(type default)
			)
			(layer "B.Fab")
		)
		(pad "1" smd rect
			(at 0.2667 0 270)
			(size 0.3048 0.381)
			(layers "B.Cu" "B.Mask" "B.Paste")
			(net "P5E_CPU1_P1_TX_BUF_C_DN<0>")
		)
		(pad "2" smd rect
			(at -0.2667 0 270)
			(size 0.3048 0.381)
			(layers "B.Cu" "B.Mask" "B.Paste")
			(net "P5E_CPU1_P1_TX_BUF_DN<0>")
		)
	)
	(footprint ""
		(layer "B.Cu")
		(at 132.478526 -386.766562 90)
		(property "Reference" "C448"
			(at 0 0 90)
			(layer "B.SilkS")
			(hide yes)
			(effects
				(font
					(size 1.27 1.27)
				)
				(justify mirror)
			)
		)
		(property "Value" ""
			(at 0 0 90)
			(layer "B.Fab")
			(effects
				(font
					(size 1.27 1.27)
				)
				(justify mirror)
			)
		)
		(duplicate_pad_numbers_are_jumpers no)
		(fp_line
			(start 0.299974 -0.150114)
			(end -0.299974 -0.150114)
			(stroke
				(width 0.1)
				(type default)
			)
			(layer "B.Fab")
		)
		(fp_line
			(start -0.299974 -0.150114)
			(end -0.299974 0.150114)
			(stroke
				(width 0.1)
				(type default)
			)
			(layer "B.Fab")
		)
		(fp_line
			(start 0.299974 0.150114)
			(end 0.299974 -0.150114)
			(stroke
				(width 0.1)
				(type default)
			)
			(layer "B.Fab")
		)
		(fp_line
			(start -0.299974 0.150114)
			(end 0.299974 0.150114)
			(stroke
				(width 0.1)
				(type default)
			)
			(layer "B.Fab")
		)
		(pad "1" smd rect
			(at 0.2667 0 270)
			(size 0.3048 0.381)
			(layers "B.Cu" "B.Mask" "B.Paste")
			(net "P0V9_CPU1_RT3_2A")
		)
		(pad "2" smd rect
			(at -0.2667 0 270)
			(size 0.3048 0.381)
			(layers "B.Cu" "B.Mask" "B.Paste")
			(net "GND")
		)
	)
	(footprint ""
		(layer "B.Cu")
		(at 196.064632 -351.201736 90)
		(property "Reference" "PC27"
			(at 0 0 90)
			(layer "B.SilkS")
			(hide yes)
			(effects
				(font
					(size 1.27 1.27)
				)
				(justify mirror)
			)
		)
		(property "Value" ""
			(at 0 0 90)
			(layer "B.Fab")
			(effects
				(font
					(size 1.27 1.27)
				)
				(justify mirror)
			)
		)
		(duplicate_pad_numbers_are_jumpers no)
		(fp_line
			(start 1.524 -0.762)
			(end -1.524 -0.762)
			(stroke
				(width 0.1524)
				(type default)
			)
			(layer "B.SilkS")
		)
		(fp_line
			(start -1.524 -0.762)
			(end -1.524 0.762)
			(stroke
				(width 0.1524)
				(type default)
			)
			(layer "B.SilkS")
		)
		(fp_line
			(start 1.524 0.762)
			(end 1.524 -0.762)
			(stroke
				(width 0.1524)
				(type default)
			)
			(layer "B.SilkS")
		)
		(fp_line
			(start -1.524 0.762)
			(end 1.524 0.762)
			(stroke
				(width 0.1524)
				(type default)
			)
			(layer "B.SilkS")
		)
		(fp_line
			(start 1.1049 -0.724916)
			(end 1.1049 0.724916)
			(stroke
				(width 0.1)
				(type default)
			)
			(layer "B.Fab")
		)
		(fp_line
			(start -1.1049 -0.724916)
			(end 1.1049 -0.724916)
			(stroke
				(width 0.1)
				(type default)
			)
			(layer "B.Fab")
		)
		(fp_line
			(start 1.1049 0.724916)
			(end -1.1049 0.724916)
			(stroke
				(width 0.1)
				(type default)
			)
			(layer "B.Fab")
		)
		(fp_line
			(start -1.1049 0.724916)
			(end -1.1049 -0.724916)
			(stroke
				(width 0.1)
				(type default)
			)
			(layer "B.Fab")
		)
		(pad "1" smd rect
			(at 0.889 0 90)
			(size 1.016 1.27)
			(layers "B.Cu" "B.Mask" "B.Paste")
			(net "SW_P12V_AUX_PVDD11_S3_P1_FLT")
		)
		(pad "2" smd rect
			(at -0.889 0 90)
			(size 1.016 1.27)
			(layers "B.Cu" "B.Mask" "B.Paste")
			(net "GND")
		)
	)
	(footprint ""
		(layer "B.Cu")
		(at 34.570162 -347.780356 -90)
		(property "Reference" "PR371"
			(at 0 0 90)
			(layer "B.SilkS")
			(hide yes)
			(effects
				(font
					(size 1.27 1.27)
				)
				(justify mirror)
			)
		)
		(property "Value" ""
			(at 0 0 90)
			(layer "B.Fab")
			(effects
				(font
					(size 1.27 1.27)
				)
				(justify mirror)
			)
		)
		(duplicate_pad_numbers_are_jumpers no)
		(fp_line
			(start -0.7874 0.4064)
			(end 0.7874 0.4064)
			(stroke
				(width 0.1524)
				(type default)
			)
			(layer "B.SilkS")
		)
		(fp_line
			(start 0.7874 0.4064)
			(end 0.7874 -0.4064)
			(stroke
				(width 0.1524)
				(type default)
			)
			(layer "B.SilkS")
		)
		(fp_line
			(start -0.7874 -0.4064)
			(end -0.7874 0.4064)
			(stroke
				(width 0.1524)
				(type default)
			)
			(layer "B.SilkS")
		)
		(fp_line
			(start 0.7874 -0.4064)
			(end -0.7874 -0.4064)
			(stroke
				(width 0.1524)
				(type default)
			)
			(layer "B.SilkS")
		)
		(fp_line
			(start -0.67945 0.3048)
			(end -0.120396 0.3048)
			(stroke
				(width 0.1)
				(type default)
			)
			(layer "B.Fab")
		)
		(fp_line
			(start -0.120396 0.3048)
			(end -0.120396 0.2794)
			(stroke
				(width 0.1)
				(type default)
			)
			(layer "B.Fab")
		)
		(fp_line
			(start 0.12065 0.3048)
			(end 0.67945 0.3048)
			(stroke
				(width 0.1)
				(type default)
			)
			(layer "B.Fab")
		)
		(fp_line
			(start 0.67945 0.3048)
			(end 0.67945 -0.305054)
			(stroke
				(width 0.1)
				(type default)
			)
			(layer "B.Fab")
		)
		(fp_line
			(start -0.120396 0.2794)
			(end 0.12065 0.2794)
			(stroke
				(width 0.1)
				(type default)
			)
			(layer "B.Fab")
		)
		(fp_line
			(start 0.12065 0.2794)
			(end 0.12065 0.3048)
			(stroke
				(width 0.1)
				(type default)
			)
			(layer "B.Fab")
		)
		(fp_line
			(start -0.12065 -0.2794)
			(end -0.12065 -0.3048)
			(stroke
				(width 0.1)
				(type default)
			)
			(layer "B.Fab")
		)
		(fp_line
			(start 0.12065 -0.2794)
			(end -0.12065 -0.2794)
			(stroke
				(width 0.1)
				(type default)
			)
			(layer "B.Fab")
		)
		(fp_line
			(start -0.67945 -0.3048)
			(end -0.67945 0.3048)
			(stroke
				(width 0.1)
				(type default)
			)
			(layer "B.Fab")
		)
		(fp_line
			(start -0.12065 -0.3048)
			(end -0.67945 -0.3048)
			(stroke
				(width 0.1)
				(type default)
			)
			(layer "B.Fab")
		)
		(fp_line
			(start 0.12065 -0.305054)
			(end 0.12065 -0.2794)
			(stroke
				(width 0.1)
				(type default)
			)
			(layer "B.Fab")
		)
		(fp_line
			(start 0.67945 -0.305054)
			(end 0.12065 -0.305054)
			(stroke
				(width 0.1)
				(type default)
			)
			(layer "B.Fab")
		)
		(pad "1" smd circle
			(at 0.40005 0 90)
			(size 0 0)
			(layers "B.Cu" "B.Mask" "B.Paste")
			(net "PVDDCR_CPU1_P1_PVCC")
		)
		(pad "2" smd circle
			(at -0.40005 0 90)
			(size 0 0)
			(layers "B.Cu" "B.Mask" "B.Paste")
			(net "PVDDIO_P1_VCC3")
		)
	)
	(footprint ""
		(layer "B.Cu")
		(at 216.25306 -78.448408 180)
		(property "Reference" "R3212"
			(at 0 0 0)
			(layer "B.SilkS")
			(hide yes)
			(effects
				(font
					(size 1.27 1.27)
				)
				(justify mirror)
			)
		)
		(property "Value" ""
			(at 0 0 0)
			(layer "B.Fab")
			(effects
				(font
					(size 1.27 1.27)
				)
				(justify mirror)
			)
		)
		(duplicate_pad_numbers_are_jumpers no)
		(fp_line
			(start 0.7874 0.4064)
			(end 0.7874 -0.4064)
			(stroke
				(width 0.1524)
				(type default)
			)
			(layer "B.SilkS")
		)
		(fp_line
			(start 0.7874 -0.4064)
			(end -0.7874 -0.4064)
			(stroke
				(width 0.1524)
				(type default)
			)
			(layer "B.SilkS")
		)
		(fp_line
			(start -0.7874 0.4064)
			(end 0.7874 0.4064)
			(stroke
				(width 0.1524)
				(type default)
			)
			(layer "B.SilkS")
		)
		(fp_line
			(start -0.7874 -0.4064)
			(end -0.7874 0.4064)
			(stroke
				(width 0.1524)
				(type default)
			)
			(layer "B.SilkS")
		)
		(fp_line
			(start 0.67945 0.3048)
			(end 0.67945 -0.305054)
			(stroke
				(width 0.1)
				(type default)
			)
			(layer "B.Fab")
		)
		(fp_line
			(start 0.67945 -0.305054)
			(end 0.12065 -0.305054)
			(stroke
				(width 0.1)
				(type default)
			)
			(layer "B.Fab")
		)
		(fp_line
			(start 0.12065 0.3048)
			(end 0.67945 0.3048)
			(stroke
				(width 0.1)
				(type default)
			)
			(layer "B.Fab")
		)
		(fp_line
			(start 0.12065 0.2794)
			(end 0.12065 0.3048)
			(stroke
				(width 0.1)
				(type default)
			)
			(layer "B.Fab")
		)
		(fp_line
			(start 0.12065 -0.2794)
			(end -0.12065 -0.2794)
			(stroke
				(width 0.1)
				(type default)
			)
			(layer "B.Fab")
		)
		(fp_line
			(start 0.12065 -0.305054)
			(end 0.12065 -0.2794)
			(stroke
				(width 0.1)
				(type default)
			)
			(layer "B.Fab")
		)
		(fp_line
			(start -0.120396 0.3048)
			(end -0.120396 0.2794)
			(stroke
				(width 0.1)
				(type default)
			)
			(layer "B.Fab")
		)
		(fp_line
			(start -0.120396 0.2794)
			(end 0.12065 0.2794)
			(stroke
				(width 0.1)
				(type default)
			)
			(layer "B.Fab")
		)
		(fp_line
			(start -0.12065 -0.2794)
			(end -0.12065 -0.3048)
			(stroke
				(width 0.1)
				(type default)
			)
			(layer "B.Fab")
		)
		(fp_line
			(start -0.12065 -0.3048)
			(end -0.67945 -0.3048)
			(stroke
				(width 0.1)
				(type default)
			)
			(layer "B.Fab")
		)
		(fp_line
			(start -0.67945 0.3048)
			(end -0.120396 0.3048)
			(stroke
				(width 0.1)
				(type default)
			)
			(layer "B.Fab")
		)
		(fp_line
			(start -0.67945 -0.3048)
			(end -0.67945 0.3048)
			(stroke
				(width 0.1)
				(type default)
			)
			(layer "B.Fab")
		)
		(pad "1" smd circle
			(at 0.40005 0)
			(size 0 0)
			(layers "B.Cu" "B.Mask" "B.Paste")
			(net "NCSI_BMC_RXD1_R1")
		)
		(pad "2" smd circle
			(at -0.40005 0)
			(size 0 0)
			(layers "B.Cu" "B.Mask" "B.Paste")
			(net "RMII_OCP_BMC_RXD_1")
		)
	)
	(footprint ""
		(layer "B.Cu")
		(at 91.508834 -305.406552 180)
		(property "Reference" "R515"
			(at 0 0 0)
			(layer "B.SilkS")
			(hide yes)
			(effects
				(font
					(size 1.27 1.27)
				)
				(justify mirror)
			)
		)
		(property "Value" ""
			(at 0 0 0)
			(layer "B.Fab")
			(effects
				(font
					(size 1.27 1.27)
				)
				(justify mirror)
			)
		)
		(duplicate_pad_numbers_are_jumpers no)
		(fp_line
			(start 0.7874 0.4064)
			(end 0.7874 -0.4064)
			(stroke
				(width 0.1524)
				(type default)
			)
			(layer "B.SilkS")
		)
		(fp_line
			(start 0.7874 -0.4064)
			(end -0.7874 -0.4064)
			(stroke
				(width 0.1524)
				(type default)
			)
			(layer "B.SilkS")
		)
		(fp_line
			(start -0.7874 0.4064)
			(end 0.7874 0.4064)
			(stroke
				(width 0.1524)
				(type default)
			)
			(layer "B.SilkS")
		)
		(fp_line
			(start -0.7874 -0.4064)
			(end -0.7874 0.4064)
			(stroke
				(width 0.1524)
				(type default)
			)
			(layer "B.SilkS")
		)
		(fp_line
			(start 0.67945 0.3048)
			(end 0.67945 -0.305054)
			(stroke
				(width 0.1)
				(type default)
			)
			(layer "B.Fab")
		)
		(fp_line
			(start 0.67945 -0.305054)
			(end 0.12065 -0.305054)
			(stroke
				(width 0.1)
				(type default)
			)
			(layer "B.Fab")
		)
		(fp_line
			(start 0.12065 0.3048)
			(end 0.67945 0.3048)
			(stroke
				(width 0.1)
				(type default)
			)
			(layer "B.Fab")
		)
		(fp_line
			(start 0.12065 0.2794)
			(end 0.12065 0.3048)
			(stroke
				(width 0.1)
				(type default)
			)
			(layer "B.Fab")
		)
		(fp_line
			(start 0.12065 -0.2794)
			(end -0.12065 -0.2794)
			(stroke
				(width 0.1)
				(type default)
			)
			(layer "B.Fab")
		)
		(fp_line
			(start 0.12065 -0.305054)
			(end 0.12065 -0.2794)
			(stroke
				(width 0.1)
				(type default)
			)
			(layer "B.Fab")
		)
		(fp_line
			(start -0.120396 0.3048)
			(end -0.120396 0.2794)
			(stroke
				(width 0.1)
				(type default)
			)
			(layer "B.Fab")
		)
		(fp_line
			(start -0.120396 0.2794)
			(end 0.12065 0.2794)
			(stroke
				(width 0.1)
				(type default)
			)
			(layer "B.Fab")
		)
		(fp_line
			(start -0.12065 -0.2794)
			(end -0.12065 -0.3048)
			(stroke
				(width 0.1)
				(type default)
			)
			(layer "B.Fab")
		)
		(fp_line
			(start -0.12065 -0.3048)
			(end -0.67945 -0.3048)
			(stroke
				(width 0.1)
				(type default)
			)
			(layer "B.Fab")
		)
		(fp_line
			(start -0.67945 0.3048)
			(end -0.120396 0.3048)
			(stroke
				(width 0.1)
				(type default)
			)
			(layer "B.Fab")
		)
		(fp_line
			(start -0.67945 -0.3048)
			(end -0.67945 0.3048)
			(stroke
				(width 0.1)
				(type default)
			)
			(layer "B.Fab")
		)
		(pad "1" smd circle
			(at 0.40005 0)
			(size 0 0)
			(layers "B.Cu" "B.Mask" "B.Paste")
			(net "P3V3_AUX")
		)
		(pad "2" smd circle
			(at -0.40005 0)
			(size 0 0)
			(layers "B.Cu" "B.Mask" "B.Paste")
			(net "CPU1_SP5R3")
		)
	)
	(footprint ""
		(layer "B.Cu")
		(at 216.123774 -323.588634 180)
		(property "Reference" "R1243"
			(at 0 0 0)
			(layer "B.SilkS")
			(hide yes)
			(effects
				(font
					(size 1.27 1.27)
				)
				(justify mirror)
			)
		)
		(property "Value" ""
			(at 0 0 0)
			(layer "B.Fab")
			(effects
				(font
					(size 1.27 1.27)
				)
				(justify mirror)
			)
		)
		(duplicate_pad_numbers_are_jumpers no)
		(fp_line
			(start 0.7874 0.4064)
			(end 0.7874 -0.4064)
			(stroke
				(width 0.1524)
				(type default)
			)
			(layer "B.SilkS")
		)
		(fp_line
			(start 0.7874 -0.4064)
			(end -0.7874 -0.4064)
			(stroke
				(width 0.1524)
				(type default)
			)
			(layer "B.SilkS")
		)
		(fp_line
			(start -0.7874 0.4064)
			(end 0.7874 0.4064)
			(stroke
				(width 0.1524)
				(type default)
			)
			(layer "B.SilkS")
		)
		(fp_line
			(start -0.7874 -0.4064)
			(end -0.7874 0.4064)
			(stroke
				(width 0.1524)
				(type default)
			)
			(layer "B.SilkS")
		)
		(fp_line
			(start 0.67945 0.3048)
			(end 0.67945 -0.305054)
			(stroke
				(width 0.1)
				(type default)
			)
			(layer "B.Fab")
		)
		(fp_line
			(start 0.67945 -0.305054)
			(end 0.12065 -0.305054)
			(stroke
				(width 0.1)
				(type default)
			)
			(layer "B.Fab")
		)
		(fp_line
			(start 0.12065 0.3048)
			(end 0.67945 0.3048)
			(stroke
				(width 0.1)
				(type default)
			)
			(layer "B.Fab")
		)
		(fp_line
			(start 0.12065 0.2794)
			(end 0.12065 0.3048)
			(stroke
				(width 0.1)
				(type default)
			)
			(layer "B.Fab")
		)
		(fp_line
			(start 0.12065 -0.2794)
			(end -0.12065 -0.2794)
			(stroke
				(width 0.1)
				(type default)
			)
			(layer "B.Fab")
		)
		(fp_line
			(start 0.12065 -0.305054)
			(end 0.12065 -0.2794)
			(stroke
				(width 0.1)
				(type default)
			)
			(layer "B.Fab")
		)
		(fp_line
			(start -0.120396 0.3048)
			(end -0.120396 0.2794)
			(stroke
				(width 0.1)
				(type default)
			)
			(layer "B.Fab")
		)
		(fp_line
			(start -0.120396 0.2794)
			(end 0.12065 0.2794)
			(stroke
				(width 0.1)
				(type default)
			)
			(layer "B.Fab")
		)
		(fp_line
			(start -0.12065 -0.2794)
			(end -0.12065 -0.3048)
			(stroke
				(width 0.1)
				(type default)
			)
			(layer "B.Fab")
		)
		(fp_line
			(start -0.12065 -0.3048)
			(end -0.67945 -0.3048)
			(stroke
				(width 0.1)
				(type default)
			)
			(layer "B.Fab")
		)
		(fp_line
			(start -0.67945 0.3048)
			(end -0.120396 0.3048)
			(stroke
				(width 0.1)
				(type default)
			)
			(layer "B.Fab")
		)
		(fp_line
			(start -0.67945 -0.3048)
			(end -0.67945 0.3048)
			(stroke
				(width 0.1)
				(type default)
			)
			(layer "B.Fab")
		)
		(pad "1" smd circle
			(at 0.40005 0)
			(size 0 0)
			(layers "B.Cu" "B.Mask" "B.Paste")
			(net "SMB_ADC_SDA_R")
		)
		(pad "2" smd circle
			(at -0.40005 0)
			(size 0 0)
			(layers "B.Cu" "B.Mask" "B.Paste")
			(net "SMB_SEN_TIC_2_3V3AUX_SDA")
		)
	)
	(footprint ""
		(layer "B.Cu")
		(at 385.06781 -389.49503)
		(property "Reference" "C7018"
			(at 2.82956 3.177032 0)
			(unlocked yes)
			(layer "B.SilkS")
			(effects
				(font
					(size 0.7874 0.5842)
					(thickness 0.1524)
				)
				(justify left mirror)
			)
		)
		(property "Value" ""
			(at 0 0 0)
			(layer "B.Fab")
			(effects
				(font
					(size 1.27 1.27)
				)
				(justify mirror)
			)
		)
		(duplicate_pad_numbers_are_jumpers no)
		(fp_line
			(start -4.53898 -2.15011)
			(end -4.53898 2.15011)
			(stroke
				(width 0.1524)
				(type default)
			)
			(layer "B.SilkS")
		)
		(fp_line
			(start -4.53898 2.15011)
			(end 4.53898 2.15011)
			(stroke
				(width 0.1524)
				(type default)
			)
			(layer "B.SilkS")
		)
		(fp_line
			(start 4.53898 -2.150618)
			(end 4.539742 2.152142)
			(stroke
				(width 0.1524)
				(type default)
			)
			(layer "B.SilkS")
		)
		(fp_line
			(start 4.53898 -2.15011)
			(end -4.53898 -2.15011)
			(stroke
				(width 0.1524)
				(type default)
			)
			(layer "B.SilkS")
		)
		(fp_line
			(start 4.53898 2.15011)
			(end 4.53898 -2.15011)
			(stroke
				(width 0.1524)
				(type default)
			)
			(layer "B.SilkS")
		)
		(fp_line
			(start 4.69138 -2.150618)
			(end 4.692396 2.161032)
			(stroke
				(width 0.1524)
				(type default)
			)
			(layer "B.SilkS")
		)
		(fp_line
			(start 4.83108 2.150364)
			(end 4.447794 2.149348)
			(stroke
				(width 0.1524)
				(type default)
			)
			(layer "B.SilkS")
		)
		(fp_line
			(start 4.84378 -2.150618)
			(end 4.53898 -2.150618)
			(stroke
				(width 0.1524)
				(type default)
			)
			(layer "B.SilkS")
		)
		(fp_line
			(start 4.84378 -2.150618)
			(end 4.842256 2.163064)
			(stroke
				(width 0.1524)
				(type default)
			)
			(layer "B.SilkS")
		)
		(fp_line
			(start -3.64998 -2.15011)
			(end -3.64998 2.15011)
			(stroke
				(width 0.1)
				(type default)
			)
			(layer "B.Fab")
		)
		(fp_line
			(start -3.64998 2.15011)
			(end 3.64998 2.15011)
			(stroke
				(width 0.1)
				(type default)
			)
			(layer "B.Fab")
		)
		(fp_line
			(start 3.64998 -2.15011)
			(end -3.64998 -2.15011)
			(stroke
				(width 0.1)
				(type default)
			)
			(layer "B.Fab")
		)
		(fp_line
			(start 3.64998 2.15011)
			(end 3.64998 -2.15011)
			(stroke
				(width 0.1)
				(type default)
			)
			(layer "B.Fab")
		)
		(fp_text user "-"
			(at -3.017774 2.359152 0)
			(unlocked yes)
			(layer "B.SilkS")
			(effects
				(font
					(size 1.905 1.4224)
					(thickness 0.1524)
				)
				(justify left mirror)
			)
		)
		(fp_text user "+"
			(at 6.214872 -0.337058 0)
			(unlocked yes)
			(layer "B.SilkS")
			(effects
				(font
					(size 1.905 1.4224)
					(thickness 0.1524)
				)
				(justify left mirror)
			)
		)
		(fp_text user "-"
			(at -4.313174 -0.094488 0)
			(unlocked yes)
			(layer "B.Fab")
			(effects
				(font
					(size 1.905 1.4224)
					(thickness 0.1524)
				)
				(justify left mirror)
			)
		)
		(fp_text user "+"
			(at 6.214872 -0.337058 0)
			(unlocked yes)
			(layer "B.Fab")
			(effects
				(font
					(size 1.905 1.4224)
					(thickness 0.1524)
				)
				(justify left mirror)
			)
		)
		(pad "1" smd rect
			(at 3.199892 0 180)
			(size 2.413 2.8194)
			(layers "B.Cu" "B.Mask" "B.Paste")
			(net "P0V9_CPU0_RT3_2A")
		)
		(pad "2" smd rect
			(at -3.199892 0 180)
			(size 2.413 2.8194)
			(layers "B.Cu" "B.Mask" "B.Paste")
			(net "GND")
		)
	)
	(footprint ""
		(layer "B.Cu")
		(at 94.470474 -302.805592)
		(property "Reference" "R544"
			(at 0 0 0)
			(layer "B.SilkS")
			(hide yes)
			(effects
				(font
					(size 1.27 1.27)
				)
				(justify mirror)
			)
		)
		(property "Value" ""
			(at 0 0 0)
			(layer "B.Fab")
			(effects
				(font
					(size 1.27 1.27)
				)
				(justify mirror)
			)
		)
		(duplicate_pad_numbers_are_jumpers no)
		(fp_line
			(start -0.7874 -0.4064)
			(end -0.7874 0.4064)
			(stroke
				(width 0.1524)
				(type default)
			)
			(layer "B.SilkS")
		)
		(fp_line
			(start -0.7874 0.4064)
			(end 0.7874 0.4064)
			(stroke
				(width 0.1524)
				(type default)
			)
			(layer "B.SilkS")
		)
		(fp_line
			(start 0.7874 -0.4064)
			(end -0.7874 -0.4064)
			(stroke
				(width 0.1524)
				(type default)
			)
			(layer "B.SilkS")
		)
		(fp_line
			(start 0.7874 0.4064)
			(end 0.7874 -0.4064)
			(stroke
				(width 0.1524)
				(type default)
			)
			(layer "B.SilkS")
		)
		(fp_line
			(start -0.67945 -0.3048)
			(end -0.67945 0.3048)
			(stroke
				(width 0.1)
				(type default)
			)
			(layer "B.Fab")
		)
		(fp_line
			(start -0.67945 0.3048)
			(end -0.120396 0.3048)
			(stroke
				(width 0.1)
				(type default)
			)
			(layer "B.Fab")
		)
		(fp_line
			(start -0.12065 -0.3048)
			(end -0.67945 -0.3048)
			(stroke
				(width 0.1)
				(type default)
			)
			(layer "B.Fab")
		)
		(fp_line
			(start -0.12065 -0.2794)
			(end -0.12065 -0.3048)
			(stroke
				(width 0.1)
				(type default)
			)
			(layer "B.Fab")
		)
		(fp_line
			(start -0.120396 0.2794)
			(end 0.12065 0.2794)
			(stroke
				(width 0.1)
				(type default)
			)
			(layer "B.Fab")
		)
		(fp_line
			(start -0.120396 0.3048)
			(end -0.120396 0.2794)
			(stroke
				(width 0.1)
				(type default)
			)
			(layer "B.Fab")
		)
		(fp_line
			(start 0.12065 -0.305054)
			(end 0.12065 -0.2794)
			(stroke
				(width 0.1)
				(type default)
			)
			(layer "B.Fab")
		)
		(fp_line
			(start 0.12065 -0.2794)
			(end -0.12065 -0.2794)
			(stroke
				(width 0.1)
				(type default)
			)
			(layer "B.Fab")
		)
		(fp_line
			(start 0.12065 0.2794)
			(end 0.12065 0.3048)
			(stroke
				(width 0.1)
				(type default)
			)
			(layer "B.Fab")
		)
		(fp_line
			(start 0.12065 0.3048)
			(end 0.67945 0.3048)
			(stroke
				(width 0.1)
				(type default)
			)
			(layer "B.Fab")
		)
		(fp_line
			(start 0.67945 -0.305054)
			(end 0.12065 -0.305054)
			(stroke
				(width 0.1)
				(type default)
			)
			(layer "B.Fab")
		)
		(fp_line
			(start 0.67945 0.3048)
			(end 0.67945 -0.305054)
			(stroke
				(width 0.1)
				(type default)
			)
			(layer "B.Fab")
		)
		(pad "1" smd circle
			(at 0.40005 0 180)
			(size 0 0)
			(layers "B.Cu" "B.Mask" "B.Paste")
			(net "IRQ_CPU_BMC_NMI_N")
		)
		(pad "2" smd circle
			(at -0.40005 0 180)
			(size 0 0)
			(layers "B.Cu" "B.Mask" "B.Paste")
			(net "PVDD18_S5_P1")
		)
	)
	(footprint ""
		(layer "B.Cu")
		(at 401.190968 -390.035034)
		(property "Reference" "C7016"
			(at 0 0 0)
			(layer "B.SilkS")
			(hide yes)
			(effects
				(font
					(size 1.27 1.27)
				)
				(justify mirror)
			)
		)
		(property "Value" ""
			(at 0 0 0)
			(layer "B.Fab")
			(effects
				(font
					(size 1.27 1.27)
				)
				(justify mirror)
			)
		)
		(duplicate_pad_numbers_are_jumpers no)
		(fp_line
			(start -1.524 -0.762)
			(end -1.524 0.762)
			(stroke
				(width 0.1524)
				(type default)
			)
			(layer "B.SilkS")
		)
		(fp_line
			(start -1.524 0.762)
			(end 1.524 0.762)
			(stroke
				(width 0.1524)
				(type default)
			)
			(layer "B.SilkS")
		)
		(fp_line
			(start 1.524 -0.762)
			(end -1.524 -0.762)
			(stroke
				(width 0.1524)
				(type default)
			)
			(layer "B.SilkS")
		)
		(fp_line
			(start 1.524 0.762)
			(end 1.524 -0.762)
			(stroke
				(width 0.1524)
				(type default)
			)
			(layer "B.SilkS")
		)
		(fp_line
			(start -1.1049 -0.724916)
			(end 1.1049 -0.724916)
			(stroke
				(width 0.1)
				(type default)
			)
			(layer "B.Fab")
		)
		(fp_line
			(start -1.1049 0.724916)
			(end -1.1049 -0.724916)
			(stroke
				(width 0.1)
				(type default)
			)
			(layer "B.Fab")
		)
		(fp_line
			(start 1.1049 -0.724916)
			(end 1.1049 0.724916)
			(stroke
				(width 0.1)
				(type default)
			)
			(layer "B.Fab")
		)
		(fp_line
			(start 1.1049 0.724916)
			(end -1.1049 0.724916)
			(stroke
				(width 0.1)
				(type default)
			)
			(layer "B.Fab")
		)
		(pad "1" smd rect
			(at 0.889 0)
			(size 1.016 1.27)
			(layers "B.Cu" "B.Mask" "B.Paste")
			(net "P0V9_CPU0_RT2_2A")
		)
		(pad "2" smd rect
			(at -0.889 0)
			(size 1.016 1.27)
			(layers "B.Cu" "B.Mask" "B.Paste")
			(net "GND")
		)
	)
	(footprint ""
		(layer "B.Cu")
		(at 268.892528 -193.99631)
		(property "Reference" "C108"
			(at 0 0 0)
			(layer "B.SilkS")
			(hide yes)
			(effects
				(font
					(size 1.27 1.27)
				)
				(justify mirror)
			)
		)
		(property "Value" ""
			(at 0 0 0)
			(layer "B.Fab")
			(effects
				(font
					(size 1.27 1.27)
				)
				(justify mirror)
			)
		)
		(duplicate_pad_numbers_are_jumpers no)
		(fp_line
			(start -0.7874 -0.4064)
			(end -0.7874 0.4064)
			(stroke
				(width 0.1524)
				(type default)
			)
			(layer "B.SilkS")
		)
		(fp_line
			(start -0.7874 0.4064)
			(end 0.7874 0.4064)
			(stroke
				(width 0.1524)
				(type default)
			)
			(layer "B.SilkS")
		)
		(fp_line
			(start 0.7874 -0.4064)
			(end -0.7874 -0.4064)
			(stroke
				(width 0.1524)
				(type default)
			)
			(layer "B.SilkS")
		)
		(fp_line
			(start 0.7874 0.4064)
			(end 0.7874 -0.4064)
			(stroke
				(width 0.1524)
				(type default)
			)
			(layer "B.SilkS")
		)
		(fp_line
			(start -0.67945 -0.3048)
			(end -0.67945 0.3048)
			(stroke
				(width 0.1)
				(type default)
			)
			(layer "B.Fab")
		)
		(fp_line
			(start -0.67945 0.3048)
			(end -0.120396 0.3048)
			(stroke
				(width 0.1)
				(type default)
			)
			(layer "B.Fab")
		)
		(fp_line
			(start -0.12065 -0.3048)
			(end -0.67945 -0.3048)
			(stroke
				(width 0.1)
				(type default)
			)
			(layer "B.Fab")
		)
		(fp_line
			(start -0.12065 -0.2794)
			(end -0.12065 -0.3048)
			(stroke
				(width 0.1)
				(type default)
			)
			(layer "B.Fab")
		)
		(fp_line
			(start -0.120396 0.2794)
			(end 0.12065 0.2794)
			(stroke
				(width 0.1)
				(type default)
			)
			(layer "B.Fab")
		)
		(fp_line
			(start -0.120396 0.3048)
			(end -0.120396 0.2794)
			(stroke
				(width 0.1)
				(type default)
			)
			(layer "B.Fab")
		)
		(fp_line
			(start 0.12065 -0.305054)
			(end 0.12065 -0.2794)
			(stroke
				(width 0.1)
				(type default)
			)
			(layer "B.Fab")
		)
		(fp_line
			(start 0.12065 -0.2794)
			(end -0.12065 -0.2794)
			(stroke
				(width 0.1)
				(type default)
			)
			(layer "B.Fab")
		)
		(fp_line
			(start 0.12065 0.2794)
			(end 0.12065 0.3048)
			(stroke
				(width 0.1)
				(type default)
			)
			(layer "B.Fab")
		)
		(fp_line
			(start 0.12065 0.3048)
			(end 0.67945 0.3048)
			(stroke
				(width 0.1)
				(type default)
			)
			(layer "B.Fab")
		)
		(fp_line
			(start 0.67945 -0.305054)
			(end 0.12065 -0.305054)
			(stroke
				(width 0.1)
				(type default)
			)
			(layer "B.Fab")
		)
		(fp_line
			(start 0.67945 0.3048)
			(end 0.67945 -0.305054)
			(stroke
				(width 0.1)
				(type default)
			)
			(layer "B.Fab")
		)
		(pad "1" smd circle
			(at 0.40005 0 180)
			(size 0 0)
			(layers "B.Cu" "B.Mask" "B.Paste")
			(net "P3V3_AUX")
		)
		(pad "2" smd circle
			(at -0.40005 0 180)
			(size 0 0)
			(layers "B.Cu" "B.Mask" "B.Paste")
			(net "GND")
		)
	)
	(footprint ""
		(layer "B.Cu")
		(at 358.58069 -391.2616 180)
		(property "Reference" "R1042"
			(at 0 0 0)
			(layer "B.SilkS")
			(hide yes)
			(effects
				(font
					(size 1.27 1.27)
				)
				(justify mirror)
			)
		)
		(property "Value" ""
			(at 0 0 0)
			(layer "B.Fab")
			(effects
				(font
					(size 1.27 1.27)
				)
				(justify mirror)
			)
		)
		(duplicate_pad_numbers_are_jumpers no)
		(fp_line
			(start 0.32512 0.175006)
			(end 0.32512 -0.175006)
			(stroke
				(width 0.1)
				(type default)
			)
			(layer "B.Fab")
		)
		(fp_line
			(start 0.32512 -0.175006)
			(end -0.32512 -0.175006)
			(stroke
				(width 0.1)
				(type default)
			)
			(layer "B.Fab")
		)
		(fp_line
			(start -0.32512 0.175006)
			(end 0.32512 0.175006)
			(stroke
				(width 0.1)
				(type default)
			)
			(layer "B.Fab")
		)
		(fp_line
			(start -0.32512 -0.175006)
			(end -0.32512 0.175006)
			(stroke
				(width 0.1)
				(type default)
			)
			(layer "B.Fab")
		)
		(pad "1" smd rect
			(at 0.2667 0)
			(size 0.3048 0.381)
			(layers "B.Cu" "B.Mask" "B.Paste")
			(net "NCF_CPU0_P1_GND")
		)
		(pad "2" smd rect
			(at -0.2667 0 180)
			(size 0.3048 0.381)
			(layers "B.Cu" "B.Mask" "B.Paste")
			(net "GND")
		)
	)
	(footprint ""
		(layer "B.Cu")
		(at 400.211798 -326.666352)
		(property "Reference" "R742"
			(at 0 0 0)
			(layer "B.SilkS")
			(hide yes)
			(effects
				(font
					(size 1.27 1.27)
				)
				(justify mirror)
			)
		)
		(property "Value" ""
			(at 0 0 0)
			(layer "B.Fab")
			(effects
				(font
					(size 1.27 1.27)
				)
				(justify mirror)
			)
		)
		(duplicate_pad_numbers_are_jumpers no)
		(fp_line
			(start -0.7874 -0.4064)
			(end -0.7874 0.4064)
			(stroke
				(width 0.1524)
				(type default)
			)
			(layer "B.SilkS")
		)
		(fp_line
			(start -0.7874 0.4064)
			(end 0.7874 0.4064)
			(stroke
				(width 0.1524)
				(type default)
			)
			(layer "B.SilkS")
		)
		(fp_line
			(start 0.7874 -0.4064)
			(end -0.7874 -0.4064)
			(stroke
				(width 0.1524)
				(type default)
			)
			(layer "B.SilkS")
		)
		(fp_line
			(start 0.7874 0.4064)
			(end 0.7874 -0.4064)
			(stroke
				(width 0.1524)
				(type default)
			)
			(layer "B.SilkS")
		)
		(fp_line
			(start -0.67945 -0.3048)
			(end -0.67945 0.3048)
			(stroke
				(width 0.1)
				(type default)
			)
			(layer "B.Fab")
		)
		(fp_line
			(start -0.67945 0.3048)
			(end -0.120396 0.3048)
			(stroke
				(width 0.1)
				(type default)
			)
			(layer "B.Fab")
		)
		(fp_line
			(start -0.12065 -0.3048)
			(end -0.67945 -0.3048)
			(stroke
				(width 0.1)
				(type default)
			)
			(layer "B.Fab")
		)
		(fp_line
			(start -0.12065 -0.2794)
			(end -0.12065 -0.3048)
			(stroke
				(width 0.1)
				(type default)
			)
			(layer "B.Fab")
		)
		(fp_line
			(start -0.120396 0.2794)
			(end 0.12065 0.2794)
			(stroke
				(width 0.1)
				(type default)
			)
			(layer "B.Fab")
		)
		(fp_line
			(start -0.120396 0.3048)
			(end -0.120396 0.2794)
			(stroke
				(width 0.1)
				(type default)
			)
			(layer "B.Fab")
		)
		(fp_line
			(start 0.12065 -0.305054)
			(end 0.12065 -0.2794)
			(stroke
				(width 0.1)
				(type default)
			)
			(layer "B.Fab")
		)
		(fp_line
			(start 0.12065 -0.2794)
			(end -0.12065 -0.2794)
			(stroke
				(width 0.1)
				(type default)
			)
			(layer "B.Fab")
		)
		(fp_line
			(start 0.12065 0.2794)
			(end 0.12065 0.3048)
			(stroke
				(width 0.1)
				(type default)
			)
			(layer "B.Fab")
		)
		(fp_line
			(start 0.12065 0.3048)
			(end 0.67945 0.3048)
			(stroke
				(width 0.1)
				(type default)
			)
			(layer "B.Fab")
		)
		(fp_line
			(start 0.67945 -0.305054)
			(end 0.12065 -0.305054)
			(stroke
				(width 0.1)
				(type default)
			)
			(layer "B.Fab")
		)
		(fp_line
			(start 0.67945 0.3048)
			(end 0.67945 -0.305054)
			(stroke
				(width 0.1)
				(type default)
			)
			(layer "B.Fab")
		)
		(pad "1" smd circle
			(at 0.40005 0 180)
			(size 0 0)
			(layers "B.Cu" "B.Mask" "B.Paste")
			(net "PVDD18_S5_P0")
		)
		(pad "2" smd circle
			(at -0.40005 0 180)
			(size 0 0)
			(layers "B.Cu" "B.Mask" "B.Paste")
			(net "PD_ESPI_CPU0_CLK2")
		)
	)
	(footprint ""
		(layer "B.Cu")
		(at 356.29596 -258.795012 180)
		(property "Reference" "C2598"
			(at 0 0 0)
			(layer "B.SilkS")
			(hide yes)
			(effects
				(font
					(size 1.27 1.27)
				)
				(justify mirror)
			)
		)
		(property "Value" ""
			(at 0 0 0)
			(layer "B.Fab")
			(effects
				(font
					(size 1.27 1.27)
				)
				(justify mirror)
			)
		)
		(duplicate_pad_numbers_are_jumpers no)
		(fp_line
			(start 0.7874 0.4064)
			(end 0.7874 -0.4064)
			(stroke
				(width 0.1524)
				(type default)
			)
			(layer "B.SilkS")
		)
		(fp_line
			(start 0.7874 -0.4064)
			(end -0.7874 -0.4064)
			(stroke
				(width 0.1524)
				(type default)
			)
			(layer "B.SilkS")
		)
		(fp_line
			(start -0.7874 0.4064)
			(end 0.7874 0.4064)
			(stroke
				(width 0.1524)
				(type default)
			)
			(layer "B.SilkS")
		)
		(fp_line
			(start -0.7874 -0.4064)
			(end -0.7874 0.4064)
			(stroke
				(width 0.1524)
				(type default)
			)
			(layer "B.SilkS")
		)
		(fp_line
			(start 0.67945 0.3048)
			(end 0.67945 -0.305054)
			(stroke
				(width 0.1)
				(type default)
			)
			(layer "B.Fab")
		)
		(fp_line
			(start 0.67945 -0.305054)
			(end 0.12065 -0.305054)
			(stroke
				(width 0.1)
				(type default)
			)
			(layer "B.Fab")
		)
		(fp_line
			(start 0.12065 0.3048)
			(end 0.67945 0.3048)
			(stroke
				(width 0.1)
				(type default)
			)
			(layer "B.Fab")
		)
		(fp_line
			(start 0.12065 0.2794)
			(end 0.12065 0.3048)
			(stroke
				(width 0.1)
				(type default)
			)
			(layer "B.Fab")
		)
		(fp_line
			(start 0.12065 -0.2794)
			(end -0.12065 -0.2794)
			(stroke
				(width 0.1)
				(type default)
			)
			(layer "B.Fab")
		)
		(fp_line
			(start 0.12065 -0.305054)
			(end 0.12065 -0.2794)
			(stroke
				(width 0.1)
				(type default)
			)
			(layer "B.Fab")
		)
		(fp_line
			(start -0.120396 0.3048)
			(end -0.120396 0.2794)
			(stroke
				(width 0.1)
				(type default)
			)
			(layer "B.Fab")
		)
		(fp_line
			(start -0.120396 0.2794)
			(end 0.12065 0.2794)
			(stroke
				(width 0.1)
				(type default)
			)
			(layer "B.Fab")
		)
		(fp_line
			(start -0.12065 -0.2794)
			(end -0.12065 -0.3048)
			(stroke
				(width 0.1)
				(type default)
			)
			(layer "B.Fab")
		)
		(fp_line
			(start -0.12065 -0.3048)
			(end -0.67945 -0.3048)
			(stroke
				(width 0.1)
				(type default)
			)
			(layer "B.Fab")
		)
		(fp_line
			(start -0.67945 0.3048)
			(end -0.120396 0.3048)
			(stroke
				(width 0.1)
				(type default)
			)
			(layer "B.Fab")
		)
		(fp_line
			(start -0.67945 -0.3048)
			(end -0.67945 0.3048)
			(stroke
				(width 0.1)
				(type default)
			)
			(layer "B.Fab")
		)
		(pad "1" smd circle
			(at 0.40005 0)
			(size 0 0)
			(layers "B.Cu" "B.Mask" "B.Paste")
			(net "PVDDIO_P0")
		)
		(pad "2" smd circle
			(at -0.40005 0)
			(size 0 0)
			(layers "B.Cu" "B.Mask" "B.Paste")
			(net "GND")
		)
	)
	(footprint ""
		(layer "B.Cu")
		(at 87.118952 -390.560052 90)
		(property "Reference" "C333"
			(at 0 0 90)
			(layer "B.SilkS")
			(hide yes)
			(effects
				(font
					(size 1.27 1.27)
				)
				(justify mirror)
			)
		)
		(property "Value" ""
			(at 0 0 90)
			(layer "B.Fab")
			(effects
				(font
					(size 1.27 1.27)
				)
				(justify mirror)
			)
		)
		(duplicate_pad_numbers_are_jumpers no)
		(fp_line
			(start 0.7874 -0.4064)
			(end -0.7874 -0.4064)
			(stroke
				(width 0.1524)
				(type default)
			)
			(layer "B.SilkS")
		)
		(fp_line
			(start -0.7874 -0.4064)
			(end -0.7874 0.4064)
			(stroke
				(width 0.1524)
				(type default)
			)
			(layer "B.SilkS")
		)
		(fp_line
			(start 0.7874 0.4064)
			(end 0.7874 -0.4064)
			(stroke
				(width 0.1524)
				(type default)
			)
			(layer "B.SilkS")
		)
		(fp_line
			(start -0.7874 0.4064)
			(end 0.7874 0.4064)
			(stroke
				(width 0.1524)
				(type default)
			)
			(layer "B.SilkS")
		)
		(fp_line
			(start 0.67945 -0.305054)
			(end 0.12065 -0.305054)
			(stroke
				(width 0.1)
				(type default)
			)
			(layer "B.Fab")
		)
		(fp_line
			(start 0.12065 -0.305054)
			(end 0.12065 -0.2794)
			(stroke
				(width 0.1)
				(type default)
			)
			(layer "B.Fab")
		)
		(fp_line
			(start -0.12065 -0.3048)
			(end -0.67945 -0.3048)
			(stroke
				(width 0.1)
				(type default)
			)
			(layer "B.Fab")
		)
		(fp_line
			(start -0.67945 -0.3048)
			(end -0.67945 0.3048)
			(stroke
				(width 0.1)
				(type default)
			)
			(layer "B.Fab")
		)
		(fp_line
			(start 0.12065 -0.2794)
			(end -0.12065 -0.2794)
			(stroke
				(width 0.1)
				(type default)
			)
			(layer "B.Fab")
		)
		(fp_line
			(start -0.12065 -0.2794)
			(end -0.12065 -0.3048)
			(stroke
				(width 0.1)
				(type default)
			)
			(layer "B.Fab")
		)
		(fp_line
			(start 0.12065 0.2794)
			(end 0.12065 0.3048)
			(stroke
				(width 0.1)
				(type default)
			)
			(layer "B.Fab")
		)
		(fp_line
			(start -0.120396 0.2794)
			(end 0.12065 0.2794)
			(stroke
				(width 0.1)
				(type default)
			)
			(layer "B.Fab")
		)
		(fp_line
			(start 0.67945 0.3048)
			(end 0.67945 -0.305054)
			(stroke
				(width 0.1)
				(type default)
			)
			(layer "B.Fab")
		)
		(fp_line
			(start 0.12065 0.3048)
			(end 0.67945 0.3048)
			(stroke
				(width 0.1)
				(type default)
			)
			(layer "B.Fab")
		)
		(fp_line
			(start -0.120396 0.3048)
			(end -0.120396 0.2794)
			(stroke
				(width 0.1)
				(type default)
			)
			(layer "B.Fab")
		)
		(fp_line
			(start -0.67945 0.3048)
			(end -0.120396 0.3048)
			(stroke
				(width 0.1)
				(type default)
			)
			(layer "B.Fab")
		)
		(pad "1" smd circle
			(at 0.40005 0 270)
			(size 0 0)
			(layers "B.Cu" "B.Mask" "B.Paste")
			(net "P0V9_CPU1_RT_2D")
		)
		(pad "2" smd circle
			(at -0.40005 0 270)
			(size 0 0)
			(layers "B.Cu" "B.Mask" "B.Paste")
			(net "GND")
		)
	)
	(footprint ""
		(layer "B.Cu")
		(at 284.074108 -420.491412 90)
		(property "Reference" "C2334"
			(at 0 0 90)
			(layer "B.SilkS")
			(hide yes)
			(effects
				(font
					(size 1.27 1.27)
				)
				(justify mirror)
			)
		)
		(property "Value" ""
			(at 0 0 90)
			(layer "B.Fab")
			(effects
				(font
					(size 1.27 1.27)
				)
				(justify mirror)
			)
		)
		(duplicate_pad_numbers_are_jumpers no)
		(fp_line
			(start 0.7874 -0.4064)
			(end -0.7874 -0.4064)
			(stroke
				(width 0.1524)
				(type default)
			)
			(layer "B.SilkS")
		)
		(fp_line
			(start -0.7874 -0.4064)
			(end -0.7874 0.4064)
			(stroke
				(width 0.1524)
				(type default)
			)
			(layer "B.SilkS")
		)
		(fp_line
			(start 0.7874 0.4064)
			(end 0.7874 -0.4064)
			(stroke
				(width 0.1524)
				(type default)
			)
			(layer "B.SilkS")
		)
		(fp_line
			(start -0.7874 0.4064)
			(end 0.7874 0.4064)
			(stroke
				(width 0.1524)
				(type default)
			)
			(layer "B.SilkS")
		)
		(fp_line
			(start 0.67945 -0.305054)
			(end 0.12065 -0.305054)
			(stroke
				(width 0.1)
				(type default)
			)
			(layer "B.Fab")
		)
		(fp_line
			(start 0.12065 -0.305054)
			(end 0.12065 -0.2794)
			(stroke
				(width 0.1)
				(type default)
			)
			(layer "B.Fab")
		)
		(fp_line
			(start -0.12065 -0.3048)
			(end -0.67945 -0.3048)
			(stroke
				(width 0.1)
				(type default)
			)
			(layer "B.Fab")
		)
		(fp_line
			(start -0.67945 -0.3048)
			(end -0.67945 0.3048)
			(stroke
				(width 0.1)
				(type default)
			)
			(layer "B.Fab")
		)
		(fp_line
			(start 0.12065 -0.2794)
			(end -0.12065 -0.2794)
			(stroke
				(width 0.1)
				(type default)
			)
			(layer "B.Fab")
		)
		(fp_line
			(start -0.12065 -0.2794)
			(end -0.12065 -0.3048)
			(stroke
				(width 0.1)
				(type default)
			)
			(layer "B.Fab")
		)
		(fp_line
			(start 0.12065 0.2794)
			(end 0.12065 0.3048)
			(stroke
				(width 0.1)
				(type default)
			)
			(layer "B.Fab")
		)
		(fp_line
			(start -0.120396 0.2794)
			(end 0.12065 0.2794)
			(stroke
				(width 0.1)
				(type default)
			)
			(layer "B.Fab")
		)
		(fp_line
			(start 0.67945 0.3048)
			(end 0.67945 -0.305054)
			(stroke
				(width 0.1)
				(type default)
			)
			(layer "B.Fab")
		)
		(fp_line
			(start 0.12065 0.3048)
			(end 0.67945 0.3048)
			(stroke
				(width 0.1)
				(type default)
			)
			(layer "B.Fab")
		)
		(fp_line
			(start -0.120396 0.3048)
			(end -0.120396 0.2794)
			(stroke
				(width 0.1)
				(type default)
			)
			(layer "B.Fab")
		)
		(fp_line
			(start -0.67945 0.3048)
			(end -0.120396 0.3048)
			(stroke
				(width 0.1)
				(type default)
			)
			(layer "B.Fab")
		)
		(pad "1" smd circle
			(at 0.40005 0 270)
			(size 0 0)
			(layers "B.Cu" "B.Mask" "B.Paste")
			(net "P3V3_9ZXL045_P0_VDDA")
		)
		(pad "2" smd circle
			(at -0.40005 0 270)
			(size 0 0)
			(layers "B.Cu" "B.Mask" "B.Paste")
			(net "GND")
		)
	)
	(footprint ""
		(layer "B.Cu")
		(at 363.550454 -251.78131)
		(property "Reference" "C2550"
			(at 0 0 0)
			(layer "B.SilkS")
			(hide yes)
			(effects
				(font
					(size 1.27 1.27)
				)
				(justify mirror)
			)
		)
		(property "Value" ""
			(at 0 0 0)
			(layer "B.Fab")
			(effects
				(font
					(size 1.27 1.27)
				)
				(justify mirror)
			)
		)
		(duplicate_pad_numbers_are_jumpers no)
		(fp_line
			(start -0.7874 -0.4064)
			(end -0.7874 0.4064)
			(stroke
				(width 0.1524)
				(type default)
			)
			(layer "B.SilkS")
		)
		(fp_line
			(start -0.7874 0.4064)
			(end 0.7874 0.4064)
			(stroke
				(width 0.1524)
				(type default)
			)
			(layer "B.SilkS")
		)
		(fp_line
			(start 0.7874 -0.4064)
			(end -0.7874 -0.4064)
			(stroke
				(width 0.1524)
				(type default)
			)
			(layer "B.SilkS")
		)
		(fp_line
			(start 0.7874 0.4064)
			(end 0.7874 -0.4064)
			(stroke
				(width 0.1524)
				(type default)
			)
			(layer "B.SilkS")
		)
		(fp_line
			(start -0.67945 -0.3048)
			(end -0.67945 0.3048)
			(stroke
				(width 0.1)
				(type default)
			)
			(layer "B.Fab")
		)
		(fp_line
			(start -0.67945 0.3048)
			(end -0.120396 0.3048)
			(stroke
				(width 0.1)
				(type default)
			)
			(layer "B.Fab")
		)
		(fp_line
			(start -0.12065 -0.3048)
			(end -0.67945 -0.3048)
			(stroke
				(width 0.1)
				(type default)
			)
			(layer "B.Fab")
		)
		(fp_line
			(start -0.12065 -0.2794)
			(end -0.12065 -0.3048)
			(stroke
				(width 0.1)
				(type default)
			)
			(layer "B.Fab")
		)
		(fp_line
			(start -0.120396 0.2794)
			(end 0.12065 0.2794)
			(stroke
				(width 0.1)
				(type default)
			)
			(layer "B.Fab")
		)
		(fp_line
			(start -0.120396 0.3048)
			(end -0.120396 0.2794)
			(stroke
				(width 0.1)
				(type default)
			)
			(layer "B.Fab")
		)
		(fp_line
			(start 0.12065 -0.305054)
			(end 0.12065 -0.2794)
			(stroke
				(width 0.1)
				(type default)
			)
			(layer "B.Fab")
		)
		(fp_line
			(start 0.12065 -0.2794)
			(end -0.12065 -0.2794)
			(stroke
				(width 0.1)
				(type default)
			)
			(layer "B.Fab")
		)
		(fp_line
			(start 0.12065 0.2794)
			(end 0.12065 0.3048)
			(stroke
				(width 0.1)
				(type default)
			)
			(layer "B.Fab")
		)
		(fp_line
			(start 0.12065 0.3048)
			(end 0.67945 0.3048)
			(stroke
				(width 0.1)
				(type default)
			)
			(layer "B.Fab")
		)
		(fp_line
			(start 0.67945 -0.305054)
			(end 0.12065 -0.305054)
			(stroke
				(width 0.1)
				(type default)
			)
			(layer "B.Fab")
		)
		(fp_line
			(start 0.67945 0.3048)
			(end 0.67945 -0.305054)
			(stroke
				(width 0.1)
				(type default)
			)
			(layer "B.Fab")
		)
		(pad "1" smd circle
			(at 0.40005 0 180)
			(size 0 0)
			(layers "B.Cu" "B.Mask" "B.Paste")
			(net "PVDDCR_SOC_P0")
		)
		(pad "2" smd circle
			(at -0.40005 0 180)
			(size 0 0)
			(layers "B.Cu" "B.Mask" "B.Paste")
			(net "GND")
		)
	)
	(footprint ""
		(layer "B.Cu")
		(at 163.806378 -386.766562 90)
		(property "Reference" "C422"
			(at 0 0 90)
			(layer "B.SilkS")
			(hide yes)
			(effects
				(font
					(size 1.27 1.27)
				)
				(justify mirror)
			)
		)
		(property "Value" ""
			(at 0 0 90)
			(layer "B.Fab")
			(effects
				(font
					(size 1.27 1.27)
				)
				(justify mirror)
			)
		)
		(duplicate_pad_numbers_are_jumpers no)
		(fp_line
			(start 0.299974 -0.150114)
			(end -0.299974 -0.150114)
			(stroke
				(width 0.1)
				(type default)
			)
			(layer "B.Fab")
		)
		(fp_line
			(start -0.299974 -0.150114)
			(end -0.299974 0.150114)
			(stroke
				(width 0.1)
				(type default)
			)
			(layer "B.Fab")
		)
		(fp_line
			(start 0.299974 0.150114)
			(end 0.299974 -0.150114)
			(stroke
				(width 0.1)
				(type default)
			)
			(layer "B.Fab")
		)
		(fp_line
			(start -0.299974 0.150114)
			(end 0.299974 0.150114)
			(stroke
				(width 0.1)
				(type default)
			)
			(layer "B.Fab")
		)
		(pad "1" smd rect
			(at 0.2667 0 270)
			(size 0.3048 0.381)
			(layers "B.Cu" "B.Mask" "B.Paste")
			(net "P0V9_CPU1_RT2_2A")
		)
		(pad "2" smd rect
			(at -0.2667 0 270)
			(size 0.3048 0.381)
			(layers "B.Cu" "B.Mask" "B.Paste")
			(net "GND")
		)
	)
	(footprint ""
		(layer "B.Cu")
		(at 353.900232 -262.204962)
		(property "Reference" "C3935"
			(at 0 0 0)
			(layer "B.SilkS")
			(hide yes)
			(effects
				(font
					(size 1.27 1.27)
				)
				(justify mirror)
			)
		)
		(property "Value" ""
			(at 0 0 0)
			(layer "B.Fab")
			(effects
				(font
					(size 1.27 1.27)
				)
				(justify mirror)
			)
		)
		(duplicate_pad_numbers_are_jumpers no)
		(fp_line
			(start -0.7874 -0.4064)
			(end -0.7874 0.4064)
			(stroke
				(width 0.1524)
				(type default)
			)
			(layer "B.SilkS")
		)
		(fp_line
			(start -0.7874 0.4064)
			(end 0.7874 0.4064)
			(stroke
				(width 0.1524)
				(type default)
			)
			(layer "B.SilkS")
		)
		(fp_line
			(start 0.7874 -0.4064)
			(end -0.7874 -0.4064)
			(stroke
				(width 0.1524)
				(type default)
			)
			(layer "B.SilkS")
		)
		(fp_line
			(start 0.7874 0.4064)
			(end 0.7874 -0.4064)
			(stroke
				(width 0.1524)
				(type default)
			)
			(layer "B.SilkS")
		)
		(fp_line
			(start -0.67945 -0.3048)
			(end -0.67945 0.3048)
			(stroke
				(width 0.1)
				(type default)
			)
			(layer "B.Fab")
		)
		(fp_line
			(start -0.67945 0.3048)
			(end -0.120396 0.3048)
			(stroke
				(width 0.1)
				(type default)
			)
			(layer "B.Fab")
		)
		(fp_line
			(start -0.12065 -0.3048)
			(end -0.67945 -0.3048)
			(stroke
				(width 0.1)
				(type default)
			)
			(layer "B.Fab")
		)
		(fp_line
			(start -0.12065 -0.2794)
			(end -0.12065 -0.3048)
			(stroke
				(width 0.1)
				(type default)
			)
			(layer "B.Fab")
		)
		(fp_line
			(start -0.120396 0.2794)
			(end 0.12065 0.2794)
			(stroke
				(width 0.1)
				(type default)
			)
			(layer "B.Fab")
		)
		(fp_line
			(start -0.120396 0.3048)
			(end -0.120396 0.2794)
			(stroke
				(width 0.1)
				(type default)
			)
			(layer "B.Fab")
		)
		(fp_line
			(start 0.12065 -0.305054)
			(end 0.12065 -0.2794)
			(stroke
				(width 0.1)
				(type default)
			)
			(layer "B.Fab")
		)
		(fp_line
			(start 0.12065 -0.2794)
			(end -0.12065 -0.2794)
			(stroke
				(width 0.1)
				(type default)
			)
			(layer "B.Fab")
		)
		(fp_line
			(start 0.12065 0.2794)
			(end 0.12065 0.3048)
			(stroke
				(width 0.1)
				(type default)
			)
			(layer "B.Fab")
		)
		(fp_line
			(start 0.12065 0.3048)
			(end 0.67945 0.3048)
			(stroke
				(width 0.1)
				(type default)
			)
			(layer "B.Fab")
		)
		(fp_line
			(start 0.67945 -0.305054)
			(end 0.12065 -0.305054)
			(stroke
				(width 0.1)
				(type default)
			)
			(layer "B.Fab")
		)
		(fp_line
			(start 0.67945 0.3048)
			(end 0.67945 -0.305054)
			(stroke
				(width 0.1)
				(type default)
			)
			(layer "B.Fab")
		)
		(pad "1" smd circle
			(at 0.40005 0 180)
			(size 0 0)
			(layers "B.Cu" "B.Mask" "B.Paste")
			(net "PVDD11_S3_P0")
		)
		(pad "2" smd circle
			(at -0.40005 0 180)
			(size 0 0)
			(layers "B.Cu" "B.Mask" "B.Paste")
			(net "GND")
		)
	)
	(footprint ""
		(layer "B.Cu")
		(at 167.116252 -115.28552)
		(property "Reference" "R993"
			(at 0 0 0)
			(layer "B.SilkS")
			(hide yes)
			(effects
				(font
					(size 1.27 1.27)
				)
				(justify mirror)
			)
		)
		(property "Value" ""
			(at 0 0 0)
			(layer "B.Fab")
			(effects
				(font
					(size 1.27 1.27)
				)
				(justify mirror)
			)
		)
		(duplicate_pad_numbers_are_jumpers no)
		(fp_line
			(start -0.7874 -0.4064)
			(end -0.7874 0.4064)
			(stroke
				(width 0.1524)
				(type default)
			)
			(layer "B.SilkS")
		)
		(fp_line
			(start -0.7874 0.4064)
			(end 0.7874 0.4064)
			(stroke
				(width 0.1524)
				(type default)
			)
			(layer "B.SilkS")
		)
		(fp_line
			(start 0.7874 -0.4064)
			(end -0.7874 -0.4064)
			(stroke
				(width 0.1524)
				(type default)
			)
			(layer "B.SilkS")
		)
		(fp_line
			(start 0.7874 0.4064)
			(end 0.7874 -0.4064)
			(stroke
				(width 0.1524)
				(type default)
			)
			(layer "B.SilkS")
		)
		(fp_line
			(start -0.67945 -0.3048)
			(end -0.67945 0.3048)
			(stroke
				(width 0.1)
				(type default)
			)
			(layer "B.Fab")
		)
		(fp_line
			(start -0.67945 0.3048)
			(end -0.120396 0.3048)
			(stroke
				(width 0.1)
				(type default)
			)
			(layer "B.Fab")
		)
		(fp_line
			(start -0.12065 -0.3048)
			(end -0.67945 -0.3048)
			(stroke
				(width 0.1)
				(type default)
			)
			(layer "B.Fab")
		)
		(fp_line
			(start -0.12065 -0.2794)
			(end -0.12065 -0.3048)
			(stroke
				(width 0.1)
				(type default)
			)
			(layer "B.Fab")
		)
		(fp_line
			(start -0.120396 0.2794)
			(end 0.12065 0.2794)
			(stroke
				(width 0.1)
				(type default)
			)
			(layer "B.Fab")
		)
		(fp_line
			(start -0.120396 0.3048)
			(end -0.120396 0.2794)
			(stroke
				(width 0.1)
				(type default)
			)
			(layer "B.Fab")
		)
		(fp_line
			(start 0.12065 -0.305054)
			(end 0.12065 -0.2794)
			(stroke
				(width 0.1)
				(type default)
			)
			(layer "B.Fab")
		)
		(fp_line
			(start 0.12065 -0.2794)
			(end -0.12065 -0.2794)
			(stroke
				(width 0.1)
				(type default)
			)
			(layer "B.Fab")
		)
		(fp_line
			(start 0.12065 0.2794)
			(end 0.12065 0.3048)
			(stroke
				(width 0.1)
				(type default)
			)
			(layer "B.Fab")
		)
		(fp_line
			(start 0.12065 0.3048)
			(end 0.67945 0.3048)
			(stroke
				(width 0.1)
				(type default)
			)
			(layer "B.Fab")
		)
		(fp_line
			(start 0.67945 -0.305054)
			(end 0.12065 -0.305054)
			(stroke
				(width 0.1)
				(type default)
			)
			(layer "B.Fab")
		)
		(fp_line
			(start 0.67945 0.3048)
			(end 0.67945 -0.305054)
			(stroke
				(width 0.1)
				(type default)
			)
			(layer "B.Fab")
		)
		(pad "1" smd circle
			(at 0.40005 0 180)
			(size 0 0)
			(layers "B.Cu" "B.Mask" "B.Paste")
			(net "FM_SYS_THROTTLE_N")
		)
		(pad "2" smd circle
			(at -0.40005 0 180)
			(size 0 0)
			(layers "B.Cu" "B.Mask" "B.Paste")
			(net "P3V3_AUX")
		)
	)
	(footprint ""
		(layer "B.Cu")
		(at 53.09362 -422.777666)
		(property "Reference" "R3318"
			(at 0 0 0)
			(layer "B.SilkS")
			(hide yes)
			(effects
				(font
					(size 1.27 1.27)
				)
				(justify mirror)
			)
		)
		(property "Value" ""
			(at 0 0 0)
			(layer "B.Fab")
			(effects
				(font
					(size 1.27 1.27)
				)
				(justify mirror)
			)
		)
		(duplicate_pad_numbers_are_jumpers no)
		(fp_line
			(start -0.7874 -0.4064)
			(end -0.7874 0.4064)
			(stroke
				(width 0.1524)
				(type default)
			)
			(layer "B.SilkS")
		)
		(fp_line
			(start -0.7874 0.4064)
			(end 0.7874 0.4064)
			(stroke
				(width 0.1524)
				(type default)
			)
			(layer "B.SilkS")
		)
		(fp_line
			(start 0.7874 -0.4064)
			(end -0.7874 -0.4064)
			(stroke
				(width 0.1524)
				(type default)
			)
			(layer "B.SilkS")
		)
		(fp_line
			(start 0.7874 0.4064)
			(end 0.7874 -0.4064)
			(stroke
				(width 0.1524)
				(type default)
			)
			(layer "B.SilkS")
		)
		(fp_line
			(start -0.67945 -0.3048)
			(end -0.67945 0.3048)
			(stroke
				(width 0.1)
				(type default)
			)
			(layer "B.Fab")
		)
		(fp_line
			(start -0.67945 0.3048)
			(end -0.120396 0.3048)
			(stroke
				(width 0.1)
				(type default)
			)
			(layer "B.Fab")
		)
		(fp_line
			(start -0.12065 -0.3048)
			(end -0.67945 -0.3048)
			(stroke
				(width 0.1)
				(type default)
			)
			(layer "B.Fab")
		)
		(fp_line
			(start -0.12065 -0.2794)
			(end -0.12065 -0.3048)
			(stroke
				(width 0.1)
				(type default)
			)
			(layer "B.Fab")
		)
		(fp_line
			(start -0.120396 0.2794)
			(end 0.12065 0.2794)
			(stroke
				(width 0.1)
				(type default)
			)
			(layer "B.Fab")
		)
		(fp_line
			(start -0.120396 0.3048)
			(end -0.120396 0.2794)
			(stroke
				(width 0.1)
				(type default)
			)
			(layer "B.Fab")
		)
		(fp_line
			(start 0.12065 -0.305054)
			(end 0.12065 -0.2794)
			(stroke
				(width 0.1)
				(type default)
			)
			(layer "B.Fab")
		)
		(fp_line
			(start 0.12065 -0.2794)
			(end -0.12065 -0.2794)
			(stroke
				(width 0.1)
				(type default)
			)
			(layer "B.Fab")
		)
		(fp_line
			(start 0.12065 0.2794)
			(end 0.12065 0.3048)
			(stroke
				(width 0.1)
				(type default)
			)
			(layer "B.Fab")
		)
		(fp_line
			(start 0.12065 0.3048)
			(end 0.67945 0.3048)
			(stroke
				(width 0.1)
				(type default)
			)
			(layer "B.Fab")
		)
		(fp_line
			(start 0.67945 -0.305054)
			(end 0.12065 -0.305054)
			(stroke
				(width 0.1)
				(type default)
			)
			(layer "B.Fab")
		)
		(fp_line
			(start 0.67945 0.3048)
			(end 0.67945 -0.305054)
			(stroke
				(width 0.1)
				(type default)
			)
			(layer "B.Fab")
		)
		(pad "1" smd circle
			(at 0.40005 0 180)
			(size 0 0)
			(layers "B.Cu" "B.Mask" "B.Paste")
			(net "P3V3_AUX")
		)
		(pad "2" smd circle
			(at -0.40005 0 180)
			(size 0 0)
			(layers "B.Cu" "B.Mask" "B.Paste")
			(net "GPU_FPGA_READY")
		)
	)
	(footprint ""
		(layer "B.Cu")
		(at 161.419032 -390.560052 90)
		(property "Reference" "C420"
			(at 0 0 90)
			(layer "B.SilkS")
			(hide yes)
			(effects
				(font
					(size 1.27 1.27)
				)
				(justify mirror)
			)
		)
		(property "Value" ""
			(at 0 0 90)
			(layer "B.Fab")
			(effects
				(font
					(size 1.27 1.27)
				)
				(justify mirror)
			)
		)
		(duplicate_pad_numbers_are_jumpers no)
		(fp_line
			(start 0.7874 -0.4064)
			(end -0.7874 -0.4064)
			(stroke
				(width 0.1524)
				(type default)
			)
			(layer "B.SilkS")
		)
		(fp_line
			(start -0.7874 -0.4064)
			(end -0.7874 0.4064)
			(stroke
				(width 0.1524)
				(type default)
			)
			(layer "B.SilkS")
		)
		(fp_line
			(start 0.7874 0.4064)
			(end 0.7874 -0.4064)
			(stroke
				(width 0.1524)
				(type default)
			)
			(layer "B.SilkS")
		)
		(fp_line
			(start -0.7874 0.4064)
			(end 0.7874 0.4064)
			(stroke
				(width 0.1524)
				(type default)
			)
			(layer "B.SilkS")
		)
		(fp_line
			(start 0.67945 -0.305054)
			(end 0.12065 -0.305054)
			(stroke
				(width 0.1)
				(type default)
			)
			(layer "B.Fab")
		)
		(fp_line
			(start 0.12065 -0.305054)
			(end 0.12065 -0.2794)
			(stroke
				(width 0.1)
				(type default)
			)
			(layer "B.Fab")
		)
		(fp_line
			(start -0.12065 -0.3048)
			(end -0.67945 -0.3048)
			(stroke
				(width 0.1)
				(type default)
			)
			(layer "B.Fab")
		)
		(fp_line
			(start -0.67945 -0.3048)
			(end -0.67945 0.3048)
			(stroke
				(width 0.1)
				(type default)
			)
			(layer "B.Fab")
		)
		(fp_line
			(start 0.12065 -0.2794)
			(end -0.12065 -0.2794)
			(stroke
				(width 0.1)
				(type default)
			)
			(layer "B.Fab")
		)
		(fp_line
			(start -0.12065 -0.2794)
			(end -0.12065 -0.3048)
			(stroke
				(width 0.1)
				(type default)
			)
			(layer "B.Fab")
		)
		(fp_line
			(start 0.12065 0.2794)
			(end 0.12065 0.3048)
			(stroke
				(width 0.1)
				(type default)
			)
			(layer "B.Fab")
		)
		(fp_line
			(start -0.120396 0.2794)
			(end 0.12065 0.2794)
			(stroke
				(width 0.1)
				(type default)
			)
			(layer "B.Fab")
		)
		(fp_line
			(start 0.67945 0.3048)
			(end 0.67945 -0.305054)
			(stroke
				(width 0.1)
				(type default)
			)
			(layer "B.Fab")
		)
		(fp_line
			(start 0.12065 0.3048)
			(end 0.67945 0.3048)
			(stroke
				(width 0.1)
				(type default)
			)
			(layer "B.Fab")
		)
		(fp_line
			(start -0.120396 0.3048)
			(end -0.120396 0.2794)
			(stroke
				(width 0.1)
				(type default)
			)
			(layer "B.Fab")
		)
		(fp_line
			(start -0.67945 0.3048)
			(end -0.120396 0.3048)
			(stroke
				(width 0.1)
				(type default)
			)
			(layer "B.Fab")
		)
		(pad "1" smd circle
			(at 0.40005 0 270)
			(size 0 0)
			(layers "B.Cu" "B.Mask" "B.Paste")
			(net "P0V9_CPU1_RT2_2A")
		)
		(pad "2" smd circle
			(at -0.40005 0 270)
			(size 0 0)
			(layers "B.Cu" "B.Mask" "B.Paste")
			(net "GND")
		)
	)
	(footprint ""
		(layer "B.Cu")
		(at 165.58514 -9.013444 90)
		(property "Reference" "R65"
			(at 0 0 90)
			(layer "B.SilkS")
			(hide yes)
			(effects
				(font
					(size 1.27 1.27)
				)
				(justify mirror)
			)
		)
		(property "Value" ""
			(at 0 0 90)
			(layer "B.Fab")
			(effects
				(font
					(size 1.27 1.27)
				)
				(justify mirror)
			)
		)
		(duplicate_pad_numbers_are_jumpers no)
		(fp_line
			(start 0.7874 -0.4064)
			(end -0.7874 -0.4064)
			(stroke
				(width 0.1524)
				(type default)
			)
			(layer "B.SilkS")
		)
		(fp_line
			(start -0.7874 -0.4064)
			(end -0.7874 0.4064)
			(stroke
				(width 0.1524)
				(type default)
			)
			(layer "B.SilkS")
		)
		(fp_line
			(start 0.7874 0.4064)
			(end 0.7874 -0.4064)
			(stroke
				(width 0.1524)
				(type default)
			)
			(layer "B.SilkS")
		)
		(fp_line
			(start -0.7874 0.4064)
			(end 0.7874 0.4064)
			(stroke
				(width 0.1524)
				(type default)
			)
			(layer "B.SilkS")
		)
		(fp_line
			(start 0.67945 -0.305054)
			(end 0.12065 -0.305054)
			(stroke
				(width 0.1)
				(type default)
			)
			(layer "B.Fab")
		)
		(fp_line
			(start 0.12065 -0.305054)
			(end 0.12065 -0.2794)
			(stroke
				(width 0.1)
				(type default)
			)
			(layer "B.Fab")
		)
		(fp_line
			(start -0.12065 -0.3048)
			(end -0.67945 -0.3048)
			(stroke
				(width 0.1)
				(type default)
			)
			(layer "B.Fab")
		)
		(fp_line
			(start -0.67945 -0.3048)
			(end -0.67945 0.3048)
			(stroke
				(width 0.1)
				(type default)
			)
			(layer "B.Fab")
		)
		(fp_line
			(start 0.12065 -0.2794)
			(end -0.12065 -0.2794)
			(stroke
				(width 0.1)
				(type default)
			)
			(layer "B.Fab")
		)
		(fp_line
			(start -0.12065 -0.2794)
			(end -0.12065 -0.3048)
			(stroke
				(width 0.1)
				(type default)
			)
			(layer "B.Fab")
		)
		(fp_line
			(start 0.12065 0.2794)
			(end 0.12065 0.3048)
			(stroke
				(width 0.1)
				(type default)
			)
			(layer "B.Fab")
		)
		(fp_line
			(start -0.120396 0.2794)
			(end 0.12065 0.2794)
			(stroke
				(width 0.1)
				(type default)
			)
			(layer "B.Fab")
		)
		(fp_line
			(start 0.67945 0.3048)
			(end 0.67945 -0.305054)
			(stroke
				(width 0.1)
				(type default)
			)
			(layer "B.Fab")
		)
		(fp_line
			(start 0.12065 0.3048)
			(end 0.67945 0.3048)
			(stroke
				(width 0.1)
				(type default)
			)
			(layer "B.Fab")
		)
		(fp_line
			(start -0.120396 0.3048)
			(end -0.120396 0.2794)
			(stroke
				(width 0.1)
				(type default)
			)
			(layer "B.Fab")
		)
		(fp_line
			(start -0.67945 0.3048)
			(end -0.120396 0.3048)
			(stroke
				(width 0.1)
				(type default)
			)
			(layer "B.Fab")
		)
		(pad "1" smd circle
			(at 0.40005 0 270)
			(size 0 0)
			(layers "B.Cu" "B.Mask" "B.Paste")
			(net "SMB_PCIE0_3V3AUX_SCL")
		)
		(pad "2" smd circle
			(at -0.40005 0 270)
			(size 0 0)
			(layers "B.Cu" "B.Mask" "B.Paste")
			(net "SMB_PCIE0_3V3AUX_SCL_R")
		)
	)
	(footprint ""
		(layer "B.Cu")
		(at 428.98695 -32.197548 180)
		(property "Reference" "R1358"
			(at 0 0 0)
			(layer "B.SilkS")
			(hide yes)
			(effects
				(font
					(size 1.27 1.27)
				)
				(justify mirror)
			)
		)
		(property "Value" ""
			(at 0 0 0)
			(layer "B.Fab")
			(effects
				(font
					(size 1.27 1.27)
				)
				(justify mirror)
			)
		)
		(duplicate_pad_numbers_are_jumpers no)
		(fp_line
			(start 0.7874 0.4064)
			(end 0.7874 -0.4064)
			(stroke
				(width 0.1524)
				(type default)
			)
			(layer "B.SilkS")
		)
		(fp_line
			(start 0.7874 -0.4064)
			(end -0.7874 -0.4064)
			(stroke
				(width 0.1524)
				(type default)
			)
			(layer "B.SilkS")
		)
		(fp_line
			(start -0.7874 0.4064)
			(end 0.7874 0.4064)
			(stroke
				(width 0.1524)
				(type default)
			)
			(layer "B.SilkS")
		)
		(fp_line
			(start -0.7874 -0.4064)
			(end -0.7874 0.4064)
			(stroke
				(width 0.1524)
				(type default)
			)
			(layer "B.SilkS")
		)
		(fp_line
			(start 0.67945 0.3048)
			(end 0.67945 -0.305054)
			(stroke
				(width 0.1)
				(type default)
			)
			(layer "B.Fab")
		)
		(fp_line
			(start 0.67945 -0.305054)
			(end 0.12065 -0.305054)
			(stroke
				(width 0.1)
				(type default)
			)
			(layer "B.Fab")
		)
		(fp_line
			(start 0.12065 0.3048)
			(end 0.67945 0.3048)
			(stroke
				(width 0.1)
				(type default)
			)
			(layer "B.Fab")
		)
		(fp_line
			(start 0.12065 0.2794)
			(end 0.12065 0.3048)
			(stroke
				(width 0.1)
				(type default)
			)
			(layer "B.Fab")
		)
		(fp_line
			(start 0.12065 -0.2794)
			(end -0.12065 -0.2794)
			(stroke
				(width 0.1)
				(type default)
			)
			(layer "B.Fab")
		)
		(fp_line
			(start 0.12065 -0.305054)
			(end 0.12065 -0.2794)
			(stroke
				(width 0.1)
				(type default)
			)
			(layer "B.Fab")
		)
		(fp_line
			(start -0.120396 0.3048)
			(end -0.120396 0.2794)
			(stroke
				(width 0.1)
				(type default)
			)
			(layer "B.Fab")
		)
		(fp_line
			(start -0.120396 0.2794)
			(end 0.12065 0.2794)
			(stroke
				(width 0.1)
				(type default)
			)
			(layer "B.Fab")
		)
		(fp_line
			(start -0.12065 -0.2794)
			(end -0.12065 -0.3048)
			(stroke
				(width 0.1)
				(type default)
			)
			(layer "B.Fab")
		)
		(fp_line
			(start -0.12065 -0.3048)
			(end -0.67945 -0.3048)
			(stroke
				(width 0.1)
				(type default)
			)
			(layer "B.Fab")
		)
		(fp_line
			(start -0.67945 0.3048)
			(end -0.120396 0.3048)
			(stroke
				(width 0.1)
				(type default)
			)
			(layer "B.Fab")
		)
		(fp_line
			(start -0.67945 -0.3048)
			(end -0.67945 0.3048)
			(stroke
				(width 0.1)
				(type default)
			)
			(layer "B.Fab")
		)
		(pad "1" smd circle
			(at 0.40005 0)
			(size 0 0)
			(layers "B.Cu" "B.Mask" "B.Paste")
			(net "P1V8_AUX")
		)
		(pad "2" smd circle
			(at -0.40005 0)
			(size 0 0)
			(layers "B.Cu" "B.Mask" "B.Paste")
			(net "FM_PASSWORD_CLEAR_N")
		)
	)
	(footprint ""
		(layer "B.Cu")
		(at 353.485958 -272.284952)
		(property "Reference" "C2250"
			(at 0 0 0)
			(layer "B.SilkS")
			(hide yes)
			(effects
				(font
					(size 1.27 1.27)
				)
				(justify mirror)
			)
		)
		(property "Value" ""
			(at 0 0 0)
			(layer "B.Fab")
			(effects
				(font
					(size 1.27 1.27)
				)
				(justify mirror)
			)
		)
		(duplicate_pad_numbers_are_jumpers no)
		(fp_line
			(start -0.7874 -0.4064)
			(end -0.7874 0.4064)
			(stroke
				(width 0.1524)
				(type default)
			)
			(layer "B.SilkS")
		)
		(fp_line
			(start -0.7874 0.4064)
			(end 0.7874 0.4064)
			(stroke
				(width 0.1524)
				(type default)
			)
			(layer "B.SilkS")
		)
		(fp_line
			(start 0.7874 -0.4064)
			(end -0.7874 -0.4064)
			(stroke
				(width 0.1524)
				(type default)
			)
			(layer "B.SilkS")
		)
		(fp_line
			(start 0.7874 0.4064)
			(end 0.7874 -0.4064)
			(stroke
				(width 0.1524)
				(type default)
			)
			(layer "B.SilkS")
		)
		(fp_line
			(start -0.67945 -0.3048)
			(end -0.67945 0.3048)
			(stroke
				(width 0.1)
				(type default)
			)
			(layer "B.Fab")
		)
		(fp_line
			(start -0.67945 0.3048)
			(end -0.120396 0.3048)
			(stroke
				(width 0.1)
				(type default)
			)
			(layer "B.Fab")
		)
		(fp_line
			(start -0.12065 -0.3048)
			(end -0.67945 -0.3048)
			(stroke
				(width 0.1)
				(type default)
			)
			(layer "B.Fab")
		)
		(fp_line
			(start -0.12065 -0.2794)
			(end -0.12065 -0.3048)
			(stroke
				(width 0.1)
				(type default)
			)
			(layer "B.Fab")
		)
		(fp_line
			(start -0.120396 0.2794)
			(end 0.12065 0.2794)
			(stroke
				(width 0.1)
				(type default)
			)
			(layer "B.Fab")
		)
		(fp_line
			(start -0.120396 0.3048)
			(end -0.120396 0.2794)
			(stroke
				(width 0.1)
				(type default)
			)
			(layer "B.Fab")
		)
		(fp_line
			(start 0.12065 -0.305054)
			(end 0.12065 -0.2794)
			(stroke
				(width 0.1)
				(type default)
			)
			(layer "B.Fab")
		)
		(fp_line
			(start 0.12065 -0.2794)
			(end -0.12065 -0.2794)
			(stroke
				(width 0.1)
				(type default)
			)
			(layer "B.Fab")
		)
		(fp_line
			(start 0.12065 0.2794)
			(end 0.12065 0.3048)
			(stroke
				(width 0.1)
				(type default)
			)
			(layer "B.Fab")
		)
		(fp_line
			(start 0.12065 0.3048)
			(end 0.67945 0.3048)
			(stroke
				(width 0.1)
				(type default)
			)
			(layer "B.Fab")
		)
		(fp_line
			(start 0.67945 -0.305054)
			(end 0.12065 -0.305054)
			(stroke
				(width 0.1)
				(type default)
			)
			(layer "B.Fab")
		)
		(fp_line
			(start 0.67945 0.3048)
			(end 0.67945 -0.305054)
			(stroke
				(width 0.1)
				(type default)
			)
			(layer "B.Fab")
		)
		(pad "1" smd circle
			(at 0.40005 0 180)
			(size 0 0)
			(layers "B.Cu" "B.Mask" "B.Paste")
			(net "PVDDCR_CPU1_P0")
		)
		(pad "2" smd circle
			(at -0.40005 0 180)
			(size 0 0)
			(layers "B.Cu" "B.Mask" "B.Paste")
			(net "GND")
		)
	)
	(footprint ""
		(layer "B.Cu")
		(at 353.136454 -248.47931)
		(property "Reference" "C2178"
			(at 0 0 0)
			(layer "B.SilkS")
			(hide yes)
			(effects
				(font
					(size 1.27 1.27)
				)
				(justify mirror)
			)
		)
		(property "Value" ""
			(at 0 0 0)
			(layer "B.Fab")
			(effects
				(font
					(size 1.27 1.27)
				)
				(justify mirror)
			)
		)
		(duplicate_pad_numbers_are_jumpers no)
		(fp_line
			(start -0.7874 -0.4064)
			(end -0.7874 0.4064)
			(stroke
				(width 0.1524)
				(type default)
			)
			(layer "B.SilkS")
		)
		(fp_line
			(start -0.7874 0.4064)
			(end 0.7874 0.4064)
			(stroke
				(width 0.1524)
				(type default)
			)
			(layer "B.SilkS")
		)
		(fp_line
			(start 0.7874 -0.4064)
			(end -0.7874 -0.4064)
			(stroke
				(width 0.1524)
				(type default)
			)
			(layer "B.SilkS")
		)
		(fp_line
			(start 0.7874 0.4064)
			(end 0.7874 -0.4064)
			(stroke
				(width 0.1524)
				(type default)
			)
			(layer "B.SilkS")
		)
		(fp_line
			(start -0.67945 -0.3048)
			(end -0.67945 0.3048)
			(stroke
				(width 0.1)
				(type default)
			)
			(layer "B.Fab")
		)
		(fp_line
			(start -0.67945 0.3048)
			(end -0.120396 0.3048)
			(stroke
				(width 0.1)
				(type default)
			)
			(layer "B.Fab")
		)
		(fp_line
			(start -0.12065 -0.3048)
			(end -0.67945 -0.3048)
			(stroke
				(width 0.1)
				(type default)
			)
			(layer "B.Fab")
		)
		(fp_line
			(start -0.12065 -0.2794)
			(end -0.12065 -0.3048)
			(stroke
				(width 0.1)
				(type default)
			)
			(layer "B.Fab")
		)
		(fp_line
			(start -0.120396 0.2794)
			(end 0.12065 0.2794)
			(stroke
				(width 0.1)
				(type default)
			)
			(layer "B.Fab")
		)
		(fp_line
			(start -0.120396 0.3048)
			(end -0.120396 0.2794)
			(stroke
				(width 0.1)
				(type default)
			)
			(layer "B.Fab")
		)
		(fp_line
			(start 0.12065 -0.305054)
			(end 0.12065 -0.2794)
			(stroke
				(width 0.1)
				(type default)
			)
			(layer "B.Fab")
		)
		(fp_line
			(start 0.12065 -0.2794)
			(end -0.12065 -0.2794)
			(stroke
				(width 0.1)
				(type default)
			)
			(layer "B.Fab")
		)
		(fp_line
			(start 0.12065 0.2794)
			(end 0.12065 0.3048)
			(stroke
				(width 0.1)
				(type default)
			)
			(layer "B.Fab")
		)
		(fp_line
			(start 0.12065 0.3048)
			(end 0.67945 0.3048)
			(stroke
				(width 0.1)
				(type default)
			)
			(layer "B.Fab")
		)
		(fp_line
			(start 0.67945 -0.305054)
			(end 0.12065 -0.305054)
			(stroke
				(width 0.1)
				(type default)
			)
			(layer "B.Fab")
		)
		(fp_line
			(start 0.67945 0.3048)
			(end 0.67945 -0.305054)
			(stroke
				(width 0.1)
				(type default)
			)
			(layer "B.Fab")
		)
		(pad "1" smd circle
			(at 0.40005 0 180)
			(size 0 0)
			(layers "B.Cu" "B.Mask" "B.Paste")
			(net "PVDDCR_CPU0_P0")
		)
		(pad "2" smd circle
			(at -0.40005 0 180)
			(size 0 0)
			(layers "B.Cu" "B.Mask" "B.Paste")
			(net "GND")
		)
	)
	(footprint ""
		(layer "B.Cu")
		(at 79.700628 -385.50088 -90)
		(property "Reference" "C293"
			(at 0 0 90)
			(layer "B.SilkS")
			(hide yes)
			(effects
				(font
					(size 1.27 1.27)
				)
				(justify mirror)
			)
		)
		(property "Value" ""
			(at 0 0 90)
			(layer "B.Fab")
			(effects
				(font
					(size 1.27 1.27)
				)
				(justify mirror)
			)
		)
		(duplicate_pad_numbers_are_jumpers no)
		(fp_line
			(start -0.299974 0.150114)
			(end 0.299974 0.150114)
			(stroke
				(width 0.1)
				(type default)
			)
			(layer "B.Fab")
		)
		(fp_line
			(start 0.299974 0.150114)
			(end 0.299974 -0.150114)
			(stroke
				(width 0.1)
				(type default)
			)
			(layer "B.Fab")
		)
		(fp_line
			(start -0.299974 -0.150114)
			(end -0.299974 0.150114)
			(stroke
				(width 0.1)
				(type default)
			)
			(layer "B.Fab")
		)
		(fp_line
			(start 0.299974 -0.150114)
			(end -0.299974 -0.150114)
			(stroke
				(width 0.1)
				(type default)
			)
			(layer "B.Fab")
		)
		(pad "1" smd rect
			(at 0.2667 0 90)
			(size 0.3048 0.381)
			(layers "B.Cu" "B.Mask" "B.Paste")
			(net "P0V9_CPU1_RT1_2A")
		)
		(pad "2" smd rect
			(at -0.2667 0 90)
			(size 0.3048 0.381)
			(layers "B.Cu" "B.Mask" "B.Paste")
			(net "GND")
		)
	)
	(footprint ""
		(layer "B.Cu")
		(at 148.122386 -314.47105)
		(property "Reference" "C236"
			(at 0 0 0)
			(layer "B.SilkS")
			(hide yes)
			(effects
				(font
					(size 1.27 1.27)
				)
				(justify mirror)
			)
		)
		(property "Value" ""
			(at 0 0 0)
			(layer "B.Fab")
			(effects
				(font
					(size 1.27 1.27)
				)
				(justify mirror)
			)
		)
		(duplicate_pad_numbers_are_jumpers no)
		(fp_line
			(start -0.7874 -0.4064)
			(end -0.7874 0.4064)
			(stroke
				(width 0.1524)
				(type default)
			)
			(layer "B.SilkS")
		)
		(fp_line
			(start -0.7874 0.4064)
			(end 0.7874 0.4064)
			(stroke
				(width 0.1524)
				(type default)
			)
			(layer "B.SilkS")
		)
		(fp_line
			(start 0.7874 -0.4064)
			(end -0.7874 -0.4064)
			(stroke
				(width 0.1524)
				(type default)
			)
			(layer "B.SilkS")
		)
		(fp_line
			(start 0.7874 0.4064)
			(end 0.7874 -0.4064)
			(stroke
				(width 0.1524)
				(type default)
			)
			(layer "B.SilkS")
		)
		(fp_line
			(start -0.67945 -0.3048)
			(end -0.67945 0.3048)
			(stroke
				(width 0.1)
				(type default)
			)
			(layer "B.Fab")
		)
		(fp_line
			(start -0.67945 0.3048)
			(end -0.120396 0.3048)
			(stroke
				(width 0.1)
				(type default)
			)
			(layer "B.Fab")
		)
		(fp_line
			(start -0.12065 -0.3048)
			(end -0.67945 -0.3048)
			(stroke
				(width 0.1)
				(type default)
			)
			(layer "B.Fab")
		)
		(fp_line
			(start -0.12065 -0.2794)
			(end -0.12065 -0.3048)
			(stroke
				(width 0.1)
				(type default)
			)
			(layer "B.Fab")
		)
		(fp_line
			(start -0.120396 0.2794)
			(end 0.12065 0.2794)
			(stroke
				(width 0.1)
				(type default)
			)
			(layer "B.Fab")
		)
		(fp_line
			(start -0.120396 0.3048)
			(end -0.120396 0.2794)
			(stroke
				(width 0.1)
				(type default)
			)
			(layer "B.Fab")
		)
		(fp_line
			(start 0.12065 -0.305054)
			(end 0.12065 -0.2794)
			(stroke
				(width 0.1)
				(type default)
			)
			(layer "B.Fab")
		)
		(fp_line
			(start 0.12065 -0.2794)
			(end -0.12065 -0.2794)
			(stroke
				(width 0.1)
				(type default)
			)
			(layer "B.Fab")
		)
		(fp_line
			(start 0.12065 0.2794)
			(end 0.12065 0.3048)
			(stroke
				(width 0.1)
				(type default)
			)
			(layer "B.Fab")
		)
		(fp_line
			(start 0.12065 0.3048)
			(end 0.67945 0.3048)
			(stroke
				(width 0.1)
				(type default)
			)
			(layer "B.Fab")
		)
		(fp_line
			(start 0.67945 -0.305054)
			(end 0.12065 -0.305054)
			(stroke
				(width 0.1)
				(type default)
			)
			(layer "B.Fab")
		)
		(fp_line
			(start 0.67945 0.3048)
			(end 0.67945 -0.305054)
			(stroke
				(width 0.1)
				(type default)
			)
			(layer "B.Fab")
		)
		(pad "1" smd circle
			(at 0.40005 0 180)
			(size 0 0)
			(layers "B.Cu" "B.Mask" "B.Paste")
			(net "XTAL_CPU1_X48M_X1")
		)
		(pad "2" smd circle
			(at -0.40005 0 180)
			(size 0 0)
			(layers "B.Cu" "B.Mask" "B.Paste")
			(net "GND")
		)
	)
	(footprint ""
		(layer "B.Cu")
		(at 115.70589 -259.845302 180)
		(property "Reference" "C2488"
			(at 0 0 0)
			(layer "B.SilkS")
			(hide yes)
			(effects
				(font
					(size 1.27 1.27)
				)
				(justify mirror)
			)
		)
		(property "Value" ""
			(at 0 0 0)
			(layer "B.Fab")
			(effects
				(font
					(size 1.27 1.27)
				)
				(justify mirror)
			)
		)
		(duplicate_pad_numbers_are_jumpers no)
		(fp_line
			(start 0.7874 0.4064)
			(end 0.7874 -0.4064)
			(stroke
				(width 0.1524)
				(type default)
			)
			(layer "B.SilkS")
		)
		(fp_line
			(start 0.7874 -0.4064)
			(end -0.7874 -0.4064)
			(stroke
				(width 0.1524)
				(type default)
			)
			(layer "B.SilkS")
		)
		(fp_line
			(start -0.7874 0.4064)
			(end 0.7874 0.4064)
			(stroke
				(width 0.1524)
				(type default)
			)
			(layer "B.SilkS")
		)
		(fp_line
			(start -0.7874 -0.4064)
			(end -0.7874 0.4064)
			(stroke
				(width 0.1524)
				(type default)
			)
			(layer "B.SilkS")
		)
		(fp_line
			(start 0.67945 0.3048)
			(end 0.67945 -0.305054)
			(stroke
				(width 0.1)
				(type default)
			)
			(layer "B.Fab")
		)
		(fp_line
			(start 0.67945 -0.305054)
			(end 0.12065 -0.305054)
			(stroke
				(width 0.1)
				(type default)
			)
			(layer "B.Fab")
		)
		(fp_line
			(start 0.12065 0.3048)
			(end 0.67945 0.3048)
			(stroke
				(width 0.1)
				(type default)
			)
			(layer "B.Fab")
		)
		(fp_line
			(start 0.12065 0.2794)
			(end 0.12065 0.3048)
			(stroke
				(width 0.1)
				(type default)
			)
			(layer "B.Fab")
		)
		(fp_line
			(start 0.12065 -0.2794)
			(end -0.12065 -0.2794)
			(stroke
				(width 0.1)
				(type default)
			)
			(layer "B.Fab")
		)
		(fp_line
			(start 0.12065 -0.305054)
			(end 0.12065 -0.2794)
			(stroke
				(width 0.1)
				(type default)
			)
			(layer "B.Fab")
		)
		(fp_line
			(start -0.120396 0.3048)
			(end -0.120396 0.2794)
			(stroke
				(width 0.1)
				(type default)
			)
			(layer "B.Fab")
		)
		(fp_line
			(start -0.120396 0.2794)
			(end 0.12065 0.2794)
			(stroke
				(width 0.1)
				(type default)
			)
			(layer "B.Fab")
		)
		(fp_line
			(start -0.12065 -0.2794)
			(end -0.12065 -0.3048)
			(stroke
				(width 0.1)
				(type default)
			)
			(layer "B.Fab")
		)
		(fp_line
			(start -0.12065 -0.3048)
			(end -0.67945 -0.3048)
			(stroke
				(width 0.1)
				(type default)
			)
			(layer "B.Fab")
		)
		(fp_line
			(start -0.67945 0.3048)
			(end -0.120396 0.3048)
			(stroke
				(width 0.1)
				(type default)
			)
			(layer "B.Fab")
		)
		(fp_line
			(start -0.67945 -0.3048)
			(end -0.67945 0.3048)
			(stroke
				(width 0.1)
				(type default)
			)
			(layer "B.Fab")
		)
		(pad "1" smd circle
			(at 0.40005 0)
			(size 0 0)
			(layers "B.Cu" "B.Mask" "B.Paste")
			(net "PVDD11_S3_P1")
		)
		(pad "2" smd circle
			(at -0.40005 0)
			(size 0 0)
			(layers "B.Cu" "B.Mask" "B.Paste")
			(net "GND")
		)
	)
	(footprint ""
		(layer "B.Cu")
		(at 72.052434 -386.745988 -90)
		(property "Reference" "C122"
			(at 0 0 90)
			(layer "B.SilkS")
			(hide yes)
			(effects
				(font
					(size 1.27 1.27)
				)
				(justify mirror)
			)
		)
		(property "Value" ""
			(at 0 0 90)
			(layer "B.Fab")
			(effects
				(font
					(size 1.27 1.27)
				)
				(justify mirror)
			)
		)
		(duplicate_pad_numbers_are_jumpers no)
		(fp_line
			(start -0.7874 0.4064)
			(end 0.7874 0.4064)
			(stroke
				(width 0.1524)
				(type default)
			)
			(layer "B.SilkS")
		)
		(fp_line
			(start 0.7874 0.4064)
			(end 0.7874 -0.4064)
			(stroke
				(width 0.1524)
				(type default)
			)
			(layer "B.SilkS")
		)
		(fp_line
			(start -0.7874 -0.4064)
			(end -0.7874 0.4064)
			(stroke
				(width 0.1524)
				(type default)
			)
			(layer "B.SilkS")
		)
		(fp_line
			(start 0.7874 -0.4064)
			(end -0.7874 -0.4064)
			(stroke
				(width 0.1524)
				(type default)
			)
			(layer "B.SilkS")
		)
		(fp_line
			(start -0.67945 0.3048)
			(end -0.120396 0.3048)
			(stroke
				(width 0.1)
				(type default)
			)
			(layer "B.Fab")
		)
		(fp_line
			(start -0.120396 0.3048)
			(end -0.120396 0.2794)
			(stroke
				(width 0.1)
				(type default)
			)
			(layer "B.Fab")
		)
		(fp_line
			(start 0.12065 0.3048)
			(end 0.67945 0.3048)
			(stroke
				(width 0.1)
				(type default)
			)
			(layer "B.Fab")
		)
		(fp_line
			(start 0.67945 0.3048)
			(end 0.67945 -0.305054)
			(stroke
				(width 0.1)
				(type default)
			)
			(layer "B.Fab")
		)
		(fp_line
			(start -0.120396 0.2794)
			(end 0.12065 0.2794)
			(stroke
				(width 0.1)
				(type default)
			)
			(layer "B.Fab")
		)
		(fp_line
			(start 0.12065 0.2794)
			(end 0.12065 0.3048)
			(stroke
				(width 0.1)
				(type default)
			)
			(layer "B.Fab")
		)
		(fp_line
			(start -0.12065 -0.2794)
			(end -0.12065 -0.3048)
			(stroke
				(width 0.1)
				(type default)
			)
			(layer "B.Fab")
		)
		(fp_line
			(start 0.12065 -0.2794)
			(end -0.12065 -0.2794)
			(stroke
				(width 0.1)
				(type default)
			)
			(layer "B.Fab")
		)
		(fp_line
			(start -0.67945 -0.3048)
			(end -0.67945 0.3048)
			(stroke
				(width 0.1)
				(type default)
			)
			(layer "B.Fab")
		)
		(fp_line
			(start -0.12065 -0.3048)
			(end -0.67945 -0.3048)
			(stroke
				(width 0.1)
				(type default)
			)
			(layer "B.Fab")
		)
		(fp_line
			(start 0.12065 -0.305054)
			(end 0.12065 -0.2794)
			(stroke
				(width 0.1)
				(type default)
			)
			(layer "B.Fab")
		)
		(fp_line
			(start 0.67945 -0.305054)
			(end 0.12065 -0.305054)
			(stroke
				(width 0.1)
				(type default)
			)
			(layer "B.Fab")
		)
		(pad "1" smd circle
			(at 0.40005 0 90)
			(size 0 0)
			(layers "B.Cu" "B.Mask" "B.Paste")
			(net "P1V8_CPU1_RT_1D")
		)
		(pad "2" smd circle
			(at -0.40005 0 90)
			(size 0 0)
			(layers "B.Cu" "B.Mask" "B.Paste")
			(net "GND")
		)
	)
	(footprint ""
		(layer "B.Cu")
		(at 185.496708 -422.208452 90)
		(property "Reference" "R8109"
			(at 0 0 90)
			(layer "B.SilkS")
			(hide yes)
			(effects
				(font
					(size 1.27 1.27)
				)
				(justify mirror)
			)
		)
		(property "Value" ""
			(at 0 0 90)
			(layer "B.Fab")
			(effects
				(font
					(size 1.27 1.27)
				)
				(justify mirror)
			)
		)
		(duplicate_pad_numbers_are_jumpers no)
		(fp_line
			(start 0.7874 -0.4064)
			(end -0.7874 -0.4064)
			(stroke
				(width 0.1524)
				(type default)
			)
			(layer "B.SilkS")
		)
		(fp_line
			(start -0.7874 -0.4064)
			(end -0.7874 0.4064)
			(stroke
				(width 0.1524)
				(type default)
			)
			(layer "B.SilkS")
		)
		(fp_line
			(start 0.7874 0.4064)
			(end 0.7874 -0.4064)
			(stroke
				(width 0.1524)
				(type default)
			)
			(layer "B.SilkS")
		)
		(fp_line
			(start -0.7874 0.4064)
			(end 0.7874 0.4064)
			(stroke
				(width 0.1524)
				(type default)
			)
			(layer "B.SilkS")
		)
		(fp_line
			(start 0.67945 -0.305054)
			(end 0.12065 -0.305054)
			(stroke
				(width 0.1)
				(type default)
			)
			(layer "B.Fab")
		)
		(fp_line
			(start 0.12065 -0.305054)
			(end 0.12065 -0.2794)
			(stroke
				(width 0.1)
				(type default)
			)
			(layer "B.Fab")
		)
		(fp_line
			(start -0.12065 -0.3048)
			(end -0.67945 -0.3048)
			(stroke
				(width 0.1)
				(type default)
			)
			(layer "B.Fab")
		)
		(fp_line
			(start -0.67945 -0.3048)
			(end -0.67945 0.3048)
			(stroke
				(width 0.1)
				(type default)
			)
			(layer "B.Fab")
		)
		(fp_line
			(start 0.12065 -0.2794)
			(end -0.12065 -0.2794)
			(stroke
				(width 0.1)
				(type default)
			)
			(layer "B.Fab")
		)
		(fp_line
			(start -0.12065 -0.2794)
			(end -0.12065 -0.3048)
			(stroke
				(width 0.1)
				(type default)
			)
			(layer "B.Fab")
		)
		(fp_line
			(start 0.12065 0.2794)
			(end 0.12065 0.3048)
			(stroke
				(width 0.1)
				(type default)
			)
			(layer "B.Fab")
		)
		(fp_line
			(start -0.120396 0.2794)
			(end 0.12065 0.2794)
			(stroke
				(width 0.1)
				(type default)
			)
			(layer "B.Fab")
		)
		(fp_line
			(start 0.67945 0.3048)
			(end 0.67945 -0.305054)
			(stroke
				(width 0.1)
				(type default)
			)
			(layer "B.Fab")
		)
		(fp_line
			(start 0.12065 0.3048)
			(end 0.67945 0.3048)
			(stroke
				(width 0.1)
				(type default)
			)
			(layer "B.Fab")
		)
		(fp_line
			(start -0.120396 0.3048)
			(end -0.120396 0.2794)
			(stroke
				(width 0.1)
				(type default)
			)
			(layer "B.Fab")
		)
		(fp_line
			(start -0.67945 0.3048)
			(end -0.120396 0.3048)
			(stroke
				(width 0.1)
				(type default)
			)
			(layer "B.Fab")
		)
		(pad "1" smd circle
			(at 0.40005 0 270)
			(size 0 0)
			(layers "B.Cu" "B.Mask" "B.Paste")
			(net "HSC_OC_VOL")
		)
		(pad "2" smd circle
			(at -0.40005 0 270)
			(size 0 0)
			(layers "B.Cu" "B.Mask" "B.Paste")
			(net "GND")
		)
	)
	(footprint ""
		(layer "B.Cu")
		(at 109.519466 -390.587484)
		(property "Reference" "C479"
			(at 0 0 0)
			(layer "B.SilkS")
			(hide yes)
			(effects
				(font
					(size 1.27 1.27)
				)
				(justify mirror)
			)
		)
		(property "Value" ""
			(at 0 0 0)
			(layer "B.Fab")
			(effects
				(font
					(size 1.27 1.27)
				)
				(justify mirror)
			)
		)
		(duplicate_pad_numbers_are_jumpers no)
		(fp_line
			(start -1.524 -0.762)
			(end -1.524 0.762)
			(stroke
				(width 0.1524)
				(type default)
			)
			(layer "B.SilkS")
		)
		(fp_line
			(start -1.524 0.762)
			(end 1.524 0.762)
			(stroke
				(width 0.1524)
				(type default)
			)
			(layer "B.SilkS")
		)
		(fp_line
			(start 1.524 -0.762)
			(end -1.524 -0.762)
			(stroke
				(width 0.1524)
				(type default)
			)
			(layer "B.SilkS")
		)
		(fp_line
			(start 1.524 0.762)
			(end 1.524 -0.762)
			(stroke
				(width 0.1524)
				(type default)
			)
			(layer "B.SilkS")
		)
		(fp_line
			(start -1.1049 -0.724916)
			(end 1.1049 -0.724916)
			(stroke
				(width 0.1)
				(type default)
			)
			(layer "B.Fab")
		)
		(fp_line
			(start -1.1049 0.724916)
			(end -1.1049 -0.724916)
			(stroke
				(width 0.1)
				(type default)
			)
			(layer "B.Fab")
		)
		(fp_line
			(start 1.1049 -0.724916)
			(end 1.1049 0.724916)
			(stroke
				(width 0.1)
				(type default)
			)
			(layer "B.Fab")
		)
		(fp_line
			(start 1.1049 0.724916)
			(end -1.1049 0.724916)
			(stroke
				(width 0.1)
				(type default)
			)
			(layer "B.Fab")
		)
		(pad "1" smd rect
			(at 0.889 0)
			(size 1.016 1.27)
			(layers "B.Cu" "B.Mask" "B.Paste")
			(net "P0V9_CPU1_RT3_2A")
		)
		(pad "2" smd rect
			(at -0.889 0)
			(size 1.016 1.27)
			(layers "B.Cu" "B.Mask" "B.Paste")
			(net "GND")
		)
	)
	(footprint ""
		(layer "B.Cu")
		(at 306.978304 -395.148562 90)
		(property "Reference" "C581"
			(at 0 0 90)
			(layer "B.SilkS")
			(hide yes)
			(effects
				(font
					(size 1.27 1.27)
				)
				(justify mirror)
			)
		)
		(property "Value" ""
			(at 0 0 90)
			(layer "B.Fab")
			(effects
				(font
					(size 1.27 1.27)
				)
				(justify mirror)
			)
		)
		(duplicate_pad_numbers_are_jumpers no)
		(fp_line
			(start 0.299974 -0.150114)
			(end -0.299974 -0.150114)
			(stroke
				(width 0.1)
				(type default)
			)
			(layer "B.Fab")
		)
		(fp_line
			(start -0.299974 -0.150114)
			(end -0.299974 0.150114)
			(stroke
				(width 0.1)
				(type default)
			)
			(layer "B.Fab")
		)
		(fp_line
			(start 0.299974 0.150114)
			(end 0.299974 -0.150114)
			(stroke
				(width 0.1)
				(type default)
			)
			(layer "B.Fab")
		)
		(fp_line
			(start -0.299974 0.150114)
			(end 0.299974 0.150114)
			(stroke
				(width 0.1)
				(type default)
			)
			(layer "B.Fab")
		)
		(pad "1" smd rect
			(at 0.2667 0 270)
			(size 0.3048 0.381)
			(layers "B.Cu" "B.Mask" "B.Paste")
			(net "P0V9_CPU0_RT0_2A")
		)
		(pad "2" smd rect
			(at -0.2667 0 270)
			(size 0.3048 0.381)
			(layers "B.Cu" "B.Mask" "B.Paste")
			(net "GND")
		)
	)
	(footprint ""
		(layer "B.Cu")
		(at 380.075186 -214.523828 90)
		(property "Reference" "R8564"
			(at 0 0 90)
			(layer "B.SilkS")
			(hide yes)
			(effects
				(font
					(size 1.27 1.27)
				)
				(justify mirror)
			)
		)
		(property "Value" ""
			(at 0 0 90)
			(layer "B.Fab")
			(effects
				(font
					(size 1.27 1.27)
				)
				(justify mirror)
			)
		)
		(duplicate_pad_numbers_are_jumpers no)
		(fp_line
			(start 0.7874 -0.4064)
			(end -0.7874 -0.4064)
			(stroke
				(width 0.1524)
				(type default)
			)
			(layer "B.SilkS")
		)
		(fp_line
			(start -0.7874 -0.4064)
			(end -0.7874 0.010414)
			(stroke
				(width 0.1524)
				(type default)
			)
			(layer "B.SilkS")
		)
		(fp_line
			(start 0.7874 0.035814)
			(end 0.7874 -0.4064)
			(stroke
				(width 0.1524)
				(type default)
			)
			(layer "B.SilkS")
		)
		(fp_line
			(start -0.325628 0.4064)
			(end 0.436372 0.4064)
			(stroke
				(width 0.1524)
				(type default)
			)
			(layer "B.SilkS")
		)
		(fp_line
			(start 0.67945 -0.305054)
			(end 0.12065 -0.305054)
			(stroke
				(width 0.1)
				(type default)
			)
			(layer "B.Fab")
		)
		(fp_line
			(start 0.12065 -0.305054)
			(end 0.12065 -0.2794)
			(stroke
				(width 0.1)
				(type default)
			)
			(layer "B.Fab")
		)
		(fp_line
			(start -0.12065 -0.3048)
			(end -0.67945 -0.3048)
			(stroke
				(width 0.1)
				(type default)
			)
			(layer "B.Fab")
		)
		(fp_line
			(start -0.67945 -0.3048)
			(end -0.67945 0.3048)
			(stroke
				(width 0.1)
				(type default)
			)
			(layer "B.Fab")
		)
		(fp_line
			(start 0.12065 -0.2794)
			(end -0.12065 -0.2794)
			(stroke
				(width 0.1)
				(type default)
			)
			(layer "B.Fab")
		)
		(fp_line
			(start -0.12065 -0.2794)
			(end -0.12065 -0.3048)
			(stroke
				(width 0.1)
				(type default)
			)
			(layer "B.Fab")
		)
		(fp_line
			(start 0.12065 0.2794)
			(end 0.12065 0.3048)
			(stroke
				(width 0.1)
				(type default)
			)
			(layer "B.Fab")
		)
		(fp_line
			(start -0.120396 0.2794)
			(end 0.12065 0.2794)
			(stroke
				(width 0.1)
				(type default)
			)
			(layer "B.Fab")
		)
		(fp_line
			(start 0.67945 0.3048)
			(end 0.67945 -0.305054)
			(stroke
				(width 0.1)
				(type default)
			)
			(layer "B.Fab")
		)
		(fp_line
			(start 0.12065 0.3048)
			(end 0.67945 0.3048)
			(stroke
				(width 0.1)
				(type default)
			)
			(layer "B.Fab")
		)
		(fp_line
			(start -0.120396 0.3048)
			(end -0.120396 0.2794)
			(stroke
				(width 0.1)
				(type default)
			)
			(layer "B.Fab")
		)
		(fp_line
			(start -0.67945 0.3048)
			(end -0.120396 0.3048)
			(stroke
				(width 0.1)
				(type default)
			)
			(layer "B.Fab")
		)
		(pad "1" smd circle
			(at 0.40005 0 270)
			(size 0 0)
			(layers "B.Cu" "B.Mask" "B.Paste")
			(net "CLK_100M_CPU0_CLK02_R_DN")
		)
		(pad "2" smd circle
			(at -0.40005 0 270)
			(size 0 0)
			(layers "B.Cu" "B.Mask" "B.Paste")
			(net "CLK_100M_CPU0_CLK02_DN")
		)
	)
	(footprint ""
		(layer "B.Cu")
		(at 216.916 -337.439 90)
		(property "Reference" "R6739"
			(at 0 0 90)
			(layer "B.SilkS")
			(hide yes)
			(effects
				(font
					(size 1.27 1.27)
				)
				(justify mirror)
			)
		)
		(property "Value" ""
			(at 0 0 90)
			(layer "B.Fab")
			(effects
				(font
					(size 1.27 1.27)
				)
				(justify mirror)
			)
		)
		(duplicate_pad_numbers_are_jumpers no)
		(fp_line
			(start 0.32512 -0.175006)
			(end -0.32512 -0.175006)
			(stroke
				(width 0.1)
				(type default)
			)
			(layer "B.Fab")
		)
		(fp_line
			(start -0.32512 -0.175006)
			(end -0.32512 0.175006)
			(stroke
				(width 0.1)
				(type default)
			)
			(layer "B.Fab")
		)
		(fp_line
			(start 0.32512 0.175006)
			(end 0.32512 -0.175006)
			(stroke
				(width 0.1)
				(type default)
			)
			(layer "B.Fab")
		)
		(fp_line
			(start -0.32512 0.175006)
			(end 0.32512 0.175006)
			(stroke
				(width 0.1)
				(type default)
			)
			(layer "B.Fab")
		)
		(pad "1" smd rect
			(at 0.2667 0 270)
			(size 0.3048 0.381)
			(layers "B.Cu" "B.Mask" "B.Paste")
			(net "P1V8_CPU1_RT_1D")
		)
		(pad "2" smd rect
			(at -0.2667 0 90)
			(size 0.3048 0.381)
			(layers "B.Cu" "B.Mask" "B.Paste")
			(net "SMB_RT_CPU1_P1_R_SCL")
		)
	)
	(footprint ""
		(layer "B.Cu")
		(at 306.7304 -354.076 180)
		(property "Reference" "TP6"
			(at 0.69088 -0.114554 0)
			(unlocked yes)
			(layer "B.SilkS")
			(effects
				(font
					(size 0.7874 0.5842)
					(thickness 0.1524)
				)
				(justify left mirror)
			)
		)
		(property "Value" ""
			(at 0 0 0)
			(layer "B.Fab")
			(effects
				(font
					(size 1.27 1.27)
				)
				(justify mirror)
			)
		)
		(duplicate_pad_numbers_are_jumpers no)
		(pad "1" smd circle
			(at 0 0)
			(size 0.762 0.762)
			(layers "B.Cu" "B.Mask" "B.Paste")
			(net "VSENSE_PVDDCR_CPU1_P0_DP")
		)
	)
	(footprint ""
		(layer "B.Cu")
		(at 73.806304 -408.517344 90)
		(property "Reference" "C6678"
			(at 0 0 90)
			(layer "B.SilkS")
			(hide yes)
			(effects
				(font
					(size 1.27 1.27)
				)
				(justify mirror)
			)
		)
		(property "Value" ""
			(at 0 0 90)
			(layer "B.Fab")
			(effects
				(font
					(size 1.27 1.27)
				)
				(justify mirror)
			)
		)
		(duplicate_pad_numbers_are_jumpers no)
		(fp_line
			(start 0.299974 -0.150114)
			(end -0.299974 -0.150114)
			(stroke
				(width 0.1)
				(type default)
			)
			(layer "B.Fab")
		)
		(fp_line
			(start -0.299974 -0.150114)
			(end -0.299974 0.150114)
			(stroke
				(width 0.1)
				(type default)
			)
			(layer "B.Fab")
		)
		(fp_line
			(start 0.299974 0.150114)
			(end 0.299974 -0.150114)
			(stroke
				(width 0.1)
				(type default)
			)
			(layer "B.Fab")
		)
		(fp_line
			(start -0.299974 0.150114)
			(end 0.299974 0.150114)
			(stroke
				(width 0.1)
				(type default)
			)
			(layer "B.Fab")
		)
		(pad "1" smd rect
			(at 0.2667 0 270)
			(size 0.3048 0.381)
			(layers "B.Cu" "B.Mask" "B.Paste")
			(net "P5E_CPU1_P1_TX_BUF_C_DN<8>")
		)
		(pad "2" smd rect
			(at -0.2667 0 270)
			(size 0.3048 0.381)
			(layers "B.Cu" "B.Mask" "B.Paste")
			(net "P5E_CPU1_P1_TX_BUF_DN<8>")
		)
	)
	(footprint ""
		(layer "B.Cu")
		(at 317.791084 -398.942052 90)
		(property "Reference" "C584"
			(at 0 0 90)
			(layer "B.SilkS")
			(hide yes)
			(effects
				(font
					(size 1.27 1.27)
				)
				(justify mirror)
			)
		)
		(property "Value" ""
			(at 0 0 90)
			(layer "B.Fab")
			(effects
				(font
					(size 1.27 1.27)
				)
				(justify mirror)
			)
		)
		(duplicate_pad_numbers_are_jumpers no)
		(fp_line
			(start 0.7874 -0.4064)
			(end -0.7874 -0.4064)
			(stroke
				(width 0.1524)
				(type default)
			)
			(layer "B.SilkS")
		)
		(fp_line
			(start -0.7874 -0.4064)
			(end -0.7874 0.4064)
			(stroke
				(width 0.1524)
				(type default)
			)
			(layer "B.SilkS")
		)
		(fp_line
			(start 0.7874 0.4064)
			(end 0.7874 -0.4064)
			(stroke
				(width 0.1524)
				(type default)
			)
			(layer "B.SilkS")
		)
		(fp_line
			(start -0.7874 0.4064)
			(end 0.7874 0.4064)
			(stroke
				(width 0.1524)
				(type default)
			)
			(layer "B.SilkS")
		)
		(fp_line
			(start 0.67945 -0.305054)
			(end 0.12065 -0.305054)
			(stroke
				(width 0.1)
				(type default)
			)
			(layer "B.Fab")
		)
		(fp_line
			(start 0.12065 -0.305054)
			(end 0.12065 -0.2794)
			(stroke
				(width 0.1)
				(type default)
			)
			(layer "B.Fab")
		)
		(fp_line
			(start -0.12065 -0.3048)
			(end -0.67945 -0.3048)
			(stroke
				(width 0.1)
				(type default)
			)
			(layer "B.Fab")
		)
		(fp_line
			(start -0.67945 -0.3048)
			(end -0.67945 0.3048)
			(stroke
				(width 0.1)
				(type default)
			)
			(layer "B.Fab")
		)
		(fp_line
			(start 0.12065 -0.2794)
			(end -0.12065 -0.2794)
			(stroke
				(width 0.1)
				(type default)
			)
			(layer "B.Fab")
		)
		(fp_line
			(start -0.12065 -0.2794)
			(end -0.12065 -0.3048)
			(stroke
				(width 0.1)
				(type default)
			)
			(layer "B.Fab")
		)
		(fp_line
			(start 0.12065 0.2794)
			(end 0.12065 0.3048)
			(stroke
				(width 0.1)
				(type default)
			)
			(layer "B.Fab")
		)
		(fp_line
			(start -0.120396 0.2794)
			(end 0.12065 0.2794)
			(stroke
				(width 0.1)
				(type default)
			)
			(layer "B.Fab")
		)
		(fp_line
			(start 0.67945 0.3048)
			(end 0.67945 -0.305054)
			(stroke
				(width 0.1)
				(type default)
			)
			(layer "B.Fab")
		)
		(fp_line
			(start 0.12065 0.3048)
			(end 0.67945 0.3048)
			(stroke
				(width 0.1)
				(type default)
			)
			(layer "B.Fab")
		)
		(fp_line
			(start -0.120396 0.3048)
			(end -0.120396 0.2794)
			(stroke
				(width 0.1)
				(type default)
			)
			(layer "B.Fab")
		)
		(fp_line
			(start -0.67945 0.3048)
			(end -0.120396 0.3048)
			(stroke
				(width 0.1)
				(type default)
			)
			(layer "B.Fab")
		)
		(pad "1" smd circle
			(at 0.40005 0 270)
			(size 0 0)
			(layers "B.Cu" "B.Mask" "B.Paste")
			(net "P0V9_CPU0_RT0_2A")
		)
		(pad "2" smd circle
			(at -0.40005 0 270)
			(size 0 0)
			(layers "B.Cu" "B.Mask" "B.Paste")
			(net "GND")
		)
	)
	(footprint ""
		(layer "B.Cu")
		(at 392.118088 -314.172854 90)
		(property "Reference" "R740"
			(at 0 0 90)
			(layer "B.SilkS")
			(hide yes)
			(effects
				(font
					(size 1.27 1.27)
				)
				(justify mirror)
			)
		)
		(property "Value" ""
			(at 0 0 90)
			(layer "B.Fab")
			(effects
				(font
					(size 1.27 1.27)
				)
				(justify mirror)
			)
		)
		(duplicate_pad_numbers_are_jumpers no)
		(fp_line
			(start 0.7874 -0.4064)
			(end -0.7874 -0.4064)
			(stroke
				(width 0.1524)
				(type default)
			)
			(layer "B.SilkS")
		)
		(fp_line
			(start -0.7874 -0.4064)
			(end -0.7874 0.4064)
			(stroke
				(width 0.1524)
				(type default)
			)
			(layer "B.SilkS")
		)
		(fp_line
			(start 0.7874 0.4064)
			(end 0.7874 -0.4064)
			(stroke
				(width 0.1524)
				(type default)
			)
			(layer "B.SilkS")
		)
		(fp_line
			(start -0.7874 0.4064)
			(end 0.7874 0.4064)
			(stroke
				(width 0.1524)
				(type default)
			)
			(layer "B.SilkS")
		)
		(fp_line
			(start 0.67945 -0.305054)
			(end 0.12065 -0.305054)
			(stroke
				(width 0.1)
				(type default)
			)
			(layer "B.Fab")
		)
		(fp_line
			(start 0.12065 -0.305054)
			(end 0.12065 -0.2794)
			(stroke
				(width 0.1)
				(type default)
			)
			(layer "B.Fab")
		)
		(fp_line
			(start -0.12065 -0.3048)
			(end -0.67945 -0.3048)
			(stroke
				(width 0.1)
				(type default)
			)
			(layer "B.Fab")
		)
		(fp_line
			(start -0.67945 -0.3048)
			(end -0.67945 0.3048)
			(stroke
				(width 0.1)
				(type default)
			)
			(layer "B.Fab")
		)
		(fp_line
			(start 0.12065 -0.2794)
			(end -0.12065 -0.2794)
			(stroke
				(width 0.1)
				(type default)
			)
			(layer "B.Fab")
		)
		(fp_line
			(start -0.12065 -0.2794)
			(end -0.12065 -0.3048)
			(stroke
				(width 0.1)
				(type default)
			)
			(layer "B.Fab")
		)
		(fp_line
			(start 0.12065 0.2794)
			(end 0.12065 0.3048)
			(stroke
				(width 0.1)
				(type default)
			)
			(layer "B.Fab")
		)
		(fp_line
			(start -0.120396 0.2794)
			(end 0.12065 0.2794)
			(stroke
				(width 0.1)
				(type default)
			)
			(layer "B.Fab")
		)
		(fp_line
			(start 0.67945 0.3048)
			(end 0.67945 -0.305054)
			(stroke
				(width 0.1)
				(type default)
			)
			(layer "B.Fab")
		)
		(fp_line
			(start 0.12065 0.3048)
			(end 0.67945 0.3048)
			(stroke
				(width 0.1)
				(type default)
			)
			(layer "B.Fab")
		)
		(fp_line
			(start -0.120396 0.3048)
			(end -0.120396 0.2794)
			(stroke
				(width 0.1)
				(type default)
			)
			(layer "B.Fab")
		)
		(fp_line
			(start -0.67945 0.3048)
			(end -0.120396 0.3048)
			(stroke
				(width 0.1)
				(type default)
			)
			(layer "B.Fab")
		)
		(pad "1" smd circle
			(at 0.40005 0 270)
			(size 0 0)
			(layers "B.Cu" "B.Mask" "B.Paste")
			(net "PVDD18_S5_P0")
		)
		(pad "2" smd circle
			(at -0.40005 0 270)
			(size 0 0)
			(layers "B.Cu" "B.Mask" "B.Paste")
			(net "CLK_CPU0_RTCCLK")
		)
	)
	(footprint ""
		(layer "B.Cu")
		(at 153.018998 -390.560052 90)
		(property "Reference" "C419"
			(at 0 0 90)
			(layer "B.SilkS")
			(hide yes)
			(effects
				(font
					(size 1.27 1.27)
				)
				(justify mirror)
			)
		)
		(property "Value" ""
			(at 0 0 90)
			(layer "B.Fab")
			(effects
				(font
					(size 1.27 1.27)
				)
				(justify mirror)
			)
		)
		(duplicate_pad_numbers_are_jumpers no)
		(fp_line
			(start 0.7874 -0.4064)
			(end -0.7874 -0.4064)
			(stroke
				(width 0.1524)
				(type default)
			)
			(layer "B.SilkS")
		)
		(fp_line
			(start -0.7874 -0.4064)
			(end -0.7874 0.4064)
			(stroke
				(width 0.1524)
				(type default)
			)
			(layer "B.SilkS")
		)
		(fp_line
			(start 0.7874 0.4064)
			(end 0.7874 -0.4064)
			(stroke
				(width 0.1524)
				(type default)
			)
			(layer "B.SilkS")
		)
		(fp_line
			(start -0.7874 0.4064)
			(end 0.7874 0.4064)
			(stroke
				(width 0.1524)
				(type default)
			)
			(layer "B.SilkS")
		)
		(fp_line
			(start 0.67945 -0.305054)
			(end 0.12065 -0.305054)
			(stroke
				(width 0.1)
				(type default)
			)
			(layer "B.Fab")
		)
		(fp_line
			(start 0.12065 -0.305054)
			(end 0.12065 -0.2794)
			(stroke
				(width 0.1)
				(type default)
			)
			(layer "B.Fab")
		)
		(fp_line
			(start -0.12065 -0.3048)
			(end -0.67945 -0.3048)
			(stroke
				(width 0.1)
				(type default)
			)
			(layer "B.Fab")
		)
		(fp_line
			(start -0.67945 -0.3048)
			(end -0.67945 0.3048)
			(stroke
				(width 0.1)
				(type default)
			)
			(layer "B.Fab")
		)
		(fp_line
			(start 0.12065 -0.2794)
			(end -0.12065 -0.2794)
			(stroke
				(width 0.1)
				(type default)
			)
			(layer "B.Fab")
		)
		(fp_line
			(start -0.12065 -0.2794)
			(end -0.12065 -0.3048)
			(stroke
				(width 0.1)
				(type default)
			)
			(layer "B.Fab")
		)
		(fp_line
			(start 0.12065 0.2794)
			(end 0.12065 0.3048)
			(stroke
				(width 0.1)
				(type default)
			)
			(layer "B.Fab")
		)
		(fp_line
			(start -0.120396 0.2794)
			(end 0.12065 0.2794)
			(stroke
				(width 0.1)
				(type default)
			)
			(layer "B.Fab")
		)
		(fp_line
			(start 0.67945 0.3048)
			(end 0.67945 -0.305054)
			(stroke
				(width 0.1)
				(type default)
			)
			(layer "B.Fab")
		)
		(fp_line
			(start 0.12065 0.3048)
			(end 0.67945 0.3048)
			(stroke
				(width 0.1)
				(type default)
			)
			(layer "B.Fab")
		)
		(fp_line
			(start -0.120396 0.3048)
			(end -0.120396 0.2794)
			(stroke
				(width 0.1)
				(type default)
			)
			(layer "B.Fab")
		)
		(fp_line
			(start -0.67945 0.3048)
			(end -0.120396 0.3048)
			(stroke
				(width 0.1)
				(type default)
			)
			(layer "B.Fab")
		)
		(pad "1" smd circle
			(at 0.40005 0 270)
			(size 0 0)
			(layers "B.Cu" "B.Mask" "B.Paste")
			(net "P0V9_CPU1_RT_2D")
		)
		(pad "2" smd circle
			(at -0.40005 0 270)
			(size 0 0)
			(layers "B.Cu" "B.Mask" "B.Paste")
			(net "GND")
		)
	)
	(footprint ""
		(layer "B.Cu")
		(at 167.502332 -431.326544 180)
		(property "Reference" "Q131"
			(at -6.290056 0.352552 0)
			(unlocked yes)
			(layer "B.SilkS")
			(effects
				(font
					(size 0.7874 0.5842)
					(thickness 0.1524)
				)
				(justify left mirror)
			)
		)
		(property "Value" ""
			(at 0 0 0)
			(layer "B.Fab")
			(effects
				(font
					(size 1.27 1.27)
				)
				(justify mirror)
			)
		)
		(duplicate_pad_numbers_are_jumpers no)
		(fp_line
			(start 1.332738 1.100074)
			(end 1.332738 -1.100074)
			(stroke
				(width 0.1524)
				(type default)
			)
			(layer "B.SilkS")
		)
		(fp_line
			(start 1.332738 -1.100074)
			(end 0.4826 -1.100074)
			(stroke
				(width 0.1524)
				(type default)
			)
			(layer "B.SilkS")
		)
		(fp_line
			(start 0.4826 -1.100074)
			(end 0 -0.541274)
			(stroke
				(width 0.1524)
				(type default)
			)
			(layer "B.SilkS")
		)
		(fp_line
			(start 0 -0.541274)
			(end -0.4826 -1.100074)
			(stroke
				(width 0.1524)
				(type default)
			)
			(layer "B.SilkS")
		)
		(fp_line
			(start -0.4826 -1.100074)
			(end -1.332738 -1.100074)
			(stroke
				(width 0.1524)
				(type default)
			)
			(layer "B.SilkS")
		)
		(fp_line
			(start -1.332738 1.100074)
			(end 1.332738 1.100074)
			(stroke
				(width 0.1524)
				(type default)
			)
			(layer "B.SilkS")
		)
		(fp_line
			(start -1.332738 -1.100074)
			(end -1.332738 1.100074)
			(stroke
				(width 0.1524)
				(type default)
			)
			(layer "B.SilkS")
		)
		(fp_poly
			(pts
				(xy 1.362456 -1.189482) (xy 2.10693 -1.43764) (xy 1.610614 -1.933956)
			)
			(stroke
				(width 0)
				(type default)
			)
			(fill yes)
			(layer "B.SilkS")
		)
		(fp_line
			(start 0.674878 1.100074)
			(end 0.674878 -1.100074)
			(stroke
				(width 0.1)
				(type default)
			)
			(layer "B.Fab")
		)
		(fp_line
			(start 0.674878 -1.100074)
			(end -0.674878 -1.100074)
			(stroke
				(width 0.1)
				(type default)
			)
			(layer "B.Fab")
		)
		(fp_line
			(start -0.674878 1.100074)
			(end 0.674878 1.100074)
			(stroke
				(width 0.1)
				(type default)
			)
			(layer "B.Fab")
		)
		(fp_line
			(start -0.674878 -1.100074)
			(end -0.674878 1.100074)
			(stroke
				(width 0.1)
				(type default)
			)
			(layer "B.Fab")
		)
		(fp_poly
			(pts
				(xy 2.2352 -0.298958) (xy 2.2352 -1.001014) (xy 1.533144 -0.649986)
			)
			(stroke
				(width 0)
				(type default)
			)
			(fill yes)
			(layer "B.Fab")
		)
		(pad "1" smd rect
			(at 0.94996 -0.649986 270)
			(size 0.4318 0.508)
			(layers "B.Cu" "B.Mask" "B.Paste")
			(net "GND")
		)
		(pad "2" smd rect
			(at 0.94996 0 270)
			(size 0.4318 0.508)
			(layers "B.Cu" "B.Mask" "B.Paste")
			(net "GPU_3V3IO_RSVD1_FFU")
		)
		(pad "3" smd rect
			(at 0.94996 0.649986 270)
			(size 0.4318 0.508)
			(layers "B.Cu" "B.Mask" "B.Paste")
			(net "GPU_3V3IO_RSVD1_FFU_ISO")
		)
		(pad "4" smd rect
			(at -0.94996 0.649986 270)
			(size 0.4318 0.508)
			(layers "B.Cu" "B.Mask" "B.Paste")
			(net "GND")
		)
		(pad "5" smd rect
			(at -0.94996 0 270)
			(size 0.4318 0.508)
			(layers "B.Cu" "B.Mask" "B.Paste")
			(net "GPU_3V3IO_RSVD1_FFU_N")
		)
		(pad "6" smd rect
			(at -0.94996 -0.649986 270)
			(size 0.4318 0.508)
			(layers "B.Cu" "B.Mask" "B.Paste")
			(net "GPU_3V3IO_RSVD1_FFU_N")
		)
	)
	(footprint ""
		(layer "B.Cu")
		(at 47.784004 -192.66027 180)
		(property "Reference" "C175"
			(at 0 0 0)
			(layer "B.SilkS")
			(hide yes)
			(effects
				(font
					(size 1.27 1.27)
				)
				(justify mirror)
			)
		)
		(property "Value" ""
			(at 0 0 0)
			(layer "B.Fab")
			(effects
				(font
					(size 1.27 1.27)
				)
				(justify mirror)
			)
		)
		(duplicate_pad_numbers_are_jumpers no)
		(fp_line
			(start 1.524 0.762)
			(end 1.524 -0.762)
			(stroke
				(width 0.1524)
				(type default)
			)
			(layer "B.SilkS")
		)
		(fp_line
			(start 1.524 -0.762)
			(end -1.524 -0.762)
			(stroke
				(width 0.1524)
				(type default)
			)
			(layer "B.SilkS")
		)
		(fp_line
			(start -1.524 0.762)
			(end 1.524 0.762)
			(stroke
				(width 0.1524)
				(type default)
			)
			(layer "B.SilkS")
		)
		(fp_line
			(start -1.524 -0.762)
			(end -1.524 0.762)
			(stroke
				(width 0.1524)
				(type default)
			)
			(layer "B.SilkS")
		)
		(fp_line
			(start 1.1049 0.724916)
			(end -1.1049 0.724916)
			(stroke
				(width 0.1)
				(type default)
			)
			(layer "B.Fab")
		)
		(fp_line
			(start 1.1049 -0.724916)
			(end 1.1049 0.724916)
			(stroke
				(width 0.1)
				(type default)
			)
			(layer "B.Fab")
		)
		(fp_line
			(start -1.1049 0.724916)
			(end -1.1049 -0.724916)
			(stroke
				(width 0.1)
				(type default)
			)
			(layer "B.Fab")
		)
		(fp_line
			(start -1.1049 -0.724916)
			(end 1.1049 -0.724916)
			(stroke
				(width 0.1)
				(type default)
			)
			(layer "B.Fab")
		)
		(pad "1" smd rect
			(at 0.889 0 180)
			(size 1.016 1.27)
			(layers "B.Cu" "B.Mask" "B.Paste")
			(net "P12V_MEM_CPU1")
		)
		(pad "2" smd rect
			(at -0.889 0 180)
			(size 1.016 1.27)
			(layers "B.Cu" "B.Mask" "B.Paste")
			(net "GND")
		)
	)
	(footprint ""
		(layer "B.Cu")
		(at 374.487186 -214.523828 90)
		(property "Reference" "R9273"
			(at 0 0 90)
			(layer "B.SilkS")
			(hide yes)
			(effects
				(font
					(size 1.27 1.27)
				)
				(justify mirror)
			)
		)
		(property "Value" ""
			(at 0 0 90)
			(layer "B.Fab")
			(effects
				(font
					(size 1.27 1.27)
				)
				(justify mirror)
			)
		)
		(duplicate_pad_numbers_are_jumpers no)
		(fp_line
			(start 0.436372 -0.4064)
			(end -0.351028 -0.4064)
			(stroke
				(width 0.1524)
				(type default)
			)
			(layer "B.SilkS")
		)
		(fp_line
			(start -0.7874 0.035814)
			(end -0.7874 0.4064)
			(stroke
				(width 0.1524)
				(type default)
			)
			(layer "B.SilkS")
		)
		(fp_line
			(start 0.7874 0.4064)
			(end 0.7874 -0.014986)
			(stroke
				(width 0.1524)
				(type default)
			)
			(layer "B.SilkS")
		)
		(fp_line
			(start -0.7874 0.4064)
			(end 0.7874 0.4064)
			(stroke
				(width 0.1524)
				(type default)
			)
			(layer "B.SilkS")
		)
		(fp_line
			(start 0.67945 -0.305054)
			(end 0.12065 -0.305054)
			(stroke
				(width 0.1)
				(type default)
			)
			(layer "B.Fab")
		)
		(fp_line
			(start 0.12065 -0.305054)
			(end 0.12065 -0.2794)
			(stroke
				(width 0.1)
				(type default)
			)
			(layer "B.Fab")
		)
		(fp_line
			(start -0.12065 -0.3048)
			(end -0.67945 -0.3048)
			(stroke
				(width 0.1)
				(type default)
			)
			(layer "B.Fab")
		)
		(fp_line
			(start -0.67945 -0.3048)
			(end -0.67945 0.3048)
			(stroke
				(width 0.1)
				(type default)
			)
			(layer "B.Fab")
		)
		(fp_line
			(start 0.12065 -0.2794)
			(end -0.12065 -0.2794)
			(stroke
				(width 0.1)
				(type default)
			)
			(layer "B.Fab")
		)
		(fp_line
			(start -0.12065 -0.2794)
			(end -0.12065 -0.3048)
			(stroke
				(width 0.1)
				(type default)
			)
			(layer "B.Fab")
		)
		(fp_line
			(start 0.12065 0.2794)
			(end 0.12065 0.3048)
			(stroke
				(width 0.1)
				(type default)
			)
			(layer "B.Fab")
		)
		(fp_line
			(start -0.120396 0.2794)
			(end 0.12065 0.2794)
			(stroke
				(width 0.1)
				(type default)
			)
			(layer "B.Fab")
		)
		(fp_line
			(start 0.67945 0.3048)
			(end 0.67945 -0.305054)
			(stroke
				(width 0.1)
				(type default)
			)
			(layer "B.Fab")
		)
		(fp_line
			(start 0.12065 0.3048)
			(end 0.67945 0.3048)
			(stroke
				(width 0.1)
				(type default)
			)
			(layer "B.Fab")
		)
		(fp_line
			(start -0.120396 0.3048)
			(end -0.120396 0.2794)
			(stroke
				(width 0.1)
				(type default)
			)
			(layer "B.Fab")
		)
		(fp_line
			(start -0.67945 0.3048)
			(end -0.120396 0.3048)
			(stroke
				(width 0.1)
				(type default)
			)
			(layer "B.Fab")
		)
		(pad "1" smd circle
			(at 0.40005 0 270)
			(size 0 0)
			(layers "B.Cu" "B.Mask" "B.Paste")
			(net "CLK_100M_CPU0_CLK04_R_DP")
		)
		(pad "2" smd circle
			(at -0.40005 0 270)
			(size 0 0)
			(layers "B.Cu" "B.Mask" "B.Paste")
			(net "CLK_100M_CPU0_CLK04_DP")
		)
	)
	(footprint ""
		(layer "B.Cu")
		(at 369.62588 -258.830064)
		(property "Reference" "C2537"
			(at 0 0 0)
			(layer "B.SilkS")
			(hide yes)
			(effects
				(font
					(size 1.27 1.27)
				)
				(justify mirror)
			)
		)
		(property "Value" ""
			(at 0 0 0)
			(layer "B.Fab")
			(effects
				(font
					(size 1.27 1.27)
				)
				(justify mirror)
			)
		)
		(duplicate_pad_numbers_are_jumpers no)
		(fp_line
			(start -0.7874 -0.4064)
			(end -0.7874 0.4064)
			(stroke
				(width 0.1524)
				(type default)
			)
			(layer "B.SilkS")
		)
		(fp_line
			(start -0.7874 0.4064)
			(end 0.7874 0.4064)
			(stroke
				(width 0.1524)
				(type default)
			)
			(layer "B.SilkS")
		)
		(fp_line
			(start 0.7874 -0.4064)
			(end -0.7874 -0.4064)
			(stroke
				(width 0.1524)
				(type default)
			)
			(layer "B.SilkS")
		)
		(fp_line
			(start 0.7874 0.4064)
			(end 0.7874 -0.4064)
			(stroke
				(width 0.1524)
				(type default)
			)
			(layer "B.SilkS")
		)
		(fp_line
			(start -0.67945 -0.3048)
			(end -0.67945 0.3048)
			(stroke
				(width 0.1)
				(type default)
			)
			(layer "B.Fab")
		)
		(fp_line
			(start -0.67945 0.3048)
			(end -0.120396 0.3048)
			(stroke
				(width 0.1)
				(type default)
			)
			(layer "B.Fab")
		)
		(fp_line
			(start -0.12065 -0.3048)
			(end -0.67945 -0.3048)
			(stroke
				(width 0.1)
				(type default)
			)
			(layer "B.Fab")
		)
		(fp_line
			(start -0.12065 -0.2794)
			(end -0.12065 -0.3048)
			(stroke
				(width 0.1)
				(type default)
			)
			(layer "B.Fab")
		)
		(fp_line
			(start -0.120396 0.2794)
			(end 0.12065 0.2794)
			(stroke
				(width 0.1)
				(type default)
			)
			(layer "B.Fab")
		)
		(fp_line
			(start -0.120396 0.3048)
			(end -0.120396 0.2794)
			(stroke
				(width 0.1)
				(type default)
			)
			(layer "B.Fab")
		)
		(fp_line
			(start 0.12065 -0.305054)
			(end 0.12065 -0.2794)
			(stroke
				(width 0.1)
				(type default)
			)
			(layer "B.Fab")
		)
		(fp_line
			(start 0.12065 -0.2794)
			(end -0.12065 -0.2794)
			(stroke
				(width 0.1)
				(type default)
			)
			(layer "B.Fab")
		)
		(fp_line
			(start 0.12065 0.2794)
			(end 0.12065 0.3048)
			(stroke
				(width 0.1)
				(type default)
			)
			(layer "B.Fab")
		)
		(fp_line
			(start 0.12065 0.3048)
			(end 0.67945 0.3048)
			(stroke
				(width 0.1)
				(type default)
			)
			(layer "B.Fab")
		)
		(fp_line
			(start 0.67945 -0.305054)
			(end 0.12065 -0.305054)
			(stroke
				(width 0.1)
				(type default)
			)
			(layer "B.Fab")
		)
		(fp_line
			(start 0.67945 0.3048)
			(end 0.67945 -0.305054)
			(stroke
				(width 0.1)
				(type default)
			)
			(layer "B.Fab")
		)
		(pad "1" smd circle
			(at 0.40005 0 180)
			(size 0 0)
			(layers "B.Cu" "B.Mask" "B.Paste")
			(net "PVDDCR_SOC_P0")
		)
		(pad "2" smd circle
			(at -0.40005 0 180)
			(size 0 0)
			(layers "B.Cu" "B.Mask" "B.Paste")
			(net "GND")
		)
	)
	(footprint ""
		(layer "B.Cu")
		(at 120.055386 -268.418564)
		(property "Reference" "C2398"
			(at 0 0 0)
			(layer "B.SilkS")
			(hide yes)
			(effects
				(font
					(size 1.27 1.27)
				)
				(justify mirror)
			)
		)
		(property "Value" ""
			(at 0 0 0)
			(layer "B.Fab")
			(effects
				(font
					(size 1.27 1.27)
				)
				(justify mirror)
			)
		)
		(duplicate_pad_numbers_are_jumpers no)
		(fp_line
			(start -0.7874 -0.4064)
			(end -0.7874 0.4064)
			(stroke
				(width 0.1524)
				(type default)
			)
			(layer "B.SilkS")
		)
		(fp_line
			(start -0.7874 0.4064)
			(end 0.7874 0.4064)
			(stroke
				(width 0.1524)
				(type default)
			)
			(layer "B.SilkS")
		)
		(fp_line
			(start 0.7874 -0.4064)
			(end -0.7874 -0.4064)
			(stroke
				(width 0.1524)
				(type default)
			)
			(layer "B.SilkS")
		)
		(fp_line
			(start 0.7874 0.4064)
			(end 0.7874 -0.4064)
			(stroke
				(width 0.1524)
				(type default)
			)
			(layer "B.SilkS")
		)
		(fp_line
			(start -0.67945 -0.3048)
			(end -0.67945 0.3048)
			(stroke
				(width 0.1)
				(type default)
			)
			(layer "B.Fab")
		)
		(fp_line
			(start -0.67945 0.3048)
			(end -0.120396 0.3048)
			(stroke
				(width 0.1)
				(type default)
			)
			(layer "B.Fab")
		)
		(fp_line
			(start -0.12065 -0.3048)
			(end -0.67945 -0.3048)
			(stroke
				(width 0.1)
				(type default)
			)
			(layer "B.Fab")
		)
		(fp_line
			(start -0.12065 -0.2794)
			(end -0.12065 -0.3048)
			(stroke
				(width 0.1)
				(type default)
			)
			(layer "B.Fab")
		)
		(fp_line
			(start -0.120396 0.2794)
			(end 0.12065 0.2794)
			(stroke
				(width 0.1)
				(type default)
			)
			(layer "B.Fab")
		)
		(fp_line
			(start -0.120396 0.3048)
			(end -0.120396 0.2794)
			(stroke
				(width 0.1)
				(type default)
			)
			(layer "B.Fab")
		)
		(fp_line
			(start 0.12065 -0.305054)
			(end 0.12065 -0.2794)
			(stroke
				(width 0.1)
				(type default)
			)
			(layer "B.Fab")
		)
		(fp_line
			(start 0.12065 -0.2794)
			(end -0.12065 -0.2794)
			(stroke
				(width 0.1)
				(type default)
			)
			(layer "B.Fab")
		)
		(fp_line
			(start 0.12065 0.2794)
			(end 0.12065 0.3048)
			(stroke
				(width 0.1)
				(type default)
			)
			(layer "B.Fab")
		)
		(fp_line
			(start 0.12065 0.3048)
			(end 0.67945 0.3048)
			(stroke
				(width 0.1)
				(type default)
			)
			(layer "B.Fab")
		)
		(fp_line
			(start 0.67945 -0.305054)
			(end 0.12065 -0.305054)
			(stroke
				(width 0.1)
				(type default)
			)
			(layer "B.Fab")
		)
		(fp_line
			(start 0.67945 0.3048)
			(end 0.67945 -0.305054)
			(stroke
				(width 0.1)
				(type default)
			)
			(layer "B.Fab")
		)
		(pad "1" smd circle
			(at 0.40005 0 180)
			(size 0 0)
			(layers "B.Cu" "B.Mask" "B.Paste")
			(net "PVDDCR_CPU1_P1")
		)
		(pad "2" smd circle
			(at -0.40005 0 180)
			(size 0 0)
			(layers "B.Cu" "B.Mask" "B.Paste")
			(net "GND")
		)
	)
	(footprint ""
		(layer "B.Cu")
		(at 64.401954 -165.119812 90)
		(property "Reference" "PC129_6"
			(at 0 0 90)
			(layer "B.SilkS")
			(hide yes)
			(effects
				(font
					(size 1.27 1.27)
				)
				(justify mirror)
			)
		)
		(property "Value" ""
			(at 0 0 90)
			(layer "B.Fab")
			(effects
				(font
					(size 1.27 1.27)
				)
				(justify mirror)
			)
		)
		(duplicate_pad_numbers_are_jumpers no)
		(fp_line
			(start 1.524 -0.762)
			(end -1.524 -0.762)
			(stroke
				(width 0.1524)
				(type default)
			)
			(layer "B.SilkS")
		)
		(fp_line
			(start -1.524 -0.762)
			(end -1.524 0.762)
			(stroke
				(width 0.1524)
				(type default)
			)
			(layer "B.SilkS")
		)
		(fp_line
			(start 1.524 0.762)
			(end 1.524 -0.762)
			(stroke
				(width 0.1524)
				(type default)
			)
			(layer "B.SilkS")
		)
		(fp_line
			(start -1.524 0.762)
			(end 1.524 0.762)
			(stroke
				(width 0.1524)
				(type default)
			)
			(layer "B.SilkS")
		)
		(fp_line
			(start 1.1049 -0.724916)
			(end 1.1049 0.724916)
			(stroke
				(width 0.1)
				(type default)
			)
			(layer "B.Fab")
		)
		(fp_line
			(start -1.1049 -0.724916)
			(end 1.1049 -0.724916)
			(stroke
				(width 0.1)
				(type default)
			)
			(layer "B.Fab")
		)
		(fp_line
			(start 1.1049 0.724916)
			(end -1.1049 0.724916)
			(stroke
				(width 0.1)
				(type default)
			)
			(layer "B.Fab")
		)
		(fp_line
			(start -1.1049 0.724916)
			(end -1.1049 -0.724916)
			(stroke
				(width 0.1)
				(type default)
			)
			(layer "B.Fab")
		)
		(pad "1" smd rect
			(at 0.889 0 90)
			(size 1.016 1.27)
			(layers "B.Cu" "B.Mask" "B.Paste")
			(net "SW_P12V_AUX_PVDDCR_CPU0_P1_FLT")
		)
		(pad "2" smd rect
			(at -0.889 0 90)
			(size 1.016 1.27)
			(layers "B.Cu" "B.Mask" "B.Paste")
			(net "GND")
		)
	)
	(footprint ""
		(layer "B.Cu")
		(at 242.702842 -382.467358 180)
		(property "Reference" "PC1750"
			(at 0 0 0)
			(layer "B.SilkS")
			(hide yes)
			(effects
				(font
					(size 1.27 1.27)
				)
				(justify mirror)
			)
		)
		(property "Value" ""
			(at 0 0 0)
			(layer "B.Fab")
			(effects
				(font
					(size 1.27 1.27)
				)
				(justify mirror)
			)
		)
		(duplicate_pad_numbers_are_jumpers no)
		(fp_line
			(start 0.7874 0.4064)
			(end 0.7874 -0.4064)
			(stroke
				(width 0.1524)
				(type default)
			)
			(layer "B.SilkS")
		)
		(fp_line
			(start 0.7874 -0.4064)
			(end -0.7874 -0.4064)
			(stroke
				(width 0.1524)
				(type default)
			)
			(layer "B.SilkS")
		)
		(fp_line
			(start -0.7874 0.4064)
			(end 0.7874 0.4064)
			(stroke
				(width 0.1524)
				(type default)
			)
			(layer "B.SilkS")
		)
		(fp_line
			(start -0.7874 -0.4064)
			(end -0.7874 0.4064)
			(stroke
				(width 0.1524)
				(type default)
			)
			(layer "B.SilkS")
		)
		(fp_line
			(start 0.67945 0.3048)
			(end 0.67945 -0.305054)
			(stroke
				(width 0.1)
				(type default)
			)
			(layer "B.Fab")
		)
		(fp_line
			(start 0.67945 -0.305054)
			(end 0.12065 -0.305054)
			(stroke
				(width 0.1)
				(type default)
			)
			(layer "B.Fab")
		)
		(fp_line
			(start 0.12065 0.3048)
			(end 0.67945 0.3048)
			(stroke
				(width 0.1)
				(type default)
			)
			(layer "B.Fab")
		)
		(fp_line
			(start 0.12065 0.2794)
			(end 0.12065 0.3048)
			(stroke
				(width 0.1)
				(type default)
			)
			(layer "B.Fab")
		)
		(fp_line
			(start 0.12065 -0.2794)
			(end -0.12065 -0.2794)
			(stroke
				(width 0.1)
				(type default)
			)
			(layer "B.Fab")
		)
		(fp_line
			(start 0.12065 -0.305054)
			(end 0.12065 -0.2794)
			(stroke
				(width 0.1)
				(type default)
			)
			(layer "B.Fab")
		)
		(fp_line
			(start -0.120396 0.3048)
			(end -0.120396 0.2794)
			(stroke
				(width 0.1)
				(type default)
			)
			(layer "B.Fab")
		)
		(fp_line
			(start -0.120396 0.2794)
			(end 0.12065 0.2794)
			(stroke
				(width 0.1)
				(type default)
			)
			(layer "B.Fab")
		)
		(fp_line
			(start -0.12065 -0.2794)
			(end -0.12065 -0.3048)
			(stroke
				(width 0.1)
				(type default)
			)
			(layer "B.Fab")
		)
		(fp_line
			(start -0.12065 -0.3048)
			(end -0.67945 -0.3048)
			(stroke
				(width 0.1)
				(type default)
			)
			(layer "B.Fab")
		)
		(fp_line
			(start -0.67945 0.3048)
			(end -0.120396 0.3048)
			(stroke
				(width 0.1)
				(type default)
			)
			(layer "B.Fab")
		)
		(fp_line
			(start -0.67945 -0.3048)
			(end -0.67945 0.3048)
			(stroke
				(width 0.1)
				(type default)
			)
			(layer "B.Fab")
		)
		(pad "1" smd circle
			(at 0.40005 0)
			(size 0 0)
			(layers "B.Cu" "B.Mask" "B.Paste")
			(net "P12V_AUX")
		)
		(pad "2" smd circle
			(at -0.40005 0)
			(size 0 0)
			(layers "B.Cu" "B.Mask" "B.Paste")
			(net "P12V_HSC_GATE2")
		)
	)
	(footprint ""
		(layer "B.Cu")
		(at 89.646252 -388.011162 -90)
		(property "Reference" "C287"
			(at 0 0 90)
			(layer "B.SilkS")
			(hide yes)
			(effects
				(font
					(size 1.27 1.27)
				)
				(justify mirror)
			)
		)
		(property "Value" ""
			(at 0 0 90)
			(layer "B.Fab")
			(effects
				(font
					(size 1.27 1.27)
				)
				(justify mirror)
			)
		)
		(duplicate_pad_numbers_are_jumpers no)
		(fp_line
			(start -0.299974 0.150114)
			(end 0.299974 0.150114)
			(stroke
				(width 0.1)
				(type default)
			)
			(layer "B.Fab")
		)
		(fp_line
			(start 0.299974 0.150114)
			(end 0.299974 -0.150114)
			(stroke
				(width 0.1)
				(type default)
			)
			(layer "B.Fab")
		)
		(fp_line
			(start -0.299974 -0.150114)
			(end -0.299974 0.150114)
			(stroke
				(width 0.1)
				(type default)
			)
			(layer "B.Fab")
		)
		(fp_line
			(start 0.299974 -0.150114)
			(end -0.299974 -0.150114)
			(stroke
				(width 0.1)
				(type default)
			)
			(layer "B.Fab")
		)
		(pad "1" smd rect
			(at 0.2667 0 90)
			(size 0.3048 0.381)
			(layers "B.Cu" "B.Mask" "B.Paste")
			(net "P1V8_CPU1_RT1_1A")
		)
		(pad "2" smd rect
			(at -0.2667 0 90)
			(size 0.3048 0.381)
			(layers "B.Cu" "B.Mask" "B.Paste")
			(net "GND")
		)
	)
	(footprint ""
		(layer "B.Cu")
		(at 357.835454 -251.78131)
		(property "Reference" "C2593"
			(at 0 0 0)
			(layer "B.SilkS")
			(hide yes)
			(effects
				(font
					(size 1.27 1.27)
				)
				(justify mirror)
			)
		)
		(property "Value" ""
			(at 0 0 0)
			(layer "B.Fab")
			(effects
				(font
					(size 1.27 1.27)
				)
				(justify mirror)
			)
		)
		(duplicate_pad_numbers_are_jumpers no)
		(fp_line
			(start -0.7874 -0.4064)
			(end -0.7874 0.4064)
			(stroke
				(width 0.1524)
				(type default)
			)
			(layer "B.SilkS")
		)
		(fp_line
			(start -0.7874 0.4064)
			(end 0.7874 0.4064)
			(stroke
				(width 0.1524)
				(type default)
			)
			(layer "B.SilkS")
		)
		(fp_line
			(start 0.7874 -0.4064)
			(end -0.7874 -0.4064)
			(stroke
				(width 0.1524)
				(type default)
			)
			(layer "B.SilkS")
		)
		(fp_line
			(start 0.7874 0.4064)
			(end 0.7874 -0.4064)
			(stroke
				(width 0.1524)
				(type default)
			)
			(layer "B.SilkS")
		)
		(fp_line
			(start -0.67945 -0.3048)
			(end -0.67945 0.3048)
			(stroke
				(width 0.1)
				(type default)
			)
			(layer "B.Fab")
		)
		(fp_line
			(start -0.67945 0.3048)
			(end -0.120396 0.3048)
			(stroke
				(width 0.1)
				(type default)
			)
			(layer "B.Fab")
		)
		(fp_line
			(start -0.12065 -0.3048)
			(end -0.67945 -0.3048)
			(stroke
				(width 0.1)
				(type default)
			)
			(layer "B.Fab")
		)
		(fp_line
			(start -0.12065 -0.2794)
			(end -0.12065 -0.3048)
			(stroke
				(width 0.1)
				(type default)
			)
			(layer "B.Fab")
		)
		(fp_line
			(start -0.120396 0.2794)
			(end 0.12065 0.2794)
			(stroke
				(width 0.1)
				(type default)
			)
			(layer "B.Fab")
		)
		(fp_line
			(start -0.120396 0.3048)
			(end -0.120396 0.2794)
			(stroke
				(width 0.1)
				(type default)
			)
			(layer "B.Fab")
		)
		(fp_line
			(start 0.12065 -0.305054)
			(end 0.12065 -0.2794)
			(stroke
				(width 0.1)
				(type default)
			)
			(layer "B.Fab")
		)
		(fp_line
			(start 0.12065 -0.2794)
			(end -0.12065 -0.2794)
			(stroke
				(width 0.1)
				(type default)
			)
			(layer "B.Fab")
		)
		(fp_line
			(start 0.12065 0.2794)
			(end 0.12065 0.3048)
			(stroke
				(width 0.1)
				(type default)
			)
			(layer "B.Fab")
		)
		(fp_line
			(start 0.12065 0.3048)
			(end 0.67945 0.3048)
			(stroke
				(width 0.1)
				(type default)
			)
			(layer "B.Fab")
		)
		(fp_line
			(start 0.67945 -0.305054)
			(end 0.12065 -0.305054)
			(stroke
				(width 0.1)
				(type default)
			)
			(layer "B.Fab")
		)
		(fp_line
			(start 0.67945 0.3048)
			(end 0.67945 -0.305054)
			(stroke
				(width 0.1)
				(type default)
			)
			(layer "B.Fab")
		)
		(pad "1" smd circle
			(at 0.40005 0 180)
			(size 0 0)
			(layers "B.Cu" "B.Mask" "B.Paste")
			(net "PVDDCR_SOC_P0")
		)
		(pad "2" smd circle
			(at -0.40005 0 180)
			(size 0 0)
			(layers "B.Cu" "B.Mask" "B.Paste")
			(net "GND")
		)
	)
	(footprint ""
		(layer "B.Cu")
		(at 112.518444 -387.05028)
		(property "Reference" "C488"
			(at 0 0 0)
			(layer "B.SilkS")
			(hide yes)
			(effects
				(font
					(size 1.27 1.27)
				)
				(justify mirror)
			)
		)
		(property "Value" ""
			(at 0 0 0)
			(layer "B.Fab")
			(effects
				(font
					(size 1.27 1.27)
				)
				(justify mirror)
			)
		)
		(duplicate_pad_numbers_are_jumpers no)
		(fp_line
			(start -0.299974 -0.150114)
			(end -0.299974 0.150114)
			(stroke
				(width 0.1)
				(type default)
			)
			(layer "B.Fab")
		)
		(fp_line
			(start -0.299974 0.150114)
			(end 0.299974 0.150114)
			(stroke
				(width 0.1)
				(type default)
			)
			(layer "B.Fab")
		)
		(fp_line
			(start 0.299974 -0.150114)
			(end -0.299974 -0.150114)
			(stroke
				(width 0.1)
				(type default)
			)
			(layer "B.Fab")
		)
		(fp_line
			(start 0.299974 0.150114)
			(end 0.299974 -0.150114)
			(stroke
				(width 0.1)
				(type default)
			)
			(layer "B.Fab")
		)
		(pad "1" smd rect
			(at 0.2667 0 180)
			(size 0.3048 0.381)
			(layers "B.Cu" "B.Mask" "B.Paste")
			(net "P0V9_CPU1_RT3_2A")
		)
		(pad "2" smd rect
			(at -0.2667 0 180)
			(size 0.3048 0.381)
			(layers "B.Cu" "B.Mask" "B.Paste")
			(net "GND")
		)
	)
	(footprint ""
		(layer "B.Cu")
		(at 109.550454 -31.549086 180)
		(property "Reference" "C6093"
			(at 0 0 0)
			(layer "B.SilkS")
			(hide yes)
			(effects
				(font
					(size 1.27 1.27)
				)
				(justify mirror)
			)
		)
		(property "Value" ""
			(at 0 0 0)
			(layer "B.Fab")
			(effects
				(font
					(size 1.27 1.27)
				)
				(justify mirror)
			)
		)
		(duplicate_pad_numbers_are_jumpers no)
		(fp_line
			(start 0.7874 0.4064)
			(end 0.7874 -0.4064)
			(stroke
				(width 0.1524)
				(type default)
			)
			(layer "B.SilkS")
		)
		(fp_line
			(start 0.7874 -0.4064)
			(end -0.7874 -0.4064)
			(stroke
				(width 0.1524)
				(type default)
			)
			(layer "B.SilkS")
		)
		(fp_line
			(start -0.7874 0.4064)
			(end 0.7874 0.4064)
			(stroke
				(width 0.1524)
				(type default)
			)
			(layer "B.SilkS")
		)
		(fp_line
			(start -0.7874 -0.4064)
			(end -0.7874 0.4064)
			(stroke
				(width 0.1524)
				(type default)
			)
			(layer "B.SilkS")
		)
		(fp_line
			(start 0.67945 0.3048)
			(end 0.67945 -0.305054)
			(stroke
				(width 0.1)
				(type default)
			)
			(layer "B.Fab")
		)
		(fp_line
			(start 0.67945 -0.305054)
			(end 0.12065 -0.305054)
			(stroke
				(width 0.1)
				(type default)
			)
			(layer "B.Fab")
		)
		(fp_line
			(start 0.12065 0.3048)
			(end 0.67945 0.3048)
			(stroke
				(width 0.1)
				(type default)
			)
			(layer "B.Fab")
		)
		(fp_line
			(start 0.12065 0.2794)
			(end 0.12065 0.3048)
			(stroke
				(width 0.1)
				(type default)
			)
			(layer "B.Fab")
		)
		(fp_line
			(start 0.12065 -0.2794)
			(end -0.12065 -0.2794)
			(stroke
				(width 0.1)
				(type default)
			)
			(layer "B.Fab")
		)
		(fp_line
			(start 0.12065 -0.305054)
			(end 0.12065 -0.2794)
			(stroke
				(width 0.1)
				(type default)
			)
			(layer "B.Fab")
		)
		(fp_line
			(start -0.120396 0.3048)
			(end -0.120396 0.2794)
			(stroke
				(width 0.1)
				(type default)
			)
			(layer "B.Fab")
		)
		(fp_line
			(start -0.120396 0.2794)
			(end 0.12065 0.2794)
			(stroke
				(width 0.1)
				(type default)
			)
			(layer "B.Fab")
		)
		(fp_line
			(start -0.12065 -0.2794)
			(end -0.12065 -0.3048)
			(stroke
				(width 0.1)
				(type default)
			)
			(layer "B.Fab")
		)
		(fp_line
			(start -0.12065 -0.3048)
			(end -0.67945 -0.3048)
			(stroke
				(width 0.1)
				(type default)
			)
			(layer "B.Fab")
		)
		(fp_line
			(start -0.67945 0.3048)
			(end -0.120396 0.3048)
			(stroke
				(width 0.1)
				(type default)
			)
			(layer "B.Fab")
		)
		(fp_line
			(start -0.67945 -0.3048)
			(end -0.67945 0.3048)
			(stroke
				(width 0.1)
				(type default)
			)
			(layer "B.Fab")
		)
		(pad "1" smd circle
			(at 0.40005 0)
			(size 0 0)
			(layers "B.Cu" "B.Mask" "B.Paste")
			(net "P3V3_AUX_CPU0_USB2_AVDD33")
		)
		(pad "2" smd circle
			(at -0.40005 0)
			(size 0 0)
			(layers "B.Cu" "B.Mask" "B.Paste")
			(net "GND")
		)
	)
	(footprint ""
		(layer "B.Cu")
		(at 151.806148 -386.766562 90)
		(property "Reference" "C390"
			(at 0 0 90)
			(layer "B.SilkS")
			(hide yes)
			(effects
				(font
					(size 1.27 1.27)
				)
				(justify mirror)
			)
		)
		(property "Value" ""
			(at 0 0 90)
			(layer "B.Fab")
			(effects
				(font
					(size 1.27 1.27)
				)
				(justify mirror)
			)
		)
		(duplicate_pad_numbers_are_jumpers no)
		(fp_line
			(start 0.299974 -0.150114)
			(end -0.299974 -0.150114)
			(stroke
				(width 0.1)
				(type default)
			)
			(layer "B.Fab")
		)
		(fp_line
			(start -0.299974 -0.150114)
			(end -0.299974 0.150114)
			(stroke
				(width 0.1)
				(type default)
			)
			(layer "B.Fab")
		)
		(fp_line
			(start 0.299974 0.150114)
			(end 0.299974 -0.150114)
			(stroke
				(width 0.1)
				(type default)
			)
			(layer "B.Fab")
		)
		(fp_line
			(start -0.299974 0.150114)
			(end 0.299974 0.150114)
			(stroke
				(width 0.1)
				(type default)
			)
			(layer "B.Fab")
		)
		(pad "1" smd rect
			(at 0.2667 0 270)
			(size 0.3048 0.381)
			(layers "B.Cu" "B.Mask" "B.Paste")
			(net "P0V9_CPU1_RT2_2A_2D")
		)
		(pad "2" smd rect
			(at -0.2667 0 270)
			(size 0.3048 0.381)
			(layers "B.Cu" "B.Mask" "B.Paste")
			(net "GND")
		)
	)
	(footprint ""
		(layer "B.Cu")
		(at 165.146228 -388.011162 -90)
		(property "Reference" "C395"
			(at 0 0 90)
			(layer "B.SilkS")
			(hide yes)
			(effects
				(font
					(size 1.27 1.27)
				)
				(justify mirror)
			)
		)
		(property "Value" ""
			(at 0 0 90)
			(layer "B.Fab")
			(effects
				(font
					(size 1.27 1.27)
				)
				(justify mirror)
			)
		)
		(duplicate_pad_numbers_are_jumpers no)
		(fp_line
			(start -0.299974 0.150114)
			(end 0.299974 0.150114)
			(stroke
				(width 0.1)
				(type default)
			)
			(layer "B.Fab")
		)
		(fp_line
			(start 0.299974 0.150114)
			(end 0.299974 -0.150114)
			(stroke
				(width 0.1)
				(type default)
			)
			(layer "B.Fab")
		)
		(fp_line
			(start -0.299974 -0.150114)
			(end -0.299974 0.150114)
			(stroke
				(width 0.1)
				(type default)
			)
			(layer "B.Fab")
		)
		(fp_line
			(start 0.299974 -0.150114)
			(end -0.299974 -0.150114)
			(stroke
				(width 0.1)
				(type default)
			)
			(layer "B.Fab")
		)
		(pad "1" smd rect
			(at 0.2667 0 90)
			(size 0.3048 0.381)
			(layers "B.Cu" "B.Mask" "B.Paste")
			(net "P0V9_CPU1_RT2_2A")
		)
		(pad "2" smd rect
			(at -0.2667 0 90)
			(size 0.3048 0.381)
			(layers "B.Cu" "B.Mask" "B.Paste")
			(net "GND")
		)
	)
	(footprint ""
		(layer "B.Cu")
		(at 351.645982 -396.393162 -90)
		(property "Reference" "C659"
			(at 0 0 90)
			(layer "B.SilkS")
			(hide yes)
			(effects
				(font
					(size 1.27 1.27)
				)
				(justify mirror)
			)
		)
		(property "Value" ""
			(at 0 0 90)
			(layer "B.Fab")
			(effects
				(font
					(size 1.27 1.27)
				)
				(justify mirror)
			)
		)
		(duplicate_pad_numbers_are_jumpers no)
		(fp_line
			(start -0.299974 0.150114)
			(end 0.299974 0.150114)
			(stroke
				(width 0.1)
				(type default)
			)
			(layer "B.Fab")
		)
		(fp_line
			(start 0.299974 0.150114)
			(end 0.299974 -0.150114)
			(stroke
				(width 0.1)
				(type default)
			)
			(layer "B.Fab")
		)
		(fp_line
			(start -0.299974 -0.150114)
			(end -0.299974 0.150114)
			(stroke
				(width 0.1)
				(type default)
			)
			(layer "B.Fab")
		)
		(fp_line
			(start 0.299974 -0.150114)
			(end -0.299974 -0.150114)
			(stroke
				(width 0.1)
				(type default)
			)
			(layer "B.Fab")
		)
		(pad "1" smd rect
			(at 0.2667 0 90)
			(size 0.3048 0.381)
			(layers "B.Cu" "B.Mask" "B.Paste")
			(net "P0V9_CPU0_RT1_2A")
		)
		(pad "2" smd rect
			(at -0.2667 0 90)
			(size 0.3048 0.381)
			(layers "B.Cu" "B.Mask" "B.Paste")
			(net "GND")
		)
	)
	(footprint ""
		(layer "B.Cu")
		(at 352.163126 -416.899344 90)
		(property "Reference" "C6563"
			(at 0 0 90)
			(layer "B.SilkS")
			(hide yes)
			(effects
				(font
					(size 1.27 1.27)
				)
				(justify mirror)
			)
		)
		(property "Value" ""
			(at 0 0 90)
			(layer "B.Fab")
			(effects
				(font
					(size 1.27 1.27)
				)
				(justify mirror)
			)
		)
		(duplicate_pad_numbers_are_jumpers no)
		(fp_line
			(start 0.299974 -0.150114)
			(end -0.299974 -0.150114)
			(stroke
				(width 0.1)
				(type default)
			)
			(layer "B.Fab")
		)
		(fp_line
			(start -0.299974 -0.150114)
			(end -0.299974 0.150114)
			(stroke
				(width 0.1)
				(type default)
			)
			(layer "B.Fab")
		)
		(fp_line
			(start 0.299974 0.150114)
			(end 0.299974 -0.150114)
			(stroke
				(width 0.1)
				(type default)
			)
			(layer "B.Fab")
		)
		(fp_line
			(start -0.299974 0.150114)
			(end 0.299974 0.150114)
			(stroke
				(width 0.1)
				(type default)
			)
			(layer "B.Fab")
		)
		(pad "1" smd rect
			(at 0.2667 0 270)
			(size 0.3048 0.381)
			(layers "B.Cu" "B.Mask" "B.Paste")
			(net "P5E_CPU0_P1_TX_BUF_C_DP<15>")
		)
		(pad "2" smd rect
			(at -0.2667 0 270)
			(size 0.3048 0.381)
			(layers "B.Cu" "B.Mask" "B.Paste")
			(net "P5E_CPU0_P1_TX_BUF_DP<15>")
		)
	)
	(footprint ""
		(layer "B.Cu")
		(at 28.46324 -193.996564)
		(property "Reference" "C152"
			(at 0 0 0)
			(layer "B.SilkS")
			(hide yes)
			(effects
				(font
					(size 1.27 1.27)
				)
				(justify mirror)
			)
		)
		(property "Value" ""
			(at 0 0 0)
			(layer "B.Fab")
			(effects
				(font
					(size 1.27 1.27)
				)
				(justify mirror)
			)
		)
		(duplicate_pad_numbers_are_jumpers no)
		(fp_line
			(start -0.7874 -0.4064)
			(end -0.7874 0.4064)
			(stroke
				(width 0.1524)
				(type default)
			)
			(layer "B.SilkS")
		)
		(fp_line
			(start -0.7874 0.4064)
			(end 0.7874 0.4064)
			(stroke
				(width 0.1524)
				(type default)
			)
			(layer "B.SilkS")
		)
		(fp_line
			(start 0.7874 -0.4064)
			(end -0.7874 -0.4064)
			(stroke
				(width 0.1524)
				(type default)
			)
			(layer "B.SilkS")
		)
		(fp_line
			(start 0.7874 0.4064)
			(end 0.7874 -0.4064)
			(stroke
				(width 0.1524)
				(type default)
			)
			(layer "B.SilkS")
		)
		(fp_line
			(start -0.67945 -0.3048)
			(end -0.67945 0.3048)
			(stroke
				(width 0.1)
				(type default)
			)
			(layer "B.Fab")
		)
		(fp_line
			(start -0.67945 0.3048)
			(end -0.120396 0.3048)
			(stroke
				(width 0.1)
				(type default)
			)
			(layer "B.Fab")
		)
		(fp_line
			(start -0.12065 -0.3048)
			(end -0.67945 -0.3048)
			(stroke
				(width 0.1)
				(type default)
			)
			(layer "B.Fab")
		)
		(fp_line
			(start -0.12065 -0.2794)
			(end -0.12065 -0.3048)
			(stroke
				(width 0.1)
				(type default)
			)
			(layer "B.Fab")
		)
		(fp_line
			(start -0.120396 0.2794)
			(end 0.12065 0.2794)
			(stroke
				(width 0.1)
				(type default)
			)
			(layer "B.Fab")
		)
		(fp_line
			(start -0.120396 0.3048)
			(end -0.120396 0.2794)
			(stroke
				(width 0.1)
				(type default)
			)
			(layer "B.Fab")
		)
		(fp_line
			(start 0.12065 -0.305054)
			(end 0.12065 -0.2794)
			(stroke
				(width 0.1)
				(type default)
			)
			(layer "B.Fab")
		)
		(fp_line
			(start 0.12065 -0.2794)
			(end -0.12065 -0.2794)
			(stroke
				(width 0.1)
				(type default)
			)
			(layer "B.Fab")
		)
		(fp_line
			(start 0.12065 0.2794)
			(end 0.12065 0.3048)
			(stroke
				(width 0.1)
				(type default)
			)
			(layer "B.Fab")
		)
		(fp_line
			(start 0.12065 0.3048)
			(end 0.67945 0.3048)
			(stroke
				(width 0.1)
				(type default)
			)
			(layer "B.Fab")
		)
		(fp_line
			(start 0.67945 -0.305054)
			(end 0.12065 -0.305054)
			(stroke
				(width 0.1)
				(type default)
			)
			(layer "B.Fab")
		)
		(fp_line
			(start 0.67945 0.3048)
			(end 0.67945 -0.305054)
			(stroke
				(width 0.1)
				(type default)
			)
			(layer "B.Fab")
		)
		(pad "1" smd circle
			(at 0.40005 0 180)
			(size 0 0)
			(layers "B.Cu" "B.Mask" "B.Paste")
			(net "P3V3_AUX")
		)
		(pad "2" smd circle
			(at -0.40005 0 180)
			(size 0 0)
			(layers "B.Cu" "B.Mask" "B.Paste")
			(net "GND")
		)
	)
	(footprint ""
		(layer "B.Cu")
		(at 299.265594 -391.88136 180)
		(property "Reference" "R973"
			(at 0 0 0)
			(layer "B.SilkS")
			(hide yes)
			(effects
				(font
					(size 1.27 1.27)
				)
				(justify mirror)
			)
		)
		(property "Value" ""
			(at 0 0 0)
			(layer "B.Fab")
			(effects
				(font
					(size 1.27 1.27)
				)
				(justify mirror)
			)
		)
		(duplicate_pad_numbers_are_jumpers no)
		(fp_line
			(start 0.32512 0.175006)
			(end 0.32512 -0.175006)
			(stroke
				(width 0.1)
				(type default)
			)
			(layer "B.Fab")
		)
		(fp_line
			(start 0.32512 -0.175006)
			(end -0.32512 -0.175006)
			(stroke
				(width 0.1)
				(type default)
			)
			(layer "B.Fab")
		)
		(fp_line
			(start -0.32512 0.175006)
			(end 0.32512 0.175006)
			(stroke
				(width 0.1)
				(type default)
			)
			(layer "B.Fab")
		)
		(fp_line
			(start -0.32512 -0.175006)
			(end -0.32512 0.175006)
			(stroke
				(width 0.1)
				(type default)
			)
			(layer "B.Fab")
		)
		(pad "1" smd rect
			(at 0.2667 0)
			(size 0.3048 0.381)
			(layers "B.Cu" "B.Mask" "B.Paste")
			(net "RT_CPU0_P0_SCAN_MODE")
		)
		(pad "2" smd rect
			(at -0.2667 0 180)
			(size 0.3048 0.381)
			(layers "B.Cu" "B.Mask" "B.Paste")
			(net "GND")
		)
	)
	(footprint ""
		(layer "B.Cu")
		(at 125.418342 -388.011162 -90)
		(property "Reference" "C444"
			(at 0 0 90)
			(layer "B.SilkS")
			(hide yes)
			(effects
				(font
					(size 1.27 1.27)
				)
				(justify mirror)
			)
		)
		(property "Value" ""
			(at 0 0 90)
			(layer "B.Fab")
			(effects
				(font
					(size 1.27 1.27)
				)
				(justify mirror)
			)
		)
		(duplicate_pad_numbers_are_jumpers no)
		(fp_line
			(start -0.299974 0.150114)
			(end 0.299974 0.150114)
			(stroke
				(width 0.1)
				(type default)
			)
			(layer "B.Fab")
		)
		(fp_line
			(start 0.299974 0.150114)
			(end 0.299974 -0.150114)
			(stroke
				(width 0.1)
				(type default)
			)
			(layer "B.Fab")
		)
		(fp_line
			(start -0.299974 -0.150114)
			(end -0.299974 0.150114)
			(stroke
				(width 0.1)
				(type default)
			)
			(layer "B.Fab")
		)
		(fp_line
			(start 0.299974 -0.150114)
			(end -0.299974 -0.150114)
			(stroke
				(width 0.1)
				(type default)
			)
			(layer "B.Fab")
		)
		(pad "1" smd rect
			(at 0.2667 0 90)
			(size 0.3048 0.381)
			(layers "B.Cu" "B.Mask" "B.Paste")
			(net "P1V8_CPU1_RT3_1A_1D")
		)
		(pad "2" smd rect
			(at -0.2667 0 90)
			(size 0.3048 0.381)
			(layers "B.Cu" "B.Mask" "B.Paste")
			(net "GND")
		)
	)
	(footprint ""
		(layer "B.Cu")
		(at 419.089586 -425.82338 180)
		(property "Reference" "R1217"
			(at 0 0 0)
			(layer "B.SilkS")
			(hide yes)
			(effects
				(font
					(size 1.27 1.27)
				)
				(justify mirror)
			)
		)
		(property "Value" ""
			(at 0 0 0)
			(layer "B.Fab")
			(effects
				(font
					(size 1.27 1.27)
				)
				(justify mirror)
			)
		)
		(duplicate_pad_numbers_are_jumpers no)
		(fp_line
			(start 0.32512 0.175006)
			(end 0.32512 -0.175006)
			(stroke
				(width 0.1)
				(type default)
			)
			(layer "B.Fab")
		)
		(fp_line
			(start 0.32512 -0.175006)
			(end -0.32512 -0.175006)
			(stroke
				(width 0.1)
				(type default)
			)
			(layer "B.Fab")
		)
		(fp_line
			(start -0.32512 0.175006)
			(end 0.32512 0.175006)
			(stroke
				(width 0.1)
				(type default)
			)
			(layer "B.Fab")
		)
		(fp_line
			(start -0.32512 -0.175006)
			(end -0.32512 0.175006)
			(stroke
				(width 0.1)
				(type default)
			)
			(layer "B.Fab")
		)
		(pad "1" smd rect
			(at 0.2667 0)
			(size 0.3048 0.381)
			(layers "B.Cu" "B.Mask" "B.Paste")
			(net "GND")
		)
		(pad "2" smd rect
			(at -0.2667 0 180)
			(size 0.3048 0.381)
			(layers "B.Cu" "B.Mask" "B.Paste")
			(net "RT_ROM_MUX8_OE_N")
		)
	)
	(footprint ""
		(layer "B.Cu")
		(at 403.981158 -327.987152)
		(property "Reference" "R737"
			(at 0 0 0)
			(layer "B.SilkS")
			(hide yes)
			(effects
				(font
					(size 1.27 1.27)
				)
				(justify mirror)
			)
		)
		(property "Value" ""
			(at 0 0 0)
			(layer "B.Fab")
			(effects
				(font
					(size 1.27 1.27)
				)
				(justify mirror)
			)
		)
		(duplicate_pad_numbers_are_jumpers no)
		(fp_line
			(start -0.7874 -0.4064)
			(end -0.7874 0.4064)
			(stroke
				(width 0.1524)
				(type default)
			)
			(layer "B.SilkS")
		)
		(fp_line
			(start -0.7874 0.4064)
			(end 0.7874 0.4064)
			(stroke
				(width 0.1524)
				(type default)
			)
			(layer "B.SilkS")
		)
		(fp_line
			(start 0.7874 -0.4064)
			(end -0.7874 -0.4064)
			(stroke
				(width 0.1524)
				(type default)
			)
			(layer "B.SilkS")
		)
		(fp_line
			(start 0.7874 0.4064)
			(end 0.7874 -0.4064)
			(stroke
				(width 0.1524)
				(type default)
			)
			(layer "B.SilkS")
		)
		(fp_line
			(start -0.67945 -0.3048)
			(end -0.67945 0.3048)
			(stroke
				(width 0.1)
				(type default)
			)
			(layer "B.Fab")
		)
		(fp_line
			(start -0.67945 0.3048)
			(end -0.120396 0.3048)
			(stroke
				(width 0.1)
				(type default)
			)
			(layer "B.Fab")
		)
		(fp_line
			(start -0.12065 -0.3048)
			(end -0.67945 -0.3048)
			(stroke
				(width 0.1)
				(type default)
			)
			(layer "B.Fab")
		)
		(fp_line
			(start -0.12065 -0.2794)
			(end -0.12065 -0.3048)
			(stroke
				(width 0.1)
				(type default)
			)
			(layer "B.Fab")
		)
		(fp_line
			(start -0.120396 0.2794)
			(end 0.12065 0.2794)
			(stroke
				(width 0.1)
				(type default)
			)
			(layer "B.Fab")
		)
		(fp_line
			(start -0.120396 0.3048)
			(end -0.120396 0.2794)
			(stroke
				(width 0.1)
				(type default)
			)
			(layer "B.Fab")
		)
		(fp_line
			(start 0.12065 -0.305054)
			(end 0.12065 -0.2794)
			(stroke
				(width 0.1)
				(type default)
			)
			(layer "B.Fab")
		)
		(fp_line
			(start 0.12065 -0.2794)
			(end -0.12065 -0.2794)
			(stroke
				(width 0.1)
				(type default)
			)
			(layer "B.Fab")
		)
		(fp_line
			(start 0.12065 0.2794)
			(end 0.12065 0.3048)
			(stroke
				(width 0.1)
				(type default)
			)
			(layer "B.Fab")
		)
		(fp_line
			(start 0.12065 0.3048)
			(end 0.67945 0.3048)
			(stroke
				(width 0.1)
				(type default)
			)
			(layer "B.Fab")
		)
		(fp_line
			(start 0.67945 -0.305054)
			(end 0.12065 -0.305054)
			(stroke
				(width 0.1)
				(type default)
			)
			(layer "B.Fab")
		)
		(fp_line
			(start 0.67945 0.3048)
			(end 0.67945 -0.305054)
			(stroke
				(width 0.1)
				(type default)
			)
			(layer "B.Fab")
		)
		(pad "1" smd circle
			(at 0.40005 0 180)
			(size 0 0)
			(layers "B.Cu" "B.Mask" "B.Paste")
			(net "PVDD18_S5_P0")
		)
		(pad "2" smd circle
			(at -0.40005 0 180)
			(size 0 0)
			(layers "B.Cu" "B.Mask" "B.Paste")
			(net "CPU0_ROM_TYPE_SELECT")
		)
	)
	(footprint ""
		(layer "B.Cu")
		(at 226.777042 -315.95568 -90)
		(property "Reference" "PC6528"
			(at 0 0 90)
			(layer "B.SilkS")
			(hide yes)
			(effects
				(font
					(size 1.27 1.27)
				)
				(justify mirror)
			)
		)
		(property "Value" ""
			(at 0 0 90)
			(layer "B.Fab")
			(effects
				(font
					(size 1.27 1.27)
				)
				(justify mirror)
			)
		)
		(duplicate_pad_numbers_are_jumpers no)
		(fp_line
			(start -1.524 0.762)
			(end 1.524 0.762)
			(stroke
				(width 0.1524)
				(type default)
			)
			(layer "B.SilkS")
		)
		(fp_line
			(start 1.524 0.762)
			(end 1.524 -0.762)
			(stroke
				(width 0.1524)
				(type default)
			)
			(layer "B.SilkS")
		)
		(fp_line
			(start -1.524 -0.762)
			(end -1.524 0.762)
			(stroke
				(width 0.1524)
				(type default)
			)
			(layer "B.SilkS")
		)
		(fp_line
			(start 1.524 -0.762)
			(end -1.524 -0.762)
			(stroke
				(width 0.1524)
				(type default)
			)
			(layer "B.SilkS")
		)
		(fp_line
			(start -1.1049 0.724916)
			(end -1.1049 -0.724916)
			(stroke
				(width 0.1)
				(type default)
			)
			(layer "B.Fab")
		)
		(fp_line
			(start 1.1049 0.724916)
			(end -1.1049 0.724916)
			(stroke
				(width 0.1)
				(type default)
			)
			(layer "B.Fab")
		)
		(fp_line
			(start -1.1049 -0.724916)
			(end 1.1049 -0.724916)
			(stroke
				(width 0.1)
				(type default)
			)
			(layer "B.Fab")
		)
		(fp_line
			(start 1.1049 -0.724916)
			(end 1.1049 0.724916)
			(stroke
				(width 0.1)
				(type default)
			)
			(layer "B.Fab")
		)
		(pad "1" smd rect
			(at 0.889 0 270)
			(size 1.016 1.27)
			(layers "B.Cu" "B.Mask" "B.Paste")
			(net "P1V8_CPU1_RT_1D")
		)
		(pad "2" smd rect
			(at -0.889 0 270)
			(size 1.016 1.27)
			(layers "B.Cu" "B.Mask" "B.Paste")
			(net "GND")
		)
	)
	(footprint ""
		(layer "B.Cu")
		(at 232.669842 -315.95568 -90)
		(property "Reference" "PC6530"
			(at 0 0 90)
			(layer "B.SilkS")
			(hide yes)
			(effects
				(font
					(size 1.27 1.27)
				)
				(justify mirror)
			)
		)
		(property "Value" ""
			(at 0 0 90)
			(layer "B.Fab")
			(effects
				(font
					(size 1.27 1.27)
				)
				(justify mirror)
			)
		)
		(duplicate_pad_numbers_are_jumpers no)
		(fp_line
			(start -1.524 0.762)
			(end 1.524 0.762)
			(stroke
				(width 0.1524)
				(type default)
			)
			(layer "B.SilkS")
		)
		(fp_line
			(start 1.524 0.762)
			(end 1.524 -0.762)
			(stroke
				(width 0.1524)
				(type default)
			)
			(layer "B.SilkS")
		)
		(fp_line
			(start -1.524 -0.762)
			(end -1.524 0.762)
			(stroke
				(width 0.1524)
				(type default)
			)
			(layer "B.SilkS")
		)
		(fp_line
			(start 1.524 -0.762)
			(end -1.524 -0.762)
			(stroke
				(width 0.1524)
				(type default)
			)
			(layer "B.SilkS")
		)
		(fp_line
			(start -1.1049 0.724916)
			(end -1.1049 -0.724916)
			(stroke
				(width 0.1)
				(type default)
			)
			(layer "B.Fab")
		)
		(fp_line
			(start 1.1049 0.724916)
			(end -1.1049 0.724916)
			(stroke
				(width 0.1)
				(type default)
			)
			(layer "B.Fab")
		)
		(fp_line
			(start -1.1049 -0.724916)
			(end 1.1049 -0.724916)
			(stroke
				(width 0.1)
				(type default)
			)
			(layer "B.Fab")
		)
		(fp_line
			(start 1.1049 -0.724916)
			(end 1.1049 0.724916)
			(stroke
				(width 0.1)
				(type default)
			)
			(layer "B.Fab")
		)
		(pad "1" smd rect
			(at 0.889 0 270)
			(size 1.016 1.27)
			(layers "B.Cu" "B.Mask" "B.Paste")
			(net "P1V8_CPU1_RT_1D")
		)
		(pad "2" smd rect
			(at -0.889 0 270)
			(size 1.016 1.27)
			(layers "B.Cu" "B.Mask" "B.Paste")
			(net "GND")
		)
	)
	(footprint ""
		(layer "B.Cu")
		(at 70.172834 -202.688952)
		(property "Reference" "R535"
			(at 0 0 0)
			(layer "B.SilkS")
			(hide yes)
			(effects
				(font
					(size 1.27 1.27)
				)
				(justify mirror)
			)
		)
		(property "Value" ""
			(at 0 0 0)
			(layer "B.Fab")
			(effects
				(font
					(size 1.27 1.27)
				)
				(justify mirror)
			)
		)
		(duplicate_pad_numbers_are_jumpers no)
		(fp_line
			(start -0.7874 -0.4064)
			(end -0.7874 0.4064)
			(stroke
				(width 0.1524)
				(type default)
			)
			(layer "B.SilkS")
		)
		(fp_line
			(start -0.7874 0.4064)
			(end 0.7874 0.4064)
			(stroke
				(width 0.1524)
				(type default)
			)
			(layer "B.SilkS")
		)
		(fp_line
			(start 0.7874 -0.4064)
			(end -0.7874 -0.4064)
			(stroke
				(width 0.1524)
				(type default)
			)
			(layer "B.SilkS")
		)
		(fp_line
			(start 0.7874 0.4064)
			(end 0.7874 -0.4064)
			(stroke
				(width 0.1524)
				(type default)
			)
			(layer "B.SilkS")
		)
		(fp_line
			(start -0.67945 -0.3048)
			(end -0.67945 0.3048)
			(stroke
				(width 0.1)
				(type default)
			)
			(layer "B.Fab")
		)
		(fp_line
			(start -0.67945 0.3048)
			(end -0.120396 0.3048)
			(stroke
				(width 0.1)
				(type default)
			)
			(layer "B.Fab")
		)
		(fp_line
			(start -0.12065 -0.3048)
			(end -0.67945 -0.3048)
			(stroke
				(width 0.1)
				(type default)
			)
			(layer "B.Fab")
		)
		(fp_line
			(start -0.12065 -0.2794)
			(end -0.12065 -0.3048)
			(stroke
				(width 0.1)
				(type default)
			)
			(layer "B.Fab")
		)
		(fp_line
			(start -0.120396 0.2794)
			(end 0.12065 0.2794)
			(stroke
				(width 0.1)
				(type default)
			)
			(layer "B.Fab")
		)
		(fp_line
			(start -0.120396 0.3048)
			(end -0.120396 0.2794)
			(stroke
				(width 0.1)
				(type default)
			)
			(layer "B.Fab")
		)
		(fp_line
			(start 0.12065 -0.305054)
			(end 0.12065 -0.2794)
			(stroke
				(width 0.1)
				(type default)
			)
			(layer "B.Fab")
		)
		(fp_line
			(start 0.12065 -0.2794)
			(end -0.12065 -0.2794)
			(stroke
				(width 0.1)
				(type default)
			)
			(layer "B.Fab")
		)
		(fp_line
			(start 0.12065 0.2794)
			(end 0.12065 0.3048)
			(stroke
				(width 0.1)
				(type default)
			)
			(layer "B.Fab")
		)
		(fp_line
			(start 0.12065 0.3048)
			(end 0.67945 0.3048)
			(stroke
				(width 0.1)
				(type default)
			)
			(layer "B.Fab")
		)
		(fp_line
			(start 0.67945 -0.305054)
			(end 0.12065 -0.305054)
			(stroke
				(width 0.1)
				(type default)
			)
			(layer "B.Fab")
		)
		(fp_line
			(start 0.67945 0.3048)
			(end 0.67945 -0.305054)
			(stroke
				(width 0.1)
				(type default)
			)
			(layer "B.Fab")
		)
		(pad "1" smd circle
			(at 0.40005 0 180)
			(size 0 0)
			(layers "B.Cu" "B.Mask" "B.Paste")
			(net "APML_CPU1_ALERT_N")
		)
		(pad "2" smd circle
			(at -0.40005 0 180)
			(size 0 0)
			(layers "B.Cu" "B.Mask" "B.Paste")
			(net "PVDD18_S5_P1")
		)
	)
	(footprint ""
		(layer "B.Cu")
		(at 65.391284 -390.560052 90)
		(property "Reference" "C269"
			(at 0 0 90)
			(layer "B.SilkS")
			(hide yes)
			(effects
				(font
					(size 1.27 1.27)
				)
				(justify mirror)
			)
		)
		(property "Value" ""
			(at 0 0 90)
			(layer "B.Fab")
			(effects
				(font
					(size 1.27 1.27)
				)
				(justify mirror)
			)
		)
		(duplicate_pad_numbers_are_jumpers no)
		(fp_line
			(start 0.7874 -0.4064)
			(end -0.7874 -0.4064)
			(stroke
				(width 0.1524)
				(type default)
			)
			(layer "B.SilkS")
		)
		(fp_line
			(start -0.7874 -0.4064)
			(end -0.7874 0.4064)
			(stroke
				(width 0.1524)
				(type default)
			)
			(layer "B.SilkS")
		)
		(fp_line
			(start 0.7874 0.4064)
			(end 0.7874 -0.4064)
			(stroke
				(width 0.1524)
				(type default)
			)
			(layer "B.SilkS")
		)
		(fp_line
			(start -0.7874 0.4064)
			(end 0.7874 0.4064)
			(stroke
				(width 0.1524)
				(type default)
			)
			(layer "B.SilkS")
		)
		(fp_line
			(start 0.67945 -0.305054)
			(end 0.12065 -0.305054)
			(stroke
				(width 0.1)
				(type default)
			)
			(layer "B.Fab")
		)
		(fp_line
			(start 0.12065 -0.305054)
			(end 0.12065 -0.2794)
			(stroke
				(width 0.1)
				(type default)
			)
			(layer "B.Fab")
		)
		(fp_line
			(start -0.12065 -0.3048)
			(end -0.67945 -0.3048)
			(stroke
				(width 0.1)
				(type default)
			)
			(layer "B.Fab")
		)
		(fp_line
			(start -0.67945 -0.3048)
			(end -0.67945 0.3048)
			(stroke
				(width 0.1)
				(type default)
			)
			(layer "B.Fab")
		)
		(fp_line
			(start 0.12065 -0.2794)
			(end -0.12065 -0.2794)
			(stroke
				(width 0.1)
				(type default)
			)
			(layer "B.Fab")
		)
		(fp_line
			(start -0.12065 -0.2794)
			(end -0.12065 -0.3048)
			(stroke
				(width 0.1)
				(type default)
			)
			(layer "B.Fab")
		)
		(fp_line
			(start 0.12065 0.2794)
			(end 0.12065 0.3048)
			(stroke
				(width 0.1)
				(type default)
			)
			(layer "B.Fab")
		)
		(fp_line
			(start -0.120396 0.2794)
			(end 0.12065 0.2794)
			(stroke
				(width 0.1)
				(type default)
			)
			(layer "B.Fab")
		)
		(fp_line
			(start 0.67945 0.3048)
			(end 0.67945 -0.305054)
			(stroke
				(width 0.1)
				(type default)
			)
			(layer "B.Fab")
		)
		(fp_line
			(start 0.12065 0.3048)
			(end 0.67945 0.3048)
			(stroke
				(width 0.1)
				(type default)
			)
			(layer "B.Fab")
		)
		(fp_line
			(start -0.120396 0.3048)
			(end -0.120396 0.2794)
			(stroke
				(width 0.1)
				(type default)
			)
			(layer "B.Fab")
		)
		(fp_line
			(start -0.67945 0.3048)
			(end -0.120396 0.3048)
			(stroke
				(width 0.1)
				(type default)
			)
			(layer "B.Fab")
		)
		(pad "1" smd circle
			(at 0.40005 0 270)
			(size 0 0)
			(layers "B.Cu" "B.Mask" "B.Paste")
			(net "P0V9_CPU1_RT0_2A")
		)
		(pad "2" smd circle
			(at -0.40005 0 270)
			(size 0 0)
			(layers "B.Cu" "B.Mask" "B.Paste")
			(net "GND")
		)
	)
	(footprint ""
		(layer "B.Cu")
		(at 109.895386 -250.257564)
		(property "Reference" "C2322"
			(at 0 0 0)
			(layer "B.SilkS")
			(hide yes)
			(effects
				(font
					(size 1.27 1.27)
				)
				(justify mirror)
			)
		)
		(property "Value" ""
			(at 0 0 0)
			(layer "B.Fab")
			(effects
				(font
					(size 1.27 1.27)
				)
				(justify mirror)
			)
		)
		(duplicate_pad_numbers_are_jumpers no)
		(fp_line
			(start -0.7874 -0.4064)
			(end -0.7874 0.4064)
			(stroke
				(width 0.1524)
				(type default)
			)
			(layer "B.SilkS")
		)
		(fp_line
			(start -0.7874 0.4064)
			(end 0.7874 0.4064)
			(stroke
				(width 0.1524)
				(type default)
			)
			(layer "B.SilkS")
		)
		(fp_line
			(start 0.7874 -0.4064)
			(end -0.7874 -0.4064)
			(stroke
				(width 0.1524)
				(type default)
			)
			(layer "B.SilkS")
		)
		(fp_line
			(start 0.7874 0.4064)
			(end 0.7874 -0.4064)
			(stroke
				(width 0.1524)
				(type default)
			)
			(layer "B.SilkS")
		)
		(fp_line
			(start -0.67945 -0.3048)
			(end -0.67945 0.3048)
			(stroke
				(width 0.1)
				(type default)
			)
			(layer "B.Fab")
		)
		(fp_line
			(start -0.67945 0.3048)
			(end -0.120396 0.3048)
			(stroke
				(width 0.1)
				(type default)
			)
			(layer "B.Fab")
		)
		(fp_line
			(start -0.12065 -0.3048)
			(end -0.67945 -0.3048)
			(stroke
				(width 0.1)
				(type default)
			)
			(layer "B.Fab")
		)
		(fp_line
			(start -0.12065 -0.2794)
			(end -0.12065 -0.3048)
			(stroke
				(width 0.1)
				(type default)
			)
			(layer "B.Fab")
		)
		(fp_line
			(start -0.120396 0.2794)
			(end 0.12065 0.2794)
			(stroke
				(width 0.1)
				(type default)
			)
			(layer "B.Fab")
		)
		(fp_line
			(start -0.120396 0.3048)
			(end -0.120396 0.2794)
			(stroke
				(width 0.1)
				(type default)
			)
			(layer "B.Fab")
		)
		(fp_line
			(start 0.12065 -0.305054)
			(end 0.12065 -0.2794)
			(stroke
				(width 0.1)
				(type default)
			)
			(layer "B.Fab")
		)
		(fp_line
			(start 0.12065 -0.2794)
			(end -0.12065 -0.2794)
			(stroke
				(width 0.1)
				(type default)
			)
			(layer "B.Fab")
		)
		(fp_line
			(start 0.12065 0.2794)
			(end 0.12065 0.3048)
			(stroke
				(width 0.1)
				(type default)
			)
			(layer "B.Fab")
		)
		(fp_line
			(start 0.12065 0.3048)
			(end 0.67945 0.3048)
			(stroke
				(width 0.1)
				(type default)
			)
			(layer "B.Fab")
		)
		(fp_line
			(start 0.67945 -0.305054)
			(end 0.12065 -0.305054)
			(stroke
				(width 0.1)
				(type default)
			)
			(layer "B.Fab")
		)
		(fp_line
			(start 0.67945 0.3048)
			(end 0.67945 -0.305054)
			(stroke
				(width 0.1)
				(type default)
			)
			(layer "B.Fab")
		)
		(pad "1" smd circle
			(at 0.40005 0 180)
			(size 0 0)
			(layers "B.Cu" "B.Mask" "B.Paste")
			(net "PVDDCR_CPU0_P1")
		)
		(pad "2" smd circle
			(at -0.40005 0 180)
			(size 0 0)
			(layers "B.Cu" "B.Mask" "B.Paste")
			(net "GND")
		)
	)
	(footprint ""
		(layer "B.Cu")
		(at 115.275868 -256.012442 -90)
		(property "Reference" "C2418"
			(at 0 0 90)
			(layer "B.SilkS")
			(hide yes)
			(effects
				(font
					(size 1.27 1.27)
				)
				(justify mirror)
			)
		)
		(property "Value" ""
			(at 0 0 90)
			(layer "B.Fab")
			(effects
				(font
					(size 1.27 1.27)
				)
				(justify mirror)
			)
		)
		(duplicate_pad_numbers_are_jumpers no)
		(fp_line
			(start -0.7874 0.4064)
			(end 0.7874 0.4064)
			(stroke
				(width 0.1524)
				(type default)
			)
			(layer "B.SilkS")
		)
		(fp_line
			(start 0.7874 0.4064)
			(end 0.7874 -0.4064)
			(stroke
				(width 0.1524)
				(type default)
			)
			(layer "B.SilkS")
		)
		(fp_line
			(start -0.7874 -0.4064)
			(end -0.7874 0.4064)
			(stroke
				(width 0.1524)
				(type default)
			)
			(layer "B.SilkS")
		)
		(fp_line
			(start 0.7874 -0.4064)
			(end -0.7874 -0.4064)
			(stroke
				(width 0.1524)
				(type default)
			)
			(layer "B.SilkS")
		)
		(fp_line
			(start -0.67945 0.3048)
			(end -0.120396 0.3048)
			(stroke
				(width 0.1)
				(type default)
			)
			(layer "B.Fab")
		)
		(fp_line
			(start -0.120396 0.3048)
			(end -0.120396 0.2794)
			(stroke
				(width 0.1)
				(type default)
			)
			(layer "B.Fab")
		)
		(fp_line
			(start 0.12065 0.3048)
			(end 0.67945 0.3048)
			(stroke
				(width 0.1)
				(type default)
			)
			(layer "B.Fab")
		)
		(fp_line
			(start 0.67945 0.3048)
			(end 0.67945 -0.305054)
			(stroke
				(width 0.1)
				(type default)
			)
			(layer "B.Fab")
		)
		(fp_line
			(start -0.120396 0.2794)
			(end 0.12065 0.2794)
			(stroke
				(width 0.1)
				(type default)
			)
			(layer "B.Fab")
		)
		(fp_line
			(start 0.12065 0.2794)
			(end 0.12065 0.3048)
			(stroke
				(width 0.1)
				(type default)
			)
			(layer "B.Fab")
		)
		(fp_line
			(start -0.12065 -0.2794)
			(end -0.12065 -0.3048)
			(stroke
				(width 0.1)
				(type default)
			)
			(layer "B.Fab")
		)
		(fp_line
			(start 0.12065 -0.2794)
			(end -0.12065 -0.2794)
			(stroke
				(width 0.1)
				(type default)
			)
			(layer "B.Fab")
		)
		(fp_line
			(start -0.67945 -0.3048)
			(end -0.67945 0.3048)
			(stroke
				(width 0.1)
				(type default)
			)
			(layer "B.Fab")
		)
		(fp_line
			(start -0.12065 -0.3048)
			(end -0.67945 -0.3048)
			(stroke
				(width 0.1)
				(type default)
			)
			(layer "B.Fab")
		)
		(fp_line
			(start 0.12065 -0.305054)
			(end 0.12065 -0.2794)
			(stroke
				(width 0.1)
				(type default)
			)
			(layer "B.Fab")
		)
		(fp_line
			(start 0.67945 -0.305054)
			(end 0.12065 -0.305054)
			(stroke
				(width 0.1)
				(type default)
			)
			(layer "B.Fab")
		)
		(pad "1" smd circle
			(at 0.40005 0 90)
			(size 0 0)
			(layers "B.Cu" "B.Mask" "B.Paste")
			(net "PVDDCR_SOC_P1")
		)
		(pad "2" smd circle
			(at -0.40005 0 90)
			(size 0 0)
			(layers "B.Cu" "B.Mask" "B.Paste")
			(net "GND")
		)
	)
	(footprint ""
		(layer "B.Cu")
		(at 363.804454 -266.00531)
		(property "Reference" "C2656"
			(at 0 0 0)
			(layer "B.SilkS")
			(hide yes)
			(effects
				(font
					(size 1.27 1.27)
				)
				(justify mirror)
			)
		)
		(property "Value" ""
			(at 0 0 0)
			(layer "B.Fab")
			(effects
				(font
					(size 1.27 1.27)
				)
				(justify mirror)
			)
		)
		(duplicate_pad_numbers_are_jumpers no)
		(fp_line
			(start -0.7874 -0.4064)
			(end -0.7874 0.4064)
			(stroke
				(width 0.1524)
				(type default)
			)
			(layer "B.SilkS")
		)
		(fp_line
			(start -0.7874 0.4064)
			(end 0.7874 0.4064)
			(stroke
				(width 0.1524)
				(type default)
			)
			(layer "B.SilkS")
		)
		(fp_line
			(start 0.7874 -0.4064)
			(end -0.7874 -0.4064)
			(stroke
				(width 0.1524)
				(type default)
			)
			(layer "B.SilkS")
		)
		(fp_line
			(start 0.7874 0.4064)
			(end 0.7874 -0.4064)
			(stroke
				(width 0.1524)
				(type default)
			)
			(layer "B.SilkS")
		)
		(fp_line
			(start -0.67945 -0.3048)
			(end -0.67945 0.3048)
			(stroke
				(width 0.1)
				(type default)
			)
			(layer "B.Fab")
		)
		(fp_line
			(start -0.67945 0.3048)
			(end -0.120396 0.3048)
			(stroke
				(width 0.1)
				(type default)
			)
			(layer "B.Fab")
		)
		(fp_line
			(start -0.12065 -0.3048)
			(end -0.67945 -0.3048)
			(stroke
				(width 0.1)
				(type default)
			)
			(layer "B.Fab")
		)
		(fp_line
			(start -0.12065 -0.2794)
			(end -0.12065 -0.3048)
			(stroke
				(width 0.1)
				(type default)
			)
			(layer "B.Fab")
		)
		(fp_line
			(start -0.120396 0.2794)
			(end 0.12065 0.2794)
			(stroke
				(width 0.1)
				(type default)
			)
			(layer "B.Fab")
		)
		(fp_line
			(start -0.120396 0.3048)
			(end -0.120396 0.2794)
			(stroke
				(width 0.1)
				(type default)
			)
			(layer "B.Fab")
		)
		(fp_line
			(start 0.12065 -0.305054)
			(end 0.12065 -0.2794)
			(stroke
				(width 0.1)
				(type default)
			)
			(layer "B.Fab")
		)
		(fp_line
			(start 0.12065 -0.2794)
			(end -0.12065 -0.2794)
			(stroke
				(width 0.1)
				(type default)
			)
			(layer "B.Fab")
		)
		(fp_line
			(start 0.12065 0.2794)
			(end 0.12065 0.3048)
			(stroke
				(width 0.1)
				(type default)
			)
			(layer "B.Fab")
		)
		(fp_line
			(start 0.12065 0.3048)
			(end 0.67945 0.3048)
			(stroke
				(width 0.1)
				(type default)
			)
			(layer "B.Fab")
		)
		(fp_line
			(start 0.67945 -0.305054)
			(end 0.12065 -0.305054)
			(stroke
				(width 0.1)
				(type default)
			)
			(layer "B.Fab")
		)
		(fp_line
			(start 0.67945 0.3048)
			(end 0.67945 -0.305054)
			(stroke
				(width 0.1)
				(type default)
			)
			(layer "B.Fab")
		)
		(pad "1" smd circle
			(at 0.40005 0 180)
			(size 0 0)
			(layers "B.Cu" "B.Mask" "B.Paste")
			(net "PVDD11_S3_P0")
		)
		(pad "2" smd circle
			(at -0.40005 0 180)
			(size 0 0)
			(layers "B.Cu" "B.Mask" "B.Paste")
			(net "GND")
		)
	)
	(footprint ""
		(layer "B.Cu")
		(at 365.835692 -256.505202)
		(property "Reference" "C2147"
			(at 0 0 0)
			(layer "B.SilkS")
			(hide yes)
			(effects
				(font
					(size 1.27 1.27)
				)
				(justify mirror)
			)
		)
		(property "Value" ""
			(at 0 0 0)
			(layer "B.Fab")
			(effects
				(font
					(size 1.27 1.27)
				)
				(justify mirror)
			)
		)
		(duplicate_pad_numbers_are_jumpers no)
		(fp_line
			(start -0.7874 -0.4064)
			(end -0.7874 0.4064)
			(stroke
				(width 0.1524)
				(type default)
			)
			(layer "B.SilkS")
		)
		(fp_line
			(start -0.7874 0.4064)
			(end 0.7874 0.4064)
			(stroke
				(width 0.1524)
				(type default)
			)
			(layer "B.SilkS")
		)
		(fp_line
			(start 0.7874 -0.4064)
			(end -0.7874 -0.4064)
			(stroke
				(width 0.1524)
				(type default)
			)
			(layer "B.SilkS")
		)
		(fp_line
			(start 0.7874 0.4064)
			(end 0.7874 -0.4064)
			(stroke
				(width 0.1524)
				(type default)
			)
			(layer "B.SilkS")
		)
		(fp_line
			(start -0.67945 -0.3048)
			(end -0.67945 0.3048)
			(stroke
				(width 0.1)
				(type default)
			)
			(layer "B.Fab")
		)
		(fp_line
			(start -0.67945 0.3048)
			(end -0.120396 0.3048)
			(stroke
				(width 0.1)
				(type default)
			)
			(layer "B.Fab")
		)
		(fp_line
			(start -0.12065 -0.3048)
			(end -0.67945 -0.3048)
			(stroke
				(width 0.1)
				(type default)
			)
			(layer "B.Fab")
		)
		(fp_line
			(start -0.12065 -0.2794)
			(end -0.12065 -0.3048)
			(stroke
				(width 0.1)
				(type default)
			)
			(layer "B.Fab")
		)
		(fp_line
			(start -0.120396 0.2794)
			(end 0.12065 0.2794)
			(stroke
				(width 0.1)
				(type default)
			)
			(layer "B.Fab")
		)
		(fp_line
			(start -0.120396 0.3048)
			(end -0.120396 0.2794)
			(stroke
				(width 0.1)
				(type default)
			)
			(layer "B.Fab")
		)
		(fp_line
			(start 0.12065 -0.305054)
			(end 0.12065 -0.2794)
			(stroke
				(width 0.1)
				(type default)
			)
			(layer "B.Fab")
		)
		(fp_line
			(start 0.12065 -0.2794)
			(end -0.12065 -0.2794)
			(stroke
				(width 0.1)
				(type default)
			)
			(layer "B.Fab")
		)
		(fp_line
			(start 0.12065 0.2794)
			(end 0.12065 0.3048)
			(stroke
				(width 0.1)
				(type default)
			)
			(layer "B.Fab")
		)
		(fp_line
			(start 0.12065 0.3048)
			(end 0.67945 0.3048)
			(stroke
				(width 0.1)
				(type default)
			)
			(layer "B.Fab")
		)
		(fp_line
			(start 0.67945 -0.305054)
			(end 0.12065 -0.305054)
			(stroke
				(width 0.1)
				(type default)
			)
			(layer "B.Fab")
		)
		(fp_line
			(start 0.67945 0.3048)
			(end 0.67945 -0.305054)
			(stroke
				(width 0.1)
				(type default)
			)
			(layer "B.Fab")
		)
		(pad "1" smd circle
			(at 0.40005 0 180)
			(size 0 0)
			(layers "B.Cu" "B.Mask" "B.Paste")
			(net "PVDDCR_SOC_P0")
		)
		(pad "2" smd circle
			(at -0.40005 0 180)
			(size 0 0)
			(layers "B.Cu" "B.Mask" "B.Paste")
			(net "GND")
		)
	)
	(footprint ""
		(layer "B.Cu")
		(at 106.891074 -412.028386 90)
		(property "Reference" "C6"
			(at 0 0 90)
			(layer "B.SilkS")
			(hide yes)
			(effects
				(font
					(size 1.27 1.27)
				)
				(justify mirror)
			)
		)
		(property "Value" ""
			(at 0 0 90)
			(layer "B.Fab")
			(effects
				(font
					(size 1.27 1.27)
				)
				(justify mirror)
			)
		)
		(duplicate_pad_numbers_are_jumpers no)
		(fp_line
			(start 0.7874 -0.4064)
			(end -0.7874 -0.4064)
			(stroke
				(width 0.1524)
				(type default)
			)
			(layer "B.SilkS")
		)
		(fp_line
			(start -0.7874 -0.4064)
			(end -0.7874 0.4064)
			(stroke
				(width 0.1524)
				(type default)
			)
			(layer "B.SilkS")
		)
		(fp_line
			(start 0.7874 0.4064)
			(end 0.7874 -0.4064)
			(stroke
				(width 0.1524)
				(type default)
			)
			(layer "B.SilkS")
		)
		(fp_line
			(start -0.7874 0.4064)
			(end 0.7874 0.4064)
			(stroke
				(width 0.1524)
				(type default)
			)
			(layer "B.SilkS")
		)
		(fp_line
			(start 0.67945 -0.305054)
			(end 0.12065 -0.305054)
			(stroke
				(width 0.1)
				(type default)
			)
			(layer "B.Fab")
		)
		(fp_line
			(start 0.12065 -0.305054)
			(end 0.12065 -0.2794)
			(stroke
				(width 0.1)
				(type default)
			)
			(layer "B.Fab")
		)
		(fp_line
			(start -0.12065 -0.3048)
			(end -0.67945 -0.3048)
			(stroke
				(width 0.1)
				(type default)
			)
			(layer "B.Fab")
		)
		(fp_line
			(start -0.67945 -0.3048)
			(end -0.67945 0.3048)
			(stroke
				(width 0.1)
				(type default)
			)
			(layer "B.Fab")
		)
		(fp_line
			(start 0.12065 -0.2794)
			(end -0.12065 -0.2794)
			(stroke
				(width 0.1)
				(type default)
			)
			(layer "B.Fab")
		)
		(fp_line
			(start -0.12065 -0.2794)
			(end -0.12065 -0.3048)
			(stroke
				(width 0.1)
				(type default)
			)
			(layer "B.Fab")
		)
		(fp_line
			(start 0.12065 0.2794)
			(end 0.12065 0.3048)
			(stroke
				(width 0.1)
				(type default)
			)
			(layer "B.Fab")
		)
		(fp_line
			(start -0.120396 0.2794)
			(end 0.12065 0.2794)
			(stroke
				(width 0.1)
				(type default)
			)
			(layer "B.Fab")
		)
		(fp_line
			(start 0.67945 0.3048)
			(end 0.67945 -0.305054)
			(stroke
				(width 0.1)
				(type default)
			)
			(layer "B.Fab")
		)
		(fp_line
			(start 0.12065 0.3048)
			(end 0.67945 0.3048)
			(stroke
				(width 0.1)
				(type default)
			)
			(layer "B.Fab")
		)
		(fp_line
			(start -0.120396 0.3048)
			(end -0.120396 0.2794)
			(stroke
				(width 0.1)
				(type default)
			)
			(layer "B.Fab")
		)
		(fp_line
			(start -0.67945 0.3048)
			(end -0.120396 0.3048)
			(stroke
				(width 0.1)
				(type default)
			)
			(layer "B.Fab")
		)
		(pad "1" smd circle
			(at 0.40005 0 270)
			(size 0 0)
			(layers "B.Cu" "B.Mask" "B.Paste")
			(net "HGX_DETECT_N_ISO")
		)
		(pad "2" smd circle
			(at -0.40005 0 270)
			(size 0 0)
			(layers "B.Cu" "B.Mask" "B.Paste")
			(net "GND")
		)
	)
	(footprint ""
		(layer "B.Cu")
		(at 138.65352 -39.749222 180)
		(property "Reference" "C6059"
			(at 0 0 0)
			(layer "B.SilkS")
			(hide yes)
			(effects
				(font
					(size 1.27 1.27)
				)
				(justify mirror)
			)
		)
		(property "Value" ""
			(at 0 0 0)
			(layer "B.Fab")
			(effects
				(font
					(size 1.27 1.27)
				)
				(justify mirror)
			)
		)
		(duplicate_pad_numbers_are_jumpers no)
		(fp_line
			(start 0.7874 0.4064)
			(end 0.7874 -0.4064)
			(stroke
				(width 0.1524)
				(type default)
			)
			(layer "B.SilkS")
		)
		(fp_line
			(start 0.7874 -0.4064)
			(end -0.7874 -0.4064)
			(stroke
				(width 0.1524)
				(type default)
			)
			(layer "B.SilkS")
		)
		(fp_line
			(start -0.7874 0.4064)
			(end 0.7874 0.4064)
			(stroke
				(width 0.1524)
				(type default)
			)
			(layer "B.SilkS")
		)
		(fp_line
			(start -0.7874 -0.4064)
			(end -0.7874 0.4064)
			(stroke
				(width 0.1524)
				(type default)
			)
			(layer "B.SilkS")
		)
		(fp_line
			(start 0.67945 0.3048)
			(end 0.67945 -0.305054)
			(stroke
				(width 0.1)
				(type default)
			)
			(layer "B.Fab")
		)
		(fp_line
			(start 0.67945 -0.305054)
			(end 0.12065 -0.305054)
			(stroke
				(width 0.1)
				(type default)
			)
			(layer "B.Fab")
		)
		(fp_line
			(start 0.12065 0.3048)
			(end 0.67945 0.3048)
			(stroke
				(width 0.1)
				(type default)
			)
			(layer "B.Fab")
		)
		(fp_line
			(start 0.12065 0.2794)
			(end 0.12065 0.3048)
			(stroke
				(width 0.1)
				(type default)
			)
			(layer "B.Fab")
		)
		(fp_line
			(start 0.12065 -0.2794)
			(end -0.12065 -0.2794)
			(stroke
				(width 0.1)
				(type default)
			)
			(layer "B.Fab")
		)
		(fp_line
			(start 0.12065 -0.305054)
			(end 0.12065 -0.2794)
			(stroke
				(width 0.1)
				(type default)
			)
			(layer "B.Fab")
		)
		(fp_line
			(start -0.120396 0.3048)
			(end -0.120396 0.2794)
			(stroke
				(width 0.1)
				(type default)
			)
			(layer "B.Fab")
		)
		(fp_line
			(start -0.120396 0.2794)
			(end 0.12065 0.2794)
			(stroke
				(width 0.1)
				(type default)
			)
			(layer "B.Fab")
		)
		(fp_line
			(start -0.12065 -0.2794)
			(end -0.12065 -0.3048)
			(stroke
				(width 0.1)
				(type default)
			)
			(layer "B.Fab")
		)
		(fp_line
			(start -0.12065 -0.3048)
			(end -0.67945 -0.3048)
			(stroke
				(width 0.1)
				(type default)
			)
			(layer "B.Fab")
		)
		(fp_line
			(start -0.67945 0.3048)
			(end -0.120396 0.3048)
			(stroke
				(width 0.1)
				(type default)
			)
			(layer "B.Fab")
		)
		(fp_line
			(start -0.67945 -0.3048)
			(end -0.67945 0.3048)
			(stroke
				(width 0.1)
				(type default)
			)
			(layer "B.Fab")
		)
		(pad "1" smd circle
			(at 0.40005 0)
			(size 0 0)
			(layers "B.Cu" "B.Mask" "B.Paste")
			(net "P1V2_AUX")
		)
		(pad "2" smd circle
			(at -0.40005 0)
			(size 0 0)
			(layers "B.Cu" "B.Mask" "B.Paste")
			(net "GND")
		)
	)
	(footprint ""
		(layer "B.Cu")
		(at 412.74619 -396.393162 -90)
		(property "Reference" "C776"
			(at 0 0 90)
			(layer "B.SilkS")
			(hide yes)
			(effects
				(font
					(size 1.27 1.27)
				)
				(justify mirror)
			)
		)
		(property "Value" ""
			(at 0 0 90)
			(layer "B.Fab")
			(effects
				(font
					(size 1.27 1.27)
				)
				(justify mirror)
			)
		)
		(duplicate_pad_numbers_are_jumpers no)
		(fp_line
			(start -0.299974 0.150114)
			(end 0.299974 0.150114)
			(stroke
				(width 0.1)
				(type default)
			)
			(layer "B.Fab")
		)
		(fp_line
			(start 0.299974 0.150114)
			(end 0.299974 -0.150114)
			(stroke
				(width 0.1)
				(type default)
			)
			(layer "B.Fab")
		)
		(fp_line
			(start -0.299974 -0.150114)
			(end -0.299974 0.150114)
			(stroke
				(width 0.1)
				(type default)
			)
			(layer "B.Fab")
		)
		(fp_line
			(start 0.299974 -0.150114)
			(end -0.299974 -0.150114)
			(stroke
				(width 0.1)
				(type default)
			)
			(layer "B.Fab")
		)
		(pad "1" smd rect
			(at 0.2667 0 90)
			(size 0.3048 0.381)
			(layers "B.Cu" "B.Mask" "B.Paste")
			(net "P1V8_CPU0_RT2_1A")
		)
		(pad "2" smd rect
			(at -0.2667 0 90)
			(size 0.3048 0.381)
			(layers "B.Cu" "B.Mask" "B.Paste")
			(net "GND")
		)
	)
	(footprint ""
		(layer "B.Cu")
		(at 365.512858 -397.228568)
		(property "Reference" "C1033"
			(at 0 0 0)
			(layer "B.SilkS")
			(hide yes)
			(effects
				(font
					(size 1.27 1.27)
				)
				(justify mirror)
			)
		)
		(property "Value" ""
			(at 0 0 0)
			(layer "B.Fab")
			(effects
				(font
					(size 1.27 1.27)
				)
				(justify mirror)
			)
		)
		(duplicate_pad_numbers_are_jumpers no)
		(fp_line
			(start -1.524 -0.762)
			(end -1.524 0.762)
			(stroke
				(width 0.1524)
				(type default)
			)
			(layer "B.SilkS")
		)
		(fp_line
			(start -1.524 0.762)
			(end 1.524 0.762)
			(stroke
				(width 0.1524)
				(type default)
			)
			(layer "B.SilkS")
		)
		(fp_line
			(start 1.524 -0.762)
			(end -1.524 -0.762)
			(stroke
				(width 0.1524)
				(type default)
			)
			(layer "B.SilkS")
		)
		(fp_line
			(start 1.524 0.762)
			(end 1.524 -0.762)
			(stroke
				(width 0.1524)
				(type default)
			)
			(layer "B.SilkS")
		)
		(fp_line
			(start -1.1049 -0.724916)
			(end 1.1049 -0.724916)
			(stroke
				(width 0.1)
				(type default)
			)
			(layer "B.Fab")
		)
		(fp_line
			(start -1.1049 0.724916)
			(end -1.1049 -0.724916)
			(stroke
				(width 0.1)
				(type default)
			)
			(layer "B.Fab")
		)
		(fp_line
			(start 1.1049 -0.724916)
			(end 1.1049 0.724916)
			(stroke
				(width 0.1)
				(type default)
			)
			(layer "B.Fab")
		)
		(fp_line
			(start 1.1049 0.724916)
			(end -1.1049 0.724916)
			(stroke
				(width 0.1)
				(type default)
			)
			(layer "B.Fab")
		)
		(pad "1" smd rect
			(at 0.889 0)
			(size 1.016 1.27)
			(layers "B.Cu" "B.Mask" "B.Paste")
			(net "P0V9_CPU0_RT3_2A")
		)
		(pad "2" smd rect
			(at -0.889 0)
			(size 1.016 1.27)
			(layers "B.Cu" "B.Mask" "B.Paste")
			(net "GND")
		)
	)
	(footprint ""
		(layer "B.Cu")
		(at 114.491008 -390.560052 90)
		(property "Reference" "C480"
			(at 0 0 90)
			(layer "B.SilkS")
			(hide yes)
			(effects
				(font
					(size 1.27 1.27)
				)
				(justify mirror)
			)
		)
		(property "Value" ""
			(at 0 0 90)
			(layer "B.Fab")
			(effects
				(font
					(size 1.27 1.27)
				)
				(justify mirror)
			)
		)
		(duplicate_pad_numbers_are_jumpers no)
		(fp_line
			(start 0.7874 -0.4064)
			(end -0.7874 -0.4064)
			(stroke
				(width 0.1524)
				(type default)
			)
			(layer "B.SilkS")
		)
		(fp_line
			(start -0.7874 -0.4064)
			(end -0.7874 0.4064)
			(stroke
				(width 0.1524)
				(type default)
			)
			(layer "B.SilkS")
		)
		(fp_line
			(start 0.7874 0.4064)
			(end 0.7874 -0.4064)
			(stroke
				(width 0.1524)
				(type default)
			)
			(layer "B.SilkS")
		)
		(fp_line
			(start -0.7874 0.4064)
			(end 0.7874 0.4064)
			(stroke
				(width 0.1524)
				(type default)
			)
			(layer "B.SilkS")
		)
		(fp_line
			(start 0.67945 -0.305054)
			(end 0.12065 -0.305054)
			(stroke
				(width 0.1)
				(type default)
			)
			(layer "B.Fab")
		)
		(fp_line
			(start 0.12065 -0.305054)
			(end 0.12065 -0.2794)
			(stroke
				(width 0.1)
				(type default)
			)
			(layer "B.Fab")
		)
		(fp_line
			(start -0.12065 -0.3048)
			(end -0.67945 -0.3048)
			(stroke
				(width 0.1)
				(type default)
			)
			(layer "B.Fab")
		)
		(fp_line
			(start -0.67945 -0.3048)
			(end -0.67945 0.3048)
			(stroke
				(width 0.1)
				(type default)
			)
			(layer "B.Fab")
		)
		(fp_line
			(start 0.12065 -0.2794)
			(end -0.12065 -0.2794)
			(stroke
				(width 0.1)
				(type default)
			)
			(layer "B.Fab")
		)
		(fp_line
			(start -0.12065 -0.2794)
			(end -0.12065 -0.3048)
			(stroke
				(width 0.1)
				(type default)
			)
			(layer "B.Fab")
		)
		(fp_line
			(start 0.12065 0.2794)
			(end 0.12065 0.3048)
			(stroke
				(width 0.1)
				(type default)
			)
			(layer "B.Fab")
		)
		(fp_line
			(start -0.120396 0.2794)
			(end 0.12065 0.2794)
			(stroke
				(width 0.1)
				(type default)
			)
			(layer "B.Fab")
		)
		(fp_line
			(start 0.67945 0.3048)
			(end 0.67945 -0.305054)
			(stroke
				(width 0.1)
				(type default)
			)
			(layer "B.Fab")
		)
		(fp_line
			(start 0.12065 0.3048)
			(end 0.67945 0.3048)
			(stroke
				(width 0.1)
				(type default)
			)
			(layer "B.Fab")
		)
		(fp_line
			(start -0.120396 0.3048)
			(end -0.120396 0.2794)
			(stroke
				(width 0.1)
				(type default)
			)
			(layer "B.Fab")
		)
		(fp_line
			(start -0.67945 0.3048)
			(end -0.120396 0.3048)
			(stroke
				(width 0.1)
				(type default)
			)
			(layer "B.Fab")
		)
		(pad "1" smd circle
			(at 0.40005 0 270)
			(size 0 0)
			(layers "B.Cu" "B.Mask" "B.Paste")
			(net "P0V9_CPU1_RT3_2A")
		)
		(pad "2" smd circle
			(at -0.40005 0 270)
			(size 0 0)
			(layers "B.Cu" "B.Mask" "B.Paste")
			(net "GND")
		)
	)
	(footprint ""
		(layer "B.Cu")
		(at 35.09899 -424.772582)
		(property "Reference" "C1867"
			(at 0 0 0)
			(layer "B.SilkS")
			(hide yes)
			(effects
				(font
					(size 1.27 1.27)
				)
				(justify mirror)
			)
		)
		(property "Value" ""
			(at 0 0 0)
			(layer "B.Fab")
			(effects
				(font
					(size 1.27 1.27)
				)
				(justify mirror)
			)
		)
		(duplicate_pad_numbers_are_jumpers no)
		(fp_line
			(start -1.524 -0.762)
			(end -1.524 0.762)
			(stroke
				(width 0.1524)
				(type default)
			)
			(layer "B.SilkS")
		)
		(fp_line
			(start -1.524 0.762)
			(end 1.524 0.762)
			(stroke
				(width 0.1524)
				(type default)
			)
			(layer "B.SilkS")
		)
		(fp_line
			(start 1.524 -0.762)
			(end -1.524 -0.762)
			(stroke
				(width 0.1524)
				(type default)
			)
			(layer "B.SilkS")
		)
		(fp_line
			(start 1.524 0.762)
			(end 1.524 -0.762)
			(stroke
				(width 0.1524)
				(type default)
			)
			(layer "B.SilkS")
		)
		(fp_line
			(start -1.1049 -0.724916)
			(end 1.1049 -0.724916)
			(stroke
				(width 0.1)
				(type default)
			)
			(layer "B.Fab")
		)
		(fp_line
			(start -1.1049 0.724916)
			(end -1.1049 -0.724916)
			(stroke
				(width 0.1)
				(type default)
			)
			(layer "B.Fab")
		)
		(fp_line
			(start 1.1049 -0.724916)
			(end 1.1049 0.724916)
			(stroke
				(width 0.1)
				(type default)
			)
			(layer "B.Fab")
		)
		(fp_line
			(start 1.1049 0.724916)
			(end -1.1049 0.724916)
			(stroke
				(width 0.1)
				(type default)
			)
			(layer "B.Fab")
		)
		(pad "1" smd rect
			(at 0.889 0)
			(size 1.016 1.27)
			(layers "B.Cu" "B.Mask" "B.Paste")
			(net "P3V3_AUX")
		)
		(pad "2" smd rect
			(at -0.889 0)
			(size 1.016 1.27)
			(layers "B.Cu" "B.Mask" "B.Paste")
			(net "GND")
		)
	)
	(footprint ""
		(layer "B.Cu")
		(at 180.166518 -412.949644 -90)
		(property "Reference" "R2926"
			(at 0 0 90)
			(layer "B.SilkS")
			(hide yes)
			(effects
				(font
					(size 1.27 1.27)
				)
				(justify mirror)
			)
		)
		(property "Value" ""
			(at 0 0 90)
			(layer "B.Fab")
			(effects
				(font
					(size 1.27 1.27)
				)
				(justify mirror)
			)
		)
		(duplicate_pad_numbers_are_jumpers no)
		(fp_line
			(start -0.7874 0.4064)
			(end 0.7874 0.4064)
			(stroke
				(width 0.1524)
				(type default)
			)
			(layer "B.SilkS")
		)
		(fp_line
			(start 0.7874 0.4064)
			(end 0.7874 -0.4064)
			(stroke
				(width 0.1524)
				(type default)
			)
			(layer "B.SilkS")
		)
		(fp_line
			(start -0.7874 -0.4064)
			(end -0.7874 0.4064)
			(stroke
				(width 0.1524)
				(type default)
			)
			(layer "B.SilkS")
		)
		(fp_line
			(start 0.7874 -0.4064)
			(end -0.7874 -0.4064)
			(stroke
				(width 0.1524)
				(type default)
			)
			(layer "B.SilkS")
		)
		(fp_line
			(start -0.67945 0.3048)
			(end -0.120396 0.3048)
			(stroke
				(width 0.1)
				(type default)
			)
			(layer "B.Fab")
		)
		(fp_line
			(start -0.120396 0.3048)
			(end -0.120396 0.2794)
			(stroke
				(width 0.1)
				(type default)
			)
			(layer "B.Fab")
		)
		(fp_line
			(start 0.12065 0.3048)
			(end 0.67945 0.3048)
			(stroke
				(width 0.1)
				(type default)
			)
			(layer "B.Fab")
		)
		(fp_line
			(start 0.67945 0.3048)
			(end 0.67945 -0.305054)
			(stroke
				(width 0.1)
				(type default)
			)
			(layer "B.Fab")
		)
		(fp_line
			(start -0.120396 0.2794)
			(end 0.12065 0.2794)
			(stroke
				(width 0.1)
				(type default)
			)
			(layer "B.Fab")
		)
		(fp_line
			(start 0.12065 0.2794)
			(end 0.12065 0.3048)
			(stroke
				(width 0.1)
				(type default)
			)
			(layer "B.Fab")
		)
		(fp_line
			(start -0.12065 -0.2794)
			(end -0.12065 -0.3048)
			(stroke
				(width 0.1)
				(type default)
			)
			(layer "B.Fab")
		)
		(fp_line
			(start 0.12065 -0.2794)
			(end -0.12065 -0.2794)
			(stroke
				(width 0.1)
				(type default)
			)
			(layer "B.Fab")
		)
		(fp_line
			(start -0.67945 -0.3048)
			(end -0.67945 0.3048)
			(stroke
				(width 0.1)
				(type default)
			)
			(layer "B.Fab")
		)
		(fp_line
			(start -0.12065 -0.3048)
			(end -0.67945 -0.3048)
			(stroke
				(width 0.1)
				(type default)
			)
			(layer "B.Fab")
		)
		(fp_line
			(start 0.12065 -0.305054)
			(end 0.12065 -0.2794)
			(stroke
				(width 0.1)
				(type default)
			)
			(layer "B.Fab")
		)
		(fp_line
			(start 0.67945 -0.305054)
			(end 0.12065 -0.305054)
			(stroke
				(width 0.1)
				(type default)
			)
			(layer "B.Fab")
		)
		(pad "1" smd circle
			(at 0.40005 0 90)
			(size 0 0)
			(layers "B.Cu" "B.Mask" "B.Paste")
			(net "BMC_MONITER_BUF_R")
		)
		(pad "2" smd circle
			(at -0.40005 0 90)
			(size 0 0)
			(layers "B.Cu" "B.Mask" "B.Paste")
			(net "GND")
		)
	)
	(footprint ""
		(layer "B.Cu")
		(at 352.247454 -251.78131)
		(property "Reference" "C2588"
			(at 0 0 0)
			(layer "B.SilkS")
			(hide yes)
			(effects
				(font
					(size 1.27 1.27)
				)
				(justify mirror)
			)
		)
		(property "Value" ""
			(at 0 0 0)
			(layer "B.Fab")
			(effects
				(font
					(size 1.27 1.27)
				)
				(justify mirror)
			)
		)
		(duplicate_pad_numbers_are_jumpers no)
		(fp_line
			(start -0.7874 -0.4064)
			(end -0.7874 0.4064)
			(stroke
				(width 0.1524)
				(type default)
			)
			(layer "B.SilkS")
		)
		(fp_line
			(start -0.7874 0.4064)
			(end 0.7874 0.4064)
			(stroke
				(width 0.1524)
				(type default)
			)
			(layer "B.SilkS")
		)
		(fp_line
			(start 0.7874 -0.4064)
			(end -0.7874 -0.4064)
			(stroke
				(width 0.1524)
				(type default)
			)
			(layer "B.SilkS")
		)
		(fp_line
			(start 0.7874 0.4064)
			(end 0.7874 -0.4064)
			(stroke
				(width 0.1524)
				(type default)
			)
			(layer "B.SilkS")
		)
		(fp_line
			(start -0.67945 -0.3048)
			(end -0.67945 0.3048)
			(stroke
				(width 0.1)
				(type default)
			)
			(layer "B.Fab")
		)
		(fp_line
			(start -0.67945 0.3048)
			(end -0.120396 0.3048)
			(stroke
				(width 0.1)
				(type default)
			)
			(layer "B.Fab")
		)
		(fp_line
			(start -0.12065 -0.3048)
			(end -0.67945 -0.3048)
			(stroke
				(width 0.1)
				(type default)
			)
			(layer "B.Fab")
		)
		(fp_line
			(start -0.12065 -0.2794)
			(end -0.12065 -0.3048)
			(stroke
				(width 0.1)
				(type default)
			)
			(layer "B.Fab")
		)
		(fp_line
			(start -0.120396 0.2794)
			(end 0.12065 0.2794)
			(stroke
				(width 0.1)
				(type default)
			)
			(layer "B.Fab")
		)
		(fp_line
			(start -0.120396 0.3048)
			(end -0.120396 0.2794)
			(stroke
				(width 0.1)
				(type default)
			)
			(layer "B.Fab")
		)
		(fp_line
			(start 0.12065 -0.305054)
			(end 0.12065 -0.2794)
			(stroke
				(width 0.1)
				(type default)
			)
			(layer "B.Fab")
		)
		(fp_line
			(start 0.12065 -0.2794)
			(end -0.12065 -0.2794)
			(stroke
				(width 0.1)
				(type default)
			)
			(layer "B.Fab")
		)
		(fp_line
			(start 0.12065 0.2794)
			(end 0.12065 0.3048)
			(stroke
				(width 0.1)
				(type default)
			)
			(layer "B.Fab")
		)
		(fp_line
			(start 0.12065 0.3048)
			(end 0.67945 0.3048)
			(stroke
				(width 0.1)
				(type default)
			)
			(layer "B.Fab")
		)
		(fp_line
			(start 0.67945 -0.305054)
			(end 0.12065 -0.305054)
			(stroke
				(width 0.1)
				(type default)
			)
			(layer "B.Fab")
		)
		(fp_line
			(start 0.67945 0.3048)
			(end 0.67945 -0.305054)
			(stroke
				(width 0.1)
				(type default)
			)
			(layer "B.Fab")
		)
		(pad "1" smd circle
			(at 0.40005 0 180)
			(size 0 0)
			(layers "B.Cu" "B.Mask" "B.Paste")
			(net "PVDDCR_SOC_P0")
		)
		(pad "2" smd circle
			(at -0.40005 0 180)
			(size 0 0)
			(layers "B.Cu" "B.Mask" "B.Paste")
			(net "GND")
		)
	)
	(footprint ""
		(layer "B.Cu")
		(at 48.618902 -421.460676)
		(property "Reference" "Q96"
			(at 0.70104 -1.773682 0)
			(unlocked yes)
			(layer "B.SilkS")
			(effects
				(font
					(size 0.7874 0.5842)
					(thickness 0.1524)
				)
				(justify left mirror)
			)
		)
		(property "Value" ""
			(at 0 0 0)
			(layer "B.Fab")
			(effects
				(font
					(size 1.27 1.27)
				)
				(justify mirror)
			)
		)
		(duplicate_pad_numbers_are_jumpers no)
		(fp_line
			(start -1.332738 -1.100074)
			(end -1.332738 1.100074)
			(stroke
				(width 0.1524)
				(type default)
			)
			(layer "B.SilkS")
		)
		(fp_line
			(start -1.332738 1.100074)
			(end 1.332738 1.100074)
			(stroke
				(width 0.1524)
				(type default)
			)
			(layer "B.SilkS")
		)
		(fp_line
			(start -0.4826 -1.100074)
			(end -1.332738 -1.100074)
			(stroke
				(width 0.1524)
				(type default)
			)
			(layer "B.SilkS")
		)
		(fp_line
			(start 0 -0.541274)
			(end -0.4826 -1.100074)
			(stroke
				(width 0.1524)
				(type default)
			)
			(layer "B.SilkS")
		)
		(fp_line
			(start 0.4826 -1.100074)
			(end 0 -0.541274)
			(stroke
				(width 0.1524)
				(type default)
			)
			(layer "B.SilkS")
		)
		(fp_line
			(start 1.332738 -1.100074)
			(end 0.4826 -1.100074)
			(stroke
				(width 0.1524)
				(type default)
			)
			(layer "B.SilkS")
		)
		(fp_line
			(start 1.332738 1.100074)
			(end 1.332738 -1.100074)
			(stroke
				(width 0.1524)
				(type default)
			)
			(layer "B.SilkS")
		)
		(fp_poly
			(pts
				(xy 1.039114 -1.794002) (xy 1.373378 -2.504186) (xy 0.671576 -2.487676)
			)
			(stroke
				(width 0)
				(type default)
			)
			(fill yes)
			(layer "B.SilkS")
		)
		(fp_line
			(start -0.674878 -1.100074)
			(end -0.674878 1.100074)
			(stroke
				(width 0.1)
				(type default)
			)
			(layer "B.Fab")
		)
		(fp_line
			(start -0.674878 1.100074)
			(end 0.674878 1.100074)
			(stroke
				(width 0.1)
				(type default)
			)
			(layer "B.Fab")
		)
		(fp_line
			(start 0.674878 -1.100074)
			(end -0.674878 -1.100074)
			(stroke
				(width 0.1)
				(type default)
			)
			(layer "B.Fab")
		)
		(fp_line
			(start 0.674878 1.100074)
			(end 0.674878 -1.100074)
			(stroke
				(width 0.1)
				(type default)
			)
			(layer "B.Fab")
		)
		(fp_poly
			(pts
				(xy 2.2352 -0.298958) (xy 2.2352 -1.001014) (xy 1.533144 -0.649986)
			)
			(stroke
				(width 0)
				(type default)
			)
			(fill yes)
			(layer "B.Fab")
		)
		(pad "1" smd rect
			(at 0.94996 -0.649986 90)
			(size 0.4318 0.508)
			(layers "B.Cu" "B.Mask" "B.Paste")
			(net "GND")
		)
		(pad "2" smd rect
			(at 0.94996 0 90)
			(size 0.4318 0.508)
			(layers "B.Cu" "B.Mask" "B.Paste")
			(net "GPU_FPGA_READY")
		)
		(pad "3" smd rect
			(at 0.94996 0.649986 90)
			(size 0.4318 0.508)
			(layers "B.Cu" "B.Mask" "B.Paste")
			(net "GPU_FPGA_READY_ISO")
		)
		(pad "4" smd rect
			(at -0.94996 0.649986 90)
			(size 0.4318 0.508)
			(layers "B.Cu" "B.Mask" "B.Paste")
			(net "GND")
		)
		(pad "5" smd rect
			(at -0.94996 0 90)
			(size 0.4318 0.508)
			(layers "B.Cu" "B.Mask" "B.Paste")
			(net "GPU_FPGA_READY_N")
		)
		(pad "6" smd rect
			(at -0.94996 -0.649986 90)
			(size 0.4318 0.508)
			(layers "B.Cu" "B.Mask" "B.Paste")
			(net "GPU_FPGA_READY_N")
		)
	)
	(footprint ""
		(layer "B.Cu")
		(at 254.635 -330.962 180)
		(property "Reference" "R850"
			(at 0 0 0)
			(layer "B.SilkS")
			(hide yes)
			(effects
				(font
					(size 1.27 1.27)
				)
				(justify mirror)
			)
		)
		(property "Value" ""
			(at 0 0 0)
			(layer "B.Fab")
			(effects
				(font
					(size 1.27 1.27)
				)
				(justify mirror)
			)
		)
		(duplicate_pad_numbers_are_jumpers no)
		(fp_line
			(start 0.32512 0.175006)
			(end 0.32512 -0.175006)
			(stroke
				(width 0.1)
				(type default)
			)
			(layer "B.Fab")
		)
		(fp_line
			(start 0.32512 -0.175006)
			(end -0.32512 -0.175006)
			(stroke
				(width 0.1)
				(type default)
			)
			(layer "B.Fab")
		)
		(fp_line
			(start -0.32512 0.175006)
			(end 0.32512 0.175006)
			(stroke
				(width 0.1)
				(type default)
			)
			(layer "B.Fab")
		)
		(fp_line
			(start -0.32512 -0.175006)
			(end -0.32512 0.175006)
			(stroke
				(width 0.1)
				(type default)
			)
			(layer "B.Fab")
		)
		(pad "1" smd rect
			(at 0.2667 0)
			(size 0.3048 0.381)
			(layers "B.Cu" "B.Mask" "B.Paste")
			(net "SMB_MUX_RT_ROM_SDA")
		)
		(pad "2" smd rect
			(at -0.2667 0 180)
			(size 0.3048 0.381)
			(layers "B.Cu" "B.Mask" "B.Paste")
			(net "SMB_MUX_RT_ROM_R1_SDA")
		)
	)
	(footprint ""
		(layer "B.Cu")
		(at 68.098162 -336.059272 -90)
		(property "Reference" "PR265"
			(at 0 0 90)
			(layer "B.SilkS")
			(hide yes)
			(effects
				(font
					(size 1.27 1.27)
				)
				(justify mirror)
			)
		)
		(property "Value" ""
			(at 0 0 90)
			(layer "B.Fab")
			(effects
				(font
					(size 1.27 1.27)
				)
				(justify mirror)
			)
		)
		(duplicate_pad_numbers_are_jumpers no)
		(fp_line
			(start -0.7874 0.4064)
			(end 0.7874 0.4064)
			(stroke
				(width 0.1524)
				(type default)
			)
			(layer "B.SilkS")
		)
		(fp_line
			(start 0.7874 0.4064)
			(end 0.7874 -0.4064)
			(stroke
				(width 0.1524)
				(type default)
			)
			(layer "B.SilkS")
		)
		(fp_line
			(start -0.7874 -0.4064)
			(end -0.7874 0.4064)
			(stroke
				(width 0.1524)
				(type default)
			)
			(layer "B.SilkS")
		)
		(fp_line
			(start 0.7874 -0.4064)
			(end -0.7874 -0.4064)
			(stroke
				(width 0.1524)
				(type default)
			)
			(layer "B.SilkS")
		)
		(fp_line
			(start -0.67945 0.3048)
			(end -0.120396 0.3048)
			(stroke
				(width 0.1)
				(type default)
			)
			(layer "B.Fab")
		)
		(fp_line
			(start -0.120396 0.3048)
			(end -0.120396 0.2794)
			(stroke
				(width 0.1)
				(type default)
			)
			(layer "B.Fab")
		)
		(fp_line
			(start 0.12065 0.3048)
			(end 0.67945 0.3048)
			(stroke
				(width 0.1)
				(type default)
			)
			(layer "B.Fab")
		)
		(fp_line
			(start 0.67945 0.3048)
			(end 0.67945 -0.305054)
			(stroke
				(width 0.1)
				(type default)
			)
			(layer "B.Fab")
		)
		(fp_line
			(start -0.120396 0.2794)
			(end 0.12065 0.2794)
			(stroke
				(width 0.1)
				(type default)
			)
			(layer "B.Fab")
		)
		(fp_line
			(start 0.12065 0.2794)
			(end 0.12065 0.3048)
			(stroke
				(width 0.1)
				(type default)
			)
			(layer "B.Fab")
		)
		(fp_line
			(start -0.12065 -0.2794)
			(end -0.12065 -0.3048)
			(stroke
				(width 0.1)
				(type default)
			)
			(layer "B.Fab")
		)
		(fp_line
			(start 0.12065 -0.2794)
			(end -0.12065 -0.2794)
			(stroke
				(width 0.1)
				(type default)
			)
			(layer "B.Fab")
		)
		(fp_line
			(start -0.67945 -0.3048)
			(end -0.67945 0.3048)
			(stroke
				(width 0.1)
				(type default)
			)
			(layer "B.Fab")
		)
		(fp_line
			(start -0.12065 -0.3048)
			(end -0.67945 -0.3048)
			(stroke
				(width 0.1)
				(type default)
			)
			(layer "B.Fab")
		)
		(fp_line
			(start 0.12065 -0.305054)
			(end 0.12065 -0.2794)
			(stroke
				(width 0.1)
				(type default)
			)
			(layer "B.Fab")
		)
		(fp_line
			(start 0.67945 -0.305054)
			(end 0.12065 -0.305054)
			(stroke
				(width 0.1)
				(type default)
			)
			(layer "B.Fab")
		)
		(pad "1" smd circle
			(at 0.40005 0 90)
			(size 0 0)
			(layers "B.Cu" "B.Mask" "B.Paste")
			(net "PVDDCR_CPU1_P1_PVCC")
		)
		(pad "2" smd circle
			(at -0.40005 0 90)
			(size 0 0)
			(layers "B.Cu" "B.Mask" "B.Paste")
			(net "PVDDCR_CPU1_P1_VCC3")
		)
	)
	(footprint ""
		(layer "B.Cu")
		(at 186.758834 -342.261952 -90)
		(property "Reference" "PC527_2"
			(at 0 0 90)
			(layer "B.SilkS")
			(hide yes)
			(effects
				(font
					(size 1.27 1.27)
				)
				(justify mirror)
			)
		)
		(property "Value" ""
			(at 0 0 90)
			(layer "B.Fab")
			(effects
				(font
					(size 1.27 1.27)
				)
				(justify mirror)
			)
		)
		(duplicate_pad_numbers_are_jumpers no)
		(fp_line
			(start -1.524 0.762)
			(end 1.524 0.762)
			(stroke
				(width 0.1524)
				(type default)
			)
			(layer "B.SilkS")
		)
		(fp_line
			(start 1.524 0.762)
			(end 1.524 -0.762)
			(stroke
				(width 0.1524)
				(type default)
			)
			(layer "B.SilkS")
		)
		(fp_line
			(start -1.524 -0.762)
			(end -1.524 0.762)
			(stroke
				(width 0.1524)
				(type default)
			)
			(layer "B.SilkS")
		)
		(fp_line
			(start 1.524 -0.762)
			(end -1.524 -0.762)
			(stroke
				(width 0.1524)
				(type default)
			)
			(layer "B.SilkS")
		)
		(fp_line
			(start -1.1049 0.724916)
			(end -1.1049 -0.724916)
			(stroke
				(width 0.1)
				(type default)
			)
			(layer "B.Fab")
		)
		(fp_line
			(start 1.1049 0.724916)
			(end -1.1049 0.724916)
			(stroke
				(width 0.1)
				(type default)
			)
			(layer "B.Fab")
		)
		(fp_line
			(start -1.1049 -0.724916)
			(end 1.1049 -0.724916)
			(stroke
				(width 0.1)
				(type default)
			)
			(layer "B.Fab")
		)
		(fp_line
			(start 1.1049 -0.724916)
			(end 1.1049 0.724916)
			(stroke
				(width 0.1)
				(type default)
			)
			(layer "B.Fab")
		)
		(pad "1" smd rect
			(at 0.889 0 270)
			(size 1.016 1.27)
			(layers "B.Cu" "B.Mask" "B.Paste")
			(net "PVDD11_S3_P1")
		)
		(pad "2" smd rect
			(at -0.889 0 270)
			(size 1.016 1.27)
			(layers "B.Cu" "B.Mask" "B.Paste")
			(net "GND")
		)
	)
	(footprint ""
		(layer "B.Cu")
		(at 384.113278 -142.234158 180)
		(property "Reference" "PC472"
			(at 0 0 0)
			(layer "B.SilkS")
			(hide yes)
			(effects
				(font
					(size 1.27 1.27)
				)
				(justify mirror)
			)
		)
		(property "Value" ""
			(at 0 0 0)
			(layer "B.Fab")
			(effects
				(font
					(size 1.27 1.27)
				)
				(justify mirror)
			)
		)
		(duplicate_pad_numbers_are_jumpers no)
		(fp_line
			(start 0.7874 0.4064)
			(end 0.7874 -0.4064)
			(stroke
				(width 0.1524)
				(type default)
			)
			(layer "B.SilkS")
		)
		(fp_line
			(start 0.7874 -0.4064)
			(end -0.7874 -0.4064)
			(stroke
				(width 0.1524)
				(type default)
			)
			(layer "B.SilkS")
		)
		(fp_line
			(start -0.7874 0.4064)
			(end 0.7874 0.4064)
			(stroke
				(width 0.1524)
				(type default)
			)
			(layer "B.SilkS")
		)
		(fp_line
			(start -0.7874 -0.4064)
			(end -0.7874 0.4064)
			(stroke
				(width 0.1524)
				(type default)
			)
			(layer "B.SilkS")
		)
		(fp_line
			(start 0.67945 0.3048)
			(end 0.67945 -0.305054)
			(stroke
				(width 0.1)
				(type default)
			)
			(layer "B.Fab")
		)
		(fp_line
			(start 0.67945 -0.305054)
			(end 0.12065 -0.305054)
			(stroke
				(width 0.1)
				(type default)
			)
			(layer "B.Fab")
		)
		(fp_line
			(start 0.12065 0.3048)
			(end 0.67945 0.3048)
			(stroke
				(width 0.1)
				(type default)
			)
			(layer "B.Fab")
		)
		(fp_line
			(start 0.12065 0.2794)
			(end 0.12065 0.3048)
			(stroke
				(width 0.1)
				(type default)
			)
			(layer "B.Fab")
		)
		(fp_line
			(start 0.12065 -0.2794)
			(end -0.12065 -0.2794)
			(stroke
				(width 0.1)
				(type default)
			)
			(layer "B.Fab")
		)
		(fp_line
			(start 0.12065 -0.305054)
			(end 0.12065 -0.2794)
			(stroke
				(width 0.1)
				(type default)
			)
			(layer "B.Fab")
		)
		(fp_line
			(start -0.120396 0.3048)
			(end -0.120396 0.2794)
			(stroke
				(width 0.1)
				(type default)
			)
			(layer "B.Fab")
		)
		(fp_line
			(start -0.120396 0.2794)
			(end 0.12065 0.2794)
			(stroke
				(width 0.1)
				(type default)
			)
			(layer "B.Fab")
		)
		(fp_line
			(start -0.12065 -0.2794)
			(end -0.12065 -0.3048)
			(stroke
				(width 0.1)
				(type default)
			)
			(layer "B.Fab")
		)
		(fp_line
			(start -0.12065 -0.3048)
			(end -0.67945 -0.3048)
			(stroke
				(width 0.1)
				(type default)
			)
			(layer "B.Fab")
		)
		(fp_line
			(start -0.67945 0.3048)
			(end -0.120396 0.3048)
			(stroke
				(width 0.1)
				(type default)
			)
			(layer "B.Fab")
		)
		(fp_line
			(start -0.67945 -0.3048)
			(end -0.67945 0.3048)
			(stroke
				(width 0.1)
				(type default)
			)
			(layer "B.Fab")
		)
		(pad "1" smd circle
			(at 0.40005 0)
			(size 0 0)
			(layers "B.Cu" "B.Mask" "B.Paste")
			(net "PVDDCR_SOC_P0_TEMP1")
		)
		(pad "2" smd circle
			(at -0.40005 0)
			(size 0 0)
			(layers "B.Cu" "B.Mask" "B.Paste")
			(net "GND")
		)
	)
	(footprint ""
		(layer "B.Cu")
		(at 124.173234 -269.313152 180)
		(property "Reference" "C2363"
			(at 0 0 0)
			(layer "B.SilkS")
			(hide yes)
			(effects
				(font
					(size 1.27 1.27)
				)
				(justify mirror)
			)
		)
		(property "Value" ""
			(at 0 0 0)
			(layer "B.Fab")
			(effects
				(font
					(size 1.27 1.27)
				)
				(justify mirror)
			)
		)
		(duplicate_pad_numbers_are_jumpers no)
		(fp_line
			(start 0.7874 0.4064)
			(end 0.7874 -0.4064)
			(stroke
				(width 0.1524)
				(type default)
			)
			(layer "B.SilkS")
		)
		(fp_line
			(start 0.7874 -0.4064)
			(end -0.7874 -0.4064)
			(stroke
				(width 0.1524)
				(type default)
			)
			(layer "B.SilkS")
		)
		(fp_line
			(start -0.7874 0.4064)
			(end 0.7874 0.4064)
			(stroke
				(width 0.1524)
				(type default)
			)
			(layer "B.SilkS")
		)
		(fp_line
			(start -0.7874 -0.4064)
			(end -0.7874 0.4064)
			(stroke
				(width 0.1524)
				(type default)
			)
			(layer "B.SilkS")
		)
		(fp_line
			(start 0.67945 0.3048)
			(end 0.67945 -0.305054)
			(stroke
				(width 0.1)
				(type default)
			)
			(layer "B.Fab")
		)
		(fp_line
			(start 0.67945 -0.305054)
			(end 0.12065 -0.305054)
			(stroke
				(width 0.1)
				(type default)
			)
			(layer "B.Fab")
		)
		(fp_line
			(start 0.12065 0.3048)
			(end 0.67945 0.3048)
			(stroke
				(width 0.1)
				(type default)
			)
			(layer "B.Fab")
		)
		(fp_line
			(start 0.12065 0.2794)
			(end 0.12065 0.3048)
			(stroke
				(width 0.1)
				(type default)
			)
			(layer "B.Fab")
		)
		(fp_line
			(start 0.12065 -0.2794)
			(end -0.12065 -0.2794)
			(stroke
				(width 0.1)
				(type default)
			)
			(layer "B.Fab")
		)
		(fp_line
			(start 0.12065 -0.305054)
			(end 0.12065 -0.2794)
			(stroke
				(width 0.1)
				(type default)
			)
			(layer "B.Fab")
		)
		(fp_line
			(start -0.120396 0.3048)
			(end -0.120396 0.2794)
			(stroke
				(width 0.1)
				(type default)
			)
			(layer "B.Fab")
		)
		(fp_line
			(start -0.120396 0.2794)
			(end 0.12065 0.2794)
			(stroke
				(width 0.1)
				(type default)
			)
			(layer "B.Fab")
		)
		(fp_line
			(start -0.12065 -0.2794)
			(end -0.12065 -0.3048)
			(stroke
				(width 0.1)
				(type default)
			)
			(layer "B.Fab")
		)
		(fp_line
			(start -0.12065 -0.3048)
			(end -0.67945 -0.3048)
			(stroke
				(width 0.1)
				(type default)
			)
			(layer "B.Fab")
		)
		(fp_line
			(start -0.67945 0.3048)
			(end -0.120396 0.3048)
			(stroke
				(width 0.1)
				(type default)
			)
			(layer "B.Fab")
		)
		(fp_line
			(start -0.67945 -0.3048)
			(end -0.67945 0.3048)
			(stroke
				(width 0.1)
				(type default)
			)
			(layer "B.Fab")
		)
		(pad "1" smd circle
			(at 0.40005 0)
			(size 0 0)
			(layers "B.Cu" "B.Mask" "B.Paste")
			(net "PVDDCR_CPU1_P1")
		)
		(pad "2" smd circle
			(at -0.40005 0)
			(size 0 0)
			(layers "B.Cu" "B.Mask" "B.Paste")
			(net "GND")
		)
	)
	(footprint ""
		(layer "B.Cu")
		(at 230.6828 -338.582 180)
		(property "Reference" "R6757"
			(at 0 0 0)
			(layer "B.SilkS")
			(hide yes)
			(effects
				(font
					(size 1.27 1.27)
				)
				(justify mirror)
			)
		)
		(property "Value" ""
			(at 0 0 0)
			(layer "B.Fab")
			(effects
				(font
					(size 1.27 1.27)
				)
				(justify mirror)
			)
		)
		(duplicate_pad_numbers_are_jumpers no)
		(fp_line
			(start 0.32512 0.175006)
			(end 0.32512 -0.175006)
			(stroke
				(width 0.1)
				(type default)
			)
			(layer "B.Fab")
		)
		(fp_line
			(start 0.32512 -0.175006)
			(end -0.32512 -0.175006)
			(stroke
				(width 0.1)
				(type default)
			)
			(layer "B.Fab")
		)
		(fp_line
			(start -0.32512 0.175006)
			(end 0.32512 0.175006)
			(stroke
				(width 0.1)
				(type default)
			)
			(layer "B.Fab")
		)
		(fp_line
			(start -0.32512 -0.175006)
			(end -0.32512 0.175006)
			(stroke
				(width 0.1)
				(type default)
			)
			(layer "B.Fab")
		)
		(pad "1" smd rect
			(at 0.2667 0)
			(size 0.3048 0.381)
			(layers "B.Cu" "B.Mask" "B.Paste")
			(net "SMB_RT_CPU0_P1_SCL")
		)
		(pad "2" smd rect
			(at -0.2667 0 180)
			(size 0.3048 0.381)
			(layers "B.Cu" "B.Mask" "B.Paste")
			(net "SMB_RT_CPU0_P1_R_SCL")
		)
	)
	(footprint ""
		(layer "B.Cu")
		(at 301.48657 -346.784168 90)
		(property "Reference" "PC152_1"
			(at 0 0 90)
			(layer "B.SilkS")
			(hide yes)
			(effects
				(font
					(size 1.27 1.27)
				)
				(justify mirror)
			)
		)
		(property "Value" ""
			(at 0 0 90)
			(layer "B.Fab")
			(effects
				(font
					(size 1.27 1.27)
				)
				(justify mirror)
			)
		)
		(duplicate_pad_numbers_are_jumpers no)
		(fp_line
			(start 1.524 -0.762)
			(end -1.524 -0.762)
			(stroke
				(width 0.1524)
				(type default)
			)
			(layer "B.SilkS")
		)
		(fp_line
			(start -1.524 -0.762)
			(end -1.524 0.762)
			(stroke
				(width 0.1524)
				(type default)
			)
			(layer "B.SilkS")
		)
		(fp_line
			(start 1.524 0.762)
			(end 1.524 -0.762)
			(stroke
				(width 0.1524)
				(type default)
			)
			(layer "B.SilkS")
		)
		(fp_line
			(start -1.524 0.762)
			(end 1.524 0.762)
			(stroke
				(width 0.1524)
				(type default)
			)
			(layer "B.SilkS")
		)
		(fp_line
			(start 1.1049 -0.724916)
			(end 1.1049 0.724916)
			(stroke
				(width 0.1)
				(type default)
			)
			(layer "B.Fab")
		)
		(fp_line
			(start -1.1049 -0.724916)
			(end 1.1049 -0.724916)
			(stroke
				(width 0.1)
				(type default)
			)
			(layer "B.Fab")
		)
		(fp_line
			(start 1.1049 0.724916)
			(end -1.1049 0.724916)
			(stroke
				(width 0.1)
				(type default)
			)
			(layer "B.Fab")
		)
		(fp_line
			(start -1.1049 0.724916)
			(end -1.1049 -0.724916)
			(stroke
				(width 0.1)
				(type default)
			)
			(layer "B.Fab")
		)
		(pad "1" smd rect
			(at 0.889 0 90)
			(size 1.016 1.27)
			(layers "B.Cu" "B.Mask" "B.Paste")
			(net "SW_P12V_AUX_PVDDIO_P0_FLT")
		)
		(pad "2" smd rect
			(at -0.889 0 90)
			(size 1.016 1.27)
			(layers "B.Cu" "B.Mask" "B.Paste")
			(net "GND")
		)
	)
	(footprint ""
		(layer "B.Cu")
		(at 338.859876 -66.708782 90)
		(property "Reference" "R3094"
			(at 0 0 90)
			(layer "B.SilkS")
			(hide yes)
			(effects
				(font
					(size 1.27 1.27)
				)
				(justify mirror)
			)
		)
		(property "Value" ""
			(at 0 0 90)
			(layer "B.Fab")
			(effects
				(font
					(size 1.27 1.27)
				)
				(justify mirror)
			)
		)
		(duplicate_pad_numbers_are_jumpers no)
		(fp_line
			(start 0.7874 -0.4064)
			(end -0.7874 -0.4064)
			(stroke
				(width 0.1524)
				(type default)
			)
			(layer "B.SilkS")
		)
		(fp_line
			(start -0.7874 -0.4064)
			(end -0.7874 0.4064)
			(stroke
				(width 0.1524)
				(type default)
			)
			(layer "B.SilkS")
		)
		(fp_line
			(start 0.7874 0.4064)
			(end 0.7874 -0.4064)
			(stroke
				(width 0.1524)
				(type default)
			)
			(layer "B.SilkS")
		)
		(fp_line
			(start -0.7874 0.4064)
			(end 0.7874 0.4064)
			(stroke
				(width 0.1524)
				(type default)
			)
			(layer "B.SilkS")
		)
		(fp_line
			(start 0.67945 -0.305054)
			(end 0.12065 -0.305054)
			(stroke
				(width 0.1)
				(type default)
			)
			(layer "B.Fab")
		)
		(fp_line
			(start 0.12065 -0.305054)
			(end 0.12065 -0.2794)
			(stroke
				(width 0.1)
				(type default)
			)
			(layer "B.Fab")
		)
		(fp_line
			(start -0.12065 -0.3048)
			(end -0.67945 -0.3048)
			(stroke
				(width 0.1)
				(type default)
			)
			(layer "B.Fab")
		)
		(fp_line
			(start -0.67945 -0.3048)
			(end -0.67945 0.3048)
			(stroke
				(width 0.1)
				(type default)
			)
			(layer "B.Fab")
		)
		(fp_line
			(start 0.12065 -0.2794)
			(end -0.12065 -0.2794)
			(stroke
				(width 0.1)
				(type default)
			)
			(layer "B.Fab")
		)
		(fp_line
			(start -0.12065 -0.2794)
			(end -0.12065 -0.3048)
			(stroke
				(width 0.1)
				(type default)
			)
			(layer "B.Fab")
		)
		(fp_line
			(start 0.12065 0.2794)
			(end 0.12065 0.3048)
			(stroke
				(width 0.1)
				(type default)
			)
			(layer "B.Fab")
		)
		(fp_line
			(start -0.120396 0.2794)
			(end 0.12065 0.2794)
			(stroke
				(width 0.1)
				(type default)
			)
			(layer "B.Fab")
		)
		(fp_line
			(start 0.67945 0.3048)
			(end 0.67945 -0.305054)
			(stroke
				(width 0.1)
				(type default)
			)
			(layer "B.Fab")
		)
		(fp_line
			(start 0.12065 0.3048)
			(end 0.67945 0.3048)
			(stroke
				(width 0.1)
				(type default)
			)
			(layer "B.Fab")
		)
		(fp_line
			(start -0.120396 0.3048)
			(end -0.120396 0.2794)
			(stroke
				(width 0.1)
				(type default)
			)
			(layer "B.Fab")
		)
		(fp_line
			(start -0.67945 0.3048)
			(end -0.120396 0.3048)
			(stroke
				(width 0.1)
				(type default)
			)
			(layer "B.Fab")
		)
		(pad "1" smd circle
			(at 0.40005 0 270)
			(size 0 0)
			(layers "B.Cu" "B.Mask" "B.Paste")
			(net "LED_PWRGD_PVDDCR_SOC_P1_R")
		)
		(pad "2" smd circle
			(at -0.40005 0 270)
			(size 0 0)
			(layers "B.Cu" "B.Mask" "B.Paste")
			(net "P3V3_AUX")
		)
	)
	(footprint ""
		(layer "B.Cu")
		(at 359.833926 -416.923474 180)
		(property "Reference" "C1774"
			(at 0 0 0)
			(layer "B.SilkS")
			(hide yes)
			(effects
				(font
					(size 1.27 1.27)
				)
				(justify mirror)
			)
		)
		(property "Value" ""
			(at 0 0 0)
			(layer "B.Fab")
			(effects
				(font
					(size 1.27 1.27)
				)
				(justify mirror)
			)
		)
		(duplicate_pad_numbers_are_jumpers no)
		(fp_line
			(start 0.7874 0.4064)
			(end 0.7874 -0.4064)
			(stroke
				(width 0.1524)
				(type default)
			)
			(layer "B.SilkS")
		)
		(fp_line
			(start 0.7874 -0.4064)
			(end -0.7874 -0.4064)
			(stroke
				(width 0.1524)
				(type default)
			)
			(layer "B.SilkS")
		)
		(fp_line
			(start -0.7874 0.4064)
			(end 0.7874 0.4064)
			(stroke
				(width 0.1524)
				(type default)
			)
			(layer "B.SilkS")
		)
		(fp_line
			(start -0.7874 -0.4064)
			(end -0.7874 0.4064)
			(stroke
				(width 0.1524)
				(type default)
			)
			(layer "B.SilkS")
		)
		(fp_line
			(start 0.67945 0.3048)
			(end 0.67945 -0.305054)
			(stroke
				(width 0.1)
				(type default)
			)
			(layer "B.Fab")
		)
		(fp_line
			(start 0.67945 -0.305054)
			(end 0.12065 -0.305054)
			(stroke
				(width 0.1)
				(type default)
			)
			(layer "B.Fab")
		)
		(fp_line
			(start 0.12065 0.3048)
			(end 0.67945 0.3048)
			(stroke
				(width 0.1)
				(type default)
			)
			(layer "B.Fab")
		)
		(fp_line
			(start 0.12065 0.2794)
			(end 0.12065 0.3048)
			(stroke
				(width 0.1)
				(type default)
			)
			(layer "B.Fab")
		)
		(fp_line
			(start 0.12065 -0.2794)
			(end -0.12065 -0.2794)
			(stroke
				(width 0.1)
				(type default)
			)
			(layer "B.Fab")
		)
		(fp_line
			(start 0.12065 -0.305054)
			(end 0.12065 -0.2794)
			(stroke
				(width 0.1)
				(type default)
			)
			(layer "B.Fab")
		)
		(fp_line
			(start -0.120396 0.3048)
			(end -0.120396 0.2794)
			(stroke
				(width 0.1)
				(type default)
			)
			(layer "B.Fab")
		)
		(fp_line
			(start -0.120396 0.2794)
			(end 0.12065 0.2794)
			(stroke
				(width 0.1)
				(type default)
			)
			(layer "B.Fab")
		)
		(fp_line
			(start -0.12065 -0.2794)
			(end -0.12065 -0.3048)
			(stroke
				(width 0.1)
				(type default)
			)
			(layer "B.Fab")
		)
		(fp_line
			(start -0.12065 -0.3048)
			(end -0.67945 -0.3048)
			(stroke
				(width 0.1)
				(type default)
			)
			(layer "B.Fab")
		)
		(fp_line
			(start -0.67945 0.3048)
			(end -0.120396 0.3048)
			(stroke
				(width 0.1)
				(type default)
			)
			(layer "B.Fab")
		)
		(fp_line
			(start -0.67945 -0.3048)
			(end -0.67945 0.3048)
			(stroke
				(width 0.1)
				(type default)
			)
			(layer "B.Fab")
		)
		(pad "1" smd circle
			(at 0.40005 0)
			(size 0 0)
			(layers "B.Cu" "B.Mask" "B.Paste")
			(net "FM_SWB_PWRGD_ISO")
		)
		(pad "2" smd circle
			(at -0.40005 0)
			(size 0 0)
			(layers "B.Cu" "B.Mask" "B.Paste")
			(net "GND")
		)
	)
	(footprint ""
		(layer "B.Cu")
		(at 362.265976 -256.012188 -90)
		(property "Reference" "C2543"
			(at 0 0 90)
			(layer "B.SilkS")
			(hide yes)
			(effects
				(font
					(size 1.27 1.27)
				)
				(justify mirror)
			)
		)
		(property "Value" ""
			(at 0 0 90)
			(layer "B.Fab")
			(effects
				(font
					(size 1.27 1.27)
				)
				(justify mirror)
			)
		)
		(duplicate_pad_numbers_are_jumpers no)
		(fp_line
			(start -0.7874 0.4064)
			(end 0.7874 0.4064)
			(stroke
				(width 0.1524)
				(type default)
			)
			(layer "B.SilkS")
		)
		(fp_line
			(start 0.7874 0.4064)
			(end 0.7874 -0.4064)
			(stroke
				(width 0.1524)
				(type default)
			)
			(layer "B.SilkS")
		)
		(fp_line
			(start -0.7874 -0.4064)
			(end -0.7874 0.4064)
			(stroke
				(width 0.1524)
				(type default)
			)
			(layer "B.SilkS")
		)
		(fp_line
			(start 0.7874 -0.4064)
			(end -0.7874 -0.4064)
			(stroke
				(width 0.1524)
				(type default)
			)
			(layer "B.SilkS")
		)
		(fp_line
			(start -0.67945 0.3048)
			(end -0.120396 0.3048)
			(stroke
				(width 0.1)
				(type default)
			)
			(layer "B.Fab")
		)
		(fp_line
			(start -0.120396 0.3048)
			(end -0.120396 0.2794)
			(stroke
				(width 0.1)
				(type default)
			)
			(layer "B.Fab")
		)
		(fp_line
			(start 0.12065 0.3048)
			(end 0.67945 0.3048)
			(stroke
				(width 0.1)
				(type default)
			)
			(layer "B.Fab")
		)
		(fp_line
			(start 0.67945 0.3048)
			(end 0.67945 -0.305054)
			(stroke
				(width 0.1)
				(type default)
			)
			(layer "B.Fab")
		)
		(fp_line
			(start -0.120396 0.2794)
			(end 0.12065 0.2794)
			(stroke
				(width 0.1)
				(type default)
			)
			(layer "B.Fab")
		)
		(fp_line
			(start 0.12065 0.2794)
			(end 0.12065 0.3048)
			(stroke
				(width 0.1)
				(type default)
			)
			(layer "B.Fab")
		)
		(fp_line
			(start -0.12065 -0.2794)
			(end -0.12065 -0.3048)
			(stroke
				(width 0.1)
				(type default)
			)
			(layer "B.Fab")
		)
		(fp_line
			(start 0.12065 -0.2794)
			(end -0.12065 -0.2794)
			(stroke
				(width 0.1)
				(type default)
			)
			(layer "B.Fab")
		)
		(fp_line
			(start -0.67945 -0.3048)
			(end -0.67945 0.3048)
			(stroke
				(width 0.1)
				(type default)
			)
			(layer "B.Fab")
		)
		(fp_line
			(start -0.12065 -0.3048)
			(end -0.67945 -0.3048)
			(stroke
				(width 0.1)
				(type default)
			)
			(layer "B.Fab")
		)
		(fp_line
			(start 0.12065 -0.305054)
			(end 0.12065 -0.2794)
			(stroke
				(width 0.1)
				(type default)
			)
			(layer "B.Fab")
		)
		(fp_line
			(start 0.67945 -0.305054)
			(end 0.12065 -0.305054)
			(stroke
				(width 0.1)
				(type default)
			)
			(layer "B.Fab")
		)
		(pad "1" smd circle
			(at 0.40005 0 90)
			(size 0 0)
			(layers "B.Cu" "B.Mask" "B.Paste")
			(net "PVDDCR_SOC_P0")
		)
		(pad "2" smd circle
			(at -0.40005 0 90)
			(size 0 0)
			(layers "B.Cu" "B.Mask" "B.Paste")
			(net "GND")
		)
	)
	(footprint ""
		(layer "B.Cu")
		(at 422.2115 -395.148562 90)
		(property "Reference" "C979"
			(at 0 0 90)
			(layer "B.SilkS")
			(hide yes)
			(effects
				(font
					(size 1.27 1.27)
				)
				(justify mirror)
			)
		)
		(property "Value" ""
			(at 0 0 90)
			(layer "B.Fab")
			(effects
				(font
					(size 1.27 1.27)
				)
				(justify mirror)
			)
		)
		(duplicate_pad_numbers_are_jumpers no)
		(fp_line
			(start 0.299974 -0.150114)
			(end -0.299974 -0.150114)
			(stroke
				(width 0.1)
				(type default)
			)
			(layer "B.Fab")
		)
		(fp_line
			(start -0.299974 -0.150114)
			(end -0.299974 0.150114)
			(stroke
				(width 0.1)
				(type default)
			)
			(layer "B.Fab")
		)
		(fp_line
			(start 0.299974 0.150114)
			(end 0.299974 -0.150114)
			(stroke
				(width 0.1)
				(type default)
			)
			(layer "B.Fab")
		)
		(fp_line
			(start -0.299974 0.150114)
			(end 0.299974 0.150114)
			(stroke
				(width 0.1)
				(type default)
			)
			(layer "B.Fab")
		)
		(pad "1" smd rect
			(at 0.2667 0 270)
			(size 0.3048 0.381)
			(layers "B.Cu" "B.Mask" "B.Paste")
			(net "P0V9_CPU0_RT2_2A")
		)
		(pad "2" smd rect
			(at -0.2667 0 270)
			(size 0.3048 0.381)
			(layers "B.Cu" "B.Mask" "B.Paste")
			(net "GND")
		)
	)
	(footprint ""
		(layer "B.Cu")
		(at 347.008958 -252.54331 180)
		(property "Reference" "C2516"
			(at 0 0 0)
			(layer "B.SilkS")
			(hide yes)
			(effects
				(font
					(size 1.27 1.27)
				)
				(justify mirror)
			)
		)
		(property "Value" ""
			(at 0 0 0)
			(layer "B.Fab")
			(effects
				(font
					(size 1.27 1.27)
				)
				(justify mirror)
			)
		)
		(duplicate_pad_numbers_are_jumpers no)
		(fp_line
			(start 0.7874 0.4064)
			(end 0.7874 -0.4064)
			(stroke
				(width 0.1524)
				(type default)
			)
			(layer "B.SilkS")
		)
		(fp_line
			(start 0.7874 -0.4064)
			(end -0.7874 -0.4064)
			(stroke
				(width 0.1524)
				(type default)
			)
			(layer "B.SilkS")
		)
		(fp_line
			(start -0.7874 0.4064)
			(end 0.7874 0.4064)
			(stroke
				(width 0.1524)
				(type default)
			)
			(layer "B.SilkS")
		)
		(fp_line
			(start -0.7874 -0.4064)
			(end -0.7874 0.4064)
			(stroke
				(width 0.1524)
				(type default)
			)
			(layer "B.SilkS")
		)
		(fp_line
			(start 0.67945 0.3048)
			(end 0.67945 -0.305054)
			(stroke
				(width 0.1)
				(type default)
			)
			(layer "B.Fab")
		)
		(fp_line
			(start 0.67945 -0.305054)
			(end 0.12065 -0.305054)
			(stroke
				(width 0.1)
				(type default)
			)
			(layer "B.Fab")
		)
		(fp_line
			(start 0.12065 0.3048)
			(end 0.67945 0.3048)
			(stroke
				(width 0.1)
				(type default)
			)
			(layer "B.Fab")
		)
		(fp_line
			(start 0.12065 0.2794)
			(end 0.12065 0.3048)
			(stroke
				(width 0.1)
				(type default)
			)
			(layer "B.Fab")
		)
		(fp_line
			(start 0.12065 -0.2794)
			(end -0.12065 -0.2794)
			(stroke
				(width 0.1)
				(type default)
			)
			(layer "B.Fab")
		)
		(fp_line
			(start 0.12065 -0.305054)
			(end 0.12065 -0.2794)
			(stroke
				(width 0.1)
				(type default)
			)
			(layer "B.Fab")
		)
		(fp_line
			(start -0.120396 0.3048)
			(end -0.120396 0.2794)
			(stroke
				(width 0.1)
				(type default)
			)
			(layer "B.Fab")
		)
		(fp_line
			(start -0.120396 0.2794)
			(end 0.12065 0.2794)
			(stroke
				(width 0.1)
				(type default)
			)
			(layer "B.Fab")
		)
		(fp_line
			(start -0.12065 -0.2794)
			(end -0.12065 -0.3048)
			(stroke
				(width 0.1)
				(type default)
			)
			(layer "B.Fab")
		)
		(fp_line
			(start -0.12065 -0.3048)
			(end -0.67945 -0.3048)
			(stroke
				(width 0.1)
				(type default)
			)
			(layer "B.Fab")
		)
		(fp_line
			(start -0.67945 0.3048)
			(end -0.120396 0.3048)
			(stroke
				(width 0.1)
				(type default)
			)
			(layer "B.Fab")
		)
		(fp_line
			(start -0.67945 -0.3048)
			(end -0.67945 0.3048)
			(stroke
				(width 0.1)
				(type default)
			)
			(layer "B.Fab")
		)
		(pad "1" smd circle
			(at 0.40005 0)
			(size 0 0)
			(layers "B.Cu" "B.Mask" "B.Paste")
			(net "PVDD18_S5_P0")
		)
		(pad "2" smd circle
			(at -0.40005 0)
			(size 0 0)
			(layers "B.Cu" "B.Mask" "B.Paste")
			(net "GND")
		)
	)
	(footprint ""
		(layer "B.Cu")
		(at 182.332376 -116.242846 180)
		(property "Reference" "C1172"
			(at 0 0 0)
			(layer "B.SilkS")
			(hide yes)
			(effects
				(font
					(size 1.27 1.27)
				)
				(justify mirror)
			)
		)
		(property "Value" ""
			(at 0 0 0)
			(layer "B.Fab")
			(effects
				(font
					(size 1.27 1.27)
				)
				(justify mirror)
			)
		)
		(duplicate_pad_numbers_are_jumpers no)
		(fp_line
			(start 0.69215 0.2921)
			(end 0.69215 -0.2921)
			(stroke
				(width 0.1524)
				(type default)
			)
			(layer "B.SilkS")
		)
		(fp_line
			(start 0.69215 -0.2921)
			(end -0.69215 -0.2921)
			(stroke
				(width 0.1524)
				(type default)
			)
			(layer "B.SilkS")
		)
		(fp_line
			(start -0.69215 0.2921)
			(end 0.69215 0.2921)
			(stroke
				(width 0.1524)
				(type default)
			)
			(layer "B.SilkS")
		)
		(fp_line
			(start -0.69215 -0.2921)
			(end -0.69215 0.2921)
			(stroke
				(width 0.1524)
				(type default)
			)
			(layer "B.SilkS")
		)
		(fp_line
			(start 0.51435 0.2794)
			(end 0.51435 -0.2794)
			(stroke
				(width 0.1)
				(type default)
			)
			(layer "B.Fab")
		)
		(fp_line
			(start 0.51435 -0.2794)
			(end -0.51435 -0.2794)
			(stroke
				(width 0.1)
				(type default)
			)
			(layer "B.Fab")
		)
		(fp_line
			(start -0.51435 0.2794)
			(end 0.51435 0.2794)
			(stroke
				(width 0.1)
				(type default)
			)
			(layer "B.Fab")
		)
		(fp_line
			(start -0.51435 -0.2794)
			(end -0.51435 0.2794)
			(stroke
				(width 0.1)
				(type default)
			)
			(layer "B.Fab")
		)
		(pad "1" smd circle
			(at 0.40005 0)
			(size 0 0)
			(layers "B.Cu" "B.Mask" "B.Paste")
			(net "P3V3_AUX")
		)
		(pad "2" smd circle
			(at -0.40005 0)
			(size 0 0)
			(layers "B.Cu" "B.Mask" "B.Paste")
			(net "GND")
		)
		(zone
			(layer "B.Cu")
			(hatch none 0.5)
			(connect_pads
				(clearance 0)
			)
			(min_thickness 0.25)
			(keepout
				(tracks not_allowed)
				(vias allowed)
				(pads allowed)
				(copperpour not_allowed)
				(footprints allowed)
			)
			(placement
				(enabled no)
				(sheetname "")
			)
			(fill
				(thermal_gap 0.5)
				(thermal_bridge_width 0.5)
				(island_removal_mode 0)
			)
			(polygon
				(pts
					(xy 182.141876 -116.154962) (xy 182.141876 -116.330476) (xy 182.233316 -116.388642) (xy 182.432706 -116.388642)
					(xy 182.522876 -116.330476) (xy 182.522876 -116.155216) (xy 182.432706 -116.096796) (xy 182.233316 -116.096796)
				)
			)
		)
	)
	(footprint ""
		(layer "B.Cu")
		(at 319.467484 -335.063084 90)
		(property "Reference" "PC120_3"
			(at 0 0 90)
			(layer "B.SilkS")
			(hide yes)
			(effects
				(font
					(size 1.27 1.27)
				)
				(justify mirror)
			)
		)
		(property "Value" ""
			(at 0 0 90)
			(layer "B.Fab")
			(effects
				(font
					(size 1.27 1.27)
				)
				(justify mirror)
			)
		)
		(duplicate_pad_numbers_are_jumpers no)
		(fp_line
			(start 1.524 -0.762)
			(end -1.524 -0.762)
			(stroke
				(width 0.1524)
				(type default)
			)
			(layer "B.SilkS")
		)
		(fp_line
			(start -1.524 -0.762)
			(end -1.524 0.762)
			(stroke
				(width 0.1524)
				(type default)
			)
			(layer "B.SilkS")
		)
		(fp_line
			(start 1.524 0.762)
			(end 1.524 -0.762)
			(stroke
				(width 0.1524)
				(type default)
			)
			(layer "B.SilkS")
		)
		(fp_line
			(start -1.524 0.762)
			(end 1.524 0.762)
			(stroke
				(width 0.1524)
				(type default)
			)
			(layer "B.SilkS")
		)
		(fp_line
			(start 1.1049 -0.724916)
			(end 1.1049 0.724916)
			(stroke
				(width 0.1)
				(type default)
			)
			(layer "B.Fab")
		)
		(fp_line
			(start -1.1049 -0.724916)
			(end 1.1049 -0.724916)
			(stroke
				(width 0.1)
				(type default)
			)
			(layer "B.Fab")
		)
		(fp_line
			(start 1.1049 0.724916)
			(end -1.1049 0.724916)
			(stroke
				(width 0.1)
				(type default)
			)
			(layer "B.Fab")
		)
		(fp_line
			(start -1.1049 0.724916)
			(end -1.1049 -0.724916)
			(stroke
				(width 0.1)
				(type default)
			)
			(layer "B.Fab")
		)
		(pad "1" smd rect
			(at 0.889 0 90)
			(size 1.016 1.27)
			(layers "B.Cu" "B.Mask" "B.Paste")
			(net "SW_P12V_AUX_PVDDCR_CPU1_P0_FLT")
		)
		(pad "2" smd rect
			(at -0.889 0 90)
			(size 1.016 1.27)
			(layers "B.Cu" "B.Mask" "B.Paste")
			(net "GND")
		)
	)
	(footprint ""
		(layer "B.Cu")
		(at 158.440628 -16.553942 180)
		(property "Reference" "R331"
			(at 0 0 0)
			(layer "B.SilkS")
			(hide yes)
			(effects
				(font
					(size 1.27 1.27)
				)
				(justify mirror)
			)
		)
		(property "Value" ""
			(at 0 0 0)
			(layer "B.Fab")
			(effects
				(font
					(size 1.27 1.27)
				)
				(justify mirror)
			)
		)
		(duplicate_pad_numbers_are_jumpers no)
		(fp_line
			(start 0.7874 0.4064)
			(end 0.7874 -0.4064)
			(stroke
				(width 0.1524)
				(type default)
			)
			(layer "B.SilkS")
		)
		(fp_line
			(start 0.7874 -0.4064)
			(end -0.7874 -0.4064)
			(stroke
				(width 0.1524)
				(type default)
			)
			(layer "B.SilkS")
		)
		(fp_line
			(start -0.7874 0.4064)
			(end 0.7874 0.4064)
			(stroke
				(width 0.1524)
				(type default)
			)
			(layer "B.SilkS")
		)
		(fp_line
			(start -0.7874 -0.4064)
			(end -0.7874 0.4064)
			(stroke
				(width 0.1524)
				(type default)
			)
			(layer "B.SilkS")
		)
		(fp_line
			(start 0.67945 0.3048)
			(end 0.67945 -0.305054)
			(stroke
				(width 0.1)
				(type default)
			)
			(layer "B.Fab")
		)
		(fp_line
			(start 0.67945 -0.305054)
			(end 0.12065 -0.305054)
			(stroke
				(width 0.1)
				(type default)
			)
			(layer "B.Fab")
		)
		(fp_line
			(start 0.12065 0.3048)
			(end 0.67945 0.3048)
			(stroke
				(width 0.1)
				(type default)
			)
			(layer "B.Fab")
		)
		(fp_line
			(start 0.12065 0.2794)
			(end 0.12065 0.3048)
			(stroke
				(width 0.1)
				(type default)
			)
			(layer "B.Fab")
		)
		(fp_line
			(start 0.12065 -0.2794)
			(end -0.12065 -0.2794)
			(stroke
				(width 0.1)
				(type default)
			)
			(layer "B.Fab")
		)
		(fp_line
			(start 0.12065 -0.305054)
			(end 0.12065 -0.2794)
			(stroke
				(width 0.1)
				(type default)
			)
			(layer "B.Fab")
		)
		(fp_line
			(start -0.120396 0.3048)
			(end -0.120396 0.2794)
			(stroke
				(width 0.1)
				(type default)
			)
			(layer "B.Fab")
		)
		(fp_line
			(start -0.120396 0.2794)
			(end 0.12065 0.2794)
			(stroke
				(width 0.1)
				(type default)
			)
			(layer "B.Fab")
		)
		(fp_line
			(start -0.12065 -0.2794)
			(end -0.12065 -0.3048)
			(stroke
				(width 0.1)
				(type default)
			)
			(layer "B.Fab")
		)
		(fp_line
			(start -0.12065 -0.3048)
			(end -0.67945 -0.3048)
			(stroke
				(width 0.1)
				(type default)
			)
			(layer "B.Fab")
		)
		(fp_line
			(start -0.67945 0.3048)
			(end -0.120396 0.3048)
			(stroke
				(width 0.1)
				(type default)
			)
			(layer "B.Fab")
		)
		(fp_line
			(start -0.67945 -0.3048)
			(end -0.67945 0.3048)
			(stroke
				(width 0.1)
				(type default)
			)
			(layer "B.Fab")
		)
		(pad "1" smd circle
			(at 0.40005 0)
			(size 0 0)
			(layers "B.Cu" "B.Mask" "B.Paste")
			(net "SMB_FAN_3V3AUX_SDA")
		)
		(pad "2" smd circle
			(at -0.40005 0)
			(size 0 0)
			(layers "B.Cu" "B.Mask" "B.Paste")
			(net "P3V3_AUX")
		)
	)
	(footprint ""
		(layer "B.Cu")
		(at 180.271928 -193.996564)
		(property "Reference" "R112"
			(at 0 0 0)
			(layer "B.SilkS")
			(hide yes)
			(effects
				(font
					(size 1.27 1.27)
				)
				(justify mirror)
			)
		)
		(property "Value" ""
			(at 0 0 0)
			(layer "B.Fab")
			(effects
				(font
					(size 1.27 1.27)
				)
				(justify mirror)
			)
		)
		(duplicate_pad_numbers_are_jumpers no)
		(fp_line
			(start -0.7874 -0.4064)
			(end -0.7874 0.4064)
			(stroke
				(width 0.1524)
				(type default)
			)
			(layer "B.SilkS")
		)
		(fp_line
			(start -0.7874 0.4064)
			(end 0.7874 0.4064)
			(stroke
				(width 0.1524)
				(type default)
			)
			(layer "B.SilkS")
		)
		(fp_line
			(start 0.7874 -0.4064)
			(end -0.7874 -0.4064)
			(stroke
				(width 0.1524)
				(type default)
			)
			(layer "B.SilkS")
		)
		(fp_line
			(start 0.7874 0.4064)
			(end 0.7874 -0.4064)
			(stroke
				(width 0.1524)
				(type default)
			)
			(layer "B.SilkS")
		)
		(fp_line
			(start -0.67945 -0.3048)
			(end -0.67945 0.3048)
			(stroke
				(width 0.1)
				(type default)
			)
			(layer "B.Fab")
		)
		(fp_line
			(start -0.67945 0.3048)
			(end -0.120396 0.3048)
			(stroke
				(width 0.1)
				(type default)
			)
			(layer "B.Fab")
		)
		(fp_line
			(start -0.12065 -0.3048)
			(end -0.67945 -0.3048)
			(stroke
				(width 0.1)
				(type default)
			)
			(layer "B.Fab")
		)
		(fp_line
			(start -0.12065 -0.2794)
			(end -0.12065 -0.3048)
			(stroke
				(width 0.1)
				(type default)
			)
			(layer "B.Fab")
		)
		(fp_line
			(start -0.120396 0.2794)
			(end 0.12065 0.2794)
			(stroke
				(width 0.1)
				(type default)
			)
			(layer "B.Fab")
		)
		(fp_line
			(start -0.120396 0.3048)
			(end -0.120396 0.2794)
			(stroke
				(width 0.1)
				(type default)
			)
			(layer "B.Fab")
		)
		(fp_line
			(start 0.12065 -0.305054)
			(end 0.12065 -0.2794)
			(stroke
				(width 0.1)
				(type default)
			)
			(layer "B.Fab")
		)
		(fp_line
			(start 0.12065 -0.2794)
			(end -0.12065 -0.2794)
			(stroke
				(width 0.1)
				(type default)
			)
			(layer "B.Fab")
		)
		(fp_line
			(start 0.12065 0.2794)
			(end 0.12065 0.3048)
			(stroke
				(width 0.1)
				(type default)
			)
			(layer "B.Fab")
		)
		(fp_line
			(start 0.12065 0.3048)
			(end 0.67945 0.3048)
			(stroke
				(width 0.1)
				(type default)
			)
			(layer "B.Fab")
		)
		(fp_line
			(start 0.67945 -0.305054)
			(end 0.12065 -0.305054)
			(stroke
				(width 0.1)
				(type default)
			)
			(layer "B.Fab")
		)
		(fp_line
			(start 0.67945 0.3048)
			(end 0.67945 -0.305054)
			(stroke
				(width 0.1)
				(type default)
			)
			(layer "B.Fab")
		)
		(pad "1" smd circle
			(at 0.40005 0 180)
			(size 0 0)
			(layers "B.Cu" "B.Mask" "B.Paste")
			(net "P3V3")
		)
		(pad "2" smd circle
			(at -0.40005 0 180)
			(size 0 0)
			(layers "B.Cu" "B.Mask" "B.Paste")
			(net "PWRGD_CHI_CPU1_DIMM")
		)
	)
	(footprint ""
		(layer "B.Cu")
		(at 208.461356 -386.152136)
		(property "Reference" "PR2516"
			(at 0 0 0)
			(layer "B.SilkS")
			(hide yes)
			(effects
				(font
					(size 1.27 1.27)
				)
				(justify mirror)
			)
		)
		(property "Value" ""
			(at 0 0 0)
			(layer "B.Fab")
			(effects
				(font
					(size 1.27 1.27)
				)
				(justify mirror)
			)
		)
		(duplicate_pad_numbers_are_jumpers no)
		(fp_line
			(start -0.7874 -0.4064)
			(end -0.7874 0.4064)
			(stroke
				(width 0.1524)
				(type default)
			)
			(layer "B.SilkS")
		)
		(fp_line
			(start -0.7874 0.4064)
			(end 0.7874 0.4064)
			(stroke
				(width 0.1524)
				(type default)
			)
			(layer "B.SilkS")
		)
		(fp_line
			(start 0.7874 -0.4064)
			(end -0.7874 -0.4064)
			(stroke
				(width 0.1524)
				(type default)
			)
			(layer "B.SilkS")
		)
		(fp_line
			(start 0.7874 0.4064)
			(end 0.7874 -0.4064)
			(stroke
				(width 0.1524)
				(type default)
			)
			(layer "B.SilkS")
		)
		(fp_line
			(start -0.67945 -0.3048)
			(end -0.67945 0.3048)
			(stroke
				(width 0.1)
				(type default)
			)
			(layer "B.Fab")
		)
		(fp_line
			(start -0.67945 0.3048)
			(end -0.120396 0.3048)
			(stroke
				(width 0.1)
				(type default)
			)
			(layer "B.Fab")
		)
		(fp_line
			(start -0.12065 -0.3048)
			(end -0.67945 -0.3048)
			(stroke
				(width 0.1)
				(type default)
			)
			(layer "B.Fab")
		)
		(fp_line
			(start -0.12065 -0.2794)
			(end -0.12065 -0.3048)
			(stroke
				(width 0.1)
				(type default)
			)
			(layer "B.Fab")
		)
		(fp_line
			(start -0.120396 0.2794)
			(end 0.12065 0.2794)
			(stroke
				(width 0.1)
				(type default)
			)
			(layer "B.Fab")
		)
		(fp_line
			(start -0.120396 0.3048)
			(end -0.120396 0.2794)
			(stroke
				(width 0.1)
				(type default)
			)
			(layer "B.Fab")
		)
		(fp_line
			(start 0.12065 -0.305054)
			(end 0.12065 -0.2794)
			(stroke
				(width 0.1)
				(type default)
			)
			(layer "B.Fab")
		)
		(fp_line
			(start 0.12065 -0.2794)
			(end -0.12065 -0.2794)
			(stroke
				(width 0.1)
				(type default)
			)
			(layer "B.Fab")
		)
		(fp_line
			(start 0.12065 0.2794)
			(end 0.12065 0.3048)
			(stroke
				(width 0.1)
				(type default)
			)
			(layer "B.Fab")
		)
		(fp_line
			(start 0.12065 0.3048)
			(end 0.67945 0.3048)
			(stroke
				(width 0.1)
				(type default)
			)
			(layer "B.Fab")
		)
		(fp_line
			(start 0.67945 -0.305054)
			(end 0.12065 -0.305054)
			(stroke
				(width 0.1)
				(type default)
			)
			(layer "B.Fab")
		)
		(fp_line
			(start 0.67945 0.3048)
			(end 0.67945 -0.305054)
			(stroke
				(width 0.1)
				(type default)
			)
			(layer "B.Fab")
		)
		(pad "1" smd circle
			(at 0.40005 0 180)
			(size 0 0)
			(layers "B.Cu" "B.Mask" "B.Paste")
			(net "P12V_HSC_ADC_N")
		)
		(pad "2" smd circle
			(at -0.40005 0 180)
			(size 0 0)
			(layers "B.Cu" "B.Mask" "B.Paste")
			(net "P12V_HSC_SENSE2_R2_N")
		)
	)
	(footprint ""
		(layer "B.Cu")
		(at 254.635 -335.13268 180)
		(property "Reference" "R1382"
			(at 0 0 0)
			(layer "B.SilkS")
			(hide yes)
			(effects
				(font
					(size 1.27 1.27)
				)
				(justify mirror)
			)
		)
		(property "Value" ""
			(at 0 0 0)
			(layer "B.Fab")
			(effects
				(font
					(size 1.27 1.27)
				)
				(justify mirror)
			)
		)
		(duplicate_pad_numbers_are_jumpers no)
		(fp_line
			(start 0.32512 0.175006)
			(end 0.32512 -0.175006)
			(stroke
				(width 0.1)
				(type default)
			)
			(layer "B.Fab")
		)
		(fp_line
			(start 0.32512 -0.175006)
			(end -0.32512 -0.175006)
			(stroke
				(width 0.1)
				(type default)
			)
			(layer "B.Fab")
		)
		(fp_line
			(start -0.32512 0.175006)
			(end 0.32512 0.175006)
			(stroke
				(width 0.1)
				(type default)
			)
			(layer "B.Fab")
		)
		(fp_line
			(start -0.32512 -0.175006)
			(end -0.32512 0.175006)
			(stroke
				(width 0.1)
				(type default)
			)
			(layer "B.Fab")
		)
		(pad "1" smd rect
			(at 0.2667 0)
			(size 0.3048 0.381)
			(layers "B.Cu" "B.Mask" "B.Paste")
			(net "P1V8_CPU0_RT_1D")
		)
		(pad "2" smd rect
			(at -0.2667 0 180)
			(size 0.3048 0.381)
			(layers "B.Cu" "B.Mask" "B.Paste")
			(net "SMB_RT_CPU0_P2_ROM_MUX_2D_R_SDA")
		)
	)
	(footprint ""
		(layer "B.Cu")
		(at 418.191188 -161.102548 90)
		(property "Reference" "PR367"
			(at 0 0 90)
			(layer "B.SilkS")
			(hide yes)
			(effects
				(font
					(size 1.27 1.27)
				)
				(justify mirror)
			)
		)
		(property "Value" ""
			(at 0 0 90)
			(layer "B.Fab")
			(effects
				(font
					(size 1.27 1.27)
				)
				(justify mirror)
			)
		)
		(duplicate_pad_numbers_are_jumpers no)
		(fp_line
			(start 0.7874 -0.4064)
			(end -0.7874 -0.4064)
			(stroke
				(width 0.1524)
				(type default)
			)
			(layer "B.SilkS")
		)
		(fp_line
			(start -0.7874 -0.4064)
			(end -0.7874 0.4064)
			(stroke
				(width 0.1524)
				(type default)
			)
			(layer "B.SilkS")
		)
		(fp_line
			(start 0.7874 0.4064)
			(end 0.7874 -0.4064)
			(stroke
				(width 0.1524)
				(type default)
			)
			(layer "B.SilkS")
		)
		(fp_line
			(start -0.7874 0.4064)
			(end 0.7874 0.4064)
			(stroke
				(width 0.1524)
				(type default)
			)
			(layer "B.SilkS")
		)
		(fp_line
			(start 0.67945 -0.305054)
			(end 0.12065 -0.305054)
			(stroke
				(width 0.1)
				(type default)
			)
			(layer "B.Fab")
		)
		(fp_line
			(start 0.12065 -0.305054)
			(end 0.12065 -0.2794)
			(stroke
				(width 0.1)
				(type default)
			)
			(layer "B.Fab")
		)
		(fp_line
			(start -0.12065 -0.3048)
			(end -0.67945 -0.3048)
			(stroke
				(width 0.1)
				(type default)
			)
			(layer "B.Fab")
		)
		(fp_line
			(start -0.67945 -0.3048)
			(end -0.67945 0.3048)
			(stroke
				(width 0.1)
				(type default)
			)
			(layer "B.Fab")
		)
		(fp_line
			(start 0.12065 -0.2794)
			(end -0.12065 -0.2794)
			(stroke
				(width 0.1)
				(type default)
			)
			(layer "B.Fab")
		)
		(fp_line
			(start -0.12065 -0.2794)
			(end -0.12065 -0.3048)
			(stroke
				(width 0.1)
				(type default)
			)
			(layer "B.Fab")
		)
		(fp_line
			(start 0.12065 0.2794)
			(end 0.12065 0.3048)
			(stroke
				(width 0.1)
				(type default)
			)
			(layer "B.Fab")
		)
		(fp_line
			(start -0.120396 0.2794)
			(end 0.12065 0.2794)
			(stroke
				(width 0.1)
				(type default)
			)
			(layer "B.Fab")
		)
		(fp_line
			(start 0.67945 0.3048)
			(end 0.67945 -0.305054)
			(stroke
				(width 0.1)
				(type default)
			)
			(layer "B.Fab")
		)
		(fp_line
			(start 0.12065 0.3048)
			(end 0.67945 0.3048)
			(stroke
				(width 0.1)
				(type default)
			)
			(layer "B.Fab")
		)
		(fp_line
			(start -0.120396 0.3048)
			(end -0.120396 0.2794)
			(stroke
				(width 0.1)
				(type default)
			)
			(layer "B.Fab")
		)
		(fp_line
			(start -0.67945 0.3048)
			(end -0.120396 0.3048)
			(stroke
				(width 0.1)
				(type default)
			)
			(layer "B.Fab")
		)
		(pad "1" smd circle
			(at 0.40005 0 270)
			(size 0 0)
			(layers "B.Cu" "B.Mask" "B.Paste")
			(net "PVDDCR_SOC_P0_VOS3")
		)
		(pad "2" smd circle
			(at -0.40005 0 270)
			(size 0 0)
			(layers "B.Cu" "B.Mask" "B.Paste")
			(net "PVDDCR_SOC_P0")
		)
	)
	(footprint ""
		(layer "B.Cu")
		(at 62.752732 -338.091272 -90)
		(property "Reference" "PC420_4"
			(at 0 0 90)
			(layer "B.SilkS")
			(hide yes)
			(effects
				(font
					(size 1.27 1.27)
				)
				(justify mirror)
			)
		)
		(property "Value" ""
			(at 0 0 90)
			(layer "B.Fab")
			(effects
				(font
					(size 1.27 1.27)
				)
				(justify mirror)
			)
		)
		(duplicate_pad_numbers_are_jumpers no)
		(fp_line
			(start -1.524 0.762)
			(end 1.524 0.762)
			(stroke
				(width 0.1524)
				(type default)
			)
			(layer "B.SilkS")
		)
		(fp_line
			(start 1.524 0.762)
			(end 1.524 -0.762)
			(stroke
				(width 0.1524)
				(type default)
			)
			(layer "B.SilkS")
		)
		(fp_line
			(start -1.524 -0.762)
			(end -1.524 0.762)
			(stroke
				(width 0.1524)
				(type default)
			)
			(layer "B.SilkS")
		)
		(fp_line
			(start 1.524 -0.762)
			(end -1.524 -0.762)
			(stroke
				(width 0.1524)
				(type default)
			)
			(layer "B.SilkS")
		)
		(fp_line
			(start -1.1049 0.724916)
			(end -1.1049 -0.724916)
			(stroke
				(width 0.1)
				(type default)
			)
			(layer "B.Fab")
		)
		(fp_line
			(start 1.1049 0.724916)
			(end -1.1049 0.724916)
			(stroke
				(width 0.1)
				(type default)
			)
			(layer "B.Fab")
		)
		(fp_line
			(start -1.1049 -0.724916)
			(end 1.1049 -0.724916)
			(stroke
				(width 0.1)
				(type default)
			)
			(layer "B.Fab")
		)
		(fp_line
			(start 1.1049 -0.724916)
			(end 1.1049 0.724916)
			(stroke
				(width 0.1)
				(type default)
			)
			(layer "B.Fab")
		)
		(pad "1" smd rect
			(at 0.889 0 270)
			(size 1.016 1.27)
			(layers "B.Cu" "B.Mask" "B.Paste")
			(net "PVDDCR_CPU1_P1")
		)
		(pad "2" smd rect
			(at -0.889 0 270)
			(size 1.016 1.27)
			(layers "B.Cu" "B.Mask" "B.Paste")
			(net "GND")
		)
	)
	(footprint ""
		(layer "B.Cu")
		(at 123.611386 -249.368564)
		(property "Reference" "C2320"
			(at 0 0 0)
			(layer "B.SilkS")
			(hide yes)
			(effects
				(font
					(size 1.27 1.27)
				)
				(justify mirror)
			)
		)
		(property "Value" ""
			(at 0 0 0)
			(layer "B.Fab")
			(effects
				(font
					(size 1.27 1.27)
				)
				(justify mirror)
			)
		)
		(duplicate_pad_numbers_are_jumpers no)
		(fp_line
			(start -0.7874 -0.4064)
			(end -0.7874 0.4064)
			(stroke
				(width 0.1524)
				(type default)
			)
			(layer "B.SilkS")
		)
		(fp_line
			(start -0.7874 0.4064)
			(end 0.7874 0.4064)
			(stroke
				(width 0.1524)
				(type default)
			)
			(layer "B.SilkS")
		)
		(fp_line
			(start 0.7874 -0.4064)
			(end -0.7874 -0.4064)
			(stroke
				(width 0.1524)
				(type default)
			)
			(layer "B.SilkS")
		)
		(fp_line
			(start 0.7874 0.4064)
			(end 0.7874 -0.4064)
			(stroke
				(width 0.1524)
				(type default)
			)
			(layer "B.SilkS")
		)
		(fp_line
			(start -0.67945 -0.3048)
			(end -0.67945 0.3048)
			(stroke
				(width 0.1)
				(type default)
			)
			(layer "B.Fab")
		)
		(fp_line
			(start -0.67945 0.3048)
			(end -0.120396 0.3048)
			(stroke
				(width 0.1)
				(type default)
			)
			(layer "B.Fab")
		)
		(fp_line
			(start -0.12065 -0.3048)
			(end -0.67945 -0.3048)
			(stroke
				(width 0.1)
				(type default)
			)
			(layer "B.Fab")
		)
		(fp_line
			(start -0.12065 -0.2794)
			(end -0.12065 -0.3048)
			(stroke
				(width 0.1)
				(type default)
			)
			(layer "B.Fab")
		)
		(fp_line
			(start -0.120396 0.2794)
			(end 0.12065 0.2794)
			(stroke
				(width 0.1)
				(type default)
			)
			(layer "B.Fab")
		)
		(fp_line
			(start -0.120396 0.3048)
			(end -0.120396 0.2794)
			(stroke
				(width 0.1)
				(type default)
			)
			(layer "B.Fab")
		)
		(fp_line
			(start 0.12065 -0.305054)
			(end 0.12065 -0.2794)
			(stroke
				(width 0.1)
				(type default)
			)
			(layer "B.Fab")
		)
		(fp_line
			(start 0.12065 -0.2794)
			(end -0.12065 -0.2794)
			(stroke
				(width 0.1)
				(type default)
			)
			(layer "B.Fab")
		)
		(fp_line
			(start 0.12065 0.2794)
			(end 0.12065 0.3048)
			(stroke
				(width 0.1)
				(type default)
			)
			(layer "B.Fab")
		)
		(fp_line
			(start 0.12065 0.3048)
			(end 0.67945 0.3048)
			(stroke
				(width 0.1)
				(type default)
			)
			(layer "B.Fab")
		)
		(fp_line
			(start 0.67945 -0.305054)
			(end 0.12065 -0.305054)
			(stroke
				(width 0.1)
				(type default)
			)
			(layer "B.Fab")
		)
		(fp_line
			(start 0.67945 0.3048)
			(end 0.67945 -0.305054)
			(stroke
				(width 0.1)
				(type default)
			)
			(layer "B.Fab")
		)
		(pad "1" smd circle
			(at 0.40005 0 180)
			(size 0 0)
			(layers "B.Cu" "B.Mask" "B.Paste")
			(net "PVDDCR_CPU0_P1")
		)
		(pad "2" smd circle
			(at -0.40005 0 180)
			(size 0 0)
			(layers "B.Cu" "B.Mask" "B.Paste")
			(net "GND")
		)
	)
	(footprint ""
		(layer "B.Cu")
		(at 12.025376 -134.189216 180)
		(property "Reference" "C1889"
			(at 0 0 0)
			(layer "B.SilkS")
			(hide yes)
			(effects
				(font
					(size 1.27 1.27)
				)
				(justify mirror)
			)
		)
		(property "Value" ""
			(at 0 0 0)
			(layer "B.Fab")
			(effects
				(font
					(size 1.27 1.27)
				)
				(justify mirror)
			)
		)
		(duplicate_pad_numbers_are_jumpers no)
		(fp_line
			(start 0.7874 0.4064)
			(end 0.7874 -0.4064)
			(stroke
				(width 0.1524)
				(type default)
			)
			(layer "B.SilkS")
		)
		(fp_line
			(start 0.7874 -0.4064)
			(end -0.7874 -0.4064)
			(stroke
				(width 0.1524)
				(type default)
			)
			(layer "B.SilkS")
		)
		(fp_line
			(start -0.7874 0.4064)
			(end 0.7874 0.4064)
			(stroke
				(width 0.1524)
				(type default)
			)
			(layer "B.SilkS")
		)
		(fp_line
			(start -0.7874 -0.4064)
			(end -0.7874 0.4064)
			(stroke
				(width 0.1524)
				(type default)
			)
			(layer "B.SilkS")
		)
		(fp_line
			(start 0.67945 0.3048)
			(end 0.67945 -0.305054)
			(stroke
				(width 0.1)
				(type default)
			)
			(layer "B.Fab")
		)
		(fp_line
			(start 0.67945 -0.305054)
			(end 0.12065 -0.305054)
			(stroke
				(width 0.1)
				(type default)
			)
			(layer "B.Fab")
		)
		(fp_line
			(start 0.12065 0.3048)
			(end 0.67945 0.3048)
			(stroke
				(width 0.1)
				(type default)
			)
			(layer "B.Fab")
		)
		(fp_line
			(start 0.12065 0.2794)
			(end 0.12065 0.3048)
			(stroke
				(width 0.1)
				(type default)
			)
			(layer "B.Fab")
		)
		(fp_line
			(start 0.12065 -0.2794)
			(end -0.12065 -0.2794)
			(stroke
				(width 0.1)
				(type default)
			)
			(layer "B.Fab")
		)
		(fp_line
			(start 0.12065 -0.305054)
			(end 0.12065 -0.2794)
			(stroke
				(width 0.1)
				(type default)
			)
			(layer "B.Fab")
		)
		(fp_line
			(start -0.120396 0.3048)
			(end -0.120396 0.2794)
			(stroke
				(width 0.1)
				(type default)
			)
			(layer "B.Fab")
		)
		(fp_line
			(start -0.120396 0.2794)
			(end 0.12065 0.2794)
			(stroke
				(width 0.1)
				(type default)
			)
			(layer "B.Fab")
		)
		(fp_line
			(start -0.12065 -0.2794)
			(end -0.12065 -0.3048)
			(stroke
				(width 0.1)
				(type default)
			)
			(layer "B.Fab")
		)
		(fp_line
			(start -0.12065 -0.3048)
			(end -0.67945 -0.3048)
			(stroke
				(width 0.1)
				(type default)
			)
			(layer "B.Fab")
		)
		(fp_line
			(start -0.67945 0.3048)
			(end -0.120396 0.3048)
			(stroke
				(width 0.1)
				(type default)
			)
			(layer "B.Fab")
		)
		(fp_line
			(start -0.67945 -0.3048)
			(end -0.67945 0.3048)
			(stroke
				(width 0.1)
				(type default)
			)
			(layer "B.Fab")
		)
		(pad "1" smd circle
			(at 0.40005 0)
			(size 0 0)
			(layers "B.Cu" "B.Mask" "B.Paste")
			(net "VFG3P3_CLK_GEN")
		)
		(pad "2" smd circle
			(at -0.40005 0)
			(size 0 0)
			(layers "B.Cu" "B.Mask" "B.Paste")
			(net "GND")
		)
	)
	(footprint ""
		(layer "B.Cu")
		(at 350.723454 -269.30731)
		(property "Reference" "C2210"
			(at 0 0 0)
			(layer "B.SilkS")
			(hide yes)
			(effects
				(font
					(size 1.27 1.27)
				)
				(justify mirror)
			)
		)
		(property "Value" ""
			(at 0 0 0)
			(layer "B.Fab")
			(effects
				(font
					(size 1.27 1.27)
				)
				(justify mirror)
			)
		)
		(duplicate_pad_numbers_are_jumpers no)
		(fp_line
			(start -0.7874 -0.4064)
			(end -0.7874 0.4064)
			(stroke
				(width 0.1524)
				(type default)
			)
			(layer "B.SilkS")
		)
		(fp_line
			(start -0.7874 0.4064)
			(end 0.7874 0.4064)
			(stroke
				(width 0.1524)
				(type default)
			)
			(layer "B.SilkS")
		)
		(fp_line
			(start 0.7874 -0.4064)
			(end -0.7874 -0.4064)
			(stroke
				(width 0.1524)
				(type default)
			)
			(layer "B.SilkS")
		)
		(fp_line
			(start 0.7874 0.4064)
			(end 0.7874 -0.4064)
			(stroke
				(width 0.1524)
				(type default)
			)
			(layer "B.SilkS")
		)
		(fp_line
			(start -0.67945 -0.3048)
			(end -0.67945 0.3048)
			(stroke
				(width 0.1)
				(type default)
			)
			(layer "B.Fab")
		)
		(fp_line
			(start -0.67945 0.3048)
			(end -0.120396 0.3048)
			(stroke
				(width 0.1)
				(type default)
			)
			(layer "B.Fab")
		)
		(fp_line
			(start -0.12065 -0.3048)
			(end -0.67945 -0.3048)
			(stroke
				(width 0.1)
				(type default)
			)
			(layer "B.Fab")
		)
		(fp_line
			(start -0.12065 -0.2794)
			(end -0.12065 -0.3048)
			(stroke
				(width 0.1)
				(type default)
			)
			(layer "B.Fab")
		)
		(fp_line
			(start -0.120396 0.2794)
			(end 0.12065 0.2794)
			(stroke
				(width 0.1)
				(type default)
			)
			(layer "B.Fab")
		)
		(fp_line
			(start -0.120396 0.3048)
			(end -0.120396 0.2794)
			(stroke
				(width 0.1)
				(type default)
			)
			(layer "B.Fab")
		)
		(fp_line
			(start 0.12065 -0.305054)
			(end 0.12065 -0.2794)
			(stroke
				(width 0.1)
				(type default)
			)
			(layer "B.Fab")
		)
		(fp_line
			(start 0.12065 -0.2794)
			(end -0.12065 -0.2794)
			(stroke
				(width 0.1)
				(type default)
			)
			(layer "B.Fab")
		)
		(fp_line
			(start 0.12065 0.2794)
			(end 0.12065 0.3048)
			(stroke
				(width 0.1)
				(type default)
			)
			(layer "B.Fab")
		)
		(fp_line
			(start 0.12065 0.3048)
			(end 0.67945 0.3048)
			(stroke
				(width 0.1)
				(type default)
			)
			(layer "B.Fab")
		)
		(fp_line
			(start 0.67945 -0.305054)
			(end 0.12065 -0.305054)
			(stroke
				(width 0.1)
				(type default)
			)
			(layer "B.Fab")
		)
		(fp_line
			(start 0.67945 0.3048)
			(end 0.67945 -0.305054)
			(stroke
				(width 0.1)
				(type default)
			)
			(layer "B.Fab")
		)
		(pad "1" smd circle
			(at 0.40005 0 180)
			(size 0 0)
			(layers "B.Cu" "B.Mask" "B.Paste")
			(net "PVDDCR_CPU1_P0")
		)
		(pad "2" smd circle
			(at -0.40005 0 180)
			(size 0 0)
			(layers "B.Cu" "B.Mask" "B.Paste")
			(net "GND")
		)
	)
	(footprint ""
		(layer "B.Cu")
		(at 24.939244 -349.386398 -90)
		(property "Reference" "PR375"
			(at 0 0 90)
			(layer "B.SilkS")
			(hide yes)
			(effects
				(font
					(size 1.27 1.27)
				)
				(justify mirror)
			)
		)
		(property "Value" ""
			(at 0 0 90)
			(layer "B.Fab")
			(effects
				(font
					(size 1.27 1.27)
				)
				(justify mirror)
			)
		)
		(duplicate_pad_numbers_are_jumpers no)
		(fp_line
			(start -0.7874 0.4064)
			(end 0.7874 0.4064)
			(stroke
				(width 0.1524)
				(type default)
			)
			(layer "B.SilkS")
		)
		(fp_line
			(start 0.7874 0.4064)
			(end 0.7874 -0.4064)
			(stroke
				(width 0.1524)
				(type default)
			)
			(layer "B.SilkS")
		)
		(fp_line
			(start -0.7874 -0.4064)
			(end -0.7874 0.4064)
			(stroke
				(width 0.1524)
				(type default)
			)
			(layer "B.SilkS")
		)
		(fp_line
			(start 0.7874 -0.4064)
			(end -0.7874 -0.4064)
			(stroke
				(width 0.1524)
				(type default)
			)
			(layer "B.SilkS")
		)
		(fp_line
			(start -0.67945 0.3048)
			(end -0.120396 0.3048)
			(stroke
				(width 0.1)
				(type default)
			)
			(layer "B.Fab")
		)
		(fp_line
			(start -0.120396 0.3048)
			(end -0.120396 0.2794)
			(stroke
				(width 0.1)
				(type default)
			)
			(layer "B.Fab")
		)
		(fp_line
			(start 0.12065 0.3048)
			(end 0.67945 0.3048)
			(stroke
				(width 0.1)
				(type default)
			)
			(layer "B.Fab")
		)
		(fp_line
			(start 0.67945 0.3048)
			(end 0.67945 -0.305054)
			(stroke
				(width 0.1)
				(type default)
			)
			(layer "B.Fab")
		)
		(fp_line
			(start -0.120396 0.2794)
			(end 0.12065 0.2794)
			(stroke
				(width 0.1)
				(type default)
			)
			(layer "B.Fab")
		)
		(fp_line
			(start 0.12065 0.2794)
			(end 0.12065 0.3048)
			(stroke
				(width 0.1)
				(type default)
			)
			(layer "B.Fab")
		)
		(fp_line
			(start -0.12065 -0.2794)
			(end -0.12065 -0.3048)
			(stroke
				(width 0.1)
				(type default)
			)
			(layer "B.Fab")
		)
		(fp_line
			(start 0.12065 -0.2794)
			(end -0.12065 -0.2794)
			(stroke
				(width 0.1)
				(type default)
			)
			(layer "B.Fab")
		)
		(fp_line
			(start -0.67945 -0.3048)
			(end -0.67945 0.3048)
			(stroke
				(width 0.1)
				(type default)
			)
			(layer "B.Fab")
		)
		(fp_line
			(start -0.12065 -0.3048)
			(end -0.67945 -0.3048)
			(stroke
				(width 0.1)
				(type default)
			)
			(layer "B.Fab")
		)
		(fp_line
			(start 0.12065 -0.305054)
			(end 0.12065 -0.2794)
			(stroke
				(width 0.1)
				(type default)
			)
			(layer "B.Fab")
		)
		(fp_line
			(start 0.67945 -0.305054)
			(end 0.12065 -0.305054)
			(stroke
				(width 0.1)
				(type default)
			)
			(layer "B.Fab")
		)
		(pad "1" smd circle
			(at 0.40005 0 90)
			(size 0 0)
			(layers "B.Cu" "B.Mask" "B.Paste")
			(net "PVDDIO_P1_VOS4")
		)
		(pad "2" smd circle
			(at -0.40005 0 90)
			(size 0 0)
			(layers "B.Cu" "B.Mask" "B.Paste")
			(net "PVDDIO_P1")
		)
	)
	(footprint ""
		(layer "B.Cu")
		(at 412.0642 -172.407072 90)
		(property "Reference" "PC614_3"
			(at 0 0 90)
			(layer "B.SilkS")
			(hide yes)
			(effects
				(font
					(size 1.27 1.27)
				)
				(justify mirror)
			)
		)
		(property "Value" ""
			(at 0 0 90)
			(layer "B.Fab")
			(effects
				(font
					(size 1.27 1.27)
				)
				(justify mirror)
			)
		)
		(duplicate_pad_numbers_are_jumpers no)
		(fp_line
			(start 1.524 -0.762)
			(end -1.524 -0.762)
			(stroke
				(width 0.1524)
				(type default)
			)
			(layer "B.SilkS")
		)
		(fp_line
			(start -1.524 -0.762)
			(end -1.524 0.762)
			(stroke
				(width 0.1524)
				(type default)
			)
			(layer "B.SilkS")
		)
		(fp_line
			(start 1.524 0.762)
			(end 1.524 -0.762)
			(stroke
				(width 0.1524)
				(type default)
			)
			(layer "B.SilkS")
		)
		(fp_line
			(start -1.524 0.762)
			(end 1.524 0.762)
			(stroke
				(width 0.1524)
				(type default)
			)
			(layer "B.SilkS")
		)
		(fp_line
			(start 1.1049 -0.724916)
			(end 1.1049 0.724916)
			(stroke
				(width 0.1)
				(type default)
			)
			(layer "B.Fab")
		)
		(fp_line
			(start -1.1049 -0.724916)
			(end 1.1049 -0.724916)
			(stroke
				(width 0.1)
				(type default)
			)
			(layer "B.Fab")
		)
		(fp_line
			(start 1.1049 0.724916)
			(end -1.1049 0.724916)
			(stroke
				(width 0.1)
				(type default)
			)
			(layer "B.Fab")
		)
		(fp_line
			(start -1.1049 0.724916)
			(end -1.1049 -0.724916)
			(stroke
				(width 0.1)
				(type default)
			)
			(layer "B.Fab")
		)
		(pad "1" smd rect
			(at 0.889 0 90)
			(size 1.016 1.27)
			(layers "B.Cu" "B.Mask" "B.Paste")
			(net "PVDDCR_SOC_P0")
		)
		(pad "2" smd rect
			(at -0.889 0 90)
			(size 1.016 1.27)
			(layers "B.Cu" "B.Mask" "B.Paste")
			(net "GND")
		)
	)
	(footprint ""
		(layer "B.Cu")
		(at 367.975388 -175.106076 90)
		(property "Reference" "PR324"
			(at 0 0 90)
			(layer "B.SilkS")
			(hide yes)
			(effects
				(font
					(size 1.27 1.27)
				)
				(justify mirror)
			)
		)
		(property "Value" ""
			(at 0 0 90)
			(layer "B.Fab")
			(effects
				(font
					(size 1.27 1.27)
				)
				(justify mirror)
			)
		)
		(duplicate_pad_numbers_are_jumpers no)
		(fp_line
			(start 0.7874 -0.4064)
			(end -0.7874 -0.4064)
			(stroke
				(width 0.1524)
				(type default)
			)
			(layer "B.SilkS")
		)
		(fp_line
			(start -0.7874 -0.4064)
			(end -0.7874 0.4064)
			(stroke
				(width 0.1524)
				(type default)
			)
			(layer "B.SilkS")
		)
		(fp_line
			(start 0.7874 0.4064)
			(end 0.7874 -0.4064)
			(stroke
				(width 0.1524)
				(type default)
			)
			(layer "B.SilkS")
		)
		(fp_line
			(start -0.7874 0.4064)
			(end 0.7874 0.4064)
			(stroke
				(width 0.1524)
				(type default)
			)
			(layer "B.SilkS")
		)
		(fp_line
			(start 0.67945 -0.305054)
			(end 0.12065 -0.305054)
			(stroke
				(width 0.1)
				(type default)
			)
			(layer "B.Fab")
		)
		(fp_line
			(start 0.12065 -0.305054)
			(end 0.12065 -0.2794)
			(stroke
				(width 0.1)
				(type default)
			)
			(layer "B.Fab")
		)
		(fp_line
			(start -0.12065 -0.3048)
			(end -0.67945 -0.3048)
			(stroke
				(width 0.1)
				(type default)
			)
			(layer "B.Fab")
		)
		(fp_line
			(start -0.67945 -0.3048)
			(end -0.67945 0.3048)
			(stroke
				(width 0.1)
				(type default)
			)
			(layer "B.Fab")
		)
		(fp_line
			(start 0.12065 -0.2794)
			(end -0.12065 -0.2794)
			(stroke
				(width 0.1)
				(type default)
			)
			(layer "B.Fab")
		)
		(fp_line
			(start -0.12065 -0.2794)
			(end -0.12065 -0.3048)
			(stroke
				(width 0.1)
				(type default)
			)
			(layer "B.Fab")
		)
		(fp_line
			(start 0.12065 0.2794)
			(end 0.12065 0.3048)
			(stroke
				(width 0.1)
				(type default)
			)
			(layer "B.Fab")
		)
		(fp_line
			(start -0.120396 0.2794)
			(end 0.12065 0.2794)
			(stroke
				(width 0.1)
				(type default)
			)
			(layer "B.Fab")
		)
		(fp_line
			(start 0.67945 0.3048)
			(end 0.67945 -0.305054)
			(stroke
				(width 0.1)
				(type default)
			)
			(layer "B.Fab")
		)
		(fp_line
			(start 0.12065 0.3048)
			(end 0.67945 0.3048)
			(stroke
				(width 0.1)
				(type default)
			)
			(layer "B.Fab")
		)
		(fp_line
			(start -0.120396 0.3048)
			(end -0.120396 0.2794)
			(stroke
				(width 0.1)
				(type default)
			)
			(layer "B.Fab")
		)
		(fp_line
			(start -0.67945 0.3048)
			(end -0.120396 0.3048)
			(stroke
				(width 0.1)
				(type default)
			)
			(layer "B.Fab")
		)
		(pad "1" smd circle
			(at 0.40005 0 270)
			(size 0 0)
			(layers "B.Cu" "B.Mask" "B.Paste")
			(net "PVDDCR_CPU0_P0_VOS1")
		)
		(pad "2" smd circle
			(at -0.40005 0 270)
			(size 0 0)
			(layers "B.Cu" "B.Mask" "B.Paste")
			(net "PVDDCR_CPU0_P0")
		)
	)
	(footprint ""
		(layer "B.Cu")
		(at 355.111304 -395.148562 90)
		(property "Reference" "C653"
			(at 0 0 90)
			(layer "B.SilkS")
			(hide yes)
			(effects
				(font
					(size 1.27 1.27)
				)
				(justify mirror)
			)
		)
		(property "Value" ""
			(at 0 0 90)
			(layer "B.Fab")
			(effects
				(font
					(size 1.27 1.27)
				)
				(justify mirror)
			)
		)
		(duplicate_pad_numbers_are_jumpers no)
		(fp_line
			(start 0.299974 -0.150114)
			(end -0.299974 -0.150114)
			(stroke
				(width 0.1)
				(type default)
			)
			(layer "B.Fab")
		)
		(fp_line
			(start -0.299974 -0.150114)
			(end -0.299974 0.150114)
			(stroke
				(width 0.1)
				(type default)
			)
			(layer "B.Fab")
		)
		(fp_line
			(start 0.299974 0.150114)
			(end 0.299974 -0.150114)
			(stroke
				(width 0.1)
				(type default)
			)
			(layer "B.Fab")
		)
		(fp_line
			(start -0.299974 0.150114)
			(end 0.299974 0.150114)
			(stroke
				(width 0.1)
				(type default)
			)
			(layer "B.Fab")
		)
		(pad "1" smd rect
			(at 0.2667 0 270)
			(size 0.3048 0.381)
			(layers "B.Cu" "B.Mask" "B.Paste")
			(net "P0V9_CPU0_RT1_2A")
		)
		(pad "2" smd rect
			(at -0.2667 0 270)
			(size 0.3048 0.381)
			(layers "B.Cu" "B.Mask" "B.Paste")
			(net "GND")
		)
	)
	(footprint ""
		(layer "B.Cu")
		(at 90.590878 -189.461648 90)
		(property "Reference" "PC276"
			(at 6.607556 -0.649986 270)
			(unlocked yes)
			(layer "B.SilkS")
			(effects
				(font
					(size 0.7874 0.5842)
					(thickness 0.1524)
				)
				(justify left mirror)
			)
		)
		(property "Value" ""
			(at 0 0 90)
			(layer "B.Fab")
			(effects
				(font
					(size 1.27 1.27)
				)
				(justify mirror)
			)
		)
		(duplicate_pad_numbers_are_jumpers no)
		(fp_line
			(start 4.533392 -2.249932)
			(end -4.533392 -2.249932)
			(stroke
				(width 0.1524)
				(type default)
			)
			(layer "B.SilkS")
		)
		(fp_line
			(start -4.533392 -2.249932)
			(end -4.533392 2.249932)
			(stroke
				(width 0.1524)
				(type default)
			)
			(layer "B.SilkS")
		)
		(fp_line
			(start 4.533392 2.249932)
			(end 4.533392 -2.249932)
			(stroke
				(width 0.1524)
				(type default)
			)
			(layer "B.SilkS")
		)
		(fp_line
			(start -4.533392 2.249932)
			(end 4.533392 2.249932)
			(stroke
				(width 0.1524)
				(type default)
			)
			(layer "B.SilkS")
		)
		(fp_rect
			(start 4.533392 -2.326132)
			(end 5.39242 2.326132)
			(stroke
				(width 0)
				(type default)
			)
			(fill yes)
			(layer "B.SilkS")
		)
		(fp_line
			(start 3.750056 -2.249932)
			(end -3.750056 -2.249932)
			(stroke
				(width 0.1)
				(type default)
			)
			(layer "B.Fab")
		)
		(fp_line
			(start -3.750056 -2.249932)
			(end -3.750056 2.249932)
			(stroke
				(width 0.1)
				(type default)
			)
			(layer "B.Fab")
		)
		(fp_line
			(start 3.750056 2.249932)
			(end 3.750056 -2.249932)
			(stroke
				(width 0.1)
				(type default)
			)
			(layer "B.Fab")
		)
		(fp_line
			(start -3.750056 2.249932)
			(end 3.750056 2.249932)
			(stroke
				(width 0.1)
				(type default)
			)
			(layer "B.Fab")
		)
		(fp_text user "-"
			(at -4.8514 -0.14605 90)
			(unlocked yes)
			(layer "B.SilkS")
			(effects
				(font
					(size 1.905 1.4224)
					(thickness 0.1524)
				)
				(justify left mirror)
			)
		)
		(fp_text user "+"
			(at 6.322314 0.786384 0)
			(unlocked yes)
			(layer "B.SilkS")
			(effects
				(font
					(size 1.905 1.4224)
					(thickness 0.1524)
				)
				(justify left mirror)
			)
		)
		(fp_text user "-"
			(at -4.8514 -0.14605 90)
			(unlocked yes)
			(layer "B.Fab")
			(effects
				(font
					(size 1.905 1.4224)
					(thickness 0.1524)
				)
				(justify left mirror)
			)
		)
		(fp_text user "+"
			(at 6.322314 0.786384 0)
			(unlocked yes)
			(layer "B.Fab")
			(effects
				(font
					(size 1.905 1.4224)
					(thickness 0.1524)
				)
				(justify left mirror)
			)
		)
		(pad "1" smd rect
			(at 3.199892 0 270)
			(size 2.413 2.8194)
			(layers "B.Cu" "B.Mask" "B.Paste")
			(net "PVDDCR_CPU0_P1")
		)
		(pad "2" smd rect
			(at -3.199892 0 270)
			(size 2.413 2.8194)
			(layers "B.Cu" "B.Mask" "B.Paste")
			(net "GND")
		)
	)
	(footprint ""
		(layer "B.Cu")
		(at 109.577124 -261.748016 90)
		(property "Reference" "C2125"
			(at 0 0 90)
			(layer "B.SilkS")
			(hide yes)
			(effects
				(font
					(size 1.27 1.27)
				)
				(justify mirror)
			)
		)
		(property "Value" ""
			(at 0 0 90)
			(layer "B.Fab")
			(effects
				(font
					(size 1.27 1.27)
				)
				(justify mirror)
			)
		)
		(duplicate_pad_numbers_are_jumpers no)
		(fp_line
			(start 0.7874 -0.4064)
			(end -0.7874 -0.4064)
			(stroke
				(width 0.1524)
				(type default)
			)
			(layer "B.SilkS")
		)
		(fp_line
			(start -0.7874 -0.4064)
			(end -0.7874 0.4064)
			(stroke
				(width 0.1524)
				(type default)
			)
			(layer "B.SilkS")
		)
		(fp_line
			(start 0.7874 0.4064)
			(end 0.7874 -0.4064)
			(stroke
				(width 0.1524)
				(type default)
			)
			(layer "B.SilkS")
		)
		(fp_line
			(start -0.7874 0.4064)
			(end 0.7874 0.4064)
			(stroke
				(width 0.1524)
				(type default)
			)
			(layer "B.SilkS")
		)
		(fp_line
			(start 0.67945 -0.305054)
			(end 0.12065 -0.305054)
			(stroke
				(width 0.1)
				(type default)
			)
			(layer "B.Fab")
		)
		(fp_line
			(start 0.12065 -0.305054)
			(end 0.12065 -0.2794)
			(stroke
				(width 0.1)
				(type default)
			)
			(layer "B.Fab")
		)
		(fp_line
			(start -0.12065 -0.3048)
			(end -0.67945 -0.3048)
			(stroke
				(width 0.1)
				(type default)
			)
			(layer "B.Fab")
		)
		(fp_line
			(start -0.67945 -0.3048)
			(end -0.67945 0.3048)
			(stroke
				(width 0.1)
				(type default)
			)
			(layer "B.Fab")
		)
		(fp_line
			(start 0.12065 -0.2794)
			(end -0.12065 -0.2794)
			(stroke
				(width 0.1)
				(type default)
			)
			(layer "B.Fab")
		)
		(fp_line
			(start -0.12065 -0.2794)
			(end -0.12065 -0.3048)
			(stroke
				(width 0.1)
				(type default)
			)
			(layer "B.Fab")
		)
		(fp_line
			(start 0.12065 0.2794)
			(end 0.12065 0.3048)
			(stroke
				(width 0.1)
				(type default)
			)
			(layer "B.Fab")
		)
		(fp_line
			(start -0.120396 0.2794)
			(end 0.12065 0.2794)
			(stroke
				(width 0.1)
				(type default)
			)
			(layer "B.Fab")
		)
		(fp_line
			(start 0.67945 0.3048)
			(end 0.67945 -0.305054)
			(stroke
				(width 0.1)
				(type default)
			)
			(layer "B.Fab")
		)
		(fp_line
			(start 0.12065 0.3048)
			(end 0.67945 0.3048)
			(stroke
				(width 0.1)
				(type default)
			)
			(layer "B.Fab")
		)
		(fp_line
			(start -0.120396 0.3048)
			(end -0.120396 0.2794)
			(stroke
				(width 0.1)
				(type default)
			)
			(layer "B.Fab")
		)
		(fp_line
			(start -0.67945 0.3048)
			(end -0.120396 0.3048)
			(stroke
				(width 0.1)
				(type default)
			)
			(layer "B.Fab")
		)
		(pad "1" smd circle
			(at 0.40005 0 270)
			(size 0 0)
			(layers "B.Cu" "B.Mask" "B.Paste")
			(net "PVDD11_S3_P1")
		)
		(pad "2" smd circle
			(at -0.40005 0 270)
			(size 0 0)
			(layers "B.Cu" "B.Mask" "B.Paste")
			(net "GND")
		)
	)
	(footprint ""
		(layer "B.Cu")
		(at 407.806144 -395.148562 90)
		(property "Reference" "C787"
			(at 0 0 90)
			(layer "B.SilkS")
			(hide yes)
			(effects
				(font
					(size 1.27 1.27)
				)
				(justify mirror)
			)
		)
		(property "Value" ""
			(at 0 0 90)
			(layer "B.Fab")
			(effects
				(font
					(size 1.27 1.27)
				)
				(justify mirror)
			)
		)
		(duplicate_pad_numbers_are_jumpers no)
		(fp_line
			(start 0.299974 -0.150114)
			(end -0.299974 -0.150114)
			(stroke
				(width 0.1)
				(type default)
			)
			(layer "B.Fab")
		)
		(fp_line
			(start -0.299974 -0.150114)
			(end -0.299974 0.150114)
			(stroke
				(width 0.1)
				(type default)
			)
			(layer "B.Fab")
		)
		(fp_line
			(start 0.299974 0.150114)
			(end 0.299974 -0.150114)
			(stroke
				(width 0.1)
				(type default)
			)
			(layer "B.Fab")
		)
		(fp_line
			(start -0.299974 0.150114)
			(end 0.299974 0.150114)
			(stroke
				(width 0.1)
				(type default)
			)
			(layer "B.Fab")
		)
		(pad "1" smd rect
			(at 0.2667 0 270)
			(size 0.3048 0.381)
			(layers "B.Cu" "B.Mask" "B.Paste")
			(net "P0V9_CPU0_RT2_2A_2D")
		)
		(pad "2" smd rect
			(at -0.2667 0 270)
			(size 0.3048 0.381)
			(layers "B.Cu" "B.Mask" "B.Paste")
			(net "GND")
		)
	)
	(footprint ""
		(layer "B.Cu")
		(at 393.352274 -392.957558)
		(property "Reference" "L22"
			(at 0 0 0)
			(layer "B.SilkS")
			(hide yes)
			(effects
				(font
					(size 1.27 1.27)
				)
				(justify mirror)
			)
		)
		(property "Value" ""
			(at 0 0 0)
			(layer "B.Fab")
			(effects
				(font
					(size 1.27 1.27)
				)
				(justify mirror)
			)
		)
		(duplicate_pad_numbers_are_jumpers no)
		(fp_line
			(start -1.63576 -0.8128)
			(end -1.63576 0.8128)
			(stroke
				(width 0.1524)
				(type default)
			)
			(layer "B.SilkS")
		)
		(fp_line
			(start -1.63576 0.8128)
			(end 1.63576 0.8128)
			(stroke
				(width 0.1524)
				(type default)
			)
			(layer "B.SilkS")
		)
		(fp_line
			(start 1.63576 -0.8128)
			(end -1.63576 -0.8128)
			(stroke
				(width 0.1524)
				(type default)
			)
			(layer "B.SilkS")
		)
		(fp_line
			(start 1.63576 -0.8128)
			(end 1.63576 0.8128)
			(stroke
				(width 0.1524)
				(type default)
			)
			(layer "B.SilkS")
		)
		(fp_line
			(start -1.560576 -0.738632)
			(end 1.56083 -0.738632)
			(stroke
				(width 0.1)
				(type default)
			)
			(layer "B.Fab")
		)
		(fp_line
			(start -1.560576 0.7366)
			(end -1.560576 -0.738632)
			(stroke
				(width 0.1)
				(type default)
			)
			(layer "B.Fab")
		)
		(fp_line
			(start -1.524 0.7366)
			(end -1.560576 0.7366)
			(stroke
				(width 0.1)
				(type default)
			)
			(layer "B.Fab")
		)
		(fp_line
			(start 1.524 0.7366)
			(end -1.524 0.7366)
			(stroke
				(width 0.1)
				(type default)
			)
			(layer "B.Fab")
		)
		(fp_line
			(start 1.56083 -0.738632)
			(end 1.56083 0.7366)
			(stroke
				(width 0.1)
				(type default)
			)
			(layer "B.Fab")
		)
		(fp_line
			(start 1.56083 0.7366)
			(end 1.524 0.7366)
			(stroke
				(width 0.1)
				(type default)
			)
			(layer "B.Fab")
		)
		(pad "1" smd rect
			(at 0.94996 0)
			(size 1.1176 1.3716)
			(layers "B.Cu" "B.Mask" "B.Paste")
			(net "P1V8_CPU0_RT_1D")
		)
		(pad "2" smd rect
			(at -0.94996 0)
			(size 1.1176 1.3716)
			(layers "B.Cu" "B.Mask" "B.Paste")
			(net "P1V8_CPU0_RT3_1A")
		)
	)
	(footprint ""
		(layer "B.Cu")
		(at 435.549802 -13.120116 180)
		(property "Reference" "C1237"
			(at 0 0 0)
			(layer "B.SilkS")
			(hide yes)
			(effects
				(font
					(size 1.27 1.27)
				)
				(justify mirror)
			)
		)
		(property "Value" ""
			(at 0 0 0)
			(layer "B.Fab")
			(effects
				(font
					(size 1.27 1.27)
				)
				(justify mirror)
			)
		)
		(duplicate_pad_numbers_are_jumpers no)
		(fp_line
			(start 0.7874 0.4064)
			(end 0.7874 -0.4064)
			(stroke
				(width 0.1524)
				(type default)
			)
			(layer "B.SilkS")
		)
		(fp_line
			(start 0.7874 -0.4064)
			(end -0.7874 -0.4064)
			(stroke
				(width 0.1524)
				(type default)
			)
			(layer "B.SilkS")
		)
		(fp_line
			(start -0.7874 0.4064)
			(end 0.7874 0.4064)
			(stroke
				(width 0.1524)
				(type default)
			)
			(layer "B.SilkS")
		)
		(fp_line
			(start -0.7874 -0.4064)
			(end -0.7874 0.4064)
			(stroke
				(width 0.1524)
				(type default)
			)
			(layer "B.SilkS")
		)
		(fp_line
			(start 0.67945 0.3048)
			(end 0.67945 -0.305054)
			(stroke
				(width 0.1)
				(type default)
			)
			(layer "B.Fab")
		)
		(fp_line
			(start 0.67945 -0.305054)
			(end 0.12065 -0.305054)
			(stroke
				(width 0.1)
				(type default)
			)
			(layer "B.Fab")
		)
		(fp_line
			(start 0.12065 0.3048)
			(end 0.67945 0.3048)
			(stroke
				(width 0.1)
				(type default)
			)
			(layer "B.Fab")
		)
		(fp_line
			(start 0.12065 0.2794)
			(end 0.12065 0.3048)
			(stroke
				(width 0.1)
				(type default)
			)
			(layer "B.Fab")
		)
		(fp_line
			(start 0.12065 -0.2794)
			(end -0.12065 -0.2794)
			(stroke
				(width 0.1)
				(type default)
			)
			(layer "B.Fab")
		)
		(fp_line
			(start 0.12065 -0.305054)
			(end 0.12065 -0.2794)
			(stroke
				(width 0.1)
				(type default)
			)
			(layer "B.Fab")
		)
		(fp_line
			(start -0.120396 0.3048)
			(end -0.120396 0.2794)
			(stroke
				(width 0.1)
				(type default)
			)
			(layer "B.Fab")
		)
		(fp_line
			(start -0.120396 0.2794)
			(end 0.12065 0.2794)
			(stroke
				(width 0.1)
				(type default)
			)
			(layer "B.Fab")
		)
		(fp_line
			(start -0.12065 -0.2794)
			(end -0.12065 -0.3048)
			(stroke
				(width 0.1)
				(type default)
			)
			(layer "B.Fab")
		)
		(fp_line
			(start -0.12065 -0.3048)
			(end -0.67945 -0.3048)
			(stroke
				(width 0.1)
				(type default)
			)
			(layer "B.Fab")
		)
		(fp_line
			(start -0.67945 0.3048)
			(end -0.120396 0.3048)
			(stroke
				(width 0.1)
				(type default)
			)
			(layer "B.Fab")
		)
		(fp_line
			(start -0.67945 -0.3048)
			(end -0.67945 0.3048)
			(stroke
				(width 0.1)
				(type default)
			)
			(layer "B.Fab")
		)
		(pad "1" smd circle
			(at 0.40005 0)
			(size 0 0)
			(layers "B.Cu" "B.Mask" "B.Paste")
			(net "P3V3_OCP_SFF")
		)
		(pad "2" smd circle
			(at -0.40005 0)
			(size 0 0)
			(layers "B.Cu" "B.Mask" "B.Paste")
			(net "GND")
		)
	)
	(footprint ""
		(layer "B.Cu")
		(at 17.90065 -388.789926 90)
		(property "Reference" "PC6615_1"
			(at 0 0 90)
			(layer "B.SilkS")
			(hide yes)
			(effects
				(font
					(size 1.27 1.27)
				)
				(justify mirror)
			)
		)
		(property "Value" ""
			(at 0 0 90)
			(layer "B.Fab")
			(effects
				(font
					(size 1.27 1.27)
				)
				(justify mirror)
			)
		)
		(duplicate_pad_numbers_are_jumpers no)
		(fp_line
			(start 1.524 -0.762)
			(end -1.524 -0.762)
			(stroke
				(width 0.1524)
				(type default)
			)
			(layer "B.SilkS")
		)
		(fp_line
			(start -1.524 -0.762)
			(end -1.524 0.762)
			(stroke
				(width 0.1524)
				(type default)
			)
			(layer "B.SilkS")
		)
		(fp_line
			(start 1.524 0.762)
			(end 1.524 -0.762)
			(stroke
				(width 0.1524)
				(type default)
			)
			(layer "B.SilkS")
		)
		(fp_line
			(start -1.524 0.762)
			(end 1.524 0.762)
			(stroke
				(width 0.1524)
				(type default)
			)
			(layer "B.SilkS")
		)
		(fp_line
			(start 1.1049 -0.724916)
			(end 1.1049 0.724916)
			(stroke
				(width 0.1)
				(type default)
			)
			(layer "B.Fab")
		)
		(fp_line
			(start -1.1049 -0.724916)
			(end 1.1049 -0.724916)
			(stroke
				(width 0.1)
				(type default)
			)
			(layer "B.Fab")
		)
		(fp_line
			(start 1.1049 0.724916)
			(end -1.1049 0.724916)
			(stroke
				(width 0.1)
				(type default)
			)
			(layer "B.Fab")
		)
		(fp_line
			(start -1.1049 0.724916)
			(end -1.1049 -0.724916)
			(stroke
				(width 0.1)
				(type default)
			)
			(layer "B.Fab")
		)
		(pad "1" smd rect
			(at 0.889 0 90)
			(size 1.016 1.27)
			(layers "B.Cu" "B.Mask" "B.Paste")
			(net "SW_P12V_AUX_P0V9_RETIMER_CPU1_FLT")
		)
		(pad "2" smd rect
			(at -0.889 0 90)
			(size 1.016 1.27)
			(layers "B.Cu" "B.Mask" "B.Paste")
			(net "GND")
		)
	)
	(footprint ""
		(layer "B.Cu")
		(at 348.151958 -263.521952)
		(property "Reference" "C2597"
			(at 0 0 0)
			(layer "B.SilkS")
			(hide yes)
			(effects
				(font
					(size 1.27 1.27)
				)
				(justify mirror)
			)
		)
		(property "Value" ""
			(at 0 0 0)
			(layer "B.Fab")
			(effects
				(font
					(size 1.27 1.27)
				)
				(justify mirror)
			)
		)
		(duplicate_pad_numbers_are_jumpers no)
		(fp_line
			(start -0.7874 -0.4064)
			(end -0.7874 0.4064)
			(stroke
				(width 0.1524)
				(type default)
			)
			(layer "B.SilkS")
		)
		(fp_line
			(start -0.7874 0.4064)
			(end 0.7874 0.4064)
			(stroke
				(width 0.1524)
				(type default)
			)
			(layer "B.SilkS")
		)
		(fp_line
			(start 0.7874 -0.4064)
			(end -0.7874 -0.4064)
			(stroke
				(width 0.1524)
				(type default)
			)
			(layer "B.SilkS")
		)
		(fp_line
			(start 0.7874 0.4064)
			(end 0.7874 -0.4064)
			(stroke
				(width 0.1524)
				(type default)
			)
			(layer "B.SilkS")
		)
		(fp_line
			(start -0.67945 -0.3048)
			(end -0.67945 0.3048)
			(stroke
				(width 0.1)
				(type default)
			)
			(layer "B.Fab")
		)
		(fp_line
			(start -0.67945 0.3048)
			(end -0.120396 0.3048)
			(stroke
				(width 0.1)
				(type default)
			)
			(layer "B.Fab")
		)
		(fp_line
			(start -0.12065 -0.3048)
			(end -0.67945 -0.3048)
			(stroke
				(width 0.1)
				(type default)
			)
			(layer "B.Fab")
		)
		(fp_line
			(start -0.12065 -0.2794)
			(end -0.12065 -0.3048)
			(stroke
				(width 0.1)
				(type default)
			)
			(layer "B.Fab")
		)
		(fp_line
			(start -0.120396 0.2794)
			(end 0.12065 0.2794)
			(stroke
				(width 0.1)
				(type default)
			)
			(layer "B.Fab")
		)
		(fp_line
			(start -0.120396 0.3048)
			(end -0.120396 0.2794)
			(stroke
				(width 0.1)
				(type default)
			)
			(layer "B.Fab")
		)
		(fp_line
			(start 0.12065 -0.305054)
			(end 0.12065 -0.2794)
			(stroke
				(width 0.1)
				(type default)
			)
			(layer "B.Fab")
		)
		(fp_line
			(start 0.12065 -0.2794)
			(end -0.12065 -0.2794)
			(stroke
				(width 0.1)
				(type default)
			)
			(layer "B.Fab")
		)
		(fp_line
			(start 0.12065 0.2794)
			(end 0.12065 0.3048)
			(stroke
				(width 0.1)
				(type default)
			)
			(layer "B.Fab")
		)
		(fp_line
			(start 0.12065 0.3048)
			(end 0.67945 0.3048)
			(stroke
				(width 0.1)
				(type default)
			)
			(layer "B.Fab")
		)
		(fp_line
			(start 0.67945 -0.305054)
			(end 0.12065 -0.305054)
			(stroke
				(width 0.1)
				(type default)
			)
			(layer "B.Fab")
		)
		(fp_line
			(start 0.67945 0.3048)
			(end 0.67945 -0.305054)
			(stroke
				(width 0.1)
				(type default)
			)
			(layer "B.Fab")
		)
		(pad "1" smd circle
			(at 0.40005 0 180)
			(size 0 0)
			(layers "B.Cu" "B.Mask" "B.Paste")
			(net "PVDDIO_P0")
		)
		(pad "2" smd circle
			(at -0.40005 0 180)
			(size 0 0)
			(layers "B.Cu" "B.Mask" "B.Paste")
			(net "GND")
		)
	)
	(footprint ""
		(layer "B.Cu")
		(at 79.932784 -408.517344 90)
		(property "Reference" "C6682"
			(at 0 0 90)
			(layer "B.SilkS")
			(hide yes)
			(effects
				(font
					(size 1.27 1.27)
				)
				(justify mirror)
			)
		)
		(property "Value" ""
			(at 0 0 90)
			(layer "B.Fab")
			(effects
				(font
					(size 1.27 1.27)
				)
				(justify mirror)
			)
		)
		(duplicate_pad_numbers_are_jumpers no)
		(fp_line
			(start 0.299974 -0.150114)
			(end -0.299974 -0.150114)
			(stroke
				(width 0.1)
				(type default)
			)
			(layer "B.Fab")
		)
		(fp_line
			(start -0.299974 -0.150114)
			(end -0.299974 0.150114)
			(stroke
				(width 0.1)
				(type default)
			)
			(layer "B.Fab")
		)
		(fp_line
			(start 0.299974 0.150114)
			(end 0.299974 -0.150114)
			(stroke
				(width 0.1)
				(type default)
			)
			(layer "B.Fab")
		)
		(fp_line
			(start -0.299974 0.150114)
			(end 0.299974 0.150114)
			(stroke
				(width 0.1)
				(type default)
			)
			(layer "B.Fab")
		)
		(pad "1" smd rect
			(at 0.2667 0 270)
			(size 0.3048 0.381)
			(layers "B.Cu" "B.Mask" "B.Paste")
			(net "P5E_CPU1_P1_TX_BUF_C_DN<10>")
		)
		(pad "2" smd rect
			(at -0.2667 0 270)
			(size 0.3048 0.381)
			(layers "B.Cu" "B.Mask" "B.Paste")
			(net "P5E_CPU1_P1_TX_BUF_DN<10>")
		)
	)
	(footprint ""
		(layer "B.Cu")
		(at 138.65352 -41.781222 180)
		(property "Reference" "C6069"
			(at 0 0 0)
			(layer "B.SilkS")
			(hide yes)
			(effects
				(font
					(size 1.27 1.27)
				)
				(justify mirror)
			)
		)
		(property "Value" ""
			(at 0 0 0)
			(layer "B.Fab")
			(effects
				(font
					(size 1.27 1.27)
				)
				(justify mirror)
			)
		)
		(duplicate_pad_numbers_are_jumpers no)
		(fp_line
			(start 0.7874 0.4064)
			(end 0.7874 -0.4064)
			(stroke
				(width 0.1524)
				(type default)
			)
			(layer "B.SilkS")
		)
		(fp_line
			(start 0.7874 -0.4064)
			(end -0.7874 -0.4064)
			(stroke
				(width 0.1524)
				(type default)
			)
			(layer "B.SilkS")
		)
		(fp_line
			(start -0.7874 0.4064)
			(end 0.7874 0.4064)
			(stroke
				(width 0.1524)
				(type default)
			)
			(layer "B.SilkS")
		)
		(fp_line
			(start -0.7874 -0.4064)
			(end -0.7874 0.4064)
			(stroke
				(width 0.1524)
				(type default)
			)
			(layer "B.SilkS")
		)
		(fp_line
			(start 0.67945 0.3048)
			(end 0.67945 -0.305054)
			(stroke
				(width 0.1)
				(type default)
			)
			(layer "B.Fab")
		)
		(fp_line
			(start 0.67945 -0.305054)
			(end 0.12065 -0.305054)
			(stroke
				(width 0.1)
				(type default)
			)
			(layer "B.Fab")
		)
		(fp_line
			(start 0.12065 0.3048)
			(end 0.67945 0.3048)
			(stroke
				(width 0.1)
				(type default)
			)
			(layer "B.Fab")
		)
		(fp_line
			(start 0.12065 0.2794)
			(end 0.12065 0.3048)
			(stroke
				(width 0.1)
				(type default)
			)
			(layer "B.Fab")
		)
		(fp_line
			(start 0.12065 -0.2794)
			(end -0.12065 -0.2794)
			(stroke
				(width 0.1)
				(type default)
			)
			(layer "B.Fab")
		)
		(fp_line
			(start 0.12065 -0.305054)
			(end 0.12065 -0.2794)
			(stroke
				(width 0.1)
				(type default)
			)
			(layer "B.Fab")
		)
		(fp_line
			(start -0.120396 0.3048)
			(end -0.120396 0.2794)
			(stroke
				(width 0.1)
				(type default)
			)
			(layer "B.Fab")
		)
		(fp_line
			(start -0.120396 0.2794)
			(end 0.12065 0.2794)
			(stroke
				(width 0.1)
				(type default)
			)
			(layer "B.Fab")
		)
		(fp_line
			(start -0.12065 -0.2794)
			(end -0.12065 -0.3048)
			(stroke
				(width 0.1)
				(type default)
			)
			(layer "B.Fab")
		)
		(fp_line
			(start -0.12065 -0.3048)
			(end -0.67945 -0.3048)
			(stroke
				(width 0.1)
				(type default)
			)
			(layer "B.Fab")
		)
		(fp_line
			(start -0.67945 0.3048)
			(end -0.120396 0.3048)
			(stroke
				(width 0.1)
				(type default)
			)
			(layer "B.Fab")
		)
		(fp_line
			(start -0.67945 -0.3048)
			(end -0.67945 0.3048)
			(stroke
				(width 0.1)
				(type default)
			)
			(layer "B.Fab")
		)
		(pad "1" smd circle
			(at 0.40005 0)
			(size 0 0)
			(layers "B.Cu" "B.Mask" "B.Paste")
			(net "P1V2_AUX")
		)
		(pad "2" smd circle
			(at -0.40005 0)
			(size 0 0)
			(layers "B.Cu" "B.Mask" "B.Paste")
			(net "GND")
		)
	)
	(footprint ""
		(layer "B.Cu")
		(at 181.845458 -426.898816 -90)
		(property "Reference" "R6233"
			(at 0 0 90)
			(layer "B.SilkS")
			(hide yes)
			(effects
				(font
					(size 1.27 1.27)
				)
				(justify mirror)
			)
		)
		(property "Value" ""
			(at 0 0 90)
			(layer "B.Fab")
			(effects
				(font
					(size 1.27 1.27)
				)
				(justify mirror)
			)
		)
		(duplicate_pad_numbers_are_jumpers no)
		(fp_line
			(start -0.7874 0.4064)
			(end 0.7874 0.4064)
			(stroke
				(width 0.1524)
				(type default)
			)
			(layer "B.SilkS")
		)
		(fp_line
			(start 0.7874 0.4064)
			(end 0.7874 -0.4064)
			(stroke
				(width 0.1524)
				(type default)
			)
			(layer "B.SilkS")
		)
		(fp_line
			(start -0.7874 -0.4064)
			(end -0.7874 0.4064)
			(stroke
				(width 0.1524)
				(type default)
			)
			(layer "B.SilkS")
		)
		(fp_line
			(start 0.7874 -0.4064)
			(end -0.7874 -0.4064)
			(stroke
				(width 0.1524)
				(type default)
			)
			(layer "B.SilkS")
		)
		(fp_line
			(start -0.67945 0.3048)
			(end -0.120396 0.3048)
			(stroke
				(width 0.1)
				(type default)
			)
			(layer "B.Fab")
		)
		(fp_line
			(start -0.120396 0.3048)
			(end -0.120396 0.2794)
			(stroke
				(width 0.1)
				(type default)
			)
			(layer "B.Fab")
		)
		(fp_line
			(start 0.12065 0.3048)
			(end 0.67945 0.3048)
			(stroke
				(width 0.1)
				(type default)
			)
			(layer "B.Fab")
		)
		(fp_line
			(start 0.67945 0.3048)
			(end 0.67945 -0.305054)
			(stroke
				(width 0.1)
				(type default)
			)
			(layer "B.Fab")
		)
		(fp_line
			(start -0.120396 0.2794)
			(end 0.12065 0.2794)
			(stroke
				(width 0.1)
				(type default)
			)
			(layer "B.Fab")
		)
		(fp_line
			(start 0.12065 0.2794)
			(end 0.12065 0.3048)
			(stroke
				(width 0.1)
				(type default)
			)
			(layer "B.Fab")
		)
		(fp_line
			(start -0.12065 -0.2794)
			(end -0.12065 -0.3048)
			(stroke
				(width 0.1)
				(type default)
			)
			(layer "B.Fab")
		)
		(fp_line
			(start 0.12065 -0.2794)
			(end -0.12065 -0.2794)
			(stroke
				(width 0.1)
				(type default)
			)
			(layer "B.Fab")
		)
		(fp_line
			(start -0.67945 -0.3048)
			(end -0.67945 0.3048)
			(stroke
				(width 0.1)
				(type default)
			)
			(layer "B.Fab")
		)
		(fp_line
			(start -0.12065 -0.3048)
			(end -0.67945 -0.3048)
			(stroke
				(width 0.1)
				(type default)
			)
			(layer "B.Fab")
		)
		(fp_line
			(start 0.12065 -0.305054)
			(end 0.12065 -0.2794)
			(stroke
				(width 0.1)
				(type default)
			)
			(layer "B.Fab")
		)
		(fp_line
			(start 0.67945 -0.305054)
			(end 0.12065 -0.305054)
			(stroke
				(width 0.1)
				(type default)
			)
			(layer "B.Fab")
		)
		(pad "1" smd circle
			(at 0.40005 0 90)
			(size 0 0)
			(layers "B.Cu" "B.Mask" "B.Paste")
			(net "A_HSC_LOW")
		)
		(pad "2" smd circle
			(at -0.40005 0 90)
			(size 0 0)
			(layers "B.Cu" "B.Mask" "B.Paste")
			(net "GND")
		)
	)
	(footprint ""
		(layer "B.Cu")
		(at 386.078476 -395.148562 90)
		(property "Reference" "C1039"
			(at 0 0 90)
			(layer "B.SilkS")
			(hide yes)
			(effects
				(font
					(size 1.27 1.27)
				)
				(justify mirror)
			)
		)
		(property "Value" ""
			(at 0 0 90)
			(layer "B.Fab")
			(effects
				(font
					(size 1.27 1.27)
				)
				(justify mirror)
			)
		)
		(duplicate_pad_numbers_are_jumpers no)
		(fp_line
			(start 0.299974 -0.150114)
			(end -0.299974 -0.150114)
			(stroke
				(width 0.1)
				(type default)
			)
			(layer "B.Fab")
		)
		(fp_line
			(start -0.299974 -0.150114)
			(end -0.299974 0.150114)
			(stroke
				(width 0.1)
				(type default)
			)
			(layer "B.Fab")
		)
		(fp_line
			(start 0.299974 0.150114)
			(end 0.299974 -0.150114)
			(stroke
				(width 0.1)
				(type default)
			)
			(layer "B.Fab")
		)
		(fp_line
			(start -0.299974 0.150114)
			(end 0.299974 0.150114)
			(stroke
				(width 0.1)
				(type default)
			)
			(layer "B.Fab")
		)
		(pad "1" smd rect
			(at 0.2667 0 270)
			(size 0.3048 0.381)
			(layers "B.Cu" "B.Mask" "B.Paste")
			(net "P0V9_CPU0_RT3_2A")
		)
		(pad "2" smd rect
			(at -0.2667 0 270)
			(size 0.3048 0.381)
			(layers "B.Cu" "B.Mask" "B.Paste")
			(net "GND")
		)
	)
	(footprint ""
		(layer "B.Cu")
		(at 421.90289 -426.765974)
		(property "Reference" "U47"
			(at -1.528826 -2.937002 0)
			(unlocked yes)
			(layer "B.SilkS")
			(effects
				(font
					(size 0.7874 0.5842)
					(thickness 0.1524)
				)
				(justify mirror)
			)
		)
		(property "Value" ""
			(at 0 0 0)
			(layer "B.Fab")
			(effects
				(font
					(size 1.27 1.27)
				)
				(justify mirror)
			)
		)
		(duplicate_pad_numbers_are_jumpers no)
		(fp_line
			(start -1.03378 -1.284478)
			(end -1.03378 1.284478)
			(stroke
				(width 0.1524)
				(type default)
			)
			(layer "B.SilkS")
		)
		(fp_line
			(start -1.03378 1.284478)
			(end 1.03378 1.284478)
			(stroke
				(width 0.1524)
				(type default)
			)
			(layer "B.SilkS")
		)
		(fp_line
			(start 1.03378 -1.284478)
			(end -1.03378 -1.284478)
			(stroke
				(width 0.1524)
				(type default)
			)
			(layer "B.SilkS")
		)
		(fp_line
			(start 1.03378 1.284478)
			(end 1.03378 -1.284478)
			(stroke
				(width 0.1524)
				(type default)
			)
			(layer "B.SilkS")
		)
		(fp_poly
			(pts
				(xy 1.266698 -0.776732) (xy 1.871726 -0.474218) (xy 1.871726 -1.079246)
			)
			(stroke
				(width 0)
				(type default)
			)
			(fill yes)
			(layer "B.SilkS")
		)
		(fp_line
			(start -0.774954 -1.02489)
			(end -0.774954 1.02489)
			(stroke
				(width 0.1)
				(type default)
			)
			(layer "B.Fab")
		)
		(fp_line
			(start -0.774954 1.02489)
			(end 0.774954 1.02489)
			(stroke
				(width 0.1)
				(type default)
			)
			(layer "B.Fab")
		)
		(fp_line
			(start 0.774954 -1.02489)
			(end -0.774954 -1.02489)
			(stroke
				(width 0.1)
				(type default)
			)
			(layer "B.Fab")
		)
		(fp_line
			(start 0.774954 1.02489)
			(end 0.774954 -1.02489)
			(stroke
				(width 0.1)
				(type default)
			)
			(layer "B.Fab")
		)
		(fp_poly
			(pts
				(xy 1.201674 -0.750062) (xy 1.806702 -0.447548) (xy 1.806702 -1.052576)
			)
			(stroke
				(width 0)
				(type default)
			)
			(fill yes)
			(layer "B.Fab")
		)
		(pad "1" smd rect
			(at 0.64008 -0.750062 90)
			(size 0.3048 0.5334)
			(layers "B.Cu" "B.Mask" "B.Paste")
			(net "SMB_RT_CPU0_P2_ROM_MUX_1D_SCL")
		)
		(pad "2" smd rect
			(at 0.64008 -0.249936 90)
			(size 0.254 0.5334)
			(layers "B.Cu" "B.Mask" "B.Paste")
			(net "SMB_RT_CPU0_P2_ROM_MUX_1D_SDA")
		)
		(pad "3" smd rect
			(at 0.64008 0.249936 90)
			(size 0.254 0.5334)
			(layers "B.Cu" "B.Mask" "B.Paste")
			(net "SMB_RT_CPU0_P2_ROM_MUX_2D_SCL")
		)
		(pad "4" smd rect
			(at 0.64008 0.750062 90)
			(size 0.3048 0.5334)
			(layers "B.Cu" "B.Mask" "B.Paste")
			(net "SMB_RT_CPU0_P2_ROM_MUX_2D_SDA")
		)
		(pad "5" smd rect
			(at 0 0.839978 180)
			(size 0.3302 0.635)
			(layers "B.Cu" "B.Mask" "B.Paste")
			(net "GND")
		)
		(pad "6" smd rect
			(at -0.64008 0.750062 90)
			(size 0.3048 0.5334)
			(layers "B.Cu" "B.Mask" "B.Paste")
			(net "RT_ROM_MUX8_OE_N")
		)
		(pad "7" smd rect
			(at -0.64008 0.249936 90)
			(size 0.254 0.5334)
			(layers "B.Cu" "B.Mask" "B.Paste")
			(net "SMB_RT_CPU0_P2_ROM_R_SDA")
		)
		(pad "8" smd rect
			(at -0.64008 -0.249936 90)
			(size 0.254 0.5334)
			(layers "B.Cu" "B.Mask" "B.Paste")
			(net "SMB_RT_CPU0_P2_ROM_R_SCL")
		)
		(pad "9" smd rect
			(at -0.64008 -0.750062 90)
			(size 0.3048 0.5334)
			(layers "B.Cu" "B.Mask" "B.Paste")
			(net "FM_SMB_RT_ROM_MUX8_SEL")
		)
		(pad "10" smd rect
			(at 0 -0.839978 180)
			(size 0.3302 0.635)
			(layers "B.Cu" "B.Mask" "B.Paste")
			(net "P3V3_AUX")
		)
	)
	(footprint ""
		(layer "B.Cu")
		(at 347.008958 -254.06731 180)
		(property "Reference" "C2523"
			(at 0 0 0)
			(layer "B.SilkS")
			(hide yes)
			(effects
				(font
					(size 1.27 1.27)
				)
				(justify mirror)
			)
		)
		(property "Value" ""
			(at 0 0 0)
			(layer "B.Fab")
			(effects
				(font
					(size 1.27 1.27)
				)
				(justify mirror)
			)
		)
		(duplicate_pad_numbers_are_jumpers no)
		(fp_line
			(start 0.7874 0.4064)
			(end 0.7874 -0.4064)
			(stroke
				(width 0.1524)
				(type default)
			)
			(layer "B.SilkS")
		)
		(fp_line
			(start 0.7874 -0.4064)
			(end -0.7874 -0.4064)
			(stroke
				(width 0.1524)
				(type default)
			)
			(layer "B.SilkS")
		)
		(fp_line
			(start -0.7874 0.4064)
			(end 0.7874 0.4064)
			(stroke
				(width 0.1524)
				(type default)
			)
			(layer "B.SilkS")
		)
		(fp_line
			(start -0.7874 -0.4064)
			(end -0.7874 0.4064)
			(stroke
				(width 0.1524)
				(type default)
			)
			(layer "B.SilkS")
		)
		(fp_line
			(start 0.67945 0.3048)
			(end 0.67945 -0.305054)
			(stroke
				(width 0.1)
				(type default)
			)
			(layer "B.Fab")
		)
		(fp_line
			(start 0.67945 -0.305054)
			(end 0.12065 -0.305054)
			(stroke
				(width 0.1)
				(type default)
			)
			(layer "B.Fab")
		)
		(fp_line
			(start 0.12065 0.3048)
			(end 0.67945 0.3048)
			(stroke
				(width 0.1)
				(type default)
			)
			(layer "B.Fab")
		)
		(fp_line
			(start 0.12065 0.2794)
			(end 0.12065 0.3048)
			(stroke
				(width 0.1)
				(type default)
			)
			(layer "B.Fab")
		)
		(fp_line
			(start 0.12065 -0.2794)
			(end -0.12065 -0.2794)
			(stroke
				(width 0.1)
				(type default)
			)
			(layer "B.Fab")
		)
		(fp_line
			(start 0.12065 -0.305054)
			(end 0.12065 -0.2794)
			(stroke
				(width 0.1)
				(type default)
			)
			(layer "B.Fab")
		)
		(fp_line
			(start -0.120396 0.3048)
			(end -0.120396 0.2794)
			(stroke
				(width 0.1)
				(type default)
			)
			(layer "B.Fab")
		)
		(fp_line
			(start -0.120396 0.2794)
			(end 0.12065 0.2794)
			(stroke
				(width 0.1)
				(type default)
			)
			(layer "B.Fab")
		)
		(fp_line
			(start -0.12065 -0.2794)
			(end -0.12065 -0.3048)
			(stroke
				(width 0.1)
				(type default)
			)
			(layer "B.Fab")
		)
		(fp_line
			(start -0.12065 -0.3048)
			(end -0.67945 -0.3048)
			(stroke
				(width 0.1)
				(type default)
			)
			(layer "B.Fab")
		)
		(fp_line
			(start -0.67945 0.3048)
			(end -0.120396 0.3048)
			(stroke
				(width 0.1)
				(type default)
			)
			(layer "B.Fab")
		)
		(fp_line
			(start -0.67945 -0.3048)
			(end -0.67945 0.3048)
			(stroke
				(width 0.1)
				(type default)
			)
			(layer "B.Fab")
		)
		(pad "1" smd circle
			(at 0.40005 0)
			(size 0 0)
			(layers "B.Cu" "B.Mask" "B.Paste")
			(net "PVDD18_S5_P0")
		)
		(pad "2" smd circle
			(at -0.40005 0)
			(size 0 0)
			(layers "B.Cu" "B.Mask" "B.Paste")
			(net "GND")
		)
	)
	(footprint ""
		(layer "B.Cu")
		(at 64.191388 -390.560052 90)
		(property "Reference" "C258"
			(at 0 0 90)
			(layer "B.SilkS")
			(hide yes)
			(effects
				(font
					(size 1.27 1.27)
				)
				(justify mirror)
			)
		)
		(property "Value" ""
			(at 0 0 90)
			(layer "B.Fab")
			(effects
				(font
					(size 1.27 1.27)
				)
				(justify mirror)
			)
		)
		(duplicate_pad_numbers_are_jumpers no)
		(fp_line
			(start 0.7874 -0.4064)
			(end -0.7874 -0.4064)
			(stroke
				(width 0.1524)
				(type default)
			)
			(layer "B.SilkS")
		)
		(fp_line
			(start -0.7874 -0.4064)
			(end -0.7874 0.4064)
			(stroke
				(width 0.1524)
				(type default)
			)
			(layer "B.SilkS")
		)
		(fp_line
			(start 0.7874 0.4064)
			(end 0.7874 -0.4064)
			(stroke
				(width 0.1524)
				(type default)
			)
			(layer "B.SilkS")
		)
		(fp_line
			(start -0.7874 0.4064)
			(end 0.7874 0.4064)
			(stroke
				(width 0.1524)
				(type default)
			)
			(layer "B.SilkS")
		)
		(fp_line
			(start 0.67945 -0.305054)
			(end 0.12065 -0.305054)
			(stroke
				(width 0.1)
				(type default)
			)
			(layer "B.Fab")
		)
		(fp_line
			(start 0.12065 -0.305054)
			(end 0.12065 -0.2794)
			(stroke
				(width 0.1)
				(type default)
			)
			(layer "B.Fab")
		)
		(fp_line
			(start -0.12065 -0.3048)
			(end -0.67945 -0.3048)
			(stroke
				(width 0.1)
				(type default)
			)
			(layer "B.Fab")
		)
		(fp_line
			(start -0.67945 -0.3048)
			(end -0.67945 0.3048)
			(stroke
				(width 0.1)
				(type default)
			)
			(layer "B.Fab")
		)
		(fp_line
			(start 0.12065 -0.2794)
			(end -0.12065 -0.2794)
			(stroke
				(width 0.1)
				(type default)
			)
			(layer "B.Fab")
		)
		(fp_line
			(start -0.12065 -0.2794)
			(end -0.12065 -0.3048)
			(stroke
				(width 0.1)
				(type default)
			)
			(layer "B.Fab")
		)
		(fp_line
			(start 0.12065 0.2794)
			(end 0.12065 0.3048)
			(stroke
				(width 0.1)
				(type default)
			)
			(layer "B.Fab")
		)
		(fp_line
			(start -0.120396 0.2794)
			(end 0.12065 0.2794)
			(stroke
				(width 0.1)
				(type default)
			)
			(layer "B.Fab")
		)
		(fp_line
			(start 0.67945 0.3048)
			(end 0.67945 -0.305054)
			(stroke
				(width 0.1)
				(type default)
			)
			(layer "B.Fab")
		)
		(fp_line
			(start 0.12065 0.3048)
			(end 0.67945 0.3048)
			(stroke
				(width 0.1)
				(type default)
			)
			(layer "B.Fab")
		)
		(fp_line
			(start -0.120396 0.3048)
			(end -0.120396 0.2794)
			(stroke
				(width 0.1)
				(type default)
			)
			(layer "B.Fab")
		)
		(fp_line
			(start -0.67945 0.3048)
			(end -0.120396 0.3048)
			(stroke
				(width 0.1)
				(type default)
			)
			(layer "B.Fab")
		)
		(pad "1" smd circle
			(at 0.40005 0 270)
			(size 0 0)
			(layers "B.Cu" "B.Mask" "B.Paste")
			(net "P0V9_CPU1_RT0_2A")
		)
		(pad "2" smd circle
			(at -0.40005 0 270)
			(size 0 0)
			(layers "B.Cu" "B.Mask" "B.Paste")
			(net "GND")
		)
	)
	(footprint ""
		(layer "B.Cu")
		(at 445.888364 -194.89547 180)
		(property "Reference" "R1578"
			(at 0 0 0)
			(layer "B.SilkS")
			(hide yes)
			(effects
				(font
					(size 1.27 1.27)
				)
				(justify mirror)
			)
		)
		(property "Value" ""
			(at 0 0 0)
			(layer "B.Fab")
			(effects
				(font
					(size 1.27 1.27)
				)
				(justify mirror)
			)
		)
		(duplicate_pad_numbers_are_jumpers no)
		(fp_line
			(start 0.7874 0.4064)
			(end 0.7874 -0.4064)
			(stroke
				(width 0.1524)
				(type default)
			)
			(layer "B.SilkS")
		)
		(fp_line
			(start 0.7874 -0.4064)
			(end -0.7874 -0.4064)
			(stroke
				(width 0.1524)
				(type default)
			)
			(layer "B.SilkS")
		)
		(fp_line
			(start -0.7874 0.4064)
			(end 0.7874 0.4064)
			(stroke
				(width 0.1524)
				(type default)
			)
			(layer "B.SilkS")
		)
		(fp_line
			(start -0.7874 -0.4064)
			(end -0.7874 0.4064)
			(stroke
				(width 0.1524)
				(type default)
			)
			(layer "B.SilkS")
		)
		(fp_line
			(start 0.67945 0.3048)
			(end 0.67945 -0.305054)
			(stroke
				(width 0.1)
				(type default)
			)
			(layer "B.Fab")
		)
		(fp_line
			(start 0.67945 -0.305054)
			(end 0.12065 -0.305054)
			(stroke
				(width 0.1)
				(type default)
			)
			(layer "B.Fab")
		)
		(fp_line
			(start 0.12065 0.3048)
			(end 0.67945 0.3048)
			(stroke
				(width 0.1)
				(type default)
			)
			(layer "B.Fab")
		)
		(fp_line
			(start 0.12065 0.2794)
			(end 0.12065 0.3048)
			(stroke
				(width 0.1)
				(type default)
			)
			(layer "B.Fab")
		)
		(fp_line
			(start 0.12065 -0.2794)
			(end -0.12065 -0.2794)
			(stroke
				(width 0.1)
				(type default)
			)
			(layer "B.Fab")
		)
		(fp_line
			(start 0.12065 -0.305054)
			(end 0.12065 -0.2794)
			(stroke
				(width 0.1)
				(type default)
			)
			(layer "B.Fab")
		)
		(fp_line
			(start -0.120396 0.3048)
			(end -0.120396 0.2794)
			(stroke
				(width 0.1)
				(type default)
			)
			(layer "B.Fab")
		)
		(fp_line
			(start -0.120396 0.2794)
			(end 0.12065 0.2794)
			(stroke
				(width 0.1)
				(type default)
			)
			(layer "B.Fab")
		)
		(fp_line
			(start -0.12065 -0.2794)
			(end -0.12065 -0.3048)
			(stroke
				(width 0.1)
				(type default)
			)
			(layer "B.Fab")
		)
		(fp_line
			(start -0.12065 -0.3048)
			(end -0.67945 -0.3048)
			(stroke
				(width 0.1)
				(type default)
			)
			(layer "B.Fab")
		)
		(fp_line
			(start -0.67945 0.3048)
			(end -0.120396 0.3048)
			(stroke
				(width 0.1)
				(type default)
			)
			(layer "B.Fab")
		)
		(fp_line
			(start -0.67945 -0.3048)
			(end -0.67945 0.3048)
			(stroke
				(width 0.1)
				(type default)
			)
			(layer "B.Fab")
		)
		(pad "1" smd circle
			(at 0.40005 0)
			(size 0 0)
			(layers "B.Cu" "B.Mask" "B.Paste")
			(net "I3C_SPD_DDRGL_CPU0_SCL")
		)
		(pad "2" smd circle
			(at -0.40005 0)
			(size 0 0)
			(layers "B.Cu" "B.Mask" "B.Paste")
			(net "I3C_SPD_DDRK_CPU0_SCL")
		)
	)
	(footprint ""
		(layer "B.Cu")
		(at 122.861578 -261.93623)
		(property "Reference" "C2456"
			(at 0 0 0)
			(layer "B.SilkS")
			(hide yes)
			(effects
				(font
					(size 1.27 1.27)
				)
				(justify mirror)
			)
		)
		(property "Value" ""
			(at 0 0 0)
			(layer "B.Fab")
			(effects
				(font
					(size 1.27 1.27)
				)
				(justify mirror)
			)
		)
		(duplicate_pad_numbers_are_jumpers no)
		(fp_line
			(start -0.7874 -0.4064)
			(end -0.7874 0.4064)
			(stroke
				(width 0.1524)
				(type default)
			)
			(layer "B.SilkS")
		)
		(fp_line
			(start -0.7874 0.4064)
			(end 0.7874 0.4064)
			(stroke
				(width 0.1524)
				(type default)
			)
			(layer "B.SilkS")
		)
		(fp_line
			(start 0.7874 -0.4064)
			(end -0.7874 -0.4064)
			(stroke
				(width 0.1524)
				(type default)
			)
			(layer "B.SilkS")
		)
		(fp_line
			(start 0.7874 0.4064)
			(end 0.7874 -0.4064)
			(stroke
				(width 0.1524)
				(type default)
			)
			(layer "B.SilkS")
		)
		(fp_line
			(start -0.67945 -0.3048)
			(end -0.67945 0.3048)
			(stroke
				(width 0.1)
				(type default)
			)
			(layer "B.Fab")
		)
		(fp_line
			(start -0.67945 0.3048)
			(end -0.120396 0.3048)
			(stroke
				(width 0.1)
				(type default)
			)
			(layer "B.Fab")
		)
		(fp_line
			(start -0.12065 -0.3048)
			(end -0.67945 -0.3048)
			(stroke
				(width 0.1)
				(type default)
			)
			(layer "B.Fab")
		)
		(fp_line
			(start -0.12065 -0.2794)
			(end -0.12065 -0.3048)
			(stroke
				(width 0.1)
				(type default)
			)
			(layer "B.Fab")
		)
		(fp_line
			(start -0.120396 0.2794)
			(end 0.12065 0.2794)
			(stroke
				(width 0.1)
				(type default)
			)
			(layer "B.Fab")
		)
		(fp_line
			(start -0.120396 0.3048)
			(end -0.120396 0.2794)
			(stroke
				(width 0.1)
				(type default)
			)
			(layer "B.Fab")
		)
		(fp_line
			(start 0.12065 -0.305054)
			(end 0.12065 -0.2794)
			(stroke
				(width 0.1)
				(type default)
			)
			(layer "B.Fab")
		)
		(fp_line
			(start 0.12065 -0.2794)
			(end -0.12065 -0.2794)
			(stroke
				(width 0.1)
				(type default)
			)
			(layer "B.Fab")
		)
		(fp_line
			(start 0.12065 0.2794)
			(end 0.12065 0.3048)
			(stroke
				(width 0.1)
				(type default)
			)
			(layer "B.Fab")
		)
		(fp_line
			(start 0.12065 0.3048)
			(end 0.67945 0.3048)
			(stroke
				(width 0.1)
				(type default)
			)
			(layer "B.Fab")
		)
		(fp_line
			(start 0.67945 -0.305054)
			(end 0.12065 -0.305054)
			(stroke
				(width 0.1)
				(type default)
			)
			(layer "B.Fab")
		)
		(fp_line
			(start 0.67945 0.3048)
			(end 0.67945 -0.305054)
			(stroke
				(width 0.1)
				(type default)
			)
			(layer "B.Fab")
		)
		(pad "1" smd circle
			(at 0.40005 0 180)
			(size 0 0)
			(layers "B.Cu" "B.Mask" "B.Paste")
			(net "PVDDCR_SOC_P1")
		)
		(pad "2" smd circle
			(at -0.40005 0 180)
			(size 0 0)
			(layers "B.Cu" "B.Mask" "B.Paste")
			(net "GND")
		)
	)
	(footprint ""
		(layer "B.Cu")
		(at 198.374 -144.272 -90)
		(property "Reference" "R8103"
			(at 0 0 90)
			(layer "B.SilkS")
			(hide yes)
			(effects
				(font
					(size 1.27 1.27)
				)
				(justify mirror)
			)
		)
		(property "Value" ""
			(at 0 0 90)
			(layer "B.Fab")
			(effects
				(font
					(size 1.27 1.27)
				)
				(justify mirror)
			)
		)
		(duplicate_pad_numbers_are_jumpers no)
		(fp_line
			(start -0.7874 0.4064)
			(end 0.7874 0.4064)
			(stroke
				(width 0.1524)
				(type default)
			)
			(layer "B.SilkS")
		)
		(fp_line
			(start 0.7874 0.4064)
			(end 0.7874 -0.4064)
			(stroke
				(width 0.1524)
				(type default)
			)
			(layer "B.SilkS")
		)
		(fp_line
			(start -0.7874 -0.4064)
			(end -0.7874 0.4064)
			(stroke
				(width 0.1524)
				(type default)
			)
			(layer "B.SilkS")
		)
		(fp_line
			(start 0.7874 -0.4064)
			(end -0.7874 -0.4064)
			(stroke
				(width 0.1524)
				(type default)
			)
			(layer "B.SilkS")
		)
		(fp_line
			(start -0.67945 0.3048)
			(end -0.120396 0.3048)
			(stroke
				(width 0.1)
				(type default)
			)
			(layer "B.Fab")
		)
		(fp_line
			(start -0.120396 0.3048)
			(end -0.120396 0.2794)
			(stroke
				(width 0.1)
				(type default)
			)
			(layer "B.Fab")
		)
		(fp_line
			(start 0.12065 0.3048)
			(end 0.67945 0.3048)
			(stroke
				(width 0.1)
				(type default)
			)
			(layer "B.Fab")
		)
		(fp_line
			(start 0.67945 0.3048)
			(end 0.67945 -0.305054)
			(stroke
				(width 0.1)
				(type default)
			)
			(layer "B.Fab")
		)
		(fp_line
			(start -0.120396 0.2794)
			(end 0.12065 0.2794)
			(stroke
				(width 0.1)
				(type default)
			)
			(layer "B.Fab")
		)
		(fp_line
			(start 0.12065 0.2794)
			(end 0.12065 0.3048)
			(stroke
				(width 0.1)
				(type default)
			)
			(layer "B.Fab")
		)
		(fp_line
			(start -0.12065 -0.2794)
			(end -0.12065 -0.3048)
			(stroke
				(width 0.1)
				(type default)
			)
			(layer "B.Fab")
		)
		(fp_line
			(start 0.12065 -0.2794)
			(end -0.12065 -0.2794)
			(stroke
				(width 0.1)
				(type default)
			)
			(layer "B.Fab")
		)
		(fp_line
			(start -0.67945 -0.3048)
			(end -0.67945 0.3048)
			(stroke
				(width 0.1)
				(type default)
			)
			(layer "B.Fab")
		)
		(fp_line
			(start -0.12065 -0.3048)
			(end -0.67945 -0.3048)
			(stroke
				(width 0.1)
				(type default)
			)
			(layer "B.Fab")
		)
		(fp_line
			(start 0.12065 -0.305054)
			(end 0.12065 -0.2794)
			(stroke
				(width 0.1)
				(type default)
			)
			(layer "B.Fab")
		)
		(fp_line
			(start 0.67945 -0.305054)
			(end 0.12065 -0.305054)
			(stroke
				(width 0.1)
				(type default)
			)
			(layer "B.Fab")
		)
		(pad "1" smd circle
			(at 0.40005 0 90)
			(size 0 0)
			(layers "B.Cu" "B.Mask" "B.Paste")
			(net "P3V3_AUX")
		)
		(pad "2" smd circle
			(at -0.40005 0 90)
			(size 0 0)
			(layers "B.Cu" "B.Mask" "B.Paste")
			(net "FM_AC_PWR_BTN_R_N")
		)
	)
	(footprint ""
		(layer "B.Cu")
		(at 72.416416 -393.242546 180)
		(property "Reference" "R705"
			(at 0 0 0)
			(layer "B.SilkS")
			(hide yes)
			(effects
				(font
					(size 1.27 1.27)
				)
				(justify mirror)
			)
		)
		(property "Value" ""
			(at 0 0 0)
			(layer "B.Fab")
			(effects
				(font
					(size 1.27 1.27)
				)
				(justify mirror)
			)
		)
		(duplicate_pad_numbers_are_jumpers no)
		(fp_line
			(start 1.2954 0.5842)
			(end 1.2954 -0.5842)
			(stroke
				(width 0.1524)
				(type default)
			)
			(layer "B.SilkS")
		)
		(fp_line
			(start 1.2954 -0.5842)
			(end -1.2954 -0.5842)
			(stroke
				(width 0.1524)
				(type default)
			)
			(layer "B.SilkS")
		)
		(fp_line
			(start -1.2954 0.5842)
			(end 1.2954 0.5842)
			(stroke
				(width 0.1524)
				(type default)
			)
			(layer "B.SilkS")
		)
		(fp_line
			(start -1.2954 -0.5842)
			(end -1.2954 0.5842)
			(stroke
				(width 0.1524)
				(type default)
			)
			(layer "B.SilkS")
		)
		(fp_line
			(start 1.1938 0.4064)
			(end 1.1938 -0.406654)
			(stroke
				(width 0.1)
				(type default)
			)
			(layer "B.Fab")
		)
		(fp_line
			(start 1.1938 -0.406654)
			(end 0.8636 -0.406654)
			(stroke
				(width 0.1)
				(type default)
			)
			(layer "B.Fab")
		)
		(fp_line
			(start 0.8636 0.4572)
			(end 0.8636 0.4318)
			(stroke
				(width 0.1)
				(type default)
			)
			(layer "B.Fab")
		)
		(fp_line
			(start 0.8636 0.4318)
			(end 0.8636 0.4064)
			(stroke
				(width 0.1)
				(type default)
			)
			(layer "B.Fab")
		)
		(fp_line
			(start 0.8636 0.4064)
			(end 1.1938 0.4064)
			(stroke
				(width 0.1)
				(type default)
			)
			(layer "B.Fab")
		)
		(fp_line
			(start 0.8636 -0.406654)
			(end 0.8636 -0.4572)
			(stroke
				(width 0.1)
				(type default)
			)
			(layer "B.Fab")
		)
		(fp_line
			(start 0.8636 -0.4572)
			(end -0.8636 -0.4572)
			(stroke
				(width 0.1)
				(type default)
			)
			(layer "B.Fab")
		)
		(fp_line
			(start -0.8636 0.4572)
			(end 0.8636 0.4572)
			(stroke
				(width 0.1)
				(type default)
			)
			(layer "B.Fab")
		)
		(fp_line
			(start -0.8636 0.4064)
			(end -0.8636 0.4572)
			(stroke
				(width 0.1)
				(type default)
			)
			(layer "B.Fab")
		)
		(fp_line
			(start -0.8636 -0.406654)
			(end -1.1938 -0.406654)
			(stroke
				(width 0.1)
				(type default)
			)
			(layer "B.Fab")
		)
		(fp_line
			(start -0.8636 -0.4572)
			(end -0.8636 -0.406654)
			(stroke
				(width 0.1)
				(type default)
			)
			(layer "B.Fab")
		)
		(fp_line
			(start -1.1938 0.4064)
			(end -0.8636 0.4064)
			(stroke
				(width 0.1)
				(type default)
			)
			(layer "B.Fab")
		)
		(fp_line
			(start -1.1938 -0.406654)
			(end -1.1938 0.4064)
			(stroke
				(width 0.1)
				(type default)
			)
			(layer "B.Fab")
		)
		(pad "1" smd rect
			(at 0.7366 0 90)
			(size 0.7112 0.8128)
			(layers "B.Cu" "B.Mask" "B.Paste")
			(net "P0V9_CPU1_RT_2D")
		)
		(pad "2" smd rect
			(at -0.7366 0 90)
			(size 0.7112 0.8128)
			(layers "B.Cu" "B.Mask" "B.Paste")
			(net "P0V9_CPU1_RT1_2A_2D")
		)
	)
	(footprint ""
		(layer "B.Cu")
		(at 12.076684 -112.319308 -90)
		(property "Reference" "U5201"
			(at -3.494532 -1.880616 0)
			(unlocked yes)
			(layer "B.SilkS")
			(effects
				(font
					(size 0.7874 0.5842)
					(thickness 0.1524)
				)
				(justify left mirror)
			)
		)
		(property "Value" ""
			(at 0 0 90)
			(layer "B.Fab")
			(effects
				(font
					(size 1.27 1.27)
				)
				(justify mirror)
			)
		)
		(duplicate_pad_numbers_are_jumpers no)
		(fp_line
			(start -1.2446 1.2446)
			(end -1.2446 0.479044)
			(stroke
				(width 0.1524)
				(type default)
			)
			(layer "B.SilkS")
		)
		(fp_line
			(start 1.2446 1.2446)
			(end -1.2446 1.2446)
			(stroke
				(width 0.1524)
				(type default)
			)
			(layer "B.SilkS")
		)
		(fp_line
			(start 1.2446 0.593344)
			(end 1.2446 1.2446)
			(stroke
				(width 0.1524)
				(type default)
			)
			(layer "B.SilkS")
		)
		(fp_line
			(start -1.2446 -0.506476)
			(end -1.2446 -1.2446)
			(stroke
				(width 0.1524)
				(type default)
			)
			(layer "B.SilkS")
		)
		(fp_line
			(start -1.2446 -1.2446)
			(end 1.2446 -1.2446)
			(stroke
				(width 0.1524)
				(type default)
			)
			(layer "B.SilkS")
		)
		(fp_line
			(start 1.2446 -1.2446)
			(end 1.2446 -0.592836)
			(stroke
				(width 0.1524)
				(type default)
			)
			(layer "B.SilkS")
		)
		(fp_poly
			(pts
				(xy 2.23266 -0.702056) (xy 1.416812 -0.430022) (xy 1.688592 -1.246124)
			)
			(stroke
				(width 0)
				(type default)
			)
			(fill yes)
			(layer "B.SilkS")
		)
		(fp_line
			(start -0.824992 0.824992)
			(end -0.824992 -0.824992)
			(stroke
				(width 0.1)
				(type default)
			)
			(layer "B.Fab")
		)
		(fp_line
			(start 0.824992 0.824992)
			(end -0.824992 0.824992)
			(stroke
				(width 0.1)
				(type default)
			)
			(layer "B.Fab")
		)
		(fp_line
			(start -0.824992 -0.824992)
			(end 0.824992 -0.824992)
			(stroke
				(width 0.1)
				(type default)
			)
			(layer "B.Fab")
		)
		(fp_line
			(start 0.824992 -0.824992)
			(end 0.824992 0.824992)
			(stroke
				(width 0.1)
				(type default)
			)
			(layer "B.Fab")
		)
		(fp_poly
			(pts
				(xy 1.389634 -0.199898) (xy 2.159 0.184658) (xy 2.159 -0.584708)
			)
			(stroke
				(width 0)
				(type default)
			)
			(fill yes)
			(layer "B.Fab")
		)
		(pad "1" smd rect
			(at 0.700024 -0.199898 180)
			(size 0.1778 0.8128)
			(layers "B.Cu" "B.Mask" "B.Paste")
			(net "USB2_HUB_BUF_SWB_R_DN")
		)
		(pad "2" smd rect
			(at 0.700024 0.199898 180)
			(size 0.1778 0.8128)
			(layers "B.Cu" "B.Mask" "B.Paste")
			(net "USB2_HUB_BUF_SWB_R_DP")
		)
		(pad "3" smd rect
			(at 0.599948 0.8001 90)
			(size 0.1778 0.6096)
			(layers "B.Cu" "B.Mask" "B.Paste")
			(net "TP_USB2_TEST")
		)
		(pad "4" smd rect
			(at 0.199898 0.8001 90)
			(size 0.1778 0.6096)
			(layers "B.Cu" "B.Mask" "B.Paste")
			(net "TP_USB2_CD")
		)
		(pad "5" smd rect
			(at -0.199898 0.8001 90)
			(size 0.1778 0.6096)
			(layers "B.Cu" "B.Mask" "B.Paste")
			(net "PD_U5201_RSTN")
		)
		(pad "6" smd rect
			(at -0.599948 0.8001 90)
			(size 0.1778 0.6096)
			(layers "B.Cu" "B.Mask" "B.Paste")
			(net "PD_U5201_EQ")
		)
		(pad "7" smd rect
			(at -0.700024 0.199898 180)
			(size 0.1778 0.8128)
			(layers "B.Cu" "B.Mask" "B.Paste")
			(net "USB2_HUB_BUF_SWB_R_DP")
		)
		(pad "8" smd rect
			(at -0.700024 -0.199898 180)
			(size 0.1778 0.8128)
			(layers "B.Cu" "B.Mask" "B.Paste")
			(net "USB2_HUB_BUF_SWB_R_DN")
		)
		(pad "9" smd rect
			(at -0.599948 -0.8001 90)
			(size 0.1778 0.6096)
			(layers "B.Cu" "B.Mask" "B.Paste")
			(net "TP_USB2_ENA_HS")
		)
		(pad "10" smd rect
			(at -0.199898 -0.8001 90)
			(size 0.1778 0.6096)
			(layers "B.Cu" "B.Mask" "B.Paste")
			(net "GND")
		)
		(pad "11" smd rect
			(at 0.199898 -0.8001 90)
			(size 0.1778 0.6096)
			(layers "B.Cu" "B.Mask" "B.Paste")
			(net "PD_U5201_VREG")
		)
		(pad "12" smd rect
			(at 0.599948 -0.8001 90)
			(size 0.1778 0.6096)
			(layers "B.Cu" "B.Mask" "B.Paste")
			(net "P3V3_AUX")
		)
	)
	(footprint ""
		(layer "B.Cu")
		(at 230.6828 -339.598 180)
		(property "Reference" "R6756"
			(at 0 0 0)
			(layer "B.SilkS")
			(hide yes)
			(effects
				(font
					(size 1.27 1.27)
				)
				(justify mirror)
			)
		)
		(property "Value" ""
			(at 0 0 0)
			(layer "B.Fab")
			(effects
				(font
					(size 1.27 1.27)
				)
				(justify mirror)
			)
		)
		(duplicate_pad_numbers_are_jumpers no)
		(fp_line
			(start 0.32512 0.175006)
			(end 0.32512 -0.175006)
			(stroke
				(width 0.1)
				(type default)
			)
			(layer "B.Fab")
		)
		(fp_line
			(start 0.32512 -0.175006)
			(end -0.32512 -0.175006)
			(stroke
				(width 0.1)
				(type default)
			)
			(layer "B.Fab")
		)
		(fp_line
			(start -0.32512 0.175006)
			(end 0.32512 0.175006)
			(stroke
				(width 0.1)
				(type default)
			)
			(layer "B.Fab")
		)
		(fp_line
			(start -0.32512 -0.175006)
			(end -0.32512 0.175006)
			(stroke
				(width 0.1)
				(type default)
			)
			(layer "B.Fab")
		)
		(pad "1" smd rect
			(at 0.2667 0)
			(size 0.3048 0.381)
			(layers "B.Cu" "B.Mask" "B.Paste")
			(net "SMB_RT_CPU0_P1_SDA")
		)
		(pad "2" smd rect
			(at -0.2667 0 180)
			(size 0.3048 0.381)
			(layers "B.Cu" "B.Mask" "B.Paste")
			(net "SMB_RT_CPU0_P1_R_SDA")
		)
	)
	(footprint ""
		(layer "B.Cu")
		(at 300.538388 7.622794)
		(property "Reference" "J82"
			(at 4.445 1.171956 270)
			(unlocked yes)
			(layer "B.SilkS")
			(effects
				(font
					(size 0.7874 0.5842)
					(thickness 0.1524)
				)
				(justify left mirror)
			)
		)
		(property "Value" ""
			(at 0 0 0)
			(layer "B.Fab")
			(effects
				(font
					(size 1.27 1.27)
				)
				(justify mirror)
			)
		)
		(duplicate_pad_numbers_are_jumpers no)
		(fp_line
			(start -1.2192 -2.06756)
			(end -1.2192 2.06756)
			(stroke
				(width 0.1524)
				(type default)
			)
			(layer "B.SilkS")
		)
		(fp_line
			(start -1.2192 2.06756)
			(end 1.2192 2.06756)
			(stroke
				(width 0.1524)
				(type default)
			)
			(layer "B.SilkS")
		)
		(fp_line
			(start 1.2192 -2.06756)
			(end -1.2192 -2.06756)
			(stroke
				(width 0.1524)
				(type default)
			)
			(layer "B.SilkS")
		)
		(fp_line
			(start 1.2192 2.06756)
			(end 1.2192 -2.06756)
			(stroke
				(width 0.1524)
				(type default)
			)
			(layer "B.SilkS")
		)
		(pad "" np_thru_hole circle
			(at -3.4671 -1.27 270)
			(size 1.0414 1.0414)
			(drill 1.0414)
			(layers "*.Cu" "*.Mask")
			(clearance 0.381)
			(thermal_gap 0.381)
		)
		(pad "" np_thru_hole circle
			(at -3.4671 1.27 270)
			(size 1.0414 1.0414)
			(drill 1.0414)
			(layers "*.Cu" "*.Mask")
			(clearance 0.381)
			(thermal_gap 0.381)
		)
		(pad "" np_thru_hole circle
			(at 2.8829 -1.27 270)
			(size 1.0414 1.0414)
			(drill 1.0414)
			(layers "*.Cu" "*.Mask")
			(clearance 0.381)
			(thermal_gap 0.381)
		)
		(pad "" np_thru_hole circle
			(at 2.8829 1.27 270)
			(size 1.0414 1.0414)
			(drill 1.0414)
			(layers "*.Cu" "*.Mask")
			(clearance 0.381)
			(thermal_gap 0.381)
		)
		(pad "1" smd rect
			(at -0.8255 -0.249936 270)
			(size 0.3048 0.508)
			(layers "B.Cu" "B.Mask" "B.Paste")
			(net "DELTA_L_85_10INCH_BOT_DN")
		)
		(pad "2" smd rect
			(at -0.8255 0.249936 270)
			(size 0.3048 0.508)
			(layers "B.Cu" "B.Mask" "B.Paste")
			(net "DELTA_L_85_10INCH_BOT_DP")
		)
		(pad "3" smd circle
			(at 0 0 180)
			(size 0 0)
			(layers "B.Cu" "B.Mask" "B.Paste")
			(net "DELTA_L_GND_1")
		)
		(zone
			(layers "F.Cu" "B.Cu" "In1.Cu" "In2.Cu" "In3.Cu" "In4.Cu" "In5.Cu" "In6.Cu"
				"In7.Cu" "In8.Cu" "In9.Cu" "In10.Cu" "In11.Cu" "In12.Cu" "In13.Cu" "In14.Cu"
				"In15.Cu" "In16.Cu"
			)
			(hatch none 0.5)
			(connect_pads
				(clearance 0)
			)
			(min_thickness 0.25)
			(keepout
				(tracks not_allowed)
				(vias allowed)
				(pads allowed)
				(copperpour not_allowed)
				(footprints allowed)
			)
			(placement
				(enabled no)
				(sheetname "")
			)
			(fill
				(thermal_gap 0.5)
				(thermal_bridge_width 0.5)
				(island_removal_mode 0)
			)
			(polygon
				(pts
					(arc
						(start 297.998388 6.352794)
						(mid 296.144188 6.352794)
						(end 297.998388 6.352794)
					)
				)
			)
		)
		(zone
			(layers "F.Cu" "B.Cu" "In1.Cu" "In2.Cu" "In3.Cu" "In4.Cu" "In5.Cu" "In6.Cu"
				"In7.Cu" "In8.Cu" "In9.Cu" "In10.Cu" "In11.Cu" "In12.Cu" "In13.Cu" "In14.Cu"
				"In15.Cu" "In16.Cu"
			)
			(hatch none 0.5)
			(connect_pads
				(clearance 0)
			)
			(min_thickness 0.25)
			(keepout
				(tracks not_allowed)
				(vias allowed)
				(pads allowed)
				(copperpour not_allowed)
				(footprints allowed)
			)
			(placement
				(enabled no)
				(sheetname "")
			)
			(fill
				(thermal_gap 0.5)
				(thermal_bridge_width 0.5)
				(island_removal_mode 0)
			)
			(polygon
				(pts
					(arc
						(start 297.998388 8.892794)
						(mid 296.144188 8.892794)
						(end 297.998388 8.892794)
					)
				)
			)
		)
		(zone
			(layers "F.Cu" "B.Cu" "In1.Cu" "In2.Cu" "In3.Cu" "In4.Cu" "In5.Cu" "In6.Cu"
				"In7.Cu" "In8.Cu" "In9.Cu" "In10.Cu" "In11.Cu" "In12.Cu" "In13.Cu" "In14.Cu"
				"In15.Cu" "In16.Cu"
			)
			(hatch none 0.5)
			(connect_pads
				(clearance 0)
			)
			(min_thickness 0.25)
			(keepout
				(tracks not_allowed)
				(vias allowed)
				(pads allowed)
				(copperpour not_allowed)
				(footprints allowed)
			)
			(placement
				(enabled no)
				(sheetname "")
			)
			(fill
				(thermal_gap 0.5)
				(thermal_bridge_width 0.5)
				(island_removal_mode 0)
			)
			(polygon
				(pts
					(arc
						(start 304.348388 6.352794)
						(mid 302.494188 6.352794)
						(end 304.348388 6.352794)
					)
				)
			)
		)
		(zone
			(layers "F.Cu" "B.Cu" "In1.Cu" "In2.Cu" "In3.Cu" "In4.Cu" "In5.Cu" "In6.Cu"
				"In7.Cu" "In8.Cu" "In9.Cu" "In10.Cu" "In11.Cu" "In12.Cu" "In13.Cu" "In14.Cu"
				"In15.Cu" "In16.Cu"
			)
			(hatch none 0.5)
			(connect_pads
				(clearance 0)
			)
			(min_thickness 0.25)
			(keepout
				(tracks not_allowed)
				(vias allowed)
				(pads allowed)
				(copperpour not_allowed)
				(footprints allowed)
			)
			(placement
				(enabled no)
				(sheetname "")
			)
			(fill
				(thermal_gap 0.5)
				(thermal_bridge_width 0.5)
				(island_removal_mode 0)
			)
			(polygon
				(pts
					(arc
						(start 304.348388 8.892794)
						(mid 302.494188 8.892794)
						(end 304.348388 8.892794)
					)
				)
			)
		)
		(zone
			(layer "B.Cu")
			(hatch none 0.5)
			(connect_pads
				(clearance 0)
			)
			(min_thickness 0.25)
			(keepout
				(tracks not_allowed)
				(vias allowed)
				(pads allowed)
				(copperpour not_allowed)
				(footprints allowed)
			)
			(placement
				(enabled no)
				(sheetname "")
			)
			(fill
				(thermal_gap 0.5)
				(thermal_bridge_width 0.5)
				(island_removal_mode 0)
			)
			(polygon
				(pts
					(xy 299.420788 7.074154) (xy 299.420788 7.169658) (xy 300.017688 7.169658) (xy 300.017688 7.576058)
					(xy 299.420788 7.576058) (xy 299.420788 7.66953) (xy 300.017688 7.66953) (xy 300.017688 8.07593)
					(xy 299.420788 8.07593) (xy 299.420788 8.171434) (xy 300.119288 8.171434) (xy 300.119288 7.074154)
				)
			)
		)
	)
	(footprint ""
		(layer "B.Cu")
		(at 51.72964 -424.225212 90)
		(property "Reference" "C1756"
			(at 0 0 90)
			(layer "B.SilkS")
			(hide yes)
			(effects
				(font
					(size 1.27 1.27)
				)
				(justify mirror)
			)
		)
		(property "Value" ""
			(at 0 0 90)
			(layer "B.Fab")
			(effects
				(font
					(size 1.27 1.27)
				)
				(justify mirror)
			)
		)
		(duplicate_pad_numbers_are_jumpers no)
		(fp_line
			(start 0.7874 -0.4064)
			(end -0.7874 -0.4064)
			(stroke
				(width 0.1524)
				(type default)
			)
			(layer "B.SilkS")
		)
		(fp_line
			(start -0.7874 -0.4064)
			(end -0.7874 0.4064)
			(stroke
				(width 0.1524)
				(type default)
			)
			(layer "B.SilkS")
		)
		(fp_line
			(start 0.7874 0.4064)
			(end 0.7874 -0.4064)
			(stroke
				(width 0.1524)
				(type default)
			)
			(layer "B.SilkS")
		)
		(fp_line
			(start -0.7874 0.4064)
			(end 0.7874 0.4064)
			(stroke
				(width 0.1524)
				(type default)
			)
			(layer "B.SilkS")
		)
		(fp_line
			(start 0.67945 -0.305054)
			(end 0.12065 -0.305054)
			(stroke
				(width 0.1)
				(type default)
			)
			(layer "B.Fab")
		)
		(fp_line
			(start 0.12065 -0.305054)
			(end 0.12065 -0.2794)
			(stroke
				(width 0.1)
				(type default)
			)
			(layer "B.Fab")
		)
		(fp_line
			(start -0.12065 -0.3048)
			(end -0.67945 -0.3048)
			(stroke
				(width 0.1)
				(type default)
			)
			(layer "B.Fab")
		)
		(fp_line
			(start -0.67945 -0.3048)
			(end -0.67945 0.3048)
			(stroke
				(width 0.1)
				(type default)
			)
			(layer "B.Fab")
		)
		(fp_line
			(start 0.12065 -0.2794)
			(end -0.12065 -0.2794)
			(stroke
				(width 0.1)
				(type default)
			)
			(layer "B.Fab")
		)
		(fp_line
			(start -0.12065 -0.2794)
			(end -0.12065 -0.3048)
			(stroke
				(width 0.1)
				(type default)
			)
			(layer "B.Fab")
		)
		(fp_line
			(start 0.12065 0.2794)
			(end 0.12065 0.3048)
			(stroke
				(width 0.1)
				(type default)
			)
			(layer "B.Fab")
		)
		(fp_line
			(start -0.120396 0.2794)
			(end 0.12065 0.2794)
			(stroke
				(width 0.1)
				(type default)
			)
			(layer "B.Fab")
		)
		(fp_line
			(start 0.67945 0.3048)
			(end 0.67945 -0.305054)
			(stroke
				(width 0.1)
				(type default)
			)
			(layer "B.Fab")
		)
		(fp_line
			(start 0.12065 0.3048)
			(end 0.67945 0.3048)
			(stroke
				(width 0.1)
				(type default)
			)
			(layer "B.Fab")
		)
		(fp_line
			(start -0.120396 0.3048)
			(end -0.120396 0.2794)
			(stroke
				(width 0.1)
				(type default)
			)
			(layer "B.Fab")
		)
		(fp_line
			(start -0.67945 0.3048)
			(end -0.120396 0.3048)
			(stroke
				(width 0.1)
				(type default)
			)
			(layer "B.Fab")
		)
		(pad "1" smd circle
			(at 0.40005 0 270)
			(size 0 0)
			(layers "B.Cu" "B.Mask" "B.Paste")
			(net "FM_GPU_PWRGD_ISO")
		)
		(pad "2" smd circle
			(at -0.40005 0 270)
			(size 0 0)
			(layers "B.Cu" "B.Mask" "B.Paste")
			(net "GND")
		)
	)
	(footprint ""
		(layer "B.Cu")
		(at 370.491004 -398.942052 90)
		(property "Reference" "C1037"
			(at 0 0 90)
			(layer "B.SilkS")
			(hide yes)
			(effects
				(font
					(size 1.27 1.27)
				)
				(justify mirror)
			)
		)
		(property "Value" ""
			(at 0 0 90)
			(layer "B.Fab")
			(effects
				(font
					(size 1.27 1.27)
				)
				(justify mirror)
			)
		)
		(duplicate_pad_numbers_are_jumpers no)
		(fp_line
			(start 0.7874 -0.4064)
			(end -0.7874 -0.4064)
			(stroke
				(width 0.1524)
				(type default)
			)
			(layer "B.SilkS")
		)
		(fp_line
			(start -0.7874 -0.4064)
			(end -0.7874 0.4064)
			(stroke
				(width 0.1524)
				(type default)
			)
			(layer "B.SilkS")
		)
		(fp_line
			(start 0.7874 0.4064)
			(end 0.7874 -0.4064)
			(stroke
				(width 0.1524)
				(type default)
			)
			(layer "B.SilkS")
		)
		(fp_line
			(start -0.7874 0.4064)
			(end 0.7874 0.4064)
			(stroke
				(width 0.1524)
				(type default)
			)
			(layer "B.SilkS")
		)
		(fp_line
			(start 0.67945 -0.305054)
			(end 0.12065 -0.305054)
			(stroke
				(width 0.1)
				(type default)
			)
			(layer "B.Fab")
		)
		(fp_line
			(start 0.12065 -0.305054)
			(end 0.12065 -0.2794)
			(stroke
				(width 0.1)
				(type default)
			)
			(layer "B.Fab")
		)
		(fp_line
			(start -0.12065 -0.3048)
			(end -0.67945 -0.3048)
			(stroke
				(width 0.1)
				(type default)
			)
			(layer "B.Fab")
		)
		(fp_line
			(start -0.67945 -0.3048)
			(end -0.67945 0.3048)
			(stroke
				(width 0.1)
				(type default)
			)
			(layer "B.Fab")
		)
		(fp_line
			(start 0.12065 -0.2794)
			(end -0.12065 -0.2794)
			(stroke
				(width 0.1)
				(type default)
			)
			(layer "B.Fab")
		)
		(fp_line
			(start -0.12065 -0.2794)
			(end -0.12065 -0.3048)
			(stroke
				(width 0.1)
				(type default)
			)
			(layer "B.Fab")
		)
		(fp_line
			(start 0.12065 0.2794)
			(end 0.12065 0.3048)
			(stroke
				(width 0.1)
				(type default)
			)
			(layer "B.Fab")
		)
		(fp_line
			(start -0.120396 0.2794)
			(end 0.12065 0.2794)
			(stroke
				(width 0.1)
				(type default)
			)
			(layer "B.Fab")
		)
		(fp_line
			(start 0.67945 0.3048)
			(end 0.67945 -0.305054)
			(stroke
				(width 0.1)
				(type default)
			)
			(layer "B.Fab")
		)
		(fp_line
			(start 0.12065 0.3048)
			(end 0.67945 0.3048)
			(stroke
				(width 0.1)
				(type default)
			)
			(layer "B.Fab")
		)
		(fp_line
			(start -0.120396 0.3048)
			(end -0.120396 0.2794)
			(stroke
				(width 0.1)
				(type default)
			)
			(layer "B.Fab")
		)
		(fp_line
			(start -0.67945 0.3048)
			(end -0.120396 0.3048)
			(stroke
				(width 0.1)
				(type default)
			)
			(layer "B.Fab")
		)
		(pad "1" smd circle
			(at 0.40005 0 270)
			(size 0 0)
			(layers "B.Cu" "B.Mask" "B.Paste")
			(net "P0V9_CPU0_RT3_2A")
		)
		(pad "2" smd circle
			(at -0.40005 0 270)
			(size 0 0)
			(layers "B.Cu" "B.Mask" "B.Paste")
			(net "GND")
		)
	)
	(footprint ""
		(layer "B.Cu")
		(at 352.425 -177.912522 90)
		(property "Reference" "PC576_5"
			(at 0 0 90)
			(layer "B.SilkS")
			(hide yes)
			(effects
				(font
					(size 1.27 1.27)
				)
				(justify mirror)
			)
		)
		(property "Value" ""
			(at 0 0 90)
			(layer "B.Fab")
			(effects
				(font
					(size 1.27 1.27)
				)
				(justify mirror)
			)
		)
		(duplicate_pad_numbers_are_jumpers no)
		(fp_line
			(start 1.524 -0.762)
			(end -1.524 -0.762)
			(stroke
				(width 0.1524)
				(type default)
			)
			(layer "B.SilkS")
		)
		(fp_line
			(start -1.524 -0.762)
			(end -1.524 0.762)
			(stroke
				(width 0.1524)
				(type default)
			)
			(layer "B.SilkS")
		)
		(fp_line
			(start 1.524 0.762)
			(end 1.524 -0.762)
			(stroke
				(width 0.1524)
				(type default)
			)
			(layer "B.SilkS")
		)
		(fp_line
			(start -1.524 0.762)
			(end 1.524 0.762)
			(stroke
				(width 0.1524)
				(type default)
			)
			(layer "B.SilkS")
		)
		(fp_line
			(start 1.1049 -0.724916)
			(end 1.1049 0.724916)
			(stroke
				(width 0.1)
				(type default)
			)
			(layer "B.Fab")
		)
		(fp_line
			(start -1.1049 -0.724916)
			(end 1.1049 -0.724916)
			(stroke
				(width 0.1)
				(type default)
			)
			(layer "B.Fab")
		)
		(fp_line
			(start 1.1049 0.724916)
			(end -1.1049 0.724916)
			(stroke
				(width 0.1)
				(type default)
			)
			(layer "B.Fab")
		)
		(fp_line
			(start -1.1049 0.724916)
			(end -1.1049 -0.724916)
			(stroke
				(width 0.1)
				(type default)
			)
			(layer "B.Fab")
		)
		(pad "1" smd rect
			(at 0.889 0 90)
			(size 1.016 1.27)
			(layers "B.Cu" "B.Mask" "B.Paste")
			(net "PVDDCR_CPU0_P0")
		)
		(pad "2" smd rect
			(at -0.889 0 90)
			(size 1.016 1.27)
			(layers "B.Cu" "B.Mask" "B.Paste")
			(net "GND")
		)
	)
	(footprint ""
		(layer "B.Cu")
		(at 355.041454 -248.47931 180)
		(property "Reference" "C263"
			(at 0 0 0)
			(layer "B.SilkS")
			(hide yes)
			(effects
				(font
					(size 1.27 1.27)
				)
				(justify mirror)
			)
		)
		(property "Value" ""
			(at 0 0 0)
			(layer "B.Fab")
			(effects
				(font
					(size 1.27 1.27)
				)
				(justify mirror)
			)
		)
		(duplicate_pad_numbers_are_jumpers no)
		(fp_line
			(start 0.7874 0.4064)
			(end 0.7874 -0.4064)
			(stroke
				(width 0.1524)
				(type default)
			)
			(layer "B.SilkS")
		)
		(fp_line
			(start 0.7874 -0.4064)
			(end -0.7874 -0.4064)
			(stroke
				(width 0.1524)
				(type default)
			)
			(layer "B.SilkS")
		)
		(fp_line
			(start -0.7874 0.4064)
			(end 0.7874 0.4064)
			(stroke
				(width 0.1524)
				(type default)
			)
			(layer "B.SilkS")
		)
		(fp_line
			(start -0.7874 -0.4064)
			(end -0.7874 0.4064)
			(stroke
				(width 0.1524)
				(type default)
			)
			(layer "B.SilkS")
		)
		(fp_line
			(start 0.67945 0.3048)
			(end 0.67945 -0.305054)
			(stroke
				(width 0.1)
				(type default)
			)
			(layer "B.Fab")
		)
		(fp_line
			(start 0.67945 -0.305054)
			(end 0.12065 -0.305054)
			(stroke
				(width 0.1)
				(type default)
			)
			(layer "B.Fab")
		)
		(fp_line
			(start 0.12065 0.3048)
			(end 0.67945 0.3048)
			(stroke
				(width 0.1)
				(type default)
			)
			(layer "B.Fab")
		)
		(fp_line
			(start 0.12065 0.2794)
			(end 0.12065 0.3048)
			(stroke
				(width 0.1)
				(type default)
			)
			(layer "B.Fab")
		)
		(fp_line
			(start 0.12065 -0.2794)
			(end -0.12065 -0.2794)
			(stroke
				(width 0.1)
				(type default)
			)
			(layer "B.Fab")
		)
		(fp_line
			(start 0.12065 -0.305054)
			(end 0.12065 -0.2794)
			(stroke
				(width 0.1)
				(type default)
			)
			(layer "B.Fab")
		)
		(fp_line
			(start -0.120396 0.3048)
			(end -0.120396 0.2794)
			(stroke
				(width 0.1)
				(type default)
			)
			(layer "B.Fab")
		)
		(fp_line
			(start -0.120396 0.2794)
			(end 0.12065 0.2794)
			(stroke
				(width 0.1)
				(type default)
			)
			(layer "B.Fab")
		)
		(fp_line
			(start -0.12065 -0.2794)
			(end -0.12065 -0.3048)
			(stroke
				(width 0.1)
				(type default)
			)
			(layer "B.Fab")
		)
		(fp_line
			(start -0.12065 -0.3048)
			(end -0.67945 -0.3048)
			(stroke
				(width 0.1)
				(type default)
			)
			(layer "B.Fab")
		)
		(fp_line
			(start -0.67945 0.3048)
			(end -0.120396 0.3048)
			(stroke
				(width 0.1)
				(type default)
			)
			(layer "B.Fab")
		)
		(fp_line
			(start -0.67945 -0.3048)
			(end -0.67945 0.3048)
			(stroke
				(width 0.1)
				(type default)
			)
			(layer "B.Fab")
		)
		(pad "1" smd circle
			(at 0.40005 0)
			(size 0 0)
			(layers "B.Cu" "B.Mask" "B.Paste")
			(net "PVDDCR_CPU0_P0")
		)
		(pad "2" smd circle
			(at -0.40005 0)
			(size 0 0)
			(layers "B.Cu" "B.Mask" "B.Paste")
			(net "GND")
		)
	)
	(footprint ""
		(layer "B.Cu")
		(at 134.840218 -41.127426)
		(property "Reference" "C6034"
			(at 0 0 0)
			(layer "B.SilkS")
			(hide yes)
			(effects
				(font
					(size 1.27 1.27)
				)
				(justify mirror)
			)
		)
		(property "Value" ""
			(at 0 0 0)
			(layer "B.Fab")
			(effects
				(font
					(size 1.27 1.27)
				)
				(justify mirror)
			)
		)
		(duplicate_pad_numbers_are_jumpers no)
		(fp_line
			(start -0.7874 -0.4064)
			(end -0.7874 0.4064)
			(stroke
				(width 0.1524)
				(type default)
			)
			(layer "B.SilkS")
		)
		(fp_line
			(start -0.7874 0.4064)
			(end 0.7874 0.4064)
			(stroke
				(width 0.1524)
				(type default)
			)
			(layer "B.SilkS")
		)
		(fp_line
			(start 0.7874 -0.4064)
			(end -0.7874 -0.4064)
			(stroke
				(width 0.1524)
				(type default)
			)
			(layer "B.SilkS")
		)
		(fp_line
			(start 0.7874 0.4064)
			(end 0.7874 -0.4064)
			(stroke
				(width 0.1524)
				(type default)
			)
			(layer "B.SilkS")
		)
		(fp_line
			(start -0.67945 -0.3048)
			(end -0.67945 0.3048)
			(stroke
				(width 0.1)
				(type default)
			)
			(layer "B.Fab")
		)
		(fp_line
			(start -0.67945 0.3048)
			(end -0.120396 0.3048)
			(stroke
				(width 0.1)
				(type default)
			)
			(layer "B.Fab")
		)
		(fp_line
			(start -0.12065 -0.3048)
			(end -0.67945 -0.3048)
			(stroke
				(width 0.1)
				(type default)
			)
			(layer "B.Fab")
		)
		(fp_line
			(start -0.12065 -0.2794)
			(end -0.12065 -0.3048)
			(stroke
				(width 0.1)
				(type default)
			)
			(layer "B.Fab")
		)
		(fp_line
			(start -0.120396 0.2794)
			(end 0.12065 0.2794)
			(stroke
				(width 0.1)
				(type default)
			)
			(layer "B.Fab")
		)
		(fp_line
			(start -0.120396 0.3048)
			(end -0.120396 0.2794)
			(stroke
				(width 0.1)
				(type default)
			)
			(layer "B.Fab")
		)
		(fp_line
			(start 0.12065 -0.305054)
			(end 0.12065 -0.2794)
			(stroke
				(width 0.1)
				(type default)
			)
			(layer "B.Fab")
		)
		(fp_line
			(start 0.12065 -0.2794)
			(end -0.12065 -0.2794)
			(stroke
				(width 0.1)
				(type default)
			)
			(layer "B.Fab")
		)
		(fp_line
			(start 0.12065 0.2794)
			(end 0.12065 0.3048)
			(stroke
				(width 0.1)
				(type default)
			)
			(layer "B.Fab")
		)
		(fp_line
			(start 0.12065 0.3048)
			(end 0.67945 0.3048)
			(stroke
				(width 0.1)
				(type default)
			)
			(layer "B.Fab")
		)
		(fp_line
			(start 0.67945 -0.305054)
			(end 0.12065 -0.305054)
			(stroke
				(width 0.1)
				(type default)
			)
			(layer "B.Fab")
		)
		(fp_line
			(start 0.67945 0.3048)
			(end 0.67945 -0.305054)
			(stroke
				(width 0.1)
				(type default)
			)
			(layer "B.Fab")
		)
		(pad "1" smd circle
			(at 0.40005 0 180)
			(size 0 0)
			(layers "B.Cu" "B.Mask" "B.Paste")
			(net "P1V2_CPU0_USB_DVDD12")
		)
		(pad "2" smd circle
			(at -0.40005 0 180)
			(size 0 0)
			(layers "B.Cu" "B.Mask" "B.Paste")
			(net "GND")
		)
	)
	(footprint ""
		(layer "B.Cu")
		(at 373.369586 -214.523828 90)
		(property "Reference" "R9274"
			(at 0 0 90)
			(layer "B.SilkS")
			(hide yes)
			(effects
				(font
					(size 1.27 1.27)
				)
				(justify mirror)
			)
		)
		(property "Value" ""
			(at 0 0 90)
			(layer "B.Fab")
			(effects
				(font
					(size 1.27 1.27)
				)
				(justify mirror)
			)
		)
		(duplicate_pad_numbers_are_jumpers no)
		(fp_line
			(start 0.7874 -0.4064)
			(end -0.7874 -0.4064)
			(stroke
				(width 0.1524)
				(type default)
			)
			(layer "B.SilkS")
		)
		(fp_line
			(start -0.7874 -0.4064)
			(end -0.7874 -0.065786)
			(stroke
				(width 0.1524)
				(type default)
			)
			(layer "B.SilkS")
		)
		(fp_line
			(start 0.7874 0.010414)
			(end 0.7874 -0.4064)
			(stroke
				(width 0.1524)
				(type default)
			)
			(layer "B.SilkS")
		)
		(fp_line
			(start -0.351028 0.4064)
			(end 0.436372 0.4064)
			(stroke
				(width 0.1524)
				(type default)
			)
			(layer "B.SilkS")
		)
		(fp_line
			(start 0.67945 -0.305054)
			(end 0.12065 -0.305054)
			(stroke
				(width 0.1)
				(type default)
			)
			(layer "B.Fab")
		)
		(fp_line
			(start 0.12065 -0.305054)
			(end 0.12065 -0.2794)
			(stroke
				(width 0.1)
				(type default)
			)
			(layer "B.Fab")
		)
		(fp_line
			(start -0.12065 -0.3048)
			(end -0.67945 -0.3048)
			(stroke
				(width 0.1)
				(type default)
			)
			(layer "B.Fab")
		)
		(fp_line
			(start -0.67945 -0.3048)
			(end -0.67945 0.3048)
			(stroke
				(width 0.1)
				(type default)
			)
			(layer "B.Fab")
		)
		(fp_line
			(start 0.12065 -0.2794)
			(end -0.12065 -0.2794)
			(stroke
				(width 0.1)
				(type default)
			)
			(layer "B.Fab")
		)
		(fp_line
			(start -0.12065 -0.2794)
			(end -0.12065 -0.3048)
			(stroke
				(width 0.1)
				(type default)
			)
			(layer "B.Fab")
		)
		(fp_line
			(start 0.12065 0.2794)
			(end 0.12065 0.3048)
			(stroke
				(width 0.1)
				(type default)
			)
			(layer "B.Fab")
		)
		(fp_line
			(start -0.120396 0.2794)
			(end 0.12065 0.2794)
			(stroke
				(width 0.1)
				(type default)
			)
			(layer "B.Fab")
		)
		(fp_line
			(start 0.67945 0.3048)
			(end 0.67945 -0.305054)
			(stroke
				(width 0.1)
				(type default)
			)
			(layer "B.Fab")
		)
		(fp_line
			(start 0.12065 0.3048)
			(end 0.67945 0.3048)
			(stroke
				(width 0.1)
				(type default)
			)
			(layer "B.Fab")
		)
		(fp_line
			(start -0.120396 0.3048)
			(end -0.120396 0.2794)
			(stroke
				(width 0.1)
				(type default)
			)
			(layer "B.Fab")
		)
		(fp_line
			(start -0.67945 0.3048)
			(end -0.120396 0.3048)
			(stroke
				(width 0.1)
				(type default)
			)
			(layer "B.Fab")
		)
		(pad "1" smd circle
			(at 0.40005 0 270)
			(size 0 0)
			(layers "B.Cu" "B.Mask" "B.Paste")
			(net "CLK_100M_CPU0_CLK04_R_DN")
		)
		(pad "2" smd circle
			(at -0.40005 0 270)
			(size 0 0)
			(layers "B.Cu" "B.Mask" "B.Paste")
			(net "CLK_100M_CPU0_CLK04_DN")
		)
	)
	(footprint ""
		(layer "B.Cu")
		(at 395.881098 -170.458892 180)
		(property "Reference" "PC593_1"
			(at 0 0 0)
			(layer "B.SilkS")
			(hide yes)
			(effects
				(font
					(size 1.27 1.27)
				)
				(justify mirror)
			)
		)
		(property "Value" ""
			(at 0 0 0)
			(layer "B.Fab")
			(effects
				(font
					(size 1.27 1.27)
				)
				(justify mirror)
			)
		)
		(duplicate_pad_numbers_are_jumpers no)
		(fp_line
			(start 1.524 0.762)
			(end 1.524 -0.762)
			(stroke
				(width 0.1524)
				(type default)
			)
			(layer "B.SilkS")
		)
		(fp_line
			(start 1.524 -0.762)
			(end -1.524 -0.762)
			(stroke
				(width 0.1524)
				(type default)
			)
			(layer "B.SilkS")
		)
		(fp_line
			(start -1.524 0.762)
			(end 1.524 0.762)
			(stroke
				(width 0.1524)
				(type default)
			)
			(layer "B.SilkS")
		)
		(fp_line
			(start -1.524 -0.762)
			(end -1.524 0.762)
			(stroke
				(width 0.1524)
				(type default)
			)
			(layer "B.SilkS")
		)
		(fp_line
			(start 1.1049 0.724916)
			(end -1.1049 0.724916)
			(stroke
				(width 0.1)
				(type default)
			)
			(layer "B.Fab")
		)
		(fp_line
			(start 1.1049 -0.724916)
			(end 1.1049 0.724916)
			(stroke
				(width 0.1)
				(type default)
			)
			(layer "B.Fab")
		)
		(fp_line
			(start -1.1049 0.724916)
			(end -1.1049 -0.724916)
			(stroke
				(width 0.1)
				(type default)
			)
			(layer "B.Fab")
		)
		(fp_line
			(start -1.1049 -0.724916)
			(end 1.1049 -0.724916)
			(stroke
				(width 0.1)
				(type default)
			)
			(layer "B.Fab")
		)
		(pad "1" smd rect
			(at 0.889 0 180)
			(size 1.016 1.27)
			(layers "B.Cu" "B.Mask" "B.Paste")
			(net "SW_P12V_AUX_PVDDCR_SOC_P0_FLT")
		)
		(pad "2" smd rect
			(at -0.889 0 180)
			(size 1.016 1.27)
			(layers "B.Cu" "B.Mask" "B.Paste")
			(net "GND")
		)
	)
	(footprint ""
		(layer "B.Cu")
		(at 395.252194 -203.882498 -90)
		(property "Reference" "R6132"
			(at 0 0 90)
			(layer "B.SilkS")
			(hide yes)
			(effects
				(font
					(size 1.27 1.27)
				)
				(justify mirror)
			)
		)
		(property "Value" ""
			(at 0 0 90)
			(layer "B.Fab")
			(effects
				(font
					(size 1.27 1.27)
				)
				(justify mirror)
			)
		)
		(duplicate_pad_numbers_are_jumpers no)
		(fp_line
			(start -0.7874 0.4064)
			(end 0.7874 0.4064)
			(stroke
				(width 0.1524)
				(type default)
			)
			(layer "B.SilkS")
		)
		(fp_line
			(start 0.7874 0.4064)
			(end 0.7874 -0.4064)
			(stroke
				(width 0.1524)
				(type default)
			)
			(layer "B.SilkS")
		)
		(fp_line
			(start -0.7874 -0.4064)
			(end -0.7874 0.4064)
			(stroke
				(width 0.1524)
				(type default)
			)
			(layer "B.SilkS")
		)
		(fp_line
			(start 0.7874 -0.4064)
			(end -0.7874 -0.4064)
			(stroke
				(width 0.1524)
				(type default)
			)
			(layer "B.SilkS")
		)
		(fp_line
			(start -0.67945 0.3048)
			(end -0.120396 0.3048)
			(stroke
				(width 0.1)
				(type default)
			)
			(layer "B.Fab")
		)
		(fp_line
			(start -0.120396 0.3048)
			(end -0.120396 0.2794)
			(stroke
				(width 0.1)
				(type default)
			)
			(layer "B.Fab")
		)
		(fp_line
			(start 0.12065 0.3048)
			(end 0.67945 0.3048)
			(stroke
				(width 0.1)
				(type default)
			)
			(layer "B.Fab")
		)
		(fp_line
			(start 0.67945 0.3048)
			(end 0.67945 -0.305054)
			(stroke
				(width 0.1)
				(type default)
			)
			(layer "B.Fab")
		)
		(fp_line
			(start -0.120396 0.2794)
			(end 0.12065 0.2794)
			(stroke
				(width 0.1)
				(type default)
			)
			(layer "B.Fab")
		)
		(fp_line
			(start 0.12065 0.2794)
			(end 0.12065 0.3048)
			(stroke
				(width 0.1)
				(type default)
			)
			(layer "B.Fab")
		)
		(fp_line
			(start -0.12065 -0.2794)
			(end -0.12065 -0.3048)
			(stroke
				(width 0.1)
				(type default)
			)
			(layer "B.Fab")
		)
		(fp_line
			(start 0.12065 -0.2794)
			(end -0.12065 -0.2794)
			(stroke
				(width 0.1)
				(type default)
			)
			(layer "B.Fab")
		)
		(fp_line
			(start -0.67945 -0.3048)
			(end -0.67945 0.3048)
			(stroke
				(width 0.1)
				(type default)
			)
			(layer "B.Fab")
		)
		(fp_line
			(start -0.12065 -0.3048)
			(end -0.67945 -0.3048)
			(stroke
				(width 0.1)
				(type default)
			)
			(layer "B.Fab")
		)
		(fp_line
			(start 0.12065 -0.305054)
			(end 0.12065 -0.2794)
			(stroke
				(width 0.1)
				(type default)
			)
			(layer "B.Fab")
		)
		(fp_line
			(start 0.67945 -0.305054)
			(end 0.12065 -0.305054)
			(stroke
				(width 0.1)
				(type default)
			)
			(layer "B.Fab")
		)
		(pad "1" smd circle
			(at 0.40005 0 90)
			(size 0 0)
			(layers "B.Cu" "B.Mask" "B.Paste")
			(net "PVDD18_S5_P0")
		)
		(pad "2" smd circle
			(at -0.40005 0 90)
			(size 0 0)
			(layers "B.Cu" "B.Mask" "B.Paste")
			(net "FAB_REV_ID0")
		)
	)
	(footprint ""
		(layer "B.Cu")
		(at 392.016234 -395.466062 -90)
		(property "Reference" "C991"
			(at 0 0 90)
			(layer "B.SilkS")
			(hide yes)
			(effects
				(font
					(size 1.27 1.27)
				)
				(justify mirror)
			)
		)
		(property "Value" ""
			(at 0 0 90)
			(layer "B.Fab")
			(effects
				(font
					(size 1.27 1.27)
				)
				(justify mirror)
			)
		)
		(duplicate_pad_numbers_are_jumpers no)
		(fp_line
			(start -1.524 0.762)
			(end 1.524 0.762)
			(stroke
				(width 0.1524)
				(type default)
			)
			(layer "B.SilkS")
		)
		(fp_line
			(start 1.524 0.762)
			(end 1.524 -0.762)
			(stroke
				(width 0.1524)
				(type default)
			)
			(layer "B.SilkS")
		)
		(fp_line
			(start -1.524 -0.762)
			(end -1.524 0.762)
			(stroke
				(width 0.1524)
				(type default)
			)
			(layer "B.SilkS")
		)
		(fp_line
			(start 1.524 -0.762)
			(end -1.524 -0.762)
			(stroke
				(width 0.1524)
				(type default)
			)
			(layer "B.SilkS")
		)
		(fp_line
			(start -1.1049 0.724916)
			(end -1.1049 -0.724916)
			(stroke
				(width 0.1)
				(type default)
			)
			(layer "B.Fab")
		)
		(fp_line
			(start 1.1049 0.724916)
			(end -1.1049 0.724916)
			(stroke
				(width 0.1)
				(type default)
			)
			(layer "B.Fab")
		)
		(fp_line
			(start -1.1049 -0.724916)
			(end 1.1049 -0.724916)
			(stroke
				(width 0.1)
				(type default)
			)
			(layer "B.Fab")
		)
		(fp_line
			(start 1.1049 -0.724916)
			(end 1.1049 0.724916)
			(stroke
				(width 0.1)
				(type default)
			)
			(layer "B.Fab")
		)
		(pad "1" smd rect
			(at 0.889 0 270)
			(size 1.016 1.27)
			(layers "B.Cu" "B.Mask" "B.Paste")
			(net "P1V8_CPU0_RT3_1A")
		)
		(pad "2" smd rect
			(at -0.889 0 270)
			(size 1.016 1.27)
			(layers "B.Cu" "B.Mask" "B.Paste")
			(net "GND")
		)
	)
	(footprint ""
		(layer "B.Cu")
		(at 56.073802 -193.996564)
		(property "Reference" "R103"
			(at 0 0 0)
			(layer "B.SilkS")
			(hide yes)
			(effects
				(font
					(size 1.27 1.27)
				)
				(justify mirror)
			)
		)
		(property "Value" ""
			(at 0 0 0)
			(layer "B.Fab")
			(effects
				(font
					(size 1.27 1.27)
				)
				(justify mirror)
			)
		)
		(duplicate_pad_numbers_are_jumpers no)
		(fp_line
			(start -0.7874 -0.4064)
			(end -0.7874 0.4064)
			(stroke
				(width 0.1524)
				(type default)
			)
			(layer "B.SilkS")
		)
		(fp_line
			(start -0.7874 0.4064)
			(end 0.7874 0.4064)
			(stroke
				(width 0.1524)
				(type default)
			)
			(layer "B.SilkS")
		)
		(fp_line
			(start 0.7874 -0.4064)
			(end -0.7874 -0.4064)
			(stroke
				(width 0.1524)
				(type default)
			)
			(layer "B.SilkS")
		)
		(fp_line
			(start 0.7874 0.4064)
			(end 0.7874 -0.4064)
			(stroke
				(width 0.1524)
				(type default)
			)
			(layer "B.SilkS")
		)
		(fp_line
			(start -0.67945 -0.3048)
			(end -0.67945 0.3048)
			(stroke
				(width 0.1)
				(type default)
			)
			(layer "B.Fab")
		)
		(fp_line
			(start -0.67945 0.3048)
			(end -0.120396 0.3048)
			(stroke
				(width 0.1)
				(type default)
			)
			(layer "B.Fab")
		)
		(fp_line
			(start -0.12065 -0.3048)
			(end -0.67945 -0.3048)
			(stroke
				(width 0.1)
				(type default)
			)
			(layer "B.Fab")
		)
		(fp_line
			(start -0.12065 -0.2794)
			(end -0.12065 -0.3048)
			(stroke
				(width 0.1)
				(type default)
			)
			(layer "B.Fab")
		)
		(fp_line
			(start -0.120396 0.2794)
			(end 0.12065 0.2794)
			(stroke
				(width 0.1)
				(type default)
			)
			(layer "B.Fab")
		)
		(fp_line
			(start -0.120396 0.3048)
			(end -0.120396 0.2794)
			(stroke
				(width 0.1)
				(type default)
			)
			(layer "B.Fab")
		)
		(fp_line
			(start 0.12065 -0.305054)
			(end 0.12065 -0.2794)
			(stroke
				(width 0.1)
				(type default)
			)
			(layer "B.Fab")
		)
		(fp_line
			(start 0.12065 -0.2794)
			(end -0.12065 -0.2794)
			(stroke
				(width 0.1)
				(type default)
			)
			(layer "B.Fab")
		)
		(fp_line
			(start 0.12065 0.2794)
			(end 0.12065 0.3048)
			(stroke
				(width 0.1)
				(type default)
			)
			(layer "B.Fab")
		)
		(fp_line
			(start 0.12065 0.3048)
			(end 0.67945 0.3048)
			(stroke
				(width 0.1)
				(type default)
			)
			(layer "B.Fab")
		)
		(fp_line
			(start 0.67945 -0.305054)
			(end 0.12065 -0.305054)
			(stroke
				(width 0.1)
				(type default)
			)
			(layer "B.Fab")
		)
		(fp_line
			(start 0.67945 0.3048)
			(end 0.67945 -0.305054)
			(stroke
				(width 0.1)
				(type default)
			)
			(layer "B.Fab")
		)
		(pad "1" smd circle
			(at 0.40005 0 180)
			(size 0 0)
			(layers "B.Cu" "B.Mask" "B.Paste")
			(net "P3V3")
		)
		(pad "2" smd circle
			(at -0.40005 0 180)
			(size 0 0)
			(layers "B.Cu" "B.Mask" "B.Paste")
			(net "PWRGD_CHA_CPU1_DIMM0")
		)
	)
	(footprint ""
		(layer "B.Cu")
		(at 369.900454 -268.41831)
		(property "Reference" "C2214"
			(at 0 0 0)
			(layer "B.SilkS")
			(hide yes)
			(effects
				(font
					(size 1.27 1.27)
				)
				(justify mirror)
			)
		)
		(property "Value" ""
			(at 0 0 0)
			(layer "B.Fab")
			(effects
				(font
					(size 1.27 1.27)
				)
				(justify mirror)
			)
		)
		(duplicate_pad_numbers_are_jumpers no)
		(fp_line
			(start -0.7874 -0.4064)
			(end -0.7874 0.4064)
			(stroke
				(width 0.1524)
				(type default)
			)
			(layer "B.SilkS")
		)
		(fp_line
			(start -0.7874 0.4064)
			(end 0.7874 0.4064)
			(stroke
				(width 0.1524)
				(type default)
			)
			(layer "B.SilkS")
		)
		(fp_line
			(start 0.7874 -0.4064)
			(end -0.7874 -0.4064)
			(stroke
				(width 0.1524)
				(type default)
			)
			(layer "B.SilkS")
		)
		(fp_line
			(start 0.7874 0.4064)
			(end 0.7874 -0.4064)
			(stroke
				(width 0.1524)
				(type default)
			)
			(layer "B.SilkS")
		)
		(fp_line
			(start -0.67945 -0.3048)
			(end -0.67945 0.3048)
			(stroke
				(width 0.1)
				(type default)
			)
			(layer "B.Fab")
		)
		(fp_line
			(start -0.67945 0.3048)
			(end -0.120396 0.3048)
			(stroke
				(width 0.1)
				(type default)
			)
			(layer "B.Fab")
		)
		(fp_line
			(start -0.12065 -0.3048)
			(end -0.67945 -0.3048)
			(stroke
				(width 0.1)
				(type default)
			)
			(layer "B.Fab")
		)
		(fp_line
			(start -0.12065 -0.2794)
			(end -0.12065 -0.3048)
			(stroke
				(width 0.1)
				(type default)
			)
			(layer "B.Fab")
		)
		(fp_line
			(start -0.120396 0.2794)
			(end 0.12065 0.2794)
			(stroke
				(width 0.1)
				(type default)
			)
			(layer "B.Fab")
		)
		(fp_line
			(start -0.120396 0.3048)
			(end -0.120396 0.2794)
			(stroke
				(width 0.1)
				(type default)
			)
			(layer "B.Fab")
		)
		(fp_line
			(start 0.12065 -0.305054)
			(end 0.12065 -0.2794)
			(stroke
				(width 0.1)
				(type default)
			)
			(layer "B.Fab")
		)
		(fp_line
			(start 0.12065 -0.2794)
			(end -0.12065 -0.2794)
			(stroke
				(width 0.1)
				(type default)
			)
			(layer "B.Fab")
		)
		(fp_line
			(start 0.12065 0.2794)
			(end 0.12065 0.3048)
			(stroke
				(width 0.1)
				(type default)
			)
			(layer "B.Fab")
		)
		(fp_line
			(start 0.12065 0.3048)
			(end 0.67945 0.3048)
			(stroke
				(width 0.1)
				(type default)
			)
			(layer "B.Fab")
		)
		(fp_line
			(start 0.67945 -0.305054)
			(end 0.12065 -0.305054)
			(stroke
				(width 0.1)
				(type default)
			)
			(layer "B.Fab")
		)
		(fp_line
			(start 0.67945 0.3048)
			(end 0.67945 -0.305054)
			(stroke
				(width 0.1)
				(type default)
			)
			(layer "B.Fab")
		)
		(pad "1" smd circle
			(at 0.40005 0 180)
			(size 0 0)
			(layers "B.Cu" "B.Mask" "B.Paste")
			(net "PVDDCR_CPU1_P0")
		)
		(pad "2" smd circle
			(at -0.40005 0 180)
			(size 0 0)
			(layers "B.Cu" "B.Mask" "B.Paste")
			(net "GND")
		)
	)
	(footprint ""
		(layer "B.Cu")
		(at 182.308246 -421.375586 90)
		(property "Reference" "R6235"
			(at 0 0 90)
			(layer "B.SilkS")
			(hide yes)
			(effects
				(font
					(size 1.27 1.27)
				)
				(justify mirror)
			)
		)
		(property "Value" ""
			(at 0 0 90)
			(layer "B.Fab")
			(effects
				(font
					(size 1.27 1.27)
				)
				(justify mirror)
			)
		)
		(duplicate_pad_numbers_are_jumpers no)
		(fp_line
			(start 0.7874 -0.4064)
			(end -0.7874 -0.4064)
			(stroke
				(width 0.1524)
				(type default)
			)
			(layer "B.SilkS")
		)
		(fp_line
			(start -0.7874 -0.4064)
			(end -0.7874 0.4064)
			(stroke
				(width 0.1524)
				(type default)
			)
			(layer "B.SilkS")
		)
		(fp_line
			(start 0.7874 0.4064)
			(end 0.7874 -0.4064)
			(stroke
				(width 0.1524)
				(type default)
			)
			(layer "B.SilkS")
		)
		(fp_line
			(start -0.7874 0.4064)
			(end 0.7874 0.4064)
			(stroke
				(width 0.1524)
				(type default)
			)
			(layer "B.SilkS")
		)
		(fp_line
			(start 0.67945 -0.305054)
			(end 0.12065 -0.305054)
			(stroke
				(width 0.1)
				(type default)
			)
			(layer "B.Fab")
		)
		(fp_line
			(start 0.12065 -0.305054)
			(end 0.12065 -0.2794)
			(stroke
				(width 0.1)
				(type default)
			)
			(layer "B.Fab")
		)
		(fp_line
			(start -0.12065 -0.3048)
			(end -0.67945 -0.3048)
			(stroke
				(width 0.1)
				(type default)
			)
			(layer "B.Fab")
		)
		(fp_line
			(start -0.67945 -0.3048)
			(end -0.67945 0.3048)
			(stroke
				(width 0.1)
				(type default)
			)
			(layer "B.Fab")
		)
		(fp_line
			(start 0.12065 -0.2794)
			(end -0.12065 -0.2794)
			(stroke
				(width 0.1)
				(type default)
			)
			(layer "B.Fab")
		)
		(fp_line
			(start -0.12065 -0.2794)
			(end -0.12065 -0.3048)
			(stroke
				(width 0.1)
				(type default)
			)
			(layer "B.Fab")
		)
		(fp_line
			(start 0.12065 0.2794)
			(end 0.12065 0.3048)
			(stroke
				(width 0.1)
				(type default)
			)
			(layer "B.Fab")
		)
		(fp_line
			(start -0.120396 0.2794)
			(end 0.12065 0.2794)
			(stroke
				(width 0.1)
				(type default)
			)
			(layer "B.Fab")
		)
		(fp_line
			(start 0.67945 0.3048)
			(end 0.67945 -0.305054)
			(stroke
				(width 0.1)
				(type default)
			)
			(layer "B.Fab")
		)
		(fp_line
			(start 0.12065 0.3048)
			(end 0.67945 0.3048)
			(stroke
				(width 0.1)
				(type default)
			)
			(layer "B.Fab")
		)
		(fp_line
			(start -0.120396 0.3048)
			(end -0.120396 0.2794)
			(stroke
				(width 0.1)
				(type default)
			)
			(layer "B.Fab")
		)
		(fp_line
			(start -0.67945 0.3048)
			(end -0.120396 0.3048)
			(stroke
				(width 0.1)
				(type default)
			)
			(layer "B.Fab")
		)
		(pad "1" smd circle
			(at 0.40005 0 270)
			(size 0 0)
			(layers "B.Cu" "B.Mask" "B.Paste")
			(net "A_HSC_HIGH")
		)
		(pad "2" smd circle
			(at -0.40005 0 270)
			(size 0 0)
			(layers "B.Cu" "B.Mask" "B.Paste")
			(net "GND")
		)
	)
	(footprint ""
		(layer "B.Cu")
		(at 123.01855 -388.011162 -90)
		(property "Reference" "C442"
			(at 0 0 90)
			(layer "B.SilkS")
			(hide yes)
			(effects
				(font
					(size 1.27 1.27)
				)
				(justify mirror)
			)
		)
		(property "Value" ""
			(at 0 0 90)
			(layer "B.Fab")
			(effects
				(font
					(size 1.27 1.27)
				)
				(justify mirror)
			)
		)
		(duplicate_pad_numbers_are_jumpers no)
		(fp_line
			(start -0.299974 0.150114)
			(end 0.299974 0.150114)
			(stroke
				(width 0.1)
				(type default)
			)
			(layer "B.Fab")
		)
		(fp_line
			(start 0.299974 0.150114)
			(end 0.299974 -0.150114)
			(stroke
				(width 0.1)
				(type default)
			)
			(layer "B.Fab")
		)
		(fp_line
			(start -0.299974 -0.150114)
			(end -0.299974 0.150114)
			(stroke
				(width 0.1)
				(type default)
			)
			(layer "B.Fab")
		)
		(fp_line
			(start 0.299974 -0.150114)
			(end -0.299974 -0.150114)
			(stroke
				(width 0.1)
				(type default)
			)
			(layer "B.Fab")
		)
		(pad "1" smd rect
			(at 0.2667 0 90)
			(size 0.3048 0.381)
			(layers "B.Cu" "B.Mask" "B.Paste")
			(net "P1V8_CPU1_RT3_1A")
		)
		(pad "2" smd rect
			(at -0.2667 0 90)
			(size 0.3048 0.381)
			(layers "B.Cu" "B.Mask" "B.Paste")
			(net "GND")
		)
	)
	(footprint ""
		(layer "B.Cu")
		(at 168.3004 -421.277796 -90)
		(property "Reference" "R1462"
			(at 0 0 90)
			(layer "B.SilkS")
			(hide yes)
			(effects
				(font
					(size 1.27 1.27)
				)
				(justify mirror)
			)
		)
		(property "Value" ""
			(at 0 0 90)
			(layer "B.Fab")
			(effects
				(font
					(size 1.27 1.27)
				)
				(justify mirror)
			)
		)
		(duplicate_pad_numbers_are_jumpers no)
		(fp_line
			(start -0.32512 0.175006)
			(end 0.32512 0.175006)
			(stroke
				(width 0.1)
				(type default)
			)
			(layer "B.Fab")
		)
		(fp_line
			(start 0.32512 0.175006)
			(end 0.32512 -0.175006)
			(stroke
				(width 0.1)
				(type default)
			)
			(layer "B.Fab")
		)
		(fp_line
			(start -0.32512 -0.175006)
			(end -0.32512 0.175006)
			(stroke
				(width 0.1)
				(type default)
			)
			(layer "B.Fab")
		)
		(fp_line
			(start 0.32512 -0.175006)
			(end -0.32512 -0.175006)
			(stroke
				(width 0.1)
				(type default)
			)
			(layer "B.Fab")
		)
		(pad "1" smd rect
			(at 0.2667 0 90)
			(size 0.3048 0.381)
			(layers "B.Cu" "B.Mask" "B.Paste")
			(net "P1V8_CPU1_RT_1D")
		)
		(pad "2" smd rect
			(at -0.2667 0 270)
			(size 0.3048 0.381)
			(layers "B.Cu" "B.Mask" "B.Paste")
			(net "SMB_RT_CPU1_P3_ROM_MUX_1D_SDA")
		)
	)
	(footprint ""
		(layer "B.Cu")
		(at 202.148186 -192.660016 180)
		(property "Reference" "C549"
			(at 0 0 0)
			(layer "B.SilkS")
			(hide yes)
			(effects
				(font
					(size 1.27 1.27)
				)
				(justify mirror)
			)
		)
		(property "Value" ""
			(at 0 0 0)
			(layer "B.Fab")
			(effects
				(font
					(size 1.27 1.27)
				)
				(justify mirror)
			)
		)
		(duplicate_pad_numbers_are_jumpers no)
		(fp_line
			(start 1.524 0.762)
			(end 1.524 -0.762)
			(stroke
				(width 0.1524)
				(type default)
			)
			(layer "B.SilkS")
		)
		(fp_line
			(start 1.524 -0.762)
			(end -1.524 -0.762)
			(stroke
				(width 0.1524)
				(type default)
			)
			(layer "B.SilkS")
		)
		(fp_line
			(start -1.524 0.762)
			(end 1.524 0.762)
			(stroke
				(width 0.1524)
				(type default)
			)
			(layer "B.SilkS")
		)
		(fp_line
			(start -1.524 -0.762)
			(end -1.524 0.762)
			(stroke
				(width 0.1524)
				(type default)
			)
			(layer "B.SilkS")
		)
		(fp_line
			(start 1.1049 0.724916)
			(end -1.1049 0.724916)
			(stroke
				(width 0.1)
				(type default)
			)
			(layer "B.Fab")
		)
		(fp_line
			(start 1.1049 -0.724916)
			(end 1.1049 0.724916)
			(stroke
				(width 0.1)
				(type default)
			)
			(layer "B.Fab")
		)
		(fp_line
			(start -1.1049 0.724916)
			(end -1.1049 -0.724916)
			(stroke
				(width 0.1)
				(type default)
			)
			(layer "B.Fab")
		)
		(fp_line
			(start -1.1049 -0.724916)
			(end 1.1049 -0.724916)
			(stroke
				(width 0.1)
				(type default)
			)
			(layer "B.Fab")
		)
		(pad "1" smd rect
			(at 0.889 0 180)
			(size 1.016 1.27)
			(layers "B.Cu" "B.Mask" "B.Paste")
			(net "P12V_MEM_CPU1")
		)
		(pad "2" smd rect
			(at -0.889 0 180)
			(size 1.016 1.27)
			(layers "B.Cu" "B.Mask" "B.Paste")
			(net "GND")
		)
	)
	(footprint ""
		(layer "B.Cu")
		(at 371.646958 -245.868952 -90)
		(property "Reference" "C2198"
			(at 0 0 90)
			(layer "B.SilkS")
			(hide yes)
			(effects
				(font
					(size 1.27 1.27)
				)
				(justify mirror)
			)
		)
		(property "Value" ""
			(at 0 0 90)
			(layer "B.Fab")
			(effects
				(font
					(size 1.27 1.27)
				)
				(justify mirror)
			)
		)
		(duplicate_pad_numbers_are_jumpers no)
		(fp_line
			(start -0.7874 0.4064)
			(end 0.7874 0.4064)
			(stroke
				(width 0.1524)
				(type default)
			)
			(layer "B.SilkS")
		)
		(fp_line
			(start 0.7874 0.4064)
			(end 0.7874 -0.4064)
			(stroke
				(width 0.1524)
				(type default)
			)
			(layer "B.SilkS")
		)
		(fp_line
			(start -0.7874 -0.4064)
			(end -0.7874 0.4064)
			(stroke
				(width 0.1524)
				(type default)
			)
			(layer "B.SilkS")
		)
		(fp_line
			(start 0.7874 -0.4064)
			(end -0.7874 -0.4064)
			(stroke
				(width 0.1524)
				(type default)
			)
			(layer "B.SilkS")
		)
		(fp_line
			(start -0.67945 0.3048)
			(end -0.120396 0.3048)
			(stroke
				(width 0.1)
				(type default)
			)
			(layer "B.Fab")
		)
		(fp_line
			(start -0.120396 0.3048)
			(end -0.120396 0.2794)
			(stroke
				(width 0.1)
				(type default)
			)
			(layer "B.Fab")
		)
		(fp_line
			(start 0.12065 0.3048)
			(end 0.67945 0.3048)
			(stroke
				(width 0.1)
				(type default)
			)
			(layer "B.Fab")
		)
		(fp_line
			(start 0.67945 0.3048)
			(end 0.67945 -0.305054)
			(stroke
				(width 0.1)
				(type default)
			)
			(layer "B.Fab")
		)
		(fp_line
			(start -0.120396 0.2794)
			(end 0.12065 0.2794)
			(stroke
				(width 0.1)
				(type default)
			)
			(layer "B.Fab")
		)
		(fp_line
			(start 0.12065 0.2794)
			(end 0.12065 0.3048)
			(stroke
				(width 0.1)
				(type default)
			)
			(layer "B.Fab")
		)
		(fp_line
			(start -0.12065 -0.2794)
			(end -0.12065 -0.3048)
			(stroke
				(width 0.1)
				(type default)
			)
			(layer "B.Fab")
		)
		(fp_line
			(start 0.12065 -0.2794)
			(end -0.12065 -0.2794)
			(stroke
				(width 0.1)
				(type default)
			)
			(layer "B.Fab")
		)
		(fp_line
			(start -0.67945 -0.3048)
			(end -0.67945 0.3048)
			(stroke
				(width 0.1)
				(type default)
			)
			(layer "B.Fab")
		)
		(fp_line
			(start -0.12065 -0.3048)
			(end -0.67945 -0.3048)
			(stroke
				(width 0.1)
				(type default)
			)
			(layer "B.Fab")
		)
		(fp_line
			(start 0.12065 -0.305054)
			(end 0.12065 -0.2794)
			(stroke
				(width 0.1)
				(type default)
			)
			(layer "B.Fab")
		)
		(fp_line
			(start 0.67945 -0.305054)
			(end 0.12065 -0.305054)
			(stroke
				(width 0.1)
				(type default)
			)
			(layer "B.Fab")
		)
		(pad "1" smd circle
			(at 0.40005 0 90)
			(size 0 0)
			(layers "B.Cu" "B.Mask" "B.Paste")
			(net "PVDDCR_CPU0_P0")
		)
		(pad "2" smd circle
			(at -0.40005 0 90)
			(size 0 0)
			(layers "B.Cu" "B.Mask" "B.Paste")
			(net "GND")
		)
	)
	(footprint ""
		(layer "B.Cu")
		(at 82.319114 -390.560052 90)
		(property "Reference" "C325"
			(at 0 0 90)
			(layer "B.SilkS")
			(hide yes)
			(effects
				(font
					(size 1.27 1.27)
				)
				(justify mirror)
			)
		)
		(property "Value" ""
			(at 0 0 90)
			(layer "B.Fab")
			(effects
				(font
					(size 1.27 1.27)
				)
				(justify mirror)
			)
		)
		(duplicate_pad_numbers_are_jumpers no)
		(fp_line
			(start 0.7874 -0.4064)
			(end -0.7874 -0.4064)
			(stroke
				(width 0.1524)
				(type default)
			)
			(layer "B.SilkS")
		)
		(fp_line
			(start -0.7874 -0.4064)
			(end -0.7874 0.4064)
			(stroke
				(width 0.1524)
				(type default)
			)
			(layer "B.SilkS")
		)
		(fp_line
			(start 0.7874 0.4064)
			(end 0.7874 -0.4064)
			(stroke
				(width 0.1524)
				(type default)
			)
			(layer "B.SilkS")
		)
		(fp_line
			(start -0.7874 0.4064)
			(end 0.7874 0.4064)
			(stroke
				(width 0.1524)
				(type default)
			)
			(layer "B.SilkS")
		)
		(fp_line
			(start 0.67945 -0.305054)
			(end 0.12065 -0.305054)
			(stroke
				(width 0.1)
				(type default)
			)
			(layer "B.Fab")
		)
		(fp_line
			(start 0.12065 -0.305054)
			(end 0.12065 -0.2794)
			(stroke
				(width 0.1)
				(type default)
			)
			(layer "B.Fab")
		)
		(fp_line
			(start -0.12065 -0.3048)
			(end -0.67945 -0.3048)
			(stroke
				(width 0.1)
				(type default)
			)
			(layer "B.Fab")
		)
		(fp_line
			(start -0.67945 -0.3048)
			(end -0.67945 0.3048)
			(stroke
				(width 0.1)
				(type default)
			)
			(layer "B.Fab")
		)
		(fp_line
			(start 0.12065 -0.2794)
			(end -0.12065 -0.2794)
			(stroke
				(width 0.1)
				(type default)
			)
			(layer "B.Fab")
		)
		(fp_line
			(start -0.12065 -0.2794)
			(end -0.12065 -0.3048)
			(stroke
				(width 0.1)
				(type default)
			)
			(layer "B.Fab")
		)
		(fp_line
			(start 0.12065 0.2794)
			(end 0.12065 0.3048)
			(stroke
				(width 0.1)
				(type default)
			)
			(layer "B.Fab")
		)
		(fp_line
			(start -0.120396 0.2794)
			(end 0.12065 0.2794)
			(stroke
				(width 0.1)
				(type default)
			)
			(layer "B.Fab")
		)
		(fp_line
			(start 0.67945 0.3048)
			(end 0.67945 -0.305054)
			(stroke
				(width 0.1)
				(type default)
			)
			(layer "B.Fab")
		)
		(fp_line
			(start 0.12065 0.3048)
			(end 0.67945 0.3048)
			(stroke
				(width 0.1)
				(type default)
			)
			(layer "B.Fab")
		)
		(fp_line
			(start -0.120396 0.3048)
			(end -0.120396 0.2794)
			(stroke
				(width 0.1)
				(type default)
			)
			(layer "B.Fab")
		)
		(fp_line
			(start -0.67945 0.3048)
			(end -0.120396 0.3048)
			(stroke
				(width 0.1)
				(type default)
			)
			(layer "B.Fab")
		)
		(pad "1" smd circle
			(at 0.40005 0 270)
			(size 0 0)
			(layers "B.Cu" "B.Mask" "B.Paste")
			(net "P0V9_CPU1_RT1_2A")
		)
		(pad "2" smd circle
			(at -0.40005 0 270)
			(size 0 0)
			(layers "B.Cu" "B.Mask" "B.Paste")
			(net "GND")
		)
	)
	(footprint ""
		(layer "B.Cu")
		(at 418.348922 -416.899344 90)
		(property "Reference" "C6628"
			(at 0 0 90)
			(layer "B.SilkS")
			(hide yes)
			(effects
				(font
					(size 1.27 1.27)
				)
				(justify mirror)
			)
		)
		(property "Value" ""
			(at 0 0 90)
			(layer "B.Fab")
			(effects
				(font
					(size 1.27 1.27)
				)
				(justify mirror)
			)
		)
		(duplicate_pad_numbers_are_jumpers no)
		(fp_line
			(start 0.299974 -0.150114)
			(end -0.299974 -0.150114)
			(stroke
				(width 0.1)
				(type default)
			)
			(layer "B.Fab")
		)
		(fp_line
			(start -0.299974 -0.150114)
			(end -0.299974 0.150114)
			(stroke
				(width 0.1)
				(type default)
			)
			(layer "B.Fab")
		)
		(fp_line
			(start 0.299974 0.150114)
			(end 0.299974 -0.150114)
			(stroke
				(width 0.1)
				(type default)
			)
			(layer "B.Fab")
		)
		(fp_line
			(start -0.299974 0.150114)
			(end 0.299974 0.150114)
			(stroke
				(width 0.1)
				(type default)
			)
			(layer "B.Fab")
		)
		(pad "1" smd rect
			(at 0.2667 0 270)
			(size 0.3048 0.381)
			(layers "B.Cu" "B.Mask" "B.Paste")
			(net "P5E_CPU0_P3_TX_BUF_C_DN<15>")
		)
		(pad "2" smd rect
			(at -0.2667 0 270)
			(size 0.3048 0.381)
			(layers "B.Cu" "B.Mask" "B.Paste")
			(net "P5E_CPU0_P3_TX_BUF_DN<15>")
		)
	)
	(footprint ""
		(layer "B.Cu")
		(at 98.493834 -263.521952)
		(property "Reference" "C2493"
			(at 0 0 0)
			(layer "B.SilkS")
			(hide yes)
			(effects
				(font
					(size 1.27 1.27)
				)
				(justify mirror)
			)
		)
		(property "Value" ""
			(at 0 0 0)
			(layer "B.Fab")
			(effects
				(font
					(size 1.27 1.27)
				)
				(justify mirror)
			)
		)
		(duplicate_pad_numbers_are_jumpers no)
		(fp_line
			(start -0.7874 -0.4064)
			(end -0.7874 0.4064)
			(stroke
				(width 0.1524)
				(type default)
			)
			(layer "B.SilkS")
		)
		(fp_line
			(start -0.7874 0.4064)
			(end 0.7874 0.4064)
			(stroke
				(width 0.1524)
				(type default)
			)
			(layer "B.SilkS")
		)
		(fp_line
			(start 0.7874 -0.4064)
			(end -0.7874 -0.4064)
			(stroke
				(width 0.1524)
				(type default)
			)
			(layer "B.SilkS")
		)
		(fp_line
			(start 0.7874 0.4064)
			(end 0.7874 -0.4064)
			(stroke
				(width 0.1524)
				(type default)
			)
			(layer "B.SilkS")
		)
		(fp_line
			(start -0.67945 -0.3048)
			(end -0.67945 0.3048)
			(stroke
				(width 0.1)
				(type default)
			)
			(layer "B.Fab")
		)
		(fp_line
			(start -0.67945 0.3048)
			(end -0.120396 0.3048)
			(stroke
				(width 0.1)
				(type default)
			)
			(layer "B.Fab")
		)
		(fp_line
			(start -0.12065 -0.3048)
			(end -0.67945 -0.3048)
			(stroke
				(width 0.1)
				(type default)
			)
			(layer "B.Fab")
		)
		(fp_line
			(start -0.12065 -0.2794)
			(end -0.12065 -0.3048)
			(stroke
				(width 0.1)
				(type default)
			)
			(layer "B.Fab")
		)
		(fp_line
			(start -0.120396 0.2794)
			(end 0.12065 0.2794)
			(stroke
				(width 0.1)
				(type default)
			)
			(layer "B.Fab")
		)
		(fp_line
			(start -0.120396 0.3048)
			(end -0.120396 0.2794)
			(stroke
				(width 0.1)
				(type default)
			)
			(layer "B.Fab")
		)
		(fp_line
			(start 0.12065 -0.305054)
			(end 0.12065 -0.2794)
			(stroke
				(width 0.1)
				(type default)
			)
			(layer "B.Fab")
		)
		(fp_line
			(start 0.12065 -0.2794)
			(end -0.12065 -0.2794)
			(stroke
				(width 0.1)
				(type default)
			)
			(layer "B.Fab")
		)
		(fp_line
			(start 0.12065 0.2794)
			(end 0.12065 0.3048)
			(stroke
				(width 0.1)
				(type default)
			)
			(layer "B.Fab")
		)
		(fp_line
			(start 0.12065 0.3048)
			(end 0.67945 0.3048)
			(stroke
				(width 0.1)
				(type default)
			)
			(layer "B.Fab")
		)
		(fp_line
			(start 0.67945 -0.305054)
			(end 0.12065 -0.305054)
			(stroke
				(width 0.1)
				(type default)
			)
			(layer "B.Fab")
		)
		(fp_line
			(start 0.67945 0.3048)
			(end 0.67945 -0.305054)
			(stroke
				(width 0.1)
				(type default)
			)
			(layer "B.Fab")
		)
		(pad "1" smd circle
			(at 0.40005 0 180)
			(size 0 0)
			(layers "B.Cu" "B.Mask" "B.Paste")
			(net "PVDDIO_P1")
		)
		(pad "2" smd circle
			(at -0.40005 0 180)
			(size 0 0)
			(layers "B.Cu" "B.Mask" "B.Paste")
			(net "GND")
		)
	)
	(footprint ""
		(layer "B.Cu")
		(at 115.991386 -249.368564)
		(property "Reference" "C2307"
			(at 0 0 0)
			(layer "B.SilkS")
			(hide yes)
			(effects
				(font
					(size 1.27 1.27)
				)
				(justify mirror)
			)
		)
		(property "Value" ""
			(at 0 0 0)
			(layer "B.Fab")
			(effects
				(font
					(size 1.27 1.27)
				)
				(justify mirror)
			)
		)
		(duplicate_pad_numbers_are_jumpers no)
		(fp_line
			(start -0.7874 -0.4064)
			(end -0.7874 0.4064)
			(stroke
				(width 0.1524)
				(type default)
			)
			(layer "B.SilkS")
		)
		(fp_line
			(start -0.7874 0.4064)
			(end 0.7874 0.4064)
			(stroke
				(width 0.1524)
				(type default)
			)
			(layer "B.SilkS")
		)
		(fp_line
			(start 0.7874 -0.4064)
			(end -0.7874 -0.4064)
			(stroke
				(width 0.1524)
				(type default)
			)
			(layer "B.SilkS")
		)
		(fp_line
			(start 0.7874 0.4064)
			(end 0.7874 -0.4064)
			(stroke
				(width 0.1524)
				(type default)
			)
			(layer "B.SilkS")
		)
		(fp_line
			(start -0.67945 -0.3048)
			(end -0.67945 0.3048)
			(stroke
				(width 0.1)
				(type default)
			)
			(layer "B.Fab")
		)
		(fp_line
			(start -0.67945 0.3048)
			(end -0.120396 0.3048)
			(stroke
				(width 0.1)
				(type default)
			)
			(layer "B.Fab")
		)
		(fp_line
			(start -0.12065 -0.3048)
			(end -0.67945 -0.3048)
			(stroke
				(width 0.1)
				(type default)
			)
			(layer "B.Fab")
		)
		(fp_line
			(start -0.12065 -0.2794)
			(end -0.12065 -0.3048)
			(stroke
				(width 0.1)
				(type default)
			)
			(layer "B.Fab")
		)
		(fp_line
			(start -0.120396 0.2794)
			(end 0.12065 0.2794)
			(stroke
				(width 0.1)
				(type default)
			)
			(layer "B.Fab")
		)
		(fp_line
			(start -0.120396 0.3048)
			(end -0.120396 0.2794)
			(stroke
				(width 0.1)
				(type default)
			)
			(layer "B.Fab")
		)
		(fp_line
			(start 0.12065 -0.305054)
			(end 0.12065 -0.2794)
			(stroke
				(width 0.1)
				(type default)
			)
			(layer "B.Fab")
		)
		(fp_line
			(start 0.12065 -0.2794)
			(end -0.12065 -0.2794)
			(stroke
				(width 0.1)
				(type default)
			)
			(layer "B.Fab")
		)
		(fp_line
			(start 0.12065 0.2794)
			(end 0.12065 0.3048)
			(stroke
				(width 0.1)
				(type default)
			)
			(layer "B.Fab")
		)
		(fp_line
			(start 0.12065 0.3048)
			(end 0.67945 0.3048)
			(stroke
				(width 0.1)
				(type default)
			)
			(layer "B.Fab")
		)
		(fp_line
			(start 0.67945 -0.305054)
			(end 0.12065 -0.305054)
			(stroke
				(width 0.1)
				(type default)
			)
			(layer "B.Fab")
		)
		(fp_line
			(start 0.67945 0.3048)
			(end 0.67945 -0.305054)
			(stroke
				(width 0.1)
				(type default)
			)
			(layer "B.Fab")
		)
		(pad "1" smd circle
			(at 0.40005 0 180)
			(size 0 0)
			(layers "B.Cu" "B.Mask" "B.Paste")
			(net "PVDDCR_CPU0_P1")
		)
		(pad "2" smd circle
			(at -0.40005 0 180)
			(size 0 0)
			(layers "B.Cu" "B.Mask" "B.Paste")
			(net "GND")
		)
	)
	(footprint ""
		(layer "B.Cu")
		(at 455.07783 -48.106838 -90)
		(property "Reference" "R3118"
			(at 0 0 90)
			(layer "B.SilkS")
			(hide yes)
			(effects
				(font
					(size 1.27 1.27)
				)
				(justify mirror)
			)
		)
		(property "Value" ""
			(at 0 0 90)
			(layer "B.Fab")
			(effects
				(font
					(size 1.27 1.27)
				)
				(justify mirror)
			)
		)
		(duplicate_pad_numbers_are_jumpers no)
		(fp_line
			(start -0.7874 0.4064)
			(end 0.7874 0.4064)
			(stroke
				(width 0.1524)
				(type default)
			)
			(layer "B.SilkS")
		)
		(fp_line
			(start 0.7874 0.4064)
			(end 0.7874 -0.4064)
			(stroke
				(width 0.1524)
				(type default)
			)
			(layer "B.SilkS")
		)
		(fp_line
			(start -0.7874 -0.4064)
			(end -0.7874 0.4064)
			(stroke
				(width 0.1524)
				(type default)
			)
			(layer "B.SilkS")
		)
		(fp_line
			(start 0.7874 -0.4064)
			(end -0.7874 -0.4064)
			(stroke
				(width 0.1524)
				(type default)
			)
			(layer "B.SilkS")
		)
		(fp_line
			(start -0.67945 0.3048)
			(end -0.120396 0.3048)
			(stroke
				(width 0.1)
				(type default)
			)
			(layer "B.Fab")
		)
		(fp_line
			(start -0.120396 0.3048)
			(end -0.120396 0.2794)
			(stroke
				(width 0.1)
				(type default)
			)
			(layer "B.Fab")
		)
		(fp_line
			(start 0.12065 0.3048)
			(end 0.67945 0.3048)
			(stroke
				(width 0.1)
				(type default)
			)
			(layer "B.Fab")
		)
		(fp_line
			(start 0.67945 0.3048)
			(end 0.67945 -0.305054)
			(stroke
				(width 0.1)
				(type default)
			)
			(layer "B.Fab")
		)
		(fp_line
			(start -0.120396 0.2794)
			(end 0.12065 0.2794)
			(stroke
				(width 0.1)
				(type default)
			)
			(layer "B.Fab")
		)
		(fp_line
			(start 0.12065 0.2794)
			(end 0.12065 0.3048)
			(stroke
				(width 0.1)
				(type default)
			)
			(layer "B.Fab")
		)
		(fp_line
			(start -0.12065 -0.2794)
			(end -0.12065 -0.3048)
			(stroke
				(width 0.1)
				(type default)
			)
			(layer "B.Fab")
		)
		(fp_line
			(start 0.12065 -0.2794)
			(end -0.12065 -0.2794)
			(stroke
				(width 0.1)
				(type default)
			)
			(layer "B.Fab")
		)
		(fp_line
			(start -0.67945 -0.3048)
			(end -0.67945 0.3048)
			(stroke
				(width 0.1)
				(type default)
			)
			(layer "B.Fab")
		)
		(fp_line
			(start -0.12065 -0.3048)
			(end -0.67945 -0.3048)
			(stroke
				(width 0.1)
				(type default)
			)
			(layer "B.Fab")
		)
		(fp_line
			(start 0.12065 -0.305054)
			(end 0.12065 -0.2794)
			(stroke
				(width 0.1)
				(type default)
			)
			(layer "B.Fab")
		)
		(fp_line
			(start 0.67945 -0.305054)
			(end 0.12065 -0.305054)
			(stroke
				(width 0.1)
				(type default)
			)
			(layer "B.Fab")
		)
		(pad "1" smd circle
			(at 0.40005 0 90)
			(size 0 0)
			(layers "B.Cu" "B.Mask" "B.Paste")
			(net "P3V3_AUX_EN")
		)
		(pad "2" smd circle
			(at -0.40005 0 90)
			(size 0 0)
			(layers "B.Cu" "B.Mask" "B.Paste")
			(net "GND")
		)
	)
	(footprint ""
		(layer "B.Cu")
		(at 49.91862 -388.011162 -90)
		(property "Reference" "C184"
			(at 0 0 90)
			(layer "B.SilkS")
			(hide yes)
			(effects
				(font
					(size 1.27 1.27)
				)
				(justify mirror)
			)
		)
		(property "Value" ""
			(at 0 0 90)
			(layer "B.Fab")
			(effects
				(font
					(size 1.27 1.27)
				)
				(justify mirror)
			)
		)
		(duplicate_pad_numbers_are_jumpers no)
		(fp_line
			(start -0.299974 0.150114)
			(end 0.299974 0.150114)
			(stroke
				(width 0.1)
				(type default)
			)
			(layer "B.Fab")
		)
		(fp_line
			(start 0.299974 0.150114)
			(end 0.299974 -0.150114)
			(stroke
				(width 0.1)
				(type default)
			)
			(layer "B.Fab")
		)
		(fp_line
			(start -0.299974 -0.150114)
			(end -0.299974 0.150114)
			(stroke
				(width 0.1)
				(type default)
			)
			(layer "B.Fab")
		)
		(fp_line
			(start 0.299974 -0.150114)
			(end -0.299974 -0.150114)
			(stroke
				(width 0.1)
				(type default)
			)
			(layer "B.Fab")
		)
		(pad "1" smd rect
			(at 0.2667 0 90)
			(size 0.3048 0.381)
			(layers "B.Cu" "B.Mask" "B.Paste")
			(net "P0V9_CPU1_RT0_2A")
		)
		(pad "2" smd rect
			(at -0.2667 0 90)
			(size 0.3048 0.381)
			(layers "B.Cu" "B.Mask" "B.Paste")
			(net "GND")
		)
	)
	(footprint ""
		(layer "B.Cu")
		(at 101.894386 -255.845564)
		(property "Reference" "C2470"
			(at 0 0 0)
			(layer "B.SilkS")
			(hide yes)
			(effects
				(font
					(size 1.27 1.27)
				)
				(justify mirror)
			)
		)
		(property "Value" ""
			(at 0 0 0)
			(layer "B.Fab")
			(effects
				(font
					(size 1.27 1.27)
				)
				(justify mirror)
			)
		)
		(duplicate_pad_numbers_are_jumpers no)
		(fp_line
			(start -0.7874 -0.4064)
			(end -0.7874 0.4064)
			(stroke
				(width 0.1524)
				(type default)
			)
			(layer "B.SilkS")
		)
		(fp_line
			(start -0.7874 0.4064)
			(end 0.7874 0.4064)
			(stroke
				(width 0.1524)
				(type default)
			)
			(layer "B.SilkS")
		)
		(fp_line
			(start 0.7874 -0.4064)
			(end -0.7874 -0.4064)
			(stroke
				(width 0.1524)
				(type default)
			)
			(layer "B.SilkS")
		)
		(fp_line
			(start 0.7874 0.4064)
			(end 0.7874 -0.4064)
			(stroke
				(width 0.1524)
				(type default)
			)
			(layer "B.SilkS")
		)
		(fp_line
			(start -0.67945 -0.3048)
			(end -0.67945 0.3048)
			(stroke
				(width 0.1)
				(type default)
			)
			(layer "B.Fab")
		)
		(fp_line
			(start -0.67945 0.3048)
			(end -0.120396 0.3048)
			(stroke
				(width 0.1)
				(type default)
			)
			(layer "B.Fab")
		)
		(fp_line
			(start -0.12065 -0.3048)
			(end -0.67945 -0.3048)
			(stroke
				(width 0.1)
				(type default)
			)
			(layer "B.Fab")
		)
		(fp_line
			(start -0.12065 -0.2794)
			(end -0.12065 -0.3048)
			(stroke
				(width 0.1)
				(type default)
			)
			(layer "B.Fab")
		)
		(fp_line
			(start -0.120396 0.2794)
			(end 0.12065 0.2794)
			(stroke
				(width 0.1)
				(type default)
			)
			(layer "B.Fab")
		)
		(fp_line
			(start -0.120396 0.3048)
			(end -0.120396 0.2794)
			(stroke
				(width 0.1)
				(type default)
			)
			(layer "B.Fab")
		)
		(fp_line
			(start 0.12065 -0.305054)
			(end 0.12065 -0.2794)
			(stroke
				(width 0.1)
				(type default)
			)
			(layer "B.Fab")
		)
		(fp_line
			(start 0.12065 -0.2794)
			(end -0.12065 -0.2794)
			(stroke
				(width 0.1)
				(type default)
			)
			(layer "B.Fab")
		)
		(fp_line
			(start 0.12065 0.2794)
			(end 0.12065 0.3048)
			(stroke
				(width 0.1)
				(type default)
			)
			(layer "B.Fab")
		)
		(fp_line
			(start 0.12065 0.3048)
			(end 0.67945 0.3048)
			(stroke
				(width 0.1)
				(type default)
			)
			(layer "B.Fab")
		)
		(fp_line
			(start 0.67945 -0.305054)
			(end 0.12065 -0.305054)
			(stroke
				(width 0.1)
				(type default)
			)
			(layer "B.Fab")
		)
		(fp_line
			(start 0.67945 0.3048)
			(end 0.67945 -0.305054)
			(stroke
				(width 0.1)
				(type default)
			)
			(layer "B.Fab")
		)
		(pad "1" smd circle
			(at 0.40005 0 180)
			(size 0 0)
			(layers "B.Cu" "B.Mask" "B.Paste")
			(net "PVDDCR_SOC_P1")
		)
		(pad "2" smd circle
			(at -0.40005 0 180)
			(size 0 0)
			(layers "B.Cu" "B.Mask" "B.Paste")
			(net "GND")
		)
	)
	(footprint ""
		(layer "B.Cu")
		(at 77.627734 -388.609078 90)
		(property "Reference" "C312"
			(at 0 0 90)
			(layer "B.SilkS")
			(hide yes)
			(effects
				(font
					(size 1.27 1.27)
				)
				(justify mirror)
			)
		)
		(property "Value" ""
			(at 0 0 90)
			(layer "B.Fab")
			(effects
				(font
					(size 1.27 1.27)
				)
				(justify mirror)
			)
		)
		(duplicate_pad_numbers_are_jumpers no)
		(fp_line
			(start 0.299974 -0.150114)
			(end -0.299974 -0.150114)
			(stroke
				(width 0.1)
				(type default)
			)
			(layer "B.Fab")
		)
		(fp_line
			(start -0.299974 -0.150114)
			(end -0.299974 0.150114)
			(stroke
				(width 0.1)
				(type default)
			)
			(layer "B.Fab")
		)
		(fp_line
			(start 0.299974 0.150114)
			(end 0.299974 -0.150114)
			(stroke
				(width 0.1)
				(type default)
			)
			(layer "B.Fab")
		)
		(fp_line
			(start -0.299974 0.150114)
			(end 0.299974 0.150114)
			(stroke
				(width 0.1)
				(type default)
			)
			(layer "B.Fab")
		)
		(pad "1" smd rect
			(at 0.2667 0 270)
			(size 0.3048 0.381)
			(layers "B.Cu" "B.Mask" "B.Paste")
			(net "P0V9_CPU1_RT1_2A")
		)
		(pad "2" smd rect
			(at -0.2667 0 270)
			(size 0.3048 0.381)
			(layers "B.Cu" "B.Mask" "B.Paste")
			(net "GND")
		)
	)
	(footprint ""
		(layer "B.Cu")
		(at 126.911608 -38.87343 90)
		(property "Reference" "C6060"
			(at 0 0 90)
			(layer "B.SilkS")
			(hide yes)
			(effects
				(font
					(size 1.27 1.27)
				)
				(justify mirror)
			)
		)
		(property "Value" ""
			(at 0 0 90)
			(layer "B.Fab")
			(effects
				(font
					(size 1.27 1.27)
				)
				(justify mirror)
			)
		)
		(duplicate_pad_numbers_are_jumpers no)
		(fp_line
			(start 0.7874 -0.4064)
			(end -0.7874 -0.4064)
			(stroke
				(width 0.1524)
				(type default)
			)
			(layer "B.SilkS")
		)
		(fp_line
			(start -0.7874 -0.4064)
			(end -0.7874 0.4064)
			(stroke
				(width 0.1524)
				(type default)
			)
			(layer "B.SilkS")
		)
		(fp_line
			(start 0.7874 0.4064)
			(end 0.7874 -0.4064)
			(stroke
				(width 0.1524)
				(type default)
			)
			(layer "B.SilkS")
		)
		(fp_line
			(start -0.7874 0.4064)
			(end 0.7874 0.4064)
			(stroke
				(width 0.1524)
				(type default)
			)
			(layer "B.SilkS")
		)
		(fp_line
			(start 0.67945 -0.305054)
			(end 0.12065 -0.305054)
			(stroke
				(width 0.1)
				(type default)
			)
			(layer "B.Fab")
		)
		(fp_line
			(start 0.12065 -0.305054)
			(end 0.12065 -0.2794)
			(stroke
				(width 0.1)
				(type default)
			)
			(layer "B.Fab")
		)
		(fp_line
			(start -0.12065 -0.3048)
			(end -0.67945 -0.3048)
			(stroke
				(width 0.1)
				(type default)
			)
			(layer "B.Fab")
		)
		(fp_line
			(start -0.67945 -0.3048)
			(end -0.67945 0.3048)
			(stroke
				(width 0.1)
				(type default)
			)
			(layer "B.Fab")
		)
		(fp_line
			(start 0.12065 -0.2794)
			(end -0.12065 -0.2794)
			(stroke
				(width 0.1)
				(type default)
			)
			(layer "B.Fab")
		)
		(fp_line
			(start -0.12065 -0.2794)
			(end -0.12065 -0.3048)
			(stroke
				(width 0.1)
				(type default)
			)
			(layer "B.Fab")
		)
		(fp_line
			(start 0.12065 0.2794)
			(end 0.12065 0.3048)
			(stroke
				(width 0.1)
				(type default)
			)
			(layer "B.Fab")
		)
		(fp_line
			(start -0.120396 0.2794)
			(end 0.12065 0.2794)
			(stroke
				(width 0.1)
				(type default)
			)
			(layer "B.Fab")
		)
		(fp_line
			(start 0.67945 0.3048)
			(end 0.67945 -0.305054)
			(stroke
				(width 0.1)
				(type default)
			)
			(layer "B.Fab")
		)
		(fp_line
			(start 0.12065 0.3048)
			(end 0.67945 0.3048)
			(stroke
				(width 0.1)
				(type default)
			)
			(layer "B.Fab")
		)
		(fp_line
			(start -0.120396 0.3048)
			(end -0.120396 0.2794)
			(stroke
				(width 0.1)
				(type default)
			)
			(layer "B.Fab")
		)
		(fp_line
			(start -0.67945 0.3048)
			(end -0.120396 0.3048)
			(stroke
				(width 0.1)
				(type default)
			)
			(layer "B.Fab")
		)
		(pad "1" smd circle
			(at 0.40005 0 270)
			(size 0 0)
			(layers "B.Cu" "B.Mask" "B.Paste")
			(net "P1V2_AUX")
		)
		(pad "2" smd circle
			(at -0.40005 0 270)
			(size 0 0)
			(layers "B.Cu" "B.Mask" "B.Paste")
			(net "GND")
		)
	)
	(footprint ""
		(layer "B.Cu")
		(at 76.869544 -408.517344 90)
		(property "Reference" "C6680"
			(at 0 0 90)
			(layer "B.SilkS")
			(hide yes)
			(effects
				(font
					(size 1.27 1.27)
				)
				(justify mirror)
			)
		)
		(property "Value" ""
			(at 0 0 90)
			(layer "B.Fab")
			(effects
				(font
					(size 1.27 1.27)
				)
				(justify mirror)
			)
		)
		(duplicate_pad_numbers_are_jumpers no)
		(fp_line
			(start 0.299974 -0.150114)
			(end -0.299974 -0.150114)
			(stroke
				(width 0.1)
				(type default)
			)
			(layer "B.Fab")
		)
		(fp_line
			(start -0.299974 -0.150114)
			(end -0.299974 0.150114)
			(stroke
				(width 0.1)
				(type default)
			)
			(layer "B.Fab")
		)
		(fp_line
			(start 0.299974 0.150114)
			(end 0.299974 -0.150114)
			(stroke
				(width 0.1)
				(type default)
			)
			(layer "B.Fab")
		)
		(fp_line
			(start -0.299974 0.150114)
			(end 0.299974 0.150114)
			(stroke
				(width 0.1)
				(type default)
			)
			(layer "B.Fab")
		)
		(pad "1" smd rect
			(at 0.2667 0 270)
			(size 0.3048 0.381)
			(layers "B.Cu" "B.Mask" "B.Paste")
			(net "P5E_CPU1_P1_TX_BUF_C_DN<9>")
		)
		(pad "2" smd rect
			(at -0.2667 0 270)
			(size 0.3048 0.381)
			(layers "B.Cu" "B.Mask" "B.Paste")
			(net "P5E_CPU1_P1_TX_BUF_DN<9>")
		)
	)
	(footprint ""
		(layer "B.Cu")
		(at 94.31909 -390.560052 90)
		(property "Reference" "C339"
			(at 0 0 90)
			(layer "B.SilkS")
			(hide yes)
			(effects
				(font
					(size 1.27 1.27)
				)
				(justify mirror)
			)
		)
		(property "Value" ""
			(at 0 0 90)
			(layer "B.Fab")
			(effects
				(font
					(size 1.27 1.27)
				)
				(justify mirror)
			)
		)
		(duplicate_pad_numbers_are_jumpers no)
		(fp_line
			(start 0.7874 -0.4064)
			(end -0.7874 -0.4064)
			(stroke
				(width 0.1524)
				(type default)
			)
			(layer "B.SilkS")
		)
		(fp_line
			(start -0.7874 -0.4064)
			(end -0.7874 0.4064)
			(stroke
				(width 0.1524)
				(type default)
			)
			(layer "B.SilkS")
		)
		(fp_line
			(start 0.7874 0.4064)
			(end 0.7874 -0.4064)
			(stroke
				(width 0.1524)
				(type default)
			)
			(layer "B.SilkS")
		)
		(fp_line
			(start -0.7874 0.4064)
			(end 0.7874 0.4064)
			(stroke
				(width 0.1524)
				(type default)
			)
			(layer "B.SilkS")
		)
		(fp_line
			(start 0.67945 -0.305054)
			(end 0.12065 -0.305054)
			(stroke
				(width 0.1)
				(type default)
			)
			(layer "B.Fab")
		)
		(fp_line
			(start 0.12065 -0.305054)
			(end 0.12065 -0.2794)
			(stroke
				(width 0.1)
				(type default)
			)
			(layer "B.Fab")
		)
		(fp_line
			(start -0.12065 -0.3048)
			(end -0.67945 -0.3048)
			(stroke
				(width 0.1)
				(type default)
			)
			(layer "B.Fab")
		)
		(fp_line
			(start -0.67945 -0.3048)
			(end -0.67945 0.3048)
			(stroke
				(width 0.1)
				(type default)
			)
			(layer "B.Fab")
		)
		(fp_line
			(start 0.12065 -0.2794)
			(end -0.12065 -0.2794)
			(stroke
				(width 0.1)
				(type default)
			)
			(layer "B.Fab")
		)
		(fp_line
			(start -0.12065 -0.2794)
			(end -0.12065 -0.3048)
			(stroke
				(width 0.1)
				(type default)
			)
			(layer "B.Fab")
		)
		(fp_line
			(start 0.12065 0.2794)
			(end 0.12065 0.3048)
			(stroke
				(width 0.1)
				(type default)
			)
			(layer "B.Fab")
		)
		(fp_line
			(start -0.120396 0.2794)
			(end 0.12065 0.2794)
			(stroke
				(width 0.1)
				(type default)
			)
			(layer "B.Fab")
		)
		(fp_line
			(start 0.67945 0.3048)
			(end 0.67945 -0.305054)
			(stroke
				(width 0.1)
				(type default)
			)
			(layer "B.Fab")
		)
		(fp_line
			(start 0.12065 0.3048)
			(end 0.67945 0.3048)
			(stroke
				(width 0.1)
				(type default)
			)
			(layer "B.Fab")
		)
		(fp_line
			(start -0.120396 0.3048)
			(end -0.120396 0.2794)
			(stroke
				(width 0.1)
				(type default)
			)
			(layer "B.Fab")
		)
		(fp_line
			(start -0.67945 0.3048)
			(end -0.120396 0.3048)
			(stroke
				(width 0.1)
				(type default)
			)
			(layer "B.Fab")
		)
		(pad "1" smd circle
			(at 0.40005 0 270)
			(size 0 0)
			(layers "B.Cu" "B.Mask" "B.Paste")
			(net "P0V9_CPU1_RT1_2A")
		)
		(pad "2" smd circle
			(at -0.40005 0 270)
			(size 0 0)
			(layers "B.Cu" "B.Mask" "B.Paste")
			(net "GND")
		)
	)
	(footprint ""
		(layer "B.Cu")
		(at 329.068176 -395.127988 -90)
		(property "Reference" "C506"
			(at 0 0 90)
			(layer "B.SilkS")
			(hide yes)
			(effects
				(font
					(size 1.27 1.27)
				)
				(justify mirror)
			)
		)
		(property "Value" ""
			(at 0 0 90)
			(layer "B.Fab")
			(effects
				(font
					(size 1.27 1.27)
				)
				(justify mirror)
			)
		)
		(duplicate_pad_numbers_are_jumpers no)
		(fp_line
			(start -0.7874 0.4064)
			(end 0.7874 0.4064)
			(stroke
				(width 0.1524)
				(type default)
			)
			(layer "B.SilkS")
		)
		(fp_line
			(start 0.7874 0.4064)
			(end 0.7874 -0.4064)
			(stroke
				(width 0.1524)
				(type default)
			)
			(layer "B.SilkS")
		)
		(fp_line
			(start -0.7874 -0.4064)
			(end -0.7874 0.4064)
			(stroke
				(width 0.1524)
				(type default)
			)
			(layer "B.SilkS")
		)
		(fp_line
			(start 0.7874 -0.4064)
			(end -0.7874 -0.4064)
			(stroke
				(width 0.1524)
				(type default)
			)
			(layer "B.SilkS")
		)
		(fp_line
			(start -0.67945 0.3048)
			(end -0.120396 0.3048)
			(stroke
				(width 0.1)
				(type default)
			)
			(layer "B.Fab")
		)
		(fp_line
			(start -0.120396 0.3048)
			(end -0.120396 0.2794)
			(stroke
				(width 0.1)
				(type default)
			)
			(layer "B.Fab")
		)
		(fp_line
			(start 0.12065 0.3048)
			(end 0.67945 0.3048)
			(stroke
				(width 0.1)
				(type default)
			)
			(layer "B.Fab")
		)
		(fp_line
			(start 0.67945 0.3048)
			(end 0.67945 -0.305054)
			(stroke
				(width 0.1)
				(type default)
			)
			(layer "B.Fab")
		)
		(fp_line
			(start -0.120396 0.2794)
			(end 0.12065 0.2794)
			(stroke
				(width 0.1)
				(type default)
			)
			(layer "B.Fab")
		)
		(fp_line
			(start 0.12065 0.2794)
			(end 0.12065 0.3048)
			(stroke
				(width 0.1)
				(type default)
			)
			(layer "B.Fab")
		)
		(fp_line
			(start -0.12065 -0.2794)
			(end -0.12065 -0.3048)
			(stroke
				(width 0.1)
				(type default)
			)
			(layer "B.Fab")
		)
		(fp_line
			(start 0.12065 -0.2794)
			(end -0.12065 -0.2794)
			(stroke
				(width 0.1)
				(type default)
			)
			(layer "B.Fab")
		)
		(fp_line
			(start -0.67945 -0.3048)
			(end -0.67945 0.3048)
			(stroke
				(width 0.1)
				(type default)
			)
			(layer "B.Fab")
		)
		(fp_line
			(start -0.12065 -0.3048)
			(end -0.67945 -0.3048)
			(stroke
				(width 0.1)
				(type default)
			)
			(layer "B.Fab")
		)
		(fp_line
			(start 0.12065 -0.305054)
			(end 0.12065 -0.2794)
			(stroke
				(width 0.1)
				(type default)
			)
			(layer "B.Fab")
		)
		(fp_line
			(start 0.67945 -0.305054)
			(end 0.12065 -0.305054)
			(stroke
				(width 0.1)
				(type default)
			)
			(layer "B.Fab")
		)
		(pad "1" smd circle
			(at 0.40005 0 90)
			(size 0 0)
			(layers "B.Cu" "B.Mask" "B.Paste")
			(net "P1V8_CPU0_RT_1D")
		)
		(pad "2" smd circle
			(at -0.40005 0 90)
			(size 0 0)
			(layers "B.Cu" "B.Mask" "B.Paste")
			(net "GND")
		)
	)
	(footprint ""
		(layer "B.Cu")
		(at 268.892528 -194.893946 180)
		(property "Reference" "R1573"
			(at 0 0 0)
			(layer "B.SilkS")
			(hide yes)
			(effects
				(font
					(size 1.27 1.27)
				)
				(justify mirror)
			)
		)
		(property "Value" ""
			(at 0 0 0)
			(layer "B.Fab")
			(effects
				(font
					(size 1.27 1.27)
				)
				(justify mirror)
			)
		)
		(duplicate_pad_numbers_are_jumpers no)
		(fp_line
			(start 0.7874 0.4064)
			(end 0.7874 -0.4064)
			(stroke
				(width 0.1524)
				(type default)
			)
			(layer "B.SilkS")
		)
		(fp_line
			(start 0.7874 -0.4064)
			(end -0.7874 -0.4064)
			(stroke
				(width 0.1524)
				(type default)
			)
			(layer "B.SilkS")
		)
		(fp_line
			(start -0.7874 0.4064)
			(end 0.7874 0.4064)
			(stroke
				(width 0.1524)
				(type default)
			)
			(layer "B.SilkS")
		)
		(fp_line
			(start -0.7874 -0.4064)
			(end -0.7874 0.4064)
			(stroke
				(width 0.1524)
				(type default)
			)
			(layer "B.SilkS")
		)
		(fp_line
			(start 0.67945 0.3048)
			(end 0.67945 -0.305054)
			(stroke
				(width 0.1)
				(type default)
			)
			(layer "B.Fab")
		)
		(fp_line
			(start 0.67945 -0.305054)
			(end 0.12065 -0.305054)
			(stroke
				(width 0.1)
				(type default)
			)
			(layer "B.Fab")
		)
		(fp_line
			(start 0.12065 0.3048)
			(end 0.67945 0.3048)
			(stroke
				(width 0.1)
				(type default)
			)
			(layer "B.Fab")
		)
		(fp_line
			(start 0.12065 0.2794)
			(end 0.12065 0.3048)
			(stroke
				(width 0.1)
				(type default)
			)
			(layer "B.Fab")
		)
		(fp_line
			(start 0.12065 -0.2794)
			(end -0.12065 -0.2794)
			(stroke
				(width 0.1)
				(type default)
			)
			(layer "B.Fab")
		)
		(fp_line
			(start 0.12065 -0.305054)
			(end 0.12065 -0.2794)
			(stroke
				(width 0.1)
				(type default)
			)
			(layer "B.Fab")
		)
		(fp_line
			(start -0.120396 0.3048)
			(end -0.120396 0.2794)
			(stroke
				(width 0.1)
				(type default)
			)
			(layer "B.Fab")
		)
		(fp_line
			(start -0.120396 0.2794)
			(end 0.12065 0.2794)
			(stroke
				(width 0.1)
				(type default)
			)
			(layer "B.Fab")
		)
		(fp_line
			(start -0.12065 -0.2794)
			(end -0.12065 -0.3048)
			(stroke
				(width 0.1)
				(type default)
			)
			(layer "B.Fab")
		)
		(fp_line
			(start -0.12065 -0.3048)
			(end -0.67945 -0.3048)
			(stroke
				(width 0.1)
				(type default)
			)
			(layer "B.Fab")
		)
		(fp_line
			(start -0.67945 0.3048)
			(end -0.120396 0.3048)
			(stroke
				(width 0.1)
				(type default)
			)
			(layer "B.Fab")
		)
		(fp_line
			(start -0.67945 -0.3048)
			(end -0.67945 0.3048)
			(stroke
				(width 0.1)
				(type default)
			)
			(layer "B.Fab")
		)
		(pad "1" smd circle
			(at 0.40005 0)
			(size 0 0)
			(layers "B.Cu" "B.Mask" "B.Paste")
			(net "I3C_SPD_DDRAF_CPU0_SCL")
		)
		(pad "2" smd circle
			(at -0.40005 0)
			(size 0 0)
			(layers "B.Cu" "B.Mask" "B.Paste")
			(net "I3C_SPD_DDRF_CPU0_SCL")
		)
	)
	(footprint ""
		(layer "B.Cu")
		(at 393.745466 -395.466062 -90)
		(property "Reference" "C990"
			(at 0 0 90)
			(layer "B.SilkS")
			(hide yes)
			(effects
				(font
					(size 1.27 1.27)
				)
				(justify mirror)
			)
		)
		(property "Value" ""
			(at 0 0 90)
			(layer "B.Fab")
			(effects
				(font
					(size 1.27 1.27)
				)
				(justify mirror)
			)
		)
		(duplicate_pad_numbers_are_jumpers no)
		(fp_line
			(start -1.524 0.762)
			(end 1.524 0.762)
			(stroke
				(width 0.1524)
				(type default)
			)
			(layer "B.SilkS")
		)
		(fp_line
			(start 1.524 0.762)
			(end 1.524 -0.762)
			(stroke
				(width 0.1524)
				(type default)
			)
			(layer "B.SilkS")
		)
		(fp_line
			(start -1.524 -0.762)
			(end -1.524 0.762)
			(stroke
				(width 0.1524)
				(type default)
			)
			(layer "B.SilkS")
		)
		(fp_line
			(start 1.524 -0.762)
			(end -1.524 -0.762)
			(stroke
				(width 0.1524)
				(type default)
			)
			(layer "B.SilkS")
		)
		(fp_line
			(start -1.1049 0.724916)
			(end -1.1049 -0.724916)
			(stroke
				(width 0.1)
				(type default)
			)
			(layer "B.Fab")
		)
		(fp_line
			(start 1.1049 0.724916)
			(end -1.1049 0.724916)
			(stroke
				(width 0.1)
				(type default)
			)
			(layer "B.Fab")
		)
		(fp_line
			(start -1.1049 -0.724916)
			(end 1.1049 -0.724916)
			(stroke
				(width 0.1)
				(type default)
			)
			(layer "B.Fab")
		)
		(fp_line
			(start 1.1049 -0.724916)
			(end 1.1049 0.724916)
			(stroke
				(width 0.1)
				(type default)
			)
			(layer "B.Fab")
		)
		(pad "1" smd rect
			(at 0.889 0 270)
			(size 1.016 1.27)
			(layers "B.Cu" "B.Mask" "B.Paste")
			(net "P1V8_CPU0_RT_1D")
		)
		(pad "2" smd rect
			(at -0.889 0 270)
			(size 1.016 1.27)
			(layers "B.Cu" "B.Mask" "B.Paste")
			(net "GND")
		)
	)
	(footprint ""
		(layer "B.Cu")
		(at 93.4212 -139.192)
		(property "Reference" "R309"
			(at 0 0 0)
			(layer "B.SilkS")
			(hide yes)
			(effects
				(font
					(size 1.27 1.27)
				)
				(justify mirror)
			)
		)
		(property "Value" ""
			(at 0 0 0)
			(layer "B.Fab")
			(effects
				(font
					(size 1.27 1.27)
				)
				(justify mirror)
			)
		)
		(duplicate_pad_numbers_are_jumpers no)
		(fp_line
			(start -0.7874 -0.4064)
			(end -0.7874 0.4064)
			(stroke
				(width 0.1524)
				(type default)
			)
			(layer "B.SilkS")
		)
		(fp_line
			(start -0.7874 0.4064)
			(end 0.7874 0.4064)
			(stroke
				(width 0.1524)
				(type default)
			)
			(layer "B.SilkS")
		)
		(fp_line
			(start 0.7874 -0.4064)
			(end -0.7874 -0.4064)
			(stroke
				(width 0.1524)
				(type default)
			)
			(layer "B.SilkS")
		)
		(fp_line
			(start 0.7874 0.4064)
			(end 0.7874 -0.4064)
			(stroke
				(width 0.1524)
				(type default)
			)
			(layer "B.SilkS")
		)
		(fp_line
			(start -0.67945 -0.3048)
			(end -0.67945 0.3048)
			(stroke
				(width 0.1)
				(type default)
			)
			(layer "B.Fab")
		)
		(fp_line
			(start -0.67945 0.3048)
			(end -0.120396 0.3048)
			(stroke
				(width 0.1)
				(type default)
			)
			(layer "B.Fab")
		)
		(fp_line
			(start -0.12065 -0.3048)
			(end -0.67945 -0.3048)
			(stroke
				(width 0.1)
				(type default)
			)
			(layer "B.Fab")
		)
		(fp_line
			(start -0.12065 -0.2794)
			(end -0.12065 -0.3048)
			(stroke
				(width 0.1)
				(type default)
			)
			(layer "B.Fab")
		)
		(fp_line
			(start -0.120396 0.2794)
			(end 0.12065 0.2794)
			(stroke
				(width 0.1)
				(type default)
			)
			(layer "B.Fab")
		)
		(fp_line
			(start -0.120396 0.3048)
			(end -0.120396 0.2794)
			(stroke
				(width 0.1)
				(type default)
			)
			(layer "B.Fab")
		)
		(fp_line
			(start 0.12065 -0.305054)
			(end 0.12065 -0.2794)
			(stroke
				(width 0.1)
				(type default)
			)
			(layer "B.Fab")
		)
		(fp_line
			(start 0.12065 -0.2794)
			(end -0.12065 -0.2794)
			(stroke
				(width 0.1)
				(type default)
			)
			(layer "B.Fab")
		)
		(fp_line
			(start 0.12065 0.2794)
			(end 0.12065 0.3048)
			(stroke
				(width 0.1)
				(type default)
			)
			(layer "B.Fab")
		)
		(fp_line
			(start 0.12065 0.3048)
			(end 0.67945 0.3048)
			(stroke
				(width 0.1)
				(type default)
			)
			(layer "B.Fab")
		)
		(fp_line
			(start 0.67945 -0.305054)
			(end 0.12065 -0.305054)
			(stroke
				(width 0.1)
				(type default)
			)
			(layer "B.Fab")
		)
		(fp_line
			(start 0.67945 0.3048)
			(end 0.67945 -0.305054)
			(stroke
				(width 0.1)
				(type default)
			)
			(layer "B.Fab")
		)
		(pad "1" smd circle
			(at 0.40005 0 180)
			(size 0 0)
			(layers "B.Cu" "B.Mask" "B.Paste")
			(net "SMB_VR_3V3AUX_SDA")
		)
		(pad "2" smd circle
			(at -0.40005 0 180)
			(size 0 0)
			(layers "B.Cu" "B.Mask" "B.Paste")
			(net "SMB_VR_3V3STBY_SDA")
		)
	)
	(footprint ""
		(layer "B.Cu")
		(at 450.534278 -8.3566 90)
		(property "Reference" "R33"
			(at 0 0 90)
			(layer "B.SilkS")
			(hide yes)
			(effects
				(font
					(size 1.27 1.27)
				)
				(justify mirror)
			)
		)
		(property "Value" ""
			(at 0 0 90)
			(layer "B.Fab")
			(effects
				(font
					(size 1.27 1.27)
				)
				(justify mirror)
			)
		)
		(duplicate_pad_numbers_are_jumpers no)
		(fp_line
			(start 0.7874 -0.4064)
			(end -0.7874 -0.4064)
			(stroke
				(width 0.1524)
				(type default)
			)
			(layer "B.SilkS")
		)
		(fp_line
			(start -0.7874 -0.4064)
			(end -0.7874 0.4064)
			(stroke
				(width 0.1524)
				(type default)
			)
			(layer "B.SilkS")
		)
		(fp_line
			(start 0.7874 0.4064)
			(end 0.7874 -0.4064)
			(stroke
				(width 0.1524)
				(type default)
			)
			(layer "B.SilkS")
		)
		(fp_line
			(start -0.7874 0.4064)
			(end 0.7874 0.4064)
			(stroke
				(width 0.1524)
				(type default)
			)
			(layer "B.SilkS")
		)
		(fp_line
			(start 0.67945 -0.305054)
			(end 0.12065 -0.305054)
			(stroke
				(width 0.1)
				(type default)
			)
			(layer "B.Fab")
		)
		(fp_line
			(start 0.12065 -0.305054)
			(end 0.12065 -0.2794)
			(stroke
				(width 0.1)
				(type default)
			)
			(layer "B.Fab")
		)
		(fp_line
			(start -0.12065 -0.3048)
			(end -0.67945 -0.3048)
			(stroke
				(width 0.1)
				(type default)
			)
			(layer "B.Fab")
		)
		(fp_line
			(start -0.67945 -0.3048)
			(end -0.67945 0.3048)
			(stroke
				(width 0.1)
				(type default)
			)
			(layer "B.Fab")
		)
		(fp_line
			(start 0.12065 -0.2794)
			(end -0.12065 -0.2794)
			(stroke
				(width 0.1)
				(type default)
			)
			(layer "B.Fab")
		)
		(fp_line
			(start -0.12065 -0.2794)
			(end -0.12065 -0.3048)
			(stroke
				(width 0.1)
				(type default)
			)
			(layer "B.Fab")
		)
		(fp_line
			(start 0.12065 0.2794)
			(end 0.12065 0.3048)
			(stroke
				(width 0.1)
				(type default)
			)
			(layer "B.Fab")
		)
		(fp_line
			(start -0.120396 0.2794)
			(end 0.12065 0.2794)
			(stroke
				(width 0.1)
				(type default)
			)
			(layer "B.Fab")
		)
		(fp_line
			(start 0.67945 0.3048)
			(end 0.67945 -0.305054)
			(stroke
				(width 0.1)
				(type default)
			)
			(layer "B.Fab")
		)
		(fp_line
			(start 0.12065 0.3048)
			(end 0.67945 0.3048)
			(stroke
				(width 0.1)
				(type default)
			)
			(layer "B.Fab")
		)
		(fp_line
			(start -0.120396 0.3048)
			(end -0.120396 0.2794)
			(stroke
				(width 0.1)
				(type default)
			)
			(layer "B.Fab")
		)
		(fp_line
			(start -0.67945 0.3048)
			(end -0.120396 0.3048)
			(stroke
				(width 0.1)
				(type default)
			)
			(layer "B.Fab")
		)
		(pad "1" smd circle
			(at 0.40005 0 270)
			(size 0 0)
			(layers "B.Cu" "B.Mask" "B.Paste")
			(net "P3V3_OCP_SFF")
		)
		(pad "2" smd circle
			(at -0.40005 0 270)
			(size 0 0)
			(layers "B.Cu" "B.Mask" "B.Paste")
			(net "OCP_SFF_ID1")
		)
	)
	(footprint ""
		(layer "B.Cu")
		(at 344.668856 -161.263076 -90)
		(property "Reference" "PC159_6"
			(at 0 0 90)
			(layer "B.SilkS")
			(hide yes)
			(effects
				(font
					(size 1.27 1.27)
				)
				(justify mirror)
			)
		)
		(property "Value" ""
			(at 0 0 90)
			(layer "B.Fab")
			(effects
				(font
					(size 1.27 1.27)
				)
				(justify mirror)
			)
		)
		(duplicate_pad_numbers_are_jumpers no)
		(fp_line
			(start -1.524 0.762)
			(end 1.524 0.762)
			(stroke
				(width 0.1524)
				(type default)
			)
			(layer "B.SilkS")
		)
		(fp_line
			(start 1.524 0.762)
			(end 1.524 -0.762)
			(stroke
				(width 0.1524)
				(type default)
			)
			(layer "B.SilkS")
		)
		(fp_line
			(start -1.524 -0.762)
			(end -1.524 0.762)
			(stroke
				(width 0.1524)
				(type default)
			)
			(layer "B.SilkS")
		)
		(fp_line
			(start 1.524 -0.762)
			(end -1.524 -0.762)
			(stroke
				(width 0.1524)
				(type default)
			)
			(layer "B.SilkS")
		)
		(fp_line
			(start -1.1049 0.724916)
			(end -1.1049 -0.724916)
			(stroke
				(width 0.1)
				(type default)
			)
			(layer "B.Fab")
		)
		(fp_line
			(start 1.1049 0.724916)
			(end -1.1049 0.724916)
			(stroke
				(width 0.1)
				(type default)
			)
			(layer "B.Fab")
		)
		(fp_line
			(start -1.1049 -0.724916)
			(end 1.1049 -0.724916)
			(stroke
				(width 0.1)
				(type default)
			)
			(layer "B.Fab")
		)
		(fp_line
			(start 1.1049 -0.724916)
			(end 1.1049 0.724916)
			(stroke
				(width 0.1)
				(type default)
			)
			(layer "B.Fab")
		)
		(pad "1" smd rect
			(at 0.889 0 270)
			(size 1.016 1.27)
			(layers "B.Cu" "B.Mask" "B.Paste")
			(net "SW_P12V_AUX_PVDDCR_CPU0_P0_FLT")
		)
		(pad "2" smd rect
			(at -0.889 0 270)
			(size 1.016 1.27)
			(layers "B.Cu" "B.Mask" "B.Paste")
			(net "GND")
		)
	)
	(footprint ""
		(layer "B.Cu")
		(at 106.212386 -253.432564)
		(property "Reference" "C2436"
			(at 0 0 0)
			(layer "B.SilkS")
			(hide yes)
			(effects
				(font
					(size 1.27 1.27)
				)
				(justify mirror)
			)
		)
		(property "Value" ""
			(at 0 0 0)
			(layer "B.Fab")
			(effects
				(font
					(size 1.27 1.27)
				)
				(justify mirror)
			)
		)
		(duplicate_pad_numbers_are_jumpers no)
		(fp_line
			(start -0.7874 -0.4064)
			(end -0.7874 0.4064)
			(stroke
				(width 0.1524)
				(type default)
			)
			(layer "B.SilkS")
		)
		(fp_line
			(start -0.7874 0.4064)
			(end 0.7874 0.4064)
			(stroke
				(width 0.1524)
				(type default)
			)
			(layer "B.SilkS")
		)
		(fp_line
			(start 0.7874 -0.4064)
			(end -0.7874 -0.4064)
			(stroke
				(width 0.1524)
				(type default)
			)
			(layer "B.SilkS")
		)
		(fp_line
			(start 0.7874 0.4064)
			(end 0.7874 -0.4064)
			(stroke
				(width 0.1524)
				(type default)
			)
			(layer "B.SilkS")
		)
		(fp_line
			(start -0.67945 -0.3048)
			(end -0.67945 0.3048)
			(stroke
				(width 0.1)
				(type default)
			)
			(layer "B.Fab")
		)
		(fp_line
			(start -0.67945 0.3048)
			(end -0.120396 0.3048)
			(stroke
				(width 0.1)
				(type default)
			)
			(layer "B.Fab")
		)
		(fp_line
			(start -0.12065 -0.3048)
			(end -0.67945 -0.3048)
			(stroke
				(width 0.1)
				(type default)
			)
			(layer "B.Fab")
		)
		(fp_line
			(start -0.12065 -0.2794)
			(end -0.12065 -0.3048)
			(stroke
				(width 0.1)
				(type default)
			)
			(layer "B.Fab")
		)
		(fp_line
			(start -0.120396 0.2794)
			(end 0.12065 0.2794)
			(stroke
				(width 0.1)
				(type default)
			)
			(layer "B.Fab")
		)
		(fp_line
			(start -0.120396 0.3048)
			(end -0.120396 0.2794)
			(stroke
				(width 0.1)
				(type default)
			)
			(layer "B.Fab")
		)
		(fp_line
			(start 0.12065 -0.305054)
			(end 0.12065 -0.2794)
			(stroke
				(width 0.1)
				(type default)
			)
			(layer "B.Fab")
		)
		(fp_line
			(start 0.12065 -0.2794)
			(end -0.12065 -0.2794)
			(stroke
				(width 0.1)
				(type default)
			)
			(layer "B.Fab")
		)
		(fp_line
			(start 0.12065 0.2794)
			(end 0.12065 0.3048)
			(stroke
				(width 0.1)
				(type default)
			)
			(layer "B.Fab")
		)
		(fp_line
			(start 0.12065 0.3048)
			(end 0.67945 0.3048)
			(stroke
				(width 0.1)
				(type default)
			)
			(layer "B.Fab")
		)
		(fp_line
			(start 0.67945 -0.305054)
			(end 0.12065 -0.305054)
			(stroke
				(width 0.1)
				(type default)
			)
			(layer "B.Fab")
		)
		(fp_line
			(start 0.67945 0.3048)
			(end 0.67945 -0.305054)
			(stroke
				(width 0.1)
				(type default)
			)
			(layer "B.Fab")
		)
		(pad "1" smd circle
			(at 0.40005 0 180)
			(size 0 0)
			(layers "B.Cu" "B.Mask" "B.Paste")
			(net "PVDDCR_SOC_P1")
		)
		(pad "2" smd circle
			(at -0.40005 0 180)
			(size 0 0)
			(layers "B.Cu" "B.Mask" "B.Paste")
			(net "GND")
		)
	)
	(footprint ""
		(layer "B.Cu")
		(at 234.81157 -323.746114 180)
		(property "Reference" "R1221"
			(at 0 0 0)
			(layer "B.SilkS")
			(hide yes)
			(effects
				(font
					(size 1.27 1.27)
				)
				(justify mirror)
			)
		)
		(property "Value" ""
			(at 0 0 0)
			(layer "B.Fab")
			(effects
				(font
					(size 1.27 1.27)
				)
				(justify mirror)
			)
		)
		(duplicate_pad_numbers_are_jumpers no)
		(fp_line
			(start 0.7874 0.4064)
			(end 0.7874 -0.4064)
			(stroke
				(width 0.1524)
				(type default)
			)
			(layer "B.SilkS")
		)
		(fp_line
			(start 0.7874 -0.4064)
			(end -0.7874 -0.4064)
			(stroke
				(width 0.1524)
				(type default)
			)
			(layer "B.SilkS")
		)
		(fp_line
			(start -0.7874 0.4064)
			(end 0.7874 0.4064)
			(stroke
				(width 0.1524)
				(type default)
			)
			(layer "B.SilkS")
		)
		(fp_line
			(start -0.7874 -0.4064)
			(end -0.7874 0.4064)
			(stroke
				(width 0.1524)
				(type default)
			)
			(layer "B.SilkS")
		)
		(fp_line
			(start 0.67945 0.3048)
			(end 0.67945 -0.305054)
			(stroke
				(width 0.1)
				(type default)
			)
			(layer "B.Fab")
		)
		(fp_line
			(start 0.67945 -0.305054)
			(end 0.12065 -0.305054)
			(stroke
				(width 0.1)
				(type default)
			)
			(layer "B.Fab")
		)
		(fp_line
			(start 0.12065 0.3048)
			(end 0.67945 0.3048)
			(stroke
				(width 0.1)
				(type default)
			)
			(layer "B.Fab")
		)
		(fp_line
			(start 0.12065 0.2794)
			(end 0.12065 0.3048)
			(stroke
				(width 0.1)
				(type default)
			)
			(layer "B.Fab")
		)
		(fp_line
			(start 0.12065 -0.2794)
			(end -0.12065 -0.2794)
			(stroke
				(width 0.1)
				(type default)
			)
			(layer "B.Fab")
		)
		(fp_line
			(start 0.12065 -0.305054)
			(end 0.12065 -0.2794)
			(stroke
				(width 0.1)
				(type default)
			)
			(layer "B.Fab")
		)
		(fp_line
			(start -0.120396 0.3048)
			(end -0.120396 0.2794)
			(stroke
				(width 0.1)
				(type default)
			)
			(layer "B.Fab")
		)
		(fp_line
			(start -0.120396 0.2794)
			(end 0.12065 0.2794)
			(stroke
				(width 0.1)
				(type default)
			)
			(layer "B.Fab")
		)
		(fp_line
			(start -0.12065 -0.2794)
			(end -0.12065 -0.3048)
			(stroke
				(width 0.1)
				(type default)
			)
			(layer "B.Fab")
		)
		(fp_line
			(start -0.12065 -0.3048)
			(end -0.67945 -0.3048)
			(stroke
				(width 0.1)
				(type default)
			)
			(layer "B.Fab")
		)
		(fp_line
			(start -0.67945 0.3048)
			(end -0.120396 0.3048)
			(stroke
				(width 0.1)
				(type default)
			)
			(layer "B.Fab")
		)
		(fp_line
			(start -0.67945 -0.3048)
			(end -0.67945 0.3048)
			(stroke
				(width 0.1)
				(type default)
			)
			(layer "B.Fab")
		)
		(pad "1" smd circle
			(at 0.40005 0)
			(size 0 0)
			(layers "B.Cu" "B.Mask" "B.Paste")
			(net "P1V2_AUX_ADC")
		)
		(pad "2" smd circle
			(at -0.40005 0)
			(size 0 0)
			(layers "B.Cu" "B.Mask" "B.Paste")
			(net "GND")
		)
	)
	(footprint ""
		(layer "B.Cu")
		(at 34.034476 -338.010754 -90)
		(property "Reference" "PC635_3"
			(at 0 0 90)
			(layer "B.SilkS")
			(hide yes)
			(effects
				(font
					(size 1.27 1.27)
				)
				(justify mirror)
			)
		)
		(property "Value" ""
			(at 0 0 90)
			(layer "B.Fab")
			(effects
				(font
					(size 1.27 1.27)
				)
				(justify mirror)
			)
		)
		(duplicate_pad_numbers_are_jumpers no)
		(fp_line
			(start -1.524 0.762)
			(end 1.524 0.762)
			(stroke
				(width 0.1524)
				(type default)
			)
			(layer "B.SilkS")
		)
		(fp_line
			(start 1.524 0.762)
			(end 1.524 -0.762)
			(stroke
				(width 0.1524)
				(type default)
			)
			(layer "B.SilkS")
		)
		(fp_line
			(start -1.524 -0.762)
			(end -1.524 0.762)
			(stroke
				(width 0.1524)
				(type default)
			)
			(layer "B.SilkS")
		)
		(fp_line
			(start 1.524 -0.762)
			(end -1.524 -0.762)
			(stroke
				(width 0.1524)
				(type default)
			)
			(layer "B.SilkS")
		)
		(fp_line
			(start -1.1049 0.724916)
			(end -1.1049 -0.724916)
			(stroke
				(width 0.1)
				(type default)
			)
			(layer "B.Fab")
		)
		(fp_line
			(start 1.1049 0.724916)
			(end -1.1049 0.724916)
			(stroke
				(width 0.1)
				(type default)
			)
			(layer "B.Fab")
		)
		(fp_line
			(start -1.1049 -0.724916)
			(end 1.1049 -0.724916)
			(stroke
				(width 0.1)
				(type default)
			)
			(layer "B.Fab")
		)
		(fp_line
			(start 1.1049 -0.724916)
			(end 1.1049 0.724916)
			(stroke
				(width 0.1)
				(type default)
			)
			(layer "B.Fab")
		)
		(pad "1" smd rect
			(at 0.889 0 270)
			(size 1.016 1.27)
			(layers "B.Cu" "B.Mask" "B.Paste")
			(net "PVDDIO_P1")
		)
		(pad "2" smd rect
			(at -0.889 0 270)
			(size 1.016 1.27)
			(layers "B.Cu" "B.Mask" "B.Paste")
			(net "GND")
		)
	)
	(footprint ""
		(layer "B.Cu")
		(at 391.694162 -416.899344 90)
		(property "Reference" "C6609"
			(at 0 0 90)
			(layer "B.SilkS")
			(hide yes)
			(effects
				(font
					(size 1.27 1.27)
				)
				(justify mirror)
			)
		)
		(property "Value" ""
			(at 0 0 90)
			(layer "B.Fab")
			(effects
				(font
					(size 1.27 1.27)
				)
				(justify mirror)
			)
		)
		(duplicate_pad_numbers_are_jumpers no)
		(fp_line
			(start 0.299974 -0.150114)
			(end -0.299974 -0.150114)
			(stroke
				(width 0.1)
				(type default)
			)
			(layer "B.Fab")
		)
		(fp_line
			(start -0.299974 -0.150114)
			(end -0.299974 0.150114)
			(stroke
				(width 0.1)
				(type default)
			)
			(layer "B.Fab")
		)
		(fp_line
			(start 0.299974 0.150114)
			(end 0.299974 -0.150114)
			(stroke
				(width 0.1)
				(type default)
			)
			(layer "B.Fab")
		)
		(fp_line
			(start -0.299974 0.150114)
			(end 0.299974 0.150114)
			(stroke
				(width 0.1)
				(type default)
			)
			(layer "B.Fab")
		)
		(pad "1" smd rect
			(at 0.2667 0 270)
			(size 0.3048 0.381)
			(layers "B.Cu" "B.Mask" "B.Paste")
			(net "P5E_CPU0_P3_TX_BUF_C_DP<6>")
		)
		(pad "2" smd rect
			(at -0.2667 0 270)
			(size 0.3048 0.381)
			(layers "B.Cu" "B.Mask" "B.Paste")
			(net "P5E_CPU0_P3_TX_BUF_DP<6>")
		)
	)
	(footprint ""
		(layer "B.Cu")
		(at 79.886302 -338.93252 -90)
		(property "Reference" "PC385_2"
			(at 0 0 90)
			(layer "B.SilkS")
			(hide yes)
			(effects
				(font
					(size 1.27 1.27)
				)
				(justify mirror)
			)
		)
		(property "Value" ""
			(at 0 0 90)
			(layer "B.Fab")
			(effects
				(font
					(size 1.27 1.27)
				)
				(justify mirror)
			)
		)
		(duplicate_pad_numbers_are_jumpers no)
		(fp_line
			(start -1.524 0.762)
			(end 1.524 0.762)
			(stroke
				(width 0.1524)
				(type default)
			)
			(layer "B.SilkS")
		)
		(fp_line
			(start 1.524 0.762)
			(end 1.524 -0.762)
			(stroke
				(width 0.1524)
				(type default)
			)
			(layer "B.SilkS")
		)
		(fp_line
			(start -1.524 -0.762)
			(end -1.524 0.762)
			(stroke
				(width 0.1524)
				(type default)
			)
			(layer "B.SilkS")
		)
		(fp_line
			(start 1.524 -0.762)
			(end -1.524 -0.762)
			(stroke
				(width 0.1524)
				(type default)
			)
			(layer "B.SilkS")
		)
		(fp_line
			(start -1.1049 0.724916)
			(end -1.1049 -0.724916)
			(stroke
				(width 0.1)
				(type default)
			)
			(layer "B.Fab")
		)
		(fp_line
			(start 1.1049 0.724916)
			(end -1.1049 0.724916)
			(stroke
				(width 0.1)
				(type default)
			)
			(layer "B.Fab")
		)
		(fp_line
			(start -1.1049 -0.724916)
			(end 1.1049 -0.724916)
			(stroke
				(width 0.1)
				(type default)
			)
			(layer "B.Fab")
		)
		(fp_line
			(start 1.1049 -0.724916)
			(end 1.1049 0.724916)
			(stroke
				(width 0.1)
				(type default)
			)
			(layer "B.Fab")
		)
		(pad "1" smd rect
			(at 0.889 0 270)
			(size 1.016 1.27)
			(layers "B.Cu" "B.Mask" "B.Paste")
			(net "SW_P12V_AUX_PVDDCR_CPU1_P1_FLT")
		)
		(pad "2" smd rect
			(at -0.889 0 270)
			(size 1.016 1.27)
			(layers "B.Cu" "B.Mask" "B.Paste")
			(net "GND")
		)
	)
	(footprint ""
		(layer "B.Cu")
		(at 371.551454 -249.36831)
		(property "Reference" "C274"
			(at 0 0 0)
			(layer "B.SilkS")
			(hide yes)
			(effects
				(font
					(size 1.27 1.27)
				)
				(justify mirror)
			)
		)
		(property "Value" ""
			(at 0 0 0)
			(layer "B.Fab")
			(effects
				(font
					(size 1.27 1.27)
				)
				(justify mirror)
			)
		)
		(duplicate_pad_numbers_are_jumpers no)
		(fp_line
			(start -0.7874 -0.4064)
			(end -0.7874 0.4064)
			(stroke
				(width 0.1524)
				(type default)
			)
			(layer "B.SilkS")
		)
		(fp_line
			(start -0.7874 0.4064)
			(end 0.7874 0.4064)
			(stroke
				(width 0.1524)
				(type default)
			)
			(layer "B.SilkS")
		)
		(fp_line
			(start 0.7874 -0.4064)
			(end -0.7874 -0.4064)
			(stroke
				(width 0.1524)
				(type default)
			)
			(layer "B.SilkS")
		)
		(fp_line
			(start 0.7874 0.4064)
			(end 0.7874 -0.4064)
			(stroke
				(width 0.1524)
				(type default)
			)
			(layer "B.SilkS")
		)
		(fp_line
			(start -0.67945 -0.3048)
			(end -0.67945 0.3048)
			(stroke
				(width 0.1)
				(type default)
			)
			(layer "B.Fab")
		)
		(fp_line
			(start -0.67945 0.3048)
			(end -0.120396 0.3048)
			(stroke
				(width 0.1)
				(type default)
			)
			(layer "B.Fab")
		)
		(fp_line
			(start -0.12065 -0.3048)
			(end -0.67945 -0.3048)
			(stroke
				(width 0.1)
				(type default)
			)
			(layer "B.Fab")
		)
		(fp_line
			(start -0.12065 -0.2794)
			(end -0.12065 -0.3048)
			(stroke
				(width 0.1)
				(type default)
			)
			(layer "B.Fab")
		)
		(fp_line
			(start -0.120396 0.2794)
			(end 0.12065 0.2794)
			(stroke
				(width 0.1)
				(type default)
			)
			(layer "B.Fab")
		)
		(fp_line
			(start -0.120396 0.3048)
			(end -0.120396 0.2794)
			(stroke
				(width 0.1)
				(type default)
			)
			(layer "B.Fab")
		)
		(fp_line
			(start 0.12065 -0.305054)
			(end 0.12065 -0.2794)
			(stroke
				(width 0.1)
				(type default)
			)
			(layer "B.Fab")
		)
		(fp_line
			(start 0.12065 -0.2794)
			(end -0.12065 -0.2794)
			(stroke
				(width 0.1)
				(type default)
			)
			(layer "B.Fab")
		)
		(fp_line
			(start 0.12065 0.2794)
			(end 0.12065 0.3048)
			(stroke
				(width 0.1)
				(type default)
			)
			(layer "B.Fab")
		)
		(fp_line
			(start 0.12065 0.3048)
			(end 0.67945 0.3048)
			(stroke
				(width 0.1)
				(type default)
			)
			(layer "B.Fab")
		)
		(fp_line
			(start 0.67945 -0.305054)
			(end 0.12065 -0.305054)
			(stroke
				(width 0.1)
				(type default)
			)
			(layer "B.Fab")
		)
		(fp_line
			(start 0.67945 0.3048)
			(end 0.67945 -0.305054)
			(stroke
				(width 0.1)
				(type default)
			)
			(layer "B.Fab")
		)
		(pad "1" smd circle
			(at 0.40005 0 180)
			(size 0 0)
			(layers "B.Cu" "B.Mask" "B.Paste")
			(net "PVDDCR_CPU0_P0")
		)
		(pad "2" smd circle
			(at -0.40005 0 180)
			(size 0 0)
			(layers "B.Cu" "B.Mask" "B.Paste")
			(net "GND")
		)
	)
	(footprint ""
		(layer "B.Cu")
		(at 236.8169 -249.555 180)
		(property "Reference" "R327"
			(at 0 0 0)
			(layer "B.SilkS")
			(hide yes)
			(effects
				(font
					(size 1.27 1.27)
				)
				(justify mirror)
			)
		)
		(property "Value" ""
			(at 0 0 0)
			(layer "B.Fab")
			(effects
				(font
					(size 1.27 1.27)
				)
				(justify mirror)
			)
		)
		(duplicate_pad_numbers_are_jumpers no)
		(fp_line
			(start 0.7874 0.4064)
			(end 0.7874 -0.4064)
			(stroke
				(width 0.1524)
				(type default)
			)
			(layer "B.SilkS")
		)
		(fp_line
			(start 0.7874 -0.4064)
			(end -0.7874 -0.4064)
			(stroke
				(width 0.1524)
				(type default)
			)
			(layer "B.SilkS")
		)
		(fp_line
			(start -0.7874 0.4064)
			(end 0.7874 0.4064)
			(stroke
				(width 0.1524)
				(type default)
			)
			(layer "B.SilkS")
		)
		(fp_line
			(start -0.7874 -0.4064)
			(end -0.7874 0.4064)
			(stroke
				(width 0.1524)
				(type default)
			)
			(layer "B.SilkS")
		)
		(fp_line
			(start 0.67945 0.3048)
			(end 0.67945 -0.305054)
			(stroke
				(width 0.1)
				(type default)
			)
			(layer "B.Fab")
		)
		(fp_line
			(start 0.67945 -0.305054)
			(end 0.12065 -0.305054)
			(stroke
				(width 0.1)
				(type default)
			)
			(layer "B.Fab")
		)
		(fp_line
			(start 0.12065 0.3048)
			(end 0.67945 0.3048)
			(stroke
				(width 0.1)
				(type default)
			)
			(layer "B.Fab")
		)
		(fp_line
			(start 0.12065 0.2794)
			(end 0.12065 0.3048)
			(stroke
				(width 0.1)
				(type default)
			)
			(layer "B.Fab")
		)
		(fp_line
			(start 0.12065 -0.2794)
			(end -0.12065 -0.2794)
			(stroke
				(width 0.1)
				(type default)
			)
			(layer "B.Fab")
		)
		(fp_line
			(start 0.12065 -0.305054)
			(end 0.12065 -0.2794)
			(stroke
				(width 0.1)
				(type default)
			)
			(layer "B.Fab")
		)
		(fp_line
			(start -0.120396 0.3048)
			(end -0.120396 0.2794)
			(stroke
				(width 0.1)
				(type default)
			)
			(layer "B.Fab")
		)
		(fp_line
			(start -0.120396 0.2794)
			(end 0.12065 0.2794)
			(stroke
				(width 0.1)
				(type default)
			)
			(layer "B.Fab")
		)
		(fp_line
			(start -0.12065 -0.2794)
			(end -0.12065 -0.3048)
			(stroke
				(width 0.1)
				(type default)
			)
			(layer "B.Fab")
		)
		(fp_line
			(start -0.12065 -0.3048)
			(end -0.67945 -0.3048)
			(stroke
				(width 0.1)
				(type default)
			)
			(layer "B.Fab")
		)
		(fp_line
			(start -0.67945 0.3048)
			(end -0.120396 0.3048)
			(stroke
				(width 0.1)
				(type default)
			)
			(layer "B.Fab")
		)
		(fp_line
			(start -0.67945 -0.3048)
			(end -0.67945 0.3048)
			(stroke
				(width 0.1)
				(type default)
			)
			(layer "B.Fab")
		)
		(pad "1" smd rect
			(at 0.40005 0 180)
			(size 0.4572 0.508)
			(layers "B.Cu" "B.Mask" "B.Paste")
			(net "SMB_APML_CPU0_MUX2_SCL")
		)
		(pad "2" smd rect
			(at -0.40005 0 180)
			(size 0.4572 0.508)
			(layers "B.Cu" "B.Mask" "B.Paste")
			(net "SMB_APML_CPU0_SCL")
		)
	)
	(footprint ""
		(layer "B.Cu")
		(at 113.375948 -256.012442 -90)
		(property "Reference" "C3908"
			(at 0 0 90)
			(layer "B.SilkS")
			(hide yes)
			(effects
				(font
					(size 1.27 1.27)
				)
				(justify mirror)
			)
		)
		(property "Value" ""
			(at 0 0 90)
			(layer "B.Fab")
			(effects
				(font
					(size 1.27 1.27)
				)
				(justify mirror)
			)
		)
		(duplicate_pad_numbers_are_jumpers no)
		(fp_line
			(start -0.7874 0.4064)
			(end 0.7874 0.4064)
			(stroke
				(width 0.1524)
				(type default)
			)
			(layer "B.SilkS")
		)
		(fp_line
			(start 0.7874 0.4064)
			(end 0.7874 -0.4064)
			(stroke
				(width 0.1524)
				(type default)
			)
			(layer "B.SilkS")
		)
		(fp_line
			(start -0.7874 -0.4064)
			(end -0.7874 0.4064)
			(stroke
				(width 0.1524)
				(type default)
			)
			(layer "B.SilkS")
		)
		(fp_line
			(start 0.7874 -0.4064)
			(end -0.7874 -0.4064)
			(stroke
				(width 0.1524)
				(type default)
			)
			(layer "B.SilkS")
		)
		(fp_line
			(start -0.67945 0.3048)
			(end -0.120396 0.3048)
			(stroke
				(width 0.1)
				(type default)
			)
			(layer "B.Fab")
		)
		(fp_line
			(start -0.120396 0.3048)
			(end -0.120396 0.2794)
			(stroke
				(width 0.1)
				(type default)
			)
			(layer "B.Fab")
		)
		(fp_line
			(start 0.12065 0.3048)
			(end 0.67945 0.3048)
			(stroke
				(width 0.1)
				(type default)
			)
			(layer "B.Fab")
		)
		(fp_line
			(start 0.67945 0.3048)
			(end 0.67945 -0.305054)
			(stroke
				(width 0.1)
				(type default)
			)
			(layer "B.Fab")
		)
		(fp_line
			(start -0.120396 0.2794)
			(end 0.12065 0.2794)
			(stroke
				(width 0.1)
				(type default)
			)
			(layer "B.Fab")
		)
		(fp_line
			(start 0.12065 0.2794)
			(end 0.12065 0.3048)
			(stroke
				(width 0.1)
				(type default)
			)
			(layer "B.Fab")
		)
		(fp_line
			(start -0.12065 -0.2794)
			(end -0.12065 -0.3048)
			(stroke
				(width 0.1)
				(type default)
			)
			(layer "B.Fab")
		)
		(fp_line
			(start 0.12065 -0.2794)
			(end -0.12065 -0.2794)
			(stroke
				(width 0.1)
				(type default)
			)
			(layer "B.Fab")
		)
		(fp_line
			(start -0.67945 -0.3048)
			(end -0.67945 0.3048)
			(stroke
				(width 0.1)
				(type default)
			)
			(layer "B.Fab")
		)
		(fp_line
			(start -0.12065 -0.3048)
			(end -0.67945 -0.3048)
			(stroke
				(width 0.1)
				(type default)
			)
			(layer "B.Fab")
		)
		(fp_line
			(start 0.12065 -0.305054)
			(end 0.12065 -0.2794)
			(stroke
				(width 0.1)
				(type default)
			)
			(layer "B.Fab")
		)
		(fp_line
			(start 0.67945 -0.305054)
			(end 0.12065 -0.305054)
			(stroke
				(width 0.1)
				(type default)
			)
			(layer "B.Fab")
		)
		(pad "1" smd circle
			(at 0.40005 0 90)
			(size 0 0)
			(layers "B.Cu" "B.Mask" "B.Paste")
			(net "PVDDCR_SOC_P1")
		)
		(pad "2" smd circle
			(at -0.40005 0 90)
			(size 0 0)
			(layers "B.Cu" "B.Mask" "B.Paste")
			(net "GND")
		)
	)
	(footprint ""
		(layer "B.Cu")
		(at 127.818388 -388.011162 -90)
		(property "Reference" "C464"
			(at 0 0 90)
			(layer "B.SilkS")
			(hide yes)
			(effects
				(font
					(size 1.27 1.27)
				)
				(justify mirror)
			)
		)
		(property "Value" ""
			(at 0 0 90)
			(layer "B.Fab")
			(effects
				(font
					(size 1.27 1.27)
				)
				(justify mirror)
			)
		)
		(duplicate_pad_numbers_are_jumpers no)
		(fp_line
			(start -0.299974 0.150114)
			(end 0.299974 0.150114)
			(stroke
				(width 0.1)
				(type default)
			)
			(layer "B.Fab")
		)
		(fp_line
			(start 0.299974 0.150114)
			(end 0.299974 -0.150114)
			(stroke
				(width 0.1)
				(type default)
			)
			(layer "B.Fab")
		)
		(fp_line
			(start -0.299974 -0.150114)
			(end -0.299974 0.150114)
			(stroke
				(width 0.1)
				(type default)
			)
			(layer "B.Fab")
		)
		(fp_line
			(start 0.299974 -0.150114)
			(end -0.299974 -0.150114)
			(stroke
				(width 0.1)
				(type default)
			)
			(layer "B.Fab")
		)
		(pad "1" smd rect
			(at 0.2667 0 90)
			(size 0.3048 0.381)
			(layers "B.Cu" "B.Mask" "B.Paste")
			(net "P0V9_CPU1_RT3_2A_2D")
		)
		(pad "2" smd rect
			(at -0.2667 0 90)
			(size 0.3048 0.381)
			(layers "B.Cu" "B.Mask" "B.Paste")
			(net "GND")
		)
	)
	(footprint ""
		(layer "B.Cu")
		(at 320.272664 -73.534778)
		(property "Reference" "Q78"
			(at 1.4224 -1.768348 0)
			(unlocked yes)
			(layer "B.SilkS")
			(effects
				(font
					(size 0.7874 0.5842)
					(thickness 0.1524)
				)
				(justify left mirror)
			)
		)
		(property "Value" ""
			(at 0 0 0)
			(layer "B.Fab")
			(effects
				(font
					(size 1.27 1.27)
				)
				(justify mirror)
			)
		)
		(duplicate_pad_numbers_are_jumpers no)
		(fp_line
			(start -1.332738 -1.100074)
			(end -1.332738 1.100074)
			(stroke
				(width 0.1524)
				(type default)
			)
			(layer "B.SilkS")
		)
		(fp_line
			(start -1.332738 1.100074)
			(end 1.332738 1.100074)
			(stroke
				(width 0.1524)
				(type default)
			)
			(layer "B.SilkS")
		)
		(fp_line
			(start -0.4826 -1.100074)
			(end -1.332738 -1.100074)
			(stroke
				(width 0.1524)
				(type default)
			)
			(layer "B.SilkS")
		)
		(fp_line
			(start 0 -0.541274)
			(end -0.4826 -1.100074)
			(stroke
				(width 0.1524)
				(type default)
			)
			(layer "B.SilkS")
		)
		(fp_line
			(start 0.4826 -1.100074)
			(end 0 -0.541274)
			(stroke
				(width 0.1524)
				(type default)
			)
			(layer "B.SilkS")
		)
		(fp_line
			(start 1.332738 -1.100074)
			(end 0.4826 -1.100074)
			(stroke
				(width 0.1524)
				(type default)
			)
			(layer "B.SilkS")
		)
		(fp_line
			(start 1.332738 1.100074)
			(end 1.332738 -1.100074)
			(stroke
				(width 0.1524)
				(type default)
			)
			(layer "B.SilkS")
		)
		(fp_poly
			(pts
				(xy 1.489456 -1.189482) (xy 1.737614 -1.933956) (xy 2.23393 -1.43764)
			)
			(stroke
				(width 0)
				(type default)
			)
			(fill yes)
			(layer "B.SilkS")
		)
		(fp_line
			(start -0.674878 -1.100074)
			(end -0.674878 1.100074)
			(stroke
				(width 0.1)
				(type default)
			)
			(layer "B.Fab")
		)
		(fp_line
			(start -0.674878 1.100074)
			(end 0.674878 1.100074)
			(stroke
				(width 0.1)
				(type default)
			)
			(layer "B.Fab")
		)
		(fp_line
			(start 0.674878 -1.100074)
			(end -0.674878 -1.100074)
			(stroke
				(width 0.1)
				(type default)
			)
			(layer "B.Fab")
		)
		(fp_line
			(start 0.674878 1.100074)
			(end 0.674878 -1.100074)
			(stroke
				(width 0.1)
				(type default)
			)
			(layer "B.Fab")
		)
		(fp_poly
			(pts
				(xy 2.2352 -0.298958) (xy 2.2352 -1.001014) (xy 1.533144 -0.649986)
			)
			(stroke
				(width 0)
				(type default)
			)
			(fill yes)
			(layer "B.Fab")
		)
		(pad "1" smd rect
			(at 0.94996 -0.649986 90)
			(size 0.4318 0.508)
			(layers "B.Cu" "B.Mask" "B.Paste")
			(net "GND")
		)
		(pad "2" smd rect
			(at 0.94996 0 90)
			(size 0.4318 0.508)
			(layers "B.Cu" "B.Mask" "B.Paste")
			(net "PWRGD_P1V8_AUX_R")
		)
		(pad "3" smd rect
			(at 0.94996 0.649986 90)
			(size 0.4318 0.508)
			(layers "B.Cu" "B.Mask" "B.Paste")
			(net "LED_PWRGD_PS_PWROK_PLD_D")
		)
		(pad "4" smd rect
			(at -0.94996 0.649986 90)
			(size 0.4318 0.508)
			(layers "B.Cu" "B.Mask" "B.Paste")
			(net "GND")
		)
		(pad "5" smd rect
			(at -0.94996 0 90)
			(size 0.4318 0.508)
			(layers "B.Cu" "B.Mask" "B.Paste")
			(net "PWRGD_PS_PWROK_PLD")
		)
		(pad "6" smd rect
			(at -0.94996 -0.649986 90)
			(size 0.4318 0.508)
			(layers "B.Cu" "B.Mask" "B.Paste")
			(net "LED_PWRGD_P1V8_AUX_D")
		)
	)
	(footprint ""
		(layer "B.Cu")
		(at 324.635876 -66.708782 90)
		(property "Reference" "R3087"
			(at 0 0 90)
			(layer "B.SilkS")
			(hide yes)
			(effects
				(font
					(size 1.27 1.27)
				)
				(justify mirror)
			)
		)
		(property "Value" ""
			(at 0 0 90)
			(layer "B.Fab")
			(effects
				(font
					(size 1.27 1.27)
				)
				(justify mirror)
			)
		)
		(duplicate_pad_numbers_are_jumpers no)
		(fp_line
			(start 0.7874 -0.4064)
			(end -0.7874 -0.4064)
			(stroke
				(width 0.1524)
				(type default)
			)
			(layer "B.SilkS")
		)
		(fp_line
			(start -0.7874 -0.4064)
			(end -0.7874 0.4064)
			(stroke
				(width 0.1524)
				(type default)
			)
			(layer "B.SilkS")
		)
		(fp_line
			(start 0.7874 0.4064)
			(end 0.7874 -0.4064)
			(stroke
				(width 0.1524)
				(type default)
			)
			(layer "B.SilkS")
		)
		(fp_line
			(start -0.7874 0.4064)
			(end 0.7874 0.4064)
			(stroke
				(width 0.1524)
				(type default)
			)
			(layer "B.SilkS")
		)
		(fp_line
			(start 0.67945 -0.305054)
			(end 0.12065 -0.305054)
			(stroke
				(width 0.1)
				(type default)
			)
			(layer "B.Fab")
		)
		(fp_line
			(start 0.12065 -0.305054)
			(end 0.12065 -0.2794)
			(stroke
				(width 0.1)
				(type default)
			)
			(layer "B.Fab")
		)
		(fp_line
			(start -0.12065 -0.3048)
			(end -0.67945 -0.3048)
			(stroke
				(width 0.1)
				(type default)
			)
			(layer "B.Fab")
		)
		(fp_line
			(start -0.67945 -0.3048)
			(end -0.67945 0.3048)
			(stroke
				(width 0.1)
				(type default)
			)
			(layer "B.Fab")
		)
		(fp_line
			(start 0.12065 -0.2794)
			(end -0.12065 -0.2794)
			(stroke
				(width 0.1)
				(type default)
			)
			(layer "B.Fab")
		)
		(fp_line
			(start -0.12065 -0.2794)
			(end -0.12065 -0.3048)
			(stroke
				(width 0.1)
				(type default)
			)
			(layer "B.Fab")
		)
		(fp_line
			(start 0.12065 0.2794)
			(end 0.12065 0.3048)
			(stroke
				(width 0.1)
				(type default)
			)
			(layer "B.Fab")
		)
		(fp_line
			(start -0.120396 0.2794)
			(end 0.12065 0.2794)
			(stroke
				(width 0.1)
				(type default)
			)
			(layer "B.Fab")
		)
		(fp_line
			(start 0.67945 0.3048)
			(end 0.67945 -0.305054)
			(stroke
				(width 0.1)
				(type default)
			)
			(layer "B.Fab")
		)
		(fp_line
			(start 0.12065 0.3048)
			(end 0.67945 0.3048)
			(stroke
				(width 0.1)
				(type default)
			)
			(layer "B.Fab")
		)
		(fp_line
			(start -0.120396 0.3048)
			(end -0.120396 0.2794)
			(stroke
				(width 0.1)
				(type default)
			)
			(layer "B.Fab")
		)
		(fp_line
			(start -0.67945 0.3048)
			(end -0.120396 0.3048)
			(stroke
				(width 0.1)
				(type default)
			)
			(layer "B.Fab")
		)
		(pad "1" smd circle
			(at 0.40005 0 270)
			(size 0 0)
			(layers "B.Cu" "B.Mask" "B.Paste")
			(net "LED_PWRGD_PVDDCR_CPU0_P0_R")
		)
		(pad "2" smd circle
			(at -0.40005 0 270)
			(size 0 0)
			(layers "B.Cu" "B.Mask" "B.Paste")
			(net "P3V3_AUX")
		)
	)
	(footprint ""
		(layer "B.Cu")
		(at 20.919186 -193.996564)
		(property "Reference" "C156"
			(at 0 0 0)
			(layer "B.SilkS")
			(hide yes)
			(effects
				(font
					(size 1.27 1.27)
				)
				(justify mirror)
			)
		)
		(property "Value" ""
			(at 0 0 0)
			(layer "B.Fab")
			(effects
				(font
					(size 1.27 1.27)
				)
				(justify mirror)
			)
		)
		(duplicate_pad_numbers_are_jumpers no)
		(fp_line
			(start -0.7874 -0.4064)
			(end -0.7874 0.4064)
			(stroke
				(width 0.1524)
				(type default)
			)
			(layer "B.SilkS")
		)
		(fp_line
			(start -0.7874 0.4064)
			(end 0.7874 0.4064)
			(stroke
				(width 0.1524)
				(type default)
			)
			(layer "B.SilkS")
		)
		(fp_line
			(start 0.7874 -0.4064)
			(end -0.7874 -0.4064)
			(stroke
				(width 0.1524)
				(type default)
			)
			(layer "B.SilkS")
		)
		(fp_line
			(start 0.7874 0.4064)
			(end 0.7874 -0.4064)
			(stroke
				(width 0.1524)
				(type default)
			)
			(layer "B.SilkS")
		)
		(fp_line
			(start -0.67945 -0.3048)
			(end -0.67945 0.3048)
			(stroke
				(width 0.1)
				(type default)
			)
			(layer "B.Fab")
		)
		(fp_line
			(start -0.67945 0.3048)
			(end -0.120396 0.3048)
			(stroke
				(width 0.1)
				(type default)
			)
			(layer "B.Fab")
		)
		(fp_line
			(start -0.12065 -0.3048)
			(end -0.67945 -0.3048)
			(stroke
				(width 0.1)
				(type default)
			)
			(layer "B.Fab")
		)
		(fp_line
			(start -0.12065 -0.2794)
			(end -0.12065 -0.3048)
			(stroke
				(width 0.1)
				(type default)
			)
			(layer "B.Fab")
		)
		(fp_line
			(start -0.120396 0.2794)
			(end 0.12065 0.2794)
			(stroke
				(width 0.1)
				(type default)
			)
			(layer "B.Fab")
		)
		(fp_line
			(start -0.120396 0.3048)
			(end -0.120396 0.2794)
			(stroke
				(width 0.1)
				(type default)
			)
			(layer "B.Fab")
		)
		(fp_line
			(start 0.12065 -0.305054)
			(end 0.12065 -0.2794)
			(stroke
				(width 0.1)
				(type default)
			)
			(layer "B.Fab")
		)
		(fp_line
			(start 0.12065 -0.2794)
			(end -0.12065 -0.2794)
			(stroke
				(width 0.1)
				(type default)
			)
			(layer "B.Fab")
		)
		(fp_line
			(start 0.12065 0.2794)
			(end 0.12065 0.3048)
			(stroke
				(width 0.1)
				(type default)
			)
			(layer "B.Fab")
		)
		(fp_line
			(start 0.12065 0.3048)
			(end 0.67945 0.3048)
			(stroke
				(width 0.1)
				(type default)
			)
			(layer "B.Fab")
		)
		(fp_line
			(start 0.67945 -0.305054)
			(end 0.12065 -0.305054)
			(stroke
				(width 0.1)
				(type default)
			)
			(layer "B.Fab")
		)
		(fp_line
			(start 0.67945 0.3048)
			(end 0.67945 -0.305054)
			(stroke
				(width 0.1)
				(type default)
			)
			(layer "B.Fab")
		)
		(pad "1" smd circle
			(at 0.40005 0 180)
			(size 0 0)
			(layers "B.Cu" "B.Mask" "B.Paste")
			(net "P3V3_AUX")
		)
		(pad "2" smd circle
			(at -0.40005 0 180)
			(size 0 0)
			(layers "B.Cu" "B.Mask" "B.Paste")
			(net "GND")
		)
	)
	(footprint ""
		(layer "B.Cu")
		(at 164.508688 -9.013444 90)
		(property "Reference" "R55"
			(at 0 0 90)
			(layer "B.SilkS")
			(hide yes)
			(effects
				(font
					(size 1.27 1.27)
				)
				(justify mirror)
			)
		)
		(property "Value" ""
			(at 0 0 90)
			(layer "B.Fab")
			(effects
				(font
					(size 1.27 1.27)
				)
				(justify mirror)
			)
		)
		(duplicate_pad_numbers_are_jumpers no)
		(fp_line
			(start 0.7874 -0.4064)
			(end -0.7874 -0.4064)
			(stroke
				(width 0.1524)
				(type default)
			)
			(layer "B.SilkS")
		)
		(fp_line
			(start -0.7874 -0.4064)
			(end -0.7874 0.4064)
			(stroke
				(width 0.1524)
				(type default)
			)
			(layer "B.SilkS")
		)
		(fp_line
			(start 0.7874 0.4064)
			(end 0.7874 -0.4064)
			(stroke
				(width 0.1524)
				(type default)
			)
			(layer "B.SilkS")
		)
		(fp_line
			(start -0.7874 0.4064)
			(end 0.7874 0.4064)
			(stroke
				(width 0.1524)
				(type default)
			)
			(layer "B.SilkS")
		)
		(fp_line
			(start 0.67945 -0.305054)
			(end 0.12065 -0.305054)
			(stroke
				(width 0.1)
				(type default)
			)
			(layer "B.Fab")
		)
		(fp_line
			(start 0.12065 -0.305054)
			(end 0.12065 -0.2794)
			(stroke
				(width 0.1)
				(type default)
			)
			(layer "B.Fab")
		)
		(fp_line
			(start -0.12065 -0.3048)
			(end -0.67945 -0.3048)
			(stroke
				(width 0.1)
				(type default)
			)
			(layer "B.Fab")
		)
		(fp_line
			(start -0.67945 -0.3048)
			(end -0.67945 0.3048)
			(stroke
				(width 0.1)
				(type default)
			)
			(layer "B.Fab")
		)
		(fp_line
			(start 0.12065 -0.2794)
			(end -0.12065 -0.2794)
			(stroke
				(width 0.1)
				(type default)
			)
			(layer "B.Fab")
		)
		(fp_line
			(start -0.12065 -0.2794)
			(end -0.12065 -0.3048)
			(stroke
				(width 0.1)
				(type default)
			)
			(layer "B.Fab")
		)
		(fp_line
			(start 0.12065 0.2794)
			(end 0.12065 0.3048)
			(stroke
				(width 0.1)
				(type default)
			)
			(layer "B.Fab")
		)
		(fp_line
			(start -0.120396 0.2794)
			(end 0.12065 0.2794)
			(stroke
				(width 0.1)
				(type default)
			)
			(layer "B.Fab")
		)
		(fp_line
			(start 0.67945 0.3048)
			(end 0.67945 -0.305054)
			(stroke
				(width 0.1)
				(type default)
			)
			(layer "B.Fab")
		)
		(fp_line
			(start 0.12065 0.3048)
			(end 0.67945 0.3048)
			(stroke
				(width 0.1)
				(type default)
			)
			(layer "B.Fab")
		)
		(fp_line
			(start -0.120396 0.3048)
			(end -0.120396 0.2794)
			(stroke
				(width 0.1)
				(type default)
			)
			(layer "B.Fab")
		)
		(fp_line
			(start -0.67945 0.3048)
			(end -0.120396 0.3048)
			(stroke
				(width 0.1)
				(type default)
			)
			(layer "B.Fab")
		)
		(pad "1" smd circle
			(at 0.40005 0 270)
			(size 0 0)
			(layers "B.Cu" "B.Mask" "B.Paste")
			(net "SMB_PCIE0_3V3AUX_SDA")
		)
		(pad "2" smd circle
			(at -0.40005 0 270)
			(size 0 0)
			(layers "B.Cu" "B.Mask" "B.Paste")
			(net "SMB_PCIE0_3V3AUX_SDA_R")
		)
	)
	(footprint ""
		(layer "B.Cu")
		(at 153.865834 -322.903342 -90)
		(property "Reference" "R754"
			(at 0 0 90)
			(layer "B.SilkS")
			(hide yes)
			(effects
				(font
					(size 1.27 1.27)
				)
				(justify mirror)
			)
		)
		(property "Value" ""
			(at 0 0 90)
			(layer "B.Fab")
			(effects
				(font
					(size 1.27 1.27)
				)
				(justify mirror)
			)
		)
		(duplicate_pad_numbers_are_jumpers no)
		(fp_line
			(start -0.7874 0.4064)
			(end 0.7874 0.4064)
			(stroke
				(width 0.1524)
				(type default)
			)
			(layer "B.SilkS")
		)
		(fp_line
			(start 0.7874 0.4064)
			(end 0.7874 -0.4064)
			(stroke
				(width 0.1524)
				(type default)
			)
			(layer "B.SilkS")
		)
		(fp_line
			(start -0.7874 -0.4064)
			(end -0.7874 0.4064)
			(stroke
				(width 0.1524)
				(type default)
			)
			(layer "B.SilkS")
		)
		(fp_line
			(start 0.7874 -0.4064)
			(end -0.7874 -0.4064)
			(stroke
				(width 0.1524)
				(type default)
			)
			(layer "B.SilkS")
		)
		(fp_line
			(start -0.67945 0.3048)
			(end -0.120396 0.3048)
			(stroke
				(width 0.1)
				(type default)
			)
			(layer "B.Fab")
		)
		(fp_line
			(start -0.120396 0.3048)
			(end -0.120396 0.2794)
			(stroke
				(width 0.1)
				(type default)
			)
			(layer "B.Fab")
		)
		(fp_line
			(start 0.12065 0.3048)
			(end 0.67945 0.3048)
			(stroke
				(width 0.1)
				(type default)
			)
			(layer "B.Fab")
		)
		(fp_line
			(start 0.67945 0.3048)
			(end 0.67945 -0.305054)
			(stroke
				(width 0.1)
				(type default)
			)
			(layer "B.Fab")
		)
		(fp_line
			(start -0.120396 0.2794)
			(end 0.12065 0.2794)
			(stroke
				(width 0.1)
				(type default)
			)
			(layer "B.Fab")
		)
		(fp_line
			(start 0.12065 0.2794)
			(end 0.12065 0.3048)
			(stroke
				(width 0.1)
				(type default)
			)
			(layer "B.Fab")
		)
		(fp_line
			(start -0.12065 -0.2794)
			(end -0.12065 -0.3048)
			(stroke
				(width 0.1)
				(type default)
			)
			(layer "B.Fab")
		)
		(fp_line
			(start 0.12065 -0.2794)
			(end -0.12065 -0.2794)
			(stroke
				(width 0.1)
				(type default)
			)
			(layer "B.Fab")
		)
		(fp_line
			(start -0.67945 -0.3048)
			(end -0.67945 0.3048)
			(stroke
				(width 0.1)
				(type default)
			)
			(layer "B.Fab")
		)
		(fp_line
			(start -0.12065 -0.3048)
			(end -0.67945 -0.3048)
			(stroke
				(width 0.1)
				(type default)
			)
			(layer "B.Fab")
		)
		(fp_line
			(start 0.12065 -0.305054)
			(end 0.12065 -0.2794)
			(stroke
				(width 0.1)
				(type default)
			)
			(layer "B.Fab")
		)
		(fp_line
			(start 0.67945 -0.305054)
			(end 0.12065 -0.305054)
			(stroke
				(width 0.1)
				(type default)
			)
			(layer "B.Fab")
		)
		(pad "1" smd circle
			(at 0.40005 0 90)
			(size 0 0)
			(layers "B.Cu" "B.Mask" "B.Paste")
			(net "GND")
		)
		(pad "2" smd circle
			(at -0.40005 0 90)
			(size 0 0)
			(layers "B.Cu" "B.Mask" "B.Paste")
			(net "SPI_CPU1_CLK")
		)
	)
	(footprint ""
		(layer "B.Cu")
		(at 98.918522 -150.698962 -90)
		(property "Reference" "PR437"
			(at 0 0 90)
			(layer "B.SilkS")
			(hide yes)
			(effects
				(font
					(size 1.27 1.27)
				)
				(justify mirror)
			)
		)
		(property "Value" ""
			(at 0 0 90)
			(layer "B.Fab")
			(effects
				(font
					(size 1.27 1.27)
				)
				(justify mirror)
			)
		)
		(duplicate_pad_numbers_are_jumpers no)
		(fp_line
			(start -0.7874 0.4064)
			(end 0.7874 0.4064)
			(stroke
				(width 0.1524)
				(type default)
			)
			(layer "B.SilkS")
		)
		(fp_line
			(start 0.7874 0.4064)
			(end 0.7874 -0.4064)
			(stroke
				(width 0.1524)
				(type default)
			)
			(layer "B.SilkS")
		)
		(fp_line
			(start -0.7874 -0.4064)
			(end -0.7874 0.4064)
			(stroke
				(width 0.1524)
				(type default)
			)
			(layer "B.SilkS")
		)
		(fp_line
			(start 0.7874 -0.4064)
			(end -0.7874 -0.4064)
			(stroke
				(width 0.1524)
				(type default)
			)
			(layer "B.SilkS")
		)
		(fp_line
			(start -0.67945 0.3048)
			(end -0.120396 0.3048)
			(stroke
				(width 0.1)
				(type default)
			)
			(layer "B.Fab")
		)
		(fp_line
			(start -0.120396 0.3048)
			(end -0.120396 0.2794)
			(stroke
				(width 0.1)
				(type default)
			)
			(layer "B.Fab")
		)
		(fp_line
			(start 0.12065 0.3048)
			(end 0.67945 0.3048)
			(stroke
				(width 0.1)
				(type default)
			)
			(layer "B.Fab")
		)
		(fp_line
			(start 0.67945 0.3048)
			(end 0.67945 -0.305054)
			(stroke
				(width 0.1)
				(type default)
			)
			(layer "B.Fab")
		)
		(fp_line
			(start -0.120396 0.2794)
			(end 0.12065 0.2794)
			(stroke
				(width 0.1)
				(type default)
			)
			(layer "B.Fab")
		)
		(fp_line
			(start 0.12065 0.2794)
			(end 0.12065 0.3048)
			(stroke
				(width 0.1)
				(type default)
			)
			(layer "B.Fab")
		)
		(fp_line
			(start -0.12065 -0.2794)
			(end -0.12065 -0.3048)
			(stroke
				(width 0.1)
				(type default)
			)
			(layer "B.Fab")
		)
		(fp_line
			(start 0.12065 -0.2794)
			(end -0.12065 -0.2794)
			(stroke
				(width 0.1)
				(type default)
			)
			(layer "B.Fab")
		)
		(fp_line
			(start -0.67945 -0.3048)
			(end -0.67945 0.3048)
			(stroke
				(width 0.1)
				(type default)
			)
			(layer "B.Fab")
		)
		(fp_line
			(start -0.12065 -0.3048)
			(end -0.67945 -0.3048)
			(stroke
				(width 0.1)
				(type default)
			)
			(layer "B.Fab")
		)
		(fp_line
			(start 0.12065 -0.305054)
			(end 0.12065 -0.2794)
			(stroke
				(width 0.1)
				(type default)
			)
			(layer "B.Fab")
		)
		(fp_line
			(start 0.67945 -0.305054)
			(end 0.12065 -0.305054)
			(stroke
				(width 0.1)
				(type default)
			)
			(layer "B.Fab")
		)
		(pad "1" smd circle
			(at 0.40005 0 90)
			(size 0 0)
			(layers "B.Cu" "B.Mask" "B.Paste")
			(net "NC_PVDDCR_CPU0_P1_IMON9")
		)
		(pad "2" smd circle
			(at -0.40005 0 90)
			(size 0 0)
			(layers "B.Cu" "B.Mask" "B.Paste")
			(net "GND")
		)
	)
	(footprint ""
		(layer "B.Cu")
		(at 402.466302 -152.29078 -90)
		(property "Reference" "R4641"
			(at 0 0 90)
			(layer "B.SilkS")
			(hide yes)
			(effects
				(font
					(size 1.27 1.27)
				)
				(justify mirror)
			)
		)
		(property "Value" ""
			(at 0 0 90)
			(layer "B.Fab")
			(effects
				(font
					(size 1.27 1.27)
				)
				(justify mirror)
			)
		)
		(duplicate_pad_numbers_are_jumpers no)
		(fp_line
			(start -2.234946 0.9271)
			(end 2.234946 0.9271)
			(stroke
				(width 0.1524)
				(type default)
			)
			(layer "B.SilkS")
		)
		(fp_line
			(start 2.234946 0.9271)
			(end 2.234946 -0.9271)
			(stroke
				(width 0.1524)
				(type default)
			)
			(layer "B.SilkS")
		)
		(fp_line
			(start -2.234946 -0.9271)
			(end -2.234946 0.9271)
			(stroke
				(width 0.1524)
				(type default)
			)
			(layer "B.SilkS")
		)
		(fp_line
			(start 2.234946 -0.9271)
			(end -2.234946 -0.9271)
			(stroke
				(width 0.1524)
				(type default)
			)
			(layer "B.SilkS")
		)
		(fp_line
			(start -1.575054 0.824992)
			(end -1.575054 -0.824992)
			(stroke
				(width 0.1)
				(type default)
			)
			(layer "B.Fab")
		)
		(fp_line
			(start 1.575054 0.824992)
			(end -1.575054 0.824992)
			(stroke
				(width 0.1)
				(type default)
			)
			(layer "B.Fab")
		)
		(fp_line
			(start -1.575054 -0.824992)
			(end 1.575054 -0.824992)
			(stroke
				(width 0.1)
				(type default)
			)
			(layer "B.Fab")
		)
		(fp_line
			(start 1.575054 -0.824992)
			(end 1.575054 0.824992)
			(stroke
				(width 0.1)
				(type default)
			)
			(layer "B.Fab")
		)
		(pad "1" smd rect
			(at 1.599946 0 90)
			(size 1.016 1.6002)
			(layers "B.Cu" "B.Mask" "B.Paste")
			(net "P5V")
		)
		(pad "2" smd rect
			(at -1.599946 0 90)
			(size 1.016 1.6002)
			(layers "B.Cu" "B.Mask" "B.Paste")
			(net "VR_P5V_EN_D")
		)
	)
	(footprint ""
		(layer "B.Cu")
		(at 13.622782 -415.644584 -90)
		(property "Reference" "PR6542"
			(at 0 0 90)
			(layer "B.SilkS")
			(hide yes)
			(effects
				(font
					(size 1.27 1.27)
				)
				(justify mirror)
			)
		)
		(property "Value" ""
			(at 0 0 90)
			(layer "B.Fab")
			(effects
				(font
					(size 1.27 1.27)
				)
				(justify mirror)
			)
		)
		(duplicate_pad_numbers_are_jumpers no)
		(fp_line
			(start -0.7874 0.4064)
			(end 0.7874 0.4064)
			(stroke
				(width 0.1524)
				(type default)
			)
			(layer "B.SilkS")
		)
		(fp_line
			(start 0.7874 0.4064)
			(end 0.7874 -0.4064)
			(stroke
				(width 0.1524)
				(type default)
			)
			(layer "B.SilkS")
		)
		(fp_line
			(start -0.7874 -0.4064)
			(end -0.7874 0.4064)
			(stroke
				(width 0.1524)
				(type default)
			)
			(layer "B.SilkS")
		)
		(fp_line
			(start 0.7874 -0.4064)
			(end -0.7874 -0.4064)
			(stroke
				(width 0.1524)
				(type default)
			)
			(layer "B.SilkS")
		)
		(fp_line
			(start -0.67945 0.3048)
			(end -0.120396 0.3048)
			(stroke
				(width 0.1)
				(type default)
			)
			(layer "B.Fab")
		)
		(fp_line
			(start -0.120396 0.3048)
			(end -0.120396 0.2794)
			(stroke
				(width 0.1)
				(type default)
			)
			(layer "B.Fab")
		)
		(fp_line
			(start 0.12065 0.3048)
			(end 0.67945 0.3048)
			(stroke
				(width 0.1)
				(type default)
			)
			(layer "B.Fab")
		)
		(fp_line
			(start 0.67945 0.3048)
			(end 0.67945 -0.305054)
			(stroke
				(width 0.1)
				(type default)
			)
			(layer "B.Fab")
		)
		(fp_line
			(start -0.120396 0.2794)
			(end 0.12065 0.2794)
			(stroke
				(width 0.1)
				(type default)
			)
			(layer "B.Fab")
		)
		(fp_line
			(start 0.12065 0.2794)
			(end 0.12065 0.3048)
			(stroke
				(width 0.1)
				(type default)
			)
			(layer "B.Fab")
		)
		(fp_line
			(start -0.12065 -0.2794)
			(end -0.12065 -0.3048)
			(stroke
				(width 0.1)
				(type default)
			)
			(layer "B.Fab")
		)
		(fp_line
			(start 0.12065 -0.2794)
			(end -0.12065 -0.2794)
			(stroke
				(width 0.1)
				(type default)
			)
			(layer "B.Fab")
		)
		(fp_line
			(start -0.67945 -0.3048)
			(end -0.67945 0.3048)
			(stroke
				(width 0.1)
				(type default)
			)
			(layer "B.Fab")
		)
		(fp_line
			(start -0.12065 -0.3048)
			(end -0.67945 -0.3048)
			(stroke
				(width 0.1)
				(type default)
			)
			(layer "B.Fab")
		)
		(fp_line
			(start 0.12065 -0.305054)
			(end 0.12065 -0.2794)
			(stroke
				(width 0.1)
				(type default)
			)
			(layer "B.Fab")
		)
		(fp_line
			(start 0.67945 -0.305054)
			(end 0.12065 -0.305054)
			(stroke
				(width 0.1)
				(type default)
			)
			(layer "B.Fab")
		)
		(pad "1" smd circle
			(at 0.40005 0 90)
			(size 0 0)
			(layers "B.Cu" "B.Mask" "B.Paste")
			(net "NC_P0V9_RETIMER_CPU1_IMON6")
		)
		(pad "2" smd circle
			(at -0.40005 0 90)
			(size 0 0)
			(layers "B.Cu" "B.Mask" "B.Paste")
			(net "GND")
		)
	)
	(footprint ""
		(layer "B.Cu")
		(at 295.257982 -346.784168 90)
		(property "Reference" "PC159_2"
			(at 0 0 90)
			(layer "B.SilkS")
			(hide yes)
			(effects
				(font
					(size 1.27 1.27)
				)
				(justify mirror)
			)
		)
		(property "Value" ""
			(at 0 0 90)
			(layer "B.Fab")
			(effects
				(font
					(size 1.27 1.27)
				)
				(justify mirror)
			)
		)
		(duplicate_pad_numbers_are_jumpers no)
		(fp_line
			(start 1.524 -0.762)
			(end -1.524 -0.762)
			(stroke
				(width 0.1524)
				(type default)
			)
			(layer "B.SilkS")
		)
		(fp_line
			(start -1.524 -0.762)
			(end -1.524 0.762)
			(stroke
				(width 0.1524)
				(type default)
			)
			(layer "B.SilkS")
		)
		(fp_line
			(start 1.524 0.762)
			(end 1.524 -0.762)
			(stroke
				(width 0.1524)
				(type default)
			)
			(layer "B.SilkS")
		)
		(fp_line
			(start -1.524 0.762)
			(end 1.524 0.762)
			(stroke
				(width 0.1524)
				(type default)
			)
			(layer "B.SilkS")
		)
		(fp_line
			(start 1.1049 -0.724916)
			(end 1.1049 0.724916)
			(stroke
				(width 0.1)
				(type default)
			)
			(layer "B.Fab")
		)
		(fp_line
			(start -1.1049 -0.724916)
			(end 1.1049 -0.724916)
			(stroke
				(width 0.1)
				(type default)
			)
			(layer "B.Fab")
		)
		(fp_line
			(start 1.1049 0.724916)
			(end -1.1049 0.724916)
			(stroke
				(width 0.1)
				(type default)
			)
			(layer "B.Fab")
		)
		(fp_line
			(start -1.1049 0.724916)
			(end -1.1049 -0.724916)
			(stroke
				(width 0.1)
				(type default)
			)
			(layer "B.Fab")
		)
		(pad "1" smd rect
			(at 0.889 0 90)
			(size 1.016 1.27)
			(layers "B.Cu" "B.Mask" "B.Paste")
			(net "SW_P12V_AUX_PVDDIO_P0_FLT")
		)
		(pad "2" smd rect
			(at -0.889 0 90)
			(size 1.016 1.27)
			(layers "B.Cu" "B.Mask" "B.Paste")
			(net "GND")
		)
	)
	(footprint ""
		(layer "B.Cu")
		(at 233.172 -234.569 -90)
		(property "Reference" "C24"
			(at 0 0 90)
			(layer "B.SilkS")
			(hide yes)
			(effects
				(font
					(size 1.27 1.27)
				)
				(justify mirror)
			)
		)
		(property "Value" ""
			(at 0 0 90)
			(layer "B.Fab")
			(effects
				(font
					(size 1.27 1.27)
				)
				(justify mirror)
			)
		)
		(duplicate_pad_numbers_are_jumpers no)
		(fp_line
			(start -0.7874 0.4064)
			(end 0.7874 0.4064)
			(stroke
				(width 0.1524)
				(type default)
			)
			(layer "B.SilkS")
		)
		(fp_line
			(start 0.7874 0.4064)
			(end 0.7874 -0.4064)
			(stroke
				(width 0.1524)
				(type default)
			)
			(layer "B.SilkS")
		)
		(fp_line
			(start -0.7874 -0.4064)
			(end -0.7874 0.4064)
			(stroke
				(width 0.1524)
				(type default)
			)
			(layer "B.SilkS")
		)
		(fp_line
			(start 0.7874 -0.4064)
			(end -0.7874 -0.4064)
			(stroke
				(width 0.1524)
				(type default)
			)
			(layer "B.SilkS")
		)
		(fp_line
			(start -0.67945 0.3048)
			(end -0.120396 0.3048)
			(stroke
				(width 0.1)
				(type default)
			)
			(layer "B.Fab")
		)
		(fp_line
			(start -0.120396 0.3048)
			(end -0.120396 0.2794)
			(stroke
				(width 0.1)
				(type default)
			)
			(layer "B.Fab")
		)
		(fp_line
			(start 0.12065 0.3048)
			(end 0.67945 0.3048)
			(stroke
				(width 0.1)
				(type default)
			)
			(layer "B.Fab")
		)
		(fp_line
			(start 0.67945 0.3048)
			(end 0.67945 -0.305054)
			(stroke
				(width 0.1)
				(type default)
			)
			(layer "B.Fab")
		)
		(fp_line
			(start -0.120396 0.2794)
			(end 0.12065 0.2794)
			(stroke
				(width 0.1)
				(type default)
			)
			(layer "B.Fab")
		)
		(fp_line
			(start 0.12065 0.2794)
			(end 0.12065 0.3048)
			(stroke
				(width 0.1)
				(type default)
			)
			(layer "B.Fab")
		)
		(fp_line
			(start -0.12065 -0.2794)
			(end -0.12065 -0.3048)
			(stroke
				(width 0.1)
				(type default)
			)
			(layer "B.Fab")
		)
		(fp_line
			(start 0.12065 -0.2794)
			(end -0.12065 -0.2794)
			(stroke
				(width 0.1)
				(type default)
			)
			(layer "B.Fab")
		)
		(fp_line
			(start -0.67945 -0.3048)
			(end -0.67945 0.3048)
			(stroke
				(width 0.1)
				(type default)
			)
			(layer "B.Fab")
		)
		(fp_line
			(start -0.12065 -0.3048)
			(end -0.67945 -0.3048)
			(stroke
				(width 0.1)
				(type default)
			)
			(layer "B.Fab")
		)
		(fp_line
			(start 0.12065 -0.305054)
			(end 0.12065 -0.2794)
			(stroke
				(width 0.1)
				(type default)
			)
			(layer "B.Fab")
		)
		(fp_line
			(start 0.67945 -0.305054)
			(end 0.12065 -0.305054)
			(stroke
				(width 0.1)
				(type default)
			)
			(layer "B.Fab")
		)
		(pad "1" smd circle
			(at 0.40005 0 90)
			(size 0 0)
			(layers "B.Cu" "B.Mask" "B.Paste")
			(net "PVDD18_S5_P0")
		)
		(pad "2" smd circle
			(at -0.40005 0 90)
			(size 0 0)
			(layers "B.Cu" "B.Mask" "B.Paste")
			(net "GND")
		)
	)
	(footprint ""
		(layer "B.Cu")
		(at 255.905 -341.884 180)
		(property "Reference" "R797"
			(at 0 0 0)
			(layer "B.SilkS")
			(hide yes)
			(effects
				(font
					(size 1.27 1.27)
				)
				(justify mirror)
			)
		)
		(property "Value" ""
			(at 0 0 0)
			(layer "B.Fab")
			(effects
				(font
					(size 1.27 1.27)
				)
				(justify mirror)
			)
		)
		(duplicate_pad_numbers_are_jumpers no)
		(fp_line
			(start 0.32512 0.175006)
			(end 0.32512 -0.175006)
			(stroke
				(width 0.1)
				(type default)
			)
			(layer "B.Fab")
		)
		(fp_line
			(start 0.32512 -0.175006)
			(end -0.32512 -0.175006)
			(stroke
				(width 0.1)
				(type default)
			)
			(layer "B.Fab")
		)
		(fp_line
			(start -0.32512 0.175006)
			(end 0.32512 0.175006)
			(stroke
				(width 0.1)
				(type default)
			)
			(layer "B.Fab")
		)
		(fp_line
			(start -0.32512 -0.175006)
			(end -0.32512 0.175006)
			(stroke
				(width 0.1)
				(type default)
			)
			(layer "B.Fab")
		)
		(pad "1" smd rect
			(at 0.2667 0)
			(size 0.3048 0.381)
			(layers "B.Cu" "B.Mask" "B.Paste")
			(net "SMB_RT_CPU0_P0_ROM_MUX_2D_R_SDA")
		)
		(pad "2" smd rect
			(at -0.2667 0 180)
			(size 0.3048 0.381)
			(layers "B.Cu" "B.Mask" "B.Paste")
			(net "SMB_RT_CPU0_P0_ROM_MUX_2D_SDA")
		)
	)
	(footprint ""
		(layer "B.Cu")
		(at 330.523342 -392.1252 180)
		(property "Reference" "R1021"
			(at 0 0 0)
			(layer "B.SilkS")
			(hide yes)
			(effects
				(font
					(size 1.27 1.27)
				)
				(justify mirror)
			)
		)
		(property "Value" ""
			(at 0 0 0)
			(layer "B.Fab")
			(effects
				(font
					(size 1.27 1.27)
				)
				(justify mirror)
			)
		)
		(duplicate_pad_numbers_are_jumpers no)
		(fp_line
			(start 0.32512 0.175006)
			(end 0.32512 -0.175006)
			(stroke
				(width 0.1)
				(type default)
			)
			(layer "B.Fab")
		)
		(fp_line
			(start 0.32512 -0.175006)
			(end -0.32512 -0.175006)
			(stroke
				(width 0.1)
				(type default)
			)
			(layer "B.Fab")
		)
		(fp_line
			(start -0.32512 0.175006)
			(end 0.32512 0.175006)
			(stroke
				(width 0.1)
				(type default)
			)
			(layer "B.Fab")
		)
		(fp_line
			(start -0.32512 -0.175006)
			(end -0.32512 0.175006)
			(stroke
				(width 0.1)
				(type default)
			)
			(layer "B.Fab")
		)
		(pad "1" smd rect
			(at 0.2667 0)
			(size 0.3048 0.381)
			(layers "B.Cu" "B.Mask" "B.Paste")
			(net "P1V8_CPU0_RT_1D")
		)
		(pad "2" smd rect
			(at -0.2667 0 180)
			(size 0.3048 0.381)
			(layers "B.Cu" "B.Mask" "B.Paste")
			(net "RT_CPU0_P1_SCAN_MODE")
		)
	)
	(footprint ""
		(layer "B.Cu")
		(at 111.47806 -35.088068 90)
		(property "Reference" "C6111"
			(at 0 0 90)
			(layer "B.SilkS")
			(hide yes)
			(effects
				(font
					(size 1.27 1.27)
				)
				(justify mirror)
			)
		)
		(property "Value" ""
			(at 0 0 90)
			(layer "B.Fab")
			(effects
				(font
					(size 1.27 1.27)
				)
				(justify mirror)
			)
		)
		(duplicate_pad_numbers_are_jumpers no)
		(fp_line
			(start 0.7874 -0.4064)
			(end -0.7874 -0.4064)
			(stroke
				(width 0.1524)
				(type default)
			)
			(layer "B.SilkS")
		)
		(fp_line
			(start -0.7874 -0.4064)
			(end -0.7874 0.4064)
			(stroke
				(width 0.1524)
				(type default)
			)
			(layer "B.SilkS")
		)
		(fp_line
			(start 0.7874 0.4064)
			(end 0.7874 -0.4064)
			(stroke
				(width 0.1524)
				(type default)
			)
			(layer "B.SilkS")
		)
		(fp_line
			(start -0.7874 0.4064)
			(end 0.7874 0.4064)
			(stroke
				(width 0.1524)
				(type default)
			)
			(layer "B.SilkS")
		)
		(fp_line
			(start 0.67945 -0.305054)
			(end 0.12065 -0.305054)
			(stroke
				(width 0.1)
				(type default)
			)
			(layer "B.Fab")
		)
		(fp_line
			(start 0.12065 -0.305054)
			(end 0.12065 -0.2794)
			(stroke
				(width 0.1)
				(type default)
			)
			(layer "B.Fab")
		)
		(fp_line
			(start -0.12065 -0.3048)
			(end -0.67945 -0.3048)
			(stroke
				(width 0.1)
				(type default)
			)
			(layer "B.Fab")
		)
		(fp_line
			(start -0.67945 -0.3048)
			(end -0.67945 0.3048)
			(stroke
				(width 0.1)
				(type default)
			)
			(layer "B.Fab")
		)
		(fp_line
			(start 0.12065 -0.2794)
			(end -0.12065 -0.2794)
			(stroke
				(width 0.1)
				(type default)
			)
			(layer "B.Fab")
		)
		(fp_line
			(start -0.12065 -0.2794)
			(end -0.12065 -0.3048)
			(stroke
				(width 0.1)
				(type default)
			)
			(layer "B.Fab")
		)
		(fp_line
			(start 0.12065 0.2794)
			(end 0.12065 0.3048)
			(stroke
				(width 0.1)
				(type default)
			)
			(layer "B.Fab")
		)
		(fp_line
			(start -0.120396 0.2794)
			(end 0.12065 0.2794)
			(stroke
				(width 0.1)
				(type default)
			)
			(layer "B.Fab")
		)
		(fp_line
			(start 0.67945 0.3048)
			(end 0.67945 -0.305054)
			(stroke
				(width 0.1)
				(type default)
			)
			(layer "B.Fab")
		)
		(fp_line
			(start 0.12065 0.3048)
			(end 0.67945 0.3048)
			(stroke
				(width 0.1)
				(type default)
			)
			(layer "B.Fab")
		)
		(fp_line
			(start -0.120396 0.3048)
			(end -0.120396 0.2794)
			(stroke
				(width 0.1)
				(type default)
			)
			(layer "B.Fab")
		)
		(fp_line
			(start -0.67945 0.3048)
			(end -0.120396 0.3048)
			(stroke
				(width 0.1)
				(type default)
			)
			(layer "B.Fab")
		)
		(pad "1" smd circle
			(at 0.40005 0 270)
			(size 0 0)
			(layers "B.Cu" "B.Mask" "B.Paste")
			(net "P1V2_CPU0_USB2_DVDD12")
		)
		(pad "2" smd circle
			(at -0.40005 0 270)
			(size 0 0)
			(layers "B.Cu" "B.Mask" "B.Paste")
			(net "GND")
		)
	)
	(footprint ""
		(layer "B.Cu")
		(at 304.718212 -396.393162 -90)
		(property "Reference" "C523"
			(at 0 0 90)
			(layer "B.SilkS")
			(hide yes)
			(effects
				(font
					(size 1.27 1.27)
				)
				(justify mirror)
			)
		)
		(property "Value" ""
			(at 0 0 90)
			(layer "B.Fab")
			(effects
				(font
					(size 1.27 1.27)
				)
				(justify mirror)
			)
		)
		(duplicate_pad_numbers_are_jumpers no)
		(fp_line
			(start -0.299974 0.150114)
			(end 0.299974 0.150114)
			(stroke
				(width 0.1)
				(type default)
			)
			(layer "B.Fab")
		)
		(fp_line
			(start 0.299974 0.150114)
			(end 0.299974 -0.150114)
			(stroke
				(width 0.1)
				(type default)
			)
			(layer "B.Fab")
		)
		(fp_line
			(start -0.299974 -0.150114)
			(end -0.299974 0.150114)
			(stroke
				(width 0.1)
				(type default)
			)
			(layer "B.Fab")
		)
		(fp_line
			(start 0.299974 -0.150114)
			(end -0.299974 -0.150114)
			(stroke
				(width 0.1)
				(type default)
			)
			(layer "B.Fab")
		)
		(pad "1" smd rect
			(at 0.2667 0 90)
			(size 0.3048 0.381)
			(layers "B.Cu" "B.Mask" "B.Paste")
			(net "P0V9_CPU0_RT0_2A")
		)
		(pad "2" smd rect
			(at -0.2667 0 90)
			(size 0.3048 0.381)
			(layers "B.Cu" "B.Mask" "B.Paste")
			(net "GND")
		)
	)
	(footprint ""
		(layer "B.Cu")
		(at 416.218878 -398.942052 90)
		(property "Reference" "C981"
			(at 0 0 90)
			(layer "B.SilkS")
			(hide yes)
			(effects
				(font
					(size 1.27 1.27)
				)
				(justify mirror)
			)
		)
		(property "Value" ""
			(at 0 0 90)
			(layer "B.Fab")
			(effects
				(font
					(size 1.27 1.27)
				)
				(justify mirror)
			)
		)
		(duplicate_pad_numbers_are_jumpers no)
		(fp_line
			(start 0.7874 -0.4064)
			(end -0.7874 -0.4064)
			(stroke
				(width 0.1524)
				(type default)
			)
			(layer "B.SilkS")
		)
		(fp_line
			(start -0.7874 -0.4064)
			(end -0.7874 0.4064)
			(stroke
				(width 0.1524)
				(type default)
			)
			(layer "B.SilkS")
		)
		(fp_line
			(start 0.7874 0.4064)
			(end 0.7874 -0.4064)
			(stroke
				(width 0.1524)
				(type default)
			)
			(layer "B.SilkS")
		)
		(fp_line
			(start -0.7874 0.4064)
			(end 0.7874 0.4064)
			(stroke
				(width 0.1524)
				(type default)
			)
			(layer "B.SilkS")
		)
		(fp_line
			(start 0.67945 -0.305054)
			(end 0.12065 -0.305054)
			(stroke
				(width 0.1)
				(type default)
			)
			(layer "B.Fab")
		)
		(fp_line
			(start 0.12065 -0.305054)
			(end 0.12065 -0.2794)
			(stroke
				(width 0.1)
				(type default)
			)
			(layer "B.Fab")
		)
		(fp_line
			(start -0.12065 -0.3048)
			(end -0.67945 -0.3048)
			(stroke
				(width 0.1)
				(type default)
			)
			(layer "B.Fab")
		)
		(fp_line
			(start -0.67945 -0.3048)
			(end -0.67945 0.3048)
			(stroke
				(width 0.1)
				(type default)
			)
			(layer "B.Fab")
		)
		(fp_line
			(start 0.12065 -0.2794)
			(end -0.12065 -0.2794)
			(stroke
				(width 0.1)
				(type default)
			)
			(layer "B.Fab")
		)
		(fp_line
			(start -0.12065 -0.2794)
			(end -0.12065 -0.3048)
			(stroke
				(width 0.1)
				(type default)
			)
			(layer "B.Fab")
		)
		(fp_line
			(start 0.12065 0.2794)
			(end 0.12065 0.3048)
			(stroke
				(width 0.1)
				(type default)
			)
			(layer "B.Fab")
		)
		(fp_line
			(start -0.120396 0.2794)
			(end 0.12065 0.2794)
			(stroke
				(width 0.1)
				(type default)
			)
			(layer "B.Fab")
		)
		(fp_line
			(start 0.67945 0.3048)
			(end 0.67945 -0.305054)
			(stroke
				(width 0.1)
				(type default)
			)
			(layer "B.Fab")
		)
		(fp_line
			(start 0.12065 0.3048)
			(end 0.67945 0.3048)
			(stroke
				(width 0.1)
				(type default)
			)
			(layer "B.Fab")
		)
		(fp_line
			(start -0.120396 0.3048)
			(end -0.120396 0.2794)
			(stroke
				(width 0.1)
				(type default)
			)
			(layer "B.Fab")
		)
		(fp_line
			(start -0.67945 0.3048)
			(end -0.120396 0.3048)
			(stroke
				(width 0.1)
				(type default)
			)
			(layer "B.Fab")
		)
		(pad "1" smd circle
			(at 0.40005 0 270)
			(size 0 0)
			(layers "B.Cu" "B.Mask" "B.Paste")
			(net "P0V9_CPU0_RT2_2A")
		)
		(pad "2" smd circle
			(at -0.40005 0 270)
			(size 0 0)
			(layers "B.Cu" "B.Mask" "B.Paste")
			(net "GND")
		)
	)
	(footprint ""
		(layer "B.Cu")
		(at 242.443 -231.648 -90)
		(property "Reference" "R367"
			(at 0 0 90)
			(layer "B.SilkS")
			(hide yes)
			(effects
				(font
					(size 1.27 1.27)
				)
				(justify mirror)
			)
		)
		(property "Value" ""
			(at 0 0 90)
			(layer "B.Fab")
			(effects
				(font
					(size 1.27 1.27)
				)
				(justify mirror)
			)
		)
		(duplicate_pad_numbers_are_jumpers no)
		(fp_line
			(start -0.7874 0.4064)
			(end 0.7874 0.4064)
			(stroke
				(width 0.1524)
				(type default)
			)
			(layer "B.SilkS")
		)
		(fp_line
			(start 0.7874 0.4064)
			(end 0.7874 -0.4064)
			(stroke
				(width 0.1524)
				(type default)
			)
			(layer "B.SilkS")
		)
		(fp_line
			(start -0.7874 -0.4064)
			(end -0.7874 0.4064)
			(stroke
				(width 0.1524)
				(type default)
			)
			(layer "B.SilkS")
		)
		(fp_line
			(start 0.7874 -0.4064)
			(end -0.7874 -0.4064)
			(stroke
				(width 0.1524)
				(type default)
			)
			(layer "B.SilkS")
		)
		(fp_line
			(start -0.67945 0.3048)
			(end -0.120396 0.3048)
			(stroke
				(width 0.1)
				(type default)
			)
			(layer "B.Fab")
		)
		(fp_line
			(start -0.120396 0.3048)
			(end -0.120396 0.2794)
			(stroke
				(width 0.1)
				(type default)
			)
			(layer "B.Fab")
		)
		(fp_line
			(start 0.12065 0.3048)
			(end 0.67945 0.3048)
			(stroke
				(width 0.1)
				(type default)
			)
			(layer "B.Fab")
		)
		(fp_line
			(start 0.67945 0.3048)
			(end 0.67945 -0.305054)
			(stroke
				(width 0.1)
				(type default)
			)
			(layer "B.Fab")
		)
		(fp_line
			(start -0.120396 0.2794)
			(end 0.12065 0.2794)
			(stroke
				(width 0.1)
				(type default)
			)
			(layer "B.Fab")
		)
		(fp_line
			(start 0.12065 0.2794)
			(end 0.12065 0.3048)
			(stroke
				(width 0.1)
				(type default)
			)
			(layer "B.Fab")
		)
		(fp_line
			(start -0.12065 -0.2794)
			(end -0.12065 -0.3048)
			(stroke
				(width 0.1)
				(type default)
			)
			(layer "B.Fab")
		)
		(fp_line
			(start 0.12065 -0.2794)
			(end -0.12065 -0.2794)
			(stroke
				(width 0.1)
				(type default)
			)
			(layer "B.Fab")
		)
		(fp_line
			(start -0.67945 -0.3048)
			(end -0.67945 0.3048)
			(stroke
				(width 0.1)
				(type default)
			)
			(layer "B.Fab")
		)
		(fp_line
			(start -0.12065 -0.3048)
			(end -0.67945 -0.3048)
			(stroke
				(width 0.1)
				(type default)
			)
			(layer "B.Fab")
		)
		(fp_line
			(start 0.12065 -0.305054)
			(end 0.12065 -0.2794)
			(stroke
				(width 0.1)
				(type default)
			)
			(layer "B.Fab")
		)
		(fp_line
			(start 0.67945 -0.305054)
			(end 0.12065 -0.305054)
			(stroke
				(width 0.1)
				(type default)
			)
			(layer "B.Fab")
		)
		(pad "1" smd circle
			(at 0.40005 0 90)
			(size 0 0)
			(layers "B.Cu" "B.Mask" "B.Paste")
			(net "PVDD18_S5_P0")
		)
		(pad "2" smd circle
			(at -0.40005 0 90)
			(size 0 0)
			(layers "B.Cu" "B.Mask" "B.Paste")
			(net "SMB_CPU0_SEC_SCL")
		)
	)
	(footprint ""
		(layer "B.Cu")
		(at 112.611154 -180.200046 90)
		(property "Reference" "PC341_1"
			(at 0 0 90)
			(layer "B.SilkS")
			(hide yes)
			(effects
				(font
					(size 1.27 1.27)
				)
				(justify mirror)
			)
		)
		(property "Value" ""
			(at 0 0 90)
			(layer "B.Fab")
			(effects
				(font
					(size 1.27 1.27)
				)
				(justify mirror)
			)
		)
		(duplicate_pad_numbers_are_jumpers no)
		(fp_line
			(start 1.524 -0.762)
			(end -1.524 -0.762)
			(stroke
				(width 0.1524)
				(type default)
			)
			(layer "B.SilkS")
		)
		(fp_line
			(start -1.524 -0.762)
			(end -1.524 0.762)
			(stroke
				(width 0.1524)
				(type default)
			)
			(layer "B.SilkS")
		)
		(fp_line
			(start 1.524 0.762)
			(end 1.524 -0.762)
			(stroke
				(width 0.1524)
				(type default)
			)
			(layer "B.SilkS")
		)
		(fp_line
			(start -1.524 0.762)
			(end 1.524 0.762)
			(stroke
				(width 0.1524)
				(type default)
			)
			(layer "B.SilkS")
		)
		(fp_line
			(start 1.1049 -0.724916)
			(end 1.1049 0.724916)
			(stroke
				(width 0.1)
				(type default)
			)
			(layer "B.Fab")
		)
		(fp_line
			(start -1.1049 -0.724916)
			(end 1.1049 -0.724916)
			(stroke
				(width 0.1)
				(type default)
			)
			(layer "B.Fab")
		)
		(fp_line
			(start 1.1049 0.724916)
			(end -1.1049 0.724916)
			(stroke
				(width 0.1)
				(type default)
			)
			(layer "B.Fab")
		)
		(fp_line
			(start -1.1049 0.724916)
			(end -1.1049 -0.724916)
			(stroke
				(width 0.1)
				(type default)
			)
			(layer "B.Fab")
		)
		(pad "1" smd rect
			(at 0.889 0 90)
			(size 1.016 1.27)
			(layers "B.Cu" "B.Mask" "B.Paste")
			(net "PVDDCR_SOC_P1")
		)
		(pad "2" smd rect
			(at -0.889 0 90)
			(size 1.016 1.27)
			(layers "B.Cu" "B.Mask" "B.Paste")
			(net "GND")
		)
	)
	(footprint ""
		(layer "B.Cu")
		(at 376.218958 -205.101952 -90)
		(property "Reference" "R398"
			(at 0 0 90)
			(layer "B.SilkS")
			(hide yes)
			(effects
				(font
					(size 1.27 1.27)
				)
				(justify mirror)
			)
		)
		(property "Value" ""
			(at 0 0 90)
			(layer "B.Fab")
			(effects
				(font
					(size 1.27 1.27)
				)
				(justify mirror)
			)
		)
		(duplicate_pad_numbers_are_jumpers no)
		(fp_line
			(start -0.7874 0.4064)
			(end 0.7874 0.4064)
			(stroke
				(width 0.1524)
				(type default)
			)
			(layer "B.SilkS")
		)
		(fp_line
			(start 0.7874 0.4064)
			(end 0.7874 -0.4064)
			(stroke
				(width 0.1524)
				(type default)
			)
			(layer "B.SilkS")
		)
		(fp_line
			(start -0.7874 -0.4064)
			(end -0.7874 0.4064)
			(stroke
				(width 0.1524)
				(type default)
			)
			(layer "B.SilkS")
		)
		(fp_line
			(start 0.7874 -0.4064)
			(end -0.7874 -0.4064)
			(stroke
				(width 0.1524)
				(type default)
			)
			(layer "B.SilkS")
		)
		(fp_line
			(start -0.67945 0.3048)
			(end -0.120396 0.3048)
			(stroke
				(width 0.1)
				(type default)
			)
			(layer "B.Fab")
		)
		(fp_line
			(start -0.120396 0.3048)
			(end -0.120396 0.2794)
			(stroke
				(width 0.1)
				(type default)
			)
			(layer "B.Fab")
		)
		(fp_line
			(start 0.12065 0.3048)
			(end 0.67945 0.3048)
			(stroke
				(width 0.1)
				(type default)
			)
			(layer "B.Fab")
		)
		(fp_line
			(start 0.67945 0.3048)
			(end 0.67945 -0.305054)
			(stroke
				(width 0.1)
				(type default)
			)
			(layer "B.Fab")
		)
		(fp_line
			(start -0.120396 0.2794)
			(end 0.12065 0.2794)
			(stroke
				(width 0.1)
				(type default)
			)
			(layer "B.Fab")
		)
		(fp_line
			(start 0.12065 0.2794)
			(end 0.12065 0.3048)
			(stroke
				(width 0.1)
				(type default)
			)
			(layer "B.Fab")
		)
		(fp_line
			(start -0.12065 -0.2794)
			(end -0.12065 -0.3048)
			(stroke
				(width 0.1)
				(type default)
			)
			(layer "B.Fab")
		)
		(fp_line
			(start 0.12065 -0.2794)
			(end -0.12065 -0.2794)
			(stroke
				(width 0.1)
				(type default)
			)
			(layer "B.Fab")
		)
		(fp_line
			(start -0.67945 -0.3048)
			(end -0.67945 0.3048)
			(stroke
				(width 0.1)
				(type default)
			)
			(layer "B.Fab")
		)
		(fp_line
			(start -0.12065 -0.3048)
			(end -0.67945 -0.3048)
			(stroke
				(width 0.1)
				(type default)
			)
			(layer "B.Fab")
		)
		(fp_line
			(start 0.12065 -0.305054)
			(end 0.12065 -0.2794)
			(stroke
				(width 0.1)
				(type default)
			)
			(layer "B.Fab")
		)
		(fp_line
			(start 0.67945 -0.305054)
			(end 0.12065 -0.305054)
			(stroke
				(width 0.1)
				(type default)
			)
			(layer "B.Fab")
		)
		(pad "1" smd circle
			(at 0.40005 0 90)
			(size 0 0)
			(layers "B.Cu" "B.Mask" "B.Paste")
			(net "PVDD18_S5_P0")
		)
		(pad "2" smd circle
			(at -0.40005 0 90)
			(size 0 0)
			(layers "B.Cu" "B.Mask" "B.Paste")
			(net "JTAG_CPU0_TDO")
		)
	)
	(footprint ""
		(layer "B.Cu")
		(at 112.550448 -171.785534 -90)
		(property "Reference" "PC331_1"
			(at 0 0 90)
			(layer "B.SilkS")
			(hide yes)
			(effects
				(font
					(size 1.27 1.27)
				)
				(justify mirror)
			)
		)
		(property "Value" ""
			(at 0 0 90)
			(layer "B.Fab")
			(effects
				(font
					(size 1.27 1.27)
				)
				(justify mirror)
			)
		)
		(duplicate_pad_numbers_are_jumpers no)
		(fp_line
			(start -1.524 0.762)
			(end 1.524 0.762)
			(stroke
				(width 0.1524)
				(type default)
			)
			(layer "B.SilkS")
		)
		(fp_line
			(start 1.524 0.762)
			(end 1.524 -0.762)
			(stroke
				(width 0.1524)
				(type default)
			)
			(layer "B.SilkS")
		)
		(fp_line
			(start -1.524 -0.762)
			(end -1.524 0.762)
			(stroke
				(width 0.1524)
				(type default)
			)
			(layer "B.SilkS")
		)
		(fp_line
			(start 1.524 -0.762)
			(end -1.524 -0.762)
			(stroke
				(width 0.1524)
				(type default)
			)
			(layer "B.SilkS")
		)
		(fp_line
			(start -1.1049 0.724916)
			(end -1.1049 -0.724916)
			(stroke
				(width 0.1)
				(type default)
			)
			(layer "B.Fab")
		)
		(fp_line
			(start 1.1049 0.724916)
			(end -1.1049 0.724916)
			(stroke
				(width 0.1)
				(type default)
			)
			(layer "B.Fab")
		)
		(fp_line
			(start -1.1049 -0.724916)
			(end 1.1049 -0.724916)
			(stroke
				(width 0.1)
				(type default)
			)
			(layer "B.Fab")
		)
		(fp_line
			(start 1.1049 -0.724916)
			(end 1.1049 0.724916)
			(stroke
				(width 0.1)
				(type default)
			)
			(layer "B.Fab")
		)
		(pad "1" smd rect
			(at 0.889 0 270)
			(size 1.016 1.27)
			(layers "B.Cu" "B.Mask" "B.Paste")
			(net "SW_P12V_AUX_PVDDCR_SOC_P1_FLT")
		)
		(pad "2" smd rect
			(at -0.889 0 270)
			(size 1.016 1.27)
			(layers "B.Cu" "B.Mask" "B.Paste")
			(net "GND")
		)
	)
	(footprint ""
		(layer "B.Cu")
		(at 107.129834 -245.487952 180)
		(property "Reference" "C2308"
			(at 0 0 0)
			(layer "B.SilkS")
			(hide yes)
			(effects
				(font
					(size 1.27 1.27)
				)
				(justify mirror)
			)
		)
		(property "Value" ""
			(at 0 0 0)
			(layer "B.Fab")
			(effects
				(font
					(size 1.27 1.27)
				)
				(justify mirror)
			)
		)
		(duplicate_pad_numbers_are_jumpers no)
		(fp_line
			(start 0.7874 0.4064)
			(end 0.7874 -0.4064)
			(stroke
				(width 0.1524)
				(type default)
			)
			(layer "B.SilkS")
		)
		(fp_line
			(start 0.7874 -0.4064)
			(end -0.7874 -0.4064)
			(stroke
				(width 0.1524)
				(type default)
			)
			(layer "B.SilkS")
		)
		(fp_line
			(start -0.7874 0.4064)
			(end 0.7874 0.4064)
			(stroke
				(width 0.1524)
				(type default)
			)
			(layer "B.SilkS")
		)
		(fp_line
			(start -0.7874 -0.4064)
			(end -0.7874 0.4064)
			(stroke
				(width 0.1524)
				(type default)
			)
			(layer "B.SilkS")
		)
		(fp_line
			(start 0.67945 0.3048)
			(end 0.67945 -0.305054)
			(stroke
				(width 0.1)
				(type default)
			)
			(layer "B.Fab")
		)
		(fp_line
			(start 0.67945 -0.305054)
			(end 0.12065 -0.305054)
			(stroke
				(width 0.1)
				(type default)
			)
			(layer "B.Fab")
		)
		(fp_line
			(start 0.12065 0.3048)
			(end 0.67945 0.3048)
			(stroke
				(width 0.1)
				(type default)
			)
			(layer "B.Fab")
		)
		(fp_line
			(start 0.12065 0.2794)
			(end 0.12065 0.3048)
			(stroke
				(width 0.1)
				(type default)
			)
			(layer "B.Fab")
		)
		(fp_line
			(start 0.12065 -0.2794)
			(end -0.12065 -0.2794)
			(stroke
				(width 0.1)
				(type default)
			)
			(layer "B.Fab")
		)
		(fp_line
			(start 0.12065 -0.305054)
			(end 0.12065 -0.2794)
			(stroke
				(width 0.1)
				(type default)
			)
			(layer "B.Fab")
		)
		(fp_line
			(start -0.120396 0.3048)
			(end -0.120396 0.2794)
			(stroke
				(width 0.1)
				(type default)
			)
			(layer "B.Fab")
		)
		(fp_line
			(start -0.120396 0.2794)
			(end 0.12065 0.2794)
			(stroke
				(width 0.1)
				(type default)
			)
			(layer "B.Fab")
		)
		(fp_line
			(start -0.12065 -0.2794)
			(end -0.12065 -0.3048)
			(stroke
				(width 0.1)
				(type default)
			)
			(layer "B.Fab")
		)
		(fp_line
			(start -0.12065 -0.3048)
			(end -0.67945 -0.3048)
			(stroke
				(width 0.1)
				(type default)
			)
			(layer "B.Fab")
		)
		(fp_line
			(start -0.67945 0.3048)
			(end -0.120396 0.3048)
			(stroke
				(width 0.1)
				(type default)
			)
			(layer "B.Fab")
		)
		(fp_line
			(start -0.67945 -0.3048)
			(end -0.67945 0.3048)
			(stroke
				(width 0.1)
				(type default)
			)
			(layer "B.Fab")
		)
		(pad "1" smd circle
			(at 0.40005 0)
			(size 0 0)
			(layers "B.Cu" "B.Mask" "B.Paste")
			(net "PVDDCR_CPU0_P1")
		)
		(pad "2" smd circle
			(at -0.40005 0)
			(size 0 0)
			(layers "B.Cu" "B.Mask" "B.Paste")
			(net "GND")
		)
	)
	(footprint ""
		(layer "B.Cu")
		(at 123.611386 -259.73024)
		(property "Reference" "C2432"
			(at 0 0 0)
			(layer "B.SilkS")
			(hide yes)
			(effects
				(font
					(size 1.27 1.27)
				)
				(justify mirror)
			)
		)
		(property "Value" ""
			(at 0 0 0)
			(layer "B.Fab")
			(effects
				(font
					(size 1.27 1.27)
				)
				(justify mirror)
			)
		)
		(duplicate_pad_numbers_are_jumpers no)
		(fp_line
			(start -0.7874 -0.4064)
			(end -0.7874 0.4064)
			(stroke
				(width 0.1524)
				(type default)
			)
			(layer "B.SilkS")
		)
		(fp_line
			(start -0.7874 0.4064)
			(end 0.7874 0.4064)
			(stroke
				(width 0.1524)
				(type default)
			)
			(layer "B.SilkS")
		)
		(fp_line
			(start 0.7874 -0.4064)
			(end -0.7874 -0.4064)
			(stroke
				(width 0.1524)
				(type default)
			)
			(layer "B.SilkS")
		)
		(fp_line
			(start 0.7874 0.4064)
			(end 0.7874 -0.4064)
			(stroke
				(width 0.1524)
				(type default)
			)
			(layer "B.SilkS")
		)
		(fp_line
			(start -0.67945 -0.3048)
			(end -0.67945 0.3048)
			(stroke
				(width 0.1)
				(type default)
			)
			(layer "B.Fab")
		)
		(fp_line
			(start -0.67945 0.3048)
			(end -0.120396 0.3048)
			(stroke
				(width 0.1)
				(type default)
			)
			(layer "B.Fab")
		)
		(fp_line
			(start -0.12065 -0.3048)
			(end -0.67945 -0.3048)
			(stroke
				(width 0.1)
				(type default)
			)
			(layer "B.Fab")
		)
		(fp_line
			(start -0.12065 -0.2794)
			(end -0.12065 -0.3048)
			(stroke
				(width 0.1)
				(type default)
			)
			(layer "B.Fab")
		)
		(fp_line
			(start -0.120396 0.2794)
			(end 0.12065 0.2794)
			(stroke
				(width 0.1)
				(type default)
			)
			(layer "B.Fab")
		)
		(fp_line
			(start -0.120396 0.3048)
			(end -0.120396 0.2794)
			(stroke
				(width 0.1)
				(type default)
			)
			(layer "B.Fab")
		)
		(fp_line
			(start 0.12065 -0.305054)
			(end 0.12065 -0.2794)
			(stroke
				(width 0.1)
				(type default)
			)
			(layer "B.Fab")
		)
		(fp_line
			(start 0.12065 -0.2794)
			(end -0.12065 -0.2794)
			(stroke
				(width 0.1)
				(type default)
			)
			(layer "B.Fab")
		)
		(fp_line
			(start 0.12065 0.2794)
			(end 0.12065 0.3048)
			(stroke
				(width 0.1)
				(type default)
			)
			(layer "B.Fab")
		)
		(fp_line
			(start 0.12065 0.3048)
			(end 0.67945 0.3048)
			(stroke
				(width 0.1)
				(type default)
			)
			(layer "B.Fab")
		)
		(fp_line
			(start 0.67945 -0.305054)
			(end 0.12065 -0.305054)
			(stroke
				(width 0.1)
				(type default)
			)
			(layer "B.Fab")
		)
		(fp_line
			(start 0.67945 0.3048)
			(end 0.67945 -0.305054)
			(stroke
				(width 0.1)
				(type default)
			)
			(layer "B.Fab")
		)
		(pad "1" smd circle
			(at 0.40005 0 180)
			(size 0 0)
			(layers "B.Cu" "B.Mask" "B.Paste")
			(net "PVDDCR_SOC_P1")
		)
		(pad "2" smd circle
			(at -0.40005 0 180)
			(size 0 0)
			(layers "B.Cu" "B.Mask" "B.Paste")
			(net "GND")
		)
	)
	(footprint ""
		(layer "B.Cu")
		(at 48.618902 -425.275248)
		(property "Reference" "Q72"
			(at 0.318008 -1.866138 0)
			(unlocked yes)
			(layer "B.SilkS")
			(effects
				(font
					(size 0.7874 0.5842)
					(thickness 0.1524)
				)
				(justify left mirror)
			)
		)
		(property "Value" ""
			(at 0 0 0)
			(layer "B.Fab")
			(effects
				(font
					(size 1.27 1.27)
				)
				(justify mirror)
			)
		)
		(duplicate_pad_numbers_are_jumpers no)
		(fp_line
			(start -1.332738 -1.100074)
			(end -1.332738 1.100074)
			(stroke
				(width 0.1524)
				(type default)
			)
			(layer "B.SilkS")
		)
		(fp_line
			(start -1.332738 1.100074)
			(end 1.332738 1.100074)
			(stroke
				(width 0.1524)
				(type default)
			)
			(layer "B.SilkS")
		)
		(fp_line
			(start -0.4826 -1.100074)
			(end -1.332738 -1.100074)
			(stroke
				(width 0.1524)
				(type default)
			)
			(layer "B.SilkS")
		)
		(fp_line
			(start 0 -0.541274)
			(end -0.4826 -1.100074)
			(stroke
				(width 0.1524)
				(type default)
			)
			(layer "B.SilkS")
		)
		(fp_line
			(start 0.4826 -1.100074)
			(end 0 -0.541274)
			(stroke
				(width 0.1524)
				(type default)
			)
			(layer "B.SilkS")
		)
		(fp_line
			(start 1.332738 -1.100074)
			(end 0.4826 -1.100074)
			(stroke
				(width 0.1524)
				(type default)
			)
			(layer "B.SilkS")
		)
		(fp_line
			(start 1.332738 1.100074)
			(end 1.332738 -1.100074)
			(stroke
				(width 0.1524)
				(type default)
			)
			(layer "B.SilkS")
		)
		(fp_poly
			(pts
				(xy 1.62814 -1.297686) (xy 2.372614 -1.545844) (xy 1.876298 -2.042414)
			)
			(stroke
				(width 0)
				(type default)
			)
			(fill yes)
			(layer "B.SilkS")
		)
		(fp_line
			(start -0.674878 -1.100074)
			(end -0.674878 1.100074)
			(stroke
				(width 0.1)
				(type default)
			)
			(layer "B.Fab")
		)
		(fp_line
			(start -0.674878 1.100074)
			(end 0.674878 1.100074)
			(stroke
				(width 0.1)
				(type default)
			)
			(layer "B.Fab")
		)
		(fp_line
			(start 0.674878 -1.100074)
			(end -0.674878 -1.100074)
			(stroke
				(width 0.1)
				(type default)
			)
			(layer "B.Fab")
		)
		(fp_line
			(start 0.674878 1.100074)
			(end 0.674878 -1.100074)
			(stroke
				(width 0.1)
				(type default)
			)
			(layer "B.Fab")
		)
		(fp_poly
			(pts
				(xy 2.2352 -0.298958) (xy 2.2352 -1.001014) (xy 1.533144 -0.649986)
			)
			(stroke
				(width 0)
				(type default)
			)
			(fill yes)
			(layer "B.Fab")
		)
		(pad "1" smd rect
			(at 0.94996 -0.649986 90)
			(size 0.4318 0.508)
			(layers "B.Cu" "B.Mask" "B.Paste")
			(net "GND")
		)
		(pad "2" smd rect
			(at 0.94996 0 90)
			(size 0.4318 0.508)
			(layers "B.Cu" "B.Mask" "B.Paste")
			(net "FM_GPU_PWRGD")
		)
		(pad "3" smd rect
			(at 0.94996 0.649986 90)
			(size 0.4318 0.508)
			(layers "B.Cu" "B.Mask" "B.Paste")
			(net "FM_GPU_PWRGD_ISO")
		)
		(pad "4" smd rect
			(at -0.94996 0.649986 90)
			(size 0.4318 0.508)
			(layers "B.Cu" "B.Mask" "B.Paste")
			(net "GND")
		)
		(pad "5" smd rect
			(at -0.94996 0 90)
			(size 0.4318 0.508)
			(layers "B.Cu" "B.Mask" "B.Paste")
			(net "FM_GPU_PWRGD_N")
		)
		(pad "6" smd rect
			(at -0.94996 -0.649986 90)
			(size 0.4318 0.508)
			(layers "B.Cu" "B.Mask" "B.Paste")
			(net "FM_GPU_PWRGD_N")
		)
	)
	(footprint ""
		(layer "B.Cu")
		(at 305.300126 -416.899344 90)
		(property "Reference" "C6534"
			(at 0 0 90)
			(layer "B.SilkS")
			(hide yes)
			(effects
				(font
					(size 1.27 1.27)
				)
				(justify mirror)
			)
		)
		(property "Value" ""
			(at 0 0 90)
			(layer "B.Fab")
			(effects
				(font
					(size 1.27 1.27)
				)
				(justify mirror)
			)
		)
		(duplicate_pad_numbers_are_jumpers no)
		(fp_line
			(start 0.299974 -0.150114)
			(end -0.299974 -0.150114)
			(stroke
				(width 0.1)
				(type default)
			)
			(layer "B.Fab")
		)
		(fp_line
			(start -0.299974 -0.150114)
			(end -0.299974 0.150114)
			(stroke
				(width 0.1)
				(type default)
			)
			(layer "B.Fab")
		)
		(fp_line
			(start 0.299974 0.150114)
			(end 0.299974 -0.150114)
			(stroke
				(width 0.1)
				(type default)
			)
			(layer "B.Fab")
		)
		(fp_line
			(start -0.299974 0.150114)
			(end 0.299974 0.150114)
			(stroke
				(width 0.1)
				(type default)
			)
			(layer "B.Fab")
		)
		(pad "1" smd rect
			(at 0.2667 0 270)
			(size 0.3048 0.381)
			(layers "B.Cu" "B.Mask" "B.Paste")
			(net "P5E_CPU0_P1_TX_BUF_C_DN<0>")
		)
		(pad "2" smd rect
			(at -0.2667 0 270)
			(size 0.3048 0.381)
			(layers "B.Cu" "B.Mask" "B.Paste")
			(net "P5E_CPU0_P1_TX_BUF_DN<0>")
		)
	)
	(footprint ""
		(layer "B.Cu")
		(at 82.014314 -335.060798 90)
		(property "Reference" "PC380_2"
			(at 0 0 90)
			(layer "B.SilkS")
			(hide yes)
			(effects
				(font
					(size 1.27 1.27)
				)
				(justify mirror)
			)
		)
		(property "Value" ""
			(at 0 0 90)
			(layer "B.Fab")
			(effects
				(font
					(size 1.27 1.27)
				)
				(justify mirror)
			)
		)
		(duplicate_pad_numbers_are_jumpers no)
		(fp_line
			(start 1.524 -0.762)
			(end -1.524 -0.762)
			(stroke
				(width 0.1524)
				(type default)
			)
			(layer "B.SilkS")
		)
		(fp_line
			(start -1.524 -0.762)
			(end -1.524 0.762)
			(stroke
				(width 0.1524)
				(type default)
			)
			(layer "B.SilkS")
		)
		(fp_line
			(start 1.524 0.762)
			(end 1.524 -0.762)
			(stroke
				(width 0.1524)
				(type default)
			)
			(layer "B.SilkS")
		)
		(fp_line
			(start -1.524 0.762)
			(end 1.524 0.762)
			(stroke
				(width 0.1524)
				(type default)
			)
			(layer "B.SilkS")
		)
		(fp_line
			(start 1.1049 -0.724916)
			(end 1.1049 0.724916)
			(stroke
				(width 0.1)
				(type default)
			)
			(layer "B.Fab")
		)
		(fp_line
			(start -1.1049 -0.724916)
			(end 1.1049 -0.724916)
			(stroke
				(width 0.1)
				(type default)
			)
			(layer "B.Fab")
		)
		(fp_line
			(start 1.1049 0.724916)
			(end -1.1049 0.724916)
			(stroke
				(width 0.1)
				(type default)
			)
			(layer "B.Fab")
		)
		(fp_line
			(start -1.1049 0.724916)
			(end -1.1049 -0.724916)
			(stroke
				(width 0.1)
				(type default)
			)
			(layer "B.Fab")
		)
		(pad "1" smd rect
			(at 0.889 0 90)
			(size 1.016 1.27)
			(layers "B.Cu" "B.Mask" "B.Paste")
			(net "SW_P12V_AUX_PVDDCR_CPU1_P1_FLT")
		)
		(pad "2" smd rect
			(at -0.889 0 90)
			(size 1.016 1.27)
			(layers "B.Cu" "B.Mask" "B.Paste")
			(net "GND")
		)
	)
	(footprint ""
		(layer "B.Cu")
		(at 305.034696 -349.381572 -90)
		(property "Reference" "PR91"
			(at 0 0 90)
			(layer "B.SilkS")
			(hide yes)
			(effects
				(font
					(size 1.27 1.27)
				)
				(justify mirror)
			)
		)
		(property "Value" ""
			(at 0 0 90)
			(layer "B.Fab")
			(effects
				(font
					(size 1.27 1.27)
				)
				(justify mirror)
			)
		)
		(duplicate_pad_numbers_are_jumpers no)
		(fp_line
			(start -0.7874 0.4064)
			(end 0.7874 0.4064)
			(stroke
				(width 0.1524)
				(type default)
			)
			(layer "B.SilkS")
		)
		(fp_line
			(start 0.7874 0.4064)
			(end 0.7874 -0.4064)
			(stroke
				(width 0.1524)
				(type default)
			)
			(layer "B.SilkS")
		)
		(fp_line
			(start -0.7874 -0.4064)
			(end -0.7874 0.4064)
			(stroke
				(width 0.1524)
				(type default)
			)
			(layer "B.SilkS")
		)
		(fp_line
			(start 0.7874 -0.4064)
			(end -0.7874 -0.4064)
			(stroke
				(width 0.1524)
				(type default)
			)
			(layer "B.SilkS")
		)
		(fp_line
			(start -0.67945 0.3048)
			(end -0.120396 0.3048)
			(stroke
				(width 0.1)
				(type default)
			)
			(layer "B.Fab")
		)
		(fp_line
			(start -0.120396 0.3048)
			(end -0.120396 0.2794)
			(stroke
				(width 0.1)
				(type default)
			)
			(layer "B.Fab")
		)
		(fp_line
			(start 0.12065 0.3048)
			(end 0.67945 0.3048)
			(stroke
				(width 0.1)
				(type default)
			)
			(layer "B.Fab")
		)
		(fp_line
			(start 0.67945 0.3048)
			(end 0.67945 -0.305054)
			(stroke
				(width 0.1)
				(type default)
			)
			(layer "B.Fab")
		)
		(fp_line
			(start -0.120396 0.2794)
			(end 0.12065 0.2794)
			(stroke
				(width 0.1)
				(type default)
			)
			(layer "B.Fab")
		)
		(fp_line
			(start 0.12065 0.2794)
			(end 0.12065 0.3048)
			(stroke
				(width 0.1)
				(type default)
			)
			(layer "B.Fab")
		)
		(fp_line
			(start -0.12065 -0.2794)
			(end -0.12065 -0.3048)
			(stroke
				(width 0.1)
				(type default)
			)
			(layer "B.Fab")
		)
		(fp_line
			(start 0.12065 -0.2794)
			(end -0.12065 -0.2794)
			(stroke
				(width 0.1)
				(type default)
			)
			(layer "B.Fab")
		)
		(fp_line
			(start -0.67945 -0.3048)
			(end -0.67945 0.3048)
			(stroke
				(width 0.1)
				(type default)
			)
			(layer "B.Fab")
		)
		(fp_line
			(start -0.12065 -0.3048)
			(end -0.67945 -0.3048)
			(stroke
				(width 0.1)
				(type default)
			)
			(layer "B.Fab")
		)
		(fp_line
			(start 0.12065 -0.305054)
			(end 0.12065 -0.2794)
			(stroke
				(width 0.1)
				(type default)
			)
			(layer "B.Fab")
		)
		(fp_line
			(start 0.67945 -0.305054)
			(end 0.12065 -0.305054)
			(stroke
				(width 0.1)
				(type default)
			)
			(layer "B.Fab")
		)
		(pad "1" smd circle
			(at 0.40005 0 90)
			(size 0 0)
			(layers "B.Cu" "B.Mask" "B.Paste")
			(net "PVDDCR_CPU1_P0_VOS4")
		)
		(pad "2" smd circle
			(at -0.40005 0 90)
			(size 0 0)
			(layers "B.Cu" "B.Mask" "B.Paste")
			(net "PVDDCR_CPU1_P0")
		)
	)
	(footprint ""
		(layer "B.Cu")
		(at 192.287652 -80.20304 -90)
		(property "Reference" "C640"
			(at 0 0 90)
			(layer "B.SilkS")
			(hide yes)
			(effects
				(font
					(size 1.27 1.27)
				)
				(justify mirror)
			)
		)
		(property "Value" ""
			(at 0 0 90)
			(layer "B.Fab")
			(effects
				(font
					(size 1.27 1.27)
				)
				(justify mirror)
			)
		)
		(duplicate_pad_numbers_are_jumpers no)
		(fp_line
			(start -0.7874 0.4064)
			(end 0.7874 0.4064)
			(stroke
				(width 0.1524)
				(type default)
			)
			(layer "B.SilkS")
		)
		(fp_line
			(start 0.7874 0.4064)
			(end 0.7874 -0.4064)
			(stroke
				(width 0.1524)
				(type default)
			)
			(layer "B.SilkS")
		)
		(fp_line
			(start -0.7874 -0.4064)
			(end -0.7874 0.4064)
			(stroke
				(width 0.1524)
				(type default)
			)
			(layer "B.SilkS")
		)
		(fp_line
			(start 0.7874 -0.4064)
			(end -0.7874 -0.4064)
			(stroke
				(width 0.1524)
				(type default)
			)
			(layer "B.SilkS")
		)
		(fp_line
			(start -0.67945 0.3048)
			(end -0.120396 0.3048)
			(stroke
				(width 0.1)
				(type default)
			)
			(layer "B.Fab")
		)
		(fp_line
			(start -0.120396 0.3048)
			(end -0.120396 0.2794)
			(stroke
				(width 0.1)
				(type default)
			)
			(layer "B.Fab")
		)
		(fp_line
			(start 0.12065 0.3048)
			(end 0.67945 0.3048)
			(stroke
				(width 0.1)
				(type default)
			)
			(layer "B.Fab")
		)
		(fp_line
			(start 0.67945 0.3048)
			(end 0.67945 -0.305054)
			(stroke
				(width 0.1)
				(type default)
			)
			(layer "B.Fab")
		)
		(fp_line
			(start -0.120396 0.2794)
			(end 0.12065 0.2794)
			(stroke
				(width 0.1)
				(type default)
			)
			(layer "B.Fab")
		)
		(fp_line
			(start 0.12065 0.2794)
			(end 0.12065 0.3048)
			(stroke
				(width 0.1)
				(type default)
			)
			(layer "B.Fab")
		)
		(fp_line
			(start -0.12065 -0.2794)
			(end -0.12065 -0.3048)
			(stroke
				(width 0.1)
				(type default)
			)
			(layer "B.Fab")
		)
		(fp_line
			(start 0.12065 -0.2794)
			(end -0.12065 -0.2794)
			(stroke
				(width 0.1)
				(type default)
			)
			(layer "B.Fab")
		)
		(fp_line
			(start -0.67945 -0.3048)
			(end -0.67945 0.3048)
			(stroke
				(width 0.1)
				(type default)
			)
			(layer "B.Fab")
		)
		(fp_line
			(start -0.12065 -0.3048)
			(end -0.67945 -0.3048)
			(stroke
				(width 0.1)
				(type default)
			)
			(layer "B.Fab")
		)
		(fp_line
			(start 0.12065 -0.305054)
			(end 0.12065 -0.2794)
			(stroke
				(width 0.1)
				(type default)
			)
			(layer "B.Fab")
		)
		(fp_line
			(start 0.67945 -0.305054)
			(end 0.12065 -0.305054)
			(stroke
				(width 0.1)
				(type default)
			)
			(layer "B.Fab")
		)
		(pad "1" smd circle
			(at 0.40005 0 90)
			(size 0 0)
			(layers "B.Cu" "B.Mask" "B.Paste")
			(net "P3V3_AUX")
		)
		(pad "2" smd circle
			(at -0.40005 0 90)
			(size 0 0)
			(layers "B.Cu" "B.Mask" "B.Paste")
			(net "GND")
		)
	)
	(footprint ""
		(layer "B.Cu")
		(at 236.20095 -51.209448)
		(property "Reference" "R10296"
			(at 0 0 0)
			(layer "B.SilkS")
			(hide yes)
			(effects
				(font
					(size 1.27 1.27)
				)
				(justify mirror)
			)
		)
		(property "Value" ""
			(at 0 0 0)
			(layer "B.Fab")
			(effects
				(font
					(size 1.27 1.27)
				)
				(justify mirror)
			)
		)
		(duplicate_pad_numbers_are_jumpers no)
		(fp_line
			(start -0.7874 -0.4064)
			(end -0.7874 0.4064)
			(stroke
				(width 0.1524)
				(type default)
			)
			(layer "B.SilkS")
		)
		(fp_line
			(start -0.7874 0.4064)
			(end 0.7874 0.4064)
			(stroke
				(width 0.1524)
				(type default)
			)
			(layer "B.SilkS")
		)
		(fp_line
			(start 0.7874 -0.4064)
			(end -0.7874 -0.4064)
			(stroke
				(width 0.1524)
				(type default)
			)
			(layer "B.SilkS")
		)
		(fp_line
			(start 0.7874 0.4064)
			(end 0.7874 -0.4064)
			(stroke
				(width 0.1524)
				(type default)
			)
			(layer "B.SilkS")
		)
		(fp_line
			(start -0.67945 -0.3048)
			(end -0.67945 0.3048)
			(stroke
				(width 0.1)
				(type default)
			)
			(layer "B.Fab")
		)
		(fp_line
			(start -0.67945 0.3048)
			(end -0.120396 0.3048)
			(stroke
				(width 0.1)
				(type default)
			)
			(layer "B.Fab")
		)
		(fp_line
			(start -0.12065 -0.3048)
			(end -0.67945 -0.3048)
			(stroke
				(width 0.1)
				(type default)
			)
			(layer "B.Fab")
		)
		(fp_line
			(start -0.12065 -0.2794)
			(end -0.12065 -0.3048)
			(stroke
				(width 0.1)
				(type default)
			)
			(layer "B.Fab")
		)
		(fp_line
			(start -0.120396 0.2794)
			(end 0.12065 0.2794)
			(stroke
				(width 0.1)
				(type default)
			)
			(layer "B.Fab")
		)
		(fp_line
			(start -0.120396 0.3048)
			(end -0.120396 0.2794)
			(stroke
				(width 0.1)
				(type default)
			)
			(layer "B.Fab")
		)
		(fp_line
			(start 0.12065 -0.305054)
			(end 0.12065 -0.2794)
			(stroke
				(width 0.1)
				(type default)
			)
			(layer "B.Fab")
		)
		(fp_line
			(start 0.12065 -0.2794)
			(end -0.12065 -0.2794)
			(stroke
				(width 0.1)
				(type default)
			)
			(layer "B.Fab")
		)
		(fp_line
			(start 0.12065 0.2794)
			(end 0.12065 0.3048)
			(stroke
				(width 0.1)
				(type default)
			)
			(layer "B.Fab")
		)
		(fp_line
			(start 0.12065 0.3048)
			(end 0.67945 0.3048)
			(stroke
				(width 0.1)
				(type default)
			)
			(layer "B.Fab")
		)
		(fp_line
			(start 0.67945 -0.305054)
			(end 0.12065 -0.305054)
			(stroke
				(width 0.1)
				(type default)
			)
			(layer "B.Fab")
		)
		(fp_line
			(start 0.67945 0.3048)
			(end 0.67945 -0.305054)
			(stroke
				(width 0.1)
				(type default)
			)
			(layer "B.Fab")
		)
		(pad "1" smd circle
			(at 0.40005 0 180)
			(size 0 0)
			(layers "B.Cu" "B.Mask" "B.Paste")
			(net "E1S_0_PWRDIS")
		)
		(pad "2" smd circle
			(at -0.40005 0 180)
			(size 0 0)
			(layers "B.Cu" "B.Mask" "B.Paste")
			(net "GND")
		)
	)
	(footprint ""
		(layer "B.Cu")
		(at 20.919186 -195.926964 180)
		(property "Reference" "R1704"
			(at 0 0 0)
			(layer "B.SilkS")
			(hide yes)
			(effects
				(font
					(size 1.27 1.27)
				)
				(justify mirror)
			)
		)
		(property "Value" ""
			(at 0 0 0)
			(layer "B.Fab")
			(effects
				(font
					(size 1.27 1.27)
				)
				(justify mirror)
			)
		)
		(duplicate_pad_numbers_are_jumpers no)
		(fp_line
			(start 0.7874 0.4064)
			(end 0.7874 -0.4064)
			(stroke
				(width 0.1524)
				(type default)
			)
			(layer "B.SilkS")
		)
		(fp_line
			(start 0.7874 -0.4064)
			(end -0.7874 -0.4064)
			(stroke
				(width 0.1524)
				(type default)
			)
			(layer "B.SilkS")
		)
		(fp_line
			(start -0.7874 0.4064)
			(end 0.7874 0.4064)
			(stroke
				(width 0.1524)
				(type default)
			)
			(layer "B.SilkS")
		)
		(fp_line
			(start -0.7874 -0.4064)
			(end -0.7874 0.4064)
			(stroke
				(width 0.1524)
				(type default)
			)
			(layer "B.SilkS")
		)
		(fp_line
			(start 0.67945 0.3048)
			(end 0.67945 -0.305054)
			(stroke
				(width 0.1)
				(type default)
			)
			(layer "B.Fab")
		)
		(fp_line
			(start 0.67945 -0.305054)
			(end 0.12065 -0.305054)
			(stroke
				(width 0.1)
				(type default)
			)
			(layer "B.Fab")
		)
		(fp_line
			(start 0.12065 0.3048)
			(end 0.67945 0.3048)
			(stroke
				(width 0.1)
				(type default)
			)
			(layer "B.Fab")
		)
		(fp_line
			(start 0.12065 0.2794)
			(end 0.12065 0.3048)
			(stroke
				(width 0.1)
				(type default)
			)
			(layer "B.Fab")
		)
		(fp_line
			(start 0.12065 -0.2794)
			(end -0.12065 -0.2794)
			(stroke
				(width 0.1)
				(type default)
			)
			(layer "B.Fab")
		)
		(fp_line
			(start 0.12065 -0.305054)
			(end 0.12065 -0.2794)
			(stroke
				(width 0.1)
				(type default)
			)
			(layer "B.Fab")
		)
		(fp_line
			(start -0.120396 0.3048)
			(end -0.120396 0.2794)
			(stroke
				(width 0.1)
				(type default)
			)
			(layer "B.Fab")
		)
		(fp_line
			(start -0.120396 0.2794)
			(end 0.12065 0.2794)
			(stroke
				(width 0.1)
				(type default)
			)
			(layer "B.Fab")
		)
		(fp_line
			(start -0.12065 -0.2794)
			(end -0.12065 -0.3048)
			(stroke
				(width 0.1)
				(type default)
			)
			(layer "B.Fab")
		)
		(fp_line
			(start -0.12065 -0.3048)
			(end -0.67945 -0.3048)
			(stroke
				(width 0.1)
				(type default)
			)
			(layer "B.Fab")
		)
		(fp_line
			(start -0.67945 0.3048)
			(end -0.120396 0.3048)
			(stroke
				(width 0.1)
				(type default)
			)
			(layer "B.Fab")
		)
		(fp_line
			(start -0.67945 -0.3048)
			(end -0.67945 0.3048)
			(stroke
				(width 0.1)
				(type default)
			)
			(layer "B.Fab")
		)
		(pad "1" smd circle
			(at 0.40005 0)
			(size 0 0)
			(layers "B.Cu" "B.Mask" "B.Paste")
			(net "I3C_SPD_DDRAF_CPU1_SDA")
		)
		(pad "2" smd circle
			(at -0.40005 0)
			(size 0 0)
			(layers "B.Cu" "B.Mask" "B.Paste")
			(net "I3C_SPD_DDRF_CPU1_SDA")
		)
	)
	(footprint ""
		(layer "B.Cu")
		(at 378.449078 -356.362508 180)
		(property "Reference" ""
			(at 0 0 0)
			(layer "B.SilkS")
			(hide yes)
			(effects
				(font
					(size 1.27 1.27)
				)
				(justify mirror)
			)
		)
		(property "Value" ""
			(at 0 0 0)
			(layer "B.Fab")
			(effects
				(font
					(size 1.27 1.27)
				)
				(justify mirror)
			)
		)
		(duplicate_pad_numbers_are_jumpers no)
		(pad "1" smd circle
			(at 0 0)
			(size 0.9906 0.9906)
			(layers "B.Cu" "B.Mask" "B.Paste")
			(net "Net_2233")
		)
		(zone
			(layer "B.Cu")
			(hatch none 0.5)
			(connect_pads
				(clearance 0)
			)
			(min_thickness 0.25)
			(keepout
				(tracks not_allowed)
				(vias allowed)
				(pads allowed)
				(copperpour not_allowed)
				(footprints allowed)
			)
			(placement
				(enabled no)
				(sheetname "")
			)
			(fill
				(thermal_gap 0.5)
				(thermal_bridge_width 0.5)
				(island_removal_mode 0)
			)
			(polygon
				(pts
					(arc
						(start 380.074678 -356.362508)
						(mid 376.823478 -356.362508)
						(end 380.074678 -356.362508)
					)
				)
			)
		)
	)
	(footprint ""
		(layer "B.Cu")
		(at 439.029602 -421.37711)
		(property "Reference" "PR883"
			(at 0 0 0)
			(layer "B.SilkS")
			(hide yes)
			(effects
				(font
					(size 1.27 1.27)
				)
				(justify mirror)
			)
		)
		(property "Value" ""
			(at 0 0 0)
			(layer "B.Fab")
			(effects
				(font
					(size 1.27 1.27)
				)
				(justify mirror)
			)
		)
		(duplicate_pad_numbers_are_jumpers no)
		(fp_line
			(start -0.7874 -0.4064)
			(end -0.7874 0.4064)
			(stroke
				(width 0.1524)
				(type default)
			)
			(layer "B.SilkS")
		)
		(fp_line
			(start -0.7874 0.4064)
			(end 0.7874 0.4064)
			(stroke
				(width 0.1524)
				(type default)
			)
			(layer "B.SilkS")
		)
		(fp_line
			(start 0.7874 -0.4064)
			(end -0.7874 -0.4064)
			(stroke
				(width 0.1524)
				(type default)
			)
			(layer "B.SilkS")
		)
		(fp_line
			(start 0.7874 0.4064)
			(end 0.7874 -0.4064)
			(stroke
				(width 0.1524)
				(type default)
			)
			(layer "B.SilkS")
		)
		(fp_line
			(start -0.67945 -0.3048)
			(end -0.67945 0.3048)
			(stroke
				(width 0.1)
				(type default)
			)
			(layer "B.Fab")
		)
		(fp_line
			(start -0.67945 0.3048)
			(end -0.120396 0.3048)
			(stroke
				(width 0.1)
				(type default)
			)
			(layer "B.Fab")
		)
		(fp_line
			(start -0.12065 -0.3048)
			(end -0.67945 -0.3048)
			(stroke
				(width 0.1)
				(type default)
			)
			(layer "B.Fab")
		)
		(fp_line
			(start -0.12065 -0.2794)
			(end -0.12065 -0.3048)
			(stroke
				(width 0.1)
				(type default)
			)
			(layer "B.Fab")
		)
		(fp_line
			(start -0.120396 0.2794)
			(end 0.12065 0.2794)
			(stroke
				(width 0.1)
				(type default)
			)
			(layer "B.Fab")
		)
		(fp_line
			(start -0.120396 0.3048)
			(end -0.120396 0.2794)
			(stroke
				(width 0.1)
				(type default)
			)
			(layer "B.Fab")
		)
		(fp_line
			(start 0.12065 -0.305054)
			(end 0.12065 -0.2794)
			(stroke
				(width 0.1)
				(type default)
			)
			(layer "B.Fab")
		)
		(fp_line
			(start 0.12065 -0.2794)
			(end -0.12065 -0.2794)
			(stroke
				(width 0.1)
				(type default)
			)
			(layer "B.Fab")
		)
		(fp_line
			(start 0.12065 0.2794)
			(end 0.12065 0.3048)
			(stroke
				(width 0.1)
				(type default)
			)
			(layer "B.Fab")
		)
		(fp_line
			(start 0.12065 0.3048)
			(end 0.67945 0.3048)
			(stroke
				(width 0.1)
				(type default)
			)
			(layer "B.Fab")
		)
		(fp_line
			(start 0.67945 -0.305054)
			(end 0.12065 -0.305054)
			(stroke
				(width 0.1)
				(type default)
			)
			(layer "B.Fab")
		)
		(fp_line
			(start 0.67945 0.3048)
			(end 0.67945 -0.305054)
			(stroke
				(width 0.1)
				(type default)
			)
			(layer "B.Fab")
		)
		(pad "1" smd circle
			(at 0.40005 0 180)
			(size 0 0)
			(layers "B.Cu" "B.Mask" "B.Paste")
			(net "TP_P0V9_RETIMER_CPU0_SVID_ALERT_N")
		)
		(pad "2" smd circle
			(at -0.40005 0 180)
			(size 0 0)
			(layers "B.Cu" "B.Mask" "B.Paste")
			(net "GND")
		)
	)
	(footprint ""
		(layer "B.Cu")
		(at 187.071 -422.402)
		(property "Reference" "C8014"
			(at 0 0 0)
			(layer "B.SilkS")
			(hide yes)
			(effects
				(font
					(size 1.27 1.27)
				)
				(justify mirror)
			)
		)
		(property "Value" ""
			(at 0 0 0)
			(layer "B.Fab")
			(effects
				(font
					(size 1.27 1.27)
				)
				(justify mirror)
			)
		)
		(duplicate_pad_numbers_are_jumpers no)
		(fp_line
			(start -0.7874 -0.4064)
			(end -0.7874 0.4064)
			(stroke
				(width 0.1524)
				(type default)
			)
			(layer "B.SilkS")
		)
		(fp_line
			(start -0.7874 0.4064)
			(end 0.7874 0.4064)
			(stroke
				(width 0.1524)
				(type default)
			)
			(layer "B.SilkS")
		)
		(fp_line
			(start 0.7874 -0.4064)
			(end -0.7874 -0.4064)
			(stroke
				(width 0.1524)
				(type default)
			)
			(layer "B.SilkS")
		)
		(fp_line
			(start 0.7874 0.4064)
			(end 0.7874 -0.4064)
			(stroke
				(width 0.1524)
				(type default)
			)
			(layer "B.SilkS")
		)
		(fp_line
			(start -0.67945 -0.3048)
			(end -0.67945 0.3048)
			(stroke
				(width 0.1)
				(type default)
			)
			(layer "B.Fab")
		)
		(fp_line
			(start -0.67945 0.3048)
			(end -0.120396 0.3048)
			(stroke
				(width 0.1)
				(type default)
			)
			(layer "B.Fab")
		)
		(fp_line
			(start -0.12065 -0.3048)
			(end -0.67945 -0.3048)
			(stroke
				(width 0.1)
				(type default)
			)
			(layer "B.Fab")
		)
		(fp_line
			(start -0.12065 -0.2794)
			(end -0.12065 -0.3048)
			(stroke
				(width 0.1)
				(type default)
			)
			(layer "B.Fab")
		)
		(fp_line
			(start -0.120396 0.2794)
			(end 0.12065 0.2794)
			(stroke
				(width 0.1)
				(type default)
			)
			(layer "B.Fab")
		)
		(fp_line
			(start -0.120396 0.3048)
			(end -0.120396 0.2794)
			(stroke
				(width 0.1)
				(type default)
			)
			(layer "B.Fab")
		)
		(fp_line
			(start 0.12065 -0.305054)
			(end 0.12065 -0.2794)
			(stroke
				(width 0.1)
				(type default)
			)
			(layer "B.Fab")
		)
		(fp_line
			(start 0.12065 -0.2794)
			(end -0.12065 -0.2794)
			(stroke
				(width 0.1)
				(type default)
			)
			(layer "B.Fab")
		)
		(fp_line
			(start 0.12065 0.2794)
			(end 0.12065 0.3048)
			(stroke
				(width 0.1)
				(type default)
			)
			(layer "B.Fab")
		)
		(fp_line
			(start 0.12065 0.3048)
			(end 0.67945 0.3048)
			(stroke
				(width 0.1)
				(type default)
			)
			(layer "B.Fab")
		)
		(fp_line
			(start 0.67945 -0.305054)
			(end 0.12065 -0.305054)
			(stroke
				(width 0.1)
				(type default)
			)
			(layer "B.Fab")
		)
		(fp_line
			(start 0.67945 0.3048)
			(end 0.67945 -0.305054)
			(stroke
				(width 0.1)
				(type default)
			)
			(layer "B.Fab")
		)
		(pad "1" smd circle
			(at 0.40005 0 180)
			(size 0 0)
			(layers "B.Cu" "B.Mask" "B.Paste")
			(net "OC_P2V5_COMP")
		)
		(pad "2" smd circle
			(at -0.40005 0 180)
			(size 0 0)
			(layers "B.Cu" "B.Mask" "B.Paste")
			(net "GND")
		)
	)
	(footprint ""
		(layer "B.Cu")
		(at 165.419532 -435.13248 -90)
		(property "Reference" "R4573"
			(at 0 0 90)
			(layer "B.SilkS")
			(hide yes)
			(effects
				(font
					(size 1.27 1.27)
				)
				(justify mirror)
			)
		)
		(property "Value" ""
			(at 0 0 90)
			(layer "B.Fab")
			(effects
				(font
					(size 1.27 1.27)
				)
				(justify mirror)
			)
		)
		(duplicate_pad_numbers_are_jumpers no)
		(fp_line
			(start -0.7874 0.4064)
			(end 0.7874 0.4064)
			(stroke
				(width 0.1524)
				(type default)
			)
			(layer "B.SilkS")
		)
		(fp_line
			(start 0.7874 0.4064)
			(end 0.7874 -0.4064)
			(stroke
				(width 0.1524)
				(type default)
			)
			(layer "B.SilkS")
		)
		(fp_line
			(start -0.7874 -0.4064)
			(end -0.7874 0.4064)
			(stroke
				(width 0.1524)
				(type default)
			)
			(layer "B.SilkS")
		)
		(fp_line
			(start 0.7874 -0.4064)
			(end -0.7874 -0.4064)
			(stroke
				(width 0.1524)
				(type default)
			)
			(layer "B.SilkS")
		)
		(fp_line
			(start -0.67945 0.3048)
			(end -0.120396 0.3048)
			(stroke
				(width 0.1)
				(type default)
			)
			(layer "B.Fab")
		)
		(fp_line
			(start -0.120396 0.3048)
			(end -0.120396 0.2794)
			(stroke
				(width 0.1)
				(type default)
			)
			(layer "B.Fab")
		)
		(fp_line
			(start 0.12065 0.3048)
			(end 0.67945 0.3048)
			(stroke
				(width 0.1)
				(type default)
			)
			(layer "B.Fab")
		)
		(fp_line
			(start 0.67945 0.3048)
			(end 0.67945 -0.305054)
			(stroke
				(width 0.1)
				(type default)
			)
			(layer "B.Fab")
		)
		(fp_line
			(start -0.120396 0.2794)
			(end 0.12065 0.2794)
			(stroke
				(width 0.1)
				(type default)
			)
			(layer "B.Fab")
		)
		(fp_line
			(start 0.12065 0.2794)
			(end 0.12065 0.3048)
			(stroke
				(width 0.1)
				(type default)
			)
			(layer "B.Fab")
		)
		(fp_line
			(start -0.12065 -0.2794)
			(end -0.12065 -0.3048)
			(stroke
				(width 0.1)
				(type default)
			)
			(layer "B.Fab")
		)
		(fp_line
			(start 0.12065 -0.2794)
			(end -0.12065 -0.2794)
			(stroke
				(width 0.1)
				(type default)
			)
			(layer "B.Fab")
		)
		(fp_line
			(start -0.67945 -0.3048)
			(end -0.67945 0.3048)
			(stroke
				(width 0.1)
				(type default)
			)
			(layer "B.Fab")
		)
		(fp_line
			(start -0.12065 -0.3048)
			(end -0.67945 -0.3048)
			(stroke
				(width 0.1)
				(type default)
			)
			(layer "B.Fab")
		)
		(fp_line
			(start 0.12065 -0.305054)
			(end 0.12065 -0.2794)
			(stroke
				(width 0.1)
				(type default)
			)
			(layer "B.Fab")
		)
		(fp_line
			(start 0.67945 -0.305054)
			(end 0.12065 -0.305054)
			(stroke
				(width 0.1)
				(type default)
			)
			(layer "B.Fab")
		)
		(pad "1" smd circle
			(at 0.40005 0 90)
			(size 0 0)
			(layers "B.Cu" "B.Mask" "B.Paste")
			(net "PRSNT_CABLE_GPU_B3_N")
		)
		(pad "2" smd circle
			(at -0.40005 0 90)
			(size 0 0)
			(layers "B.Cu" "B.Mask" "B.Paste")
			(net "PRSNT_CABLE_GPU_B3_ISO_N")
		)
	)
	(footprint ""
		(layer "B.Cu")
		(at 278.189182 -244.08511 180)
		(property "Reference" "R379"
			(at 0 0 0)
			(layer "B.SilkS")
			(hide yes)
			(effects
				(font
					(size 1.27 1.27)
				)
				(justify mirror)
			)
		)
		(property "Value" ""
			(at 0 0 0)
			(layer "B.Fab")
			(effects
				(font
					(size 1.27 1.27)
				)
				(justify mirror)
			)
		)
		(duplicate_pad_numbers_are_jumpers no)
		(fp_line
			(start 0.7874 0.4064)
			(end 0.7874 -0.4064)
			(stroke
				(width 0.1524)
				(type default)
			)
			(layer "B.SilkS")
		)
		(fp_line
			(start 0.7874 -0.4064)
			(end -0.7874 -0.4064)
			(stroke
				(width 0.1524)
				(type default)
			)
			(layer "B.SilkS")
		)
		(fp_line
			(start -0.7874 0.4064)
			(end 0.7874 0.4064)
			(stroke
				(width 0.1524)
				(type default)
			)
			(layer "B.SilkS")
		)
		(fp_line
			(start -0.7874 -0.4064)
			(end -0.7874 0.4064)
			(stroke
				(width 0.1524)
				(type default)
			)
			(layer "B.SilkS")
		)
		(fp_line
			(start 0.67945 0.3048)
			(end 0.67945 -0.305054)
			(stroke
				(width 0.1)
				(type default)
			)
			(layer "B.Fab")
		)
		(fp_line
			(start 0.67945 -0.305054)
			(end 0.12065 -0.305054)
			(stroke
				(width 0.1)
				(type default)
			)
			(layer "B.Fab")
		)
		(fp_line
			(start 0.12065 0.3048)
			(end 0.67945 0.3048)
			(stroke
				(width 0.1)
				(type default)
			)
			(layer "B.Fab")
		)
		(fp_line
			(start 0.12065 0.2794)
			(end 0.12065 0.3048)
			(stroke
				(width 0.1)
				(type default)
			)
			(layer "B.Fab")
		)
		(fp_line
			(start 0.12065 -0.2794)
			(end -0.12065 -0.2794)
			(stroke
				(width 0.1)
				(type default)
			)
			(layer "B.Fab")
		)
		(fp_line
			(start 0.12065 -0.305054)
			(end 0.12065 -0.2794)
			(stroke
				(width 0.1)
				(type default)
			)
			(layer "B.Fab")
		)
		(fp_line
			(start -0.120396 0.3048)
			(end -0.120396 0.2794)
			(stroke
				(width 0.1)
				(type default)
			)
			(layer "B.Fab")
		)
		(fp_line
			(start -0.120396 0.2794)
			(end 0.12065 0.2794)
			(stroke
				(width 0.1)
				(type default)
			)
			(layer "B.Fab")
		)
		(fp_line
			(start -0.12065 -0.2794)
			(end -0.12065 -0.3048)
			(stroke
				(width 0.1)
				(type default)
			)
			(layer "B.Fab")
		)
		(fp_line
			(start -0.12065 -0.3048)
			(end -0.67945 -0.3048)
			(stroke
				(width 0.1)
				(type default)
			)
			(layer "B.Fab")
		)
		(fp_line
			(start -0.67945 0.3048)
			(end -0.120396 0.3048)
			(stroke
				(width 0.1)
				(type default)
			)
			(layer "B.Fab")
		)
		(fp_line
			(start -0.67945 -0.3048)
			(end -0.67945 0.3048)
			(stroke
				(width 0.1)
				(type default)
			)
			(layer "B.Fab")
		)
		(pad "1" smd circle
			(at 0.40005 0)
			(size 0 0)
			(layers "B.Cu" "B.Mask" "B.Paste")
			(net "M_E_CPU0_ALERT_N")
		)
		(pad "2" smd circle
			(at -0.40005 0)
			(size 0 0)
			(layers "B.Cu" "B.Mask" "B.Paste")
			(net "M_E_CPU0_ALERT_R_N")
		)
	)
	(footprint ""
		(layer "B.Cu")
		(at 104.521 -424.815)
		(property "Reference" "R8002"
			(at 0 0 0)
			(layer "B.SilkS")
			(hide yes)
			(effects
				(font
					(size 1.27 1.27)
				)
				(justify mirror)
			)
		)
		(property "Value" ""
			(at 0 0 0)
			(layer "B.Fab")
			(effects
				(font
					(size 1.27 1.27)
				)
				(justify mirror)
			)
		)
		(duplicate_pad_numbers_are_jumpers no)
		(fp_line
			(start -0.7874 -0.4064)
			(end -0.7874 0.4064)
			(stroke
				(width 0.1524)
				(type default)
			)
			(layer "B.SilkS")
		)
		(fp_line
			(start -0.7874 0.4064)
			(end 0.7874 0.4064)
			(stroke
				(width 0.1524)
				(type default)
			)
			(layer "B.SilkS")
		)
		(fp_line
			(start 0.7874 -0.4064)
			(end -0.7874 -0.4064)
			(stroke
				(width 0.1524)
				(type default)
			)
			(layer "B.SilkS")
		)
		(fp_line
			(start 0.7874 0.4064)
			(end 0.7874 -0.4064)
			(stroke
				(width 0.1524)
				(type default)
			)
			(layer "B.SilkS")
		)
		(fp_line
			(start -0.67945 -0.3048)
			(end -0.67945 0.3048)
			(stroke
				(width 0.1)
				(type default)
			)
			(layer "B.Fab")
		)
		(fp_line
			(start -0.67945 0.3048)
			(end -0.120396 0.3048)
			(stroke
				(width 0.1)
				(type default)
			)
			(layer "B.Fab")
		)
		(fp_line
			(start -0.12065 -0.3048)
			(end -0.67945 -0.3048)
			(stroke
				(width 0.1)
				(type default)
			)
			(layer "B.Fab")
		)
		(fp_line
			(start -0.12065 -0.2794)
			(end -0.12065 -0.3048)
			(stroke
				(width 0.1)
				(type default)
			)
			(layer "B.Fab")
		)
		(fp_line
			(start -0.120396 0.2794)
			(end 0.12065 0.2794)
			(stroke
				(width 0.1)
				(type default)
			)
			(layer "B.Fab")
		)
		(fp_line
			(start -0.120396 0.3048)
			(end -0.120396 0.2794)
			(stroke
				(width 0.1)
				(type default)
			)
			(layer "B.Fab")
		)
		(fp_line
			(start 0.12065 -0.305054)
			(end 0.12065 -0.2794)
			(stroke
				(width 0.1)
				(type default)
			)
			(layer "B.Fab")
		)
		(fp_line
			(start 0.12065 -0.2794)
			(end -0.12065 -0.2794)
			(stroke
				(width 0.1)
				(type default)
			)
			(layer "B.Fab")
		)
		(fp_line
			(start 0.12065 0.2794)
			(end 0.12065 0.3048)
			(stroke
				(width 0.1)
				(type default)
			)
			(layer "B.Fab")
		)
		(fp_line
			(start 0.12065 0.3048)
			(end 0.67945 0.3048)
			(stroke
				(width 0.1)
				(type default)
			)
			(layer "B.Fab")
		)
		(fp_line
			(start 0.67945 -0.305054)
			(end 0.12065 -0.305054)
			(stroke
				(width 0.1)
				(type default)
			)
			(layer "B.Fab")
		)
		(fp_line
			(start 0.67945 0.3048)
			(end 0.67945 -0.305054)
			(stroke
				(width 0.1)
				(type default)
			)
			(layer "B.Fab")
		)
		(pad "1" smd circle
			(at 0.40005 0 180)
			(size 0 0)
			(layers "B.Cu" "B.Mask" "B.Paste")
			(net "P3V3_AUX")
		)
		(pad "2" smd circle
			(at -0.40005 0 180)
			(size 0 0)
			(layers "B.Cu" "B.Mask" "B.Paste")
			(net "PRSNT_SWB")
		)
	)
	(footprint ""
		(layer "B.Cu")
		(at 398.230344 -145.401538 90)
		(property "Reference" "C9226"
			(at 0 0 90)
			(layer "B.SilkS")
			(hide yes)
			(effects
				(font
					(size 1.27 1.27)
				)
				(justify mirror)
			)
		)
		(property "Value" ""
			(at 0 0 90)
			(layer "B.Fab")
			(effects
				(font
					(size 1.27 1.27)
				)
				(justify mirror)
			)
		)
		(duplicate_pad_numbers_are_jumpers no)
		(fp_line
			(start 0.7874 -0.4064)
			(end -0.7874 -0.4064)
			(stroke
				(width 0.1524)
				(type default)
			)
			(layer "B.SilkS")
		)
		(fp_line
			(start -0.7874 -0.4064)
			(end -0.7874 0.4064)
			(stroke
				(width 0.1524)
				(type default)
			)
			(layer "B.SilkS")
		)
		(fp_line
			(start 0.7874 0.4064)
			(end 0.7874 -0.4064)
			(stroke
				(width 0.1524)
				(type default)
			)
			(layer "B.SilkS")
		)
		(fp_line
			(start -0.7874 0.4064)
			(end 0.7874 0.4064)
			(stroke
				(width 0.1524)
				(type default)
			)
			(layer "B.SilkS")
		)
		(fp_line
			(start 0.67945 -0.305054)
			(end 0.12065 -0.305054)
			(stroke
				(width 0.1)
				(type default)
			)
			(layer "B.Fab")
		)
		(fp_line
			(start 0.12065 -0.305054)
			(end 0.12065 -0.2794)
			(stroke
				(width 0.1)
				(type default)
			)
			(layer "B.Fab")
		)
		(fp_line
			(start -0.12065 -0.3048)
			(end -0.67945 -0.3048)
			(stroke
				(width 0.1)
				(type default)
			)
			(layer "B.Fab")
		)
		(fp_line
			(start -0.67945 -0.3048)
			(end -0.67945 0.3048)
			(stroke
				(width 0.1)
				(type default)
			)
			(layer "B.Fab")
		)
		(fp_line
			(start 0.12065 -0.2794)
			(end -0.12065 -0.2794)
			(stroke
				(width 0.1)
				(type default)
			)
			(layer "B.Fab")
		)
		(fp_line
			(start -0.12065 -0.2794)
			(end -0.12065 -0.3048)
			(stroke
				(width 0.1)
				(type default)
			)
			(layer "B.Fab")
		)
		(fp_line
			(start 0.12065 0.2794)
			(end 0.12065 0.3048)
			(stroke
				(width 0.1)
				(type default)
			)
			(layer "B.Fab")
		)
		(fp_line
			(start -0.120396 0.2794)
			(end 0.12065 0.2794)
			(stroke
				(width 0.1)
				(type default)
			)
			(layer "B.Fab")
		)
		(fp_line
			(start 0.67945 0.3048)
			(end 0.67945 -0.305054)
			(stroke
				(width 0.1)
				(type default)
			)
			(layer "B.Fab")
		)
		(fp_line
			(start 0.12065 0.3048)
			(end 0.67945 0.3048)
			(stroke
				(width 0.1)
				(type default)
			)
			(layer "B.Fab")
		)
		(fp_line
			(start -0.120396 0.3048)
			(end -0.120396 0.2794)
			(stroke
				(width 0.1)
				(type default)
			)
			(layer "B.Fab")
		)
		(fp_line
			(start -0.67945 0.3048)
			(end -0.120396 0.3048)
			(stroke
				(width 0.1)
				(type default)
			)
			(layer "B.Fab")
		)
		(pad "1" smd circle
			(at 0.40005 0 270)
			(size 0 0)
			(layers "B.Cu" "B.Mask" "B.Paste")
			(net "VR_P5V_EN_D_R")
		)
		(pad "2" smd circle
			(at -0.40005 0 270)
			(size 0 0)
			(layers "B.Cu" "B.Mask" "B.Paste")
			(net "GND")
		)
	)
	(footprint ""
		(layer "B.Cu")
		(at 281.391614 -347.77553 -90)
		(property "Reference" "PR108"
			(at 0 0 90)
			(layer "B.SilkS")
			(hide yes)
			(effects
				(font
					(size 1.27 1.27)
				)
				(justify mirror)
			)
		)
		(property "Value" ""
			(at 0 0 90)
			(layer "B.Fab")
			(effects
				(font
					(size 1.27 1.27)
				)
				(justify mirror)
			)
		)
		(duplicate_pad_numbers_are_jumpers no)
		(fp_line
			(start -0.7874 0.4064)
			(end 0.7874 0.4064)
			(stroke
				(width 0.1524)
				(type default)
			)
			(layer "B.SilkS")
		)
		(fp_line
			(start 0.7874 0.4064)
			(end 0.7874 -0.4064)
			(stroke
				(width 0.1524)
				(type default)
			)
			(layer "B.SilkS")
		)
		(fp_line
			(start -0.7874 -0.4064)
			(end -0.7874 0.4064)
			(stroke
				(width 0.1524)
				(type default)
			)
			(layer "B.SilkS")
		)
		(fp_line
			(start 0.7874 -0.4064)
			(end -0.7874 -0.4064)
			(stroke
				(width 0.1524)
				(type default)
			)
			(layer "B.SilkS")
		)
		(fp_line
			(start -0.67945 0.3048)
			(end -0.120396 0.3048)
			(stroke
				(width 0.1)
				(type default)
			)
			(layer "B.Fab")
		)
		(fp_line
			(start -0.120396 0.3048)
			(end -0.120396 0.2794)
			(stroke
				(width 0.1)
				(type default)
			)
			(layer "B.Fab")
		)
		(fp_line
			(start 0.12065 0.3048)
			(end 0.67945 0.3048)
			(stroke
				(width 0.1)
				(type default)
			)
			(layer "B.Fab")
		)
		(fp_line
			(start 0.67945 0.3048)
			(end 0.67945 -0.305054)
			(stroke
				(width 0.1)
				(type default)
			)
			(layer "B.Fab")
		)
		(fp_line
			(start -0.120396 0.2794)
			(end 0.12065 0.2794)
			(stroke
				(width 0.1)
				(type default)
			)
			(layer "B.Fab")
		)
		(fp_line
			(start 0.12065 0.2794)
			(end 0.12065 0.3048)
			(stroke
				(width 0.1)
				(type default)
			)
			(layer "B.Fab")
		)
		(fp_line
			(start -0.12065 -0.2794)
			(end -0.12065 -0.3048)
			(stroke
				(width 0.1)
				(type default)
			)
			(layer "B.Fab")
		)
		(fp_line
			(start 0.12065 -0.2794)
			(end -0.12065 -0.2794)
			(stroke
				(width 0.1)
				(type default)
			)
			(layer "B.Fab")
		)
		(fp_line
			(start -0.67945 -0.3048)
			(end -0.67945 0.3048)
			(stroke
				(width 0.1)
				(type default)
			)
			(layer "B.Fab")
		)
		(fp_line
			(start -0.12065 -0.3048)
			(end -0.67945 -0.3048)
			(stroke
				(width 0.1)
				(type default)
			)
			(layer "B.Fab")
		)
		(fp_line
			(start 0.12065 -0.305054)
			(end 0.12065 -0.2794)
			(stroke
				(width 0.1)
				(type default)
			)
			(layer "B.Fab")
		)
		(fp_line
			(start 0.67945 -0.305054)
			(end 0.12065 -0.305054)
			(stroke
				(width 0.1)
				(type default)
			)
			(layer "B.Fab")
		)
		(pad "1" smd circle
			(at 0.40005 0 90)
			(size 0 0)
			(layers "B.Cu" "B.Mask" "B.Paste")
			(net "PVDDCR_CPU1_P0_PVCC")
		)
		(pad "2" smd circle
			(at -0.40005 0 90)
			(size 0 0)
			(layers "B.Cu" "B.Mask" "B.Paste")
			(net "PVDDIO_P0_VCC3")
		)
	)
	(footprint ""
		(layer "B.Cu")
		(at 117.388386 -253.432564)
		(property "Reference" "C2415"
			(at 0 0 0)
			(layer "B.SilkS")
			(hide yes)
			(effects
				(font
					(size 1.27 1.27)
				)
				(justify mirror)
			)
		)
		(property "Value" ""
			(at 0 0 0)
			(layer "B.Fab")
			(effects
				(font
					(size 1.27 1.27)
				)
				(justify mirror)
			)
		)
		(duplicate_pad_numbers_are_jumpers no)
		(fp_line
			(start -0.7874 -0.4064)
			(end -0.7874 0.4064)
			(stroke
				(width 0.1524)
				(type default)
			)
			(layer "B.SilkS")
		)
		(fp_line
			(start -0.7874 0.4064)
			(end 0.7874 0.4064)
			(stroke
				(width 0.1524)
				(type default)
			)
			(layer "B.SilkS")
		)
		(fp_line
			(start 0.7874 -0.4064)
			(end -0.7874 -0.4064)
			(stroke
				(width 0.1524)
				(type default)
			)
			(layer "B.SilkS")
		)
		(fp_line
			(start 0.7874 0.4064)
			(end 0.7874 -0.4064)
			(stroke
				(width 0.1524)
				(type default)
			)
			(layer "B.SilkS")
		)
		(fp_line
			(start -0.67945 -0.3048)
			(end -0.67945 0.3048)
			(stroke
				(width 0.1)
				(type default)
			)
			(layer "B.Fab")
		)
		(fp_line
			(start -0.67945 0.3048)
			(end -0.120396 0.3048)
			(stroke
				(width 0.1)
				(type default)
			)
			(layer "B.Fab")
		)
		(fp_line
			(start -0.12065 -0.3048)
			(end -0.67945 -0.3048)
			(stroke
				(width 0.1)
				(type default)
			)
			(layer "B.Fab")
		)
		(fp_line
			(start -0.12065 -0.2794)
			(end -0.12065 -0.3048)
			(stroke
				(width 0.1)
				(type default)
			)
			(layer "B.Fab")
		)
		(fp_line
			(start -0.120396 0.2794)
			(end 0.12065 0.2794)
			(stroke
				(width 0.1)
				(type default)
			)
			(layer "B.Fab")
		)
		(fp_line
			(start -0.120396 0.3048)
			(end -0.120396 0.2794)
			(stroke
				(width 0.1)
				(type default)
			)
			(layer "B.Fab")
		)
		(fp_line
			(start 0.12065 -0.305054)
			(end 0.12065 -0.2794)
			(stroke
				(width 0.1)
				(type default)
			)
			(layer "B.Fab")
		)
		(fp_line
			(start 0.12065 -0.2794)
			(end -0.12065 -0.2794)
			(stroke
				(width 0.1)
				(type default)
			)
			(layer "B.Fab")
		)
		(fp_line
			(start 0.12065 0.2794)
			(end 0.12065 0.3048)
			(stroke
				(width 0.1)
				(type default)
			)
			(layer "B.Fab")
		)
		(fp_line
			(start 0.12065 0.3048)
			(end 0.67945 0.3048)
			(stroke
				(width 0.1)
				(type default)
			)
			(layer "B.Fab")
		)
		(fp_line
			(start 0.67945 -0.305054)
			(end 0.12065 -0.305054)
			(stroke
				(width 0.1)
				(type default)
			)
			(layer "B.Fab")
		)
		(fp_line
			(start 0.67945 0.3048)
			(end 0.67945 -0.305054)
			(stroke
				(width 0.1)
				(type default)
			)
			(layer "B.Fab")
		)
		(pad "1" smd circle
			(at 0.40005 0 180)
			(size 0 0)
			(layers "B.Cu" "B.Mask" "B.Paste")
			(net "PVDDCR_SOC_P1")
		)
		(pad "2" smd circle
			(at -0.40005 0 180)
			(size 0 0)
			(layers "B.Cu" "B.Mask" "B.Paste")
			(net "GND")
		)
	)
	(footprint ""
		(layer "B.Cu")
		(at 450.482716 -10.594086 90)
		(property "Reference" "R8422"
			(at 0 0 90)
			(layer "B.SilkS")
			(hide yes)
			(effects
				(font
					(size 1.27 1.27)
				)
				(justify mirror)
			)
		)
		(property "Value" ""
			(at 0 0 90)
			(layer "B.Fab")
			(effects
				(font
					(size 1.27 1.27)
				)
				(justify mirror)
			)
		)
		(duplicate_pad_numbers_are_jumpers no)
		(fp_line
			(start 0.7874 -0.4064)
			(end -0.7874 -0.4064)
			(stroke
				(width 0.1524)
				(type default)
			)
			(layer "B.SilkS")
		)
		(fp_line
			(start -0.7874 -0.4064)
			(end -0.7874 0.4064)
			(stroke
				(width 0.1524)
				(type default)
			)
			(layer "B.SilkS")
		)
		(fp_line
			(start 0.7874 0.4064)
			(end 0.7874 -0.4064)
			(stroke
				(width 0.1524)
				(type default)
			)
			(layer "B.SilkS")
		)
		(fp_line
			(start -0.7874 0.4064)
			(end 0.7874 0.4064)
			(stroke
				(width 0.1524)
				(type default)
			)
			(layer "B.SilkS")
		)
		(fp_line
			(start 0.67945 -0.305054)
			(end 0.12065 -0.305054)
			(stroke
				(width 0.1)
				(type default)
			)
			(layer "B.Fab")
		)
		(fp_line
			(start 0.12065 -0.305054)
			(end 0.12065 -0.2794)
			(stroke
				(width 0.1)
				(type default)
			)
			(layer "B.Fab")
		)
		(fp_line
			(start -0.12065 -0.3048)
			(end -0.67945 -0.3048)
			(stroke
				(width 0.1)
				(type default)
			)
			(layer "B.Fab")
		)
		(fp_line
			(start -0.67945 -0.3048)
			(end -0.67945 0.3048)
			(stroke
				(width 0.1)
				(type default)
			)
			(layer "B.Fab")
		)
		(fp_line
			(start 0.12065 -0.2794)
			(end -0.12065 -0.2794)
			(stroke
				(width 0.1)
				(type default)
			)
			(layer "B.Fab")
		)
		(fp_line
			(start -0.12065 -0.2794)
			(end -0.12065 -0.3048)
			(stroke
				(width 0.1)
				(type default)
			)
			(layer "B.Fab")
		)
		(fp_line
			(start 0.12065 0.2794)
			(end 0.12065 0.3048)
			(stroke
				(width 0.1)
				(type default)
			)
			(layer "B.Fab")
		)
		(fp_line
			(start -0.120396 0.2794)
			(end 0.12065 0.2794)
			(stroke
				(width 0.1)
				(type default)
			)
			(layer "B.Fab")
		)
		(fp_line
			(start 0.67945 0.3048)
			(end 0.67945 -0.305054)
			(stroke
				(width 0.1)
				(type default)
			)
			(layer "B.Fab")
		)
		(fp_line
			(start 0.12065 0.3048)
			(end 0.67945 0.3048)
			(stroke
				(width 0.1)
				(type default)
			)
			(layer "B.Fab")
		)
		(fp_line
			(start -0.120396 0.3048)
			(end -0.120396 0.2794)
			(stroke
				(width 0.1)
				(type default)
			)
			(layer "B.Fab")
		)
		(fp_line
			(start -0.67945 0.3048)
			(end -0.120396 0.3048)
			(stroke
				(width 0.1)
				(type default)
			)
			(layer "B.Fab")
		)
		(pad "1" smd circle
			(at 0.40005 0 270)
			(size 0 0)
			(layers "B.Cu" "B.Mask" "B.Paste")
			(net "SGPIO_OCP_SFF_DATAOUT")
		)
		(pad "2" smd circle
			(at -0.40005 0 270)
			(size 0 0)
			(layers "B.Cu" "B.Mask" "B.Paste")
			(net "GND")
		)
	)
	(footprint ""
		(layer "B.Cu")
		(at 107.790742 -331.309472 -90)
		(property "Reference" "PC148_6"
			(at 0 0 90)
			(layer "B.SilkS")
			(hide yes)
			(effects
				(font
					(size 1.27 1.27)
				)
				(justify mirror)
			)
		)
		(property "Value" ""
			(at 0 0 90)
			(layer "B.Fab")
			(effects
				(font
					(size 1.27 1.27)
				)
				(justify mirror)
			)
		)
		(duplicate_pad_numbers_are_jumpers no)
		(fp_line
			(start -1.524 0.762)
			(end 1.524 0.762)
			(stroke
				(width 0.1524)
				(type default)
			)
			(layer "B.SilkS")
		)
		(fp_line
			(start 1.524 0.762)
			(end 1.524 -0.762)
			(stroke
				(width 0.1524)
				(type default)
			)
			(layer "B.SilkS")
		)
		(fp_line
			(start -1.524 -0.762)
			(end -1.524 0.762)
			(stroke
				(width 0.1524)
				(type default)
			)
			(layer "B.SilkS")
		)
		(fp_line
			(start 1.524 -0.762)
			(end -1.524 -0.762)
			(stroke
				(width 0.1524)
				(type default)
			)
			(layer "B.SilkS")
		)
		(fp_line
			(start -1.1049 0.724916)
			(end -1.1049 -0.724916)
			(stroke
				(width 0.1)
				(type default)
			)
			(layer "B.Fab")
		)
		(fp_line
			(start 1.1049 0.724916)
			(end -1.1049 0.724916)
			(stroke
				(width 0.1)
				(type default)
			)
			(layer "B.Fab")
		)
		(fp_line
			(start -1.1049 -0.724916)
			(end 1.1049 -0.724916)
			(stroke
				(width 0.1)
				(type default)
			)
			(layer "B.Fab")
		)
		(fp_line
			(start 1.1049 -0.724916)
			(end 1.1049 0.724916)
			(stroke
				(width 0.1)
				(type default)
			)
			(layer "B.Fab")
		)
		(pad "1" smd rect
			(at 0.889 0 270)
			(size 1.016 1.27)
			(layers "B.Cu" "B.Mask" "B.Paste")
			(net "PVDDCR_CPU1_P1")
		)
		(pad "2" smd rect
			(at -0.889 0 270)
			(size 1.016 1.27)
			(layers "B.Cu" "B.Mask" "B.Paste")
			(net "GND")
		)
	)
	(footprint ""
		(layer "B.Cu")
		(at 290.092384 -425.179998 180)
		(property "Reference" "R3111"
			(at 0 0 0)
			(layer "B.SilkS")
			(hide yes)
			(effects
				(font
					(size 1.27 1.27)
				)
				(justify mirror)
			)
		)
		(property "Value" ""
			(at 0 0 0)
			(layer "B.Fab")
			(effects
				(font
					(size 1.27 1.27)
				)
				(justify mirror)
			)
		)
		(duplicate_pad_numbers_are_jumpers no)
		(fp_line
			(start 0.7874 0.4064)
			(end 0.7874 -0.4064)
			(stroke
				(width 0.1524)
				(type default)
			)
			(layer "B.SilkS")
		)
		(fp_line
			(start 0.7874 -0.4064)
			(end -0.7874 -0.4064)
			(stroke
				(width 0.1524)
				(type default)
			)
			(layer "B.SilkS")
		)
		(fp_line
			(start -0.7874 0.4064)
			(end 0.7874 0.4064)
			(stroke
				(width 0.1524)
				(type default)
			)
			(layer "B.SilkS")
		)
		(fp_line
			(start -0.7874 -0.4064)
			(end -0.7874 0.4064)
			(stroke
				(width 0.1524)
				(type default)
			)
			(layer "B.SilkS")
		)
		(fp_line
			(start 0.67945 0.3048)
			(end 0.67945 -0.305054)
			(stroke
				(width 0.1)
				(type default)
			)
			(layer "B.Fab")
		)
		(fp_line
			(start 0.67945 -0.305054)
			(end 0.12065 -0.305054)
			(stroke
				(width 0.1)
				(type default)
			)
			(layer "B.Fab")
		)
		(fp_line
			(start 0.12065 0.3048)
			(end 0.67945 0.3048)
			(stroke
				(width 0.1)
				(type default)
			)
			(layer "B.Fab")
		)
		(fp_line
			(start 0.12065 0.2794)
			(end 0.12065 0.3048)
			(stroke
				(width 0.1)
				(type default)
			)
			(layer "B.Fab")
		)
		(fp_line
			(start 0.12065 -0.2794)
			(end -0.12065 -0.2794)
			(stroke
				(width 0.1)
				(type default)
			)
			(layer "B.Fab")
		)
		(fp_line
			(start 0.12065 -0.305054)
			(end 0.12065 -0.2794)
			(stroke
				(width 0.1)
				(type default)
			)
			(layer "B.Fab")
		)
		(fp_line
			(start -0.120396 0.3048)
			(end -0.120396 0.2794)
			(stroke
				(width 0.1)
				(type default)
			)
			(layer "B.Fab")
		)
		(fp_line
			(start -0.120396 0.2794)
			(end 0.12065 0.2794)
			(stroke
				(width 0.1)
				(type default)
			)
			(layer "B.Fab")
		)
		(fp_line
			(start -0.12065 -0.2794)
			(end -0.12065 -0.3048)
			(stroke
				(width 0.1)
				(type default)
			)
			(layer "B.Fab")
		)
		(fp_line
			(start -0.12065 -0.3048)
			(end -0.67945 -0.3048)
			(stroke
				(width 0.1)
				(type default)
			)
			(layer "B.Fab")
		)
		(fp_line
			(start -0.67945 0.3048)
			(end -0.120396 0.3048)
			(stroke
				(width 0.1)
				(type default)
			)
			(layer "B.Fab")
		)
		(fp_line
			(start -0.67945 -0.3048)
			(end -0.67945 0.3048)
			(stroke
				(width 0.1)
				(type default)
			)
			(layer "B.Fab")
		)
		(pad "1" smd circle
			(at 0.40005 0)
			(size 0 0)
			(layers "B.Cu" "B.Mask" "B.Paste")
			(net "I3C_BMC_SWB_SDA")
		)
		(pad "2" smd circle
			(at -0.40005 0)
			(size 0 0)
			(layers "B.Cu" "B.Mask" "B.Paste")
			(net "I3C_BMC_SWB_R_SDA")
		)
	)
	(footprint ""
		(layer "B.Cu")
		(at 139.516358 -393.242546 180)
		(property "Reference" "R858"
			(at 0 0 0)
			(layer "B.SilkS")
			(hide yes)
			(effects
				(font
					(size 1.27 1.27)
				)
				(justify mirror)
			)
		)
		(property "Value" ""
			(at 0 0 0)
			(layer "B.Fab")
			(effects
				(font
					(size 1.27 1.27)
				)
				(justify mirror)
			)
		)
		(duplicate_pad_numbers_are_jumpers no)
		(fp_line
			(start 1.2954 0.5842)
			(end 1.2954 -0.5842)
			(stroke
				(width 0.1524)
				(type default)
			)
			(layer "B.SilkS")
		)
		(fp_line
			(start 1.2954 -0.5842)
			(end -1.2954 -0.5842)
			(stroke
				(width 0.1524)
				(type default)
			)
			(layer "B.SilkS")
		)
		(fp_line
			(start -1.2954 0.5842)
			(end 1.2954 0.5842)
			(stroke
				(width 0.1524)
				(type default)
			)
			(layer "B.SilkS")
		)
		(fp_line
			(start -1.2954 -0.5842)
			(end -1.2954 0.5842)
			(stroke
				(width 0.1524)
				(type default)
			)
			(layer "B.SilkS")
		)
		(fp_line
			(start 1.1938 0.4064)
			(end 1.1938 -0.406654)
			(stroke
				(width 0.1)
				(type default)
			)
			(layer "B.Fab")
		)
		(fp_line
			(start 1.1938 -0.406654)
			(end 0.8636 -0.406654)
			(stroke
				(width 0.1)
				(type default)
			)
			(layer "B.Fab")
		)
		(fp_line
			(start 0.8636 0.4572)
			(end 0.8636 0.4318)
			(stroke
				(width 0.1)
				(type default)
			)
			(layer "B.Fab")
		)
		(fp_line
			(start 0.8636 0.4318)
			(end 0.8636 0.4064)
			(stroke
				(width 0.1)
				(type default)
			)
			(layer "B.Fab")
		)
		(fp_line
			(start 0.8636 0.4064)
			(end 1.1938 0.4064)
			(stroke
				(width 0.1)
				(type default)
			)
			(layer "B.Fab")
		)
		(fp_line
			(start 0.8636 -0.406654)
			(end 0.8636 -0.4572)
			(stroke
				(width 0.1)
				(type default)
			)
			(layer "B.Fab")
		)
		(fp_line
			(start 0.8636 -0.4572)
			(end -0.8636 -0.4572)
			(stroke
				(width 0.1)
				(type default)
			)
			(layer "B.Fab")
		)
		(fp_line
			(start -0.8636 0.4572)
			(end 0.8636 0.4572)
			(stroke
				(width 0.1)
				(type default)
			)
			(layer "B.Fab")
		)
		(fp_line
			(start -0.8636 0.4064)
			(end -0.8636 0.4572)
			(stroke
				(width 0.1)
				(type default)
			)
			(layer "B.Fab")
		)
		(fp_line
			(start -0.8636 -0.406654)
			(end -1.1938 -0.406654)
			(stroke
				(width 0.1)
				(type default)
			)
			(layer "B.Fab")
		)
		(fp_line
			(start -0.8636 -0.4572)
			(end -0.8636 -0.406654)
			(stroke
				(width 0.1)
				(type default)
			)
			(layer "B.Fab")
		)
		(fp_line
			(start -1.1938 0.4064)
			(end -0.8636 0.4064)
			(stroke
				(width 0.1)
				(type default)
			)
			(layer "B.Fab")
		)
		(fp_line
			(start -1.1938 -0.406654)
			(end -1.1938 0.4064)
			(stroke
				(width 0.1)
				(type default)
			)
			(layer "B.Fab")
		)
		(pad "1" smd rect
			(at 0.7366 0 90)
			(size 0.7112 0.8128)
			(layers "B.Cu" "B.Mask" "B.Paste")
			(net "P0V9_CPU1_RT_2D")
		)
		(pad "2" smd rect
			(at -0.7366 0 90)
			(size 0.7112 0.8128)
			(layers "B.Cu" "B.Mask" "B.Paste")
			(net "P0V9_CPU1_RT2_2A_2D")
		)
	)
	(footprint ""
		(layer "B.Cu")
		(at 321.530726 -416.899344 90)
		(property "Reference" "C6543"
			(at 0 0 90)
			(layer "B.SilkS")
			(hide yes)
			(effects
				(font
					(size 1.27 1.27)
				)
				(justify mirror)
			)
		)
		(property "Value" ""
			(at 0 0 90)
			(layer "B.Fab")
			(effects
				(font
					(size 1.27 1.27)
				)
				(justify mirror)
			)
		)
		(duplicate_pad_numbers_are_jumpers no)
		(fp_line
			(start 0.299974 -0.150114)
			(end -0.299974 -0.150114)
			(stroke
				(width 0.1)
				(type default)
			)
			(layer "B.Fab")
		)
		(fp_line
			(start -0.299974 -0.150114)
			(end -0.299974 0.150114)
			(stroke
				(width 0.1)
				(type default)
			)
			(layer "B.Fab")
		)
		(fp_line
			(start 0.299974 0.150114)
			(end 0.299974 -0.150114)
			(stroke
				(width 0.1)
				(type default)
			)
			(layer "B.Fab")
		)
		(fp_line
			(start -0.299974 0.150114)
			(end 0.299974 0.150114)
			(stroke
				(width 0.1)
				(type default)
			)
			(layer "B.Fab")
		)
		(pad "1" smd rect
			(at 0.2667 0 270)
			(size 0.3048 0.381)
			(layers "B.Cu" "B.Mask" "B.Paste")
			(net "P5E_CPU0_P1_TX_BUF_C_DP<5>")
		)
		(pad "2" smd rect
			(at -0.2667 0 270)
			(size 0.3048 0.381)
			(layers "B.Cu" "B.Mask" "B.Paste")
			(net "P5E_CPU0_P1_TX_BUF_DP<5>")
		)
	)
	(footprint ""
		(layer "B.Cu")
		(at 256.432558 -328.744072)
		(property "Reference" "R1230"
			(at 0 0 0)
			(layer "B.SilkS")
			(hide yes)
			(effects
				(font
					(size 1.27 1.27)
				)
				(justify mirror)
			)
		)
		(property "Value" ""
			(at 0 0 0)
			(layer "B.Fab")
			(effects
				(font
					(size 1.27 1.27)
				)
				(justify mirror)
			)
		)
		(duplicate_pad_numbers_are_jumpers no)
		(fp_line
			(start -0.7874 -0.4064)
			(end -0.7874 0.4064)
			(stroke
				(width 0.1524)
				(type default)
			)
			(layer "B.SilkS")
		)
		(fp_line
			(start -0.7874 0.4064)
			(end 0.7874 0.4064)
			(stroke
				(width 0.1524)
				(type default)
			)
			(layer "B.SilkS")
		)
		(fp_line
			(start 0.7874 -0.4064)
			(end -0.7874 -0.4064)
			(stroke
				(width 0.1524)
				(type default)
			)
			(layer "B.SilkS")
		)
		(fp_line
			(start 0.7874 0.4064)
			(end 0.7874 -0.4064)
			(stroke
				(width 0.1524)
				(type default)
			)
			(layer "B.SilkS")
		)
		(fp_line
			(start -0.67945 -0.3048)
			(end -0.67945 0.3048)
			(stroke
				(width 0.1)
				(type default)
			)
			(layer "B.Fab")
		)
		(fp_line
			(start -0.67945 0.3048)
			(end -0.120396 0.3048)
			(stroke
				(width 0.1)
				(type default)
			)
			(layer "B.Fab")
		)
		(fp_line
			(start -0.12065 -0.3048)
			(end -0.67945 -0.3048)
			(stroke
				(width 0.1)
				(type default)
			)
			(layer "B.Fab")
		)
		(fp_line
			(start -0.12065 -0.2794)
			(end -0.12065 -0.3048)
			(stroke
				(width 0.1)
				(type default)
			)
			(layer "B.Fab")
		)
		(fp_line
			(start -0.120396 0.2794)
			(end 0.12065 0.2794)
			(stroke
				(width 0.1)
				(type default)
			)
			(layer "B.Fab")
		)
		(fp_line
			(start -0.120396 0.3048)
			(end -0.120396 0.2794)
			(stroke
				(width 0.1)
				(type default)
			)
			(layer "B.Fab")
		)
		(fp_line
			(start 0.12065 -0.305054)
			(end 0.12065 -0.2794)
			(stroke
				(width 0.1)
				(type default)
			)
			(layer "B.Fab")
		)
		(fp_line
			(start 0.12065 -0.2794)
			(end -0.12065 -0.2794)
			(stroke
				(width 0.1)
				(type default)
			)
			(layer "B.Fab")
		)
		(fp_line
			(start 0.12065 0.2794)
			(end 0.12065 0.3048)
			(stroke
				(width 0.1)
				(type default)
			)
			(layer "B.Fab")
		)
		(fp_line
			(start 0.12065 0.3048)
			(end 0.67945 0.3048)
			(stroke
				(width 0.1)
				(type default)
			)
			(layer "B.Fab")
		)
		(fp_line
			(start 0.67945 -0.305054)
			(end 0.12065 -0.305054)
			(stroke
				(width 0.1)
				(type default)
			)
			(layer "B.Fab")
		)
		(fp_line
			(start 0.67945 0.3048)
			(end 0.67945 -0.305054)
			(stroke
				(width 0.1)
				(type default)
			)
			(layer "B.Fab")
		)
		(pad "1" smd circle
			(at 0.40005 0 180)
			(size 0 0)
			(layers "B.Cu" "B.Mask" "B.Paste")
			(net "MAX11617_2_VREF")
		)
		(pad "2" smd circle
			(at -0.40005 0 180)
			(size 0 0)
			(layers "B.Cu" "B.Mask" "B.Paste")
			(net "MAX11617_2_VREF_R")
		)
	)
	(footprint ""
		(layer "B.Cu")
		(at 231.834182 -328.25182 180)
		(property "Reference" "R1247"
			(at 0 0 0)
			(layer "B.SilkS")
			(hide yes)
			(effects
				(font
					(size 1.27 1.27)
				)
				(justify mirror)
			)
		)
		(property "Value" ""
			(at 0 0 0)
			(layer "B.Fab")
			(effects
				(font
					(size 1.27 1.27)
				)
				(justify mirror)
			)
		)
		(duplicate_pad_numbers_are_jumpers no)
		(fp_line
			(start 0.7874 0.4064)
			(end 0.7874 -0.4064)
			(stroke
				(width 0.1524)
				(type default)
			)
			(layer "B.SilkS")
		)
		(fp_line
			(start 0.7874 -0.4064)
			(end -0.7874 -0.4064)
			(stroke
				(width 0.1524)
				(type default)
			)
			(layer "B.SilkS")
		)
		(fp_line
			(start -0.7874 0.4064)
			(end 0.7874 0.4064)
			(stroke
				(width 0.1524)
				(type default)
			)
			(layer "B.SilkS")
		)
		(fp_line
			(start -0.7874 -0.4064)
			(end -0.7874 0.4064)
			(stroke
				(width 0.1524)
				(type default)
			)
			(layer "B.SilkS")
		)
		(fp_line
			(start 0.67945 0.3048)
			(end 0.67945 -0.305054)
			(stroke
				(width 0.1)
				(type default)
			)
			(layer "B.Fab")
		)
		(fp_line
			(start 0.67945 -0.305054)
			(end 0.12065 -0.305054)
			(stroke
				(width 0.1)
				(type default)
			)
			(layer "B.Fab")
		)
		(fp_line
			(start 0.12065 0.3048)
			(end 0.67945 0.3048)
			(stroke
				(width 0.1)
				(type default)
			)
			(layer "B.Fab")
		)
		(fp_line
			(start 0.12065 0.2794)
			(end 0.12065 0.3048)
			(stroke
				(width 0.1)
				(type default)
			)
			(layer "B.Fab")
		)
		(fp_line
			(start 0.12065 -0.2794)
			(end -0.12065 -0.2794)
			(stroke
				(width 0.1)
				(type default)
			)
			(layer "B.Fab")
		)
		(fp_line
			(start 0.12065 -0.305054)
			(end 0.12065 -0.2794)
			(stroke
				(width 0.1)
				(type default)
			)
			(layer "B.Fab")
		)
		(fp_line
			(start -0.120396 0.3048)
			(end -0.120396 0.2794)
			(stroke
				(width 0.1)
				(type default)
			)
			(layer "B.Fab")
		)
		(fp_line
			(start -0.120396 0.2794)
			(end 0.12065 0.2794)
			(stroke
				(width 0.1)
				(type default)
			)
			(layer "B.Fab")
		)
		(fp_line
			(start -0.12065 -0.2794)
			(end -0.12065 -0.3048)
			(stroke
				(width 0.1)
				(type default)
			)
			(layer "B.Fab")
		)
		(fp_line
			(start -0.12065 -0.3048)
			(end -0.67945 -0.3048)
			(stroke
				(width 0.1)
				(type default)
			)
			(layer "B.Fab")
		)
		(fp_line
			(start -0.67945 0.3048)
			(end -0.120396 0.3048)
			(stroke
				(width 0.1)
				(type default)
			)
			(layer "B.Fab")
		)
		(fp_line
			(start -0.67945 -0.3048)
			(end -0.67945 0.3048)
			(stroke
				(width 0.1)
				(type default)
			)
			(layer "B.Fab")
		)
		(pad "1" smd rect
			(at 0.40005 0 180)
			(size 0.4572 0.508)
			(layers "B.Cu" "B.Mask" "B.Paste")
			(net "PVDD18_S5_P0_ADC")
		)
		(pad "2" smd rect
			(at -0.40005 0 180)
			(size 0.4572 0.508)
			(layers "B.Cu" "B.Mask" "B.Paste")
			(net "PVDD18_S5_P0_ADC_MAM")
		)
	)
	(footprint ""
		(layer "B.Cu")
		(at 217.678 -334.01 180)
		(property "Reference" "R6810"
			(at 0 0 0)
			(layer "B.SilkS")
			(hide yes)
			(effects
				(font
					(size 1.27 1.27)
				)
				(justify mirror)
			)
		)
		(property "Value" ""
			(at 0 0 0)
			(layer "B.Fab")
			(effects
				(font
					(size 1.27 1.27)
				)
				(justify mirror)
			)
		)
		(duplicate_pad_numbers_are_jumpers no)
		(fp_line
			(start 0.32512 0.175006)
			(end 0.32512 -0.175006)
			(stroke
				(width 0.1)
				(type default)
			)
			(layer "B.Fab")
		)
		(fp_line
			(start 0.32512 -0.175006)
			(end -0.32512 -0.175006)
			(stroke
				(width 0.1)
				(type default)
			)
			(layer "B.Fab")
		)
		(fp_line
			(start -0.32512 0.175006)
			(end 0.32512 0.175006)
			(stroke
				(width 0.1)
				(type default)
			)
			(layer "B.Fab")
		)
		(fp_line
			(start -0.32512 -0.175006)
			(end -0.32512 0.175006)
			(stroke
				(width 0.1)
				(type default)
			)
			(layer "B.Fab")
		)
		(pad "1" smd rect
			(at 0.2667 0)
			(size 0.3048 0.381)
			(layers "B.Cu" "B.Mask" "B.Paste")
			(net "SMB_RT_CPU1_P0_R_SDA")
		)
		(pad "2" smd rect
			(at -0.2667 0 180)
			(size 0.3048 0.381)
			(layers "B.Cu" "B.Mask" "B.Paste")
			(net "SMB_RT_CPU1_P0_SDA")
		)
	)
	(footprint ""
		(layer "B.Cu")
		(at 30.65526 -353.11334)
		(property "Reference" "PC7001"
			(at 0 0 0)
			(layer "B.SilkS")
			(hide yes)
			(effects
				(font
					(size 1.27 1.27)
				)
				(justify mirror)
			)
		)
		(property "Value" ""
			(at 0 0 0)
			(layer "B.Fab")
			(effects
				(font
					(size 1.27 1.27)
				)
				(justify mirror)
			)
		)
		(duplicate_pad_numbers_are_jumpers no)
		(fp_line
			(start -1.524 -0.762)
			(end -1.524 0.762)
			(stroke
				(width 0.1524)
				(type default)
			)
			(layer "B.SilkS")
		)
		(fp_line
			(start -1.524 0.762)
			(end 1.524 0.762)
			(stroke
				(width 0.1524)
				(type default)
			)
			(layer "B.SilkS")
		)
		(fp_line
			(start 1.524 -0.762)
			(end -1.524 -0.762)
			(stroke
				(width 0.1524)
				(type default)
			)
			(layer "B.SilkS")
		)
		(fp_line
			(start 1.524 0.762)
			(end 1.524 -0.762)
			(stroke
				(width 0.1524)
				(type default)
			)
			(layer "B.SilkS")
		)
		(fp_line
			(start -1.1049 -0.724916)
			(end 1.1049 -0.724916)
			(stroke
				(width 0.1)
				(type default)
			)
			(layer "B.Fab")
		)
		(fp_line
			(start -1.1049 0.724916)
			(end -1.1049 -0.724916)
			(stroke
				(width 0.1)
				(type default)
			)
			(layer "B.Fab")
		)
		(fp_line
			(start 1.1049 -0.724916)
			(end 1.1049 0.724916)
			(stroke
				(width 0.1)
				(type default)
			)
			(layer "B.Fab")
		)
		(fp_line
			(start 1.1049 0.724916)
			(end -1.1049 0.724916)
			(stroke
				(width 0.1)
				(type default)
			)
			(layer "B.Fab")
		)
		(pad "1" smd rect
			(at 0.889 0)
			(size 1.016 1.27)
			(layers "B.Cu" "B.Mask" "B.Paste")
			(net "SW_P12V_AUX_PVDDIO_P1_FLT")
		)
		(pad "2" smd rect
			(at -0.889 0)
			(size 1.016 1.27)
			(layers "B.Cu" "B.Mask" "B.Paste")
			(net "GND")
		)
	)
	(footprint ""
		(layer "B.Cu")
		(at 449.932552 -380.027434 90)
		(property "Reference" "PC6570"
			(at -6.293104 2.314448 0)
			(unlocked yes)
			(layer "B.SilkS")
			(effects
				(font
					(size 0.7874 0.5842)
					(thickness 0.1524)
				)
				(justify left mirror)
			)
		)
		(property "Value" ""
			(at 0 0 90)
			(layer "B.Fab")
			(effects
				(font
					(size 1.27 1.27)
				)
				(justify mirror)
			)
		)
		(duplicate_pad_numbers_are_jumpers no)
		(fp_line
			(start 4.84378 -2.150618)
			(end 4.53898 -2.150618)
			(stroke
				(width 0.1524)
				(type default)
			)
			(layer "B.SilkS")
		)
		(fp_line
			(start 4.84378 -2.150618)
			(end 4.842256 2.163064)
			(stroke
				(width 0.1524)
				(type default)
			)
			(layer "B.SilkS")
		)
		(fp_line
			(start 4.69138 -2.150618)
			(end 4.692396 2.161032)
			(stroke
				(width 0.1524)
				(type default)
			)
			(layer "B.SilkS")
		)
		(fp_line
			(start 4.53898 -2.150618)
			(end 4.539742 2.152142)
			(stroke
				(width 0.1524)
				(type default)
			)
			(layer "B.SilkS")
		)
		(fp_line
			(start 4.53898 -2.15011)
			(end -4.53898 -2.15011)
			(stroke
				(width 0.1524)
				(type default)
			)
			(layer "B.SilkS")
		)
		(fp_line
			(start -4.53898 -2.15011)
			(end -4.53898 2.15011)
			(stroke
				(width 0.1524)
				(type default)
			)
			(layer "B.SilkS")
		)
		(fp_line
			(start 4.53898 2.15011)
			(end 4.53898 -2.15011)
			(stroke
				(width 0.1524)
				(type default)
			)
			(layer "B.SilkS")
		)
		(fp_line
			(start -4.53898 2.15011)
			(end 4.53898 2.15011)
			(stroke
				(width 0.1524)
				(type default)
			)
			(layer "B.SilkS")
		)
		(fp_line
			(start 4.83108 2.150364)
			(end 4.447794 2.149348)
			(stroke
				(width 0.1524)
				(type default)
			)
			(layer "B.SilkS")
		)
		(fp_line
			(start 3.64998 -2.15011)
			(end -3.64998 -2.15011)
			(stroke
				(width 0.1)
				(type default)
			)
			(layer "B.Fab")
		)
		(fp_line
			(start -3.64998 -2.15011)
			(end -3.64998 2.15011)
			(stroke
				(width 0.1)
				(type default)
			)
			(layer "B.Fab")
		)
		(fp_line
			(start 3.64998 2.15011)
			(end 3.64998 -2.15011)
			(stroke
				(width 0.1)
				(type default)
			)
			(layer "B.Fab")
		)
		(fp_line
			(start -3.64998 2.15011)
			(end 3.64998 2.15011)
			(stroke
				(width 0.1)
				(type default)
			)
			(layer "B.Fab")
		)
		(fp_text user "-"
			(at -4.313174 -0.094488 90)
			(unlocked yes)
			(layer "B.SilkS")
			(effects
				(font
					(size 1.905 1.4224)
					(thickness 0.1524)
				)
				(justify left mirror)
			)
		)
		(fp_text user "+"
			(at 6.179566 0.060198 90)
			(unlocked yes)
			(layer "B.SilkS")
			(effects
				(font
					(size 1.905 1.4224)
					(thickness 0.1524)
				)
				(justify left mirror)
			)
		)
		(fp_text user "+"
			(at 6.214872 -0.337058 90)
			(unlocked yes)
			(layer "B.Fab")
			(effects
				(font
					(size 1.905 1.4224)
					(thickness 0.1524)
				)
				(justify left mirror)
			)
		)
		(fp_text user "-"
			(at -4.313174 -0.094488 90)
			(unlocked yes)
			(layer "B.Fab")
			(effects
				(font
					(size 1.905 1.4224)
					(thickness 0.1524)
				)
				(justify left mirror)
			)
		)
		(pad "1" smd rect
			(at 3.199892 0 270)
			(size 2.413 2.8194)
			(layers "B.Cu" "B.Mask" "B.Paste")
			(net "P0V9_CPU0_RT_2D")
		)
		(pad "2" smd rect
			(at -3.199892 0 270)
			(size 2.413 2.8194)
			(layers "B.Cu" "B.Mask" "B.Paste")
			(net "GND")
		)
	)
	(footprint ""
		(layer "B.Cu")
		(at 106.98861 -393.242546 180)
		(property "Reference" "R898"
			(at 0 0 0)
			(layer "B.SilkS")
			(hide yes)
			(effects
				(font
					(size 1.27 1.27)
				)
				(justify mirror)
			)
		)
		(property "Value" ""
			(at 0 0 0)
			(layer "B.Fab")
			(effects
				(font
					(size 1.27 1.27)
				)
				(justify mirror)
			)
		)
		(duplicate_pad_numbers_are_jumpers no)
		(fp_line
			(start 1.2954 0.5842)
			(end 1.2954 -0.5842)
			(stroke
				(width 0.1524)
				(type default)
			)
			(layer "B.SilkS")
		)
		(fp_line
			(start 1.2954 -0.5842)
			(end -1.2954 -0.5842)
			(stroke
				(width 0.1524)
				(type default)
			)
			(layer "B.SilkS")
		)
		(fp_line
			(start -1.2954 0.5842)
			(end 1.2954 0.5842)
			(stroke
				(width 0.1524)
				(type default)
			)
			(layer "B.SilkS")
		)
		(fp_line
			(start -1.2954 -0.5842)
			(end -1.2954 0.5842)
			(stroke
				(width 0.1524)
				(type default)
			)
			(layer "B.SilkS")
		)
		(fp_line
			(start 1.1938 0.4064)
			(end 1.1938 -0.406654)
			(stroke
				(width 0.1)
				(type default)
			)
			(layer "B.Fab")
		)
		(fp_line
			(start 1.1938 -0.406654)
			(end 0.8636 -0.406654)
			(stroke
				(width 0.1)
				(type default)
			)
			(layer "B.Fab")
		)
		(fp_line
			(start 0.8636 0.4572)
			(end 0.8636 0.4318)
			(stroke
				(width 0.1)
				(type default)
			)
			(layer "B.Fab")
		)
		(fp_line
			(start 0.8636 0.4318)
			(end 0.8636 0.4064)
			(stroke
				(width 0.1)
				(type default)
			)
			(layer "B.Fab")
		)
		(fp_line
			(start 0.8636 0.4064)
			(end 1.1938 0.4064)
			(stroke
				(width 0.1)
				(type default)
			)
			(layer "B.Fab")
		)
		(fp_line
			(start 0.8636 -0.406654)
			(end 0.8636 -0.4572)
			(stroke
				(width 0.1)
				(type default)
			)
			(layer "B.Fab")
		)
		(fp_line
			(start 0.8636 -0.4572)
			(end -0.8636 -0.4572)
			(stroke
				(width 0.1)
				(type default)
			)
			(layer "B.Fab")
		)
		(fp_line
			(start -0.8636 0.4572)
			(end 0.8636 0.4572)
			(stroke
				(width 0.1)
				(type default)
			)
			(layer "B.Fab")
		)
		(fp_line
			(start -0.8636 0.4064)
			(end -0.8636 0.4572)
			(stroke
				(width 0.1)
				(type default)
			)
			(layer "B.Fab")
		)
		(fp_line
			(start -0.8636 -0.406654)
			(end -1.1938 -0.406654)
			(stroke
				(width 0.1)
				(type default)
			)
			(layer "B.Fab")
		)
		(fp_line
			(start -0.8636 -0.4572)
			(end -0.8636 -0.406654)
			(stroke
				(width 0.1)
				(type default)
			)
			(layer "B.Fab")
		)
		(fp_line
			(start -1.1938 0.4064)
			(end -0.8636 0.4064)
			(stroke
				(width 0.1)
				(type default)
			)
			(layer "B.Fab")
		)
		(fp_line
			(start -1.1938 -0.406654)
			(end -1.1938 0.4064)
			(stroke
				(width 0.1)
				(type default)
			)
			(layer "B.Fab")
		)
		(pad "1" smd rect
			(at 0.7366 0 90)
			(size 0.7112 0.8128)
			(layers "B.Cu" "B.Mask" "B.Paste")
			(net "P0V9_CPU1_RT_2D")
		)
		(pad "2" smd rect
			(at -0.7366 0 90)
			(size 0.7112 0.8128)
			(layers "B.Cu" "B.Mask" "B.Paste")
			(net "P0V9_CPU1_RT3_2A_2D")
		)
	)
	(footprint ""
		(layer "B.Cu")
		(at 171.201334 -103.942388 180)
		(property "Reference" "R6150"
			(at 0 0 0)
			(layer "B.SilkS")
			(hide yes)
			(effects
				(font
					(size 1.27 1.27)
				)
				(justify mirror)
			)
		)
		(property "Value" ""
			(at 0 0 0)
			(layer "B.Fab")
			(effects
				(font
					(size 1.27 1.27)
				)
				(justify mirror)
			)
		)
		(duplicate_pad_numbers_are_jumpers no)
		(fp_line
			(start 0.7874 0.4064)
			(end 0.7874 -0.4064)
			(stroke
				(width 0.1524)
				(type default)
			)
			(layer "B.SilkS")
		)
		(fp_line
			(start 0.7874 -0.4064)
			(end -0.7874 -0.4064)
			(stroke
				(width 0.1524)
				(type default)
			)
			(layer "B.SilkS")
		)
		(fp_line
			(start -0.7874 0.4064)
			(end 0.7874 0.4064)
			(stroke
				(width 0.1524)
				(type default)
			)
			(layer "B.SilkS")
		)
		(fp_line
			(start -0.7874 -0.4064)
			(end -0.7874 0.4064)
			(stroke
				(width 0.1524)
				(type default)
			)
			(layer "B.SilkS")
		)
		(fp_line
			(start 0.67945 0.3048)
			(end 0.67945 -0.305054)
			(stroke
				(width 0.1)
				(type default)
			)
			(layer "B.Fab")
		)
		(fp_line
			(start 0.67945 -0.305054)
			(end 0.12065 -0.305054)
			(stroke
				(width 0.1)
				(type default)
			)
			(layer "B.Fab")
		)
		(fp_line
			(start 0.12065 0.3048)
			(end 0.67945 0.3048)
			(stroke
				(width 0.1)
				(type default)
			)
			(layer "B.Fab")
		)
		(fp_line
			(start 0.12065 0.2794)
			(end 0.12065 0.3048)
			(stroke
				(width 0.1)
				(type default)
			)
			(layer "B.Fab")
		)
		(fp_line
			(start 0.12065 -0.2794)
			(end -0.12065 -0.2794)
			(stroke
				(width 0.1)
				(type default)
			)
			(layer "B.Fab")
		)
		(fp_line
			(start 0.12065 -0.305054)
			(end 0.12065 -0.2794)
			(stroke
				(width 0.1)
				(type default)
			)
			(layer "B.Fab")
		)
		(fp_line
			(start -0.120396 0.3048)
			(end -0.120396 0.2794)
			(stroke
				(width 0.1)
				(type default)
			)
			(layer "B.Fab")
		)
		(fp_line
			(start -0.120396 0.2794)
			(end 0.12065 0.2794)
			(stroke
				(width 0.1)
				(type default)
			)
			(layer "B.Fab")
		)
		(fp_line
			(start -0.12065 -0.2794)
			(end -0.12065 -0.3048)
			(stroke
				(width 0.1)
				(type default)
			)
			(layer "B.Fab")
		)
		(fp_line
			(start -0.12065 -0.3048)
			(end -0.67945 -0.3048)
			(stroke
				(width 0.1)
				(type default)
			)
			(layer "B.Fab")
		)
		(fp_line
			(start -0.67945 0.3048)
			(end -0.120396 0.3048)
			(stroke
				(width 0.1)
				(type default)
			)
			(layer "B.Fab")
		)
		(fp_line
			(start -0.67945 -0.3048)
			(end -0.67945 0.3048)
			(stroke
				(width 0.1)
				(type default)
			)
			(layer "B.Fab")
		)
		(pad "1" smd circle
			(at 0.40005 0)
			(size 0 0)
			(layers "B.Cu" "B.Mask" "B.Paste")
			(net "FAB_BMC_REV_ID1")
		)
		(pad "2" smd circle
			(at -0.40005 0)
			(size 0 0)
			(layers "B.Cu" "B.Mask" "B.Paste")
			(net "GND")
		)
	)
	(footprint ""
		(layer "B.Cu")
		(at 291.52469 -195.859146 180)
		(property "Reference" "R1677"
			(at 0 0 0)
			(layer "B.SilkS")
			(hide yes)
			(effects
				(font
					(size 1.27 1.27)
				)
				(justify mirror)
			)
		)
		(property "Value" ""
			(at 0 0 0)
			(layer "B.Fab")
			(effects
				(font
					(size 1.27 1.27)
				)
				(justify mirror)
			)
		)
		(duplicate_pad_numbers_are_jumpers no)
		(fp_line
			(start 0.7874 0.4064)
			(end 0.7874 -0.4064)
			(stroke
				(width 0.1524)
				(type default)
			)
			(layer "B.SilkS")
		)
		(fp_line
			(start 0.7874 -0.4064)
			(end -0.7874 -0.4064)
			(stroke
				(width 0.1524)
				(type default)
			)
			(layer "B.SilkS")
		)
		(fp_line
			(start -0.7874 0.4064)
			(end 0.7874 0.4064)
			(stroke
				(width 0.1524)
				(type default)
			)
			(layer "B.SilkS")
		)
		(fp_line
			(start -0.7874 -0.4064)
			(end -0.7874 0.4064)
			(stroke
				(width 0.1524)
				(type default)
			)
			(layer "B.SilkS")
		)
		(fp_line
			(start 0.67945 0.3048)
			(end 0.67945 -0.305054)
			(stroke
				(width 0.1)
				(type default)
			)
			(layer "B.Fab")
		)
		(fp_line
			(start 0.67945 -0.305054)
			(end 0.12065 -0.305054)
			(stroke
				(width 0.1)
				(type default)
			)
			(layer "B.Fab")
		)
		(fp_line
			(start 0.12065 0.3048)
			(end 0.67945 0.3048)
			(stroke
				(width 0.1)
				(type default)
			)
			(layer "B.Fab")
		)
		(fp_line
			(start 0.12065 0.2794)
			(end 0.12065 0.3048)
			(stroke
				(width 0.1)
				(type default)
			)
			(layer "B.Fab")
		)
		(fp_line
			(start 0.12065 -0.2794)
			(end -0.12065 -0.2794)
			(stroke
				(width 0.1)
				(type default)
			)
			(layer "B.Fab")
		)
		(fp_line
			(start 0.12065 -0.305054)
			(end 0.12065 -0.2794)
			(stroke
				(width 0.1)
				(type default)
			)
			(layer "B.Fab")
		)
		(fp_line
			(start -0.120396 0.3048)
			(end -0.120396 0.2794)
			(stroke
				(width 0.1)
				(type default)
			)
			(layer "B.Fab")
		)
		(fp_line
			(start -0.120396 0.2794)
			(end 0.12065 0.2794)
			(stroke
				(width 0.1)
				(type default)
			)
			(layer "B.Fab")
		)
		(fp_line
			(start -0.12065 -0.2794)
			(end -0.12065 -0.3048)
			(stroke
				(width 0.1)
				(type default)
			)
			(layer "B.Fab")
		)
		(fp_line
			(start -0.12065 -0.3048)
			(end -0.67945 -0.3048)
			(stroke
				(width 0.1)
				(type default)
			)
			(layer "B.Fab")
		)
		(fp_line
			(start -0.67945 0.3048)
			(end -0.120396 0.3048)
			(stroke
				(width 0.1)
				(type default)
			)
			(layer "B.Fab")
		)
		(fp_line
			(start -0.67945 -0.3048)
			(end -0.67945 0.3048)
			(stroke
				(width 0.1)
				(type default)
			)
			(layer "B.Fab")
		)
		(pad "1" smd circle
			(at 0.40005 0)
			(size 0 0)
			(layers "B.Cu" "B.Mask" "B.Paste")
			(net "I3C_SPD_DDRAF_CPU0_SDA")
		)
		(pad "2" smd circle
			(at -0.40005 0)
			(size 0 0)
			(layers "B.Cu" "B.Mask" "B.Paste")
			(net "I3C_SPD_DDRC_CPU0_SDA")
		)
	)
	(footprint ""
		(layer "B.Cu")
		(at 380.282958 -205.101952 -90)
		(property "Reference" "R428"
			(at 0 0 90)
			(layer "B.SilkS")
			(hide yes)
			(effects
				(font
					(size 1.27 1.27)
				)
				(justify mirror)
			)
		)
		(property "Value" ""
			(at 0 0 90)
			(layer "B.Fab")
			(effects
				(font
					(size 1.27 1.27)
				)
				(justify mirror)
			)
		)
		(duplicate_pad_numbers_are_jumpers no)
		(fp_line
			(start -0.7874 0.4064)
			(end 0.7874 0.4064)
			(stroke
				(width 0.1524)
				(type default)
			)
			(layer "B.SilkS")
		)
		(fp_line
			(start 0.7874 0.4064)
			(end 0.7874 -0.4064)
			(stroke
				(width 0.1524)
				(type default)
			)
			(layer "B.SilkS")
		)
		(fp_line
			(start -0.7874 -0.4064)
			(end -0.7874 0.4064)
			(stroke
				(width 0.1524)
				(type default)
			)
			(layer "B.SilkS")
		)
		(fp_line
			(start 0.7874 -0.4064)
			(end -0.7874 -0.4064)
			(stroke
				(width 0.1524)
				(type default)
			)
			(layer "B.SilkS")
		)
		(fp_line
			(start -0.67945 0.3048)
			(end -0.120396 0.3048)
			(stroke
				(width 0.1)
				(type default)
			)
			(layer "B.Fab")
		)
		(fp_line
			(start -0.120396 0.3048)
			(end -0.120396 0.2794)
			(stroke
				(width 0.1)
				(type default)
			)
			(layer "B.Fab")
		)
		(fp_line
			(start 0.12065 0.3048)
			(end 0.67945 0.3048)
			(stroke
				(width 0.1)
				(type default)
			)
			(layer "B.Fab")
		)
		(fp_line
			(start 0.67945 0.3048)
			(end 0.67945 -0.305054)
			(stroke
				(width 0.1)
				(type default)
			)
			(layer "B.Fab")
		)
		(fp_line
			(start -0.120396 0.2794)
			(end 0.12065 0.2794)
			(stroke
				(width 0.1)
				(type default)
			)
			(layer "B.Fab")
		)
		(fp_line
			(start 0.12065 0.2794)
			(end 0.12065 0.3048)
			(stroke
				(width 0.1)
				(type default)
			)
			(layer "B.Fab")
		)
		(fp_line
			(start -0.12065 -0.2794)
			(end -0.12065 -0.3048)
			(stroke
				(width 0.1)
				(type default)
			)
			(layer "B.Fab")
		)
		(fp_line
			(start 0.12065 -0.2794)
			(end -0.12065 -0.2794)
			(stroke
				(width 0.1)
				(type default)
			)
			(layer "B.Fab")
		)
		(fp_line
			(start -0.67945 -0.3048)
			(end -0.67945 0.3048)
			(stroke
				(width 0.1)
				(type default)
			)
			(layer "B.Fab")
		)
		(fp_line
			(start -0.12065 -0.3048)
			(end -0.67945 -0.3048)
			(stroke
				(width 0.1)
				(type default)
			)
			(layer "B.Fab")
		)
		(fp_line
			(start 0.12065 -0.305054)
			(end 0.12065 -0.2794)
			(stroke
				(width 0.1)
				(type default)
			)
			(layer "B.Fab")
		)
		(fp_line
			(start 0.67945 -0.305054)
			(end 0.12065 -0.305054)
			(stroke
				(width 0.1)
				(type default)
			)
			(layer "B.Fab")
		)
		(pad "1" smd rect
			(at 0.40005 0 270)
			(size 0.4572 0.508)
			(layers "B.Cu" "B.Mask" "B.Paste")
			(net "I3C_1_SPD_DDRGL_CPU0_SCL")
		)
		(pad "2" smd rect
			(at -0.40005 0 270)
			(size 0.4572 0.508)
			(layers "B.Cu" "B.Mask" "B.Paste")
			(net "I3C_1_SPD_DDRGL_CPU0_R_SCL")
		)
	)
	(footprint ""
		(layer "B.Cu")
		(at 12.060428 -135.63219 180)
		(property "Reference" "C2257"
			(at 0 0 0)
			(layer "B.SilkS")
			(hide yes)
			(effects
				(font
					(size 1.27 1.27)
				)
				(justify mirror)
			)
		)
		(property "Value" ""
			(at 0 0 0)
			(layer "B.Fab")
			(effects
				(font
					(size 1.27 1.27)
				)
				(justify mirror)
			)
		)
		(duplicate_pad_numbers_are_jumpers no)
		(fp_line
			(start 0.7874 0.4064)
			(end 0.7874 -0.4064)
			(stroke
				(width 0.1524)
				(type default)
			)
			(layer "B.SilkS")
		)
		(fp_line
			(start 0.7874 -0.4064)
			(end -0.7874 -0.4064)
			(stroke
				(width 0.1524)
				(type default)
			)
			(layer "B.SilkS")
		)
		(fp_line
			(start -0.7874 0.4064)
			(end 0.7874 0.4064)
			(stroke
				(width 0.1524)
				(type default)
			)
			(layer "B.SilkS")
		)
		(fp_line
			(start -0.7874 -0.4064)
			(end -0.7874 0.4064)
			(stroke
				(width 0.1524)
				(type default)
			)
			(layer "B.SilkS")
		)
		(fp_line
			(start 0.67945 0.3048)
			(end 0.67945 -0.305054)
			(stroke
				(width 0.1)
				(type default)
			)
			(layer "B.Fab")
		)
		(fp_line
			(start 0.67945 -0.305054)
			(end 0.12065 -0.305054)
			(stroke
				(width 0.1)
				(type default)
			)
			(layer "B.Fab")
		)
		(fp_line
			(start 0.12065 0.3048)
			(end 0.67945 0.3048)
			(stroke
				(width 0.1)
				(type default)
			)
			(layer "B.Fab")
		)
		(fp_line
			(start 0.12065 0.2794)
			(end 0.12065 0.3048)
			(stroke
				(width 0.1)
				(type default)
			)
			(layer "B.Fab")
		)
		(fp_line
			(start 0.12065 -0.2794)
			(end -0.12065 -0.2794)
			(stroke
				(width 0.1)
				(type default)
			)
			(layer "B.Fab")
		)
		(fp_line
			(start 0.12065 -0.305054)
			(end 0.12065 -0.2794)
			(stroke
				(width 0.1)
				(type default)
			)
			(layer "B.Fab")
		)
		(fp_line
			(start -0.120396 0.3048)
			(end -0.120396 0.2794)
			(stroke
				(width 0.1)
				(type default)
			)
			(layer "B.Fab")
		)
		(fp_line
			(start -0.120396 0.2794)
			(end 0.12065 0.2794)
			(stroke
				(width 0.1)
				(type default)
			)
			(layer "B.Fab")
		)
		(fp_line
			(start -0.12065 -0.2794)
			(end -0.12065 -0.3048)
			(stroke
				(width 0.1)
				(type default)
			)
			(layer "B.Fab")
		)
		(fp_line
			(start -0.12065 -0.3048)
			(end -0.67945 -0.3048)
			(stroke
				(width 0.1)
				(type default)
			)
			(layer "B.Fab")
		)
		(fp_line
			(start -0.67945 0.3048)
			(end -0.120396 0.3048)
			(stroke
				(width 0.1)
				(type default)
			)
			(layer "B.Fab")
		)
		(fp_line
			(start -0.67945 -0.3048)
			(end -0.67945 0.3048)
			(stroke
				(width 0.1)
				(type default)
			)
			(layer "B.Fab")
		)
		(pad "1" smd circle
			(at 0.40005 0)
			(size 0 0)
			(layers "B.Cu" "B.Mask" "B.Paste")
			(net "VFG3P3_CLK_GEN")
		)
		(pad "2" smd circle
			(at -0.40005 0)
			(size 0 0)
			(layers "B.Cu" "B.Mask" "B.Paste")
			(net "GND")
		)
	)
	(footprint ""
		(layer "B.Cu")
		(at 183.36006 -407.222198 -90)
		(property "Reference" "PR3927"
			(at 0 0 90)
			(layer "B.SilkS")
			(hide yes)
			(effects
				(font
					(size 1.27 1.27)
				)
				(justify mirror)
			)
		)
		(property "Value" ""
			(at 0 0 90)
			(layer "B.Fab")
			(effects
				(font
					(size 1.27 1.27)
				)
				(justify mirror)
			)
		)
		(duplicate_pad_numbers_are_jumpers no)
		(fp_line
			(start -0.7874 0.4064)
			(end 0.7874 0.4064)
			(stroke
				(width 0.1524)
				(type default)
			)
			(layer "B.SilkS")
		)
		(fp_line
			(start 0.7874 0.4064)
			(end 0.7874 -0.4064)
			(stroke
				(width 0.1524)
				(type default)
			)
			(layer "B.SilkS")
		)
		(fp_line
			(start -0.7874 -0.4064)
			(end -0.7874 0.4064)
			(stroke
				(width 0.1524)
				(type default)
			)
			(layer "B.SilkS")
		)
		(fp_line
			(start 0.7874 -0.4064)
			(end -0.7874 -0.4064)
			(stroke
				(width 0.1524)
				(type default)
			)
			(layer "B.SilkS")
		)
		(fp_line
			(start -0.67945 0.3048)
			(end -0.120396 0.3048)
			(stroke
				(width 0.1)
				(type default)
			)
			(layer "B.Fab")
		)
		(fp_line
			(start -0.120396 0.3048)
			(end -0.120396 0.2794)
			(stroke
				(width 0.1)
				(type default)
			)
			(layer "B.Fab")
		)
		(fp_line
			(start 0.12065 0.3048)
			(end 0.67945 0.3048)
			(stroke
				(width 0.1)
				(type default)
			)
			(layer "B.Fab")
		)
		(fp_line
			(start 0.67945 0.3048)
			(end 0.67945 -0.305054)
			(stroke
				(width 0.1)
				(type default)
			)
			(layer "B.Fab")
		)
		(fp_line
			(start -0.120396 0.2794)
			(end 0.12065 0.2794)
			(stroke
				(width 0.1)
				(type default)
			)
			(layer "B.Fab")
		)
		(fp_line
			(start 0.12065 0.2794)
			(end 0.12065 0.3048)
			(stroke
				(width 0.1)
				(type default)
			)
			(layer "B.Fab")
		)
		(fp_line
			(start -0.12065 -0.2794)
			(end -0.12065 -0.3048)
			(stroke
				(width 0.1)
				(type default)
			)
			(layer "B.Fab")
		)
		(fp_line
			(start 0.12065 -0.2794)
			(end -0.12065 -0.2794)
			(stroke
				(width 0.1)
				(type default)
			)
			(layer "B.Fab")
		)
		(fp_line
			(start -0.67945 -0.3048)
			(end -0.67945 0.3048)
			(stroke
				(width 0.1)
				(type default)
			)
			(layer "B.Fab")
		)
		(fp_line
			(start -0.12065 -0.3048)
			(end -0.67945 -0.3048)
			(stroke
				(width 0.1)
				(type default)
			)
			(layer "B.Fab")
		)
		(fp_line
			(start 0.12065 -0.305054)
			(end 0.12065 -0.2794)
			(stroke
				(width 0.1)
				(type default)
			)
			(layer "B.Fab")
		)
		(fp_line
			(start 0.67945 -0.305054)
			(end 0.12065 -0.305054)
			(stroke
				(width 0.1)
				(type default)
			)
			(layer "B.Fab")
		)
		(pad "1" smd circle
			(at 0.40005 0 90)
			(size 0 0)
			(layers "B.Cu" "B.Mask" "B.Paste")
			(net "HSC_VSENSE")
		)
		(pad "2" smd circle
			(at -0.40005 0 90)
			(size 0 0)
			(layers "B.Cu" "B.Mask" "B.Paste")
			(net "AGND_HSC")
		)
	)
	(footprint ""
		(layer "B.Cu")
		(at 173.863 -420.243)
		(property "Reference" "C1751"
			(at 0 0 0)
			(layer "B.SilkS")
			(hide yes)
			(effects
				(font
					(size 1.27 1.27)
				)
				(justify mirror)
			)
		)
		(property "Value" ""
			(at 0 0 0)
			(layer "B.Fab")
			(effects
				(font
					(size 1.27 1.27)
				)
				(justify mirror)
			)
		)
		(duplicate_pad_numbers_are_jumpers no)
		(fp_line
			(start -0.7874 -0.4064)
			(end -0.7874 0.4064)
			(stroke
				(width 0.1524)
				(type default)
			)
			(layer "B.SilkS")
		)
		(fp_line
			(start -0.7874 0.4064)
			(end 0.7874 0.4064)
			(stroke
				(width 0.1524)
				(type default)
			)
			(layer "B.SilkS")
		)
		(fp_line
			(start 0.7874 -0.4064)
			(end -0.7874 -0.4064)
			(stroke
				(width 0.1524)
				(type default)
			)
			(layer "B.SilkS")
		)
		(fp_line
			(start 0.7874 0.4064)
			(end 0.7874 -0.4064)
			(stroke
				(width 0.1524)
				(type default)
			)
			(layer "B.SilkS")
		)
		(fp_line
			(start -0.67945 -0.3048)
			(end -0.67945 0.3048)
			(stroke
				(width 0.1)
				(type default)
			)
			(layer "B.Fab")
		)
		(fp_line
			(start -0.67945 0.3048)
			(end -0.120396 0.3048)
			(stroke
				(width 0.1)
				(type default)
			)
			(layer "B.Fab")
		)
		(fp_line
			(start -0.12065 -0.3048)
			(end -0.67945 -0.3048)
			(stroke
				(width 0.1)
				(type default)
			)
			(layer "B.Fab")
		)
		(fp_line
			(start -0.12065 -0.2794)
			(end -0.12065 -0.3048)
			(stroke
				(width 0.1)
				(type default)
			)
			(layer "B.Fab")
		)
		(fp_line
			(start -0.120396 0.2794)
			(end 0.12065 0.2794)
			(stroke
				(width 0.1)
				(type default)
			)
			(layer "B.Fab")
		)
		(fp_line
			(start -0.120396 0.3048)
			(end -0.120396 0.2794)
			(stroke
				(width 0.1)
				(type default)
			)
			(layer "B.Fab")
		)
		(fp_line
			(start 0.12065 -0.305054)
			(end 0.12065 -0.2794)
			(stroke
				(width 0.1)
				(type default)
			)
			(layer "B.Fab")
		)
		(fp_line
			(start 0.12065 -0.2794)
			(end -0.12065 -0.2794)
			(stroke
				(width 0.1)
				(type default)
			)
			(layer "B.Fab")
		)
		(fp_line
			(start 0.12065 0.2794)
			(end 0.12065 0.3048)
			(stroke
				(width 0.1)
				(type default)
			)
			(layer "B.Fab")
		)
		(fp_line
			(start 0.12065 0.3048)
			(end 0.67945 0.3048)
			(stroke
				(width 0.1)
				(type default)
			)
			(layer "B.Fab")
		)
		(fp_line
			(start 0.67945 -0.305054)
			(end 0.12065 -0.305054)
			(stroke
				(width 0.1)
				(type default)
			)
			(layer "B.Fab")
		)
		(fp_line
			(start 0.67945 0.3048)
			(end 0.67945 -0.305054)
			(stroke
				(width 0.1)
				(type default)
			)
			(layer "B.Fab")
		)
		(pad "1" smd circle
			(at 0.40005 0 180)
			(size 0 0)
			(layers "B.Cu" "B.Mask" "B.Paste")
			(net "P3V3_AUX")
		)
		(pad "2" smd circle
			(at -0.40005 0 180)
			(size 0 0)
			(layers "B.Cu" "B.Mask" "B.Paste")
			(net "GND")
		)
	)
	(footprint ""
		(layer "B.Cu")
		(at 419.819074 -398.942052 90)
		(property "Reference" "C977"
			(at 0 0 90)
			(layer "B.SilkS")
			(hide yes)
			(effects
				(font
					(size 1.27 1.27)
				)
				(justify mirror)
			)
		)
		(property "Value" ""
			(at 0 0 90)
			(layer "B.Fab")
			(effects
				(font
					(size 1.27 1.27)
				)
				(justify mirror)
			)
		)
		(duplicate_pad_numbers_are_jumpers no)
		(fp_line
			(start 0.7874 -0.4064)
			(end -0.7874 -0.4064)
			(stroke
				(width 0.1524)
				(type default)
			)
			(layer "B.SilkS")
		)
		(fp_line
			(start -0.7874 -0.4064)
			(end -0.7874 0.4064)
			(stroke
				(width 0.1524)
				(type default)
			)
			(layer "B.SilkS")
		)
		(fp_line
			(start 0.7874 0.4064)
			(end 0.7874 -0.4064)
			(stroke
				(width 0.1524)
				(type default)
			)
			(layer "B.SilkS")
		)
		(fp_line
			(start -0.7874 0.4064)
			(end 0.7874 0.4064)
			(stroke
				(width 0.1524)
				(type default)
			)
			(layer "B.SilkS")
		)
		(fp_line
			(start 0.67945 -0.305054)
			(end 0.12065 -0.305054)
			(stroke
				(width 0.1)
				(type default)
			)
			(layer "B.Fab")
		)
		(fp_line
			(start 0.12065 -0.305054)
			(end 0.12065 -0.2794)
			(stroke
				(width 0.1)
				(type default)
			)
			(layer "B.Fab")
		)
		(fp_line
			(start -0.12065 -0.3048)
			(end -0.67945 -0.3048)
			(stroke
				(width 0.1)
				(type default)
			)
			(layer "B.Fab")
		)
		(fp_line
			(start -0.67945 -0.3048)
			(end -0.67945 0.3048)
			(stroke
				(width 0.1)
				(type default)
			)
			(layer "B.Fab")
		)
		(fp_line
			(start 0.12065 -0.2794)
			(end -0.12065 -0.2794)
			(stroke
				(width 0.1)
				(type default)
			)
			(layer "B.Fab")
		)
		(fp_line
			(start -0.12065 -0.2794)
			(end -0.12065 -0.3048)
			(stroke
				(width 0.1)
				(type default)
			)
			(layer "B.Fab")
		)
		(fp_line
			(start 0.12065 0.2794)
			(end 0.12065 0.3048)
			(stroke
				(width 0.1)
				(type default)
			)
			(layer "B.Fab")
		)
		(fp_line
			(start -0.120396 0.2794)
			(end 0.12065 0.2794)
			(stroke
				(width 0.1)
				(type default)
			)
			(layer "B.Fab")
		)
		(fp_line
			(start 0.67945 0.3048)
			(end 0.67945 -0.305054)
			(stroke
				(width 0.1)
				(type default)
			)
			(layer "B.Fab")
		)
		(fp_line
			(start 0.12065 0.3048)
			(end 0.67945 0.3048)
			(stroke
				(width 0.1)
				(type default)
			)
			(layer "B.Fab")
		)
		(fp_line
			(start -0.120396 0.3048)
			(end -0.120396 0.2794)
			(stroke
				(width 0.1)
				(type default)
			)
			(layer "B.Fab")
		)
		(fp_line
			(start -0.67945 0.3048)
			(end -0.120396 0.3048)
			(stroke
				(width 0.1)
				(type default)
			)
			(layer "B.Fab")
		)
		(pad "1" smd circle
			(at 0.40005 0 270)
			(size 0 0)
			(layers "B.Cu" "B.Mask" "B.Paste")
			(net "P0V9_CPU0_RT2_2A")
		)
		(pad "2" smd circle
			(at -0.40005 0 270)
			(size 0 0)
			(layers "B.Cu" "B.Mask" "B.Paste")
			(net "GND")
		)
	)
	(footprint ""
		(layer "B.Cu")
		(at 397.623538 -393.04468 180)
		(property "Reference" "R1075"
			(at 0 0 0)
			(layer "B.SilkS")
			(hide yes)
			(effects
				(font
					(size 1.27 1.27)
				)
				(justify mirror)
			)
		)
		(property "Value" ""
			(at 0 0 0)
			(layer "B.Fab")
			(effects
				(font
					(size 1.27 1.27)
				)
				(justify mirror)
			)
		)
		(duplicate_pad_numbers_are_jumpers no)
		(fp_line
			(start 0.32512 0.175006)
			(end 0.32512 -0.175006)
			(stroke
				(width 0.1)
				(type default)
			)
			(layer "B.Fab")
		)
		(fp_line
			(start 0.32512 -0.175006)
			(end -0.32512 -0.175006)
			(stroke
				(width 0.1)
				(type default)
			)
			(layer "B.Fab")
		)
		(fp_line
			(start -0.32512 0.175006)
			(end 0.32512 0.175006)
			(stroke
				(width 0.1)
				(type default)
			)
			(layer "B.Fab")
		)
		(fp_line
			(start -0.32512 -0.175006)
			(end -0.32512 0.175006)
			(stroke
				(width 0.1)
				(type default)
			)
			(layer "B.Fab")
		)
		(pad "1" smd rect
			(at 0.2667 0)
			(size 0.3048 0.381)
			(layers "B.Cu" "B.Mask" "B.Paste")
			(net "P1V8_CPU0_RT_1D")
		)
		(pad "2" smd rect
			(at -0.2667 0 180)
			(size 0.3048 0.381)
			(layers "B.Cu" "B.Mask" "B.Paste")
			(net "TEST1_RT_CPU0_P2")
		)
	)
	(footprint ""
		(layer "B.Cu")
		(at 295.402 -424.942 180)
		(property "Reference" "R834"
			(at 0 0 0)
			(layer "B.SilkS")
			(hide yes)
			(effects
				(font
					(size 1.27 1.27)
				)
				(justify mirror)
			)
		)
		(property "Value" ""
			(at 0 0 0)
			(layer "B.Fab")
			(effects
				(font
					(size 1.27 1.27)
				)
				(justify mirror)
			)
		)
		(duplicate_pad_numbers_are_jumpers no)
		(fp_line
			(start 0.32512 0.175006)
			(end 0.32512 -0.175006)
			(stroke
				(width 0.1)
				(type default)
			)
			(layer "B.Fab")
		)
		(fp_line
			(start 0.32512 -0.175006)
			(end -0.32512 -0.175006)
			(stroke
				(width 0.1)
				(type default)
			)
			(layer "B.Fab")
		)
		(fp_line
			(start -0.32512 0.175006)
			(end 0.32512 0.175006)
			(stroke
				(width 0.1)
				(type default)
			)
			(layer "B.Fab")
		)
		(fp_line
			(start -0.32512 -0.175006)
			(end -0.32512 0.175006)
			(stroke
				(width 0.1)
				(type default)
			)
			(layer "B.Fab")
		)
		(pad "1" smd rect
			(at 0.2667 0)
			(size 0.3048 0.381)
			(layers "B.Cu" "B.Mask" "B.Paste")
			(net "P1V8_CPU0_RT_1D")
		)
		(pad "2" smd rect
			(at -0.2667 0 180)
			(size 0.3048 0.381)
			(layers "B.Cu" "B.Mask" "B.Paste")
			(net "SMB_RT_CPU0_P0_ROM_R_SDA")
		)
	)
	(footprint ""
		(layer "B.Cu")
		(at 184.332372 -116.642896 -90)
		(property "Reference" "C1174"
			(at 0 0 90)
			(layer "B.SilkS")
			(hide yes)
			(effects
				(font
					(size 1.27 1.27)
				)
				(justify mirror)
			)
		)
		(property "Value" ""
			(at 0 0 90)
			(layer "B.Fab")
			(effects
				(font
					(size 1.27 1.27)
				)
				(justify mirror)
			)
		)
		(duplicate_pad_numbers_are_jumpers no)
		(fp_line
			(start -0.69215 0.2921)
			(end 0.69215 0.2921)
			(stroke
				(width 0.1524)
				(type default)
			)
			(layer "B.SilkS")
		)
		(fp_line
			(start 0.69215 0.2921)
			(end 0.69215 -0.2921)
			(stroke
				(width 0.1524)
				(type default)
			)
			(layer "B.SilkS")
		)
		(fp_line
			(start -0.69215 -0.2921)
			(end -0.69215 0.2921)
			(stroke
				(width 0.1524)
				(type default)
			)
			(layer "B.SilkS")
		)
		(fp_line
			(start 0.69215 -0.2921)
			(end -0.69215 -0.2921)
			(stroke
				(width 0.1524)
				(type default)
			)
			(layer "B.SilkS")
		)
		(fp_line
			(start -0.51435 0.2794)
			(end 0.51435 0.2794)
			(stroke
				(width 0.1)
				(type default)
			)
			(layer "B.Fab")
		)
		(fp_line
			(start 0.51435 0.2794)
			(end 0.51435 -0.2794)
			(stroke
				(width 0.1)
				(type default)
			)
			(layer "B.Fab")
		)
		(fp_line
			(start -0.51435 -0.2794)
			(end -0.51435 0.2794)
			(stroke
				(width 0.1)
				(type default)
			)
			(layer "B.Fab")
		)
		(fp_line
			(start 0.51435 -0.2794)
			(end -0.51435 -0.2794)
			(stroke
				(width 0.1)
				(type default)
			)
			(layer "B.Fab")
		)
		(pad "1" smd circle
			(at 0.40005 0 90)
			(size 0 0)
			(layers "B.Cu" "B.Mask" "B.Paste")
			(net "P3V3_AUX")
		)
		(pad "2" smd circle
			(at -0.40005 0 90)
			(size 0 0)
			(layers "B.Cu" "B.Mask" "B.Paste")
			(net "GND")
		)
		(zone
			(layer "B.Cu")
			(hatch none 0.5)
			(connect_pads
				(clearance 0)
			)
			(min_thickness 0.25)
			(keepout
				(tracks not_allowed)
				(vias allowed)
				(pads allowed)
				(copperpour not_allowed)
				(footprints allowed)
			)
			(placement
				(enabled no)
				(sheetname "")
			)
			(fill
				(thermal_gap 0.5)
				(thermal_bridge_width 0.5)
				(island_removal_mode 0)
			)
			(polygon
				(pts
					(xy 184.186576 -116.543836) (xy 184.186576 -116.743226) (xy 184.244742 -116.833396) (xy 184.420002 -116.833396)
					(xy 184.478422 -116.743226) (xy 184.478422 -116.543836) (xy 184.420256 -116.452396) (xy 184.244742 -116.452396)
				)
			)
		)
	)
	(footprint ""
		(layer "B.Cu")
		(at 74.55408 -4.251198 90)
		(property "Reference" "R3167"
			(at 0 0 90)
			(layer "B.SilkS")
			(hide yes)
			(effects
				(font
					(size 1.27 1.27)
				)
				(justify mirror)
			)
		)
		(property "Value" ""
			(at 0 0 90)
			(layer "B.Fab")
			(effects
				(font
					(size 1.27 1.27)
				)
				(justify mirror)
			)
		)
		(duplicate_pad_numbers_are_jumpers no)
		(fp_line
			(start 0.7874 -0.4064)
			(end -0.7874 -0.4064)
			(stroke
				(width 0.1524)
				(type default)
			)
			(layer "B.SilkS")
		)
		(fp_line
			(start -0.7874 -0.4064)
			(end -0.7874 0.4064)
			(stroke
				(width 0.1524)
				(type default)
			)
			(layer "B.SilkS")
		)
		(fp_line
			(start 0.7874 0.4064)
			(end 0.7874 -0.4064)
			(stroke
				(width 0.1524)
				(type default)
			)
			(layer "B.SilkS")
		)
		(fp_line
			(start -0.7874 0.4064)
			(end 0.7874 0.4064)
			(stroke
				(width 0.1524)
				(type default)
			)
			(layer "B.SilkS")
		)
		(fp_line
			(start 0.67945 -0.305054)
			(end 0.12065 -0.305054)
			(stroke
				(width 0.1)
				(type default)
			)
			(layer "B.Fab")
		)
		(fp_line
			(start 0.12065 -0.305054)
			(end 0.12065 -0.2794)
			(stroke
				(width 0.1)
				(type default)
			)
			(layer "B.Fab")
		)
		(fp_line
			(start -0.12065 -0.3048)
			(end -0.67945 -0.3048)
			(stroke
				(width 0.1)
				(type default)
			)
			(layer "B.Fab")
		)
		(fp_line
			(start -0.67945 -0.3048)
			(end -0.67945 0.3048)
			(stroke
				(width 0.1)
				(type default)
			)
			(layer "B.Fab")
		)
		(fp_line
			(start 0.12065 -0.2794)
			(end -0.12065 -0.2794)
			(stroke
				(width 0.1)
				(type default)
			)
			(layer "B.Fab")
		)
		(fp_line
			(start -0.12065 -0.2794)
			(end -0.12065 -0.3048)
			(stroke
				(width 0.1)
				(type default)
			)
			(layer "B.Fab")
		)
		(fp_line
			(start 0.12065 0.2794)
			(end 0.12065 0.3048)
			(stroke
				(width 0.1)
				(type default)
			)
			(layer "B.Fab")
		)
		(fp_line
			(start -0.120396 0.2794)
			(end 0.12065 0.2794)
			(stroke
				(width 0.1)
				(type default)
			)
			(layer "B.Fab")
		)
		(fp_line
			(start 0.67945 0.3048)
			(end 0.67945 -0.305054)
			(stroke
				(width 0.1)
				(type default)
			)
			(layer "B.Fab")
		)
		(fp_line
			(start 0.12065 0.3048)
			(end 0.67945 0.3048)
			(stroke
				(width 0.1)
				(type default)
			)
			(layer "B.Fab")
		)
		(fp_line
			(start -0.120396 0.3048)
			(end -0.120396 0.2794)
			(stroke
				(width 0.1)
				(type default)
			)
			(layer "B.Fab")
		)
		(fp_line
			(start -0.67945 0.3048)
			(end -0.120396 0.3048)
			(stroke
				(width 0.1)
				(type default)
			)
			(layer "B.Fab")
		)
		(pad "1" smd circle
			(at 0.40005 0 270)
			(size 0 0)
			(layers "B.Cu" "B.Mask" "B.Paste")
			(net "OCP_V3_2_ID1")
		)
		(pad "2" smd circle
			(at -0.40005 0 270)
			(size 0 0)
			(layers "B.Cu" "B.Mask" "B.Paste")
			(net "GND")
		)
	)
	(footprint ""
		(layer "B.Cu")
		(at 89.560146 -178.736244 90)
		(property "Reference" "PC267_2"
			(at 0 0 90)
			(layer "B.SilkS")
			(hide yes)
			(effects
				(font
					(size 1.27 1.27)
				)
				(justify mirror)
			)
		)
		(property "Value" ""
			(at 0 0 90)
			(layer "B.Fab")
			(effects
				(font
					(size 1.27 1.27)
				)
				(justify mirror)
			)
		)
		(duplicate_pad_numbers_are_jumpers no)
		(fp_line
			(start 1.524 -0.762)
			(end -1.524 -0.762)
			(stroke
				(width 0.1524)
				(type default)
			)
			(layer "B.SilkS")
		)
		(fp_line
			(start -1.524 -0.762)
			(end -1.524 0.762)
			(stroke
				(width 0.1524)
				(type default)
			)
			(layer "B.SilkS")
		)
		(fp_line
			(start 1.524 0.762)
			(end 1.524 -0.762)
			(stroke
				(width 0.1524)
				(type default)
			)
			(layer "B.SilkS")
		)
		(fp_line
			(start -1.524 0.762)
			(end 1.524 0.762)
			(stroke
				(width 0.1524)
				(type default)
			)
			(layer "B.SilkS")
		)
		(fp_line
			(start 1.1049 -0.724916)
			(end 1.1049 0.724916)
			(stroke
				(width 0.1)
				(type default)
			)
			(layer "B.Fab")
		)
		(fp_line
			(start -1.1049 -0.724916)
			(end 1.1049 -0.724916)
			(stroke
				(width 0.1)
				(type default)
			)
			(layer "B.Fab")
		)
		(fp_line
			(start 1.1049 0.724916)
			(end -1.1049 0.724916)
			(stroke
				(width 0.1)
				(type default)
			)
			(layer "B.Fab")
		)
		(fp_line
			(start -1.1049 0.724916)
			(end -1.1049 -0.724916)
			(stroke
				(width 0.1)
				(type default)
			)
			(layer "B.Fab")
		)
		(pad "1" smd rect
			(at 0.889 0 90)
			(size 1.016 1.27)
			(layers "B.Cu" "B.Mask" "B.Paste")
			(net "SW_P12V_AUX_PVDDCR_CPU0_P1_FLT")
		)
		(pad "2" smd rect
			(at -0.889 0 90)
			(size 1.016 1.27)
			(layers "B.Cu" "B.Mask" "B.Paste")
			(net "GND")
		)
	)
	(footprint ""
		(layer "B.Cu")
		(at 344.511884 -335.092294 90)
		(property "Reference" "PC138_5"
			(at 0 0 90)
			(layer "B.SilkS")
			(hide yes)
			(effects
				(font
					(size 1.27 1.27)
				)
				(justify mirror)
			)
		)
		(property "Value" ""
			(at 0 0 90)
			(layer "B.Fab")
			(effects
				(font
					(size 1.27 1.27)
				)
				(justify mirror)
			)
		)
		(duplicate_pad_numbers_are_jumpers no)
		(fp_line
			(start 1.524 -0.762)
			(end -1.524 -0.762)
			(stroke
				(width 0.1524)
				(type default)
			)
			(layer "B.SilkS")
		)
		(fp_line
			(start -1.524 -0.762)
			(end -1.524 0.762)
			(stroke
				(width 0.1524)
				(type default)
			)
			(layer "B.SilkS")
		)
		(fp_line
			(start 1.524 0.762)
			(end 1.524 -0.762)
			(stroke
				(width 0.1524)
				(type default)
			)
			(layer "B.SilkS")
		)
		(fp_line
			(start -1.524 0.762)
			(end 1.524 0.762)
			(stroke
				(width 0.1524)
				(type default)
			)
			(layer "B.SilkS")
		)
		(fp_line
			(start 1.1049 -0.724916)
			(end 1.1049 0.724916)
			(stroke
				(width 0.1)
				(type default)
			)
			(layer "B.Fab")
		)
		(fp_line
			(start -1.1049 -0.724916)
			(end 1.1049 -0.724916)
			(stroke
				(width 0.1)
				(type default)
			)
			(layer "B.Fab")
		)
		(fp_line
			(start 1.1049 0.724916)
			(end -1.1049 0.724916)
			(stroke
				(width 0.1)
				(type default)
			)
			(layer "B.Fab")
		)
		(fp_line
			(start -1.1049 0.724916)
			(end -1.1049 -0.724916)
			(stroke
				(width 0.1)
				(type default)
			)
			(layer "B.Fab")
		)
		(pad "1" smd rect
			(at 0.889 0 90)
			(size 1.016 1.27)
			(layers "B.Cu" "B.Mask" "B.Paste")
			(net "SW_P12V_AUX_PVDDCR_CPU1_P0_FLT")
		)
		(pad "2" smd rect
			(at -0.889 0 90)
			(size 1.016 1.27)
			(layers "B.Cu" "B.Mask" "B.Paste")
			(net "GND")
		)
	)
	(footprint ""
		(layer "B.Cu")
		(at 103.759 -418.592 90)
		(property "Reference" "R3034"
			(at 0 0 90)
			(layer "B.SilkS")
			(hide yes)
			(effects
				(font
					(size 1.27 1.27)
				)
				(justify mirror)
			)
		)
		(property "Value" ""
			(at 0 0 90)
			(layer "B.Fab")
			(effects
				(font
					(size 1.27 1.27)
				)
				(justify mirror)
			)
		)
		(duplicate_pad_numbers_are_jumpers no)
		(fp_line
			(start 0.7874 -0.4064)
			(end -0.7874 -0.4064)
			(stroke
				(width 0.1524)
				(type default)
			)
			(layer "B.SilkS")
		)
		(fp_line
			(start -0.7874 -0.4064)
			(end -0.7874 0.4064)
			(stroke
				(width 0.1524)
				(type default)
			)
			(layer "B.SilkS")
		)
		(fp_line
			(start 0.7874 0.4064)
			(end 0.7874 -0.4064)
			(stroke
				(width 0.1524)
				(type default)
			)
			(layer "B.SilkS")
		)
		(fp_line
			(start -0.7874 0.4064)
			(end 0.7874 0.4064)
			(stroke
				(width 0.1524)
				(type default)
			)
			(layer "B.SilkS")
		)
		(fp_line
			(start 0.67945 -0.305054)
			(end 0.12065 -0.305054)
			(stroke
				(width 0.1)
				(type default)
			)
			(layer "B.Fab")
		)
		(fp_line
			(start 0.12065 -0.305054)
			(end 0.12065 -0.2794)
			(stroke
				(width 0.1)
				(type default)
			)
			(layer "B.Fab")
		)
		(fp_line
			(start -0.12065 -0.3048)
			(end -0.67945 -0.3048)
			(stroke
				(width 0.1)
				(type default)
			)
			(layer "B.Fab")
		)
		(fp_line
			(start -0.67945 -0.3048)
			(end -0.67945 0.3048)
			(stroke
				(width 0.1)
				(type default)
			)
			(layer "B.Fab")
		)
		(fp_line
			(start 0.12065 -0.2794)
			(end -0.12065 -0.2794)
			(stroke
				(width 0.1)
				(type default)
			)
			(layer "B.Fab")
		)
		(fp_line
			(start -0.12065 -0.2794)
			(end -0.12065 -0.3048)
			(stroke
				(width 0.1)
				(type default)
			)
			(layer "B.Fab")
		)
		(fp_line
			(start 0.12065 0.2794)
			(end 0.12065 0.3048)
			(stroke
				(width 0.1)
				(type default)
			)
			(layer "B.Fab")
		)
		(fp_line
			(start -0.120396 0.2794)
			(end 0.12065 0.2794)
			(stroke
				(width 0.1)
				(type default)
			)
			(layer "B.Fab")
		)
		(fp_line
			(start 0.67945 0.3048)
			(end 0.67945 -0.305054)
			(stroke
				(width 0.1)
				(type default)
			)
			(layer "B.Fab")
		)
		(fp_line
			(start 0.12065 0.3048)
			(end 0.67945 0.3048)
			(stroke
				(width 0.1)
				(type default)
			)
			(layer "B.Fab")
		)
		(fp_line
			(start -0.120396 0.3048)
			(end -0.120396 0.2794)
			(stroke
				(width 0.1)
				(type default)
			)
			(layer "B.Fab")
		)
		(fp_line
			(start -0.67945 0.3048)
			(end -0.120396 0.3048)
			(stroke
				(width 0.1)
				(type default)
			)
			(layer "B.Fab")
		)
		(pad "1" smd circle
			(at 0.40005 0 270)
			(size 0 0)
			(layers "B.Cu" "B.Mask" "B.Paste")
			(net "P3V3_AUX")
		)
		(pad "2" smd circle
			(at -0.40005 0 270)
			(size 0 0)
			(layers "B.Cu" "B.Mask" "B.Paste")
			(net "FM_SMB_2_ALERT_GPU")
		)
	)
	(footprint ""
		(layer "B.Cu")
		(at 213.616286 -329.201272)
		(property "Reference" "R1240"
			(at 0 0 0)
			(layer "B.SilkS")
			(hide yes)
			(effects
				(font
					(size 1.27 1.27)
				)
				(justify mirror)
			)
		)
		(property "Value" ""
			(at 0 0 0)
			(layer "B.Fab")
			(effects
				(font
					(size 1.27 1.27)
				)
				(justify mirror)
			)
		)
		(duplicate_pad_numbers_are_jumpers no)
		(fp_line
			(start -0.7874 -0.4064)
			(end -0.7874 0.4064)
			(stroke
				(width 0.1524)
				(type default)
			)
			(layer "B.SilkS")
		)
		(fp_line
			(start -0.7874 0.4064)
			(end 0.7874 0.4064)
			(stroke
				(width 0.1524)
				(type default)
			)
			(layer "B.SilkS")
		)
		(fp_line
			(start 0.7874 -0.4064)
			(end -0.7874 -0.4064)
			(stroke
				(width 0.1524)
				(type default)
			)
			(layer "B.SilkS")
		)
		(fp_line
			(start 0.7874 0.4064)
			(end 0.7874 -0.4064)
			(stroke
				(width 0.1524)
				(type default)
			)
			(layer "B.SilkS")
		)
		(fp_line
			(start -0.67945 -0.3048)
			(end -0.67945 0.3048)
			(stroke
				(width 0.1)
				(type default)
			)
			(layer "B.Fab")
		)
		(fp_line
			(start -0.67945 0.3048)
			(end -0.120396 0.3048)
			(stroke
				(width 0.1)
				(type default)
			)
			(layer "B.Fab")
		)
		(fp_line
			(start -0.12065 -0.3048)
			(end -0.67945 -0.3048)
			(stroke
				(width 0.1)
				(type default)
			)
			(layer "B.Fab")
		)
		(fp_line
			(start -0.12065 -0.2794)
			(end -0.12065 -0.3048)
			(stroke
				(width 0.1)
				(type default)
			)
			(layer "B.Fab")
		)
		(fp_line
			(start -0.120396 0.2794)
			(end 0.12065 0.2794)
			(stroke
				(width 0.1)
				(type default)
			)
			(layer "B.Fab")
		)
		(fp_line
			(start -0.120396 0.3048)
			(end -0.120396 0.2794)
			(stroke
				(width 0.1)
				(type default)
			)
			(layer "B.Fab")
		)
		(fp_line
			(start 0.12065 -0.305054)
			(end 0.12065 -0.2794)
			(stroke
				(width 0.1)
				(type default)
			)
			(layer "B.Fab")
		)
		(fp_line
			(start 0.12065 -0.2794)
			(end -0.12065 -0.2794)
			(stroke
				(width 0.1)
				(type default)
			)
			(layer "B.Fab")
		)
		(fp_line
			(start 0.12065 0.2794)
			(end 0.12065 0.3048)
			(stroke
				(width 0.1)
				(type default)
			)
			(layer "B.Fab")
		)
		(fp_line
			(start 0.12065 0.3048)
			(end 0.67945 0.3048)
			(stroke
				(width 0.1)
				(type default)
			)
			(layer "B.Fab")
		)
		(fp_line
			(start 0.67945 -0.305054)
			(end 0.12065 -0.305054)
			(stroke
				(width 0.1)
				(type default)
			)
			(layer "B.Fab")
		)
		(fp_line
			(start 0.67945 0.3048)
			(end 0.67945 -0.305054)
			(stroke
				(width 0.1)
				(type default)
			)
			(layer "B.Fab")
		)
		(pad "1" smd circle
			(at 0.40005 0 180)
			(size 0 0)
			(layers "B.Cu" "B.Mask" "B.Paste")
			(net "ADC128_2_A1")
		)
		(pad "2" smd circle
			(at -0.40005 0 180)
			(size 0 0)
			(layers "B.Cu" "B.Mask" "B.Paste")
			(net "GND")
		)
	)
	(footprint ""
		(layer "B.Cu")
		(at 384.113278 -143.250158)
		(property "Reference" "R8301"
			(at 0 0 0)
			(layer "B.SilkS")
			(hide yes)
			(effects
				(font
					(size 1.27 1.27)
				)
				(justify mirror)
			)
		)
		(property "Value" ""
			(at 0 0 0)
			(layer "B.Fab")
			(effects
				(font
					(size 1.27 1.27)
				)
				(justify mirror)
			)
		)
		(duplicate_pad_numbers_are_jumpers no)
		(fp_line
			(start -0.7874 -0.4064)
			(end -0.7874 0.4064)
			(stroke
				(width 0.1524)
				(type default)
			)
			(layer "B.SilkS")
		)
		(fp_line
			(start -0.7874 0.4064)
			(end 0.7874 0.4064)
			(stroke
				(width 0.1524)
				(type default)
			)
			(layer "B.SilkS")
		)
		(fp_line
			(start 0.7874 -0.4064)
			(end -0.7874 -0.4064)
			(stroke
				(width 0.1524)
				(type default)
			)
			(layer "B.SilkS")
		)
		(fp_line
			(start 0.7874 0.4064)
			(end 0.7874 -0.4064)
			(stroke
				(width 0.1524)
				(type default)
			)
			(layer "B.SilkS")
		)
		(fp_line
			(start -0.67945 -0.3048)
			(end -0.67945 0.3048)
			(stroke
				(width 0.1)
				(type default)
			)
			(layer "B.Fab")
		)
		(fp_line
			(start -0.67945 0.3048)
			(end -0.120396 0.3048)
			(stroke
				(width 0.1)
				(type default)
			)
			(layer "B.Fab")
		)
		(fp_line
			(start -0.12065 -0.3048)
			(end -0.67945 -0.3048)
			(stroke
				(width 0.1)
				(type default)
			)
			(layer "B.Fab")
		)
		(fp_line
			(start -0.12065 -0.2794)
			(end -0.12065 -0.3048)
			(stroke
				(width 0.1)
				(type default)
			)
			(layer "B.Fab")
		)
		(fp_line
			(start -0.120396 0.2794)
			(end 0.12065 0.2794)
			(stroke
				(width 0.1)
				(type default)
			)
			(layer "B.Fab")
		)
		(fp_line
			(start -0.120396 0.3048)
			(end -0.120396 0.2794)
			(stroke
				(width 0.1)
				(type default)
			)
			(layer "B.Fab")
		)
		(fp_line
			(start 0.12065 -0.305054)
			(end 0.12065 -0.2794)
			(stroke
				(width 0.1)
				(type default)
			)
			(layer "B.Fab")
		)
		(fp_line
			(start 0.12065 -0.2794)
			(end -0.12065 -0.2794)
			(stroke
				(width 0.1)
				(type default)
			)
			(layer "B.Fab")
		)
		(fp_line
			(start 0.12065 0.2794)
			(end 0.12065 0.3048)
			(stroke
				(width 0.1)
				(type default)
			)
			(layer "B.Fab")
		)
		(fp_line
			(start 0.12065 0.3048)
			(end 0.67945 0.3048)
			(stroke
				(width 0.1)
				(type default)
			)
			(layer "B.Fab")
		)
		(fp_line
			(start 0.67945 -0.305054)
			(end 0.12065 -0.305054)
			(stroke
				(width 0.1)
				(type default)
			)
			(layer "B.Fab")
		)
		(fp_line
			(start 0.67945 0.3048)
			(end 0.67945 -0.305054)
			(stroke
				(width 0.1)
				(type default)
			)
			(layer "B.Fab")
		)
		(pad "1" smd circle
			(at 0.40005 0 180)
			(size 0 0)
			(layers "B.Cu" "B.Mask" "B.Paste")
			(net "PVDDCR_CPU0_P0_OCP_N")
		)
		(pad "2" smd circle
			(at -0.40005 0 180)
			(size 0 0)
			(layers "B.Cu" "B.Mask" "B.Paste")
			(net "PVDDCR_CPU0_P0_OCP_N_R")
		)
	)
	(footprint ""
		(layer "B.Cu")
		(at 339.846158 -309.214012 -90)
		(property "Reference" "R393"
			(at 0 0 90)
			(layer "B.SilkS")
			(hide yes)
			(effects
				(font
					(size 1.27 1.27)
				)
				(justify mirror)
			)
		)
		(property "Value" ""
			(at 0 0 90)
			(layer "B.Fab")
			(effects
				(font
					(size 1.27 1.27)
				)
				(justify mirror)
			)
		)
		(duplicate_pad_numbers_are_jumpers no)
		(fp_line
			(start -0.7874 0.4064)
			(end 0.7874 0.4064)
			(stroke
				(width 0.1524)
				(type default)
			)
			(layer "B.SilkS")
		)
		(fp_line
			(start 0.7874 0.4064)
			(end 0.7874 -0.4064)
			(stroke
				(width 0.1524)
				(type default)
			)
			(layer "B.SilkS")
		)
		(fp_line
			(start -0.7874 -0.4064)
			(end -0.7874 0.4064)
			(stroke
				(width 0.1524)
				(type default)
			)
			(layer "B.SilkS")
		)
		(fp_line
			(start 0.7874 -0.4064)
			(end -0.7874 -0.4064)
			(stroke
				(width 0.1524)
				(type default)
			)
			(layer "B.SilkS")
		)
		(fp_line
			(start -0.67945 0.3048)
			(end -0.120396 0.3048)
			(stroke
				(width 0.1)
				(type default)
			)
			(layer "B.Fab")
		)
		(fp_line
			(start -0.120396 0.3048)
			(end -0.120396 0.2794)
			(stroke
				(width 0.1)
				(type default)
			)
			(layer "B.Fab")
		)
		(fp_line
			(start 0.12065 0.3048)
			(end 0.67945 0.3048)
			(stroke
				(width 0.1)
				(type default)
			)
			(layer "B.Fab")
		)
		(fp_line
			(start 0.67945 0.3048)
			(end 0.67945 -0.305054)
			(stroke
				(width 0.1)
				(type default)
			)
			(layer "B.Fab")
		)
		(fp_line
			(start -0.120396 0.2794)
			(end 0.12065 0.2794)
			(stroke
				(width 0.1)
				(type default)
			)
			(layer "B.Fab")
		)
		(fp_line
			(start 0.12065 0.2794)
			(end 0.12065 0.3048)
			(stroke
				(width 0.1)
				(type default)
			)
			(layer "B.Fab")
		)
		(fp_line
			(start -0.12065 -0.2794)
			(end -0.12065 -0.3048)
			(stroke
				(width 0.1)
				(type default)
			)
			(layer "B.Fab")
		)
		(fp_line
			(start 0.12065 -0.2794)
			(end -0.12065 -0.2794)
			(stroke
				(width 0.1)
				(type default)
			)
			(layer "B.Fab")
		)
		(fp_line
			(start -0.67945 -0.3048)
			(end -0.67945 0.3048)
			(stroke
				(width 0.1)
				(type default)
			)
			(layer "B.Fab")
		)
		(fp_line
			(start -0.12065 -0.3048)
			(end -0.67945 -0.3048)
			(stroke
				(width 0.1)
				(type default)
			)
			(layer "B.Fab")
		)
		(fp_line
			(start 0.12065 -0.305054)
			(end 0.12065 -0.2794)
			(stroke
				(width 0.1)
				(type default)
			)
			(layer "B.Fab")
		)
		(fp_line
			(start 0.67945 -0.305054)
			(end 0.12065 -0.305054)
			(stroke
				(width 0.1)
				(type default)
			)
			(layer "B.Fab")
		)
		(pad "1" smd circle
			(at 0.40005 0 90)
			(size 0 0)
			(layers "B.Cu" "B.Mask" "B.Paste")
			(net "CPU0_SA0")
		)
		(pad "2" smd circle
			(at -0.40005 0 90)
			(size 0 0)
			(layers "B.Cu" "B.Mask" "B.Paste")
			(net "GND")
		)
	)
	(footprint ""
		(layer "B.Cu")
		(at 111.981996 -26.952448 90)
		(property "Reference" "C6094"
			(at 0 0 90)
			(layer "B.SilkS")
			(hide yes)
			(effects
				(font
					(size 1.27 1.27)
				)
				(justify mirror)
			)
		)
		(property "Value" ""
			(at 0 0 90)
			(layer "B.Fab")
			(effects
				(font
					(size 1.27 1.27)
				)
				(justify mirror)
			)
		)
		(duplicate_pad_numbers_are_jumpers no)
		(fp_line
			(start 0.7874 -0.4064)
			(end -0.7874 -0.4064)
			(stroke
				(width 0.1524)
				(type default)
			)
			(layer "B.SilkS")
		)
		(fp_line
			(start -0.7874 -0.4064)
			(end -0.7874 0.4064)
			(stroke
				(width 0.1524)
				(type default)
			)
			(layer "B.SilkS")
		)
		(fp_line
			(start 0.7874 0.4064)
			(end 0.7874 -0.4064)
			(stroke
				(width 0.1524)
				(type default)
			)
			(layer "B.SilkS")
		)
		(fp_line
			(start -0.7874 0.4064)
			(end 0.7874 0.4064)
			(stroke
				(width 0.1524)
				(type default)
			)
			(layer "B.SilkS")
		)
		(fp_line
			(start 0.67945 -0.305054)
			(end 0.12065 -0.305054)
			(stroke
				(width 0.1)
				(type default)
			)
			(layer "B.Fab")
		)
		(fp_line
			(start 0.12065 -0.305054)
			(end 0.12065 -0.2794)
			(stroke
				(width 0.1)
				(type default)
			)
			(layer "B.Fab")
		)
		(fp_line
			(start -0.12065 -0.3048)
			(end -0.67945 -0.3048)
			(stroke
				(width 0.1)
				(type default)
			)
			(layer "B.Fab")
		)
		(fp_line
			(start -0.67945 -0.3048)
			(end -0.67945 0.3048)
			(stroke
				(width 0.1)
				(type default)
			)
			(layer "B.Fab")
		)
		(fp_line
			(start 0.12065 -0.2794)
			(end -0.12065 -0.2794)
			(stroke
				(width 0.1)
				(type default)
			)
			(layer "B.Fab")
		)
		(fp_line
			(start -0.12065 -0.2794)
			(end -0.12065 -0.3048)
			(stroke
				(width 0.1)
				(type default)
			)
			(layer "B.Fab")
		)
		(fp_line
			(start 0.12065 0.2794)
			(end 0.12065 0.3048)
			(stroke
				(width 0.1)
				(type default)
			)
			(layer "B.Fab")
		)
		(fp_line
			(start -0.120396 0.2794)
			(end 0.12065 0.2794)
			(stroke
				(width 0.1)
				(type default)
			)
			(layer "B.Fab")
		)
		(fp_line
			(start 0.67945 0.3048)
			(end 0.67945 -0.305054)
			(stroke
				(width 0.1)
				(type default)
			)
			(layer "B.Fab")
		)
		(fp_line
			(start 0.12065 0.3048)
			(end 0.67945 0.3048)
			(stroke
				(width 0.1)
				(type default)
			)
			(layer "B.Fab")
		)
		(fp_line
			(start -0.120396 0.3048)
			(end -0.120396 0.2794)
			(stroke
				(width 0.1)
				(type default)
			)
			(layer "B.Fab")
		)
		(fp_line
			(start -0.67945 0.3048)
			(end -0.120396 0.3048)
			(stroke
				(width 0.1)
				(type default)
			)
			(layer "B.Fab")
		)
		(pad "1" smd circle
			(at 0.40005 0 270)
			(size 0 0)
			(layers "B.Cu" "B.Mask" "B.Paste")
			(net "P3V3_AUX_CPU0_USB2_AVDD33")
		)
		(pad "2" smd circle
			(at -0.40005 0 270)
			(size 0 0)
			(layers "B.Cu" "B.Mask" "B.Paste")
			(net "GND")
		)
	)
	(footprint ""
		(layer "B.Cu")
		(at 288.935668 -194.88531 180)
		(property "Reference" "R762"
			(at 0 0 0)
			(layer "B.SilkS")
			(hide yes)
			(effects
				(font
					(size 1.27 1.27)
				)
				(justify mirror)
			)
		)
		(property "Value" ""
			(at 0 0 0)
			(layer "B.Fab")
			(effects
				(font
					(size 1.27 1.27)
				)
				(justify mirror)
			)
		)
		(duplicate_pad_numbers_are_jumpers no)
		(fp_line
			(start 0.7874 0.4064)
			(end 0.7874 -0.4064)
			(stroke
				(width 0.1524)
				(type default)
			)
			(layer "B.SilkS")
		)
		(fp_line
			(start 0.7874 -0.4064)
			(end -0.7874 -0.4064)
			(stroke
				(width 0.1524)
				(type default)
			)
			(layer "B.SilkS")
		)
		(fp_line
			(start -0.7874 0.4064)
			(end 0.7874 0.4064)
			(stroke
				(width 0.1524)
				(type default)
			)
			(layer "B.SilkS")
		)
		(fp_line
			(start -0.7874 -0.4064)
			(end -0.7874 0.4064)
			(stroke
				(width 0.1524)
				(type default)
			)
			(layer "B.SilkS")
		)
		(fp_line
			(start 0.67945 0.3048)
			(end 0.67945 -0.305054)
			(stroke
				(width 0.1)
				(type default)
			)
			(layer "B.Fab")
		)
		(fp_line
			(start 0.67945 -0.305054)
			(end 0.12065 -0.305054)
			(stroke
				(width 0.1)
				(type default)
			)
			(layer "B.Fab")
		)
		(fp_line
			(start 0.12065 0.3048)
			(end 0.67945 0.3048)
			(stroke
				(width 0.1)
				(type default)
			)
			(layer "B.Fab")
		)
		(fp_line
			(start 0.12065 0.2794)
			(end 0.12065 0.3048)
			(stroke
				(width 0.1)
				(type default)
			)
			(layer "B.Fab")
		)
		(fp_line
			(start 0.12065 -0.2794)
			(end -0.12065 -0.2794)
			(stroke
				(width 0.1)
				(type default)
			)
			(layer "B.Fab")
		)
		(fp_line
			(start 0.12065 -0.305054)
			(end 0.12065 -0.2794)
			(stroke
				(width 0.1)
				(type default)
			)
			(layer "B.Fab")
		)
		(fp_line
			(start -0.120396 0.3048)
			(end -0.120396 0.2794)
			(stroke
				(width 0.1)
				(type default)
			)
			(layer "B.Fab")
		)
		(fp_line
			(start -0.120396 0.2794)
			(end 0.12065 0.2794)
			(stroke
				(width 0.1)
				(type default)
			)
			(layer "B.Fab")
		)
		(fp_line
			(start -0.12065 -0.2794)
			(end -0.12065 -0.3048)
			(stroke
				(width 0.1)
				(type default)
			)
			(layer "B.Fab")
		)
		(fp_line
			(start -0.12065 -0.3048)
			(end -0.67945 -0.3048)
			(stroke
				(width 0.1)
				(type default)
			)
			(layer "B.Fab")
		)
		(fp_line
			(start -0.67945 0.3048)
			(end -0.120396 0.3048)
			(stroke
				(width 0.1)
				(type default)
			)
			(layer "B.Fab")
		)
		(fp_line
			(start -0.67945 -0.3048)
			(end -0.67945 0.3048)
			(stroke
				(width 0.1)
				(type default)
			)
			(layer "B.Fab")
		)
		(pad "1" smd circle
			(at 0.40005 0)
			(size 0 0)
			(layers "B.Cu" "B.Mask" "B.Paste")
			(net "PD_CHC_CPU0_DIMM_SAA")
		)
		(pad "2" smd circle
			(at -0.40005 0)
			(size 0 0)
			(layers "B.Cu" "B.Mask" "B.Paste")
			(net "GND")
		)
	)
	(footprint ""
		(layer "B.Cu")
		(at 133.332474 -165.190932 90)
		(property "Reference" "PC342_2"
			(at 0 0 90)
			(layer "B.SilkS")
			(hide yes)
			(effects
				(font
					(size 1.27 1.27)
				)
				(justify mirror)
			)
		)
		(property "Value" ""
			(at 0 0 90)
			(layer "B.Fab")
			(effects
				(font
					(size 1.27 1.27)
				)
				(justify mirror)
			)
		)
		(duplicate_pad_numbers_are_jumpers no)
		(fp_line
			(start 1.524 -0.762)
			(end -1.524 -0.762)
			(stroke
				(width 0.1524)
				(type default)
			)
			(layer "B.SilkS")
		)
		(fp_line
			(start -1.524 -0.762)
			(end -1.524 0.762)
			(stroke
				(width 0.1524)
				(type default)
			)
			(layer "B.SilkS")
		)
		(fp_line
			(start 1.524 0.762)
			(end 1.524 -0.762)
			(stroke
				(width 0.1524)
				(type default)
			)
			(layer "B.SilkS")
		)
		(fp_line
			(start -1.524 0.762)
			(end 1.524 0.762)
			(stroke
				(width 0.1524)
				(type default)
			)
			(layer "B.SilkS")
		)
		(fp_line
			(start 1.1049 -0.724916)
			(end 1.1049 0.724916)
			(stroke
				(width 0.1)
				(type default)
			)
			(layer "B.Fab")
		)
		(fp_line
			(start -1.1049 -0.724916)
			(end 1.1049 -0.724916)
			(stroke
				(width 0.1)
				(type default)
			)
			(layer "B.Fab")
		)
		(fp_line
			(start 1.1049 0.724916)
			(end -1.1049 0.724916)
			(stroke
				(width 0.1)
				(type default)
			)
			(layer "B.Fab")
		)
		(fp_line
			(start -1.1049 0.724916)
			(end -1.1049 -0.724916)
			(stroke
				(width 0.1)
				(type default)
			)
			(layer "B.Fab")
		)
		(pad "1" smd rect
			(at 0.889 0 90)
			(size 1.016 1.27)
			(layers "B.Cu" "B.Mask" "B.Paste")
			(net "PVDDCR_SOC_P1")
		)
		(pad "2" smd rect
			(at -0.889 0 90)
			(size 1.016 1.27)
			(layers "B.Cu" "B.Mask" "B.Paste")
			(net "GND")
		)
	)
	(footprint ""
		(layer "B.Cu")
		(at 98.578924 -258.830318 180)
		(property "Reference" "C2109"
			(at 0 0 0)
			(layer "B.SilkS")
			(hide yes)
			(effects
				(font
					(size 1.27 1.27)
				)
				(justify mirror)
			)
		)
		(property "Value" ""
			(at 0 0 0)
			(layer "B.Fab")
			(effects
				(font
					(size 1.27 1.27)
				)
				(justify mirror)
			)
		)
		(duplicate_pad_numbers_are_jumpers no)
		(fp_line
			(start 0.7874 0.4064)
			(end 0.7874 -0.4064)
			(stroke
				(width 0.1524)
				(type default)
			)
			(layer "B.SilkS")
		)
		(fp_line
			(start 0.7874 -0.4064)
			(end -0.7874 -0.4064)
			(stroke
				(width 0.1524)
				(type default)
			)
			(layer "B.SilkS")
		)
		(fp_line
			(start -0.7874 0.4064)
			(end 0.7874 0.4064)
			(stroke
				(width 0.1524)
				(type default)
			)
			(layer "B.SilkS")
		)
		(fp_line
			(start -0.7874 -0.4064)
			(end -0.7874 0.4064)
			(stroke
				(width 0.1524)
				(type default)
			)
			(layer "B.SilkS")
		)
		(fp_line
			(start 0.67945 0.3048)
			(end 0.67945 -0.305054)
			(stroke
				(width 0.1)
				(type default)
			)
			(layer "B.Fab")
		)
		(fp_line
			(start 0.67945 -0.305054)
			(end 0.12065 -0.305054)
			(stroke
				(width 0.1)
				(type default)
			)
			(layer "B.Fab")
		)
		(fp_line
			(start 0.12065 0.3048)
			(end 0.67945 0.3048)
			(stroke
				(width 0.1)
				(type default)
			)
			(layer "B.Fab")
		)
		(fp_line
			(start 0.12065 0.2794)
			(end 0.12065 0.3048)
			(stroke
				(width 0.1)
				(type default)
			)
			(layer "B.Fab")
		)
		(fp_line
			(start 0.12065 -0.2794)
			(end -0.12065 -0.2794)
			(stroke
				(width 0.1)
				(type default)
			)
			(layer "B.Fab")
		)
		(fp_line
			(start 0.12065 -0.305054)
			(end 0.12065 -0.2794)
			(stroke
				(width 0.1)
				(type default)
			)
			(layer "B.Fab")
		)
		(fp_line
			(start -0.120396 0.3048)
			(end -0.120396 0.2794)
			(stroke
				(width 0.1)
				(type default)
			)
			(layer "B.Fab")
		)
		(fp_line
			(start -0.120396 0.2794)
			(end 0.12065 0.2794)
			(stroke
				(width 0.1)
				(type default)
			)
			(layer "B.Fab")
		)
		(fp_line
			(start -0.12065 -0.2794)
			(end -0.12065 -0.3048)
			(stroke
				(width 0.1)
				(type default)
			)
			(layer "B.Fab")
		)
		(fp_line
			(start -0.12065 -0.3048)
			(end -0.67945 -0.3048)
			(stroke
				(width 0.1)
				(type default)
			)
			(layer "B.Fab")
		)
		(fp_line
			(start -0.67945 0.3048)
			(end -0.120396 0.3048)
			(stroke
				(width 0.1)
				(type default)
			)
			(layer "B.Fab")
		)
		(fp_line
			(start -0.67945 -0.3048)
			(end -0.67945 0.3048)
			(stroke
				(width 0.1)
				(type default)
			)
			(layer "B.Fab")
		)
		(pad "1" smd circle
			(at 0.40005 0)
			(size 0 0)
			(layers "B.Cu" "B.Mask" "B.Paste")
			(net "PVDDIO_P1")
		)
		(pad "2" smd circle
			(at -0.40005 0)
			(size 0 0)
			(layers "B.Cu" "B.Mask" "B.Paste")
			(net "GND")
		)
	)
	(footprint ""
		(layer "B.Cu")
		(at 365.835692 -255.554988)
		(property "Reference" "C2152"
			(at 0 0 0)
			(layer "B.SilkS")
			(hide yes)
			(effects
				(font
					(size 1.27 1.27)
				)
				(justify mirror)
			)
		)
		(property "Value" ""
			(at 0 0 0)
			(layer "B.Fab")
			(effects
				(font
					(size 1.27 1.27)
				)
				(justify mirror)
			)
		)
		(duplicate_pad_numbers_are_jumpers no)
		(fp_line
			(start -0.7874 -0.4064)
			(end -0.7874 0.4064)
			(stroke
				(width 0.1524)
				(type default)
			)
			(layer "B.SilkS")
		)
		(fp_line
			(start -0.7874 0.4064)
			(end 0.7874 0.4064)
			(stroke
				(width 0.1524)
				(type default)
			)
			(layer "B.SilkS")
		)
		(fp_line
			(start 0.7874 -0.4064)
			(end -0.7874 -0.4064)
			(stroke
				(width 0.1524)
				(type default)
			)
			(layer "B.SilkS")
		)
		(fp_line
			(start 0.7874 0.4064)
			(end 0.7874 -0.4064)
			(stroke
				(width 0.1524)
				(type default)
			)
			(layer "B.SilkS")
		)
		(fp_line
			(start -0.67945 -0.3048)
			(end -0.67945 0.3048)
			(stroke
				(width 0.1)
				(type default)
			)
			(layer "B.Fab")
		)
		(fp_line
			(start -0.67945 0.3048)
			(end -0.120396 0.3048)
			(stroke
				(width 0.1)
				(type default)
			)
			(layer "B.Fab")
		)
		(fp_line
			(start -0.12065 -0.3048)
			(end -0.67945 -0.3048)
			(stroke
				(width 0.1)
				(type default)
			)
			(layer "B.Fab")
		)
		(fp_line
			(start -0.12065 -0.2794)
			(end -0.12065 -0.3048)
			(stroke
				(width 0.1)
				(type default)
			)
			(layer "B.Fab")
		)
		(fp_line
			(start -0.120396 0.2794)
			(end 0.12065 0.2794)
			(stroke
				(width 0.1)
				(type default)
			)
			(layer "B.Fab")
		)
		(fp_line
			(start -0.120396 0.3048)
			(end -0.120396 0.2794)
			(stroke
				(width 0.1)
				(type default)
			)
			(layer "B.Fab")
		)
		(fp_line
			(start 0.12065 -0.305054)
			(end 0.12065 -0.2794)
			(stroke
				(width 0.1)
				(type default)
			)
			(layer "B.Fab")
		)
		(fp_line
			(start 0.12065 -0.2794)
			(end -0.12065 -0.2794)
			(stroke
				(width 0.1)
				(type default)
			)
			(layer "B.Fab")
		)
		(fp_line
			(start 0.12065 0.2794)
			(end 0.12065 0.3048)
			(stroke
				(width 0.1)
				(type default)
			)
			(layer "B.Fab")
		)
		(fp_line
			(start 0.12065 0.3048)
			(end 0.67945 0.3048)
			(stroke
				(width 0.1)
				(type default)
			)
			(layer "B.Fab")
		)
		(fp_line
			(start 0.67945 -0.305054)
			(end 0.12065 -0.305054)
			(stroke
				(width 0.1)
				(type default)
			)
			(layer "B.Fab")
		)
		(fp_line
			(start 0.67945 0.3048)
			(end 0.67945 -0.305054)
			(stroke
				(width 0.1)
				(type default)
			)
			(layer "B.Fab")
		)
		(pad "1" smd circle
			(at 0.40005 0 180)
			(size 0 0)
			(layers "B.Cu" "B.Mask" "B.Paste")
			(net "PVDDCR_SOC_P0")
		)
		(pad "2" smd circle
			(at -0.40005 0 180)
			(size 0 0)
			(layers "B.Cu" "B.Mask" "B.Paste")
			(net "GND")
		)
	)
	(footprint ""
		(layer "B.Cu")
		(at 238.310928 -289.828732)
		(property "Reference" "C6758"
			(at 0 0 0)
			(layer "B.SilkS")
			(hide yes)
			(effects
				(font
					(size 1.27 1.27)
				)
				(justify mirror)
			)
		)
		(property "Value" ""
			(at 0 0 0)
			(layer "B.Fab")
			(effects
				(font
					(size 1.27 1.27)
				)
				(justify mirror)
			)
		)
		(duplicate_pad_numbers_are_jumpers no)
		(fp_line
			(start -0.7874 -0.4064)
			(end -0.7874 0.4064)
			(stroke
				(width 0.1524)
				(type default)
			)
			(layer "B.SilkS")
		)
		(fp_line
			(start -0.7874 0.4064)
			(end 0.7874 0.4064)
			(stroke
				(width 0.1524)
				(type default)
			)
			(layer "B.SilkS")
		)
		(fp_line
			(start 0.7874 -0.4064)
			(end -0.7874 -0.4064)
			(stroke
				(width 0.1524)
				(type default)
			)
			(layer "B.SilkS")
		)
		(fp_line
			(start 0.7874 0.4064)
			(end 0.7874 -0.4064)
			(stroke
				(width 0.1524)
				(type default)
			)
			(layer "B.SilkS")
		)
		(fp_line
			(start -0.67945 -0.3048)
			(end -0.67945 0.3048)
			(stroke
				(width 0.1)
				(type default)
			)
			(layer "B.Fab")
		)
		(fp_line
			(start -0.67945 0.3048)
			(end -0.120396 0.3048)
			(stroke
				(width 0.1)
				(type default)
			)
			(layer "B.Fab")
		)
		(fp_line
			(start -0.12065 -0.3048)
			(end -0.67945 -0.3048)
			(stroke
				(width 0.1)
				(type default)
			)
			(layer "B.Fab")
		)
		(fp_line
			(start -0.12065 -0.2794)
			(end -0.12065 -0.3048)
			(stroke
				(width 0.1)
				(type default)
			)
			(layer "B.Fab")
		)
		(fp_line
			(start -0.120396 0.2794)
			(end 0.12065 0.2794)
			(stroke
				(width 0.1)
				(type default)
			)
			(layer "B.Fab")
		)
		(fp_line
			(start -0.120396 0.3048)
			(end -0.120396 0.2794)
			(stroke
				(width 0.1)
				(type default)
			)
			(layer "B.Fab")
		)
		(fp_line
			(start 0.12065 -0.305054)
			(end 0.12065 -0.2794)
			(stroke
				(width 0.1)
				(type default)
			)
			(layer "B.Fab")
		)
		(fp_line
			(start 0.12065 -0.2794)
			(end -0.12065 -0.2794)
			(stroke
				(width 0.1)
				(type default)
			)
			(layer "B.Fab")
		)
		(fp_line
			(start 0.12065 0.2794)
			(end 0.12065 0.3048)
			(stroke
				(width 0.1)
				(type default)
			)
			(layer "B.Fab")
		)
		(fp_line
			(start 0.12065 0.3048)
			(end 0.67945 0.3048)
			(stroke
				(width 0.1)
				(type default)
			)
			(layer "B.Fab")
		)
		(fp_line
			(start 0.67945 -0.305054)
			(end 0.12065 -0.305054)
			(stroke
				(width 0.1)
				(type default)
			)
			(layer "B.Fab")
		)
		(fp_line
			(start 0.67945 0.3048)
			(end 0.67945 -0.305054)
			(stroke
				(width 0.1)
				(type default)
			)
			(layer "B.Fab")
		)
		(pad "1" smd circle
			(at 0.40005 0 180)
			(size 0 0)
			(layers "B.Cu" "B.Mask" "B.Paste")
			(net "FM_PWRGD_P1V8_RETIMER_CPU0")
		)
		(pad "2" smd circle
			(at -0.40005 0 180)
			(size 0 0)
			(layers "B.Cu" "B.Mask" "B.Paste")
			(net "GND")
		)
	)
	(footprint ""
		(layer "B.Cu")
		(at 206.429356 -378.682504 180)
		(property "Reference" "PR2524"
			(at 0 0 0)
			(layer "B.SilkS")
			(hide yes)
			(effects
				(font
					(size 1.27 1.27)
				)
				(justify mirror)
			)
		)
		(property "Value" ""
			(at 0 0 0)
			(layer "B.Fab")
			(effects
				(font
					(size 1.27 1.27)
				)
				(justify mirror)
			)
		)
		(duplicate_pad_numbers_are_jumpers no)
		(fp_line
			(start 0.7874 0.4064)
			(end 0.7874 -0.4064)
			(stroke
				(width 0.1524)
				(type default)
			)
			(layer "B.SilkS")
		)
		(fp_line
			(start 0.7874 -0.4064)
			(end -0.7874 -0.4064)
			(stroke
				(width 0.1524)
				(type default)
			)
			(layer "B.SilkS")
		)
		(fp_line
			(start -0.7874 0.4064)
			(end 0.7874 0.4064)
			(stroke
				(width 0.1524)
				(type default)
			)
			(layer "B.SilkS")
		)
		(fp_line
			(start -0.7874 -0.4064)
			(end -0.7874 0.4064)
			(stroke
				(width 0.1524)
				(type default)
			)
			(layer "B.SilkS")
		)
		(fp_line
			(start 0.67945 0.3048)
			(end 0.67945 -0.305054)
			(stroke
				(width 0.1)
				(type default)
			)
			(layer "B.Fab")
		)
		(fp_line
			(start 0.67945 -0.305054)
			(end 0.12065 -0.305054)
			(stroke
				(width 0.1)
				(type default)
			)
			(layer "B.Fab")
		)
		(fp_line
			(start 0.12065 0.3048)
			(end 0.67945 0.3048)
			(stroke
				(width 0.1)
				(type default)
			)
			(layer "B.Fab")
		)
		(fp_line
			(start 0.12065 0.2794)
			(end 0.12065 0.3048)
			(stroke
				(width 0.1)
				(type default)
			)
			(layer "B.Fab")
		)
		(fp_line
			(start 0.12065 -0.2794)
			(end -0.12065 -0.2794)
			(stroke
				(width 0.1)
				(type default)
			)
			(layer "B.Fab")
		)
		(fp_line
			(start 0.12065 -0.305054)
			(end 0.12065 -0.2794)
			(stroke
				(width 0.1)
				(type default)
			)
			(layer "B.Fab")
		)
		(fp_line
			(start -0.120396 0.3048)
			(end -0.120396 0.2794)
			(stroke
				(width 0.1)
				(type default)
			)
			(layer "B.Fab")
		)
		(fp_line
			(start -0.120396 0.2794)
			(end 0.12065 0.2794)
			(stroke
				(width 0.1)
				(type default)
			)
			(layer "B.Fab")
		)
		(fp_line
			(start -0.12065 -0.2794)
			(end -0.12065 -0.3048)
			(stroke
				(width 0.1)
				(type default)
			)
			(layer "B.Fab")
		)
		(fp_line
			(start -0.12065 -0.3048)
			(end -0.67945 -0.3048)
			(stroke
				(width 0.1)
				(type default)
			)
			(layer "B.Fab")
		)
		(fp_line
			(start -0.67945 0.3048)
			(end -0.120396 0.3048)
			(stroke
				(width 0.1)
				(type default)
			)
			(layer "B.Fab")
		)
		(fp_line
			(start -0.67945 -0.3048)
			(end -0.67945 0.3048)
			(stroke
				(width 0.1)
				(type default)
			)
			(layer "B.Fab")
		)
		(pad "1" smd circle
			(at 0.40005 0)
			(size 0 0)
			(layers "B.Cu" "B.Mask" "B.Paste")
			(net "P12V_HSC_SENSE2_N")
		)
		(pad "2" smd circle
			(at -0.40005 0)
			(size 0 0)
			(layers "B.Cu" "B.Mask" "B.Paste")
			(net "P12V_HSC_SENSE2_R1_N")
		)
	)
	(footprint ""
		(layer "B.Cu")
		(at 187.511944 -117.442996 90)
		(property "Reference" "C1128"
			(at 0 0 90)
			(layer "B.SilkS")
			(hide yes)
			(effects
				(font
					(size 1.27 1.27)
				)
				(justify mirror)
			)
		)
		(property "Value" ""
			(at 0 0 90)
			(layer "B.Fab")
			(effects
				(font
					(size 1.27 1.27)
				)
				(justify mirror)
			)
		)
		(duplicate_pad_numbers_are_jumpers no)
		(fp_line
			(start 0.69215 -0.2921)
			(end -0.69215 -0.2921)
			(stroke
				(width 0.1524)
				(type default)
			)
			(layer "B.SilkS")
		)
		(fp_line
			(start -0.69215 -0.2921)
			(end -0.69215 0.2921)
			(stroke
				(width 0.1524)
				(type default)
			)
			(layer "B.SilkS")
		)
		(fp_line
			(start 0.69215 0.2921)
			(end 0.69215 -0.2921)
			(stroke
				(width 0.1524)
				(type default)
			)
			(layer "B.SilkS")
		)
		(fp_line
			(start -0.69215 0.2921)
			(end 0.69215 0.2921)
			(stroke
				(width 0.1524)
				(type default)
			)
			(layer "B.SilkS")
		)
		(fp_line
			(start 0.51435 -0.2794)
			(end -0.51435 -0.2794)
			(stroke
				(width 0.1)
				(type default)
			)
			(layer "B.Fab")
		)
		(fp_line
			(start -0.51435 -0.2794)
			(end -0.51435 0.2794)
			(stroke
				(width 0.1)
				(type default)
			)
			(layer "B.Fab")
		)
		(fp_line
			(start 0.51435 0.2794)
			(end 0.51435 -0.2794)
			(stroke
				(width 0.1)
				(type default)
			)
			(layer "B.Fab")
		)
		(fp_line
			(start -0.51435 0.2794)
			(end 0.51435 0.2794)
			(stroke
				(width 0.1)
				(type default)
			)
			(layer "B.Fab")
		)
		(pad "1" smd circle
			(at 0.40005 0 270)
			(size 0 0)
			(layers "B.Cu" "B.Mask" "B.Paste")
			(net "P1V8_AUX")
		)
		(pad "2" smd circle
			(at -0.40005 0 270)
			(size 0 0)
			(layers "B.Cu" "B.Mask" "B.Paste")
			(net "GND")
		)
		(zone
			(layer "B.Cu")
			(hatch none 0.5)
			(connect_pads
				(clearance 0)
			)
			(min_thickness 0.25)
			(keepout
				(tracks not_allowed)
				(vias allowed)
				(pads allowed)
				(copperpour not_allowed)
				(footprints allowed)
			)
			(placement
				(enabled no)
				(sheetname "")
			)
			(fill
				(thermal_gap 0.5)
				(thermal_bridge_width 0.5)
				(island_removal_mode 0)
			)
			(polygon
				(pts
					(xy 187.365894 -117.342666) (xy 187.365894 -117.542056) (xy 187.42406 -117.633496) (xy 187.599574 -117.633496)
					(xy 187.65774 -117.542056) (xy 187.65774 -117.342666) (xy 187.599574 -117.252496) (xy 187.424314 -117.252496)
				)
			)
		)
	)
	(footprint ""
		(layer "B.Cu")
		(at 213.285578 -326.509888)
		(property "Reference" "C1095"
			(at 0 0 0)
			(layer "B.SilkS")
			(hide yes)
			(effects
				(font
					(size 1.27 1.27)
				)
				(justify mirror)
			)
		)
		(property "Value" ""
			(at 0 0 0)
			(layer "B.Fab")
			(effects
				(font
					(size 1.27 1.27)
				)
				(justify mirror)
			)
		)
		(duplicate_pad_numbers_are_jumpers no)
		(fp_line
			(start -0.7874 -0.4064)
			(end -0.7874 0.4064)
			(stroke
				(width 0.1524)
				(type default)
			)
			(layer "B.SilkS")
		)
		(fp_line
			(start -0.7874 0.4064)
			(end 0.7874 0.4064)
			(stroke
				(width 0.1524)
				(type default)
			)
			(layer "B.SilkS")
		)
		(fp_line
			(start 0.7874 -0.4064)
			(end -0.7874 -0.4064)
			(stroke
				(width 0.1524)
				(type default)
			)
			(layer "B.SilkS")
		)
		(fp_line
			(start 0.7874 0.4064)
			(end 0.7874 -0.4064)
			(stroke
				(width 0.1524)
				(type default)
			)
			(layer "B.SilkS")
		)
		(fp_line
			(start -0.67945 -0.3048)
			(end -0.67945 0.3048)
			(stroke
				(width 0.1)
				(type default)
			)
			(layer "B.Fab")
		)
		(fp_line
			(start -0.67945 0.3048)
			(end -0.120396 0.3048)
			(stroke
				(width 0.1)
				(type default)
			)
			(layer "B.Fab")
		)
		(fp_line
			(start -0.12065 -0.3048)
			(end -0.67945 -0.3048)
			(stroke
				(width 0.1)
				(type default)
			)
			(layer "B.Fab")
		)
		(fp_line
			(start -0.12065 -0.2794)
			(end -0.12065 -0.3048)
			(stroke
				(width 0.1)
				(type default)
			)
			(layer "B.Fab")
		)
		(fp_line
			(start -0.120396 0.2794)
			(end 0.12065 0.2794)
			(stroke
				(width 0.1)
				(type default)
			)
			(layer "B.Fab")
		)
		(fp_line
			(start -0.120396 0.3048)
			(end -0.120396 0.2794)
			(stroke
				(width 0.1)
				(type default)
			)
			(layer "B.Fab")
		)
		(fp_line
			(start 0.12065 -0.305054)
			(end 0.12065 -0.2794)
			(stroke
				(width 0.1)
				(type default)
			)
			(layer "B.Fab")
		)
		(fp_line
			(start 0.12065 -0.2794)
			(end -0.12065 -0.2794)
			(stroke
				(width 0.1)
				(type default)
			)
			(layer "B.Fab")
		)
		(fp_line
			(start 0.12065 0.2794)
			(end 0.12065 0.3048)
			(stroke
				(width 0.1)
				(type default)
			)
			(layer "B.Fab")
		)
		(fp_line
			(start 0.12065 0.3048)
			(end 0.67945 0.3048)
			(stroke
				(width 0.1)
				(type default)
			)
			(layer "B.Fab")
		)
		(fp_line
			(start 0.67945 -0.305054)
			(end 0.12065 -0.305054)
			(stroke
				(width 0.1)
				(type default)
			)
			(layer "B.Fab")
		)
		(fp_line
			(start 0.67945 0.3048)
			(end 0.67945 -0.305054)
			(stroke
				(width 0.1)
				(type default)
			)
			(layer "B.Fab")
		)
		(pad "1" smd circle
			(at 0.40005 0 180)
			(size 0 0)
			(layers "B.Cu" "B.Mask" "B.Paste")
			(net "P3V3_ADC128_2_VCC")
		)
		(pad "2" smd circle
			(at -0.40005 0 180)
			(size 0 0)
			(layers "B.Cu" "B.Mask" "B.Paste")
			(net "GND")
		)
	)
	(footprint ""
		(layer "B.Cu")
		(at 206.429356 -385.136136 180)
		(property "Reference" "PR2521"
			(at 0 0 0)
			(layer "B.SilkS")
			(hide yes)
			(effects
				(font
					(size 1.27 1.27)
				)
				(justify mirror)
			)
		)
		(property "Value" ""
			(at 0 0 0)
			(layer "B.Fab")
			(effects
				(font
					(size 1.27 1.27)
				)
				(justify mirror)
			)
		)
		(duplicate_pad_numbers_are_jumpers no)
		(fp_line
			(start 0.7874 0.4064)
			(end 0.7874 -0.4064)
			(stroke
				(width 0.1524)
				(type default)
			)
			(layer "B.SilkS")
		)
		(fp_line
			(start 0.7874 -0.4064)
			(end -0.7874 -0.4064)
			(stroke
				(width 0.1524)
				(type default)
			)
			(layer "B.SilkS")
		)
		(fp_line
			(start -0.7874 0.4064)
			(end 0.7874 0.4064)
			(stroke
				(width 0.1524)
				(type default)
			)
			(layer "B.SilkS")
		)
		(fp_line
			(start -0.7874 -0.4064)
			(end -0.7874 0.4064)
			(stroke
				(width 0.1524)
				(type default)
			)
			(layer "B.SilkS")
		)
		(fp_line
			(start 0.67945 0.3048)
			(end 0.67945 -0.305054)
			(stroke
				(width 0.1)
				(type default)
			)
			(layer "B.Fab")
		)
		(fp_line
			(start 0.67945 -0.305054)
			(end 0.12065 -0.305054)
			(stroke
				(width 0.1)
				(type default)
			)
			(layer "B.Fab")
		)
		(fp_line
			(start 0.12065 0.3048)
			(end 0.67945 0.3048)
			(stroke
				(width 0.1)
				(type default)
			)
			(layer "B.Fab")
		)
		(fp_line
			(start 0.12065 0.2794)
			(end 0.12065 0.3048)
			(stroke
				(width 0.1)
				(type default)
			)
			(layer "B.Fab")
		)
		(fp_line
			(start 0.12065 -0.2794)
			(end -0.12065 -0.2794)
			(stroke
				(width 0.1)
				(type default)
			)
			(layer "B.Fab")
		)
		(fp_line
			(start 0.12065 -0.305054)
			(end 0.12065 -0.2794)
			(stroke
				(width 0.1)
				(type default)
			)
			(layer "B.Fab")
		)
		(fp_line
			(start -0.120396 0.3048)
			(end -0.120396 0.2794)
			(stroke
				(width 0.1)
				(type default)
			)
			(layer "B.Fab")
		)
		(fp_line
			(start -0.120396 0.2794)
			(end 0.12065 0.2794)
			(stroke
				(width 0.1)
				(type default)
			)
			(layer "B.Fab")
		)
		(fp_line
			(start -0.12065 -0.2794)
			(end -0.12065 -0.3048)
			(stroke
				(width 0.1)
				(type default)
			)
			(layer "B.Fab")
		)
		(fp_line
			(start -0.12065 -0.3048)
			(end -0.67945 -0.3048)
			(stroke
				(width 0.1)
				(type default)
			)
			(layer "B.Fab")
		)
		(fp_line
			(start -0.67945 0.3048)
			(end -0.120396 0.3048)
			(stroke
				(width 0.1)
				(type default)
			)
			(layer "B.Fab")
		)
		(fp_line
			(start -0.67945 -0.3048)
			(end -0.67945 0.3048)
			(stroke
				(width 0.1)
				(type default)
			)
			(layer "B.Fab")
		)
		(pad "1" smd circle
			(at 0.40005 0)
			(size 0 0)
			(layers "B.Cu" "B.Mask" "B.Paste")
			(net "P12V_HSC_SENSE2_P")
		)
		(pad "2" smd circle
			(at -0.40005 0)
			(size 0 0)
			(layers "B.Cu" "B.Mask" "B.Paste")
			(net "P12V_HSC_SENSE2_R2_P")
		)
	)
	(footprint ""
		(layer "B.Cu")
		(at 393.617958 -324.862952)
		(property "Reference" "R470"
			(at 0 0 0)
			(layer "B.SilkS")
			(hide yes)
			(effects
				(font
					(size 1.27 1.27)
				)
				(justify mirror)
			)
		)
		(property "Value" ""
			(at 0 0 0)
			(layer "B.Fab")
			(effects
				(font
					(size 1.27 1.27)
				)
				(justify mirror)
			)
		)
		(duplicate_pad_numbers_are_jumpers no)
		(fp_line
			(start -0.7874 -0.4064)
			(end -0.7874 0.4064)
			(stroke
				(width 0.1524)
				(type default)
			)
			(layer "B.SilkS")
		)
		(fp_line
			(start -0.7874 0.4064)
			(end 0.7874 0.4064)
			(stroke
				(width 0.1524)
				(type default)
			)
			(layer "B.SilkS")
		)
		(fp_line
			(start 0.7874 -0.4064)
			(end -0.7874 -0.4064)
			(stroke
				(width 0.1524)
				(type default)
			)
			(layer "B.SilkS")
		)
		(fp_line
			(start 0.7874 0.4064)
			(end 0.7874 -0.4064)
			(stroke
				(width 0.1524)
				(type default)
			)
			(layer "B.SilkS")
		)
		(fp_line
			(start -0.67945 -0.3048)
			(end -0.67945 0.3048)
			(stroke
				(width 0.1)
				(type default)
			)
			(layer "B.Fab")
		)
		(fp_line
			(start -0.67945 0.3048)
			(end -0.120396 0.3048)
			(stroke
				(width 0.1)
				(type default)
			)
			(layer "B.Fab")
		)
		(fp_line
			(start -0.12065 -0.3048)
			(end -0.67945 -0.3048)
			(stroke
				(width 0.1)
				(type default)
			)
			(layer "B.Fab")
		)
		(fp_line
			(start -0.12065 -0.2794)
			(end -0.12065 -0.3048)
			(stroke
				(width 0.1)
				(type default)
			)
			(layer "B.Fab")
		)
		(fp_line
			(start -0.120396 0.2794)
			(end 0.12065 0.2794)
			(stroke
				(width 0.1)
				(type default)
			)
			(layer "B.Fab")
		)
		(fp_line
			(start -0.120396 0.3048)
			(end -0.120396 0.2794)
			(stroke
				(width 0.1)
				(type default)
			)
			(layer "B.Fab")
		)
		(fp_line
			(start 0.12065 -0.305054)
			(end 0.12065 -0.2794)
			(stroke
				(width 0.1)
				(type default)
			)
			(layer "B.Fab")
		)
		(fp_line
			(start 0.12065 -0.2794)
			(end -0.12065 -0.2794)
			(stroke
				(width 0.1)
				(type default)
			)
			(layer "B.Fab")
		)
		(fp_line
			(start 0.12065 0.2794)
			(end 0.12065 0.3048)
			(stroke
				(width 0.1)
				(type default)
			)
			(layer "B.Fab")
		)
		(fp_line
			(start 0.12065 0.3048)
			(end 0.67945 0.3048)
			(stroke
				(width 0.1)
				(type default)
			)
			(layer "B.Fab")
		)
		(fp_line
			(start 0.67945 -0.305054)
			(end 0.12065 -0.305054)
			(stroke
				(width 0.1)
				(type default)
			)
			(layer "B.Fab")
		)
		(fp_line
			(start 0.67945 0.3048)
			(end 0.67945 -0.305054)
			(stroke
				(width 0.1)
				(type default)
			)
			(layer "B.Fab")
		)
		(pad "1" smd circle
			(at 0.40005 0 180)
			(size 0 0)
			(layers "B.Cu" "B.Mask" "B.Paste")
			(net "ESPI_CPU0_D2")
		)
		(pad "2" smd circle
			(at -0.40005 0 180)
			(size 0 0)
			(layers "B.Cu" "B.Mask" "B.Paste")
			(net "ESPI_CPU0_R_D2")
		)
	)
	(footprint ""
		(layer "B.Cu")
		(at 280.492454 -190.94831 180)
		(property "Reference" "R294"
			(at 0 0 0)
			(layer "B.SilkS")
			(hide yes)
			(effects
				(font
					(size 1.27 1.27)
				)
				(justify mirror)
			)
		)
		(property "Value" ""
			(at 0 0 0)
			(layer "B.Fab")
			(effects
				(font
					(size 1.27 1.27)
				)
				(justify mirror)
			)
		)
		(duplicate_pad_numbers_are_jumpers no)
		(fp_line
			(start 0.7874 0.4064)
			(end 0.7874 -0.4064)
			(stroke
				(width 0.1524)
				(type default)
			)
			(layer "B.SilkS")
		)
		(fp_line
			(start 0.7874 -0.4064)
			(end -0.7874 -0.4064)
			(stroke
				(width 0.1524)
				(type default)
			)
			(layer "B.SilkS")
		)
		(fp_line
			(start -0.7874 0.4064)
			(end 0.7874 0.4064)
			(stroke
				(width 0.1524)
				(type default)
			)
			(layer "B.SilkS")
		)
		(fp_line
			(start -0.7874 -0.4064)
			(end -0.7874 0.4064)
			(stroke
				(width 0.1524)
				(type default)
			)
			(layer "B.SilkS")
		)
		(fp_line
			(start 0.67945 0.3048)
			(end 0.67945 -0.305054)
			(stroke
				(width 0.1)
				(type default)
			)
			(layer "B.Fab")
		)
		(fp_line
			(start 0.67945 -0.305054)
			(end 0.12065 -0.305054)
			(stroke
				(width 0.1)
				(type default)
			)
			(layer "B.Fab")
		)
		(fp_line
			(start 0.12065 0.3048)
			(end 0.67945 0.3048)
			(stroke
				(width 0.1)
				(type default)
			)
			(layer "B.Fab")
		)
		(fp_line
			(start 0.12065 0.2794)
			(end 0.12065 0.3048)
			(stroke
				(width 0.1)
				(type default)
			)
			(layer "B.Fab")
		)
		(fp_line
			(start 0.12065 -0.2794)
			(end -0.12065 -0.2794)
			(stroke
				(width 0.1)
				(type default)
			)
			(layer "B.Fab")
		)
		(fp_line
			(start 0.12065 -0.305054)
			(end 0.12065 -0.2794)
			(stroke
				(width 0.1)
				(type default)
			)
			(layer "B.Fab")
		)
		(fp_line
			(start -0.120396 0.3048)
			(end -0.120396 0.2794)
			(stroke
				(width 0.1)
				(type default)
			)
			(layer "B.Fab")
		)
		(fp_line
			(start -0.120396 0.2794)
			(end 0.12065 0.2794)
			(stroke
				(width 0.1)
				(type default)
			)
			(layer "B.Fab")
		)
		(fp_line
			(start -0.12065 -0.2794)
			(end -0.12065 -0.3048)
			(stroke
				(width 0.1)
				(type default)
			)
			(layer "B.Fab")
		)
		(fp_line
			(start -0.12065 -0.3048)
			(end -0.67945 -0.3048)
			(stroke
				(width 0.1)
				(type default)
			)
			(layer "B.Fab")
		)
		(fp_line
			(start -0.67945 0.3048)
			(end -0.120396 0.3048)
			(stroke
				(width 0.1)
				(type default)
			)
			(layer "B.Fab")
		)
		(fp_line
			(start -0.67945 -0.3048)
			(end -0.67945 0.3048)
			(stroke
				(width 0.1)
				(type default)
			)
			(layer "B.Fab")
		)
		(pad "1" smd circle
			(at 0.40005 0)
			(size 0 0)
			(layers "B.Cu" "B.Mask" "B.Paste")
			(net "PWRGD_CHD_CPU0_DIMM")
		)
		(pad "2" smd circle
			(at -0.40005 0)
			(size 0 0)
			(layers "B.Cu" "B.Mask" "B.Paste")
			(net "PWRGD_CHAF_CPU0")
		)
	)
	(footprint ""
		(layer "B.Cu")
		(at 81.257648 -182.656734 -90)
		(property "Reference" "PC266_1"
			(at 0 0 90)
			(layer "B.SilkS")
			(hide yes)
			(effects
				(font
					(size 1.27 1.27)
				)
				(justify mirror)
			)
		)
		(property "Value" ""
			(at 0 0 90)
			(layer "B.Fab")
			(effects
				(font
					(size 1.27 1.27)
				)
				(justify mirror)
			)
		)
		(duplicate_pad_numbers_are_jumpers no)
		(fp_line
			(start -1.524 0.762)
			(end 1.524 0.762)
			(stroke
				(width 0.1524)
				(type default)
			)
			(layer "B.SilkS")
		)
		(fp_line
			(start 1.524 0.762)
			(end 1.524 -0.762)
			(stroke
				(width 0.1524)
				(type default)
			)
			(layer "B.SilkS")
		)
		(fp_line
			(start -1.524 -0.762)
			(end -1.524 0.762)
			(stroke
				(width 0.1524)
				(type default)
			)
			(layer "B.SilkS")
		)
		(fp_line
			(start 1.524 -0.762)
			(end -1.524 -0.762)
			(stroke
				(width 0.1524)
				(type default)
			)
			(layer "B.SilkS")
		)
		(fp_line
			(start -1.1049 0.724916)
			(end -1.1049 -0.724916)
			(stroke
				(width 0.1)
				(type default)
			)
			(layer "B.Fab")
		)
		(fp_line
			(start 1.1049 0.724916)
			(end -1.1049 0.724916)
			(stroke
				(width 0.1)
				(type default)
			)
			(layer "B.Fab")
		)
		(fp_line
			(start -1.1049 -0.724916)
			(end 1.1049 -0.724916)
			(stroke
				(width 0.1)
				(type default)
			)
			(layer "B.Fab")
		)
		(fp_line
			(start 1.1049 -0.724916)
			(end 1.1049 0.724916)
			(stroke
				(width 0.1)
				(type default)
			)
			(layer "B.Fab")
		)
		(pad "1" smd rect
			(at 0.889 0 270)
			(size 1.016 1.27)
			(layers "B.Cu" "B.Mask" "B.Paste")
			(net "SW_P12V_AUX_PVDDCR_CPU0_P1_FLT")
		)
		(pad "2" smd rect
			(at -0.889 0 270)
			(size 1.016 1.27)
			(layers "B.Cu" "B.Mask" "B.Paste")
			(net "GND")
		)
	)
	(footprint ""
		(layer "B.Cu")
		(at 374.986042 -181.684676 90)
		(property "Reference" "PR319"
			(at 0 0 90)
			(layer "B.SilkS")
			(hide yes)
			(effects
				(font
					(size 1.27 1.27)
				)
				(justify mirror)
			)
		)
		(property "Value" ""
			(at 0 0 90)
			(layer "B.Fab")
			(effects
				(font
					(size 1.27 1.27)
				)
				(justify mirror)
			)
		)
		(duplicate_pad_numbers_are_jumpers no)
		(fp_line
			(start 0.7874 -0.4064)
			(end -0.7874 -0.4064)
			(stroke
				(width 0.1524)
				(type default)
			)
			(layer "B.SilkS")
		)
		(fp_line
			(start -0.7874 -0.4064)
			(end -0.7874 0.4064)
			(stroke
				(width 0.1524)
				(type default)
			)
			(layer "B.SilkS")
		)
		(fp_line
			(start 0.7874 0.4064)
			(end 0.7874 -0.4064)
			(stroke
				(width 0.1524)
				(type default)
			)
			(layer "B.SilkS")
		)
		(fp_line
			(start -0.7874 0.4064)
			(end 0.7874 0.4064)
			(stroke
				(width 0.1524)
				(type default)
			)
			(layer "B.SilkS")
		)
		(fp_line
			(start 0.67945 -0.305054)
			(end 0.12065 -0.305054)
			(stroke
				(width 0.1)
				(type default)
			)
			(layer "B.Fab")
		)
		(fp_line
			(start 0.12065 -0.305054)
			(end 0.12065 -0.2794)
			(stroke
				(width 0.1)
				(type default)
			)
			(layer "B.Fab")
		)
		(fp_line
			(start -0.12065 -0.3048)
			(end -0.67945 -0.3048)
			(stroke
				(width 0.1)
				(type default)
			)
			(layer "B.Fab")
		)
		(fp_line
			(start -0.67945 -0.3048)
			(end -0.67945 0.3048)
			(stroke
				(width 0.1)
				(type default)
			)
			(layer "B.Fab")
		)
		(fp_line
			(start 0.12065 -0.2794)
			(end -0.12065 -0.2794)
			(stroke
				(width 0.1)
				(type default)
			)
			(layer "B.Fab")
		)
		(fp_line
			(start -0.12065 -0.2794)
			(end -0.12065 -0.3048)
			(stroke
				(width 0.1)
				(type default)
			)
			(layer "B.Fab")
		)
		(fp_line
			(start 0.12065 0.2794)
			(end 0.12065 0.3048)
			(stroke
				(width 0.1)
				(type default)
			)
			(layer "B.Fab")
		)
		(fp_line
			(start -0.120396 0.2794)
			(end 0.12065 0.2794)
			(stroke
				(width 0.1)
				(type default)
			)
			(layer "B.Fab")
		)
		(fp_line
			(start 0.67945 0.3048)
			(end 0.67945 -0.305054)
			(stroke
				(width 0.1)
				(type default)
			)
			(layer "B.Fab")
		)
		(fp_line
			(start 0.12065 0.3048)
			(end 0.67945 0.3048)
			(stroke
				(width 0.1)
				(type default)
			)
			(layer "B.Fab")
		)
		(fp_line
			(start -0.120396 0.3048)
			(end -0.120396 0.2794)
			(stroke
				(width 0.1)
				(type default)
			)
			(layer "B.Fab")
		)
		(fp_line
			(start -0.67945 0.3048)
			(end -0.120396 0.3048)
			(stroke
				(width 0.1)
				(type default)
			)
			(layer "B.Fab")
		)
		(pad "1" smd circle
			(at 0.40005 0 270)
			(size 0 0)
			(layers "B.Cu" "B.Mask" "B.Paste")
			(net "PVDDCR_CPU0_P0_PVCC")
		)
		(pad "2" smd circle
			(at -0.40005 0 270)
			(size 0 0)
			(layers "B.Cu" "B.Mask" "B.Paste")
			(net "PVDDCR_CPU0_P0_VCC2")
		)
	)
	(footprint ""
		(layer "B.Cu")
		(at 101.033834 -250.892564 180)
		(property "Reference" "C2673"
			(at 0 0 0)
			(layer "B.SilkS")
			(hide yes)
			(effects
				(font
					(size 1.27 1.27)
				)
				(justify mirror)
			)
		)
		(property "Value" ""
			(at 0 0 0)
			(layer "B.Fab")
			(effects
				(font
					(size 1.27 1.27)
				)
				(justify mirror)
			)
		)
		(duplicate_pad_numbers_are_jumpers no)
		(fp_line
			(start 0.7874 0.4064)
			(end 0.7874 -0.4064)
			(stroke
				(width 0.1524)
				(type default)
			)
			(layer "B.SilkS")
		)
		(fp_line
			(start 0.7874 -0.4064)
			(end -0.7874 -0.4064)
			(stroke
				(width 0.1524)
				(type default)
			)
			(layer "B.SilkS")
		)
		(fp_line
			(start -0.7874 0.4064)
			(end 0.7874 0.4064)
			(stroke
				(width 0.1524)
				(type default)
			)
			(layer "B.SilkS")
		)
		(fp_line
			(start -0.7874 -0.4064)
			(end -0.7874 0.4064)
			(stroke
				(width 0.1524)
				(type default)
			)
			(layer "B.SilkS")
		)
		(fp_line
			(start 0.67945 0.3048)
			(end 0.67945 -0.305054)
			(stroke
				(width 0.1)
				(type default)
			)
			(layer "B.Fab")
		)
		(fp_line
			(start 0.67945 -0.305054)
			(end 0.12065 -0.305054)
			(stroke
				(width 0.1)
				(type default)
			)
			(layer "B.Fab")
		)
		(fp_line
			(start 0.12065 0.3048)
			(end 0.67945 0.3048)
			(stroke
				(width 0.1)
				(type default)
			)
			(layer "B.Fab")
		)
		(fp_line
			(start 0.12065 0.2794)
			(end 0.12065 0.3048)
			(stroke
				(width 0.1)
				(type default)
			)
			(layer "B.Fab")
		)
		(fp_line
			(start 0.12065 -0.2794)
			(end -0.12065 -0.2794)
			(stroke
				(width 0.1)
				(type default)
			)
			(layer "B.Fab")
		)
		(fp_line
			(start 0.12065 -0.305054)
			(end 0.12065 -0.2794)
			(stroke
				(width 0.1)
				(type default)
			)
			(layer "B.Fab")
		)
		(fp_line
			(start -0.120396 0.3048)
			(end -0.120396 0.2794)
			(stroke
				(width 0.1)
				(type default)
			)
			(layer "B.Fab")
		)
		(fp_line
			(start -0.120396 0.2794)
			(end 0.12065 0.2794)
			(stroke
				(width 0.1)
				(type default)
			)
			(layer "B.Fab")
		)
		(fp_line
			(start -0.12065 -0.2794)
			(end -0.12065 -0.3048)
			(stroke
				(width 0.1)
				(type default)
			)
			(layer "B.Fab")
		)
		(fp_line
			(start -0.12065 -0.3048)
			(end -0.67945 -0.3048)
			(stroke
				(width 0.1)
				(type default)
			)
			(layer "B.Fab")
		)
		(fp_line
			(start -0.67945 0.3048)
			(end -0.120396 0.3048)
			(stroke
				(width 0.1)
				(type default)
			)
			(layer "B.Fab")
		)
		(fp_line
			(start -0.67945 -0.3048)
			(end -0.67945 0.3048)
			(stroke
				(width 0.1)
				(type default)
			)
			(layer "B.Fab")
		)
		(pad "1" smd circle
			(at 0.40005 0)
			(size 0 0)
			(layers "B.Cu" "B.Mask" "B.Paste")
			(net "PVDD18_S5_P1")
		)
		(pad "2" smd circle
			(at -0.40005 0)
			(size 0 0)
			(layers "B.Cu" "B.Mask" "B.Paste")
			(net "GND")
		)
	)
	(footprint ""
		(layer "B.Cu")
		(at 214.884 -332.74)
		(property "Reference" "R6778"
			(at 0 0 0)
			(layer "B.SilkS")
			(hide yes)
			(effects
				(font
					(size 1.27 1.27)
				)
				(justify mirror)
			)
		)
		(property "Value" ""
			(at 0 0 0)
			(layer "B.Fab")
			(effects
				(font
					(size 1.27 1.27)
				)
				(justify mirror)
			)
		)
		(duplicate_pad_numbers_are_jumpers no)
		(fp_line
			(start -0.32512 -0.175006)
			(end -0.32512 0.175006)
			(stroke
				(width 0.1)
				(type default)
			)
			(layer "B.Fab")
		)
		(fp_line
			(start -0.32512 0.175006)
			(end 0.32512 0.175006)
			(stroke
				(width 0.1)
				(type default)
			)
			(layer "B.Fab")
		)
		(fp_line
			(start 0.32512 -0.175006)
			(end -0.32512 -0.175006)
			(stroke
				(width 0.1)
				(type default)
			)
			(layer "B.Fab")
		)
		(fp_line
			(start 0.32512 0.175006)
			(end 0.32512 -0.175006)
			(stroke
				(width 0.1)
				(type default)
			)
			(layer "B.Fab")
		)
		(pad "1" smd rect
			(at 0.2667 0 180)
			(size 0.3048 0.381)
			(layers "B.Cu" "B.Mask" "B.Paste")
			(net "RST_SMB_RT_R1_N")
		)
		(pad "2" smd rect
			(at -0.2667 0)
			(size 0.3048 0.381)
			(layers "B.Cu" "B.Mask" "B.Paste")
			(net "GND")
		)
	)
	(footprint ""
		(layer "B.Cu")
		(at 341.475314 -310.974486)
		(property "Reference" "PR59"
			(at 0 0 0)
			(layer "B.SilkS")
			(hide yes)
			(effects
				(font
					(size 1.27 1.27)
				)
				(justify mirror)
			)
		)
		(property "Value" ""
			(at 0 0 0)
			(layer "B.Fab")
			(effects
				(font
					(size 1.27 1.27)
				)
				(justify mirror)
			)
		)
		(duplicate_pad_numbers_are_jumpers no)
		(fp_line
			(start -0.7874 -0.4064)
			(end -0.7874 0.4064)
			(stroke
				(width 0.1524)
				(type default)
			)
			(layer "B.SilkS")
		)
		(fp_line
			(start -0.7874 0.4064)
			(end 0.7874 0.4064)
			(stroke
				(width 0.1524)
				(type default)
			)
			(layer "B.SilkS")
		)
		(fp_line
			(start 0.7874 -0.4064)
			(end -0.7874 -0.4064)
			(stroke
				(width 0.1524)
				(type default)
			)
			(layer "B.SilkS")
		)
		(fp_line
			(start 0.7874 0.4064)
			(end 0.7874 -0.4064)
			(stroke
				(width 0.1524)
				(type default)
			)
			(layer "B.SilkS")
		)
		(fp_line
			(start -0.67945 -0.3048)
			(end -0.67945 0.3048)
			(stroke
				(width 0.1)
				(type default)
			)
			(layer "B.Fab")
		)
		(fp_line
			(start -0.67945 0.3048)
			(end -0.120396 0.3048)
			(stroke
				(width 0.1)
				(type default)
			)
			(layer "B.Fab")
		)
		(fp_line
			(start -0.12065 -0.3048)
			(end -0.67945 -0.3048)
			(stroke
				(width 0.1)
				(type default)
			)
			(layer "B.Fab")
		)
		(fp_line
			(start -0.12065 -0.2794)
			(end -0.12065 -0.3048)
			(stroke
				(width 0.1)
				(type default)
			)
			(layer "B.Fab")
		)
		(fp_line
			(start -0.120396 0.2794)
			(end 0.12065 0.2794)
			(stroke
				(width 0.1)
				(type default)
			)
			(layer "B.Fab")
		)
		(fp_line
			(start -0.120396 0.3048)
			(end -0.120396 0.2794)
			(stroke
				(width 0.1)
				(type default)
			)
			(layer "B.Fab")
		)
		(fp_line
			(start 0.12065 -0.305054)
			(end 0.12065 -0.2794)
			(stroke
				(width 0.1)
				(type default)
			)
			(layer "B.Fab")
		)
		(fp_line
			(start 0.12065 -0.2794)
			(end -0.12065 -0.2794)
			(stroke
				(width 0.1)
				(type default)
			)
			(layer "B.Fab")
		)
		(fp_line
			(start 0.12065 0.2794)
			(end 0.12065 0.3048)
			(stroke
				(width 0.1)
				(type default)
			)
			(layer "B.Fab")
		)
		(fp_line
			(start 0.12065 0.3048)
			(end 0.67945 0.3048)
			(stroke
				(width 0.1)
				(type default)
			)
			(layer "B.Fab")
		)
		(fp_line
			(start 0.67945 -0.305054)
			(end 0.12065 -0.305054)
			(stroke
				(width 0.1)
				(type default)
			)
			(layer "B.Fab")
		)
		(fp_line
			(start 0.67945 0.3048)
			(end 0.67945 -0.305054)
			(stroke
				(width 0.1)
				(type default)
			)
			(layer "B.Fab")
		)
		(pad "1" smd circle
			(at 0.40005 0 180)
			(size 0 0)
			(layers "B.Cu" "B.Mask" "B.Paste")
			(net "SVID_PVDDCR_CPU1_P0_SVC_R")
		)
		(pad "2" smd circle
			(at -0.40005 0 180)
			(size 0 0)
			(layers "B.Cu" "B.Mask" "B.Paste")
			(net "SVID_PVDDCR_CPU1_P0_SVC")
		)
	)
	(footprint ""
		(layer "B.Cu")
		(at 93.170502 -205.14945 90)
		(property "Reference" "R534"
			(at 0 0 90)
			(layer "B.SilkS")
			(hide yes)
			(effects
				(font
					(size 1.27 1.27)
				)
				(justify mirror)
			)
		)
		(property "Value" ""
			(at 0 0 90)
			(layer "B.Fab")
			(effects
				(font
					(size 1.27 1.27)
				)
				(justify mirror)
			)
		)
		(duplicate_pad_numbers_are_jumpers no)
		(fp_line
			(start 0.7874 -0.4064)
			(end -0.7874 -0.4064)
			(stroke
				(width 0.1524)
				(type default)
			)
			(layer "B.SilkS")
		)
		(fp_line
			(start -0.7874 -0.4064)
			(end -0.7874 0.4064)
			(stroke
				(width 0.1524)
				(type default)
			)
			(layer "B.SilkS")
		)
		(fp_line
			(start 0.7874 0.4064)
			(end 0.7874 -0.4064)
			(stroke
				(width 0.1524)
				(type default)
			)
			(layer "B.SilkS")
		)
		(fp_line
			(start -0.7874 0.4064)
			(end 0.7874 0.4064)
			(stroke
				(width 0.1524)
				(type default)
			)
			(layer "B.SilkS")
		)
		(fp_line
			(start 0.67945 -0.305054)
			(end 0.12065 -0.305054)
			(stroke
				(width 0.1)
				(type default)
			)
			(layer "B.Fab")
		)
		(fp_line
			(start 0.12065 -0.305054)
			(end 0.12065 -0.2794)
			(stroke
				(width 0.1)
				(type default)
			)
			(layer "B.Fab")
		)
		(fp_line
			(start -0.12065 -0.3048)
			(end -0.67945 -0.3048)
			(stroke
				(width 0.1)
				(type default)
			)
			(layer "B.Fab")
		)
		(fp_line
			(start -0.67945 -0.3048)
			(end -0.67945 0.3048)
			(stroke
				(width 0.1)
				(type default)
			)
			(layer "B.Fab")
		)
		(fp_line
			(start 0.12065 -0.2794)
			(end -0.12065 -0.2794)
			(stroke
				(width 0.1)
				(type default)
			)
			(layer "B.Fab")
		)
		(fp_line
			(start -0.12065 -0.2794)
			(end -0.12065 -0.3048)
			(stroke
				(width 0.1)
				(type default)
			)
			(layer "B.Fab")
		)
		(fp_line
			(start 0.12065 0.2794)
			(end 0.12065 0.3048)
			(stroke
				(width 0.1)
				(type default)
			)
			(layer "B.Fab")
		)
		(fp_line
			(start -0.120396 0.2794)
			(end 0.12065 0.2794)
			(stroke
				(width 0.1)
				(type default)
			)
			(layer "B.Fab")
		)
		(fp_line
			(start 0.67945 0.3048)
			(end 0.67945 -0.305054)
			(stroke
				(width 0.1)
				(type default)
			)
			(layer "B.Fab")
		)
		(fp_line
			(start 0.12065 0.3048)
			(end 0.67945 0.3048)
			(stroke
				(width 0.1)
				(type default)
			)
			(layer "B.Fab")
		)
		(fp_line
			(start -0.120396 0.3048)
			(end -0.120396 0.2794)
			(stroke
				(width 0.1)
				(type default)
			)
			(layer "B.Fab")
		)
		(fp_line
			(start -0.67945 0.3048)
			(end -0.120396 0.3048)
			(stroke
				(width 0.1)
				(type default)
			)
			(layer "B.Fab")
		)
		(pad "1" smd circle
			(at 0.40005 0 270)
			(size 0 0)
			(layers "B.Cu" "B.Mask" "B.Paste")
			(net "CPU1_BP3")
		)
		(pad "2" smd circle
			(at -0.40005 0 270)
			(size 0 0)
			(layers "B.Cu" "B.Mask" "B.Paste")
			(net "PVDD18_S5_P1")
		)
	)
	(footprint ""
		(layer "B.Cu")
		(at 188.087 -143.256 180)
		(property "Reference" "R8033"
			(at 0 0 0)
			(layer "B.SilkS")
			(hide yes)
			(effects
				(font
					(size 1.27 1.27)
				)
				(justify mirror)
			)
		)
		(property "Value" ""
			(at 0 0 0)
			(layer "B.Fab")
			(effects
				(font
					(size 1.27 1.27)
				)
				(justify mirror)
			)
		)
		(duplicate_pad_numbers_are_jumpers no)
		(fp_line
			(start 0.7874 0.4064)
			(end 0.7874 -0.4064)
			(stroke
				(width 0.1524)
				(type default)
			)
			(layer "B.SilkS")
		)
		(fp_line
			(start 0.7874 -0.4064)
			(end -0.7874 -0.4064)
			(stroke
				(width 0.1524)
				(type default)
			)
			(layer "B.SilkS")
		)
		(fp_line
			(start -0.7874 0.4064)
			(end 0.7874 0.4064)
			(stroke
				(width 0.1524)
				(type default)
			)
			(layer "B.SilkS")
		)
		(fp_line
			(start -0.7874 -0.4064)
			(end -0.7874 0.4064)
			(stroke
				(width 0.1524)
				(type default)
			)
			(layer "B.SilkS")
		)
		(fp_line
			(start 0.67945 0.3048)
			(end 0.67945 -0.305054)
			(stroke
				(width 0.1)
				(type default)
			)
			(layer "B.Fab")
		)
		(fp_line
			(start 0.67945 -0.305054)
			(end 0.12065 -0.305054)
			(stroke
				(width 0.1)
				(type default)
			)
			(layer "B.Fab")
		)
		(fp_line
			(start 0.12065 0.3048)
			(end 0.67945 0.3048)
			(stroke
				(width 0.1)
				(type default)
			)
			(layer "B.Fab")
		)
		(fp_line
			(start 0.12065 0.2794)
			(end 0.12065 0.3048)
			(stroke
				(width 0.1)
				(type default)
			)
			(layer "B.Fab")
		)
		(fp_line
			(start 0.12065 -0.2794)
			(end -0.12065 -0.2794)
			(stroke
				(width 0.1)
				(type default)
			)
			(layer "B.Fab")
		)
		(fp_line
			(start 0.12065 -0.305054)
			(end 0.12065 -0.2794)
			(stroke
				(width 0.1)
				(type default)
			)
			(layer "B.Fab")
		)
		(fp_line
			(start -0.120396 0.3048)
			(end -0.120396 0.2794)
			(stroke
				(width 0.1)
				(type default)
			)
			(layer "B.Fab")
		)
		(fp_line
			(start -0.120396 0.2794)
			(end 0.12065 0.2794)
			(stroke
				(width 0.1)
				(type default)
			)
			(layer "B.Fab")
		)
		(fp_line
			(start -0.12065 -0.2794)
			(end -0.12065 -0.3048)
			(stroke
				(width 0.1)
				(type default)
			)
			(layer "B.Fab")
		)
		(fp_line
			(start -0.12065 -0.3048)
			(end -0.67945 -0.3048)
			(stroke
				(width 0.1)
				(type default)
			)
			(layer "B.Fab")
		)
		(fp_line
			(start -0.67945 0.3048)
			(end -0.120396 0.3048)
			(stroke
				(width 0.1)
				(type default)
			)
			(layer "B.Fab")
		)
		(fp_line
			(start -0.67945 -0.3048)
			(end -0.67945 0.3048)
			(stroke
				(width 0.1)
				(type default)
			)
			(layer "B.Fab")
		)
		(pad "1" smd circle
			(at 0.40005 0)
			(size 0 0)
			(layers "B.Cu" "B.Mask" "B.Paste")
			(net "FM_ESPI_CPU0_ALERT_R_SEL")
		)
		(pad "2" smd circle
			(at -0.40005 0)
			(size 0 0)
			(layers "B.Cu" "B.Mask" "B.Paste")
			(net "GND")
		)
	)
	(footprint ""
		(layer "B.Cu")
		(at 413.819086 -398.942052 90)
		(property "Reference" "C805"
			(at 0 0 90)
			(layer "B.SilkS")
			(hide yes)
			(effects
				(font
					(size 1.27 1.27)
				)
				(justify mirror)
			)
		)
		(property "Value" ""
			(at 0 0 90)
			(layer "B.Fab")
			(effects
				(font
					(size 1.27 1.27)
				)
				(justify mirror)
			)
		)
		(duplicate_pad_numbers_are_jumpers no)
		(fp_line
			(start 0.7874 -0.4064)
			(end -0.7874 -0.4064)
			(stroke
				(width 0.1524)
				(type default)
			)
			(layer "B.SilkS")
		)
		(fp_line
			(start -0.7874 -0.4064)
			(end -0.7874 0.4064)
			(stroke
				(width 0.1524)
				(type default)
			)
			(layer "B.SilkS")
		)
		(fp_line
			(start 0.7874 0.4064)
			(end 0.7874 -0.4064)
			(stroke
				(width 0.1524)
				(type default)
			)
			(layer "B.SilkS")
		)
		(fp_line
			(start -0.7874 0.4064)
			(end 0.7874 0.4064)
			(stroke
				(width 0.1524)
				(type default)
			)
			(layer "B.SilkS")
		)
		(fp_line
			(start 0.67945 -0.305054)
			(end 0.12065 -0.305054)
			(stroke
				(width 0.1)
				(type default)
			)
			(layer "B.Fab")
		)
		(fp_line
			(start 0.12065 -0.305054)
			(end 0.12065 -0.2794)
			(stroke
				(width 0.1)
				(type default)
			)
			(layer "B.Fab")
		)
		(fp_line
			(start -0.12065 -0.3048)
			(end -0.67945 -0.3048)
			(stroke
				(width 0.1)
				(type default)
			)
			(layer "B.Fab")
		)
		(fp_line
			(start -0.67945 -0.3048)
			(end -0.67945 0.3048)
			(stroke
				(width 0.1)
				(type default)
			)
			(layer "B.Fab")
		)
		(fp_line
			(start 0.12065 -0.2794)
			(end -0.12065 -0.2794)
			(stroke
				(width 0.1)
				(type default)
			)
			(layer "B.Fab")
		)
		(fp_line
			(start -0.12065 -0.2794)
			(end -0.12065 -0.3048)
			(stroke
				(width 0.1)
				(type default)
			)
			(layer "B.Fab")
		)
		(fp_line
			(start 0.12065 0.2794)
			(end 0.12065 0.3048)
			(stroke
				(width 0.1)
				(type default)
			)
			(layer "B.Fab")
		)
		(fp_line
			(start -0.120396 0.2794)
			(end 0.12065 0.2794)
			(stroke
				(width 0.1)
				(type default)
			)
			(layer "B.Fab")
		)
		(fp_line
			(start 0.67945 0.3048)
			(end 0.67945 -0.305054)
			(stroke
				(width 0.1)
				(type default)
			)
			(layer "B.Fab")
		)
		(fp_line
			(start 0.12065 0.3048)
			(end 0.67945 0.3048)
			(stroke
				(width 0.1)
				(type default)
			)
			(layer "B.Fab")
		)
		(fp_line
			(start -0.120396 0.3048)
			(end -0.120396 0.2794)
			(stroke
				(width 0.1)
				(type default)
			)
			(layer "B.Fab")
		)
		(fp_line
			(start -0.67945 0.3048)
			(end -0.120396 0.3048)
			(stroke
				(width 0.1)
				(type default)
			)
			(layer "B.Fab")
		)
		(pad "1" smd circle
			(at 0.40005 0 270)
			(size 0 0)
			(layers "B.Cu" "B.Mask" "B.Paste")
			(net "P0V9_CPU0_RT_2D")
		)
		(pad "2" smd circle
			(at -0.40005 0 270)
			(size 0 0)
			(layers "B.Cu" "B.Mask" "B.Paste")
			(net "GND")
		)
	)
	(footprint ""
		(layer "B.Cu")
		(at 369.587272 -399.722848 -90)
		(property "Reference" "C1054"
			(at 0 0 90)
			(layer "B.SilkS")
			(hide yes)
			(effects
				(font
					(size 1.27 1.27)
				)
				(justify mirror)
			)
		)
		(property "Value" ""
			(at 0 0 90)
			(layer "B.Fab")
			(effects
				(font
					(size 1.27 1.27)
				)
				(justify mirror)
			)
		)
		(duplicate_pad_numbers_are_jumpers no)
		(fp_line
			(start -0.7874 0.4064)
			(end 0.7874 0.4064)
			(stroke
				(width 0.1524)
				(type default)
			)
			(layer "B.SilkS")
		)
		(fp_line
			(start 0.7874 0.4064)
			(end 0.7874 -0.4064)
			(stroke
				(width 0.1524)
				(type default)
			)
			(layer "B.SilkS")
		)
		(fp_line
			(start -0.7874 -0.4064)
			(end -0.7874 0.4064)
			(stroke
				(width 0.1524)
				(type default)
			)
			(layer "B.SilkS")
		)
		(fp_line
			(start 0.7874 -0.4064)
			(end -0.7874 -0.4064)
			(stroke
				(width 0.1524)
				(type default)
			)
			(layer "B.SilkS")
		)
		(fp_line
			(start -0.67945 0.3048)
			(end -0.120396 0.3048)
			(stroke
				(width 0.1)
				(type default)
			)
			(layer "B.Fab")
		)
		(fp_line
			(start -0.120396 0.3048)
			(end -0.120396 0.2794)
			(stroke
				(width 0.1)
				(type default)
			)
			(layer "B.Fab")
		)
		(fp_line
			(start 0.12065 0.3048)
			(end 0.67945 0.3048)
			(stroke
				(width 0.1)
				(type default)
			)
			(layer "B.Fab")
		)
		(fp_line
			(start 0.67945 0.3048)
			(end 0.67945 -0.305054)
			(stroke
				(width 0.1)
				(type default)
			)
			(layer "B.Fab")
		)
		(fp_line
			(start -0.120396 0.2794)
			(end 0.12065 0.2794)
			(stroke
				(width 0.1)
				(type default)
			)
			(layer "B.Fab")
		)
		(fp_line
			(start 0.12065 0.2794)
			(end 0.12065 0.3048)
			(stroke
				(width 0.1)
				(type default)
			)
			(layer "B.Fab")
		)
		(fp_line
			(start -0.12065 -0.2794)
			(end -0.12065 -0.3048)
			(stroke
				(width 0.1)
				(type default)
			)
			(layer "B.Fab")
		)
		(fp_line
			(start 0.12065 -0.2794)
			(end -0.12065 -0.2794)
			(stroke
				(width 0.1)
				(type default)
			)
			(layer "B.Fab")
		)
		(fp_line
			(start -0.67945 -0.3048)
			(end -0.67945 0.3048)
			(stroke
				(width 0.1)
				(type default)
			)
			(layer "B.Fab")
		)
		(fp_line
			(start -0.12065 -0.3048)
			(end -0.67945 -0.3048)
			(stroke
				(width 0.1)
				(type default)
			)
			(layer "B.Fab")
		)
		(fp_line
			(start 0.12065 -0.305054)
			(end 0.12065 -0.2794)
			(stroke
				(width 0.1)
				(type default)
			)
			(layer "B.Fab")
		)
		(fp_line
			(start 0.67945 -0.305054)
			(end 0.12065 -0.305054)
			(stroke
				(width 0.1)
				(type default)
			)
			(layer "B.Fab")
		)
		(pad "1" smd circle
			(at 0.40005 0 90)
			(size 0 0)
			(layers "B.Cu" "B.Mask" "B.Paste")
			(net "P0V9_CPU0_RT3_2A")
		)
		(pad "2" smd circle
			(at -0.40005 0 90)
			(size 0 0)
			(layers "B.Cu" "B.Mask" "B.Paste")
			(net "GND")
		)
	)
	(footprint ""
		(layer "B.Cu")
		(at 147.261834 -203.679552 -90)
		(property "Reference" "C234"
			(at 0 0 90)
			(layer "B.SilkS")
			(hide yes)
			(effects
				(font
					(size 1.27 1.27)
				)
				(justify mirror)
			)
		)
		(property "Value" ""
			(at 0 0 90)
			(layer "B.Fab")
			(effects
				(font
					(size 1.27 1.27)
				)
				(justify mirror)
			)
		)
		(duplicate_pad_numbers_are_jumpers no)
		(fp_line
			(start -0.7874 0.4064)
			(end 0.7874 0.4064)
			(stroke
				(width 0.1524)
				(type default)
			)
			(layer "B.SilkS")
		)
		(fp_line
			(start 0.7874 0.4064)
			(end 0.7874 -0.4064)
			(stroke
				(width 0.1524)
				(type default)
			)
			(layer "B.SilkS")
		)
		(fp_line
			(start -0.7874 -0.4064)
			(end -0.7874 0.4064)
			(stroke
				(width 0.1524)
				(type default)
			)
			(layer "B.SilkS")
		)
		(fp_line
			(start 0.7874 -0.4064)
			(end -0.7874 -0.4064)
			(stroke
				(width 0.1524)
				(type default)
			)
			(layer "B.SilkS")
		)
		(fp_line
			(start -0.67945 0.3048)
			(end -0.120396 0.3048)
			(stroke
				(width 0.1)
				(type default)
			)
			(layer "B.Fab")
		)
		(fp_line
			(start -0.120396 0.3048)
			(end -0.120396 0.2794)
			(stroke
				(width 0.1)
				(type default)
			)
			(layer "B.Fab")
		)
		(fp_line
			(start 0.12065 0.3048)
			(end 0.67945 0.3048)
			(stroke
				(width 0.1)
				(type default)
			)
			(layer "B.Fab")
		)
		(fp_line
			(start 0.67945 0.3048)
			(end 0.67945 -0.305054)
			(stroke
				(width 0.1)
				(type default)
			)
			(layer "B.Fab")
		)
		(fp_line
			(start -0.120396 0.2794)
			(end 0.12065 0.2794)
			(stroke
				(width 0.1)
				(type default)
			)
			(layer "B.Fab")
		)
		(fp_line
			(start 0.12065 0.2794)
			(end 0.12065 0.3048)
			(stroke
				(width 0.1)
				(type default)
			)
			(layer "B.Fab")
		)
		(fp_line
			(start -0.12065 -0.2794)
			(end -0.12065 -0.3048)
			(stroke
				(width 0.1)
				(type default)
			)
			(layer "B.Fab")
		)
		(fp_line
			(start 0.12065 -0.2794)
			(end -0.12065 -0.2794)
			(stroke
				(width 0.1)
				(type default)
			)
			(layer "B.Fab")
		)
		(fp_line
			(start -0.67945 -0.3048)
			(end -0.67945 0.3048)
			(stroke
				(width 0.1)
				(type default)
			)
			(layer "B.Fab")
		)
		(fp_line
			(start -0.12065 -0.3048)
			(end -0.67945 -0.3048)
			(stroke
				(width 0.1)
				(type default)
			)
			(layer "B.Fab")
		)
		(fp_line
			(start 0.12065 -0.305054)
			(end 0.12065 -0.2794)
			(stroke
				(width 0.1)
				(type default)
			)
			(layer "B.Fab")
		)
		(fp_line
			(start 0.67945 -0.305054)
			(end 0.12065 -0.305054)
			(stroke
				(width 0.1)
				(type default)
			)
			(layer "B.Fab")
		)
		(pad "1" smd circle
			(at 0.40005 0 90)
			(size 0 0)
			(layers "B.Cu" "B.Mask" "B.Paste")
			(net "JTAG_CPU1_TMS")
		)
		(pad "2" smd circle
			(at -0.40005 0 90)
			(size 0 0)
			(layers "B.Cu" "B.Mask" "B.Paste")
			(net "GND")
		)
	)
	(footprint ""
		(layer "B.Cu")
		(at 421.090344 -392.684762 -90)
		(property "Reference" "C987"
			(at 0 0 90)
			(layer "B.SilkS")
			(hide yes)
			(effects
				(font
					(size 1.27 1.27)
				)
				(justify mirror)
			)
		)
		(property "Value" ""
			(at 0 0 90)
			(layer "B.Fab")
			(effects
				(font
					(size 1.27 1.27)
				)
				(justify mirror)
			)
		)
		(duplicate_pad_numbers_are_jumpers no)
		(fp_line
			(start -0.299974 0.150114)
			(end 0.299974 0.150114)
			(stroke
				(width 0.1)
				(type default)
			)
			(layer "B.Fab")
		)
		(fp_line
			(start 0.299974 0.150114)
			(end 0.299974 -0.150114)
			(stroke
				(width 0.1)
				(type default)
			)
			(layer "B.Fab")
		)
		(fp_line
			(start -0.299974 -0.150114)
			(end -0.299974 0.150114)
			(stroke
				(width 0.1)
				(type default)
			)
			(layer "B.Fab")
		)
		(fp_line
			(start 0.299974 -0.150114)
			(end -0.299974 -0.150114)
			(stroke
				(width 0.1)
				(type default)
			)
			(layer "B.Fab")
		)
		(pad "1" smd rect
			(at 0.2667 0 90)
			(size 0.3048 0.381)
			(layers "B.Cu" "B.Mask" "B.Paste")
			(net "P0V9_CPU0_RT2_2A")
		)
		(pad "2" smd rect
			(at -0.2667 0 90)
			(size 0.3048 0.381)
			(layers "B.Cu" "B.Mask" "B.Paste")
			(net "GND")
		)
	)
	(footprint ""
		(layer "B.Cu")
		(at 197.98665 -193.996564)
		(property "Reference" "C176"
			(at 0 0 0)
			(layer "B.SilkS")
			(hide yes)
			(effects
				(font
					(size 1.27 1.27)
				)
				(justify mirror)
			)
		)
		(property "Value" ""
			(at 0 0 0)
			(layer "B.Fab")
			(effects
				(font
					(size 1.27 1.27)
				)
				(justify mirror)
			)
		)
		(duplicate_pad_numbers_are_jumpers no)
		(fp_line
			(start -0.7874 -0.4064)
			(end -0.7874 0.4064)
			(stroke
				(width 0.1524)
				(type default)
			)
			(layer "B.SilkS")
		)
		(fp_line
			(start -0.7874 0.4064)
			(end 0.7874 0.4064)
			(stroke
				(width 0.1524)
				(type default)
			)
			(layer "B.SilkS")
		)
		(fp_line
			(start 0.7874 -0.4064)
			(end -0.7874 -0.4064)
			(stroke
				(width 0.1524)
				(type default)
			)
			(layer "B.SilkS")
		)
		(fp_line
			(start 0.7874 0.4064)
			(end 0.7874 -0.4064)
			(stroke
				(width 0.1524)
				(type default)
			)
			(layer "B.SilkS")
		)
		(fp_line
			(start -0.67945 -0.3048)
			(end -0.67945 0.3048)
			(stroke
				(width 0.1)
				(type default)
			)
			(layer "B.Fab")
		)
		(fp_line
			(start -0.67945 0.3048)
			(end -0.120396 0.3048)
			(stroke
				(width 0.1)
				(type default)
			)
			(layer "B.Fab")
		)
		(fp_line
			(start -0.12065 -0.3048)
			(end -0.67945 -0.3048)
			(stroke
				(width 0.1)
				(type default)
			)
			(layer "B.Fab")
		)
		(fp_line
			(start -0.12065 -0.2794)
			(end -0.12065 -0.3048)
			(stroke
				(width 0.1)
				(type default)
			)
			(layer "B.Fab")
		)
		(fp_line
			(start -0.120396 0.2794)
			(end 0.12065 0.2794)
			(stroke
				(width 0.1)
				(type default)
			)
			(layer "B.Fab")
		)
		(fp_line
			(start -0.120396 0.3048)
			(end -0.120396 0.2794)
			(stroke
				(width 0.1)
				(type default)
			)
			(layer "B.Fab")
		)
		(fp_line
			(start 0.12065 -0.305054)
			(end 0.12065 -0.2794)
			(stroke
				(width 0.1)
				(type default)
			)
			(layer "B.Fab")
		)
		(fp_line
			(start 0.12065 -0.2794)
			(end -0.12065 -0.2794)
			(stroke
				(width 0.1)
				(type default)
			)
			(layer "B.Fab")
		)
		(fp_line
			(start 0.12065 0.2794)
			(end 0.12065 0.3048)
			(stroke
				(width 0.1)
				(type default)
			)
			(layer "B.Fab")
		)
		(fp_line
			(start 0.12065 0.3048)
			(end 0.67945 0.3048)
			(stroke
				(width 0.1)
				(type default)
			)
			(layer "B.Fab")
		)
		(fp_line
			(start 0.67945 -0.305054)
			(end 0.12065 -0.305054)
			(stroke
				(width 0.1)
				(type default)
			)
			(layer "B.Fab")
		)
		(fp_line
			(start 0.67945 0.3048)
			(end 0.67945 -0.305054)
			(stroke
				(width 0.1)
				(type default)
			)
			(layer "B.Fab")
		)
		(pad "1" smd circle
			(at 0.40005 0 180)
			(size 0 0)
			(layers "B.Cu" "B.Mask" "B.Paste")
			(net "P3V3_AUX")
		)
		(pad "2" smd circle
			(at -0.40005 0 180)
			(size 0 0)
			(layers "B.Cu" "B.Mask" "B.Paste")
			(net "GND")
		)
	)
	(footprint ""
		(layer "B.Cu")
		(at 339.506052 -395.148562 90)
		(property "Reference" "C607"
			(at 0 0 90)
			(layer "B.SilkS")
			(hide yes)
			(effects
				(font
					(size 1.27 1.27)
				)
				(justify mirror)
			)
		)
		(property "Value" ""
			(at 0 0 90)
			(layer "B.Fab")
			(effects
				(font
					(size 1.27 1.27)
				)
				(justify mirror)
			)
		)
		(duplicate_pad_numbers_are_jumpers no)
		(fp_line
			(start 0.299974 -0.150114)
			(end -0.299974 -0.150114)
			(stroke
				(width 0.1)
				(type default)
			)
			(layer "B.Fab")
		)
		(fp_line
			(start -0.299974 -0.150114)
			(end -0.299974 0.150114)
			(stroke
				(width 0.1)
				(type default)
			)
			(layer "B.Fab")
		)
		(fp_line
			(start 0.299974 0.150114)
			(end 0.299974 -0.150114)
			(stroke
				(width 0.1)
				(type default)
			)
			(layer "B.Fab")
		)
		(fp_line
			(start -0.299974 0.150114)
			(end 0.299974 0.150114)
			(stroke
				(width 0.1)
				(type default)
			)
			(layer "B.Fab")
		)
		(pad "1" smd rect
			(at 0.2667 0 270)
			(size 0.3048 0.381)
			(layers "B.Cu" "B.Mask" "B.Paste")
			(net "P0V9_CPU0_RT1_2A")
		)
		(pad "2" smd rect
			(at -0.2667 0 270)
			(size 0.3048 0.381)
			(layers "B.Cu" "B.Mask" "B.Paste")
			(net "GND")
		)
	)
	(footprint ""
		(layer "B.Cu")
		(at 164.465 -426.4152 -90)
		(property "Reference" "R1430"
			(at 0 0 90)
			(layer "B.SilkS")
			(hide yes)
			(effects
				(font
					(size 1.27 1.27)
				)
				(justify mirror)
			)
		)
		(property "Value" ""
			(at 0 0 90)
			(layer "B.Fab")
			(effects
				(font
					(size 1.27 1.27)
				)
				(justify mirror)
			)
		)
		(duplicate_pad_numbers_are_jumpers no)
		(fp_line
			(start -0.32512 0.175006)
			(end 0.32512 0.175006)
			(stroke
				(width 0.1)
				(type default)
			)
			(layer "B.Fab")
		)
		(fp_line
			(start 0.32512 0.175006)
			(end 0.32512 -0.175006)
			(stroke
				(width 0.1)
				(type default)
			)
			(layer "B.Fab")
		)
		(fp_line
			(start -0.32512 -0.175006)
			(end -0.32512 0.175006)
			(stroke
				(width 0.1)
				(type default)
			)
			(layer "B.Fab")
		)
		(fp_line
			(start 0.32512 -0.175006)
			(end -0.32512 -0.175006)
			(stroke
				(width 0.1)
				(type default)
			)
			(layer "B.Fab")
		)
		(pad "1" smd rect
			(at 0.2667 0 90)
			(size 0.3048 0.381)
			(layers "B.Cu" "B.Mask" "B.Paste")
			(net "JTAG_TCK_RT_CPU1_P3")
		)
		(pad "2" smd rect
			(at -0.2667 0 270)
			(size 0.3048 0.381)
			(layers "B.Cu" "B.Mask" "B.Paste")
			(net "GND")
		)
	)
	(footprint ""
		(layer "B.Cu")
		(at 309.518304 -396.393162 -90)
		(property "Reference" "C522"
			(at 0 0 90)
			(layer "B.SilkS")
			(hide yes)
			(effects
				(font
					(size 1.27 1.27)
				)
				(justify mirror)
			)
		)
		(property "Value" ""
			(at 0 0 90)
			(layer "B.Fab")
			(effects
				(font
					(size 1.27 1.27)
				)
				(justify mirror)
			)
		)
		(duplicate_pad_numbers_are_jumpers no)
		(fp_line
			(start -0.299974 0.150114)
			(end 0.299974 0.150114)
			(stroke
				(width 0.1)
				(type default)
			)
			(layer "B.Fab")
		)
		(fp_line
			(start 0.299974 0.150114)
			(end 0.299974 -0.150114)
			(stroke
				(width 0.1)
				(type default)
			)
			(layer "B.Fab")
		)
		(fp_line
			(start -0.299974 -0.150114)
			(end -0.299974 0.150114)
			(stroke
				(width 0.1)
				(type default)
			)
			(layer "B.Fab")
		)
		(fp_line
			(start 0.299974 -0.150114)
			(end -0.299974 -0.150114)
			(stroke
				(width 0.1)
				(type default)
			)
			(layer "B.Fab")
		)
		(pad "1" smd rect
			(at 0.2667 0 90)
			(size 0.3048 0.381)
			(layers "B.Cu" "B.Mask" "B.Paste")
			(net "P0V9_CPU0_RT_2D")
		)
		(pad "2" smd rect
			(at -0.2667 0 90)
			(size 0.3048 0.381)
			(layers "B.Cu" "B.Mask" "B.Paste")
			(net "GND")
		)
	)
	(footprint ""
		(layer "B.Cu")
		(at 213.79688 -54.447948 90)
		(property "Reference" "R3751"
			(at 0 0 90)
			(layer "B.SilkS")
			(hide yes)
			(effects
				(font
					(size 1.27 1.27)
				)
				(justify mirror)
			)
		)
		(property "Value" ""
			(at 0 0 90)
			(layer "B.Fab")
			(effects
				(font
					(size 1.27 1.27)
				)
				(justify mirror)
			)
		)
		(duplicate_pad_numbers_are_jumpers no)
		(fp_line
			(start 0.7874 -0.4064)
			(end -0.7874 -0.4064)
			(stroke
				(width 0.1524)
				(type default)
			)
			(layer "B.SilkS")
		)
		(fp_line
			(start -0.7874 -0.4064)
			(end -0.7874 0.4064)
			(stroke
				(width 0.1524)
				(type default)
			)
			(layer "B.SilkS")
		)
		(fp_line
			(start 0.7874 0.4064)
			(end 0.7874 -0.4064)
			(stroke
				(width 0.1524)
				(type default)
			)
			(layer "B.SilkS")
		)
		(fp_line
			(start -0.7874 0.4064)
			(end 0.7874 0.4064)
			(stroke
				(width 0.1524)
				(type default)
			)
			(layer "B.SilkS")
		)
		(fp_line
			(start 0.67945 -0.305054)
			(end 0.12065 -0.305054)
			(stroke
				(width 0.1)
				(type default)
			)
			(layer "B.Fab")
		)
		(fp_line
			(start 0.12065 -0.305054)
			(end 0.12065 -0.2794)
			(stroke
				(width 0.1)
				(type default)
			)
			(layer "B.Fab")
		)
		(fp_line
			(start -0.12065 -0.3048)
			(end -0.67945 -0.3048)
			(stroke
				(width 0.1)
				(type default)
			)
			(layer "B.Fab")
		)
		(fp_line
			(start -0.67945 -0.3048)
			(end -0.67945 0.3048)
			(stroke
				(width 0.1)
				(type default)
			)
			(layer "B.Fab")
		)
		(fp_line
			(start 0.12065 -0.2794)
			(end -0.12065 -0.2794)
			(stroke
				(width 0.1)
				(type default)
			)
			(layer "B.Fab")
		)
		(fp_line
			(start -0.12065 -0.2794)
			(end -0.12065 -0.3048)
			(stroke
				(width 0.1)
				(type default)
			)
			(layer "B.Fab")
		)
		(fp_line
			(start 0.12065 0.2794)
			(end 0.12065 0.3048)
			(stroke
				(width 0.1)
				(type default)
			)
			(layer "B.Fab")
		)
		(fp_line
			(start -0.120396 0.2794)
			(end 0.12065 0.2794)
			(stroke
				(width 0.1)
				(type default)
			)
			(layer "B.Fab")
		)
		(fp_line
			(start 0.67945 0.3048)
			(end 0.67945 -0.305054)
			(stroke
				(width 0.1)
				(type default)
			)
			(layer "B.Fab")
		)
		(fp_line
			(start 0.12065 0.3048)
			(end 0.67945 0.3048)
			(stroke
				(width 0.1)
				(type default)
			)
			(layer "B.Fab")
		)
		(fp_line
			(start -0.120396 0.3048)
			(end -0.120396 0.2794)
			(stroke
				(width 0.1)
				(type default)
			)
			(layer "B.Fab")
		)
		(fp_line
			(start -0.67945 0.3048)
			(end -0.120396 0.3048)
			(stroke
				(width 0.1)
				(type default)
			)
			(layer "B.Fab")
		)
		(pad "1" smd circle
			(at 0.40005 0 270)
			(size 0 0)
			(layers "B.Cu" "B.Mask" "B.Paste")
			(net "INA230_2_A0")
		)
		(pad "2" smd circle
			(at -0.40005 0 270)
			(size 0 0)
			(layers "B.Cu" "B.Mask" "B.Paste")
			(net "SMB_INA230_2_3V3AUX_SDA_R1")
		)
	)
	(footprint ""
		(layer "B.Cu")
		(at 265.506454 -190.82131 180)
		(property "Reference" "R296"
			(at 0 0 0)
			(layer "B.SilkS")
			(hide yes)
			(effects
				(font
					(size 1.27 1.27)
				)
				(justify mirror)
			)
		)
		(property "Value" ""
			(at 0 0 0)
			(layer "B.Fab")
			(effects
				(font
					(size 1.27 1.27)
				)
				(justify mirror)
			)
		)
		(duplicate_pad_numbers_are_jumpers no)
		(fp_line
			(start 0.7874 0.4064)
			(end 0.7874 -0.4064)
			(stroke
				(width 0.1524)
				(type default)
			)
			(layer "B.SilkS")
		)
		(fp_line
			(start 0.7874 -0.4064)
			(end -0.7874 -0.4064)
			(stroke
				(width 0.1524)
				(type default)
			)
			(layer "B.SilkS")
		)
		(fp_line
			(start -0.7874 0.4064)
			(end 0.7874 0.4064)
			(stroke
				(width 0.1524)
				(type default)
			)
			(layer "B.SilkS")
		)
		(fp_line
			(start -0.7874 -0.4064)
			(end -0.7874 0.4064)
			(stroke
				(width 0.1524)
				(type default)
			)
			(layer "B.SilkS")
		)
		(fp_line
			(start 0.67945 0.3048)
			(end 0.67945 -0.305054)
			(stroke
				(width 0.1)
				(type default)
			)
			(layer "B.Fab")
		)
		(fp_line
			(start 0.67945 -0.305054)
			(end 0.12065 -0.305054)
			(stroke
				(width 0.1)
				(type default)
			)
			(layer "B.Fab")
		)
		(fp_line
			(start 0.12065 0.3048)
			(end 0.67945 0.3048)
			(stroke
				(width 0.1)
				(type default)
			)
			(layer "B.Fab")
		)
		(fp_line
			(start 0.12065 0.2794)
			(end 0.12065 0.3048)
			(stroke
				(width 0.1)
				(type default)
			)
			(layer "B.Fab")
		)
		(fp_line
			(start 0.12065 -0.2794)
			(end -0.12065 -0.2794)
			(stroke
				(width 0.1)
				(type default)
			)
			(layer "B.Fab")
		)
		(fp_line
			(start 0.12065 -0.305054)
			(end 0.12065 -0.2794)
			(stroke
				(width 0.1)
				(type default)
			)
			(layer "B.Fab")
		)
		(fp_line
			(start -0.120396 0.3048)
			(end -0.120396 0.2794)
			(stroke
				(width 0.1)
				(type default)
			)
			(layer "B.Fab")
		)
		(fp_line
			(start -0.120396 0.2794)
			(end 0.12065 0.2794)
			(stroke
				(width 0.1)
				(type default)
			)
			(layer "B.Fab")
		)
		(fp_line
			(start -0.12065 -0.2794)
			(end -0.12065 -0.3048)
			(stroke
				(width 0.1)
				(type default)
			)
			(layer "B.Fab")
		)
		(fp_line
			(start -0.12065 -0.3048)
			(end -0.67945 -0.3048)
			(stroke
				(width 0.1)
				(type default)
			)
			(layer "B.Fab")
		)
		(fp_line
			(start -0.67945 0.3048)
			(end -0.120396 0.3048)
			(stroke
				(width 0.1)
				(type default)
			)
			(layer "B.Fab")
		)
		(fp_line
			(start -0.67945 -0.3048)
			(end -0.67945 0.3048)
			(stroke
				(width 0.1)
				(type default)
			)
			(layer "B.Fab")
		)
		(pad "1" smd circle
			(at 0.40005 0)
			(size 0 0)
			(layers "B.Cu" "B.Mask" "B.Paste")
			(net "PWRGD_CHF_CPU0_DIMM")
		)
		(pad "2" smd circle
			(at -0.40005 0)
			(size 0 0)
			(layers "B.Cu" "B.Mask" "B.Paste")
			(net "PWRGD_CHAF_CPU0")
		)
	)
	(footprint ""
		(layer "B.Cu")
		(at 299.265594 -392.66876 180)
		(property "Reference" "R984"
			(at 0 0 0)
			(layer "B.SilkS")
			(hide yes)
			(effects
				(font
					(size 1.27 1.27)
				)
				(justify mirror)
			)
		)
		(property "Value" ""
			(at 0 0 0)
			(layer "B.Fab")
			(effects
				(font
					(size 1.27 1.27)
				)
				(justify mirror)
			)
		)
		(duplicate_pad_numbers_are_jumpers no)
		(fp_line
			(start 0.32512 0.175006)
			(end 0.32512 -0.175006)
			(stroke
				(width 0.1)
				(type default)
			)
			(layer "B.Fab")
		)
		(fp_line
			(start 0.32512 -0.175006)
			(end -0.32512 -0.175006)
			(stroke
				(width 0.1)
				(type default)
			)
			(layer "B.Fab")
		)
		(fp_line
			(start -0.32512 0.175006)
			(end 0.32512 0.175006)
			(stroke
				(width 0.1)
				(type default)
			)
			(layer "B.Fab")
		)
		(fp_line
			(start -0.32512 -0.175006)
			(end -0.32512 0.175006)
			(stroke
				(width 0.1)
				(type default)
			)
			(layer "B.Fab")
		)
		(pad "1" smd rect
			(at 0.2667 0)
			(size 0.3048 0.381)
			(layers "B.Cu" "B.Mask" "B.Paste")
			(net "TEST1_RT_CPU0_P0")
		)
		(pad "2" smd rect
			(at -0.2667 0 180)
			(size 0.3048 0.381)
			(layers "B.Cu" "B.Mask" "B.Paste")
			(net "GND")
		)
	)
	(footprint ""
		(layer "B.Cu")
		(at 139.34694 -13.52169 -90)
		(property "Reference" "R4809"
			(at 0 0 90)
			(layer "B.SilkS")
			(hide yes)
			(effects
				(font
					(size 1.27 1.27)
				)
				(justify mirror)
			)
		)
		(property "Value" ""
			(at 0 0 90)
			(layer "B.Fab")
			(effects
				(font
					(size 1.27 1.27)
				)
				(justify mirror)
			)
		)
		(duplicate_pad_numbers_are_jumpers no)
		(fp_line
			(start -0.7874 0.4064)
			(end 0.7874 0.4064)
			(stroke
				(width 0.1524)
				(type default)
			)
			(layer "B.SilkS")
		)
		(fp_line
			(start 0.7874 0.4064)
			(end 0.7874 -0.4064)
			(stroke
				(width 0.1524)
				(type default)
			)
			(layer "B.SilkS")
		)
		(fp_line
			(start -0.7874 -0.4064)
			(end -0.7874 0.4064)
			(stroke
				(width 0.1524)
				(type default)
			)
			(layer "B.SilkS")
		)
		(fp_line
			(start 0.7874 -0.4064)
			(end -0.7874 -0.4064)
			(stroke
				(width 0.1524)
				(type default)
			)
			(layer "B.SilkS")
		)
		(fp_line
			(start -0.67945 0.3048)
			(end -0.120396 0.3048)
			(stroke
				(width 0.1)
				(type default)
			)
			(layer "B.Fab")
		)
		(fp_line
			(start -0.120396 0.3048)
			(end -0.120396 0.2794)
			(stroke
				(width 0.1)
				(type default)
			)
			(layer "B.Fab")
		)
		(fp_line
			(start 0.12065 0.3048)
			(end 0.67945 0.3048)
			(stroke
				(width 0.1)
				(type default)
			)
			(layer "B.Fab")
		)
		(fp_line
			(start 0.67945 0.3048)
			(end 0.67945 -0.305054)
			(stroke
				(width 0.1)
				(type default)
			)
			(layer "B.Fab")
		)
		(fp_line
			(start -0.120396 0.2794)
			(end 0.12065 0.2794)
			(stroke
				(width 0.1)
				(type default)
			)
			(layer "B.Fab")
		)
		(fp_line
			(start 0.12065 0.2794)
			(end 0.12065 0.3048)
			(stroke
				(width 0.1)
				(type default)
			)
			(layer "B.Fab")
		)
		(fp_line
			(start -0.12065 -0.2794)
			(end -0.12065 -0.3048)
			(stroke
				(width 0.1)
				(type default)
			)
			(layer "B.Fab")
		)
		(fp_line
			(start 0.12065 -0.2794)
			(end -0.12065 -0.2794)
			(stroke
				(width 0.1)
				(type default)
			)
			(layer "B.Fab")
		)
		(fp_line
			(start -0.67945 -0.3048)
			(end -0.67945 0.3048)
			(stroke
				(width 0.1)
				(type default)
			)
			(layer "B.Fab")
		)
		(fp_line
			(start -0.12065 -0.3048)
			(end -0.67945 -0.3048)
			(stroke
				(width 0.1)
				(type default)
			)
			(layer "B.Fab")
		)
		(fp_line
			(start 0.12065 -0.305054)
			(end 0.12065 -0.2794)
			(stroke
				(width 0.1)
				(type default)
			)
			(layer "B.Fab")
		)
		(fp_line
			(start 0.67945 -0.305054)
			(end 0.12065 -0.305054)
			(stroke
				(width 0.1)
				(type default)
			)
			(layer "B.Fab")
		)
		(pad "1" smd circle
			(at 0.40005 0 90)
			(size 0 0)
			(layers "B.Cu" "B.Mask" "B.Paste")
			(net "TP_CHASI")
		)
		(pad "2" smd circle
			(at -0.40005 0 90)
			(size 0 0)
			(layers "B.Cu" "B.Mask" "B.Paste")
			(net "GND")
		)
	)
	(footprint ""
		(layer "B.Cu")
		(at 488.03433 -147.888198 90)
		(property "Reference" "X6"
			(at 1.112012 2.605024 270)
			(unlocked yes)
			(layer "B.SilkS")
			(effects
				(font
					(size 0.7874 0.5842)
					(thickness 0.1524)
				)
				(justify left mirror)
			)
		)
		(property "Value" ""
			(at 0 0 90)
			(layer "B.Fab")
			(effects
				(font
					(size 1.27 1.27)
				)
				(justify mirror)
			)
		)
		(property "Device Type" "TP_TDR_4P_FTS_TH-TP_TDR_4P_DIP,EMPTY,TP15"
			(at -1.30175 1.27 0)
			(unlocked yes)
			(layer "B.Fab")
			(hide yes)
			(effects
				(font
					(size 0.635 0.4064)
					(thickness 0.1524)
				)
				(justify mirror)
			)
		)
		(property "User Part Number" "N_A"
			(at -1.30175 1.27 0)
			(unlocked yes)
			(layer "Cmts.User")
			(hide yes)
			(effects
				(font
					(size 0.635 0.4064)
					(thickness 0.1524)
				)
				(justify mirror)
			)
		)
		(duplicate_pad_numbers_are_jumpers no)
		(fp_line
			(start 0 -1.27)
			(end 0 -0.635)
			(stroke
				(width 0.1524)
				(type default)
			)
			(layer "B.SilkS")
		)
		(fp_line
			(start -2.54 -1.27)
			(end 0 -1.27)
			(stroke
				(width 0.1524)
				(type default)
			)
			(layer "B.SilkS")
		)
		(fp_line
			(start -2.54 -1.1303)
			(end -2.54 -1.27)
			(stroke
				(width 0.1524)
				(type default)
			)
			(layer "B.SilkS")
		)
		(fp_line
			(start 0 0.635)
			(end 0 1.905)
			(stroke
				(width 0.1524)
				(type default)
			)
			(layer "B.SilkS")
		)
		(fp_line
			(start -2.54 1.4097)
			(end -2.54 1.1303)
			(stroke
				(width 0.1524)
				(type default)
			)
			(layer "B.SilkS")
		)
		(fp_line
			(start 0 3.175)
			(end 0 3.81)
			(stroke
				(width 0.1524)
				(type default)
			)
			(layer "B.SilkS")
		)
		(fp_line
			(start 0 3.81)
			(end -2.54 3.81)
			(stroke
				(width 0.1524)
				(type default)
			)
			(layer "B.SilkS")
		)
		(fp_line
			(start -2.54 3.81)
			(end -2.54 3.6703)
			(stroke
				(width 0.1524)
				(type default)
			)
			(layer "B.SilkS")
		)
		(fp_poly
			(pts
				(xy 2.285746 -0.762) (xy 2.285746 0.762) (xy 0.761746 0)
			)
			(stroke
				(width 0)
				(type default)
			)
			(fill yes)
			(layer "B.SilkS")
		)
		(fp_line
			(start 0 -1.27)
			(end 0 3.81)
			(stroke
				(width 0.1)
				(type default)
			)
			(layer "B.Fab")
		)
		(fp_line
			(start -2.54 -1.27)
			(end 0 -1.27)
			(stroke
				(width 0.1)
				(type default)
			)
			(layer "B.Fab")
		)
		(fp_line
			(start 0 3.81)
			(end -2.54 3.81)
			(stroke
				(width 0.1)
				(type default)
			)
			(layer "B.Fab")
		)
		(fp_line
			(start -2.54 3.81)
			(end -2.54 -1.27)
			(stroke
				(width 0.1)
				(type default)
			)
			(layer "B.Fab")
		)
		(fp_poly
			(pts
				(xy 0.761746 0) (xy 2.285746 -0.762) (xy 2.285746 0.762)
			)
			(stroke
				(width 0)
				(type default)
			)
			(fill yes)
			(layer "B.Fab")
		)
		(pad "1" thru_hole circle
			(at 0 0 270)
			(size 1.0033 1.0033)
			(drill 0.249936)
			(layers "*.Cu" "*.Mask")
			(remove_unused_layers no)
			(net "TDR_DIFF_80_BOT_DP")
			(clearance 0.10795)
			(padstack
				(mode front_inner_back)
				(layer "Inner"
					(shape circle)
					(size 0.8001 0.8001)
					(clearance 0.1524)
				)
				(layer "B.Cu"
					(shape circle)
					(size 1.0033 1.0033)
					(thermal_gap 0.10795)
					(clearance 0.10795)
				)
			)
		)
		(pad "2" thru_hole circle
			(at -2.54 0 270)
			(size 1.9939 1.9939)
			(drill 0.249936)
			(layers "*.Cu" "*.Mask")
			(remove_unused_layers no)
			(net "T1_GND")
			(clearance 0.10795)
			(padstack
				(mode front_inner_back)
				(layer "Inner"
					(shape circle)
					(size 0.8001 0.8001)
					(clearance 0.1524)
				)
				(layer "B.Cu"
					(shape circle)
					(size 1.9939 1.9939)
					(thermal_gap 0.10795)
					(clearance 0.10795)
				)
			)
		)
		(pad "3" thru_hole circle
			(at -2.54 2.54 270)
			(size 1.9939 1.9939)
			(drill 0.249936)
			(layers "*.Cu" "*.Mask")
			(remove_unused_layers no)
			(net "T1_GND")
			(clearance 0.10795)
			(padstack
				(mode front_inner_back)
				(layer "Inner"
					(shape circle)
					(size 0.8001 0.8001)
					(clearance 0.1524)
				)
				(layer "B.Cu"
					(shape circle)
					(size 1.9939 1.9939)
					(thermal_gap 0.10795)
					(clearance 0.10795)
				)
			)
		)
		(pad "4" thru_hole circle
			(at 0 2.54 270)
			(size 1.0033 1.0033)
			(drill 0.249936)
			(layers "*.Cu" "*.Mask")
			(remove_unused_layers no)
			(net "TDR_DIFF_80_BOT_DN")
			(clearance 0.10795)
			(padstack
				(mode front_inner_back)
				(layer "Inner"
					(shape circle)
					(size 0.8001 0.8001)
					(clearance 0.1524)
				)
				(layer "B.Cu"
					(shape circle)
					(size 1.0033 1.0033)
					(thermal_gap 0.10795)
					(clearance 0.10795)
				)
			)
		)
	)
	(footprint ""
		(layer "B.Cu")
		(at 311.778396 -395.148562 90)
		(property "Reference" "C517"
			(at 0 0 90)
			(layer "B.SilkS")
			(hide yes)
			(effects
				(font
					(size 1.27 1.27)
				)
				(justify mirror)
			)
		)
		(property "Value" ""
			(at 0 0 90)
			(layer "B.Fab")
			(effects
				(font
					(size 1.27 1.27)
				)
				(justify mirror)
			)
		)
		(duplicate_pad_numbers_are_jumpers no)
		(fp_line
			(start 0.299974 -0.150114)
			(end -0.299974 -0.150114)
			(stroke
				(width 0.1)
				(type default)
			)
			(layer "B.Fab")
		)
		(fp_line
			(start -0.299974 -0.150114)
			(end -0.299974 0.150114)
			(stroke
				(width 0.1)
				(type default)
			)
			(layer "B.Fab")
		)
		(fp_line
			(start 0.299974 0.150114)
			(end 0.299974 -0.150114)
			(stroke
				(width 0.1)
				(type default)
			)
			(layer "B.Fab")
		)
		(fp_line
			(start -0.299974 0.150114)
			(end 0.299974 0.150114)
			(stroke
				(width 0.1)
				(type default)
			)
			(layer "B.Fab")
		)
		(pad "1" smd rect
			(at 0.2667 0 270)
			(size 0.3048 0.381)
			(layers "B.Cu" "B.Mask" "B.Paste")
			(net "P1V8_CPU0_RT0_1A")
		)
		(pad "2" smd rect
			(at -0.2667 0 270)
			(size 0.3048 0.381)
			(layers "B.Cu" "B.Mask" "B.Paste")
			(net "GND")
		)
	)
	(footprint ""
		(layer "B.Cu")
		(at 350.215454 -268.41831)
		(property "Reference" "C2238"
			(at 0 0 0)
			(layer "B.SilkS")
			(hide yes)
			(effects
				(font
					(size 1.27 1.27)
				)
				(justify mirror)
			)
		)
		(property "Value" ""
			(at 0 0 0)
			(layer "B.Fab")
			(effects
				(font
					(size 1.27 1.27)
				)
				(justify mirror)
			)
		)
		(duplicate_pad_numbers_are_jumpers no)
		(fp_line
			(start -0.7874 -0.4064)
			(end -0.7874 0.4064)
			(stroke
				(width 0.1524)
				(type default)
			)
			(layer "B.SilkS")
		)
		(fp_line
			(start -0.7874 0.4064)
			(end 0.7874 0.4064)
			(stroke
				(width 0.1524)
				(type default)
			)
			(layer "B.SilkS")
		)
		(fp_line
			(start 0.7874 -0.4064)
			(end -0.7874 -0.4064)
			(stroke
				(width 0.1524)
				(type default)
			)
			(layer "B.SilkS")
		)
		(fp_line
			(start 0.7874 0.4064)
			(end 0.7874 -0.4064)
			(stroke
				(width 0.1524)
				(type default)
			)
			(layer "B.SilkS")
		)
		(fp_line
			(start -0.67945 -0.3048)
			(end -0.67945 0.3048)
			(stroke
				(width 0.1)
				(type default)
			)
			(layer "B.Fab")
		)
		(fp_line
			(start -0.67945 0.3048)
			(end -0.120396 0.3048)
			(stroke
				(width 0.1)
				(type default)
			)
			(layer "B.Fab")
		)
		(fp_line
			(start -0.12065 -0.3048)
			(end -0.67945 -0.3048)
			(stroke
				(width 0.1)
				(type default)
			)
			(layer "B.Fab")
		)
		(fp_line
			(start -0.12065 -0.2794)
			(end -0.12065 -0.3048)
			(stroke
				(width 0.1)
				(type default)
			)
			(layer "B.Fab")
		)
		(fp_line
			(start -0.120396 0.2794)
			(end 0.12065 0.2794)
			(stroke
				(width 0.1)
				(type default)
			)
			(layer "B.Fab")
		)
		(fp_line
			(start -0.120396 0.3048)
			(end -0.120396 0.2794)
			(stroke
				(width 0.1)
				(type default)
			)
			(layer "B.Fab")
		)
		(fp_line
			(start 0.12065 -0.305054)
			(end 0.12065 -0.2794)
			(stroke
				(width 0.1)
				(type default)
			)
			(layer "B.Fab")
		)
		(fp_line
			(start 0.12065 -0.2794)
			(end -0.12065 -0.2794)
			(stroke
				(width 0.1)
				(type default)
			)
			(layer "B.Fab")
		)
		(fp_line
			(start 0.12065 0.2794)
			(end 0.12065 0.3048)
			(stroke
				(width 0.1)
				(type default)
			)
			(layer "B.Fab")
		)
		(fp_line
			(start 0.12065 0.3048)
			(end 0.67945 0.3048)
			(stroke
				(width 0.1)
				(type default)
			)
			(layer "B.Fab")
		)
		(fp_line
			(start 0.67945 -0.305054)
			(end 0.12065 -0.305054)
			(stroke
				(width 0.1)
				(type default)
			)
			(layer "B.Fab")
		)
		(fp_line
			(start 0.67945 0.3048)
			(end 0.67945 -0.305054)
			(stroke
				(width 0.1)
				(type default)
			)
			(layer "B.Fab")
		)
		(pad "1" smd circle
			(at 0.40005 0 180)
			(size 0 0)
			(layers "B.Cu" "B.Mask" "B.Paste")
			(net "PVDDCR_CPU1_P0")
		)
		(pad "2" smd circle
			(at -0.40005 0 180)
			(size 0 0)
			(layers "B.Cu" "B.Mask" "B.Paste")
			(net "GND")
		)
	)
	(footprint ""
		(layer "B.Cu")
		(at 24.765 -363.347 180)
		(property "Reference" "R8247"
			(at 0 0 0)
			(layer "B.SilkS")
			(hide yes)
			(effects
				(font
					(size 1.27 1.27)
				)
				(justify mirror)
			)
		)
		(property "Value" ""
			(at 0 0 0)
			(layer "B.Fab")
			(effects
				(font
					(size 1.27 1.27)
				)
				(justify mirror)
			)
		)
		(duplicate_pad_numbers_are_jumpers no)
		(fp_line
			(start 0.7874 0.4064)
			(end 0.7874 -0.4064)
			(stroke
				(width 0.1524)
				(type default)
			)
			(layer "B.SilkS")
		)
		(fp_line
			(start 0.7874 -0.4064)
			(end -0.7874 -0.4064)
			(stroke
				(width 0.1524)
				(type default)
			)
			(layer "B.SilkS")
		)
		(fp_line
			(start -0.7874 0.4064)
			(end 0.7874 0.4064)
			(stroke
				(width 0.1524)
				(type default)
			)
			(layer "B.SilkS")
		)
		(fp_line
			(start -0.7874 -0.4064)
			(end -0.7874 0.4064)
			(stroke
				(width 0.1524)
				(type default)
			)
			(layer "B.SilkS")
		)
		(fp_line
			(start 0.67945 0.3048)
			(end 0.67945 -0.305054)
			(stroke
				(width 0.1)
				(type default)
			)
			(layer "B.Fab")
		)
		(fp_line
			(start 0.67945 -0.305054)
			(end 0.12065 -0.305054)
			(stroke
				(width 0.1)
				(type default)
			)
			(layer "B.Fab")
		)
		(fp_line
			(start 0.12065 0.3048)
			(end 0.67945 0.3048)
			(stroke
				(width 0.1)
				(type default)
			)
			(layer "B.Fab")
		)
		(fp_line
			(start 0.12065 0.2794)
			(end 0.12065 0.3048)
			(stroke
				(width 0.1)
				(type default)
			)
			(layer "B.Fab")
		)
		(fp_line
			(start 0.12065 -0.2794)
			(end -0.12065 -0.2794)
			(stroke
				(width 0.1)
				(type default)
			)
			(layer "B.Fab")
		)
		(fp_line
			(start 0.12065 -0.305054)
			(end 0.12065 -0.2794)
			(stroke
				(width 0.1)
				(type default)
			)
			(layer "B.Fab")
		)
		(fp_line
			(start -0.120396 0.3048)
			(end -0.120396 0.2794)
			(stroke
				(width 0.1)
				(type default)
			)
			(layer "B.Fab")
		)
		(fp_line
			(start -0.120396 0.2794)
			(end 0.12065 0.2794)
			(stroke
				(width 0.1)
				(type default)
			)
			(layer "B.Fab")
		)
		(fp_line
			(start -0.12065 -0.2794)
			(end -0.12065 -0.3048)
			(stroke
				(width 0.1)
				(type default)
			)
			(layer "B.Fab")
		)
		(fp_line
			(start -0.12065 -0.3048)
			(end -0.67945 -0.3048)
			(stroke
				(width 0.1)
				(type default)
			)
			(layer "B.Fab")
		)
		(fp_line
			(start -0.67945 0.3048)
			(end -0.120396 0.3048)
			(stroke
				(width 0.1)
				(type default)
			)
			(layer "B.Fab")
		)
		(fp_line
			(start -0.67945 -0.3048)
			(end -0.67945 0.3048)
			(stroke
				(width 0.1)
				(type default)
			)
			(layer "B.Fab")
		)
		(pad "1" smd circle
			(at 0.40005 0)
			(size 0 0)
			(layers "B.Cu" "B.Mask" "B.Paste")
			(net "PVDD18_S5_P1")
		)
		(pad "2" smd circle
			(at -0.40005 0)
			(size 0 0)
			(layers "B.Cu" "B.Mask" "B.Paste")
			(net "PVDDCR_CPU1_P1_RESET_N_R")
		)
	)
	(footprint ""
		(layer "B.Cu")
		(at 101.854 -413.2072 180)
		(property "Reference" "R1516"
			(at 0 0 0)
			(layer "B.SilkS")
			(hide yes)
			(effects
				(font
					(size 1.27 1.27)
				)
				(justify mirror)
			)
		)
		(property "Value" ""
			(at 0 0 0)
			(layer "B.Fab")
			(effects
				(font
					(size 1.27 1.27)
				)
				(justify mirror)
			)
		)
		(duplicate_pad_numbers_are_jumpers no)
		(fp_line
			(start 0.7874 0.4064)
			(end 0.7874 -0.4064)
			(stroke
				(width 0.1524)
				(type default)
			)
			(layer "B.SilkS")
		)
		(fp_line
			(start 0.7874 -0.4064)
			(end -0.7874 -0.4064)
			(stroke
				(width 0.1524)
				(type default)
			)
			(layer "B.SilkS")
		)
		(fp_line
			(start -0.7874 0.4064)
			(end 0.7874 0.4064)
			(stroke
				(width 0.1524)
				(type default)
			)
			(layer "B.SilkS")
		)
		(fp_line
			(start -0.7874 -0.4064)
			(end -0.7874 0.4064)
			(stroke
				(width 0.1524)
				(type default)
			)
			(layer "B.SilkS")
		)
		(fp_line
			(start 0.67945 0.3048)
			(end 0.67945 -0.305054)
			(stroke
				(width 0.1)
				(type default)
			)
			(layer "B.Fab")
		)
		(fp_line
			(start 0.67945 -0.305054)
			(end 0.12065 -0.305054)
			(stroke
				(width 0.1)
				(type default)
			)
			(layer "B.Fab")
		)
		(fp_line
			(start 0.12065 0.3048)
			(end 0.67945 0.3048)
			(stroke
				(width 0.1)
				(type default)
			)
			(layer "B.Fab")
		)
		(fp_line
			(start 0.12065 0.2794)
			(end 0.12065 0.3048)
			(stroke
				(width 0.1)
				(type default)
			)
			(layer "B.Fab")
		)
		(fp_line
			(start 0.12065 -0.2794)
			(end -0.12065 -0.2794)
			(stroke
				(width 0.1)
				(type default)
			)
			(layer "B.Fab")
		)
		(fp_line
			(start 0.12065 -0.305054)
			(end 0.12065 -0.2794)
			(stroke
				(width 0.1)
				(type default)
			)
			(layer "B.Fab")
		)
		(fp_line
			(start -0.120396 0.3048)
			(end -0.120396 0.2794)
			(stroke
				(width 0.1)
				(type default)
			)
			(layer "B.Fab")
		)
		(fp_line
			(start -0.120396 0.2794)
			(end 0.12065 0.2794)
			(stroke
				(width 0.1)
				(type default)
			)
			(layer "B.Fab")
		)
		(fp_line
			(start -0.12065 -0.2794)
			(end -0.12065 -0.3048)
			(stroke
				(width 0.1)
				(type default)
			)
			(layer "B.Fab")
		)
		(fp_line
			(start -0.12065 -0.3048)
			(end -0.67945 -0.3048)
			(stroke
				(width 0.1)
				(type default)
			)
			(layer "B.Fab")
		)
		(fp_line
			(start -0.67945 0.3048)
			(end -0.120396 0.3048)
			(stroke
				(width 0.1)
				(type default)
			)
			(layer "B.Fab")
		)
		(fp_line
			(start -0.67945 -0.3048)
			(end -0.67945 0.3048)
			(stroke
				(width 0.1)
				(type default)
			)
			(layer "B.Fab")
		)
		(pad "1" smd circle
			(at 0.40005 0)
			(size 0 0)
			(layers "B.Cu" "B.Mask" "B.Paste")
			(net "SMB_HOST_CLK_3V3AUX_SCL")
		)
		(pad "2" smd circle
			(at -0.40005 0)
			(size 0 0)
			(layers "B.Cu" "B.Mask" "B.Paste")
			(net "SMB_HOST_CLK_3V3AUX_SCL_R1")
		)
	)
	(footprint ""
		(layer "B.Cu")
		(at 402.844 -349.218504 -90)
		(property "Reference" "R6123"
			(at 0 0 90)
			(layer "B.SilkS")
			(hide yes)
			(effects
				(font
					(size 1.27 1.27)
				)
				(justify mirror)
			)
		)
		(property "Value" ""
			(at 0 0 90)
			(layer "B.Fab")
			(effects
				(font
					(size 1.27 1.27)
				)
				(justify mirror)
			)
		)
		(duplicate_pad_numbers_are_jumpers no)
		(fp_line
			(start -0.7874 0.4064)
			(end 0.7874 0.4064)
			(stroke
				(width 0.1524)
				(type default)
			)
			(layer "B.SilkS")
		)
		(fp_line
			(start 0.7874 0.4064)
			(end 0.7874 -0.4064)
			(stroke
				(width 0.1524)
				(type default)
			)
			(layer "B.SilkS")
		)
		(fp_line
			(start -0.7874 -0.4064)
			(end -0.7874 0.4064)
			(stroke
				(width 0.1524)
				(type default)
			)
			(layer "B.SilkS")
		)
		(fp_line
			(start 0.7874 -0.4064)
			(end -0.7874 -0.4064)
			(stroke
				(width 0.1524)
				(type default)
			)
			(layer "B.SilkS")
		)
		(fp_line
			(start -0.67945 0.3048)
			(end -0.120396 0.3048)
			(stroke
				(width 0.1)
				(type default)
			)
			(layer "B.Fab")
		)
		(fp_line
			(start -0.120396 0.3048)
			(end -0.120396 0.2794)
			(stroke
				(width 0.1)
				(type default)
			)
			(layer "B.Fab")
		)
		(fp_line
			(start 0.12065 0.3048)
			(end 0.67945 0.3048)
			(stroke
				(width 0.1)
				(type default)
			)
			(layer "B.Fab")
		)
		(fp_line
			(start 0.67945 0.3048)
			(end 0.67945 -0.305054)
			(stroke
				(width 0.1)
				(type default)
			)
			(layer "B.Fab")
		)
		(fp_line
			(start -0.120396 0.2794)
			(end 0.12065 0.2794)
			(stroke
				(width 0.1)
				(type default)
			)
			(layer "B.Fab")
		)
		(fp_line
			(start 0.12065 0.2794)
			(end 0.12065 0.3048)
			(stroke
				(width 0.1)
				(type default)
			)
			(layer "B.Fab")
		)
		(fp_line
			(start -0.12065 -0.2794)
			(end -0.12065 -0.3048)
			(stroke
				(width 0.1)
				(type default)
			)
			(layer "B.Fab")
		)
		(fp_line
			(start 0.12065 -0.2794)
			(end -0.12065 -0.2794)
			(stroke
				(width 0.1)
				(type default)
			)
			(layer "B.Fab")
		)
		(fp_line
			(start -0.67945 -0.3048)
			(end -0.67945 0.3048)
			(stroke
				(width 0.1)
				(type default)
			)
			(layer "B.Fab")
		)
		(fp_line
			(start -0.12065 -0.3048)
			(end -0.67945 -0.3048)
			(stroke
				(width 0.1)
				(type default)
			)
			(layer "B.Fab")
		)
		(fp_line
			(start 0.12065 -0.305054)
			(end 0.12065 -0.2794)
			(stroke
				(width 0.1)
				(type default)
			)
			(layer "B.Fab")
		)
		(fp_line
			(start 0.67945 -0.305054)
			(end 0.12065 -0.305054)
			(stroke
				(width 0.1)
				(type default)
			)
			(layer "B.Fab")
		)
		(pad "1" smd circle
			(at 0.40005 0 90)
			(size 0 0)
			(layers "B.Cu" "B.Mask" "B.Paste")
			(net "PVDD18_S5_P0")
		)
		(pad "2" smd circle
			(at -0.40005 0 90)
			(size 0 0)
			(layers "B.Cu" "B.Mask" "B.Paste")
			(net "FM_BOARD_SKU_ID1")
		)
	)
	(footprint ""
		(layer "B.Cu")
		(at 197.269608 -117.689376 180)
		(property "Reference" "R4170"
			(at 0 0 0)
			(layer "B.SilkS")
			(hide yes)
			(effects
				(font
					(size 1.27 1.27)
				)
				(justify mirror)
			)
		)
		(property "Value" ""
			(at 0 0 0)
			(layer "B.Fab")
			(effects
				(font
					(size 1.27 1.27)
				)
				(justify mirror)
			)
		)
		(duplicate_pad_numbers_are_jumpers no)
		(fp_line
			(start 0.7874 0.4064)
			(end 0.7874 -0.4064)
			(stroke
				(width 0.1524)
				(type default)
			)
			(layer "B.SilkS")
		)
		(fp_line
			(start 0.7874 -0.4064)
			(end -0.7874 -0.4064)
			(stroke
				(width 0.1524)
				(type default)
			)
			(layer "B.SilkS")
		)
		(fp_line
			(start -0.7874 0.4064)
			(end 0.7874 0.4064)
			(stroke
				(width 0.1524)
				(type default)
			)
			(layer "B.SilkS")
		)
		(fp_line
			(start -0.7874 -0.4064)
			(end -0.7874 0.4064)
			(stroke
				(width 0.1524)
				(type default)
			)
			(layer "B.SilkS")
		)
		(fp_line
			(start 0.67945 0.3048)
			(end 0.67945 -0.305054)
			(stroke
				(width 0.1)
				(type default)
			)
			(layer "B.Fab")
		)
		(fp_line
			(start 0.67945 -0.305054)
			(end 0.12065 -0.305054)
			(stroke
				(width 0.1)
				(type default)
			)
			(layer "B.Fab")
		)
		(fp_line
			(start 0.12065 0.3048)
			(end 0.67945 0.3048)
			(stroke
				(width 0.1)
				(type default)
			)
			(layer "B.Fab")
		)
		(fp_line
			(start 0.12065 0.2794)
			(end 0.12065 0.3048)
			(stroke
				(width 0.1)
				(type default)
			)
			(layer "B.Fab")
		)
		(fp_line
			(start 0.12065 -0.2794)
			(end -0.12065 -0.2794)
			(stroke
				(width 0.1)
				(type default)
			)
			(layer "B.Fab")
		)
		(fp_line
			(start 0.12065 -0.305054)
			(end 0.12065 -0.2794)
			(stroke
				(width 0.1)
				(type default)
			)
			(layer "B.Fab")
		)
		(fp_line
			(start -0.120396 0.3048)
			(end -0.120396 0.2794)
			(stroke
				(width 0.1)
				(type default)
			)
			(layer "B.Fab")
		)
		(fp_line
			(start -0.120396 0.2794)
			(end 0.12065 0.2794)
			(stroke
				(width 0.1)
				(type default)
			)
			(layer "B.Fab")
		)
		(fp_line
			(start -0.12065 -0.2794)
			(end -0.12065 -0.3048)
			(stroke
				(width 0.1)
				(type default)
			)
			(layer "B.Fab")
		)
		(fp_line
			(start -0.12065 -0.3048)
			(end -0.67945 -0.3048)
			(stroke
				(width 0.1)
				(type default)
			)
			(layer "B.Fab")
		)
		(fp_line
			(start -0.67945 0.3048)
			(end -0.120396 0.3048)
			(stroke
				(width 0.1)
				(type default)
			)
			(layer "B.Fab")
		)
		(fp_line
			(start -0.67945 -0.3048)
			(end -0.67945 0.3048)
			(stroke
				(width 0.1)
				(type default)
			)
			(layer "B.Fab")
		)
		(pad "1" smd circle
			(at 0.40005 0)
			(size 0 0)
			(layers "B.Cu" "B.Mask" "B.Paste")
			(net "GPU_3V3IO_RSVD1_ISO_R")
		)
		(pad "2" smd circle
			(at -0.40005 0)
			(size 0 0)
			(layers "B.Cu" "B.Mask" "B.Paste")
			(net "GPU_3V3IO_RSVD1_ISO")
		)
	)
	(footprint ""
		(layer "B.Cu")
		(at 511.924808 -298.345606 -90)
		(property "Reference" "X27"
			(at 3.097276 3.214878 270)
			(unlocked yes)
			(layer "B.SilkS")
			(effects
				(font
					(size 0.7874 0.5842)
					(thickness 0.1524)
				)
				(justify left mirror)
			)
		)
		(property "Value" ""
			(at 0 0 90)
			(layer "B.Fab")
			(effects
				(font
					(size 1.27 1.27)
				)
				(justify mirror)
			)
		)
		(property "User Part Number" "N_A"
			(at -1.30175 1.27 180)
			(unlocked yes)
			(layer "Cmts.User")
			(hide yes)
			(effects
				(font
					(size 0.635 0.4064)
					(thickness 0.1524)
				)
				(justify mirror)
			)
		)
		(property "Device Type" "TP_TDR_4P_FTS_TH-TP_TDR_4P_DIP,EMPTY,TP15"
			(at -1.30175 1.27 180)
			(unlocked yes)
			(layer "B.Fab")
			(hide yes)
			(effects
				(font
					(size 0.635 0.4064)
					(thickness 0.1524)
				)
				(justify mirror)
			)
		)
		(duplicate_pad_numbers_are_jumpers no)
		(fp_line
			(start -2.54 3.81)
			(end -2.54 3.6703)
			(stroke
				(width 0.1524)
				(type default)
			)
			(layer "B.SilkS")
		)
		(fp_line
			(start 0 3.81)
			(end -2.54 3.81)
			(stroke
				(width 0.1524)
				(type default)
			)
			(layer "B.SilkS")
		)
		(fp_line
			(start 0 3.175)
			(end 0 3.81)
			(stroke
				(width 0.1524)
				(type default)
			)
			(layer "B.SilkS")
		)
		(fp_line
			(start -2.54 1.4097)
			(end -2.54 1.1303)
			(stroke
				(width 0.1524)
				(type default)
			)
			(layer "B.SilkS")
		)
		(fp_line
			(start 0 0.635)
			(end 0 1.905)
			(stroke
				(width 0.1524)
				(type default)
			)
			(layer "B.SilkS")
		)
		(fp_line
			(start -2.54 -1.1303)
			(end -2.54 -1.27)
			(stroke
				(width 0.1524)
				(type default)
			)
			(layer "B.SilkS")
		)
		(fp_line
			(start -2.54 -1.27)
			(end 0 -1.27)
			(stroke
				(width 0.1524)
				(type default)
			)
			(layer "B.SilkS")
		)
		(fp_line
			(start 0 -1.27)
			(end 0 -0.635)
			(stroke
				(width 0.1524)
				(type default)
			)
			(layer "B.SilkS")
		)
		(fp_poly
			(pts
				(xy 2.285746 -0.762) (xy 2.285746 0.762) (xy 0.761746 0)
			)
			(stroke
				(width 0)
				(type default)
			)
			(fill yes)
			(layer "B.SilkS")
		)
		(fp_line
			(start -2.54 3.81)
			(end -2.54 -1.27)
			(stroke
				(width 0.1)
				(type default)
			)
			(layer "B.Fab")
		)
		(fp_line
			(start 0 3.81)
			(end -2.54 3.81)
			(stroke
				(width 0.1)
				(type default)
			)
			(layer "B.Fab")
		)
		(fp_line
			(start -2.54 -1.27)
			(end 0 -1.27)
			(stroke
				(width 0.1)
				(type default)
			)
			(layer "B.Fab")
		)
		(fp_line
			(start 0 -1.27)
			(end 0 3.81)
			(stroke
				(width 0.1)
				(type default)
			)
			(layer "B.Fab")
		)
		(fp_poly
			(pts
				(xy 0.761746 0) (xy 2.285746 -0.762) (xy 2.285746 0.762)
			)
			(stroke
				(width 0)
				(type default)
			)
			(fill yes)
			(layer "B.Fab")
		)
		(pad "1" thru_hole circle
			(at 0 0 90)
			(size 1.0033 1.0033)
			(drill 0.249936)
			(layers "*.Cu" "*.Mask")
			(remove_unused_layers no)
			(net "TDR_DIFF_80_IN5_DN")
			(clearance 0.10795)
			(padstack
				(mode front_inner_back)
				(layer "Inner"
					(shape circle)
					(size 0.8001 0.8001)
					(clearance 0.1524)
				)
				(layer "B.Cu"
					(shape circle)
					(size 1.0033 1.0033)
					(thermal_gap 0.10795)
					(clearance 0.10795)
				)
			)
		)
		(pad "2" thru_hole circle
			(at -2.54 0 90)
			(size 1.9939 1.9939)
			(drill 0.249936)
			(layers "*.Cu" "*.Mask")
			(remove_unused_layers no)
			(net "T1_GND")
			(clearance 0.10795)
			(padstack
				(mode front_inner_back)
				(layer "Inner"
					(shape circle)
					(size 0.8001 0.8001)
					(clearance 0.1524)
				)
				(layer "B.Cu"
					(shape circle)
					(size 1.9939 1.9939)
					(thermal_gap 0.10795)
					(clearance 0.10795)
				)
			)
		)
		(pad "3" thru_hole circle
			(at -2.54 2.54 90)
			(size 1.9939 1.9939)
			(drill 0.249936)
			(layers "*.Cu" "*.Mask")
			(remove_unused_layers no)
			(net "T1_GND")
			(clearance 0.10795)
			(padstack
				(mode front_inner_back)
				(layer "Inner"
					(shape circle)
					(size 0.8001 0.8001)
					(clearance 0.1524)
				)
				(layer "B.Cu"
					(shape circle)
					(size 1.9939 1.9939)
					(thermal_gap 0.10795)
					(clearance 0.10795)
				)
			)
		)
		(pad "4" thru_hole circle
			(at 0 2.54 90)
			(size 1.0033 1.0033)
			(drill 0.249936)
			(layers "*.Cu" "*.Mask")
			(remove_unused_layers no)
			(net "TDR_DIFF_80_IN5_DP")
			(clearance 0.10795)
			(padstack
				(mode front_inner_back)
				(layer "Inner"
					(shape circle)
					(size 0.8001 0.8001)
					(clearance 0.1524)
				)
				(layer "B.Cu"
					(shape circle)
					(size 1.0033 1.0033)
					(thermal_gap 0.10795)
					(clearance 0.10795)
				)
			)
		)
	)
	(footprint ""
		(layer "B.Cu")
		(at 284.736286 -192.660016)
		(property "Reference" "C150"
			(at 0 0 0)
			(layer "B.SilkS")
			(hide yes)
			(effects
				(font
					(size 1.27 1.27)
				)
				(justify mirror)
			)
		)
		(property "Value" ""
			(at 0 0 0)
			(layer "B.Fab")
			(effects
				(font
					(size 1.27 1.27)
				)
				(justify mirror)
			)
		)
		(duplicate_pad_numbers_are_jumpers no)
		(fp_line
			(start -1.524 -0.762)
			(end -1.524 0.762)
			(stroke
				(width 0.1524)
				(type default)
			)
			(layer "B.SilkS")
		)
		(fp_line
			(start -1.524 0.762)
			(end 1.524 0.762)
			(stroke
				(width 0.1524)
				(type default)
			)
			(layer "B.SilkS")
		)
		(fp_line
			(start 1.524 -0.762)
			(end -1.524 -0.762)
			(stroke
				(width 0.1524)
				(type default)
			)
			(layer "B.SilkS")
		)
		(fp_line
			(start 1.524 0.762)
			(end 1.524 -0.762)
			(stroke
				(width 0.1524)
				(type default)
			)
			(layer "B.SilkS")
		)
		(fp_line
			(start -1.1049 -0.724916)
			(end 1.1049 -0.724916)
			(stroke
				(width 0.1)
				(type default)
			)
			(layer "B.Fab")
		)
		(fp_line
			(start -1.1049 0.724916)
			(end -1.1049 -0.724916)
			(stroke
				(width 0.1)
				(type default)
			)
			(layer "B.Fab")
		)
		(fp_line
			(start 1.1049 -0.724916)
			(end 1.1049 0.724916)
			(stroke
				(width 0.1)
				(type default)
			)
			(layer "B.Fab")
		)
		(fp_line
			(start 1.1049 0.724916)
			(end -1.1049 0.724916)
			(stroke
				(width 0.1)
				(type default)
			)
			(layer "B.Fab")
		)
		(pad "1" smd rect
			(at 0.889 0)
			(size 1.016 1.27)
			(layers "B.Cu" "B.Mask" "B.Paste")
			(net "P12V_MEM_CPU0")
		)
		(pad "2" smd rect
			(at -0.889 0)
			(size 1.016 1.27)
			(layers "B.Cu" "B.Mask" "B.Paste")
			(net "GND")
		)
	)
	(footprint ""
		(layer "B.Cu")
		(at 376.491246 -398.942052 90)
		(property "Reference" "C1038"
			(at 0 0 90)
			(layer "B.SilkS")
			(hide yes)
			(effects
				(font
					(size 1.27 1.27)
				)
				(justify mirror)
			)
		)
		(property "Value" ""
			(at 0 0 90)
			(layer "B.Fab")
			(effects
				(font
					(size 1.27 1.27)
				)
				(justify mirror)
			)
		)
		(duplicate_pad_numbers_are_jumpers no)
		(fp_line
			(start 0.7874 -0.4064)
			(end -0.7874 -0.4064)
			(stroke
				(width 0.1524)
				(type default)
			)
			(layer "B.SilkS")
		)
		(fp_line
			(start -0.7874 -0.4064)
			(end -0.7874 0.4064)
			(stroke
				(width 0.1524)
				(type default)
			)
			(layer "B.SilkS")
		)
		(fp_line
			(start 0.7874 0.4064)
			(end 0.7874 -0.4064)
			(stroke
				(width 0.1524)
				(type default)
			)
			(layer "B.SilkS")
		)
		(fp_line
			(start -0.7874 0.4064)
			(end 0.7874 0.4064)
			(stroke
				(width 0.1524)
				(type default)
			)
			(layer "B.SilkS")
		)
		(fp_line
			(start 0.67945 -0.305054)
			(end 0.12065 -0.305054)
			(stroke
				(width 0.1)
				(type default)
			)
			(layer "B.Fab")
		)
		(fp_line
			(start 0.12065 -0.305054)
			(end 0.12065 -0.2794)
			(stroke
				(width 0.1)
				(type default)
			)
			(layer "B.Fab")
		)
		(fp_line
			(start -0.12065 -0.3048)
			(end -0.67945 -0.3048)
			(stroke
				(width 0.1)
				(type default)
			)
			(layer "B.Fab")
		)
		(fp_line
			(start -0.67945 -0.3048)
			(end -0.67945 0.3048)
			(stroke
				(width 0.1)
				(type default)
			)
			(layer "B.Fab")
		)
		(fp_line
			(start 0.12065 -0.2794)
			(end -0.12065 -0.2794)
			(stroke
				(width 0.1)
				(type default)
			)
			(layer "B.Fab")
		)
		(fp_line
			(start -0.12065 -0.2794)
			(end -0.12065 -0.3048)
			(stroke
				(width 0.1)
				(type default)
			)
			(layer "B.Fab")
		)
		(fp_line
			(start 0.12065 0.2794)
			(end 0.12065 0.3048)
			(stroke
				(width 0.1)
				(type default)
			)
			(layer "B.Fab")
		)
		(fp_line
			(start -0.120396 0.2794)
			(end 0.12065 0.2794)
			(stroke
				(width 0.1)
				(type default)
			)
			(layer "B.Fab")
		)
		(fp_line
			(start 0.67945 0.3048)
			(end 0.67945 -0.305054)
			(stroke
				(width 0.1)
				(type default)
			)
			(layer "B.Fab")
		)
		(fp_line
			(start 0.12065 0.3048)
			(end 0.67945 0.3048)
			(stroke
				(width 0.1)
				(type default)
			)
			(layer "B.Fab")
		)
		(fp_line
			(start -0.120396 0.3048)
			(end -0.120396 0.2794)
			(stroke
				(width 0.1)
				(type default)
			)
			(layer "B.Fab")
		)
		(fp_line
			(start -0.67945 0.3048)
			(end -0.120396 0.3048)
			(stroke
				(width 0.1)
				(type default)
			)
			(layer "B.Fab")
		)
		(pad "1" smd circle
			(at 0.40005 0 270)
			(size 0 0)
			(layers "B.Cu" "B.Mask" "B.Paste")
			(net "P0V9_CPU0_RT_2D")
		)
		(pad "2" smd circle
			(at -0.40005 0 270)
			(size 0 0)
			(layers "B.Cu" "B.Mask" "B.Paste")
			(net "GND")
		)
	)
	(footprint ""
		(layer "B.Cu")
		(at 182.732172 -111.863124 -90)
		(property "Reference" "C1127"
			(at 0 0 90)
			(layer "B.SilkS")
			(hide yes)
			(effects
				(font
					(size 1.27 1.27)
				)
				(justify mirror)
			)
		)
		(property "Value" ""
			(at 0 0 90)
			(layer "B.Fab")
			(effects
				(font
					(size 1.27 1.27)
				)
				(justify mirror)
			)
		)
		(duplicate_pad_numbers_are_jumpers no)
		(fp_line
			(start -0.69215 0.2921)
			(end 0.69215 0.2921)
			(stroke
				(width 0.1524)
				(type default)
			)
			(layer "B.SilkS")
		)
		(fp_line
			(start 0.69215 0.2921)
			(end 0.69215 -0.2921)
			(stroke
				(width 0.1524)
				(type default)
			)
			(layer "B.SilkS")
		)
		(fp_line
			(start -0.69215 -0.2921)
			(end -0.69215 0.2921)
			(stroke
				(width 0.1524)
				(type default)
			)
			(layer "B.SilkS")
		)
		(fp_line
			(start 0.69215 -0.2921)
			(end -0.69215 -0.2921)
			(stroke
				(width 0.1524)
				(type default)
			)
			(layer "B.SilkS")
		)
		(fp_line
			(start -0.51435 0.2794)
			(end 0.51435 0.2794)
			(stroke
				(width 0.1)
				(type default)
			)
			(layer "B.Fab")
		)
		(fp_line
			(start 0.51435 0.2794)
			(end 0.51435 -0.2794)
			(stroke
				(width 0.1)
				(type default)
			)
			(layer "B.Fab")
		)
		(fp_line
			(start -0.51435 -0.2794)
			(end -0.51435 0.2794)
			(stroke
				(width 0.1)
				(type default)
			)
			(layer "B.Fab")
		)
		(fp_line
			(start 0.51435 -0.2794)
			(end -0.51435 -0.2794)
			(stroke
				(width 0.1)
				(type default)
			)
			(layer "B.Fab")
		)
		(pad "1" smd circle
			(at 0.40005 0 90)
			(size 0 0)
			(layers "B.Cu" "B.Mask" "B.Paste")
			(net "P1V8_AUX")
		)
		(pad "2" smd circle
			(at -0.40005 0 90)
			(size 0 0)
			(layers "B.Cu" "B.Mask" "B.Paste")
			(net "GND")
		)
		(zone
			(layer "B.Cu")
			(hatch none 0.5)
			(connect_pads
				(clearance 0)
			)
			(min_thickness 0.25)
			(keepout
				(tracks not_allowed)
				(vias allowed)
				(pads allowed)
				(copperpour not_allowed)
				(footprints allowed)
			)
			(placement
				(enabled no)
				(sheetname "")
			)
			(fill
				(thermal_gap 0.5)
				(thermal_bridge_width 0.5)
				(island_removal_mode 0)
			)
			(polygon
				(pts
					(xy 182.586376 -111.764064) (xy 182.586376 -111.963454) (xy 182.644542 -112.053624) (xy 182.819802 -112.053624)
					(xy 182.878222 -111.963454) (xy 182.878222 -111.764064) (xy 182.820056 -111.672624) (xy 182.644542 -111.672624)
				)
			)
		)
	)
	(footprint ""
		(layer "B.Cu")
		(at 90.719148 -390.560052 90)
		(property "Reference" "C327"
			(at 0 0 90)
			(layer "B.SilkS")
			(hide yes)
			(effects
				(font
					(size 1.27 1.27)
				)
				(justify mirror)
			)
		)
		(property "Value" ""
			(at 0 0 90)
			(layer "B.Fab")
			(effects
				(font
					(size 1.27 1.27)
				)
				(justify mirror)
			)
		)
		(duplicate_pad_numbers_are_jumpers no)
		(fp_line
			(start 0.7874 -0.4064)
			(end -0.7874 -0.4064)
			(stroke
				(width 0.1524)
				(type default)
			)
			(layer "B.SilkS")
		)
		(fp_line
			(start -0.7874 -0.4064)
			(end -0.7874 0.4064)
			(stroke
				(width 0.1524)
				(type default)
			)
			(layer "B.SilkS")
		)
		(fp_line
			(start 0.7874 0.4064)
			(end 0.7874 -0.4064)
			(stroke
				(width 0.1524)
				(type default)
			)
			(layer "B.SilkS")
		)
		(fp_line
			(start -0.7874 0.4064)
			(end 0.7874 0.4064)
			(stroke
				(width 0.1524)
				(type default)
			)
			(layer "B.SilkS")
		)
		(fp_line
			(start 0.67945 -0.305054)
			(end 0.12065 -0.305054)
			(stroke
				(width 0.1)
				(type default)
			)
			(layer "B.Fab")
		)
		(fp_line
			(start 0.12065 -0.305054)
			(end 0.12065 -0.2794)
			(stroke
				(width 0.1)
				(type default)
			)
			(layer "B.Fab")
		)
		(fp_line
			(start -0.12065 -0.3048)
			(end -0.67945 -0.3048)
			(stroke
				(width 0.1)
				(type default)
			)
			(layer "B.Fab")
		)
		(fp_line
			(start -0.67945 -0.3048)
			(end -0.67945 0.3048)
			(stroke
				(width 0.1)
				(type default)
			)
			(layer "B.Fab")
		)
		(fp_line
			(start 0.12065 -0.2794)
			(end -0.12065 -0.2794)
			(stroke
				(width 0.1)
				(type default)
			)
			(layer "B.Fab")
		)
		(fp_line
			(start -0.12065 -0.2794)
			(end -0.12065 -0.3048)
			(stroke
				(width 0.1)
				(type default)
			)
			(layer "B.Fab")
		)
		(fp_line
			(start 0.12065 0.2794)
			(end 0.12065 0.3048)
			(stroke
				(width 0.1)
				(type default)
			)
			(layer "B.Fab")
		)
		(fp_line
			(start -0.120396 0.2794)
			(end 0.12065 0.2794)
			(stroke
				(width 0.1)
				(type default)
			)
			(layer "B.Fab")
		)
		(fp_line
			(start 0.67945 0.3048)
			(end 0.67945 -0.305054)
			(stroke
				(width 0.1)
				(type default)
			)
			(layer "B.Fab")
		)
		(fp_line
			(start 0.12065 0.3048)
			(end 0.67945 0.3048)
			(stroke
				(width 0.1)
				(type default)
			)
			(layer "B.Fab")
		)
		(fp_line
			(start -0.120396 0.3048)
			(end -0.120396 0.2794)
			(stroke
				(width 0.1)
				(type default)
			)
			(layer "B.Fab")
		)
		(fp_line
			(start -0.67945 0.3048)
			(end -0.120396 0.3048)
			(stroke
				(width 0.1)
				(type default)
			)
			(layer "B.Fab")
		)
		(pad "1" smd circle
			(at 0.40005 0 270)
			(size 0 0)
			(layers "B.Cu" "B.Mask" "B.Paste")
			(net "P0V9_CPU1_RT_2D")
		)
		(pad "2" smd circle
			(at -0.40005 0 270)
			(size 0 0)
			(layers "B.Cu" "B.Mask" "B.Paste")
			(net "GND")
		)
	)
	(footprint ""
		(layer "B.Cu")
		(at 397.637508 -341.168736 -90)
		(property "Reference" "R942"
			(at 0 0 90)
			(layer "B.SilkS")
			(hide yes)
			(effects
				(font
					(size 1.27 1.27)
				)
				(justify mirror)
			)
		)
		(property "Value" ""
			(at 0 0 90)
			(layer "B.Fab")
			(effects
				(font
					(size 1.27 1.27)
				)
				(justify mirror)
			)
		)
		(duplicate_pad_numbers_are_jumpers no)
		(fp_line
			(start -0.7874 0.4064)
			(end 0.7874 0.4064)
			(stroke
				(width 0.1524)
				(type default)
			)
			(layer "B.SilkS")
		)
		(fp_line
			(start 0.7874 0.4064)
			(end 0.7874 -0.4064)
			(stroke
				(width 0.1524)
				(type default)
			)
			(layer "B.SilkS")
		)
		(fp_line
			(start -0.7874 -0.4064)
			(end -0.7874 0.4064)
			(stroke
				(width 0.1524)
				(type default)
			)
			(layer "B.SilkS")
		)
		(fp_line
			(start 0.7874 -0.4064)
			(end -0.7874 -0.4064)
			(stroke
				(width 0.1524)
				(type default)
			)
			(layer "B.SilkS")
		)
		(fp_line
			(start -0.67945 0.3048)
			(end -0.120396 0.3048)
			(stroke
				(width 0.1)
				(type default)
			)
			(layer "B.Fab")
		)
		(fp_line
			(start -0.120396 0.3048)
			(end -0.120396 0.2794)
			(stroke
				(width 0.1)
				(type default)
			)
			(layer "B.Fab")
		)
		(fp_line
			(start 0.12065 0.3048)
			(end 0.67945 0.3048)
			(stroke
				(width 0.1)
				(type default)
			)
			(layer "B.Fab")
		)
		(fp_line
			(start 0.67945 0.3048)
			(end 0.67945 -0.305054)
			(stroke
				(width 0.1)
				(type default)
			)
			(layer "B.Fab")
		)
		(fp_line
			(start -0.120396 0.2794)
			(end 0.12065 0.2794)
			(stroke
				(width 0.1)
				(type default)
			)
			(layer "B.Fab")
		)
		(fp_line
			(start 0.12065 0.2794)
			(end 0.12065 0.3048)
			(stroke
				(width 0.1)
				(type default)
			)
			(layer "B.Fab")
		)
		(fp_line
			(start -0.12065 -0.2794)
			(end -0.12065 -0.3048)
			(stroke
				(width 0.1)
				(type default)
			)
			(layer "B.Fab")
		)
		(fp_line
			(start 0.12065 -0.2794)
			(end -0.12065 -0.2794)
			(stroke
				(width 0.1)
				(type default)
			)
			(layer "B.Fab")
		)
		(fp_line
			(start -0.67945 -0.3048)
			(end -0.67945 0.3048)
			(stroke
				(width 0.1)
				(type default)
			)
			(layer "B.Fab")
		)
		(fp_line
			(start -0.12065 -0.3048)
			(end -0.67945 -0.3048)
			(stroke
				(width 0.1)
				(type default)
			)
			(layer "B.Fab")
		)
		(fp_line
			(start 0.12065 -0.305054)
			(end 0.12065 -0.2794)
			(stroke
				(width 0.1)
				(type default)
			)
			(layer "B.Fab")
		)
		(fp_line
			(start 0.67945 -0.305054)
			(end 0.12065 -0.305054)
			(stroke
				(width 0.1)
				(type default)
			)
			(layer "B.Fab")
		)
		(pad "1" smd circle
			(at 0.40005 0 90)
			(size 0 0)
			(layers "B.Cu" "B.Mask" "B.Paste")
			(net "PVDD18_S5_P0")
		)
		(pad "2" smd circle
			(at -0.40005 0 90)
			(size 0 0)
			(layers "B.Cu" "B.Mask" "B.Paste")
			(net "FM_BIOS_POST_CMPLT_N")
		)
	)
	(footprint ""
		(layer "B.Cu")
		(at 117.895624 -256.505456)
		(property "Reference" "C2430"
			(at 0 0 0)
			(layer "B.SilkS")
			(hide yes)
			(effects
				(font
					(size 1.27 1.27)
				)
				(justify mirror)
			)
		)
		(property "Value" ""
			(at 0 0 0)
			(layer "B.Fab")
			(effects
				(font
					(size 1.27 1.27)
				)
				(justify mirror)
			)
		)
		(duplicate_pad_numbers_are_jumpers no)
		(fp_line
			(start -0.7874 -0.4064)
			(end -0.7874 0.4064)
			(stroke
				(width 0.1524)
				(type default)
			)
			(layer "B.SilkS")
		)
		(fp_line
			(start -0.7874 0.4064)
			(end 0.7874 0.4064)
			(stroke
				(width 0.1524)
				(type default)
			)
			(layer "B.SilkS")
		)
		(fp_line
			(start 0.7874 -0.4064)
			(end -0.7874 -0.4064)
			(stroke
				(width 0.1524)
				(type default)
			)
			(layer "B.SilkS")
		)
		(fp_line
			(start 0.7874 0.4064)
			(end 0.7874 -0.4064)
			(stroke
				(width 0.1524)
				(type default)
			)
			(layer "B.SilkS")
		)
		(fp_line
			(start -0.67945 -0.3048)
			(end -0.67945 0.3048)
			(stroke
				(width 0.1)
				(type default)
			)
			(layer "B.Fab")
		)
		(fp_line
			(start -0.67945 0.3048)
			(end -0.120396 0.3048)
			(stroke
				(width 0.1)
				(type default)
			)
			(layer "B.Fab")
		)
		(fp_line
			(start -0.12065 -0.3048)
			(end -0.67945 -0.3048)
			(stroke
				(width 0.1)
				(type default)
			)
			(layer "B.Fab")
		)
		(fp_line
			(start -0.12065 -0.2794)
			(end -0.12065 -0.3048)
			(stroke
				(width 0.1)
				(type default)
			)
			(layer "B.Fab")
		)
		(fp_line
			(start -0.120396 0.2794)
			(end 0.12065 0.2794)
			(stroke
				(width 0.1)
				(type default)
			)
			(layer "B.Fab")
		)
		(fp_line
			(start -0.120396 0.3048)
			(end -0.120396 0.2794)
			(stroke
				(width 0.1)
				(type default)
			)
			(layer "B.Fab")
		)
		(fp_line
			(start 0.12065 -0.305054)
			(end 0.12065 -0.2794)
			(stroke
				(width 0.1)
				(type default)
			)
			(layer "B.Fab")
		)
		(fp_line
			(start 0.12065 -0.2794)
			(end -0.12065 -0.2794)
			(stroke
				(width 0.1)
				(type default)
			)
			(layer "B.Fab")
		)
		(fp_line
			(start 0.12065 0.2794)
			(end 0.12065 0.3048)
			(stroke
				(width 0.1)
				(type default)
			)
			(layer "B.Fab")
		)
		(fp_line
			(start 0.12065 0.3048)
			(end 0.67945 0.3048)
			(stroke
				(width 0.1)
				(type default)
			)
			(layer "B.Fab")
		)
		(fp_line
			(start 0.67945 -0.305054)
			(end 0.12065 -0.305054)
			(stroke
				(width 0.1)
				(type default)
			)
			(layer "B.Fab")
		)
		(fp_line
			(start 0.67945 0.3048)
			(end 0.67945 -0.305054)
			(stroke
				(width 0.1)
				(type default)
			)
			(layer "B.Fab")
		)
		(pad "1" smd circle
			(at 0.40005 0 180)
			(size 0 0)
			(layers "B.Cu" "B.Mask" "B.Paste")
			(net "PVDDCR_SOC_P1")
		)
		(pad "2" smd circle
			(at -0.40005 0 180)
			(size 0 0)
			(layers "B.Cu" "B.Mask" "B.Paste")
			(net "GND")
		)
	)
	(footprint ""
		(layer "B.Cu")
		(at 367.671858 -136.986772)
		(property "Reference" "C461"
			(at 0 0 0)
			(layer "B.SilkS")
			(hide yes)
			(effects
				(font
					(size 1.27 1.27)
				)
				(justify mirror)
			)
		)
		(property "Value" ""
			(at 0 0 0)
			(layer "B.Fab")
			(effects
				(font
					(size 1.27 1.27)
				)
				(justify mirror)
			)
		)
		(duplicate_pad_numbers_are_jumpers no)
		(fp_line
			(start -0.7874 -0.4064)
			(end -0.7874 0.4064)
			(stroke
				(width 0.1524)
				(type default)
			)
			(layer "B.SilkS")
		)
		(fp_line
			(start -0.7874 0.4064)
			(end 0.7874 0.4064)
			(stroke
				(width 0.1524)
				(type default)
			)
			(layer "B.SilkS")
		)
		(fp_line
			(start 0.7874 -0.4064)
			(end -0.7874 -0.4064)
			(stroke
				(width 0.1524)
				(type default)
			)
			(layer "B.SilkS")
		)
		(fp_line
			(start 0.7874 0.4064)
			(end 0.7874 -0.4064)
			(stroke
				(width 0.1524)
				(type default)
			)
			(layer "B.SilkS")
		)
		(fp_line
			(start -0.67945 -0.3048)
			(end -0.67945 0.3048)
			(stroke
				(width 0.1)
				(type default)
			)
			(layer "B.Fab")
		)
		(fp_line
			(start -0.67945 0.3048)
			(end -0.120396 0.3048)
			(stroke
				(width 0.1)
				(type default)
			)
			(layer "B.Fab")
		)
		(fp_line
			(start -0.12065 -0.3048)
			(end -0.67945 -0.3048)
			(stroke
				(width 0.1)
				(type default)
			)
			(layer "B.Fab")
		)
		(fp_line
			(start -0.12065 -0.2794)
			(end -0.12065 -0.3048)
			(stroke
				(width 0.1)
				(type default)
			)
			(layer "B.Fab")
		)
		(fp_line
			(start -0.120396 0.2794)
			(end 0.12065 0.2794)
			(stroke
				(width 0.1)
				(type default)
			)
			(layer "B.Fab")
		)
		(fp_line
			(start -0.120396 0.3048)
			(end -0.120396 0.2794)
			(stroke
				(width 0.1)
				(type default)
			)
			(layer "B.Fab")
		)
		(fp_line
			(start 0.12065 -0.305054)
			(end 0.12065 -0.2794)
			(stroke
				(width 0.1)
				(type default)
			)
			(layer "B.Fab")
		)
		(fp_line
			(start 0.12065 -0.2794)
			(end -0.12065 -0.2794)
			(stroke
				(width 0.1)
				(type default)
			)
			(layer "B.Fab")
		)
		(fp_line
			(start 0.12065 0.2794)
			(end 0.12065 0.3048)
			(stroke
				(width 0.1)
				(type default)
			)
			(layer "B.Fab")
		)
		(fp_line
			(start 0.12065 0.3048)
			(end 0.67945 0.3048)
			(stroke
				(width 0.1)
				(type default)
			)
			(layer "B.Fab")
		)
		(fp_line
			(start 0.67945 -0.305054)
			(end 0.12065 -0.305054)
			(stroke
				(width 0.1)
				(type default)
			)
			(layer "B.Fab")
		)
		(fp_line
			(start 0.67945 0.3048)
			(end 0.67945 -0.305054)
			(stroke
				(width 0.1)
				(type default)
			)
			(layer "B.Fab")
		)
		(pad "1" smd circle
			(at 0.40005 0 180)
			(size 0 0)
			(layers "B.Cu" "B.Mask" "B.Paste")
			(net "PVDDCR_SOC_P0_EN_RC")
		)
		(pad "2" smd circle
			(at -0.40005 0 180)
			(size 0 0)
			(layers "B.Cu" "B.Mask" "B.Paste")
			(net "GND")
		)
	)
	(footprint ""
		(layer "B.Cu")
		(at 119.674386 -264.354564)
		(property "Reference" "C2119"
			(at 0 0 0)
			(layer "B.SilkS")
			(hide yes)
			(effects
				(font
					(size 1.27 1.27)
				)
				(justify mirror)
			)
		)
		(property "Value" ""
			(at 0 0 0)
			(layer "B.Fab")
			(effects
				(font
					(size 1.27 1.27)
				)
				(justify mirror)
			)
		)
		(duplicate_pad_numbers_are_jumpers no)
		(fp_line
			(start -0.7874 -0.4064)
			(end -0.7874 0.4064)
			(stroke
				(width 0.1524)
				(type default)
			)
			(layer "B.SilkS")
		)
		(fp_line
			(start -0.7874 0.4064)
			(end 0.7874 0.4064)
			(stroke
				(width 0.1524)
				(type default)
			)
			(layer "B.SilkS")
		)
		(fp_line
			(start 0.7874 -0.4064)
			(end -0.7874 -0.4064)
			(stroke
				(width 0.1524)
				(type default)
			)
			(layer "B.SilkS")
		)
		(fp_line
			(start 0.7874 0.4064)
			(end 0.7874 -0.4064)
			(stroke
				(width 0.1524)
				(type default)
			)
			(layer "B.SilkS")
		)
		(fp_line
			(start -0.67945 -0.3048)
			(end -0.67945 0.3048)
			(stroke
				(width 0.1)
				(type default)
			)
			(layer "B.Fab")
		)
		(fp_line
			(start -0.67945 0.3048)
			(end -0.120396 0.3048)
			(stroke
				(width 0.1)
				(type default)
			)
			(layer "B.Fab")
		)
		(fp_line
			(start -0.12065 -0.3048)
			(end -0.67945 -0.3048)
			(stroke
				(width 0.1)
				(type default)
			)
			(layer "B.Fab")
		)
		(fp_line
			(start -0.12065 -0.2794)
			(end -0.12065 -0.3048)
			(stroke
				(width 0.1)
				(type default)
			)
			(layer "B.Fab")
		)
		(fp_line
			(start -0.120396 0.2794)
			(end 0.12065 0.2794)
			(stroke
				(width 0.1)
				(type default)
			)
			(layer "B.Fab")
		)
		(fp_line
			(start -0.120396 0.3048)
			(end -0.120396 0.2794)
			(stroke
				(width 0.1)
				(type default)
			)
			(layer "B.Fab")
		)
		(fp_line
			(start 0.12065 -0.305054)
			(end 0.12065 -0.2794)
			(stroke
				(width 0.1)
				(type default)
			)
			(layer "B.Fab")
		)
		(fp_line
			(start 0.12065 -0.2794)
			(end -0.12065 -0.2794)
			(stroke
				(width 0.1)
				(type default)
			)
			(layer "B.Fab")
		)
		(fp_line
			(start 0.12065 0.2794)
			(end 0.12065 0.3048)
			(stroke
				(width 0.1)
				(type default)
			)
			(layer "B.Fab")
		)
		(fp_line
			(start 0.12065 0.3048)
			(end 0.67945 0.3048)
			(stroke
				(width 0.1)
				(type default)
			)
			(layer "B.Fab")
		)
		(fp_line
			(start 0.67945 -0.305054)
			(end 0.12065 -0.305054)
			(stroke
				(width 0.1)
				(type default)
			)
			(layer "B.Fab")
		)
		(fp_line
			(start 0.67945 0.3048)
			(end 0.67945 -0.305054)
			(stroke
				(width 0.1)
				(type default)
			)
			(layer "B.Fab")
		)
		(pad "1" smd circle
			(at 0.40005 0 180)
			(size 0 0)
			(layers "B.Cu" "B.Mask" "B.Paste")
			(net "PVDD11_S3_P1")
		)
		(pad "2" smd circle
			(at -0.40005 0 180)
			(size 0 0)
			(layers "B.Cu" "B.Mask" "B.Paste")
			(net "GND")
		)
	)
	(footprint ""
		(layer "B.Cu")
		(at 139.562586 -389.673084 90)
		(property "Reference" "C404"
			(at 0 0 90)
			(layer "B.SilkS")
			(hide yes)
			(effects
				(font
					(size 1.27 1.27)
				)
				(justify mirror)
			)
		)
		(property "Value" ""
			(at 0 0 90)
			(layer "B.Fab")
			(effects
				(font
					(size 1.27 1.27)
				)
				(justify mirror)
			)
		)
		(duplicate_pad_numbers_are_jumpers no)
		(fp_line
			(start 1.524 -0.762)
			(end -1.524 -0.762)
			(stroke
				(width 0.1524)
				(type default)
			)
			(layer "B.SilkS")
		)
		(fp_line
			(start -1.524 -0.762)
			(end -1.524 0.762)
			(stroke
				(width 0.1524)
				(type default)
			)
			(layer "B.SilkS")
		)
		(fp_line
			(start 1.524 0.762)
			(end 1.524 -0.762)
			(stroke
				(width 0.1524)
				(type default)
			)
			(layer "B.SilkS")
		)
		(fp_line
			(start -1.524 0.762)
			(end 1.524 0.762)
			(stroke
				(width 0.1524)
				(type default)
			)
			(layer "B.SilkS")
		)
		(fp_line
			(start 1.1049 -0.724916)
			(end 1.1049 0.724916)
			(stroke
				(width 0.1)
				(type default)
			)
			(layer "B.Fab")
		)
		(fp_line
			(start -1.1049 -0.724916)
			(end 1.1049 -0.724916)
			(stroke
				(width 0.1)
				(type default)
			)
			(layer "B.Fab")
		)
		(fp_line
			(start 1.1049 0.724916)
			(end -1.1049 0.724916)
			(stroke
				(width 0.1)
				(type default)
			)
			(layer "B.Fab")
		)
		(fp_line
			(start -1.1049 0.724916)
			(end -1.1049 -0.724916)
			(stroke
				(width 0.1)
				(type default)
			)
			(layer "B.Fab")
		)
		(pad "1" smd rect
			(at 0.889 0 90)
			(size 1.016 1.27)
			(layers "B.Cu" "B.Mask" "B.Paste")
			(net "P0V9_CPU1_RT_2D")
		)
		(pad "2" smd rect
			(at -0.889 0 90)
			(size 1.016 1.27)
			(layers "B.Cu" "B.Mask" "B.Paste")
			(net "GND")
		)
	)
	(footprint ""
		(layer "B.Cu")
		(at 370.618512 -396.393162 -90)
		(property "Reference" "C1052"
			(at 0 0 90)
			(layer "B.SilkS")
			(hide yes)
			(effects
				(font
					(size 1.27 1.27)
				)
				(justify mirror)
			)
		)
		(property "Value" ""
			(at 0 0 90)
			(layer "B.Fab")
			(effects
				(font
					(size 1.27 1.27)
				)
				(justify mirror)
			)
		)
		(duplicate_pad_numbers_are_jumpers no)
		(fp_line
			(start -0.299974 0.150114)
			(end 0.299974 0.150114)
			(stroke
				(width 0.1)
				(type default)
			)
			(layer "B.Fab")
		)
		(fp_line
			(start 0.299974 0.150114)
			(end 0.299974 -0.150114)
			(stroke
				(width 0.1)
				(type default)
			)
			(layer "B.Fab")
		)
		(fp_line
			(start -0.299974 -0.150114)
			(end -0.299974 0.150114)
			(stroke
				(width 0.1)
				(type default)
			)
			(layer "B.Fab")
		)
		(fp_line
			(start 0.299974 -0.150114)
			(end -0.299974 -0.150114)
			(stroke
				(width 0.1)
				(type default)
			)
			(layer "B.Fab")
		)
		(pad "1" smd rect
			(at 0.2667 0 90)
			(size 0.3048 0.381)
			(layers "B.Cu" "B.Mask" "B.Paste")
			(net "P0V9_CPU0_RT3_2A")
		)
		(pad "2" smd rect
			(at -0.2667 0 90)
			(size 0.3048 0.381)
			(layers "B.Cu" "B.Mask" "B.Paste")
			(net "GND")
		)
	)
	(footprint ""
		(layer "B.Cu")
		(at 365.519462 -398.969484)
		(property "Reference" "C1029"
			(at 0 0 0)
			(layer "B.SilkS")
			(hide yes)
			(effects
				(font
					(size 1.27 1.27)
				)
				(justify mirror)
			)
		)
		(property "Value" ""
			(at 0 0 0)
			(layer "B.Fab")
			(effects
				(font
					(size 1.27 1.27)
				)
				(justify mirror)
			)
		)
		(duplicate_pad_numbers_are_jumpers no)
		(fp_line
			(start -1.524 -0.762)
			(end -1.524 0.762)
			(stroke
				(width 0.1524)
				(type default)
			)
			(layer "B.SilkS")
		)
		(fp_line
			(start -1.524 0.762)
			(end 1.524 0.762)
			(stroke
				(width 0.1524)
				(type default)
			)
			(layer "B.SilkS")
		)
		(fp_line
			(start 1.524 -0.762)
			(end -1.524 -0.762)
			(stroke
				(width 0.1524)
				(type default)
			)
			(layer "B.SilkS")
		)
		(fp_line
			(start 1.524 0.762)
			(end 1.524 -0.762)
			(stroke
				(width 0.1524)
				(type default)
			)
			(layer "B.SilkS")
		)
		(fp_line
			(start -1.1049 -0.724916)
			(end 1.1049 -0.724916)
			(stroke
				(width 0.1)
				(type default)
			)
			(layer "B.Fab")
		)
		(fp_line
			(start -1.1049 0.724916)
			(end -1.1049 -0.724916)
			(stroke
				(width 0.1)
				(type default)
			)
			(layer "B.Fab")
		)
		(fp_line
			(start 1.1049 -0.724916)
			(end 1.1049 0.724916)
			(stroke
				(width 0.1)
				(type default)
			)
			(layer "B.Fab")
		)
		(fp_line
			(start 1.1049 0.724916)
			(end -1.1049 0.724916)
			(stroke
				(width 0.1)
				(type default)
			)
			(layer "B.Fab")
		)
		(pad "1" smd rect
			(at 0.889 0)
			(size 1.016 1.27)
			(layers "B.Cu" "B.Mask" "B.Paste")
			(net "P0V9_CPU0_RT3_2A")
		)
		(pad "2" smd rect
			(at -0.889 0)
			(size 1.016 1.27)
			(layers "B.Cu" "B.Mask" "B.Paste")
			(net "GND")
		)
	)
	(footprint ""
		(layer "B.Cu")
		(at 241.427 -234.061 -90)
		(property "Reference" "R145"
			(at 0 0 90)
			(layer "B.SilkS")
			(hide yes)
			(effects
				(font
					(size 1.27 1.27)
				)
				(justify mirror)
			)
		)
		(property "Value" ""
			(at 0 0 90)
			(layer "B.Fab")
			(effects
				(font
					(size 1.27 1.27)
				)
				(justify mirror)
			)
		)
		(duplicate_pad_numbers_are_jumpers no)
		(fp_line
			(start -0.7874 0.4064)
			(end 0.7874 0.4064)
			(stroke
				(width 0.1524)
				(type default)
			)
			(layer "B.SilkS")
		)
		(fp_line
			(start 0.7874 0.4064)
			(end 0.7874 -0.4064)
			(stroke
				(width 0.1524)
				(type default)
			)
			(layer "B.SilkS")
		)
		(fp_line
			(start -0.7874 -0.4064)
			(end -0.7874 0.4064)
			(stroke
				(width 0.1524)
				(type default)
			)
			(layer "B.SilkS")
		)
		(fp_line
			(start 0.7874 -0.4064)
			(end -0.7874 -0.4064)
			(stroke
				(width 0.1524)
				(type default)
			)
			(layer "B.SilkS")
		)
		(fp_line
			(start -0.67945 0.3048)
			(end -0.120396 0.3048)
			(stroke
				(width 0.1)
				(type default)
			)
			(layer "B.Fab")
		)
		(fp_line
			(start -0.120396 0.3048)
			(end -0.120396 0.2794)
			(stroke
				(width 0.1)
				(type default)
			)
			(layer "B.Fab")
		)
		(fp_line
			(start 0.12065 0.3048)
			(end 0.67945 0.3048)
			(stroke
				(width 0.1)
				(type default)
			)
			(layer "B.Fab")
		)
		(fp_line
			(start 0.67945 0.3048)
			(end 0.67945 -0.305054)
			(stroke
				(width 0.1)
				(type default)
			)
			(layer "B.Fab")
		)
		(fp_line
			(start -0.120396 0.2794)
			(end 0.12065 0.2794)
			(stroke
				(width 0.1)
				(type default)
			)
			(layer "B.Fab")
		)
		(fp_line
			(start 0.12065 0.2794)
			(end 0.12065 0.3048)
			(stroke
				(width 0.1)
				(type default)
			)
			(layer "B.Fab")
		)
		(fp_line
			(start -0.12065 -0.2794)
			(end -0.12065 -0.3048)
			(stroke
				(width 0.1)
				(type default)
			)
			(layer "B.Fab")
		)
		(fp_line
			(start 0.12065 -0.2794)
			(end -0.12065 -0.2794)
			(stroke
				(width 0.1)
				(type default)
			)
			(layer "B.Fab")
		)
		(fp_line
			(start -0.67945 -0.3048)
			(end -0.67945 0.3048)
			(stroke
				(width 0.1)
				(type default)
			)
			(layer "B.Fab")
		)
		(fp_line
			(start -0.12065 -0.3048)
			(end -0.67945 -0.3048)
			(stroke
				(width 0.1)
				(type default)
			)
			(layer "B.Fab")
		)
		(fp_line
			(start 0.12065 -0.305054)
			(end 0.12065 -0.2794)
			(stroke
				(width 0.1)
				(type default)
			)
			(layer "B.Fab")
		)
		(fp_line
			(start 0.67945 -0.305054)
			(end 0.12065 -0.305054)
			(stroke
				(width 0.1)
				(type default)
			)
			(layer "B.Fab")
		)
		(pad "1" smd circle
			(at 0.40005 0 90)
			(size 0 0)
			(layers "B.Cu" "B.Mask" "B.Paste")
			(net "SMB_CPU0_CPU1_SEC_SCL_R2")
		)
		(pad "2" smd circle
			(at -0.40005 0 90)
			(size 0 0)
			(layers "B.Cu" "B.Mask" "B.Paste")
			(net "SMB_CPU0_SEC_R_SCL")
		)
	)
	(footprint ""
		(layer "B.Cu")
		(at 304.419 -355.854 180)
		(property "Reference" "R8042"
			(at 0 0 0)
			(layer "B.SilkS")
			(hide yes)
			(effects
				(font
					(size 1.27 1.27)
				)
				(justify mirror)
			)
		)
		(property "Value" ""
			(at 0 0 0)
			(layer "B.Fab")
			(effects
				(font
					(size 1.27 1.27)
				)
				(justify mirror)
			)
		)
		(duplicate_pad_numbers_are_jumpers no)
		(fp_line
			(start 0.7874 0.4064)
			(end 0.7874 -0.4064)
			(stroke
				(width 0.1524)
				(type default)
			)
			(layer "B.SilkS")
		)
		(fp_line
			(start 0.7874 -0.4064)
			(end -0.7874 -0.4064)
			(stroke
				(width 0.1524)
				(type default)
			)
			(layer "B.SilkS")
		)
		(fp_line
			(start -0.7874 0.4064)
			(end 0.7874 0.4064)
			(stroke
				(width 0.1524)
				(type default)
			)
			(layer "B.SilkS")
		)
		(fp_line
			(start -0.7874 -0.4064)
			(end -0.7874 0.4064)
			(stroke
				(width 0.1524)
				(type default)
			)
			(layer "B.SilkS")
		)
		(fp_line
			(start 0.67945 0.3048)
			(end 0.67945 -0.305054)
			(stroke
				(width 0.1)
				(type default)
			)
			(layer "B.Fab")
		)
		(fp_line
			(start 0.67945 -0.305054)
			(end 0.12065 -0.305054)
			(stroke
				(width 0.1)
				(type default)
			)
			(layer "B.Fab")
		)
		(fp_line
			(start 0.12065 0.3048)
			(end 0.67945 0.3048)
			(stroke
				(width 0.1)
				(type default)
			)
			(layer "B.Fab")
		)
		(fp_line
			(start 0.12065 0.2794)
			(end 0.12065 0.3048)
			(stroke
				(width 0.1)
				(type default)
			)
			(layer "B.Fab")
		)
		(fp_line
			(start 0.12065 -0.2794)
			(end -0.12065 -0.2794)
			(stroke
				(width 0.1)
				(type default)
			)
			(layer "B.Fab")
		)
		(fp_line
			(start 0.12065 -0.305054)
			(end 0.12065 -0.2794)
			(stroke
				(width 0.1)
				(type default)
			)
			(layer "B.Fab")
		)
		(fp_line
			(start -0.120396 0.3048)
			(end -0.120396 0.2794)
			(stroke
				(width 0.1)
				(type default)
			)
			(layer "B.Fab")
		)
		(fp_line
			(start -0.120396 0.2794)
			(end 0.12065 0.2794)
			(stroke
				(width 0.1)
				(type default)
			)
			(layer "B.Fab")
		)
		(fp_line
			(start -0.12065 -0.2794)
			(end -0.12065 -0.3048)
			(stroke
				(width 0.1)
				(type default)
			)
			(layer "B.Fab")
		)
		(fp_line
			(start -0.12065 -0.3048)
			(end -0.67945 -0.3048)
			(stroke
				(width 0.1)
				(type default)
			)
			(layer "B.Fab")
		)
		(fp_line
			(start -0.67945 0.3048)
			(end -0.120396 0.3048)
			(stroke
				(width 0.1)
				(type default)
			)
			(layer "B.Fab")
		)
		(fp_line
			(start -0.67945 -0.3048)
			(end -0.67945 0.3048)
			(stroke
				(width 0.1)
				(type default)
			)
			(layer "B.Fab")
		)
		(pad "1" smd circle
			(at 0.40005 0)
			(size 0 0)
			(layers "B.Cu" "B.Mask" "B.Paste")
			(net "SVID_PVDDCR_CPU1_P0_SVTO")
		)
		(pad "2" smd circle
			(at -0.40005 0)
			(size 0 0)
			(layers "B.Cu" "B.Mask" "B.Paste")
			(net "GND")
		)
	)
	(footprint ""
		(layer "B.Cu")
		(at 114.607848 -171.785534 -90)
		(property "Reference" "PC329_1"
			(at 0 0 90)
			(layer "B.SilkS")
			(hide yes)
			(effects
				(font
					(size 1.27 1.27)
				)
				(justify mirror)
			)
		)
		(property "Value" ""
			(at 0 0 90)
			(layer "B.Fab")
			(effects
				(font
					(size 1.27 1.27)
				)
				(justify mirror)
			)
		)
		(duplicate_pad_numbers_are_jumpers no)
		(fp_line
			(start -1.524 0.762)
			(end 1.524 0.762)
			(stroke
				(width 0.1524)
				(type default)
			)
			(layer "B.SilkS")
		)
		(fp_line
			(start 1.524 0.762)
			(end 1.524 -0.762)
			(stroke
				(width 0.1524)
				(type default)
			)
			(layer "B.SilkS")
		)
		(fp_line
			(start -1.524 -0.762)
			(end -1.524 0.762)
			(stroke
				(width 0.1524)
				(type default)
			)
			(layer "B.SilkS")
		)
		(fp_line
			(start 1.524 -0.762)
			(end -1.524 -0.762)
			(stroke
				(width 0.1524)
				(type default)
			)
			(layer "B.SilkS")
		)
		(fp_line
			(start -1.1049 0.724916)
			(end -1.1049 -0.724916)
			(stroke
				(width 0.1)
				(type default)
			)
			(layer "B.Fab")
		)
		(fp_line
			(start 1.1049 0.724916)
			(end -1.1049 0.724916)
			(stroke
				(width 0.1)
				(type default)
			)
			(layer "B.Fab")
		)
		(fp_line
			(start -1.1049 -0.724916)
			(end 1.1049 -0.724916)
			(stroke
				(width 0.1)
				(type default)
			)
			(layer "B.Fab")
		)
		(fp_line
			(start 1.1049 -0.724916)
			(end 1.1049 0.724916)
			(stroke
				(width 0.1)
				(type default)
			)
			(layer "B.Fab")
		)
		(pad "1" smd rect
			(at 0.889 0 270)
			(size 1.016 1.27)
			(layers "B.Cu" "B.Mask" "B.Paste")
			(net "SW_P12V_AUX_PVDDCR_SOC_P1_FLT")
		)
		(pad "2" smd rect
			(at -0.889 0 270)
			(size 1.016 1.27)
			(layers "B.Cu" "B.Mask" "B.Paste")
			(net "GND")
		)
	)
	(footprint ""
		(layer "B.Cu")
		(at 328.699876 -66.708782 90)
		(property "Reference" "R3088"
			(at 0 0 90)
			(layer "B.SilkS")
			(hide yes)
			(effects
				(font
					(size 1.27 1.27)
				)
				(justify mirror)
			)
		)
		(property "Value" ""
			(at 0 0 90)
			(layer "B.Fab")
			(effects
				(font
					(size 1.27 1.27)
				)
				(justify mirror)
			)
		)
		(duplicate_pad_numbers_are_jumpers no)
		(fp_line
			(start 0.7874 -0.4064)
			(end -0.7874 -0.4064)
			(stroke
				(width 0.1524)
				(type default)
			)
			(layer "B.SilkS")
		)
		(fp_line
			(start -0.7874 -0.4064)
			(end -0.7874 0.4064)
			(stroke
				(width 0.1524)
				(type default)
			)
			(layer "B.SilkS")
		)
		(fp_line
			(start 0.7874 0.4064)
			(end 0.7874 -0.4064)
			(stroke
				(width 0.1524)
				(type default)
			)
			(layer "B.SilkS")
		)
		(fp_line
			(start -0.7874 0.4064)
			(end 0.7874 0.4064)
			(stroke
				(width 0.1524)
				(type default)
			)
			(layer "B.SilkS")
		)
		(fp_line
			(start 0.67945 -0.305054)
			(end 0.12065 -0.305054)
			(stroke
				(width 0.1)
				(type default)
			)
			(layer "B.Fab")
		)
		(fp_line
			(start 0.12065 -0.305054)
			(end 0.12065 -0.2794)
			(stroke
				(width 0.1)
				(type default)
			)
			(layer "B.Fab")
		)
		(fp_line
			(start -0.12065 -0.3048)
			(end -0.67945 -0.3048)
			(stroke
				(width 0.1)
				(type default)
			)
			(layer "B.Fab")
		)
		(fp_line
			(start -0.67945 -0.3048)
			(end -0.67945 0.3048)
			(stroke
				(width 0.1)
				(type default)
			)
			(layer "B.Fab")
		)
		(fp_line
			(start 0.12065 -0.2794)
			(end -0.12065 -0.2794)
			(stroke
				(width 0.1)
				(type default)
			)
			(layer "B.Fab")
		)
		(fp_line
			(start -0.12065 -0.2794)
			(end -0.12065 -0.3048)
			(stroke
				(width 0.1)
				(type default)
			)
			(layer "B.Fab")
		)
		(fp_line
			(start 0.12065 0.2794)
			(end 0.12065 0.3048)
			(stroke
				(width 0.1)
				(type default)
			)
			(layer "B.Fab")
		)
		(fp_line
			(start -0.120396 0.2794)
			(end 0.12065 0.2794)
			(stroke
				(width 0.1)
				(type default)
			)
			(layer "B.Fab")
		)
		(fp_line
			(start 0.67945 0.3048)
			(end 0.67945 -0.305054)
			(stroke
				(width 0.1)
				(type default)
			)
			(layer "B.Fab")
		)
		(fp_line
			(start 0.12065 0.3048)
			(end 0.67945 0.3048)
			(stroke
				(width 0.1)
				(type default)
			)
			(layer "B.Fab")
		)
		(fp_line
			(start -0.120396 0.3048)
			(end -0.120396 0.2794)
			(stroke
				(width 0.1)
				(type default)
			)
			(layer "B.Fab")
		)
		(fp_line
			(start -0.67945 0.3048)
			(end -0.120396 0.3048)
			(stroke
				(width 0.1)
				(type default)
			)
			(layer "B.Fab")
		)
		(pad "1" smd circle
			(at 0.40005 0 270)
			(size 0 0)
			(layers "B.Cu" "B.Mask" "B.Paste")
			(net "LED_PWRGD_PVDDCR_CPU1_P0_R")
		)
		(pad "2" smd circle
			(at -0.40005 0 270)
			(size 0 0)
			(layers "B.Cu" "B.Mask" "B.Paste")
			(net "P3V3_AUX")
		)
	)
	(footprint ""
		(layer "B.Cu")
		(at 385.256278 -137.535158 90)
		(property "Reference" "PR316"
			(at 0 0 90)
			(layer "B.SilkS")
			(hide yes)
			(effects
				(font
					(size 1.27 1.27)
				)
				(justify mirror)
			)
		)
		(property "Value" ""
			(at 0 0 90)
			(layer "B.Fab")
			(effects
				(font
					(size 1.27 1.27)
				)
				(justify mirror)
			)
		)
		(duplicate_pad_numbers_are_jumpers no)
		(fp_line
			(start 0.7874 -0.4064)
			(end -0.7874 -0.4064)
			(stroke
				(width 0.1524)
				(type default)
			)
			(layer "B.SilkS")
		)
		(fp_line
			(start -0.7874 -0.4064)
			(end -0.7874 0.4064)
			(stroke
				(width 0.1524)
				(type default)
			)
			(layer "B.SilkS")
		)
		(fp_line
			(start 0.7874 0.4064)
			(end 0.7874 -0.4064)
			(stroke
				(width 0.1524)
				(type default)
			)
			(layer "B.SilkS")
		)
		(fp_line
			(start -0.7874 0.4064)
			(end 0.7874 0.4064)
			(stroke
				(width 0.1524)
				(type default)
			)
			(layer "B.SilkS")
		)
		(fp_line
			(start 0.67945 -0.305054)
			(end 0.12065 -0.305054)
			(stroke
				(width 0.1)
				(type default)
			)
			(layer "B.Fab")
		)
		(fp_line
			(start 0.12065 -0.305054)
			(end 0.12065 -0.2794)
			(stroke
				(width 0.1)
				(type default)
			)
			(layer "B.Fab")
		)
		(fp_line
			(start -0.12065 -0.3048)
			(end -0.67945 -0.3048)
			(stroke
				(width 0.1)
				(type default)
			)
			(layer "B.Fab")
		)
		(fp_line
			(start -0.67945 -0.3048)
			(end -0.67945 0.3048)
			(stroke
				(width 0.1)
				(type default)
			)
			(layer "B.Fab")
		)
		(fp_line
			(start 0.12065 -0.2794)
			(end -0.12065 -0.2794)
			(stroke
				(width 0.1)
				(type default)
			)
			(layer "B.Fab")
		)
		(fp_line
			(start -0.12065 -0.2794)
			(end -0.12065 -0.3048)
			(stroke
				(width 0.1)
				(type default)
			)
			(layer "B.Fab")
		)
		(fp_line
			(start 0.12065 0.2794)
			(end 0.12065 0.3048)
			(stroke
				(width 0.1)
				(type default)
			)
			(layer "B.Fab")
		)
		(fp_line
			(start -0.120396 0.2794)
			(end 0.12065 0.2794)
			(stroke
				(width 0.1)
				(type default)
			)
			(layer "B.Fab")
		)
		(fp_line
			(start 0.67945 0.3048)
			(end 0.67945 -0.305054)
			(stroke
				(width 0.1)
				(type default)
			)
			(layer "B.Fab")
		)
		(fp_line
			(start 0.12065 0.3048)
			(end 0.67945 0.3048)
			(stroke
				(width 0.1)
				(type default)
			)
			(layer "B.Fab")
		)
		(fp_line
			(start -0.120396 0.3048)
			(end -0.120396 0.2794)
			(stroke
				(width 0.1)
				(type default)
			)
			(layer "B.Fab")
		)
		(fp_line
			(start -0.67945 0.3048)
			(end -0.120396 0.3048)
			(stroke
				(width 0.1)
				(type default)
			)
			(layer "B.Fab")
		)
		(pad "1" smd circle
			(at 0.40005 0 270)
			(size 0 0)
			(layers "B.Cu" "B.Mask" "B.Paste")
			(net "PVDDCR_CPU0_P0_VCC")
		)
		(pad "2" smd circle
			(at -0.40005 0 270)
			(size 0 0)
			(layers "B.Cu" "B.Mask" "B.Paste")
			(net "P3V3_AUX")
		)
	)
	(footprint ""
		(layer "B.Cu")
		(at 346.373958 -265.045952)
		(property "Reference" "C2612"
			(at 0 0 0)
			(layer "B.SilkS")
			(hide yes)
			(effects
				(font
					(size 1.27 1.27)
				)
				(justify mirror)
			)
		)
		(property "Value" ""
			(at 0 0 0)
			(layer "B.Fab")
			(effects
				(font
					(size 1.27 1.27)
				)
				(justify mirror)
			)
		)
		(duplicate_pad_numbers_are_jumpers no)
		(fp_line
			(start -0.7874 -0.4064)
			(end -0.7874 0.4064)
			(stroke
				(width 0.1524)
				(type default)
			)
			(layer "B.SilkS")
		)
		(fp_line
			(start -0.7874 0.4064)
			(end 0.7874 0.4064)
			(stroke
				(width 0.1524)
				(type default)
			)
			(layer "B.SilkS")
		)
		(fp_line
			(start 0.7874 -0.4064)
			(end -0.7874 -0.4064)
			(stroke
				(width 0.1524)
				(type default)
			)
			(layer "B.SilkS")
		)
		(fp_line
			(start 0.7874 0.4064)
			(end 0.7874 -0.4064)
			(stroke
				(width 0.1524)
				(type default)
			)
			(layer "B.SilkS")
		)
		(fp_line
			(start -0.67945 -0.3048)
			(end -0.67945 0.3048)
			(stroke
				(width 0.1)
				(type default)
			)
			(layer "B.Fab")
		)
		(fp_line
			(start -0.67945 0.3048)
			(end -0.120396 0.3048)
			(stroke
				(width 0.1)
				(type default)
			)
			(layer "B.Fab")
		)
		(fp_line
			(start -0.12065 -0.3048)
			(end -0.67945 -0.3048)
			(stroke
				(width 0.1)
				(type default)
			)
			(layer "B.Fab")
		)
		(fp_line
			(start -0.12065 -0.2794)
			(end -0.12065 -0.3048)
			(stroke
				(width 0.1)
				(type default)
			)
			(layer "B.Fab")
		)
		(fp_line
			(start -0.120396 0.2794)
			(end 0.12065 0.2794)
			(stroke
				(width 0.1)
				(type default)
			)
			(layer "B.Fab")
		)
		(fp_line
			(start -0.120396 0.3048)
			(end -0.120396 0.2794)
			(stroke
				(width 0.1)
				(type default)
			)
			(layer "B.Fab")
		)
		(fp_line
			(start 0.12065 -0.305054)
			(end 0.12065 -0.2794)
			(stroke
				(width 0.1)
				(type default)
			)
			(layer "B.Fab")
		)
		(fp_line
			(start 0.12065 -0.2794)
			(end -0.12065 -0.2794)
			(stroke
				(width 0.1)
				(type default)
			)
			(layer "B.Fab")
		)
		(fp_line
			(start 0.12065 0.2794)
			(end 0.12065 0.3048)
			(stroke
				(width 0.1)
				(type default)
			)
			(layer "B.Fab")
		)
		(fp_line
			(start 0.12065 0.3048)
			(end 0.67945 0.3048)
			(stroke
				(width 0.1)
				(type default)
			)
			(layer "B.Fab")
		)
		(fp_line
			(start 0.67945 -0.305054)
			(end 0.12065 -0.305054)
			(stroke
				(width 0.1)
				(type default)
			)
			(layer "B.Fab")
		)
		(fp_line
			(start 0.67945 0.3048)
			(end 0.67945 -0.305054)
			(stroke
				(width 0.1)
				(type default)
			)
			(layer "B.Fab")
		)
		(pad "1" smd circle
			(at 0.40005 0 180)
			(size 0 0)
			(layers "B.Cu" "B.Mask" "B.Paste")
			(net "PVDDIO_P0")
		)
		(pad "2" smd circle
			(at -0.40005 0 180)
			(size 0 0)
			(layers "B.Cu" "B.Mask" "B.Paste")
			(net "GND")
		)
	)
	(footprint ""
		(layer "B.Cu")
		(at 126.504446 -408.517344 90)
		(property "Reference" "C6731"
			(at 0 0 90)
			(layer "B.SilkS")
			(hide yes)
			(effects
				(font
					(size 1.27 1.27)
				)
				(justify mirror)
			)
		)
		(property "Value" ""
			(at 0 0 90)
			(layer "B.Fab")
			(effects
				(font
					(size 1.27 1.27)
				)
				(justify mirror)
			)
		)
		(duplicate_pad_numbers_are_jumpers no)
		(fp_line
			(start 0.299974 -0.150114)
			(end -0.299974 -0.150114)
			(stroke
				(width 0.1)
				(type default)
			)
			(layer "B.Fab")
		)
		(fp_line
			(start -0.299974 -0.150114)
			(end -0.299974 0.150114)
			(stroke
				(width 0.1)
				(type default)
			)
			(layer "B.Fab")
		)
		(fp_line
			(start 0.299974 0.150114)
			(end 0.299974 -0.150114)
			(stroke
				(width 0.1)
				(type default)
			)
			(layer "B.Fab")
		)
		(fp_line
			(start -0.299974 0.150114)
			(end 0.299974 0.150114)
			(stroke
				(width 0.1)
				(type default)
			)
			(layer "B.Fab")
		)
		(pad "1" smd rect
			(at 0.2667 0 270)
			(size 0.3048 0.381)
			(layers "B.Cu" "B.Mask" "B.Paste")
			(net "P5E_CPU1_P3_TX_BUF_C_DP<3>")
		)
		(pad "2" smd rect
			(at -0.2667 0 270)
			(size 0.3048 0.381)
			(layers "B.Cu" "B.Mask" "B.Paste")
			(net "P5E_CPU1_P3_TX_BUF_DP<3>")
		)
	)
	(footprint ""
		(layer "B.Cu")
		(at 195.390008 -126.833376 180)
		(property "Reference" "R1549"
			(at 0 0 0)
			(layer "B.SilkS")
			(hide yes)
			(effects
				(font
					(size 1.27 1.27)
				)
				(justify mirror)
			)
		)
		(property "Value" ""
			(at 0 0 0)
			(layer "B.Fab")
			(effects
				(font
					(size 1.27 1.27)
				)
				(justify mirror)
			)
		)
		(duplicate_pad_numbers_are_jumpers no)
		(fp_line
			(start 0.7874 0.4064)
			(end 0.7874 -0.4064)
			(stroke
				(width 0.1524)
				(type default)
			)
			(layer "B.SilkS")
		)
		(fp_line
			(start 0.7874 -0.4064)
			(end -0.7874 -0.4064)
			(stroke
				(width 0.1524)
				(type default)
			)
			(layer "B.SilkS")
		)
		(fp_line
			(start -0.7874 0.4064)
			(end 0.7874 0.4064)
			(stroke
				(width 0.1524)
				(type default)
			)
			(layer "B.SilkS")
		)
		(fp_line
			(start -0.7874 -0.4064)
			(end -0.7874 0.4064)
			(stroke
				(width 0.1524)
				(type default)
			)
			(layer "B.SilkS")
		)
		(fp_line
			(start 0.67945 0.3048)
			(end 0.67945 -0.305054)
			(stroke
				(width 0.1)
				(type default)
			)
			(layer "B.Fab")
		)
		(fp_line
			(start 0.67945 -0.305054)
			(end 0.12065 -0.305054)
			(stroke
				(width 0.1)
				(type default)
			)
			(layer "B.Fab")
		)
		(fp_line
			(start 0.12065 0.3048)
			(end 0.67945 0.3048)
			(stroke
				(width 0.1)
				(type default)
			)
			(layer "B.Fab")
		)
		(fp_line
			(start 0.12065 0.2794)
			(end 0.12065 0.3048)
			(stroke
				(width 0.1)
				(type default)
			)
			(layer "B.Fab")
		)
		(fp_line
			(start 0.12065 -0.2794)
			(end -0.12065 -0.2794)
			(stroke
				(width 0.1)
				(type default)
			)
			(layer "B.Fab")
		)
		(fp_line
			(start 0.12065 -0.305054)
			(end 0.12065 -0.2794)
			(stroke
				(width 0.1)
				(type default)
			)
			(layer "B.Fab")
		)
		(fp_line
			(start -0.120396 0.3048)
			(end -0.120396 0.2794)
			(stroke
				(width 0.1)
				(type default)
			)
			(layer "B.Fab")
		)
		(fp_line
			(start -0.120396 0.2794)
			(end 0.12065 0.2794)
			(stroke
				(width 0.1)
				(type default)
			)
			(layer "B.Fab")
		)
		(fp_line
			(start -0.12065 -0.2794)
			(end -0.12065 -0.3048)
			(stroke
				(width 0.1)
				(type default)
			)
			(layer "B.Fab")
		)
		(fp_line
			(start -0.12065 -0.3048)
			(end -0.67945 -0.3048)
			(stroke
				(width 0.1)
				(type default)
			)
			(layer "B.Fab")
		)
		(fp_line
			(start -0.67945 0.3048)
			(end -0.120396 0.3048)
			(stroke
				(width 0.1)
				(type default)
			)
			(layer "B.Fab")
		)
		(fp_line
			(start -0.67945 -0.3048)
			(end -0.67945 0.3048)
			(stroke
				(width 0.1)
				(type default)
			)
			(layer "B.Fab")
		)
		(pad "1" smd circle
			(at 0.40005 0)
			(size 0 0)
			(layers "B.Cu" "B.Mask" "B.Paste")
			(net "ESPI_CPU0_R1_D0")
		)
		(pad "2" smd circle
			(at -0.40005 0)
			(size 0 0)
			(layers "B.Cu" "B.Mask" "B.Paste")
			(net "ESPI_CPU0_D0")
		)
	)
	(footprint ""
		(layer "B.Cu")
		(at 84.595462 -181.684676 90)
		(property "Reference" "PR185"
			(at 0 0 90)
			(layer "B.SilkS")
			(hide yes)
			(effects
				(font
					(size 1.27 1.27)
				)
				(justify mirror)
			)
		)
		(property "Value" ""
			(at 0 0 90)
			(layer "B.Fab")
			(effects
				(font
					(size 1.27 1.27)
				)
				(justify mirror)
			)
		)
		(duplicate_pad_numbers_are_jumpers no)
		(fp_line
			(start 0.7874 -0.4064)
			(end -0.7874 -0.4064)
			(stroke
				(width 0.1524)
				(type default)
			)
			(layer "B.SilkS")
		)
		(fp_line
			(start -0.7874 -0.4064)
			(end -0.7874 0.4064)
			(stroke
				(width 0.1524)
				(type default)
			)
			(layer "B.SilkS")
		)
		(fp_line
			(start 0.7874 0.4064)
			(end 0.7874 -0.4064)
			(stroke
				(width 0.1524)
				(type default)
			)
			(layer "B.SilkS")
		)
		(fp_line
			(start -0.7874 0.4064)
			(end 0.7874 0.4064)
			(stroke
				(width 0.1524)
				(type default)
			)
			(layer "B.SilkS")
		)
		(fp_line
			(start 0.67945 -0.305054)
			(end 0.12065 -0.305054)
			(stroke
				(width 0.1)
				(type default)
			)
			(layer "B.Fab")
		)
		(fp_line
			(start 0.12065 -0.305054)
			(end 0.12065 -0.2794)
			(stroke
				(width 0.1)
				(type default)
			)
			(layer "B.Fab")
		)
		(fp_line
			(start -0.12065 -0.3048)
			(end -0.67945 -0.3048)
			(stroke
				(width 0.1)
				(type default)
			)
			(layer "B.Fab")
		)
		(fp_line
			(start -0.67945 -0.3048)
			(end -0.67945 0.3048)
			(stroke
				(width 0.1)
				(type default)
			)
			(layer "B.Fab")
		)
		(fp_line
			(start 0.12065 -0.2794)
			(end -0.12065 -0.2794)
			(stroke
				(width 0.1)
				(type default)
			)
			(layer "B.Fab")
		)
		(fp_line
			(start -0.12065 -0.2794)
			(end -0.12065 -0.3048)
			(stroke
				(width 0.1)
				(type default)
			)
			(layer "B.Fab")
		)
		(fp_line
			(start 0.12065 0.2794)
			(end 0.12065 0.3048)
			(stroke
				(width 0.1)
				(type default)
			)
			(layer "B.Fab")
		)
		(fp_line
			(start -0.120396 0.2794)
			(end 0.12065 0.2794)
			(stroke
				(width 0.1)
				(type default)
			)
			(layer "B.Fab")
		)
		(fp_line
			(start 0.67945 0.3048)
			(end 0.67945 -0.305054)
			(stroke
				(width 0.1)
				(type default)
			)
			(layer "B.Fab")
		)
		(fp_line
			(start 0.12065 0.3048)
			(end 0.67945 0.3048)
			(stroke
				(width 0.1)
				(type default)
			)
			(layer "B.Fab")
		)
		(fp_line
			(start -0.120396 0.3048)
			(end -0.120396 0.2794)
			(stroke
				(width 0.1)
				(type default)
			)
			(layer "B.Fab")
		)
		(fp_line
			(start -0.67945 0.3048)
			(end -0.120396 0.3048)
			(stroke
				(width 0.1)
				(type default)
			)
			(layer "B.Fab")
		)
		(pad "1" smd circle
			(at 0.40005 0 270)
			(size 0 0)
			(layers "B.Cu" "B.Mask" "B.Paste")
			(net "PVDDCR_CPU0_P1_PVCC")
		)
		(pad "2" smd circle
			(at -0.40005 0 270)
			(size 0 0)
			(layers "B.Cu" "B.Mask" "B.Paste")
			(net "PVDDCR_CPU0_P1_VCC1")
		)
	)
	(footprint ""
		(layer "B.Cu")
		(at 309.37835 -395.148562 90)
		(property "Reference" "C540"
			(at 0 0 90)
			(layer "B.SilkS")
			(hide yes)
			(effects
				(font
					(size 1.27 1.27)
				)
				(justify mirror)
			)
		)
		(property "Value" ""
			(at 0 0 90)
			(layer "B.Fab")
			(effects
				(font
					(size 1.27 1.27)
				)
				(justify mirror)
			)
		)
		(duplicate_pad_numbers_are_jumpers no)
		(fp_line
			(start 0.299974 -0.150114)
			(end -0.299974 -0.150114)
			(stroke
				(width 0.1)
				(type default)
			)
			(layer "B.Fab")
		)
		(fp_line
			(start -0.299974 -0.150114)
			(end -0.299974 0.150114)
			(stroke
				(width 0.1)
				(type default)
			)
			(layer "B.Fab")
		)
		(fp_line
			(start 0.299974 0.150114)
			(end 0.299974 -0.150114)
			(stroke
				(width 0.1)
				(type default)
			)
			(layer "B.Fab")
		)
		(fp_line
			(start -0.299974 0.150114)
			(end 0.299974 0.150114)
			(stroke
				(width 0.1)
				(type default)
			)
			(layer "B.Fab")
		)
		(pad "1" smd rect
			(at 0.2667 0 270)
			(size 0.3048 0.381)
			(layers "B.Cu" "B.Mask" "B.Paste")
			(net "P0V9_CPU0_RT_2D")
		)
		(pad "2" smd rect
			(at -0.2667 0 270)
			(size 0.3048 0.381)
			(layers "B.Cu" "B.Mask" "B.Paste")
			(net "GND")
		)
	)
	(footprint ""
		(layer "B.Cu")
		(at 109.49686 -35.088068 90)
		(property "Reference" "C6114"
			(at 0 0 90)
			(layer "B.SilkS")
			(hide yes)
			(effects
				(font
					(size 1.27 1.27)
				)
				(justify mirror)
			)
		)
		(property "Value" ""
			(at 0 0 90)
			(layer "B.Fab")
			(effects
				(font
					(size 1.27 1.27)
				)
				(justify mirror)
			)
		)
		(duplicate_pad_numbers_are_jumpers no)
		(fp_line
			(start 0.7874 -0.4064)
			(end -0.7874 -0.4064)
			(stroke
				(width 0.1524)
				(type default)
			)
			(layer "B.SilkS")
		)
		(fp_line
			(start -0.7874 -0.4064)
			(end -0.7874 0.4064)
			(stroke
				(width 0.1524)
				(type default)
			)
			(layer "B.SilkS")
		)
		(fp_line
			(start 0.7874 0.4064)
			(end 0.7874 -0.4064)
			(stroke
				(width 0.1524)
				(type default)
			)
			(layer "B.SilkS")
		)
		(fp_line
			(start -0.7874 0.4064)
			(end 0.7874 0.4064)
			(stroke
				(width 0.1524)
				(type default)
			)
			(layer "B.SilkS")
		)
		(fp_line
			(start 0.67945 -0.305054)
			(end 0.12065 -0.305054)
			(stroke
				(width 0.1)
				(type default)
			)
			(layer "B.Fab")
		)
		(fp_line
			(start 0.12065 -0.305054)
			(end 0.12065 -0.2794)
			(stroke
				(width 0.1)
				(type default)
			)
			(layer "B.Fab")
		)
		(fp_line
			(start -0.12065 -0.3048)
			(end -0.67945 -0.3048)
			(stroke
				(width 0.1)
				(type default)
			)
			(layer "B.Fab")
		)
		(fp_line
			(start -0.67945 -0.3048)
			(end -0.67945 0.3048)
			(stroke
				(width 0.1)
				(type default)
			)
			(layer "B.Fab")
		)
		(fp_line
			(start 0.12065 -0.2794)
			(end -0.12065 -0.2794)
			(stroke
				(width 0.1)
				(type default)
			)
			(layer "B.Fab")
		)
		(fp_line
			(start -0.12065 -0.2794)
			(end -0.12065 -0.3048)
			(stroke
				(width 0.1)
				(type default)
			)
			(layer "B.Fab")
		)
		(fp_line
			(start 0.12065 0.2794)
			(end 0.12065 0.3048)
			(stroke
				(width 0.1)
				(type default)
			)
			(layer "B.Fab")
		)
		(fp_line
			(start -0.120396 0.2794)
			(end 0.12065 0.2794)
			(stroke
				(width 0.1)
				(type default)
			)
			(layer "B.Fab")
		)
		(fp_line
			(start 0.67945 0.3048)
			(end 0.67945 -0.305054)
			(stroke
				(width 0.1)
				(type default)
			)
			(layer "B.Fab")
		)
		(fp_line
			(start 0.12065 0.3048)
			(end 0.67945 0.3048)
			(stroke
				(width 0.1)
				(type default)
			)
			(layer "B.Fab")
		)
		(fp_line
			(start -0.120396 0.3048)
			(end -0.120396 0.2794)
			(stroke
				(width 0.1)
				(type default)
			)
			(layer "B.Fab")
		)
		(fp_line
			(start -0.67945 0.3048)
			(end -0.120396 0.3048)
			(stroke
				(width 0.1)
				(type default)
			)
			(layer "B.Fab")
		)
		(pad "1" smd circle
			(at 0.40005 0 270)
			(size 0 0)
			(layers "B.Cu" "B.Mask" "B.Paste")
			(net "P1V2_CPU0_USB2_DVDD12")
		)
		(pad "2" smd circle
			(at -0.40005 0 270)
			(size 0 0)
			(layers "B.Cu" "B.Mask" "B.Paste")
			(net "GND")
		)
	)
	(footprint ""
		(layer "B.Cu")
		(at 208.461356 -382.596136)
		(property "Reference" "PR2513"
			(at 0 0 0)
			(layer "B.SilkS")
			(hide yes)
			(effects
				(font
					(size 1.27 1.27)
				)
				(justify mirror)
			)
		)
		(property "Value" ""
			(at 0 0 0)
			(layer "B.Fab")
			(effects
				(font
					(size 1.27 1.27)
				)
				(justify mirror)
			)
		)
		(duplicate_pad_numbers_are_jumpers no)
		(fp_line
			(start -0.7874 -0.4064)
			(end -0.7874 0.4064)
			(stroke
				(width 0.1524)
				(type default)
			)
			(layer "B.SilkS")
		)
		(fp_line
			(start -0.7874 0.4064)
			(end 0.7874 0.4064)
			(stroke
				(width 0.1524)
				(type default)
			)
			(layer "B.SilkS")
		)
		(fp_line
			(start 0.7874 -0.4064)
			(end -0.7874 -0.4064)
			(stroke
				(width 0.1524)
				(type default)
			)
			(layer "B.SilkS")
		)
		(fp_line
			(start 0.7874 0.4064)
			(end 0.7874 -0.4064)
			(stroke
				(width 0.1524)
				(type default)
			)
			(layer "B.SilkS")
		)
		(fp_line
			(start -0.67945 -0.3048)
			(end -0.67945 0.3048)
			(stroke
				(width 0.1)
				(type default)
			)
			(layer "B.Fab")
		)
		(fp_line
			(start -0.67945 0.3048)
			(end -0.120396 0.3048)
			(stroke
				(width 0.1)
				(type default)
			)
			(layer "B.Fab")
		)
		(fp_line
			(start -0.12065 -0.3048)
			(end -0.67945 -0.3048)
			(stroke
				(width 0.1)
				(type default)
			)
			(layer "B.Fab")
		)
		(fp_line
			(start -0.12065 -0.2794)
			(end -0.12065 -0.3048)
			(stroke
				(width 0.1)
				(type default)
			)
			(layer "B.Fab")
		)
		(fp_line
			(start -0.120396 0.2794)
			(end 0.12065 0.2794)
			(stroke
				(width 0.1)
				(type default)
			)
			(layer "B.Fab")
		)
		(fp_line
			(start -0.120396 0.3048)
			(end -0.120396 0.2794)
			(stroke
				(width 0.1)
				(type default)
			)
			(layer "B.Fab")
		)
		(fp_line
			(start 0.12065 -0.305054)
			(end 0.12065 -0.2794)
			(stroke
				(width 0.1)
				(type default)
			)
			(layer "B.Fab")
		)
		(fp_line
			(start 0.12065 -0.2794)
			(end -0.12065 -0.2794)
			(stroke
				(width 0.1)
				(type default)
			)
			(layer "B.Fab")
		)
		(fp_line
			(start 0.12065 0.2794)
			(end 0.12065 0.3048)
			(stroke
				(width 0.1)
				(type default)
			)
			(layer "B.Fab")
		)
		(fp_line
			(start 0.12065 0.3048)
			(end 0.67945 0.3048)
			(stroke
				(width 0.1)
				(type default)
			)
			(layer "B.Fab")
		)
		(fp_line
			(start 0.67945 -0.305054)
			(end 0.12065 -0.305054)
			(stroke
				(width 0.1)
				(type default)
			)
			(layer "B.Fab")
		)
		(fp_line
			(start 0.67945 0.3048)
			(end 0.67945 -0.305054)
			(stroke
				(width 0.1)
				(type default)
			)
			(layer "B.Fab")
		)
		(pad "1" smd circle
			(at 0.40005 0 180)
			(size 0 0)
			(layers "B.Cu" "B.Mask" "B.Paste")
			(net "P12V_HSC_ADC_P")
		)
		(pad "2" smd circle
			(at -0.40005 0 180)
			(size 0 0)
			(layers "B.Cu" "B.Mask" "B.Paste")
			(net "P12V_HSC_SENSE2_R4_P")
		)
	)
	(footprint ""
		(layer "B.Cu")
		(at 94.470474 -304.710592 180)
		(property "Reference" "R5031"
			(at 0 0 0)
			(layer "B.SilkS")
			(hide yes)
			(effects
				(font
					(size 1.27 1.27)
				)
				(justify mirror)
			)
		)
		(property "Value" ""
			(at 0 0 0)
			(layer "B.Fab")
			(effects
				(font
					(size 1.27 1.27)
				)
				(justify mirror)
			)
		)
		(duplicate_pad_numbers_are_jumpers no)
		(fp_line
			(start 0.7874 0.4064)
			(end 0.7874 -0.4064)
			(stroke
				(width 0.1524)
				(type default)
			)
			(layer "B.SilkS")
		)
		(fp_line
			(start 0.7874 -0.4064)
			(end -0.7874 -0.4064)
			(stroke
				(width 0.1524)
				(type default)
			)
			(layer "B.SilkS")
		)
		(fp_line
			(start -0.7874 0.4064)
			(end 0.7874 0.4064)
			(stroke
				(width 0.1524)
				(type default)
			)
			(layer "B.SilkS")
		)
		(fp_line
			(start -0.7874 -0.4064)
			(end -0.7874 0.4064)
			(stroke
				(width 0.1524)
				(type default)
			)
			(layer "B.SilkS")
		)
		(fp_line
			(start 0.67945 0.3048)
			(end 0.67945 -0.305054)
			(stroke
				(width 0.1)
				(type default)
			)
			(layer "B.Fab")
		)
		(fp_line
			(start 0.67945 -0.305054)
			(end 0.12065 -0.305054)
			(stroke
				(width 0.1)
				(type default)
			)
			(layer "B.Fab")
		)
		(fp_line
			(start 0.12065 0.3048)
			(end 0.67945 0.3048)
			(stroke
				(width 0.1)
				(type default)
			)
			(layer "B.Fab")
		)
		(fp_line
			(start 0.12065 0.2794)
			(end 0.12065 0.3048)
			(stroke
				(width 0.1)
				(type default)
			)
			(layer "B.Fab")
		)
		(fp_line
			(start 0.12065 -0.2794)
			(end -0.12065 -0.2794)
			(stroke
				(width 0.1)
				(type default)
			)
			(layer "B.Fab")
		)
		(fp_line
			(start 0.12065 -0.305054)
			(end 0.12065 -0.2794)
			(stroke
				(width 0.1)
				(type default)
			)
			(layer "B.Fab")
		)
		(fp_line
			(start -0.120396 0.3048)
			(end -0.120396 0.2794)
			(stroke
				(width 0.1)
				(type default)
			)
			(layer "B.Fab")
		)
		(fp_line
			(start -0.120396 0.2794)
			(end 0.12065 0.2794)
			(stroke
				(width 0.1)
				(type default)
			)
			(layer "B.Fab")
		)
		(fp_line
			(start -0.12065 -0.2794)
			(end -0.12065 -0.3048)
			(stroke
				(width 0.1)
				(type default)
			)
			(layer "B.Fab")
		)
		(fp_line
			(start -0.12065 -0.3048)
			(end -0.67945 -0.3048)
			(stroke
				(width 0.1)
				(type default)
			)
			(layer "B.Fab")
		)
		(fp_line
			(start -0.67945 0.3048)
			(end -0.120396 0.3048)
			(stroke
				(width 0.1)
				(type default)
			)
			(layer "B.Fab")
		)
		(fp_line
			(start -0.67945 -0.3048)
			(end -0.67945 0.3048)
			(stroke
				(width 0.1)
				(type default)
			)
			(layer "B.Fab")
		)
		(pad "1" smd circle
			(at 0.40005 0)
			(size 0 0)
			(layers "B.Cu" "B.Mask" "B.Paste")
			(net "GND")
		)
		(pad "2" smd circle
			(at -0.40005 0)
			(size 0 0)
			(layers "B.Cu" "B.Mask" "B.Paste")
			(net "FM_BMC_READY_N")
		)
	)
	(footprint ""
		(layer "B.Cu")
		(at 322.603876 -66.708782 90)
		(property "Reference" "R3086"
			(at 0 0 90)
			(layer "B.SilkS")
			(hide yes)
			(effects
				(font
					(size 1.27 1.27)
				)
				(justify mirror)
			)
		)
		(property "Value" ""
			(at 0 0 90)
			(layer "B.Fab")
			(effects
				(font
					(size 1.27 1.27)
				)
				(justify mirror)
			)
		)
		(duplicate_pad_numbers_are_jumpers no)
		(fp_line
			(start 0.7874 -0.4064)
			(end -0.7874 -0.4064)
			(stroke
				(width 0.1524)
				(type default)
			)
			(layer "B.SilkS")
		)
		(fp_line
			(start -0.7874 -0.4064)
			(end -0.7874 0.4064)
			(stroke
				(width 0.1524)
				(type default)
			)
			(layer "B.SilkS")
		)
		(fp_line
			(start 0.7874 0.4064)
			(end 0.7874 -0.4064)
			(stroke
				(width 0.1524)
				(type default)
			)
			(layer "B.SilkS")
		)
		(fp_line
			(start -0.7874 0.4064)
			(end 0.7874 0.4064)
			(stroke
				(width 0.1524)
				(type default)
			)
			(layer "B.SilkS")
		)
		(fp_line
			(start 0.67945 -0.305054)
			(end 0.12065 -0.305054)
			(stroke
				(width 0.1)
				(type default)
			)
			(layer "B.Fab")
		)
		(fp_line
			(start 0.12065 -0.305054)
			(end 0.12065 -0.2794)
			(stroke
				(width 0.1)
				(type default)
			)
			(layer "B.Fab")
		)
		(fp_line
			(start -0.12065 -0.3048)
			(end -0.67945 -0.3048)
			(stroke
				(width 0.1)
				(type default)
			)
			(layer "B.Fab")
		)
		(fp_line
			(start -0.67945 -0.3048)
			(end -0.67945 0.3048)
			(stroke
				(width 0.1)
				(type default)
			)
			(layer "B.Fab")
		)
		(fp_line
			(start 0.12065 -0.2794)
			(end -0.12065 -0.2794)
			(stroke
				(width 0.1)
				(type default)
			)
			(layer "B.Fab")
		)
		(fp_line
			(start -0.12065 -0.2794)
			(end -0.12065 -0.3048)
			(stroke
				(width 0.1)
				(type default)
			)
			(layer "B.Fab")
		)
		(fp_line
			(start 0.12065 0.2794)
			(end 0.12065 0.3048)
			(stroke
				(width 0.1)
				(type default)
			)
			(layer "B.Fab")
		)
		(fp_line
			(start -0.120396 0.2794)
			(end 0.12065 0.2794)
			(stroke
				(width 0.1)
				(type default)
			)
			(layer "B.Fab")
		)
		(fp_line
			(start 0.67945 0.3048)
			(end 0.67945 -0.305054)
			(stroke
				(width 0.1)
				(type default)
			)
			(layer "B.Fab")
		)
		(fp_line
			(start 0.12065 0.3048)
			(end 0.67945 0.3048)
			(stroke
				(width 0.1)
				(type default)
			)
			(layer "B.Fab")
		)
		(fp_line
			(start -0.120396 0.3048)
			(end -0.120396 0.2794)
			(stroke
				(width 0.1)
				(type default)
			)
			(layer "B.Fab")
		)
		(fp_line
			(start -0.67945 0.3048)
			(end -0.120396 0.3048)
			(stroke
				(width 0.1)
				(type default)
			)
			(layer "B.Fab")
		)
		(pad "1" smd circle
			(at 0.40005 0 270)
			(size 0 0)
			(layers "B.Cu" "B.Mask" "B.Paste")
			(net "LED_PWRGD_PVDD33_S5_R")
		)
		(pad "2" smd circle
			(at -0.40005 0 270)
			(size 0 0)
			(layers "B.Cu" "B.Mask" "B.Paste")
			(net "P3V3_AUX")
		)
	)
	(footprint ""
		(layer "B.Cu")
		(at 406.312878 -349.209614 -90)
		(property "Reference" "R6120"
			(at 0 0 90)
			(layer "B.SilkS")
			(hide yes)
			(effects
				(font
					(size 1.27 1.27)
				)
				(justify mirror)
			)
		)
		(property "Value" ""
			(at 0 0 90)
			(layer "B.Fab")
			(effects
				(font
					(size 1.27 1.27)
				)
				(justify mirror)
			)
		)
		(duplicate_pad_numbers_are_jumpers no)
		(fp_line
			(start -0.7874 0.4064)
			(end 0.7874 0.4064)
			(stroke
				(width 0.1524)
				(type default)
			)
			(layer "B.SilkS")
		)
		(fp_line
			(start 0.7874 0.4064)
			(end 0.7874 -0.4064)
			(stroke
				(width 0.1524)
				(type default)
			)
			(layer "B.SilkS")
		)
		(fp_line
			(start -0.7874 -0.4064)
			(end -0.7874 0.4064)
			(stroke
				(width 0.1524)
				(type default)
			)
			(layer "B.SilkS")
		)
		(fp_line
			(start 0.7874 -0.4064)
			(end -0.7874 -0.4064)
			(stroke
				(width 0.1524)
				(type default)
			)
			(layer "B.SilkS")
		)
		(fp_line
			(start -0.67945 0.3048)
			(end -0.120396 0.3048)
			(stroke
				(width 0.1)
				(type default)
			)
			(layer "B.Fab")
		)
		(fp_line
			(start -0.120396 0.3048)
			(end -0.120396 0.2794)
			(stroke
				(width 0.1)
				(type default)
			)
			(layer "B.Fab")
		)
		(fp_line
			(start 0.12065 0.3048)
			(end 0.67945 0.3048)
			(stroke
				(width 0.1)
				(type default)
			)
			(layer "B.Fab")
		)
		(fp_line
			(start 0.67945 0.3048)
			(end 0.67945 -0.305054)
			(stroke
				(width 0.1)
				(type default)
			)
			(layer "B.Fab")
		)
		(fp_line
			(start -0.120396 0.2794)
			(end 0.12065 0.2794)
			(stroke
				(width 0.1)
				(type default)
			)
			(layer "B.Fab")
		)
		(fp_line
			(start 0.12065 0.2794)
			(end 0.12065 0.3048)
			(stroke
				(width 0.1)
				(type default)
			)
			(layer "B.Fab")
		)
		(fp_line
			(start -0.12065 -0.2794)
			(end -0.12065 -0.3048)
			(stroke
				(width 0.1)
				(type default)
			)
			(layer "B.Fab")
		)
		(fp_line
			(start 0.12065 -0.2794)
			(end -0.12065 -0.2794)
			(stroke
				(width 0.1)
				(type default)
			)
			(layer "B.Fab")
		)
		(fp_line
			(start -0.67945 -0.3048)
			(end -0.67945 0.3048)
			(stroke
				(width 0.1)
				(type default)
			)
			(layer "B.Fab")
		)
		(fp_line
			(start -0.12065 -0.3048)
			(end -0.67945 -0.3048)
			(stroke
				(width 0.1)
				(type default)
			)
			(layer "B.Fab")
		)
		(fp_line
			(start 0.12065 -0.305054)
			(end 0.12065 -0.2794)
			(stroke
				(width 0.1)
				(type default)
			)
			(layer "B.Fab")
		)
		(fp_line
			(start 0.67945 -0.305054)
			(end 0.12065 -0.305054)
			(stroke
				(width 0.1)
				(type default)
			)
			(layer "B.Fab")
		)
		(pad "1" smd circle
			(at 0.40005 0 90)
			(size 0 0)
			(layers "B.Cu" "B.Mask" "B.Paste")
			(net "PVDD18_S5_P0")
		)
		(pad "2" smd circle
			(at -0.40005 0 90)
			(size 0 0)
			(layers "B.Cu" "B.Mask" "B.Paste")
			(net "FM_BOARD_SKU_ID4")
		)
	)
	(footprint ""
		(layer "B.Cu")
		(at 121.685812 -259.73024)
		(property "Reference" "C3912"
			(at 0 0 0)
			(layer "B.SilkS")
			(hide yes)
			(effects
				(font
					(size 1.27 1.27)
				)
				(justify mirror)
			)
		)
		(property "Value" ""
			(at 0 0 0)
			(layer "B.Fab")
			(effects
				(font
					(size 1.27 1.27)
				)
				(justify mirror)
			)
		)
		(duplicate_pad_numbers_are_jumpers no)
		(fp_line
			(start -0.7874 -0.4064)
			(end -0.7874 0.4064)
			(stroke
				(width 0.1524)
				(type default)
			)
			(layer "B.SilkS")
		)
		(fp_line
			(start -0.7874 0.4064)
			(end 0.7874 0.4064)
			(stroke
				(width 0.1524)
				(type default)
			)
			(layer "B.SilkS")
		)
		(fp_line
			(start 0.7874 -0.4064)
			(end -0.7874 -0.4064)
			(stroke
				(width 0.1524)
				(type default)
			)
			(layer "B.SilkS")
		)
		(fp_line
			(start 0.7874 0.4064)
			(end 0.7874 -0.4064)
			(stroke
				(width 0.1524)
				(type default)
			)
			(layer "B.SilkS")
		)
		(fp_line
			(start -0.67945 -0.3048)
			(end -0.67945 0.3048)
			(stroke
				(width 0.1)
				(type default)
			)
			(layer "B.Fab")
		)
		(fp_line
			(start -0.67945 0.3048)
			(end -0.120396 0.3048)
			(stroke
				(width 0.1)
				(type default)
			)
			(layer "B.Fab")
		)
		(fp_line
			(start -0.12065 -0.3048)
			(end -0.67945 -0.3048)
			(stroke
				(width 0.1)
				(type default)
			)
			(layer "B.Fab")
		)
		(fp_line
			(start -0.12065 -0.2794)
			(end -0.12065 -0.3048)
			(stroke
				(width 0.1)
				(type default)
			)
			(layer "B.Fab")
		)
		(fp_line
			(start -0.120396 0.2794)
			(end 0.12065 0.2794)
			(stroke
				(width 0.1)
				(type default)
			)
			(layer "B.Fab")
		)
		(fp_line
			(start -0.120396 0.3048)
			(end -0.120396 0.2794)
			(stroke
				(width 0.1)
				(type default)
			)
			(layer "B.Fab")
		)
		(fp_line
			(start 0.12065 -0.305054)
			(end 0.12065 -0.2794)
			(stroke
				(width 0.1)
				(type default)
			)
			(layer "B.Fab")
		)
		(fp_line
			(start 0.12065 -0.2794)
			(end -0.12065 -0.2794)
			(stroke
				(width 0.1)
				(type default)
			)
			(layer "B.Fab")
		)
		(fp_line
			(start 0.12065 0.2794)
			(end 0.12065 0.3048)
			(stroke
				(width 0.1)
				(type default)
			)
			(layer "B.Fab")
		)
		(fp_line
			(start 0.12065 0.3048)
			(end 0.67945 0.3048)
			(stroke
				(width 0.1)
				(type default)
			)
			(layer "B.Fab")
		)
		(fp_line
			(start 0.67945 -0.305054)
			(end 0.12065 -0.305054)
			(stroke
				(width 0.1)
				(type default)
			)
			(layer "B.Fab")
		)
		(fp_line
			(start 0.67945 0.3048)
			(end 0.67945 -0.305054)
			(stroke
				(width 0.1)
				(type default)
			)
			(layer "B.Fab")
		)
		(pad "1" smd circle
			(at 0.40005 0 180)
			(size 0 0)
			(layers "B.Cu" "B.Mask" "B.Paste")
			(net "PVDDCR_SOC_P1")
		)
		(pad "2" smd circle
			(at -0.40005 0 180)
			(size 0 0)
			(layers "B.Cu" "B.Mask" "B.Paste")
			(net "GND")
		)
	)
	(footprint ""
		(layer "B.Cu")
		(at 378.891292 -398.942052 90)
		(property "Reference" "C996"
			(at 0 0 90)
			(layer "B.SilkS")
			(hide yes)
			(effects
				(font
					(size 1.27 1.27)
				)
				(justify mirror)
			)
		)
		(property "Value" ""
			(at 0 0 90)
			(layer "B.Fab")
			(effects
				(font
					(size 1.27 1.27)
				)
				(justify mirror)
			)
		)
		(duplicate_pad_numbers_are_jumpers no)
		(fp_line
			(start 0.7874 -0.4064)
			(end -0.7874 -0.4064)
			(stroke
				(width 0.1524)
				(type default)
			)
			(layer "B.SilkS")
		)
		(fp_line
			(start -0.7874 -0.4064)
			(end -0.7874 0.4064)
			(stroke
				(width 0.1524)
				(type default)
			)
			(layer "B.SilkS")
		)
		(fp_line
			(start 0.7874 0.4064)
			(end 0.7874 -0.4064)
			(stroke
				(width 0.1524)
				(type default)
			)
			(layer "B.SilkS")
		)
		(fp_line
			(start -0.7874 0.4064)
			(end 0.7874 0.4064)
			(stroke
				(width 0.1524)
				(type default)
			)
			(layer "B.SilkS")
		)
		(fp_line
			(start 0.67945 -0.305054)
			(end 0.12065 -0.305054)
			(stroke
				(width 0.1)
				(type default)
			)
			(layer "B.Fab")
		)
		(fp_line
			(start 0.12065 -0.305054)
			(end 0.12065 -0.2794)
			(stroke
				(width 0.1)
				(type default)
			)
			(layer "B.Fab")
		)
		(fp_line
			(start -0.12065 -0.3048)
			(end -0.67945 -0.3048)
			(stroke
				(width 0.1)
				(type default)
			)
			(layer "B.Fab")
		)
		(fp_line
			(start -0.67945 -0.3048)
			(end -0.67945 0.3048)
			(stroke
				(width 0.1)
				(type default)
			)
			(layer "B.Fab")
		)
		(fp_line
			(start 0.12065 -0.2794)
			(end -0.12065 -0.2794)
			(stroke
				(width 0.1)
				(type default)
			)
			(layer "B.Fab")
		)
		(fp_line
			(start -0.12065 -0.2794)
			(end -0.12065 -0.3048)
			(stroke
				(width 0.1)
				(type default)
			)
			(layer "B.Fab")
		)
		(fp_line
			(start 0.12065 0.2794)
			(end 0.12065 0.3048)
			(stroke
				(width 0.1)
				(type default)
			)
			(layer "B.Fab")
		)
		(fp_line
			(start -0.120396 0.2794)
			(end 0.12065 0.2794)
			(stroke
				(width 0.1)
				(type default)
			)
			(layer "B.Fab")
		)
		(fp_line
			(start 0.67945 0.3048)
			(end 0.67945 -0.305054)
			(stroke
				(width 0.1)
				(type default)
			)
			(layer "B.Fab")
		)
		(fp_line
			(start 0.12065 0.3048)
			(end 0.67945 0.3048)
			(stroke
				(width 0.1)
				(type default)
			)
			(layer "B.Fab")
		)
		(fp_line
			(start -0.120396 0.3048)
			(end -0.120396 0.2794)
			(stroke
				(width 0.1)
				(type default)
			)
			(layer "B.Fab")
		)
		(fp_line
			(start -0.67945 0.3048)
			(end -0.120396 0.3048)
			(stroke
				(width 0.1)
				(type default)
			)
			(layer "B.Fab")
		)
		(pad "1" smd circle
			(at 0.40005 0 270)
			(size 0 0)
			(layers "B.Cu" "B.Mask" "B.Paste")
			(net "P1V8_CPU0_RT3_1A")
		)
		(pad "2" smd circle
			(at -0.40005 0 270)
			(size 0 0)
			(layers "B.Cu" "B.Mask" "B.Paste")
			(net "GND")
		)
	)
	(footprint ""
		(layer "B.Cu")
		(at 335.014824 -399.722848 -90)
		(property "Reference" "C649"
			(at 0 0 90)
			(layer "B.SilkS")
			(hide yes)
			(effects
				(font
					(size 1.27 1.27)
				)
				(justify mirror)
			)
		)
		(property "Value" ""
			(at 0 0 90)
			(layer "B.Fab")
			(effects
				(font
					(size 1.27 1.27)
				)
				(justify mirror)
			)
		)
		(duplicate_pad_numbers_are_jumpers no)
		(fp_line
			(start -0.7874 0.4064)
			(end 0.7874 0.4064)
			(stroke
				(width 0.1524)
				(type default)
			)
			(layer "B.SilkS")
		)
		(fp_line
			(start 0.7874 0.4064)
			(end 0.7874 -0.4064)
			(stroke
				(width 0.1524)
				(type default)
			)
			(layer "B.SilkS")
		)
		(fp_line
			(start -0.7874 -0.4064)
			(end -0.7874 0.4064)
			(stroke
				(width 0.1524)
				(type default)
			)
			(layer "B.SilkS")
		)
		(fp_line
			(start 0.7874 -0.4064)
			(end -0.7874 -0.4064)
			(stroke
				(width 0.1524)
				(type default)
			)
			(layer "B.SilkS")
		)
		(fp_line
			(start -0.67945 0.3048)
			(end -0.120396 0.3048)
			(stroke
				(width 0.1)
				(type default)
			)
			(layer "B.Fab")
		)
		(fp_line
			(start -0.120396 0.3048)
			(end -0.120396 0.2794)
			(stroke
				(width 0.1)
				(type default)
			)
			(layer "B.Fab")
		)
		(fp_line
			(start 0.12065 0.3048)
			(end 0.67945 0.3048)
			(stroke
				(width 0.1)
				(type default)
			)
			(layer "B.Fab")
		)
		(fp_line
			(start 0.67945 0.3048)
			(end 0.67945 -0.305054)
			(stroke
				(width 0.1)
				(type default)
			)
			(layer "B.Fab")
		)
		(fp_line
			(start -0.120396 0.2794)
			(end 0.12065 0.2794)
			(stroke
				(width 0.1)
				(type default)
			)
			(layer "B.Fab")
		)
		(fp_line
			(start 0.12065 0.2794)
			(end 0.12065 0.3048)
			(stroke
				(width 0.1)
				(type default)
			)
			(layer "B.Fab")
		)
		(fp_line
			(start -0.12065 -0.2794)
			(end -0.12065 -0.3048)
			(stroke
				(width 0.1)
				(type default)
			)
			(layer "B.Fab")
		)
		(fp_line
			(start 0.12065 -0.2794)
			(end -0.12065 -0.2794)
			(stroke
				(width 0.1)
				(type default)
			)
			(layer "B.Fab")
		)
		(fp_line
			(start -0.67945 -0.3048)
			(end -0.67945 0.3048)
			(stroke
				(width 0.1)
				(type default)
			)
			(layer "B.Fab")
		)
		(fp_line
			(start -0.12065 -0.3048)
			(end -0.67945 -0.3048)
			(stroke
				(width 0.1)
				(type default)
			)
			(layer "B.Fab")
		)
		(fp_line
			(start 0.12065 -0.305054)
			(end 0.12065 -0.2794)
			(stroke
				(width 0.1)
				(type default)
			)
			(layer "B.Fab")
		)
		(fp_line
			(start 0.67945 -0.305054)
			(end 0.12065 -0.305054)
			(stroke
				(width 0.1)
				(type default)
			)
			(layer "B.Fab")
		)
		(pad "1" smd circle
			(at 0.40005 0 90)
			(size 0 0)
			(layers "B.Cu" "B.Mask" "B.Paste")
			(net "P0V9_CPU0_RT1_2A")
		)
		(pad "2" smd circle
			(at -0.40005 0 90)
			(size 0 0)
			(layers "B.Cu" "B.Mask" "B.Paste")
			(net "GND")
		)
	)
	(footprint ""
		(layer "B.Cu")
		(at 401.11807 -331.360526 90)
		(property "Reference" "R441"
			(at 0 0 90)
			(layer "B.SilkS")
			(hide yes)
			(effects
				(font
					(size 1.27 1.27)
				)
				(justify mirror)
			)
		)
		(property "Value" ""
			(at 0 0 90)
			(layer "B.Fab")
			(effects
				(font
					(size 1.27 1.27)
				)
				(justify mirror)
			)
		)
		(duplicate_pad_numbers_are_jumpers no)
		(fp_line
			(start 0.7874 -0.4064)
			(end -0.7874 -0.4064)
			(stroke
				(width 0.1524)
				(type default)
			)
			(layer "B.SilkS")
		)
		(fp_line
			(start -0.7874 -0.4064)
			(end -0.7874 0.4064)
			(stroke
				(width 0.1524)
				(type default)
			)
			(layer "B.SilkS")
		)
		(fp_line
			(start 0.7874 0.4064)
			(end 0.7874 -0.4064)
			(stroke
				(width 0.1524)
				(type default)
			)
			(layer "B.SilkS")
		)
		(fp_line
			(start -0.7874 0.4064)
			(end 0.7874 0.4064)
			(stroke
				(width 0.1524)
				(type default)
			)
			(layer "B.SilkS")
		)
		(fp_line
			(start 0.67945 -0.305054)
			(end 0.12065 -0.305054)
			(stroke
				(width 0.1)
				(type default)
			)
			(layer "B.Fab")
		)
		(fp_line
			(start 0.12065 -0.305054)
			(end 0.12065 -0.2794)
			(stroke
				(width 0.1)
				(type default)
			)
			(layer "B.Fab")
		)
		(fp_line
			(start -0.12065 -0.3048)
			(end -0.67945 -0.3048)
			(stroke
				(width 0.1)
				(type default)
			)
			(layer "B.Fab")
		)
		(fp_line
			(start -0.67945 -0.3048)
			(end -0.67945 0.3048)
			(stroke
				(width 0.1)
				(type default)
			)
			(layer "B.Fab")
		)
		(fp_line
			(start 0.12065 -0.2794)
			(end -0.12065 -0.2794)
			(stroke
				(width 0.1)
				(type default)
			)
			(layer "B.Fab")
		)
		(fp_line
			(start -0.12065 -0.2794)
			(end -0.12065 -0.3048)
			(stroke
				(width 0.1)
				(type default)
			)
			(layer "B.Fab")
		)
		(fp_line
			(start 0.12065 0.2794)
			(end 0.12065 0.3048)
			(stroke
				(width 0.1)
				(type default)
			)
			(layer "B.Fab")
		)
		(fp_line
			(start -0.120396 0.2794)
			(end 0.12065 0.2794)
			(stroke
				(width 0.1)
				(type default)
			)
			(layer "B.Fab")
		)
		(fp_line
			(start 0.67945 0.3048)
			(end 0.67945 -0.305054)
			(stroke
				(width 0.1)
				(type default)
			)
			(layer "B.Fab")
		)
		(fp_line
			(start 0.12065 0.3048)
			(end 0.67945 0.3048)
			(stroke
				(width 0.1)
				(type default)
			)
			(layer "B.Fab")
		)
		(fp_line
			(start -0.120396 0.3048)
			(end -0.120396 0.2794)
			(stroke
				(width 0.1)
				(type default)
			)
			(layer "B.Fab")
		)
		(fp_line
			(start -0.67945 0.3048)
			(end -0.120396 0.3048)
			(stroke
				(width 0.1)
				(type default)
			)
			(layer "B.Fab")
		)
		(pad "1" smd circle
			(at 0.40005 0 270)
			(size 0 0)
			(layers "B.Cu" "B.Mask" "B.Paste")
			(net "CPU0_NMI_SYNC_FLOOD_N")
		)
		(pad "2" smd circle
			(at -0.40005 0 270)
			(size 0 0)
			(layers "B.Cu" "B.Mask" "B.Paste")
			(net "PVDD18_S5_P0")
		)
	)
	(footprint ""
		(layer "B.Cu")
		(at 131.474972 -41.007792 90)
		(property "Reference" "C6040"
			(at 0 0 90)
			(layer "B.SilkS")
			(hide yes)
			(effects
				(font
					(size 1.27 1.27)
				)
				(justify mirror)
			)
		)
		(property "Value" ""
			(at 0 0 90)
			(layer "B.Fab")
			(effects
				(font
					(size 1.27 1.27)
				)
				(justify mirror)
			)
		)
		(duplicate_pad_numbers_are_jumpers no)
		(fp_line
			(start 0.7874 -0.4064)
			(end -0.7874 -0.4064)
			(stroke
				(width 0.1524)
				(type default)
			)
			(layer "B.SilkS")
		)
		(fp_line
			(start -0.7874 -0.4064)
			(end -0.7874 0.4064)
			(stroke
				(width 0.1524)
				(type default)
			)
			(layer "B.SilkS")
		)
		(fp_line
			(start 0.7874 0.4064)
			(end 0.7874 -0.4064)
			(stroke
				(width 0.1524)
				(type default)
			)
			(layer "B.SilkS")
		)
		(fp_line
			(start -0.7874 0.4064)
			(end 0.7874 0.4064)
			(stroke
				(width 0.1524)
				(type default)
			)
			(layer "B.SilkS")
		)
		(fp_line
			(start 0.67945 -0.305054)
			(end 0.12065 -0.305054)
			(stroke
				(width 0.1)
				(type default)
			)
			(layer "B.Fab")
		)
		(fp_line
			(start 0.12065 -0.305054)
			(end 0.12065 -0.2794)
			(stroke
				(width 0.1)
				(type default)
			)
			(layer "B.Fab")
		)
		(fp_line
			(start -0.12065 -0.3048)
			(end -0.67945 -0.3048)
			(stroke
				(width 0.1)
				(type default)
			)
			(layer "B.Fab")
		)
		(fp_line
			(start -0.67945 -0.3048)
			(end -0.67945 0.3048)
			(stroke
				(width 0.1)
				(type default)
			)
			(layer "B.Fab")
		)
		(fp_line
			(start 0.12065 -0.2794)
			(end -0.12065 -0.2794)
			(stroke
				(width 0.1)
				(type default)
			)
			(layer "B.Fab")
		)
		(fp_line
			(start -0.12065 -0.2794)
			(end -0.12065 -0.3048)
			(stroke
				(width 0.1)
				(type default)
			)
			(layer "B.Fab")
		)
		(fp_line
			(start 0.12065 0.2794)
			(end 0.12065 0.3048)
			(stroke
				(width 0.1)
				(type default)
			)
			(layer "B.Fab")
		)
		(fp_line
			(start -0.120396 0.2794)
			(end 0.12065 0.2794)
			(stroke
				(width 0.1)
				(type default)
			)
			(layer "B.Fab")
		)
		(fp_line
			(start 0.67945 0.3048)
			(end 0.67945 -0.305054)
			(stroke
				(width 0.1)
				(type default)
			)
			(layer "B.Fab")
		)
		(fp_line
			(start 0.12065 0.3048)
			(end 0.67945 0.3048)
			(stroke
				(width 0.1)
				(type default)
			)
			(layer "B.Fab")
		)
		(fp_line
			(start -0.120396 0.3048)
			(end -0.120396 0.2794)
			(stroke
				(width 0.1)
				(type default)
			)
			(layer "B.Fab")
		)
		(fp_line
			(start -0.67945 0.3048)
			(end -0.120396 0.3048)
			(stroke
				(width 0.1)
				(type default)
			)
			(layer "B.Fab")
		)
		(pad "1" smd circle
			(at 0.40005 0 270)
			(size 0 0)
			(layers "B.Cu" "B.Mask" "B.Paste")
			(net "P3V3_AUX")
		)
		(pad "2" smd circle
			(at -0.40005 0 270)
			(size 0 0)
			(layers "B.Cu" "B.Mask" "B.Paste")
			(net "GND")
		)
	)
	(footprint ""
		(layer "B.Cu")
		(at 409.623768 -162.508438 -90)
		(property "Reference" "PC612_3"
			(at 0 0 90)
			(layer "B.SilkS")
			(hide yes)
			(effects
				(font
					(size 1.27 1.27)
				)
				(justify mirror)
			)
		)
		(property "Value" ""
			(at 0 0 90)
			(layer "B.Fab")
			(effects
				(font
					(size 1.27 1.27)
				)
				(justify mirror)
			)
		)
		(duplicate_pad_numbers_are_jumpers no)
		(fp_line
			(start -1.524 0.762)
			(end 1.524 0.762)
			(stroke
				(width 0.1524)
				(type default)
			)
			(layer "B.SilkS")
		)
		(fp_line
			(start 1.524 0.762)
			(end 1.524 -0.762)
			(stroke
				(width 0.1524)
				(type default)
			)
			(layer "B.SilkS")
		)
		(fp_line
			(start -1.524 -0.762)
			(end -1.524 0.762)
			(stroke
				(width 0.1524)
				(type default)
			)
			(layer "B.SilkS")
		)
		(fp_line
			(start 1.524 -0.762)
			(end -1.524 -0.762)
			(stroke
				(width 0.1524)
				(type default)
			)
			(layer "B.SilkS")
		)
		(fp_line
			(start -1.1049 0.724916)
			(end -1.1049 -0.724916)
			(stroke
				(width 0.1)
				(type default)
			)
			(layer "B.Fab")
		)
		(fp_line
			(start 1.1049 0.724916)
			(end -1.1049 0.724916)
			(stroke
				(width 0.1)
				(type default)
			)
			(layer "B.Fab")
		)
		(fp_line
			(start -1.1049 -0.724916)
			(end 1.1049 -0.724916)
			(stroke
				(width 0.1)
				(type default)
			)
			(layer "B.Fab")
		)
		(fp_line
			(start 1.1049 -0.724916)
			(end 1.1049 0.724916)
			(stroke
				(width 0.1)
				(type default)
			)
			(layer "B.Fab")
		)
		(pad "1" smd rect
			(at 0.889 0 270)
			(size 1.016 1.27)
			(layers "B.Cu" "B.Mask" "B.Paste")
			(net "SW_P12V_AUX_PVDDCR_SOC_P0_FLT")
		)
		(pad "2" smd rect
			(at -0.889 0 270)
			(size 1.016 1.27)
			(layers "B.Cu" "B.Mask" "B.Paste")
			(net "GND")
		)
	)
	(footprint ""
		(layer "B.Cu")
		(at 455.213466 -397.05407 90)
		(property "Reference" "PC6579_2"
			(at 0 0 90)
			(layer "B.SilkS")
			(hide yes)
			(effects
				(font
					(size 1.27 1.27)
				)
				(justify mirror)
			)
		)
		(property "Value" ""
			(at 0 0 90)
			(layer "B.Fab")
			(effects
				(font
					(size 1.27 1.27)
				)
				(justify mirror)
			)
		)
		(duplicate_pad_numbers_are_jumpers no)
		(fp_line
			(start 1.524 -0.762)
			(end -1.524 -0.762)
			(stroke
				(width 0.1524)
				(type default)
			)
			(layer "B.SilkS")
		)
		(fp_line
			(start -1.524 -0.762)
			(end -1.524 0.762)
			(stroke
				(width 0.1524)
				(type default)
			)
			(layer "B.SilkS")
		)
		(fp_line
			(start 1.524 0.762)
			(end 1.524 -0.762)
			(stroke
				(width 0.1524)
				(type default)
			)
			(layer "B.SilkS")
		)
		(fp_line
			(start -1.524 0.762)
			(end 1.524 0.762)
			(stroke
				(width 0.1524)
				(type default)
			)
			(layer "B.SilkS")
		)
		(fp_line
			(start 1.1049 -0.724916)
			(end 1.1049 0.724916)
			(stroke
				(width 0.1)
				(type default)
			)
			(layer "B.Fab")
		)
		(fp_line
			(start -1.1049 -0.724916)
			(end 1.1049 -0.724916)
			(stroke
				(width 0.1)
				(type default)
			)
			(layer "B.Fab")
		)
		(fp_line
			(start 1.1049 0.724916)
			(end -1.1049 0.724916)
			(stroke
				(width 0.1)
				(type default)
			)
			(layer "B.Fab")
		)
		(fp_line
			(start -1.1049 0.724916)
			(end -1.1049 -0.724916)
			(stroke
				(width 0.1)
				(type default)
			)
			(layer "B.Fab")
		)
		(pad "1" smd rect
			(at 0.889 0 90)
			(size 1.016 1.27)
			(layers "B.Cu" "B.Mask" "B.Paste")
			(net "SW_P12V_AUX_P0V9_RETIMER_CPU0_FLT")
		)
		(pad "2" smd rect
			(at -0.889 0 90)
			(size 1.016 1.27)
			(layers "B.Cu" "B.Mask" "B.Paste")
			(net "GND")
		)
	)
	(footprint ""
		(layer "B.Cu")
		(at 396.792958 -326.163432)
		(property "Reference" "R1506"
			(at 0 0 0)
			(layer "B.SilkS")
			(hide yes)
			(effects
				(font
					(size 1.27 1.27)
				)
				(justify mirror)
			)
		)
		(property "Value" ""
			(at 0 0 0)
			(layer "B.Fab")
			(effects
				(font
					(size 1.27 1.27)
				)
				(justify mirror)
			)
		)
		(duplicate_pad_numbers_are_jumpers no)
		(fp_line
			(start -0.7874 -0.4064)
			(end -0.7874 0.4064)
			(stroke
				(width 0.1524)
				(type default)
			)
			(layer "B.SilkS")
		)
		(fp_line
			(start -0.7874 0.4064)
			(end 0.7874 0.4064)
			(stroke
				(width 0.1524)
				(type default)
			)
			(layer "B.SilkS")
		)
		(fp_line
			(start 0.7874 -0.4064)
			(end -0.7874 -0.4064)
			(stroke
				(width 0.1524)
				(type default)
			)
			(layer "B.SilkS")
		)
		(fp_line
			(start 0.7874 0.4064)
			(end 0.7874 -0.4064)
			(stroke
				(width 0.1524)
				(type default)
			)
			(layer "B.SilkS")
		)
		(fp_line
			(start -0.67945 -0.3048)
			(end -0.67945 0.3048)
			(stroke
				(width 0.1)
				(type default)
			)
			(layer "B.Fab")
		)
		(fp_line
			(start -0.67945 0.3048)
			(end -0.120396 0.3048)
			(stroke
				(width 0.1)
				(type default)
			)
			(layer "B.Fab")
		)
		(fp_line
			(start -0.12065 -0.3048)
			(end -0.67945 -0.3048)
			(stroke
				(width 0.1)
				(type default)
			)
			(layer "B.Fab")
		)
		(fp_line
			(start -0.12065 -0.2794)
			(end -0.12065 -0.3048)
			(stroke
				(width 0.1)
				(type default)
			)
			(layer "B.Fab")
		)
		(fp_line
			(start -0.120396 0.2794)
			(end 0.12065 0.2794)
			(stroke
				(width 0.1)
				(type default)
			)
			(layer "B.Fab")
		)
		(fp_line
			(start -0.120396 0.3048)
			(end -0.120396 0.2794)
			(stroke
				(width 0.1)
				(type default)
			)
			(layer "B.Fab")
		)
		(fp_line
			(start 0.12065 -0.305054)
			(end 0.12065 -0.2794)
			(stroke
				(width 0.1)
				(type default)
			)
			(layer "B.Fab")
		)
		(fp_line
			(start 0.12065 -0.2794)
			(end -0.12065 -0.2794)
			(stroke
				(width 0.1)
				(type default)
			)
			(layer "B.Fab")
		)
		(fp_line
			(start 0.12065 0.2794)
			(end 0.12065 0.3048)
			(stroke
				(width 0.1)
				(type default)
			)
			(layer "B.Fab")
		)
		(fp_line
			(start 0.12065 0.3048)
			(end 0.67945 0.3048)
			(stroke
				(width 0.1)
				(type default)
			)
			(layer "B.Fab")
		)
		(fp_line
			(start 0.67945 -0.305054)
			(end 0.12065 -0.305054)
			(stroke
				(width 0.1)
				(type default)
			)
			(layer "B.Fab")
		)
		(fp_line
			(start 0.67945 0.3048)
			(end 0.67945 -0.305054)
			(stroke
				(width 0.1)
				(type default)
			)
			(layer "B.Fab")
		)
		(pad "1" smd circle
			(at 0.40005 0 180)
			(size 0 0)
			(layers "B.Cu" "B.Mask" "B.Paste")
			(net "PVDD18_S5_P0")
		)
		(pad "2" smd circle
			(at -0.40005 0 180)
			(size 0 0)
			(layers "B.Cu" "B.Mask" "B.Paste")
			(net "ESPI_CPU0_D3")
		)
	)
	(footprint ""
		(layer "B.Cu")
		(at 106.466386 -264.354564)
		(property "Reference" "C3903"
			(at 0 0 0)
			(layer "B.SilkS")
			(hide yes)
			(effects
				(font
					(size 1.27 1.27)
				)
				(justify mirror)
			)
		)
		(property "Value" ""
			(at 0 0 0)
			(layer "B.Fab")
			(effects
				(font
					(size 1.27 1.27)
				)
				(justify mirror)
			)
		)
		(duplicate_pad_numbers_are_jumpers no)
		(fp_line
			(start -0.7874 -0.4064)
			(end -0.7874 0.4064)
			(stroke
				(width 0.1524)
				(type default)
			)
			(layer "B.SilkS")
		)
		(fp_line
			(start -0.7874 0.4064)
			(end 0.7874 0.4064)
			(stroke
				(width 0.1524)
				(type default)
			)
			(layer "B.SilkS")
		)
		(fp_line
			(start 0.7874 -0.4064)
			(end -0.7874 -0.4064)
			(stroke
				(width 0.1524)
				(type default)
			)
			(layer "B.SilkS")
		)
		(fp_line
			(start 0.7874 0.4064)
			(end 0.7874 -0.4064)
			(stroke
				(width 0.1524)
				(type default)
			)
			(layer "B.SilkS")
		)
		(fp_line
			(start -0.67945 -0.3048)
			(end -0.67945 0.3048)
			(stroke
				(width 0.1)
				(type default)
			)
			(layer "B.Fab")
		)
		(fp_line
			(start -0.67945 0.3048)
			(end -0.120396 0.3048)
			(stroke
				(width 0.1)
				(type default)
			)
			(layer "B.Fab")
		)
		(fp_line
			(start -0.12065 -0.3048)
			(end -0.67945 -0.3048)
			(stroke
				(width 0.1)
				(type default)
			)
			(layer "B.Fab")
		)
		(fp_line
			(start -0.12065 -0.2794)
			(end -0.12065 -0.3048)
			(stroke
				(width 0.1)
				(type default)
			)
			(layer "B.Fab")
		)
		(fp_line
			(start -0.120396 0.2794)
			(end 0.12065 0.2794)
			(stroke
				(width 0.1)
				(type default)
			)
			(layer "B.Fab")
		)
		(fp_line
			(start -0.120396 0.3048)
			(end -0.120396 0.2794)
			(stroke
				(width 0.1)
				(type default)
			)
			(layer "B.Fab")
		)
		(fp_line
			(start 0.12065 -0.305054)
			(end 0.12065 -0.2794)
			(stroke
				(width 0.1)
				(type default)
			)
			(layer "B.Fab")
		)
		(fp_line
			(start 0.12065 -0.2794)
			(end -0.12065 -0.2794)
			(stroke
				(width 0.1)
				(type default)
			)
			(layer "B.Fab")
		)
		(fp_line
			(start 0.12065 0.2794)
			(end 0.12065 0.3048)
			(stroke
				(width 0.1)
				(type default)
			)
			(layer "B.Fab")
		)
		(fp_line
			(start 0.12065 0.3048)
			(end 0.67945 0.3048)
			(stroke
				(width 0.1)
				(type default)
			)
			(layer "B.Fab")
		)
		(fp_line
			(start 0.67945 -0.305054)
			(end 0.12065 -0.305054)
			(stroke
				(width 0.1)
				(type default)
			)
			(layer "B.Fab")
		)
		(fp_line
			(start 0.67945 0.3048)
			(end 0.67945 -0.305054)
			(stroke
				(width 0.1)
				(type default)
			)
			(layer "B.Fab")
		)
		(pad "1" smd circle
			(at 0.40005 0 180)
			(size 0 0)
			(layers "B.Cu" "B.Mask" "B.Paste")
			(net "PVDD11_S3_P1")
		)
		(pad "2" smd circle
			(at -0.40005 0 180)
			(size 0 0)
			(layers "B.Cu" "B.Mask" "B.Paste")
			(net "GND")
		)
	)
	(footprint ""
		(layer "B.Cu")
		(at 86.760304 -328.22388 -90)
		(property "Reference" "PC391"
			(at 9.533636 -0.911606 270)
			(unlocked yes)
			(layer "B.SilkS")
			(effects
				(font
					(size 0.7874 0.5842)
					(thickness 0.1524)
				)
				(justify left mirror)
			)
		)
		(property "Value" ""
			(at 0 0 90)
			(layer "B.Fab")
			(effects
				(font
					(size 1.27 1.27)
				)
				(justify mirror)
			)
		)
		(duplicate_pad_numbers_are_jumpers no)
		(fp_line
			(start -4.533392 2.249932)
			(end 4.533392 2.249932)
			(stroke
				(width 0.1524)
				(type default)
			)
			(layer "B.SilkS")
		)
		(fp_line
			(start 4.533392 2.249932)
			(end 4.533392 -2.249932)
			(stroke
				(width 0.1524)
				(type default)
			)
			(layer "B.SilkS")
		)
		(fp_line
			(start -4.533392 -2.249932)
			(end -4.533392 2.249932)
			(stroke
				(width 0.1524)
				(type default)
			)
			(layer "B.SilkS")
		)
		(fp_line
			(start 4.533392 -2.249932)
			(end -4.533392 -2.249932)
			(stroke
				(width 0.1524)
				(type default)
			)
			(layer "B.SilkS")
		)
		(fp_rect
			(start 5.39242 2.326132)
			(end 4.533392 -2.326132)
			(stroke
				(width 0)
				(type default)
			)
			(fill yes)
			(layer "B.SilkS")
		)
		(fp_line
			(start -3.750056 2.249932)
			(end 3.750056 2.249932)
			(stroke
				(width 0.1)
				(type default)
			)
			(layer "B.Fab")
		)
		(fp_line
			(start 3.750056 2.249932)
			(end 3.750056 -2.249932)
			(stroke
				(width 0.1)
				(type default)
			)
			(layer "B.Fab")
		)
		(fp_line
			(start -3.750056 -2.249932)
			(end -3.750056 2.249932)
			(stroke
				(width 0.1)
				(type default)
			)
			(layer "B.Fab")
		)
		(fp_line
			(start 3.750056 -2.249932)
			(end -3.750056 -2.249932)
			(stroke
				(width 0.1)
				(type default)
			)
			(layer "B.Fab")
		)
		(fp_text user "-"
			(at -4.562348 1.995932 270)
			(unlocked yes)
			(layer "B.SilkS")
			(effects
				(font
					(size 1.905 1.4224)
					(thickness 0.1524)
				)
				(justify left mirror)
			)
		)
		(fp_text user "+"
			(at 6.322314 0.786384 180)
			(unlocked yes)
			(layer "B.SilkS")
			(effects
				(font
					(size 1.905 1.4224)
					(thickness 0.1524)
				)
				(justify left mirror)
			)
		)
		(fp_text user "+"
			(at 6.322314 0.786384 180)
			(unlocked yes)
			(layer "B.Fab")
			(effects
				(font
					(size 1.905 1.4224)
					(thickness 0.1524)
				)
				(justify left mirror)
			)
		)
		(fp_text user "-"
			(at -4.8514 -0.14605 270)
			(unlocked yes)
			(layer "B.Fab")
			(effects
				(font
					(size 1.905 1.4224)
					(thickness 0.1524)
				)
				(justify left mirror)
			)
		)
		(pad "1" smd rect
			(at 3.199892 0 90)
			(size 2.413 2.8194)
			(layers "B.Cu" "B.Mask" "B.Paste")
			(net "PVDDCR_CPU1_P1")
		)
		(pad "2" smd rect
			(at -3.199892 0 90)
			(size 2.413 2.8194)
			(layers "B.Cu" "B.Mask" "B.Paste")
			(net "GND")
		)
	)
	(footprint ""
		(layer "B.Cu")
		(at 252.950726 -321.850004 180)
		(property "Reference" "C1079"
			(at 0 0 0)
			(layer "B.SilkS")
			(hide yes)
			(effects
				(font
					(size 1.27 1.27)
				)
				(justify mirror)
			)
		)
		(property "Value" ""
			(at 0 0 0)
			(layer "B.Fab")
			(effects
				(font
					(size 1.27 1.27)
				)
				(justify mirror)
			)
		)
		(duplicate_pad_numbers_are_jumpers no)
		(fp_line
			(start 0.7874 0.4064)
			(end 0.7874 -0.4064)
			(stroke
				(width 0.1524)
				(type default)
			)
			(layer "B.SilkS")
		)
		(fp_line
			(start 0.7874 -0.4064)
			(end -0.7874 -0.4064)
			(stroke
				(width 0.1524)
				(type default)
			)
			(layer "B.SilkS")
		)
		(fp_line
			(start -0.7874 0.4064)
			(end 0.7874 0.4064)
			(stroke
				(width 0.1524)
				(type default)
			)
			(layer "B.SilkS")
		)
		(fp_line
			(start -0.7874 -0.4064)
			(end -0.7874 0.4064)
			(stroke
				(width 0.1524)
				(type default)
			)
			(layer "B.SilkS")
		)
		(fp_line
			(start 0.67945 0.3048)
			(end 0.67945 -0.305054)
			(stroke
				(width 0.1)
				(type default)
			)
			(layer "B.Fab")
		)
		(fp_line
			(start 0.67945 -0.305054)
			(end 0.12065 -0.305054)
			(stroke
				(width 0.1)
				(type default)
			)
			(layer "B.Fab")
		)
		(fp_line
			(start 0.12065 0.3048)
			(end 0.67945 0.3048)
			(stroke
				(width 0.1)
				(type default)
			)
			(layer "B.Fab")
		)
		(fp_line
			(start 0.12065 0.2794)
			(end 0.12065 0.3048)
			(stroke
				(width 0.1)
				(type default)
			)
			(layer "B.Fab")
		)
		(fp_line
			(start 0.12065 -0.2794)
			(end -0.12065 -0.2794)
			(stroke
				(width 0.1)
				(type default)
			)
			(layer "B.Fab")
		)
		(fp_line
			(start 0.12065 -0.305054)
			(end 0.12065 -0.2794)
			(stroke
				(width 0.1)
				(type default)
			)
			(layer "B.Fab")
		)
		(fp_line
			(start -0.120396 0.3048)
			(end -0.120396 0.2794)
			(stroke
				(width 0.1)
				(type default)
			)
			(layer "B.Fab")
		)
		(fp_line
			(start -0.120396 0.2794)
			(end 0.12065 0.2794)
			(stroke
				(width 0.1)
				(type default)
			)
			(layer "B.Fab")
		)
		(fp_line
			(start -0.12065 -0.2794)
			(end -0.12065 -0.3048)
			(stroke
				(width 0.1)
				(type default)
			)
			(layer "B.Fab")
		)
		(fp_line
			(start -0.12065 -0.3048)
			(end -0.67945 -0.3048)
			(stroke
				(width 0.1)
				(type default)
			)
			(layer "B.Fab")
		)
		(fp_line
			(start -0.67945 0.3048)
			(end -0.120396 0.3048)
			(stroke
				(width 0.1)
				(type default)
			)
			(layer "B.Fab")
		)
		(fp_line
			(start -0.67945 -0.3048)
			(end -0.67945 0.3048)
			(stroke
				(width 0.1)
				(type default)
			)
			(layer "B.Fab")
		)
		(pad "1" smd circle
			(at 0.40005 0)
			(size 0 0)
			(layers "B.Cu" "B.Mask" "B.Paste")
			(net "P1V8_CPU0_RT_1D_ADC_MAM")
		)
		(pad "2" smd circle
			(at -0.40005 0)
			(size 0 0)
			(layers "B.Cu" "B.Mask" "B.Paste")
			(net "GND")
		)
	)
	(footprint ""
		(layer "B.Cu")
		(at 165.018974 -390.560052 90)
		(property "Reference" "C431"
			(at 0 0 90)
			(layer "B.SilkS")
			(hide yes)
			(effects
				(font
					(size 1.27 1.27)
				)
				(justify mirror)
			)
		)
		(property "Value" ""
			(at 0 0 90)
			(layer "B.Fab")
			(effects
				(font
					(size 1.27 1.27)
				)
				(justify mirror)
			)
		)
		(duplicate_pad_numbers_are_jumpers no)
		(fp_line
			(start 0.7874 -0.4064)
			(end -0.7874 -0.4064)
			(stroke
				(width 0.1524)
				(type default)
			)
			(layer "B.SilkS")
		)
		(fp_line
			(start -0.7874 -0.4064)
			(end -0.7874 0.4064)
			(stroke
				(width 0.1524)
				(type default)
			)
			(layer "B.SilkS")
		)
		(fp_line
			(start 0.7874 0.4064)
			(end 0.7874 -0.4064)
			(stroke
				(width 0.1524)
				(type default)
			)
			(layer "B.SilkS")
		)
		(fp_line
			(start -0.7874 0.4064)
			(end 0.7874 0.4064)
			(stroke
				(width 0.1524)
				(type default)
			)
			(layer "B.SilkS")
		)
		(fp_line
			(start 0.67945 -0.305054)
			(end 0.12065 -0.305054)
			(stroke
				(width 0.1)
				(type default)
			)
			(layer "B.Fab")
		)
		(fp_line
			(start 0.12065 -0.305054)
			(end 0.12065 -0.2794)
			(stroke
				(width 0.1)
				(type default)
			)
			(layer "B.Fab")
		)
		(fp_line
			(start -0.12065 -0.3048)
			(end -0.67945 -0.3048)
			(stroke
				(width 0.1)
				(type default)
			)
			(layer "B.Fab")
		)
		(fp_line
			(start -0.67945 -0.3048)
			(end -0.67945 0.3048)
			(stroke
				(width 0.1)
				(type default)
			)
			(layer "B.Fab")
		)
		(fp_line
			(start 0.12065 -0.2794)
			(end -0.12065 -0.2794)
			(stroke
				(width 0.1)
				(type default)
			)
			(layer "B.Fab")
		)
		(fp_line
			(start -0.12065 -0.2794)
			(end -0.12065 -0.3048)
			(stroke
				(width 0.1)
				(type default)
			)
			(layer "B.Fab")
		)
		(fp_line
			(start 0.12065 0.2794)
			(end 0.12065 0.3048)
			(stroke
				(width 0.1)
				(type default)
			)
			(layer "B.Fab")
		)
		(fp_line
			(start -0.120396 0.2794)
			(end 0.12065 0.2794)
			(stroke
				(width 0.1)
				(type default)
			)
			(layer "B.Fab")
		)
		(fp_line
			(start 0.67945 0.3048)
			(end 0.67945 -0.305054)
			(stroke
				(width 0.1)
				(type default)
			)
			(layer "B.Fab")
		)
		(fp_line
			(start 0.12065 0.3048)
			(end 0.67945 0.3048)
			(stroke
				(width 0.1)
				(type default)
			)
			(layer "B.Fab")
		)
		(fp_line
			(start -0.120396 0.3048)
			(end -0.120396 0.2794)
			(stroke
				(width 0.1)
				(type default)
			)
			(layer "B.Fab")
		)
		(fp_line
			(start -0.67945 0.3048)
			(end -0.120396 0.3048)
			(stroke
				(width 0.1)
				(type default)
			)
			(layer "B.Fab")
		)
		(pad "1" smd circle
			(at 0.40005 0 270)
			(size 0 0)
			(layers "B.Cu" "B.Mask" "B.Paste")
			(net "P0V9_CPU1_RT2_2A")
		)
		(pad "2" smd circle
			(at -0.40005 0 270)
			(size 0 0)
			(layers "B.Cu" "B.Mask" "B.Paste")
			(net "GND")
		)
	)
	(footprint ""
		(layer "B.Cu")
		(at 9.838182 -409.472384 90)
		(property "Reference" "PR6548"
			(at 0 0 90)
			(layer "B.SilkS")
			(hide yes)
			(effects
				(font
					(size 1.27 1.27)
				)
				(justify mirror)
			)
		)
		(property "Value" ""
			(at 0 0 90)
			(layer "B.Fab")
			(effects
				(font
					(size 1.27 1.27)
				)
				(justify mirror)
			)
		)
		(duplicate_pad_numbers_are_jumpers no)
		(fp_line
			(start 0.7874 -0.4064)
			(end -0.7874 -0.4064)
			(stroke
				(width 0.1524)
				(type default)
			)
			(layer "B.SilkS")
		)
		(fp_line
			(start -0.7874 -0.4064)
			(end -0.7874 0.4064)
			(stroke
				(width 0.1524)
				(type default)
			)
			(layer "B.SilkS")
		)
		(fp_line
			(start 0.7874 0.4064)
			(end 0.7874 -0.4064)
			(stroke
				(width 0.1524)
				(type default)
			)
			(layer "B.SilkS")
		)
		(fp_line
			(start -0.7874 0.4064)
			(end 0.7874 0.4064)
			(stroke
				(width 0.1524)
				(type default)
			)
			(layer "B.SilkS")
		)
		(fp_line
			(start 0.67945 -0.305054)
			(end 0.12065 -0.305054)
			(stroke
				(width 0.1)
				(type default)
			)
			(layer "B.Fab")
		)
		(fp_line
			(start 0.12065 -0.305054)
			(end 0.12065 -0.2794)
			(stroke
				(width 0.1)
				(type default)
			)
			(layer "B.Fab")
		)
		(fp_line
			(start -0.12065 -0.3048)
			(end -0.67945 -0.3048)
			(stroke
				(width 0.1)
				(type default)
			)
			(layer "B.Fab")
		)
		(fp_line
			(start -0.67945 -0.3048)
			(end -0.67945 0.3048)
			(stroke
				(width 0.1)
				(type default)
			)
			(layer "B.Fab")
		)
		(fp_line
			(start 0.12065 -0.2794)
			(end -0.12065 -0.2794)
			(stroke
				(width 0.1)
				(type default)
			)
			(layer "B.Fab")
		)
		(fp_line
			(start -0.12065 -0.2794)
			(end -0.12065 -0.3048)
			(stroke
				(width 0.1)
				(type default)
			)
			(layer "B.Fab")
		)
		(fp_line
			(start 0.12065 0.2794)
			(end 0.12065 0.3048)
			(stroke
				(width 0.1)
				(type default)
			)
			(layer "B.Fab")
		)
		(fp_line
			(start -0.120396 0.2794)
			(end 0.12065 0.2794)
			(stroke
				(width 0.1)
				(type default)
			)
			(layer "B.Fab")
		)
		(fp_line
			(start 0.67945 0.3048)
			(end 0.67945 -0.305054)
			(stroke
				(width 0.1)
				(type default)
			)
			(layer "B.Fab")
		)
		(fp_line
			(start 0.12065 0.3048)
			(end 0.67945 0.3048)
			(stroke
				(width 0.1)
				(type default)
			)
			(layer "B.Fab")
		)
		(fp_line
			(start -0.120396 0.3048)
			(end -0.120396 0.2794)
			(stroke
				(width 0.1)
				(type default)
			)
			(layer "B.Fab")
		)
		(fp_line
			(start -0.67945 0.3048)
			(end -0.120396 0.3048)
			(stroke
				(width 0.1)
				(type default)
			)
			(layer "B.Fab")
		)
		(pad "1" smd circle
			(at 0.40005 0 270)
			(size 0 0)
			(layers "B.Cu" "B.Mask" "B.Paste")
			(net "P0V9_RETIMER_CPU1_TEMP1_R")
		)
		(pad "2" smd circle
			(at -0.40005 0 270)
			(size 0 0)
			(layers "B.Cu" "B.Mask" "B.Paste")
			(net "GND")
		)
	)
	(footprint ""
		(layer "B.Cu")
		(at 343.39022 -169.787062 90)
		(property "Reference" "PC163_6"
			(at 0 0 90)
			(layer "B.SilkS")
			(hide yes)
			(effects
				(font
					(size 1.27 1.27)
				)
				(justify mirror)
			)
		)
		(property "Value" ""
			(at 0 0 90)
			(layer "B.Fab")
			(effects
				(font
					(size 1.27 1.27)
				)
				(justify mirror)
			)
		)
		(duplicate_pad_numbers_are_jumpers no)
		(fp_line
			(start 1.524 -0.762)
			(end -1.524 -0.762)
			(stroke
				(width 0.1524)
				(type default)
			)
			(layer "B.SilkS")
		)
		(fp_line
			(start -1.524 -0.762)
			(end -1.524 0.762)
			(stroke
				(width 0.1524)
				(type default)
			)
			(layer "B.SilkS")
		)
		(fp_line
			(start 1.524 0.762)
			(end 1.524 -0.762)
			(stroke
				(width 0.1524)
				(type default)
			)
			(layer "B.SilkS")
		)
		(fp_line
			(start -1.524 0.762)
			(end 1.524 0.762)
			(stroke
				(width 0.1524)
				(type default)
			)
			(layer "B.SilkS")
		)
		(fp_line
			(start 1.1049 -0.724916)
			(end 1.1049 0.724916)
			(stroke
				(width 0.1)
				(type default)
			)
			(layer "B.Fab")
		)
		(fp_line
			(start -1.1049 -0.724916)
			(end 1.1049 -0.724916)
			(stroke
				(width 0.1)
				(type default)
			)
			(layer "B.Fab")
		)
		(fp_line
			(start 1.1049 0.724916)
			(end -1.1049 0.724916)
			(stroke
				(width 0.1)
				(type default)
			)
			(layer "B.Fab")
		)
		(fp_line
			(start -1.1049 0.724916)
			(end -1.1049 -0.724916)
			(stroke
				(width 0.1)
				(type default)
			)
			(layer "B.Fab")
		)
		(pad "1" smd rect
			(at 0.889 0 90)
			(size 1.016 1.27)
			(layers "B.Cu" "B.Mask" "B.Paste")
			(net "PVDDCR_CPU0_P0")
		)
		(pad "2" smd rect
			(at -0.889 0 90)
			(size 1.016 1.27)
			(layers "B.Cu" "B.Mask" "B.Paste")
			(net "GND")
		)
	)
	(footprint ""
		(layer "B.Cu")
		(at 138.65352 -40.765222 180)
		(property "Reference" "C6070"
			(at 0 0 0)
			(layer "B.SilkS")
			(hide yes)
			(effects
				(font
					(size 1.27 1.27)
				)
				(justify mirror)
			)
		)
		(property "Value" ""
			(at 0 0 0)
			(layer "B.Fab")
			(effects
				(font
					(size 1.27 1.27)
				)
				(justify mirror)
			)
		)
		(duplicate_pad_numbers_are_jumpers no)
		(fp_line
			(start 0.7874 0.4064)
			(end 0.7874 -0.4064)
			(stroke
				(width 0.1524)
				(type default)
			)
			(layer "B.SilkS")
		)
		(fp_line
			(start 0.7874 -0.4064)
			(end -0.7874 -0.4064)
			(stroke
				(width 0.1524)
				(type default)
			)
			(layer "B.SilkS")
		)
		(fp_line
			(start -0.7874 0.4064)
			(end 0.7874 0.4064)
			(stroke
				(width 0.1524)
				(type default)
			)
			(layer "B.SilkS")
		)
		(fp_line
			(start -0.7874 -0.4064)
			(end -0.7874 0.4064)
			(stroke
				(width 0.1524)
				(type default)
			)
			(layer "B.SilkS")
		)
		(fp_line
			(start 0.67945 0.3048)
			(end 0.67945 -0.305054)
			(stroke
				(width 0.1)
				(type default)
			)
			(layer "B.Fab")
		)
		(fp_line
			(start 0.67945 -0.305054)
			(end 0.12065 -0.305054)
			(stroke
				(width 0.1)
				(type default)
			)
			(layer "B.Fab")
		)
		(fp_line
			(start 0.12065 0.3048)
			(end 0.67945 0.3048)
			(stroke
				(width 0.1)
				(type default)
			)
			(layer "B.Fab")
		)
		(fp_line
			(start 0.12065 0.2794)
			(end 0.12065 0.3048)
			(stroke
				(width 0.1)
				(type default)
			)
			(layer "B.Fab")
		)
		(fp_line
			(start 0.12065 -0.2794)
			(end -0.12065 -0.2794)
			(stroke
				(width 0.1)
				(type default)
			)
			(layer "B.Fab")
		)
		(fp_line
			(start 0.12065 -0.305054)
			(end 0.12065 -0.2794)
			(stroke
				(width 0.1)
				(type default)
			)
			(layer "B.Fab")
		)
		(fp_line
			(start -0.120396 0.3048)
			(end -0.120396 0.2794)
			(stroke
				(width 0.1)
				(type default)
			)
			(layer "B.Fab")
		)
		(fp_line
			(start -0.120396 0.2794)
			(end 0.12065 0.2794)
			(stroke
				(width 0.1)
				(type default)
			)
			(layer "B.Fab")
		)
		(fp_line
			(start -0.12065 -0.2794)
			(end -0.12065 -0.3048)
			(stroke
				(width 0.1)
				(type default)
			)
			(layer "B.Fab")
		)
		(fp_line
			(start -0.12065 -0.3048)
			(end -0.67945 -0.3048)
			(stroke
				(width 0.1)
				(type default)
			)
			(layer "B.Fab")
		)
		(fp_line
			(start -0.67945 0.3048)
			(end -0.120396 0.3048)
			(stroke
				(width 0.1)
				(type default)
			)
			(layer "B.Fab")
		)
		(fp_line
			(start -0.67945 -0.3048)
			(end -0.67945 0.3048)
			(stroke
				(width 0.1)
				(type default)
			)
			(layer "B.Fab")
		)
		(pad "1" smd circle
			(at 0.40005 0)
			(size 0 0)
			(layers "B.Cu" "B.Mask" "B.Paste")
			(net "P1V2_AUX")
		)
		(pad "2" smd circle
			(at -0.40005 0)
			(size 0 0)
			(layers "B.Cu" "B.Mask" "B.Paste")
			(net "GND")
		)
	)
	(footprint ""
		(layer "B.Cu")
		(at 160.69183 -16.77416)
		(property "Reference" "R4152"
			(at 0 0 0)
			(layer "B.SilkS")
			(hide yes)
			(effects
				(font
					(size 1.27 1.27)
				)
				(justify mirror)
			)
		)
		(property "Value" ""
			(at 0 0 0)
			(layer "B.Fab")
			(effects
				(font
					(size 1.27 1.27)
				)
				(justify mirror)
			)
		)
		(duplicate_pad_numbers_are_jumpers no)
		(fp_line
			(start -0.7874 -0.4064)
			(end -0.7874 0.4064)
			(stroke
				(width 0.1524)
				(type default)
			)
			(layer "B.SilkS")
		)
		(fp_line
			(start -0.7874 0.4064)
			(end 0.7874 0.4064)
			(stroke
				(width 0.1524)
				(type default)
			)
			(layer "B.SilkS")
		)
		(fp_line
			(start 0.7874 -0.4064)
			(end -0.7874 -0.4064)
			(stroke
				(width 0.1524)
				(type default)
			)
			(layer "B.SilkS")
		)
		(fp_line
			(start 0.7874 0.4064)
			(end 0.7874 -0.4064)
			(stroke
				(width 0.1524)
				(type default)
			)
			(layer "B.SilkS")
		)
		(fp_line
			(start -0.67945 -0.3048)
			(end -0.67945 0.3048)
			(stroke
				(width 0.1)
				(type default)
			)
			(layer "B.Fab")
		)
		(fp_line
			(start -0.67945 0.3048)
			(end -0.120396 0.3048)
			(stroke
				(width 0.1)
				(type default)
			)
			(layer "B.Fab")
		)
		(fp_line
			(start -0.12065 -0.3048)
			(end -0.67945 -0.3048)
			(stroke
				(width 0.1)
				(type default)
			)
			(layer "B.Fab")
		)
		(fp_line
			(start -0.12065 -0.2794)
			(end -0.12065 -0.3048)
			(stroke
				(width 0.1)
				(type default)
			)
			(layer "B.Fab")
		)
		(fp_line
			(start -0.120396 0.2794)
			(end 0.12065 0.2794)
			(stroke
				(width 0.1)
				(type default)
			)
			(layer "B.Fab")
		)
		(fp_line
			(start -0.120396 0.3048)
			(end -0.120396 0.2794)
			(stroke
				(width 0.1)
				(type default)
			)
			(layer "B.Fab")
		)
		(fp_line
			(start 0.12065 -0.305054)
			(end 0.12065 -0.2794)
			(stroke
				(width 0.1)
				(type default)
			)
			(layer "B.Fab")
		)
		(fp_line
			(start 0.12065 -0.2794)
			(end -0.12065 -0.2794)
			(stroke
				(width 0.1)
				(type default)
			)
			(layer "B.Fab")
		)
		(fp_line
			(start 0.12065 0.2794)
			(end 0.12065 0.3048)
			(stroke
				(width 0.1)
				(type default)
			)
			(layer "B.Fab")
		)
		(fp_line
			(start 0.12065 0.3048)
			(end 0.67945 0.3048)
			(stroke
				(width 0.1)
				(type default)
			)
			(layer "B.Fab")
		)
		(fp_line
			(start 0.67945 -0.305054)
			(end 0.12065 -0.305054)
			(stroke
				(width 0.1)
				(type default)
			)
			(layer "B.Fab")
		)
		(fp_line
			(start 0.67945 0.3048)
			(end 0.67945 -0.305054)
			(stroke
				(width 0.1)
				(type default)
			)
			(layer "B.Fab")
		)
		(pad "1" smd circle
			(at 0.40005 0 180)
			(size 0 0)
			(layers "B.Cu" "B.Mask" "B.Paste")
			(net "SMB_1_PLD_3V3AUX_SDA")
		)
		(pad "2" smd circle
			(at -0.40005 0 180)
			(size 0 0)
			(layers "B.Cu" "B.Mask" "B.Paste")
			(net "SMB_2_PLD_3V3AUX_SDA_R1")
		)
	)
	(footprint ""
		(layer "B.Cu")
		(at 61.553344 -408.517344 90)
		(property "Reference" "C6670"
			(at 0 0 90)
			(layer "B.SilkS")
			(hide yes)
			(effects
				(font
					(size 1.27 1.27)
				)
				(justify mirror)
			)
		)
		(property "Value" ""
			(at 0 0 90)
			(layer "B.Fab")
			(effects
				(font
					(size 1.27 1.27)
				)
				(justify mirror)
			)
		)
		(duplicate_pad_numbers_are_jumpers no)
		(fp_line
			(start 0.299974 -0.150114)
			(end -0.299974 -0.150114)
			(stroke
				(width 0.1)
				(type default)
			)
			(layer "B.Fab")
		)
		(fp_line
			(start -0.299974 -0.150114)
			(end -0.299974 0.150114)
			(stroke
				(width 0.1)
				(type default)
			)
			(layer "B.Fab")
		)
		(fp_line
			(start 0.299974 0.150114)
			(end 0.299974 -0.150114)
			(stroke
				(width 0.1)
				(type default)
			)
			(layer "B.Fab")
		)
		(fp_line
			(start -0.299974 0.150114)
			(end 0.299974 0.150114)
			(stroke
				(width 0.1)
				(type default)
			)
			(layer "B.Fab")
		)
		(pad "1" smd rect
			(at 0.2667 0 270)
			(size 0.3048 0.381)
			(layers "B.Cu" "B.Mask" "B.Paste")
			(net "P5E_CPU1_P1_TX_BUF_C_DN<4>")
		)
		(pad "2" smd rect
			(at -0.2667 0 270)
			(size 0.3048 0.381)
			(layers "B.Cu" "B.Mask" "B.Paste")
			(net "P5E_CPU1_P1_TX_BUF_DN<4>")
		)
	)
	(footprint ""
		(layer "B.Cu")
		(at 74.5236 -383.7432 180)
		(property "Reference" "R755"
			(at 0 0 0)
			(layer "B.SilkS")
			(hide yes)
			(effects
				(font
					(size 1.27 1.27)
				)
				(justify mirror)
			)
		)
		(property "Value" ""
			(at 0 0 0)
			(layer "B.Fab")
			(effects
				(font
					(size 1.27 1.27)
				)
				(justify mirror)
			)
		)
		(duplicate_pad_numbers_are_jumpers no)
		(fp_line
			(start 0.32512 0.175006)
			(end 0.32512 -0.175006)
			(stroke
				(width 0.1)
				(type default)
			)
			(layer "B.Fab")
		)
		(fp_line
			(start 0.32512 -0.175006)
			(end -0.32512 -0.175006)
			(stroke
				(width 0.1)
				(type default)
			)
			(layer "B.Fab")
		)
		(fp_line
			(start -0.32512 0.175006)
			(end 0.32512 0.175006)
			(stroke
				(width 0.1)
				(type default)
			)
			(layer "B.Fab")
		)
		(fp_line
			(start -0.32512 -0.175006)
			(end -0.32512 0.175006)
			(stroke
				(width 0.1)
				(type default)
			)
			(layer "B.Fab")
		)
		(pad "1" smd rect
			(at 0.2667 0)
			(size 0.3048 0.381)
			(layers "B.Cu" "B.Mask" "B.Paste")
			(net "P1V8_CPU1_RT_1D")
		)
		(pad "2" smd rect
			(at -0.2667 0 180)
			(size 0.3048 0.381)
			(layers "B.Cu" "B.Mask" "B.Paste")
			(net "RT_CPU1_P1_SCAN_MODE")
		)
	)
	(footprint ""
		(layer "B.Cu")
		(at 181.872382 -20.378166 90)
		(property "Reference" "R2419"
			(at 0 0 90)
			(layer "B.SilkS")
			(hide yes)
			(effects
				(font
					(size 1.27 1.27)
				)
				(justify mirror)
			)
		)
		(property "Value" ""
			(at 0 0 90)
			(layer "B.Fab")
			(effects
				(font
					(size 1.27 1.27)
				)
				(justify mirror)
			)
		)
		(duplicate_pad_numbers_are_jumpers no)
		(fp_line
			(start 0.7874 -0.4064)
			(end -0.7874 -0.4064)
			(stroke
				(width 0.1524)
				(type default)
			)
			(layer "B.SilkS")
		)
		(fp_line
			(start -0.7874 -0.4064)
			(end -0.7874 0.4064)
			(stroke
				(width 0.1524)
				(type default)
			)
			(layer "B.SilkS")
		)
		(fp_line
			(start 0.7874 0.4064)
			(end 0.7874 -0.4064)
			(stroke
				(width 0.1524)
				(type default)
			)
			(layer "B.SilkS")
		)
		(fp_line
			(start -0.7874 0.4064)
			(end 0.7874 0.4064)
			(stroke
				(width 0.1524)
				(type default)
			)
			(layer "B.SilkS")
		)
		(fp_line
			(start 0.67945 -0.305054)
			(end 0.12065 -0.305054)
			(stroke
				(width 0.1)
				(type default)
			)
			(layer "B.Fab")
		)
		(fp_line
			(start 0.12065 -0.305054)
			(end 0.12065 -0.2794)
			(stroke
				(width 0.1)
				(type default)
			)
			(layer "B.Fab")
		)
		(fp_line
			(start -0.12065 -0.3048)
			(end -0.67945 -0.3048)
			(stroke
				(width 0.1)
				(type default)
			)
			(layer "B.Fab")
		)
		(fp_line
			(start -0.67945 -0.3048)
			(end -0.67945 0.3048)
			(stroke
				(width 0.1)
				(type default)
			)
			(layer "B.Fab")
		)
		(fp_line
			(start 0.12065 -0.2794)
			(end -0.12065 -0.2794)
			(stroke
				(width 0.1)
				(type default)
			)
			(layer "B.Fab")
		)
		(fp_line
			(start -0.12065 -0.2794)
			(end -0.12065 -0.3048)
			(stroke
				(width 0.1)
				(type default)
			)
			(layer "B.Fab")
		)
		(fp_line
			(start 0.12065 0.2794)
			(end 0.12065 0.3048)
			(stroke
				(width 0.1)
				(type default)
			)
			(layer "B.Fab")
		)
		(fp_line
			(start -0.120396 0.2794)
			(end 0.12065 0.2794)
			(stroke
				(width 0.1)
				(type default)
			)
			(layer "B.Fab")
		)
		(fp_line
			(start 0.67945 0.3048)
			(end 0.67945 -0.305054)
			(stroke
				(width 0.1)
				(type default)
			)
			(layer "B.Fab")
		)
		(fp_line
			(start 0.12065 0.3048)
			(end 0.67945 0.3048)
			(stroke
				(width 0.1)
				(type default)
			)
			(layer "B.Fab")
		)
		(fp_line
			(start -0.120396 0.3048)
			(end -0.120396 0.2794)
			(stroke
				(width 0.1)
				(type default)
			)
			(layer "B.Fab")
		)
		(fp_line
			(start -0.67945 0.3048)
			(end -0.120396 0.3048)
			(stroke
				(width 0.1)
				(type default)
			)
			(layer "B.Fab")
		)
		(pad "1" smd circle
			(at 0.40005 0 270)
			(size 0 0)
			(layers "B.Cu" "B.Mask" "B.Paste")
			(net "SMB_CPU0_CPU1_APML_SCL")
		)
		(pad "2" smd circle
			(at -0.40005 0 270)
			(size 0 0)
			(layers "B.Cu" "B.Mask" "B.Paste")
			(net "SMB_CPU0_CPU1_APML_SCL_R")
		)
	)
	(footprint ""
		(layer "B.Cu")
		(at 158.90113 -13.127228 180)
		(property "Reference" "R3113"
			(at 0 0 0)
			(layer "B.SilkS")
			(hide yes)
			(effects
				(font
					(size 1.27 1.27)
				)
				(justify mirror)
			)
		)
		(property "Value" ""
			(at 0 0 0)
			(layer "B.Fab")
			(effects
				(font
					(size 1.27 1.27)
				)
				(justify mirror)
			)
		)
		(duplicate_pad_numbers_are_jumpers no)
		(fp_line
			(start 0.7874 0.4064)
			(end 0.7874 -0.4064)
			(stroke
				(width 0.1524)
				(type default)
			)
			(layer "B.SilkS")
		)
		(fp_line
			(start 0.7874 -0.4064)
			(end -0.7874 -0.4064)
			(stroke
				(width 0.1524)
				(type default)
			)
			(layer "B.SilkS")
		)
		(fp_line
			(start -0.7874 0.4064)
			(end 0.7874 0.4064)
			(stroke
				(width 0.1524)
				(type default)
			)
			(layer "B.SilkS")
		)
		(fp_line
			(start -0.7874 -0.4064)
			(end -0.7874 0.4064)
			(stroke
				(width 0.1524)
				(type default)
			)
			(layer "B.SilkS")
		)
		(fp_line
			(start 0.67945 0.3048)
			(end 0.67945 -0.305054)
			(stroke
				(width 0.1)
				(type default)
			)
			(layer "B.Fab")
		)
		(fp_line
			(start 0.67945 -0.305054)
			(end 0.12065 -0.305054)
			(stroke
				(width 0.1)
				(type default)
			)
			(layer "B.Fab")
		)
		(fp_line
			(start 0.12065 0.3048)
			(end 0.67945 0.3048)
			(stroke
				(width 0.1)
				(type default)
			)
			(layer "B.Fab")
		)
		(fp_line
			(start 0.12065 0.2794)
			(end 0.12065 0.3048)
			(stroke
				(width 0.1)
				(type default)
			)
			(layer "B.Fab")
		)
		(fp_line
			(start 0.12065 -0.2794)
			(end -0.12065 -0.2794)
			(stroke
				(width 0.1)
				(type default)
			)
			(layer "B.Fab")
		)
		(fp_line
			(start 0.12065 -0.305054)
			(end 0.12065 -0.2794)
			(stroke
				(width 0.1)
				(type default)
			)
			(layer "B.Fab")
		)
		(fp_line
			(start -0.120396 0.3048)
			(end -0.120396 0.2794)
			(stroke
				(width 0.1)
				(type default)
			)
			(layer "B.Fab")
		)
		(fp_line
			(start -0.120396 0.2794)
			(end 0.12065 0.2794)
			(stroke
				(width 0.1)
				(type default)
			)
			(layer "B.Fab")
		)
		(fp_line
			(start -0.12065 -0.2794)
			(end -0.12065 -0.3048)
			(stroke
				(width 0.1)
				(type default)
			)
			(layer "B.Fab")
		)
		(fp_line
			(start -0.12065 -0.3048)
			(end -0.67945 -0.3048)
			(stroke
				(width 0.1)
				(type default)
			)
			(layer "B.Fab")
		)
		(fp_line
			(start -0.67945 0.3048)
			(end -0.120396 0.3048)
			(stroke
				(width 0.1)
				(type default)
			)
			(layer "B.Fab")
		)
		(fp_line
			(start -0.67945 -0.3048)
			(end -0.67945 0.3048)
			(stroke
				(width 0.1)
				(type default)
			)
			(layer "B.Fab")
		)
		(pad "1" smd circle
			(at 0.40005 0)
			(size 0 0)
			(layers "B.Cu" "B.Mask" "B.Paste")
			(net "SMB_FAN_3V3AUX_SCL")
		)
		(pad "2" smd circle
			(at -0.40005 0)
			(size 0 0)
			(layers "B.Cu" "B.Mask" "B.Paste")
			(net "SMB_FAN_3V3AUX_R_SCL")
		)
	)
	(footprint ""
		(layer "B.Cu")
		(at 99.128834 -254.067564 180)
		(property "Reference" "C2672"
			(at 0 0 0)
			(layer "B.SilkS")
			(hide yes)
			(effects
				(font
					(size 1.27 1.27)
				)
				(justify mirror)
			)
		)
		(property "Value" ""
			(at 0 0 0)
			(layer "B.Fab")
			(effects
				(font
					(size 1.27 1.27)
				)
				(justify mirror)
			)
		)
		(duplicate_pad_numbers_are_jumpers no)
		(fp_line
			(start 0.7874 0.4064)
			(end 0.7874 -0.4064)
			(stroke
				(width 0.1524)
				(type default)
			)
			(layer "B.SilkS")
		)
		(fp_line
			(start 0.7874 -0.4064)
			(end -0.7874 -0.4064)
			(stroke
				(width 0.1524)
				(type default)
			)
			(layer "B.SilkS")
		)
		(fp_line
			(start -0.7874 0.4064)
			(end 0.7874 0.4064)
			(stroke
				(width 0.1524)
				(type default)
			)
			(layer "B.SilkS")
		)
		(fp_line
			(start -0.7874 -0.4064)
			(end -0.7874 0.4064)
			(stroke
				(width 0.1524)
				(type default)
			)
			(layer "B.SilkS")
		)
		(fp_line
			(start 0.67945 0.3048)
			(end 0.67945 -0.305054)
			(stroke
				(width 0.1)
				(type default)
			)
			(layer "B.Fab")
		)
		(fp_line
			(start 0.67945 -0.305054)
			(end 0.12065 -0.305054)
			(stroke
				(width 0.1)
				(type default)
			)
			(layer "B.Fab")
		)
		(fp_line
			(start 0.12065 0.3048)
			(end 0.67945 0.3048)
			(stroke
				(width 0.1)
				(type default)
			)
			(layer "B.Fab")
		)
		(fp_line
			(start 0.12065 0.2794)
			(end 0.12065 0.3048)
			(stroke
				(width 0.1)
				(type default)
			)
			(layer "B.Fab")
		)
		(fp_line
			(start 0.12065 -0.2794)
			(end -0.12065 -0.2794)
			(stroke
				(width 0.1)
				(type default)
			)
			(layer "B.Fab")
		)
		(fp_line
			(start 0.12065 -0.305054)
			(end 0.12065 -0.2794)
			(stroke
				(width 0.1)
				(type default)
			)
			(layer "B.Fab")
		)
		(fp_line
			(start -0.120396 0.3048)
			(end -0.120396 0.2794)
			(stroke
				(width 0.1)
				(type default)
			)
			(layer "B.Fab")
		)
		(fp_line
			(start -0.120396 0.2794)
			(end 0.12065 0.2794)
			(stroke
				(width 0.1)
				(type default)
			)
			(layer "B.Fab")
		)
		(fp_line
			(start -0.12065 -0.2794)
			(end -0.12065 -0.3048)
			(stroke
				(width 0.1)
				(type default)
			)
			(layer "B.Fab")
		)
		(fp_line
			(start -0.12065 -0.3048)
			(end -0.67945 -0.3048)
			(stroke
				(width 0.1)
				(type default)
			)
			(layer "B.Fab")
		)
		(fp_line
			(start -0.67945 0.3048)
			(end -0.120396 0.3048)
			(stroke
				(width 0.1)
				(type default)
			)
			(layer "B.Fab")
		)
		(fp_line
			(start -0.67945 -0.3048)
			(end -0.67945 0.3048)
			(stroke
				(width 0.1)
				(type default)
			)
			(layer "B.Fab")
		)
		(pad "1" smd circle
			(at 0.40005 0)
			(size 0 0)
			(layers "B.Cu" "B.Mask" "B.Paste")
			(net "PVDD18_S5_P1")
		)
		(pad "2" smd circle
			(at -0.40005 0)
			(size 0 0)
			(layers "B.Cu" "B.Mask" "B.Paste")
			(net "GND")
		)
	)
	(footprint ""
		(layer "B.Cu")
		(at 140.989558 -393.242546 180)
		(property "Reference" "R859"
			(at 0 0 0)
			(layer "B.SilkS")
			(hide yes)
			(effects
				(font
					(size 1.27 1.27)
				)
				(justify mirror)
			)
		)
		(property "Value" ""
			(at 0 0 0)
			(layer "B.Fab")
			(effects
				(font
					(size 1.27 1.27)
				)
				(justify mirror)
			)
		)
		(duplicate_pad_numbers_are_jumpers no)
		(fp_line
			(start 1.2954 0.5842)
			(end 1.2954 -0.5842)
			(stroke
				(width 0.1524)
				(type default)
			)
			(layer "B.SilkS")
		)
		(fp_line
			(start 1.2954 -0.5842)
			(end -1.2954 -0.5842)
			(stroke
				(width 0.1524)
				(type default)
			)
			(layer "B.SilkS")
		)
		(fp_line
			(start -1.2954 0.5842)
			(end 1.2954 0.5842)
			(stroke
				(width 0.1524)
				(type default)
			)
			(layer "B.SilkS")
		)
		(fp_line
			(start -1.2954 -0.5842)
			(end -1.2954 0.5842)
			(stroke
				(width 0.1524)
				(type default)
			)
			(layer "B.SilkS")
		)
		(fp_line
			(start 1.1938 0.4064)
			(end 1.1938 -0.406654)
			(stroke
				(width 0.1)
				(type default)
			)
			(layer "B.Fab")
		)
		(fp_line
			(start 1.1938 -0.406654)
			(end 0.8636 -0.406654)
			(stroke
				(width 0.1)
				(type default)
			)
			(layer "B.Fab")
		)
		(fp_line
			(start 0.8636 0.4572)
			(end 0.8636 0.4318)
			(stroke
				(width 0.1)
				(type default)
			)
			(layer "B.Fab")
		)
		(fp_line
			(start 0.8636 0.4318)
			(end 0.8636 0.4064)
			(stroke
				(width 0.1)
				(type default)
			)
			(layer "B.Fab")
		)
		(fp_line
			(start 0.8636 0.4064)
			(end 1.1938 0.4064)
			(stroke
				(width 0.1)
				(type default)
			)
			(layer "B.Fab")
		)
		(fp_line
			(start 0.8636 -0.406654)
			(end 0.8636 -0.4572)
			(stroke
				(width 0.1)
				(type default)
			)
			(layer "B.Fab")
		)
		(fp_line
			(start 0.8636 -0.4572)
			(end -0.8636 -0.4572)
			(stroke
				(width 0.1)
				(type default)
			)
			(layer "B.Fab")
		)
		(fp_line
			(start -0.8636 0.4572)
			(end 0.8636 0.4572)
			(stroke
				(width 0.1)
				(type default)
			)
			(layer "B.Fab")
		)
		(fp_line
			(start -0.8636 0.4064)
			(end -0.8636 0.4572)
			(stroke
				(width 0.1)
				(type default)
			)
			(layer "B.Fab")
		)
		(fp_line
			(start -0.8636 -0.406654)
			(end -1.1938 -0.406654)
			(stroke
				(width 0.1)
				(type default)
			)
			(layer "B.Fab")
		)
		(fp_line
			(start -0.8636 -0.4572)
			(end -0.8636 -0.406654)
			(stroke
				(width 0.1)
				(type default)
			)
			(layer "B.Fab")
		)
		(fp_line
			(start -1.1938 0.4064)
			(end -0.8636 0.4064)
			(stroke
				(width 0.1)
				(type default)
			)
			(layer "B.Fab")
		)
		(fp_line
			(start -1.1938 -0.406654)
			(end -1.1938 0.4064)
			(stroke
				(width 0.1)
				(type default)
			)
			(layer "B.Fab")
		)
		(pad "1" smd rect
			(at 0.7366 0 90)
			(size 0.7112 0.8128)
			(layers "B.Cu" "B.Mask" "B.Paste")
			(net "P0V9_CPU1_RT2_2A_2D")
		)
		(pad "2" smd rect
			(at -0.7366 0 90)
			(size 0.7112 0.8128)
			(layers "B.Cu" "B.Mask" "B.Paste")
			(net "P0V9_CPU1_RT2_2A")
		)
	)
	(footprint ""
		(layer "B.Cu")
		(at 75.51801 -148.451316 -90)
		(property "Reference" "PR397"
			(at 0 0 90)
			(layer "B.SilkS")
			(hide yes)
			(effects
				(font
					(size 1.27 1.27)
				)
				(justify mirror)
			)
		)
		(property "Value" ""
			(at 0 0 90)
			(layer "B.Fab")
			(effects
				(font
					(size 1.27 1.27)
				)
				(justify mirror)
			)
		)
		(duplicate_pad_numbers_are_jumpers no)
		(fp_line
			(start -0.7874 0.4064)
			(end 0.7874 0.4064)
			(stroke
				(width 0.1524)
				(type default)
			)
			(layer "B.SilkS")
		)
		(fp_line
			(start 0.7874 0.4064)
			(end 0.7874 -0.4064)
			(stroke
				(width 0.1524)
				(type default)
			)
			(layer "B.SilkS")
		)
		(fp_line
			(start -0.7874 -0.4064)
			(end -0.7874 0.4064)
			(stroke
				(width 0.1524)
				(type default)
			)
			(layer "B.SilkS")
		)
		(fp_line
			(start 0.7874 -0.4064)
			(end -0.7874 -0.4064)
			(stroke
				(width 0.1524)
				(type default)
			)
			(layer "B.SilkS")
		)
		(fp_line
			(start -0.67945 0.3048)
			(end -0.120396 0.3048)
			(stroke
				(width 0.1)
				(type default)
			)
			(layer "B.Fab")
		)
		(fp_line
			(start -0.120396 0.3048)
			(end -0.120396 0.2794)
			(stroke
				(width 0.1)
				(type default)
			)
			(layer "B.Fab")
		)
		(fp_line
			(start 0.12065 0.3048)
			(end 0.67945 0.3048)
			(stroke
				(width 0.1)
				(type default)
			)
			(layer "B.Fab")
		)
		(fp_line
			(start 0.67945 0.3048)
			(end 0.67945 -0.305054)
			(stroke
				(width 0.1)
				(type default)
			)
			(layer "B.Fab")
		)
		(fp_line
			(start -0.120396 0.2794)
			(end 0.12065 0.2794)
			(stroke
				(width 0.1)
				(type default)
			)
			(layer "B.Fab")
		)
		(fp_line
			(start 0.12065 0.2794)
			(end 0.12065 0.3048)
			(stroke
				(width 0.1)
				(type default)
			)
			(layer "B.Fab")
		)
		(fp_line
			(start -0.12065 -0.2794)
			(end -0.12065 -0.3048)
			(stroke
				(width 0.1)
				(type default)
			)
			(layer "B.Fab")
		)
		(fp_line
			(start 0.12065 -0.2794)
			(end -0.12065 -0.2794)
			(stroke
				(width 0.1)
				(type default)
			)
			(layer "B.Fab")
		)
		(fp_line
			(start -0.67945 -0.3048)
			(end -0.67945 0.3048)
			(stroke
				(width 0.1)
				(type default)
			)
			(layer "B.Fab")
		)
		(fp_line
			(start -0.12065 -0.3048)
			(end -0.67945 -0.3048)
			(stroke
				(width 0.1)
				(type default)
			)
			(layer "B.Fab")
		)
		(fp_line
			(start 0.12065 -0.305054)
			(end 0.12065 -0.2794)
			(stroke
				(width 0.1)
				(type default)
			)
			(layer "B.Fab")
		)
		(fp_line
			(start 0.67945 -0.305054)
			(end 0.12065 -0.305054)
			(stroke
				(width 0.1)
				(type default)
			)
			(layer "B.Fab")
		)
		(pad "1" smd circle
			(at 0.40005 0 90)
			(size 0 0)
			(layers "B.Cu" "B.Mask" "B.Paste")
			(net "P3V3_AUX")
		)
		(pad "2" smd circle
			(at -0.40005 0 90)
			(size 0 0)
			(layers "B.Cu" "B.Mask" "B.Paste")
			(net "PVDD18_S5_P1_VCC")
		)
	)
	(footprint ""
		(layer "B.Cu")
		(at 141.623542 -383.7432 180)
		(property "Reference" "R868"
			(at 0 0 0)
			(layer "B.SilkS")
			(hide yes)
			(effects
				(font
					(size 1.27 1.27)
				)
				(justify mirror)
			)
		)
		(property "Value" ""
			(at 0 0 0)
			(layer "B.Fab")
			(effects
				(font
					(size 1.27 1.27)
				)
				(justify mirror)
			)
		)
		(duplicate_pad_numbers_are_jumpers no)
		(fp_line
			(start 0.32512 0.175006)
			(end 0.32512 -0.175006)
			(stroke
				(width 0.1)
				(type default)
			)
			(layer "B.Fab")
		)
		(fp_line
			(start 0.32512 -0.175006)
			(end -0.32512 -0.175006)
			(stroke
				(width 0.1)
				(type default)
			)
			(layer "B.Fab")
		)
		(fp_line
			(start -0.32512 0.175006)
			(end 0.32512 0.175006)
			(stroke
				(width 0.1)
				(type default)
			)
			(layer "B.Fab")
		)
		(fp_line
			(start -0.32512 -0.175006)
			(end -0.32512 0.175006)
			(stroke
				(width 0.1)
				(type default)
			)
			(layer "B.Fab")
		)
		(pad "1" smd rect
			(at 0.2667 0)
			(size 0.3048 0.381)
			(layers "B.Cu" "B.Mask" "B.Paste")
			(net "P1V8_CPU1_RT_1D")
		)
		(pad "2" smd rect
			(at -0.2667 0 180)
			(size 0.3048 0.381)
			(layers "B.Cu" "B.Mask" "B.Paste")
			(net "RT_CPU1_P2_SCAN_MODE")
		)
	)
	(footprint ""
		(layer "B.Cu")
		(at 238.669576 -237.230666 -90)
		(property "Reference" "U6"
			(at 0.09271 2.847594 270)
			(unlocked yes)
			(layer "B.SilkS")
			(effects
				(font
					(size 0.7874 0.5842)
					(thickness 0.1524)
				)
				(justify mirror)
			)
		)
		(property "Value" ""
			(at 0 0 90)
			(layer "B.Fab")
			(effects
				(font
					(size 1.27 1.27)
				)
				(justify mirror)
			)
		)
		(duplicate_pad_numbers_are_jumpers no)
		(fp_line
			(start -1.03378 1.284478)
			(end 1.03378 1.284478)
			(stroke
				(width 0.1524)
				(type default)
			)
			(layer "B.SilkS")
		)
		(fp_line
			(start 1.03378 1.284478)
			(end 1.03378 -1.284478)
			(stroke
				(width 0.1524)
				(type default)
			)
			(layer "B.SilkS")
		)
		(fp_line
			(start -1.03378 -1.284478)
			(end -1.03378 1.284478)
			(stroke
				(width 0.1524)
				(type default)
			)
			(layer "B.SilkS")
		)
		(fp_line
			(start 1.03378 -1.284478)
			(end -1.03378 -1.284478)
			(stroke
				(width 0.1524)
				(type default)
			)
			(layer "B.SilkS")
		)
		(fp_poly
			(pts
				(xy 1.485646 -1.824482) (xy 1.20015 -1.211326) (xy 1.86182 -1.350772)
			)
			(stroke
				(width 0)
				(type default)
			)
			(fill yes)
			(layer "B.SilkS")
		)
		(fp_line
			(start -0.774954 1.02489)
			(end 0.774954 1.02489)
			(stroke
				(width 0.1)
				(type default)
			)
			(layer "B.Fab")
		)
		(fp_line
			(start 0.774954 1.02489)
			(end 0.774954 -1.02489)
			(stroke
				(width 0.1)
				(type default)
			)
			(layer "B.Fab")
		)
		(fp_line
			(start -0.774954 -1.02489)
			(end -0.774954 1.02489)
			(stroke
				(width 0.1)
				(type default)
			)
			(layer "B.Fab")
		)
		(fp_line
			(start 0.774954 -1.02489)
			(end -0.774954 -1.02489)
			(stroke
				(width 0.1)
				(type default)
			)
			(layer "B.Fab")
		)
		(fp_poly
			(pts
				(xy 1.201674 -0.750062) (xy 1.806702 -0.447548) (xy 1.806702 -1.052576)
			)
			(stroke
				(width 0)
				(type default)
			)
			(fill yes)
			(layer "B.Fab")
		)
		(pad "1" smd rect
			(at 0.64008 -0.750062)
			(size 0.3048 0.5334)
			(layers "B.Cu" "B.Mask" "B.Paste")
			(net "SMB_CPU0_SEC_R_SCL")
		)
		(pad "2" smd rect
			(at 0.64008 -0.249936)
			(size 0.254 0.5334)
			(layers "B.Cu" "B.Mask" "B.Paste")
			(net "SMB_CPU0_SEC_R_SDA")
		)
		(pad "3" smd rect
			(at 0.64008 0.249936)
			(size 0.254 0.5334)
			(layers "B.Cu" "B.Mask" "B.Paste")
			(net "SMB_CPU1_SEC_R_SCL")
		)
		(pad "4" smd rect
			(at 0.64008 0.750062)
			(size 0.3048 0.5334)
			(layers "B.Cu" "B.Mask" "B.Paste")
			(net "SMB_CPU1_SEC_R_SDA")
		)
		(pad "5" smd rect
			(at 0 0.839978 90)
			(size 0.3302 0.635)
			(layers "B.Cu" "B.Mask" "B.Paste")
			(net "GND")
		)
		(pad "6" smd rect
			(at -0.64008 0.750062)
			(size 0.3048 0.5334)
			(layers "B.Cu" "B.Mask" "B.Paste")
			(net "FM_SEC_MUX_OE_N")
		)
		(pad "7" smd rect
			(at -0.64008 0.249936)
			(size 0.254 0.5334)
			(layers "B.Cu" "B.Mask" "B.Paste")
			(net "SMB_CPU0_CPU1_SEC_SDA_R2")
		)
		(pad "8" smd rect
			(at -0.64008 -0.249936)
			(size 0.254 0.5334)
			(layers "B.Cu" "B.Mask" "B.Paste")
			(net "SMB_CPU0_CPU1_SEC_SCL_R2")
		)
		(pad "9" smd rect
			(at -0.64008 -0.750062)
			(size 0.3048 0.5334)
			(layers "B.Cu" "B.Mask" "B.Paste")
			(net "FM_SEC_MUX_SEL")
		)
		(pad "10" smd rect
			(at 0 -0.839978 90)
			(size 0.3302 0.635)
			(layers "B.Cu" "B.Mask" "B.Paste")
			(net "P3V3_AUX")
		)
	)
	(footprint ""
		(layer "B.Cu")
		(at 187.111894 -112.263174 180)
		(property "Reference" "C1175"
			(at 0 0 0)
			(layer "B.SilkS")
			(hide yes)
			(effects
				(font
					(size 1.27 1.27)
				)
				(justify mirror)
			)
		)
		(property "Value" ""
			(at 0 0 0)
			(layer "B.Fab")
			(effects
				(font
					(size 1.27 1.27)
				)
				(justify mirror)
			)
		)
		(duplicate_pad_numbers_are_jumpers no)
		(fp_line
			(start 0.69215 0.2921)
			(end 0.69215 -0.2921)
			(stroke
				(width 0.1524)
				(type default)
			)
			(layer "B.SilkS")
		)
		(fp_line
			(start 0.69215 -0.2921)
			(end -0.69215 -0.2921)
			(stroke
				(width 0.1524)
				(type default)
			)
			(layer "B.SilkS")
		)
		(fp_line
			(start -0.69215 0.2921)
			(end 0.69215 0.2921)
			(stroke
				(width 0.1524)
				(type default)
			)
			(layer "B.SilkS")
		)
		(fp_line
			(start -0.69215 -0.2921)
			(end -0.69215 0.2921)
			(stroke
				(width 0.1524)
				(type default)
			)
			(layer "B.SilkS")
		)
		(fp_line
			(start 0.51435 0.2794)
			(end 0.51435 -0.2794)
			(stroke
				(width 0.1)
				(type default)
			)
			(layer "B.Fab")
		)
		(fp_line
			(start 0.51435 -0.2794)
			(end -0.51435 -0.2794)
			(stroke
				(width 0.1)
				(type default)
			)
			(layer "B.Fab")
		)
		(fp_line
			(start -0.51435 0.2794)
			(end 0.51435 0.2794)
			(stroke
				(width 0.1)
				(type default)
			)
			(layer "B.Fab")
		)
		(fp_line
			(start -0.51435 -0.2794)
			(end -0.51435 0.2794)
			(stroke
				(width 0.1)
				(type default)
			)
			(layer "B.Fab")
		)
		(pad "1" smd circle
			(at 0.40005 0)
			(size 0 0)
			(layers "B.Cu" "B.Mask" "B.Paste")
			(net "P3V3_AUX")
		)
		(pad "2" smd circle
			(at -0.40005 0)
			(size 0 0)
			(layers "B.Cu" "B.Mask" "B.Paste")
			(net "GND")
		)
		(zone
			(layer "B.Cu")
			(hatch none 0.5)
			(connect_pads
				(clearance 0)
			)
			(min_thickness 0.25)
			(keepout
				(tracks not_allowed)
				(vias allowed)
				(pads allowed)
				(copperpour not_allowed)
				(footprints allowed)
			)
			(placement
				(enabled no)
				(sheetname "")
			)
			(fill
				(thermal_gap 0.5)
				(thermal_bridge_width 0.5)
				(island_removal_mode 0)
			)
			(polygon
				(pts
					(xy 186.921394 -112.17529) (xy 186.921394 -112.350804) (xy 187.012834 -112.40897) (xy 187.212224 -112.40897)
					(xy 187.302394 -112.350804) (xy 187.302394 -112.175544) (xy 187.212224 -112.117124) (xy 187.012834 -112.117124)
				)
			)
		)
	)
	(footprint ""
		(layer "B.Cu")
		(at 104.555544 -412.832296 90)
		(property "Reference" "R4546"
			(at 0 0 90)
			(layer "B.SilkS")
			(hide yes)
			(effects
				(font
					(size 1.27 1.27)
				)
				(justify mirror)
			)
		)
		(property "Value" ""
			(at 0 0 90)
			(layer "B.Fab")
			(effects
				(font
					(size 1.27 1.27)
				)
				(justify mirror)
			)
		)
		(duplicate_pad_numbers_are_jumpers no)
		(fp_line
			(start 0.7874 -0.4064)
			(end -0.7874 -0.4064)
			(stroke
				(width 0.1524)
				(type default)
			)
			(layer "B.SilkS")
		)
		(fp_line
			(start -0.7874 -0.4064)
			(end -0.7874 0.4064)
			(stroke
				(width 0.1524)
				(type default)
			)
			(layer "B.SilkS")
		)
		(fp_line
			(start 0.7874 0.4064)
			(end 0.7874 -0.4064)
			(stroke
				(width 0.1524)
				(type default)
			)
			(layer "B.SilkS")
		)
		(fp_line
			(start -0.7874 0.4064)
			(end 0.7874 0.4064)
			(stroke
				(width 0.1524)
				(type default)
			)
			(layer "B.SilkS")
		)
		(fp_line
			(start 0.67945 -0.305054)
			(end 0.12065 -0.305054)
			(stroke
				(width 0.1)
				(type default)
			)
			(layer "B.Fab")
		)
		(fp_line
			(start 0.12065 -0.305054)
			(end 0.12065 -0.2794)
			(stroke
				(width 0.1)
				(type default)
			)
			(layer "B.Fab")
		)
		(fp_line
			(start -0.12065 -0.3048)
			(end -0.67945 -0.3048)
			(stroke
				(width 0.1)
				(type default)
			)
			(layer "B.Fab")
		)
		(fp_line
			(start -0.67945 -0.3048)
			(end -0.67945 0.3048)
			(stroke
				(width 0.1)
				(type default)
			)
			(layer "B.Fab")
		)
		(fp_line
			(start 0.12065 -0.2794)
			(end -0.12065 -0.2794)
			(stroke
				(width 0.1)
				(type default)
			)
			(layer "B.Fab")
		)
		(fp_line
			(start -0.12065 -0.2794)
			(end -0.12065 -0.3048)
			(stroke
				(width 0.1)
				(type default)
			)
			(layer "B.Fab")
		)
		(fp_line
			(start 0.12065 0.2794)
			(end 0.12065 0.3048)
			(stroke
				(width 0.1)
				(type default)
			)
			(layer "B.Fab")
		)
		(fp_line
			(start -0.120396 0.2794)
			(end 0.12065 0.2794)
			(stroke
				(width 0.1)
				(type default)
			)
			(layer "B.Fab")
		)
		(fp_line
			(start 0.67945 0.3048)
			(end 0.67945 -0.305054)
			(stroke
				(width 0.1)
				(type default)
			)
			(layer "B.Fab")
		)
		(fp_line
			(start 0.12065 0.3048)
			(end 0.67945 0.3048)
			(stroke
				(width 0.1)
				(type default)
			)
			(layer "B.Fab")
		)
		(fp_line
			(start -0.120396 0.3048)
			(end -0.120396 0.2794)
			(stroke
				(width 0.1)
				(type default)
			)
			(layer "B.Fab")
		)
		(fp_line
			(start -0.67945 0.3048)
			(end -0.120396 0.3048)
			(stroke
				(width 0.1)
				(type default)
			)
			(layer "B.Fab")
		)
		(pad "1" smd circle
			(at 0.40005 0 270)
			(size 0 0)
			(layers "B.Cu" "B.Mask" "B.Paste")
			(net "P3V3_AUX")
		)
		(pad "2" smd circle
			(at -0.40005 0 270)
			(size 0 0)
			(layers "B.Cu" "B.Mask" "B.Paste")
			(net "HGX_DETECT_N_ISO")
		)
	)
	(footprint ""
		(layer "B.Cu")
		(at 119.801386 -250.892564)
		(property "Reference" "C2296"
			(at 0 0 0)
			(layer "B.SilkS")
			(hide yes)
			(effects
				(font
					(size 1.27 1.27)
				)
				(justify mirror)
			)
		)
		(property "Value" ""
			(at 0 0 0)
			(layer "B.Fab")
			(effects
				(font
					(size 1.27 1.27)
				)
				(justify mirror)
			)
		)
		(duplicate_pad_numbers_are_jumpers no)
		(fp_line
			(start -0.7874 -0.4064)
			(end -0.7874 0.4064)
			(stroke
				(width 0.1524)
				(type default)
			)
			(layer "B.SilkS")
		)
		(fp_line
			(start -0.7874 0.4064)
			(end 0.7874 0.4064)
			(stroke
				(width 0.1524)
				(type default)
			)
			(layer "B.SilkS")
		)
		(fp_line
			(start 0.7874 -0.4064)
			(end -0.7874 -0.4064)
			(stroke
				(width 0.1524)
				(type default)
			)
			(layer "B.SilkS")
		)
		(fp_line
			(start 0.7874 0.4064)
			(end 0.7874 -0.4064)
			(stroke
				(width 0.1524)
				(type default)
			)
			(layer "B.SilkS")
		)
		(fp_line
			(start -0.67945 -0.3048)
			(end -0.67945 0.3048)
			(stroke
				(width 0.1)
				(type default)
			)
			(layer "B.Fab")
		)
		(fp_line
			(start -0.67945 0.3048)
			(end -0.120396 0.3048)
			(stroke
				(width 0.1)
				(type default)
			)
			(layer "B.Fab")
		)
		(fp_line
			(start -0.12065 -0.3048)
			(end -0.67945 -0.3048)
			(stroke
				(width 0.1)
				(type default)
			)
			(layer "B.Fab")
		)
		(fp_line
			(start -0.12065 -0.2794)
			(end -0.12065 -0.3048)
			(stroke
				(width 0.1)
				(type default)
			)
			(layer "B.Fab")
		)
		(fp_line
			(start -0.120396 0.2794)
			(end 0.12065 0.2794)
			(stroke
				(width 0.1)
				(type default)
			)
			(layer "B.Fab")
		)
		(fp_line
			(start -0.120396 0.3048)
			(end -0.120396 0.2794)
			(stroke
				(width 0.1)
				(type default)
			)
			(layer "B.Fab")
		)
		(fp_line
			(start 0.12065 -0.305054)
			(end 0.12065 -0.2794)
			(stroke
				(width 0.1)
				(type default)
			)
			(layer "B.Fab")
		)
		(fp_line
			(start 0.12065 -0.2794)
			(end -0.12065 -0.2794)
			(stroke
				(width 0.1)
				(type default)
			)
			(layer "B.Fab")
		)
		(fp_line
			(start 0.12065 0.2794)
			(end 0.12065 0.3048)
			(stroke
				(width 0.1)
				(type default)
			)
			(layer "B.Fab")
		)
		(fp_line
			(start 0.12065 0.3048)
			(end 0.67945 0.3048)
			(stroke
				(width 0.1)
				(type default)
			)
			(layer "B.Fab")
		)
		(fp_line
			(start 0.67945 -0.305054)
			(end 0.12065 -0.305054)
			(stroke
				(width 0.1)
				(type default)
			)
			(layer "B.Fab")
		)
		(fp_line
			(start 0.67945 0.3048)
			(end 0.67945 -0.305054)
			(stroke
				(width 0.1)
				(type default)
			)
			(layer "B.Fab")
		)
		(pad "1" smd circle
			(at 0.40005 0 180)
			(size 0 0)
			(layers "B.Cu" "B.Mask" "B.Paste")
			(net "PVDDCR_CPU0_P1")
		)
		(pad "2" smd circle
			(at -0.40005 0 180)
			(size 0 0)
			(layers "B.Cu" "B.Mask" "B.Paste")
			(net "GND")
		)
	)
	(footprint ""
		(layer "B.Cu")
		(at 125.389386 -249.368564)
		(property "Reference" "C2313"
			(at 0 0 0)
			(layer "B.SilkS")
			(hide yes)
			(effects
				(font
					(size 1.27 1.27)
				)
				(justify mirror)
			)
		)
		(property "Value" ""
			(at 0 0 0)
			(layer "B.Fab")
			(effects
				(font
					(size 1.27 1.27)
				)
				(justify mirror)
			)
		)
		(duplicate_pad_numbers_are_jumpers no)
		(fp_line
			(start -0.7874 -0.4064)
			(end -0.7874 0.4064)
			(stroke
				(width 0.1524)
				(type default)
			)
			(layer "B.SilkS")
		)
		(fp_line
			(start -0.7874 0.4064)
			(end 0.7874 0.4064)
			(stroke
				(width 0.1524)
				(type default)
			)
			(layer "B.SilkS")
		)
		(fp_line
			(start 0.7874 -0.4064)
			(end -0.7874 -0.4064)
			(stroke
				(width 0.1524)
				(type default)
			)
			(layer "B.SilkS")
		)
		(fp_line
			(start 0.7874 0.4064)
			(end 0.7874 -0.4064)
			(stroke
				(width 0.1524)
				(type default)
			)
			(layer "B.SilkS")
		)
		(fp_line
			(start -0.67945 -0.3048)
			(end -0.67945 0.3048)
			(stroke
				(width 0.1)
				(type default)
			)
			(layer "B.Fab")
		)
		(fp_line
			(start -0.67945 0.3048)
			(end -0.120396 0.3048)
			(stroke
				(width 0.1)
				(type default)
			)
			(layer "B.Fab")
		)
		(fp_line
			(start -0.12065 -0.3048)
			(end -0.67945 -0.3048)
			(stroke
				(width 0.1)
				(type default)
			)
			(layer "B.Fab")
		)
		(fp_line
			(start -0.12065 -0.2794)
			(end -0.12065 -0.3048)
			(stroke
				(width 0.1)
				(type default)
			)
			(layer "B.Fab")
		)
		(fp_line
			(start -0.120396 0.2794)
			(end 0.12065 0.2794)
			(stroke
				(width 0.1)
				(type default)
			)
			(layer "B.Fab")
		)
		(fp_line
			(start -0.120396 0.3048)
			(end -0.120396 0.2794)
			(stroke
				(width 0.1)
				(type default)
			)
			(layer "B.Fab")
		)
		(fp_line
			(start 0.12065 -0.305054)
			(end 0.12065 -0.2794)
			(stroke
				(width 0.1)
				(type default)
			)
			(layer "B.Fab")
		)
		(fp_line
			(start 0.12065 -0.2794)
			(end -0.12065 -0.2794)
			(stroke
				(width 0.1)
				(type default)
			)
			(layer "B.Fab")
		)
		(fp_line
			(start 0.12065 0.2794)
			(end 0.12065 0.3048)
			(stroke
				(width 0.1)
				(type default)
			)
			(layer "B.Fab")
		)
		(fp_line
			(start 0.12065 0.3048)
			(end 0.67945 0.3048)
			(stroke
				(width 0.1)
				(type default)
			)
			(layer "B.Fab")
		)
		(fp_line
			(start 0.67945 -0.305054)
			(end 0.12065 -0.305054)
			(stroke
				(width 0.1)
				(type default)
			)
			(layer "B.Fab")
		)
		(fp_line
			(start 0.67945 0.3048)
			(end 0.67945 -0.305054)
			(stroke
				(width 0.1)
				(type default)
			)
			(layer "B.Fab")
		)
		(pad "1" smd circle
			(at 0.40005 0 180)
			(size 0 0)
			(layers "B.Cu" "B.Mask" "B.Paste")
			(net "PVDDCR_CPU0_P1")
		)
		(pad "2" smd circle
			(at -0.40005 0 180)
			(size 0 0)
			(layers "B.Cu" "B.Mask" "B.Paste")
			(net "GND")
		)
	)
	(footprint ""
		(layer "B.Cu")
		(at 81.246218 -388.011162 -90)
		(property "Reference" "C322"
			(at 0 0 90)
			(layer "B.SilkS")
			(hide yes)
			(effects
				(font
					(size 1.27 1.27)
				)
				(justify mirror)
			)
		)
		(property "Value" ""
			(at 0 0 90)
			(layer "B.Fab")
			(effects
				(font
					(size 1.27 1.27)
				)
				(justify mirror)
			)
		)
		(duplicate_pad_numbers_are_jumpers no)
		(fp_line
			(start -0.299974 0.150114)
			(end 0.299974 0.150114)
			(stroke
				(width 0.1)
				(type default)
			)
			(layer "B.Fab")
		)
		(fp_line
			(start 0.299974 0.150114)
			(end 0.299974 -0.150114)
			(stroke
				(width 0.1)
				(type default)
			)
			(layer "B.Fab")
		)
		(fp_line
			(start -0.299974 -0.150114)
			(end -0.299974 0.150114)
			(stroke
				(width 0.1)
				(type default)
			)
			(layer "B.Fab")
		)
		(fp_line
			(start 0.299974 -0.150114)
			(end -0.299974 -0.150114)
			(stroke
				(width 0.1)
				(type default)
			)
			(layer "B.Fab")
		)
		(pad "1" smd rect
			(at 0.2667 0 90)
			(size 0.3048 0.381)
			(layers "B.Cu" "B.Mask" "B.Paste")
			(net "P0V9_CPU1_RT1_2A")
		)
		(pad "2" smd rect
			(at -0.2667 0 90)
			(size 0.3048 0.381)
			(layers "B.Cu" "B.Mask" "B.Paste")
			(net "GND")
		)
	)
	(footprint ""
		(layer "B.Cu")
		(at 10.066782 -412.291784)
		(property "Reference" "PR6815"
			(at 0 0 0)
			(layer "B.SilkS")
			(hide yes)
			(effects
				(font
					(size 1.27 1.27)
				)
				(justify mirror)
			)
		)
		(property "Value" ""
			(at 0 0 0)
			(layer "B.Fab")
			(effects
				(font
					(size 1.27 1.27)
				)
				(justify mirror)
			)
		)
		(duplicate_pad_numbers_are_jumpers no)
		(fp_line
			(start -0.7874 -0.4064)
			(end -0.7874 0.4064)
			(stroke
				(width 0.1524)
				(type default)
			)
			(layer "B.SilkS")
		)
		(fp_line
			(start -0.7874 0.4064)
			(end 0.7874 0.4064)
			(stroke
				(width 0.1524)
				(type default)
			)
			(layer "B.SilkS")
		)
		(fp_line
			(start 0.7874 -0.4064)
			(end -0.7874 -0.4064)
			(stroke
				(width 0.1524)
				(type default)
			)
			(layer "B.SilkS")
		)
		(fp_line
			(start 0.7874 0.4064)
			(end 0.7874 -0.4064)
			(stroke
				(width 0.1524)
				(type default)
			)
			(layer "B.SilkS")
		)
		(fp_line
			(start -0.67945 -0.3048)
			(end -0.67945 0.3048)
			(stroke
				(width 0.1)
				(type default)
			)
			(layer "B.Fab")
		)
		(fp_line
			(start -0.67945 0.3048)
			(end -0.120396 0.3048)
			(stroke
				(width 0.1)
				(type default)
			)
			(layer "B.Fab")
		)
		(fp_line
			(start -0.12065 -0.3048)
			(end -0.67945 -0.3048)
			(stroke
				(width 0.1)
				(type default)
			)
			(layer "B.Fab")
		)
		(fp_line
			(start -0.12065 -0.2794)
			(end -0.12065 -0.3048)
			(stroke
				(width 0.1)
				(type default)
			)
			(layer "B.Fab")
		)
		(fp_line
			(start -0.120396 0.2794)
			(end 0.12065 0.2794)
			(stroke
				(width 0.1)
				(type default)
			)
			(layer "B.Fab")
		)
		(fp_line
			(start -0.120396 0.3048)
			(end -0.120396 0.2794)
			(stroke
				(width 0.1)
				(type default)
			)
			(layer "B.Fab")
		)
		(fp_line
			(start 0.12065 -0.305054)
			(end 0.12065 -0.2794)
			(stroke
				(width 0.1)
				(type default)
			)
			(layer "B.Fab")
		)
		(fp_line
			(start 0.12065 -0.2794)
			(end -0.12065 -0.2794)
			(stroke
				(width 0.1)
				(type default)
			)
			(layer "B.Fab")
		)
		(fp_line
			(start 0.12065 0.2794)
			(end 0.12065 0.3048)
			(stroke
				(width 0.1)
				(type default)
			)
			(layer "B.Fab")
		)
		(fp_line
			(start 0.12065 0.3048)
			(end 0.67945 0.3048)
			(stroke
				(width 0.1)
				(type default)
			)
			(layer "B.Fab")
		)
		(fp_line
			(start 0.67945 -0.305054)
			(end 0.12065 -0.305054)
			(stroke
				(width 0.1)
				(type default)
			)
			(layer "B.Fab")
		)
		(fp_line
			(start 0.67945 0.3048)
			(end 0.67945 -0.305054)
			(stroke
				(width 0.1)
				(type default)
			)
			(layer "B.Fab")
		)
		(pad "1" smd circle
			(at 0.40005 0 180)
			(size 0 0)
			(layers "B.Cu" "B.Mask" "B.Paste")
			(net "P0V9_RETIMER_CPU1_TEMP0")
		)
		(pad "2" smd circle
			(at -0.40005 0 180)
			(size 0 0)
			(layers "B.Cu" "B.Mask" "B.Paste")
			(net "GND")
		)
	)
	(footprint ""
		(layer "B.Cu")
		(at 393.637008 -321.179952)
		(property "Reference" "R750"
			(at 0 0 0)
			(layer "B.SilkS")
			(hide yes)
			(effects
				(font
					(size 1.27 1.27)
				)
				(justify mirror)
			)
		)
		(property "Value" ""
			(at 0 0 0)
			(layer "B.Fab")
			(effects
				(font
					(size 1.27 1.27)
				)
				(justify mirror)
			)
		)
		(duplicate_pad_numbers_are_jumpers no)
		(fp_line
			(start -0.7874 -0.4064)
			(end -0.7874 0.4064)
			(stroke
				(width 0.1524)
				(type default)
			)
			(layer "B.SilkS")
		)
		(fp_line
			(start -0.7874 0.4064)
			(end 0.7874 0.4064)
			(stroke
				(width 0.1524)
				(type default)
			)
			(layer "B.SilkS")
		)
		(fp_line
			(start 0.7874 -0.4064)
			(end -0.7874 -0.4064)
			(stroke
				(width 0.1524)
				(type default)
			)
			(layer "B.SilkS")
		)
		(fp_line
			(start 0.7874 0.4064)
			(end 0.7874 -0.4064)
			(stroke
				(width 0.1524)
				(type default)
			)
			(layer "B.SilkS")
		)
		(fp_line
			(start -0.67945 -0.3048)
			(end -0.67945 0.3048)
			(stroke
				(width 0.1)
				(type default)
			)
			(layer "B.Fab")
		)
		(fp_line
			(start -0.67945 0.3048)
			(end -0.120396 0.3048)
			(stroke
				(width 0.1)
				(type default)
			)
			(layer "B.Fab")
		)
		(fp_line
			(start -0.12065 -0.3048)
			(end -0.67945 -0.3048)
			(stroke
				(width 0.1)
				(type default)
			)
			(layer "B.Fab")
		)
		(fp_line
			(start -0.12065 -0.2794)
			(end -0.12065 -0.3048)
			(stroke
				(width 0.1)
				(type default)
			)
			(layer "B.Fab")
		)
		(fp_line
			(start -0.120396 0.2794)
			(end 0.12065 0.2794)
			(stroke
				(width 0.1)
				(type default)
			)
			(layer "B.Fab")
		)
		(fp_line
			(start -0.120396 0.3048)
			(end -0.120396 0.2794)
			(stroke
				(width 0.1)
				(type default)
			)
			(layer "B.Fab")
		)
		(fp_line
			(start 0.12065 -0.305054)
			(end 0.12065 -0.2794)
			(stroke
				(width 0.1)
				(type default)
			)
			(layer "B.Fab")
		)
		(fp_line
			(start 0.12065 -0.2794)
			(end -0.12065 -0.2794)
			(stroke
				(width 0.1)
				(type default)
			)
			(layer "B.Fab")
		)
		(fp_line
			(start 0.12065 0.2794)
			(end 0.12065 0.3048)
			(stroke
				(width 0.1)
				(type default)
			)
			(layer "B.Fab")
		)
		(fp_line
			(start 0.12065 0.3048)
			(end 0.67945 0.3048)
			(stroke
				(width 0.1)
				(type default)
			)
			(layer "B.Fab")
		)
		(fp_line
			(start 0.67945 -0.305054)
			(end 0.12065 -0.305054)
			(stroke
				(width 0.1)
				(type default)
			)
			(layer "B.Fab")
		)
		(fp_line
			(start 0.67945 0.3048)
			(end 0.67945 -0.305054)
			(stroke
				(width 0.1)
				(type default)
			)
			(layer "B.Fab")
		)
		(pad "1" smd circle
			(at 0.40005 0 180)
			(size 0 0)
			(layers "B.Cu" "B.Mask" "B.Paste")
			(net "GND")
		)
		(pad "2" smd circle
			(at -0.40005 0 180)
			(size 0 0)
			(layers "B.Cu" "B.Mask" "B.Paste")
			(net "CLK_ESPI_CPU0_CLK1")
		)
	)
	(footprint ""
		(layer "B.Cu")
		(at 346.026994 -308.517798)
		(property "Reference" "R405"
			(at 0 0 0)
			(layer "B.SilkS")
			(hide yes)
			(effects
				(font
					(size 1.27 1.27)
				)
				(justify mirror)
			)
		)
		(property "Value" ""
			(at 0 0 0)
			(layer "B.Fab")
			(effects
				(font
					(size 1.27 1.27)
				)
				(justify mirror)
			)
		)
		(duplicate_pad_numbers_are_jumpers no)
		(fp_line
			(start -0.7874 -0.4064)
			(end -0.7874 0.4064)
			(stroke
				(width 0.1524)
				(type default)
			)
			(layer "B.SilkS")
		)
		(fp_line
			(start -0.7874 0.4064)
			(end 0.7874 0.4064)
			(stroke
				(width 0.1524)
				(type default)
			)
			(layer "B.SilkS")
		)
		(fp_line
			(start 0.7874 -0.4064)
			(end -0.7874 -0.4064)
			(stroke
				(width 0.1524)
				(type default)
			)
			(layer "B.SilkS")
		)
		(fp_line
			(start 0.7874 0.4064)
			(end 0.7874 -0.4064)
			(stroke
				(width 0.1524)
				(type default)
			)
			(layer "B.SilkS")
		)
		(fp_line
			(start -0.67945 -0.3048)
			(end -0.67945 0.3048)
			(stroke
				(width 0.1)
				(type default)
			)
			(layer "B.Fab")
		)
		(fp_line
			(start -0.67945 0.3048)
			(end -0.120396 0.3048)
			(stroke
				(width 0.1)
				(type default)
			)
			(layer "B.Fab")
		)
		(fp_line
			(start -0.12065 -0.3048)
			(end -0.67945 -0.3048)
			(stroke
				(width 0.1)
				(type default)
			)
			(layer "B.Fab")
		)
		(fp_line
			(start -0.12065 -0.2794)
			(end -0.12065 -0.3048)
			(stroke
				(width 0.1)
				(type default)
			)
			(layer "B.Fab")
		)
		(fp_line
			(start -0.120396 0.2794)
			(end 0.12065 0.2794)
			(stroke
				(width 0.1)
				(type default)
			)
			(layer "B.Fab")
		)
		(fp_line
			(start -0.120396 0.3048)
			(end -0.120396 0.2794)
			(stroke
				(width 0.1)
				(type default)
			)
			(layer "B.Fab")
		)
		(fp_line
			(start 0.12065 -0.305054)
			(end 0.12065 -0.2794)
			(stroke
				(width 0.1)
				(type default)
			)
			(layer "B.Fab")
		)
		(fp_line
			(start 0.12065 -0.2794)
			(end -0.12065 -0.2794)
			(stroke
				(width 0.1)
				(type default)
			)
			(layer "B.Fab")
		)
		(fp_line
			(start 0.12065 0.2794)
			(end 0.12065 0.3048)
			(stroke
				(width 0.1)
				(type default)
			)
			(layer "B.Fab")
		)
		(fp_line
			(start 0.12065 0.3048)
			(end 0.67945 0.3048)
			(stroke
				(width 0.1)
				(type default)
			)
			(layer "B.Fab")
		)
		(fp_line
			(start 0.67945 -0.305054)
			(end 0.12065 -0.305054)
			(stroke
				(width 0.1)
				(type default)
			)
			(layer "B.Fab")
		)
		(fp_line
			(start 0.67945 0.3048)
			(end 0.67945 -0.305054)
			(stroke
				(width 0.1)
				(type default)
			)
			(layer "B.Fab")
		)
		(pad "1" smd circle
			(at 0.40005 0 180)
			(size 0 0)
			(layers "B.Cu" "B.Mask" "B.Paste")
			(net "UART_CPU0_UART0_TX")
		)
		(pad "2" smd circle
			(at -0.40005 0 180)
			(size 0 0)
			(layers "B.Cu" "B.Mask" "B.Paste")
			(net "UART_CPU0_UART0_R_TX")
		)
	)
	(footprint ""
		(layer "B.Cu")
		(at 378.398278 -142.361158 -90)
		(property "Reference" "PU42"
			(at 5.846572 1.250696 0)
			(unlocked yes)
			(layer "B.SilkS")
			(effects
				(font
					(size 0.7874 0.5842)
					(thickness 0.1524)
				)
				(justify mirror)
			)
		)
		(property "Value" ""
			(at 0 0 90)
			(layer "B.Fab")
			(effects
				(font
					(size 1.27 1.27)
				)
				(justify mirror)
			)
		)
		(duplicate_pad_numbers_are_jumpers no)
		(fp_line
			(start -3.024886 3.024886)
			(end -2.428494 3.024886)
			(stroke
				(width 0.1524)
				(type default)
			)
			(layer "B.SilkS")
		)
		(fp_line
			(start 2.428494 3.024886)
			(end 3.024886 3.024886)
			(stroke
				(width 0.1524)
				(type default)
			)
			(layer "B.SilkS")
		)
		(fp_line
			(start 3.024886 3.024886)
			(end 3.024886 2.428494)
			(stroke
				(width 0.1524)
				(type default)
			)
			(layer "B.SilkS")
		)
		(fp_line
			(start -3.024886 2.428494)
			(end -3.024886 3.024886)
			(stroke
				(width 0.1524)
				(type default)
			)
			(layer "B.SilkS")
		)
		(fp_line
			(start 3.024886 -2.428494)
			(end 3.024886 -3.024886)
			(stroke
				(width 0.1524)
				(type default)
			)
			(layer "B.SilkS")
		)
		(fp_line
			(start -3.024886 -3.024886)
			(end -3.024886 -2.428494)
			(stroke
				(width 0.1524)
				(type default)
			)
			(layer "B.SilkS")
		)
		(fp_line
			(start -2.428494 -3.024886)
			(end -3.024886 -3.024886)
			(stroke
				(width 0.1524)
				(type default)
			)
			(layer "B.SilkS")
		)
		(fp_line
			(start 3.024886 -3.024886)
			(end 2.428494 -3.024886)
			(stroke
				(width 0.1524)
				(type default)
			)
			(layer "B.SilkS")
		)
		(fp_poly
			(pts
				(xy 4.10337 -1.79197) (xy 3.307588 -2.192274) (xy 4.10337 -2.587752)
			)
			(stroke
				(width 0)
				(type default)
			)
			(fill yes)
			(layer "B.SilkS")
		)
		(fp_line
			(start -3.024886 3.024886)
			(end 3.024886 3.024886)
			(stroke
				(width 0.1)
				(type default)
			)
			(layer "B.Fab")
		)
		(fp_line
			(start 3.024886 3.024886)
			(end 3.024886 -3.024886)
			(stroke
				(width 0.1)
				(type default)
			)
			(layer "B.Fab")
		)
		(fp_line
			(start -3.024886 -3.024886)
			(end -3.024886 3.024886)
			(stroke
				(width 0.1)
				(type default)
			)
			(layer "B.Fab")
		)
		(fp_line
			(start 3.024886 -3.024886)
			(end -3.024886 -3.024886)
			(stroke
				(width 0.1)
				(type default)
			)
			(layer "B.Fab")
		)
		(fp_poly
			(pts
				(xy 3.332226 -2.199894) (xy 4.348226 -1.691894) (xy 4.348226 -2.707894)
			)
			(stroke
				(width 0)
				(type default)
			)
			(fill yes)
			(layer "B.Fab")
		)
		(pad "1" smd rect
			(at 2.875026 -2.199894 180)
			(size 0.1778 0.6604)
			(layers "B.Cu" "B.Mask" "B.Paste")
			(net "PVDDCR_SOC_P0_PWM1")
		)
		(pad "2" smd rect
			(at 2.875026 -1.800098 180)
			(size 0.1778 0.6604)
			(layers "B.Cu" "B.Mask" "B.Paste")
			(net "PVDDCR_SOC_P0_PWM2")
		)
		(pad "3" smd rect
			(at 2.875026 -1.400048 180)
			(size 0.1778 0.6604)
			(layers "B.Cu" "B.Mask" "B.Paste")
			(net "PVDDCR_SOC_P0_PWM3")
		)
		(pad "4" smd rect
			(at 2.875026 -0.999998 180)
			(size 0.1778 0.6604)
			(layers "B.Cu" "B.Mask" "B.Paste")
			(net "NC_PVDDCR_CPU0_P0_PWM9")
		)
		(pad "5" smd rect
			(at 2.875026 -0.599948 180)
			(size 0.1778 0.6604)
			(layers "B.Cu" "B.Mask" "B.Paste")
			(net "NC_PVDDCR_CPU0_P0_PWM8")
		)
		(pad "6" smd rect
			(at 2.875026 -0.199898 180)
			(size 0.1778 0.6604)
			(layers "B.Cu" "B.Mask" "B.Paste")
			(net "NC_PVDDCR_CPU0_P0_PWM7")
		)
		(pad "7" smd rect
			(at 2.875026 0.199898 180)
			(size 0.1778 0.6604)
			(layers "B.Cu" "B.Mask" "B.Paste")
			(net "PVDDCR_CPU0_P0_PWM6")
		)
		(pad "8" smd rect
			(at 2.875026 0.599948 180)
			(size 0.1778 0.6604)
			(layers "B.Cu" "B.Mask" "B.Paste")
			(net "PVDDCR_CPU0_P0_PWM5")
		)
		(pad "9" smd rect
			(at 2.875026 0.999998 180)
			(size 0.1778 0.6604)
			(layers "B.Cu" "B.Mask" "B.Paste")
			(net "PVDDCR_CPU0_P0_PWM4")
		)
		(pad "10" smd rect
			(at 2.875026 1.400048 180)
			(size 0.1778 0.6604)
			(layers "B.Cu" "B.Mask" "B.Paste")
			(net "PVDDCR_CPU0_P0_PWM3")
		)
		(pad "11" smd rect
			(at 2.875026 1.800098 180)
			(size 0.1778 0.6604)
			(layers "B.Cu" "B.Mask" "B.Paste")
			(net "PVDDCR_CPU0_P0_PWM2")
		)
		(pad "12" smd rect
			(at 2.875026 2.199894 180)
			(size 0.1778 0.6604)
			(layers "B.Cu" "B.Mask" "B.Paste")
			(net "PVDDCR_CPU0_P0_PWM1")
		)
		(pad "13" smd rect
			(at 2.199894 2.875026 90)
			(size 0.1778 0.6604)
			(layers "B.Cu" "B.Mask" "B.Paste")
			(net "PVDDCR_CPU0_P0_PMSDA_R")
		)
		(pad "14" smd rect
			(at 1.800098 2.875026 90)
			(size 0.1778 0.6604)
			(layers "B.Cu" "B.Mask" "B.Paste")
			(net "PVDDCR_CPU0_P0_PMSCL_R")
		)
		(pad "15" smd rect
			(at 1.400048 2.875026 90)
			(size 0.1778 0.6604)
			(layers "B.Cu" "B.Mask" "B.Paste")
			(net "PVDDCR_CPU0_P0_PMALERT_R")
		)
		(pad "16" smd rect
			(at 0.999998 2.875026 90)
			(size 0.1778 0.6604)
			(layers "B.Cu" "B.Mask" "B.Paste")
			(net "PWRGD_PVDDCR_CPU0_P0_R")
		)
		(pad "17" smd rect
			(at 0.599948 2.875026 90)
			(size 0.1778 0.6604)
			(layers "B.Cu" "B.Mask" "B.Paste")
			(net "PVDDCR_CPU0_P0_EN_R")
		)
		(pad "18" smd rect
			(at 0.199898 2.875026 90)
			(size 0.1778 0.6604)
			(layers "B.Cu" "B.Mask" "B.Paste")
			(net "PVDDCR_CPU0_P0_RESET_N_R")
		)
		(pad "19" smd rect
			(at -0.199898 2.875026 90)
			(size 0.1778 0.6604)
			(layers "B.Cu" "B.Mask" "B.Paste")
			(net "PVDD18_S5_P0")
		)
		(pad "20" smd rect
			(at -0.599948 2.875026 90)
			(size 0.1778 0.6604)
			(layers "B.Cu" "B.Mask" "B.Paste")
			(net "PWRGD_PVDDCR_SOC_P0_R")
		)
		(pad "21" smd rect
			(at -0.999998 2.875026 90)
			(size 0.1778 0.6604)
			(layers "B.Cu" "B.Mask" "B.Paste")
			(net "SVID_PVDDCR_CPU0_P0_SVD_R1")
		)
		(pad "22" smd rect
			(at -1.400048 2.875026 90)
			(size 0.1778 0.6604)
			(layers "B.Cu" "B.Mask" "B.Paste")
			(net "SVID_PVDDCR_CPU0_P0_SVC_R1")
		)
		(pad "23" smd rect
			(at -1.800098 2.875026 90)
			(size 0.1778 0.6604)
			(layers "B.Cu" "B.Mask" "B.Paste")
			(net "SVID_PVDDCR_CPU0_P0_SVTO_R")
		)
		(pad "24" smd rect
			(at -2.199894 2.875026 90)
			(size 0.1778 0.6604)
			(layers "B.Cu" "B.Mask" "B.Paste")
			(net "SVID_PVDDCR_CPU0_P0_SVTI_R")
		)
		(pad "25" smd rect
			(at -2.875026 2.199894 180)
			(size 0.1778 0.6604)
			(layers "B.Cu" "B.Mask" "B.Paste")
			(net "VSENSE_PVDDCR_CPU0_P0_VSEN0")
		)
		(pad "26" smd rect
			(at -2.875026 1.800098 180)
			(size 0.1778 0.6604)
			(layers "B.Cu" "B.Mask" "B.Paste")
			(net "VSENSE_VSS_SENSE_A_P0")
		)
		(pad "27" smd rect
			(at -2.875026 1.400048 180)
			(size 0.1778 0.6604)
			(layers "B.Cu" "B.Mask" "B.Paste")
			(net "PVDDCR_CPU0_P0_IMON1")
		)
		(pad "28" smd rect
			(at -2.875026 0.999998 180)
			(size 0.1778 0.6604)
			(layers "B.Cu" "B.Mask" "B.Paste")
			(net "PVDDCR_CPU0_P0_IMON2")
		)
		(pad "29" smd rect
			(at -2.875026 0.599948 180)
			(size 0.1778 0.6604)
			(layers "B.Cu" "B.Mask" "B.Paste")
			(net "PVDDCR_CPU0_P0_IMON3")
		)
		(pad "30" smd rect
			(at -2.875026 0.199898 180)
			(size 0.1778 0.6604)
			(layers "B.Cu" "B.Mask" "B.Paste")
			(net "PVDDCR_CPU0_P0_IMON4")
		)
		(pad "31" smd rect
			(at -2.875026 -0.199898 180)
			(size 0.1778 0.6604)
			(layers "B.Cu" "B.Mask" "B.Paste")
			(net "PVDDCR_CPU0_P0_IMON5")
		)
		(pad "32" smd rect
			(at -2.875026 -0.599948 180)
			(size 0.1778 0.6604)
			(layers "B.Cu" "B.Mask" "B.Paste")
			(net "PVDDCR_CPU0_P0_IMON6")
		)
		(pad "33" smd rect
			(at -2.875026 -0.999998 180)
			(size 0.1778 0.6604)
			(layers "B.Cu" "B.Mask" "B.Paste")
			(net "NC_PVDDCR_CPU0_P0_IMON7")
		)
		(pad "34" smd rect
			(at -2.875026 -1.400048 180)
			(size 0.1778 0.6604)
			(layers "B.Cu" "B.Mask" "B.Paste")
			(net "NC_PVDDCR_CPU0_P0_IMON8")
		)
		(pad "35" smd rect
			(at -2.875026 -1.800098 180)
			(size 0.1778 0.6604)
			(layers "B.Cu" "B.Mask" "B.Paste")
			(net "NC_PVDDCR_CPU0_P0_IMON9")
		)
		(pad "36" smd rect
			(at -2.875026 -2.199894 180)
			(size 0.1778 0.6604)
			(layers "B.Cu" "B.Mask" "B.Paste")
			(net "PVDDCR_SOC_P0_IMON3")
		)
		(pad "37" smd rect
			(at -2.199894 -2.875026 90)
			(size 0.1778 0.6604)
			(layers "B.Cu" "B.Mask" "B.Paste")
			(net "PVDDCR_SOC_P0_IMON2")
		)
		(pad "38" smd rect
			(at -1.800098 -2.875026 90)
			(size 0.1778 0.6604)
			(layers "B.Cu" "B.Mask" "B.Paste")
			(net "PVDDCR_SOC_P0_IMON1")
		)
		(pad "39" smd rect
			(at -1.400048 -2.875026 90)
			(size 0.1778 0.6604)
			(layers "B.Cu" "B.Mask" "B.Paste")
			(net "VSENSE_VSS_SENSE_A_P0")
		)
		(pad "40" smd rect
			(at -0.999998 -2.875026 90)
			(size 0.1778 0.6604)
			(layers "B.Cu" "B.Mask" "B.Paste")
			(net "VSENSE_PVDDCR_SOC_P0_VSEN1")
		)
		(pad "41" smd rect
			(at -0.599948 -2.875026 90)
			(size 0.1778 0.6604)
			(layers "B.Cu" "B.Mask" "B.Paste")
			(net "PVDDCR_CPU0_P0_OCP_N_R")
		)
		(pad "42" smd rect
			(at -0.199898 -2.875026 90)
			(size 0.1778 0.6604)
			(layers "B.Cu" "B.Mask" "B.Paste")
			(net "PVDDCR_SOC_P0_EN//ADDR_CFG")
		)
		(pad "43" smd rect
			(at 0.199898 -2.875026 90)
			(size 0.1778 0.6604)
			(layers "B.Cu" "B.Mask" "B.Paste")
			(net "PVDDCR_SOC_P0_TEMP1")
		)
		(pad "44" smd rect
			(at 0.599948 -2.875026 90)
			(size 0.1778 0.6604)
			(layers "B.Cu" "B.Mask" "B.Paste")
			(net "PVDDCR_CPU0_P0_TEMP0")
		)
		(pad "45" smd rect
			(at 0.999998 -2.875026 90)
			(size 0.1778 0.6604)
			(layers "B.Cu" "B.Mask" "B.Paste")
			(net "PVDDCR_CPU0_P0_VMON")
		)
		(pad "46" smd rect
			(at 1.400048 -2.875026 90)
			(size 0.1778 0.6604)
			(layers "B.Cu" "B.Mask" "B.Paste")
			(net "PVDDCR_CPU0_P0_VINSEN")
		)
		(pad "47" smd rect
			(at 1.800098 -2.875026 90)
			(size 0.1778 0.6604)
			(layers "B.Cu" "B.Mask" "B.Paste")
			(net "PVDDCR_CPU0_P0_VCC")
		)
		(pad "48" smd rect
			(at 2.199894 -2.875026 90)
			(size 0.1778 0.6604)
			(layers "B.Cu" "B.Mask" "B.Paste")
			(net "PVDDCR_CPU0_P0_VCCS")
		)
		(pad "TH" smd rect
			(at 0 0 90)
			(size 4.4196 4.4196)
			(layers "B.Cu" "B.Mask" "B.Paste")
			(net "GND")
		)
		(zone
			(layer "B.Cu")
			(hatch none 0.5)
			(connect_pads
				(clearance 0)
			)
			(min_thickness 0.25)
			(keepout
				(tracks not_allowed)
				(vias allowed)
				(pads allowed)
				(copperpour not_allowed)
				(footprints allowed)
			)
			(placement
				(enabled no)
				(sheetname "")
			)
			(fill
				(thermal_gap 0.5)
				(thermal_bridge_width 0.5)
				(island_removal_mode 0)
			)
			(polygon
				(pts
					(xy 378.423678 -139.867132) (xy 380.892304 -139.867132) (xy 380.892304 -144.855184) (xy 375.904252 -144.855184)
					(xy 375.904252 -139.867132) (xy 378.398278 -139.867132) (xy 378.398278 -140.100558) (xy 376.137678 -140.100558)
					(xy 376.137678 -144.621758) (xy 380.658878 -144.621758) (xy 380.658878 -140.100558) (xy 378.423678 -140.100558)
				)
			)
		)
	)
	(footprint ""
		(layer "B.Cu")
		(at 102.528878 -139.93241 90)
		(property "Reference" "PR183"
			(at 0 0 90)
			(layer "B.SilkS")
			(hide yes)
			(effects
				(font
					(size 1.27 1.27)
				)
				(justify mirror)
			)
		)
		(property "Value" ""
			(at 0 0 90)
			(layer "B.Fab")
			(effects
				(font
					(size 1.27 1.27)
				)
				(justify mirror)
			)
		)
		(duplicate_pad_numbers_are_jumpers no)
		(fp_line
			(start 0.7874 -0.4064)
			(end -0.7874 -0.4064)
			(stroke
				(width 0.1524)
				(type default)
			)
			(layer "B.SilkS")
		)
		(fp_line
			(start -0.7874 -0.4064)
			(end -0.7874 0.4064)
			(stroke
				(width 0.1524)
				(type default)
			)
			(layer "B.SilkS")
		)
		(fp_line
			(start 0.7874 0.4064)
			(end 0.7874 -0.4064)
			(stroke
				(width 0.1524)
				(type default)
			)
			(layer "B.SilkS")
		)
		(fp_line
			(start -0.7874 0.4064)
			(end 0.7874 0.4064)
			(stroke
				(width 0.1524)
				(type default)
			)
			(layer "B.SilkS")
		)
		(fp_line
			(start 0.67945 -0.305054)
			(end 0.12065 -0.305054)
			(stroke
				(width 0.1)
				(type default)
			)
			(layer "B.Fab")
		)
		(fp_line
			(start 0.12065 -0.305054)
			(end 0.12065 -0.2794)
			(stroke
				(width 0.1)
				(type default)
			)
			(layer "B.Fab")
		)
		(fp_line
			(start -0.12065 -0.3048)
			(end -0.67945 -0.3048)
			(stroke
				(width 0.1)
				(type default)
			)
			(layer "B.Fab")
		)
		(fp_line
			(start -0.67945 -0.3048)
			(end -0.67945 0.3048)
			(stroke
				(width 0.1)
				(type default)
			)
			(layer "B.Fab")
		)
		(fp_line
			(start 0.12065 -0.2794)
			(end -0.12065 -0.2794)
			(stroke
				(width 0.1)
				(type default)
			)
			(layer "B.Fab")
		)
		(fp_line
			(start -0.12065 -0.2794)
			(end -0.12065 -0.3048)
			(stroke
				(width 0.1)
				(type default)
			)
			(layer "B.Fab")
		)
		(fp_line
			(start 0.12065 0.2794)
			(end 0.12065 0.3048)
			(stroke
				(width 0.1)
				(type default)
			)
			(layer "B.Fab")
		)
		(fp_line
			(start -0.120396 0.2794)
			(end 0.12065 0.2794)
			(stroke
				(width 0.1)
				(type default)
			)
			(layer "B.Fab")
		)
		(fp_line
			(start 0.67945 0.3048)
			(end 0.67945 -0.305054)
			(stroke
				(width 0.1)
				(type default)
			)
			(layer "B.Fab")
		)
		(fp_line
			(start 0.12065 0.3048)
			(end 0.67945 0.3048)
			(stroke
				(width 0.1)
				(type default)
			)
			(layer "B.Fab")
		)
		(fp_line
			(start -0.120396 0.3048)
			(end -0.120396 0.2794)
			(stroke
				(width 0.1)
				(type default)
			)
			(layer "B.Fab")
		)
		(fp_line
			(start -0.67945 0.3048)
			(end -0.120396 0.3048)
			(stroke
				(width 0.1)
				(type default)
			)
			(layer "B.Fab")
		)
		(pad "1" smd circle
			(at 0.40005 0 270)
			(size 0 0)
			(layers "B.Cu" "B.Mask" "B.Paste")
			(net "PVDDCR_CPU0_P1_VCC")
		)
		(pad "2" smd circle
			(at -0.40005 0 270)
			(size 0 0)
			(layers "B.Cu" "B.Mask" "B.Paste")
			(net "P3V3_AUX")
		)
	)
	(footprint ""
		(layer "B.Cu")
		(at 302.133 -355.854 180)
		(property "Reference" "R8043"
			(at 0 0 0)
			(layer "B.SilkS")
			(hide yes)
			(effects
				(font
					(size 1.27 1.27)
				)
				(justify mirror)
			)
		)
		(property "Value" ""
			(at 0 0 0)
			(layer "B.Fab")
			(effects
				(font
					(size 1.27 1.27)
				)
				(justify mirror)
			)
		)
		(duplicate_pad_numbers_are_jumpers no)
		(fp_line
			(start 0.7874 0.4064)
			(end 0.7874 -0.4064)
			(stroke
				(width 0.1524)
				(type default)
			)
			(layer "B.SilkS")
		)
		(fp_line
			(start 0.7874 -0.4064)
			(end -0.7874 -0.4064)
			(stroke
				(width 0.1524)
				(type default)
			)
			(layer "B.SilkS")
		)
		(fp_line
			(start -0.7874 0.4064)
			(end 0.7874 0.4064)
			(stroke
				(width 0.1524)
				(type default)
			)
			(layer "B.SilkS")
		)
		(fp_line
			(start -0.7874 -0.4064)
			(end -0.7874 0.4064)
			(stroke
				(width 0.1524)
				(type default)
			)
			(layer "B.SilkS")
		)
		(fp_line
			(start 0.67945 0.3048)
			(end 0.67945 -0.305054)
			(stroke
				(width 0.1)
				(type default)
			)
			(layer "B.Fab")
		)
		(fp_line
			(start 0.67945 -0.305054)
			(end 0.12065 -0.305054)
			(stroke
				(width 0.1)
				(type default)
			)
			(layer "B.Fab")
		)
		(fp_line
			(start 0.12065 0.3048)
			(end 0.67945 0.3048)
			(stroke
				(width 0.1)
				(type default)
			)
			(layer "B.Fab")
		)
		(fp_line
			(start 0.12065 0.2794)
			(end 0.12065 0.3048)
			(stroke
				(width 0.1)
				(type default)
			)
			(layer "B.Fab")
		)
		(fp_line
			(start 0.12065 -0.2794)
			(end -0.12065 -0.2794)
			(stroke
				(width 0.1)
				(type default)
			)
			(layer "B.Fab")
		)
		(fp_line
			(start 0.12065 -0.305054)
			(end 0.12065 -0.2794)
			(stroke
				(width 0.1)
				(type default)
			)
			(layer "B.Fab")
		)
		(fp_line
			(start -0.120396 0.3048)
			(end -0.120396 0.2794)
			(stroke
				(width 0.1)
				(type default)
			)
			(layer "B.Fab")
		)
		(fp_line
			(start -0.120396 0.2794)
			(end 0.12065 0.2794)
			(stroke
				(width 0.1)
				(type default)
			)
			(layer "B.Fab")
		)
		(fp_line
			(start -0.12065 -0.2794)
			(end -0.12065 -0.3048)
			(stroke
				(width 0.1)
				(type default)
			)
			(layer "B.Fab")
		)
		(fp_line
			(start -0.12065 -0.3048)
			(end -0.67945 -0.3048)
			(stroke
				(width 0.1)
				(type default)
			)
			(layer "B.Fab")
		)
		(fp_line
			(start -0.67945 0.3048)
			(end -0.120396 0.3048)
			(stroke
				(width 0.1)
				(type default)
			)
			(layer "B.Fab")
		)
		(fp_line
			(start -0.67945 -0.3048)
			(end -0.67945 0.3048)
			(stroke
				(width 0.1)
				(type default)
			)
			(layer "B.Fab")
		)
		(pad "1" smd circle
			(at 0.40005 0)
			(size 0 0)
			(layers "B.Cu" "B.Mask" "B.Paste")
			(net "PVDD18_S5_P0")
		)
		(pad "2" smd circle
			(at -0.40005 0)
			(size 0 0)
			(layers "B.Cu" "B.Mask" "B.Paste")
			(net "SVID_PVDDCR_CPU1_P0_SVTO")
		)
	)
	(footprint ""
		(layer "B.Cu")
		(at 322.583556 -395.148562 90)
		(property "Reference" "C577"
			(at 0 0 90)
			(layer "B.SilkS")
			(hide yes)
			(effects
				(font
					(size 1.27 1.27)
				)
				(justify mirror)
			)
		)
		(property "Value" ""
			(at 0 0 90)
			(layer "B.Fab")
			(effects
				(font
					(size 1.27 1.27)
				)
				(justify mirror)
			)
		)
		(duplicate_pad_numbers_are_jumpers no)
		(fp_line
			(start 0.299974 -0.150114)
			(end -0.299974 -0.150114)
			(stroke
				(width 0.1)
				(type default)
			)
			(layer "B.Fab")
		)
		(fp_line
			(start -0.299974 -0.150114)
			(end -0.299974 0.150114)
			(stroke
				(width 0.1)
				(type default)
			)
			(layer "B.Fab")
		)
		(fp_line
			(start 0.299974 0.150114)
			(end 0.299974 -0.150114)
			(stroke
				(width 0.1)
				(type default)
			)
			(layer "B.Fab")
		)
		(fp_line
			(start -0.299974 0.150114)
			(end 0.299974 0.150114)
			(stroke
				(width 0.1)
				(type default)
			)
			(layer "B.Fab")
		)
		(pad "1" smd rect
			(at 0.2667 0 270)
			(size 0.3048 0.381)
			(layers "B.Cu" "B.Mask" "B.Paste")
			(net "P0V9_CPU0_RT0_2A")
		)
		(pad "2" smd rect
			(at -0.2667 0 270)
			(size 0.3048 0.381)
			(layers "B.Cu" "B.Mask" "B.Paste")
			(net "GND")
		)
	)
	(footprint ""
		(layer "B.Cu")
		(at 119.674386 -267.49883)
		(property "Reference" "C2368"
			(at 0 0 0)
			(layer "B.SilkS")
			(hide yes)
			(effects
				(font
					(size 1.27 1.27)
				)
				(justify mirror)
			)
		)
		(property "Value" ""
			(at 0 0 0)
			(layer "B.Fab")
			(effects
				(font
					(size 1.27 1.27)
				)
				(justify mirror)
			)
		)
		(duplicate_pad_numbers_are_jumpers no)
		(fp_line
			(start -0.7874 -0.4064)
			(end -0.7874 0.4064)
			(stroke
				(width 0.1524)
				(type default)
			)
			(layer "B.SilkS")
		)
		(fp_line
			(start -0.7874 0.4064)
			(end 0.7874 0.4064)
			(stroke
				(width 0.1524)
				(type default)
			)
			(layer "B.SilkS")
		)
		(fp_line
			(start 0.7874 -0.4064)
			(end -0.7874 -0.4064)
			(stroke
				(width 0.1524)
				(type default)
			)
			(layer "B.SilkS")
		)
		(fp_line
			(start 0.7874 0.4064)
			(end 0.7874 -0.4064)
			(stroke
				(width 0.1524)
				(type default)
			)
			(layer "B.SilkS")
		)
		(fp_line
			(start -0.67945 -0.3048)
			(end -0.67945 0.3048)
			(stroke
				(width 0.1)
				(type default)
			)
			(layer "B.Fab")
		)
		(fp_line
			(start -0.67945 0.3048)
			(end -0.120396 0.3048)
			(stroke
				(width 0.1)
				(type default)
			)
			(layer "B.Fab")
		)
		(fp_line
			(start -0.12065 -0.3048)
			(end -0.67945 -0.3048)
			(stroke
				(width 0.1)
				(type default)
			)
			(layer "B.Fab")
		)
		(fp_line
			(start -0.12065 -0.2794)
			(end -0.12065 -0.3048)
			(stroke
				(width 0.1)
				(type default)
			)
			(layer "B.Fab")
		)
		(fp_line
			(start -0.120396 0.2794)
			(end 0.12065 0.2794)
			(stroke
				(width 0.1)
				(type default)
			)
			(layer "B.Fab")
		)
		(fp_line
			(start -0.120396 0.3048)
			(end -0.120396 0.2794)
			(stroke
				(width 0.1)
				(type default)
			)
			(layer "B.Fab")
		)
		(fp_line
			(start 0.12065 -0.305054)
			(end 0.12065 -0.2794)
			(stroke
				(width 0.1)
				(type default)
			)
			(layer "B.Fab")
		)
		(fp_line
			(start 0.12065 -0.2794)
			(end -0.12065 -0.2794)
			(stroke
				(width 0.1)
				(type default)
			)
			(layer "B.Fab")
		)
		(fp_line
			(start 0.12065 0.2794)
			(end 0.12065 0.3048)
			(stroke
				(width 0.1)
				(type default)
			)
			(layer "B.Fab")
		)
		(fp_line
			(start 0.12065 0.3048)
			(end 0.67945 0.3048)
			(stroke
				(width 0.1)
				(type default)
			)
			(layer "B.Fab")
		)
		(fp_line
			(start 0.67945 -0.305054)
			(end 0.12065 -0.305054)
			(stroke
				(width 0.1)
				(type default)
			)
			(layer "B.Fab")
		)
		(fp_line
			(start 0.67945 0.3048)
			(end 0.67945 -0.305054)
			(stroke
				(width 0.1)
				(type default)
			)
			(layer "B.Fab")
		)
		(pad "1" smd circle
			(at 0.40005 0 180)
			(size 0 0)
			(layers "B.Cu" "B.Mask" "B.Paste")
			(net "PVDDCR_CPU1_P1")
		)
		(pad "2" smd circle
			(at -0.40005 0 180)
			(size 0 0)
			(layers "B.Cu" "B.Mask" "B.Paste")
			(net "GND")
		)
	)
	(footprint ""
		(layer "B.Cu")
		(at 254.635 -332.867 180)
		(property "Reference" "R842"
			(at 0 0 0)
			(layer "B.SilkS")
			(hide yes)
			(effects
				(font
					(size 1.27 1.27)
				)
				(justify mirror)
			)
		)
		(property "Value" ""
			(at 0 0 0)
			(layer "B.Fab")
			(effects
				(font
					(size 1.27 1.27)
				)
				(justify mirror)
			)
		)
		(duplicate_pad_numbers_are_jumpers no)
		(fp_line
			(start 0.32512 0.175006)
			(end 0.32512 -0.175006)
			(stroke
				(width 0.1)
				(type default)
			)
			(layer "B.Fab")
		)
		(fp_line
			(start 0.32512 -0.175006)
			(end -0.32512 -0.175006)
			(stroke
				(width 0.1)
				(type default)
			)
			(layer "B.Fab")
		)
		(fp_line
			(start -0.32512 0.175006)
			(end 0.32512 0.175006)
			(stroke
				(width 0.1)
				(type default)
			)
			(layer "B.Fab")
		)
		(fp_line
			(start -0.32512 -0.175006)
			(end -0.32512 0.175006)
			(stroke
				(width 0.1)
				(type default)
			)
			(layer "B.Fab")
		)
		(pad "1" smd rect
			(at 0.2667 0)
			(size 0.3048 0.381)
			(layers "B.Cu" "B.Mask" "B.Paste")
			(net "P1V8_AUX")
		)
		(pad "2" smd rect
			(at -0.2667 0 180)
			(size 0.3048 0.381)
			(layers "B.Cu" "B.Mask" "B.Paste")
			(net "RT_ROM_SMB_MUX_ADDR2")
		)
	)
	(footprint ""
		(layer "B.Cu")
		(at 236.8169 -248.285 180)
		(property "Reference" "R328"
			(at 0 0 0)
			(layer "B.SilkS")
			(hide yes)
			(effects
				(font
					(size 1.27 1.27)
				)
				(justify mirror)
			)
		)
		(property "Value" ""
			(at 0 0 0)
			(layer "B.Fab")
			(effects
				(font
					(size 1.27 1.27)
				)
				(justify mirror)
			)
		)
		(duplicate_pad_numbers_are_jumpers no)
		(fp_line
			(start 0.7874 0.4064)
			(end 0.7874 -0.4064)
			(stroke
				(width 0.1524)
				(type default)
			)
			(layer "B.SilkS")
		)
		(fp_line
			(start 0.7874 -0.4064)
			(end -0.7874 -0.4064)
			(stroke
				(width 0.1524)
				(type default)
			)
			(layer "B.SilkS")
		)
		(fp_line
			(start -0.7874 0.4064)
			(end 0.7874 0.4064)
			(stroke
				(width 0.1524)
				(type default)
			)
			(layer "B.SilkS")
		)
		(fp_line
			(start -0.7874 -0.4064)
			(end -0.7874 0.4064)
			(stroke
				(width 0.1524)
				(type default)
			)
			(layer "B.SilkS")
		)
		(fp_line
			(start 0.67945 0.3048)
			(end 0.67945 -0.305054)
			(stroke
				(width 0.1)
				(type default)
			)
			(layer "B.Fab")
		)
		(fp_line
			(start 0.67945 -0.305054)
			(end 0.12065 -0.305054)
			(stroke
				(width 0.1)
				(type default)
			)
			(layer "B.Fab")
		)
		(fp_line
			(start 0.12065 0.3048)
			(end 0.67945 0.3048)
			(stroke
				(width 0.1)
				(type default)
			)
			(layer "B.Fab")
		)
		(fp_line
			(start 0.12065 0.2794)
			(end 0.12065 0.3048)
			(stroke
				(width 0.1)
				(type default)
			)
			(layer "B.Fab")
		)
		(fp_line
			(start 0.12065 -0.2794)
			(end -0.12065 -0.2794)
			(stroke
				(width 0.1)
				(type default)
			)
			(layer "B.Fab")
		)
		(fp_line
			(start 0.12065 -0.305054)
			(end 0.12065 -0.2794)
			(stroke
				(width 0.1)
				(type default)
			)
			(layer "B.Fab")
		)
		(fp_line
			(start -0.120396 0.3048)
			(end -0.120396 0.2794)
			(stroke
				(width 0.1)
				(type default)
			)
			(layer "B.Fab")
		)
		(fp_line
			(start -0.120396 0.2794)
			(end 0.12065 0.2794)
			(stroke
				(width 0.1)
				(type default)
			)
			(layer "B.Fab")
		)
		(fp_line
			(start -0.12065 -0.2794)
			(end -0.12065 -0.3048)
			(stroke
				(width 0.1)
				(type default)
			)
			(layer "B.Fab")
		)
		(fp_line
			(start -0.12065 -0.3048)
			(end -0.67945 -0.3048)
			(stroke
				(width 0.1)
				(type default)
			)
			(layer "B.Fab")
		)
		(fp_line
			(start -0.67945 0.3048)
			(end -0.120396 0.3048)
			(stroke
				(width 0.1)
				(type default)
			)
			(layer "B.Fab")
		)
		(fp_line
			(start -0.67945 -0.3048)
			(end -0.67945 0.3048)
			(stroke
				(width 0.1)
				(type default)
			)
			(layer "B.Fab")
		)
		(pad "1" smd rect
			(at 0.40005 0 180)
			(size 0.4572 0.508)
			(layers "B.Cu" "B.Mask" "B.Paste")
			(net "SMB_APML_CPU0_MUX2_SDA")
		)
		(pad "2" smd rect
			(at -0.40005 0 180)
			(size 0.4572 0.508)
			(layers "B.Cu" "B.Mask" "B.Paste")
			(net "SMB_APML_CPU0_SDA")
		)
	)
	(footprint ""
		(layer "B.Cu")
		(at 239.903 -335.026)
		(property "Reference" "R1390"
			(at 0 0 0)
			(layer "B.SilkS")
			(hide yes)
			(effects
				(font
					(size 1.27 1.27)
				)
				(justify mirror)
			)
		)
		(property "Value" ""
			(at 0 0 0)
			(layer "B.Fab")
			(effects
				(font
					(size 1.27 1.27)
				)
				(justify mirror)
			)
		)
		(duplicate_pad_numbers_are_jumpers no)
		(fp_line
			(start -0.32512 -0.175006)
			(end -0.32512 0.175006)
			(stroke
				(width 0.1)
				(type default)
			)
			(layer "B.Fab")
		)
		(fp_line
			(start -0.32512 0.175006)
			(end 0.32512 0.175006)
			(stroke
				(width 0.1)
				(type default)
			)
			(layer "B.Fab")
		)
		(fp_line
			(start 0.32512 -0.175006)
			(end -0.32512 -0.175006)
			(stroke
				(width 0.1)
				(type default)
			)
			(layer "B.Fab")
		)
		(fp_line
			(start 0.32512 0.175006)
			(end 0.32512 -0.175006)
			(stroke
				(width 0.1)
				(type default)
			)
			(layer "B.Fab")
		)
		(pad "1" smd rect
			(at 0.2667 0 180)
			(size 0.3048 0.381)
			(layers "B.Cu" "B.Mask" "B.Paste")
			(net "P1V8_CPU1_RT_1D")
		)
		(pad "2" smd rect
			(at -0.2667 0)
			(size 0.3048 0.381)
			(layers "B.Cu" "B.Mask" "B.Paste")
			(net "SMB_RT_CPU1_P0_ROM_MUX_2D_R_SCL")
		)
	)
	(footprint ""
		(layer "B.Cu")
		(at 291.52469 -193.99631)
		(property "Reference" "C96"
			(at 0 0 0)
			(layer "B.SilkS")
			(hide yes)
			(effects
				(font
					(size 1.27 1.27)
				)
				(justify mirror)
			)
		)
		(property "Value" ""
			(at 0 0 0)
			(layer "B.Fab")
			(effects
				(font
					(size 1.27 1.27)
				)
				(justify mirror)
			)
		)
		(duplicate_pad_numbers_are_jumpers no)
		(fp_line
			(start -0.7874 -0.4064)
			(end -0.7874 0.4064)
			(stroke
				(width 0.1524)
				(type default)
			)
			(layer "B.SilkS")
		)
		(fp_line
			(start -0.7874 0.4064)
			(end 0.7874 0.4064)
			(stroke
				(width 0.1524)
				(type default)
			)
			(layer "B.SilkS")
		)
		(fp_line
			(start 0.7874 -0.4064)
			(end -0.7874 -0.4064)
			(stroke
				(width 0.1524)
				(type default)
			)
			(layer "B.SilkS")
		)
		(fp_line
			(start 0.7874 0.4064)
			(end 0.7874 -0.4064)
			(stroke
				(width 0.1524)
				(type default)
			)
			(layer "B.SilkS")
		)
		(fp_line
			(start -0.67945 -0.3048)
			(end -0.67945 0.3048)
			(stroke
				(width 0.1)
				(type default)
			)
			(layer "B.Fab")
		)
		(fp_line
			(start -0.67945 0.3048)
			(end -0.120396 0.3048)
			(stroke
				(width 0.1)
				(type default)
			)
			(layer "B.Fab")
		)
		(fp_line
			(start -0.12065 -0.3048)
			(end -0.67945 -0.3048)
			(stroke
				(width 0.1)
				(type default)
			)
			(layer "B.Fab")
		)
		(fp_line
			(start -0.12065 -0.2794)
			(end -0.12065 -0.3048)
			(stroke
				(width 0.1)
				(type default)
			)
			(layer "B.Fab")
		)
		(fp_line
			(start -0.120396 0.2794)
			(end 0.12065 0.2794)
			(stroke
				(width 0.1)
				(type default)
			)
			(layer "B.Fab")
		)
		(fp_line
			(start -0.120396 0.3048)
			(end -0.120396 0.2794)
			(stroke
				(width 0.1)
				(type default)
			)
			(layer "B.Fab")
		)
		(fp_line
			(start 0.12065 -0.305054)
			(end 0.12065 -0.2794)
			(stroke
				(width 0.1)
				(type default)
			)
			(layer "B.Fab")
		)
		(fp_line
			(start 0.12065 -0.2794)
			(end -0.12065 -0.2794)
			(stroke
				(width 0.1)
				(type default)
			)
			(layer "B.Fab")
		)
		(fp_line
			(start 0.12065 0.2794)
			(end 0.12065 0.3048)
			(stroke
				(width 0.1)
				(type default)
			)
			(layer "B.Fab")
		)
		(fp_line
			(start 0.12065 0.3048)
			(end 0.67945 0.3048)
			(stroke
				(width 0.1)
				(type default)
			)
			(layer "B.Fab")
		)
		(fp_line
			(start 0.67945 -0.305054)
			(end 0.12065 -0.305054)
			(stroke
				(width 0.1)
				(type default)
			)
			(layer "B.Fab")
		)
		(fp_line
			(start 0.67945 0.3048)
			(end 0.67945 -0.305054)
			(stroke
				(width 0.1)
				(type default)
			)
			(layer "B.Fab")
		)
		(pad "1" smd circle
			(at 0.40005 0 180)
			(size 0 0)
			(layers "B.Cu" "B.Mask" "B.Paste")
			(net "P3V3_AUX")
		)
		(pad "2" smd circle
			(at -0.40005 0 180)
			(size 0 0)
			(layers "B.Cu" "B.Mask" "B.Paste")
			(net "GND")
		)
	)
	(footprint ""
		(layer "B.Cu")
		(at 410.21889 -398.942052 90)
		(property "Reference" "C971"
			(at 0 0 90)
			(layer "B.SilkS")
			(hide yes)
			(effects
				(font
					(size 1.27 1.27)
				)
				(justify mirror)
			)
		)
		(property "Value" ""
			(at 0 0 90)
			(layer "B.Fab")
			(effects
				(font
					(size 1.27 1.27)
				)
				(justify mirror)
			)
		)
		(duplicate_pad_numbers_are_jumpers no)
		(fp_line
			(start 0.7874 -0.4064)
			(end -0.7874 -0.4064)
			(stroke
				(width 0.1524)
				(type default)
			)
			(layer "B.SilkS")
		)
		(fp_line
			(start -0.7874 -0.4064)
			(end -0.7874 0.4064)
			(stroke
				(width 0.1524)
				(type default)
			)
			(layer "B.SilkS")
		)
		(fp_line
			(start 0.7874 0.4064)
			(end 0.7874 -0.4064)
			(stroke
				(width 0.1524)
				(type default)
			)
			(layer "B.SilkS")
		)
		(fp_line
			(start -0.7874 0.4064)
			(end 0.7874 0.4064)
			(stroke
				(width 0.1524)
				(type default)
			)
			(layer "B.SilkS")
		)
		(fp_line
			(start 0.67945 -0.305054)
			(end 0.12065 -0.305054)
			(stroke
				(width 0.1)
				(type default)
			)
			(layer "B.Fab")
		)
		(fp_line
			(start 0.12065 -0.305054)
			(end 0.12065 -0.2794)
			(stroke
				(width 0.1)
				(type default)
			)
			(layer "B.Fab")
		)
		(fp_line
			(start -0.12065 -0.3048)
			(end -0.67945 -0.3048)
			(stroke
				(width 0.1)
				(type default)
			)
			(layer "B.Fab")
		)
		(fp_line
			(start -0.67945 -0.3048)
			(end -0.67945 0.3048)
			(stroke
				(width 0.1)
				(type default)
			)
			(layer "B.Fab")
		)
		(fp_line
			(start 0.12065 -0.2794)
			(end -0.12065 -0.2794)
			(stroke
				(width 0.1)
				(type default)
			)
			(layer "B.Fab")
		)
		(fp_line
			(start -0.12065 -0.2794)
			(end -0.12065 -0.3048)
			(stroke
				(width 0.1)
				(type default)
			)
			(layer "B.Fab")
		)
		(fp_line
			(start 0.12065 0.2794)
			(end 0.12065 0.3048)
			(stroke
				(width 0.1)
				(type default)
			)
			(layer "B.Fab")
		)
		(fp_line
			(start -0.120396 0.2794)
			(end 0.12065 0.2794)
			(stroke
				(width 0.1)
				(type default)
			)
			(layer "B.Fab")
		)
		(fp_line
			(start 0.67945 0.3048)
			(end 0.67945 -0.305054)
			(stroke
				(width 0.1)
				(type default)
			)
			(layer "B.Fab")
		)
		(fp_line
			(start 0.12065 0.3048)
			(end 0.67945 0.3048)
			(stroke
				(width 0.1)
				(type default)
			)
			(layer "B.Fab")
		)
		(fp_line
			(start -0.120396 0.3048)
			(end -0.120396 0.2794)
			(stroke
				(width 0.1)
				(type default)
			)
			(layer "B.Fab")
		)
		(fp_line
			(start -0.67945 0.3048)
			(end -0.120396 0.3048)
			(stroke
				(width 0.1)
				(type default)
			)
			(layer "B.Fab")
		)
		(pad "1" smd circle
			(at 0.40005 0 270)
			(size 0 0)
			(layers "B.Cu" "B.Mask" "B.Paste")
			(net "P0V9_CPU0_RT_2D")
		)
		(pad "2" smd circle
			(at -0.40005 0 270)
			(size 0 0)
			(layers "B.Cu" "B.Mask" "B.Paste")
			(net "GND")
		)
	)
	(footprint ""
		(layer "B.Cu")
		(at 358.779826 -392.957558)
		(property "Reference" "L13"
			(at 0 0 0)
			(layer "B.SilkS")
			(hide yes)
			(effects
				(font
					(size 1.27 1.27)
				)
				(justify mirror)
			)
		)
		(property "Value" ""
			(at 0 0 0)
			(layer "B.Fab")
			(effects
				(font
					(size 1.27 1.27)
				)
				(justify mirror)
			)
		)
		(duplicate_pad_numbers_are_jumpers no)
		(fp_line
			(start -1.63576 -0.8128)
			(end -1.63576 0.8128)
			(stroke
				(width 0.1524)
				(type default)
			)
			(layer "B.SilkS")
		)
		(fp_line
			(start -1.63576 0.8128)
			(end 1.63576 0.8128)
			(stroke
				(width 0.1524)
				(type default)
			)
			(layer "B.SilkS")
		)
		(fp_line
			(start 1.63576 -0.8128)
			(end -1.63576 -0.8128)
			(stroke
				(width 0.1524)
				(type default)
			)
			(layer "B.SilkS")
		)
		(fp_line
			(start 1.63576 -0.8128)
			(end 1.63576 0.8128)
			(stroke
				(width 0.1524)
				(type default)
			)
			(layer "B.SilkS")
		)
		(fp_line
			(start -1.560576 -0.738632)
			(end 1.56083 -0.738632)
			(stroke
				(width 0.1)
				(type default)
			)
			(layer "B.Fab")
		)
		(fp_line
			(start -1.560576 0.7366)
			(end -1.560576 -0.738632)
			(stroke
				(width 0.1)
				(type default)
			)
			(layer "B.Fab")
		)
		(fp_line
			(start -1.524 0.7366)
			(end -1.560576 0.7366)
			(stroke
				(width 0.1)
				(type default)
			)
			(layer "B.Fab")
		)
		(fp_line
			(start 1.524 0.7366)
			(end -1.524 0.7366)
			(stroke
				(width 0.1)
				(type default)
			)
			(layer "B.Fab")
		)
		(fp_line
			(start 1.56083 -0.738632)
			(end 1.56083 0.7366)
			(stroke
				(width 0.1)
				(type default)
			)
			(layer "B.Fab")
		)
		(fp_line
			(start 1.56083 0.7366)
			(end 1.524 0.7366)
			(stroke
				(width 0.1)
				(type default)
			)
			(layer "B.Fab")
		)
		(pad "1" smd rect
			(at 0.94996 0)
			(size 1.1176 1.3716)
			(layers "B.Cu" "B.Mask" "B.Paste")
			(net "P1V8_CPU0_RT_1D")
		)
		(pad "2" smd rect
			(at -0.94996 0)
			(size 1.1176 1.3716)
			(layers "B.Cu" "B.Mask" "B.Paste")
			(net "P1V8_CPU0_RT1_1A")
		)
	)
	(footprint ""
		(layer "B.Cu")
		(at 367.544858 -142.574772 180)
		(property "Reference" "PR285"
			(at 0 0 0)
			(layer "B.SilkS")
			(hide yes)
			(effects
				(font
					(size 1.27 1.27)
				)
				(justify mirror)
			)
		)
		(property "Value" ""
			(at 0 0 0)
			(layer "B.Fab")
			(effects
				(font
					(size 1.27 1.27)
				)
				(justify mirror)
			)
		)
		(duplicate_pad_numbers_are_jumpers no)
		(fp_line
			(start 0.7874 0.4064)
			(end 0.7874 -0.4064)
			(stroke
				(width 0.1524)
				(type default)
			)
			(layer "B.SilkS")
		)
		(fp_line
			(start 0.7874 -0.4064)
			(end -0.7874 -0.4064)
			(stroke
				(width 0.1524)
				(type default)
			)
			(layer "B.SilkS")
		)
		(fp_line
			(start -0.7874 0.4064)
			(end 0.7874 0.4064)
			(stroke
				(width 0.1524)
				(type default)
			)
			(layer "B.SilkS")
		)
		(fp_line
			(start -0.7874 -0.4064)
			(end -0.7874 0.4064)
			(stroke
				(width 0.1524)
				(type default)
			)
			(layer "B.SilkS")
		)
		(fp_line
			(start 0.67945 0.3048)
			(end 0.67945 -0.305054)
			(stroke
				(width 0.1)
				(type default)
			)
			(layer "B.Fab")
		)
		(fp_line
			(start 0.67945 -0.305054)
			(end 0.12065 -0.305054)
			(stroke
				(width 0.1)
				(type default)
			)
			(layer "B.Fab")
		)
		(fp_line
			(start 0.12065 0.3048)
			(end 0.67945 0.3048)
			(stroke
				(width 0.1)
				(type default)
			)
			(layer "B.Fab")
		)
		(fp_line
			(start 0.12065 0.2794)
			(end 0.12065 0.3048)
			(stroke
				(width 0.1)
				(type default)
			)
			(layer "B.Fab")
		)
		(fp_line
			(start 0.12065 -0.2794)
			(end -0.12065 -0.2794)
			(stroke
				(width 0.1)
				(type default)
			)
			(layer "B.Fab")
		)
		(fp_line
			(start 0.12065 -0.305054)
			(end 0.12065 -0.2794)
			(stroke
				(width 0.1)
				(type default)
			)
			(layer "B.Fab")
		)
		(fp_line
			(start -0.120396 0.3048)
			(end -0.120396 0.2794)
			(stroke
				(width 0.1)
				(type default)
			)
			(layer "B.Fab")
		)
		(fp_line
			(start -0.120396 0.2794)
			(end 0.12065 0.2794)
			(stroke
				(width 0.1)
				(type default)
			)
			(layer "B.Fab")
		)
		(fp_line
			(start -0.12065 -0.2794)
			(end -0.12065 -0.3048)
			(stroke
				(width 0.1)
				(type default)
			)
			(layer "B.Fab")
		)
		(fp_line
			(start -0.12065 -0.3048)
			(end -0.67945 -0.3048)
			(stroke
				(width 0.1)
				(type default)
			)
			(layer "B.Fab")
		)
		(fp_line
			(start -0.67945 0.3048)
			(end -0.120396 0.3048)
			(stroke
				(width 0.1)
				(type default)
			)
			(layer "B.Fab")
		)
		(fp_line
			(start -0.67945 -0.3048)
			(end -0.67945 0.3048)
			(stroke
				(width 0.1)
				(type default)
			)
			(layer "B.Fab")
		)
		(pad "1" smd circle
			(at 0.40005 0)
			(size 0 0)
			(layers "B.Cu" "B.Mask" "B.Paste")
			(net "P3V3_AUX")
		)
		(pad "2" smd circle
			(at -0.40005 0)
			(size 0 0)
			(layers "B.Cu" "B.Mask" "B.Paste")
			(net "PVDDCR_SOC_P0_EN_GD")
		)
	)
	(footprint ""
		(layer "B.Cu")
		(at 228.420422 -329.698858 180)
		(property "Reference" "C1090"
			(at 0 0 0)
			(layer "B.SilkS")
			(hide yes)
			(effects
				(font
					(size 1.27 1.27)
				)
				(justify mirror)
			)
		)
		(property "Value" ""
			(at 0 0 0)
			(layer "B.Fab")
			(effects
				(font
					(size 1.27 1.27)
				)
				(justify mirror)
			)
		)
		(duplicate_pad_numbers_are_jumpers no)
		(fp_line
			(start 0.7874 0.4064)
			(end 0.7874 -0.4064)
			(stroke
				(width 0.1524)
				(type default)
			)
			(layer "B.SilkS")
		)
		(fp_line
			(start 0.7874 -0.4064)
			(end -0.7874 -0.4064)
			(stroke
				(width 0.1524)
				(type default)
			)
			(layer "B.SilkS")
		)
		(fp_line
			(start -0.7874 0.4064)
			(end 0.7874 0.4064)
			(stroke
				(width 0.1524)
				(type default)
			)
			(layer "B.SilkS")
		)
		(fp_line
			(start -0.7874 -0.4064)
			(end -0.7874 0.4064)
			(stroke
				(width 0.1524)
				(type default)
			)
			(layer "B.SilkS")
		)
		(fp_line
			(start 0.67945 0.3048)
			(end 0.67945 -0.305054)
			(stroke
				(width 0.1)
				(type default)
			)
			(layer "B.Fab")
		)
		(fp_line
			(start 0.67945 -0.305054)
			(end 0.12065 -0.305054)
			(stroke
				(width 0.1)
				(type default)
			)
			(layer "B.Fab")
		)
		(fp_line
			(start 0.12065 0.3048)
			(end 0.67945 0.3048)
			(stroke
				(width 0.1)
				(type default)
			)
			(layer "B.Fab")
		)
		(fp_line
			(start 0.12065 0.2794)
			(end 0.12065 0.3048)
			(stroke
				(width 0.1)
				(type default)
			)
			(layer "B.Fab")
		)
		(fp_line
			(start 0.12065 -0.2794)
			(end -0.12065 -0.2794)
			(stroke
				(width 0.1)
				(type default)
			)
			(layer "B.Fab")
		)
		(fp_line
			(start 0.12065 -0.305054)
			(end 0.12065 -0.2794)
			(stroke
				(width 0.1)
				(type default)
			)
			(layer "B.Fab")
		)
		(fp_line
			(start -0.120396 0.3048)
			(end -0.120396 0.2794)
			(stroke
				(width 0.1)
				(type default)
			)
			(layer "B.Fab")
		)
		(fp_line
			(start -0.120396 0.2794)
			(end 0.12065 0.2794)
			(stroke
				(width 0.1)
				(type default)
			)
			(layer "B.Fab")
		)
		(fp_line
			(start -0.12065 -0.2794)
			(end -0.12065 -0.3048)
			(stroke
				(width 0.1)
				(type default)
			)
			(layer "B.Fab")
		)
		(fp_line
			(start -0.12065 -0.3048)
			(end -0.67945 -0.3048)
			(stroke
				(width 0.1)
				(type default)
			)
			(layer "B.Fab")
		)
		(fp_line
			(start -0.67945 0.3048)
			(end -0.120396 0.3048)
			(stroke
				(width 0.1)
				(type default)
			)
			(layer "B.Fab")
		)
		(fp_line
			(start -0.67945 -0.3048)
			(end -0.67945 0.3048)
			(stroke
				(width 0.1)
				(type default)
			)
			(layer "B.Fab")
		)
		(pad "1" smd circle
			(at 0.40005 0)
			(size 0 0)
			(layers "B.Cu" "B.Mask" "B.Paste")
			(net "PVDD18_S5_P1_ADC_TIC")
		)
		(pad "2" smd circle
			(at -0.40005 0)
			(size 0 0)
			(layers "B.Cu" "B.Mask" "B.Paste")
			(net "GND")
		)
	)
	(footprint ""
		(layer "B.Cu")
		(at 102.783386 -266.005564)
		(property "Reference" "C2115"
			(at 0 0 0)
			(layer "B.SilkS")
			(hide yes)
			(effects
				(font
					(size 1.27 1.27)
				)
				(justify mirror)
			)
		)
		(property "Value" ""
			(at 0 0 0)
			(layer "B.Fab")
			(effects
				(font
					(size 1.27 1.27)
				)
				(justify mirror)
			)
		)
		(duplicate_pad_numbers_are_jumpers no)
		(fp_line
			(start -0.7874 -0.4064)
			(end -0.7874 0.4064)
			(stroke
				(width 0.1524)
				(type default)
			)
			(layer "B.SilkS")
		)
		(fp_line
			(start -0.7874 0.4064)
			(end 0.7874 0.4064)
			(stroke
				(width 0.1524)
				(type default)
			)
			(layer "B.SilkS")
		)
		(fp_line
			(start 0.7874 -0.4064)
			(end -0.7874 -0.4064)
			(stroke
				(width 0.1524)
				(type default)
			)
			(layer "B.SilkS")
		)
		(fp_line
			(start 0.7874 0.4064)
			(end 0.7874 -0.4064)
			(stroke
				(width 0.1524)
				(type default)
			)
			(layer "B.SilkS")
		)
		(fp_line
			(start -0.67945 -0.3048)
			(end -0.67945 0.3048)
			(stroke
				(width 0.1)
				(type default)
			)
			(layer "B.Fab")
		)
		(fp_line
			(start -0.67945 0.3048)
			(end -0.120396 0.3048)
			(stroke
				(width 0.1)
				(type default)
			)
			(layer "B.Fab")
		)
		(fp_line
			(start -0.12065 -0.3048)
			(end -0.67945 -0.3048)
			(stroke
				(width 0.1)
				(type default)
			)
			(layer "B.Fab")
		)
		(fp_line
			(start -0.12065 -0.2794)
			(end -0.12065 -0.3048)
			(stroke
				(width 0.1)
				(type default)
			)
			(layer "B.Fab")
		)
		(fp_line
			(start -0.120396 0.2794)
			(end 0.12065 0.2794)
			(stroke
				(width 0.1)
				(type default)
			)
			(layer "B.Fab")
		)
		(fp_line
			(start -0.120396 0.3048)
			(end -0.120396 0.2794)
			(stroke
				(width 0.1)
				(type default)
			)
			(layer "B.Fab")
		)
		(fp_line
			(start 0.12065 -0.305054)
			(end 0.12065 -0.2794)
			(stroke
				(width 0.1)
				(type default)
			)
			(layer "B.Fab")
		)
		(fp_line
			(start 0.12065 -0.2794)
			(end -0.12065 -0.2794)
			(stroke
				(width 0.1)
				(type default)
			)
			(layer "B.Fab")
		)
		(fp_line
			(start 0.12065 0.2794)
			(end 0.12065 0.3048)
			(stroke
				(width 0.1)
				(type default)
			)
			(layer "B.Fab")
		)
		(fp_line
			(start 0.12065 0.3048)
			(end 0.67945 0.3048)
			(stroke
				(width 0.1)
				(type default)
			)
			(layer "B.Fab")
		)
		(fp_line
			(start 0.67945 -0.305054)
			(end 0.12065 -0.305054)
			(stroke
				(width 0.1)
				(type default)
			)
			(layer "B.Fab")
		)
		(fp_line
			(start 0.67945 0.3048)
			(end 0.67945 -0.305054)
			(stroke
				(width 0.1)
				(type default)
			)
			(layer "B.Fab")
		)
		(pad "1" smd circle
			(at 0.40005 0 180)
			(size 0 0)
			(layers "B.Cu" "B.Mask" "B.Paste")
			(net "PVDD11_S3_P1")
		)
		(pad "2" smd circle
			(at -0.40005 0 180)
			(size 0 0)
			(layers "B.Cu" "B.Mask" "B.Paste")
			(net "GND")
		)
	)
	(footprint ""
		(layer "B.Cu")
		(at 131.29133 -390.560052 90)
		(property "Reference" "C494"
			(at 0 0 90)
			(layer "B.SilkS")
			(hide yes)
			(effects
				(font
					(size 1.27 1.27)
				)
				(justify mirror)
			)
		)
		(property "Value" ""
			(at 0 0 90)
			(layer "B.Fab")
			(effects
				(font
					(size 1.27 1.27)
				)
				(justify mirror)
			)
		)
		(duplicate_pad_numbers_are_jumpers no)
		(fp_line
			(start 0.7874 -0.4064)
			(end -0.7874 -0.4064)
			(stroke
				(width 0.1524)
				(type default)
			)
			(layer "B.SilkS")
		)
		(fp_line
			(start -0.7874 -0.4064)
			(end -0.7874 0.4064)
			(stroke
				(width 0.1524)
				(type default)
			)
			(layer "B.SilkS")
		)
		(fp_line
			(start 0.7874 0.4064)
			(end 0.7874 -0.4064)
			(stroke
				(width 0.1524)
				(type default)
			)
			(layer "B.SilkS")
		)
		(fp_line
			(start -0.7874 0.4064)
			(end 0.7874 0.4064)
			(stroke
				(width 0.1524)
				(type default)
			)
			(layer "B.SilkS")
		)
		(fp_line
			(start 0.67945 -0.305054)
			(end 0.12065 -0.305054)
			(stroke
				(width 0.1)
				(type default)
			)
			(layer "B.Fab")
		)
		(fp_line
			(start 0.12065 -0.305054)
			(end 0.12065 -0.2794)
			(stroke
				(width 0.1)
				(type default)
			)
			(layer "B.Fab")
		)
		(fp_line
			(start -0.12065 -0.3048)
			(end -0.67945 -0.3048)
			(stroke
				(width 0.1)
				(type default)
			)
			(layer "B.Fab")
		)
		(fp_line
			(start -0.67945 -0.3048)
			(end -0.67945 0.3048)
			(stroke
				(width 0.1)
				(type default)
			)
			(layer "B.Fab")
		)
		(fp_line
			(start 0.12065 -0.2794)
			(end -0.12065 -0.2794)
			(stroke
				(width 0.1)
				(type default)
			)
			(layer "B.Fab")
		)
		(fp_line
			(start -0.12065 -0.2794)
			(end -0.12065 -0.3048)
			(stroke
				(width 0.1)
				(type default)
			)
			(layer "B.Fab")
		)
		(fp_line
			(start 0.12065 0.2794)
			(end 0.12065 0.3048)
			(stroke
				(width 0.1)
				(type default)
			)
			(layer "B.Fab")
		)
		(fp_line
			(start -0.120396 0.2794)
			(end 0.12065 0.2794)
			(stroke
				(width 0.1)
				(type default)
			)
			(layer "B.Fab")
		)
		(fp_line
			(start 0.67945 0.3048)
			(end 0.67945 -0.305054)
			(stroke
				(width 0.1)
				(type default)
			)
			(layer "B.Fab")
		)
		(fp_line
			(start 0.12065 0.3048)
			(end 0.67945 0.3048)
			(stroke
				(width 0.1)
				(type default)
			)
			(layer "B.Fab")
		)
		(fp_line
			(start -0.120396 0.3048)
			(end -0.120396 0.2794)
			(stroke
				(width 0.1)
				(type default)
			)
			(layer "B.Fab")
		)
		(fp_line
			(start -0.67945 0.3048)
			(end -0.120396 0.3048)
			(stroke
				(width 0.1)
				(type default)
			)
			(layer "B.Fab")
		)
		(pad "1" smd circle
			(at 0.40005 0 270)
			(size 0 0)
			(layers "B.Cu" "B.Mask" "B.Paste")
			(net "P0V9_CPU1_RT3_2A")
		)
		(pad "2" smd circle
			(at -0.40005 0 270)
			(size 0 0)
			(layers "B.Cu" "B.Mask" "B.Paste")
			(net "GND")
		)
	)
	(footprint ""
		(layer "B.Cu")
		(at 391.636758 -202.48499)
		(property "Reference" "R6083"
			(at 0 0 0)
			(layer "B.SilkS")
			(hide yes)
			(effects
				(font
					(size 1.27 1.27)
				)
				(justify mirror)
			)
		)
		(property "Value" ""
			(at 0 0 0)
			(layer "B.Fab")
			(effects
				(font
					(size 1.27 1.27)
				)
				(justify mirror)
			)
		)
		(duplicate_pad_numbers_are_jumpers no)
		(fp_line
			(start -0.7874 -0.4064)
			(end -0.7874 0.4064)
			(stroke
				(width 0.1524)
				(type default)
			)
			(layer "B.SilkS")
		)
		(fp_line
			(start -0.7874 0.4064)
			(end 0.7874 0.4064)
			(stroke
				(width 0.1524)
				(type default)
			)
			(layer "B.SilkS")
		)
		(fp_line
			(start 0.7874 -0.4064)
			(end -0.7874 -0.4064)
			(stroke
				(width 0.1524)
				(type default)
			)
			(layer "B.SilkS")
		)
		(fp_line
			(start 0.7874 0.4064)
			(end 0.7874 -0.4064)
			(stroke
				(width 0.1524)
				(type default)
			)
			(layer "B.SilkS")
		)
		(fp_line
			(start -0.67945 -0.3048)
			(end -0.67945 0.3048)
			(stroke
				(width 0.1)
				(type default)
			)
			(layer "B.Fab")
		)
		(fp_line
			(start -0.67945 0.3048)
			(end -0.120396 0.3048)
			(stroke
				(width 0.1)
				(type default)
			)
			(layer "B.Fab")
		)
		(fp_line
			(start -0.12065 -0.3048)
			(end -0.67945 -0.3048)
			(stroke
				(width 0.1)
				(type default)
			)
			(layer "B.Fab")
		)
		(fp_line
			(start -0.12065 -0.2794)
			(end -0.12065 -0.3048)
			(stroke
				(width 0.1)
				(type default)
			)
			(layer "B.Fab")
		)
		(fp_line
			(start -0.120396 0.2794)
			(end 0.12065 0.2794)
			(stroke
				(width 0.1)
				(type default)
			)
			(layer "B.Fab")
		)
		(fp_line
			(start -0.120396 0.3048)
			(end -0.120396 0.2794)
			(stroke
				(width 0.1)
				(type default)
			)
			(layer "B.Fab")
		)
		(fp_line
			(start 0.12065 -0.305054)
			(end 0.12065 -0.2794)
			(stroke
				(width 0.1)
				(type default)
			)
			(layer "B.Fab")
		)
		(fp_line
			(start 0.12065 -0.2794)
			(end -0.12065 -0.2794)
			(stroke
				(width 0.1)
				(type default)
			)
			(layer "B.Fab")
		)
		(fp_line
			(start 0.12065 0.2794)
			(end 0.12065 0.3048)
			(stroke
				(width 0.1)
				(type default)
			)
			(layer "B.Fab")
		)
		(fp_line
			(start 0.12065 0.3048)
			(end 0.67945 0.3048)
			(stroke
				(width 0.1)
				(type default)
			)
			(layer "B.Fab")
		)
		(fp_line
			(start 0.67945 -0.305054)
			(end 0.12065 -0.305054)
			(stroke
				(width 0.1)
				(type default)
			)
			(layer "B.Fab")
		)
		(fp_line
			(start 0.67945 0.3048)
			(end 0.67945 -0.305054)
			(stroke
				(width 0.1)
				(type default)
			)
			(layer "B.Fab")
		)
		(pad "1" smd circle
			(at 0.40005 0 180)
			(size 0 0)
			(layers "B.Cu" "B.Mask" "B.Paste")
			(net "PVDD11_S3_P0")
		)
		(pad "2" smd circle
			(at -0.40005 0 180)
			(size 0 0)
			(layers "B.Cu" "B.Mask" "B.Paste")
			(net "SMB_CPU0_3_SCL")
		)
	)
	(footprint ""
		(layer "B.Cu")
		(at 18.841974 -373.339614 90)
		(property "Reference" "PC6627"
			(at -3.642614 -2.993644 270)
			(unlocked yes)
			(layer "B.SilkS")
			(effects
				(font
					(size 0.7874 0.5842)
					(thickness 0.1524)
				)
				(justify left mirror)
			)
		)
		(property "Value" ""
			(at 0 0 90)
			(layer "B.Fab")
			(effects
				(font
					(size 1.27 1.27)
				)
				(justify mirror)
			)
		)
		(duplicate_pad_numbers_are_jumpers no)
		(fp_line
			(start 4.84378 -2.150618)
			(end 4.53898 -2.150618)
			(stroke
				(width 0.1524)
				(type default)
			)
			(layer "B.SilkS")
		)
		(fp_line
			(start 4.84378 -2.150618)
			(end 4.842256 2.163064)
			(stroke
				(width 0.1524)
				(type default)
			)
			(layer "B.SilkS")
		)
		(fp_line
			(start 4.69138 -2.150618)
			(end 4.692396 2.161032)
			(stroke
				(width 0.1524)
				(type default)
			)
			(layer "B.SilkS")
		)
		(fp_line
			(start 4.53898 -2.150618)
			(end 4.539742 2.152142)
			(stroke
				(width 0.1524)
				(type default)
			)
			(layer "B.SilkS")
		)
		(fp_line
			(start 4.53898 -2.15011)
			(end -4.53898 -2.15011)
			(stroke
				(width 0.1524)
				(type default)
			)
			(layer "B.SilkS")
		)
		(fp_line
			(start -4.53898 -2.15011)
			(end -4.53898 2.15011)
			(stroke
				(width 0.1524)
				(type default)
			)
			(layer "B.SilkS")
		)
		(fp_line
			(start 4.53898 2.15011)
			(end 4.53898 -2.15011)
			(stroke
				(width 0.1524)
				(type default)
			)
			(layer "B.SilkS")
		)
		(fp_line
			(start -4.53898 2.15011)
			(end 4.53898 2.15011)
			(stroke
				(width 0.1524)
				(type default)
			)
			(layer "B.SilkS")
		)
		(fp_line
			(start 4.83108 2.150364)
			(end 4.447794 2.149348)
			(stroke
				(width 0.1524)
				(type default)
			)
			(layer "B.SilkS")
		)
		(fp_line
			(start 3.64998 -2.15011)
			(end -3.64998 -2.15011)
			(stroke
				(width 0.1)
				(type default)
			)
			(layer "B.Fab")
		)
		(fp_line
			(start -3.64998 -2.15011)
			(end -3.64998 2.15011)
			(stroke
				(width 0.1)
				(type default)
			)
			(layer "B.Fab")
		)
		(fp_line
			(start 3.64998 2.15011)
			(end 3.64998 -2.15011)
			(stroke
				(width 0.1)
				(type default)
			)
			(layer "B.Fab")
		)
		(fp_line
			(start -3.64998 2.15011)
			(end 3.64998 2.15011)
			(stroke
				(width 0.1)
				(type default)
			)
			(layer "B.Fab")
		)
		(fp_text user "+"
			(at 6.338824 -1.180084 90)
			(unlocked yes)
			(layer "B.SilkS")
			(effects
				(font
					(size 1.905 1.4224)
					(thickness 0.1524)
				)
				(justify left mirror)
			)
		)
		(fp_text user "-"
			(at -4.313174 -0.094488 90)
			(unlocked yes)
			(layer "B.SilkS")
			(effects
				(font
					(size 1.905 1.4224)
					(thickness 0.1524)
				)
				(justify left mirror)
			)
		)
		(fp_text user "+"
			(at 6.214872 -0.337058 90)
			(unlocked yes)
			(layer "B.Fab")
			(effects
				(font
					(size 1.905 1.4224)
					(thickness 0.1524)
				)
				(justify left mirror)
			)
		)
		(fp_text user "-"
			(at -4.313174 -0.094488 90)
			(unlocked yes)
			(layer "B.Fab")
			(effects
				(font
					(size 1.905 1.4224)
					(thickness 0.1524)
				)
				(justify left mirror)
			)
		)
		(pad "1" smd rect
			(at 3.199892 0 270)
			(size 2.413 2.8194)
			(layers "B.Cu" "B.Mask" "B.Paste")
			(net "P0V9_CPU1_RT_2D")
		)
		(pad "2" smd rect
			(at -3.199892 0 270)
			(size 2.413 2.8194)
			(layers "B.Cu" "B.Mask" "B.Paste")
			(net "GND")
		)
	)
	(footprint ""
		(layer "B.Cu")
		(at 100.628704 -331.279754 -90)
		(property "Reference" "PC149_6"
			(at 0 0 90)
			(layer "B.SilkS")
			(hide yes)
			(effects
				(font
					(size 1.27 1.27)
				)
				(justify mirror)
			)
		)
		(property "Value" ""
			(at 0 0 90)
			(layer "B.Fab")
			(effects
				(font
					(size 1.27 1.27)
				)
				(justify mirror)
			)
		)
		(duplicate_pad_numbers_are_jumpers no)
		(fp_line
			(start -1.524 0.762)
			(end 1.524 0.762)
			(stroke
				(width 0.1524)
				(type default)
			)
			(layer "B.SilkS")
		)
		(fp_line
			(start 1.524 0.762)
			(end 1.524 -0.762)
			(stroke
				(width 0.1524)
				(type default)
			)
			(layer "B.SilkS")
		)
		(fp_line
			(start -1.524 -0.762)
			(end -1.524 0.762)
			(stroke
				(width 0.1524)
				(type default)
			)
			(layer "B.SilkS")
		)
		(fp_line
			(start 1.524 -0.762)
			(end -1.524 -0.762)
			(stroke
				(width 0.1524)
				(type default)
			)
			(layer "B.SilkS")
		)
		(fp_line
			(start -1.1049 0.724916)
			(end -1.1049 -0.724916)
			(stroke
				(width 0.1)
				(type default)
			)
			(layer "B.Fab")
		)
		(fp_line
			(start 1.1049 0.724916)
			(end -1.1049 0.724916)
			(stroke
				(width 0.1)
				(type default)
			)
			(layer "B.Fab")
		)
		(fp_line
			(start -1.1049 -0.724916)
			(end 1.1049 -0.724916)
			(stroke
				(width 0.1)
				(type default)
			)
			(layer "B.Fab")
		)
		(fp_line
			(start 1.1049 -0.724916)
			(end 1.1049 0.724916)
			(stroke
				(width 0.1)
				(type default)
			)
			(layer "B.Fab")
		)
		(pad "1" smd rect
			(at 0.889 0 270)
			(size 1.016 1.27)
			(layers "B.Cu" "B.Mask" "B.Paste")
			(net "PVDDCR_CPU1_P1")
		)
		(pad "2" smd rect
			(at -0.889 0 270)
			(size 1.016 1.27)
			(layers "B.Cu" "B.Mask" "B.Paste")
			(net "GND")
		)
	)
	(footprint ""
		(layer "B.Cu")
		(at 188.849 -422.402)
		(property "Reference" "R8107"
			(at 0 0 0)
			(layer "B.SilkS")
			(hide yes)
			(effects
				(font
					(size 1.27 1.27)
				)
				(justify mirror)
			)
		)
		(property "Value" ""
			(at 0 0 0)
			(layer "B.Fab")
			(effects
				(font
					(size 1.27 1.27)
				)
				(justify mirror)
			)
		)
		(duplicate_pad_numbers_are_jumpers no)
		(fp_line
			(start -0.7874 -0.4064)
			(end -0.7874 0.4064)
			(stroke
				(width 0.1524)
				(type default)
			)
			(layer "B.SilkS")
		)
		(fp_line
			(start -0.7874 0.4064)
			(end 0.7874 0.4064)
			(stroke
				(width 0.1524)
				(type default)
			)
			(layer "B.SilkS")
		)
		(fp_line
			(start 0.7874 -0.4064)
			(end -0.7874 -0.4064)
			(stroke
				(width 0.1524)
				(type default)
			)
			(layer "B.SilkS")
		)
		(fp_line
			(start 0.7874 0.4064)
			(end 0.7874 -0.4064)
			(stroke
				(width 0.1524)
				(type default)
			)
			(layer "B.SilkS")
		)
		(fp_line
			(start -0.67945 -0.3048)
			(end -0.67945 0.3048)
			(stroke
				(width 0.1)
				(type default)
			)
			(layer "B.Fab")
		)
		(fp_line
			(start -0.67945 0.3048)
			(end -0.120396 0.3048)
			(stroke
				(width 0.1)
				(type default)
			)
			(layer "B.Fab")
		)
		(fp_line
			(start -0.12065 -0.3048)
			(end -0.67945 -0.3048)
			(stroke
				(width 0.1)
				(type default)
			)
			(layer "B.Fab")
		)
		(fp_line
			(start -0.12065 -0.2794)
			(end -0.12065 -0.3048)
			(stroke
				(width 0.1)
				(type default)
			)
			(layer "B.Fab")
		)
		(fp_line
			(start -0.120396 0.2794)
			(end 0.12065 0.2794)
			(stroke
				(width 0.1)
				(type default)
			)
			(layer "B.Fab")
		)
		(fp_line
			(start -0.120396 0.3048)
			(end -0.120396 0.2794)
			(stroke
				(width 0.1)
				(type default)
			)
			(layer "B.Fab")
		)
		(fp_line
			(start 0.12065 -0.305054)
			(end 0.12065 -0.2794)
			(stroke
				(width 0.1)
				(type default)
			)
			(layer "B.Fab")
		)
		(fp_line
			(start 0.12065 -0.2794)
			(end -0.12065 -0.2794)
			(stroke
				(width 0.1)
				(type default)
			)
			(layer "B.Fab")
		)
		(fp_line
			(start 0.12065 0.2794)
			(end 0.12065 0.3048)
			(stroke
				(width 0.1)
				(type default)
			)
			(layer "B.Fab")
		)
		(fp_line
			(start 0.12065 0.3048)
			(end 0.67945 0.3048)
			(stroke
				(width 0.1)
				(type default)
			)
			(layer "B.Fab")
		)
		(fp_line
			(start 0.67945 -0.305054)
			(end 0.12065 -0.305054)
			(stroke
				(width 0.1)
				(type default)
			)
			(layer "B.Fab")
		)
		(fp_line
			(start 0.67945 0.3048)
			(end 0.67945 -0.305054)
			(stroke
				(width 0.1)
				(type default)
			)
			(layer "B.Fab")
		)
		(pad "1" smd circle
			(at 0.40005 0 180)
			(size 0 0)
			(layers "B.Cu" "B.Mask" "B.Paste")
			(net "P3V3_AUX")
		)
		(pad "2" smd circle
			(at -0.40005 0 180)
			(size 0 0)
			(layers "B.Cu" "B.Mask" "B.Paste")
			(net "OC_P2V5_COMP")
		)
	)
	(footprint ""
		(layer "B.Cu")
		(at 210.83905 -69.530468)
		(property "Reference" "U7"
			(at 2.032 -3.27533 0)
			(unlocked yes)
			(layer "B.SilkS")
			(effects
				(font
					(size 0.7874 0.5842)
					(thickness 0.1524)
				)
				(justify left mirror)
			)
		)
		(property "Value" ""
			(at 0 0 0)
			(layer "B.Fab")
			(effects
				(font
					(size 1.27 1.27)
				)
				(justify mirror)
			)
		)
		(duplicate_pad_numbers_are_jumpers no)
		(fp_line
			(start -2.0066 -2.5527)
			(end -2.0066 2.5527)
			(stroke
				(width 0.1524)
				(type default)
			)
			(layer "B.SilkS")
		)
		(fp_line
			(start -2.0066 2.5527)
			(end 2.0066 2.5527)
			(stroke
				(width 0.1524)
				(type default)
			)
			(layer "B.SilkS")
		)
		(fp_line
			(start -0.5715 -2.5527)
			(end -2.0066 -2.5527)
			(stroke
				(width 0.1524)
				(type default)
			)
			(layer "B.SilkS")
		)
		(fp_line
			(start 0 -1.9812)
			(end -0.5715 -2.5527)
			(stroke
				(width 0.1524)
				(type default)
			)
			(layer "B.SilkS")
		)
		(fp_line
			(start 0.5715 -2.5527)
			(end 0 -1.9812)
			(stroke
				(width 0.1524)
				(type default)
			)
			(layer "B.SilkS")
		)
		(fp_line
			(start 2.0066 -2.5527)
			(end 0.5715 -2.5527)
			(stroke
				(width 0.1524)
				(type default)
			)
			(layer "B.SilkS")
		)
		(fp_line
			(start 2.0066 2.5527)
			(end 2.0066 -2.5527)
			(stroke
				(width 0.1524)
				(type default)
			)
			(layer "B.SilkS")
		)
		(fp_poly
			(pts
				(xy 3.179318 -2.37617) (xy 2.893822 -2.953258) (xy 3.516884 -2.906014)
			)
			(stroke
				(width 0)
				(type default)
			)
			(fill yes)
			(layer "B.SilkS")
		)
		(fp_line
			(start -2.249932 -2.549906)
			(end -2.249932 2.549906)
			(stroke
				(width 0.1)
				(type default)
			)
			(layer "B.Fab")
		)
		(fp_line
			(start -2.249932 2.549906)
			(end 2.249932 2.549906)
			(stroke
				(width 0.1)
				(type default)
			)
			(layer "B.Fab")
		)
		(fp_line
			(start 2.249932 -2.549906)
			(end -2.249932 -2.549906)
			(stroke
				(width 0.1)
				(type default)
			)
			(layer "B.Fab")
		)
		(fp_line
			(start 2.249932 2.549906)
			(end 2.249932 -2.549906)
			(stroke
				(width 0.1)
				(type default)
			)
			(layer "B.Fab")
		)
		(fp_poly
			(pts
				(xy 4.36372 -1.608328) (xy 4.36372 -2.233168) (xy 3.81 -1.905)
			)
			(stroke
				(width 0)
				(type default)
			)
			(fill yes)
			(layer "B.Fab")
		)
		(pad "1" smd rect
			(at 2.921 -1.949958 270)
			(size 0.3556 1.4986)
			(layers "B.Cu" "B.Mask" "B.Paste")
			(net "FB_BMC_ISOLATE")
		)
		(pad "2" smd rect
			(at 2.921 -1.299972 270)
			(size 0.3556 1.4986)
			(layers "B.Cu" "B.Mask" "B.Paste")
			(net "NCSI_BMC_TXD1_R")
		)
		(pad "3" smd rect
			(at 2.921 -0.649986 270)
			(size 0.3556 1.4986)
			(layers "B.Cu" "B.Mask" "B.Paste")
			(net "NCSI_OCP_SFF_TXD1")
		)
		(pad "4" smd rect
			(at 2.921 0 270)
			(size 0.3556 1.4986)
			(layers "B.Cu" "B.Mask" "B.Paste")
			(net "FB_BMC_ISOLATE")
		)
		(pad "5" smd rect
			(at 2.921 0.649986 270)
			(size 0.3556 1.4986)
			(layers "B.Cu" "B.Mask" "B.Paste")
			(net "NCSI_BMC_TXD0_R")
		)
		(pad "6" smd rect
			(at 2.921 1.299972 270)
			(size 0.3556 1.4986)
			(layers "B.Cu" "B.Mask" "B.Paste")
			(net "NCSI_OCP_SFF_TXD0")
		)
		(pad "7" smd rect
			(at 2.921 1.949958 270)
			(size 0.3556 1.4986)
			(layers "B.Cu" "B.Mask" "B.Paste")
			(net "GND")
		)
		(pad "8" smd rect
			(at -2.921 1.949958 270)
			(size 0.3556 1.4986)
			(layers "B.Cu" "B.Mask" "B.Paste")
			(net "NCSI_OCP_SFF_TX_EN")
		)
		(pad "9" smd rect
			(at -2.921 1.299972 270)
			(size 0.3556 1.4986)
			(layers "B.Cu" "B.Mask" "B.Paste")
			(net "NCSI_BMC_TX_EN_R")
		)
		(pad "10" smd rect
			(at -2.921 0.649986 270)
			(size 0.3556 1.4986)
			(layers "B.Cu" "B.Mask" "B.Paste")
			(net "FB_BMC_ISOLATE")
		)
		(pad "11" smd rect
			(at -2.921 0 270)
			(size 0.3556 1.4986)
			(layers "B.Cu" "B.Mask" "B.Paste")
			(net "OCP_SFF_ISO2_RBT_ARB_OUT")
		)
		(pad "12" smd rect
			(at -2.921 -0.649986 270)
			(size 0.3556 1.4986)
			(layers "B.Cu" "B.Mask" "B.Paste")
			(net "OCP_SFF_RBT_ARB_OUT")
		)
		(pad "13" smd rect
			(at -2.921 -1.299972 270)
			(size 0.3556 1.4986)
			(layers "B.Cu" "B.Mask" "B.Paste")
			(net "FB_BMC_ISOLATE")
		)
		(pad "14" smd rect
			(at -2.921 -1.949958 270)
			(size 0.3556 1.4986)
			(layers "B.Cu" "B.Mask" "B.Paste")
			(net "P3V3_AUX")
		)
	)
	(footprint ""
		(layer "B.Cu")
		(at 346.532454 -256.73431 180)
		(property "Reference" "C2625"
			(at 0 0 0)
			(layer "B.SilkS")
			(hide yes)
			(effects
				(font
					(size 1.27 1.27)
				)
				(justify mirror)
			)
		)
		(property "Value" ""
			(at 0 0 0)
			(layer "B.Fab")
			(effects
				(font
					(size 1.27 1.27)
				)
				(justify mirror)
			)
		)
		(duplicate_pad_numbers_are_jumpers no)
		(fp_line
			(start 0.7874 0.4064)
			(end 0.7874 -0.4064)
			(stroke
				(width 0.1524)
				(type default)
			)
			(layer "B.SilkS")
		)
		(fp_line
			(start 0.7874 -0.4064)
			(end -0.7874 -0.4064)
			(stroke
				(width 0.1524)
				(type default)
			)
			(layer "B.SilkS")
		)
		(fp_line
			(start -0.7874 0.4064)
			(end 0.7874 0.4064)
			(stroke
				(width 0.1524)
				(type default)
			)
			(layer "B.SilkS")
		)
		(fp_line
			(start -0.7874 -0.4064)
			(end -0.7874 0.4064)
			(stroke
				(width 0.1524)
				(type default)
			)
			(layer "B.SilkS")
		)
		(fp_line
			(start 0.67945 0.3048)
			(end 0.67945 -0.305054)
			(stroke
				(width 0.1)
				(type default)
			)
			(layer "B.Fab")
		)
		(fp_line
			(start 0.67945 -0.305054)
			(end 0.12065 -0.305054)
			(stroke
				(width 0.1)
				(type default)
			)
			(layer "B.Fab")
		)
		(fp_line
			(start 0.12065 0.3048)
			(end 0.67945 0.3048)
			(stroke
				(width 0.1)
				(type default)
			)
			(layer "B.Fab")
		)
		(fp_line
			(start 0.12065 0.2794)
			(end 0.12065 0.3048)
			(stroke
				(width 0.1)
				(type default)
			)
			(layer "B.Fab")
		)
		(fp_line
			(start 0.12065 -0.2794)
			(end -0.12065 -0.2794)
			(stroke
				(width 0.1)
				(type default)
			)
			(layer "B.Fab")
		)
		(fp_line
			(start 0.12065 -0.305054)
			(end 0.12065 -0.2794)
			(stroke
				(width 0.1)
				(type default)
			)
			(layer "B.Fab")
		)
		(fp_line
			(start -0.120396 0.3048)
			(end -0.120396 0.2794)
			(stroke
				(width 0.1)
				(type default)
			)
			(layer "B.Fab")
		)
		(fp_line
			(start -0.120396 0.2794)
			(end 0.12065 0.2794)
			(stroke
				(width 0.1)
				(type default)
			)
			(layer "B.Fab")
		)
		(fp_line
			(start -0.12065 -0.2794)
			(end -0.12065 -0.3048)
			(stroke
				(width 0.1)
				(type default)
			)
			(layer "B.Fab")
		)
		(fp_line
			(start -0.12065 -0.3048)
			(end -0.67945 -0.3048)
			(stroke
				(width 0.1)
				(type default)
			)
			(layer "B.Fab")
		)
		(fp_line
			(start -0.67945 0.3048)
			(end -0.120396 0.3048)
			(stroke
				(width 0.1)
				(type default)
			)
			(layer "B.Fab")
		)
		(fp_line
			(start -0.67945 -0.3048)
			(end -0.67945 0.3048)
			(stroke
				(width 0.1)
				(type default)
			)
			(layer "B.Fab")
		)
		(pad "1" smd circle
			(at 0.40005 0)
			(size 0 0)
			(layers "B.Cu" "B.Mask" "B.Paste")
			(net "PVDDIO_P0")
		)
		(pad "2" smd circle
			(at -0.40005 0)
			(size 0 0)
			(layers "B.Cu" "B.Mask" "B.Paste")
			(net "GND")
		)
	)
	(footprint ""
		(layer "B.Cu")
		(at 119.418354 -388.011162 -90)
		(property "Reference" "C463"
			(at 0 0 90)
			(layer "B.SilkS")
			(hide yes)
			(effects
				(font
					(size 1.27 1.27)
				)
				(justify mirror)
			)
		)
		(property "Value" ""
			(at 0 0 90)
			(layer "B.Fab")
			(effects
				(font
					(size 1.27 1.27)
				)
				(justify mirror)
			)
		)
		(duplicate_pad_numbers_are_jumpers no)
		(fp_line
			(start -0.299974 0.150114)
			(end 0.299974 0.150114)
			(stroke
				(width 0.1)
				(type default)
			)
			(layer "B.Fab")
		)
		(fp_line
			(start 0.299974 0.150114)
			(end 0.299974 -0.150114)
			(stroke
				(width 0.1)
				(type default)
			)
			(layer "B.Fab")
		)
		(fp_line
			(start -0.299974 -0.150114)
			(end -0.299974 0.150114)
			(stroke
				(width 0.1)
				(type default)
			)
			(layer "B.Fab")
		)
		(fp_line
			(start 0.299974 -0.150114)
			(end -0.299974 -0.150114)
			(stroke
				(width 0.1)
				(type default)
			)
			(layer "B.Fab")
		)
		(pad "1" smd rect
			(at 0.2667 0 90)
			(size 0.3048 0.381)
			(layers "B.Cu" "B.Mask" "B.Paste")
			(net "P0V9_CPU1_RT3_2A_2D")
		)
		(pad "2" smd rect
			(at -0.2667 0 90)
			(size 0.3048 0.381)
			(layers "B.Cu" "B.Mask" "B.Paste")
			(net "GND")
		)
	)
	(footprint ""
		(layer "B.Cu")
		(at 396.797276 -177.294794 -90)
		(property "Reference" "PC589_1"
			(at 0 0 90)
			(layer "B.SilkS")
			(hide yes)
			(effects
				(font
					(size 1.27 1.27)
				)
				(justify mirror)
			)
		)
		(property "Value" ""
			(at 0 0 90)
			(layer "B.Fab")
			(effects
				(font
					(size 1.27 1.27)
				)
				(justify mirror)
			)
		)
		(duplicate_pad_numbers_are_jumpers no)
		(fp_line
			(start -1.524 0.762)
			(end 1.524 0.762)
			(stroke
				(width 0.1524)
				(type default)
			)
			(layer "B.SilkS")
		)
		(fp_line
			(start 1.524 0.762)
			(end 1.524 -0.762)
			(stroke
				(width 0.1524)
				(type default)
			)
			(layer "B.SilkS")
		)
		(fp_line
			(start -1.524 -0.762)
			(end -1.524 0.762)
			(stroke
				(width 0.1524)
				(type default)
			)
			(layer "B.SilkS")
		)
		(fp_line
			(start 1.524 -0.762)
			(end -1.524 -0.762)
			(stroke
				(width 0.1524)
				(type default)
			)
			(layer "B.SilkS")
		)
		(fp_line
			(start -1.1049 0.724916)
			(end -1.1049 -0.724916)
			(stroke
				(width 0.1)
				(type default)
			)
			(layer "B.Fab")
		)
		(fp_line
			(start 1.1049 0.724916)
			(end -1.1049 0.724916)
			(stroke
				(width 0.1)
				(type default)
			)
			(layer "B.Fab")
		)
		(fp_line
			(start -1.1049 -0.724916)
			(end 1.1049 -0.724916)
			(stroke
				(width 0.1)
				(type default)
			)
			(layer "B.Fab")
		)
		(fp_line
			(start 1.1049 -0.724916)
			(end 1.1049 0.724916)
			(stroke
				(width 0.1)
				(type default)
			)
			(layer "B.Fab")
		)
		(pad "1" smd rect
			(at 0.889 0 270)
			(size 1.016 1.27)
			(layers "B.Cu" "B.Mask" "B.Paste")
			(net "SW_P12V_AUX_PVDDCR_SOC_P0_FLT")
		)
		(pad "2" smd rect
			(at -0.889 0 270)
			(size 1.016 1.27)
			(layers "B.Cu" "B.Mask" "B.Paste")
			(net "GND")
		)
	)
	(footprint ""
		(layer "B.Cu")
		(at 323.039994 -337.653376 -90)
		(property "Reference" "PR83"
			(at 0 0 90)
			(layer "B.SilkS")
			(hide yes)
			(effects
				(font
					(size 1.27 1.27)
				)
				(justify mirror)
			)
		)
		(property "Value" ""
			(at 0 0 90)
			(layer "B.Fab")
			(effects
				(font
					(size 1.27 1.27)
				)
				(justify mirror)
			)
		)
		(duplicate_pad_numbers_are_jumpers no)
		(fp_line
			(start -0.7874 0.4064)
			(end 0.7874 0.4064)
			(stroke
				(width 0.1524)
				(type default)
			)
			(layer "B.SilkS")
		)
		(fp_line
			(start 0.7874 0.4064)
			(end 0.7874 -0.4064)
			(stroke
				(width 0.1524)
				(type default)
			)
			(layer "B.SilkS")
		)
		(fp_line
			(start -0.7874 -0.4064)
			(end -0.7874 0.4064)
			(stroke
				(width 0.1524)
				(type default)
			)
			(layer "B.SilkS")
		)
		(fp_line
			(start 0.7874 -0.4064)
			(end -0.7874 -0.4064)
			(stroke
				(width 0.1524)
				(type default)
			)
			(layer "B.SilkS")
		)
		(fp_line
			(start -0.67945 0.3048)
			(end -0.120396 0.3048)
			(stroke
				(width 0.1)
				(type default)
			)
			(layer "B.Fab")
		)
		(fp_line
			(start -0.120396 0.3048)
			(end -0.120396 0.2794)
			(stroke
				(width 0.1)
				(type default)
			)
			(layer "B.Fab")
		)
		(fp_line
			(start 0.12065 0.3048)
			(end 0.67945 0.3048)
			(stroke
				(width 0.1)
				(type default)
			)
			(layer "B.Fab")
		)
		(fp_line
			(start 0.67945 0.3048)
			(end 0.67945 -0.305054)
			(stroke
				(width 0.1)
				(type default)
			)
			(layer "B.Fab")
		)
		(fp_line
			(start -0.120396 0.2794)
			(end 0.12065 0.2794)
			(stroke
				(width 0.1)
				(type default)
			)
			(layer "B.Fab")
		)
		(fp_line
			(start 0.12065 0.2794)
			(end 0.12065 0.3048)
			(stroke
				(width 0.1)
				(type default)
			)
			(layer "B.Fab")
		)
		(fp_line
			(start -0.12065 -0.2794)
			(end -0.12065 -0.3048)
			(stroke
				(width 0.1)
				(type default)
			)
			(layer "B.Fab")
		)
		(fp_line
			(start 0.12065 -0.2794)
			(end -0.12065 -0.2794)
			(stroke
				(width 0.1)
				(type default)
			)
			(layer "B.Fab")
		)
		(fp_line
			(start -0.67945 -0.3048)
			(end -0.67945 0.3048)
			(stroke
				(width 0.1)
				(type default)
			)
			(layer "B.Fab")
		)
		(fp_line
			(start -0.12065 -0.3048)
			(end -0.67945 -0.3048)
			(stroke
				(width 0.1)
				(type default)
			)
			(layer "B.Fab")
		)
		(fp_line
			(start 0.12065 -0.305054)
			(end 0.12065 -0.2794)
			(stroke
				(width 0.1)
				(type default)
			)
			(layer "B.Fab")
		)
		(fp_line
			(start 0.67945 -0.305054)
			(end 0.12065 -0.305054)
			(stroke
				(width 0.1)
				(type default)
			)
			(layer "B.Fab")
		)
		(pad "1" smd circle
			(at 0.40005 0 90)
			(size 0 0)
			(layers "B.Cu" "B.Mask" "B.Paste")
			(net "PVDDCR_CPU1_P0_VOS2")
		)
		(pad "2" smd circle
			(at -0.40005 0 90)
			(size 0 0)
			(layers "B.Cu" "B.Mask" "B.Paste")
			(net "PVDDCR_CPU1_P0")
		)
	)
	(footprint ""
		(layer "B.Cu")
		(at 66.583814 -386.766562 90)
		(property "Reference" "C280"
			(at 0 0 90)
			(layer "B.SilkS")
			(hide yes)
			(effects
				(font
					(size 1.27 1.27)
				)
				(justify mirror)
			)
		)
		(property "Value" ""
			(at 0 0 90)
			(layer "B.Fab")
			(effects
				(font
					(size 1.27 1.27)
				)
				(justify mirror)
			)
		)
		(duplicate_pad_numbers_are_jumpers no)
		(fp_line
			(start 0.299974 -0.150114)
			(end -0.299974 -0.150114)
			(stroke
				(width 0.1)
				(type default)
			)
			(layer "B.Fab")
		)
		(fp_line
			(start -0.299974 -0.150114)
			(end -0.299974 0.150114)
			(stroke
				(width 0.1)
				(type default)
			)
			(layer "B.Fab")
		)
		(fp_line
			(start 0.299974 0.150114)
			(end 0.299974 -0.150114)
			(stroke
				(width 0.1)
				(type default)
			)
			(layer "B.Fab")
		)
		(fp_line
			(start -0.299974 0.150114)
			(end 0.299974 0.150114)
			(stroke
				(width 0.1)
				(type default)
			)
			(layer "B.Fab")
		)
		(pad "1" smd rect
			(at 0.2667 0 270)
			(size 0.3048 0.381)
			(layers "B.Cu" "B.Mask" "B.Paste")
			(net "P0V9_CPU1_RT0_2A")
		)
		(pad "2" smd rect
			(at -0.2667 0 270)
			(size 0.3048 0.381)
			(layers "B.Cu" "B.Mask" "B.Paste")
			(net "GND")
		)
	)
	(footprint ""
		(layer "B.Cu")
		(at 131.849114 -33.199578 -90)
		(property "Reference" "C6050"
			(at 0 0 90)
			(layer "B.SilkS")
			(hide yes)
			(effects
				(font
					(size 1.27 1.27)
				)
				(justify mirror)
			)
		)
		(property "Value" ""
			(at 0 0 90)
			(layer "B.Fab")
			(effects
				(font
					(size 1.27 1.27)
				)
				(justify mirror)
			)
		)
		(duplicate_pad_numbers_are_jumpers no)
		(fp_line
			(start -0.7874 0.4064)
			(end 0.7874 0.4064)
			(stroke
				(width 0.1524)
				(type default)
			)
			(layer "B.SilkS")
		)
		(fp_line
			(start 0.7874 0.4064)
			(end 0.7874 -0.4064)
			(stroke
				(width 0.1524)
				(type default)
			)
			(layer "B.SilkS")
		)
		(fp_line
			(start -0.7874 -0.4064)
			(end -0.7874 0.4064)
			(stroke
				(width 0.1524)
				(type default)
			)
			(layer "B.SilkS")
		)
		(fp_line
			(start 0.7874 -0.4064)
			(end -0.7874 -0.4064)
			(stroke
				(width 0.1524)
				(type default)
			)
			(layer "B.SilkS")
		)
		(fp_line
			(start -0.67945 0.3048)
			(end -0.120396 0.3048)
			(stroke
				(width 0.1)
				(type default)
			)
			(layer "B.Fab")
		)
		(fp_line
			(start -0.120396 0.3048)
			(end -0.120396 0.2794)
			(stroke
				(width 0.1)
				(type default)
			)
			(layer "B.Fab")
		)
		(fp_line
			(start 0.12065 0.3048)
			(end 0.67945 0.3048)
			(stroke
				(width 0.1)
				(type default)
			)
			(layer "B.Fab")
		)
		(fp_line
			(start 0.67945 0.3048)
			(end 0.67945 -0.305054)
			(stroke
				(width 0.1)
				(type default)
			)
			(layer "B.Fab")
		)
		(fp_line
			(start -0.120396 0.2794)
			(end 0.12065 0.2794)
			(stroke
				(width 0.1)
				(type default)
			)
			(layer "B.Fab")
		)
		(fp_line
			(start 0.12065 0.2794)
			(end 0.12065 0.3048)
			(stroke
				(width 0.1)
				(type default)
			)
			(layer "B.Fab")
		)
		(fp_line
			(start -0.12065 -0.2794)
			(end -0.12065 -0.3048)
			(stroke
				(width 0.1)
				(type default)
			)
			(layer "B.Fab")
		)
		(fp_line
			(start 0.12065 -0.2794)
			(end -0.12065 -0.2794)
			(stroke
				(width 0.1)
				(type default)
			)
			(layer "B.Fab")
		)
		(fp_line
			(start -0.67945 -0.3048)
			(end -0.67945 0.3048)
			(stroke
				(width 0.1)
				(type default)
			)
			(layer "B.Fab")
		)
		(fp_line
			(start -0.12065 -0.3048)
			(end -0.67945 -0.3048)
			(stroke
				(width 0.1)
				(type default)
			)
			(layer "B.Fab")
		)
		(fp_line
			(start 0.12065 -0.305054)
			(end 0.12065 -0.2794)
			(stroke
				(width 0.1)
				(type default)
			)
			(layer "B.Fab")
		)
		(fp_line
			(start 0.67945 -0.305054)
			(end 0.12065 -0.305054)
			(stroke
				(width 0.1)
				(type default)
			)
			(layer "B.Fab")
		)
		(pad "1" smd circle
			(at 0.40005 0 90)
			(size 0 0)
			(layers "B.Cu" "B.Mask" "B.Paste")
			(net "P3V3_AUX")
		)
		(pad "2" smd circle
			(at -0.40005 0 90)
			(size 0 0)
			(layers "B.Cu" "B.Mask" "B.Paste")
			(net "GND")
		)
	)
	(footprint ""
		(layer "B.Cu")
		(at 184.658 -96.738948)
		(property "Reference" "R245"
			(at 0 0 0)
			(layer "B.SilkS")
			(hide yes)
			(effects
				(font
					(size 1.27 1.27)
				)
				(justify mirror)
			)
		)
		(property "Value" ""
			(at 0 0 0)
			(layer "B.Fab")
			(effects
				(font
					(size 1.27 1.27)
				)
				(justify mirror)
			)
		)
		(duplicate_pad_numbers_are_jumpers no)
		(fp_line
			(start -0.7874 -0.4064)
			(end -0.7874 0.4064)
			(stroke
				(width 0.1524)
				(type default)
			)
			(layer "B.SilkS")
		)
		(fp_line
			(start -0.7874 0.4064)
			(end 0.7874 0.4064)
			(stroke
				(width 0.1524)
				(type default)
			)
			(layer "B.SilkS")
		)
		(fp_line
			(start 0.7874 -0.4064)
			(end -0.7874 -0.4064)
			(stroke
				(width 0.1524)
				(type default)
			)
			(layer "B.SilkS")
		)
		(fp_line
			(start 0.7874 0.4064)
			(end 0.7874 -0.4064)
			(stroke
				(width 0.1524)
				(type default)
			)
			(layer "B.SilkS")
		)
		(fp_line
			(start -0.67945 -0.3048)
			(end -0.67945 0.3048)
			(stroke
				(width 0.1)
				(type default)
			)
			(layer "B.Fab")
		)
		(fp_line
			(start -0.67945 0.3048)
			(end -0.120396 0.3048)
			(stroke
				(width 0.1)
				(type default)
			)
			(layer "B.Fab")
		)
		(fp_line
			(start -0.12065 -0.3048)
			(end -0.67945 -0.3048)
			(stroke
				(width 0.1)
				(type default)
			)
			(layer "B.Fab")
		)
		(fp_line
			(start -0.12065 -0.2794)
			(end -0.12065 -0.3048)
			(stroke
				(width 0.1)
				(type default)
			)
			(layer "B.Fab")
		)
		(fp_line
			(start -0.120396 0.2794)
			(end 0.12065 0.2794)
			(stroke
				(width 0.1)
				(type default)
			)
			(layer "B.Fab")
		)
		(fp_line
			(start -0.120396 0.3048)
			(end -0.120396 0.2794)
			(stroke
				(width 0.1)
				(type default)
			)
			(layer "B.Fab")
		)
		(fp_line
			(start 0.12065 -0.305054)
			(end 0.12065 -0.2794)
			(stroke
				(width 0.1)
				(type default)
			)
			(layer "B.Fab")
		)
		(fp_line
			(start 0.12065 -0.2794)
			(end -0.12065 -0.2794)
			(stroke
				(width 0.1)
				(type default)
			)
			(layer "B.Fab")
		)
		(fp_line
			(start 0.12065 0.2794)
			(end 0.12065 0.3048)
			(stroke
				(width 0.1)
				(type default)
			)
			(layer "B.Fab")
		)
		(fp_line
			(start 0.12065 0.3048)
			(end 0.67945 0.3048)
			(stroke
				(width 0.1)
				(type default)
			)
			(layer "B.Fab")
		)
		(fp_line
			(start 0.67945 -0.305054)
			(end 0.12065 -0.305054)
			(stroke
				(width 0.1)
				(type default)
			)
			(layer "B.Fab")
		)
		(fp_line
			(start 0.67945 0.3048)
			(end 0.67945 -0.305054)
			(stroke
				(width 0.1)
				(type default)
			)
			(layer "B.Fab")
		)
		(pad "1" smd circle
			(at 0.40005 0 180)
			(size 0 0)
			(layers "B.Cu" "B.Mask" "B.Paste")
			(net "IRQ_SMI_ACTIVE_N")
		)
		(pad "2" smd circle
			(at -0.40005 0 180)
			(size 0 0)
			(layers "B.Cu" "B.Mask" "B.Paste")
			(net "IRQ_SMI_ACTIVE_N_R")
		)
	)
	(footprint ""
		(layer "B.Cu")
		(at 287.985454 -190.94831 180)
		(property "Reference" "R293"
			(at 0 0 0)
			(layer "B.SilkS")
			(hide yes)
			(effects
				(font
					(size 1.27 1.27)
				)
				(justify mirror)
			)
		)
		(property "Value" ""
			(at 0 0 0)
			(layer "B.Fab")
			(effects
				(font
					(size 1.27 1.27)
				)
				(justify mirror)
			)
		)
		(duplicate_pad_numbers_are_jumpers no)
		(fp_line
			(start 0.7874 0.4064)
			(end 0.7874 -0.4064)
			(stroke
				(width 0.1524)
				(type default)
			)
			(layer "B.SilkS")
		)
		(fp_line
			(start 0.7874 -0.4064)
			(end -0.7874 -0.4064)
			(stroke
				(width 0.1524)
				(type default)
			)
			(layer "B.SilkS")
		)
		(fp_line
			(start -0.7874 0.4064)
			(end 0.7874 0.4064)
			(stroke
				(width 0.1524)
				(type default)
			)
			(layer "B.SilkS")
		)
		(fp_line
			(start -0.7874 -0.4064)
			(end -0.7874 0.4064)
			(stroke
				(width 0.1524)
				(type default)
			)
			(layer "B.SilkS")
		)
		(fp_line
			(start 0.67945 0.3048)
			(end 0.67945 -0.305054)
			(stroke
				(width 0.1)
				(type default)
			)
			(layer "B.Fab")
		)
		(fp_line
			(start 0.67945 -0.305054)
			(end 0.12065 -0.305054)
			(stroke
				(width 0.1)
				(type default)
			)
			(layer "B.Fab")
		)
		(fp_line
			(start 0.12065 0.3048)
			(end 0.67945 0.3048)
			(stroke
				(width 0.1)
				(type default)
			)
			(layer "B.Fab")
		)
		(fp_line
			(start 0.12065 0.2794)
			(end 0.12065 0.3048)
			(stroke
				(width 0.1)
				(type default)
			)
			(layer "B.Fab")
		)
		(fp_line
			(start 0.12065 -0.2794)
			(end -0.12065 -0.2794)
			(stroke
				(width 0.1)
				(type default)
			)
			(layer "B.Fab")
		)
		(fp_line
			(start 0.12065 -0.305054)
			(end 0.12065 -0.2794)
			(stroke
				(width 0.1)
				(type default)
			)
			(layer "B.Fab")
		)
		(fp_line
			(start -0.120396 0.3048)
			(end -0.120396 0.2794)
			(stroke
				(width 0.1)
				(type default)
			)
			(layer "B.Fab")
		)
		(fp_line
			(start -0.120396 0.2794)
			(end 0.12065 0.2794)
			(stroke
				(width 0.1)
				(type default)
			)
			(layer "B.Fab")
		)
		(fp_line
			(start -0.12065 -0.2794)
			(end -0.12065 -0.3048)
			(stroke
				(width 0.1)
				(type default)
			)
			(layer "B.Fab")
		)
		(fp_line
			(start -0.12065 -0.3048)
			(end -0.67945 -0.3048)
			(stroke
				(width 0.1)
				(type default)
			)
			(layer "B.Fab")
		)
		(fp_line
			(start -0.67945 0.3048)
			(end -0.120396 0.3048)
			(stroke
				(width 0.1)
				(type default)
			)
			(layer "B.Fab")
		)
		(fp_line
			(start -0.67945 -0.3048)
			(end -0.67945 0.3048)
			(stroke
				(width 0.1)
				(type default)
			)
			(layer "B.Fab")
		)
		(pad "1" smd circle
			(at 0.40005 0)
			(size 0 0)
			(layers "B.Cu" "B.Mask" "B.Paste")
			(net "PWRGD_CHC_CPU0_DIMM")
		)
		(pad "2" smd circle
			(at -0.40005 0)
			(size 0 0)
			(layers "B.Cu" "B.Mask" "B.Paste")
			(net "PWRGD_CHAF_CPU0")
		)
	)
	(footprint ""
		(layer "B.Cu")
		(at 346.450158 -248.47931 180)
		(property "Reference" "C275"
			(at 0 0 0)
			(layer "B.SilkS")
			(hide yes)
			(effects
				(font
					(size 1.27 1.27)
				)
				(justify mirror)
			)
		)
		(property "Value" ""
			(at 0 0 0)
			(layer "B.Fab")
			(effects
				(font
					(size 1.27 1.27)
				)
				(justify mirror)
			)
		)
		(duplicate_pad_numbers_are_jumpers no)
		(fp_line
			(start 0.7874 0.4064)
			(end 0.7874 -0.4064)
			(stroke
				(width 0.1524)
				(type default)
			)
			(layer "B.SilkS")
		)
		(fp_line
			(start 0.7874 -0.4064)
			(end -0.7874 -0.4064)
			(stroke
				(width 0.1524)
				(type default)
			)
			(layer "B.SilkS")
		)
		(fp_line
			(start -0.7874 0.4064)
			(end 0.7874 0.4064)
			(stroke
				(width 0.1524)
				(type default)
			)
			(layer "B.SilkS")
		)
		(fp_line
			(start -0.7874 -0.4064)
			(end -0.7874 0.4064)
			(stroke
				(width 0.1524)
				(type default)
			)
			(layer "B.SilkS")
		)
		(fp_line
			(start 0.67945 0.3048)
			(end 0.67945 -0.305054)
			(stroke
				(width 0.1)
				(type default)
			)
			(layer "B.Fab")
		)
		(fp_line
			(start 0.67945 -0.305054)
			(end 0.12065 -0.305054)
			(stroke
				(width 0.1)
				(type default)
			)
			(layer "B.Fab")
		)
		(fp_line
			(start 0.12065 0.3048)
			(end 0.67945 0.3048)
			(stroke
				(width 0.1)
				(type default)
			)
			(layer "B.Fab")
		)
		(fp_line
			(start 0.12065 0.2794)
			(end 0.12065 0.3048)
			(stroke
				(width 0.1)
				(type default)
			)
			(layer "B.Fab")
		)
		(fp_line
			(start 0.12065 -0.2794)
			(end -0.12065 -0.2794)
			(stroke
				(width 0.1)
				(type default)
			)
			(layer "B.Fab")
		)
		(fp_line
			(start 0.12065 -0.305054)
			(end 0.12065 -0.2794)
			(stroke
				(width 0.1)
				(type default)
			)
			(layer "B.Fab")
		)
		(fp_line
			(start -0.120396 0.3048)
			(end -0.120396 0.2794)
			(stroke
				(width 0.1)
				(type default)
			)
			(layer "B.Fab")
		)
		(fp_line
			(start -0.120396 0.2794)
			(end 0.12065 0.2794)
			(stroke
				(width 0.1)
				(type default)
			)
			(layer "B.Fab")
		)
		(fp_line
			(start -0.12065 -0.2794)
			(end -0.12065 -0.3048)
			(stroke
				(width 0.1)
				(type default)
			)
			(layer "B.Fab")
		)
		(fp_line
			(start -0.12065 -0.3048)
			(end -0.67945 -0.3048)
			(stroke
				(width 0.1)
				(type default)
			)
			(layer "B.Fab")
		)
		(fp_line
			(start -0.67945 0.3048)
			(end -0.120396 0.3048)
			(stroke
				(width 0.1)
				(type default)
			)
			(layer "B.Fab")
		)
		(fp_line
			(start -0.67945 -0.3048)
			(end -0.67945 0.3048)
			(stroke
				(width 0.1)
				(type default)
			)
			(layer "B.Fab")
		)
		(pad "1" smd circle
			(at 0.40005 0)
			(size 0 0)
			(layers "B.Cu" "B.Mask" "B.Paste")
			(net "PVDDCR_CPU0_P0")
		)
		(pad "2" smd circle
			(at -0.40005 0)
			(size 0 0)
			(layers "B.Cu" "B.Mask" "B.Paste")
			(net "GND")
		)
	)
	(footprint ""
		(layer "B.Cu")
		(at 217.678 -335.026 180)
		(property "Reference" "R6811"
			(at 0 0 0)
			(layer "B.SilkS")
			(hide yes)
			(effects
				(font
					(size 1.27 1.27)
				)
				(justify mirror)
			)
		)
		(property "Value" ""
			(at 0 0 0)
			(layer "B.Fab")
			(effects
				(font
					(size 1.27 1.27)
				)
				(justify mirror)
			)
		)
		(duplicate_pad_numbers_are_jumpers no)
		(fp_line
			(start 0.32512 0.175006)
			(end 0.32512 -0.175006)
			(stroke
				(width 0.1)
				(type default)
			)
			(layer "B.Fab")
		)
		(fp_line
			(start 0.32512 -0.175006)
			(end -0.32512 -0.175006)
			(stroke
				(width 0.1)
				(type default)
			)
			(layer "B.Fab")
		)
		(fp_line
			(start -0.32512 0.175006)
			(end 0.32512 0.175006)
			(stroke
				(width 0.1)
				(type default)
			)
			(layer "B.Fab")
		)
		(fp_line
			(start -0.32512 -0.175006)
			(end -0.32512 0.175006)
			(stroke
				(width 0.1)
				(type default)
			)
			(layer "B.Fab")
		)
		(pad "1" smd rect
			(at 0.2667 0)
			(size 0.3048 0.381)
			(layers "B.Cu" "B.Mask" "B.Paste")
			(net "SMB_RT_CPU1_P0_R_SCL")
		)
		(pad "2" smd rect
			(at -0.2667 0 180)
			(size 0.3048 0.381)
			(layers "B.Cu" "B.Mask" "B.Paste")
			(net "SMB_RT_CPU1_P0_SCL")
		)
	)
	(footprint ""
		(layer "B.Cu")
		(at 125.389386 -255.845564)
		(property "Reference" "C2447"
			(at 0 0 0)
			(layer "B.SilkS")
			(hide yes)
			(effects
				(font
					(size 1.27 1.27)
				)
				(justify mirror)
			)
		)
		(property "Value" ""
			(at 0 0 0)
			(layer "B.Fab")
			(effects
				(font
					(size 1.27 1.27)
				)
				(justify mirror)
			)
		)
		(duplicate_pad_numbers_are_jumpers no)
		(fp_line
			(start -0.7874 -0.4064)
			(end -0.7874 0.4064)
			(stroke
				(width 0.1524)
				(type default)
			)
			(layer "B.SilkS")
		)
		(fp_line
			(start -0.7874 0.4064)
			(end 0.7874 0.4064)
			(stroke
				(width 0.1524)
				(type default)
			)
			(layer "B.SilkS")
		)
		(fp_line
			(start 0.7874 -0.4064)
			(end -0.7874 -0.4064)
			(stroke
				(width 0.1524)
				(type default)
			)
			(layer "B.SilkS")
		)
		(fp_line
			(start 0.7874 0.4064)
			(end 0.7874 -0.4064)
			(stroke
				(width 0.1524)
				(type default)
			)
			(layer "B.SilkS")
		)
		(fp_line
			(start -0.67945 -0.3048)
			(end -0.67945 0.3048)
			(stroke
				(width 0.1)
				(type default)
			)
			(layer "B.Fab")
		)
		(fp_line
			(start -0.67945 0.3048)
			(end -0.120396 0.3048)
			(stroke
				(width 0.1)
				(type default)
			)
			(layer "B.Fab")
		)
		(fp_line
			(start -0.12065 -0.3048)
			(end -0.67945 -0.3048)
			(stroke
				(width 0.1)
				(type default)
			)
			(layer "B.Fab")
		)
		(fp_line
			(start -0.12065 -0.2794)
			(end -0.12065 -0.3048)
			(stroke
				(width 0.1)
				(type default)
			)
			(layer "B.Fab")
		)
		(fp_line
			(start -0.120396 0.2794)
			(end 0.12065 0.2794)
			(stroke
				(width 0.1)
				(type default)
			)
			(layer "B.Fab")
		)
		(fp_line
			(start -0.120396 0.3048)
			(end -0.120396 0.2794)
			(stroke
				(width 0.1)
				(type default)
			)
			(layer "B.Fab")
		)
		(fp_line
			(start 0.12065 -0.305054)
			(end 0.12065 -0.2794)
			(stroke
				(width 0.1)
				(type default)
			)
			(layer "B.Fab")
		)
		(fp_line
			(start 0.12065 -0.2794)
			(end -0.12065 -0.2794)
			(stroke
				(width 0.1)
				(type default)
			)
			(layer "B.Fab")
		)
		(fp_line
			(start 0.12065 0.2794)
			(end 0.12065 0.3048)
			(stroke
				(width 0.1)
				(type default)
			)
			(layer "B.Fab")
		)
		(fp_line
			(start 0.12065 0.3048)
			(end 0.67945 0.3048)
			(stroke
				(width 0.1)
				(type default)
			)
			(layer "B.Fab")
		)
		(fp_line
			(start 0.67945 -0.305054)
			(end 0.12065 -0.305054)
			(stroke
				(width 0.1)
				(type default)
			)
			(layer "B.Fab")
		)
		(fp_line
			(start 0.67945 0.3048)
			(end 0.67945 -0.305054)
			(stroke
				(width 0.1)
				(type default)
			)
			(layer "B.Fab")
		)
		(pad "1" smd circle
			(at 0.40005 0 180)
			(size 0 0)
			(layers "B.Cu" "B.Mask" "B.Paste")
			(net "PVDDCR_SOC_P1")
		)
		(pad "2" smd circle
			(at -0.40005 0 180)
			(size 0 0)
			(layers "B.Cu" "B.Mask" "B.Paste")
			(net "GND")
		)
	)
	(footprint ""
		(layer "B.Cu")
		(at 435.755796 -194.88531 180)
		(property "Reference" "R767"
			(at 0 0 0)
			(layer "B.SilkS")
			(hide yes)
			(effects
				(font
					(size 1.27 1.27)
				)
				(justify mirror)
			)
		)
		(property "Value" ""
			(at 0 0 0)
			(layer "B.Fab")
			(effects
				(font
					(size 1.27 1.27)
				)
				(justify mirror)
			)
		)
		(duplicate_pad_numbers_are_jumpers no)
		(fp_line
			(start 0.7874 0.4064)
			(end 0.7874 -0.4064)
			(stroke
				(width 0.1524)
				(type default)
			)
			(layer "B.SilkS")
		)
		(fp_line
			(start 0.7874 -0.4064)
			(end -0.7874 -0.4064)
			(stroke
				(width 0.1524)
				(type default)
			)
			(layer "B.SilkS")
		)
		(fp_line
			(start -0.7874 0.4064)
			(end 0.7874 0.4064)
			(stroke
				(width 0.1524)
				(type default)
			)
			(layer "B.SilkS")
		)
		(fp_line
			(start -0.7874 -0.4064)
			(end -0.7874 0.4064)
			(stroke
				(width 0.1524)
				(type default)
			)
			(layer "B.SilkS")
		)
		(fp_line
			(start 0.67945 0.3048)
			(end 0.67945 -0.305054)
			(stroke
				(width 0.1)
				(type default)
			)
			(layer "B.Fab")
		)
		(fp_line
			(start 0.67945 -0.305054)
			(end 0.12065 -0.305054)
			(stroke
				(width 0.1)
				(type default)
			)
			(layer "B.Fab")
		)
		(fp_line
			(start 0.12065 0.3048)
			(end 0.67945 0.3048)
			(stroke
				(width 0.1)
				(type default)
			)
			(layer "B.Fab")
		)
		(fp_line
			(start 0.12065 0.2794)
			(end 0.12065 0.3048)
			(stroke
				(width 0.1)
				(type default)
			)
			(layer "B.Fab")
		)
		(fp_line
			(start 0.12065 -0.2794)
			(end -0.12065 -0.2794)
			(stroke
				(width 0.1)
				(type default)
			)
			(layer "B.Fab")
		)
		(fp_line
			(start 0.12065 -0.305054)
			(end 0.12065 -0.2794)
			(stroke
				(width 0.1)
				(type default)
			)
			(layer "B.Fab")
		)
		(fp_line
			(start -0.120396 0.3048)
			(end -0.120396 0.2794)
			(stroke
				(width 0.1)
				(type default)
			)
			(layer "B.Fab")
		)
		(fp_line
			(start -0.120396 0.2794)
			(end 0.12065 0.2794)
			(stroke
				(width 0.1)
				(type default)
			)
			(layer "B.Fab")
		)
		(fp_line
			(start -0.12065 -0.2794)
			(end -0.12065 -0.3048)
			(stroke
				(width 0.1)
				(type default)
			)
			(layer "B.Fab")
		)
		(fp_line
			(start -0.12065 -0.3048)
			(end -0.67945 -0.3048)
			(stroke
				(width 0.1)
				(type default)
			)
			(layer "B.Fab")
		)
		(fp_line
			(start -0.67945 0.3048)
			(end -0.120396 0.3048)
			(stroke
				(width 0.1)
				(type default)
			)
			(layer "B.Fab")
		)
		(fp_line
			(start -0.67945 -0.3048)
			(end -0.67945 0.3048)
			(stroke
				(width 0.1)
				(type default)
			)
			(layer "B.Fab")
		)
		(pad "1" smd circle
			(at 0.40005 0)
			(size 0 0)
			(layers "B.Cu" "B.Mask" "B.Paste")
			(net "PD_CHJ_CPU0_DIMM_SAA")
		)
		(pad "2" smd circle
			(at -0.40005 0)
			(size 0 0)
			(layers "B.Cu" "B.Mask" "B.Paste")
			(net "GND")
		)
	)
	(footprint ""
		(layer "B.Cu")
		(at 255.905 -336.25536 180)
		(property "Reference" "R831"
			(at 0 0 0)
			(layer "B.SilkS")
			(hide yes)
			(effects
				(font
					(size 1.27 1.27)
				)
				(justify mirror)
			)
		)
		(property "Value" ""
			(at 0 0 0)
			(layer "B.Fab")
			(effects
				(font
					(size 1.27 1.27)
				)
				(justify mirror)
			)
		)
		(duplicate_pad_numbers_are_jumpers no)
		(fp_line
			(start 0.32512 0.175006)
			(end 0.32512 -0.175006)
			(stroke
				(width 0.1)
				(type default)
			)
			(layer "B.Fab")
		)
		(fp_line
			(start 0.32512 -0.175006)
			(end -0.32512 -0.175006)
			(stroke
				(width 0.1)
				(type default)
			)
			(layer "B.Fab")
		)
		(fp_line
			(start -0.32512 0.175006)
			(end 0.32512 0.175006)
			(stroke
				(width 0.1)
				(type default)
			)
			(layer "B.Fab")
		)
		(fp_line
			(start -0.32512 -0.175006)
			(end -0.32512 0.175006)
			(stroke
				(width 0.1)
				(type default)
			)
			(layer "B.Fab")
		)
		(pad "1" smd rect
			(at 0.2667 0)
			(size 0.3048 0.381)
			(layers "B.Cu" "B.Mask" "B.Paste")
			(net "SMB_RT_CPU0_P3_ROM_MUX_2D_R_SCL")
		)
		(pad "2" smd rect
			(at -0.2667 0 180)
			(size 0.3048 0.381)
			(layers "B.Cu" "B.Mask" "B.Paste")
			(net "SMB_RT_CPU0_P3_ROM_MUX_2D_SCL")
		)
	)
	(footprint ""
		(layer "B.Cu")
		(at 238.633 -341.884 180)
		(property "Reference" "R809"
			(at 0 0 0)
			(layer "B.SilkS")
			(hide yes)
			(effects
				(font
					(size 1.27 1.27)
				)
				(justify mirror)
			)
		)
		(property "Value" ""
			(at 0 0 0)
			(layer "B.Fab")
			(effects
				(font
					(size 1.27 1.27)
				)
				(justify mirror)
			)
		)
		(duplicate_pad_numbers_are_jumpers no)
		(fp_line
			(start 0.32512 0.175006)
			(end 0.32512 -0.175006)
			(stroke
				(width 0.1)
				(type default)
			)
			(layer "B.Fab")
		)
		(fp_line
			(start 0.32512 -0.175006)
			(end -0.32512 -0.175006)
			(stroke
				(width 0.1)
				(type default)
			)
			(layer "B.Fab")
		)
		(fp_line
			(start -0.32512 0.175006)
			(end 0.32512 0.175006)
			(stroke
				(width 0.1)
				(type default)
			)
			(layer "B.Fab")
		)
		(fp_line
			(start -0.32512 -0.175006)
			(end -0.32512 0.175006)
			(stroke
				(width 0.1)
				(type default)
			)
			(layer "B.Fab")
		)
		(pad "1" smd rect
			(at 0.2667 0)
			(size 0.3048 0.381)
			(layers "B.Cu" "B.Mask" "B.Paste")
			(net "SMB_RT_CPU1_P2_ROM_MUX_2D_SCL")
		)
		(pad "2" smd rect
			(at -0.2667 0 180)
			(size 0.3048 0.381)
			(layers "B.Cu" "B.Mask" "B.Paste")
			(net "SMB_RT_CPU1_P2_ROM_MUX_2D_R_SCL")
		)
	)
	(footprint ""
		(layer "B.Cu")
		(at 106.869992 -31.33344 90)
		(property "Reference" "C6112"
			(at 0 0 90)
			(layer "B.SilkS")
			(hide yes)
			(effects
				(font
					(size 1.27 1.27)
				)
				(justify mirror)
			)
		)
		(property "Value" ""
			(at 0 0 90)
			(layer "B.Fab")
			(effects
				(font
					(size 1.27 1.27)
				)
				(justify mirror)
			)
		)
		(duplicate_pad_numbers_are_jumpers no)
		(fp_line
			(start 0.7874 -0.4064)
			(end -0.7874 -0.4064)
			(stroke
				(width 0.1524)
				(type default)
			)
			(layer "B.SilkS")
		)
		(fp_line
			(start -0.7874 -0.4064)
			(end -0.7874 0.4064)
			(stroke
				(width 0.1524)
				(type default)
			)
			(layer "B.SilkS")
		)
		(fp_line
			(start 0.7874 0.4064)
			(end 0.7874 -0.4064)
			(stroke
				(width 0.1524)
				(type default)
			)
			(layer "B.SilkS")
		)
		(fp_line
			(start -0.7874 0.4064)
			(end 0.7874 0.4064)
			(stroke
				(width 0.1524)
				(type default)
			)
			(layer "B.SilkS")
		)
		(fp_line
			(start 0.67945 -0.305054)
			(end 0.12065 -0.305054)
			(stroke
				(width 0.1)
				(type default)
			)
			(layer "B.Fab")
		)
		(fp_line
			(start 0.12065 -0.305054)
			(end 0.12065 -0.2794)
			(stroke
				(width 0.1)
				(type default)
			)
			(layer "B.Fab")
		)
		(fp_line
			(start -0.12065 -0.3048)
			(end -0.67945 -0.3048)
			(stroke
				(width 0.1)
				(type default)
			)
			(layer "B.Fab")
		)
		(fp_line
			(start -0.67945 -0.3048)
			(end -0.67945 0.3048)
			(stroke
				(width 0.1)
				(type default)
			)
			(layer "B.Fab")
		)
		(fp_line
			(start 0.12065 -0.2794)
			(end -0.12065 -0.2794)
			(stroke
				(width 0.1)
				(type default)
			)
			(layer "B.Fab")
		)
		(fp_line
			(start -0.12065 -0.2794)
			(end -0.12065 -0.3048)
			(stroke
				(width 0.1)
				(type default)
			)
			(layer "B.Fab")
		)
		(fp_line
			(start 0.12065 0.2794)
			(end 0.12065 0.3048)
			(stroke
				(width 0.1)
				(type default)
			)
			(layer "B.Fab")
		)
		(fp_line
			(start -0.120396 0.2794)
			(end 0.12065 0.2794)
			(stroke
				(width 0.1)
				(type default)
			)
			(layer "B.Fab")
		)
		(fp_line
			(start 0.67945 0.3048)
			(end 0.67945 -0.305054)
			(stroke
				(width 0.1)
				(type default)
			)
			(layer "B.Fab")
		)
		(fp_line
			(start 0.12065 0.3048)
			(end 0.67945 0.3048)
			(stroke
				(width 0.1)
				(type default)
			)
			(layer "B.Fab")
		)
		(fp_line
			(start -0.120396 0.3048)
			(end -0.120396 0.2794)
			(stroke
				(width 0.1)
				(type default)
			)
			(layer "B.Fab")
		)
		(fp_line
			(start -0.67945 0.3048)
			(end -0.120396 0.3048)
			(stroke
				(width 0.1)
				(type default)
			)
			(layer "B.Fab")
		)
		(pad "1" smd circle
			(at 0.40005 0 270)
			(size 0 0)
			(layers "B.Cu" "B.Mask" "B.Paste")
			(net "P1V2_CPU0_USB2_DVDD12")
		)
		(pad "2" smd circle
			(at -0.40005 0 270)
			(size 0 0)
			(layers "B.Cu" "B.Mask" "B.Paste")
			(net "GND")
		)
	)
	(footprint ""
		(layer "B.Cu")
		(at 234.785916 -321.652138 180)
		(property "Reference" "R1226"
			(at 0 0 0)
			(layer "B.SilkS")
			(hide yes)
			(effects
				(font
					(size 1.27 1.27)
				)
				(justify mirror)
			)
		)
		(property "Value" ""
			(at 0 0 0)
			(layer "B.Fab")
			(effects
				(font
					(size 1.27 1.27)
				)
				(justify mirror)
			)
		)
		(duplicate_pad_numbers_are_jumpers no)
		(fp_line
			(start 0.7874 0.4064)
			(end 0.7874 -0.4064)
			(stroke
				(width 0.1524)
				(type default)
			)
			(layer "B.SilkS")
		)
		(fp_line
			(start 0.7874 -0.4064)
			(end -0.7874 -0.4064)
			(stroke
				(width 0.1524)
				(type default)
			)
			(layer "B.SilkS")
		)
		(fp_line
			(start -0.7874 0.4064)
			(end 0.7874 0.4064)
			(stroke
				(width 0.1524)
				(type default)
			)
			(layer "B.SilkS")
		)
		(fp_line
			(start -0.7874 -0.4064)
			(end -0.7874 0.4064)
			(stroke
				(width 0.1524)
				(type default)
			)
			(layer "B.SilkS")
		)
		(fp_line
			(start 0.67945 0.3048)
			(end 0.67945 -0.305054)
			(stroke
				(width 0.1)
				(type default)
			)
			(layer "B.Fab")
		)
		(fp_line
			(start 0.67945 -0.305054)
			(end 0.12065 -0.305054)
			(stroke
				(width 0.1)
				(type default)
			)
			(layer "B.Fab")
		)
		(fp_line
			(start 0.12065 0.3048)
			(end 0.67945 0.3048)
			(stroke
				(width 0.1)
				(type default)
			)
			(layer "B.Fab")
		)
		(fp_line
			(start 0.12065 0.2794)
			(end 0.12065 0.3048)
			(stroke
				(width 0.1)
				(type default)
			)
			(layer "B.Fab")
		)
		(fp_line
			(start 0.12065 -0.2794)
			(end -0.12065 -0.2794)
			(stroke
				(width 0.1)
				(type default)
			)
			(layer "B.Fab")
		)
		(fp_line
			(start 0.12065 -0.305054)
			(end 0.12065 -0.2794)
			(stroke
				(width 0.1)
				(type default)
			)
			(layer "B.Fab")
		)
		(fp_line
			(start -0.120396 0.3048)
			(end -0.120396 0.2794)
			(stroke
				(width 0.1)
				(type default)
			)
			(layer "B.Fab")
		)
		(fp_line
			(start -0.120396 0.2794)
			(end 0.12065 0.2794)
			(stroke
				(width 0.1)
				(type default)
			)
			(layer "B.Fab")
		)
		(fp_line
			(start -0.12065 -0.2794)
			(end -0.12065 -0.3048)
			(stroke
				(width 0.1)
				(type default)
			)
			(layer "B.Fab")
		)
		(fp_line
			(start -0.12065 -0.3048)
			(end -0.67945 -0.3048)
			(stroke
				(width 0.1)
				(type default)
			)
			(layer "B.Fab")
		)
		(fp_line
			(start -0.67945 0.3048)
			(end -0.120396 0.3048)
			(stroke
				(width 0.1)
				(type default)
			)
			(layer "B.Fab")
		)
		(fp_line
			(start -0.67945 -0.3048)
			(end -0.67945 0.3048)
			(stroke
				(width 0.1)
				(type default)
			)
			(layer "B.Fab")
		)
		(pad "1" smd circle
			(at 0.40005 0)
			(size 0 0)
			(layers "B.Cu" "B.Mask" "B.Paste")
			(net "P5V_AUX_ADC")
		)
		(pad "2" smd circle
			(at -0.40005 0)
			(size 0 0)
			(layers "B.Cu" "B.Mask" "B.Paste")
			(net "GND")
		)
	)
	(footprint ""
		(layer "B.Cu")
		(at 104.320848 -178.110134 -90)
		(property "Reference" "PC297_4"
			(at 0 0 90)
			(layer "B.SilkS")
			(hide yes)
			(effects
				(font
					(size 1.27 1.27)
				)
				(justify mirror)
			)
		)
		(property "Value" ""
			(at 0 0 90)
			(layer "B.Fab")
			(effects
				(font
					(size 1.27 1.27)
				)
				(justify mirror)
			)
		)
		(duplicate_pad_numbers_are_jumpers no)
		(fp_line
			(start -1.524 0.762)
			(end 1.524 0.762)
			(stroke
				(width 0.1524)
				(type default)
			)
			(layer "B.SilkS")
		)
		(fp_line
			(start 1.524 0.762)
			(end 1.524 -0.762)
			(stroke
				(width 0.1524)
				(type default)
			)
			(layer "B.SilkS")
		)
		(fp_line
			(start -1.524 -0.762)
			(end -1.524 0.762)
			(stroke
				(width 0.1524)
				(type default)
			)
			(layer "B.SilkS")
		)
		(fp_line
			(start 1.524 -0.762)
			(end -1.524 -0.762)
			(stroke
				(width 0.1524)
				(type default)
			)
			(layer "B.SilkS")
		)
		(fp_line
			(start -1.1049 0.724916)
			(end -1.1049 -0.724916)
			(stroke
				(width 0.1)
				(type default)
			)
			(layer "B.Fab")
		)
		(fp_line
			(start 1.1049 0.724916)
			(end -1.1049 0.724916)
			(stroke
				(width 0.1)
				(type default)
			)
			(layer "B.Fab")
		)
		(fp_line
			(start -1.1049 -0.724916)
			(end 1.1049 -0.724916)
			(stroke
				(width 0.1)
				(type default)
			)
			(layer "B.Fab")
		)
		(fp_line
			(start 1.1049 -0.724916)
			(end 1.1049 0.724916)
			(stroke
				(width 0.1)
				(type default)
			)
			(layer "B.Fab")
		)
		(pad "1" smd rect
			(at 0.889 0 270)
			(size 1.016 1.27)
			(layers "B.Cu" "B.Mask" "B.Paste")
			(net "SW_P12V_AUX_PVDDCR_CPU0_P1_FLT")
		)
		(pad "2" smd rect
			(at -0.889 0 270)
			(size 1.016 1.27)
			(layers "B.Cu" "B.Mask" "B.Paste")
			(net "GND")
		)
	)
	(footprint ""
		(layer "B.Cu")
		(at 375.202958 -205.101952 90)
		(property "Reference" "C207"
			(at 0 0 90)
			(layer "B.SilkS")
			(hide yes)
			(effects
				(font
					(size 1.27 1.27)
				)
				(justify mirror)
			)
		)
		(property "Value" ""
			(at 0 0 90)
			(layer "B.Fab")
			(effects
				(font
					(size 1.27 1.27)
				)
				(justify mirror)
			)
		)
		(duplicate_pad_numbers_are_jumpers no)
		(fp_line
			(start 0.7874 -0.4064)
			(end -0.7874 -0.4064)
			(stroke
				(width 0.1524)
				(type default)
			)
			(layer "B.SilkS")
		)
		(fp_line
			(start -0.7874 -0.4064)
			(end -0.7874 0.4064)
			(stroke
				(width 0.1524)
				(type default)
			)
			(layer "B.SilkS")
		)
		(fp_line
			(start 0.7874 0.4064)
			(end 0.7874 -0.4064)
			(stroke
				(width 0.1524)
				(type default)
			)
			(layer "B.SilkS")
		)
		(fp_line
			(start -0.7874 0.4064)
			(end 0.7874 0.4064)
			(stroke
				(width 0.1524)
				(type default)
			)
			(layer "B.SilkS")
		)
		(fp_line
			(start 0.67945 -0.305054)
			(end 0.12065 -0.305054)
			(stroke
				(width 0.1)
				(type default)
			)
			(layer "B.Fab")
		)
		(fp_line
			(start 0.12065 -0.305054)
			(end 0.12065 -0.2794)
			(stroke
				(width 0.1)
				(type default)
			)
			(layer "B.Fab")
		)
		(fp_line
			(start -0.12065 -0.3048)
			(end -0.67945 -0.3048)
			(stroke
				(width 0.1)
				(type default)
			)
			(layer "B.Fab")
		)
		(fp_line
			(start -0.67945 -0.3048)
			(end -0.67945 0.3048)
			(stroke
				(width 0.1)
				(type default)
			)
			(layer "B.Fab")
		)
		(fp_line
			(start 0.12065 -0.2794)
			(end -0.12065 -0.2794)
			(stroke
				(width 0.1)
				(type default)
			)
			(layer "B.Fab")
		)
		(fp_line
			(start -0.12065 -0.2794)
			(end -0.12065 -0.3048)
			(stroke
				(width 0.1)
				(type default)
			)
			(layer "B.Fab")
		)
		(fp_line
			(start 0.12065 0.2794)
			(end 0.12065 0.3048)
			(stroke
				(width 0.1)
				(type default)
			)
			(layer "B.Fab")
		)
		(fp_line
			(start -0.120396 0.2794)
			(end 0.12065 0.2794)
			(stroke
				(width 0.1)
				(type default)
			)
			(layer "B.Fab")
		)
		(fp_line
			(start 0.67945 0.3048)
			(end 0.67945 -0.305054)
			(stroke
				(width 0.1)
				(type default)
			)
			(layer "B.Fab")
		)
		(fp_line
			(start 0.12065 0.3048)
			(end 0.67945 0.3048)
			(stroke
				(width 0.1)
				(type default)
			)
			(layer "B.Fab")
		)
		(fp_line
			(start -0.120396 0.3048)
			(end -0.120396 0.2794)
			(stroke
				(width 0.1)
				(type default)
			)
			(layer "B.Fab")
		)
		(fp_line
			(start -0.67945 0.3048)
			(end -0.120396 0.3048)
			(stroke
				(width 0.1)
				(type default)
			)
			(layer "B.Fab")
		)
		(pad "1" smd circle
			(at 0.40005 0 270)
			(size 0 0)
			(layers "B.Cu" "B.Mask" "B.Paste")
			(net "JTAG_CPU0_TDO")
		)
		(pad "2" smd circle
			(at -0.40005 0 270)
			(size 0 0)
			(layers "B.Cu" "B.Mask" "B.Paste")
			(net "GND")
		)
	)
	(footprint ""
		(layer "B.Cu")
		(at 352.723958 -249.36831 180)
		(property "Reference" "C278"
			(at 0 0 0)
			(layer "B.SilkS")
			(hide yes)
			(effects
				(font
					(size 1.27 1.27)
				)
				(justify mirror)
			)
		)
		(property "Value" ""
			(at 0 0 0)
			(layer "B.Fab")
			(effects
				(font
					(size 1.27 1.27)
				)
				(justify mirror)
			)
		)
		(duplicate_pad_numbers_are_jumpers no)
		(fp_line
			(start 0.7874 0.4064)
			(end 0.7874 -0.4064)
			(stroke
				(width 0.1524)
				(type default)
			)
			(layer "B.SilkS")
		)
		(fp_line
			(start 0.7874 -0.4064)
			(end -0.7874 -0.4064)
			(stroke
				(width 0.1524)
				(type default)
			)
			(layer "B.SilkS")
		)
		(fp_line
			(start -0.7874 0.4064)
			(end 0.7874 0.4064)
			(stroke
				(width 0.1524)
				(type default)
			)
			(layer "B.SilkS")
		)
		(fp_line
			(start -0.7874 -0.4064)
			(end -0.7874 0.4064)
			(stroke
				(width 0.1524)
				(type default)
			)
			(layer "B.SilkS")
		)
		(fp_line
			(start 0.67945 0.3048)
			(end 0.67945 -0.305054)
			(stroke
				(width 0.1)
				(type default)
			)
			(layer "B.Fab")
		)
		(fp_line
			(start 0.67945 -0.305054)
			(end 0.12065 -0.305054)
			(stroke
				(width 0.1)
				(type default)
			)
			(layer "B.Fab")
		)
		(fp_line
			(start 0.12065 0.3048)
			(end 0.67945 0.3048)
			(stroke
				(width 0.1)
				(type default)
			)
			(layer "B.Fab")
		)
		(fp_line
			(start 0.12065 0.2794)
			(end 0.12065 0.3048)
			(stroke
				(width 0.1)
				(type default)
			)
			(layer "B.Fab")
		)
		(fp_line
			(start 0.12065 -0.2794)
			(end -0.12065 -0.2794)
			(stroke
				(width 0.1)
				(type default)
			)
			(layer "B.Fab")
		)
		(fp_line
			(start 0.12065 -0.305054)
			(end 0.12065 -0.2794)
			(stroke
				(width 0.1)
				(type default)
			)
			(layer "B.Fab")
		)
		(fp_line
			(start -0.120396 0.3048)
			(end -0.120396 0.2794)
			(stroke
				(width 0.1)
				(type default)
			)
			(layer "B.Fab")
		)
		(fp_line
			(start -0.120396 0.2794)
			(end 0.12065 0.2794)
			(stroke
				(width 0.1)
				(type default)
			)
			(layer "B.Fab")
		)
		(fp_line
			(start -0.12065 -0.2794)
			(end -0.12065 -0.3048)
			(stroke
				(width 0.1)
				(type default)
			)
			(layer "B.Fab")
		)
		(fp_line
			(start -0.12065 -0.3048)
			(end -0.67945 -0.3048)
			(stroke
				(width 0.1)
				(type default)
			)
			(layer "B.Fab")
		)
		(fp_line
			(start -0.67945 0.3048)
			(end -0.120396 0.3048)
			(stroke
				(width 0.1)
				(type default)
			)
			(layer "B.Fab")
		)
		(fp_line
			(start -0.67945 -0.3048)
			(end -0.67945 0.3048)
			(stroke
				(width 0.1)
				(type default)
			)
			(layer "B.Fab")
		)
		(pad "1" smd circle
			(at 0.40005 0)
			(size 0 0)
			(layers "B.Cu" "B.Mask" "B.Paste")
			(net "PVDDCR_CPU0_P0")
		)
		(pad "2" smd circle
			(at -0.40005 0)
			(size 0 0)
			(layers "B.Cu" "B.Mask" "B.Paste")
			(net "GND")
		)
	)
	(footprint ""
		(layer "B.Cu")
		(at 349.834454 -261.17931)
		(property "Reference" "C2581"
			(at 0 0 0)
			(layer "B.SilkS")
			(hide yes)
			(effects
				(font
					(size 1.27 1.27)
				)
				(justify mirror)
			)
		)
		(property "Value" ""
			(at 0 0 0)
			(layer "B.Fab")
			(effects
				(font
					(size 1.27 1.27)
				)
				(justify mirror)
			)
		)
		(duplicate_pad_numbers_are_jumpers no)
		(fp_line
			(start -0.7874 -0.4064)
			(end -0.7874 0.4064)
			(stroke
				(width 0.1524)
				(type default)
			)
			(layer "B.SilkS")
		)
		(fp_line
			(start -0.7874 0.4064)
			(end 0.7874 0.4064)
			(stroke
				(width 0.1524)
				(type default)
			)
			(layer "B.SilkS")
		)
		(fp_line
			(start 0.7874 -0.4064)
			(end -0.7874 -0.4064)
			(stroke
				(width 0.1524)
				(type default)
			)
			(layer "B.SilkS")
		)
		(fp_line
			(start 0.7874 0.4064)
			(end 0.7874 -0.4064)
			(stroke
				(width 0.1524)
				(type default)
			)
			(layer "B.SilkS")
		)
		(fp_line
			(start -0.67945 -0.3048)
			(end -0.67945 0.3048)
			(stroke
				(width 0.1)
				(type default)
			)
			(layer "B.Fab")
		)
		(fp_line
			(start -0.67945 0.3048)
			(end -0.120396 0.3048)
			(stroke
				(width 0.1)
				(type default)
			)
			(layer "B.Fab")
		)
		(fp_line
			(start -0.12065 -0.3048)
			(end -0.67945 -0.3048)
			(stroke
				(width 0.1)
				(type default)
			)
			(layer "B.Fab")
		)
		(fp_line
			(start -0.12065 -0.2794)
			(end -0.12065 -0.3048)
			(stroke
				(width 0.1)
				(type default)
			)
			(layer "B.Fab")
		)
		(fp_line
			(start -0.120396 0.2794)
			(end 0.12065 0.2794)
			(stroke
				(width 0.1)
				(type default)
			)
			(layer "B.Fab")
		)
		(fp_line
			(start -0.120396 0.3048)
			(end -0.120396 0.2794)
			(stroke
				(width 0.1)
				(type default)
			)
			(layer "B.Fab")
		)
		(fp_line
			(start 0.12065 -0.305054)
			(end 0.12065 -0.2794)
			(stroke
				(width 0.1)
				(type default)
			)
			(layer "B.Fab")
		)
		(fp_line
			(start 0.12065 -0.2794)
			(end -0.12065 -0.2794)
			(stroke
				(width 0.1)
				(type default)
			)
			(layer "B.Fab")
		)
		(fp_line
			(start 0.12065 0.2794)
			(end 0.12065 0.3048)
			(stroke
				(width 0.1)
				(type default)
			)
			(layer "B.Fab")
		)
		(fp_line
			(start 0.12065 0.3048)
			(end 0.67945 0.3048)
			(stroke
				(width 0.1)
				(type default)
			)
			(layer "B.Fab")
		)
		(fp_line
			(start 0.67945 -0.305054)
			(end 0.12065 -0.305054)
			(stroke
				(width 0.1)
				(type default)
			)
			(layer "B.Fab")
		)
		(fp_line
			(start 0.67945 0.3048)
			(end 0.67945 -0.305054)
			(stroke
				(width 0.1)
				(type default)
			)
			(layer "B.Fab")
		)
		(pad "1" smd circle
			(at 0.40005 0 180)
			(size 0 0)
			(layers "B.Cu" "B.Mask" "B.Paste")
			(net "PVDDCR_SOC_P0")
		)
		(pad "2" smd circle
			(at -0.40005 0 180)
			(size 0 0)
			(layers "B.Cu" "B.Mask" "B.Paste")
			(net "GND")
		)
	)
	(footprint ""
		(layer "B.Cu")
		(at 204.03312 -331.027786 -90)
		(property "Reference" "PC130"
			(at 0 0 90)
			(layer "B.SilkS")
			(hide yes)
			(effects
				(font
					(size 1.27 1.27)
				)
				(justify mirror)
			)
		)
		(property "Value" ""
			(at 0 0 90)
			(layer "B.Fab")
			(effects
				(font
					(size 1.27 1.27)
				)
				(justify mirror)
			)
		)
		(duplicate_pad_numbers_are_jumpers no)
		(fp_line
			(start -1.524 0.762)
			(end 1.524 0.762)
			(stroke
				(width 0.1524)
				(type default)
			)
			(layer "B.SilkS")
		)
		(fp_line
			(start 1.524 0.762)
			(end 1.524 -0.762)
			(stroke
				(width 0.1524)
				(type default)
			)
			(layer "B.SilkS")
		)
		(fp_line
			(start -1.524 -0.762)
			(end -1.524 0.762)
			(stroke
				(width 0.1524)
				(type default)
			)
			(layer "B.SilkS")
		)
		(fp_line
			(start 1.524 -0.762)
			(end -1.524 -0.762)
			(stroke
				(width 0.1524)
				(type default)
			)
			(layer "B.SilkS")
		)
		(fp_line
			(start -1.1049 0.724916)
			(end -1.1049 -0.724916)
			(stroke
				(width 0.1)
				(type default)
			)
			(layer "B.Fab")
		)
		(fp_line
			(start 1.1049 0.724916)
			(end -1.1049 0.724916)
			(stroke
				(width 0.1)
				(type default)
			)
			(layer "B.Fab")
		)
		(fp_line
			(start -1.1049 -0.724916)
			(end 1.1049 -0.724916)
			(stroke
				(width 0.1)
				(type default)
			)
			(layer "B.Fab")
		)
		(fp_line
			(start 1.1049 -0.724916)
			(end 1.1049 0.724916)
			(stroke
				(width 0.1)
				(type default)
			)
			(layer "B.Fab")
		)
		(pad "1" smd rect
			(at 0.889 0 270)
			(size 1.016 1.27)
			(layers "B.Cu" "B.Mask" "B.Paste")
			(net "PVDD_33_S5")
		)
		(pad "2" smd rect
			(at -0.889 0 270)
			(size 1.016 1.27)
			(layers "B.Cu" "B.Mask" "B.Paste")
			(net "GND")
		)
	)
	(footprint ""
		(layer "B.Cu")
		(at 54.591204 -390.560052 90)
		(property "Reference" "C261"
			(at 0 0 90)
			(layer "B.SilkS")
			(hide yes)
			(effects
				(font
					(size 1.27 1.27)
				)
				(justify mirror)
			)
		)
		(property "Value" ""
			(at 0 0 90)
			(layer "B.Fab")
			(effects
				(font
					(size 1.27 1.27)
				)
				(justify mirror)
			)
		)
		(duplicate_pad_numbers_are_jumpers no)
		(fp_line
			(start 0.7874 -0.4064)
			(end -0.7874 -0.4064)
			(stroke
				(width 0.1524)
				(type default)
			)
			(layer "B.SilkS")
		)
		(fp_line
			(start -0.7874 -0.4064)
			(end -0.7874 0.4064)
			(stroke
				(width 0.1524)
				(type default)
			)
			(layer "B.SilkS")
		)
		(fp_line
			(start 0.7874 0.4064)
			(end 0.7874 -0.4064)
			(stroke
				(width 0.1524)
				(type default)
			)
			(layer "B.SilkS")
		)
		(fp_line
			(start -0.7874 0.4064)
			(end 0.7874 0.4064)
			(stroke
				(width 0.1524)
				(type default)
			)
			(layer "B.SilkS")
		)
		(fp_line
			(start 0.67945 -0.305054)
			(end 0.12065 -0.305054)
			(stroke
				(width 0.1)
				(type default)
			)
			(layer "B.Fab")
		)
		(fp_line
			(start 0.12065 -0.305054)
			(end 0.12065 -0.2794)
			(stroke
				(width 0.1)
				(type default)
			)
			(layer "B.Fab")
		)
		(fp_line
			(start -0.12065 -0.3048)
			(end -0.67945 -0.3048)
			(stroke
				(width 0.1)
				(type default)
			)
			(layer "B.Fab")
		)
		(fp_line
			(start -0.67945 -0.3048)
			(end -0.67945 0.3048)
			(stroke
				(width 0.1)
				(type default)
			)
			(layer "B.Fab")
		)
		(fp_line
			(start 0.12065 -0.2794)
			(end -0.12065 -0.2794)
			(stroke
				(width 0.1)
				(type default)
			)
			(layer "B.Fab")
		)
		(fp_line
			(start -0.12065 -0.2794)
			(end -0.12065 -0.3048)
			(stroke
				(width 0.1)
				(type default)
			)
			(layer "B.Fab")
		)
		(fp_line
			(start 0.12065 0.2794)
			(end 0.12065 0.3048)
			(stroke
				(width 0.1)
				(type default)
			)
			(layer "B.Fab")
		)
		(fp_line
			(start -0.120396 0.2794)
			(end 0.12065 0.2794)
			(stroke
				(width 0.1)
				(type default)
			)
			(layer "B.Fab")
		)
		(fp_line
			(start 0.67945 0.3048)
			(end 0.67945 -0.305054)
			(stroke
				(width 0.1)
				(type default)
			)
			(layer "B.Fab")
		)
		(fp_line
			(start 0.12065 0.3048)
			(end 0.67945 0.3048)
			(stroke
				(width 0.1)
				(type default)
			)
			(layer "B.Fab")
		)
		(fp_line
			(start -0.120396 0.3048)
			(end -0.120396 0.2794)
			(stroke
				(width 0.1)
				(type default)
			)
			(layer "B.Fab")
		)
		(fp_line
			(start -0.67945 0.3048)
			(end -0.120396 0.3048)
			(stroke
				(width 0.1)
				(type default)
			)
			(layer "B.Fab")
		)
		(pad "1" smd circle
			(at 0.40005 0 270)
			(size 0 0)
			(layers "B.Cu" "B.Mask" "B.Paste")
			(net "P0V9_CPU1_RT_2D")
		)
		(pad "2" smd circle
			(at -0.40005 0 270)
			(size 0 0)
			(layers "B.Cu" "B.Mask" "B.Paste")
			(net "GND")
		)
	)
	(footprint ""
		(layer "B.Cu")
		(at 141.977872 -64.04229 90)
		(property "Reference" "R14"
			(at 0 0 90)
			(layer "B.SilkS")
			(hide yes)
			(effects
				(font
					(size 1.27 1.27)
				)
				(justify mirror)
			)
		)
		(property "Value" ""
			(at 0 0 90)
			(layer "B.Fab")
			(effects
				(font
					(size 1.27 1.27)
				)
				(justify mirror)
			)
		)
		(duplicate_pad_numbers_are_jumpers no)
		(fp_line
			(start 0.7874 -0.4064)
			(end -0.7874 -0.4064)
			(stroke
				(width 0.1524)
				(type default)
			)
			(layer "B.SilkS")
		)
		(fp_line
			(start -0.7874 -0.4064)
			(end -0.7874 0.4064)
			(stroke
				(width 0.1524)
				(type default)
			)
			(layer "B.SilkS")
		)
		(fp_line
			(start 0.7874 0.4064)
			(end 0.7874 -0.4064)
			(stroke
				(width 0.1524)
				(type default)
			)
			(layer "B.SilkS")
		)
		(fp_line
			(start -0.7874 0.4064)
			(end 0.7874 0.4064)
			(stroke
				(width 0.1524)
				(type default)
			)
			(layer "B.SilkS")
		)
		(fp_line
			(start 0.67945 -0.305054)
			(end 0.12065 -0.305054)
			(stroke
				(width 0.1)
				(type default)
			)
			(layer "B.Fab")
		)
		(fp_line
			(start 0.12065 -0.305054)
			(end 0.12065 -0.2794)
			(stroke
				(width 0.1)
				(type default)
			)
			(layer "B.Fab")
		)
		(fp_line
			(start -0.12065 -0.3048)
			(end -0.67945 -0.3048)
			(stroke
				(width 0.1)
				(type default)
			)
			(layer "B.Fab")
		)
		(fp_line
			(start -0.67945 -0.3048)
			(end -0.67945 0.3048)
			(stroke
				(width 0.1)
				(type default)
			)
			(layer "B.Fab")
		)
		(fp_line
			(start 0.12065 -0.2794)
			(end -0.12065 -0.2794)
			(stroke
				(width 0.1)
				(type default)
			)
			(layer "B.Fab")
		)
		(fp_line
			(start -0.12065 -0.2794)
			(end -0.12065 -0.3048)
			(stroke
				(width 0.1)
				(type default)
			)
			(layer "B.Fab")
		)
		(fp_line
			(start 0.12065 0.2794)
			(end 0.12065 0.3048)
			(stroke
				(width 0.1)
				(type default)
			)
			(layer "B.Fab")
		)
		(fp_line
			(start -0.120396 0.2794)
			(end 0.12065 0.2794)
			(stroke
				(width 0.1)
				(type default)
			)
			(layer "B.Fab")
		)
		(fp_line
			(start 0.67945 0.3048)
			(end 0.67945 -0.305054)
			(stroke
				(width 0.1)
				(type default)
			)
			(layer "B.Fab")
		)
		(fp_line
			(start 0.12065 0.3048)
			(end 0.67945 0.3048)
			(stroke
				(width 0.1)
				(type default)
			)
			(layer "B.Fab")
		)
		(fp_line
			(start -0.120396 0.3048)
			(end -0.120396 0.2794)
			(stroke
				(width 0.1)
				(type default)
			)
			(layer "B.Fab")
		)
		(fp_line
			(start -0.67945 0.3048)
			(end -0.120396 0.3048)
			(stroke
				(width 0.1)
				(type default)
			)
			(layer "B.Fab")
		)
		(pad "1" smd circle
			(at 0.40005 0 270)
			(size 0 0)
			(layers "B.Cu" "B.Mask" "B.Paste")
			(net "JTAG_PLD_TMS")
		)
		(pad "2" smd circle
			(at -0.40005 0 270)
			(size 0 0)
			(layers "B.Cu" "B.Mask" "B.Paste")
			(net "JTAG_SCM_PLD_TMS")
		)
	)
	(footprint ""
		(layer "B.Cu")
		(at 200.952608 -121.753376 180)
		(property "Reference" "R4563"
			(at 0 0 0)
			(layer "B.SilkS")
			(hide yes)
			(effects
				(font
					(size 1.27 1.27)
				)
				(justify mirror)
			)
		)
		(property "Value" ""
			(at 0 0 0)
			(layer "B.Fab")
			(effects
				(font
					(size 1.27 1.27)
				)
				(justify mirror)
			)
		)
		(duplicate_pad_numbers_are_jumpers no)
		(fp_line
			(start 0.7874 0.4064)
			(end 0.7874 -0.4064)
			(stroke
				(width 0.1524)
				(type default)
			)
			(layer "B.SilkS")
		)
		(fp_line
			(start 0.7874 -0.4064)
			(end -0.7874 -0.4064)
			(stroke
				(width 0.1524)
				(type default)
			)
			(layer "B.SilkS")
		)
		(fp_line
			(start -0.7874 0.4064)
			(end 0.7874 0.4064)
			(stroke
				(width 0.1524)
				(type default)
			)
			(layer "B.SilkS")
		)
		(fp_line
			(start -0.7874 -0.4064)
			(end -0.7874 0.4064)
			(stroke
				(width 0.1524)
				(type default)
			)
			(layer "B.SilkS")
		)
		(fp_line
			(start 0.67945 0.3048)
			(end 0.67945 -0.305054)
			(stroke
				(width 0.1)
				(type default)
			)
			(layer "B.Fab")
		)
		(fp_line
			(start 0.67945 -0.305054)
			(end 0.12065 -0.305054)
			(stroke
				(width 0.1)
				(type default)
			)
			(layer "B.Fab")
		)
		(fp_line
			(start 0.12065 0.3048)
			(end 0.67945 0.3048)
			(stroke
				(width 0.1)
				(type default)
			)
			(layer "B.Fab")
		)
		(fp_line
			(start 0.12065 0.2794)
			(end 0.12065 0.3048)
			(stroke
				(width 0.1)
				(type default)
			)
			(layer "B.Fab")
		)
		(fp_line
			(start 0.12065 -0.2794)
			(end -0.12065 -0.2794)
			(stroke
				(width 0.1)
				(type default)
			)
			(layer "B.Fab")
		)
		(fp_line
			(start 0.12065 -0.305054)
			(end 0.12065 -0.2794)
			(stroke
				(width 0.1)
				(type default)
			)
			(layer "B.Fab")
		)
		(fp_line
			(start -0.120396 0.3048)
			(end -0.120396 0.2794)
			(stroke
				(width 0.1)
				(type default)
			)
			(layer "B.Fab")
		)
		(fp_line
			(start -0.120396 0.2794)
			(end 0.12065 0.2794)
			(stroke
				(width 0.1)
				(type default)
			)
			(layer "B.Fab")
		)
		(fp_line
			(start -0.12065 -0.2794)
			(end -0.12065 -0.3048)
			(stroke
				(width 0.1)
				(type default)
			)
			(layer "B.Fab")
		)
		(fp_line
			(start -0.12065 -0.3048)
			(end -0.67945 -0.3048)
			(stroke
				(width 0.1)
				(type default)
			)
			(layer "B.Fab")
		)
		(fp_line
			(start -0.67945 0.3048)
			(end -0.120396 0.3048)
			(stroke
				(width 0.1)
				(type default)
			)
			(layer "B.Fab")
		)
		(fp_line
			(start -0.67945 -0.3048)
			(end -0.67945 0.3048)
			(stroke
				(width 0.1)
				(type default)
			)
			(layer "B.Fab")
		)
		(pad "1" smd circle
			(at 0.40005 0)
			(size 0 0)
			(layers "B.Cu" "B.Mask" "B.Paste")
			(net "SWB_HSC_PWRGD_ISO_R")
		)
		(pad "2" smd circle
			(at -0.40005 0)
			(size 0 0)
			(layers "B.Cu" "B.Mask" "B.Paste")
			(net "SWB_HSC_PWRGD_ISO")
		)
	)
	(footprint ""
		(layer "B.Cu")
		(at 166.696644 -9.013444 -90)
		(property "Reference" "R2204"
			(at 0 0 90)
			(layer "B.SilkS")
			(hide yes)
			(effects
				(font
					(size 1.27 1.27)
				)
				(justify mirror)
			)
		)
		(property "Value" ""
			(at 0 0 90)
			(layer "B.Fab")
			(effects
				(font
					(size 1.27 1.27)
				)
				(justify mirror)
			)
		)
		(duplicate_pad_numbers_are_jumpers no)
		(fp_line
			(start -0.7874 0.4064)
			(end 0.7874 0.4064)
			(stroke
				(width 0.1524)
				(type default)
			)
			(layer "B.SilkS")
		)
		(fp_line
			(start 0.7874 0.4064)
			(end 0.7874 -0.4064)
			(stroke
				(width 0.1524)
				(type default)
			)
			(layer "B.SilkS")
		)
		(fp_line
			(start -0.7874 -0.4064)
			(end -0.7874 0.4064)
			(stroke
				(width 0.1524)
				(type default)
			)
			(layer "B.SilkS")
		)
		(fp_line
			(start 0.7874 -0.4064)
			(end -0.7874 -0.4064)
			(stroke
				(width 0.1524)
				(type default)
			)
			(layer "B.SilkS")
		)
		(fp_line
			(start -0.67945 0.3048)
			(end -0.120396 0.3048)
			(stroke
				(width 0.1)
				(type default)
			)
			(layer "B.Fab")
		)
		(fp_line
			(start -0.120396 0.3048)
			(end -0.120396 0.2794)
			(stroke
				(width 0.1)
				(type default)
			)
			(layer "B.Fab")
		)
		(fp_line
			(start 0.12065 0.3048)
			(end 0.67945 0.3048)
			(stroke
				(width 0.1)
				(type default)
			)
			(layer "B.Fab")
		)
		(fp_line
			(start 0.67945 0.3048)
			(end 0.67945 -0.305054)
			(stroke
				(width 0.1)
				(type default)
			)
			(layer "B.Fab")
		)
		(fp_line
			(start -0.120396 0.2794)
			(end 0.12065 0.2794)
			(stroke
				(width 0.1)
				(type default)
			)
			(layer "B.Fab")
		)
		(fp_line
			(start 0.12065 0.2794)
			(end 0.12065 0.3048)
			(stroke
				(width 0.1)
				(type default)
			)
			(layer "B.Fab")
		)
		(fp_line
			(start -0.12065 -0.2794)
			(end -0.12065 -0.3048)
			(stroke
				(width 0.1)
				(type default)
			)
			(layer "B.Fab")
		)
		(fp_line
			(start 0.12065 -0.2794)
			(end -0.12065 -0.2794)
			(stroke
				(width 0.1)
				(type default)
			)
			(layer "B.Fab")
		)
		(fp_line
			(start -0.67945 -0.3048)
			(end -0.67945 0.3048)
			(stroke
				(width 0.1)
				(type default)
			)
			(layer "B.Fab")
		)
		(fp_line
			(start -0.12065 -0.3048)
			(end -0.67945 -0.3048)
			(stroke
				(width 0.1)
				(type default)
			)
			(layer "B.Fab")
		)
		(fp_line
			(start 0.12065 -0.305054)
			(end 0.12065 -0.2794)
			(stroke
				(width 0.1)
				(type default)
			)
			(layer "B.Fab")
		)
		(fp_line
			(start 0.67945 -0.305054)
			(end 0.12065 -0.305054)
			(stroke
				(width 0.1)
				(type default)
			)
			(layer "B.Fab")
		)
		(pad "1" smd circle
			(at 0.40005 0 90)
			(size 0 0)
			(layers "B.Cu" "B.Mask" "B.Paste")
			(net "P3V3_AUX")
		)
		(pad "2" smd circle
			(at -0.40005 0 90)
			(size 0 0)
			(layers "B.Cu" "B.Mask" "B.Paste")
			(net "SMB_PCIE0_3V3AUX_SCL")
		)
	)
	(footprint ""
		(layer "B.Cu")
		(at 237.871 -216.027 180)
		(property "Reference" "R361"
			(at 0 0 0)
			(layer "B.SilkS")
			(hide yes)
			(effects
				(font
					(size 1.27 1.27)
				)
				(justify mirror)
			)
		)
		(property "Value" ""
			(at 0 0 0)
			(layer "B.Fab")
			(effects
				(font
					(size 1.27 1.27)
				)
				(justify mirror)
			)
		)
		(duplicate_pad_numbers_are_jumpers no)
		(fp_line
			(start 0.7874 0.4064)
			(end 0.7874 -0.4064)
			(stroke
				(width 0.1524)
				(type default)
			)
			(layer "B.SilkS")
		)
		(fp_line
			(start 0.7874 -0.4064)
			(end -0.7874 -0.4064)
			(stroke
				(width 0.1524)
				(type default)
			)
			(layer "B.SilkS")
		)
		(fp_line
			(start -0.7874 0.4064)
			(end 0.7874 0.4064)
			(stroke
				(width 0.1524)
				(type default)
			)
			(layer "B.SilkS")
		)
		(fp_line
			(start -0.7874 -0.4064)
			(end -0.7874 0.4064)
			(stroke
				(width 0.1524)
				(type default)
			)
			(layer "B.SilkS")
		)
		(fp_line
			(start 0.67945 0.3048)
			(end 0.67945 -0.305054)
			(stroke
				(width 0.1)
				(type default)
			)
			(layer "B.Fab")
		)
		(fp_line
			(start 0.67945 -0.305054)
			(end 0.12065 -0.305054)
			(stroke
				(width 0.1)
				(type default)
			)
			(layer "B.Fab")
		)
		(fp_line
			(start 0.12065 0.3048)
			(end 0.67945 0.3048)
			(stroke
				(width 0.1)
				(type default)
			)
			(layer "B.Fab")
		)
		(fp_line
			(start 0.12065 0.2794)
			(end 0.12065 0.3048)
			(stroke
				(width 0.1)
				(type default)
			)
			(layer "B.Fab")
		)
		(fp_line
			(start 0.12065 -0.2794)
			(end -0.12065 -0.2794)
			(stroke
				(width 0.1)
				(type default)
			)
			(layer "B.Fab")
		)
		(fp_line
			(start 0.12065 -0.305054)
			(end 0.12065 -0.2794)
			(stroke
				(width 0.1)
				(type default)
			)
			(layer "B.Fab")
		)
		(fp_line
			(start -0.120396 0.3048)
			(end -0.120396 0.2794)
			(stroke
				(width 0.1)
				(type default)
			)
			(layer "B.Fab")
		)
		(fp_line
			(start -0.120396 0.2794)
			(end 0.12065 0.2794)
			(stroke
				(width 0.1)
				(type default)
			)
			(layer "B.Fab")
		)
		(fp_line
			(start -0.12065 -0.2794)
			(end -0.12065 -0.3048)
			(stroke
				(width 0.1)
				(type default)
			)
			(layer "B.Fab")
		)
		(fp_line
			(start -0.12065 -0.3048)
			(end -0.67945 -0.3048)
			(stroke
				(width 0.1)
				(type default)
			)
			(layer "B.Fab")
		)
		(fp_line
			(start -0.67945 0.3048)
			(end -0.120396 0.3048)
			(stroke
				(width 0.1)
				(type default)
			)
			(layer "B.Fab")
		)
		(fp_line
			(start -0.67945 -0.3048)
			(end -0.67945 0.3048)
			(stroke
				(width 0.1)
				(type default)
			)
			(layer "B.Fab")
		)
		(pad "1" smd circle
			(at 0.40005 0)
			(size 0 0)
			(layers "B.Cu" "B.Mask" "B.Paste")
			(net "P3V3")
		)
		(pad "2" smd circle
			(at -0.40005 0)
			(size 0 0)
			(layers "B.Cu" "B.Mask" "B.Paste")
			(net "SMB_CPU0_CPU1_APML_BUF1_SCL_R2")
		)
	)
	(footprint ""
		(layer "B.Cu")
		(at 230.886 -232.156 90)
		(property "Reference" "C9"
			(at 0 0 90)
			(layer "B.SilkS")
			(hide yes)
			(effects
				(font
					(size 1.27 1.27)
				)
				(justify mirror)
			)
		)
		(property "Value" ""
			(at 0 0 90)
			(layer "B.Fab")
			(effects
				(font
					(size 1.27 1.27)
				)
				(justify mirror)
			)
		)
		(duplicate_pad_numbers_are_jumpers no)
		(fp_line
			(start 0.7874 -0.4064)
			(end -0.7874 -0.4064)
			(stroke
				(width 0.1524)
				(type default)
			)
			(layer "B.SilkS")
		)
		(fp_line
			(start -0.7874 -0.4064)
			(end -0.7874 0.4064)
			(stroke
				(width 0.1524)
				(type default)
			)
			(layer "B.SilkS")
		)
		(fp_line
			(start 0.7874 0.4064)
			(end 0.7874 -0.4064)
			(stroke
				(width 0.1524)
				(type default)
			)
			(layer "B.SilkS")
		)
		(fp_line
			(start -0.7874 0.4064)
			(end 0.7874 0.4064)
			(stroke
				(width 0.1524)
				(type default)
			)
			(layer "B.SilkS")
		)
		(fp_line
			(start 0.67945 -0.305054)
			(end 0.12065 -0.305054)
			(stroke
				(width 0.1)
				(type default)
			)
			(layer "B.Fab")
		)
		(fp_line
			(start 0.12065 -0.305054)
			(end 0.12065 -0.2794)
			(stroke
				(width 0.1)
				(type default)
			)
			(layer "B.Fab")
		)
		(fp_line
			(start -0.12065 -0.3048)
			(end -0.67945 -0.3048)
			(stroke
				(width 0.1)
				(type default)
			)
			(layer "B.Fab")
		)
		(fp_line
			(start -0.67945 -0.3048)
			(end -0.67945 0.3048)
			(stroke
				(width 0.1)
				(type default)
			)
			(layer "B.Fab")
		)
		(fp_line
			(start 0.12065 -0.2794)
			(end -0.12065 -0.2794)
			(stroke
				(width 0.1)
				(type default)
			)
			(layer "B.Fab")
		)
		(fp_line
			(start -0.12065 -0.2794)
			(end -0.12065 -0.3048)
			(stroke
				(width 0.1)
				(type default)
			)
			(layer "B.Fab")
		)
		(fp_line
			(start 0.12065 0.2794)
			(end 0.12065 0.3048)
			(stroke
				(width 0.1)
				(type default)
			)
			(layer "B.Fab")
		)
		(fp_line
			(start -0.120396 0.2794)
			(end 0.12065 0.2794)
			(stroke
				(width 0.1)
				(type default)
			)
			(layer "B.Fab")
		)
		(fp_line
			(start 0.67945 0.3048)
			(end 0.67945 -0.305054)
			(stroke
				(width 0.1)
				(type default)
			)
			(layer "B.Fab")
		)
		(fp_line
			(start 0.12065 0.3048)
			(end 0.67945 0.3048)
			(stroke
				(width 0.1)
				(type default)
			)
			(layer "B.Fab")
		)
		(fp_line
			(start -0.120396 0.3048)
			(end -0.120396 0.2794)
			(stroke
				(width 0.1)
				(type default)
			)
			(layer "B.Fab")
		)
		(fp_line
			(start -0.67945 0.3048)
			(end -0.120396 0.3048)
			(stroke
				(width 0.1)
				(type default)
			)
			(layer "B.Fab")
		)
		(pad "1" smd circle
			(at 0.40005 0 270)
			(size 0 0)
			(layers "B.Cu" "B.Mask" "B.Paste")
			(net "I3C_MUX_CPU0_VIO")
		)
		(pad "2" smd circle
			(at -0.40005 0 270)
			(size 0 0)
			(layers "B.Cu" "B.Mask" "B.Paste")
			(net "GND")
		)
	)
	(footprint ""
		(layer "B.Cu")
		(at 314.965588 2.542794 180)
		(property "Reference" "J70"
			(at 4.55422 -0.940308 270)
			(unlocked yes)
			(layer "B.SilkS")
			(effects
				(font
					(size 0.7874 0.5842)
					(thickness 0.1524)
				)
				(justify left mirror)
			)
		)
		(property "Value" ""
			(at 0 0 0)
			(layer "B.Fab")
			(effects
				(font
					(size 1.27 1.27)
				)
				(justify mirror)
			)
		)
		(duplicate_pad_numbers_are_jumpers no)
		(fp_line
			(start 1.2192 2.06756)
			(end 1.2192 -2.06756)
			(stroke
				(width 0.1524)
				(type default)
			)
			(layer "B.SilkS")
		)
		(fp_line
			(start 1.2192 -2.06756)
			(end -1.2192 -2.06756)
			(stroke
				(width 0.1524)
				(type default)
			)
			(layer "B.SilkS")
		)
		(fp_line
			(start -1.2192 2.06756)
			(end 1.2192 2.06756)
			(stroke
				(width 0.1524)
				(type default)
			)
			(layer "B.SilkS")
		)
		(fp_line
			(start -1.2192 -2.06756)
			(end -1.2192 2.06756)
			(stroke
				(width 0.1524)
				(type default)
			)
			(layer "B.SilkS")
		)
		(pad "" np_thru_hole circle
			(at -3.4671 -1.27 90)
			(size 1.0414 1.0414)
			(drill 1.0414)
			(layers "*.Cu" "*.Mask")
			(clearance 0.381)
			(thermal_gap 0.381)
		)
		(pad "" np_thru_hole circle
			(at -3.4671 1.27 90)
			(size 1.0414 1.0414)
			(drill 1.0414)
			(layers "*.Cu" "*.Mask")
			(clearance 0.381)
			(thermal_gap 0.381)
		)
		(pad "" np_thru_hole circle
			(at 2.8829 -1.27 90)
			(size 1.0414 1.0414)
			(drill 1.0414)
			(layers "*.Cu" "*.Mask")
			(clearance 0.381)
			(thermal_gap 0.381)
		)
		(pad "" np_thru_hole circle
			(at 2.8829 1.27 90)
			(size 1.0414 1.0414)
			(drill 1.0414)
			(layers "*.Cu" "*.Mask")
			(clearance 0.381)
			(thermal_gap 0.381)
		)
		(pad "1" smd rect
			(at -0.8255 -0.249936 90)
			(size 0.3048 0.508)
			(layers "B.Cu" "B.Mask" "B.Paste")
			(net "DELTA_L_85_5INCH_BOT_DN")
		)
		(pad "2" smd rect
			(at -0.8255 0.249936 90)
			(size 0.3048 0.508)
			(layers "B.Cu" "B.Mask" "B.Paste")
			(net "DELTA_L_85_5INCH_BOT_DP")
		)
		(pad "3" smd circle
			(at 0 0)
			(size 0 0)
			(layers "B.Cu" "B.Mask" "B.Paste")
			(net "DELTA_L_GND_1")
		)
		(zone
			(layers "F.Cu" "B.Cu" "In1.Cu" "In2.Cu" "In3.Cu" "In4.Cu" "In5.Cu" "In6.Cu"
				"In7.Cu" "In8.Cu" "In9.Cu" "In10.Cu" "In11.Cu" "In12.Cu" "In13.Cu" "In14.Cu"
				"In15.Cu" "In16.Cu"
			)
			(hatch none 0.5)
			(connect_pads
				(clearance 0)
			)
			(min_thickness 0.25)
			(keepout
				(tracks not_allowed)
				(vias allowed)
				(pads allowed)
				(copperpour not_allowed)
				(footprints allowed)
			)
			(placement
				(enabled no)
				(sheetname "")
			)
			(fill
				(thermal_gap 0.5)
				(thermal_bridge_width 0.5)
				(island_removal_mode 0)
			)
			(polygon
				(pts
					(arc
						(start 313.009788 1.272794)
						(mid 311.155588 1.272794)
						(end 313.009788 1.272794)
					)
				)
			)
		)
		(zone
			(layers "F.Cu" "B.Cu" "In1.Cu" "In2.Cu" "In3.Cu" "In4.Cu" "In5.Cu" "In6.Cu"
				"In7.Cu" "In8.Cu" "In9.Cu" "In10.Cu" "In11.Cu" "In12.Cu" "In13.Cu" "In14.Cu"
				"In15.Cu" "In16.Cu"
			)
			(hatch none 0.5)
			(connect_pads
				(clearance 0)
			)
			(min_thickness 0.25)
			(keepout
				(tracks not_allowed)
				(vias allowed)
				(pads allowed)
				(copperpour not_allowed)
				(footprints allowed)
			)
			(placement
				(enabled no)
				(sheetname "")
			)
			(fill
				(thermal_gap 0.5)
				(thermal_bridge_width 0.5)
				(island_removal_mode 0)
			)
			(polygon
				(pts
					(arc
						(start 313.009788 3.812794)
						(mid 311.155588 3.812794)
						(end 313.009788 3.812794)
					)
				)
			)
		)
		(zone
			(layers "F.Cu" "B.Cu" "In1.Cu" "In2.Cu" "In3.Cu" "In4.Cu" "In5.Cu" "In6.Cu"
				"In7.Cu" "In8.Cu" "In9.Cu" "In10.Cu" "In11.Cu" "In12.Cu" "In13.Cu" "In14.Cu"
				"In15.Cu" "In16.Cu"
			)
			(hatch none 0.5)
			(connect_pads
				(clearance 0)
			)
			(min_thickness 0.25)
			(keepout
				(tracks not_allowed)
				(vias allowed)
				(pads allowed)
				(copperpour not_allowed)
				(footprints allowed)
			)
			(placement
				(enabled no)
				(sheetname "")
			)
			(fill
				(thermal_gap 0.5)
				(thermal_bridge_width 0.5)
				(island_removal_mode 0)
			)
			(polygon
				(pts
					(arc
						(start 319.359788 1.272794)
						(mid 317.505588 1.272794)
						(end 319.359788 1.272794)
					)
				)
			)
		)
		(zone
			(layers "F.Cu" "B.Cu" "In1.Cu" "In2.Cu" "In3.Cu" "In4.Cu" "In5.Cu" "In6.Cu"
				"In7.Cu" "In8.Cu" "In9.Cu" "In10.Cu" "In11.Cu" "In12.Cu" "In13.Cu" "In14.Cu"
				"In15.Cu" "In16.Cu"
			)
			(hatch none 0.5)
			(connect_pads
				(clearance 0)
			)
			(min_thickness 0.25)
			(keepout
				(tracks not_allowed)
				(vias allowed)
				(pads allowed)
				(copperpour not_allowed)
				(footprints allowed)
			)
			(placement
				(enabled no)
				(sheetname "")
			)
			(fill
				(thermal_gap 0.5)
				(thermal_bridge_width 0.5)
				(island_removal_mode 0)
			)
			(polygon
				(pts
					(arc
						(start 319.359788 3.812794)
						(mid 317.505588 3.812794)
						(end 319.359788 3.812794)
					)
				)
			)
		)
		(zone
			(layer "B.Cu")
			(hatch none 0.5)
			(connect_pads
				(clearance 0)
			)
			(min_thickness 0.25)
			(keepout
				(tracks not_allowed)
				(vias allowed)
				(pads allowed)
				(copperpour not_allowed)
				(footprints allowed)
			)
			(placement
				(enabled no)
				(sheetname "")
			)
			(fill
				(thermal_gap 0.5)
				(thermal_bridge_width 0.5)
				(island_removal_mode 0)
			)
			(polygon
				(pts
					(xy 316.083188 3.091434) (xy 316.083188 2.99593) (xy 315.486288 2.99593) (xy 315.486288 2.58953)
					(xy 316.083188 2.58953) (xy 316.083188 2.496058) (xy 315.486288 2.496058) (xy 315.486288 2.089658)
					(xy 316.083188 2.089658) (xy 316.083188 1.994154) (xy 315.384688 1.994154) (xy 315.384688 3.091434)
				)
			)
		)
	)
	(footprint ""
		(layer "B.Cu")
		(at 393.070588 -180.078634 90)
		(property "Reference" "PR351"
			(at 0 0 90)
			(layer "B.SilkS")
			(hide yes)
			(effects
				(font
					(size 1.27 1.27)
				)
				(justify mirror)
			)
		)
		(property "Value" ""
			(at 0 0 90)
			(layer "B.Fab")
			(effects
				(font
					(size 1.27 1.27)
				)
				(justify mirror)
			)
		)
		(duplicate_pad_numbers_are_jumpers no)
		(fp_line
			(start 0.7874 -0.4064)
			(end -0.7874 -0.4064)
			(stroke
				(width 0.1524)
				(type default)
			)
			(layer "B.SilkS")
		)
		(fp_line
			(start -0.7874 -0.4064)
			(end -0.7874 0.4064)
			(stroke
				(width 0.1524)
				(type default)
			)
			(layer "B.SilkS")
		)
		(fp_line
			(start 0.7874 0.4064)
			(end 0.7874 -0.4064)
			(stroke
				(width 0.1524)
				(type default)
			)
			(layer "B.SilkS")
		)
		(fp_line
			(start -0.7874 0.4064)
			(end 0.7874 0.4064)
			(stroke
				(width 0.1524)
				(type default)
			)
			(layer "B.SilkS")
		)
		(fp_line
			(start 0.67945 -0.305054)
			(end 0.12065 -0.305054)
			(stroke
				(width 0.1)
				(type default)
			)
			(layer "B.Fab")
		)
		(fp_line
			(start 0.12065 -0.305054)
			(end 0.12065 -0.2794)
			(stroke
				(width 0.1)
				(type default)
			)
			(layer "B.Fab")
		)
		(fp_line
			(start -0.12065 -0.3048)
			(end -0.67945 -0.3048)
			(stroke
				(width 0.1)
				(type default)
			)
			(layer "B.Fab")
		)
		(fp_line
			(start -0.67945 -0.3048)
			(end -0.67945 0.3048)
			(stroke
				(width 0.1)
				(type default)
			)
			(layer "B.Fab")
		)
		(fp_line
			(start 0.12065 -0.2794)
			(end -0.12065 -0.2794)
			(stroke
				(width 0.1)
				(type default)
			)
			(layer "B.Fab")
		)
		(fp_line
			(start -0.12065 -0.2794)
			(end -0.12065 -0.3048)
			(stroke
				(width 0.1)
				(type default)
			)
			(layer "B.Fab")
		)
		(fp_line
			(start 0.12065 0.2794)
			(end 0.12065 0.3048)
			(stroke
				(width 0.1)
				(type default)
			)
			(layer "B.Fab")
		)
		(fp_line
			(start -0.120396 0.2794)
			(end 0.12065 0.2794)
			(stroke
				(width 0.1)
				(type default)
			)
			(layer "B.Fab")
		)
		(fp_line
			(start 0.67945 0.3048)
			(end 0.67945 -0.305054)
			(stroke
				(width 0.1)
				(type default)
			)
			(layer "B.Fab")
		)
		(fp_line
			(start 0.12065 0.3048)
			(end 0.67945 0.3048)
			(stroke
				(width 0.1)
				(type default)
			)
			(layer "B.Fab")
		)
		(fp_line
			(start -0.120396 0.3048)
			(end -0.120396 0.2794)
			(stroke
				(width 0.1)
				(type default)
			)
			(layer "B.Fab")
		)
		(fp_line
			(start -0.67945 0.3048)
			(end -0.120396 0.3048)
			(stroke
				(width 0.1)
				(type default)
			)
			(layer "B.Fab")
		)
		(pad "1" smd circle
			(at 0.40005 0 270)
			(size 0 0)
			(layers "B.Cu" "B.Mask" "B.Paste")
			(net "PVDDCR_CPU0_P0_VOS4")
		)
		(pad "2" smd circle
			(at -0.40005 0 270)
			(size 0 0)
			(layers "B.Cu" "B.Mask" "B.Paste")
			(net "PVDDCR_CPU0_P0")
		)
	)
	(footprint ""
		(layer "B.Cu")
		(at 191.64046 -190.821564)
		(property "Reference" "R313"
			(at 0 0 0)
			(layer "B.SilkS")
			(hide yes)
			(effects
				(font
					(size 1.27 1.27)
				)
				(justify mirror)
			)
		)
		(property "Value" ""
			(at 0 0 0)
			(layer "B.Fab")
			(effects
				(font
					(size 1.27 1.27)
				)
				(justify mirror)
			)
		)
		(duplicate_pad_numbers_are_jumpers no)
		(fp_line
			(start -0.7874 -0.4064)
			(end -0.7874 0.4064)
			(stroke
				(width 0.1524)
				(type default)
			)
			(layer "B.SilkS")
		)
		(fp_line
			(start -0.7874 0.4064)
			(end 0.7874 0.4064)
			(stroke
				(width 0.1524)
				(type default)
			)
			(layer "B.SilkS")
		)
		(fp_line
			(start 0.7874 -0.4064)
			(end -0.7874 -0.4064)
			(stroke
				(width 0.1524)
				(type default)
			)
			(layer "B.SilkS")
		)
		(fp_line
			(start 0.7874 0.4064)
			(end 0.7874 -0.4064)
			(stroke
				(width 0.1524)
				(type default)
			)
			(layer "B.SilkS")
		)
		(fp_line
			(start -0.67945 -0.3048)
			(end -0.67945 0.3048)
			(stroke
				(width 0.1)
				(type default)
			)
			(layer "B.Fab")
		)
		(fp_line
			(start -0.67945 0.3048)
			(end -0.120396 0.3048)
			(stroke
				(width 0.1)
				(type default)
			)
			(layer "B.Fab")
		)
		(fp_line
			(start -0.12065 -0.3048)
			(end -0.67945 -0.3048)
			(stroke
				(width 0.1)
				(type default)
			)
			(layer "B.Fab")
		)
		(fp_line
			(start -0.12065 -0.2794)
			(end -0.12065 -0.3048)
			(stroke
				(width 0.1)
				(type default)
			)
			(layer "B.Fab")
		)
		(fp_line
			(start -0.120396 0.2794)
			(end 0.12065 0.2794)
			(stroke
				(width 0.1)
				(type default)
			)
			(layer "B.Fab")
		)
		(fp_line
			(start -0.120396 0.3048)
			(end -0.120396 0.2794)
			(stroke
				(width 0.1)
				(type default)
			)
			(layer "B.Fab")
		)
		(fp_line
			(start 0.12065 -0.305054)
			(end 0.12065 -0.2794)
			(stroke
				(width 0.1)
				(type default)
			)
			(layer "B.Fab")
		)
		(fp_line
			(start 0.12065 -0.2794)
			(end -0.12065 -0.2794)
			(stroke
				(width 0.1)
				(type default)
			)
			(layer "B.Fab")
		)
		(fp_line
			(start 0.12065 0.2794)
			(end 0.12065 0.3048)
			(stroke
				(width 0.1)
				(type default)
			)
			(layer "B.Fab")
		)
		(fp_line
			(start 0.12065 0.3048)
			(end 0.67945 0.3048)
			(stroke
				(width 0.1)
				(type default)
			)
			(layer "B.Fab")
		)
		(fp_line
			(start 0.67945 -0.305054)
			(end 0.12065 -0.305054)
			(stroke
				(width 0.1)
				(type default)
			)
			(layer "B.Fab")
		)
		(fp_line
			(start 0.67945 0.3048)
			(end 0.67945 -0.305054)
			(stroke
				(width 0.1)
				(type default)
			)
			(layer "B.Fab")
		)
		(pad "1" smd circle
			(at 0.40005 0 180)
			(size 0 0)
			(layers "B.Cu" "B.Mask" "B.Paste")
			(net "PWRGD_CHK_CPU1_DIMM")
		)
		(pad "2" smd circle
			(at -0.40005 0 180)
			(size 0 0)
			(layers "B.Cu" "B.Mask" "B.Paste")
			(net "PWRGD_CHGL_CPU1")
		)
	)
	(footprint ""
		(layer "B.Cu")
		(at 527.336512 -107.699302 180)
		(property "Reference" "DB12"
			(at 2.546096 -8.857742 270)
			(unlocked yes)
			(layer "B.SilkS")
			(effects
				(font
					(size 0.7874 0.5842)
					(thickness 0.1524)
				)
				(justify left mirror)
			)
		)
		(property "Value" ""
			(at 0 0 0)
			(layer "B.Fab")
			(effects
				(font
					(size 1.27 1.27)
				)
				(justify mirror)
			)
		)
		(duplicate_pad_numbers_are_jumpers no)
		(fp_line
			(start 3.330702 -4.771136)
			(end -3.330702 -4.771136)
			(stroke
				(width 0.1524)
				(type default)
			)
			(layer "B.SilkS")
		)
		(fp_line
			(start 0 4.011168)
			(end 3.330702 -4.771136)
			(stroke
				(width 0.1524)
				(type default)
			)
			(layer "B.SilkS")
		)
		(fp_line
			(start -3.330702 -4.771136)
			(end 0 4.011168)
			(stroke
				(width 0.1524)
				(type default)
			)
			(layer "B.SilkS")
		)
		(fp_line
			(start 3.330702 -4.771136)
			(end -3.330702 -4.771136)
			(stroke
				(width 0.1)
				(type default)
			)
			(layer "B.Fab")
		)
		(fp_line
			(start 0 4.011168)
			(end 3.330702 -4.771136)
			(stroke
				(width 0.1)
				(type default)
			)
			(layer "B.Fab")
		)
		(fp_line
			(start -3.330702 -4.771136)
			(end 0 4.011168)
			(stroke
				(width 0.1)
				(type default)
			)
			(layer "B.Fab")
		)
		(pad "1" thru_hole circle
			(at 0 0)
			(size 2.159 2.159)
			(drill 1.7018)
			(layers "*.Cu" "*.Mask")
			(remove_unused_layers no)
			(net "T1_GND")
			(clearance 0.0254)
			(thermal_gap 0.0254)
		)
		(pad "2" thru_hole circle
			(at 1.27 -3.348736)
			(size 2.159 2.159)
			(drill 1.7018)
			(layers "*.Cu" "*.Mask")
			(remove_unused_layers no)
			(net "TDR_SE_50_OHM_BOT")
			(clearance 0.0254)
			(thermal_gap 0.0254)
		)
		(pad "3" thru_hole circle
			(at -1.27 -3.348736)
			(size 2.159 2.159)
			(drill 1.7018)
			(layers "*.Cu" "*.Mask")
			(remove_unused_layers no)
			(net "TDR_SE_50_OHM_BOT")
			(clearance 0.0254)
			(thermal_gap 0.0254)
		)
	)
	(footprint ""
		(layer "B.Cu")
		(at 346.913454 -267.52931)
		(property "Reference" "C2512"
			(at 0 0 0)
			(layer "B.SilkS")
			(hide yes)
			(effects
				(font
					(size 1.27 1.27)
				)
				(justify mirror)
			)
		)
		(property "Value" ""
			(at 0 0 0)
			(layer "B.Fab")
			(effects
				(font
					(size 1.27 1.27)
				)
				(justify mirror)
			)
		)
		(duplicate_pad_numbers_are_jumpers no)
		(fp_line
			(start -0.7874 -0.4064)
			(end -0.7874 0.4064)
			(stroke
				(width 0.1524)
				(type default)
			)
			(layer "B.SilkS")
		)
		(fp_line
			(start -0.7874 0.4064)
			(end 0.7874 0.4064)
			(stroke
				(width 0.1524)
				(type default)
			)
			(layer "B.SilkS")
		)
		(fp_line
			(start 0.7874 -0.4064)
			(end -0.7874 -0.4064)
			(stroke
				(width 0.1524)
				(type default)
			)
			(layer "B.SilkS")
		)
		(fp_line
			(start 0.7874 0.4064)
			(end 0.7874 -0.4064)
			(stroke
				(width 0.1524)
				(type default)
			)
			(layer "B.SilkS")
		)
		(fp_line
			(start -0.67945 -0.3048)
			(end -0.67945 0.3048)
			(stroke
				(width 0.1)
				(type default)
			)
			(layer "B.Fab")
		)
		(fp_line
			(start -0.67945 0.3048)
			(end -0.120396 0.3048)
			(stroke
				(width 0.1)
				(type default)
			)
			(layer "B.Fab")
		)
		(fp_line
			(start -0.12065 -0.3048)
			(end -0.67945 -0.3048)
			(stroke
				(width 0.1)
				(type default)
			)
			(layer "B.Fab")
		)
		(fp_line
			(start -0.12065 -0.2794)
			(end -0.12065 -0.3048)
			(stroke
				(width 0.1)
				(type default)
			)
			(layer "B.Fab")
		)
		(fp_line
			(start -0.120396 0.2794)
			(end 0.12065 0.2794)
			(stroke
				(width 0.1)
				(type default)
			)
			(layer "B.Fab")
		)
		(fp_line
			(start -0.120396 0.3048)
			(end -0.120396 0.2794)
			(stroke
				(width 0.1)
				(type default)
			)
			(layer "B.Fab")
		)
		(fp_line
			(start 0.12065 -0.305054)
			(end 0.12065 -0.2794)
			(stroke
				(width 0.1)
				(type default)
			)
			(layer "B.Fab")
		)
		(fp_line
			(start 0.12065 -0.2794)
			(end -0.12065 -0.2794)
			(stroke
				(width 0.1)
				(type default)
			)
			(layer "B.Fab")
		)
		(fp_line
			(start 0.12065 0.2794)
			(end 0.12065 0.3048)
			(stroke
				(width 0.1)
				(type default)
			)
			(layer "B.Fab")
		)
		(fp_line
			(start 0.12065 0.3048)
			(end 0.67945 0.3048)
			(stroke
				(width 0.1)
				(type default)
			)
			(layer "B.Fab")
		)
		(fp_line
			(start 0.67945 -0.305054)
			(end 0.12065 -0.305054)
			(stroke
				(width 0.1)
				(type default)
			)
			(layer "B.Fab")
		)
		(fp_line
			(start 0.67945 0.3048)
			(end 0.67945 -0.305054)
			(stroke
				(width 0.1)
				(type default)
			)
			(layer "B.Fab")
		)
		(pad "1" smd circle
			(at 0.40005 0 180)
			(size 0 0)
			(layers "B.Cu" "B.Mask" "B.Paste")
			(net "PVDD_33_S5")
		)
		(pad "2" smd circle
			(at -0.40005 0 180)
			(size 0 0)
			(layers "B.Cu" "B.Mask" "B.Paste")
			(net "GND")
		)
	)
	(footprint ""
		(layer "B.Cu")
		(at 212.471508 2.542794 180)
		(property "Reference" "J121"
			(at 4.540504 -1.317498 270)
			(unlocked yes)
			(layer "B.SilkS")
			(effects
				(font
					(size 0.7874 0.5842)
					(thickness 0.1524)
				)
				(justify left mirror)
			)
		)
		(property "Value" ""
			(at 0 0 0)
			(layer "B.Fab")
			(effects
				(font
					(size 1.27 1.27)
				)
				(justify mirror)
			)
		)
		(duplicate_pad_numbers_are_jumpers no)
		(fp_line
			(start 1.2192 2.06756)
			(end 1.2192 -2.06756)
			(stroke
				(width 0.1524)
				(type default)
			)
			(layer "B.SilkS")
		)
		(fp_line
			(start 1.2192 -2.06756)
			(end -1.2192 -2.06756)
			(stroke
				(width 0.1524)
				(type default)
			)
			(layer "B.SilkS")
		)
		(fp_line
			(start -1.2192 2.06756)
			(end 1.2192 2.06756)
			(stroke
				(width 0.1524)
				(type default)
			)
			(layer "B.SilkS")
		)
		(fp_line
			(start -1.2192 -2.06756)
			(end -1.2192 2.06756)
			(stroke
				(width 0.1524)
				(type default)
			)
			(layer "B.SilkS")
		)
		(pad "" np_thru_hole circle
			(at -3.4671 -1.27 90)
			(size 1.0414 1.0414)
			(drill 1.0414)
			(layers "*.Cu" "*.Mask")
			(clearance 0.381)
			(thermal_gap 0.381)
		)
		(pad "" np_thru_hole circle
			(at -3.4671 1.27 90)
			(size 1.0414 1.0414)
			(drill 1.0414)
			(layers "*.Cu" "*.Mask")
			(clearance 0.381)
			(thermal_gap 0.381)
		)
		(pad "" np_thru_hole circle
			(at 2.8829 -1.27 90)
			(size 1.0414 1.0414)
			(drill 1.0414)
			(layers "*.Cu" "*.Mask")
			(clearance 0.381)
			(thermal_gap 0.381)
		)
		(pad "" np_thru_hole circle
			(at 2.8829 1.27 90)
			(size 1.0414 1.0414)
			(drill 1.0414)
			(layers "*.Cu" "*.Mask")
			(clearance 0.381)
			(thermal_gap 0.381)
		)
		(pad "1" smd rect
			(at -0.8255 -0.249936 90)
			(size 0.3048 0.508)
			(layers "B.Cu" "B.Mask" "B.Paste")
			(net "DELTA_L_85_10INCH_IN6_DN")
		)
		(pad "2" smd rect
			(at -0.8255 0.249936 90)
			(size 0.3048 0.508)
			(layers "B.Cu" "B.Mask" "B.Paste")
			(net "DELTA_L_85_10INCH_IN6_DP")
		)
		(pad "3" smd circle
			(at 0 0)
			(size 0 0)
			(layers "B.Cu" "B.Mask" "B.Paste")
			(net "DELTA_L_GND_1")
		)
		(zone
			(layers "F.Cu" "B.Cu" "In1.Cu" "In2.Cu" "In3.Cu" "In4.Cu" "In5.Cu" "In6.Cu"
				"In7.Cu" "In8.Cu" "In9.Cu" "In10.Cu" "In11.Cu" "In12.Cu" "In13.Cu" "In14.Cu"
				"In15.Cu" "In16.Cu"
			)
			(hatch none 0.5)
			(connect_pads
				(clearance 0)
			)
			(min_thickness 0.25)
			(keepout
				(tracks not_allowed)
				(vias allowed)
				(pads allowed)
				(copperpour not_allowed)
				(footprints allowed)
			)
			(placement
				(enabled no)
				(sheetname "")
			)
			(fill
				(thermal_gap 0.5)
				(thermal_bridge_width 0.5)
				(island_removal_mode 0)
			)
			(polygon
				(pts
					(arc
						(start 210.515708 1.272794)
						(mid 208.661508 1.272794)
						(end 210.515708 1.272794)
					)
				)
			)
		)
		(zone
			(layers "F.Cu" "B.Cu" "In1.Cu" "In2.Cu" "In3.Cu" "In4.Cu" "In5.Cu" "In6.Cu"
				"In7.Cu" "In8.Cu" "In9.Cu" "In10.Cu" "In11.Cu" "In12.Cu" "In13.Cu" "In14.Cu"
				"In15.Cu" "In16.Cu"
			)
			(hatch none 0.5)
			(connect_pads
				(clearance 0)
			)
			(min_thickness 0.25)
			(keepout
				(tracks not_allowed)
				(vias allowed)
				(pads allowed)
				(copperpour not_allowed)
				(footprints allowed)
			)
			(placement
				(enabled no)
				(sheetname "")
			)
			(fill
				(thermal_gap 0.5)
				(thermal_bridge_width 0.5)
				(island_removal_mode 0)
			)
			(polygon
				(pts
					(arc
						(start 210.515708 3.812794)
						(mid 208.661508 3.812794)
						(end 210.515708 3.812794)
					)
				)
			)
		)
		(zone
			(layers "F.Cu" "B.Cu" "In1.Cu" "In2.Cu" "In3.Cu" "In4.Cu" "In5.Cu" "In6.Cu"
				"In7.Cu" "In8.Cu" "In9.Cu" "In10.Cu" "In11.Cu" "In12.Cu" "In13.Cu" "In14.Cu"
				"In15.Cu" "In16.Cu"
			)
			(hatch none 0.5)
			(connect_pads
				(clearance 0)
			)
			(min_thickness 0.25)
			(keepout
				(tracks not_allowed)
				(vias allowed)
				(pads allowed)
				(copperpour not_allowed)
				(footprints allowed)
			)
			(placement
				(enabled no)
				(sheetname "")
			)
			(fill
				(thermal_gap 0.5)
				(thermal_bridge_width 0.5)
				(island_removal_mode 0)
			)
			(polygon
				(pts
					(arc
						(start 216.865708 1.272794)
						(mid 215.011508 1.272794)
						(end 216.865708 1.272794)
					)
				)
			)
		)
		(zone
			(layers "F.Cu" "B.Cu" "In1.Cu" "In2.Cu" "In3.Cu" "In4.Cu" "In5.Cu" "In6.Cu"
				"In7.Cu" "In8.Cu" "In9.Cu" "In10.Cu" "In11.Cu" "In12.Cu" "In13.Cu" "In14.Cu"
				"In15.Cu" "In16.Cu"
			)
			(hatch none 0.5)
			(connect_pads
				(clearance 0)
			)
			(min_thickness 0.25)
			(keepout
				(tracks not_allowed)
				(vias allowed)
				(pads allowed)
				(copperpour not_allowed)
				(footprints allowed)
			)
			(placement
				(enabled no)
				(sheetname "")
			)
			(fill
				(thermal_gap 0.5)
				(thermal_bridge_width 0.5)
				(island_removal_mode 0)
			)
			(polygon
				(pts
					(arc
						(start 216.865708 3.812794)
						(mid 215.011508 3.812794)
						(end 216.865708 3.812794)
					)
				)
			)
		)
		(zone
			(layer "B.Cu")
			(hatch none 0.5)
			(connect_pads
				(clearance 0)
			)
			(min_thickness 0.25)
			(keepout
				(tracks not_allowed)
				(vias allowed)
				(pads allowed)
				(copperpour not_allowed)
				(footprints allowed)
			)
			(placement
				(enabled no)
				(sheetname "")
			)
			(fill
				(thermal_gap 0.5)
				(thermal_bridge_width 0.5)
				(island_removal_mode 0)
			)
			(polygon
				(pts
					(xy 213.589108 3.091434) (xy 213.589108 2.99593) (xy 212.992208 2.99593) (xy 212.992208 2.58953)
					(xy 213.589108 2.58953) (xy 213.589108 2.496058) (xy 212.992208 2.496058) (xy 212.992208 2.089658)
					(xy 213.589108 2.089658) (xy 213.589108 1.994154) (xy 212.890608 1.994154) (xy 212.890608 3.091434)
				)
			)
		)
	)
	(footprint ""
		(layer "B.Cu")
		(at 48.591216 -390.560052 90)
		(property "Reference" "C259"
			(at 0 0 90)
			(layer "B.SilkS")
			(hide yes)
			(effects
				(font
					(size 1.27 1.27)
				)
				(justify mirror)
			)
		)
		(property "Value" ""
			(at 0 0 90)
			(layer "B.Fab")
			(effects
				(font
					(size 1.27 1.27)
				)
				(justify mirror)
			)
		)
		(duplicate_pad_numbers_are_jumpers no)
		(fp_line
			(start 0.7874 -0.4064)
			(end -0.7874 -0.4064)
			(stroke
				(width 0.1524)
				(type default)
			)
			(layer "B.SilkS")
		)
		(fp_line
			(start -0.7874 -0.4064)
			(end -0.7874 0.4064)
			(stroke
				(width 0.1524)
				(type default)
			)
			(layer "B.SilkS")
		)
		(fp_line
			(start 0.7874 0.4064)
			(end 0.7874 -0.4064)
			(stroke
				(width 0.1524)
				(type default)
			)
			(layer "B.SilkS")
		)
		(fp_line
			(start -0.7874 0.4064)
			(end 0.7874 0.4064)
			(stroke
				(width 0.1524)
				(type default)
			)
			(layer "B.SilkS")
		)
		(fp_line
			(start 0.67945 -0.305054)
			(end 0.12065 -0.305054)
			(stroke
				(width 0.1)
				(type default)
			)
			(layer "B.Fab")
		)
		(fp_line
			(start 0.12065 -0.305054)
			(end 0.12065 -0.2794)
			(stroke
				(width 0.1)
				(type default)
			)
			(layer "B.Fab")
		)
		(fp_line
			(start -0.12065 -0.3048)
			(end -0.67945 -0.3048)
			(stroke
				(width 0.1)
				(type default)
			)
			(layer "B.Fab")
		)
		(fp_line
			(start -0.67945 -0.3048)
			(end -0.67945 0.3048)
			(stroke
				(width 0.1)
				(type default)
			)
			(layer "B.Fab")
		)
		(fp_line
			(start 0.12065 -0.2794)
			(end -0.12065 -0.2794)
			(stroke
				(width 0.1)
				(type default)
			)
			(layer "B.Fab")
		)
		(fp_line
			(start -0.12065 -0.2794)
			(end -0.12065 -0.3048)
			(stroke
				(width 0.1)
				(type default)
			)
			(layer "B.Fab")
		)
		(fp_line
			(start 0.12065 0.2794)
			(end 0.12065 0.3048)
			(stroke
				(width 0.1)
				(type default)
			)
			(layer "B.Fab")
		)
		(fp_line
			(start -0.120396 0.2794)
			(end 0.12065 0.2794)
			(stroke
				(width 0.1)
				(type default)
			)
			(layer "B.Fab")
		)
		(fp_line
			(start 0.67945 0.3048)
			(end 0.67945 -0.305054)
			(stroke
				(width 0.1)
				(type default)
			)
			(layer "B.Fab")
		)
		(fp_line
			(start 0.12065 0.3048)
			(end 0.67945 0.3048)
			(stroke
				(width 0.1)
				(type default)
			)
			(layer "B.Fab")
		)
		(fp_line
			(start -0.120396 0.3048)
			(end -0.120396 0.2794)
			(stroke
				(width 0.1)
				(type default)
			)
			(layer "B.Fab")
		)
		(fp_line
			(start -0.67945 0.3048)
			(end -0.120396 0.3048)
			(stroke
				(width 0.1)
				(type default)
			)
			(layer "B.Fab")
		)
		(pad "1" smd circle
			(at 0.40005 0 270)
			(size 0 0)
			(layers "B.Cu" "B.Mask" "B.Paste")
			(net "P0V9_CPU1_RT0_2A")
		)
		(pad "2" smd circle
			(at -0.40005 0 270)
			(size 0 0)
			(layers "B.Cu" "B.Mask" "B.Paste")
			(net "GND")
		)
	)
	(footprint ""
		(layer "B.Cu")
		(at 231.902 -232.156 90)
		(property "Reference" "R139"
			(at 0 0 90)
			(layer "B.SilkS")
			(hide yes)
			(effects
				(font
					(size 1.27 1.27)
				)
				(justify mirror)
			)
		)
		(property "Value" ""
			(at 0 0 90)
			(layer "B.Fab")
			(effects
				(font
					(size 1.27 1.27)
				)
				(justify mirror)
			)
		)
		(duplicate_pad_numbers_are_jumpers no)
		(fp_line
			(start 0.7874 -0.4064)
			(end -0.7874 -0.4064)
			(stroke
				(width 0.1524)
				(type default)
			)
			(layer "B.SilkS")
		)
		(fp_line
			(start -0.7874 -0.4064)
			(end -0.7874 0.4064)
			(stroke
				(width 0.1524)
				(type default)
			)
			(layer "B.SilkS")
		)
		(fp_line
			(start 0.7874 0.4064)
			(end 0.7874 -0.4064)
			(stroke
				(width 0.1524)
				(type default)
			)
			(layer "B.SilkS")
		)
		(fp_line
			(start -0.7874 0.4064)
			(end 0.7874 0.4064)
			(stroke
				(width 0.1524)
				(type default)
			)
			(layer "B.SilkS")
		)
		(fp_line
			(start 0.67945 -0.305054)
			(end 0.12065 -0.305054)
			(stroke
				(width 0.1)
				(type default)
			)
			(layer "B.Fab")
		)
		(fp_line
			(start 0.12065 -0.305054)
			(end 0.12065 -0.2794)
			(stroke
				(width 0.1)
				(type default)
			)
			(layer "B.Fab")
		)
		(fp_line
			(start -0.12065 -0.3048)
			(end -0.67945 -0.3048)
			(stroke
				(width 0.1)
				(type default)
			)
			(layer "B.Fab")
		)
		(fp_line
			(start -0.67945 -0.3048)
			(end -0.67945 0.3048)
			(stroke
				(width 0.1)
				(type default)
			)
			(layer "B.Fab")
		)
		(fp_line
			(start 0.12065 -0.2794)
			(end -0.12065 -0.2794)
			(stroke
				(width 0.1)
				(type default)
			)
			(layer "B.Fab")
		)
		(fp_line
			(start -0.12065 -0.2794)
			(end -0.12065 -0.3048)
			(stroke
				(width 0.1)
				(type default)
			)
			(layer "B.Fab")
		)
		(fp_line
			(start 0.12065 0.2794)
			(end 0.12065 0.3048)
			(stroke
				(width 0.1)
				(type default)
			)
			(layer "B.Fab")
		)
		(fp_line
			(start -0.120396 0.2794)
			(end 0.12065 0.2794)
			(stroke
				(width 0.1)
				(type default)
			)
			(layer "B.Fab")
		)
		(fp_line
			(start 0.67945 0.3048)
			(end 0.67945 -0.305054)
			(stroke
				(width 0.1)
				(type default)
			)
			(layer "B.Fab")
		)
		(fp_line
			(start 0.12065 0.3048)
			(end 0.67945 0.3048)
			(stroke
				(width 0.1)
				(type default)
			)
			(layer "B.Fab")
		)
		(fp_line
			(start -0.120396 0.3048)
			(end -0.120396 0.2794)
			(stroke
				(width 0.1)
				(type default)
			)
			(layer "B.Fab")
		)
		(fp_line
			(start -0.67945 0.3048)
			(end -0.120396 0.3048)
			(stroke
				(width 0.1)
				(type default)
			)
			(layer "B.Fab")
		)
		(pad "1" smd circle
			(at 0.40005 0 270)
			(size 0 0)
			(layers "B.Cu" "B.Mask" "B.Paste")
			(net "I3C_MUX_CPU0_VIO")
		)
		(pad "2" smd circle
			(at -0.40005 0 270)
			(size 0 0)
			(layers "B.Cu" "B.Mask" "B.Paste")
			(net "PVDD18_S5_P0")
		)
	)
	(footprint ""
		(layer "B.Cu")
		(at 405.419052 -398.942052 90)
		(property "Reference" "C967"
			(at 0 0 90)
			(layer "B.SilkS")
			(hide yes)
			(effects
				(font
					(size 1.27 1.27)
				)
				(justify mirror)
			)
		)
		(property "Value" ""
			(at 0 0 90)
			(layer "B.Fab")
			(effects
				(font
					(size 1.27 1.27)
				)
				(justify mirror)
			)
		)
		(duplicate_pad_numbers_are_jumpers no)
		(fp_line
			(start 0.7874 -0.4064)
			(end -0.7874 -0.4064)
			(stroke
				(width 0.1524)
				(type default)
			)
			(layer "B.SilkS")
		)
		(fp_line
			(start -0.7874 -0.4064)
			(end -0.7874 0.4064)
			(stroke
				(width 0.1524)
				(type default)
			)
			(layer "B.SilkS")
		)
		(fp_line
			(start 0.7874 0.4064)
			(end 0.7874 -0.4064)
			(stroke
				(width 0.1524)
				(type default)
			)
			(layer "B.SilkS")
		)
		(fp_line
			(start -0.7874 0.4064)
			(end 0.7874 0.4064)
			(stroke
				(width 0.1524)
				(type default)
			)
			(layer "B.SilkS")
		)
		(fp_line
			(start 0.67945 -0.305054)
			(end 0.12065 -0.305054)
			(stroke
				(width 0.1)
				(type default)
			)
			(layer "B.Fab")
		)
		(fp_line
			(start 0.12065 -0.305054)
			(end 0.12065 -0.2794)
			(stroke
				(width 0.1)
				(type default)
			)
			(layer "B.Fab")
		)
		(fp_line
			(start -0.12065 -0.3048)
			(end -0.67945 -0.3048)
			(stroke
				(width 0.1)
				(type default)
			)
			(layer "B.Fab")
		)
		(fp_line
			(start -0.67945 -0.3048)
			(end -0.67945 0.3048)
			(stroke
				(width 0.1)
				(type default)
			)
			(layer "B.Fab")
		)
		(fp_line
			(start 0.12065 -0.2794)
			(end -0.12065 -0.2794)
			(stroke
				(width 0.1)
				(type default)
			)
			(layer "B.Fab")
		)
		(fp_line
			(start -0.12065 -0.2794)
			(end -0.12065 -0.3048)
			(stroke
				(width 0.1)
				(type default)
			)
			(layer "B.Fab")
		)
		(fp_line
			(start 0.12065 0.2794)
			(end 0.12065 0.3048)
			(stroke
				(width 0.1)
				(type default)
			)
			(layer "B.Fab")
		)
		(fp_line
			(start -0.120396 0.2794)
			(end 0.12065 0.2794)
			(stroke
				(width 0.1)
				(type default)
			)
			(layer "B.Fab")
		)
		(fp_line
			(start 0.67945 0.3048)
			(end 0.67945 -0.305054)
			(stroke
				(width 0.1)
				(type default)
			)
			(layer "B.Fab")
		)
		(fp_line
			(start 0.12065 0.3048)
			(end 0.67945 0.3048)
			(stroke
				(width 0.1)
				(type default)
			)
			(layer "B.Fab")
		)
		(fp_line
			(start -0.120396 0.3048)
			(end -0.120396 0.2794)
			(stroke
				(width 0.1)
				(type default)
			)
			(layer "B.Fab")
		)
		(fp_line
			(start -0.67945 0.3048)
			(end -0.120396 0.3048)
			(stroke
				(width 0.1)
				(type default)
			)
			(layer "B.Fab")
		)
		(pad "1" smd circle
			(at 0.40005 0 270)
			(size 0 0)
			(layers "B.Cu" "B.Mask" "B.Paste")
			(net "P0V9_CPU0_RT2_2A")
		)
		(pad "2" smd circle
			(at -0.40005 0 270)
			(size 0 0)
			(layers "B.Cu" "B.Mask" "B.Paste")
			(net "GND")
		)
	)
	(footprint ""
		(layer "B.Cu")
		(at 125.389386 -250.892564)
		(property "Reference" "C2443"
			(at 0 0 0)
			(layer "B.SilkS")
			(hide yes)
			(effects
				(font
					(size 1.27 1.27)
				)
				(justify mirror)
			)
		)
		(property "Value" ""
			(at 0 0 0)
			(layer "B.Fab")
			(effects
				(font
					(size 1.27 1.27)
				)
				(justify mirror)
			)
		)
		(duplicate_pad_numbers_are_jumpers no)
		(fp_line
			(start -0.7874 -0.4064)
			(end -0.7874 0.4064)
			(stroke
				(width 0.1524)
				(type default)
			)
			(layer "B.SilkS")
		)
		(fp_line
			(start -0.7874 0.4064)
			(end 0.7874 0.4064)
			(stroke
				(width 0.1524)
				(type default)
			)
			(layer "B.SilkS")
		)
		(fp_line
			(start 0.7874 -0.4064)
			(end -0.7874 -0.4064)
			(stroke
				(width 0.1524)
				(type default)
			)
			(layer "B.SilkS")
		)
		(fp_line
			(start 0.7874 0.4064)
			(end 0.7874 -0.4064)
			(stroke
				(width 0.1524)
				(type default)
			)
			(layer "B.SilkS")
		)
		(fp_line
			(start -0.67945 -0.3048)
			(end -0.67945 0.3048)
			(stroke
				(width 0.1)
				(type default)
			)
			(layer "B.Fab")
		)
		(fp_line
			(start -0.67945 0.3048)
			(end -0.120396 0.3048)
			(stroke
				(width 0.1)
				(type default)
			)
			(layer "B.Fab")
		)
		(fp_line
			(start -0.12065 -0.3048)
			(end -0.67945 -0.3048)
			(stroke
				(width 0.1)
				(type default)
			)
			(layer "B.Fab")
		)
		(fp_line
			(start -0.12065 -0.2794)
			(end -0.12065 -0.3048)
			(stroke
				(width 0.1)
				(type default)
			)
			(layer "B.Fab")
		)
		(fp_line
			(start -0.120396 0.2794)
			(end 0.12065 0.2794)
			(stroke
				(width 0.1)
				(type default)
			)
			(layer "B.Fab")
		)
		(fp_line
			(start -0.120396 0.3048)
			(end -0.120396 0.2794)
			(stroke
				(width 0.1)
				(type default)
			)
			(layer "B.Fab")
		)
		(fp_line
			(start 0.12065 -0.305054)
			(end 0.12065 -0.2794)
			(stroke
				(width 0.1)
				(type default)
			)
			(layer "B.Fab")
		)
		(fp_line
			(start 0.12065 -0.2794)
			(end -0.12065 -0.2794)
			(stroke
				(width 0.1)
				(type default)
			)
			(layer "B.Fab")
		)
		(fp_line
			(start 0.12065 0.2794)
			(end 0.12065 0.3048)
			(stroke
				(width 0.1)
				(type default)
			)
			(layer "B.Fab")
		)
		(fp_line
			(start 0.12065 0.3048)
			(end 0.67945 0.3048)
			(stroke
				(width 0.1)
				(type default)
			)
			(layer "B.Fab")
		)
		(fp_line
			(start 0.67945 -0.305054)
			(end 0.12065 -0.305054)
			(stroke
				(width 0.1)
				(type default)
			)
			(layer "B.Fab")
		)
		(fp_line
			(start 0.67945 0.3048)
			(end 0.67945 -0.305054)
			(stroke
				(width 0.1)
				(type default)
			)
			(layer "B.Fab")
		)
		(pad "1" smd circle
			(at 0.40005 0 180)
			(size 0 0)
			(layers "B.Cu" "B.Mask" "B.Paste")
			(net "PVDDCR_SOC_P1")
		)
		(pad "2" smd circle
			(at -0.40005 0 180)
			(size 0 0)
			(layers "B.Cu" "B.Mask" "B.Paste")
			(net "GND")
		)
	)
	(footprint ""
		(layer "B.Cu")
		(at 345.122246 -416.899344 90)
		(property "Reference" "C6560"
			(at 0 0 90)
			(layer "B.SilkS")
			(hide yes)
			(effects
				(font
					(size 1.27 1.27)
				)
				(justify mirror)
			)
		)
		(property "Value" ""
			(at 0 0 90)
			(layer "B.Fab")
			(effects
				(font
					(size 1.27 1.27)
				)
				(justify mirror)
			)
		)
		(duplicate_pad_numbers_are_jumpers no)
		(fp_line
			(start 0.299974 -0.150114)
			(end -0.299974 -0.150114)
			(stroke
				(width 0.1)
				(type default)
			)
			(layer "B.Fab")
		)
		(fp_line
			(start -0.299974 -0.150114)
			(end -0.299974 0.150114)
			(stroke
				(width 0.1)
				(type default)
			)
			(layer "B.Fab")
		)
		(fp_line
			(start 0.299974 0.150114)
			(end 0.299974 -0.150114)
			(stroke
				(width 0.1)
				(type default)
			)
			(layer "B.Fab")
		)
		(fp_line
			(start -0.299974 0.150114)
			(end 0.299974 0.150114)
			(stroke
				(width 0.1)
				(type default)
			)
			(layer "B.Fab")
		)
		(pad "1" smd rect
			(at 0.2667 0 270)
			(size 0.3048 0.381)
			(layers "B.Cu" "B.Mask" "B.Paste")
			(net "P5E_CPU0_P1_TX_BUF_C_DN<13>")
		)
		(pad "2" smd rect
			(at -0.2667 0 270)
			(size 0.3048 0.381)
			(layers "B.Cu" "B.Mask" "B.Paste")
			(net "P5E_CPU0_P1_TX_BUF_DN<13>")
		)
	)
	(footprint ""
		(layer "B.Cu")
		(at 403.006306 -395.148562 90)
		(property "Reference" "C983"
			(at 0 0 90)
			(layer "B.SilkS")
			(hide yes)
			(effects
				(font
					(size 1.27 1.27)
				)
				(justify mirror)
			)
		)
		(property "Value" ""
			(at 0 0 90)
			(layer "B.Fab")
			(effects
				(font
					(size 1.27 1.27)
				)
				(justify mirror)
			)
		)
		(duplicate_pad_numbers_are_jumpers no)
		(fp_line
			(start 0.299974 -0.150114)
			(end -0.299974 -0.150114)
			(stroke
				(width 0.1)
				(type default)
			)
			(layer "B.Fab")
		)
		(fp_line
			(start -0.299974 -0.150114)
			(end -0.299974 0.150114)
			(stroke
				(width 0.1)
				(type default)
			)
			(layer "B.Fab")
		)
		(fp_line
			(start 0.299974 0.150114)
			(end 0.299974 -0.150114)
			(stroke
				(width 0.1)
				(type default)
			)
			(layer "B.Fab")
		)
		(fp_line
			(start -0.299974 0.150114)
			(end 0.299974 0.150114)
			(stroke
				(width 0.1)
				(type default)
			)
			(layer "B.Fab")
		)
		(pad "1" smd rect
			(at 0.2667 0 270)
			(size 0.3048 0.381)
			(layers "B.Cu" "B.Mask" "B.Paste")
			(net "P0V9_CPU0_RT2_2A")
		)
		(pad "2" smd rect
			(at -0.2667 0 270)
			(size 0.3048 0.381)
			(layers "B.Cu" "B.Mask" "B.Paste")
			(net "GND")
		)
	)
	(footprint ""
		(layer "B.Cu")
		(at 328.462386 -398.055084 90)
		(property "Reference" "C632"
			(at 0 0 90)
			(layer "B.SilkS")
			(hide yes)
			(effects
				(font
					(size 1.27 1.27)
				)
				(justify mirror)
			)
		)
		(property "Value" ""
			(at 0 0 90)
			(layer "B.Fab")
			(effects
				(font
					(size 1.27 1.27)
				)
				(justify mirror)
			)
		)
		(duplicate_pad_numbers_are_jumpers no)
		(fp_line
			(start 1.524 -0.762)
			(end -1.524 -0.762)
			(stroke
				(width 0.1524)
				(type default)
			)
			(layer "B.SilkS")
		)
		(fp_line
			(start -1.524 -0.762)
			(end -1.524 0.762)
			(stroke
				(width 0.1524)
				(type default)
			)
			(layer "B.SilkS")
		)
		(fp_line
			(start 1.524 0.762)
			(end 1.524 -0.762)
			(stroke
				(width 0.1524)
				(type default)
			)
			(layer "B.SilkS")
		)
		(fp_line
			(start -1.524 0.762)
			(end 1.524 0.762)
			(stroke
				(width 0.1524)
				(type default)
			)
			(layer "B.SilkS")
		)
		(fp_line
			(start 1.1049 -0.724916)
			(end 1.1049 0.724916)
			(stroke
				(width 0.1)
				(type default)
			)
			(layer "B.Fab")
		)
		(fp_line
			(start -1.1049 -0.724916)
			(end 1.1049 -0.724916)
			(stroke
				(width 0.1)
				(type default)
			)
			(layer "B.Fab")
		)
		(fp_line
			(start 1.1049 0.724916)
			(end -1.1049 0.724916)
			(stroke
				(width 0.1)
				(type default)
			)
			(layer "B.Fab")
		)
		(fp_line
			(start -1.1049 0.724916)
			(end -1.1049 -0.724916)
			(stroke
				(width 0.1)
				(type default)
			)
			(layer "B.Fab")
		)
		(pad "1" smd rect
			(at 0.889 0 90)
			(size 1.016 1.27)
			(layers "B.Cu" "B.Mask" "B.Paste")
			(net "P0V9_CPU0_RT_2D")
		)
		(pad "2" smd rect
			(at -0.889 0 90)
			(size 1.016 1.27)
			(layers "B.Cu" "B.Mask" "B.Paste")
			(net "GND")
		)
	)
	(footprint ""
		(layer "B.Cu")
		(at 335.90611 -395.148562 90)
		(property "Reference" "C660"
			(at 0 0 90)
			(layer "B.SilkS")
			(hide yes)
			(effects
				(font
					(size 1.27 1.27)
				)
				(justify mirror)
			)
		)
		(property "Value" ""
			(at 0 0 90)
			(layer "B.Fab")
			(effects
				(font
					(size 1.27 1.27)
				)
				(justify mirror)
			)
		)
		(duplicate_pad_numbers_are_jumpers no)
		(fp_line
			(start 0.299974 -0.150114)
			(end -0.299974 -0.150114)
			(stroke
				(width 0.1)
				(type default)
			)
			(layer "B.Fab")
		)
		(fp_line
			(start -0.299974 -0.150114)
			(end -0.299974 0.150114)
			(stroke
				(width 0.1)
				(type default)
			)
			(layer "B.Fab")
		)
		(fp_line
			(start 0.299974 0.150114)
			(end 0.299974 -0.150114)
			(stroke
				(width 0.1)
				(type default)
			)
			(layer "B.Fab")
		)
		(fp_line
			(start -0.299974 0.150114)
			(end 0.299974 0.150114)
			(stroke
				(width 0.1)
				(type default)
			)
			(layer "B.Fab")
		)
		(pad "1" smd rect
			(at 0.2667 0 270)
			(size 0.3048 0.381)
			(layers "B.Cu" "B.Mask" "B.Paste")
			(net "P0V9_CPU0_RT1_2A")
		)
		(pad "2" smd rect
			(at -0.2667 0 270)
			(size 0.3048 0.381)
			(layers "B.Cu" "B.Mask" "B.Paste")
			(net "GND")
		)
	)
	(footprint ""
		(layer "B.Cu")
		(at 237.617 -247.269)
		(property "Reference" "R360"
			(at 0 0 0)
			(layer "B.SilkS")
			(hide yes)
			(effects
				(font
					(size 1.27 1.27)
				)
				(justify mirror)
			)
		)
		(property "Value" ""
			(at 0 0 0)
			(layer "B.Fab")
			(effects
				(font
					(size 1.27 1.27)
				)
				(justify mirror)
			)
		)
		(duplicate_pad_numbers_are_jumpers no)
		(fp_line
			(start -0.7874 -0.4064)
			(end -0.7874 0.4064)
			(stroke
				(width 0.1524)
				(type default)
			)
			(layer "B.SilkS")
		)
		(fp_line
			(start -0.7874 0.4064)
			(end 0.7874 0.4064)
			(stroke
				(width 0.1524)
				(type default)
			)
			(layer "B.SilkS")
		)
		(fp_line
			(start 0.7874 -0.4064)
			(end -0.7874 -0.4064)
			(stroke
				(width 0.1524)
				(type default)
			)
			(layer "B.SilkS")
		)
		(fp_line
			(start 0.7874 0.4064)
			(end 0.7874 -0.4064)
			(stroke
				(width 0.1524)
				(type default)
			)
			(layer "B.SilkS")
		)
		(fp_line
			(start -0.67945 -0.3048)
			(end -0.67945 0.3048)
			(stroke
				(width 0.1)
				(type default)
			)
			(layer "B.Fab")
		)
		(fp_line
			(start -0.67945 0.3048)
			(end -0.120396 0.3048)
			(stroke
				(width 0.1)
				(type default)
			)
			(layer "B.Fab")
		)
		(fp_line
			(start -0.12065 -0.3048)
			(end -0.67945 -0.3048)
			(stroke
				(width 0.1)
				(type default)
			)
			(layer "B.Fab")
		)
		(fp_line
			(start -0.12065 -0.2794)
			(end -0.12065 -0.3048)
			(stroke
				(width 0.1)
				(type default)
			)
			(layer "B.Fab")
		)
		(fp_line
			(start -0.120396 0.2794)
			(end 0.12065 0.2794)
			(stroke
				(width 0.1)
				(type default)
			)
			(layer "B.Fab")
		)
		(fp_line
			(start -0.120396 0.3048)
			(end -0.120396 0.2794)
			(stroke
				(width 0.1)
				(type default)
			)
			(layer "B.Fab")
		)
		(fp_line
			(start 0.12065 -0.305054)
			(end 0.12065 -0.2794)
			(stroke
				(width 0.1)
				(type default)
			)
			(layer "B.Fab")
		)
		(fp_line
			(start 0.12065 -0.2794)
			(end -0.12065 -0.2794)
			(stroke
				(width 0.1)
				(type default)
			)
			(layer "B.Fab")
		)
		(fp_line
			(start 0.12065 0.2794)
			(end 0.12065 0.3048)
			(stroke
				(width 0.1)
				(type default)
			)
			(layer "B.Fab")
		)
		(fp_line
			(start 0.12065 0.3048)
			(end 0.67945 0.3048)
			(stroke
				(width 0.1)
				(type default)
			)
			(layer "B.Fab")
		)
		(fp_line
			(start 0.67945 -0.305054)
			(end 0.12065 -0.305054)
			(stroke
				(width 0.1)
				(type default)
			)
			(layer "B.Fab")
		)
		(fp_line
			(start 0.67945 0.3048)
			(end 0.67945 -0.305054)
			(stroke
				(width 0.1)
				(type default)
			)
			(layer "B.Fab")
		)
		(pad "1" smd circle
			(at 0.40005 0 180)
			(size 0 0)
			(layers "B.Cu" "B.Mask" "B.Paste")
			(net "PVDD11_S3_P0")
		)
		(pad "2" smd circle
			(at -0.40005 0 180)
			(size 0 0)
			(layers "B.Cu" "B.Mask" "B.Paste")
			(net "SMB_APML_CPU0_SDA")
		)
	)
	(footprint ""
		(layer "B.Cu")
		(at 171.577 -98.135948 90)
		(property "Reference" "R6021"
			(at 0 0 90)
			(layer "B.SilkS")
			(hide yes)
			(effects
				(font
					(size 1.27 1.27)
				)
				(justify mirror)
			)
		)
		(property "Value" ""
			(at 0 0 90)
			(layer "B.Fab")
			(effects
				(font
					(size 1.27 1.27)
				)
				(justify mirror)
			)
		)
		(duplicate_pad_numbers_are_jumpers no)
		(fp_line
			(start 0.7874 -0.4064)
			(end -0.7874 -0.4064)
			(stroke
				(width 0.1524)
				(type default)
			)
			(layer "B.SilkS")
		)
		(fp_line
			(start -0.7874 -0.4064)
			(end -0.7874 0.4064)
			(stroke
				(width 0.1524)
				(type default)
			)
			(layer "B.SilkS")
		)
		(fp_line
			(start 0.7874 0.4064)
			(end 0.7874 -0.4064)
			(stroke
				(width 0.1524)
				(type default)
			)
			(layer "B.SilkS")
		)
		(fp_line
			(start -0.7874 0.4064)
			(end 0.7874 0.4064)
			(stroke
				(width 0.1524)
				(type default)
			)
			(layer "B.SilkS")
		)
		(fp_line
			(start 0.67945 -0.305054)
			(end 0.12065 -0.305054)
			(stroke
				(width 0.1)
				(type default)
			)
			(layer "B.Fab")
		)
		(fp_line
			(start 0.12065 -0.305054)
			(end 0.12065 -0.2794)
			(stroke
				(width 0.1)
				(type default)
			)
			(layer "B.Fab")
		)
		(fp_line
			(start -0.12065 -0.3048)
			(end -0.67945 -0.3048)
			(stroke
				(width 0.1)
				(type default)
			)
			(layer "B.Fab")
		)
		(fp_line
			(start -0.67945 -0.3048)
			(end -0.67945 0.3048)
			(stroke
				(width 0.1)
				(type default)
			)
			(layer "B.Fab")
		)
		(fp_line
			(start 0.12065 -0.2794)
			(end -0.12065 -0.2794)
			(stroke
				(width 0.1)
				(type default)
			)
			(layer "B.Fab")
		)
		(fp_line
			(start -0.12065 -0.2794)
			(end -0.12065 -0.3048)
			(stroke
				(width 0.1)
				(type default)
			)
			(layer "B.Fab")
		)
		(fp_line
			(start 0.12065 0.2794)
			(end 0.12065 0.3048)
			(stroke
				(width 0.1)
				(type default)
			)
			(layer "B.Fab")
		)
		(fp_line
			(start -0.120396 0.2794)
			(end 0.12065 0.2794)
			(stroke
				(width 0.1)
				(type default)
			)
			(layer "B.Fab")
		)
		(fp_line
			(start 0.67945 0.3048)
			(end 0.67945 -0.305054)
			(stroke
				(width 0.1)
				(type default)
			)
			(layer "B.Fab")
		)
		(fp_line
			(start 0.12065 0.3048)
			(end 0.67945 0.3048)
			(stroke
				(width 0.1)
				(type default)
			)
			(layer "B.Fab")
		)
		(fp_line
			(start -0.120396 0.3048)
			(end -0.120396 0.2794)
			(stroke
				(width 0.1)
				(type default)
			)
			(layer "B.Fab")
		)
		(fp_line
			(start -0.67945 0.3048)
			(end -0.120396 0.3048)
			(stroke
				(width 0.1)
				(type default)
			)
			(layer "B.Fab")
		)
		(pad "1" smd circle
			(at 0.40005 0 270)
			(size 0 0)
			(layers "B.Cu" "B.Mask" "B.Paste")
			(net "P3V3_AUX")
		)
		(pad "2" smd circle
			(at -0.40005 0 270)
			(size 0 0)
			(layers "B.Cu" "B.Mask" "B.Paste")
			(net "SGPIO_SCM_CLK_<1>")
		)
	)
	(footprint ""
		(layer "B.Cu")
		(at 156.222446 -408.517344 90)
		(property "Reference" "C6752"
			(at 0 0 90)
			(layer "B.SilkS")
			(hide yes)
			(effects
				(font
					(size 1.27 1.27)
				)
				(justify mirror)
			)
		)
		(property "Value" ""
			(at 0 0 90)
			(layer "B.Fab")
			(effects
				(font
					(size 1.27 1.27)
				)
				(justify mirror)
			)
		)
		(duplicate_pad_numbers_are_jumpers no)
		(fp_line
			(start 0.299974 -0.150114)
			(end -0.299974 -0.150114)
			(stroke
				(width 0.1)
				(type default)
			)
			(layer "B.Fab")
		)
		(fp_line
			(start -0.299974 -0.150114)
			(end -0.299974 0.150114)
			(stroke
				(width 0.1)
				(type default)
			)
			(layer "B.Fab")
		)
		(fp_line
			(start 0.299974 0.150114)
			(end 0.299974 -0.150114)
			(stroke
				(width 0.1)
				(type default)
			)
			(layer "B.Fab")
		)
		(fp_line
			(start -0.299974 0.150114)
			(end 0.299974 0.150114)
			(stroke
				(width 0.1)
				(type default)
			)
			(layer "B.Fab")
		)
		(pad "1" smd rect
			(at 0.2667 0 270)
			(size 0.3048 0.381)
			(layers "B.Cu" "B.Mask" "B.Paste")
			(net "P5E_CPU1_P3_TX_BUF_C_DN<13>")
		)
		(pad "2" smd rect
			(at -0.2667 0 270)
			(size 0.3048 0.381)
			(layers "B.Cu" "B.Mask" "B.Paste")
			(net "P5E_CPU1_P3_TX_BUF_DN<13>")
		)
	)
	(footprint ""
		(layer "B.Cu")
		(at 76.271882 -176.566576 90)
		(property "Reference" "PR201"
			(at 0 0 90)
			(layer "B.SilkS")
			(hide yes)
			(effects
				(font
					(size 1.27 1.27)
				)
				(justify mirror)
			)
		)
		(property "Value" ""
			(at 0 0 90)
			(layer "B.Fab")
			(effects
				(font
					(size 1.27 1.27)
				)
				(justify mirror)
			)
		)
		(duplicate_pad_numbers_are_jumpers no)
		(fp_line
			(start 0.7874 -0.4064)
			(end -0.7874 -0.4064)
			(stroke
				(width 0.1524)
				(type default)
			)
			(layer "B.SilkS")
		)
		(fp_line
			(start -0.7874 -0.4064)
			(end -0.7874 0.4064)
			(stroke
				(width 0.1524)
				(type default)
			)
			(layer "B.SilkS")
		)
		(fp_line
			(start 0.7874 0.4064)
			(end 0.7874 -0.4064)
			(stroke
				(width 0.1524)
				(type default)
			)
			(layer "B.SilkS")
		)
		(fp_line
			(start -0.7874 0.4064)
			(end 0.7874 0.4064)
			(stroke
				(width 0.1524)
				(type default)
			)
			(layer "B.SilkS")
		)
		(fp_line
			(start 0.67945 -0.305054)
			(end 0.12065 -0.305054)
			(stroke
				(width 0.1)
				(type default)
			)
			(layer "B.Fab")
		)
		(fp_line
			(start 0.12065 -0.305054)
			(end 0.12065 -0.2794)
			(stroke
				(width 0.1)
				(type default)
			)
			(layer "B.Fab")
		)
		(fp_line
			(start -0.12065 -0.3048)
			(end -0.67945 -0.3048)
			(stroke
				(width 0.1)
				(type default)
			)
			(layer "B.Fab")
		)
		(fp_line
			(start -0.67945 -0.3048)
			(end -0.67945 0.3048)
			(stroke
				(width 0.1)
				(type default)
			)
			(layer "B.Fab")
		)
		(fp_line
			(start 0.12065 -0.2794)
			(end -0.12065 -0.2794)
			(stroke
				(width 0.1)
				(type default)
			)
			(layer "B.Fab")
		)
		(fp_line
			(start -0.12065 -0.2794)
			(end -0.12065 -0.3048)
			(stroke
				(width 0.1)
				(type default)
			)
			(layer "B.Fab")
		)
		(fp_line
			(start 0.12065 0.2794)
			(end 0.12065 0.3048)
			(stroke
				(width 0.1)
				(type default)
			)
			(layer "B.Fab")
		)
		(fp_line
			(start -0.120396 0.2794)
			(end 0.12065 0.2794)
			(stroke
				(width 0.1)
				(type default)
			)
			(layer "B.Fab")
		)
		(fp_line
			(start 0.67945 0.3048)
			(end 0.67945 -0.305054)
			(stroke
				(width 0.1)
				(type default)
			)
			(layer "B.Fab")
		)
		(fp_line
			(start 0.12065 0.3048)
			(end 0.67945 0.3048)
			(stroke
				(width 0.1)
				(type default)
			)
			(layer "B.Fab")
		)
		(fp_line
			(start -0.120396 0.3048)
			(end -0.120396 0.2794)
			(stroke
				(width 0.1)
				(type default)
			)
			(layer "B.Fab")
		)
		(fp_line
			(start -0.67945 0.3048)
			(end -0.120396 0.3048)
			(stroke
				(width 0.1)
				(type default)
			)
			(layer "B.Fab")
		)
		(pad "1" smd circle
			(at 0.40005 0 270)
			(size 0 0)
			(layers "B.Cu" "B.Mask" "B.Paste")
			(net "PVDDCR_CPU0_P1_PVCC")
		)
		(pad "2" smd circle
			(at -0.40005 0 270)
			(size 0 0)
			(layers "B.Cu" "B.Mask" "B.Paste")
			(net "PVDDCR_CPU0_P1_VCC5")
		)
	)
	(footprint ""
		(layer "B.Cu")
		(at 410.346144 -396.393162 -90)
		(property "Reference" "C677"
			(at 0 0 90)
			(layer "B.SilkS")
			(hide yes)
			(effects
				(font
					(size 1.27 1.27)
				)
				(justify mirror)
			)
		)
		(property "Value" ""
			(at 0 0 90)
			(layer "B.Fab")
			(effects
				(font
					(size 1.27 1.27)
				)
				(justify mirror)
			)
		)
		(duplicate_pad_numbers_are_jumpers no)
		(fp_line
			(start -0.299974 0.150114)
			(end 0.299974 0.150114)
			(stroke
				(width 0.1)
				(type default)
			)
			(layer "B.Fab")
		)
		(fp_line
			(start 0.299974 0.150114)
			(end 0.299974 -0.150114)
			(stroke
				(width 0.1)
				(type default)
			)
			(layer "B.Fab")
		)
		(fp_line
			(start -0.299974 -0.150114)
			(end -0.299974 0.150114)
			(stroke
				(width 0.1)
				(type default)
			)
			(layer "B.Fab")
		)
		(fp_line
			(start 0.299974 -0.150114)
			(end -0.299974 -0.150114)
			(stroke
				(width 0.1)
				(type default)
			)
			(layer "B.Fab")
		)
		(pad "1" smd rect
			(at 0.2667 0 90)
			(size 0.3048 0.381)
			(layers "B.Cu" "B.Mask" "B.Paste")
			(net "P1V8_CPU0_RT2_1A")
		)
		(pad "2" smd rect
			(at -0.2667 0 90)
			(size 0.3048 0.381)
			(layers "B.Cu" "B.Mask" "B.Paste")
			(net "GND")
		)
	)
	(footprint ""
		(layer "B.Cu")
		(at 322.370958 -203.917296 90)
		(property "Reference" "R442"
			(at 0 0 90)
			(layer "B.SilkS")
			(hide yes)
			(effects
				(font
					(size 1.27 1.27)
				)
				(justify mirror)
			)
		)
		(property "Value" ""
			(at 0 0 90)
			(layer "B.Fab")
			(effects
				(font
					(size 1.27 1.27)
				)
				(justify mirror)
			)
		)
		(duplicate_pad_numbers_are_jumpers no)
		(fp_line
			(start 0.7874 -0.4064)
			(end -0.7874 -0.4064)
			(stroke
				(width 0.1524)
				(type default)
			)
			(layer "B.SilkS")
		)
		(fp_line
			(start -0.7874 -0.4064)
			(end -0.7874 0.4064)
			(stroke
				(width 0.1524)
				(type default)
			)
			(layer "B.SilkS")
		)
		(fp_line
			(start 0.7874 0.4064)
			(end 0.7874 -0.4064)
			(stroke
				(width 0.1524)
				(type default)
			)
			(layer "B.SilkS")
		)
		(fp_line
			(start -0.7874 0.4064)
			(end 0.7874 0.4064)
			(stroke
				(width 0.1524)
				(type default)
			)
			(layer "B.SilkS")
		)
		(fp_line
			(start 0.67945 -0.305054)
			(end 0.12065 -0.305054)
			(stroke
				(width 0.1)
				(type default)
			)
			(layer "B.Fab")
		)
		(fp_line
			(start 0.12065 -0.305054)
			(end 0.12065 -0.2794)
			(stroke
				(width 0.1)
				(type default)
			)
			(layer "B.Fab")
		)
		(fp_line
			(start -0.12065 -0.3048)
			(end -0.67945 -0.3048)
			(stroke
				(width 0.1)
				(type default)
			)
			(layer "B.Fab")
		)
		(fp_line
			(start -0.67945 -0.3048)
			(end -0.67945 0.3048)
			(stroke
				(width 0.1)
				(type default)
			)
			(layer "B.Fab")
		)
		(fp_line
			(start 0.12065 -0.2794)
			(end -0.12065 -0.2794)
			(stroke
				(width 0.1)
				(type default)
			)
			(layer "B.Fab")
		)
		(fp_line
			(start -0.12065 -0.2794)
			(end -0.12065 -0.3048)
			(stroke
				(width 0.1)
				(type default)
			)
			(layer "B.Fab")
		)
		(fp_line
			(start 0.12065 0.2794)
			(end 0.12065 0.3048)
			(stroke
				(width 0.1)
				(type default)
			)
			(layer "B.Fab")
		)
		(fp_line
			(start -0.120396 0.2794)
			(end 0.12065 0.2794)
			(stroke
				(width 0.1)
				(type default)
			)
			(layer "B.Fab")
		)
		(fp_line
			(start 0.67945 0.3048)
			(end 0.67945 -0.305054)
			(stroke
				(width 0.1)
				(type default)
			)
			(layer "B.Fab")
		)
		(fp_line
			(start 0.12065 0.3048)
			(end 0.67945 0.3048)
			(stroke
				(width 0.1)
				(type default)
			)
			(layer "B.Fab")
		)
		(fp_line
			(start -0.120396 0.3048)
			(end -0.120396 0.2794)
			(stroke
				(width 0.1)
				(type default)
			)
			(layer "B.Fab")
		)
		(fp_line
			(start -0.67945 0.3048)
			(end -0.120396 0.3048)
			(stroke
				(width 0.1)
				(type default)
			)
			(layer "B.Fab")
		)
		(pad "1" smd circle
			(at 0.40005 0 270)
			(size 0 0)
			(layers "B.Cu" "B.Mask" "B.Paste")
			(net "RST_CPU0_RESETL_N")
		)
		(pad "2" smd circle
			(at -0.40005 0 270)
			(size 0 0)
			(layers "B.Cu" "B.Mask" "B.Paste")
			(net "PVDD18_S5_P0")
		)
	)
	(footprint ""
		(layer "B.Cu")
		(at 26.289762 -347.780356 -90)
		(property "Reference" "PR370"
			(at 0 0 90)
			(layer "B.SilkS")
			(hide yes)
			(effects
				(font
					(size 1.27 1.27)
				)
				(justify mirror)
			)
		)
		(property "Value" ""
			(at 0 0 90)
			(layer "B.Fab")
			(effects
				(font
					(size 1.27 1.27)
				)
				(justify mirror)
			)
		)
		(duplicate_pad_numbers_are_jumpers no)
		(fp_line
			(start -0.7874 0.4064)
			(end 0.7874 0.4064)
			(stroke
				(width 0.1524)
				(type default)
			)
			(layer "B.SilkS")
		)
		(fp_line
			(start 0.7874 0.4064)
			(end 0.7874 -0.4064)
			(stroke
				(width 0.1524)
				(type default)
			)
			(layer "B.SilkS")
		)
		(fp_line
			(start -0.7874 -0.4064)
			(end -0.7874 0.4064)
			(stroke
				(width 0.1524)
				(type default)
			)
			(layer "B.SilkS")
		)
		(fp_line
			(start 0.7874 -0.4064)
			(end -0.7874 -0.4064)
			(stroke
				(width 0.1524)
				(type default)
			)
			(layer "B.SilkS")
		)
		(fp_line
			(start -0.67945 0.3048)
			(end -0.120396 0.3048)
			(stroke
				(width 0.1)
				(type default)
			)
			(layer "B.Fab")
		)
		(fp_line
			(start -0.120396 0.3048)
			(end -0.120396 0.2794)
			(stroke
				(width 0.1)
				(type default)
			)
			(layer "B.Fab")
		)
		(fp_line
			(start 0.12065 0.3048)
			(end 0.67945 0.3048)
			(stroke
				(width 0.1)
				(type default)
			)
			(layer "B.Fab")
		)
		(fp_line
			(start 0.67945 0.3048)
			(end 0.67945 -0.305054)
			(stroke
				(width 0.1)
				(type default)
			)
			(layer "B.Fab")
		)
		(fp_line
			(start -0.120396 0.2794)
			(end 0.12065 0.2794)
			(stroke
				(width 0.1)
				(type default)
			)
			(layer "B.Fab")
		)
		(fp_line
			(start 0.12065 0.2794)
			(end 0.12065 0.3048)
			(stroke
				(width 0.1)
				(type default)
			)
			(layer "B.Fab")
		)
		(fp_line
			(start -0.12065 -0.2794)
			(end -0.12065 -0.3048)
			(stroke
				(width 0.1)
				(type default)
			)
			(layer "B.Fab")
		)
		(fp_line
			(start 0.12065 -0.2794)
			(end -0.12065 -0.2794)
			(stroke
				(width 0.1)
				(type default)
			)
			(layer "B.Fab")
		)
		(fp_line
			(start -0.67945 -0.3048)
			(end -0.67945 0.3048)
			(stroke
				(width 0.1)
				(type default)
			)
			(layer "B.Fab")
		)
		(fp_line
			(start -0.12065 -0.3048)
			(end -0.67945 -0.3048)
			(stroke
				(width 0.1)
				(type default)
			)
			(layer "B.Fab")
		)
		(fp_line
			(start 0.12065 -0.305054)
			(end 0.12065 -0.2794)
			(stroke
				(width 0.1)
				(type default)
			)
			(layer "B.Fab")
		)
		(fp_line
			(start 0.67945 -0.305054)
			(end 0.12065 -0.305054)
			(stroke
				(width 0.1)
				(type default)
			)
			(layer "B.Fab")
		)
		(pad "1" smd circle
			(at 0.40005 0 90)
			(size 0 0)
			(layers "B.Cu" "B.Mask" "B.Paste")
			(net "PVDDCR_CPU1_P1_PVCC")
		)
		(pad "2" smd circle
			(at -0.40005 0 90)
			(size 0 0)
			(layers "B.Cu" "B.Mask" "B.Paste")
			(net "PVDDIO_P1_VCC4")
		)
	)
	(footprint ""
		(layer "B.Cu")
		(at 296.703496 -349.381572 -90)
		(property "Reference" "PR103"
			(at 0 0 90)
			(layer "B.SilkS")
			(hide yes)
			(effects
				(font
					(size 1.27 1.27)
				)
				(justify mirror)
			)
		)
		(property "Value" ""
			(at 0 0 90)
			(layer "B.Fab")
			(effects
				(font
					(size 1.27 1.27)
				)
				(justify mirror)
			)
		)
		(duplicate_pad_numbers_are_jumpers no)
		(fp_line
			(start -0.7874 0.4064)
			(end 0.7874 0.4064)
			(stroke
				(width 0.1524)
				(type default)
			)
			(layer "B.SilkS")
		)
		(fp_line
			(start 0.7874 0.4064)
			(end 0.7874 -0.4064)
			(stroke
				(width 0.1524)
				(type default)
			)
			(layer "B.SilkS")
		)
		(fp_line
			(start -0.7874 -0.4064)
			(end -0.7874 0.4064)
			(stroke
				(width 0.1524)
				(type default)
			)
			(layer "B.SilkS")
		)
		(fp_line
			(start 0.7874 -0.4064)
			(end -0.7874 -0.4064)
			(stroke
				(width 0.1524)
				(type default)
			)
			(layer "B.SilkS")
		)
		(fp_line
			(start -0.67945 0.3048)
			(end -0.120396 0.3048)
			(stroke
				(width 0.1)
				(type default)
			)
			(layer "B.Fab")
		)
		(fp_line
			(start -0.120396 0.3048)
			(end -0.120396 0.2794)
			(stroke
				(width 0.1)
				(type default)
			)
			(layer "B.Fab")
		)
		(fp_line
			(start 0.12065 0.3048)
			(end 0.67945 0.3048)
			(stroke
				(width 0.1)
				(type default)
			)
			(layer "B.Fab")
		)
		(fp_line
			(start 0.67945 0.3048)
			(end 0.67945 -0.305054)
			(stroke
				(width 0.1)
				(type default)
			)
			(layer "B.Fab")
		)
		(fp_line
			(start -0.120396 0.2794)
			(end 0.12065 0.2794)
			(stroke
				(width 0.1)
				(type default)
			)
			(layer "B.Fab")
		)
		(fp_line
			(start 0.12065 0.2794)
			(end 0.12065 0.3048)
			(stroke
				(width 0.1)
				(type default)
			)
			(layer "B.Fab")
		)
		(fp_line
			(start -0.12065 -0.2794)
			(end -0.12065 -0.3048)
			(stroke
				(width 0.1)
				(type default)
			)
			(layer "B.Fab")
		)
		(fp_line
			(start 0.12065 -0.2794)
			(end -0.12065 -0.2794)
			(stroke
				(width 0.1)
				(type default)
			)
			(layer "B.Fab")
		)
		(fp_line
			(start -0.67945 -0.3048)
			(end -0.67945 0.3048)
			(stroke
				(width 0.1)
				(type default)
			)
			(layer "B.Fab")
		)
		(fp_line
			(start -0.12065 -0.3048)
			(end -0.67945 -0.3048)
			(stroke
				(width 0.1)
				(type default)
			)
			(layer "B.Fab")
		)
		(fp_line
			(start 0.12065 -0.305054)
			(end 0.12065 -0.2794)
			(stroke
				(width 0.1)
				(type default)
			)
			(layer "B.Fab")
		)
		(fp_line
			(start 0.67945 -0.305054)
			(end 0.12065 -0.305054)
			(stroke
				(width 0.1)
				(type default)
			)
			(layer "B.Fab")
		)
		(pad "1" smd circle
			(at 0.40005 0 90)
			(size 0 0)
			(layers "B.Cu" "B.Mask" "B.Paste")
			(net "PVDDIO_P0_VOS1")
		)
		(pad "2" smd circle
			(at -0.40005 0 90)
			(size 0 0)
			(layers "B.Cu" "B.Mask" "B.Paste")
			(net "PVDDIO_P0")
		)
	)
	(footprint ""
		(layer "B.Cu")
		(at 159.7152 -191.1604 -90)
		(property "Reference" "R542"
			(at 0 0 90)
			(layer "B.SilkS")
			(hide yes)
			(effects
				(font
					(size 1.27 1.27)
				)
				(justify mirror)
			)
		)
		(property "Value" ""
			(at 0 0 90)
			(layer "B.Fab")
			(effects
				(font
					(size 1.27 1.27)
				)
				(justify mirror)
			)
		)
		(duplicate_pad_numbers_are_jumpers no)
		(fp_line
			(start -0.7874 0.4064)
			(end 0.7874 0.4064)
			(stroke
				(width 0.1524)
				(type default)
			)
			(layer "B.SilkS")
		)
		(fp_line
			(start 0.7874 0.4064)
			(end 0.7874 -0.4064)
			(stroke
				(width 0.1524)
				(type default)
			)
			(layer "B.SilkS")
		)
		(fp_line
			(start -0.7874 -0.4064)
			(end -0.7874 0.4064)
			(stroke
				(width 0.1524)
				(type default)
			)
			(layer "B.SilkS")
		)
		(fp_line
			(start 0.7874 -0.4064)
			(end -0.7874 -0.4064)
			(stroke
				(width 0.1524)
				(type default)
			)
			(layer "B.SilkS")
		)
		(fp_line
			(start -0.67945 0.3048)
			(end -0.120396 0.3048)
			(stroke
				(width 0.1)
				(type default)
			)
			(layer "B.Fab")
		)
		(fp_line
			(start -0.120396 0.3048)
			(end -0.120396 0.2794)
			(stroke
				(width 0.1)
				(type default)
			)
			(layer "B.Fab")
		)
		(fp_line
			(start 0.12065 0.3048)
			(end 0.67945 0.3048)
			(stroke
				(width 0.1)
				(type default)
			)
			(layer "B.Fab")
		)
		(fp_line
			(start 0.67945 0.3048)
			(end 0.67945 -0.305054)
			(stroke
				(width 0.1)
				(type default)
			)
			(layer "B.Fab")
		)
		(fp_line
			(start -0.120396 0.2794)
			(end 0.12065 0.2794)
			(stroke
				(width 0.1)
				(type default)
			)
			(layer "B.Fab")
		)
		(fp_line
			(start 0.12065 0.2794)
			(end 0.12065 0.3048)
			(stroke
				(width 0.1)
				(type default)
			)
			(layer "B.Fab")
		)
		(fp_line
			(start -0.12065 -0.2794)
			(end -0.12065 -0.3048)
			(stroke
				(width 0.1)
				(type default)
			)
			(layer "B.Fab")
		)
		(fp_line
			(start 0.12065 -0.2794)
			(end -0.12065 -0.2794)
			(stroke
				(width 0.1)
				(type default)
			)
			(layer "B.Fab")
		)
		(fp_line
			(start -0.67945 -0.3048)
			(end -0.67945 0.3048)
			(stroke
				(width 0.1)
				(type default)
			)
			(layer "B.Fab")
		)
		(fp_line
			(start -0.12065 -0.3048)
			(end -0.67945 -0.3048)
			(stroke
				(width 0.1)
				(type default)
			)
			(layer "B.Fab")
		)
		(fp_line
			(start 0.12065 -0.305054)
			(end 0.12065 -0.2794)
			(stroke
				(width 0.1)
				(type default)
			)
			(layer "B.Fab")
		)
		(fp_line
			(start 0.67945 -0.305054)
			(end 0.12065 -0.305054)
			(stroke
				(width 0.1)
				(type default)
			)
			(layer "B.Fab")
		)
		(pad "1" smd circle
			(at 0.40005 0 90)
			(size 0 0)
			(layers "B.Cu" "B.Mask" "B.Paste")
			(net "PVDD11_S3_P1")
		)
		(pad "2" smd circle
			(at -0.40005 0 90)
			(size 0 0)
			(layers "B.Cu" "B.Mask" "B.Paste")
			(net "I3C_1_SPD_DDRGL_CPU1_R_SCL")
		)
	)
	(footprint ""
		(layer "B.Cu")
		(at 446.644014 -192.660016)
		(property "Reference" "C169"
			(at 0 0 0)
			(layer "B.SilkS")
			(hide yes)
			(effects
				(font
					(size 1.27 1.27)
				)
				(justify mirror)
			)
		)
		(property "Value" ""
			(at 0 0 0)
			(layer "B.Fab")
			(effects
				(font
					(size 1.27 1.27)
				)
				(justify mirror)
			)
		)
		(duplicate_pad_numbers_are_jumpers no)
		(fp_line
			(start -1.524 -0.762)
			(end -1.524 0.762)
			(stroke
				(width 0.1524)
				(type default)
			)
			(layer "B.SilkS")
		)
		(fp_line
			(start -1.524 0.762)
			(end 1.524 0.762)
			(stroke
				(width 0.1524)
				(type default)
			)
			(layer "B.SilkS")
		)
		(fp_line
			(start 1.524 -0.762)
			(end -1.524 -0.762)
			(stroke
				(width 0.1524)
				(type default)
			)
			(layer "B.SilkS")
		)
		(fp_line
			(start 1.524 0.762)
			(end 1.524 -0.762)
			(stroke
				(width 0.1524)
				(type default)
			)
			(layer "B.SilkS")
		)
		(fp_line
			(start -1.1049 -0.724916)
			(end 1.1049 -0.724916)
			(stroke
				(width 0.1)
				(type default)
			)
			(layer "B.Fab")
		)
		(fp_line
			(start -1.1049 0.724916)
			(end -1.1049 -0.724916)
			(stroke
				(width 0.1)
				(type default)
			)
			(layer "B.Fab")
		)
		(fp_line
			(start 1.1049 -0.724916)
			(end 1.1049 0.724916)
			(stroke
				(width 0.1)
				(type default)
			)
			(layer "B.Fab")
		)
		(fp_line
			(start 1.1049 0.724916)
			(end -1.1049 0.724916)
			(stroke
				(width 0.1)
				(type default)
			)
			(layer "B.Fab")
		)
		(pad "1" smd rect
			(at 0.889 0)
			(size 1.016 1.27)
			(layers "B.Cu" "B.Mask" "B.Paste")
			(net "P12V_MEM_CPU0")
		)
		(pad "2" smd rect
			(at -0.889 0)
			(size 1.016 1.27)
			(layers "B.Cu" "B.Mask" "B.Paste")
			(net "GND")
		)
	)
	(footprint ""
		(layer "B.Cu")
		(at 69.30898 -166.26332 90)
		(property "Reference" "PR425"
			(at 0 0 90)
			(layer "B.SilkS")
			(hide yes)
			(effects
				(font
					(size 1.27 1.27)
				)
				(justify mirror)
			)
		)
		(property "Value" ""
			(at 0 0 90)
			(layer "B.Fab")
			(effects
				(font
					(size 1.27 1.27)
				)
				(justify mirror)
			)
		)
		(duplicate_pad_numbers_are_jumpers no)
		(fp_line
			(start 0.7874 -0.4064)
			(end -0.7874 -0.4064)
			(stroke
				(width 0.1524)
				(type default)
			)
			(layer "B.SilkS")
		)
		(fp_line
			(start -0.7874 -0.4064)
			(end -0.7874 0.4064)
			(stroke
				(width 0.1524)
				(type default)
			)
			(layer "B.SilkS")
		)
		(fp_line
			(start 0.7874 0.4064)
			(end 0.7874 -0.4064)
			(stroke
				(width 0.1524)
				(type default)
			)
			(layer "B.SilkS")
		)
		(fp_line
			(start -0.7874 0.4064)
			(end 0.7874 0.4064)
			(stroke
				(width 0.1524)
				(type default)
			)
			(layer "B.SilkS")
		)
		(fp_line
			(start 0.67945 -0.305054)
			(end 0.12065 -0.305054)
			(stroke
				(width 0.1)
				(type default)
			)
			(layer "B.Fab")
		)
		(fp_line
			(start 0.12065 -0.305054)
			(end 0.12065 -0.2794)
			(stroke
				(width 0.1)
				(type default)
			)
			(layer "B.Fab")
		)
		(fp_line
			(start -0.12065 -0.3048)
			(end -0.67945 -0.3048)
			(stroke
				(width 0.1)
				(type default)
			)
			(layer "B.Fab")
		)
		(fp_line
			(start -0.67945 -0.3048)
			(end -0.67945 0.3048)
			(stroke
				(width 0.1)
				(type default)
			)
			(layer "B.Fab")
		)
		(fp_line
			(start 0.12065 -0.2794)
			(end -0.12065 -0.2794)
			(stroke
				(width 0.1)
				(type default)
			)
			(layer "B.Fab")
		)
		(fp_line
			(start -0.12065 -0.2794)
			(end -0.12065 -0.3048)
			(stroke
				(width 0.1)
				(type default)
			)
			(layer "B.Fab")
		)
		(fp_line
			(start 0.12065 0.2794)
			(end 0.12065 0.3048)
			(stroke
				(width 0.1)
				(type default)
			)
			(layer "B.Fab")
		)
		(fp_line
			(start -0.120396 0.2794)
			(end 0.12065 0.2794)
			(stroke
				(width 0.1)
				(type default)
			)
			(layer "B.Fab")
		)
		(fp_line
			(start 0.67945 0.3048)
			(end 0.67945 -0.305054)
			(stroke
				(width 0.1)
				(type default)
			)
			(layer "B.Fab")
		)
		(fp_line
			(start 0.12065 0.3048)
			(end 0.67945 0.3048)
			(stroke
				(width 0.1)
				(type default)
			)
			(layer "B.Fab")
		)
		(fp_line
			(start -0.120396 0.3048)
			(end -0.120396 0.2794)
			(stroke
				(width 0.1)
				(type default)
			)
			(layer "B.Fab")
		)
		(fp_line
			(start -0.67945 0.3048)
			(end -0.120396 0.3048)
			(stroke
				(width 0.1)
				(type default)
			)
			(layer "B.Fab")
		)
		(pad "1" smd circle
			(at 0.40005 0 270)
			(size 0 0)
			(layers "B.Cu" "B.Mask" "B.Paste")
			(net "PVDDCR_CPU0_P1_VOS6")
		)
		(pad "2" smd circle
			(at -0.40005 0 270)
			(size 0 0)
			(layers "B.Cu" "B.Mask" "B.Paste")
			(net "PVDDCR_CPU0_P1")
		)
	)
	(footprint ""
		(layer "B.Cu")
		(at 325.861426 -398.455134 180)
		(property "Reference" "C560"
			(at 0 0 0)
			(layer "B.SilkS")
			(hide yes)
			(effects
				(font
					(size 1.27 1.27)
				)
				(justify mirror)
			)
		)
		(property "Value" ""
			(at 0 0 0)
			(layer "B.Fab")
			(effects
				(font
					(size 1.27 1.27)
				)
				(justify mirror)
			)
		)
		(duplicate_pad_numbers_are_jumpers no)
		(fp_line
			(start 1.524 0.762)
			(end 1.524 -0.762)
			(stroke
				(width 0.1524)
				(type default)
			)
			(layer "B.SilkS")
		)
		(fp_line
			(start 1.524 -0.762)
			(end -1.524 -0.762)
			(stroke
				(width 0.1524)
				(type default)
			)
			(layer "B.SilkS")
		)
		(fp_line
			(start -1.524 0.762)
			(end 1.524 0.762)
			(stroke
				(width 0.1524)
				(type default)
			)
			(layer "B.SilkS")
		)
		(fp_line
			(start -1.524 -0.762)
			(end -1.524 0.762)
			(stroke
				(width 0.1524)
				(type default)
			)
			(layer "B.SilkS")
		)
		(fp_line
			(start 1.1049 0.724916)
			(end -1.1049 0.724916)
			(stroke
				(width 0.1)
				(type default)
			)
			(layer "B.Fab")
		)
		(fp_line
			(start 1.1049 -0.724916)
			(end 1.1049 0.724916)
			(stroke
				(width 0.1)
				(type default)
			)
			(layer "B.Fab")
		)
		(fp_line
			(start -1.1049 0.724916)
			(end -1.1049 -0.724916)
			(stroke
				(width 0.1)
				(type default)
			)
			(layer "B.Fab")
		)
		(fp_line
			(start -1.1049 -0.724916)
			(end 1.1049 -0.724916)
			(stroke
				(width 0.1)
				(type default)
			)
			(layer "B.Fab")
		)
		(pad "1" smd rect
			(at 0.889 0 180)
			(size 1.016 1.27)
			(layers "B.Cu" "B.Mask" "B.Paste")
			(net "P0V9_CPU0_RT0_2A")
		)
		(pad "2" smd rect
			(at -0.889 0 180)
			(size 1.016 1.27)
			(layers "B.Cu" "B.Mask" "B.Paste")
			(net "GND")
		)
	)
	(footprint ""
		(layer "B.Cu")
		(at 402.322538 -319.198752)
		(property "Reference" "R5029"
			(at 0 0 0)
			(layer "B.SilkS")
			(hide yes)
			(effects
				(font
					(size 1.27 1.27)
				)
				(justify mirror)
			)
		)
		(property "Value" ""
			(at 0 0 0)
			(layer "B.Fab")
			(effects
				(font
					(size 1.27 1.27)
				)
				(justify mirror)
			)
		)
		(duplicate_pad_numbers_are_jumpers no)
		(fp_line
			(start -0.7874 -0.4064)
			(end -0.7874 0.4064)
			(stroke
				(width 0.1524)
				(type default)
			)
			(layer "B.SilkS")
		)
		(fp_line
			(start -0.7874 0.4064)
			(end 0.7874 0.4064)
			(stroke
				(width 0.1524)
				(type default)
			)
			(layer "B.SilkS")
		)
		(fp_line
			(start 0.7874 -0.4064)
			(end -0.7874 -0.4064)
			(stroke
				(width 0.1524)
				(type default)
			)
			(layer "B.SilkS")
		)
		(fp_line
			(start 0.7874 0.4064)
			(end 0.7874 -0.4064)
			(stroke
				(width 0.1524)
				(type default)
			)
			(layer "B.SilkS")
		)
		(fp_line
			(start -0.67945 -0.3048)
			(end -0.67945 0.3048)
			(stroke
				(width 0.1)
				(type default)
			)
			(layer "B.Fab")
		)
		(fp_line
			(start -0.67945 0.3048)
			(end -0.120396 0.3048)
			(stroke
				(width 0.1)
				(type default)
			)
			(layer "B.Fab")
		)
		(fp_line
			(start -0.12065 -0.3048)
			(end -0.67945 -0.3048)
			(stroke
				(width 0.1)
				(type default)
			)
			(layer "B.Fab")
		)
		(fp_line
			(start -0.12065 -0.2794)
			(end -0.12065 -0.3048)
			(stroke
				(width 0.1)
				(type default)
			)
			(layer "B.Fab")
		)
		(fp_line
			(start -0.120396 0.2794)
			(end 0.12065 0.2794)
			(stroke
				(width 0.1)
				(type default)
			)
			(layer "B.Fab")
		)
		(fp_line
			(start -0.120396 0.3048)
			(end -0.120396 0.2794)
			(stroke
				(width 0.1)
				(type default)
			)
			(layer "B.Fab")
		)
		(fp_line
			(start 0.12065 -0.305054)
			(end 0.12065 -0.2794)
			(stroke
				(width 0.1)
				(type default)
			)
			(layer "B.Fab")
		)
		(fp_line
			(start 0.12065 -0.2794)
			(end -0.12065 -0.2794)
			(stroke
				(width 0.1)
				(type default)
			)
			(layer "B.Fab")
		)
		(fp_line
			(start 0.12065 0.2794)
			(end 0.12065 0.3048)
			(stroke
				(width 0.1)
				(type default)
			)
			(layer "B.Fab")
		)
		(fp_line
			(start 0.12065 0.3048)
			(end 0.67945 0.3048)
			(stroke
				(width 0.1)
				(type default)
			)
			(layer "B.Fab")
		)
		(fp_line
			(start 0.67945 -0.305054)
			(end 0.12065 -0.305054)
			(stroke
				(width 0.1)
				(type default)
			)
			(layer "B.Fab")
		)
		(fp_line
			(start 0.67945 0.3048)
			(end 0.67945 -0.305054)
			(stroke
				(width 0.1)
				(type default)
			)
			(layer "B.Fab")
		)
		(pad "1" smd circle
			(at 0.40005 0 180)
			(size 0 0)
			(layers "B.Cu" "B.Mask" "B.Paste")
			(net "GND")
		)
		(pad "2" smd circle
			(at -0.40005 0 180)
			(size 0 0)
			(layers "B.Cu" "B.Mask" "B.Paste")
			(net "IRQ_TPM_SPI_R_N")
		)
	)
	(footprint ""
		(layer "B.Cu")
		(at 219.61475 -347.604588 180)
		(property "Reference" ""
			(at 0 0 0)
			(layer "B.SilkS")
			(hide yes)
			(effects
				(font
					(size 1.27 1.27)
				)
				(justify mirror)
			)
		)
		(property "Value" ""
			(at 0 0 0)
			(layer "B.Fab")
			(effects
				(font
					(size 1.27 1.27)
				)
				(justify mirror)
			)
		)
		(duplicate_pad_numbers_are_jumpers no)
		(pad "1" smd circle
			(at 0 0)
			(size 0.9906 0.9906)
			(layers "B.Cu" "B.Mask" "B.Paste")
			(net "Net_2232")
		)
		(zone
			(layer "B.Cu")
			(hatch none 0.5)
			(connect_pads
				(clearance 0)
			)
			(min_thickness 0.25)
			(keepout
				(tracks not_allowed)
				(vias allowed)
				(pads allowed)
				(copperpour not_allowed)
				(footprints allowed)
			)
			(placement
				(enabled no)
				(sheetname "")
			)
			(fill
				(thermal_gap 0.5)
				(thermal_bridge_width 0.5)
				(island_removal_mode 0)
			)
			(polygon
				(pts
					(arc
						(start 221.24035 -347.604588)
						(mid 217.98915 -347.604588)
						(end 221.24035 -347.604588)
					)
				)
			)
		)
	)
	(footprint ""
		(layer "B.Cu")
		(at 193.929 -97.119948 90)
		(property "Reference" "R266"
			(at 0 0 90)
			(layer "B.SilkS")
			(hide yes)
			(effects
				(font
					(size 1.27 1.27)
				)
				(justify mirror)
			)
		)
		(property "Value" ""
			(at 0 0 90)
			(layer "B.Fab")
			(effects
				(font
					(size 1.27 1.27)
				)
				(justify mirror)
			)
		)
		(duplicate_pad_numbers_are_jumpers no)
		(fp_line
			(start 0.7874 -0.4064)
			(end -0.7874 -0.4064)
			(stroke
				(width 0.1524)
				(type default)
			)
			(layer "B.SilkS")
		)
		(fp_line
			(start -0.7874 -0.4064)
			(end -0.7874 0.4064)
			(stroke
				(width 0.1524)
				(type default)
			)
			(layer "B.SilkS")
		)
		(fp_line
			(start 0.7874 0.4064)
			(end 0.7874 -0.4064)
			(stroke
				(width 0.1524)
				(type default)
			)
			(layer "B.SilkS")
		)
		(fp_line
			(start -0.7874 0.4064)
			(end 0.7874 0.4064)
			(stroke
				(width 0.1524)
				(type default)
			)
			(layer "B.SilkS")
		)
		(fp_line
			(start 0.67945 -0.305054)
			(end 0.12065 -0.305054)
			(stroke
				(width 0.1)
				(type default)
			)
			(layer "B.Fab")
		)
		(fp_line
			(start 0.12065 -0.305054)
			(end 0.12065 -0.2794)
			(stroke
				(width 0.1)
				(type default)
			)
			(layer "B.Fab")
		)
		(fp_line
			(start -0.12065 -0.3048)
			(end -0.67945 -0.3048)
			(stroke
				(width 0.1)
				(type default)
			)
			(layer "B.Fab")
		)
		(fp_line
			(start -0.67945 -0.3048)
			(end -0.67945 0.3048)
			(stroke
				(width 0.1)
				(type default)
			)
			(layer "B.Fab")
		)
		(fp_line
			(start 0.12065 -0.2794)
			(end -0.12065 -0.2794)
			(stroke
				(width 0.1)
				(type default)
			)
			(layer "B.Fab")
		)
		(fp_line
			(start -0.12065 -0.2794)
			(end -0.12065 -0.3048)
			(stroke
				(width 0.1)
				(type default)
			)
			(layer "B.Fab")
		)
		(fp_line
			(start 0.12065 0.2794)
			(end 0.12065 0.3048)
			(stroke
				(width 0.1)
				(type default)
			)
			(layer "B.Fab")
		)
		(fp_line
			(start -0.120396 0.2794)
			(end 0.12065 0.2794)
			(stroke
				(width 0.1)
				(type default)
			)
			(layer "B.Fab")
		)
		(fp_line
			(start 0.67945 0.3048)
			(end 0.67945 -0.305054)
			(stroke
				(width 0.1)
				(type default)
			)
			(layer "B.Fab")
		)
		(fp_line
			(start 0.12065 0.3048)
			(end 0.67945 0.3048)
			(stroke
				(width 0.1)
				(type default)
			)
			(layer "B.Fab")
		)
		(fp_line
			(start -0.120396 0.3048)
			(end -0.120396 0.2794)
			(stroke
				(width 0.1)
				(type default)
			)
			(layer "B.Fab")
		)
		(fp_line
			(start -0.67945 0.3048)
			(end -0.120396 0.3048)
			(stroke
				(width 0.1)
				(type default)
			)
			(layer "B.Fab")
		)
		(pad "1" smd circle
			(at 0.40005 0 270)
			(size 0 0)
			(layers "B.Cu" "B.Mask" "B.Paste")
			(net "FM_CPU1_SA0")
		)
		(pad "2" smd circle
			(at -0.40005 0 270)
			(size 0 0)
			(layers "B.Cu" "B.Mask" "B.Paste")
			(net "CPU1_SA0")
		)
	)
	(footprint ""
		(layer "B.Cu")
		(at 237.896654 -322.511166)
		(property "Reference" "R1237"
			(at 0 0 0)
			(layer "B.SilkS")
			(hide yes)
			(effects
				(font
					(size 1.27 1.27)
				)
				(justify mirror)
			)
		)
		(property "Value" ""
			(at 0 0 0)
			(layer "B.Fab")
			(effects
				(font
					(size 1.27 1.27)
				)
				(justify mirror)
			)
		)
		(duplicate_pad_numbers_are_jumpers no)
		(fp_line
			(start -0.7874 -0.4064)
			(end -0.7874 0.4064)
			(stroke
				(width 0.1524)
				(type default)
			)
			(layer "B.SilkS")
		)
		(fp_line
			(start -0.7874 0.4064)
			(end 0.7874 0.4064)
			(stroke
				(width 0.1524)
				(type default)
			)
			(layer "B.SilkS")
		)
		(fp_line
			(start 0.7874 -0.4064)
			(end -0.7874 -0.4064)
			(stroke
				(width 0.1524)
				(type default)
			)
			(layer "B.SilkS")
		)
		(fp_line
			(start 0.7874 0.4064)
			(end 0.7874 -0.4064)
			(stroke
				(width 0.1524)
				(type default)
			)
			(layer "B.SilkS")
		)
		(fp_line
			(start -0.67945 -0.3048)
			(end -0.67945 0.3048)
			(stroke
				(width 0.1)
				(type default)
			)
			(layer "B.Fab")
		)
		(fp_line
			(start -0.67945 0.3048)
			(end -0.120396 0.3048)
			(stroke
				(width 0.1)
				(type default)
			)
			(layer "B.Fab")
		)
		(fp_line
			(start -0.12065 -0.3048)
			(end -0.67945 -0.3048)
			(stroke
				(width 0.1)
				(type default)
			)
			(layer "B.Fab")
		)
		(fp_line
			(start -0.12065 -0.2794)
			(end -0.12065 -0.3048)
			(stroke
				(width 0.1)
				(type default)
			)
			(layer "B.Fab")
		)
		(fp_line
			(start -0.120396 0.2794)
			(end 0.12065 0.2794)
			(stroke
				(width 0.1)
				(type default)
			)
			(layer "B.Fab")
		)
		(fp_line
			(start -0.120396 0.3048)
			(end -0.120396 0.2794)
			(stroke
				(width 0.1)
				(type default)
			)
			(layer "B.Fab")
		)
		(fp_line
			(start 0.12065 -0.305054)
			(end 0.12065 -0.2794)
			(stroke
				(width 0.1)
				(type default)
			)
			(layer "B.Fab")
		)
		(fp_line
			(start 0.12065 -0.2794)
			(end -0.12065 -0.2794)
			(stroke
				(width 0.1)
				(type default)
			)
			(layer "B.Fab")
		)
		(fp_line
			(start 0.12065 0.2794)
			(end 0.12065 0.3048)
			(stroke
				(width 0.1)
				(type default)
			)
			(layer "B.Fab")
		)
		(fp_line
			(start 0.12065 0.3048)
			(end 0.67945 0.3048)
			(stroke
				(width 0.1)
				(type default)
			)
			(layer "B.Fab")
		)
		(fp_line
			(start 0.67945 -0.305054)
			(end 0.12065 -0.305054)
			(stroke
				(width 0.1)
				(type default)
			)
			(layer "B.Fab")
		)
		(fp_line
			(start 0.67945 0.3048)
			(end 0.67945 -0.305054)
			(stroke
				(width 0.1)
				(type default)
			)
			(layer "B.Fab")
		)
		(pad "1" smd circle
			(at 0.40005 0 180)
			(size 0 0)
			(layers "B.Cu" "B.Mask" "B.Paste")
			(net "P1V8_AUX")
		)
		(pad "2" smd circle
			(at -0.40005 0 180)
			(size 0 0)
			(layers "B.Cu" "B.Mask" "B.Paste")
			(net "P1V8_AUX_ADC")
		)
	)
	(footprint ""
		(layer "B.Cu")
		(at 329.95108 -335.055972 90)
		(property "Reference" "PC90_2"
			(at 0 0 90)
			(layer "B.SilkS")
			(hide yes)
			(effects
				(font
					(size 1.27 1.27)
				)
				(justify mirror)
			)
		)
		(property "Value" ""
			(at 0 0 90)
			(layer "B.Fab")
			(effects
				(font
					(size 1.27 1.27)
				)
				(justify mirror)
			)
		)
		(duplicate_pad_numbers_are_jumpers no)
		(fp_line
			(start 1.524 -0.762)
			(end -1.524 -0.762)
			(stroke
				(width 0.1524)
				(type default)
			)
			(layer "B.SilkS")
		)
		(fp_line
			(start -1.524 -0.762)
			(end -1.524 0.762)
			(stroke
				(width 0.1524)
				(type default)
			)
			(layer "B.SilkS")
		)
		(fp_line
			(start 1.524 0.762)
			(end 1.524 -0.762)
			(stroke
				(width 0.1524)
				(type default)
			)
			(layer "B.SilkS")
		)
		(fp_line
			(start -1.524 0.762)
			(end 1.524 0.762)
			(stroke
				(width 0.1524)
				(type default)
			)
			(layer "B.SilkS")
		)
		(fp_line
			(start 1.1049 -0.724916)
			(end 1.1049 0.724916)
			(stroke
				(width 0.1)
				(type default)
			)
			(layer "B.Fab")
		)
		(fp_line
			(start -1.1049 -0.724916)
			(end 1.1049 -0.724916)
			(stroke
				(width 0.1)
				(type default)
			)
			(layer "B.Fab")
		)
		(fp_line
			(start 1.1049 0.724916)
			(end -1.1049 0.724916)
			(stroke
				(width 0.1)
				(type default)
			)
			(layer "B.Fab")
		)
		(fp_line
			(start -1.1049 0.724916)
			(end -1.1049 -0.724916)
			(stroke
				(width 0.1)
				(type default)
			)
			(layer "B.Fab")
		)
		(pad "1" smd rect
			(at 0.889 0 90)
			(size 1.016 1.27)
			(layers "B.Cu" "B.Mask" "B.Paste")
			(net "SW_P12V_AUX_PVDDCR_CPU1_P0_FLT")
		)
		(pad "2" smd rect
			(at -0.889 0 90)
			(size 1.016 1.27)
			(layers "B.Cu" "B.Mask" "B.Paste")
			(net "GND")
		)
	)
	(footprint ""
		(layer "B.Cu")
		(at 169.66692 -53.431948 180)
		(property "Reference" "C1923"
			(at 0 0 0)
			(layer "B.SilkS")
			(hide yes)
			(effects
				(font
					(size 1.27 1.27)
				)
				(justify mirror)
			)
		)
		(property "Value" ""
			(at 0 0 0)
			(layer "B.Fab")
			(effects
				(font
					(size 1.27 1.27)
				)
				(justify mirror)
			)
		)
		(duplicate_pad_numbers_are_jumpers no)
		(fp_line
			(start 0.7874 0.4064)
			(end 0.7874 -0.4064)
			(stroke
				(width 0.1524)
				(type default)
			)
			(layer "B.SilkS")
		)
		(fp_line
			(start 0.7874 -0.4064)
			(end -0.7874 -0.4064)
			(stroke
				(width 0.1524)
				(type default)
			)
			(layer "B.SilkS")
		)
		(fp_line
			(start -0.7874 0.4064)
			(end 0.7874 0.4064)
			(stroke
				(width 0.1524)
				(type default)
			)
			(layer "B.SilkS")
		)
		(fp_line
			(start -0.7874 -0.4064)
			(end -0.7874 0.4064)
			(stroke
				(width 0.1524)
				(type default)
			)
			(layer "B.SilkS")
		)
		(fp_line
			(start 0.67945 0.3048)
			(end 0.67945 -0.305054)
			(stroke
				(width 0.1)
				(type default)
			)
			(layer "B.Fab")
		)
		(fp_line
			(start 0.67945 -0.305054)
			(end 0.12065 -0.305054)
			(stroke
				(width 0.1)
				(type default)
			)
			(layer "B.Fab")
		)
		(fp_line
			(start 0.12065 0.3048)
			(end 0.67945 0.3048)
			(stroke
				(width 0.1)
				(type default)
			)
			(layer "B.Fab")
		)
		(fp_line
			(start 0.12065 0.2794)
			(end 0.12065 0.3048)
			(stroke
				(width 0.1)
				(type default)
			)
			(layer "B.Fab")
		)
		(fp_line
			(start 0.12065 -0.2794)
			(end -0.12065 -0.2794)
			(stroke
				(width 0.1)
				(type default)
			)
			(layer "B.Fab")
		)
		(fp_line
			(start 0.12065 -0.305054)
			(end 0.12065 -0.2794)
			(stroke
				(width 0.1)
				(type default)
			)
			(layer "B.Fab")
		)
		(fp_line
			(start -0.120396 0.3048)
			(end -0.120396 0.2794)
			(stroke
				(width 0.1)
				(type default)
			)
			(layer "B.Fab")
		)
		(fp_line
			(start -0.120396 0.2794)
			(end 0.12065 0.2794)
			(stroke
				(width 0.1)
				(type default)
			)
			(layer "B.Fab")
		)
		(fp_line
			(start -0.12065 -0.2794)
			(end -0.12065 -0.3048)
			(stroke
				(width 0.1)
				(type default)
			)
			(layer "B.Fab")
		)
		(fp_line
			(start -0.12065 -0.3048)
			(end -0.67945 -0.3048)
			(stroke
				(width 0.1)
				(type default)
			)
			(layer "B.Fab")
		)
		(fp_line
			(start -0.67945 0.3048)
			(end -0.120396 0.3048)
			(stroke
				(width 0.1)
				(type default)
			)
			(layer "B.Fab")
		)
		(fp_line
			(start -0.67945 -0.3048)
			(end -0.67945 0.3048)
			(stroke
				(width 0.1)
				(type default)
			)
			(layer "B.Fab")
		)
		(pad "1" smd circle
			(at 0.40005 0)
			(size 0 0)
			(layers "B.Cu" "B.Mask" "B.Paste")
			(net "P3V3_M2_0")
		)
		(pad "2" smd circle
			(at -0.40005 0)
			(size 0 0)
			(layers "B.Cu" "B.Mask" "B.Paste")
			(net "GND")
		)
	)
	(footprint ""
		(layer "B.Cu")
		(at 224.999042 -315.95568 -90)
		(property "Reference" "PC6531"
			(at 0 0 90)
			(layer "B.SilkS")
			(hide yes)
			(effects
				(font
					(size 1.27 1.27)
				)
				(justify mirror)
			)
		)
		(property "Value" ""
			(at 0 0 90)
			(layer "B.Fab")
			(effects
				(font
					(size 1.27 1.27)
				)
				(justify mirror)
			)
		)
		(duplicate_pad_numbers_are_jumpers no)
		(fp_line
			(start -1.524 0.762)
			(end 1.524 0.762)
			(stroke
				(width 0.1524)
				(type default)
			)
			(layer "B.SilkS")
		)
		(fp_line
			(start 1.524 0.762)
			(end 1.524 -0.762)
			(stroke
				(width 0.1524)
				(type default)
			)
			(layer "B.SilkS")
		)
		(fp_line
			(start -1.524 -0.762)
			(end -1.524 0.762)
			(stroke
				(width 0.1524)
				(type default)
			)
			(layer "B.SilkS")
		)
		(fp_line
			(start 1.524 -0.762)
			(end -1.524 -0.762)
			(stroke
				(width 0.1524)
				(type default)
			)
			(layer "B.SilkS")
		)
		(fp_line
			(start -1.1049 0.724916)
			(end -1.1049 -0.724916)
			(stroke
				(width 0.1)
				(type default)
			)
			(layer "B.Fab")
		)
		(fp_line
			(start 1.1049 0.724916)
			(end -1.1049 0.724916)
			(stroke
				(width 0.1)
				(type default)
			)
			(layer "B.Fab")
		)
		(fp_line
			(start -1.1049 -0.724916)
			(end 1.1049 -0.724916)
			(stroke
				(width 0.1)
				(type default)
			)
			(layer "B.Fab")
		)
		(fp_line
			(start 1.1049 -0.724916)
			(end 1.1049 0.724916)
			(stroke
				(width 0.1)
				(type default)
			)
			(layer "B.Fab")
		)
		(pad "1" smd rect
			(at 0.889 0 270)
			(size 1.016 1.27)
			(layers "B.Cu" "B.Mask" "B.Paste")
			(net "P1V8_CPU1_RT_1D")
		)
		(pad "2" smd rect
			(at -0.889 0 270)
			(size 1.016 1.27)
			(layers "B.Cu" "B.Mask" "B.Paste")
			(net "GND")
		)
	)
	(footprint ""
		(layer "B.Cu")
		(at 231.267 -218.059 90)
		(property "Reference" "R202"
			(at 0 0 90)
			(layer "B.SilkS")
			(hide yes)
			(effects
				(font
					(size 1.27 1.27)
				)
				(justify mirror)
			)
		)
		(property "Value" ""
			(at 0 0 90)
			(layer "B.Fab")
			(effects
				(font
					(size 1.27 1.27)
				)
				(justify mirror)
			)
		)
		(duplicate_pad_numbers_are_jumpers no)
		(fp_line
			(start 0.7874 -0.4064)
			(end -0.7874 -0.4064)
			(stroke
				(width 0.1524)
				(type default)
			)
			(layer "B.SilkS")
		)
		(fp_line
			(start -0.7874 -0.4064)
			(end -0.7874 0.4064)
			(stroke
				(width 0.1524)
				(type default)
			)
			(layer "B.SilkS")
		)
		(fp_line
			(start 0.7874 0.4064)
			(end 0.7874 -0.4064)
			(stroke
				(width 0.1524)
				(type default)
			)
			(layer "B.SilkS")
		)
		(fp_line
			(start -0.7874 0.4064)
			(end 0.7874 0.4064)
			(stroke
				(width 0.1524)
				(type default)
			)
			(layer "B.SilkS")
		)
		(fp_line
			(start 0.67945 -0.305054)
			(end 0.12065 -0.305054)
			(stroke
				(width 0.1)
				(type default)
			)
			(layer "B.Fab")
		)
		(fp_line
			(start 0.12065 -0.305054)
			(end 0.12065 -0.2794)
			(stroke
				(width 0.1)
				(type default)
			)
			(layer "B.Fab")
		)
		(fp_line
			(start -0.12065 -0.3048)
			(end -0.67945 -0.3048)
			(stroke
				(width 0.1)
				(type default)
			)
			(layer "B.Fab")
		)
		(fp_line
			(start -0.67945 -0.3048)
			(end -0.67945 0.3048)
			(stroke
				(width 0.1)
				(type default)
			)
			(layer "B.Fab")
		)
		(fp_line
			(start 0.12065 -0.2794)
			(end -0.12065 -0.2794)
			(stroke
				(width 0.1)
				(type default)
			)
			(layer "B.Fab")
		)
		(fp_line
			(start -0.12065 -0.2794)
			(end -0.12065 -0.3048)
			(stroke
				(width 0.1)
				(type default)
			)
			(layer "B.Fab")
		)
		(fp_line
			(start 0.12065 0.2794)
			(end 0.12065 0.3048)
			(stroke
				(width 0.1)
				(type default)
			)
			(layer "B.Fab")
		)
		(fp_line
			(start -0.120396 0.2794)
			(end 0.12065 0.2794)
			(stroke
				(width 0.1)
				(type default)
			)
			(layer "B.Fab")
		)
		(fp_line
			(start 0.67945 0.3048)
			(end 0.67945 -0.305054)
			(stroke
				(width 0.1)
				(type default)
			)
			(layer "B.Fab")
		)
		(fp_line
			(start 0.12065 0.3048)
			(end 0.67945 0.3048)
			(stroke
				(width 0.1)
				(type default)
			)
			(layer "B.Fab")
		)
		(fp_line
			(start -0.120396 0.3048)
			(end -0.120396 0.2794)
			(stroke
				(width 0.1)
				(type default)
			)
			(layer "B.Fab")
		)
		(fp_line
			(start -0.67945 0.3048)
			(end -0.120396 0.3048)
			(stroke
				(width 0.1)
				(type default)
			)
			(layer "B.Fab")
		)
		(pad "1" smd circle
			(at 0.40005 0 270)
			(size 0 0)
			(layers "B.Cu" "B.Mask" "B.Paste")
			(net "SMB_CPU0_CPU1_APML_BUF2_SCL_R1")
		)
		(pad "2" smd circle
			(at -0.40005 0 270)
			(size 0 0)
			(layers "B.Cu" "B.Mask" "B.Paste")
			(net "SMB_CPU0_CPU1_APML_BUF2_SCL_R2")
		)
	)
	(footprint ""
		(layer "B.Cu")
		(at 332.763876 -66.708782 90)
		(property "Reference" "R3090"
			(at 0 0 90)
			(layer "B.SilkS")
			(hide yes)
			(effects
				(font
					(size 1.27 1.27)
				)
				(justify mirror)
			)
		)
		(property "Value" ""
			(at 0 0 90)
			(layer "B.Fab")
			(effects
				(font
					(size 1.27 1.27)
				)
				(justify mirror)
			)
		)
		(duplicate_pad_numbers_are_jumpers no)
		(fp_line
			(start 0.7874 -0.4064)
			(end -0.7874 -0.4064)
			(stroke
				(width 0.1524)
				(type default)
			)
			(layer "B.SilkS")
		)
		(fp_line
			(start -0.7874 -0.4064)
			(end -0.7874 0.4064)
			(stroke
				(width 0.1524)
				(type default)
			)
			(layer "B.SilkS")
		)
		(fp_line
			(start 0.7874 0.4064)
			(end 0.7874 -0.4064)
			(stroke
				(width 0.1524)
				(type default)
			)
			(layer "B.SilkS")
		)
		(fp_line
			(start -0.7874 0.4064)
			(end 0.7874 0.4064)
			(stroke
				(width 0.1524)
				(type default)
			)
			(layer "B.SilkS")
		)
		(fp_line
			(start 0.67945 -0.305054)
			(end 0.12065 -0.305054)
			(stroke
				(width 0.1)
				(type default)
			)
			(layer "B.Fab")
		)
		(fp_line
			(start 0.12065 -0.305054)
			(end 0.12065 -0.2794)
			(stroke
				(width 0.1)
				(type default)
			)
			(layer "B.Fab")
		)
		(fp_line
			(start -0.12065 -0.3048)
			(end -0.67945 -0.3048)
			(stroke
				(width 0.1)
				(type default)
			)
			(layer "B.Fab")
		)
		(fp_line
			(start -0.67945 -0.3048)
			(end -0.67945 0.3048)
			(stroke
				(width 0.1)
				(type default)
			)
			(layer "B.Fab")
		)
		(fp_line
			(start 0.12065 -0.2794)
			(end -0.12065 -0.2794)
			(stroke
				(width 0.1)
				(type default)
			)
			(layer "B.Fab")
		)
		(fp_line
			(start -0.12065 -0.2794)
			(end -0.12065 -0.3048)
			(stroke
				(width 0.1)
				(type default)
			)
			(layer "B.Fab")
		)
		(fp_line
			(start 0.12065 0.2794)
			(end 0.12065 0.3048)
			(stroke
				(width 0.1)
				(type default)
			)
			(layer "B.Fab")
		)
		(fp_line
			(start -0.120396 0.2794)
			(end 0.12065 0.2794)
			(stroke
				(width 0.1)
				(type default)
			)
			(layer "B.Fab")
		)
		(fp_line
			(start 0.67945 0.3048)
			(end 0.67945 -0.305054)
			(stroke
				(width 0.1)
				(type default)
			)
			(layer "B.Fab")
		)
		(fp_line
			(start 0.12065 0.3048)
			(end 0.67945 0.3048)
			(stroke
				(width 0.1)
				(type default)
			)
			(layer "B.Fab")
		)
		(fp_line
			(start -0.120396 0.3048)
			(end -0.120396 0.2794)
			(stroke
				(width 0.1)
				(type default)
			)
			(layer "B.Fab")
		)
		(fp_line
			(start -0.67945 0.3048)
			(end -0.120396 0.3048)
			(stroke
				(width 0.1)
				(type default)
			)
			(layer "B.Fab")
		)
		(pad "1" smd circle
			(at 0.40005 0 270)
			(size 0 0)
			(layers "B.Cu" "B.Mask" "B.Paste")
			(net "LED_PWRGD_PVDD11_S3_P0_R")
		)
		(pad "2" smd circle
			(at -0.40005 0 270)
			(size 0 0)
			(layers "B.Cu" "B.Mask" "B.Paste")
			(net "P3V3_AUX")
		)
	)
	(footprint ""
		(layer "B.Cu")
		(at 108.15828 -410.252672)
		(property "Reference" "C75"
			(at 0 0 0)
			(layer "B.SilkS")
			(hide yes)
			(effects
				(font
					(size 1.27 1.27)
				)
				(justify mirror)
			)
		)
		(property "Value" ""
			(at 0 0 0)
			(layer "B.Fab")
			(effects
				(font
					(size 1.27 1.27)
				)
				(justify mirror)
			)
		)
		(duplicate_pad_numbers_are_jumpers no)
		(fp_line
			(start -0.7874 -0.4064)
			(end -0.7874 0.4064)
			(stroke
				(width 0.1524)
				(type default)
			)
			(layer "B.SilkS")
		)
		(fp_line
			(start -0.7874 0.4064)
			(end 0.7874 0.4064)
			(stroke
				(width 0.1524)
				(type default)
			)
			(layer "B.SilkS")
		)
		(fp_line
			(start 0.7874 -0.4064)
			(end -0.7874 -0.4064)
			(stroke
				(width 0.1524)
				(type default)
			)
			(layer "B.SilkS")
		)
		(fp_line
			(start 0.7874 0.4064)
			(end 0.7874 -0.4064)
			(stroke
				(width 0.1524)
				(type default)
			)
			(layer "B.SilkS")
		)
		(fp_line
			(start -0.67945 -0.3048)
			(end -0.67945 0.3048)
			(stroke
				(width 0.1)
				(type default)
			)
			(layer "B.Fab")
		)
		(fp_line
			(start -0.67945 0.3048)
			(end -0.120396 0.3048)
			(stroke
				(width 0.1)
				(type default)
			)
			(layer "B.Fab")
		)
		(fp_line
			(start -0.12065 -0.3048)
			(end -0.67945 -0.3048)
			(stroke
				(width 0.1)
				(type default)
			)
			(layer "B.Fab")
		)
		(fp_line
			(start -0.12065 -0.2794)
			(end -0.12065 -0.3048)
			(stroke
				(width 0.1)
				(type default)
			)
			(layer "B.Fab")
		)
		(fp_line
			(start -0.120396 0.2794)
			(end 0.12065 0.2794)
			(stroke
				(width 0.1)
				(type default)
			)
			(layer "B.Fab")
		)
		(fp_line
			(start -0.120396 0.3048)
			(end -0.120396 0.2794)
			(stroke
				(width 0.1)
				(type default)
			)
			(layer "B.Fab")
		)
		(fp_line
			(start 0.12065 -0.305054)
			(end 0.12065 -0.2794)
			(stroke
				(width 0.1)
				(type default)
			)
			(layer "B.Fab")
		)
		(fp_line
			(start 0.12065 -0.2794)
			(end -0.12065 -0.2794)
			(stroke
				(width 0.1)
				(type default)
			)
			(layer "B.Fab")
		)
		(fp_line
			(start 0.12065 0.2794)
			(end 0.12065 0.3048)
			(stroke
				(width 0.1)
				(type default)
			)
			(layer "B.Fab")
		)
		(fp_line
			(start 0.12065 0.3048)
			(end 0.67945 0.3048)
			(stroke
				(width 0.1)
				(type default)
			)
			(layer "B.Fab")
		)
		(fp_line
			(start 0.67945 -0.305054)
			(end 0.12065 -0.305054)
			(stroke
				(width 0.1)
				(type default)
			)
			(layer "B.Fab")
		)
		(fp_line
			(start 0.67945 0.3048)
			(end 0.67945 -0.305054)
			(stroke
				(width 0.1)
				(type default)
			)
			(layer "B.Fab")
		)
		(pad "1" smd circle
			(at 0.40005 0 180)
			(size 0 0)
			(layers "B.Cu" "B.Mask" "B.Paste")
			(net "P3V3_9ZXL045_P1_VDD")
		)
		(pad "2" smd circle
			(at -0.40005 0 180)
			(size 0 0)
			(layers "B.Cu" "B.Mask" "B.Paste")
			(net "GND")
		)
	)
	(footprint ""
		(layer "B.Cu")
		(at 238.633 -333.883 180)
		(property "Reference" "R801"
			(at 0 0 0)
			(layer "B.SilkS")
			(hide yes)
			(effects
				(font
					(size 1.27 1.27)
				)
				(justify mirror)
			)
		)
		(property "Value" ""
			(at 0 0 0)
			(layer "B.Fab")
			(effects
				(font
					(size 1.27 1.27)
				)
				(justify mirror)
			)
		)
		(duplicate_pad_numbers_are_jumpers no)
		(fp_line
			(start 0.32512 0.175006)
			(end 0.32512 -0.175006)
			(stroke
				(width 0.1)
				(type default)
			)
			(layer "B.Fab")
		)
		(fp_line
			(start 0.32512 -0.175006)
			(end -0.32512 -0.175006)
			(stroke
				(width 0.1)
				(type default)
			)
			(layer "B.Fab")
		)
		(fp_line
			(start -0.32512 0.175006)
			(end 0.32512 0.175006)
			(stroke
				(width 0.1)
				(type default)
			)
			(layer "B.Fab")
		)
		(fp_line
			(start -0.32512 -0.175006)
			(end -0.32512 0.175006)
			(stroke
				(width 0.1)
				(type default)
			)
			(layer "B.Fab")
		)
		(pad "1" smd rect
			(at 0.2667 0)
			(size 0.3048 0.381)
			(layers "B.Cu" "B.Mask" "B.Paste")
			(net "SMB_RT_CPU1_P0_ROM_MUX_2D_SDA")
		)
		(pad "2" smd rect
			(at -0.2667 0 180)
			(size 0.3048 0.381)
			(layers "B.Cu" "B.Mask" "B.Paste")
			(net "SMB_RT_CPU1_P0_ROM_MUX_2D_R_SDA")
		)
	)
	(footprint ""
		(layer "B.Cu")
		(at 317.702438 -199.998838)
		(property "Reference" "R6502"
			(at 0 0 0)
			(layer "B.SilkS")
			(hide yes)
			(effects
				(font
					(size 1.27 1.27)
				)
				(justify mirror)
			)
		)
		(property "Value" ""
			(at 0 0 0)
			(layer "B.Fab")
			(effects
				(font
					(size 1.27 1.27)
				)
				(justify mirror)
			)
		)
		(duplicate_pad_numbers_are_jumpers no)
		(fp_line
			(start -0.7874 -0.4064)
			(end -0.7874 0.4064)
			(stroke
				(width 0.1524)
				(type default)
			)
			(layer "B.SilkS")
		)
		(fp_line
			(start -0.7874 0.4064)
			(end 0.7874 0.4064)
			(stroke
				(width 0.1524)
				(type default)
			)
			(layer "B.SilkS")
		)
		(fp_line
			(start 0.7874 -0.4064)
			(end -0.7874 -0.4064)
			(stroke
				(width 0.1524)
				(type default)
			)
			(layer "B.SilkS")
		)
		(fp_line
			(start 0.7874 0.4064)
			(end 0.7874 -0.4064)
			(stroke
				(width 0.1524)
				(type default)
			)
			(layer "B.SilkS")
		)
		(fp_line
			(start -0.67945 -0.3048)
			(end -0.67945 0.3048)
			(stroke
				(width 0.1)
				(type default)
			)
			(layer "B.Fab")
		)
		(fp_line
			(start -0.67945 0.3048)
			(end -0.120396 0.3048)
			(stroke
				(width 0.1)
				(type default)
			)
			(layer "B.Fab")
		)
		(fp_line
			(start -0.12065 -0.3048)
			(end -0.67945 -0.3048)
			(stroke
				(width 0.1)
				(type default)
			)
			(layer "B.Fab")
		)
		(fp_line
			(start -0.12065 -0.2794)
			(end -0.12065 -0.3048)
			(stroke
				(width 0.1)
				(type default)
			)
			(layer "B.Fab")
		)
		(fp_line
			(start -0.120396 0.2794)
			(end 0.12065 0.2794)
			(stroke
				(width 0.1)
				(type default)
			)
			(layer "B.Fab")
		)
		(fp_line
			(start -0.120396 0.3048)
			(end -0.120396 0.2794)
			(stroke
				(width 0.1)
				(type default)
			)
			(layer "B.Fab")
		)
		(fp_line
			(start 0.12065 -0.305054)
			(end 0.12065 -0.2794)
			(stroke
				(width 0.1)
				(type default)
			)
			(layer "B.Fab")
		)
		(fp_line
			(start 0.12065 -0.2794)
			(end -0.12065 -0.2794)
			(stroke
				(width 0.1)
				(type default)
			)
			(layer "B.Fab")
		)
		(fp_line
			(start 0.12065 0.2794)
			(end 0.12065 0.3048)
			(stroke
				(width 0.1)
				(type default)
			)
			(layer "B.Fab")
		)
		(fp_line
			(start 0.12065 0.3048)
			(end 0.67945 0.3048)
			(stroke
				(width 0.1)
				(type default)
			)
			(layer "B.Fab")
		)
		(fp_line
			(start 0.67945 -0.305054)
			(end 0.12065 -0.305054)
			(stroke
				(width 0.1)
				(type default)
			)
			(layer "B.Fab")
		)
		(fp_line
			(start 0.67945 0.3048)
			(end 0.67945 -0.305054)
			(stroke
				(width 0.1)
				(type default)
			)
			(layer "B.Fab")
		)
		(pad "1" smd circle
			(at 0.40005 0 180)
			(size 0 0)
			(layers "B.Cu" "B.Mask" "B.Paste")
			(net "CPU0_FORCE_SELFREFRESH")
		)
		(pad "2" smd circle
			(at -0.40005 0 180)
			(size 0 0)
			(layers "B.Cu" "B.Mask" "B.Paste")
			(net "GND")
		)
	)
	(footprint ""
		(layer "B.Cu")
		(at 70.172834 -203.679552 180)
		(property "Reference" "R517"
			(at 0 0 0)
			(layer "B.SilkS")
			(hide yes)
			(effects
				(font
					(size 1.27 1.27)
				)
				(justify mirror)
			)
		)
		(property "Value" ""
			(at 0 0 0)
			(layer "B.Fab")
			(effects
				(font
					(size 1.27 1.27)
				)
				(justify mirror)
			)
		)
		(duplicate_pad_numbers_are_jumpers no)
		(fp_line
			(start 0.7874 0.4064)
			(end 0.7874 -0.4064)
			(stroke
				(width 0.1524)
				(type default)
			)
			(layer "B.SilkS")
		)
		(fp_line
			(start 0.7874 -0.4064)
			(end -0.7874 -0.4064)
			(stroke
				(width 0.1524)
				(type default)
			)
			(layer "B.SilkS")
		)
		(fp_line
			(start -0.7874 0.4064)
			(end 0.7874 0.4064)
			(stroke
				(width 0.1524)
				(type default)
			)
			(layer "B.SilkS")
		)
		(fp_line
			(start -0.7874 -0.4064)
			(end -0.7874 0.4064)
			(stroke
				(width 0.1524)
				(type default)
			)
			(layer "B.SilkS")
		)
		(fp_line
			(start 0.67945 0.3048)
			(end 0.67945 -0.305054)
			(stroke
				(width 0.1)
				(type default)
			)
			(layer "B.Fab")
		)
		(fp_line
			(start 0.67945 -0.305054)
			(end 0.12065 -0.305054)
			(stroke
				(width 0.1)
				(type default)
			)
			(layer "B.Fab")
		)
		(fp_line
			(start 0.12065 0.3048)
			(end 0.67945 0.3048)
			(stroke
				(width 0.1)
				(type default)
			)
			(layer "B.Fab")
		)
		(fp_line
			(start 0.12065 0.2794)
			(end 0.12065 0.3048)
			(stroke
				(width 0.1)
				(type default)
			)
			(layer "B.Fab")
		)
		(fp_line
			(start 0.12065 -0.2794)
			(end -0.12065 -0.2794)
			(stroke
				(width 0.1)
				(type default)
			)
			(layer "B.Fab")
		)
		(fp_line
			(start 0.12065 -0.305054)
			(end 0.12065 -0.2794)
			(stroke
				(width 0.1)
				(type default)
			)
			(layer "B.Fab")
		)
		(fp_line
			(start -0.120396 0.3048)
			(end -0.120396 0.2794)
			(stroke
				(width 0.1)
				(type default)
			)
			(layer "B.Fab")
		)
		(fp_line
			(start -0.120396 0.2794)
			(end 0.12065 0.2794)
			(stroke
				(width 0.1)
				(type default)
			)
			(layer "B.Fab")
		)
		(fp_line
			(start -0.12065 -0.2794)
			(end -0.12065 -0.3048)
			(stroke
				(width 0.1)
				(type default)
			)
			(layer "B.Fab")
		)
		(fp_line
			(start -0.12065 -0.3048)
			(end -0.67945 -0.3048)
			(stroke
				(width 0.1)
				(type default)
			)
			(layer "B.Fab")
		)
		(fp_line
			(start -0.67945 0.3048)
			(end -0.120396 0.3048)
			(stroke
				(width 0.1)
				(type default)
			)
			(layer "B.Fab")
		)
		(fp_line
			(start -0.67945 -0.3048)
			(end -0.67945 0.3048)
			(stroke
				(width 0.1)
				(type default)
			)
			(layer "B.Fab")
		)
		(pad "1" smd circle
			(at 0.40005 0)
			(size 0 0)
			(layers "B.Cu" "B.Mask" "B.Paste")
			(net "P3V3_AUX")
		)
		(pad "2" smd circle
			(at -0.40005 0)
			(size 0 0)
			(layers "B.Cu" "B.Mask" "B.Paste")
			(net "CPU1_SP5R2")
		)
	)
	(footprint ""
		(layer "B.Cu")
		(at 109.728 -417.83 -90)
		(property "Reference" "R3035"
			(at 0 0 90)
			(layer "B.SilkS")
			(hide yes)
			(effects
				(font
					(size 1.27 1.27)
				)
				(justify mirror)
			)
		)
		(property "Value" ""
			(at 0 0 90)
			(layer "B.Fab")
			(effects
				(font
					(size 1.27 1.27)
				)
				(justify mirror)
			)
		)
		(duplicate_pad_numbers_are_jumpers no)
		(fp_line
			(start -0.7874 0.4064)
			(end 0.7874 0.4064)
			(stroke
				(width 0.1524)
				(type default)
			)
			(layer "B.SilkS")
		)
		(fp_line
			(start 0.7874 0.4064)
			(end 0.7874 -0.4064)
			(stroke
				(width 0.1524)
				(type default)
			)
			(layer "B.SilkS")
		)
		(fp_line
			(start -0.7874 -0.4064)
			(end -0.7874 0.4064)
			(stroke
				(width 0.1524)
				(type default)
			)
			(layer "B.SilkS")
		)
		(fp_line
			(start 0.7874 -0.4064)
			(end -0.7874 -0.4064)
			(stroke
				(width 0.1524)
				(type default)
			)
			(layer "B.SilkS")
		)
		(fp_line
			(start -0.67945 0.3048)
			(end -0.120396 0.3048)
			(stroke
				(width 0.1)
				(type default)
			)
			(layer "B.Fab")
		)
		(fp_line
			(start -0.120396 0.3048)
			(end -0.120396 0.2794)
			(stroke
				(width 0.1)
				(type default)
			)
			(layer "B.Fab")
		)
		(fp_line
			(start 0.12065 0.3048)
			(end 0.67945 0.3048)
			(stroke
				(width 0.1)
				(type default)
			)
			(layer "B.Fab")
		)
		(fp_line
			(start 0.67945 0.3048)
			(end 0.67945 -0.305054)
			(stroke
				(width 0.1)
				(type default)
			)
			(layer "B.Fab")
		)
		(fp_line
			(start -0.120396 0.2794)
			(end 0.12065 0.2794)
			(stroke
				(width 0.1)
				(type default)
			)
			(layer "B.Fab")
		)
		(fp_line
			(start 0.12065 0.2794)
			(end 0.12065 0.3048)
			(stroke
				(width 0.1)
				(type default)
			)
			(layer "B.Fab")
		)
		(fp_line
			(start -0.12065 -0.2794)
			(end -0.12065 -0.3048)
			(stroke
				(width 0.1)
				(type default)
			)
			(layer "B.Fab")
		)
		(fp_line
			(start 0.12065 -0.2794)
			(end -0.12065 -0.2794)
			(stroke
				(width 0.1)
				(type default)
			)
			(layer "B.Fab")
		)
		(fp_line
			(start -0.67945 -0.3048)
			(end -0.67945 0.3048)
			(stroke
				(width 0.1)
				(type default)
			)
			(layer "B.Fab")
		)
		(fp_line
			(start -0.12065 -0.3048)
			(end -0.67945 -0.3048)
			(stroke
				(width 0.1)
				(type default)
			)
			(layer "B.Fab")
		)
		(fp_line
			(start 0.12065 -0.305054)
			(end 0.12065 -0.2794)
			(stroke
				(width 0.1)
				(type default)
			)
			(layer "B.Fab")
		)
		(fp_line
			(start 0.67945 -0.305054)
			(end 0.12065 -0.305054)
			(stroke
				(width 0.1)
				(type default)
			)
			(layer "B.Fab")
		)
		(pad "1" smd circle
			(at 0.40005 0 90)
			(size 0 0)
			(layers "B.Cu" "B.Mask" "B.Paste")
			(net "P3V3_AUX")
		)
		(pad "2" smd circle
			(at -0.40005 0 90)
			(size 0 0)
			(layers "B.Cu" "B.Mask" "B.Paste")
			(net "FM_SMB_2_ALERT_GPU_ISO_N")
		)
	)
	(footprint ""
		(layer "B.Cu")
		(at 164.949378 -17.417288 180)
		(property "Reference" "R329"
			(at 0 0 0)
			(layer "B.SilkS")
			(hide yes)
			(effects
				(font
					(size 1.27 1.27)
				)
				(justify mirror)
			)
		)
		(property "Value" ""
			(at 0 0 0)
			(layer "B.Fab")
			(effects
				(font
					(size 1.27 1.27)
				)
				(justify mirror)
			)
		)
		(duplicate_pad_numbers_are_jumpers no)
		(fp_line
			(start 0.7874 0.4064)
			(end 0.7874 -0.4064)
			(stroke
				(width 0.1524)
				(type default)
			)
			(layer "B.SilkS")
		)
		(fp_line
			(start 0.7874 -0.4064)
			(end -0.7874 -0.4064)
			(stroke
				(width 0.1524)
				(type default)
			)
			(layer "B.SilkS")
		)
		(fp_line
			(start -0.7874 0.4064)
			(end 0.7874 0.4064)
			(stroke
				(width 0.1524)
				(type default)
			)
			(layer "B.SilkS")
		)
		(fp_line
			(start -0.7874 -0.4064)
			(end -0.7874 0.4064)
			(stroke
				(width 0.1524)
				(type default)
			)
			(layer "B.SilkS")
		)
		(fp_line
			(start 0.67945 0.3048)
			(end 0.67945 -0.305054)
			(stroke
				(width 0.1)
				(type default)
			)
			(layer "B.Fab")
		)
		(fp_line
			(start 0.67945 -0.305054)
			(end 0.12065 -0.305054)
			(stroke
				(width 0.1)
				(type default)
			)
			(layer "B.Fab")
		)
		(fp_line
			(start 0.12065 0.3048)
			(end 0.67945 0.3048)
			(stroke
				(width 0.1)
				(type default)
			)
			(layer "B.Fab")
		)
		(fp_line
			(start 0.12065 0.2794)
			(end 0.12065 0.3048)
			(stroke
				(width 0.1)
				(type default)
			)
			(layer "B.Fab")
		)
		(fp_line
			(start 0.12065 -0.2794)
			(end -0.12065 -0.2794)
			(stroke
				(width 0.1)
				(type default)
			)
			(layer "B.Fab")
		)
		(fp_line
			(start 0.12065 -0.305054)
			(end 0.12065 -0.2794)
			(stroke
				(width 0.1)
				(type default)
			)
			(layer "B.Fab")
		)
		(fp_line
			(start -0.120396 0.3048)
			(end -0.120396 0.2794)
			(stroke
				(width 0.1)
				(type default)
			)
			(layer "B.Fab")
		)
		(fp_line
			(start -0.120396 0.2794)
			(end 0.12065 0.2794)
			(stroke
				(width 0.1)
				(type default)
			)
			(layer "B.Fab")
		)
		(fp_line
			(start -0.12065 -0.2794)
			(end -0.12065 -0.3048)
			(stroke
				(width 0.1)
				(type default)
			)
			(layer "B.Fab")
		)
		(fp_line
			(start -0.12065 -0.3048)
			(end -0.67945 -0.3048)
			(stroke
				(width 0.1)
				(type default)
			)
			(layer "B.Fab")
		)
		(fp_line
			(start -0.67945 0.3048)
			(end -0.120396 0.3048)
			(stroke
				(width 0.1)
				(type default)
			)
			(layer "B.Fab")
		)
		(fp_line
			(start -0.67945 -0.3048)
			(end -0.67945 0.3048)
			(stroke
				(width 0.1)
				(type default)
			)
			(layer "B.Fab")
		)
		(pad "1" smd circle
			(at 0.40005 0)
			(size 0 0)
			(layers "B.Cu" "B.Mask" "B.Paste")
			(net "SMB_PMBUS_3V3AUX_SDA")
		)
		(pad "2" smd circle
			(at -0.40005 0)
			(size 0 0)
			(layers "B.Cu" "B.Mask" "B.Paste")
			(net "P3V3_AUX")
		)
	)
	(footprint ""
		(layer "B.Cu")
		(at 372.321328 -137.008108 90)
		(property "Reference" "C5011"
			(at 0 0 90)
			(layer "B.SilkS")
			(hide yes)
			(effects
				(font
					(size 1.27 1.27)
				)
				(justify mirror)
			)
		)
		(property "Value" ""
			(at 0 0 90)
			(layer "B.Fab")
			(effects
				(font
					(size 1.27 1.27)
				)
				(justify mirror)
			)
		)
		(duplicate_pad_numbers_are_jumpers no)
		(fp_line
			(start 0.7874 -0.4064)
			(end -0.7874 -0.4064)
			(stroke
				(width 0.1524)
				(type default)
			)
			(layer "B.SilkS")
		)
		(fp_line
			(start -0.7874 -0.4064)
			(end -0.7874 0.4064)
			(stroke
				(width 0.1524)
				(type default)
			)
			(layer "B.SilkS")
		)
		(fp_line
			(start 0.7874 0.4064)
			(end 0.7874 -0.4064)
			(stroke
				(width 0.1524)
				(type default)
			)
			(layer "B.SilkS")
		)
		(fp_line
			(start -0.7874 0.4064)
			(end 0.7874 0.4064)
			(stroke
				(width 0.1524)
				(type default)
			)
			(layer "B.SilkS")
		)
		(fp_line
			(start 0.67945 -0.305054)
			(end 0.12065 -0.305054)
			(stroke
				(width 0.1)
				(type default)
			)
			(layer "B.Fab")
		)
		(fp_line
			(start 0.12065 -0.305054)
			(end 0.12065 -0.2794)
			(stroke
				(width 0.1)
				(type default)
			)
			(layer "B.Fab")
		)
		(fp_line
			(start -0.12065 -0.3048)
			(end -0.67945 -0.3048)
			(stroke
				(width 0.1)
				(type default)
			)
			(layer "B.Fab")
		)
		(fp_line
			(start -0.67945 -0.3048)
			(end -0.67945 0.3048)
			(stroke
				(width 0.1)
				(type default)
			)
			(layer "B.Fab")
		)
		(fp_line
			(start 0.12065 -0.2794)
			(end -0.12065 -0.2794)
			(stroke
				(width 0.1)
				(type default)
			)
			(layer "B.Fab")
		)
		(fp_line
			(start -0.12065 -0.2794)
			(end -0.12065 -0.3048)
			(stroke
				(width 0.1)
				(type default)
			)
			(layer "B.Fab")
		)
		(fp_line
			(start 0.12065 0.2794)
			(end 0.12065 0.3048)
			(stroke
				(width 0.1)
				(type default)
			)
			(layer "B.Fab")
		)
		(fp_line
			(start -0.120396 0.2794)
			(end 0.12065 0.2794)
			(stroke
				(width 0.1)
				(type default)
			)
			(layer "B.Fab")
		)
		(fp_line
			(start 0.67945 0.3048)
			(end 0.67945 -0.305054)
			(stroke
				(width 0.1)
				(type default)
			)
			(layer "B.Fab")
		)
		(fp_line
			(start 0.12065 0.3048)
			(end 0.67945 0.3048)
			(stroke
				(width 0.1)
				(type default)
			)
			(layer "B.Fab")
		)
		(fp_line
			(start -0.120396 0.3048)
			(end -0.120396 0.2794)
			(stroke
				(width 0.1)
				(type default)
			)
			(layer "B.Fab")
		)
		(fp_line
			(start -0.67945 0.3048)
			(end -0.120396 0.3048)
			(stroke
				(width 0.1)
				(type default)
			)
			(layer "B.Fab")
		)
		(pad "1" smd circle
			(at 0.40005 0 270)
			(size 0 0)
			(layers "B.Cu" "B.Mask" "B.Paste")
			(net "PVDDCR_CPU0_P0_PMALERT")
		)
		(pad "2" smd circle
			(at -0.40005 0 270)
			(size 0 0)
			(layers "B.Cu" "B.Mask" "B.Paste")
			(net "GND")
		)
	)
	(footprint ""
		(layer "B.Cu")
		(at 136.897872 -64.04229 90)
		(property "Reference" "R15"
			(at 0 0 90)
			(layer "B.SilkS")
			(hide yes)
			(effects
				(font
					(size 1.27 1.27)
				)
				(justify mirror)
			)
		)
		(property "Value" ""
			(at 0 0 90)
			(layer "B.Fab")
			(effects
				(font
					(size 1.27 1.27)
				)
				(justify mirror)
			)
		)
		(duplicate_pad_numbers_are_jumpers no)
		(fp_line
			(start 0.7874 -0.4064)
			(end -0.7874 -0.4064)
			(stroke
				(width 0.1524)
				(type default)
			)
			(layer "B.SilkS")
		)
		(fp_line
			(start -0.7874 -0.4064)
			(end -0.7874 0.4064)
			(stroke
				(width 0.1524)
				(type default)
			)
			(layer "B.SilkS")
		)
		(fp_line
			(start 0.7874 0.4064)
			(end 0.7874 -0.4064)
			(stroke
				(width 0.1524)
				(type default)
			)
			(layer "B.SilkS")
		)
		(fp_line
			(start -0.7874 0.4064)
			(end 0.7874 0.4064)
			(stroke
				(width 0.1524)
				(type default)
			)
			(layer "B.SilkS")
		)
		(fp_line
			(start 0.67945 -0.305054)
			(end 0.12065 -0.305054)
			(stroke
				(width 0.1)
				(type default)
			)
			(layer "B.Fab")
		)
		(fp_line
			(start 0.12065 -0.305054)
			(end 0.12065 -0.2794)
			(stroke
				(width 0.1)
				(type default)
			)
			(layer "B.Fab")
		)
		(fp_line
			(start -0.12065 -0.3048)
			(end -0.67945 -0.3048)
			(stroke
				(width 0.1)
				(type default)
			)
			(layer "B.Fab")
		)
		(fp_line
			(start -0.67945 -0.3048)
			(end -0.67945 0.3048)
			(stroke
				(width 0.1)
				(type default)
			)
			(layer "B.Fab")
		)
		(fp_line
			(start 0.12065 -0.2794)
			(end -0.12065 -0.2794)
			(stroke
				(width 0.1)
				(type default)
			)
			(layer "B.Fab")
		)
		(fp_line
			(start -0.12065 -0.2794)
			(end -0.12065 -0.3048)
			(stroke
				(width 0.1)
				(type default)
			)
			(layer "B.Fab")
		)
		(fp_line
			(start 0.12065 0.2794)
			(end 0.12065 0.3048)
			(stroke
				(width 0.1)
				(type default)
			)
			(layer "B.Fab")
		)
		(fp_line
			(start -0.120396 0.2794)
			(end 0.12065 0.2794)
			(stroke
				(width 0.1)
				(type default)
			)
			(layer "B.Fab")
		)
		(fp_line
			(start 0.67945 0.3048)
			(end 0.67945 -0.305054)
			(stroke
				(width 0.1)
				(type default)
			)
			(layer "B.Fab")
		)
		(fp_line
			(start 0.12065 0.3048)
			(end 0.67945 0.3048)
			(stroke
				(width 0.1)
				(type default)
			)
			(layer "B.Fab")
		)
		(fp_line
			(start -0.120396 0.3048)
			(end -0.120396 0.2794)
			(stroke
				(width 0.1)
				(type default)
			)
			(layer "B.Fab")
		)
		(fp_line
			(start -0.67945 0.3048)
			(end -0.120396 0.3048)
			(stroke
				(width 0.1)
				(type default)
			)
			(layer "B.Fab")
		)
		(pad "1" smd circle
			(at 0.40005 0 270)
			(size 0 0)
			(layers "B.Cu" "B.Mask" "B.Paste")
			(net "JTAG_PLD_TCK")
		)
		(pad "2" smd circle
			(at -0.40005 0 270)
			(size 0 0)
			(layers "B.Cu" "B.Mask" "B.Paste")
			(net "JTAG_SCM_PLD_TCK")
		)
	)
	(footprint ""
		(layer "B.Cu")
		(at 244.348 -329.057 -90)
		(property "Reference" "C1077"
			(at 0 0 90)
			(layer "B.SilkS")
			(hide yes)
			(effects
				(font
					(size 1.27 1.27)
				)
				(justify mirror)
			)
		)
		(property "Value" ""
			(at 0 0 90)
			(layer "B.Fab")
			(effects
				(font
					(size 1.27 1.27)
				)
				(justify mirror)
			)
		)
		(duplicate_pad_numbers_are_jumpers no)
		(fp_line
			(start -1.524 0.762)
			(end 1.524 0.762)
			(stroke
				(width 0.1524)
				(type default)
			)
			(layer "B.SilkS")
		)
		(fp_line
			(start 1.524 0.762)
			(end 1.524 -0.762)
			(stroke
				(width 0.1524)
				(type default)
			)
			(layer "B.SilkS")
		)
		(fp_line
			(start -1.524 -0.762)
			(end -1.524 0.762)
			(stroke
				(width 0.1524)
				(type default)
			)
			(layer "B.SilkS")
		)
		(fp_line
			(start 1.524 -0.762)
			(end -1.524 -0.762)
			(stroke
				(width 0.1524)
				(type default)
			)
			(layer "B.SilkS")
		)
		(fp_line
			(start -1.1049 0.724916)
			(end -1.1049 -0.724916)
			(stroke
				(width 0.1)
				(type default)
			)
			(layer "B.Fab")
		)
		(fp_line
			(start 1.1049 0.724916)
			(end -1.1049 0.724916)
			(stroke
				(width 0.1)
				(type default)
			)
			(layer "B.Fab")
		)
		(fp_line
			(start -1.1049 -0.724916)
			(end 1.1049 -0.724916)
			(stroke
				(width 0.1)
				(type default)
			)
			(layer "B.Fab")
		)
		(fp_line
			(start 1.1049 -0.724916)
			(end 1.1049 0.724916)
			(stroke
				(width 0.1)
				(type default)
			)
			(layer "B.Fab")
		)
		(pad "1" smd rect
			(at 0.889 0 270)
			(size 1.016 1.27)
			(layers "B.Cu" "B.Mask" "B.Paste")
			(net "P3V3_MAX11617_2_VDD")
		)
		(pad "2" smd rect
			(at -0.889 0 270)
			(size 1.016 1.27)
			(layers "B.Cu" "B.Mask" "B.Paste")
			(net "GND")
		)
	)
	(footprint ""
		(layer "B.Cu")
		(at 148.206206 -386.766562 90)
		(property "Reference" "C425"
			(at 0 0 90)
			(layer "B.SilkS")
			(hide yes)
			(effects
				(font
					(size 1.27 1.27)
				)
				(justify mirror)
			)
		)
		(property "Value" ""
			(at 0 0 90)
			(layer "B.Fab")
			(effects
				(font
					(size 1.27 1.27)
				)
				(justify mirror)
			)
		)
		(duplicate_pad_numbers_are_jumpers no)
		(fp_line
			(start 0.299974 -0.150114)
			(end -0.299974 -0.150114)
			(stroke
				(width 0.1)
				(type default)
			)
			(layer "B.Fab")
		)
		(fp_line
			(start -0.299974 -0.150114)
			(end -0.299974 0.150114)
			(stroke
				(width 0.1)
				(type default)
			)
			(layer "B.Fab")
		)
		(fp_line
			(start 0.299974 0.150114)
			(end 0.299974 -0.150114)
			(stroke
				(width 0.1)
				(type default)
			)
			(layer "B.Fab")
		)
		(fp_line
			(start -0.299974 0.150114)
			(end 0.299974 0.150114)
			(stroke
				(width 0.1)
				(type default)
			)
			(layer "B.Fab")
		)
		(pad "1" smd rect
			(at 0.2667 0 270)
			(size 0.3048 0.381)
			(layers "B.Cu" "B.Mask" "B.Paste")
			(net "P0V9_CPU1_RT2_2A")
		)
		(pad "2" smd rect
			(at -0.2667 0 270)
			(size 0.3048 0.381)
			(layers "B.Cu" "B.Mask" "B.Paste")
			(net "GND")
		)
	)
	(footprint ""
		(layer "B.Cu")
		(at 395.516354 -401.624546 180)
		(property "Reference" "R1051"
			(at 0 0 0)
			(layer "B.SilkS")
			(hide yes)
			(effects
				(font
					(size 1.27 1.27)
				)
				(justify mirror)
			)
		)
		(property "Value" ""
			(at 0 0 0)
			(layer "B.Fab")
			(effects
				(font
					(size 1.27 1.27)
				)
				(justify mirror)
			)
		)
		(duplicate_pad_numbers_are_jumpers no)
		(fp_line
			(start 1.2954 0.5842)
			(end 1.2954 -0.5842)
			(stroke
				(width 0.1524)
				(type default)
			)
			(layer "B.SilkS")
		)
		(fp_line
			(start 1.2954 -0.5842)
			(end -1.2954 -0.5842)
			(stroke
				(width 0.1524)
				(type default)
			)
			(layer "B.SilkS")
		)
		(fp_line
			(start -1.2954 0.5842)
			(end 1.2954 0.5842)
			(stroke
				(width 0.1524)
				(type default)
			)
			(layer "B.SilkS")
		)
		(fp_line
			(start -1.2954 -0.5842)
			(end -1.2954 0.5842)
			(stroke
				(width 0.1524)
				(type default)
			)
			(layer "B.SilkS")
		)
		(fp_line
			(start 1.1938 0.4064)
			(end 1.1938 -0.406654)
			(stroke
				(width 0.1)
				(type default)
			)
			(layer "B.Fab")
		)
		(fp_line
			(start 1.1938 -0.406654)
			(end 0.8636 -0.406654)
			(stroke
				(width 0.1)
				(type default)
			)
			(layer "B.Fab")
		)
		(fp_line
			(start 0.8636 0.4572)
			(end 0.8636 0.4318)
			(stroke
				(width 0.1)
				(type default)
			)
			(layer "B.Fab")
		)
		(fp_line
			(start 0.8636 0.4318)
			(end 0.8636 0.4064)
			(stroke
				(width 0.1)
				(type default)
			)
			(layer "B.Fab")
		)
		(fp_line
			(start 0.8636 0.4064)
			(end 1.1938 0.4064)
			(stroke
				(width 0.1)
				(type default)
			)
			(layer "B.Fab")
		)
		(fp_line
			(start 0.8636 -0.406654)
			(end 0.8636 -0.4572)
			(stroke
				(width 0.1)
				(type default)
			)
			(layer "B.Fab")
		)
		(fp_line
			(start 0.8636 -0.4572)
			(end -0.8636 -0.4572)
			(stroke
				(width 0.1)
				(type default)
			)
			(layer "B.Fab")
		)
		(fp_line
			(start -0.8636 0.4572)
			(end 0.8636 0.4572)
			(stroke
				(width 0.1)
				(type default)
			)
			(layer "B.Fab")
		)
		(fp_line
			(start -0.8636 0.4064)
			(end -0.8636 0.4572)
			(stroke
				(width 0.1)
				(type default)
			)
			(layer "B.Fab")
		)
		(fp_line
			(start -0.8636 -0.406654)
			(end -1.1938 -0.406654)
			(stroke
				(width 0.1)
				(type default)
			)
			(layer "B.Fab")
		)
		(fp_line
			(start -0.8636 -0.4572)
			(end -0.8636 -0.406654)
			(stroke
				(width 0.1)
				(type default)
			)
			(layer "B.Fab")
		)
		(fp_line
			(start -1.1938 0.4064)
			(end -0.8636 0.4064)
			(stroke
				(width 0.1)
				(type default)
			)
			(layer "B.Fab")
		)
		(fp_line
			(start -1.1938 -0.406654)
			(end -1.1938 0.4064)
			(stroke
				(width 0.1)
				(type default)
			)
			(layer "B.Fab")
		)
		(pad "1" smd rect
			(at 0.7366 0 90)
			(size 0.7112 0.8128)
			(layers "B.Cu" "B.Mask" "B.Paste")
			(net "P0V9_CPU0_RT_2D")
		)
		(pad "2" smd rect
			(at -0.7366 0 90)
			(size 0.7112 0.8128)
			(layers "B.Cu" "B.Mask" "B.Paste")
			(net "P0V9_CPU0_RT2_2A_2D")
		)
	)
	(footprint ""
		(layer "B.Cu")
		(at 383.076958 -205.902052 -90)
		(property "Reference" "R987"
			(at 0 0 90)
			(layer "B.SilkS")
			(hide yes)
			(effects
				(font
					(size 1.27 1.27)
				)
				(justify mirror)
			)
		)
		(property "Value" ""
			(at 0 0 90)
			(layer "B.Fab")
			(effects
				(font
					(size 1.27 1.27)
				)
				(justify mirror)
			)
		)
		(duplicate_pad_numbers_are_jumpers no)
		(fp_line
			(start -0.7874 0.4064)
			(end 0.7874 0.4064)
			(stroke
				(width 0.1524)
				(type default)
			)
			(layer "B.SilkS")
		)
		(fp_line
			(start 0.7874 0.4064)
			(end 0.7874 -0.4064)
			(stroke
				(width 0.1524)
				(type default)
			)
			(layer "B.SilkS")
		)
		(fp_line
			(start -0.7874 -0.4064)
			(end -0.7874 0.4064)
			(stroke
				(width 0.1524)
				(type default)
			)
			(layer "B.SilkS")
		)
		(fp_line
			(start 0.7874 -0.4064)
			(end -0.7874 -0.4064)
			(stroke
				(width 0.1524)
				(type default)
			)
			(layer "B.SilkS")
		)
		(fp_line
			(start -0.67945 0.3048)
			(end -0.120396 0.3048)
			(stroke
				(width 0.1)
				(type default)
			)
			(layer "B.Fab")
		)
		(fp_line
			(start -0.120396 0.3048)
			(end -0.120396 0.2794)
			(stroke
				(width 0.1)
				(type default)
			)
			(layer "B.Fab")
		)
		(fp_line
			(start 0.12065 0.3048)
			(end 0.67945 0.3048)
			(stroke
				(width 0.1)
				(type default)
			)
			(layer "B.Fab")
		)
		(fp_line
			(start 0.67945 0.3048)
			(end 0.67945 -0.305054)
			(stroke
				(width 0.1)
				(type default)
			)
			(layer "B.Fab")
		)
		(fp_line
			(start -0.120396 0.2794)
			(end 0.12065 0.2794)
			(stroke
				(width 0.1)
				(type default)
			)
			(layer "B.Fab")
		)
		(fp_line
			(start 0.12065 0.2794)
			(end 0.12065 0.3048)
			(stroke
				(width 0.1)
				(type default)
			)
			(layer "B.Fab")
		)
		(fp_line
			(start -0.12065 -0.2794)
			(end -0.12065 -0.3048)
			(stroke
				(width 0.1)
				(type default)
			)
			(layer "B.Fab")
		)
		(fp_line
			(start 0.12065 -0.2794)
			(end -0.12065 -0.2794)
			(stroke
				(width 0.1)
				(type default)
			)
			(layer "B.Fab")
		)
		(fp_line
			(start -0.67945 -0.3048)
			(end -0.67945 0.3048)
			(stroke
				(width 0.1)
				(type default)
			)
			(layer "B.Fab")
		)
		(fp_line
			(start -0.12065 -0.3048)
			(end -0.67945 -0.3048)
			(stroke
				(width 0.1)
				(type default)
			)
			(layer "B.Fab")
		)
		(fp_line
			(start 0.12065 -0.305054)
			(end 0.12065 -0.2794)
			(stroke
				(width 0.1)
				(type default)
			)
			(layer "B.Fab")
		)
		(fp_line
			(start 0.67945 -0.305054)
			(end 0.12065 -0.305054)
			(stroke
				(width 0.1)
				(type default)
			)
			(layer "B.Fab")
		)
		(pad "1" smd rect
			(at 0.40005 0 270)
			(size 0.4572 0.508)
			(layers "B.Cu" "B.Mask" "B.Paste")
			(net "I3C_1_SPD_DDRGL_CPU0_R_SDA")
		)
		(pad "2" smd rect
			(at -0.40005 0 270)
			(size 0.4572 0.508)
			(layers "B.Cu" "B.Mask" "B.Paste")
			(net "I3C_SPD_DDRGL_CPU0_BYPASS_SDA")
		)
	)
	(footprint ""
		(layer "B.Cu")
		(at 307.0352 -428.0916 180)
		(property "Reference" "R1365"
			(at 0 0 0)
			(layer "B.SilkS")
			(hide yes)
			(effects
				(font
					(size 1.27 1.27)
				)
				(justify mirror)
			)
		)
		(property "Value" ""
			(at 0 0 0)
			(layer "B.Fab")
			(effects
				(font
					(size 1.27 1.27)
				)
				(justify mirror)
			)
		)
		(duplicate_pad_numbers_are_jumpers no)
		(fp_line
			(start 0.32512 0.175006)
			(end 0.32512 -0.175006)
			(stroke
				(width 0.1)
				(type default)
			)
			(layer "B.Fab")
		)
		(fp_line
			(start 0.32512 -0.175006)
			(end -0.32512 -0.175006)
			(stroke
				(width 0.1)
				(type default)
			)
			(layer "B.Fab")
		)
		(fp_line
			(start -0.32512 0.175006)
			(end 0.32512 0.175006)
			(stroke
				(width 0.1)
				(type default)
			)
			(layer "B.Fab")
		)
		(fp_line
			(start -0.32512 -0.175006)
			(end -0.32512 0.175006)
			(stroke
				(width 0.1)
				(type default)
			)
			(layer "B.Fab")
		)
		(pad "1" smd rect
			(at 0.2667 0)
			(size 0.3048 0.381)
			(layers "B.Cu" "B.Mask" "B.Paste")
			(net "JTAG_TCK_RT_CPU0_P0")
		)
		(pad "2" smd rect
			(at -0.2667 0 180)
			(size 0.3048 0.381)
			(layers "B.Cu" "B.Mask" "B.Paste")
			(net "GND")
		)
	)
	(footprint ""
		(layer "B.Cu")
		(at 439.42 -356.235 180)
		(property "Reference" "PC8004"
			(at 0 0 0)
			(layer "B.SilkS")
			(hide yes)
			(effects
				(font
					(size 1.27 1.27)
				)
				(justify mirror)
			)
		)
		(property "Value" ""
			(at 0 0 0)
			(layer "B.Fab")
			(effects
				(font
					(size 1.27 1.27)
				)
				(justify mirror)
			)
		)
		(duplicate_pad_numbers_are_jumpers no)
		(fp_line
			(start 1.524 0.762)
			(end 1.524 -0.762)
			(stroke
				(width 0.1524)
				(type default)
			)
			(layer "B.SilkS")
		)
		(fp_line
			(start 1.524 -0.762)
			(end -1.524 -0.762)
			(stroke
				(width 0.1524)
				(type default)
			)
			(layer "B.SilkS")
		)
		(fp_line
			(start -1.524 0.762)
			(end 1.524 0.762)
			(stroke
				(width 0.1524)
				(type default)
			)
			(layer "B.SilkS")
		)
		(fp_line
			(start -1.524 -0.762)
			(end -1.524 0.762)
			(stroke
				(width 0.1524)
				(type default)
			)
			(layer "B.SilkS")
		)
		(fp_line
			(start 1.1049 0.724916)
			(end -1.1049 0.724916)
			(stroke
				(width 0.1)
				(type default)
			)
			(layer "B.Fab")
		)
		(fp_line
			(start 1.1049 -0.724916)
			(end 1.1049 0.724916)
			(stroke
				(width 0.1)
				(type default)
			)
			(layer "B.Fab")
		)
		(fp_line
			(start -1.1049 0.724916)
			(end -1.1049 -0.724916)
			(stroke
				(width 0.1)
				(type default)
			)
			(layer "B.Fab")
		)
		(fp_line
			(start -1.1049 -0.724916)
			(end 1.1049 -0.724916)
			(stroke
				(width 0.1)
				(type default)
			)
			(layer "B.Fab")
		)
		(pad "1" smd rect
			(at 0.889 0 180)
			(size 1.016 1.27)
			(layers "B.Cu" "B.Mask" "B.Paste")
			(net "SW_P12V_AUX_PVDD11_S3_P0_FLT")
		)
		(pad "2" smd rect
			(at -0.889 0 180)
			(size 1.016 1.27)
			(layers "B.Cu" "B.Mask" "B.Paste")
			(net "GND")
		)
	)
	(footprint ""
		(layer "B.Cu")
		(at 397.623538 -393.96416 180)
		(property "Reference" "R1073"
			(at 0 0 0)
			(layer "B.SilkS")
			(hide yes)
			(effects
				(font
					(size 1.27 1.27)
				)
				(justify mirror)
			)
		)
		(property "Value" ""
			(at 0 0 0)
			(layer "B.Fab")
			(effects
				(font
					(size 1.27 1.27)
				)
				(justify mirror)
			)
		)
		(duplicate_pad_numbers_are_jumpers no)
		(fp_line
			(start 0.32512 0.175006)
			(end 0.32512 -0.175006)
			(stroke
				(width 0.1)
				(type default)
			)
			(layer "B.Fab")
		)
		(fp_line
			(start 0.32512 -0.175006)
			(end -0.32512 -0.175006)
			(stroke
				(width 0.1)
				(type default)
			)
			(layer "B.Fab")
		)
		(fp_line
			(start -0.32512 0.175006)
			(end 0.32512 0.175006)
			(stroke
				(width 0.1)
				(type default)
			)
			(layer "B.Fab")
		)
		(fp_line
			(start -0.32512 -0.175006)
			(end -0.32512 0.175006)
			(stroke
				(width 0.1)
				(type default)
			)
			(layer "B.Fab")
		)
		(pad "1" smd rect
			(at 0.2667 0)
			(size 0.3048 0.381)
			(layers "B.Cu" "B.Mask" "B.Paste")
			(net "P1V8_CPU0_RT_1D")
		)
		(pad "2" smd rect
			(at -0.2667 0 180)
			(size 0.3048 0.381)
			(layers "B.Cu" "B.Mask" "B.Paste")
			(net "TEST0_RT_CPU0_P2")
		)
	)
	(footprint ""
		(layer "B.Cu")
		(at 240.792 -217.678 -90)
		(property "Reference" "R78"
			(at 0 0 90)
			(layer "B.SilkS")
			(hide yes)
			(effects
				(font
					(size 1.27 1.27)
				)
				(justify mirror)
			)
		)
		(property "Value" ""
			(at 0 0 90)
			(layer "B.Fab")
			(effects
				(font
					(size 1.27 1.27)
				)
				(justify mirror)
			)
		)
		(duplicate_pad_numbers_are_jumpers no)
		(fp_line
			(start -0.7874 0.4064)
			(end 0.7874 0.4064)
			(stroke
				(width 0.1524)
				(type default)
			)
			(layer "B.SilkS")
		)
		(fp_line
			(start 0.7874 0.4064)
			(end 0.7874 -0.4064)
			(stroke
				(width 0.1524)
				(type default)
			)
			(layer "B.SilkS")
		)
		(fp_line
			(start -0.7874 -0.4064)
			(end -0.7874 0.4064)
			(stroke
				(width 0.1524)
				(type default)
			)
			(layer "B.SilkS")
		)
		(fp_line
			(start 0.7874 -0.4064)
			(end -0.7874 -0.4064)
			(stroke
				(width 0.1524)
				(type default)
			)
			(layer "B.SilkS")
		)
		(fp_line
			(start -0.67945 0.3048)
			(end -0.120396 0.3048)
			(stroke
				(width 0.1)
				(type default)
			)
			(layer "B.Fab")
		)
		(fp_line
			(start -0.120396 0.3048)
			(end -0.120396 0.2794)
			(stroke
				(width 0.1)
				(type default)
			)
			(layer "B.Fab")
		)
		(fp_line
			(start 0.12065 0.3048)
			(end 0.67945 0.3048)
			(stroke
				(width 0.1)
				(type default)
			)
			(layer "B.Fab")
		)
		(fp_line
			(start 0.67945 0.3048)
			(end 0.67945 -0.305054)
			(stroke
				(width 0.1)
				(type default)
			)
			(layer "B.Fab")
		)
		(fp_line
			(start -0.120396 0.2794)
			(end 0.12065 0.2794)
			(stroke
				(width 0.1)
				(type default)
			)
			(layer "B.Fab")
		)
		(fp_line
			(start 0.12065 0.2794)
			(end 0.12065 0.3048)
			(stroke
				(width 0.1)
				(type default)
			)
			(layer "B.Fab")
		)
		(fp_line
			(start -0.12065 -0.2794)
			(end -0.12065 -0.3048)
			(stroke
				(width 0.1)
				(type default)
			)
			(layer "B.Fab")
		)
		(fp_line
			(start 0.12065 -0.2794)
			(end -0.12065 -0.2794)
			(stroke
				(width 0.1)
				(type default)
			)
			(layer "B.Fab")
		)
		(fp_line
			(start -0.67945 -0.3048)
			(end -0.67945 0.3048)
			(stroke
				(width 0.1)
				(type default)
			)
			(layer "B.Fab")
		)
		(fp_line
			(start -0.12065 -0.3048)
			(end -0.67945 -0.3048)
			(stroke
				(width 0.1)
				(type default)
			)
			(layer "B.Fab")
		)
		(fp_line
			(start 0.12065 -0.305054)
			(end 0.12065 -0.2794)
			(stroke
				(width 0.1)
				(type default)
			)
			(layer "B.Fab")
		)
		(fp_line
			(start 0.67945 -0.305054)
			(end 0.12065 -0.305054)
			(stroke
				(width 0.1)
				(type default)
			)
			(layer "B.Fab")
		)
		(pad "1" smd circle
			(at 0.40005 0 90)
			(size 0 0)
			(layers "B.Cu" "B.Mask" "B.Paste")
			(net "P3V3")
		)
		(pad "2" smd circle
			(at -0.40005 0 90)
			(size 0 0)
			(layers "B.Cu" "B.Mask" "B.Paste")
			(net "PU_U5_EN")
		)
	)
	(footprint ""
		(layer "B.Cu")
		(at 331.20584 -326.311006 -90)
		(property "Reference" "PC105_1"
			(at 0 0 90)
			(layer "B.SilkS")
			(hide yes)
			(effects
				(font
					(size 1.27 1.27)
				)
				(justify mirror)
			)
		)
		(property "Value" ""
			(at 0 0 90)
			(layer "B.Fab")
			(effects
				(font
					(size 1.27 1.27)
				)
				(justify mirror)
			)
		)
		(duplicate_pad_numbers_are_jumpers no)
		(fp_line
			(start -1.524 0.762)
			(end 1.524 0.762)
			(stroke
				(width 0.1524)
				(type default)
			)
			(layer "B.SilkS")
		)
		(fp_line
			(start 1.524 0.762)
			(end 1.524 -0.762)
			(stroke
				(width 0.1524)
				(type default)
			)
			(layer "B.SilkS")
		)
		(fp_line
			(start -1.524 -0.762)
			(end -1.524 0.762)
			(stroke
				(width 0.1524)
				(type default)
			)
			(layer "B.SilkS")
		)
		(fp_line
			(start 1.524 -0.762)
			(end -1.524 -0.762)
			(stroke
				(width 0.1524)
				(type default)
			)
			(layer "B.SilkS")
		)
		(fp_line
			(start -1.1049 0.724916)
			(end -1.1049 -0.724916)
			(stroke
				(width 0.1)
				(type default)
			)
			(layer "B.Fab")
		)
		(fp_line
			(start 1.1049 0.724916)
			(end -1.1049 0.724916)
			(stroke
				(width 0.1)
				(type default)
			)
			(layer "B.Fab")
		)
		(fp_line
			(start -1.1049 -0.724916)
			(end 1.1049 -0.724916)
			(stroke
				(width 0.1)
				(type default)
			)
			(layer "B.Fab")
		)
		(fp_line
			(start 1.1049 -0.724916)
			(end 1.1049 0.724916)
			(stroke
				(width 0.1)
				(type default)
			)
			(layer "B.Fab")
		)
		(pad "1" smd rect
			(at 0.889 0 270)
			(size 1.016 1.27)
			(layers "B.Cu" "B.Mask" "B.Paste")
			(net "PVDDCR_CPU1_P0")
		)
		(pad "2" smd rect
			(at -0.889 0 270)
			(size 1.016 1.27)
			(layers "B.Cu" "B.Mask" "B.Paste")
			(net "GND")
		)
	)
	(footprint ""
		(layer "B.Cu")
		(at 350.818958 -249.36831 180)
		(property "Reference" "C1922"
			(at 0 0 0)
			(layer "B.SilkS")
			(hide yes)
			(effects
				(font
					(size 1.27 1.27)
				)
				(justify mirror)
			)
		)
		(property "Value" ""
			(at 0 0 0)
			(layer "B.Fab")
			(effects
				(font
					(size 1.27 1.27)
				)
				(justify mirror)
			)
		)
		(duplicate_pad_numbers_are_jumpers no)
		(fp_line
			(start 0.7874 0.4064)
			(end 0.7874 -0.4064)
			(stroke
				(width 0.1524)
				(type default)
			)
			(layer "B.SilkS")
		)
		(fp_line
			(start 0.7874 -0.4064)
			(end -0.7874 -0.4064)
			(stroke
				(width 0.1524)
				(type default)
			)
			(layer "B.SilkS")
		)
		(fp_line
			(start -0.7874 0.4064)
			(end 0.7874 0.4064)
			(stroke
				(width 0.1524)
				(type default)
			)
			(layer "B.SilkS")
		)
		(fp_line
			(start -0.7874 -0.4064)
			(end -0.7874 0.4064)
			(stroke
				(width 0.1524)
				(type default)
			)
			(layer "B.SilkS")
		)
		(fp_line
			(start 0.67945 0.3048)
			(end 0.67945 -0.305054)
			(stroke
				(width 0.1)
				(type default)
			)
			(layer "B.Fab")
		)
		(fp_line
			(start 0.67945 -0.305054)
			(end 0.12065 -0.305054)
			(stroke
				(width 0.1)
				(type default)
			)
			(layer "B.Fab")
		)
		(fp_line
			(start 0.12065 0.3048)
			(end 0.67945 0.3048)
			(stroke
				(width 0.1)
				(type default)
			)
			(layer "B.Fab")
		)
		(fp_line
			(start 0.12065 0.2794)
			(end 0.12065 0.3048)
			(stroke
				(width 0.1)
				(type default)
			)
			(layer "B.Fab")
		)
		(fp_line
			(start 0.12065 -0.2794)
			(end -0.12065 -0.2794)
			(stroke
				(width 0.1)
				(type default)
			)
			(layer "B.Fab")
		)
		(fp_line
			(start 0.12065 -0.305054)
			(end 0.12065 -0.2794)
			(stroke
				(width 0.1)
				(type default)
			)
			(layer "B.Fab")
		)
		(fp_line
			(start -0.120396 0.3048)
			(end -0.120396 0.2794)
			(stroke
				(width 0.1)
				(type default)
			)
			(layer "B.Fab")
		)
		(fp_line
			(start -0.120396 0.2794)
			(end 0.12065 0.2794)
			(stroke
				(width 0.1)
				(type default)
			)
			(layer "B.Fab")
		)
		(fp_line
			(start -0.12065 -0.2794)
			(end -0.12065 -0.3048)
			(stroke
				(width 0.1)
				(type default)
			)
			(layer "B.Fab")
		)
		(fp_line
			(start -0.12065 -0.3048)
			(end -0.67945 -0.3048)
			(stroke
				(width 0.1)
				(type default)
			)
			(layer "B.Fab")
		)
		(fp_line
			(start -0.67945 0.3048)
			(end -0.120396 0.3048)
			(stroke
				(width 0.1)
				(type default)
			)
			(layer "B.Fab")
		)
		(fp_line
			(start -0.67945 -0.3048)
			(end -0.67945 0.3048)
			(stroke
				(width 0.1)
				(type default)
			)
			(layer "B.Fab")
		)
		(pad "1" smd circle
			(at 0.40005 0)
			(size 0 0)
			(layers "B.Cu" "B.Mask" "B.Paste")
			(net "PVDDCR_CPU0_P0")
		)
		(pad "2" smd circle
			(at -0.40005 0)
			(size 0 0)
			(layers "B.Cu" "B.Mask" "B.Paste")
			(net "GND")
		)
	)
	(footprint ""
		(layer "B.Cu")
		(at 122.878596 -386.766562 90)
		(property "Reference" "C443"
			(at 0 0 90)
			(layer "B.SilkS")
			(hide yes)
			(effects
				(font
					(size 1.27 1.27)
				)
				(justify mirror)
			)
		)
		(property "Value" ""
			(at 0 0 90)
			(layer "B.Fab")
			(effects
				(font
					(size 1.27 1.27)
				)
				(justify mirror)
			)
		)
		(duplicate_pad_numbers_are_jumpers no)
		(fp_line
			(start 0.299974 -0.150114)
			(end -0.299974 -0.150114)
			(stroke
				(width 0.1)
				(type default)
			)
			(layer "B.Fab")
		)
		(fp_line
			(start -0.299974 -0.150114)
			(end -0.299974 0.150114)
			(stroke
				(width 0.1)
				(type default)
			)
			(layer "B.Fab")
		)
		(fp_line
			(start 0.299974 0.150114)
			(end 0.299974 -0.150114)
			(stroke
				(width 0.1)
				(type default)
			)
			(layer "B.Fab")
		)
		(fp_line
			(start -0.299974 0.150114)
			(end 0.299974 0.150114)
			(stroke
				(width 0.1)
				(type default)
			)
			(layer "B.Fab")
		)
		(pad "1" smd rect
			(at 0.2667 0 270)
			(size 0.3048 0.381)
			(layers "B.Cu" "B.Mask" "B.Paste")
			(net "P1V8_CPU1_RT3_1A")
		)
		(pad "2" smd rect
			(at -0.2667 0 270)
			(size 0.3048 0.381)
			(layers "B.Cu" "B.Mask" "B.Paste")
			(net "GND")
		)
	)
	(footprint ""
		(layer "B.Cu")
		(at 182.332376 -115.022376 180)
		(property "Reference" "C355"
			(at 0 0 0)
			(layer "B.SilkS")
			(hide yes)
			(effects
				(font
					(size 1.27 1.27)
				)
				(justify mirror)
			)
		)
		(property "Value" ""
			(at 0 0 0)
			(layer "B.Fab")
			(effects
				(font
					(size 1.27 1.27)
				)
				(justify mirror)
			)
		)
		(duplicate_pad_numbers_are_jumpers no)
		(fp_line
			(start 0.69215 0.2921)
			(end 0.69215 -0.2921)
			(stroke
				(width 0.1524)
				(type default)
			)
			(layer "B.SilkS")
		)
		(fp_line
			(start 0.69215 -0.2921)
			(end -0.69215 -0.2921)
			(stroke
				(width 0.1524)
				(type default)
			)
			(layer "B.SilkS")
		)
		(fp_line
			(start -0.69215 0.2921)
			(end 0.69215 0.2921)
			(stroke
				(width 0.1524)
				(type default)
			)
			(layer "B.SilkS")
		)
		(fp_line
			(start -0.69215 -0.2921)
			(end -0.69215 0.2921)
			(stroke
				(width 0.1524)
				(type default)
			)
			(layer "B.SilkS")
		)
		(fp_line
			(start 0.51435 0.2794)
			(end 0.51435 -0.2794)
			(stroke
				(width 0.1)
				(type default)
			)
			(layer "B.Fab")
		)
		(fp_line
			(start 0.51435 -0.2794)
			(end -0.51435 -0.2794)
			(stroke
				(width 0.1)
				(type default)
			)
			(layer "B.Fab")
		)
		(fp_line
			(start -0.51435 0.2794)
			(end 0.51435 0.2794)
			(stroke
				(width 0.1)
				(type default)
			)
			(layer "B.Fab")
		)
		(fp_line
			(start -0.51435 -0.2794)
			(end -0.51435 0.2794)
			(stroke
				(width 0.1)
				(type default)
			)
			(layer "B.Fab")
		)
		(pad "1" smd circle
			(at 0.40005 0)
			(size 0 0)
			(layers "B.Cu" "B.Mask" "B.Paste")
			(net "P3V3_AUX")
		)
		(pad "2" smd circle
			(at -0.40005 0)
			(size 0 0)
			(layers "B.Cu" "B.Mask" "B.Paste")
			(net "GND")
		)
		(zone
			(layer "B.Cu")
			(hatch none 0.5)
			(connect_pads
				(clearance 0)
			)
			(min_thickness 0.25)
			(keepout
				(tracks not_allowed)
				(vias allowed)
				(pads allowed)
				(copperpour not_allowed)
				(footprints allowed)
			)
			(placement
				(enabled no)
				(sheetname "")
			)
			(fill
				(thermal_gap 0.5)
				(thermal_bridge_width 0.5)
				(island_removal_mode 0)
			)
			(polygon
				(pts
					(xy 182.141876 -114.934492) (xy 182.141876 -115.110006) (xy 182.233316 -115.168172) (xy 182.432706 -115.168172)
					(xy 182.522876 -115.110006) (xy 182.522876 -114.934746) (xy 182.432706 -114.876326) (xy 182.233316 -114.876326)
				)
			)
		)
	)
	(footprint ""
		(layer "B.Cu")
		(at 419.684454 -191.32931 180)
		(property "Reference" "R298"
			(at 0 0 0)
			(layer "B.SilkS")
			(hide yes)
			(effects
				(font
					(size 1.27 1.27)
				)
				(justify mirror)
			)
		)
		(property "Value" ""
			(at 0 0 0)
			(layer "B.Fab")
			(effects
				(font
					(size 1.27 1.27)
				)
				(justify mirror)
			)
		)
		(duplicate_pad_numbers_are_jumpers no)
		(fp_line
			(start 0.7874 0.4064)
			(end 0.7874 -0.4064)
			(stroke
				(width 0.1524)
				(type default)
			)
			(layer "B.SilkS")
		)
		(fp_line
			(start 0.7874 -0.4064)
			(end -0.7874 -0.4064)
			(stroke
				(width 0.1524)
				(type default)
			)
			(layer "B.SilkS")
		)
		(fp_line
			(start -0.7874 0.4064)
			(end 0.7874 0.4064)
			(stroke
				(width 0.1524)
				(type default)
			)
			(layer "B.SilkS")
		)
		(fp_line
			(start -0.7874 -0.4064)
			(end -0.7874 0.4064)
			(stroke
				(width 0.1524)
				(type default)
			)
			(layer "B.SilkS")
		)
		(fp_line
			(start 0.67945 0.3048)
			(end 0.67945 -0.305054)
			(stroke
				(width 0.1)
				(type default)
			)
			(layer "B.Fab")
		)
		(fp_line
			(start 0.67945 -0.305054)
			(end 0.12065 -0.305054)
			(stroke
				(width 0.1)
				(type default)
			)
			(layer "B.Fab")
		)
		(fp_line
			(start 0.12065 0.3048)
			(end 0.67945 0.3048)
			(stroke
				(width 0.1)
				(type default)
			)
			(layer "B.Fab")
		)
		(fp_line
			(start 0.12065 0.2794)
			(end 0.12065 0.3048)
			(stroke
				(width 0.1)
				(type default)
			)
			(layer "B.Fab")
		)
		(fp_line
			(start 0.12065 -0.2794)
			(end -0.12065 -0.2794)
			(stroke
				(width 0.1)
				(type default)
			)
			(layer "B.Fab")
		)
		(fp_line
			(start 0.12065 -0.305054)
			(end 0.12065 -0.2794)
			(stroke
				(width 0.1)
				(type default)
			)
			(layer "B.Fab")
		)
		(fp_line
			(start -0.120396 0.3048)
			(end -0.120396 0.2794)
			(stroke
				(width 0.1)
				(type default)
			)
			(layer "B.Fab")
		)
		(fp_line
			(start -0.120396 0.2794)
			(end 0.12065 0.2794)
			(stroke
				(width 0.1)
				(type default)
			)
			(layer "B.Fab")
		)
		(fp_line
			(start -0.12065 -0.2794)
			(end -0.12065 -0.3048)
			(stroke
				(width 0.1)
				(type default)
			)
			(layer "B.Fab")
		)
		(fp_line
			(start -0.12065 -0.3048)
			(end -0.67945 -0.3048)
			(stroke
				(width 0.1)
				(type default)
			)
			(layer "B.Fab")
		)
		(fp_line
			(start -0.67945 0.3048)
			(end -0.120396 0.3048)
			(stroke
				(width 0.1)
				(type default)
			)
			(layer "B.Fab")
		)
		(fp_line
			(start -0.67945 -0.3048)
			(end -0.67945 0.3048)
			(stroke
				(width 0.1)
				(type default)
			)
			(layer "B.Fab")
		)
		(pad "1" smd circle
			(at 0.40005 0)
			(size 0 0)
			(layers "B.Cu" "B.Mask" "B.Paste")
			(net "PWRGD_CHH_CPU0_DIMM")
		)
		(pad "2" smd circle
			(at -0.40005 0)
			(size 0 0)
			(layers "B.Cu" "B.Mask" "B.Paste")
			(net "PWRGD_CHGL_CPU0")
		)
	)
	(footprint ""
		(layer "B.Cu")
		(at 285.23311 -416.255962 -90)
		(property "Reference" "C81"
			(at 0 0 90)
			(layer "B.SilkS")
			(hide yes)
			(effects
				(font
					(size 1.27 1.27)
				)
				(justify mirror)
			)
		)
		(property "Value" ""
			(at 0 0 90)
			(layer "B.Fab")
			(effects
				(font
					(size 1.27 1.27)
				)
				(justify mirror)
			)
		)
		(duplicate_pad_numbers_are_jumpers no)
		(fp_line
			(start -0.7874 0.4064)
			(end 0.7874 0.4064)
			(stroke
				(width 0.1524)
				(type default)
			)
			(layer "B.SilkS")
		)
		(fp_line
			(start 0.7874 0.4064)
			(end 0.7874 -0.4064)
			(stroke
				(width 0.1524)
				(type default)
			)
			(layer "B.SilkS")
		)
		(fp_line
			(start -0.7874 -0.4064)
			(end -0.7874 0.4064)
			(stroke
				(width 0.1524)
				(type default)
			)
			(layer "B.SilkS")
		)
		(fp_line
			(start 0.7874 -0.4064)
			(end -0.7874 -0.4064)
			(stroke
				(width 0.1524)
				(type default)
			)
			(layer "B.SilkS")
		)
		(fp_line
			(start -0.67945 0.3048)
			(end -0.120396 0.3048)
			(stroke
				(width 0.1)
				(type default)
			)
			(layer "B.Fab")
		)
		(fp_line
			(start -0.120396 0.3048)
			(end -0.120396 0.2794)
			(stroke
				(width 0.1)
				(type default)
			)
			(layer "B.Fab")
		)
		(fp_line
			(start 0.12065 0.3048)
			(end 0.67945 0.3048)
			(stroke
				(width 0.1)
				(type default)
			)
			(layer "B.Fab")
		)
		(fp_line
			(start 0.67945 0.3048)
			(end 0.67945 -0.305054)
			(stroke
				(width 0.1)
				(type default)
			)
			(layer "B.Fab")
		)
		(fp_line
			(start -0.120396 0.2794)
			(end 0.12065 0.2794)
			(stroke
				(width 0.1)
				(type default)
			)
			(layer "B.Fab")
		)
		(fp_line
			(start 0.12065 0.2794)
			(end 0.12065 0.3048)
			(stroke
				(width 0.1)
				(type default)
			)
			(layer "B.Fab")
		)
		(fp_line
			(start -0.12065 -0.2794)
			(end -0.12065 -0.3048)
			(stroke
				(width 0.1)
				(type default)
			)
			(layer "B.Fab")
		)
		(fp_line
			(start 0.12065 -0.2794)
			(end -0.12065 -0.2794)
			(stroke
				(width 0.1)
				(type default)
			)
			(layer "B.Fab")
		)
		(fp_line
			(start -0.67945 -0.3048)
			(end -0.67945 0.3048)
			(stroke
				(width 0.1)
				(type default)
			)
			(layer "B.Fab")
		)
		(fp_line
			(start -0.12065 -0.3048)
			(end -0.67945 -0.3048)
			(stroke
				(width 0.1)
				(type default)
			)
			(layer "B.Fab")
		)
		(fp_line
			(start 0.12065 -0.305054)
			(end 0.12065 -0.2794)
			(stroke
				(width 0.1)
				(type default)
			)
			(layer "B.Fab")
		)
		(fp_line
			(start 0.67945 -0.305054)
			(end 0.12065 -0.305054)
			(stroke
				(width 0.1)
				(type default)
			)
			(layer "B.Fab")
		)
		(pad "1" smd circle
			(at 0.40005 0 90)
			(size 0 0)
			(layers "B.Cu" "B.Mask" "B.Paste")
			(net "P3V3_9ZXL045_P0_VDD")
		)
		(pad "2" smd circle
			(at -0.40005 0 90)
			(size 0 0)
			(layers "B.Cu" "B.Mask" "B.Paste")
			(net "GND")
		)
	)
	(footprint ""
		(layer "B.Cu")
		(at 364.407958 -245.487952)
		(property "Reference" "C267"
			(at 0 0 0)
			(layer "B.SilkS")
			(hide yes)
			(effects
				(font
					(size 1.27 1.27)
				)
				(justify mirror)
			)
		)
		(property "Value" ""
			(at 0 0 0)
			(layer "B.Fab")
			(effects
				(font
					(size 1.27 1.27)
				)
				(justify mirror)
			)
		)
		(duplicate_pad_numbers_are_jumpers no)
		(fp_line
			(start -0.7874 -0.4064)
			(end -0.7874 0.4064)
			(stroke
				(width 0.1524)
				(type default)
			)
			(layer "B.SilkS")
		)
		(fp_line
			(start -0.7874 0.4064)
			(end 0.7874 0.4064)
			(stroke
				(width 0.1524)
				(type default)
			)
			(layer "B.SilkS")
		)
		(fp_line
			(start 0.7874 -0.4064)
			(end -0.7874 -0.4064)
			(stroke
				(width 0.1524)
				(type default)
			)
			(layer "B.SilkS")
		)
		(fp_line
			(start 0.7874 0.4064)
			(end 0.7874 -0.4064)
			(stroke
				(width 0.1524)
				(type default)
			)
			(layer "B.SilkS")
		)
		(fp_line
			(start -0.67945 -0.3048)
			(end -0.67945 0.3048)
			(stroke
				(width 0.1)
				(type default)
			)
			(layer "B.Fab")
		)
		(fp_line
			(start -0.67945 0.3048)
			(end -0.120396 0.3048)
			(stroke
				(width 0.1)
				(type default)
			)
			(layer "B.Fab")
		)
		(fp_line
			(start -0.12065 -0.3048)
			(end -0.67945 -0.3048)
			(stroke
				(width 0.1)
				(type default)
			)
			(layer "B.Fab")
		)
		(fp_line
			(start -0.12065 -0.2794)
			(end -0.12065 -0.3048)
			(stroke
				(width 0.1)
				(type default)
			)
			(layer "B.Fab")
		)
		(fp_line
			(start -0.120396 0.2794)
			(end 0.12065 0.2794)
			(stroke
				(width 0.1)
				(type default)
			)
			(layer "B.Fab")
		)
		(fp_line
			(start -0.120396 0.3048)
			(end -0.120396 0.2794)
			(stroke
				(width 0.1)
				(type default)
			)
			(layer "B.Fab")
		)
		(fp_line
			(start 0.12065 -0.305054)
			(end 0.12065 -0.2794)
			(stroke
				(width 0.1)
				(type default)
			)
			(layer "B.Fab")
		)
		(fp_line
			(start 0.12065 -0.2794)
			(end -0.12065 -0.2794)
			(stroke
				(width 0.1)
				(type default)
			)
			(layer "B.Fab")
		)
		(fp_line
			(start 0.12065 0.2794)
			(end 0.12065 0.3048)
			(stroke
				(width 0.1)
				(type default)
			)
			(layer "B.Fab")
		)
		(fp_line
			(start 0.12065 0.3048)
			(end 0.67945 0.3048)
			(stroke
				(width 0.1)
				(type default)
			)
			(layer "B.Fab")
		)
		(fp_line
			(start 0.67945 -0.305054)
			(end 0.12065 -0.305054)
			(stroke
				(width 0.1)
				(type default)
			)
			(layer "B.Fab")
		)
		(fp_line
			(start 0.67945 0.3048)
			(end 0.67945 -0.305054)
			(stroke
				(width 0.1)
				(type default)
			)
			(layer "B.Fab")
		)
		(pad "1" smd circle
			(at 0.40005 0 180)
			(size 0 0)
			(layers "B.Cu" "B.Mask" "B.Paste")
			(net "PVDDCR_CPU0_P0")
		)
		(pad "2" smd circle
			(at -0.40005 0 180)
			(size 0 0)
			(layers "B.Cu" "B.Mask" "B.Paste")
			(net "GND")
		)
	)
	(footprint ""
		(layer "B.Cu")
		(at 64.889126 -20.04822)
		(property "Reference" "PC2141"
			(at 0 0 0)
			(layer "B.SilkS")
			(hide yes)
			(effects
				(font
					(size 1.27 1.27)
				)
				(justify mirror)
			)
		)
		(property "Value" ""
			(at 0 0 0)
			(layer "B.Fab")
			(effects
				(font
					(size 1.27 1.27)
				)
				(justify mirror)
			)
		)
		(duplicate_pad_numbers_are_jumpers no)
		(fp_line
			(start -1.524 -0.762)
			(end -1.524 0.762)
			(stroke
				(width 0.1524)
				(type default)
			)
			(layer "B.SilkS")
		)
		(fp_line
			(start -1.524 0.762)
			(end 1.524 0.762)
			(stroke
				(width 0.1524)
				(type default)
			)
			(layer "B.SilkS")
		)
		(fp_line
			(start 1.524 -0.762)
			(end -1.524 -0.762)
			(stroke
				(width 0.1524)
				(type default)
			)
			(layer "B.SilkS")
		)
		(fp_line
			(start 1.524 0.762)
			(end 1.524 -0.762)
			(stroke
				(width 0.1524)
				(type default)
			)
			(layer "B.SilkS")
		)
		(fp_line
			(start -1.1049 -0.724916)
			(end 1.1049 -0.724916)
			(stroke
				(width 0.1)
				(type default)
			)
			(layer "B.Fab")
		)
		(fp_line
			(start -1.1049 0.724916)
			(end -1.1049 -0.724916)
			(stroke
				(width 0.1)
				(type default)
			)
			(layer "B.Fab")
		)
		(fp_line
			(start 1.1049 -0.724916)
			(end 1.1049 0.724916)
			(stroke
				(width 0.1)
				(type default)
			)
			(layer "B.Fab")
		)
		(fp_line
			(start 1.1049 0.724916)
			(end -1.1049 0.724916)
			(stroke
				(width 0.1)
				(type default)
			)
			(layer "B.Fab")
		)
		(pad "1" smd rect
			(at 0.889 0)
			(size 1.016 1.27)
			(layers "B.Cu" "B.Mask" "B.Paste")
			(net "P12V_OCP_V3_2")
		)
		(pad "2" smd rect
			(at -0.889 0)
			(size 1.016 1.27)
			(layers "B.Cu" "B.Mask" "B.Paste")
			(net "GND")
		)
	)
	(footprint ""
		(layer "B.Cu")
		(at 346.688664 -73.534778)
		(property "Reference" "Q86"
			(at 1.4224 -1.768348 0)
			(unlocked yes)
			(layer "B.SilkS")
			(effects
				(font
					(size 0.7874 0.5842)
					(thickness 0.1524)
				)
				(justify left mirror)
			)
		)
		(property "Value" ""
			(at 0 0 0)
			(layer "B.Fab")
			(effects
				(font
					(size 1.27 1.27)
				)
				(justify mirror)
			)
		)
		(duplicate_pad_numbers_are_jumpers no)
		(fp_line
			(start -1.332738 -1.100074)
			(end -1.332738 1.100074)
			(stroke
				(width 0.1524)
				(type default)
			)
			(layer "B.SilkS")
		)
		(fp_line
			(start -1.332738 1.100074)
			(end 1.332738 1.100074)
			(stroke
				(width 0.1524)
				(type default)
			)
			(layer "B.SilkS")
		)
		(fp_line
			(start -0.4826 -1.100074)
			(end -1.332738 -1.100074)
			(stroke
				(width 0.1524)
				(type default)
			)
			(layer "B.SilkS")
		)
		(fp_line
			(start 0 -0.541274)
			(end -0.4826 -1.100074)
			(stroke
				(width 0.1524)
				(type default)
			)
			(layer "B.SilkS")
		)
		(fp_line
			(start 0.4826 -1.100074)
			(end 0 -0.541274)
			(stroke
				(width 0.1524)
				(type default)
			)
			(layer "B.SilkS")
		)
		(fp_line
			(start 1.332738 -1.100074)
			(end 0.4826 -1.100074)
			(stroke
				(width 0.1524)
				(type default)
			)
			(layer "B.SilkS")
		)
		(fp_line
			(start 1.332738 1.100074)
			(end 1.332738 -1.100074)
			(stroke
				(width 0.1524)
				(type default)
			)
			(layer "B.SilkS")
		)
		(fp_poly
			(pts
				(xy 1.422654 -0.649986) (xy 2.12471 -1.001014) (xy 2.12471 -0.298958)
			)
			(stroke
				(width 0)
				(type default)
			)
			(fill yes)
			(layer "B.SilkS")
		)
		(fp_line
			(start -0.674878 -1.100074)
			(end -0.674878 1.100074)
			(stroke
				(width 0.1)
				(type default)
			)
			(layer "B.Fab")
		)
		(fp_line
			(start -0.674878 1.100074)
			(end 0.674878 1.100074)
			(stroke
				(width 0.1)
				(type default)
			)
			(layer "B.Fab")
		)
		(fp_line
			(start 0.674878 -1.100074)
			(end -0.674878 -1.100074)
			(stroke
				(width 0.1)
				(type default)
			)
			(layer "B.Fab")
		)
		(fp_line
			(start 0.674878 1.100074)
			(end 0.674878 -1.100074)
			(stroke
				(width 0.1)
				(type default)
			)
			(layer "B.Fab")
		)
		(fp_poly
			(pts
				(xy 2.2352 -0.298958) (xy 2.2352 -1.001014) (xy 1.533144 -0.649986)
			)
			(stroke
				(width 0)
				(type default)
			)
			(fill yes)
			(layer "B.Fab")
		)
		(pad "1" smd rect
			(at 0.94996 -0.649986 90)
			(size 0.4318 0.508)
			(layers "B.Cu" "B.Mask" "B.Paste")
			(net "GND")
		)
		(pad "2" smd rect
			(at 0.94996 0 90)
			(size 0.4318 0.508)
			(layers "B.Cu" "B.Mask" "B.Paste")
			(net "FM_LED_PWRGD_PVDD11_S3_P1")
		)
		(pad "3" smd rect
			(at 0.94996 0.649986 90)
			(size 0.4318 0.508)
			(layers "B.Cu" "B.Mask" "B.Paste")
			(net "LED_PWRGD_PVDD18_S5_P1_D")
		)
		(pad "4" smd rect
			(at -0.94996 0.649986 90)
			(size 0.4318 0.508)
			(layers "B.Cu" "B.Mask" "B.Paste")
			(net "GND")
		)
		(pad "5" smd rect
			(at -0.94996 0 90)
			(size 0.4318 0.508)
			(layers "B.Cu" "B.Mask" "B.Paste")
			(net "FM_LED_PWRGD_PVDD18_S5_P1")
		)
		(pad "6" smd rect
			(at -0.94996 -0.649986 90)
			(size 0.4318 0.508)
			(layers "B.Cu" "B.Mask" "B.Paste")
			(net "LED_PWRGD_PVDD11_S3_P1_D")
		)
	)
	(footprint ""
		(layer "B.Cu")
		(at 237.910624 -326.683624)
		(property "Reference" "R1235"
			(at 0 0 0)
			(layer "B.SilkS")
			(hide yes)
			(effects
				(font
					(size 1.27 1.27)
				)
				(justify mirror)
			)
		)
		(property "Value" ""
			(at 0 0 0)
			(layer "B.Fab")
			(effects
				(font
					(size 1.27 1.27)
				)
				(justify mirror)
			)
		)
		(duplicate_pad_numbers_are_jumpers no)
		(fp_line
			(start -0.7874 -0.4064)
			(end -0.7874 0.4064)
			(stroke
				(width 0.1524)
				(type default)
			)
			(layer "B.SilkS")
		)
		(fp_line
			(start -0.7874 0.4064)
			(end 0.7874 0.4064)
			(stroke
				(width 0.1524)
				(type default)
			)
			(layer "B.SilkS")
		)
		(fp_line
			(start 0.7874 -0.4064)
			(end -0.7874 -0.4064)
			(stroke
				(width 0.1524)
				(type default)
			)
			(layer "B.SilkS")
		)
		(fp_line
			(start 0.7874 0.4064)
			(end 0.7874 -0.4064)
			(stroke
				(width 0.1524)
				(type default)
			)
			(layer "B.SilkS")
		)
		(fp_line
			(start -0.67945 -0.3048)
			(end -0.67945 0.3048)
			(stroke
				(width 0.1)
				(type default)
			)
			(layer "B.Fab")
		)
		(fp_line
			(start -0.67945 0.3048)
			(end -0.120396 0.3048)
			(stroke
				(width 0.1)
				(type default)
			)
			(layer "B.Fab")
		)
		(fp_line
			(start -0.12065 -0.3048)
			(end -0.67945 -0.3048)
			(stroke
				(width 0.1)
				(type default)
			)
			(layer "B.Fab")
		)
		(fp_line
			(start -0.12065 -0.2794)
			(end -0.12065 -0.3048)
			(stroke
				(width 0.1)
				(type default)
			)
			(layer "B.Fab")
		)
		(fp_line
			(start -0.120396 0.2794)
			(end 0.12065 0.2794)
			(stroke
				(width 0.1)
				(type default)
			)
			(layer "B.Fab")
		)
		(fp_line
			(start -0.120396 0.3048)
			(end -0.120396 0.2794)
			(stroke
				(width 0.1)
				(type default)
			)
			(layer "B.Fab")
		)
		(fp_line
			(start 0.12065 -0.305054)
			(end 0.12065 -0.2794)
			(stroke
				(width 0.1)
				(type default)
			)
			(layer "B.Fab")
		)
		(fp_line
			(start 0.12065 -0.2794)
			(end -0.12065 -0.2794)
			(stroke
				(width 0.1)
				(type default)
			)
			(layer "B.Fab")
		)
		(fp_line
			(start 0.12065 0.2794)
			(end 0.12065 0.3048)
			(stroke
				(width 0.1)
				(type default)
			)
			(layer "B.Fab")
		)
		(fp_line
			(start 0.12065 0.3048)
			(end 0.67945 0.3048)
			(stroke
				(width 0.1)
				(type default)
			)
			(layer "B.Fab")
		)
		(fp_line
			(start 0.67945 -0.305054)
			(end 0.12065 -0.305054)
			(stroke
				(width 0.1)
				(type default)
			)
			(layer "B.Fab")
		)
		(fp_line
			(start 0.67945 0.3048)
			(end 0.67945 -0.305054)
			(stroke
				(width 0.1)
				(type default)
			)
			(layer "B.Fab")
		)
		(pad "1" smd circle
			(at 0.40005 0 180)
			(size 0 0)
			(layers "B.Cu" "B.Mask" "B.Paste")
			(net "PVDD_33_S5")
		)
		(pad "2" smd circle
			(at -0.40005 0 180)
			(size 0 0)
			(layers "B.Cu" "B.Mask" "B.Paste")
			(net "PVDD_33_S5_ADC")
		)
	)
	(footprint ""
		(layer "B.Cu")
		(at 314.85459 -76.889864 180)
		(property "Reference" "Q144"
			(at -1.40462 1.9939 0)
			(unlocked yes)
			(layer "B.SilkS")
			(effects
				(font
					(size 0.7874 0.5842)
					(thickness 0.1524)
				)
				(justify left mirror)
			)
		)
		(property "Value" ""
			(at 0 0 0)
			(layer "B.Fab")
			(effects
				(font
					(size 1.27 1.27)
				)
				(justify mirror)
			)
		)
		(duplicate_pad_numbers_are_jumpers no)
		(fp_line
			(start 1.332738 1.100074)
			(end 1.332738 -1.100074)
			(stroke
				(width 0.1524)
				(type default)
			)
			(layer "B.SilkS")
		)
		(fp_line
			(start 1.332738 -1.100074)
			(end 0.4826 -1.100074)
			(stroke
				(width 0.1524)
				(type default)
			)
			(layer "B.SilkS")
		)
		(fp_line
			(start 0.4826 -1.100074)
			(end 0 -0.541274)
			(stroke
				(width 0.1524)
				(type default)
			)
			(layer "B.SilkS")
		)
		(fp_line
			(start 0 -0.541274)
			(end -0.4826 -1.100074)
			(stroke
				(width 0.1524)
				(type default)
			)
			(layer "B.SilkS")
		)
		(fp_line
			(start -0.4826 -1.100074)
			(end -1.332738 -1.100074)
			(stroke
				(width 0.1524)
				(type default)
			)
			(layer "B.SilkS")
		)
		(fp_line
			(start -1.332738 1.100074)
			(end 1.332738 1.100074)
			(stroke
				(width 0.1524)
				(type default)
			)
			(layer "B.SilkS")
		)
		(fp_line
			(start -1.332738 -1.100074)
			(end -1.332738 1.100074)
			(stroke
				(width 0.1524)
				(type default)
			)
			(layer "B.SilkS")
		)
		(fp_poly
			(pts
				(xy 1.941576 -0.727202) (xy 2.643632 -1.07823) (xy 2.643632 -0.376174)
			)
			(stroke
				(width 0)
				(type default)
			)
			(fill yes)
			(layer "B.SilkS")
		)
		(fp_line
			(start 0.674878 1.100074)
			(end 0.674878 -1.100074)
			(stroke
				(width 0.1)
				(type default)
			)
			(layer "B.Fab")
		)
		(fp_line
			(start 0.674878 -1.100074)
			(end -0.674878 -1.100074)
			(stroke
				(width 0.1)
				(type default)
			)
			(layer "B.Fab")
		)
		(fp_line
			(start -0.674878 1.100074)
			(end 0.674878 1.100074)
			(stroke
				(width 0.1)
				(type default)
			)
			(layer "B.Fab")
		)
		(fp_line
			(start -0.674878 -1.100074)
			(end -0.674878 1.100074)
			(stroke
				(width 0.1)
				(type default)
			)
			(layer "B.Fab")
		)
		(fp_poly
			(pts
				(xy 2.2352 -0.298958) (xy 2.2352 -1.001014) (xy 1.533144 -0.649986)
			)
			(stroke
				(width 0)
				(type default)
			)
			(fill yes)
			(layer "B.Fab")
		)
		(pad "1" smd rect
			(at 0.94996 -0.649986 270)
			(size 0.4318 0.508)
			(layers "B.Cu" "B.Mask" "B.Paste")
			(net "GND")
		)
		(pad "2" smd rect
			(at 0.94996 0 270)
			(size 0.4318 0.508)
			(layers "B.Cu" "B.Mask" "B.Paste")
			(net "PWRGD_PS_PWROK_PLD")
		)
		(pad "3" smd rect
			(at 0.94996 0.649986 270)
			(size 0.4318 0.508)
			(layers "B.Cu" "B.Mask" "B.Paste")
			(net "PWRGD_PS_PWROK_PLD_ISO")
		)
		(pad "4" smd rect
			(at -0.94996 0.649986 270)
			(size 0.4318 0.508)
			(layers "B.Cu" "B.Mask" "B.Paste")
			(net "GND")
		)
		(pad "5" smd rect
			(at -0.94996 0 270)
			(size 0.4318 0.508)
			(layers "B.Cu" "B.Mask" "B.Paste")
			(net "PWRGD_PS_PWROK_PLD_N")
		)
		(pad "6" smd rect
			(at -0.94996 -0.649986 270)
			(size 0.4318 0.508)
			(layers "B.Cu" "B.Mask" "B.Paste")
			(net "PWRGD_PS_PWROK_PLD_N")
		)
	)
	(footprint ""
		(layer "B.Cu")
		(at 342.066118 -169.643552 90)
		(property "Reference" "PR447"
			(at 0 0 90)
			(layer "B.SilkS")
			(hide yes)
			(effects
				(font
					(size 1.27 1.27)
				)
				(justify mirror)
			)
		)
		(property "Value" ""
			(at 0 0 90)
			(layer "B.Fab")
			(effects
				(font
					(size 1.27 1.27)
				)
				(justify mirror)
			)
		)
		(duplicate_pad_numbers_are_jumpers no)
		(fp_line
			(start 0.7874 -0.4064)
			(end -0.7874 -0.4064)
			(stroke
				(width 0.1524)
				(type default)
			)
			(layer "B.SilkS")
		)
		(fp_line
			(start -0.7874 -0.4064)
			(end -0.7874 0.4064)
			(stroke
				(width 0.1524)
				(type default)
			)
			(layer "B.SilkS")
		)
		(fp_line
			(start 0.7874 0.4064)
			(end 0.7874 -0.4064)
			(stroke
				(width 0.1524)
				(type default)
			)
			(layer "B.SilkS")
		)
		(fp_line
			(start -0.7874 0.4064)
			(end 0.7874 0.4064)
			(stroke
				(width 0.1524)
				(type default)
			)
			(layer "B.SilkS")
		)
		(fp_line
			(start 0.67945 -0.305054)
			(end 0.12065 -0.305054)
			(stroke
				(width 0.1)
				(type default)
			)
			(layer "B.Fab")
		)
		(fp_line
			(start 0.12065 -0.305054)
			(end 0.12065 -0.2794)
			(stroke
				(width 0.1)
				(type default)
			)
			(layer "B.Fab")
		)
		(fp_line
			(start -0.12065 -0.3048)
			(end -0.67945 -0.3048)
			(stroke
				(width 0.1)
				(type default)
			)
			(layer "B.Fab")
		)
		(fp_line
			(start -0.67945 -0.3048)
			(end -0.67945 0.3048)
			(stroke
				(width 0.1)
				(type default)
			)
			(layer "B.Fab")
		)
		(fp_line
			(start 0.12065 -0.2794)
			(end -0.12065 -0.2794)
			(stroke
				(width 0.1)
				(type default)
			)
			(layer "B.Fab")
		)
		(fp_line
			(start -0.12065 -0.2794)
			(end -0.12065 -0.3048)
			(stroke
				(width 0.1)
				(type default)
			)
			(layer "B.Fab")
		)
		(fp_line
			(start 0.12065 0.2794)
			(end 0.12065 0.3048)
			(stroke
				(width 0.1)
				(type default)
			)
			(layer "B.Fab")
		)
		(fp_line
			(start -0.120396 0.2794)
			(end 0.12065 0.2794)
			(stroke
				(width 0.1)
				(type default)
			)
			(layer "B.Fab")
		)
		(fp_line
			(start 0.67945 0.3048)
			(end 0.67945 -0.305054)
			(stroke
				(width 0.1)
				(type default)
			)
			(layer "B.Fab")
		)
		(fp_line
			(start 0.12065 0.3048)
			(end 0.67945 0.3048)
			(stroke
				(width 0.1)
				(type default)
			)
			(layer "B.Fab")
		)
		(fp_line
			(start -0.120396 0.3048)
			(end -0.120396 0.2794)
			(stroke
				(width 0.1)
				(type default)
			)
			(layer "B.Fab")
		)
		(fp_line
			(start -0.67945 0.3048)
			(end -0.120396 0.3048)
			(stroke
				(width 0.1)
				(type default)
			)
			(layer "B.Fab")
		)
		(pad "1" smd circle
			(at 0.40005 0 270)
			(size 0 0)
			(layers "B.Cu" "B.Mask" "B.Paste")
			(net "PVDDCR_CPU0_P0")
		)
		(pad "2" smd circle
			(at -0.40005 0 270)
			(size 0 0)
			(layers "B.Cu" "B.Mask" "B.Paste")
			(net "GND")
		)
	)
	(footprint ""
		(layer "B.Cu")
		(at 356.311454 -264.35431)
		(property "Reference" "C2607"
			(at 0 0 0)
			(layer "B.SilkS")
			(hide yes)
			(effects
				(font
					(size 1.27 1.27)
				)
				(justify mirror)
			)
		)
		(property "Value" ""
			(at 0 0 0)
			(layer "B.Fab")
			(effects
				(font
					(size 1.27 1.27)
				)
				(justify mirror)
			)
		)
		(duplicate_pad_numbers_are_jumpers no)
		(fp_line
			(start -0.7874 -0.4064)
			(end -0.7874 0.4064)
			(stroke
				(width 0.1524)
				(type default)
			)
			(layer "B.SilkS")
		)
		(fp_line
			(start -0.7874 0.4064)
			(end 0.7874 0.4064)
			(stroke
				(width 0.1524)
				(type default)
			)
			(layer "B.SilkS")
		)
		(fp_line
			(start 0.7874 -0.4064)
			(end -0.7874 -0.4064)
			(stroke
				(width 0.1524)
				(type default)
			)
			(layer "B.SilkS")
		)
		(fp_line
			(start 0.7874 0.4064)
			(end 0.7874 -0.4064)
			(stroke
				(width 0.1524)
				(type default)
			)
			(layer "B.SilkS")
		)
		(fp_line
			(start -0.67945 -0.3048)
			(end -0.67945 0.3048)
			(stroke
				(width 0.1)
				(type default)
			)
			(layer "B.Fab")
		)
		(fp_line
			(start -0.67945 0.3048)
			(end -0.120396 0.3048)
			(stroke
				(width 0.1)
				(type default)
			)
			(layer "B.Fab")
		)
		(fp_line
			(start -0.12065 -0.3048)
			(end -0.67945 -0.3048)
			(stroke
				(width 0.1)
				(type default)
			)
			(layer "B.Fab")
		)
		(fp_line
			(start -0.12065 -0.2794)
			(end -0.12065 -0.3048)
			(stroke
				(width 0.1)
				(type default)
			)
			(layer "B.Fab")
		)
		(fp_line
			(start -0.120396 0.2794)
			(end 0.12065 0.2794)
			(stroke
				(width 0.1)
				(type default)
			)
			(layer "B.Fab")
		)
		(fp_line
			(start -0.120396 0.3048)
			(end -0.120396 0.2794)
			(stroke
				(width 0.1)
				(type default)
			)
			(layer "B.Fab")
		)
		(fp_line
			(start 0.12065 -0.305054)
			(end 0.12065 -0.2794)
			(stroke
				(width 0.1)
				(type default)
			)
			(layer "B.Fab")
		)
		(fp_line
			(start 0.12065 -0.2794)
			(end -0.12065 -0.2794)
			(stroke
				(width 0.1)
				(type default)
			)
			(layer "B.Fab")
		)
		(fp_line
			(start 0.12065 0.2794)
			(end 0.12065 0.3048)
			(stroke
				(width 0.1)
				(type default)
			)
			(layer "B.Fab")
		)
		(fp_line
			(start 0.12065 0.3048)
			(end 0.67945 0.3048)
			(stroke
				(width 0.1)
				(type default)
			)
			(layer "B.Fab")
		)
		(fp_line
			(start 0.67945 -0.305054)
			(end 0.12065 -0.305054)
			(stroke
				(width 0.1)
				(type default)
			)
			(layer "B.Fab")
		)
		(fp_line
			(start 0.67945 0.3048)
			(end 0.67945 -0.305054)
			(stroke
				(width 0.1)
				(type default)
			)
			(layer "B.Fab")
		)
		(pad "1" smd circle
			(at 0.40005 0 180)
			(size 0 0)
			(layers "B.Cu" "B.Mask" "B.Paste")
			(net "PVDD11_S3_P0")
		)
		(pad "2" smd circle
			(at -0.40005 0 180)
			(size 0 0)
			(layers "B.Cu" "B.Mask" "B.Paste")
			(net "GND")
		)
	)
	(footprint ""
		(layer "B.Cu")
		(at 97.996248 -182.555134 -90)
		(property "Reference" "PC296_3"
			(at 0 0 90)
			(layer "B.SilkS")
			(hide yes)
			(effects
				(font
					(size 1.27 1.27)
				)
				(justify mirror)
			)
		)
		(property "Value" ""
			(at 0 0 90)
			(layer "B.Fab")
			(effects
				(font
					(size 1.27 1.27)
				)
				(justify mirror)
			)
		)
		(duplicate_pad_numbers_are_jumpers no)
		(fp_line
			(start -1.524 0.762)
			(end 1.524 0.762)
			(stroke
				(width 0.1524)
				(type default)
			)
			(layer "B.SilkS")
		)
		(fp_line
			(start 1.524 0.762)
			(end 1.524 -0.762)
			(stroke
				(width 0.1524)
				(type default)
			)
			(layer "B.SilkS")
		)
		(fp_line
			(start -1.524 -0.762)
			(end -1.524 0.762)
			(stroke
				(width 0.1524)
				(type default)
			)
			(layer "B.SilkS")
		)
		(fp_line
			(start 1.524 -0.762)
			(end -1.524 -0.762)
			(stroke
				(width 0.1524)
				(type default)
			)
			(layer "B.SilkS")
		)
		(fp_line
			(start -1.1049 0.724916)
			(end -1.1049 -0.724916)
			(stroke
				(width 0.1)
				(type default)
			)
			(layer "B.Fab")
		)
		(fp_line
			(start 1.1049 0.724916)
			(end -1.1049 0.724916)
			(stroke
				(width 0.1)
				(type default)
			)
			(layer "B.Fab")
		)
		(fp_line
			(start -1.1049 -0.724916)
			(end 1.1049 -0.724916)
			(stroke
				(width 0.1)
				(type default)
			)
			(layer "B.Fab")
		)
		(fp_line
			(start 1.1049 -0.724916)
			(end 1.1049 0.724916)
			(stroke
				(width 0.1)
				(type default)
			)
			(layer "B.Fab")
		)
		(pad "1" smd rect
			(at 0.889 0 270)
			(size 1.016 1.27)
			(layers "B.Cu" "B.Mask" "B.Paste")
			(net "SW_P12V_AUX_PVDDCR_CPU0_P1_FLT")
		)
		(pad "2" smd rect
			(at -0.889 0 270)
			(size 1.016 1.27)
			(layers "B.Cu" "B.Mask" "B.Paste")
			(net "GND")
		)
	)
	(footprint ""
		(layer "B.Cu")
		(at 255.905 -339.63864 180)
		(property "Reference" "R828"
			(at 0 0 0)
			(layer "B.SilkS")
			(hide yes)
			(effects
				(font
					(size 1.27 1.27)
				)
				(justify mirror)
			)
		)
		(property "Value" ""
			(at 0 0 0)
			(layer "B.Fab")
			(effects
				(font
					(size 1.27 1.27)
				)
				(justify mirror)
			)
		)
		(duplicate_pad_numbers_are_jumpers no)
		(fp_line
			(start 0.32512 0.175006)
			(end 0.32512 -0.175006)
			(stroke
				(width 0.1)
				(type default)
			)
			(layer "B.Fab")
		)
		(fp_line
			(start 0.32512 -0.175006)
			(end -0.32512 -0.175006)
			(stroke
				(width 0.1)
				(type default)
			)
			(layer "B.Fab")
		)
		(fp_line
			(start -0.32512 0.175006)
			(end 0.32512 0.175006)
			(stroke
				(width 0.1)
				(type default)
			)
			(layer "B.Fab")
		)
		(fp_line
			(start -0.32512 -0.175006)
			(end -0.32512 0.175006)
			(stroke
				(width 0.1)
				(type default)
			)
			(layer "B.Fab")
		)
		(pad "1" smd rect
			(at 0.2667 0)
			(size 0.3048 0.381)
			(layers "B.Cu" "B.Mask" "B.Paste")
			(net "SMB_RT_CPU0_P1_ROM_MUX_2D_R_SDA")
		)
		(pad "2" smd rect
			(at -0.2667 0 180)
			(size 0.3048 0.381)
			(layers "B.Cu" "B.Mask" "B.Paste")
			(net "SMB_RT_CPU0_P1_ROM_MUX_2D_SDA")
		)
	)
	(footprint ""
		(layer "B.Cu")
		(at 239.141 -330.581)
		(property "Reference" "R847"
			(at 0 0 0)
			(layer "B.SilkS")
			(hide yes)
			(effects
				(font
					(size 1.27 1.27)
				)
				(justify mirror)
			)
		)
		(property "Value" ""
			(at 0 0 0)
			(layer "B.Fab")
			(effects
				(font
					(size 1.27 1.27)
				)
				(justify mirror)
			)
		)
		(duplicate_pad_numbers_are_jumpers no)
		(fp_line
			(start -0.32512 -0.175006)
			(end -0.32512 0.175006)
			(stroke
				(width 0.1)
				(type default)
			)
			(layer "B.Fab")
		)
		(fp_line
			(start -0.32512 0.175006)
			(end 0.32512 0.175006)
			(stroke
				(width 0.1)
				(type default)
			)
			(layer "B.Fab")
		)
		(fp_line
			(start 0.32512 -0.175006)
			(end -0.32512 -0.175006)
			(stroke
				(width 0.1)
				(type default)
			)
			(layer "B.Fab")
		)
		(fp_line
			(start 0.32512 0.175006)
			(end 0.32512 -0.175006)
			(stroke
				(width 0.1)
				(type default)
			)
			(layer "B.Fab")
		)
		(pad "1" smd rect
			(at 0.2667 0 180)
			(size 0.3048 0.381)
			(layers "B.Cu" "B.Mask" "B.Paste")
			(net "RT_ROM_SMB_MUX_ADDR0")
		)
		(pad "2" smd rect
			(at -0.2667 0)
			(size 0.3048 0.381)
			(layers "B.Cu" "B.Mask" "B.Paste")
			(net "GND")
		)
	)
	(footprint ""
		(layer "B.Cu")
		(at 370.376958 -272.284952)
		(property "Reference" "C2215"
			(at 0 0 0)
			(layer "B.SilkS")
			(hide yes)
			(effects
				(font
					(size 1.27 1.27)
				)
				(justify mirror)
			)
		)
		(property "Value" ""
			(at 0 0 0)
			(layer "B.Fab")
			(effects
				(font
					(size 1.27 1.27)
				)
				(justify mirror)
			)
		)
		(duplicate_pad_numbers_are_jumpers no)
		(fp_line
			(start -0.7874 -0.4064)
			(end -0.7874 0.4064)
			(stroke
				(width 0.1524)
				(type default)
			)
			(layer "B.SilkS")
		)
		(fp_line
			(start -0.7874 0.4064)
			(end 0.7874 0.4064)
			(stroke
				(width 0.1524)
				(type default)
			)
			(layer "B.SilkS")
		)
		(fp_line
			(start 0.7874 -0.4064)
			(end -0.7874 -0.4064)
			(stroke
				(width 0.1524)
				(type default)
			)
			(layer "B.SilkS")
		)
		(fp_line
			(start 0.7874 0.4064)
			(end 0.7874 -0.4064)
			(stroke
				(width 0.1524)
				(type default)
			)
			(layer "B.SilkS")
		)
		(fp_line
			(start -0.67945 -0.3048)
			(end -0.67945 0.3048)
			(stroke
				(width 0.1)
				(type default)
			)
			(layer "B.Fab")
		)
		(fp_line
			(start -0.67945 0.3048)
			(end -0.120396 0.3048)
			(stroke
				(width 0.1)
				(type default)
			)
			(layer "B.Fab")
		)
		(fp_line
			(start -0.12065 -0.3048)
			(end -0.67945 -0.3048)
			(stroke
				(width 0.1)
				(type default)
			)
			(layer "B.Fab")
		)
		(fp_line
			(start -0.12065 -0.2794)
			(end -0.12065 -0.3048)
			(stroke
				(width 0.1)
				(type default)
			)
			(layer "B.Fab")
		)
		(fp_line
			(start -0.120396 0.2794)
			(end 0.12065 0.2794)
			(stroke
				(width 0.1)
				(type default)
			)
			(layer "B.Fab")
		)
		(fp_line
			(start -0.120396 0.3048)
			(end -0.120396 0.2794)
			(stroke
				(width 0.1)
				(type default)
			)
			(layer "B.Fab")
		)
		(fp_line
			(start 0.12065 -0.305054)
			(end 0.12065 -0.2794)
			(stroke
				(width 0.1)
				(type default)
			)
			(layer "B.Fab")
		)
		(fp_line
			(start 0.12065 -0.2794)
			(end -0.12065 -0.2794)
			(stroke
				(width 0.1)
				(type default)
			)
			(layer "B.Fab")
		)
		(fp_line
			(start 0.12065 0.2794)
			(end 0.12065 0.3048)
			(stroke
				(width 0.1)
				(type default)
			)
			(layer "B.Fab")
		)
		(fp_line
			(start 0.12065 0.3048)
			(end 0.67945 0.3048)
			(stroke
				(width 0.1)
				(type default)
			)
			(layer "B.Fab")
		)
		(fp_line
			(start 0.67945 -0.305054)
			(end 0.12065 -0.305054)
			(stroke
				(width 0.1)
				(type default)
			)
			(layer "B.Fab")
		)
		(fp_line
			(start 0.67945 0.3048)
			(end 0.67945 -0.305054)
			(stroke
				(width 0.1)
				(type default)
			)
			(layer "B.Fab")
		)
		(pad "1" smd circle
			(at 0.40005 0 180)
			(size 0 0)
			(layers "B.Cu" "B.Mask" "B.Paste")
			(net "PVDDCR_CPU1_P0")
		)
		(pad "2" smd circle
			(at -0.40005 0 180)
			(size 0 0)
			(layers "B.Cu" "B.Mask" "B.Paste")
			(net "GND")
		)
	)
	(footprint ""
		(layer "B.Cu")
		(at 315.585094 -40.33774 -90)
		(property "Reference" "R3941"
			(at 0 0 90)
			(layer "B.SilkS")
			(hide yes)
			(effects
				(font
					(size 1.27 1.27)
				)
				(justify mirror)
			)
		)
		(property "Value" ""
			(at 0 0 90)
			(layer "B.Fab")
			(effects
				(font
					(size 1.27 1.27)
				)
				(justify mirror)
			)
		)
		(duplicate_pad_numbers_are_jumpers no)
		(fp_line
			(start -0.7874 0.4064)
			(end 0.7874 0.4064)
			(stroke
				(width 0.1524)
				(type default)
			)
			(layer "B.SilkS")
		)
		(fp_line
			(start 0.7874 0.4064)
			(end 0.7874 -0.4064)
			(stroke
				(width 0.1524)
				(type default)
			)
			(layer "B.SilkS")
		)
		(fp_line
			(start -0.7874 -0.4064)
			(end -0.7874 0.4064)
			(stroke
				(width 0.1524)
				(type default)
			)
			(layer "B.SilkS")
		)
		(fp_line
			(start 0.7874 -0.4064)
			(end -0.7874 -0.4064)
			(stroke
				(width 0.1524)
				(type default)
			)
			(layer "B.SilkS")
		)
		(fp_line
			(start -0.67945 0.3048)
			(end -0.120396 0.3048)
			(stroke
				(width 0.1)
				(type default)
			)
			(layer "B.Fab")
		)
		(fp_line
			(start -0.120396 0.3048)
			(end -0.120396 0.2794)
			(stroke
				(width 0.1)
				(type default)
			)
			(layer "B.Fab")
		)
		(fp_line
			(start 0.12065 0.3048)
			(end 0.67945 0.3048)
			(stroke
				(width 0.1)
				(type default)
			)
			(layer "B.Fab")
		)
		(fp_line
			(start 0.67945 0.3048)
			(end 0.67945 -0.305054)
			(stroke
				(width 0.1)
				(type default)
			)
			(layer "B.Fab")
		)
		(fp_line
			(start -0.120396 0.2794)
			(end 0.12065 0.2794)
			(stroke
				(width 0.1)
				(type default)
			)
			(layer "B.Fab")
		)
		(fp_line
			(start 0.12065 0.2794)
			(end 0.12065 0.3048)
			(stroke
				(width 0.1)
				(type default)
			)
			(layer "B.Fab")
		)
		(fp_line
			(start -0.12065 -0.2794)
			(end -0.12065 -0.3048)
			(stroke
				(width 0.1)
				(type default)
			)
			(layer "B.Fab")
		)
		(fp_line
			(start 0.12065 -0.2794)
			(end -0.12065 -0.2794)
			(stroke
				(width 0.1)
				(type default)
			)
			(layer "B.Fab")
		)
		(fp_line
			(start -0.67945 -0.3048)
			(end -0.67945 0.3048)
			(stroke
				(width 0.1)
				(type default)
			)
			(layer "B.Fab")
		)
		(fp_line
			(start -0.12065 -0.3048)
			(end -0.67945 -0.3048)
			(stroke
				(width 0.1)
				(type default)
			)
			(layer "B.Fab")
		)
		(fp_line
			(start 0.12065 -0.305054)
			(end 0.12065 -0.2794)
			(stroke
				(width 0.1)
				(type default)
			)
			(layer "B.Fab")
		)
		(fp_line
			(start 0.67945 -0.305054)
			(end 0.12065 -0.305054)
			(stroke
				(width 0.1)
				(type default)
			)
			(layer "B.Fab")
		)
		(pad "1" smd rect
			(at 0.40005 0 270)
			(size 0.4572 0.508)
			(layers "B.Cu" "B.Mask" "B.Paste")
			(net "P12V_E1S_0_ISENSE_MAM_TIC")
		)
		(pad "2" smd rect
			(at -0.40005 0 270)
			(size 0.4572 0.508)
			(layers "B.Cu" "B.Mask" "B.Paste")
			(net "P12V_E1S_0_ISENSE_TIC")
		)
	)
	(footprint ""
		(layer "B.Cu")
		(at 59.401202 -193.996564)
		(property "Reference" "C136"
			(at 0 0 0)
			(layer "B.SilkS")
			(hide yes)
			(effects
				(font
					(size 1.27 1.27)
				)
				(justify mirror)
			)
		)
		(property "Value" ""
			(at 0 0 0)
			(layer "B.Fab")
			(effects
				(font
					(size 1.27 1.27)
				)
				(justify mirror)
			)
		)
		(duplicate_pad_numbers_are_jumpers no)
		(fp_line
			(start -0.7874 -0.4064)
			(end -0.7874 0.4064)
			(stroke
				(width 0.1524)
				(type default)
			)
			(layer "B.SilkS")
		)
		(fp_line
			(start -0.7874 0.4064)
			(end 0.7874 0.4064)
			(stroke
				(width 0.1524)
				(type default)
			)
			(layer "B.SilkS")
		)
		(fp_line
			(start 0.7874 -0.4064)
			(end -0.7874 -0.4064)
			(stroke
				(width 0.1524)
				(type default)
			)
			(layer "B.SilkS")
		)
		(fp_line
			(start 0.7874 0.4064)
			(end 0.7874 -0.4064)
			(stroke
				(width 0.1524)
				(type default)
			)
			(layer "B.SilkS")
		)
		(fp_line
			(start -0.67945 -0.3048)
			(end -0.67945 0.3048)
			(stroke
				(width 0.1)
				(type default)
			)
			(layer "B.Fab")
		)
		(fp_line
			(start -0.67945 0.3048)
			(end -0.120396 0.3048)
			(stroke
				(width 0.1)
				(type default)
			)
			(layer "B.Fab")
		)
		(fp_line
			(start -0.12065 -0.3048)
			(end -0.67945 -0.3048)
			(stroke
				(width 0.1)
				(type default)
			)
			(layer "B.Fab")
		)
		(fp_line
			(start -0.12065 -0.2794)
			(end -0.12065 -0.3048)
			(stroke
				(width 0.1)
				(type default)
			)
			(layer "B.Fab")
		)
		(fp_line
			(start -0.120396 0.2794)
			(end 0.12065 0.2794)
			(stroke
				(width 0.1)
				(type default)
			)
			(layer "B.Fab")
		)
		(fp_line
			(start -0.120396 0.3048)
			(end -0.120396 0.2794)
			(stroke
				(width 0.1)
				(type default)
			)
			(layer "B.Fab")
		)
		(fp_line
			(start 0.12065 -0.305054)
			(end 0.12065 -0.2794)
			(stroke
				(width 0.1)
				(type default)
			)
			(layer "B.Fab")
		)
		(fp_line
			(start 0.12065 -0.2794)
			(end -0.12065 -0.2794)
			(stroke
				(width 0.1)
				(type default)
			)
			(layer "B.Fab")
		)
		(fp_line
			(start 0.12065 0.2794)
			(end 0.12065 0.3048)
			(stroke
				(width 0.1)
				(type default)
			)
			(layer "B.Fab")
		)
		(fp_line
			(start 0.12065 0.3048)
			(end 0.67945 0.3048)
			(stroke
				(width 0.1)
				(type default)
			)
			(layer "B.Fab")
		)
		(fp_line
			(start 0.67945 -0.305054)
			(end 0.12065 -0.305054)
			(stroke
				(width 0.1)
				(type default)
			)
			(layer "B.Fab")
		)
		(fp_line
			(start 0.67945 0.3048)
			(end 0.67945 -0.305054)
			(stroke
				(width 0.1)
				(type default)
			)
			(layer "B.Fab")
		)
		(pad "1" smd circle
			(at 0.40005 0 180)
			(size 0 0)
			(layers "B.Cu" "B.Mask" "B.Paste")
			(net "P3V3_AUX")
		)
		(pad "2" smd circle
			(at -0.40005 0 180)
			(size 0 0)
			(layers "B.Cu" "B.Mask" "B.Paste")
			(net "GND")
		)
	)
	(footprint ""
		(layer "B.Cu")
		(at 117.102128 -27.441906 180)
		(property "Reference" "C6117"
			(at 0 0 0)
			(layer "B.SilkS")
			(hide yes)
			(effects
				(font
					(size 1.27 1.27)
				)
				(justify mirror)
			)
		)
		(property "Value" ""
			(at 0 0 0)
			(layer "B.Fab")
			(effects
				(font
					(size 1.27 1.27)
				)
				(justify mirror)
			)
		)
		(duplicate_pad_numbers_are_jumpers no)
		(fp_line
			(start 0.7874 0.4064)
			(end 0.7874 -0.4064)
			(stroke
				(width 0.1524)
				(type default)
			)
			(layer "B.SilkS")
		)
		(fp_line
			(start 0.7874 -0.4064)
			(end -0.7874 -0.4064)
			(stroke
				(width 0.1524)
				(type default)
			)
			(layer "B.SilkS")
		)
		(fp_line
			(start -0.7874 0.4064)
			(end 0.7874 0.4064)
			(stroke
				(width 0.1524)
				(type default)
			)
			(layer "B.SilkS")
		)
		(fp_line
			(start -0.7874 -0.4064)
			(end -0.7874 0.4064)
			(stroke
				(width 0.1524)
				(type default)
			)
			(layer "B.SilkS")
		)
		(fp_line
			(start 0.67945 0.3048)
			(end 0.67945 -0.305054)
			(stroke
				(width 0.1)
				(type default)
			)
			(layer "B.Fab")
		)
		(fp_line
			(start 0.67945 -0.305054)
			(end 0.12065 -0.305054)
			(stroke
				(width 0.1)
				(type default)
			)
			(layer "B.Fab")
		)
		(fp_line
			(start 0.12065 0.3048)
			(end 0.67945 0.3048)
			(stroke
				(width 0.1)
				(type default)
			)
			(layer "B.Fab")
		)
		(fp_line
			(start 0.12065 0.2794)
			(end 0.12065 0.3048)
			(stroke
				(width 0.1)
				(type default)
			)
			(layer "B.Fab")
		)
		(fp_line
			(start 0.12065 -0.2794)
			(end -0.12065 -0.2794)
			(stroke
				(width 0.1)
				(type default)
			)
			(layer "B.Fab")
		)
		(fp_line
			(start 0.12065 -0.305054)
			(end 0.12065 -0.2794)
			(stroke
				(width 0.1)
				(type default)
			)
			(layer "B.Fab")
		)
		(fp_line
			(start -0.120396 0.3048)
			(end -0.120396 0.2794)
			(stroke
				(width 0.1)
				(type default)
			)
			(layer "B.Fab")
		)
		(fp_line
			(start -0.120396 0.2794)
			(end 0.12065 0.2794)
			(stroke
				(width 0.1)
				(type default)
			)
			(layer "B.Fab")
		)
		(fp_line
			(start -0.12065 -0.2794)
			(end -0.12065 -0.3048)
			(stroke
				(width 0.1)
				(type default)
			)
			(layer "B.Fab")
		)
		(fp_line
			(start -0.12065 -0.3048)
			(end -0.67945 -0.3048)
			(stroke
				(width 0.1)
				(type default)
			)
			(layer "B.Fab")
		)
		(fp_line
			(start -0.67945 0.3048)
			(end -0.120396 0.3048)
			(stroke
				(width 0.1)
				(type default)
			)
			(layer "B.Fab")
		)
		(fp_line
			(start -0.67945 -0.3048)
			(end -0.67945 0.3048)
			(stroke
				(width 0.1)
				(type default)
			)
			(layer "B.Fab")
		)
		(pad "1" smd circle
			(at 0.40005 0)
			(size 0 0)
			(layers "B.Cu" "B.Mask" "B.Paste")
			(net "P1V2_CPU0_USB2_DVDD12")
		)
		(pad "2" smd circle
			(at -0.40005 0)
			(size 0 0)
			(layers "B.Cu" "B.Mask" "B.Paste")
			(net "GND")
		)
	)
	(footprint ""
		(layer "B.Cu")
		(at 132.630926 -408.517344 90)
		(property "Reference" "C6735"
			(at 0 0 90)
			(layer "B.SilkS")
			(hide yes)
			(effects
				(font
					(size 1.27 1.27)
				)
				(justify mirror)
			)
		)
		(property "Value" ""
			(at 0 0 90)
			(layer "B.Fab")
			(effects
				(font
					(size 1.27 1.27)
				)
				(justify mirror)
			)
		)
		(duplicate_pad_numbers_are_jumpers no)
		(fp_line
			(start 0.299974 -0.150114)
			(end -0.299974 -0.150114)
			(stroke
				(width 0.1)
				(type default)
			)
			(layer "B.Fab")
		)
		(fp_line
			(start -0.299974 -0.150114)
			(end -0.299974 0.150114)
			(stroke
				(width 0.1)
				(type default)
			)
			(layer "B.Fab")
		)
		(fp_line
			(start 0.299974 0.150114)
			(end 0.299974 -0.150114)
			(stroke
				(width 0.1)
				(type default)
			)
			(layer "B.Fab")
		)
		(fp_line
			(start -0.299974 0.150114)
			(end 0.299974 0.150114)
			(stroke
				(width 0.1)
				(type default)
			)
			(layer "B.Fab")
		)
		(pad "1" smd rect
			(at 0.2667 0 270)
			(size 0.3048 0.381)
			(layers "B.Cu" "B.Mask" "B.Paste")
			(net "P5E_CPU1_P3_TX_BUF_C_DP<5>")
		)
		(pad "2" smd rect
			(at -0.2667 0 270)
			(size 0.3048 0.381)
			(layers "B.Cu" "B.Mask" "B.Paste")
			(net "P5E_CPU1_P3_TX_BUF_DP<5>")
		)
	)
	(footprint ""
		(layer "B.Cu")
		(at 382.478534 -395.148562 90)
		(property "Reference" "C1048"
			(at 0 0 90)
			(layer "B.SilkS")
			(hide yes)
			(effects
				(font
					(size 1.27 1.27)
				)
				(justify mirror)
			)
		)
		(property "Value" ""
			(at 0 0 90)
			(layer "B.Fab")
			(effects
				(font
					(size 1.27 1.27)
				)
				(justify mirror)
			)
		)
		(duplicate_pad_numbers_are_jumpers no)
		(fp_line
			(start 0.299974 -0.150114)
			(end -0.299974 -0.150114)
			(stroke
				(width 0.1)
				(type default)
			)
			(layer "B.Fab")
		)
		(fp_line
			(start -0.299974 -0.150114)
			(end -0.299974 0.150114)
			(stroke
				(width 0.1)
				(type default)
			)
			(layer "B.Fab")
		)
		(fp_line
			(start 0.299974 0.150114)
			(end 0.299974 -0.150114)
			(stroke
				(width 0.1)
				(type default)
			)
			(layer "B.Fab")
		)
		(fp_line
			(start -0.299974 0.150114)
			(end 0.299974 0.150114)
			(stroke
				(width 0.1)
				(type default)
			)
			(layer "B.Fab")
		)
		(pad "1" smd rect
			(at 0.2667 0 270)
			(size 0.3048 0.381)
			(layers "B.Cu" "B.Mask" "B.Paste")
			(net "P0V9_CPU0_RT_2D")
		)
		(pad "2" smd rect
			(at -0.2667 0 270)
			(size 0.3048 0.381)
			(layers "B.Cu" "B.Mask" "B.Paste")
			(net "GND")
		)
	)
	(footprint ""
		(layer "B.Cu")
		(at 401.046188 -395.43228)
		(property "Reference" "C781"
			(at 0 0 0)
			(layer "B.SilkS")
			(hide yes)
			(effects
				(font
					(size 1.27 1.27)
				)
				(justify mirror)
			)
		)
		(property "Value" ""
			(at 0 0 0)
			(layer "B.Fab")
			(effects
				(font
					(size 1.27 1.27)
				)
				(justify mirror)
			)
		)
		(duplicate_pad_numbers_are_jumpers no)
		(fp_line
			(start -0.299974 -0.150114)
			(end -0.299974 0.150114)
			(stroke
				(width 0.1)
				(type default)
			)
			(layer "B.Fab")
		)
		(fp_line
			(start -0.299974 0.150114)
			(end 0.299974 0.150114)
			(stroke
				(width 0.1)
				(type default)
			)
			(layer "B.Fab")
		)
		(fp_line
			(start 0.299974 -0.150114)
			(end -0.299974 -0.150114)
			(stroke
				(width 0.1)
				(type default)
			)
			(layer "B.Fab")
		)
		(fp_line
			(start 0.299974 0.150114)
			(end 0.299974 -0.150114)
			(stroke
				(width 0.1)
				(type default)
			)
			(layer "B.Fab")
		)
		(pad "1" smd rect
			(at 0.2667 0 180)
			(size 0.3048 0.381)
			(layers "B.Cu" "B.Mask" "B.Paste")
			(net "P0V9_CPU0_RT2_2A")
		)
		(pad "2" smd rect
			(at -0.2667 0 180)
			(size 0.3048 0.381)
			(layers "B.Cu" "B.Mask" "B.Paste")
			(net "GND")
		)
	)
	(footprint ""
		(layer "B.Cu")
		(at 364.312454 -268.41831)
		(property "Reference" "C2219"
			(at 0 0 0)
			(layer "B.SilkS")
			(hide yes)
			(effects
				(font
					(size 1.27 1.27)
				)
				(justify mirror)
			)
		)
		(property "Value" ""
			(at 0 0 0)
			(layer "B.Fab")
			(effects
				(font
					(size 1.27 1.27)
				)
				(justify mirror)
			)
		)
		(duplicate_pad_numbers_are_jumpers no)
		(fp_line
			(start -0.7874 -0.4064)
			(end -0.7874 0.4064)
			(stroke
				(width 0.1524)
				(type default)
			)
			(layer "B.SilkS")
		)
		(fp_line
			(start -0.7874 0.4064)
			(end 0.7874 0.4064)
			(stroke
				(width 0.1524)
				(type default)
			)
			(layer "B.SilkS")
		)
		(fp_line
			(start 0.7874 -0.4064)
			(end -0.7874 -0.4064)
			(stroke
				(width 0.1524)
				(type default)
			)
			(layer "B.SilkS")
		)
		(fp_line
			(start 0.7874 0.4064)
			(end 0.7874 -0.4064)
			(stroke
				(width 0.1524)
				(type default)
			)
			(layer "B.SilkS")
		)
		(fp_line
			(start -0.67945 -0.3048)
			(end -0.67945 0.3048)
			(stroke
				(width 0.1)
				(type default)
			)
			(layer "B.Fab")
		)
		(fp_line
			(start -0.67945 0.3048)
			(end -0.120396 0.3048)
			(stroke
				(width 0.1)
				(type default)
			)
			(layer "B.Fab")
		)
		(fp_line
			(start -0.12065 -0.3048)
			(end -0.67945 -0.3048)
			(stroke
				(width 0.1)
				(type default)
			)
			(layer "B.Fab")
		)
		(fp_line
			(start -0.12065 -0.2794)
			(end -0.12065 -0.3048)
			(stroke
				(width 0.1)
				(type default)
			)
			(layer "B.Fab")
		)
		(fp_line
			(start -0.120396 0.2794)
			(end 0.12065 0.2794)
			(stroke
				(width 0.1)
				(type default)
			)
			(layer "B.Fab")
		)
		(fp_line
			(start -0.120396 0.3048)
			(end -0.120396 0.2794)
			(stroke
				(width 0.1)
				(type default)
			)
			(layer "B.Fab")
		)
		(fp_line
			(start 0.12065 -0.305054)
			(end 0.12065 -0.2794)
			(stroke
				(width 0.1)
				(type default)
			)
			(layer "B.Fab")
		)
		(fp_line
			(start 0.12065 -0.2794)
			(end -0.12065 -0.2794)
			(stroke
				(width 0.1)
				(type default)
			)
			(layer "B.Fab")
		)
		(fp_line
			(start 0.12065 0.2794)
			(end 0.12065 0.3048)
			(stroke
				(width 0.1)
				(type default)
			)
			(layer "B.Fab")
		)
		(fp_line
			(start 0.12065 0.3048)
			(end 0.67945 0.3048)
			(stroke
				(width 0.1)
				(type default)
			)
			(layer "B.Fab")
		)
		(fp_line
			(start 0.67945 -0.305054)
			(end 0.12065 -0.305054)
			(stroke
				(width 0.1)
				(type default)
			)
			(layer "B.Fab")
		)
		(fp_line
			(start 0.67945 0.3048)
			(end 0.67945 -0.305054)
			(stroke
				(width 0.1)
				(type default)
			)
			(layer "B.Fab")
		)
		(pad "1" smd circle
			(at 0.40005 0 180)
			(size 0 0)
			(layers "B.Cu" "B.Mask" "B.Paste")
			(net "PVDDCR_CPU1_P0")
		)
		(pad "2" smd circle
			(at -0.40005 0 180)
			(size 0 0)
			(layers "B.Cu" "B.Mask" "B.Paste")
			(net "GND")
		)
	)
	(footprint ""
		(layer "B.Cu")
		(at 395.562582 -398.055084 90)
		(property "Reference" "C801"
			(at 0 0 90)
			(layer "B.SilkS")
			(hide yes)
			(effects
				(font
					(size 1.27 1.27)
				)
				(justify mirror)
			)
		)
		(property "Value" ""
			(at 0 0 90)
			(layer "B.Fab")
			(effects
				(font
					(size 1.27 1.27)
				)
				(justify mirror)
			)
		)
		(duplicate_pad_numbers_are_jumpers no)
		(fp_line
			(start 1.524 -0.762)
			(end -1.524 -0.762)
			(stroke
				(width 0.1524)
				(type default)
			)
			(layer "B.SilkS")
		)
		(fp_line
			(start -1.524 -0.762)
			(end -1.524 0.762)
			(stroke
				(width 0.1524)
				(type default)
			)
			(layer "B.SilkS")
		)
		(fp_line
			(start 1.524 0.762)
			(end 1.524 -0.762)
			(stroke
				(width 0.1524)
				(type default)
			)
			(layer "B.SilkS")
		)
		(fp_line
			(start -1.524 0.762)
			(end 1.524 0.762)
			(stroke
				(width 0.1524)
				(type default)
			)
			(layer "B.SilkS")
		)
		(fp_line
			(start 1.1049 -0.724916)
			(end 1.1049 0.724916)
			(stroke
				(width 0.1)
				(type default)
			)
			(layer "B.Fab")
		)
		(fp_line
			(start -1.1049 -0.724916)
			(end 1.1049 -0.724916)
			(stroke
				(width 0.1)
				(type default)
			)
			(layer "B.Fab")
		)
		(fp_line
			(start 1.1049 0.724916)
			(end -1.1049 0.724916)
			(stroke
				(width 0.1)
				(type default)
			)
			(layer "B.Fab")
		)
		(fp_line
			(start -1.1049 0.724916)
			(end -1.1049 -0.724916)
			(stroke
				(width 0.1)
				(type default)
			)
			(layer "B.Fab")
		)
		(pad "1" smd rect
			(at 0.889 0 90)
			(size 1.016 1.27)
			(layers "B.Cu" "B.Mask" "B.Paste")
			(net "P0V9_CPU0_RT_2D")
		)
		(pad "2" smd rect
			(at -0.889 0 90)
			(size 1.016 1.27)
			(layers "B.Cu" "B.Mask" "B.Paste")
			(net "GND")
		)
	)
	(footprint ""
		(layer "B.Cu")
		(at 372.891304 -398.942052 90)
		(property "Reference" "C1056"
			(at 0 0 90)
			(layer "B.SilkS")
			(hide yes)
			(effects
				(font
					(size 1.27 1.27)
				)
				(justify mirror)
			)
		)
		(property "Value" ""
			(at 0 0 90)
			(layer "B.Fab")
			(effects
				(font
					(size 1.27 1.27)
				)
				(justify mirror)
			)
		)
		(duplicate_pad_numbers_are_jumpers no)
		(fp_line
			(start 0.7874 -0.4064)
			(end -0.7874 -0.4064)
			(stroke
				(width 0.1524)
				(type default)
			)
			(layer "B.SilkS")
		)
		(fp_line
			(start -0.7874 -0.4064)
			(end -0.7874 0.4064)
			(stroke
				(width 0.1524)
				(type default)
			)
			(layer "B.SilkS")
		)
		(fp_line
			(start 0.7874 0.4064)
			(end 0.7874 -0.4064)
			(stroke
				(width 0.1524)
				(type default)
			)
			(layer "B.SilkS")
		)
		(fp_line
			(start -0.7874 0.4064)
			(end 0.7874 0.4064)
			(stroke
				(width 0.1524)
				(type default)
			)
			(layer "B.SilkS")
		)
		(fp_line
			(start 0.67945 -0.305054)
			(end 0.12065 -0.305054)
			(stroke
				(width 0.1)
				(type default)
			)
			(layer "B.Fab")
		)
		(fp_line
			(start 0.12065 -0.305054)
			(end 0.12065 -0.2794)
			(stroke
				(width 0.1)
				(type default)
			)
			(layer "B.Fab")
		)
		(fp_line
			(start -0.12065 -0.3048)
			(end -0.67945 -0.3048)
			(stroke
				(width 0.1)
				(type default)
			)
			(layer "B.Fab")
		)
		(fp_line
			(start -0.67945 -0.3048)
			(end -0.67945 0.3048)
			(stroke
				(width 0.1)
				(type default)
			)
			(layer "B.Fab")
		)
		(fp_line
			(start 0.12065 -0.2794)
			(end -0.12065 -0.2794)
			(stroke
				(width 0.1)
				(type default)
			)
			(layer "B.Fab")
		)
		(fp_line
			(start -0.12065 -0.2794)
			(end -0.12065 -0.3048)
			(stroke
				(width 0.1)
				(type default)
			)
			(layer "B.Fab")
		)
		(fp_line
			(start 0.12065 0.2794)
			(end 0.12065 0.3048)
			(stroke
				(width 0.1)
				(type default)
			)
			(layer "B.Fab")
		)
		(fp_line
			(start -0.120396 0.2794)
			(end 0.12065 0.2794)
			(stroke
				(width 0.1)
				(type default)
			)
			(layer "B.Fab")
		)
		(fp_line
			(start 0.67945 0.3048)
			(end 0.67945 -0.305054)
			(stroke
				(width 0.1)
				(type default)
			)
			(layer "B.Fab")
		)
		(fp_line
			(start 0.12065 0.3048)
			(end 0.67945 0.3048)
			(stroke
				(width 0.1)
				(type default)
			)
			(layer "B.Fab")
		)
		(fp_line
			(start -0.120396 0.3048)
			(end -0.120396 0.2794)
			(stroke
				(width 0.1)
				(type default)
			)
			(layer "B.Fab")
		)
		(fp_line
			(start -0.67945 0.3048)
			(end -0.120396 0.3048)
			(stroke
				(width 0.1)
				(type default)
			)
			(layer "B.Fab")
		)
		(pad "1" smd circle
			(at 0.40005 0 270)
			(size 0 0)
			(layers "B.Cu" "B.Mask" "B.Paste")
			(net "P0V9_CPU0_RT3_2A")
		)
		(pad "2" smd circle
			(at -0.40005 0 270)
			(size 0 0)
			(layers "B.Cu" "B.Mask" "B.Paste")
			(net "GND")
		)
	)
	(footprint ""
		(layer "B.Cu")
		(at 381.645922 -148.30171 -90)
		(property "Reference" "PR441"
			(at 0 0 90)
			(layer "B.SilkS")
			(hide yes)
			(effects
				(font
					(size 1.27 1.27)
				)
				(justify mirror)
			)
		)
		(property "Value" ""
			(at 0 0 90)
			(layer "B.Fab")
			(effects
				(font
					(size 1.27 1.27)
				)
				(justify mirror)
			)
		)
		(duplicate_pad_numbers_are_jumpers no)
		(fp_line
			(start -0.7874 0.4064)
			(end 0.7874 0.4064)
			(stroke
				(width 0.1524)
				(type default)
			)
			(layer "B.SilkS")
		)
		(fp_line
			(start 0.7874 0.4064)
			(end 0.7874 -0.4064)
			(stroke
				(width 0.1524)
				(type default)
			)
			(layer "B.SilkS")
		)
		(fp_line
			(start -0.7874 -0.4064)
			(end -0.7874 0.4064)
			(stroke
				(width 0.1524)
				(type default)
			)
			(layer "B.SilkS")
		)
		(fp_line
			(start 0.7874 -0.4064)
			(end -0.7874 -0.4064)
			(stroke
				(width 0.1524)
				(type default)
			)
			(layer "B.SilkS")
		)
		(fp_line
			(start -0.67945 0.3048)
			(end -0.120396 0.3048)
			(stroke
				(width 0.1)
				(type default)
			)
			(layer "B.Fab")
		)
		(fp_line
			(start -0.120396 0.3048)
			(end -0.120396 0.2794)
			(stroke
				(width 0.1)
				(type default)
			)
			(layer "B.Fab")
		)
		(fp_line
			(start 0.12065 0.3048)
			(end 0.67945 0.3048)
			(stroke
				(width 0.1)
				(type default)
			)
			(layer "B.Fab")
		)
		(fp_line
			(start 0.67945 0.3048)
			(end 0.67945 -0.305054)
			(stroke
				(width 0.1)
				(type default)
			)
			(layer "B.Fab")
		)
		(fp_line
			(start -0.120396 0.2794)
			(end 0.12065 0.2794)
			(stroke
				(width 0.1)
				(type default)
			)
			(layer "B.Fab")
		)
		(fp_line
			(start 0.12065 0.2794)
			(end 0.12065 0.3048)
			(stroke
				(width 0.1)
				(type default)
			)
			(layer "B.Fab")
		)
		(fp_line
			(start -0.12065 -0.2794)
			(end -0.12065 -0.3048)
			(stroke
				(width 0.1)
				(type default)
			)
			(layer "B.Fab")
		)
		(fp_line
			(start 0.12065 -0.2794)
			(end -0.12065 -0.2794)
			(stroke
				(width 0.1)
				(type default)
			)
			(layer "B.Fab")
		)
		(fp_line
			(start -0.67945 -0.3048)
			(end -0.67945 0.3048)
			(stroke
				(width 0.1)
				(type default)
			)
			(layer "B.Fab")
		)
		(fp_line
			(start -0.12065 -0.3048)
			(end -0.67945 -0.3048)
			(stroke
				(width 0.1)
				(type default)
			)
			(layer "B.Fab")
		)
		(fp_line
			(start 0.12065 -0.305054)
			(end 0.12065 -0.2794)
			(stroke
				(width 0.1)
				(type default)
			)
			(layer "B.Fab")
		)
		(fp_line
			(start 0.67945 -0.305054)
			(end 0.12065 -0.305054)
			(stroke
				(width 0.1)
				(type default)
			)
			(layer "B.Fab")
		)
		(pad "1" smd circle
			(at 0.40005 0 90)
			(size 0 0)
			(layers "B.Cu" "B.Mask" "B.Paste")
			(net "NC_PVDDCR_CPU0_P0_IMON9")
		)
		(pad "2" smd circle
			(at -0.40005 0 90)
			(size 0 0)
			(layers "B.Cu" "B.Mask" "B.Paste")
			(net "GND")
		)
	)
	(footprint ""
		(layer "B.Cu")
		(at 343.43467 -328.212704 -90)
		(property "Reference" "PC98"
			(at 9.746996 -0.271526 270)
			(unlocked yes)
			(layer "B.SilkS")
			(effects
				(font
					(size 0.7874 0.5842)
					(thickness 0.1524)
				)
				(justify left mirror)
			)
		)
		(property "Value" ""
			(at 0 0 90)
			(layer "B.Fab")
			(effects
				(font
					(size 1.27 1.27)
				)
				(justify mirror)
			)
		)
		(duplicate_pad_numbers_are_jumpers no)
		(fp_line
			(start -4.533392 2.249932)
			(end 4.533392 2.249932)
			(stroke
				(width 0.1524)
				(type default)
			)
			(layer "B.SilkS")
		)
		(fp_line
			(start 4.533392 2.249932)
			(end 4.533392 -2.249932)
			(stroke
				(width 0.1524)
				(type default)
			)
			(layer "B.SilkS")
		)
		(fp_line
			(start -4.533392 -2.249932)
			(end -4.533392 2.249932)
			(stroke
				(width 0.1524)
				(type default)
			)
			(layer "B.SilkS")
		)
		(fp_line
			(start 4.533392 -2.249932)
			(end -4.533392 -2.249932)
			(stroke
				(width 0.1524)
				(type default)
			)
			(layer "B.SilkS")
		)
		(fp_rect
			(start 5.39242 2.326132)
			(end 4.533392 -2.326132)
			(stroke
				(width 0)
				(type default)
			)
			(fill yes)
			(layer "B.SilkS")
		)
		(fp_line
			(start -3.750056 2.249932)
			(end 3.750056 2.249932)
			(stroke
				(width 0.1)
				(type default)
			)
			(layer "B.Fab")
		)
		(fp_line
			(start 3.750056 2.249932)
			(end 3.750056 -2.249932)
			(stroke
				(width 0.1)
				(type default)
			)
			(layer "B.Fab")
		)
		(fp_line
			(start -3.750056 -2.249932)
			(end -3.750056 2.249932)
			(stroke
				(width 0.1)
				(type default)
			)
			(layer "B.Fab")
		)
		(fp_line
			(start 3.750056 -2.249932)
			(end -3.750056 -2.249932)
			(stroke
				(width 0.1)
				(type default)
			)
			(layer "B.Fab")
		)
		(fp_text user "+"
			(at 6.322314 0.786384 180)
			(unlocked yes)
			(layer "B.SilkS")
			(effects
				(font
					(size 1.905 1.4224)
					(thickness 0.1524)
				)
				(justify left mirror)
			)
		)
		(fp_text user "-"
			(at -4.8514 -0.14605 270)
			(unlocked yes)
			(layer "B.SilkS")
			(effects
				(font
					(size 1.905 1.4224)
					(thickness 0.1524)
				)
				(justify left mirror)
			)
		)
		(fp_text user "+"
			(at 6.322314 0.786384 180)
			(unlocked yes)
			(layer "B.Fab")
			(effects
				(font
					(size 1.905 1.4224)
					(thickness 0.1524)
				)
				(justify left mirror)
			)
		)
		(fp_text user "-"
			(at -4.8514 -0.14605 270)
			(unlocked yes)
			(layer "B.Fab")
			(effects
				(font
					(size 1.905 1.4224)
					(thickness 0.1524)
				)
				(justify left mirror)
			)
		)
		(pad "1" smd rect
			(at 3.199892 0 90)
			(size 2.413 2.8194)
			(layers "B.Cu" "B.Mask" "B.Paste")
			(net "PVDDCR_CPU1_P0")
		)
		(pad "2" smd rect
			(at -3.199892 0 90)
			(size 2.413 2.8194)
			(layers "B.Cu" "B.Mask" "B.Paste")
			(net "GND")
		)
	)
	(footprint ""
		(layer "B.Cu")
		(at 408.597608 -329.987402 90)
		(property "Reference" "R5055"
			(at 0 0 90)
			(layer "B.SilkS")
			(hide yes)
			(effects
				(font
					(size 1.27 1.27)
				)
				(justify mirror)
			)
		)
		(property "Value" ""
			(at 0 0 90)
			(layer "B.Fab")
			(effects
				(font
					(size 1.27 1.27)
				)
				(justify mirror)
			)
		)
		(duplicate_pad_numbers_are_jumpers no)
		(fp_line
			(start 0.7874 -0.4064)
			(end -0.7874 -0.4064)
			(stroke
				(width 0.1524)
				(type default)
			)
			(layer "B.SilkS")
		)
		(fp_line
			(start -0.7874 -0.4064)
			(end -0.7874 0.4064)
			(stroke
				(width 0.1524)
				(type default)
			)
			(layer "B.SilkS")
		)
		(fp_line
			(start 0.7874 0.4064)
			(end 0.7874 -0.4064)
			(stroke
				(width 0.1524)
				(type default)
			)
			(layer "B.SilkS")
		)
		(fp_line
			(start -0.7874 0.4064)
			(end 0.7874 0.4064)
			(stroke
				(width 0.1524)
				(type default)
			)
			(layer "B.SilkS")
		)
		(fp_line
			(start 0.67945 -0.305054)
			(end 0.12065 -0.305054)
			(stroke
				(width 0.1)
				(type default)
			)
			(layer "B.Fab")
		)
		(fp_line
			(start 0.12065 -0.305054)
			(end 0.12065 -0.2794)
			(stroke
				(width 0.1)
				(type default)
			)
			(layer "B.Fab")
		)
		(fp_line
			(start -0.12065 -0.3048)
			(end -0.67945 -0.3048)
			(stroke
				(width 0.1)
				(type default)
			)
			(layer "B.Fab")
		)
		(fp_line
			(start -0.67945 -0.3048)
			(end -0.67945 0.3048)
			(stroke
				(width 0.1)
				(type default)
			)
			(layer "B.Fab")
		)
		(fp_line
			(start 0.12065 -0.2794)
			(end -0.12065 -0.2794)
			(stroke
				(width 0.1)
				(type default)
			)
			(layer "B.Fab")
		)
		(fp_line
			(start -0.12065 -0.2794)
			(end -0.12065 -0.3048)
			(stroke
				(width 0.1)
				(type default)
			)
			(layer "B.Fab")
		)
		(fp_line
			(start 0.12065 0.2794)
			(end 0.12065 0.3048)
			(stroke
				(width 0.1)
				(type default)
			)
			(layer "B.Fab")
		)
		(fp_line
			(start -0.120396 0.2794)
			(end 0.12065 0.2794)
			(stroke
				(width 0.1)
				(type default)
			)
			(layer "B.Fab")
		)
		(fp_line
			(start 0.67945 0.3048)
			(end 0.67945 -0.305054)
			(stroke
				(width 0.1)
				(type default)
			)
			(layer "B.Fab")
		)
		(fp_line
			(start 0.12065 0.3048)
			(end 0.67945 0.3048)
			(stroke
				(width 0.1)
				(type default)
			)
			(layer "B.Fab")
		)
		(fp_line
			(start -0.120396 0.3048)
			(end -0.120396 0.2794)
			(stroke
				(width 0.1)
				(type default)
			)
			(layer "B.Fab")
		)
		(fp_line
			(start -0.67945 0.3048)
			(end -0.120396 0.3048)
			(stroke
				(width 0.1)
				(type default)
			)
			(layer "B.Fab")
		)
		(pad "1" smd circle
			(at 0.40005 0 270)
			(size 0 0)
			(layers "B.Cu" "B.Mask" "B.Paste")
			(net "P1V5_BAT")
		)
		(pad "2" smd circle
			(at -0.40005 0 270)
			(size 0 0)
			(layers "B.Cu" "B.Mask" "B.Paste")
			(net "CPU0_RTC_LDO_SELECT")
		)
	)
	(footprint ""
		(layer "B.Cu")
		(at 353.517454 -269.30731)
		(property "Reference" "C2216"
			(at 0 0 0)
			(layer "B.SilkS")
			(hide yes)
			(effects
				(font
					(size 1.27 1.27)
				)
				(justify mirror)
			)
		)
		(property "Value" ""
			(at 0 0 0)
			(layer "B.Fab")
			(effects
				(font
					(size 1.27 1.27)
				)
				(justify mirror)
			)
		)
		(duplicate_pad_numbers_are_jumpers no)
		(fp_line
			(start -0.7874 -0.4064)
			(end -0.7874 0.4064)
			(stroke
				(width 0.1524)
				(type default)
			)
			(layer "B.SilkS")
		)
		(fp_line
			(start -0.7874 0.4064)
			(end 0.7874 0.4064)
			(stroke
				(width 0.1524)
				(type default)
			)
			(layer "B.SilkS")
		)
		(fp_line
			(start 0.7874 -0.4064)
			(end -0.7874 -0.4064)
			(stroke
				(width 0.1524)
				(type default)
			)
			(layer "B.SilkS")
		)
		(fp_line
			(start 0.7874 0.4064)
			(end 0.7874 -0.4064)
			(stroke
				(width 0.1524)
				(type default)
			)
			(layer "B.SilkS")
		)
		(fp_line
			(start -0.67945 -0.3048)
			(end -0.67945 0.3048)
			(stroke
				(width 0.1)
				(type default)
			)
			(layer "B.Fab")
		)
		(fp_line
			(start -0.67945 0.3048)
			(end -0.120396 0.3048)
			(stroke
				(width 0.1)
				(type default)
			)
			(layer "B.Fab")
		)
		(fp_line
			(start -0.12065 -0.3048)
			(end -0.67945 -0.3048)
			(stroke
				(width 0.1)
				(type default)
			)
			(layer "B.Fab")
		)
		(fp_line
			(start -0.12065 -0.2794)
			(end -0.12065 -0.3048)
			(stroke
				(width 0.1)
				(type default)
			)
			(layer "B.Fab")
		)
		(fp_line
			(start -0.120396 0.2794)
			(end 0.12065 0.2794)
			(stroke
				(width 0.1)
				(type default)
			)
			(layer "B.Fab")
		)
		(fp_line
			(start -0.120396 0.3048)
			(end -0.120396 0.2794)
			(stroke
				(width 0.1)
				(type default)
			)
			(layer "B.Fab")
		)
		(fp_line
			(start 0.12065 -0.305054)
			(end 0.12065 -0.2794)
			(stroke
				(width 0.1)
				(type default)
			)
			(layer "B.Fab")
		)
		(fp_line
			(start 0.12065 -0.2794)
			(end -0.12065 -0.2794)
			(stroke
				(width 0.1)
				(type default)
			)
			(layer "B.Fab")
		)
		(fp_line
			(start 0.12065 0.2794)
			(end 0.12065 0.3048)
			(stroke
				(width 0.1)
				(type default)
			)
			(layer "B.Fab")
		)
		(fp_line
			(start 0.12065 0.3048)
			(end 0.67945 0.3048)
			(stroke
				(width 0.1)
				(type default)
			)
			(layer "B.Fab")
		)
		(fp_line
			(start 0.67945 -0.305054)
			(end 0.12065 -0.305054)
			(stroke
				(width 0.1)
				(type default)
			)
			(layer "B.Fab")
		)
		(fp_line
			(start 0.67945 0.3048)
			(end 0.67945 -0.305054)
			(stroke
				(width 0.1)
				(type default)
			)
			(layer "B.Fab")
		)
		(pad "1" smd circle
			(at 0.40005 0 180)
			(size 0 0)
			(layers "B.Cu" "B.Mask" "B.Paste")
			(net "PVDDCR_CPU1_P0")
		)
		(pad "2" smd circle
			(at -0.40005 0 180)
			(size 0 0)
			(layers "B.Cu" "B.Mask" "B.Paste")
			(net "GND")
		)
	)
	(footprint ""
		(layer "B.Cu")
		(at 192.795906 -72.804528)
		(property "Reference" "C1827"
			(at 0 0 0)
			(layer "B.SilkS")
			(hide yes)
			(effects
				(font
					(size 1.27 1.27)
				)
				(justify mirror)
			)
		)
		(property "Value" ""
			(at 0 0 0)
			(layer "B.Fab")
			(effects
				(font
					(size 1.27 1.27)
				)
				(justify mirror)
			)
		)
		(duplicate_pad_numbers_are_jumpers no)
		(fp_line
			(start -0.7874 -0.4064)
			(end -0.7874 0.4064)
			(stroke
				(width 0.1524)
				(type default)
			)
			(layer "B.SilkS")
		)
		(fp_line
			(start -0.7874 0.4064)
			(end 0.7874 0.4064)
			(stroke
				(width 0.1524)
				(type default)
			)
			(layer "B.SilkS")
		)
		(fp_line
			(start 0.7874 -0.4064)
			(end -0.7874 -0.4064)
			(stroke
				(width 0.1524)
				(type default)
			)
			(layer "B.SilkS")
		)
		(fp_line
			(start 0.7874 0.4064)
			(end 0.7874 -0.4064)
			(stroke
				(width 0.1524)
				(type default)
			)
			(layer "B.SilkS")
		)
		(fp_line
			(start -0.67945 -0.3048)
			(end -0.67945 0.3048)
			(stroke
				(width 0.1)
				(type default)
			)
			(layer "B.Fab")
		)
		(fp_line
			(start -0.67945 0.3048)
			(end -0.120396 0.3048)
			(stroke
				(width 0.1)
				(type default)
			)
			(layer "B.Fab")
		)
		(fp_line
			(start -0.12065 -0.3048)
			(end -0.67945 -0.3048)
			(stroke
				(width 0.1)
				(type default)
			)
			(layer "B.Fab")
		)
		(fp_line
			(start -0.12065 -0.2794)
			(end -0.12065 -0.3048)
			(stroke
				(width 0.1)
				(type default)
			)
			(layer "B.Fab")
		)
		(fp_line
			(start -0.120396 0.2794)
			(end 0.12065 0.2794)
			(stroke
				(width 0.1)
				(type default)
			)
			(layer "B.Fab")
		)
		(fp_line
			(start -0.120396 0.3048)
			(end -0.120396 0.2794)
			(stroke
				(width 0.1)
				(type default)
			)
			(layer "B.Fab")
		)
		(fp_line
			(start 0.12065 -0.305054)
			(end 0.12065 -0.2794)
			(stroke
				(width 0.1)
				(type default)
			)
			(layer "B.Fab")
		)
		(fp_line
			(start 0.12065 -0.2794)
			(end -0.12065 -0.2794)
			(stroke
				(width 0.1)
				(type default)
			)
			(layer "B.Fab")
		)
		(fp_line
			(start 0.12065 0.2794)
			(end 0.12065 0.3048)
			(stroke
				(width 0.1)
				(type default)
			)
			(layer "B.Fab")
		)
		(fp_line
			(start 0.12065 0.3048)
			(end 0.67945 0.3048)
			(stroke
				(width 0.1)
				(type default)
			)
			(layer "B.Fab")
		)
		(fp_line
			(start 0.67945 -0.305054)
			(end 0.12065 -0.305054)
			(stroke
				(width 0.1)
				(type default)
			)
			(layer "B.Fab")
		)
		(fp_line
			(start 0.67945 0.3048)
			(end 0.67945 -0.305054)
			(stroke
				(width 0.1)
				(type default)
			)
			(layer "B.Fab")
		)
		(pad "1" smd circle
			(at 0.40005 0 180)
			(size 0 0)
			(layers "B.Cu" "B.Mask" "B.Paste")
			(net "P3V3_AUX")
		)
		(pad "2" smd circle
			(at -0.40005 0 180)
			(size 0 0)
			(layers "B.Cu" "B.Mask" "B.Paste")
			(net "GND")
		)
	)
	(footprint ""
		(layer "B.Cu")
		(at 393.843002 -416.899344 90)
		(property "Reference" "C6612"
			(at 0 0 90)
			(layer "B.SilkS")
			(hide yes)
			(effects
				(font
					(size 1.27 1.27)
				)
				(justify mirror)
			)
		)
		(property "Value" ""
			(at 0 0 90)
			(layer "B.Fab")
			(effects
				(font
					(size 1.27 1.27)
				)
				(justify mirror)
			)
		)
		(duplicate_pad_numbers_are_jumpers no)
		(fp_line
			(start 0.299974 -0.150114)
			(end -0.299974 -0.150114)
			(stroke
				(width 0.1)
				(type default)
			)
			(layer "B.Fab")
		)
		(fp_line
			(start -0.299974 -0.150114)
			(end -0.299974 0.150114)
			(stroke
				(width 0.1)
				(type default)
			)
			(layer "B.Fab")
		)
		(fp_line
			(start 0.299974 0.150114)
			(end 0.299974 -0.150114)
			(stroke
				(width 0.1)
				(type default)
			)
			(layer "B.Fab")
		)
		(fp_line
			(start -0.299974 0.150114)
			(end 0.299974 0.150114)
			(stroke
				(width 0.1)
				(type default)
			)
			(layer "B.Fab")
		)
		(pad "1" smd rect
			(at 0.2667 0 270)
			(size 0.3048 0.381)
			(layers "B.Cu" "B.Mask" "B.Paste")
			(net "P5E_CPU0_P3_TX_BUF_C_DN<7>")
		)
		(pad "2" smd rect
			(at -0.2667 0 270)
			(size 0.3048 0.381)
			(layers "B.Cu" "B.Mask" "B.Paste")
			(net "P5E_CPU0_P3_TX_BUF_DN<7>")
		)
	)
	(footprint ""
		(layer "B.Cu")
		(at 95.064072 -477.345502)
		(property "Reference" "ME7"
			(at 0 0 0)
			(layer "B.SilkS")
			(hide yes)
			(effects
				(font
					(size 1.27 1.27)
				)
				(justify mirror)
			)
		)
		(property "Value" ""
			(at 0 0 0)
			(layer "B.Fab")
			(effects
				(font
					(size 1.27 1.27)
				)
				(justify mirror)
			)
		)
		(duplicate_pad_numbers_are_jumpers no)
		(zone
			(layer "B.Cu")
			(hatch none 0.5)
			(connect_pads
				(clearance 0)
			)
			(min_thickness 0.25)
			(keepout
				(tracks allowed)
				(vias allowed)
				(pads allowed)
				(copperpour allowed)
				(footprints not_allowed)
			)
			(placement
				(enabled no)
				(sheetname "")
			)
			(fill
				(thermal_gap 0.5)
				(thermal_bridge_width 0.5)
				(island_removal_mode 0)
			)
			(polygon
				(pts
					(arc
						(start 453.286368 -125.607064)
						(mid 433.286408 -125.607064)
						(end 453.286368 -125.607064)
					)
				)
			)
		)
	)
	(footprint ""
		(layer "B.Cu")
		(at 382.016 -205.101952 -90)
		(property "Reference" "R420"
			(at 0 0 90)
			(layer "B.SilkS")
			(hide yes)
			(effects
				(font
					(size 1.27 1.27)
				)
				(justify mirror)
			)
		)
		(property "Value" ""
			(at 0 0 90)
			(layer "B.Fab")
			(effects
				(font
					(size 1.27 1.27)
				)
				(justify mirror)
			)
		)
		(duplicate_pad_numbers_are_jumpers no)
		(fp_line
			(start -0.7874 0.4064)
			(end 0.7874 0.4064)
			(stroke
				(width 0.1524)
				(type default)
			)
			(layer "B.SilkS")
		)
		(fp_line
			(start 0.7874 0.4064)
			(end 0.7874 -0.4064)
			(stroke
				(width 0.1524)
				(type default)
			)
			(layer "B.SilkS")
		)
		(fp_line
			(start -0.7874 -0.4064)
			(end -0.7874 0.4064)
			(stroke
				(width 0.1524)
				(type default)
			)
			(layer "B.SilkS")
		)
		(fp_line
			(start 0.7874 -0.4064)
			(end -0.7874 -0.4064)
			(stroke
				(width 0.1524)
				(type default)
			)
			(layer "B.SilkS")
		)
		(fp_line
			(start -0.67945 0.3048)
			(end -0.120396 0.3048)
			(stroke
				(width 0.1)
				(type default)
			)
			(layer "B.Fab")
		)
		(fp_line
			(start -0.120396 0.3048)
			(end -0.120396 0.2794)
			(stroke
				(width 0.1)
				(type default)
			)
			(layer "B.Fab")
		)
		(fp_line
			(start 0.12065 0.3048)
			(end 0.67945 0.3048)
			(stroke
				(width 0.1)
				(type default)
			)
			(layer "B.Fab")
		)
		(fp_line
			(start 0.67945 0.3048)
			(end 0.67945 -0.305054)
			(stroke
				(width 0.1)
				(type default)
			)
			(layer "B.Fab")
		)
		(fp_line
			(start -0.120396 0.2794)
			(end 0.12065 0.2794)
			(stroke
				(width 0.1)
				(type default)
			)
			(layer "B.Fab")
		)
		(fp_line
			(start 0.12065 0.2794)
			(end 0.12065 0.3048)
			(stroke
				(width 0.1)
				(type default)
			)
			(layer "B.Fab")
		)
		(fp_line
			(start -0.12065 -0.2794)
			(end -0.12065 -0.3048)
			(stroke
				(width 0.1)
				(type default)
			)
			(layer "B.Fab")
		)
		(fp_line
			(start 0.12065 -0.2794)
			(end -0.12065 -0.2794)
			(stroke
				(width 0.1)
				(type default)
			)
			(layer "B.Fab")
		)
		(fp_line
			(start -0.67945 -0.3048)
			(end -0.67945 0.3048)
			(stroke
				(width 0.1)
				(type default)
			)
			(layer "B.Fab")
		)
		(fp_line
			(start -0.12065 -0.3048)
			(end -0.67945 -0.3048)
			(stroke
				(width 0.1)
				(type default)
			)
			(layer "B.Fab")
		)
		(fp_line
			(start 0.12065 -0.305054)
			(end 0.12065 -0.2794)
			(stroke
				(width 0.1)
				(type default)
			)
			(layer "B.Fab")
		)
		(fp_line
			(start 0.67945 -0.305054)
			(end 0.12065 -0.305054)
			(stroke
				(width 0.1)
				(type default)
			)
			(layer "B.Fab")
		)
		(pad "1" smd circle
			(at 0.40005 0 90)
			(size 0 0)
			(layers "B.Cu" "B.Mask" "B.Paste")
			(net "PVDD11_S3_P0")
		)
		(pad "2" smd circle
			(at -0.40005 0 90)
			(size 0 0)
			(layers "B.Cu" "B.Mask" "B.Paste")
			(net "I3C_1_SPD_DDRGL_CPU0_R_SDA")
		)
	)
	(footprint ""
		(layer "B.Cu")
		(at 138.34872 -35.304222 -90)
		(property "Reference" "C6044"
			(at 0 0 90)
			(layer "B.SilkS")
			(hide yes)
			(effects
				(font
					(size 1.27 1.27)
				)
				(justify mirror)
			)
		)
		(property "Value" ""
			(at 0 0 90)
			(layer "B.Fab")
			(effects
				(font
					(size 1.27 1.27)
				)
				(justify mirror)
			)
		)
		(duplicate_pad_numbers_are_jumpers no)
		(fp_line
			(start -0.7874 0.4064)
			(end 0.7874 0.4064)
			(stroke
				(width 0.1524)
				(type default)
			)
			(layer "B.SilkS")
		)
		(fp_line
			(start 0.7874 0.4064)
			(end 0.7874 -0.4064)
			(stroke
				(width 0.1524)
				(type default)
			)
			(layer "B.SilkS")
		)
		(fp_line
			(start -0.7874 -0.4064)
			(end -0.7874 0.4064)
			(stroke
				(width 0.1524)
				(type default)
			)
			(layer "B.SilkS")
		)
		(fp_line
			(start 0.7874 -0.4064)
			(end -0.7874 -0.4064)
			(stroke
				(width 0.1524)
				(type default)
			)
			(layer "B.SilkS")
		)
		(fp_line
			(start -0.67945 0.3048)
			(end -0.120396 0.3048)
			(stroke
				(width 0.1)
				(type default)
			)
			(layer "B.Fab")
		)
		(fp_line
			(start -0.120396 0.3048)
			(end -0.120396 0.2794)
			(stroke
				(width 0.1)
				(type default)
			)
			(layer "B.Fab")
		)
		(fp_line
			(start 0.12065 0.3048)
			(end 0.67945 0.3048)
			(stroke
				(width 0.1)
				(type default)
			)
			(layer "B.Fab")
		)
		(fp_line
			(start 0.67945 0.3048)
			(end 0.67945 -0.305054)
			(stroke
				(width 0.1)
				(type default)
			)
			(layer "B.Fab")
		)
		(fp_line
			(start -0.120396 0.2794)
			(end 0.12065 0.2794)
			(stroke
				(width 0.1)
				(type default)
			)
			(layer "B.Fab")
		)
		(fp_line
			(start 0.12065 0.2794)
			(end 0.12065 0.3048)
			(stroke
				(width 0.1)
				(type default)
			)
			(layer "B.Fab")
		)
		(fp_line
			(start -0.12065 -0.2794)
			(end -0.12065 -0.3048)
			(stroke
				(width 0.1)
				(type default)
			)
			(layer "B.Fab")
		)
		(fp_line
			(start 0.12065 -0.2794)
			(end -0.12065 -0.2794)
			(stroke
				(width 0.1)
				(type default)
			)
			(layer "B.Fab")
		)
		(fp_line
			(start -0.67945 -0.3048)
			(end -0.67945 0.3048)
			(stroke
				(width 0.1)
				(type default)
			)
			(layer "B.Fab")
		)
		(fp_line
			(start -0.12065 -0.3048)
			(end -0.67945 -0.3048)
			(stroke
				(width 0.1)
				(type default)
			)
			(layer "B.Fab")
		)
		(fp_line
			(start 0.12065 -0.305054)
			(end 0.12065 -0.2794)
			(stroke
				(width 0.1)
				(type default)
			)
			(layer "B.Fab")
		)
		(fp_line
			(start 0.67945 -0.305054)
			(end 0.12065 -0.305054)
			(stroke
				(width 0.1)
				(type default)
			)
			(layer "B.Fab")
		)
		(pad "1" smd circle
			(at 0.40005 0 90)
			(size 0 0)
			(layers "B.Cu" "B.Mask" "B.Paste")
			(net "P3V3_AUX_CPU0_USB_AVDD33")
		)
		(pad "2" smd circle
			(at -0.40005 0 90)
			(size 0 0)
			(layers "B.Cu" "B.Mask" "B.Paste")
			(net "GND")
		)
	)
	(footprint ""
		(layer "B.Cu")
		(at 149.597872 -64.04229 90)
		(property "Reference" "R13"
			(at 0 0 90)
			(layer "B.SilkS")
			(hide yes)
			(effects
				(font
					(size 1.27 1.27)
				)
				(justify mirror)
			)
		)
		(property "Value" ""
			(at 0 0 90)
			(layer "B.Fab")
			(effects
				(font
					(size 1.27 1.27)
				)
				(justify mirror)
			)
		)
		(duplicate_pad_numbers_are_jumpers no)
		(fp_line
			(start 0.7874 -0.4064)
			(end -0.7874 -0.4064)
			(stroke
				(width 0.1524)
				(type default)
			)
			(layer "B.SilkS")
		)
		(fp_line
			(start -0.7874 -0.4064)
			(end -0.7874 0.4064)
			(stroke
				(width 0.1524)
				(type default)
			)
			(layer "B.SilkS")
		)
		(fp_line
			(start 0.7874 0.4064)
			(end 0.7874 -0.4064)
			(stroke
				(width 0.1524)
				(type default)
			)
			(layer "B.SilkS")
		)
		(fp_line
			(start -0.7874 0.4064)
			(end 0.7874 0.4064)
			(stroke
				(width 0.1524)
				(type default)
			)
			(layer "B.SilkS")
		)
		(fp_line
			(start 0.67945 -0.305054)
			(end 0.12065 -0.305054)
			(stroke
				(width 0.1)
				(type default)
			)
			(layer "B.Fab")
		)
		(fp_line
			(start 0.12065 -0.305054)
			(end 0.12065 -0.2794)
			(stroke
				(width 0.1)
				(type default)
			)
			(layer "B.Fab")
		)
		(fp_line
			(start -0.12065 -0.3048)
			(end -0.67945 -0.3048)
			(stroke
				(width 0.1)
				(type default)
			)
			(layer "B.Fab")
		)
		(fp_line
			(start -0.67945 -0.3048)
			(end -0.67945 0.3048)
			(stroke
				(width 0.1)
				(type default)
			)
			(layer "B.Fab")
		)
		(fp_line
			(start 0.12065 -0.2794)
			(end -0.12065 -0.2794)
			(stroke
				(width 0.1)
				(type default)
			)
			(layer "B.Fab")
		)
		(fp_line
			(start -0.12065 -0.2794)
			(end -0.12065 -0.3048)
			(stroke
				(width 0.1)
				(type default)
			)
			(layer "B.Fab")
		)
		(fp_line
			(start 0.12065 0.2794)
			(end 0.12065 0.3048)
			(stroke
				(width 0.1)
				(type default)
			)
			(layer "B.Fab")
		)
		(fp_line
			(start -0.120396 0.2794)
			(end 0.12065 0.2794)
			(stroke
				(width 0.1)
				(type default)
			)
			(layer "B.Fab")
		)
		(fp_line
			(start 0.67945 0.3048)
			(end 0.67945 -0.305054)
			(stroke
				(width 0.1)
				(type default)
			)
			(layer "B.Fab")
		)
		(fp_line
			(start 0.12065 0.3048)
			(end 0.67945 0.3048)
			(stroke
				(width 0.1)
				(type default)
			)
			(layer "B.Fab")
		)
		(fp_line
			(start -0.120396 0.3048)
			(end -0.120396 0.2794)
			(stroke
				(width 0.1)
				(type default)
			)
			(layer "B.Fab")
		)
		(fp_line
			(start -0.67945 0.3048)
			(end -0.120396 0.3048)
			(stroke
				(width 0.1)
				(type default)
			)
			(layer "B.Fab")
		)
		(pad "1" smd circle
			(at 0.40005 0 270)
			(size 0 0)
			(layers "B.Cu" "B.Mask" "B.Paste")
			(net "JTAG_PLD_TDO")
		)
		(pad "2" smd circle
			(at -0.40005 0 270)
			(size 0 0)
			(layers "B.Cu" "B.Mask" "B.Paste")
			(net "JTAG_SCM_PLD_TDO")
		)
	)
	(footprint ""
		(layer "B.Cu")
		(at 371.691154 -398.942052 90)
		(property "Reference" "C1030"
			(at 0 0 90)
			(layer "B.SilkS")
			(hide yes)
			(effects
				(font
					(size 1.27 1.27)
				)
				(justify mirror)
			)
		)
		(property "Value" ""
			(at 0 0 90)
			(layer "B.Fab")
			(effects
				(font
					(size 1.27 1.27)
				)
				(justify mirror)
			)
		)
		(duplicate_pad_numbers_are_jumpers no)
		(fp_line
			(start 0.7874 -0.4064)
			(end -0.7874 -0.4064)
			(stroke
				(width 0.1524)
				(type default)
			)
			(layer "B.SilkS")
		)
		(fp_line
			(start -0.7874 -0.4064)
			(end -0.7874 0.4064)
			(stroke
				(width 0.1524)
				(type default)
			)
			(layer "B.SilkS")
		)
		(fp_line
			(start 0.7874 0.4064)
			(end 0.7874 -0.4064)
			(stroke
				(width 0.1524)
				(type default)
			)
			(layer "B.SilkS")
		)
		(fp_line
			(start -0.7874 0.4064)
			(end 0.7874 0.4064)
			(stroke
				(width 0.1524)
				(type default)
			)
			(layer "B.SilkS")
		)
		(fp_line
			(start 0.67945 -0.305054)
			(end 0.12065 -0.305054)
			(stroke
				(width 0.1)
				(type default)
			)
			(layer "B.Fab")
		)
		(fp_line
			(start 0.12065 -0.305054)
			(end 0.12065 -0.2794)
			(stroke
				(width 0.1)
				(type default)
			)
			(layer "B.Fab")
		)
		(fp_line
			(start -0.12065 -0.3048)
			(end -0.67945 -0.3048)
			(stroke
				(width 0.1)
				(type default)
			)
			(layer "B.Fab")
		)
		(fp_line
			(start -0.67945 -0.3048)
			(end -0.67945 0.3048)
			(stroke
				(width 0.1)
				(type default)
			)
			(layer "B.Fab")
		)
		(fp_line
			(start 0.12065 -0.2794)
			(end -0.12065 -0.2794)
			(stroke
				(width 0.1)
				(type default)
			)
			(layer "B.Fab")
		)
		(fp_line
			(start -0.12065 -0.2794)
			(end -0.12065 -0.3048)
			(stroke
				(width 0.1)
				(type default)
			)
			(layer "B.Fab")
		)
		(fp_line
			(start 0.12065 0.2794)
			(end 0.12065 0.3048)
			(stroke
				(width 0.1)
				(type default)
			)
			(layer "B.Fab")
		)
		(fp_line
			(start -0.120396 0.2794)
			(end 0.12065 0.2794)
			(stroke
				(width 0.1)
				(type default)
			)
			(layer "B.Fab")
		)
		(fp_line
			(start 0.67945 0.3048)
			(end 0.67945 -0.305054)
			(stroke
				(width 0.1)
				(type default)
			)
			(layer "B.Fab")
		)
		(fp_line
			(start 0.12065 0.3048)
			(end 0.67945 0.3048)
			(stroke
				(width 0.1)
				(type default)
			)
			(layer "B.Fab")
		)
		(fp_line
			(start -0.120396 0.3048)
			(end -0.120396 0.2794)
			(stroke
				(width 0.1)
				(type default)
			)
			(layer "B.Fab")
		)
		(fp_line
			(start -0.67945 0.3048)
			(end -0.120396 0.3048)
			(stroke
				(width 0.1)
				(type default)
			)
			(layer "B.Fab")
		)
		(pad "1" smd circle
			(at 0.40005 0 270)
			(size 0 0)
			(layers "B.Cu" "B.Mask" "B.Paste")
			(net "P0V9_CPU0_RT3_2A")
		)
		(pad "2" smd circle
			(at -0.40005 0 270)
			(size 0 0)
			(layers "B.Cu" "B.Mask" "B.Paste")
			(net "GND")
		)
	)
	(footprint ""
		(layer "B.Cu")
		(at 125.389386 -254.194564)
		(property "Reference" "C2452"
			(at 0 0 0)
			(layer "B.SilkS")
			(hide yes)
			(effects
				(font
					(size 1.27 1.27)
				)
				(justify mirror)
			)
		)
		(property "Value" ""
			(at 0 0 0)
			(layer "B.Fab")
			(effects
				(font
					(size 1.27 1.27)
				)
				(justify mirror)
			)
		)
		(duplicate_pad_numbers_are_jumpers no)
		(fp_line
			(start -0.7874 -0.4064)
			(end -0.7874 0.4064)
			(stroke
				(width 0.1524)
				(type default)
			)
			(layer "B.SilkS")
		)
		(fp_line
			(start -0.7874 0.4064)
			(end 0.7874 0.4064)
			(stroke
				(width 0.1524)
				(type default)
			)
			(layer "B.SilkS")
		)
		(fp_line
			(start 0.7874 -0.4064)
			(end -0.7874 -0.4064)
			(stroke
				(width 0.1524)
				(type default)
			)
			(layer "B.SilkS")
		)
		(fp_line
			(start 0.7874 0.4064)
			(end 0.7874 -0.4064)
			(stroke
				(width 0.1524)
				(type default)
			)
			(layer "B.SilkS")
		)
		(fp_line
			(start -0.67945 -0.3048)
			(end -0.67945 0.3048)
			(stroke
				(width 0.1)
				(type default)
			)
			(layer "B.Fab")
		)
		(fp_line
			(start -0.67945 0.3048)
			(end -0.120396 0.3048)
			(stroke
				(width 0.1)
				(type default)
			)
			(layer "B.Fab")
		)
		(fp_line
			(start -0.12065 -0.3048)
			(end -0.67945 -0.3048)
			(stroke
				(width 0.1)
				(type default)
			)
			(layer "B.Fab")
		)
		(fp_line
			(start -0.12065 -0.2794)
			(end -0.12065 -0.3048)
			(stroke
				(width 0.1)
				(type default)
			)
			(layer "B.Fab")
		)
		(fp_line
			(start -0.120396 0.2794)
			(end 0.12065 0.2794)
			(stroke
				(width 0.1)
				(type default)
			)
			(layer "B.Fab")
		)
		(fp_line
			(start -0.120396 0.3048)
			(end -0.120396 0.2794)
			(stroke
				(width 0.1)
				(type default)
			)
			(layer "B.Fab")
		)
		(fp_line
			(start 0.12065 -0.305054)
			(end 0.12065 -0.2794)
			(stroke
				(width 0.1)
				(type default)
			)
			(layer "B.Fab")
		)
		(fp_line
			(start 0.12065 -0.2794)
			(end -0.12065 -0.2794)
			(stroke
				(width 0.1)
				(type default)
			)
			(layer "B.Fab")
		)
		(fp_line
			(start 0.12065 0.2794)
			(end 0.12065 0.3048)
			(stroke
				(width 0.1)
				(type default)
			)
			(layer "B.Fab")
		)
		(fp_line
			(start 0.12065 0.3048)
			(end 0.67945 0.3048)
			(stroke
				(width 0.1)
				(type default)
			)
			(layer "B.Fab")
		)
		(fp_line
			(start 0.67945 -0.305054)
			(end 0.12065 -0.305054)
			(stroke
				(width 0.1)
				(type default)
			)
			(layer "B.Fab")
		)
		(fp_line
			(start 0.67945 0.3048)
			(end 0.67945 -0.305054)
			(stroke
				(width 0.1)
				(type default)
			)
			(layer "B.Fab")
		)
		(pad "1" smd circle
			(at 0.40005 0 180)
			(size 0 0)
			(layers "B.Cu" "B.Mask" "B.Paste")
			(net "PVDDCR_SOC_P1")
		)
		(pad "2" smd circle
			(at -0.40005 0 180)
			(size 0 0)
			(layers "B.Cu" "B.Mask" "B.Paste")
			(net "GND")
		)
	)
	(footprint ""
		(layer "B.Cu")
		(at 372.937278 -142.488158)
		(property "Reference" "PC466"
			(at 0 0 0)
			(layer "B.SilkS")
			(hide yes)
			(effects
				(font
					(size 1.27 1.27)
				)
				(justify mirror)
			)
		)
		(property "Value" ""
			(at 0 0 0)
			(layer "B.Fab")
			(effects
				(font
					(size 1.27 1.27)
				)
				(justify mirror)
			)
		)
		(duplicate_pad_numbers_are_jumpers no)
		(fp_line
			(start -0.7874 -0.4064)
			(end -0.7874 0.4064)
			(stroke
				(width 0.1524)
				(type default)
			)
			(layer "B.SilkS")
		)
		(fp_line
			(start -0.7874 0.4064)
			(end 0.7874 0.4064)
			(stroke
				(width 0.1524)
				(type default)
			)
			(layer "B.SilkS")
		)
		(fp_line
			(start 0.7874 -0.4064)
			(end -0.7874 -0.4064)
			(stroke
				(width 0.1524)
				(type default)
			)
			(layer "B.SilkS")
		)
		(fp_line
			(start 0.7874 0.4064)
			(end 0.7874 -0.4064)
			(stroke
				(width 0.1524)
				(type default)
			)
			(layer "B.SilkS")
		)
		(fp_line
			(start -0.67945 -0.3048)
			(end -0.67945 0.3048)
			(stroke
				(width 0.1)
				(type default)
			)
			(layer "B.Fab")
		)
		(fp_line
			(start -0.67945 0.3048)
			(end -0.120396 0.3048)
			(stroke
				(width 0.1)
				(type default)
			)
			(layer "B.Fab")
		)
		(fp_line
			(start -0.12065 -0.3048)
			(end -0.67945 -0.3048)
			(stroke
				(width 0.1)
				(type default)
			)
			(layer "B.Fab")
		)
		(fp_line
			(start -0.12065 -0.2794)
			(end -0.12065 -0.3048)
			(stroke
				(width 0.1)
				(type default)
			)
			(layer "B.Fab")
		)
		(fp_line
			(start -0.120396 0.2794)
			(end 0.12065 0.2794)
			(stroke
				(width 0.1)
				(type default)
			)
			(layer "B.Fab")
		)
		(fp_line
			(start -0.120396 0.3048)
			(end -0.120396 0.2794)
			(stroke
				(width 0.1)
				(type default)
			)
			(layer "B.Fab")
		)
		(fp_line
			(start 0.12065 -0.305054)
			(end 0.12065 -0.2794)
			(stroke
				(width 0.1)
				(type default)
			)
			(layer "B.Fab")
		)
		(fp_line
			(start 0.12065 -0.2794)
			(end -0.12065 -0.2794)
			(stroke
				(width 0.1)
				(type default)
			)
			(layer "B.Fab")
		)
		(fp_line
			(start 0.12065 0.2794)
			(end 0.12065 0.3048)
			(stroke
				(width 0.1)
				(type default)
			)
			(layer "B.Fab")
		)
		(fp_line
			(start 0.12065 0.3048)
			(end 0.67945 0.3048)
			(stroke
				(width 0.1)
				(type default)
			)
			(layer "B.Fab")
		)
		(fp_line
			(start 0.67945 -0.305054)
			(end 0.12065 -0.305054)
			(stroke
				(width 0.1)
				(type default)
			)
			(layer "B.Fab")
		)
		(fp_line
			(start 0.67945 0.3048)
			(end 0.67945 -0.305054)
			(stroke
				(width 0.1)
				(type default)
			)
			(layer "B.Fab")
		)
		(pad "1" smd circle
			(at 0.40005 0 180)
			(size 0 0)
			(layers "B.Cu" "B.Mask" "B.Paste")
			(net "PVDD18_S5_P0")
		)
		(pad "2" smd circle
			(at -0.40005 0 180)
			(size 0 0)
			(layers "B.Cu" "B.Mask" "B.Paste")
			(net "GND")
		)
	)
	(footprint ""
		(layer "B.Cu")
		(at 144.3228 -13.765022 90)
		(property "Reference" "R6033"
			(at 0 0 90)
			(layer "B.SilkS")
			(hide yes)
			(effects
				(font
					(size 1.27 1.27)
				)
				(justify mirror)
			)
		)
		(property "Value" ""
			(at 0 0 90)
			(layer "B.Fab")
			(effects
				(font
					(size 1.27 1.27)
				)
				(justify mirror)
			)
		)
		(duplicate_pad_numbers_are_jumpers no)
		(fp_line
			(start 0.7874 -0.4064)
			(end -0.7874 -0.4064)
			(stroke
				(width 0.1524)
				(type default)
			)
			(layer "B.SilkS")
		)
		(fp_line
			(start -0.7874 -0.4064)
			(end -0.7874 0.4064)
			(stroke
				(width 0.1524)
				(type default)
			)
			(layer "B.SilkS")
		)
		(fp_line
			(start 0.7874 0.4064)
			(end 0.7874 -0.4064)
			(stroke
				(width 0.1524)
				(type default)
			)
			(layer "B.SilkS")
		)
		(fp_line
			(start -0.7874 0.4064)
			(end 0.7874 0.4064)
			(stroke
				(width 0.1524)
				(type default)
			)
			(layer "B.SilkS")
		)
		(fp_line
			(start 0.67945 -0.305054)
			(end 0.12065 -0.305054)
			(stroke
				(width 0.1)
				(type default)
			)
			(layer "B.Fab")
		)
		(fp_line
			(start 0.12065 -0.305054)
			(end 0.12065 -0.2794)
			(stroke
				(width 0.1)
				(type default)
			)
			(layer "B.Fab")
		)
		(fp_line
			(start -0.12065 -0.3048)
			(end -0.67945 -0.3048)
			(stroke
				(width 0.1)
				(type default)
			)
			(layer "B.Fab")
		)
		(fp_line
			(start -0.67945 -0.3048)
			(end -0.67945 0.3048)
			(stroke
				(width 0.1)
				(type default)
			)
			(layer "B.Fab")
		)
		(fp_line
			(start 0.12065 -0.2794)
			(end -0.12065 -0.2794)
			(stroke
				(width 0.1)
				(type default)
			)
			(layer "B.Fab")
		)
		(fp_line
			(start -0.12065 -0.2794)
			(end -0.12065 -0.3048)
			(stroke
				(width 0.1)
				(type default)
			)
			(layer "B.Fab")
		)
		(fp_line
			(start 0.12065 0.2794)
			(end 0.12065 0.3048)
			(stroke
				(width 0.1)
				(type default)
			)
			(layer "B.Fab")
		)
		(fp_line
			(start -0.120396 0.2794)
			(end 0.12065 0.2794)
			(stroke
				(width 0.1)
				(type default)
			)
			(layer "B.Fab")
		)
		(fp_line
			(start 0.67945 0.3048)
			(end 0.67945 -0.305054)
			(stroke
				(width 0.1)
				(type default)
			)
			(layer "B.Fab")
		)
		(fp_line
			(start 0.12065 0.3048)
			(end 0.67945 0.3048)
			(stroke
				(width 0.1)
				(type default)
			)
			(layer "B.Fab")
		)
		(fp_line
			(start -0.120396 0.3048)
			(end -0.120396 0.2794)
			(stroke
				(width 0.1)
				(type default)
			)
			(layer "B.Fab")
		)
		(fp_line
			(start -0.67945 0.3048)
			(end -0.120396 0.3048)
			(stroke
				(width 0.1)
				(type default)
			)
			(layer "B.Fab")
		)
		(pad "1" smd circle
			(at 0.40005 0 270)
			(size 0 0)
			(layers "B.Cu" "B.Mask" "B.Paste")
			(net "RST_MB_STBY_N")
		)
		(pad "2" smd circle
			(at -0.40005 0 270)
			(size 0 0)
			(layers "B.Cu" "B.Mask" "B.Paste")
			(net "RST_MB_STBY_R_N")
		)
	)
	(footprint ""
		(layer "B.Cu")
		(at 288.200846 -420.38143 90)
		(property "Reference" "C2329"
			(at 0 0 90)
			(layer "B.SilkS")
			(hide yes)
			(effects
				(font
					(size 1.27 1.27)
				)
				(justify mirror)
			)
		)
		(property "Value" ""
			(at 0 0 90)
			(layer "B.Fab")
			(effects
				(font
					(size 1.27 1.27)
				)
				(justify mirror)
			)
		)
		(duplicate_pad_numbers_are_jumpers no)
		(fp_line
			(start 0.7874 -0.4064)
			(end -0.7874 -0.4064)
			(stroke
				(width 0.1524)
				(type default)
			)
			(layer "B.SilkS")
		)
		(fp_line
			(start -0.7874 -0.4064)
			(end -0.7874 0.4064)
			(stroke
				(width 0.1524)
				(type default)
			)
			(layer "B.SilkS")
		)
		(fp_line
			(start 0.7874 0.4064)
			(end 0.7874 -0.4064)
			(stroke
				(width 0.1524)
				(type default)
			)
			(layer "B.SilkS")
		)
		(fp_line
			(start -0.7874 0.4064)
			(end 0.7874 0.4064)
			(stroke
				(width 0.1524)
				(type default)
			)
			(layer "B.SilkS")
		)
		(fp_line
			(start 0.67945 -0.305054)
			(end 0.12065 -0.305054)
			(stroke
				(width 0.1)
				(type default)
			)
			(layer "B.Fab")
		)
		(fp_line
			(start 0.12065 -0.305054)
			(end 0.12065 -0.2794)
			(stroke
				(width 0.1)
				(type default)
			)
			(layer "B.Fab")
		)
		(fp_line
			(start -0.12065 -0.3048)
			(end -0.67945 -0.3048)
			(stroke
				(width 0.1)
				(type default)
			)
			(layer "B.Fab")
		)
		(fp_line
			(start -0.67945 -0.3048)
			(end -0.67945 0.3048)
			(stroke
				(width 0.1)
				(type default)
			)
			(layer "B.Fab")
		)
		(fp_line
			(start 0.12065 -0.2794)
			(end -0.12065 -0.2794)
			(stroke
				(width 0.1)
				(type default)
			)
			(layer "B.Fab")
		)
		(fp_line
			(start -0.12065 -0.2794)
			(end -0.12065 -0.3048)
			(stroke
				(width 0.1)
				(type default)
			)
			(layer "B.Fab")
		)
		(fp_line
			(start 0.12065 0.2794)
			(end 0.12065 0.3048)
			(stroke
				(width 0.1)
				(type default)
			)
			(layer "B.Fab")
		)
		(fp_line
			(start -0.120396 0.2794)
			(end 0.12065 0.2794)
			(stroke
				(width 0.1)
				(type default)
			)
			(layer "B.Fab")
		)
		(fp_line
			(start 0.67945 0.3048)
			(end 0.67945 -0.305054)
			(stroke
				(width 0.1)
				(type default)
			)
			(layer "B.Fab")
		)
		(fp_line
			(start 0.12065 0.3048)
			(end 0.67945 0.3048)
			(stroke
				(width 0.1)
				(type default)
			)
			(layer "B.Fab")
		)
		(fp_line
			(start -0.120396 0.3048)
			(end -0.120396 0.2794)
			(stroke
				(width 0.1)
				(type default)
			)
			(layer "B.Fab")
		)
		(fp_line
			(start -0.67945 0.3048)
			(end -0.120396 0.3048)
			(stroke
				(width 0.1)
				(type default)
			)
			(layer "B.Fab")
		)
		(pad "1" smd circle
			(at 0.40005 0 270)
			(size 0 0)
			(layers "B.Cu" "B.Mask" "B.Paste")
			(net "P3V3_9ZXL045_P0_VDD")
		)
		(pad "2" smd circle
			(at -0.40005 0 270)
			(size 0 0)
			(layers "B.Cu" "B.Mask" "B.Paste")
			(net "GND")
		)
	)
	(footprint ""
		(layer "B.Cu")
		(at 47.17288 -385.50088 -90)
		(property "Reference" "C186"
			(at 0 0 90)
			(layer "B.SilkS")
			(hide yes)
			(effects
				(font
					(size 1.27 1.27)
				)
				(justify mirror)
			)
		)
		(property "Value" ""
			(at 0 0 90)
			(layer "B.Fab")
			(effects
				(font
					(size 1.27 1.27)
				)
				(justify mirror)
			)
		)
		(duplicate_pad_numbers_are_jumpers no)
		(fp_line
			(start -0.299974 0.150114)
			(end 0.299974 0.150114)
			(stroke
				(width 0.1)
				(type default)
			)
			(layer "B.Fab")
		)
		(fp_line
			(start 0.299974 0.150114)
			(end 0.299974 -0.150114)
			(stroke
				(width 0.1)
				(type default)
			)
			(layer "B.Fab")
		)
		(fp_line
			(start -0.299974 -0.150114)
			(end -0.299974 0.150114)
			(stroke
				(width 0.1)
				(type default)
			)
			(layer "B.Fab")
		)
		(fp_line
			(start 0.299974 -0.150114)
			(end -0.299974 -0.150114)
			(stroke
				(width 0.1)
				(type default)
			)
			(layer "B.Fab")
		)
		(pad "1" smd rect
			(at 0.2667 0 90)
			(size 0.3048 0.381)
			(layers "B.Cu" "B.Mask" "B.Paste")
			(net "P0V9_CPU1_RT0_2A")
		)
		(pad "2" smd rect
			(at -0.2667 0 90)
			(size 0.3048 0.381)
			(layers "B.Cu" "B.Mask" "B.Paste")
			(net "GND")
		)
	)
	(footprint ""
		(layer "B.Cu")
		(at 363.645958 -259.845048 180)
		(property "Reference" "C2624"
			(at 0 0 0)
			(layer "B.SilkS")
			(hide yes)
			(effects
				(font
					(size 1.27 1.27)
				)
				(justify mirror)
			)
		)
		(property "Value" ""
			(at 0 0 0)
			(layer "B.Fab")
			(effects
				(font
					(size 1.27 1.27)
				)
				(justify mirror)
			)
		)
		(duplicate_pad_numbers_are_jumpers no)
		(fp_line
			(start 0.7874 0.4064)
			(end 0.7874 -0.4064)
			(stroke
				(width 0.1524)
				(type default)
			)
			(layer "B.SilkS")
		)
		(fp_line
			(start 0.7874 -0.4064)
			(end -0.7874 -0.4064)
			(stroke
				(width 0.1524)
				(type default)
			)
			(layer "B.SilkS")
		)
		(fp_line
			(start -0.7874 0.4064)
			(end 0.7874 0.4064)
			(stroke
				(width 0.1524)
				(type default)
			)
			(layer "B.SilkS")
		)
		(fp_line
			(start -0.7874 -0.4064)
			(end -0.7874 0.4064)
			(stroke
				(width 0.1524)
				(type default)
			)
			(layer "B.SilkS")
		)
		(fp_line
			(start 0.67945 0.3048)
			(end 0.67945 -0.305054)
			(stroke
				(width 0.1)
				(type default)
			)
			(layer "B.Fab")
		)
		(fp_line
			(start 0.67945 -0.305054)
			(end 0.12065 -0.305054)
			(stroke
				(width 0.1)
				(type default)
			)
			(layer "B.Fab")
		)
		(fp_line
			(start 0.12065 0.3048)
			(end 0.67945 0.3048)
			(stroke
				(width 0.1)
				(type default)
			)
			(layer "B.Fab")
		)
		(fp_line
			(start 0.12065 0.2794)
			(end 0.12065 0.3048)
			(stroke
				(width 0.1)
				(type default)
			)
			(layer "B.Fab")
		)
		(fp_line
			(start 0.12065 -0.2794)
			(end -0.12065 -0.2794)
			(stroke
				(width 0.1)
				(type default)
			)
			(layer "B.Fab")
		)
		(fp_line
			(start 0.12065 -0.305054)
			(end 0.12065 -0.2794)
			(stroke
				(width 0.1)
				(type default)
			)
			(layer "B.Fab")
		)
		(fp_line
			(start -0.120396 0.3048)
			(end -0.120396 0.2794)
			(stroke
				(width 0.1)
				(type default)
			)
			(layer "B.Fab")
		)
		(fp_line
			(start -0.120396 0.2794)
			(end 0.12065 0.2794)
			(stroke
				(width 0.1)
				(type default)
			)
			(layer "B.Fab")
		)
		(fp_line
			(start -0.12065 -0.2794)
			(end -0.12065 -0.3048)
			(stroke
				(width 0.1)
				(type default)
			)
			(layer "B.Fab")
		)
		(fp_line
			(start -0.12065 -0.3048)
			(end -0.67945 -0.3048)
			(stroke
				(width 0.1)
				(type default)
			)
			(layer "B.Fab")
		)
		(fp_line
			(start -0.67945 0.3048)
			(end -0.120396 0.3048)
			(stroke
				(width 0.1)
				(type default)
			)
			(layer "B.Fab")
		)
		(fp_line
			(start -0.67945 -0.3048)
			(end -0.67945 0.3048)
			(stroke
				(width 0.1)
				(type default)
			)
			(layer "B.Fab")
		)
		(pad "1" smd circle
			(at 0.40005 0)
			(size 0 0)
			(layers "B.Cu" "B.Mask" "B.Paste")
			(net "PVDD11_S3_P0")
		)
		(pad "2" smd circle
			(at -0.40005 0)
			(size 0 0)
			(layers "B.Cu" "B.Mask" "B.Paste")
			(net "GND")
		)
	)
	(footprint ""
		(layer "B.Cu")
		(at 345.645994 -396.393162 -90)
		(property "Reference" "C606"
			(at 0 0 90)
			(layer "B.SilkS")
			(hide yes)
			(effects
				(font
					(size 1.27 1.27)
				)
				(justify mirror)
			)
		)
		(property "Value" ""
			(at 0 0 90)
			(layer "B.Fab")
			(effects
				(font
					(size 1.27 1.27)
				)
				(justify mirror)
			)
		)
		(duplicate_pad_numbers_are_jumpers no)
		(fp_line
			(start -0.299974 0.150114)
			(end 0.299974 0.150114)
			(stroke
				(width 0.1)
				(type default)
			)
			(layer "B.Fab")
		)
		(fp_line
			(start 0.299974 0.150114)
			(end 0.299974 -0.150114)
			(stroke
				(width 0.1)
				(type default)
			)
			(layer "B.Fab")
		)
		(fp_line
			(start -0.299974 -0.150114)
			(end -0.299974 0.150114)
			(stroke
				(width 0.1)
				(type default)
			)
			(layer "B.Fab")
		)
		(fp_line
			(start 0.299974 -0.150114)
			(end -0.299974 -0.150114)
			(stroke
				(width 0.1)
				(type default)
			)
			(layer "B.Fab")
		)
		(pad "1" smd rect
			(at 0.2667 0 90)
			(size 0.3048 0.381)
			(layers "B.Cu" "B.Mask" "B.Paste")
			(net "P1V8_CPU0_RT1_1A")
		)
		(pad "2" smd rect
			(at -0.2667 0 90)
			(size 0.3048 0.381)
			(layers "B.Cu" "B.Mask" "B.Paste")
			(net "GND")
		)
	)
	(footprint ""
		(layer "B.Cu")
		(at 59.428126 -192.66027)
		(property "Reference" "C174"
			(at 0 0 0)
			(layer "B.SilkS")
			(hide yes)
			(effects
				(font
					(size 1.27 1.27)
				)
				(justify mirror)
			)
		)
		(property "Value" ""
			(at 0 0 0)
			(layer "B.Fab")
			(effects
				(font
					(size 1.27 1.27)
				)
				(justify mirror)
			)
		)
		(duplicate_pad_numbers_are_jumpers no)
		(fp_line
			(start -1.524 -0.762)
			(end -1.524 0.762)
			(stroke
				(width 0.1524)
				(type default)
			)
			(layer "B.SilkS")
		)
		(fp_line
			(start -1.524 0.762)
			(end 1.524 0.762)
			(stroke
				(width 0.1524)
				(type default)
			)
			(layer "B.SilkS")
		)
		(fp_line
			(start 1.524 -0.762)
			(end -1.524 -0.762)
			(stroke
				(width 0.1524)
				(type default)
			)
			(layer "B.SilkS")
		)
		(fp_line
			(start 1.524 0.762)
			(end 1.524 -0.762)
			(stroke
				(width 0.1524)
				(type default)
			)
			(layer "B.SilkS")
		)
		(fp_line
			(start -1.1049 -0.724916)
			(end 1.1049 -0.724916)
			(stroke
				(width 0.1)
				(type default)
			)
			(layer "B.Fab")
		)
		(fp_line
			(start -1.1049 0.724916)
			(end -1.1049 -0.724916)
			(stroke
				(width 0.1)
				(type default)
			)
			(layer "B.Fab")
		)
		(fp_line
			(start 1.1049 -0.724916)
			(end 1.1049 0.724916)
			(stroke
				(width 0.1)
				(type default)
			)
			(layer "B.Fab")
		)
		(fp_line
			(start 1.1049 0.724916)
			(end -1.1049 0.724916)
			(stroke
				(width 0.1)
				(type default)
			)
			(layer "B.Fab")
		)
		(pad "1" smd rect
			(at 0.889 0)
			(size 1.016 1.27)
			(layers "B.Cu" "B.Mask" "B.Paste")
			(net "P12V_MEM_CPU1")
		)
		(pad "2" smd rect
			(at -0.889 0)
			(size 1.016 1.27)
			(layers "B.Cu" "B.Mask" "B.Paste")
			(net "GND")
		)
	)
	(footprint ""
		(layer "B.Cu")
		(at 98.046286 -388.011162 -90)
		(property "Reference" "C291"
			(at 0 0 90)
			(layer "B.SilkS")
			(hide yes)
			(effects
				(font
					(size 1.27 1.27)
				)
				(justify mirror)
			)
		)
		(property "Value" ""
			(at 0 0 90)
			(layer "B.Fab")
			(effects
				(font
					(size 1.27 1.27)
				)
				(justify mirror)
			)
		)
		(duplicate_pad_numbers_are_jumpers no)
		(fp_line
			(start -0.299974 0.150114)
			(end 0.299974 0.150114)
			(stroke
				(width 0.1)
				(type default)
			)
			(layer "B.Fab")
		)
		(fp_line
			(start 0.299974 0.150114)
			(end 0.299974 -0.150114)
			(stroke
				(width 0.1)
				(type default)
			)
			(layer "B.Fab")
		)
		(fp_line
			(start -0.299974 -0.150114)
			(end -0.299974 0.150114)
			(stroke
				(width 0.1)
				(type default)
			)
			(layer "B.Fab")
		)
		(fp_line
			(start 0.299974 -0.150114)
			(end -0.299974 -0.150114)
			(stroke
				(width 0.1)
				(type default)
			)
			(layer "B.Fab")
		)
		(pad "1" smd rect
			(at 0.2667 0 90)
			(size 0.3048 0.381)
			(layers "B.Cu" "B.Mask" "B.Paste")
			(net "P0V9_CPU1_RT1_2A")
		)
		(pad "2" smd rect
			(at -0.2667 0 90)
			(size 0.3048 0.381)
			(layers "B.Cu" "B.Mask" "B.Paste")
			(net "GND")
		)
	)
	(footprint ""
		(layer "B.Cu")
		(at 230.886 -330.708 180)
		(property "Reference" "R6779"
			(at 0 0 0)
			(layer "B.SilkS")
			(hide yes)
			(effects
				(font
					(size 1.27 1.27)
				)
				(justify mirror)
			)
		)
		(property "Value" ""
			(at 0 0 0)
			(layer "B.Fab")
			(effects
				(font
					(size 1.27 1.27)
				)
				(justify mirror)
			)
		)
		(duplicate_pad_numbers_are_jumpers no)
		(fp_line
			(start 0.32512 0.175006)
			(end 0.32512 -0.175006)
			(stroke
				(width 0.1)
				(type default)
			)
			(layer "B.Fab")
		)
		(fp_line
			(start 0.32512 -0.175006)
			(end -0.32512 -0.175006)
			(stroke
				(width 0.1)
				(type default)
			)
			(layer "B.Fab")
		)
		(fp_line
			(start -0.32512 0.175006)
			(end 0.32512 0.175006)
			(stroke
				(width 0.1)
				(type default)
			)
			(layer "B.Fab")
		)
		(fp_line
			(start -0.32512 -0.175006)
			(end -0.32512 0.175006)
			(stroke
				(width 0.1)
				(type default)
			)
			(layer "B.Fab")
		)
		(pad "1" smd rect
			(at 0.2667 0)
			(size 0.3048 0.381)
			(layers "B.Cu" "B.Mask" "B.Paste")
			(net "SMB_MUX_RT_SDA")
		)
		(pad "2" smd rect
			(at -0.2667 0 180)
			(size 0.3048 0.381)
			(layers "B.Cu" "B.Mask" "B.Paste")
			(net "SMB_MUX_RT_R1_SDA")
		)
	)
	(footprint ""
		(layer "B.Cu")
		(at 108.625894 -256.012442 -90)
		(property "Reference" "C2417"
			(at 0 0 90)
			(layer "B.SilkS")
			(hide yes)
			(effects
				(font
					(size 1.27 1.27)
				)
				(justify mirror)
			)
		)
		(property "Value" ""
			(at 0 0 90)
			(layer "B.Fab")
			(effects
				(font
					(size 1.27 1.27)
				)
				(justify mirror)
			)
		)
		(duplicate_pad_numbers_are_jumpers no)
		(fp_line
			(start -0.7874 0.4064)
			(end 0.7874 0.4064)
			(stroke
				(width 0.1524)
				(type default)
			)
			(layer "B.SilkS")
		)
		(fp_line
			(start 0.7874 0.4064)
			(end 0.7874 -0.4064)
			(stroke
				(width 0.1524)
				(type default)
			)
			(layer "B.SilkS")
		)
		(fp_line
			(start -0.7874 -0.4064)
			(end -0.7874 0.4064)
			(stroke
				(width 0.1524)
				(type default)
			)
			(layer "B.SilkS")
		)
		(fp_line
			(start 0.7874 -0.4064)
			(end -0.7874 -0.4064)
			(stroke
				(width 0.1524)
				(type default)
			)
			(layer "B.SilkS")
		)
		(fp_line
			(start -0.67945 0.3048)
			(end -0.120396 0.3048)
			(stroke
				(width 0.1)
				(type default)
			)
			(layer "B.Fab")
		)
		(fp_line
			(start -0.120396 0.3048)
			(end -0.120396 0.2794)
			(stroke
				(width 0.1)
				(type default)
			)
			(layer "B.Fab")
		)
		(fp_line
			(start 0.12065 0.3048)
			(end 0.67945 0.3048)
			(stroke
				(width 0.1)
				(type default)
			)
			(layer "B.Fab")
		)
		(fp_line
			(start 0.67945 0.3048)
			(end 0.67945 -0.305054)
			(stroke
				(width 0.1)
				(type default)
			)
			(layer "B.Fab")
		)
		(fp_line
			(start -0.120396 0.2794)
			(end 0.12065 0.2794)
			(stroke
				(width 0.1)
				(type default)
			)
			(layer "B.Fab")
		)
		(fp_line
			(start 0.12065 0.2794)
			(end 0.12065 0.3048)
			(stroke
				(width 0.1)
				(type default)
			)
			(layer "B.Fab")
		)
		(fp_line
			(start -0.12065 -0.2794)
			(end -0.12065 -0.3048)
			(stroke
				(width 0.1)
				(type default)
			)
			(layer "B.Fab")
		)
		(fp_line
			(start 0.12065 -0.2794)
			(end -0.12065 -0.2794)
			(stroke
				(width 0.1)
				(type default)
			)
			(layer "B.Fab")
		)
		(fp_line
			(start -0.67945 -0.3048)
			(end -0.67945 0.3048)
			(stroke
				(width 0.1)
				(type default)
			)
			(layer "B.Fab")
		)
		(fp_line
			(start -0.12065 -0.3048)
			(end -0.67945 -0.3048)
			(stroke
				(width 0.1)
				(type default)
			)
			(layer "B.Fab")
		)
		(fp_line
			(start 0.12065 -0.305054)
			(end 0.12065 -0.2794)
			(stroke
				(width 0.1)
				(type default)
			)
			(layer "B.Fab")
		)
		(fp_line
			(start 0.67945 -0.305054)
			(end 0.12065 -0.305054)
			(stroke
				(width 0.1)
				(type default)
			)
			(layer "B.Fab")
		)
		(pad "1" smd circle
			(at 0.40005 0 90)
			(size 0 0)
			(layers "B.Cu" "B.Mask" "B.Paste")
			(net "PVDDCR_SOC_P1")
		)
		(pad "2" smd circle
			(at -0.40005 0 90)
			(size 0 0)
			(layers "B.Cu" "B.Mask" "B.Paste")
			(net "GND")
		)
	)
	(footprint ""
		(layer "B.Cu")
		(at 100.906834 -249.368564 180)
		(property "Reference" "C2303"
			(at 0 0 0)
			(layer "B.SilkS")
			(hide yes)
			(effects
				(font
					(size 1.27 1.27)
				)
				(justify mirror)
			)
		)
		(property "Value" ""
			(at 0 0 0)
			(layer "B.Fab")
			(effects
				(font
					(size 1.27 1.27)
				)
				(justify mirror)
			)
		)
		(duplicate_pad_numbers_are_jumpers no)
		(fp_line
			(start 0.7874 0.4064)
			(end 0.7874 -0.4064)
			(stroke
				(width 0.1524)
				(type default)
			)
			(layer "B.SilkS")
		)
		(fp_line
			(start 0.7874 -0.4064)
			(end -0.7874 -0.4064)
			(stroke
				(width 0.1524)
				(type default)
			)
			(layer "B.SilkS")
		)
		(fp_line
			(start -0.7874 0.4064)
			(end 0.7874 0.4064)
			(stroke
				(width 0.1524)
				(type default)
			)
			(layer "B.SilkS")
		)
		(fp_line
			(start -0.7874 -0.4064)
			(end -0.7874 0.4064)
			(stroke
				(width 0.1524)
				(type default)
			)
			(layer "B.SilkS")
		)
		(fp_line
			(start 0.67945 0.3048)
			(end 0.67945 -0.305054)
			(stroke
				(width 0.1)
				(type default)
			)
			(layer "B.Fab")
		)
		(fp_line
			(start 0.67945 -0.305054)
			(end 0.12065 -0.305054)
			(stroke
				(width 0.1)
				(type default)
			)
			(layer "B.Fab")
		)
		(fp_line
			(start 0.12065 0.3048)
			(end 0.67945 0.3048)
			(stroke
				(width 0.1)
				(type default)
			)
			(layer "B.Fab")
		)
		(fp_line
			(start 0.12065 0.2794)
			(end 0.12065 0.3048)
			(stroke
				(width 0.1)
				(type default)
			)
			(layer "B.Fab")
		)
		(fp_line
			(start 0.12065 -0.2794)
			(end -0.12065 -0.2794)
			(stroke
				(width 0.1)
				(type default)
			)
			(layer "B.Fab")
		)
		(fp_line
			(start 0.12065 -0.305054)
			(end 0.12065 -0.2794)
			(stroke
				(width 0.1)
				(type default)
			)
			(layer "B.Fab")
		)
		(fp_line
			(start -0.120396 0.3048)
			(end -0.120396 0.2794)
			(stroke
				(width 0.1)
				(type default)
			)
			(layer "B.Fab")
		)
		(fp_line
			(start -0.120396 0.2794)
			(end 0.12065 0.2794)
			(stroke
				(width 0.1)
				(type default)
			)
			(layer "B.Fab")
		)
		(fp_line
			(start -0.12065 -0.2794)
			(end -0.12065 -0.3048)
			(stroke
				(width 0.1)
				(type default)
			)
			(layer "B.Fab")
		)
		(fp_line
			(start -0.12065 -0.3048)
			(end -0.67945 -0.3048)
			(stroke
				(width 0.1)
				(type default)
			)
			(layer "B.Fab")
		)
		(fp_line
			(start -0.67945 0.3048)
			(end -0.120396 0.3048)
			(stroke
				(width 0.1)
				(type default)
			)
			(layer "B.Fab")
		)
		(fp_line
			(start -0.67945 -0.3048)
			(end -0.67945 0.3048)
			(stroke
				(width 0.1)
				(type default)
			)
			(layer "B.Fab")
		)
		(pad "1" smd circle
			(at 0.40005 0)
			(size 0 0)
			(layers "B.Cu" "B.Mask" "B.Paste")
			(net "PVDDCR_CPU0_P1")
		)
		(pad "2" smd circle
			(at -0.40005 0)
			(size 0 0)
			(layers "B.Cu" "B.Mask" "B.Paste")
			(net "GND")
		)
	)
	(footprint ""
		(layer "B.Cu")
		(at 44.14901 -413.691578)
		(property "Reference" "C2073"
			(at 0 0 0)
			(layer "B.SilkS")
			(hide yes)
			(effects
				(font
					(size 1.27 1.27)
				)
				(justify mirror)
			)
		)
		(property "Value" ""
			(at 0 0 0)
			(layer "B.Fab")
			(effects
				(font
					(size 1.27 1.27)
				)
				(justify mirror)
			)
		)
		(duplicate_pad_numbers_are_jumpers no)
		(fp_line
			(start -0.299974 -0.150114)
			(end -0.299974 0.150114)
			(stroke
				(width 0.1)
				(type default)
			)
			(layer "B.Fab")
		)
		(fp_line
			(start -0.299974 0.150114)
			(end 0.299974 0.150114)
			(stroke
				(width 0.1)
				(type default)
			)
			(layer "B.Fab")
		)
		(fp_line
			(start 0.299974 -0.150114)
			(end -0.299974 -0.150114)
			(stroke
				(width 0.1)
				(type default)
			)
			(layer "B.Fab")
		)
		(fp_line
			(start 0.299974 0.150114)
			(end 0.299974 -0.150114)
			(stroke
				(width 0.1)
				(type default)
			)
			(layer "B.Fab")
		)
		(pad "1" smd rect
			(at 0.2667 0 180)
			(size 0.3048 0.381)
			(layers "B.Cu" "B.Mask" "B.Paste")
			(net "P3E_CPU1_P5_TX_C_DP<1>")
		)
		(pad "2" smd rect
			(at -0.2667 0 180)
			(size 0.3048 0.381)
			(layers "B.Cu" "B.Mask" "B.Paste")
			(net "P3E_CPU1_P5_TX_DP<1>")
		)
	)
	(footprint ""
		(layer "B.Cu")
		(at 393.809728 -200.742804 90)
		(property "Reference" "R6133"
			(at 0 0 90)
			(layer "B.SilkS")
			(hide yes)
			(effects
				(font
					(size 1.27 1.27)
				)
				(justify mirror)
			)
		)
		(property "Value" ""
			(at 0 0 90)
			(layer "B.Fab")
			(effects
				(font
					(size 1.27 1.27)
				)
				(justify mirror)
			)
		)
		(duplicate_pad_numbers_are_jumpers no)
		(fp_line
			(start 0.7874 -0.4064)
			(end -0.7874 -0.4064)
			(stroke
				(width 0.1524)
				(type default)
			)
			(layer "B.SilkS")
		)
		(fp_line
			(start -0.7874 -0.4064)
			(end -0.7874 0.4064)
			(stroke
				(width 0.1524)
				(type default)
			)
			(layer "B.SilkS")
		)
		(fp_line
			(start 0.7874 0.4064)
			(end 0.7874 -0.4064)
			(stroke
				(width 0.1524)
				(type default)
			)
			(layer "B.SilkS")
		)
		(fp_line
			(start -0.7874 0.4064)
			(end 0.7874 0.4064)
			(stroke
				(width 0.1524)
				(type default)
			)
			(layer "B.SilkS")
		)
		(fp_line
			(start 0.67945 -0.305054)
			(end 0.12065 -0.305054)
			(stroke
				(width 0.1)
				(type default)
			)
			(layer "B.Fab")
		)
		(fp_line
			(start 0.12065 -0.305054)
			(end 0.12065 -0.2794)
			(stroke
				(width 0.1)
				(type default)
			)
			(layer "B.Fab")
		)
		(fp_line
			(start -0.12065 -0.3048)
			(end -0.67945 -0.3048)
			(stroke
				(width 0.1)
				(type default)
			)
			(layer "B.Fab")
		)
		(fp_line
			(start -0.67945 -0.3048)
			(end -0.67945 0.3048)
			(stroke
				(width 0.1)
				(type default)
			)
			(layer "B.Fab")
		)
		(fp_line
			(start 0.12065 -0.2794)
			(end -0.12065 -0.2794)
			(stroke
				(width 0.1)
				(type default)
			)
			(layer "B.Fab")
		)
		(fp_line
			(start -0.12065 -0.2794)
			(end -0.12065 -0.3048)
			(stroke
				(width 0.1)
				(type default)
			)
			(layer "B.Fab")
		)
		(fp_line
			(start 0.12065 0.2794)
			(end 0.12065 0.3048)
			(stroke
				(width 0.1)
				(type default)
			)
			(layer "B.Fab")
		)
		(fp_line
			(start -0.120396 0.2794)
			(end 0.12065 0.2794)
			(stroke
				(width 0.1)
				(type default)
			)
			(layer "B.Fab")
		)
		(fp_line
			(start 0.67945 0.3048)
			(end 0.67945 -0.305054)
			(stroke
				(width 0.1)
				(type default)
			)
			(layer "B.Fab")
		)
		(fp_line
			(start 0.12065 0.3048)
			(end 0.67945 0.3048)
			(stroke
				(width 0.1)
				(type default)
			)
			(layer "B.Fab")
		)
		(fp_line
			(start -0.120396 0.3048)
			(end -0.120396 0.2794)
			(stroke
				(width 0.1)
				(type default)
			)
			(layer "B.Fab")
		)
		(fp_line
			(start -0.67945 0.3048)
			(end -0.120396 0.3048)
			(stroke
				(width 0.1)
				(type default)
			)
			(layer "B.Fab")
		)
		(pad "1" smd circle
			(at 0.40005 0 270)
			(size 0 0)
			(layers "B.Cu" "B.Mask" "B.Paste")
			(net "FAB_REV_ID2")
		)
		(pad "2" smd circle
			(at -0.40005 0 270)
			(size 0 0)
			(layers "B.Cu" "B.Mask" "B.Paste")
			(net "GND")
		)
	)
	(footprint ""
		(layer "B.Cu")
		(at 98.578924 -259.73024 180)
		(property "Reference" "C2107"
			(at 0 0 0)
			(layer "B.SilkS")
			(hide yes)
			(effects
				(font
					(size 1.27 1.27)
				)
				(justify mirror)
			)
		)
		(property "Value" ""
			(at 0 0 0)
			(layer "B.Fab")
			(effects
				(font
					(size 1.27 1.27)
				)
				(justify mirror)
			)
		)
		(duplicate_pad_numbers_are_jumpers no)
		(fp_line
			(start 0.7874 0.4064)
			(end 0.7874 -0.4064)
			(stroke
				(width 0.1524)
				(type default)
			)
			(layer "B.SilkS")
		)
		(fp_line
			(start 0.7874 -0.4064)
			(end -0.7874 -0.4064)
			(stroke
				(width 0.1524)
				(type default)
			)
			(layer "B.SilkS")
		)
		(fp_line
			(start -0.7874 0.4064)
			(end 0.7874 0.4064)
			(stroke
				(width 0.1524)
				(type default)
			)
			(layer "B.SilkS")
		)
		(fp_line
			(start -0.7874 -0.4064)
			(end -0.7874 0.4064)
			(stroke
				(width 0.1524)
				(type default)
			)
			(layer "B.SilkS")
		)
		(fp_line
			(start 0.67945 0.3048)
			(end 0.67945 -0.305054)
			(stroke
				(width 0.1)
				(type default)
			)
			(layer "B.Fab")
		)
		(fp_line
			(start 0.67945 -0.305054)
			(end 0.12065 -0.305054)
			(stroke
				(width 0.1)
				(type default)
			)
			(layer "B.Fab")
		)
		(fp_line
			(start 0.12065 0.3048)
			(end 0.67945 0.3048)
			(stroke
				(width 0.1)
				(type default)
			)
			(layer "B.Fab")
		)
		(fp_line
			(start 0.12065 0.2794)
			(end 0.12065 0.3048)
			(stroke
				(width 0.1)
				(type default)
			)
			(layer "B.Fab")
		)
		(fp_line
			(start 0.12065 -0.2794)
			(end -0.12065 -0.2794)
			(stroke
				(width 0.1)
				(type default)
			)
			(layer "B.Fab")
		)
		(fp_line
			(start 0.12065 -0.305054)
			(end 0.12065 -0.2794)
			(stroke
				(width 0.1)
				(type default)
			)
			(layer "B.Fab")
		)
		(fp_line
			(start -0.120396 0.3048)
			(end -0.120396 0.2794)
			(stroke
				(width 0.1)
				(type default)
			)
			(layer "B.Fab")
		)
		(fp_line
			(start -0.120396 0.2794)
			(end 0.12065 0.2794)
			(stroke
				(width 0.1)
				(type default)
			)
			(layer "B.Fab")
		)
		(fp_line
			(start -0.12065 -0.2794)
			(end -0.12065 -0.3048)
			(stroke
				(width 0.1)
				(type default)
			)
			(layer "B.Fab")
		)
		(fp_line
			(start -0.12065 -0.3048)
			(end -0.67945 -0.3048)
			(stroke
				(width 0.1)
				(type default)
			)
			(layer "B.Fab")
		)
		(fp_line
			(start -0.67945 0.3048)
			(end -0.120396 0.3048)
			(stroke
				(width 0.1)
				(type default)
			)
			(layer "B.Fab")
		)
		(fp_line
			(start -0.67945 -0.3048)
			(end -0.67945 0.3048)
			(stroke
				(width 0.1)
				(type default)
			)
			(layer "B.Fab")
		)
		(pad "1" smd circle
			(at 0.40005 0)
			(size 0 0)
			(layers "B.Cu" "B.Mask" "B.Paste")
			(net "PVDDIO_P1")
		)
		(pad "2" smd circle
			(at -0.40005 0)
			(size 0 0)
			(layers "B.Cu" "B.Mask" "B.Paste")
			(net "GND")
		)
	)
	(footprint ""
		(layer "B.Cu")
		(at 365.328454 -253.43231)
		(property "Reference" "C3894"
			(at 0 0 0)
			(layer "B.SilkS")
			(hide yes)
			(effects
				(font
					(size 1.27 1.27)
				)
				(justify mirror)
			)
		)
		(property "Value" ""
			(at 0 0 0)
			(layer "B.Fab")
			(effects
				(font
					(size 1.27 1.27)
				)
				(justify mirror)
			)
		)
		(duplicate_pad_numbers_are_jumpers no)
		(fp_line
			(start -0.7874 -0.4064)
			(end -0.7874 0.4064)
			(stroke
				(width 0.1524)
				(type default)
			)
			(layer "B.SilkS")
		)
		(fp_line
			(start -0.7874 0.4064)
			(end 0.7874 0.4064)
			(stroke
				(width 0.1524)
				(type default)
			)
			(layer "B.SilkS")
		)
		(fp_line
			(start 0.7874 -0.4064)
			(end -0.7874 -0.4064)
			(stroke
				(width 0.1524)
				(type default)
			)
			(layer "B.SilkS")
		)
		(fp_line
			(start 0.7874 0.4064)
			(end 0.7874 -0.4064)
			(stroke
				(width 0.1524)
				(type default)
			)
			(layer "B.SilkS")
		)
		(fp_line
			(start -0.67945 -0.3048)
			(end -0.67945 0.3048)
			(stroke
				(width 0.1)
				(type default)
			)
			(layer "B.Fab")
		)
		(fp_line
			(start -0.67945 0.3048)
			(end -0.120396 0.3048)
			(stroke
				(width 0.1)
				(type default)
			)
			(layer "B.Fab")
		)
		(fp_line
			(start -0.12065 -0.3048)
			(end -0.67945 -0.3048)
			(stroke
				(width 0.1)
				(type default)
			)
			(layer "B.Fab")
		)
		(fp_line
			(start -0.12065 -0.2794)
			(end -0.12065 -0.3048)
			(stroke
				(width 0.1)
				(type default)
			)
			(layer "B.Fab")
		)
		(fp_line
			(start -0.120396 0.2794)
			(end 0.12065 0.2794)
			(stroke
				(width 0.1)
				(type default)
			)
			(layer "B.Fab")
		)
		(fp_line
			(start -0.120396 0.3048)
			(end -0.120396 0.2794)
			(stroke
				(width 0.1)
				(type default)
			)
			(layer "B.Fab")
		)
		(fp_line
			(start 0.12065 -0.305054)
			(end 0.12065 -0.2794)
			(stroke
				(width 0.1)
				(type default)
			)
			(layer "B.Fab")
		)
		(fp_line
			(start 0.12065 -0.2794)
			(end -0.12065 -0.2794)
			(stroke
				(width 0.1)
				(type default)
			)
			(layer "B.Fab")
		)
		(fp_line
			(start 0.12065 0.2794)
			(end 0.12065 0.3048)
			(stroke
				(width 0.1)
				(type default)
			)
			(layer "B.Fab")
		)
		(fp_line
			(start 0.12065 0.3048)
			(end 0.67945 0.3048)
			(stroke
				(width 0.1)
				(type default)
			)
			(layer "B.Fab")
		)
		(fp_line
			(start 0.67945 -0.305054)
			(end 0.12065 -0.305054)
			(stroke
				(width 0.1)
				(type default)
			)
			(layer "B.Fab")
		)
		(fp_line
			(start 0.67945 0.3048)
			(end 0.67945 -0.305054)
			(stroke
				(width 0.1)
				(type default)
			)
			(layer "B.Fab")
		)
		(pad "1" smd circle
			(at 0.40005 0 180)
			(size 0 0)
			(layers "B.Cu" "B.Mask" "B.Paste")
			(net "PVDDCR_SOC_P0")
		)
		(pad "2" smd circle
			(at -0.40005 0 180)
			(size 0 0)
			(layers "B.Cu" "B.Mask" "B.Paste")
			(net "GND")
		)
	)
	(footprint ""
		(layer "B.Cu")
		(at 65.825878 -177.349912 90)
		(property "Reference" "PC135_6"
			(at 0 0 90)
			(layer "B.SilkS")
			(hide yes)
			(effects
				(font
					(size 1.27 1.27)
				)
				(justify mirror)
			)
		)
		(property "Value" ""
			(at 0 0 90)
			(layer "B.Fab")
			(effects
				(font
					(size 1.27 1.27)
				)
				(justify mirror)
			)
		)
		(duplicate_pad_numbers_are_jumpers no)
		(fp_line
			(start 1.524 -0.762)
			(end -1.524 -0.762)
			(stroke
				(width 0.1524)
				(type default)
			)
			(layer "B.SilkS")
		)
		(fp_line
			(start -1.524 -0.762)
			(end -1.524 0.762)
			(stroke
				(width 0.1524)
				(type default)
			)
			(layer "B.SilkS")
		)
		(fp_line
			(start 1.524 0.762)
			(end 1.524 -0.762)
			(stroke
				(width 0.1524)
				(type default)
			)
			(layer "B.SilkS")
		)
		(fp_line
			(start -1.524 0.762)
			(end 1.524 0.762)
			(stroke
				(width 0.1524)
				(type default)
			)
			(layer "B.SilkS")
		)
		(fp_line
			(start 1.1049 -0.724916)
			(end 1.1049 0.724916)
			(stroke
				(width 0.1)
				(type default)
			)
			(layer "B.Fab")
		)
		(fp_line
			(start -1.1049 -0.724916)
			(end 1.1049 -0.724916)
			(stroke
				(width 0.1)
				(type default)
			)
			(layer "B.Fab")
		)
		(fp_line
			(start 1.1049 0.724916)
			(end -1.1049 0.724916)
			(stroke
				(width 0.1)
				(type default)
			)
			(layer "B.Fab")
		)
		(fp_line
			(start -1.1049 0.724916)
			(end -1.1049 -0.724916)
			(stroke
				(width 0.1)
				(type default)
			)
			(layer "B.Fab")
		)
		(pad "1" smd rect
			(at 0.889 0 90)
			(size 1.016 1.27)
			(layers "B.Cu" "B.Mask" "B.Paste")
			(net "PVDDCR_CPU0_P1")
		)
		(pad "2" smd rect
			(at -0.889 0 90)
			(size 1.016 1.27)
			(layers "B.Cu" "B.Mask" "B.Paste")
			(net "GND")
		)
	)
	(footprint ""
		(layer "B.Cu")
		(at 349.245936 -396.393162 -90)
		(property "Reference" "C623"
			(at 0 0 90)
			(layer "B.SilkS")
			(hide yes)
			(effects
				(font
					(size 1.27 1.27)
				)
				(justify mirror)
			)
		)
		(property "Value" ""
			(at 0 0 90)
			(layer "B.Fab")
			(effects
				(font
					(size 1.27 1.27)
				)
				(justify mirror)
			)
		)
		(duplicate_pad_numbers_are_jumpers no)
		(fp_line
			(start -0.299974 0.150114)
			(end 0.299974 0.150114)
			(stroke
				(width 0.1)
				(type default)
			)
			(layer "B.Fab")
		)
		(fp_line
			(start 0.299974 0.150114)
			(end 0.299974 -0.150114)
			(stroke
				(width 0.1)
				(type default)
			)
			(layer "B.Fab")
		)
		(fp_line
			(start -0.299974 -0.150114)
			(end -0.299974 0.150114)
			(stroke
				(width 0.1)
				(type default)
			)
			(layer "B.Fab")
		)
		(fp_line
			(start 0.299974 -0.150114)
			(end -0.299974 -0.150114)
			(stroke
				(width 0.1)
				(type default)
			)
			(layer "B.Fab")
		)
		(pad "1" smd rect
			(at 0.2667 0 90)
			(size 0.3048 0.381)
			(layers "B.Cu" "B.Mask" "B.Paste")
			(net "P0V9_CPU0_RT1_2A_2D")
		)
		(pad "2" smd rect
			(at -0.2667 0 90)
			(size 0.3048 0.381)
			(layers "B.Cu" "B.Mask" "B.Paste")
			(net "GND")
		)
	)
	(footprint ""
		(layer "B.Cu")
		(at 52.782978 -429.84293 90)
		(property "Reference" "R3487"
			(at 0 0 90)
			(layer "B.SilkS")
			(hide yes)
			(effects
				(font
					(size 1.27 1.27)
				)
				(justify mirror)
			)
		)
		(property "Value" ""
			(at 0 0 90)
			(layer "B.Fab")
			(effects
				(font
					(size 1.27 1.27)
				)
				(justify mirror)
			)
		)
		(duplicate_pad_numbers_are_jumpers no)
		(fp_line
			(start 0.7874 -0.4064)
			(end -0.7874 -0.4064)
			(stroke
				(width 0.1524)
				(type default)
			)
			(layer "B.SilkS")
		)
		(fp_line
			(start -0.7874 -0.4064)
			(end -0.7874 0.4064)
			(stroke
				(width 0.1524)
				(type default)
			)
			(layer "B.SilkS")
		)
		(fp_line
			(start 0.7874 0.4064)
			(end 0.7874 -0.4064)
			(stroke
				(width 0.1524)
				(type default)
			)
			(layer "B.SilkS")
		)
		(fp_line
			(start -0.7874 0.4064)
			(end 0.7874 0.4064)
			(stroke
				(width 0.1524)
				(type default)
			)
			(layer "B.SilkS")
		)
		(fp_line
			(start 0.67945 -0.305054)
			(end 0.12065 -0.305054)
			(stroke
				(width 0.1)
				(type default)
			)
			(layer "B.Fab")
		)
		(fp_line
			(start 0.12065 -0.305054)
			(end 0.12065 -0.2794)
			(stroke
				(width 0.1)
				(type default)
			)
			(layer "B.Fab")
		)
		(fp_line
			(start -0.12065 -0.3048)
			(end -0.67945 -0.3048)
			(stroke
				(width 0.1)
				(type default)
			)
			(layer "B.Fab")
		)
		(fp_line
			(start -0.67945 -0.3048)
			(end -0.67945 0.3048)
			(stroke
				(width 0.1)
				(type default)
			)
			(layer "B.Fab")
		)
		(fp_line
			(start 0.12065 -0.2794)
			(end -0.12065 -0.2794)
			(stroke
				(width 0.1)
				(type default)
			)
			(layer "B.Fab")
		)
		(fp_line
			(start -0.12065 -0.2794)
			(end -0.12065 -0.3048)
			(stroke
				(width 0.1)
				(type default)
			)
			(layer "B.Fab")
		)
		(fp_line
			(start 0.12065 0.2794)
			(end 0.12065 0.3048)
			(stroke
				(width 0.1)
				(type default)
			)
			(layer "B.Fab")
		)
		(fp_line
			(start -0.120396 0.2794)
			(end 0.12065 0.2794)
			(stroke
				(width 0.1)
				(type default)
			)
			(layer "B.Fab")
		)
		(fp_line
			(start 0.67945 0.3048)
			(end 0.67945 -0.305054)
			(stroke
				(width 0.1)
				(type default)
			)
			(layer "B.Fab")
		)
		(fp_line
			(start 0.12065 0.3048)
			(end 0.67945 0.3048)
			(stroke
				(width 0.1)
				(type default)
			)
			(layer "B.Fab")
		)
		(fp_line
			(start -0.120396 0.3048)
			(end -0.120396 0.2794)
			(stroke
				(width 0.1)
				(type default)
			)
			(layer "B.Fab")
		)
		(fp_line
			(start -0.67945 0.3048)
			(end -0.120396 0.3048)
			(stroke
				(width 0.1)
				(type default)
			)
			(layer "B.Fab")
		)
		(pad "1" smd circle
			(at 0.40005 0 270)
			(size 0 0)
			(layers "B.Cu" "B.Mask" "B.Paste")
			(net "P3V3_AUX")
		)
		(pad "2" smd circle
			(at -0.40005 0 270)
			(size 0 0)
			(layers "B.Cu" "B.Mask" "B.Paste")
			(net "GPU_PRSNT_N")
		)
	)
	(footprint ""
		(layer "B.Cu")
		(at 36.796218 -192.66027)
		(property "Reference" "C181"
			(at 0 0 0)
			(layer "B.SilkS")
			(hide yes)
			(effects
				(font
					(size 1.27 1.27)
				)
				(justify mirror)
			)
		)
		(property "Value" ""
			(at 0 0 0)
			(layer "B.Fab")
			(effects
				(font
					(size 1.27 1.27)
				)
				(justify mirror)
			)
		)
		(duplicate_pad_numbers_are_jumpers no)
		(fp_line
			(start -1.524 -0.762)
			(end -1.524 0.762)
			(stroke
				(width 0.1524)
				(type default)
			)
			(layer "B.SilkS")
		)
		(fp_line
			(start -1.524 0.762)
			(end 1.524 0.762)
			(stroke
				(width 0.1524)
				(type default)
			)
			(layer "B.SilkS")
		)
		(fp_line
			(start 1.524 -0.762)
			(end -1.524 -0.762)
			(stroke
				(width 0.1524)
				(type default)
			)
			(layer "B.SilkS")
		)
		(fp_line
			(start 1.524 0.762)
			(end 1.524 -0.762)
			(stroke
				(width 0.1524)
				(type default)
			)
			(layer "B.SilkS")
		)
		(fp_line
			(start -1.1049 -0.724916)
			(end 1.1049 -0.724916)
			(stroke
				(width 0.1)
				(type default)
			)
			(layer "B.Fab")
		)
		(fp_line
			(start -1.1049 0.724916)
			(end -1.1049 -0.724916)
			(stroke
				(width 0.1)
				(type default)
			)
			(layer "B.Fab")
		)
		(fp_line
			(start 1.1049 -0.724916)
			(end 1.1049 0.724916)
			(stroke
				(width 0.1)
				(type default)
			)
			(layer "B.Fab")
		)
		(fp_line
			(start 1.1049 0.724916)
			(end -1.1049 0.724916)
			(stroke
				(width 0.1)
				(type default)
			)
			(layer "B.Fab")
		)
		(pad "1" smd rect
			(at 0.889 0)
			(size 1.016 1.27)
			(layers "B.Cu" "B.Mask" "B.Paste")
			(net "P12V_MEM_CPU1")
		)
		(pad "2" smd rect
			(at -0.889 0)
			(size 1.016 1.27)
			(layers "B.Cu" "B.Mask" "B.Paste")
			(net "GND")
		)
	)
	(footprint ""
		(layer "B.Cu")
		(at 299.06849 -195.859146 180)
		(property "Reference" "R1675"
			(at 0 0 0)
			(layer "B.SilkS")
			(hide yes)
			(effects
				(font
					(size 1.27 1.27)
				)
				(justify mirror)
			)
		)
		(property "Value" ""
			(at 0 0 0)
			(layer "B.Fab")
			(effects
				(font
					(size 1.27 1.27)
				)
				(justify mirror)
			)
		)
		(duplicate_pad_numbers_are_jumpers no)
		(fp_line
			(start 0.7874 0.4064)
			(end 0.7874 -0.4064)
			(stroke
				(width 0.1524)
				(type default)
			)
			(layer "B.SilkS")
		)
		(fp_line
			(start 0.7874 -0.4064)
			(end -0.7874 -0.4064)
			(stroke
				(width 0.1524)
				(type default)
			)
			(layer "B.SilkS")
		)
		(fp_line
			(start -0.7874 0.4064)
			(end 0.7874 0.4064)
			(stroke
				(width 0.1524)
				(type default)
			)
			(layer "B.SilkS")
		)
		(fp_line
			(start -0.7874 -0.4064)
			(end -0.7874 0.4064)
			(stroke
				(width 0.1524)
				(type default)
			)
			(layer "B.SilkS")
		)
		(fp_line
			(start 0.67945 0.3048)
			(end 0.67945 -0.305054)
			(stroke
				(width 0.1)
				(type default)
			)
			(layer "B.Fab")
		)
		(fp_line
			(start 0.67945 -0.305054)
			(end 0.12065 -0.305054)
			(stroke
				(width 0.1)
				(type default)
			)
			(layer "B.Fab")
		)
		(fp_line
			(start 0.12065 0.3048)
			(end 0.67945 0.3048)
			(stroke
				(width 0.1)
				(type default)
			)
			(layer "B.Fab")
		)
		(fp_line
			(start 0.12065 0.2794)
			(end 0.12065 0.3048)
			(stroke
				(width 0.1)
				(type default)
			)
			(layer "B.Fab")
		)
		(fp_line
			(start 0.12065 -0.2794)
			(end -0.12065 -0.2794)
			(stroke
				(width 0.1)
				(type default)
			)
			(layer "B.Fab")
		)
		(fp_line
			(start 0.12065 -0.305054)
			(end 0.12065 -0.2794)
			(stroke
				(width 0.1)
				(type default)
			)
			(layer "B.Fab")
		)
		(fp_line
			(start -0.120396 0.3048)
			(end -0.120396 0.2794)
			(stroke
				(width 0.1)
				(type default)
			)
			(layer "B.Fab")
		)
		(fp_line
			(start -0.120396 0.2794)
			(end 0.12065 0.2794)
			(stroke
				(width 0.1)
				(type default)
			)
			(layer "B.Fab")
		)
		(fp_line
			(start -0.12065 -0.2794)
			(end -0.12065 -0.3048)
			(stroke
				(width 0.1)
				(type default)
			)
			(layer "B.Fab")
		)
		(fp_line
			(start -0.12065 -0.3048)
			(end -0.67945 -0.3048)
			(stroke
				(width 0.1)
				(type default)
			)
			(layer "B.Fab")
		)
		(fp_line
			(start -0.67945 0.3048)
			(end -0.120396 0.3048)
			(stroke
				(width 0.1)
				(type default)
			)
			(layer "B.Fab")
		)
		(fp_line
			(start -0.67945 -0.3048)
			(end -0.67945 0.3048)
			(stroke
				(width 0.1)
				(type default)
			)
			(layer "B.Fab")
		)
		(pad "1" smd circle
			(at 0.40005 0)
			(size 0 0)
			(layers "B.Cu" "B.Mask" "B.Paste")
			(net "I3C_SPD_DDRAF_CPU0_SDA")
		)
		(pad "2" smd circle
			(at -0.40005 0)
			(size 0 0)
			(layers "B.Cu" "B.Mask" "B.Paste")
			(net "I3C_SPD_DDRB_CPU0_SDA")
		)
	)
	(footprint ""
		(layer "B.Cu")
		(at 163.4236 -412.18866 90)
		(property "Reference" "R692"
			(at 0 0 90)
			(layer "B.SilkS")
			(hide yes)
			(effects
				(font
					(size 1.27 1.27)
				)
				(justify mirror)
			)
		)
		(property "Value" ""
			(at 0 0 90)
			(layer "B.Fab")
			(effects
				(font
					(size 1.27 1.27)
				)
				(justify mirror)
			)
		)
		(duplicate_pad_numbers_are_jumpers no)
		(fp_line
			(start 0.32512 -0.175006)
			(end -0.32512 -0.175006)
			(stroke
				(width 0.1)
				(type default)
			)
			(layer "B.Fab")
		)
		(fp_line
			(start -0.32512 -0.175006)
			(end -0.32512 0.175006)
			(stroke
				(width 0.1)
				(type default)
			)
			(layer "B.Fab")
		)
		(fp_line
			(start 0.32512 0.175006)
			(end 0.32512 -0.175006)
			(stroke
				(width 0.1)
				(type default)
			)
			(layer "B.Fab")
		)
		(fp_line
			(start -0.32512 0.175006)
			(end 0.32512 0.175006)
			(stroke
				(width 0.1)
				(type default)
			)
			(layer "B.Fab")
		)
		(pad "1" smd rect
			(at 0.2667 0 270)
			(size 0.3048 0.381)
			(layers "B.Cu" "B.Mask" "B.Paste")
			(net "SMB_RT_CPU1_P2_ROM_MUX_1D_SDA")
		)
		(pad "2" smd rect
			(at -0.2667 0 90)
			(size 0.3048 0.381)
			(layers "B.Cu" "B.Mask" "B.Paste")
			(net "SMB_RT_CPU1_P2_ROM_MUX_1D_R_SDA")
		)
	)
	(footprint ""
		(layer "B.Cu")
		(at 332.748128 -336.032856 -90)
		(property "Reference" "PR79"
			(at 0 0 90)
			(layer "B.SilkS")
			(hide yes)
			(effects
				(font
					(size 1.27 1.27)
				)
				(justify mirror)
			)
		)
		(property "Value" ""
			(at 0 0 90)
			(layer "B.Fab")
			(effects
				(font
					(size 1.27 1.27)
				)
				(justify mirror)
			)
		)
		(duplicate_pad_numbers_are_jumpers no)
		(fp_line
			(start -0.7874 0.4064)
			(end 0.7874 0.4064)
			(stroke
				(width 0.1524)
				(type default)
			)
			(layer "B.SilkS")
		)
		(fp_line
			(start 0.7874 0.4064)
			(end 0.7874 -0.4064)
			(stroke
				(width 0.1524)
				(type default)
			)
			(layer "B.SilkS")
		)
		(fp_line
			(start -0.7874 -0.4064)
			(end -0.7874 0.4064)
			(stroke
				(width 0.1524)
				(type default)
			)
			(layer "B.SilkS")
		)
		(fp_line
			(start 0.7874 -0.4064)
			(end -0.7874 -0.4064)
			(stroke
				(width 0.1524)
				(type default)
			)
			(layer "B.SilkS")
		)
		(fp_line
			(start -0.67945 0.3048)
			(end -0.120396 0.3048)
			(stroke
				(width 0.1)
				(type default)
			)
			(layer "B.Fab")
		)
		(fp_line
			(start -0.120396 0.3048)
			(end -0.120396 0.2794)
			(stroke
				(width 0.1)
				(type default)
			)
			(layer "B.Fab")
		)
		(fp_line
			(start 0.12065 0.3048)
			(end 0.67945 0.3048)
			(stroke
				(width 0.1)
				(type default)
			)
			(layer "B.Fab")
		)
		(fp_line
			(start 0.67945 0.3048)
			(end 0.67945 -0.305054)
			(stroke
				(width 0.1)
				(type default)
			)
			(layer "B.Fab")
		)
		(fp_line
			(start -0.120396 0.2794)
			(end 0.12065 0.2794)
			(stroke
				(width 0.1)
				(type default)
			)
			(layer "B.Fab")
		)
		(fp_line
			(start 0.12065 0.2794)
			(end 0.12065 0.3048)
			(stroke
				(width 0.1)
				(type default)
			)
			(layer "B.Fab")
		)
		(fp_line
			(start -0.12065 -0.2794)
			(end -0.12065 -0.3048)
			(stroke
				(width 0.1)
				(type default)
			)
			(layer "B.Fab")
		)
		(fp_line
			(start 0.12065 -0.2794)
			(end -0.12065 -0.2794)
			(stroke
				(width 0.1)
				(type default)
			)
			(layer "B.Fab")
		)
		(fp_line
			(start -0.67945 -0.3048)
			(end -0.67945 0.3048)
			(stroke
				(width 0.1)
				(type default)
			)
			(layer "B.Fab")
		)
		(fp_line
			(start -0.12065 -0.3048)
			(end -0.67945 -0.3048)
			(stroke
				(width 0.1)
				(type default)
			)
			(layer "B.Fab")
		)
		(fp_line
			(start 0.12065 -0.305054)
			(end 0.12065 -0.2794)
			(stroke
				(width 0.1)
				(type default)
			)
			(layer "B.Fab")
		)
		(fp_line
			(start 0.67945 -0.305054)
			(end 0.12065 -0.305054)
			(stroke
				(width 0.1)
				(type default)
			)
			(layer "B.Fab")
		)
		(pad "1" smd circle
			(at 0.40005 0 90)
			(size 0 0)
			(layers "B.Cu" "B.Mask" "B.Paste")
			(net "PVDDCR_CPU1_P0_PVCC")
		)
		(pad "2" smd circle
			(at -0.40005 0 90)
			(size 0 0)
			(layers "B.Cu" "B.Mask" "B.Paste")
			(net "PVDDCR_CPU1_P0_VCC1")
		)
	)
	(footprint ""
		(layer "B.Cu")
		(at 432.21402 -437.142636 180)
		(property "Reference" "Q137"
			(at -1.600708 -3.202686 0)
			(unlocked yes)
			(layer "B.SilkS")
			(effects
				(font
					(size 0.7874 0.5842)
					(thickness 0.1524)
				)
				(justify left mirror)
			)
		)
		(property "Value" ""
			(at 0 0 0)
			(layer "B.Fab")
			(effects
				(font
					(size 1.27 1.27)
				)
				(justify mirror)
			)
		)
		(duplicate_pad_numbers_are_jumpers no)
		(fp_line
			(start 1.332738 1.100074)
			(end 1.332738 -1.100074)
			(stroke
				(width 0.1524)
				(type default)
			)
			(layer "B.SilkS")
		)
		(fp_line
			(start 1.332738 -1.100074)
			(end 0.4826 -1.100074)
			(stroke
				(width 0.1524)
				(type default)
			)
			(layer "B.SilkS")
		)
		(fp_line
			(start 0.4826 -1.100074)
			(end 0 -0.541274)
			(stroke
				(width 0.1524)
				(type default)
			)
			(layer "B.SilkS")
		)
		(fp_line
			(start 0 -0.541274)
			(end -0.4826 -1.100074)
			(stroke
				(width 0.1524)
				(type default)
			)
			(layer "B.SilkS")
		)
		(fp_line
			(start -0.4826 -1.100074)
			(end -1.332738 -1.100074)
			(stroke
				(width 0.1524)
				(type default)
			)
			(layer "B.SilkS")
		)
		(fp_line
			(start -1.332738 1.100074)
			(end 1.332738 1.100074)
			(stroke
				(width 0.1524)
				(type default)
			)
			(layer "B.SilkS")
		)
		(fp_line
			(start -1.332738 -1.100074)
			(end -1.332738 1.100074)
			(stroke
				(width 0.1524)
				(type default)
			)
			(layer "B.SilkS")
		)
		(fp_poly
			(pts
				(xy 1.255522 -1.262126) (xy 2.00025 -1.510284) (xy 1.50368 -2.006854)
			)
			(stroke
				(width 0)
				(type default)
			)
			(fill yes)
			(layer "B.SilkS")
		)
		(fp_line
			(start 0.674878 1.100074)
			(end 0.674878 -1.100074)
			(stroke
				(width 0.1)
				(type default)
			)
			(layer "B.Fab")
		)
		(fp_line
			(start 0.674878 -1.100074)
			(end -0.674878 -1.100074)
			(stroke
				(width 0.1)
				(type default)
			)
			(layer "B.Fab")
		)
		(fp_line
			(start -0.674878 1.100074)
			(end 0.674878 1.100074)
			(stroke
				(width 0.1)
				(type default)
			)
			(layer "B.Fab")
		)
		(fp_line
			(start -0.674878 -1.100074)
			(end -0.674878 1.100074)
			(stroke
				(width 0.1)
				(type default)
			)
			(layer "B.Fab")
		)
		(fp_poly
			(pts
				(xy 2.2352 -0.298958) (xy 2.2352 -1.001014) (xy 1.533144 -0.649986)
			)
			(stroke
				(width 0)
				(type default)
			)
			(fill yes)
			(layer "B.Fab")
		)
		(pad "1" smd rect
			(at 0.94996 -0.649986 270)
			(size 0.4318 0.508)
			(layers "B.Cu" "B.Mask" "B.Paste")
			(net "GND")
		)
		(pad "2" smd rect
			(at 0.94996 0 270)
			(size 0.4318 0.508)
			(layers "B.Cu" "B.Mask" "B.Paste")
			(net "GPU_3V3IO_RSVD3")
		)
		(pad "3" smd rect
			(at 0.94996 0.649986 270)
			(size 0.4318 0.508)
			(layers "B.Cu" "B.Mask" "B.Paste")
			(net "GPU_3V3IO_RSVD3_ISO")
		)
		(pad "4" smd rect
			(at -0.94996 0.649986 270)
			(size 0.4318 0.508)
			(layers "B.Cu" "B.Mask" "B.Paste")
			(net "GND")
		)
		(pad "5" smd rect
			(at -0.94996 0 270)
			(size 0.4318 0.508)
			(layers "B.Cu" "B.Mask" "B.Paste")
			(net "GPU_3V3IO_RSVD3_N")
		)
		(pad "6" smd rect
			(at -0.94996 -0.649986 270)
			(size 0.4318 0.508)
			(layers "B.Cu" "B.Mask" "B.Paste")
			(net "GPU_3V3IO_RSVD3_N")
		)
	)
	(footprint ""
		(layer "B.Cu")
		(at 351.518728 -398.942052 90)
		(property "Reference" "C656"
			(at 0 0 90)
			(layer "B.SilkS")
			(hide yes)
			(effects
				(font
					(size 1.27 1.27)
				)
				(justify mirror)
			)
		)
		(property "Value" ""
			(at 0 0 90)
			(layer "B.Fab")
			(effects
				(font
					(size 1.27 1.27)
				)
				(justify mirror)
			)
		)
		(duplicate_pad_numbers_are_jumpers no)
		(fp_line
			(start 0.7874 -0.4064)
			(end -0.7874 -0.4064)
			(stroke
				(width 0.1524)
				(type default)
			)
			(layer "B.SilkS")
		)
		(fp_line
			(start -0.7874 -0.4064)
			(end -0.7874 0.4064)
			(stroke
				(width 0.1524)
				(type default)
			)
			(layer "B.SilkS")
		)
		(fp_line
			(start 0.7874 0.4064)
			(end 0.7874 -0.4064)
			(stroke
				(width 0.1524)
				(type default)
			)
			(layer "B.SilkS")
		)
		(fp_line
			(start -0.7874 0.4064)
			(end 0.7874 0.4064)
			(stroke
				(width 0.1524)
				(type default)
			)
			(layer "B.SilkS")
		)
		(fp_line
			(start 0.67945 -0.305054)
			(end 0.12065 -0.305054)
			(stroke
				(width 0.1)
				(type default)
			)
			(layer "B.Fab")
		)
		(fp_line
			(start 0.12065 -0.305054)
			(end 0.12065 -0.2794)
			(stroke
				(width 0.1)
				(type default)
			)
			(layer "B.Fab")
		)
		(fp_line
			(start -0.12065 -0.3048)
			(end -0.67945 -0.3048)
			(stroke
				(width 0.1)
				(type default)
			)
			(layer "B.Fab")
		)
		(fp_line
			(start -0.67945 -0.3048)
			(end -0.67945 0.3048)
			(stroke
				(width 0.1)
				(type default)
			)
			(layer "B.Fab")
		)
		(fp_line
			(start 0.12065 -0.2794)
			(end -0.12065 -0.2794)
			(stroke
				(width 0.1)
				(type default)
			)
			(layer "B.Fab")
		)
		(fp_line
			(start -0.12065 -0.2794)
			(end -0.12065 -0.3048)
			(stroke
				(width 0.1)
				(type default)
			)
			(layer "B.Fab")
		)
		(fp_line
			(start 0.12065 0.2794)
			(end 0.12065 0.3048)
			(stroke
				(width 0.1)
				(type default)
			)
			(layer "B.Fab")
		)
		(fp_line
			(start -0.120396 0.2794)
			(end 0.12065 0.2794)
			(stroke
				(width 0.1)
				(type default)
			)
			(layer "B.Fab")
		)
		(fp_line
			(start 0.67945 0.3048)
			(end 0.67945 -0.305054)
			(stroke
				(width 0.1)
				(type default)
			)
			(layer "B.Fab")
		)
		(fp_line
			(start 0.12065 0.3048)
			(end 0.67945 0.3048)
			(stroke
				(width 0.1)
				(type default)
			)
			(layer "B.Fab")
		)
		(fp_line
			(start -0.120396 0.3048)
			(end -0.120396 0.2794)
			(stroke
				(width 0.1)
				(type default)
			)
			(layer "B.Fab")
		)
		(fp_line
			(start -0.67945 0.3048)
			(end -0.120396 0.3048)
			(stroke
				(width 0.1)
				(type default)
			)
			(layer "B.Fab")
		)
		(pad "1" smd circle
			(at 0.40005 0 270)
			(size 0 0)
			(layers "B.Cu" "B.Mask" "B.Paste")
			(net "P0V9_CPU0_RT1_2A")
		)
		(pad "2" smd circle
			(at -0.40005 0 270)
			(size 0 0)
			(layers "B.Cu" "B.Mask" "B.Paste")
			(net "GND")
		)
	)
	(footprint ""
		(layer "B.Cu")
		(at 171.82846 -190.948564 180)
		(property "Reference" "R310"
			(at 0 0 0)
			(layer "B.SilkS")
			(hide yes)
			(effects
				(font
					(size 1.27 1.27)
				)
				(justify mirror)
			)
		)
		(property "Value" ""
			(at 0 0 0)
			(layer "B.Fab")
			(effects
				(font
					(size 1.27 1.27)
				)
				(justify mirror)
			)
		)
		(duplicate_pad_numbers_are_jumpers no)
		(fp_line
			(start 0.7874 0.4064)
			(end 0.7874 -0.4064)
			(stroke
				(width 0.1524)
				(type default)
			)
			(layer "B.SilkS")
		)
		(fp_line
			(start 0.7874 -0.4064)
			(end -0.7874 -0.4064)
			(stroke
				(width 0.1524)
				(type default)
			)
			(layer "B.SilkS")
		)
		(fp_line
			(start -0.7874 0.4064)
			(end 0.7874 0.4064)
			(stroke
				(width 0.1524)
				(type default)
			)
			(layer "B.SilkS")
		)
		(fp_line
			(start -0.7874 -0.4064)
			(end -0.7874 0.4064)
			(stroke
				(width 0.1524)
				(type default)
			)
			(layer "B.SilkS")
		)
		(fp_line
			(start 0.67945 0.3048)
			(end 0.67945 -0.305054)
			(stroke
				(width 0.1)
				(type default)
			)
			(layer "B.Fab")
		)
		(fp_line
			(start 0.67945 -0.305054)
			(end 0.12065 -0.305054)
			(stroke
				(width 0.1)
				(type default)
			)
			(layer "B.Fab")
		)
		(fp_line
			(start 0.12065 0.3048)
			(end 0.67945 0.3048)
			(stroke
				(width 0.1)
				(type default)
			)
			(layer "B.Fab")
		)
		(fp_line
			(start 0.12065 0.2794)
			(end 0.12065 0.3048)
			(stroke
				(width 0.1)
				(type default)
			)
			(layer "B.Fab")
		)
		(fp_line
			(start 0.12065 -0.2794)
			(end -0.12065 -0.2794)
			(stroke
				(width 0.1)
				(type default)
			)
			(layer "B.Fab")
		)
		(fp_line
			(start 0.12065 -0.305054)
			(end 0.12065 -0.2794)
			(stroke
				(width 0.1)
				(type default)
			)
			(layer "B.Fab")
		)
		(fp_line
			(start -0.120396 0.3048)
			(end -0.120396 0.2794)
			(stroke
				(width 0.1)
				(type default)
			)
			(layer "B.Fab")
		)
		(fp_line
			(start -0.120396 0.2794)
			(end 0.12065 0.2794)
			(stroke
				(width 0.1)
				(type default)
			)
			(layer "B.Fab")
		)
		(fp_line
			(start -0.12065 -0.2794)
			(end -0.12065 -0.3048)
			(stroke
				(width 0.1)
				(type default)
			)
			(layer "B.Fab")
		)
		(fp_line
			(start -0.12065 -0.3048)
			(end -0.67945 -0.3048)
			(stroke
				(width 0.1)
				(type default)
			)
			(layer "B.Fab")
		)
		(fp_line
			(start -0.67945 0.3048)
			(end -0.120396 0.3048)
			(stroke
				(width 0.1)
				(type default)
			)
			(layer "B.Fab")
		)
		(fp_line
			(start -0.67945 -0.3048)
			(end -0.67945 0.3048)
			(stroke
				(width 0.1)
				(type default)
			)
			(layer "B.Fab")
		)
		(pad "1" smd circle
			(at 0.40005 0)
			(size 0 0)
			(layers "B.Cu" "B.Mask" "B.Paste")
			(net "PWRGD_CHH_CPU1_DIMM")
		)
		(pad "2" smd circle
			(at -0.40005 0)
			(size 0 0)
			(layers "B.Cu" "B.Mask" "B.Paste")
			(net "PWRGD_CHGL_CPU1")
		)
	)
	(footprint ""
		(layer "B.Cu")
		(at 105.537 -419.989)
		(property "Reference" "R3032"
			(at 0 0 0)
			(layer "B.SilkS")
			(hide yes)
			(effects
				(font
					(size 1.27 1.27)
				)
				(justify mirror)
			)
		)
		(property "Value" ""
			(at 0 0 0)
			(layer "B.Fab")
			(effects
				(font
					(size 1.27 1.27)
				)
				(justify mirror)
			)
		)
		(duplicate_pad_numbers_are_jumpers no)
		(fp_line
			(start -0.7874 -0.4064)
			(end -0.7874 0.4064)
			(stroke
				(width 0.1524)
				(type default)
			)
			(layer "B.SilkS")
		)
		(fp_line
			(start -0.7874 0.4064)
			(end 0.7874 0.4064)
			(stroke
				(width 0.1524)
				(type default)
			)
			(layer "B.SilkS")
		)
		(fp_line
			(start 0.7874 -0.4064)
			(end -0.7874 -0.4064)
			(stroke
				(width 0.1524)
				(type default)
			)
			(layer "B.SilkS")
		)
		(fp_line
			(start 0.7874 0.4064)
			(end 0.7874 -0.4064)
			(stroke
				(width 0.1524)
				(type default)
			)
			(layer "B.SilkS")
		)
		(fp_line
			(start -0.67945 -0.3048)
			(end -0.67945 0.3048)
			(stroke
				(width 0.1)
				(type default)
			)
			(layer "B.Fab")
		)
		(fp_line
			(start -0.67945 0.3048)
			(end -0.120396 0.3048)
			(stroke
				(width 0.1)
				(type default)
			)
			(layer "B.Fab")
		)
		(fp_line
			(start -0.12065 -0.3048)
			(end -0.67945 -0.3048)
			(stroke
				(width 0.1)
				(type default)
			)
			(layer "B.Fab")
		)
		(fp_line
			(start -0.12065 -0.2794)
			(end -0.12065 -0.3048)
			(stroke
				(width 0.1)
				(type default)
			)
			(layer "B.Fab")
		)
		(fp_line
			(start -0.120396 0.2794)
			(end 0.12065 0.2794)
			(stroke
				(width 0.1)
				(type default)
			)
			(layer "B.Fab")
		)
		(fp_line
			(start -0.120396 0.3048)
			(end -0.120396 0.2794)
			(stroke
				(width 0.1)
				(type default)
			)
			(layer "B.Fab")
		)
		(fp_line
			(start 0.12065 -0.305054)
			(end 0.12065 -0.2794)
			(stroke
				(width 0.1)
				(type default)
			)
			(layer "B.Fab")
		)
		(fp_line
			(start 0.12065 -0.2794)
			(end -0.12065 -0.2794)
			(stroke
				(width 0.1)
				(type default)
			)
			(layer "B.Fab")
		)
		(fp_line
			(start 0.12065 0.2794)
			(end 0.12065 0.3048)
			(stroke
				(width 0.1)
				(type default)
			)
			(layer "B.Fab")
		)
		(fp_line
			(start 0.12065 0.3048)
			(end 0.67945 0.3048)
			(stroke
				(width 0.1)
				(type default)
			)
			(layer "B.Fab")
		)
		(fp_line
			(start 0.67945 -0.305054)
			(end 0.12065 -0.305054)
			(stroke
				(width 0.1)
				(type default)
			)
			(layer "B.Fab")
		)
		(fp_line
			(start 0.67945 0.3048)
			(end 0.67945 -0.305054)
			(stroke
				(width 0.1)
				(type default)
			)
			(layer "B.Fab")
		)
		(pad "1" smd circle
			(at 0.40005 0 180)
			(size 0 0)
			(layers "B.Cu" "B.Mask" "B.Paste")
			(net "FM_SMB_2_ALERT_GPU_N")
		)
		(pad "2" smd circle
			(at -0.40005 0 180)
			(size 0 0)
			(layers "B.Cu" "B.Mask" "B.Paste")
			(net "GND")
		)
	)
	(footprint ""
		(layer "B.Cu")
		(at 104.850946 -343.878916 -90)
		(property "Reference" "PC147_6"
			(at 0 0 90)
			(layer "B.SilkS")
			(hide yes)
			(effects
				(font
					(size 1.27 1.27)
				)
				(justify mirror)
			)
		)
		(property "Value" ""
			(at 0 0 90)
			(layer "B.Fab")
			(effects
				(font
					(size 1.27 1.27)
				)
				(justify mirror)
			)
		)
		(duplicate_pad_numbers_are_jumpers no)
		(fp_line
			(start -1.524 0.762)
			(end 1.524 0.762)
			(stroke
				(width 0.1524)
				(type default)
			)
			(layer "B.SilkS")
		)
		(fp_line
			(start 1.524 0.762)
			(end 1.524 -0.762)
			(stroke
				(width 0.1524)
				(type default)
			)
			(layer "B.SilkS")
		)
		(fp_line
			(start -1.524 -0.762)
			(end -1.524 0.762)
			(stroke
				(width 0.1524)
				(type default)
			)
			(layer "B.SilkS")
		)
		(fp_line
			(start 1.524 -0.762)
			(end -1.524 -0.762)
			(stroke
				(width 0.1524)
				(type default)
			)
			(layer "B.SilkS")
		)
		(fp_line
			(start -1.1049 0.724916)
			(end -1.1049 -0.724916)
			(stroke
				(width 0.1)
				(type default)
			)
			(layer "B.Fab")
		)
		(fp_line
			(start 1.1049 0.724916)
			(end -1.1049 0.724916)
			(stroke
				(width 0.1)
				(type default)
			)
			(layer "B.Fab")
		)
		(fp_line
			(start -1.1049 -0.724916)
			(end 1.1049 -0.724916)
			(stroke
				(width 0.1)
				(type default)
			)
			(layer "B.Fab")
		)
		(fp_line
			(start 1.1049 -0.724916)
			(end 1.1049 0.724916)
			(stroke
				(width 0.1)
				(type default)
			)
			(layer "B.Fab")
		)
		(pad "1" smd rect
			(at 0.889 0 270)
			(size 1.016 1.27)
			(layers "B.Cu" "B.Mask" "B.Paste")
			(net "SW_P12V_AUX_PVDDCR_CPU1_P1_FLT")
		)
		(pad "2" smd rect
			(at -0.889 0 270)
			(size 1.016 1.27)
			(layers "B.Cu" "B.Mask" "B.Paste")
			(net "GND")
		)
	)
	(footprint ""
		(layer "B.Cu")
		(at 235.839 -240.411 -90)
		(property "Reference" "R1157"
			(at 0 0 90)
			(layer "B.SilkS")
			(hide yes)
			(effects
				(font
					(size 1.27 1.27)
				)
				(justify mirror)
			)
		)
		(property "Value" ""
			(at 0 0 90)
			(layer "B.Fab")
			(effects
				(font
					(size 1.27 1.27)
				)
				(justify mirror)
			)
		)
		(duplicate_pad_numbers_are_jumpers no)
		(fp_line
			(start -0.7874 0.4064)
			(end 0.7874 0.4064)
			(stroke
				(width 0.1524)
				(type default)
			)
			(layer "B.SilkS")
		)
		(fp_line
			(start 0.7874 0.4064)
			(end 0.7874 -0.4064)
			(stroke
				(width 0.1524)
				(type default)
			)
			(layer "B.SilkS")
		)
		(fp_line
			(start -0.7874 -0.4064)
			(end -0.7874 0.4064)
			(stroke
				(width 0.1524)
				(type default)
			)
			(layer "B.SilkS")
		)
		(fp_line
			(start 0.7874 -0.4064)
			(end -0.7874 -0.4064)
			(stroke
				(width 0.1524)
				(type default)
			)
			(layer "B.SilkS")
		)
		(fp_line
			(start -0.67945 0.3048)
			(end -0.120396 0.3048)
			(stroke
				(width 0.1)
				(type default)
			)
			(layer "B.Fab")
		)
		(fp_line
			(start -0.120396 0.3048)
			(end -0.120396 0.2794)
			(stroke
				(width 0.1)
				(type default)
			)
			(layer "B.Fab")
		)
		(fp_line
			(start 0.12065 0.3048)
			(end 0.67945 0.3048)
			(stroke
				(width 0.1)
				(type default)
			)
			(layer "B.Fab")
		)
		(fp_line
			(start 0.67945 0.3048)
			(end 0.67945 -0.305054)
			(stroke
				(width 0.1)
				(type default)
			)
			(layer "B.Fab")
		)
		(fp_line
			(start -0.120396 0.2794)
			(end 0.12065 0.2794)
			(stroke
				(width 0.1)
				(type default)
			)
			(layer "B.Fab")
		)
		(fp_line
			(start 0.12065 0.2794)
			(end 0.12065 0.3048)
			(stroke
				(width 0.1)
				(type default)
			)
			(layer "B.Fab")
		)
		(fp_line
			(start -0.12065 -0.2794)
			(end -0.12065 -0.3048)
			(stroke
				(width 0.1)
				(type default)
			)
			(layer "B.Fab")
		)
		(fp_line
			(start 0.12065 -0.2794)
			(end -0.12065 -0.2794)
			(stroke
				(width 0.1)
				(type default)
			)
			(layer "B.Fab")
		)
		(fp_line
			(start -0.67945 -0.3048)
			(end -0.67945 0.3048)
			(stroke
				(width 0.1)
				(type default)
			)
			(layer "B.Fab")
		)
		(fp_line
			(start -0.12065 -0.3048)
			(end -0.67945 -0.3048)
			(stroke
				(width 0.1)
				(type default)
			)
			(layer "B.Fab")
		)
		(fp_line
			(start 0.12065 -0.305054)
			(end 0.12065 -0.2794)
			(stroke
				(width 0.1)
				(type default)
			)
			(layer "B.Fab")
		)
		(fp_line
			(start 0.67945 -0.305054)
			(end 0.12065 -0.305054)
			(stroke
				(width 0.1)
				(type default)
			)
			(layer "B.Fab")
		)
		(pad "1" smd rect
			(at 0.40005 0 270)
			(size 0.4572 0.508)
			(layers "B.Cu" "B.Mask" "B.Paste")
			(net "SMB_APML_CPU1_R_SCL")
		)
		(pad "2" smd rect
			(at -0.40005 0 270)
			(size 0.4572 0.508)
			(layers "B.Cu" "B.Mask" "B.Paste")
			(net "SMB_APML_CPU1_SCL")
		)
	)
	(footprint ""
		(layer "B.Cu")
		(at 231.882696 -324.980554 180)
		(property "Reference" "R1246"
			(at 0 0 0)
			(layer "B.SilkS")
			(hide yes)
			(effects
				(font
					(size 1.27 1.27)
				)
				(justify mirror)
			)
		)
		(property "Value" ""
			(at 0 0 0)
			(layer "B.Fab")
			(effects
				(font
					(size 1.27 1.27)
				)
				(justify mirror)
			)
		)
		(duplicate_pad_numbers_are_jumpers no)
		(fp_line
			(start 0.7874 0.4064)
			(end 0.7874 -0.4064)
			(stroke
				(width 0.1524)
				(type default)
			)
			(layer "B.SilkS")
		)
		(fp_line
			(start 0.7874 -0.4064)
			(end -0.7874 -0.4064)
			(stroke
				(width 0.1524)
				(type default)
			)
			(layer "B.SilkS")
		)
		(fp_line
			(start -0.7874 0.4064)
			(end 0.7874 0.4064)
			(stroke
				(width 0.1524)
				(type default)
			)
			(layer "B.SilkS")
		)
		(fp_line
			(start -0.7874 -0.4064)
			(end -0.7874 0.4064)
			(stroke
				(width 0.1524)
				(type default)
			)
			(layer "B.SilkS")
		)
		(fp_line
			(start 0.67945 0.3048)
			(end 0.67945 -0.305054)
			(stroke
				(width 0.1)
				(type default)
			)
			(layer "B.Fab")
		)
		(fp_line
			(start 0.67945 -0.305054)
			(end 0.12065 -0.305054)
			(stroke
				(width 0.1)
				(type default)
			)
			(layer "B.Fab")
		)
		(fp_line
			(start 0.12065 0.3048)
			(end 0.67945 0.3048)
			(stroke
				(width 0.1)
				(type default)
			)
			(layer "B.Fab")
		)
		(fp_line
			(start 0.12065 0.2794)
			(end 0.12065 0.3048)
			(stroke
				(width 0.1)
				(type default)
			)
			(layer "B.Fab")
		)
		(fp_line
			(start 0.12065 -0.2794)
			(end -0.12065 -0.2794)
			(stroke
				(width 0.1)
				(type default)
			)
			(layer "B.Fab")
		)
		(fp_line
			(start 0.12065 -0.305054)
			(end 0.12065 -0.2794)
			(stroke
				(width 0.1)
				(type default)
			)
			(layer "B.Fab")
		)
		(fp_line
			(start -0.120396 0.3048)
			(end -0.120396 0.2794)
			(stroke
				(width 0.1)
				(type default)
			)
			(layer "B.Fab")
		)
		(fp_line
			(start -0.120396 0.2794)
			(end 0.12065 0.2794)
			(stroke
				(width 0.1)
				(type default)
			)
			(layer "B.Fab")
		)
		(fp_line
			(start -0.12065 -0.2794)
			(end -0.12065 -0.3048)
			(stroke
				(width 0.1)
				(type default)
			)
			(layer "B.Fab")
		)
		(fp_line
			(start -0.12065 -0.3048)
			(end -0.67945 -0.3048)
			(stroke
				(width 0.1)
				(type default)
			)
			(layer "B.Fab")
		)
		(fp_line
			(start -0.67945 0.3048)
			(end -0.120396 0.3048)
			(stroke
				(width 0.1)
				(type default)
			)
			(layer "B.Fab")
		)
		(fp_line
			(start -0.67945 -0.3048)
			(end -0.67945 0.3048)
			(stroke
				(width 0.1)
				(type default)
			)
			(layer "B.Fab")
		)
		(pad "1" smd rect
			(at 0.40005 0 180)
			(size 0.4572 0.508)
			(layers "B.Cu" "B.Mask" "B.Paste")
			(net "P1V8_CPU0_RT_1D_ADC")
		)
		(pad "2" smd rect
			(at -0.40005 0 180)
			(size 0.4572 0.508)
			(layers "B.Cu" "B.Mask" "B.Paste")
			(net "P1V8_CPU0_RT_1D_ADC_MAM")
		)
	)
	(footprint ""
		(layer "B.Cu")
		(at 327.823068 -338.927694 -90)
		(property "Reference" "PC93_2"
			(at 0 0 90)
			(layer "B.SilkS")
			(hide yes)
			(effects
				(font
					(size 1.27 1.27)
				)
				(justify mirror)
			)
		)
		(property "Value" ""
			(at 0 0 90)
			(layer "B.Fab")
			(effects
				(font
					(size 1.27 1.27)
				)
				(justify mirror)
			)
		)
		(duplicate_pad_numbers_are_jumpers no)
		(fp_line
			(start -1.524 0.762)
			(end 1.524 0.762)
			(stroke
				(width 0.1524)
				(type default)
			)
			(layer "B.SilkS")
		)
		(fp_line
			(start 1.524 0.762)
			(end 1.524 -0.762)
			(stroke
				(width 0.1524)
				(type default)
			)
			(layer "B.SilkS")
		)
		(fp_line
			(start -1.524 -0.762)
			(end -1.524 0.762)
			(stroke
				(width 0.1524)
				(type default)
			)
			(layer "B.SilkS")
		)
		(fp_line
			(start 1.524 -0.762)
			(end -1.524 -0.762)
			(stroke
				(width 0.1524)
				(type default)
			)
			(layer "B.SilkS")
		)
		(fp_line
			(start -1.1049 0.724916)
			(end -1.1049 -0.724916)
			(stroke
				(width 0.1)
				(type default)
			)
			(layer "B.Fab")
		)
		(fp_line
			(start 1.1049 0.724916)
			(end -1.1049 0.724916)
			(stroke
				(width 0.1)
				(type default)
			)
			(layer "B.Fab")
		)
		(fp_line
			(start -1.1049 -0.724916)
			(end 1.1049 -0.724916)
			(stroke
				(width 0.1)
				(type default)
			)
			(layer "B.Fab")
		)
		(fp_line
			(start 1.1049 -0.724916)
			(end 1.1049 0.724916)
			(stroke
				(width 0.1)
				(type default)
			)
			(layer "B.Fab")
		)
		(pad "1" smd rect
			(at 0.889 0 270)
			(size 1.016 1.27)
			(layers "B.Cu" "B.Mask" "B.Paste")
			(net "SW_P12V_AUX_PVDDCR_CPU1_P0_FLT")
		)
		(pad "2" smd rect
			(at -0.889 0 270)
			(size 1.016 1.27)
			(layers "B.Cu" "B.Mask" "B.Paste")
			(net "GND")
		)
	)
	(footprint ""
		(layer "B.Cu")
		(at 299.82414 -192.660016)
		(property "Reference" "C143"
			(at 0 0 0)
			(layer "B.SilkS")
			(hide yes)
			(effects
				(font
					(size 1.27 1.27)
				)
				(justify mirror)
			)
		)
		(property "Value" ""
			(at 0 0 0)
			(layer "B.Fab")
			(effects
				(font
					(size 1.27 1.27)
				)
				(justify mirror)
			)
		)
		(duplicate_pad_numbers_are_jumpers no)
		(fp_line
			(start -1.524 -0.762)
			(end -1.524 0.762)
			(stroke
				(width 0.1524)
				(type default)
			)
			(layer "B.SilkS")
		)
		(fp_line
			(start -1.524 0.762)
			(end 1.524 0.762)
			(stroke
				(width 0.1524)
				(type default)
			)
			(layer "B.SilkS")
		)
		(fp_line
			(start 1.524 -0.762)
			(end -1.524 -0.762)
			(stroke
				(width 0.1524)
				(type default)
			)
			(layer "B.SilkS")
		)
		(fp_line
			(start 1.524 0.762)
			(end 1.524 -0.762)
			(stroke
				(width 0.1524)
				(type default)
			)
			(layer "B.SilkS")
		)
		(fp_line
			(start -1.1049 -0.724916)
			(end 1.1049 -0.724916)
			(stroke
				(width 0.1)
				(type default)
			)
			(layer "B.Fab")
		)
		(fp_line
			(start -1.1049 0.724916)
			(end -1.1049 -0.724916)
			(stroke
				(width 0.1)
				(type default)
			)
			(layer "B.Fab")
		)
		(fp_line
			(start 1.1049 -0.724916)
			(end 1.1049 0.724916)
			(stroke
				(width 0.1)
				(type default)
			)
			(layer "B.Fab")
		)
		(fp_line
			(start 1.1049 0.724916)
			(end -1.1049 0.724916)
			(stroke
				(width 0.1)
				(type default)
			)
			(layer "B.Fab")
		)
		(pad "1" smd rect
			(at 0.889 0)
			(size 1.016 1.27)
			(layers "B.Cu" "B.Mask" "B.Paste")
			(net "P12V_MEM_CPU0")
		)
		(pad "2" smd rect
			(at -0.889 0)
			(size 1.016 1.27)
			(layers "B.Cu" "B.Mask" "B.Paste")
			(net "GND")
		)
	)
	(footprint ""
		(layer "B.Cu")
		(at 138.65352 -36.701222 180)
		(property "Reference" "C6057"
			(at 0 0 0)
			(layer "B.SilkS")
			(hide yes)
			(effects
				(font
					(size 1.27 1.27)
				)
				(justify mirror)
			)
		)
		(property "Value" ""
			(at 0 0 0)
			(layer "B.Fab")
			(effects
				(font
					(size 1.27 1.27)
				)
				(justify mirror)
			)
		)
		(duplicate_pad_numbers_are_jumpers no)
		(fp_line
			(start 0.7874 0.4064)
			(end 0.7874 -0.4064)
			(stroke
				(width 0.1524)
				(type default)
			)
			(layer "B.SilkS")
		)
		(fp_line
			(start 0.7874 -0.4064)
			(end -0.7874 -0.4064)
			(stroke
				(width 0.1524)
				(type default)
			)
			(layer "B.SilkS")
		)
		(fp_line
			(start -0.7874 0.4064)
			(end 0.7874 0.4064)
			(stroke
				(width 0.1524)
				(type default)
			)
			(layer "B.SilkS")
		)
		(fp_line
			(start -0.7874 -0.4064)
			(end -0.7874 0.4064)
			(stroke
				(width 0.1524)
				(type default)
			)
			(layer "B.SilkS")
		)
		(fp_line
			(start 0.67945 0.3048)
			(end 0.67945 -0.305054)
			(stroke
				(width 0.1)
				(type default)
			)
			(layer "B.Fab")
		)
		(fp_line
			(start 0.67945 -0.305054)
			(end 0.12065 -0.305054)
			(stroke
				(width 0.1)
				(type default)
			)
			(layer "B.Fab")
		)
		(fp_line
			(start 0.12065 0.3048)
			(end 0.67945 0.3048)
			(stroke
				(width 0.1)
				(type default)
			)
			(layer "B.Fab")
		)
		(fp_line
			(start 0.12065 0.2794)
			(end 0.12065 0.3048)
			(stroke
				(width 0.1)
				(type default)
			)
			(layer "B.Fab")
		)
		(fp_line
			(start 0.12065 -0.2794)
			(end -0.12065 -0.2794)
			(stroke
				(width 0.1)
				(type default)
			)
			(layer "B.Fab")
		)
		(fp_line
			(start 0.12065 -0.305054)
			(end 0.12065 -0.2794)
			(stroke
				(width 0.1)
				(type default)
			)
			(layer "B.Fab")
		)
		(fp_line
			(start -0.120396 0.3048)
			(end -0.120396 0.2794)
			(stroke
				(width 0.1)
				(type default)
			)
			(layer "B.Fab")
		)
		(fp_line
			(start -0.120396 0.2794)
			(end 0.12065 0.2794)
			(stroke
				(width 0.1)
				(type default)
			)
			(layer "B.Fab")
		)
		(fp_line
			(start -0.12065 -0.2794)
			(end -0.12065 -0.3048)
			(stroke
				(width 0.1)
				(type default)
			)
			(layer "B.Fab")
		)
		(fp_line
			(start -0.12065 -0.3048)
			(end -0.67945 -0.3048)
			(stroke
				(width 0.1)
				(type default)
			)
			(layer "B.Fab")
		)
		(fp_line
			(start -0.67945 0.3048)
			(end -0.120396 0.3048)
			(stroke
				(width 0.1)
				(type default)
			)
			(layer "B.Fab")
		)
		(fp_line
			(start -0.67945 -0.3048)
			(end -0.67945 0.3048)
			(stroke
				(width 0.1)
				(type default)
			)
			(layer "B.Fab")
		)
		(pad "1" smd circle
			(at 0.40005 0)
			(size 0 0)
			(layers "B.Cu" "B.Mask" "B.Paste")
			(net "P1V2_AUX")
		)
		(pad "2" smd circle
			(at -0.40005 0)
			(size 0 0)
			(layers "B.Cu" "B.Mask" "B.Paste")
			(net "GND")
		)
	)
	(footprint ""
		(layer "B.Cu")
		(at 353.900232 -257.455162 180)
		(property "Reference" "C2644"
			(at 0 0 0)
			(layer "B.SilkS")
			(hide yes)
			(effects
				(font
					(size 1.27 1.27)
				)
				(justify mirror)
			)
		)
		(property "Value" ""
			(at 0 0 0)
			(layer "B.Fab")
			(effects
				(font
					(size 1.27 1.27)
				)
				(justify mirror)
			)
		)
		(duplicate_pad_numbers_are_jumpers no)
		(fp_line
			(start 0.7874 0.4064)
			(end 0.7874 -0.4064)
			(stroke
				(width 0.1524)
				(type default)
			)
			(layer "B.SilkS")
		)
		(fp_line
			(start 0.7874 -0.4064)
			(end -0.7874 -0.4064)
			(stroke
				(width 0.1524)
				(type default)
			)
			(layer "B.SilkS")
		)
		(fp_line
			(start -0.7874 0.4064)
			(end 0.7874 0.4064)
			(stroke
				(width 0.1524)
				(type default)
			)
			(layer "B.SilkS")
		)
		(fp_line
			(start -0.7874 -0.4064)
			(end -0.7874 0.4064)
			(stroke
				(width 0.1524)
				(type default)
			)
			(layer "B.SilkS")
		)
		(fp_line
			(start 0.67945 0.3048)
			(end 0.67945 -0.305054)
			(stroke
				(width 0.1)
				(type default)
			)
			(layer "B.Fab")
		)
		(fp_line
			(start 0.67945 -0.305054)
			(end 0.12065 -0.305054)
			(stroke
				(width 0.1)
				(type default)
			)
			(layer "B.Fab")
		)
		(fp_line
			(start 0.12065 0.3048)
			(end 0.67945 0.3048)
			(stroke
				(width 0.1)
				(type default)
			)
			(layer "B.Fab")
		)
		(fp_line
			(start 0.12065 0.2794)
			(end 0.12065 0.3048)
			(stroke
				(width 0.1)
				(type default)
			)
			(layer "B.Fab")
		)
		(fp_line
			(start 0.12065 -0.2794)
			(end -0.12065 -0.2794)
			(stroke
				(width 0.1)
				(type default)
			)
			(layer "B.Fab")
		)
		(fp_line
			(start 0.12065 -0.305054)
			(end 0.12065 -0.2794)
			(stroke
				(width 0.1)
				(type default)
			)
			(layer "B.Fab")
		)
		(fp_line
			(start -0.120396 0.3048)
			(end -0.120396 0.2794)
			(stroke
				(width 0.1)
				(type default)
			)
			(layer "B.Fab")
		)
		(fp_line
			(start -0.120396 0.2794)
			(end 0.12065 0.2794)
			(stroke
				(width 0.1)
				(type default)
			)
			(layer "B.Fab")
		)
		(fp_line
			(start -0.12065 -0.2794)
			(end -0.12065 -0.3048)
			(stroke
				(width 0.1)
				(type default)
			)
			(layer "B.Fab")
		)
		(fp_line
			(start -0.12065 -0.3048)
			(end -0.67945 -0.3048)
			(stroke
				(width 0.1)
				(type default)
			)
			(layer "B.Fab")
		)
		(fp_line
			(start -0.67945 0.3048)
			(end -0.120396 0.3048)
			(stroke
				(width 0.1)
				(type default)
			)
			(layer "B.Fab")
		)
		(fp_line
			(start -0.67945 -0.3048)
			(end -0.67945 0.3048)
			(stroke
				(width 0.1)
				(type default)
			)
			(layer "B.Fab")
		)
		(pad "1" smd circle
			(at 0.40005 0)
			(size 0 0)
			(layers "B.Cu" "B.Mask" "B.Paste")
			(net "PVDDIO_P0")
		)
		(pad "2" smd circle
			(at -0.40005 0)
			(size 0 0)
			(layers "B.Cu" "B.Mask" "B.Paste")
			(net "GND")
		)
	)
	(footprint ""
		(layer "B.Cu")
		(at 359.417112 -261.747762 90)
		(property "Reference" "C2610"
			(at 0 0 90)
			(layer "B.SilkS")
			(hide yes)
			(effects
				(font
					(size 1.27 1.27)
				)
				(justify mirror)
			)
		)
		(property "Value" ""
			(at 0 0 90)
			(layer "B.Fab")
			(effects
				(font
					(size 1.27 1.27)
				)
				(justify mirror)
			)
		)
		(duplicate_pad_numbers_are_jumpers no)
		(fp_line
			(start 0.7874 -0.4064)
			(end -0.7874 -0.4064)
			(stroke
				(width 0.1524)
				(type default)
			)
			(layer "B.SilkS")
		)
		(fp_line
			(start -0.7874 -0.4064)
			(end -0.7874 0.4064)
			(stroke
				(width 0.1524)
				(type default)
			)
			(layer "B.SilkS")
		)
		(fp_line
			(start 0.7874 0.4064)
			(end 0.7874 -0.4064)
			(stroke
				(width 0.1524)
				(type default)
			)
			(layer "B.SilkS")
		)
		(fp_line
			(start -0.7874 0.4064)
			(end 0.7874 0.4064)
			(stroke
				(width 0.1524)
				(type default)
			)
			(layer "B.SilkS")
		)
		(fp_line
			(start 0.67945 -0.305054)
			(end 0.12065 -0.305054)
			(stroke
				(width 0.1)
				(type default)
			)
			(layer "B.Fab")
		)
		(fp_line
			(start 0.12065 -0.305054)
			(end 0.12065 -0.2794)
			(stroke
				(width 0.1)
				(type default)
			)
			(layer "B.Fab")
		)
		(fp_line
			(start -0.12065 -0.3048)
			(end -0.67945 -0.3048)
			(stroke
				(width 0.1)
				(type default)
			)
			(layer "B.Fab")
		)
		(fp_line
			(start -0.67945 -0.3048)
			(end -0.67945 0.3048)
			(stroke
				(width 0.1)
				(type default)
			)
			(layer "B.Fab")
		)
		(fp_line
			(start 0.12065 -0.2794)
			(end -0.12065 -0.2794)
			(stroke
				(width 0.1)
				(type default)
			)
			(layer "B.Fab")
		)
		(fp_line
			(start -0.12065 -0.2794)
			(end -0.12065 -0.3048)
			(stroke
				(width 0.1)
				(type default)
			)
			(layer "B.Fab")
		)
		(fp_line
			(start 0.12065 0.2794)
			(end 0.12065 0.3048)
			(stroke
				(width 0.1)
				(type default)
			)
			(layer "B.Fab")
		)
		(fp_line
			(start -0.120396 0.2794)
			(end 0.12065 0.2794)
			(stroke
				(width 0.1)
				(type default)
			)
			(layer "B.Fab")
		)
		(fp_line
			(start 0.67945 0.3048)
			(end 0.67945 -0.305054)
			(stroke
				(width 0.1)
				(type default)
			)
			(layer "B.Fab")
		)
		(fp_line
			(start 0.12065 0.3048)
			(end 0.67945 0.3048)
			(stroke
				(width 0.1)
				(type default)
			)
			(layer "B.Fab")
		)
		(fp_line
			(start -0.120396 0.3048)
			(end -0.120396 0.2794)
			(stroke
				(width 0.1)
				(type default)
			)
			(layer "B.Fab")
		)
		(fp_line
			(start -0.67945 0.3048)
			(end -0.120396 0.3048)
			(stroke
				(width 0.1)
				(type default)
			)
			(layer "B.Fab")
		)
		(pad "1" smd circle
			(at 0.40005 0 270)
			(size 0 0)
			(layers "B.Cu" "B.Mask" "B.Paste")
			(net "PVDD11_S3_P0")
		)
		(pad "2" smd circle
			(at -0.40005 0 270)
			(size 0 0)
			(layers "B.Cu" "B.Mask" "B.Paste")
			(net "GND")
		)
	)
	(footprint ""
		(layer "B.Cu")
		(at 163.387532 -432.37658 90)
		(property "Reference" "R4130"
			(at 0 0 90)
			(layer "B.SilkS")
			(hide yes)
			(effects
				(font
					(size 1.27 1.27)
				)
				(justify mirror)
			)
		)
		(property "Value" ""
			(at 0 0 90)
			(layer "B.Fab")
			(effects
				(font
					(size 1.27 1.27)
				)
				(justify mirror)
			)
		)
		(duplicate_pad_numbers_are_jumpers no)
		(fp_line
			(start 0.7874 -0.4064)
			(end -0.7874 -0.4064)
			(stroke
				(width 0.1524)
				(type default)
			)
			(layer "B.SilkS")
		)
		(fp_line
			(start -0.7874 -0.4064)
			(end -0.7874 0.4064)
			(stroke
				(width 0.1524)
				(type default)
			)
			(layer "B.SilkS")
		)
		(fp_line
			(start 0.7874 0.4064)
			(end 0.7874 -0.4064)
			(stroke
				(width 0.1524)
				(type default)
			)
			(layer "B.SilkS")
		)
		(fp_line
			(start -0.7874 0.4064)
			(end 0.7874 0.4064)
			(stroke
				(width 0.1524)
				(type default)
			)
			(layer "B.SilkS")
		)
		(fp_line
			(start 0.67945 -0.305054)
			(end 0.12065 -0.305054)
			(stroke
				(width 0.1)
				(type default)
			)
			(layer "B.Fab")
		)
		(fp_line
			(start 0.12065 -0.305054)
			(end 0.12065 -0.2794)
			(stroke
				(width 0.1)
				(type default)
			)
			(layer "B.Fab")
		)
		(fp_line
			(start -0.12065 -0.3048)
			(end -0.67945 -0.3048)
			(stroke
				(width 0.1)
				(type default)
			)
			(layer "B.Fab")
		)
		(fp_line
			(start -0.67945 -0.3048)
			(end -0.67945 0.3048)
			(stroke
				(width 0.1)
				(type default)
			)
			(layer "B.Fab")
		)
		(fp_line
			(start 0.12065 -0.2794)
			(end -0.12065 -0.2794)
			(stroke
				(width 0.1)
				(type default)
			)
			(layer "B.Fab")
		)
		(fp_line
			(start -0.12065 -0.2794)
			(end -0.12065 -0.3048)
			(stroke
				(width 0.1)
				(type default)
			)
			(layer "B.Fab")
		)
		(fp_line
			(start 0.12065 0.2794)
			(end 0.12065 0.3048)
			(stroke
				(width 0.1)
				(type default)
			)
			(layer "B.Fab")
		)
		(fp_line
			(start -0.120396 0.2794)
			(end 0.12065 0.2794)
			(stroke
				(width 0.1)
				(type default)
			)
			(layer "B.Fab")
		)
		(fp_line
			(start 0.67945 0.3048)
			(end 0.67945 -0.305054)
			(stroke
				(width 0.1)
				(type default)
			)
			(layer "B.Fab")
		)
		(fp_line
			(start 0.12065 0.3048)
			(end 0.67945 0.3048)
			(stroke
				(width 0.1)
				(type default)
			)
			(layer "B.Fab")
		)
		(fp_line
			(start -0.120396 0.3048)
			(end -0.120396 0.2794)
			(stroke
				(width 0.1)
				(type default)
			)
			(layer "B.Fab")
		)
		(fp_line
			(start -0.67945 0.3048)
			(end -0.120396 0.3048)
			(stroke
				(width 0.1)
				(type default)
			)
			(layer "B.Fab")
		)
		(pad "1" smd circle
			(at 0.40005 0 270)
			(size 0 0)
			(layers "B.Cu" "B.Mask" "B.Paste")
			(net "P3V3_AUX")
		)
		(pad "2" smd circle
			(at -0.40005 0 270)
			(size 0 0)
			(layers "B.Cu" "B.Mask" "B.Paste")
			(net "GPU_3V3IO_RSVD1_FFU_ISO")
		)
	)
	(footprint ""
		(layer "B.Cu")
		(at 235.077 -231.648 -90)
		(property "Reference" "R369"
			(at 0 0 90)
			(layer "B.SilkS")
			(hide yes)
			(effects
				(font
					(size 1.27 1.27)
				)
				(justify mirror)
			)
		)
		(property "Value" ""
			(at 0 0 90)
			(layer "B.Fab")
			(effects
				(font
					(size 1.27 1.27)
				)
				(justify mirror)
			)
		)
		(duplicate_pad_numbers_are_jumpers no)
		(fp_line
			(start -0.7874 0.4064)
			(end 0.7874 0.4064)
			(stroke
				(width 0.1524)
				(type default)
			)
			(layer "B.SilkS")
		)
		(fp_line
			(start 0.7874 0.4064)
			(end 0.7874 -0.4064)
			(stroke
				(width 0.1524)
				(type default)
			)
			(layer "B.SilkS")
		)
		(fp_line
			(start -0.7874 -0.4064)
			(end -0.7874 0.4064)
			(stroke
				(width 0.1524)
				(type default)
			)
			(layer "B.SilkS")
		)
		(fp_line
			(start 0.7874 -0.4064)
			(end -0.7874 -0.4064)
			(stroke
				(width 0.1524)
				(type default)
			)
			(layer "B.SilkS")
		)
		(fp_line
			(start -0.67945 0.3048)
			(end -0.120396 0.3048)
			(stroke
				(width 0.1)
				(type default)
			)
			(layer "B.Fab")
		)
		(fp_line
			(start -0.120396 0.3048)
			(end -0.120396 0.2794)
			(stroke
				(width 0.1)
				(type default)
			)
			(layer "B.Fab")
		)
		(fp_line
			(start 0.12065 0.3048)
			(end 0.67945 0.3048)
			(stroke
				(width 0.1)
				(type default)
			)
			(layer "B.Fab")
		)
		(fp_line
			(start 0.67945 0.3048)
			(end 0.67945 -0.305054)
			(stroke
				(width 0.1)
				(type default)
			)
			(layer "B.Fab")
		)
		(fp_line
			(start -0.120396 0.2794)
			(end 0.12065 0.2794)
			(stroke
				(width 0.1)
				(type default)
			)
			(layer "B.Fab")
		)
		(fp_line
			(start 0.12065 0.2794)
			(end 0.12065 0.3048)
			(stroke
				(width 0.1)
				(type default)
			)
			(layer "B.Fab")
		)
		(fp_line
			(start -0.12065 -0.2794)
			(end -0.12065 -0.3048)
			(stroke
				(width 0.1)
				(type default)
			)
			(layer "B.Fab")
		)
		(fp_line
			(start 0.12065 -0.2794)
			(end -0.12065 -0.2794)
			(stroke
				(width 0.1)
				(type default)
			)
			(layer "B.Fab")
		)
		(fp_line
			(start -0.67945 -0.3048)
			(end -0.67945 0.3048)
			(stroke
				(width 0.1)
				(type default)
			)
			(layer "B.Fab")
		)
		(fp_line
			(start -0.12065 -0.3048)
			(end -0.67945 -0.3048)
			(stroke
				(width 0.1)
				(type default)
			)
			(layer "B.Fab")
		)
		(fp_line
			(start 0.12065 -0.305054)
			(end 0.12065 -0.2794)
			(stroke
				(width 0.1)
				(type default)
			)
			(layer "B.Fab")
		)
		(fp_line
			(start 0.67945 -0.305054)
			(end 0.12065 -0.305054)
			(stroke
				(width 0.1)
				(type default)
			)
			(layer "B.Fab")
		)
		(pad "1" smd circle
			(at 0.40005 0 90)
			(size 0 0)
			(layers "B.Cu" "B.Mask" "B.Paste")
			(net "PVDD18_S5_P1")
		)
		(pad "2" smd circle
			(at -0.40005 0 90)
			(size 0 0)
			(layers "B.Cu" "B.Mask" "B.Paste")
			(net "SMB_CPU1_SEC_SDA")
		)
	)
	(footprint ""
		(layer "B.Cu")
		(at 391.636758 -203.50099)
		(property "Reference" "R6084"
			(at 0 0 0)
			(layer "B.SilkS")
			(hide yes)
			(effects
				(font
					(size 1.27 1.27)
				)
				(justify mirror)
			)
		)
		(property "Value" ""
			(at 0 0 0)
			(layer "B.Fab")
			(effects
				(font
					(size 1.27 1.27)
				)
				(justify mirror)
			)
		)
		(duplicate_pad_numbers_are_jumpers no)
		(fp_line
			(start -0.7874 -0.4064)
			(end -0.7874 0.4064)
			(stroke
				(width 0.1524)
				(type default)
			)
			(layer "B.SilkS")
		)
		(fp_line
			(start -0.7874 0.4064)
			(end 0.7874 0.4064)
			(stroke
				(width 0.1524)
				(type default)
			)
			(layer "B.SilkS")
		)
		(fp_line
			(start 0.7874 -0.4064)
			(end -0.7874 -0.4064)
			(stroke
				(width 0.1524)
				(type default)
			)
			(layer "B.SilkS")
		)
		(fp_line
			(start 0.7874 0.4064)
			(end 0.7874 -0.4064)
			(stroke
				(width 0.1524)
				(type default)
			)
			(layer "B.SilkS")
		)
		(fp_line
			(start -0.67945 -0.3048)
			(end -0.67945 0.3048)
			(stroke
				(width 0.1)
				(type default)
			)
			(layer "B.Fab")
		)
		(fp_line
			(start -0.67945 0.3048)
			(end -0.120396 0.3048)
			(stroke
				(width 0.1)
				(type default)
			)
			(layer "B.Fab")
		)
		(fp_line
			(start -0.12065 -0.3048)
			(end -0.67945 -0.3048)
			(stroke
				(width 0.1)
				(type default)
			)
			(layer "B.Fab")
		)
		(fp_line
			(start -0.12065 -0.2794)
			(end -0.12065 -0.3048)
			(stroke
				(width 0.1)
				(type default)
			)
			(layer "B.Fab")
		)
		(fp_line
			(start -0.120396 0.2794)
			(end 0.12065 0.2794)
			(stroke
				(width 0.1)
				(type default)
			)
			(layer "B.Fab")
		)
		(fp_line
			(start -0.120396 0.3048)
			(end -0.120396 0.2794)
			(stroke
				(width 0.1)
				(type default)
			)
			(layer "B.Fab")
		)
		(fp_line
			(start 0.12065 -0.305054)
			(end 0.12065 -0.2794)
			(stroke
				(width 0.1)
				(type default)
			)
			(layer "B.Fab")
		)
		(fp_line
			(start 0.12065 -0.2794)
			(end -0.12065 -0.2794)
			(stroke
				(width 0.1)
				(type default)
			)
			(layer "B.Fab")
		)
		(fp_line
			(start 0.12065 0.2794)
			(end 0.12065 0.3048)
			(stroke
				(width 0.1)
				(type default)
			)
			(layer "B.Fab")
		)
		(fp_line
			(start 0.12065 0.3048)
			(end 0.67945 0.3048)
			(stroke
				(width 0.1)
				(type default)
			)
			(layer "B.Fab")
		)
		(fp_line
			(start 0.67945 -0.305054)
			(end 0.12065 -0.305054)
			(stroke
				(width 0.1)
				(type default)
			)
			(layer "B.Fab")
		)
		(fp_line
			(start 0.67945 0.3048)
			(end 0.67945 -0.305054)
			(stroke
				(width 0.1)
				(type default)
			)
			(layer "B.Fab")
		)
		(pad "1" smd circle
			(at 0.40005 0 180)
			(size 0 0)
			(layers "B.Cu" "B.Mask" "B.Paste")
			(net "PVDD11_S3_P0")
		)
		(pad "2" smd circle
			(at -0.40005 0 180)
			(size 0 0)
			(layers "B.Cu" "B.Mask" "B.Paste")
			(net "SMB_CPU0_3_SDA")
		)
	)
	(footprint ""
		(layer "B.Cu")
		(at 361.255056 -177.894996 -90)
		(property "Reference" "PC487_1"
			(at 0 0 90)
			(layer "B.SilkS")
			(hide yes)
			(effects
				(font
					(size 1.27 1.27)
				)
				(justify mirror)
			)
		)
		(property "Value" ""
			(at 0 0 90)
			(layer "B.Fab")
			(effects
				(font
					(size 1.27 1.27)
				)
				(justify mirror)
			)
		)
		(duplicate_pad_numbers_are_jumpers no)
		(fp_line
			(start -1.524 0.762)
			(end 1.524 0.762)
			(stroke
				(width 0.1524)
				(type default)
			)
			(layer "B.SilkS")
		)
		(fp_line
			(start 1.524 0.762)
			(end 1.524 -0.762)
			(stroke
				(width 0.1524)
				(type default)
			)
			(layer "B.SilkS")
		)
		(fp_line
			(start -1.524 -0.762)
			(end -1.524 0.762)
			(stroke
				(width 0.1524)
				(type default)
			)
			(layer "B.SilkS")
		)
		(fp_line
			(start 1.524 -0.762)
			(end -1.524 -0.762)
			(stroke
				(width 0.1524)
				(type default)
			)
			(layer "B.SilkS")
		)
		(fp_line
			(start -1.1049 0.724916)
			(end -1.1049 -0.724916)
			(stroke
				(width 0.1)
				(type default)
			)
			(layer "B.Fab")
		)
		(fp_line
			(start 1.1049 0.724916)
			(end -1.1049 0.724916)
			(stroke
				(width 0.1)
				(type default)
			)
			(layer "B.Fab")
		)
		(fp_line
			(start -1.1049 -0.724916)
			(end 1.1049 -0.724916)
			(stroke
				(width 0.1)
				(type default)
			)
			(layer "B.Fab")
		)
		(fp_line
			(start 1.1049 -0.724916)
			(end 1.1049 0.724916)
			(stroke
				(width 0.1)
				(type default)
			)
			(layer "B.Fab")
		)
		(pad "1" smd rect
			(at 0.889 0 270)
			(size 1.016 1.27)
			(layers "B.Cu" "B.Mask" "B.Paste")
			(net "SW_P12V_AUX_PVDDCR_CPU0_P0_FLT")
		)
		(pad "2" smd rect
			(at -0.889 0 270)
			(size 1.016 1.27)
			(layers "B.Cu" "B.Mask" "B.Paste")
			(net "GND")
		)
	)
	(footprint ""
		(layer "B.Cu")
		(at 508.971042 -306.911248 90)
		(property "Reference" "X9005"
			(at 4.62026 -1.55829 90)
			(unlocked yes)
			(layer "B.SilkS")
			(effects
				(font
					(size 0.7874 0.5842)
					(thickness 0.1524)
				)
				(justify left mirror)
			)
		)
		(property "Value" ""
			(at 0 0 90)
			(layer "B.Fab")
			(effects
				(font
					(size 1.27 1.27)
				)
				(justify mirror)
			)
		)
		(property "User Part Number" "N_A"
			(at -1.30175 1.27 0)
			(unlocked yes)
			(layer "Cmts.User")
			(hide yes)
			(effects
				(font
					(size 0.635 0.4064)
					(thickness 0.1524)
				)
				(justify mirror)
			)
		)
		(property "Device Type" "TP_TDR_4P_FTS_TH-TP_TDR_4P_DIP,EMPTY,TP15"
			(at -1.30175 1.27 0)
			(unlocked yes)
			(layer "B.Fab")
			(hide yes)
			(effects
				(font
					(size 0.635 0.4064)
					(thickness 0.1524)
				)
				(justify mirror)
			)
		)
		(duplicate_pad_numbers_are_jumpers no)
		(fp_line
			(start 0 -1.27)
			(end 0 -0.635)
			(stroke
				(width 0.1524)
				(type default)
			)
			(layer "B.SilkS")
		)
		(fp_line
			(start -2.54 -1.27)
			(end 0 -1.27)
			(stroke
				(width 0.1524)
				(type default)
			)
			(layer "B.SilkS")
		)
		(fp_line
			(start -2.54 -1.1303)
			(end -2.54 -1.27)
			(stroke
				(width 0.1524)
				(type default)
			)
			(layer "B.SilkS")
		)
		(fp_line
			(start 0 0.635)
			(end 0 1.905)
			(stroke
				(width 0.1524)
				(type default)
			)
			(layer "B.SilkS")
		)
		(fp_line
			(start -2.54 1.4097)
			(end -2.54 1.1303)
			(stroke
				(width 0.1524)
				(type default)
			)
			(layer "B.SilkS")
		)
		(fp_line
			(start 0 3.175)
			(end 0 3.81)
			(stroke
				(width 0.1524)
				(type default)
			)
			(layer "B.SilkS")
		)
		(fp_line
			(start 0 3.81)
			(end -2.54 3.81)
			(stroke
				(width 0.1524)
				(type default)
			)
			(layer "B.SilkS")
		)
		(fp_line
			(start -2.54 3.81)
			(end -2.54 3.6703)
			(stroke
				(width 0.1524)
				(type default)
			)
			(layer "B.SilkS")
		)
		(fp_poly
			(pts
				(xy 0.761746 0) (xy 2.285746 -0.762) (xy 2.285746 0.762)
			)
			(stroke
				(width 0)
				(type default)
			)
			(fill yes)
			(layer "B.SilkS")
		)
		(fp_line
			(start 0 -1.27)
			(end 0 3.81)
			(stroke
				(width 0.1)
				(type default)
			)
			(layer "B.Fab")
		)
		(fp_line
			(start -2.54 -1.27)
			(end 0 -1.27)
			(stroke
				(width 0.1)
				(type default)
			)
			(layer "B.Fab")
		)
		(fp_line
			(start 0 3.81)
			(end -2.54 3.81)
			(stroke
				(width 0.1)
				(type default)
			)
			(layer "B.Fab")
		)
		(fp_line
			(start -2.54 3.81)
			(end -2.54 -1.27)
			(stroke
				(width 0.1)
				(type default)
			)
			(layer "B.Fab")
		)
		(fp_poly
			(pts
				(xy 0.761746 0) (xy 2.285746 -0.762) (xy 2.285746 0.762)
			)
			(stroke
				(width 0)
				(type default)
			)
			(fill yes)
			(layer "B.Fab")
		)
		(pad "1" thru_hole circle
			(at 0 0 270)
			(size 1.0033 1.0033)
			(drill 0.249936)
			(layers "*.Cu" "*.Mask")
			(remove_unused_layers no)
			(net "TDR_DIFF_85_NECK_IN4_DP")
			(clearance 0.10795)
			(padstack
				(mode front_inner_back)
				(layer "Inner"
					(shape circle)
					(size 0.8001 0.8001)
					(clearance 0.1524)
				)
				(layer "B.Cu"
					(shape circle)
					(size 1.0033 1.0033)
					(thermal_gap 0.10795)
					(clearance 0.10795)
				)
			)
		)
		(pad "2" thru_hole circle
			(at -2.54 0 270)
			(size 1.9939 1.9939)
			(drill 0.249936)
			(layers "*.Cu" "*.Mask")
			(remove_unused_layers no)
			(net "T1_GND")
			(clearance 0.10795)
			(padstack
				(mode front_inner_back)
				(layer "Inner"
					(shape circle)
					(size 0.8001 0.8001)
					(clearance 0.1524)
				)
				(layer "B.Cu"
					(shape circle)
					(size 1.9939 1.9939)
					(thermal_gap 0.10795)
					(clearance 0.10795)
				)
			)
		)
		(pad "3" thru_hole circle
			(at -2.54 2.54 270)
			(size 1.9939 1.9939)
			(drill 0.249936)
			(layers "*.Cu" "*.Mask")
			(remove_unused_layers no)
			(net "T1_GND")
			(clearance 0.10795)
			(padstack
				(mode front_inner_back)
				(layer "Inner"
					(shape circle)
					(size 0.8001 0.8001)
					(clearance 0.1524)
				)
				(layer "B.Cu"
					(shape circle)
					(size 1.9939 1.9939)
					(thermal_gap 0.10795)
					(clearance 0.10795)
				)
			)
		)
		(pad "4" thru_hole circle
			(at 0 2.54 270)
			(size 1.0033 1.0033)
			(drill 0.249936)
			(layers "*.Cu" "*.Mask")
			(remove_unused_layers no)
			(net "TDR_DIFF_85_NECK_IN4_DN")
			(clearance 0.10795)
			(padstack
				(mode front_inner_back)
				(layer "Inner"
					(shape circle)
					(size 0.8001 0.8001)
					(clearance 0.1524)
				)
				(layer "B.Cu"
					(shape circle)
					(size 1.0033 1.0033)
					(thermal_gap 0.10795)
					(clearance 0.10795)
				)
			)
		)
	)
	(footprint ""
		(layer "B.Cu")
		(at 374.715278 -137.789158 -90)
		(property "Reference" "R8309"
			(at 0 0 90)
			(layer "B.SilkS")
			(hide yes)
			(effects
				(font
					(size 1.27 1.27)
				)
				(justify mirror)
			)
		)
		(property "Value" ""
			(at 0 0 90)
			(layer "B.Fab")
			(effects
				(font
					(size 1.27 1.27)
				)
				(justify mirror)
			)
		)
		(duplicate_pad_numbers_are_jumpers no)
		(fp_line
			(start -0.7874 0.4064)
			(end 0.7874 0.4064)
			(stroke
				(width 0.1524)
				(type default)
			)
			(layer "B.SilkS")
		)
		(fp_line
			(start 0.7874 0.4064)
			(end 0.7874 -0.4064)
			(stroke
				(width 0.1524)
				(type default)
			)
			(layer "B.SilkS")
		)
		(fp_line
			(start -0.7874 -0.4064)
			(end -0.7874 0.4064)
			(stroke
				(width 0.1524)
				(type default)
			)
			(layer "B.SilkS")
		)
		(fp_line
			(start 0.7874 -0.4064)
			(end -0.7874 -0.4064)
			(stroke
				(width 0.1524)
				(type default)
			)
			(layer "B.SilkS")
		)
		(fp_line
			(start -0.67945 0.3048)
			(end -0.120396 0.3048)
			(stroke
				(width 0.1)
				(type default)
			)
			(layer "B.Fab")
		)
		(fp_line
			(start -0.120396 0.3048)
			(end -0.120396 0.2794)
			(stroke
				(width 0.1)
				(type default)
			)
			(layer "B.Fab")
		)
		(fp_line
			(start 0.12065 0.3048)
			(end 0.67945 0.3048)
			(stroke
				(width 0.1)
				(type default)
			)
			(layer "B.Fab")
		)
		(fp_line
			(start 0.67945 0.3048)
			(end 0.67945 -0.305054)
			(stroke
				(width 0.1)
				(type default)
			)
			(layer "B.Fab")
		)
		(fp_line
			(start -0.120396 0.2794)
			(end 0.12065 0.2794)
			(stroke
				(width 0.1)
				(type default)
			)
			(layer "B.Fab")
		)
		(fp_line
			(start 0.12065 0.2794)
			(end 0.12065 0.3048)
			(stroke
				(width 0.1)
				(type default)
			)
			(layer "B.Fab")
		)
		(fp_line
			(start -0.12065 -0.2794)
			(end -0.12065 -0.3048)
			(stroke
				(width 0.1)
				(type default)
			)
			(layer "B.Fab")
		)
		(fp_line
			(start 0.12065 -0.2794)
			(end -0.12065 -0.2794)
			(stroke
				(width 0.1)
				(type default)
			)
			(layer "B.Fab")
		)
		(fp_line
			(start -0.67945 -0.3048)
			(end -0.67945 0.3048)
			(stroke
				(width 0.1)
				(type default)
			)
			(layer "B.Fab")
		)
		(fp_line
			(start -0.12065 -0.3048)
			(end -0.67945 -0.3048)
			(stroke
				(width 0.1)
				(type default)
			)
			(layer "B.Fab")
		)
		(fp_line
			(start 0.12065 -0.305054)
			(end 0.12065 -0.2794)
			(stroke
				(width 0.1)
				(type default)
			)
			(layer "B.Fab")
		)
		(fp_line
			(start 0.67945 -0.305054)
			(end 0.12065 -0.305054)
			(stroke
				(width 0.1)
				(type default)
			)
			(layer "B.Fab")
		)
		(pad "1" smd circle
			(at 0.40005 0 90)
			(size 0 0)
			(layers "B.Cu" "B.Mask" "B.Paste")
			(net "SMB_SCM_2_R3_SDA")
		)
		(pad "2" smd circle
			(at -0.40005 0 90)
			(size 0 0)
			(layers "B.Cu" "B.Mask" "B.Paste")
			(net "PVDDCR_CPU0_P0_PMSDA_R")
		)
	)
	(footprint ""
		(layer "B.Cu")
		(at 305.423316 -425.6532 180)
		(property "Reference" "R1439"
			(at 0 0 0)
			(layer "B.SilkS")
			(hide yes)
			(effects
				(font
					(size 1.27 1.27)
				)
				(justify mirror)
			)
		)
		(property "Value" ""
			(at 0 0 0)
			(layer "B.Fab")
			(effects
				(font
					(size 1.27 1.27)
				)
				(justify mirror)
			)
		)
		(duplicate_pad_numbers_are_jumpers no)
		(fp_line
			(start 0.32512 0.175006)
			(end 0.32512 -0.175006)
			(stroke
				(width 0.1)
				(type default)
			)
			(layer "B.Fab")
		)
		(fp_line
			(start 0.32512 -0.175006)
			(end -0.32512 -0.175006)
			(stroke
				(width 0.1)
				(type default)
			)
			(layer "B.Fab")
		)
		(fp_line
			(start -0.32512 0.175006)
			(end 0.32512 0.175006)
			(stroke
				(width 0.1)
				(type default)
			)
			(layer "B.Fab")
		)
		(fp_line
			(start -0.32512 -0.175006)
			(end -0.32512 0.175006)
			(stroke
				(width 0.1)
				(type default)
			)
			(layer "B.Fab")
		)
		(pad "1" smd rect
			(at 0.2667 0)
			(size 0.3048 0.381)
			(layers "B.Cu" "B.Mask" "B.Paste")
			(net "P1V8_CPU0_RT_1D")
		)
		(pad "2" smd rect
			(at -0.2667 0 180)
			(size 0.3048 0.381)
			(layers "B.Cu" "B.Mask" "B.Paste")
			(net "JTAG_TMS_RT_CPU0_P0")
		)
	)
	(footprint ""
		(layer "B.Cu")
		(at 157.226 -416.1536 180)
		(property "Reference" "R1469"
			(at 0 0 0)
			(layer "B.SilkS")
			(hide yes)
			(effects
				(font
					(size 1.27 1.27)
				)
				(justify mirror)
			)
		)
		(property "Value" ""
			(at 0 0 0)
			(layer "B.Fab")
			(effects
				(font
					(size 1.27 1.27)
				)
				(justify mirror)
			)
		)
		(duplicate_pad_numbers_are_jumpers no)
		(fp_line
			(start 0.32512 0.175006)
			(end 0.32512 -0.175006)
			(stroke
				(width 0.1)
				(type default)
			)
			(layer "B.Fab")
		)
		(fp_line
			(start 0.32512 -0.175006)
			(end -0.32512 -0.175006)
			(stroke
				(width 0.1)
				(type default)
			)
			(layer "B.Fab")
		)
		(fp_line
			(start -0.32512 0.175006)
			(end 0.32512 0.175006)
			(stroke
				(width 0.1)
				(type default)
			)
			(layer "B.Fab")
		)
		(fp_line
			(start -0.32512 -0.175006)
			(end -0.32512 0.175006)
			(stroke
				(width 0.1)
				(type default)
			)
			(layer "B.Fab")
		)
		(pad "1" smd rect
			(at 0.2667 0)
			(size 0.3048 0.381)
			(layers "B.Cu" "B.Mask" "B.Paste")
			(net "P1V8_CPU1_RT_1D")
		)
		(pad "2" smd rect
			(at -0.2667 0 180)
			(size 0.3048 0.381)
			(layers "B.Cu" "B.Mask" "B.Paste")
			(net "SMB_RT_CPU1_P2_ROM_MUX_1D_SCL")
		)
	)
	(footprint ""
		(layer "B.Cu")
		(at 104.514904 -408.980894 180)
		(property "Reference" "C99"
			(at 0 0 0)
			(layer "B.SilkS")
			(hide yes)
			(effects
				(font
					(size 1.27 1.27)
				)
				(justify mirror)
			)
		)
		(property "Value" ""
			(at 0 0 0)
			(layer "B.Fab")
			(effects
				(font
					(size 1.27 1.27)
				)
				(justify mirror)
			)
		)
		(duplicate_pad_numbers_are_jumpers no)
		(fp_line
			(start 0.7874 0.4064)
			(end 0.7874 -0.4064)
			(stroke
				(width 0.1524)
				(type default)
			)
			(layer "B.SilkS")
		)
		(fp_line
			(start 0.7874 -0.4064)
			(end -0.7874 -0.4064)
			(stroke
				(width 0.1524)
				(type default)
			)
			(layer "B.SilkS")
		)
		(fp_line
			(start -0.7874 0.4064)
			(end 0.7874 0.4064)
			(stroke
				(width 0.1524)
				(type default)
			)
			(layer "B.SilkS")
		)
		(fp_line
			(start -0.7874 -0.4064)
			(end -0.7874 0.4064)
			(stroke
				(width 0.1524)
				(type default)
			)
			(layer "B.SilkS")
		)
		(fp_line
			(start 0.67945 0.3048)
			(end 0.67945 -0.305054)
			(stroke
				(width 0.1)
				(type default)
			)
			(layer "B.Fab")
		)
		(fp_line
			(start 0.67945 -0.305054)
			(end 0.12065 -0.305054)
			(stroke
				(width 0.1)
				(type default)
			)
			(layer "B.Fab")
		)
		(fp_line
			(start 0.12065 0.3048)
			(end 0.67945 0.3048)
			(stroke
				(width 0.1)
				(type default)
			)
			(layer "B.Fab")
		)
		(fp_line
			(start 0.12065 0.2794)
			(end 0.12065 0.3048)
			(stroke
				(width 0.1)
				(type default)
			)
			(layer "B.Fab")
		)
		(fp_line
			(start 0.12065 -0.2794)
			(end -0.12065 -0.2794)
			(stroke
				(width 0.1)
				(type default)
			)
			(layer "B.Fab")
		)
		(fp_line
			(start 0.12065 -0.305054)
			(end 0.12065 -0.2794)
			(stroke
				(width 0.1)
				(type default)
			)
			(layer "B.Fab")
		)
		(fp_line
			(start -0.120396 0.3048)
			(end -0.120396 0.2794)
			(stroke
				(width 0.1)
				(type default)
			)
			(layer "B.Fab")
		)
		(fp_line
			(start -0.120396 0.2794)
			(end 0.12065 0.2794)
			(stroke
				(width 0.1)
				(type default)
			)
			(layer "B.Fab")
		)
		(fp_line
			(start -0.12065 -0.2794)
			(end -0.12065 -0.3048)
			(stroke
				(width 0.1)
				(type default)
			)
			(layer "B.Fab")
		)
		(fp_line
			(start -0.12065 -0.3048)
			(end -0.67945 -0.3048)
			(stroke
				(width 0.1)
				(type default)
			)
			(layer "B.Fab")
		)
		(fp_line
			(start -0.67945 0.3048)
			(end -0.120396 0.3048)
			(stroke
				(width 0.1)
				(type default)
			)
			(layer "B.Fab")
		)
		(fp_line
			(start -0.67945 -0.3048)
			(end -0.67945 0.3048)
			(stroke
				(width 0.1)
				(type default)
			)
			(layer "B.Fab")
		)
		(pad "1" smd circle
			(at 0.40005 0)
			(size 0 0)
			(layers "B.Cu" "B.Mask" "B.Paste")
			(net "P3V3_9ZXL045_P1_VDD")
		)
		(pad "2" smd circle
			(at -0.40005 0)
			(size 0 0)
			(layers "B.Cu" "B.Mask" "B.Paste")
			(net "GND")
		)
	)
	(footprint ""
		(layer "B.Cu")
		(at 184.257696 -133.791452 90)
		(property "Reference" "R6805"
			(at 0 0 90)
			(layer "B.SilkS")
			(hide yes)
			(effects
				(font
					(size 1.27 1.27)
				)
				(justify mirror)
			)
		)
		(property "Value" ""
			(at 0 0 90)
			(layer "B.Fab")
			(effects
				(font
					(size 1.27 1.27)
				)
				(justify mirror)
			)
		)
		(duplicate_pad_numbers_are_jumpers no)
		(fp_line
			(start 0.7874 -0.4064)
			(end -0.7874 -0.4064)
			(stroke
				(width 0.1524)
				(type default)
			)
			(layer "B.SilkS")
		)
		(fp_line
			(start -0.7874 -0.4064)
			(end -0.7874 0.4064)
			(stroke
				(width 0.1524)
				(type default)
			)
			(layer "B.SilkS")
		)
		(fp_line
			(start 0.7874 0.4064)
			(end 0.7874 -0.4064)
			(stroke
				(width 0.1524)
				(type default)
			)
			(layer "B.SilkS")
		)
		(fp_line
			(start -0.7874 0.4064)
			(end 0.7874 0.4064)
			(stroke
				(width 0.1524)
				(type default)
			)
			(layer "B.SilkS")
		)
		(fp_line
			(start 0.67945 -0.305054)
			(end 0.12065 -0.305054)
			(stroke
				(width 0.1)
				(type default)
			)
			(layer "B.Fab")
		)
		(fp_line
			(start 0.12065 -0.305054)
			(end 0.12065 -0.2794)
			(stroke
				(width 0.1)
				(type default)
			)
			(layer "B.Fab")
		)
		(fp_line
			(start -0.12065 -0.3048)
			(end -0.67945 -0.3048)
			(stroke
				(width 0.1)
				(type default)
			)
			(layer "B.Fab")
		)
		(fp_line
			(start -0.67945 -0.3048)
			(end -0.67945 0.3048)
			(stroke
				(width 0.1)
				(type default)
			)
			(layer "B.Fab")
		)
		(fp_line
			(start 0.12065 -0.2794)
			(end -0.12065 -0.2794)
			(stroke
				(width 0.1)
				(type default)
			)
			(layer "B.Fab")
		)
		(fp_line
			(start -0.12065 -0.2794)
			(end -0.12065 -0.3048)
			(stroke
				(width 0.1)
				(type default)
			)
			(layer "B.Fab")
		)
		(fp_line
			(start 0.12065 0.2794)
			(end 0.12065 0.3048)
			(stroke
				(width 0.1)
				(type default)
			)
			(layer "B.Fab")
		)
		(fp_line
			(start -0.120396 0.2794)
			(end 0.12065 0.2794)
			(stroke
				(width 0.1)
				(type default)
			)
			(layer "B.Fab")
		)
		(fp_line
			(start 0.67945 0.3048)
			(end 0.67945 -0.305054)
			(stroke
				(width 0.1)
				(type default)
			)
			(layer "B.Fab")
		)
		(fp_line
			(start 0.12065 0.3048)
			(end 0.67945 0.3048)
			(stroke
				(width 0.1)
				(type default)
			)
			(layer "B.Fab")
		)
		(fp_line
			(start -0.120396 0.3048)
			(end -0.120396 0.2794)
			(stroke
				(width 0.1)
				(type default)
			)
			(layer "B.Fab")
		)
		(fp_line
			(start -0.67945 0.3048)
			(end -0.120396 0.3048)
			(stroke
				(width 0.1)
				(type default)
			)
			(layer "B.Fab")
		)
		(pad "1" smd circle
			(at 0.40005 0 270)
			(size 0 0)
			(layers "B.Cu" "B.Mask" "B.Paste")
			(net "RST_RT_CPU0_P0_RESET_R_N")
		)
		(pad "2" smd circle
			(at -0.40005 0 270)
			(size 0 0)
			(layers "B.Cu" "B.Mask" "B.Paste")
			(net "RST_RT_CPU0_P0_RESET_R2_N")
		)
	)
	(footprint ""
		(layer "B.Cu")
		(at 311.426606 -416.899344 90)
		(property "Reference" "C6538"
			(at 0 0 90)
			(layer "B.SilkS")
			(hide yes)
			(effects
				(font
					(size 1.27 1.27)
				)
				(justify mirror)
			)
		)
		(property "Value" ""
			(at 0 0 90)
			(layer "B.Fab")
			(effects
				(font
					(size 1.27 1.27)
				)
				(justify mirror)
			)
		)
		(duplicate_pad_numbers_are_jumpers no)
		(fp_line
			(start 0.299974 -0.150114)
			(end -0.299974 -0.150114)
			(stroke
				(width 0.1)
				(type default)
			)
			(layer "B.Fab")
		)
		(fp_line
			(start -0.299974 -0.150114)
			(end -0.299974 0.150114)
			(stroke
				(width 0.1)
				(type default)
			)
			(layer "B.Fab")
		)
		(fp_line
			(start 0.299974 0.150114)
			(end 0.299974 -0.150114)
			(stroke
				(width 0.1)
				(type default)
			)
			(layer "B.Fab")
		)
		(fp_line
			(start -0.299974 0.150114)
			(end 0.299974 0.150114)
			(stroke
				(width 0.1)
				(type default)
			)
			(layer "B.Fab")
		)
		(pad "1" smd rect
			(at 0.2667 0 270)
			(size 0.3048 0.381)
			(layers "B.Cu" "B.Mask" "B.Paste")
			(net "P5E_CPU0_P1_TX_BUF_C_DN<2>")
		)
		(pad "2" smd rect
			(at -0.2667 0 270)
			(size 0.3048 0.381)
			(layers "B.Cu" "B.Mask" "B.Paste")
			(net "P5E_CPU0_P1_TX_BUF_DN<2>")
		)
	)
	(footprint ""
		(layer "B.Cu")
		(at 165.599618 -416.946588 180)
		(property "Reference" "R4119"
			(at 0 0 0)
			(layer "B.SilkS")
			(hide yes)
			(effects
				(font
					(size 1.27 1.27)
				)
				(justify mirror)
			)
		)
		(property "Value" ""
			(at 0 0 0)
			(layer "B.Fab")
			(effects
				(font
					(size 1.27 1.27)
				)
				(justify mirror)
			)
		)
		(duplicate_pad_numbers_are_jumpers no)
		(fp_line
			(start 0.7874 0.4064)
			(end 0.7874 -0.4064)
			(stroke
				(width 0.1524)
				(type default)
			)
			(layer "B.SilkS")
		)
		(fp_line
			(start 0.7874 -0.4064)
			(end -0.7874 -0.4064)
			(stroke
				(width 0.1524)
				(type default)
			)
			(layer "B.SilkS")
		)
		(fp_line
			(start -0.7874 0.4064)
			(end 0.7874 0.4064)
			(stroke
				(width 0.1524)
				(type default)
			)
			(layer "B.SilkS")
		)
		(fp_line
			(start -0.7874 -0.4064)
			(end -0.7874 0.4064)
			(stroke
				(width 0.1524)
				(type default)
			)
			(layer "B.SilkS")
		)
		(fp_line
			(start 0.67945 0.3048)
			(end 0.67945 -0.305054)
			(stroke
				(width 0.1)
				(type default)
			)
			(layer "B.Fab")
		)
		(fp_line
			(start 0.67945 -0.305054)
			(end 0.12065 -0.305054)
			(stroke
				(width 0.1)
				(type default)
			)
			(layer "B.Fab")
		)
		(fp_line
			(start 0.12065 0.3048)
			(end 0.67945 0.3048)
			(stroke
				(width 0.1)
				(type default)
			)
			(layer "B.Fab")
		)
		(fp_line
			(start 0.12065 0.2794)
			(end 0.12065 0.3048)
			(stroke
				(width 0.1)
				(type default)
			)
			(layer "B.Fab")
		)
		(fp_line
			(start 0.12065 -0.2794)
			(end -0.12065 -0.2794)
			(stroke
				(width 0.1)
				(type default)
			)
			(layer "B.Fab")
		)
		(fp_line
			(start 0.12065 -0.305054)
			(end 0.12065 -0.2794)
			(stroke
				(width 0.1)
				(type default)
			)
			(layer "B.Fab")
		)
		(fp_line
			(start -0.120396 0.3048)
			(end -0.120396 0.2794)
			(stroke
				(width 0.1)
				(type default)
			)
			(layer "B.Fab")
		)
		(fp_line
			(start -0.120396 0.2794)
			(end 0.12065 0.2794)
			(stroke
				(width 0.1)
				(type default)
			)
			(layer "B.Fab")
		)
		(fp_line
			(start -0.12065 -0.2794)
			(end -0.12065 -0.3048)
			(stroke
				(width 0.1)
				(type default)
			)
			(layer "B.Fab")
		)
		(fp_line
			(start -0.12065 -0.3048)
			(end -0.67945 -0.3048)
			(stroke
				(width 0.1)
				(type default)
			)
			(layer "B.Fab")
		)
		(fp_line
			(start -0.67945 0.3048)
			(end -0.120396 0.3048)
			(stroke
				(width 0.1)
				(type default)
			)
			(layer "B.Fab")
		)
		(fp_line
			(start -0.67945 -0.3048)
			(end -0.67945 0.3048)
			(stroke
				(width 0.1)
				(type default)
			)
			(layer "B.Fab")
		)
		(pad "1" smd circle
			(at 0.40005 0)
			(size 0 0)
			(layers "B.Cu" "B.Mask" "B.Paste")
			(net "P3V3_AUX")
		)
		(pad "2" smd circle
			(at -0.40005 0)
			(size 0 0)
			(layers "B.Cu" "B.Mask" "B.Paste")
			(net "GPU_3V3IO_RSVD0_FFU")
		)
	)
	(footprint ""
		(layer "B.Cu")
		(at 128.653286 -408.517344 90)
		(property "Reference" "C6734"
			(at 0 0 90)
			(layer "B.SilkS")
			(hide yes)
			(effects
				(font
					(size 1.27 1.27)
				)
				(justify mirror)
			)
		)
		(property "Value" ""
			(at 0 0 90)
			(layer "B.Fab")
			(effects
				(font
					(size 1.27 1.27)
				)
				(justify mirror)
			)
		)
		(duplicate_pad_numbers_are_jumpers no)
		(fp_line
			(start 0.299974 -0.150114)
			(end -0.299974 -0.150114)
			(stroke
				(width 0.1)
				(type default)
			)
			(layer "B.Fab")
		)
		(fp_line
			(start -0.299974 -0.150114)
			(end -0.299974 0.150114)
			(stroke
				(width 0.1)
				(type default)
			)
			(layer "B.Fab")
		)
		(fp_line
			(start 0.299974 0.150114)
			(end 0.299974 -0.150114)
			(stroke
				(width 0.1)
				(type default)
			)
			(layer "B.Fab")
		)
		(fp_line
			(start -0.299974 0.150114)
			(end 0.299974 0.150114)
			(stroke
				(width 0.1)
				(type default)
			)
			(layer "B.Fab")
		)
		(pad "1" smd rect
			(at 0.2667 0 270)
			(size 0.3048 0.381)
			(layers "B.Cu" "B.Mask" "B.Paste")
			(net "P5E_CPU1_P3_TX_BUF_C_DN<4>")
		)
		(pad "2" smd rect
			(at -0.2667 0 270)
			(size 0.3048 0.381)
			(layers "B.Cu" "B.Mask" "B.Paste")
			(net "P5E_CPU1_P3_TX_BUF_DN<4>")
		)
	)
	(footprint ""
		(layer "B.Cu")
		(at 376.377962 -416.899344 90)
		(property "Reference" "C6599"
			(at 0 0 90)
			(layer "B.SilkS")
			(hide yes)
			(effects
				(font
					(size 1.27 1.27)
				)
				(justify mirror)
			)
		)
		(property "Value" ""
			(at 0 0 90)
			(layer "B.Fab")
			(effects
				(font
					(size 1.27 1.27)
				)
				(justify mirror)
			)
		)
		(duplicate_pad_numbers_are_jumpers no)
		(fp_line
			(start 0.299974 -0.150114)
			(end -0.299974 -0.150114)
			(stroke
				(width 0.1)
				(type default)
			)
			(layer "B.Fab")
		)
		(fp_line
			(start -0.299974 -0.150114)
			(end -0.299974 0.150114)
			(stroke
				(width 0.1)
				(type default)
			)
			(layer "B.Fab")
		)
		(fp_line
			(start 0.299974 0.150114)
			(end 0.299974 -0.150114)
			(stroke
				(width 0.1)
				(type default)
			)
			(layer "B.Fab")
		)
		(fp_line
			(start -0.299974 0.150114)
			(end 0.299974 0.150114)
			(stroke
				(width 0.1)
				(type default)
			)
			(layer "B.Fab")
		)
		(pad "1" smd rect
			(at 0.2667 0 270)
			(size 0.3048 0.381)
			(layers "B.Cu" "B.Mask" "B.Paste")
			(net "P5E_CPU0_P3_TX_BUF_C_DP<1>")
		)
		(pad "2" smd rect
			(at -0.2667 0 270)
			(size 0.3048 0.381)
			(layers "B.Cu" "B.Mask" "B.Paste")
			(net "P5E_CPU0_P3_TX_BUF_DP<1>")
		)
	)
	(footprint ""
		(layer "B.Cu")
		(at 54.578504 -386.766562 90)
		(property "Reference" "C134"
			(at 0 0 90)
			(layer "B.SilkS")
			(hide yes)
			(effects
				(font
					(size 1.27 1.27)
				)
				(justify mirror)
			)
		)
		(property "Value" ""
			(at 0 0 90)
			(layer "B.Fab")
			(effects
				(font
					(size 1.27 1.27)
				)
				(justify mirror)
			)
		)
		(duplicate_pad_numbers_are_jumpers no)
		(fp_line
			(start 0.299974 -0.150114)
			(end -0.299974 -0.150114)
			(stroke
				(width 0.1)
				(type default)
			)
			(layer "B.Fab")
		)
		(fp_line
			(start -0.299974 -0.150114)
			(end -0.299974 0.150114)
			(stroke
				(width 0.1)
				(type default)
			)
			(layer "B.Fab")
		)
		(fp_line
			(start 0.299974 0.150114)
			(end 0.299974 -0.150114)
			(stroke
				(width 0.1)
				(type default)
			)
			(layer "B.Fab")
		)
		(fp_line
			(start -0.299974 0.150114)
			(end 0.299974 0.150114)
			(stroke
				(width 0.1)
				(type default)
			)
			(layer "B.Fab")
		)
		(pad "1" smd rect
			(at 0.2667 0 270)
			(size 0.3048 0.381)
			(layers "B.Cu" "B.Mask" "B.Paste")
			(net "P1V8_CPU1_RT0_1A")
		)
		(pad "2" smd rect
			(at -0.2667 0 270)
			(size 0.3048 0.381)
			(layers "B.Cu" "B.Mask" "B.Paste")
			(net "GND")
		)
	)
	(footprint ""
		(layer "B.Cu")
		(at 349.421958 -245.487952 180)
		(property "Reference" "C2189"
			(at 0 0 0)
			(layer "B.SilkS")
			(hide yes)
			(effects
				(font
					(size 1.27 1.27)
				)
				(justify mirror)
			)
		)
		(property "Value" ""
			(at 0 0 0)
			(layer "B.Fab")
			(effects
				(font
					(size 1.27 1.27)
				)
				(justify mirror)
			)
		)
		(duplicate_pad_numbers_are_jumpers no)
		(fp_line
			(start 0.7874 0.4064)
			(end 0.7874 -0.4064)
			(stroke
				(width 0.1524)
				(type default)
			)
			(layer "B.SilkS")
		)
		(fp_line
			(start 0.7874 -0.4064)
			(end -0.7874 -0.4064)
			(stroke
				(width 0.1524)
				(type default)
			)
			(layer "B.SilkS")
		)
		(fp_line
			(start -0.7874 0.4064)
			(end 0.7874 0.4064)
			(stroke
				(width 0.1524)
				(type default)
			)
			(layer "B.SilkS")
		)
		(fp_line
			(start -0.7874 -0.4064)
			(end -0.7874 0.4064)
			(stroke
				(width 0.1524)
				(type default)
			)
			(layer "B.SilkS")
		)
		(fp_line
			(start 0.67945 0.3048)
			(end 0.67945 -0.305054)
			(stroke
				(width 0.1)
				(type default)
			)
			(layer "B.Fab")
		)
		(fp_line
			(start 0.67945 -0.305054)
			(end 0.12065 -0.305054)
			(stroke
				(width 0.1)
				(type default)
			)
			(layer "B.Fab")
		)
		(fp_line
			(start 0.12065 0.3048)
			(end 0.67945 0.3048)
			(stroke
				(width 0.1)
				(type default)
			)
			(layer "B.Fab")
		)
		(fp_line
			(start 0.12065 0.2794)
			(end 0.12065 0.3048)
			(stroke
				(width 0.1)
				(type default)
			)
			(layer "B.Fab")
		)
		(fp_line
			(start 0.12065 -0.2794)
			(end -0.12065 -0.2794)
			(stroke
				(width 0.1)
				(type default)
			)
			(layer "B.Fab")
		)
		(fp_line
			(start 0.12065 -0.305054)
			(end 0.12065 -0.2794)
			(stroke
				(width 0.1)
				(type default)
			)
			(layer "B.Fab")
		)
		(fp_line
			(start -0.120396 0.3048)
			(end -0.120396 0.2794)
			(stroke
				(width 0.1)
				(type default)
			)
			(layer "B.Fab")
		)
		(fp_line
			(start -0.120396 0.2794)
			(end 0.12065 0.2794)
			(stroke
				(width 0.1)
				(type default)
			)
			(layer "B.Fab")
		)
		(fp_line
			(start -0.12065 -0.2794)
			(end -0.12065 -0.3048)
			(stroke
				(width 0.1)
				(type default)
			)
			(layer "B.Fab")
		)
		(fp_line
			(start -0.12065 -0.3048)
			(end -0.67945 -0.3048)
			(stroke
				(width 0.1)
				(type default)
			)
			(layer "B.Fab")
		)
		(fp_line
			(start -0.67945 0.3048)
			(end -0.120396 0.3048)
			(stroke
				(width 0.1)
				(type default)
			)
			(layer "B.Fab")
		)
		(fp_line
			(start -0.67945 -0.3048)
			(end -0.67945 0.3048)
			(stroke
				(width 0.1)
				(type default)
			)
			(layer "B.Fab")
		)
		(pad "1" smd circle
			(at 0.40005 0)
			(size 0 0)
			(layers "B.Cu" "B.Mask" "B.Paste")
			(net "PVDDCR_CPU0_P0")
		)
		(pad "2" smd circle
			(at -0.40005 0)
			(size 0 0)
			(layers "B.Cu" "B.Mask" "B.Paste")
			(net "GND")
		)
	)
	(footprint ""
		(layer "B.Cu")
		(at 28.395676 -339.864954 -90)
		(property "Reference" "PC455"
			(at 9.410954 -0.914654 270)
			(unlocked yes)
			(layer "B.SilkS")
			(effects
				(font
					(size 0.7874 0.5842)
					(thickness 0.1524)
				)
				(justify left mirror)
			)
		)
		(property "Value" ""
			(at 0 0 90)
			(layer "B.Fab")
			(effects
				(font
					(size 1.27 1.27)
				)
				(justify mirror)
			)
		)
		(duplicate_pad_numbers_are_jumpers no)
		(fp_line
			(start -4.533392 2.249932)
			(end 4.533392 2.249932)
			(stroke
				(width 0.1524)
				(type default)
			)
			(layer "B.SilkS")
		)
		(fp_line
			(start 4.533392 2.249932)
			(end 4.533392 -2.249932)
			(stroke
				(width 0.1524)
				(type default)
			)
			(layer "B.SilkS")
		)
		(fp_line
			(start -4.533392 -2.249932)
			(end -4.533392 2.249932)
			(stroke
				(width 0.1524)
				(type default)
			)
			(layer "B.SilkS")
		)
		(fp_line
			(start 4.533392 -2.249932)
			(end -4.533392 -2.249932)
			(stroke
				(width 0.1524)
				(type default)
			)
			(layer "B.SilkS")
		)
		(fp_rect
			(start 5.39242 2.326132)
			(end 4.533392 -2.326132)
			(stroke
				(width 0)
				(type default)
			)
			(fill yes)
			(layer "B.SilkS")
		)
		(fp_line
			(start -3.750056 2.249932)
			(end 3.750056 2.249932)
			(stroke
				(width 0.1)
				(type default)
			)
			(layer "B.Fab")
		)
		(fp_line
			(start 3.750056 2.249932)
			(end 3.750056 -2.249932)
			(stroke
				(width 0.1)
				(type default)
			)
			(layer "B.Fab")
		)
		(fp_line
			(start -3.750056 -2.249932)
			(end -3.750056 2.249932)
			(stroke
				(width 0.1)
				(type default)
			)
			(layer "B.Fab")
		)
		(fp_line
			(start 3.750056 -2.249932)
			(end -3.750056 -2.249932)
			(stroke
				(width 0.1)
				(type default)
			)
			(layer "B.Fab")
		)
		(fp_text user "-"
			(at -4.602734 2.14122 270)
			(unlocked yes)
			(layer "B.SilkS")
			(effects
				(font
					(size 1.905 1.4224)
					(thickness 0.1524)
				)
				(justify left mirror)
			)
		)
		(fp_text user "+"
			(at 6.322314 0.786384 180)
			(unlocked yes)
			(layer "B.SilkS")
			(effects
				(font
					(size 1.905 1.4224)
					(thickness 0.1524)
				)
				(justify left mirror)
			)
		)
		(fp_text user "+"
			(at 6.322314 0.786384 180)
			(unlocked yes)
			(layer "B.Fab")
			(effects
				(font
					(size 1.905 1.4224)
					(thickness 0.1524)
				)
				(justify left mirror)
			)
		)
		(fp_text user "-"
			(at -4.8514 -0.14605 270)
			(unlocked yes)
			(layer "B.Fab")
			(effects
				(font
					(size 1.905 1.4224)
					(thickness 0.1524)
				)
				(justify left mirror)
			)
		)
		(pad "1" smd rect
			(at 3.199892 0 90)
			(size 2.413 2.8194)
			(layers "B.Cu" "B.Mask" "B.Paste")
			(net "PVDDIO_P1")
		)
		(pad "2" smd rect
			(at -3.199892 0 90)
			(size 2.413 2.8194)
			(layers "B.Cu" "B.Mask" "B.Paste")
			(net "GND")
		)
	)
	(footprint ""
		(layer "B.Cu")
		(at 361.645454 -250.25731)
		(property "Reference" "C2196"
			(at 0 0 0)
			(layer "B.SilkS")
			(hide yes)
			(effects
				(font
					(size 1.27 1.27)
				)
				(justify mirror)
			)
		)
		(property "Value" ""
			(at 0 0 0)
			(layer "B.Fab")
			(effects
				(font
					(size 1.27 1.27)
				)
				(justify mirror)
			)
		)
		(duplicate_pad_numbers_are_jumpers no)
		(fp_line
			(start -0.7874 -0.4064)
			(end -0.7874 0.4064)
			(stroke
				(width 0.1524)
				(type default)
			)
			(layer "B.SilkS")
		)
		(fp_line
			(start -0.7874 0.4064)
			(end 0.7874 0.4064)
			(stroke
				(width 0.1524)
				(type default)
			)
			(layer "B.SilkS")
		)
		(fp_line
			(start 0.7874 -0.4064)
			(end -0.7874 -0.4064)
			(stroke
				(width 0.1524)
				(type default)
			)
			(layer "B.SilkS")
		)
		(fp_line
			(start 0.7874 0.4064)
			(end 0.7874 -0.4064)
			(stroke
				(width 0.1524)
				(type default)
			)
			(layer "B.SilkS")
		)
		(fp_line
			(start -0.67945 -0.3048)
			(end -0.67945 0.3048)
			(stroke
				(width 0.1)
				(type default)
			)
			(layer "B.Fab")
		)
		(fp_line
			(start -0.67945 0.3048)
			(end -0.120396 0.3048)
			(stroke
				(width 0.1)
				(type default)
			)
			(layer "B.Fab")
		)
		(fp_line
			(start -0.12065 -0.3048)
			(end -0.67945 -0.3048)
			(stroke
				(width 0.1)
				(type default)
			)
			(layer "B.Fab")
		)
		(fp_line
			(start -0.12065 -0.2794)
			(end -0.12065 -0.3048)
			(stroke
				(width 0.1)
				(type default)
			)
			(layer "B.Fab")
		)
		(fp_line
			(start -0.120396 0.2794)
			(end 0.12065 0.2794)
			(stroke
				(width 0.1)
				(type default)
			)
			(layer "B.Fab")
		)
		(fp_line
			(start -0.120396 0.3048)
			(end -0.120396 0.2794)
			(stroke
				(width 0.1)
				(type default)
			)
			(layer "B.Fab")
		)
		(fp_line
			(start 0.12065 -0.305054)
			(end 0.12065 -0.2794)
			(stroke
				(width 0.1)
				(type default)
			)
			(layer "B.Fab")
		)
		(fp_line
			(start 0.12065 -0.2794)
			(end -0.12065 -0.2794)
			(stroke
				(width 0.1)
				(type default)
			)
			(layer "B.Fab")
		)
		(fp_line
			(start 0.12065 0.2794)
			(end 0.12065 0.3048)
			(stroke
				(width 0.1)
				(type default)
			)
			(layer "B.Fab")
		)
		(fp_line
			(start 0.12065 0.3048)
			(end 0.67945 0.3048)
			(stroke
				(width 0.1)
				(type default)
			)
			(layer "B.Fab")
		)
		(fp_line
			(start 0.67945 -0.305054)
			(end 0.12065 -0.305054)
			(stroke
				(width 0.1)
				(type default)
			)
			(layer "B.Fab")
		)
		(fp_line
			(start 0.67945 0.3048)
			(end 0.67945 -0.305054)
			(stroke
				(width 0.1)
				(type default)
			)
			(layer "B.Fab")
		)
		(pad "1" smd circle
			(at 0.40005 0 180)
			(size 0 0)
			(layers "B.Cu" "B.Mask" "B.Paste")
			(net "PVDDCR_CPU0_P0")
		)
		(pad "2" smd circle
			(at -0.40005 0 180)
			(size 0 0)
			(layers "B.Cu" "B.Mask" "B.Paste")
			(net "GND")
		)
	)
	(footprint ""
		(layer "B.Cu")
		(at 355.295454 -269.30731 180)
		(property "Reference" "C2201"
			(at 0 0 0)
			(layer "B.SilkS")
			(hide yes)
			(effects
				(font
					(size 1.27 1.27)
				)
				(justify mirror)
			)
		)
		(property "Value" ""
			(at 0 0 0)
			(layer "B.Fab")
			(effects
				(font
					(size 1.27 1.27)
				)
				(justify mirror)
			)
		)
		(duplicate_pad_numbers_are_jumpers no)
		(fp_line
			(start 0.7874 0.4064)
			(end 0.7874 -0.4064)
			(stroke
				(width 0.1524)
				(type default)
			)
			(layer "B.SilkS")
		)
		(fp_line
			(start 0.7874 -0.4064)
			(end -0.7874 -0.4064)
			(stroke
				(width 0.1524)
				(type default)
			)
			(layer "B.SilkS")
		)
		(fp_line
			(start -0.7874 0.4064)
			(end 0.7874 0.4064)
			(stroke
				(width 0.1524)
				(type default)
			)
			(layer "B.SilkS")
		)
		(fp_line
			(start -0.7874 -0.4064)
			(end -0.7874 0.4064)
			(stroke
				(width 0.1524)
				(type default)
			)
			(layer "B.SilkS")
		)
		(fp_line
			(start 0.67945 0.3048)
			(end 0.67945 -0.305054)
			(stroke
				(width 0.1)
				(type default)
			)
			(layer "B.Fab")
		)
		(fp_line
			(start 0.67945 -0.305054)
			(end 0.12065 -0.305054)
			(stroke
				(width 0.1)
				(type default)
			)
			(layer "B.Fab")
		)
		(fp_line
			(start 0.12065 0.3048)
			(end 0.67945 0.3048)
			(stroke
				(width 0.1)
				(type default)
			)
			(layer "B.Fab")
		)
		(fp_line
			(start 0.12065 0.2794)
			(end 0.12065 0.3048)
			(stroke
				(width 0.1)
				(type default)
			)
			(layer "B.Fab")
		)
		(fp_line
			(start 0.12065 -0.2794)
			(end -0.12065 -0.2794)
			(stroke
				(width 0.1)
				(type default)
			)
			(layer "B.Fab")
		)
		(fp_line
			(start 0.12065 -0.305054)
			(end 0.12065 -0.2794)
			(stroke
				(width 0.1)
				(type default)
			)
			(layer "B.Fab")
		)
		(fp_line
			(start -0.120396 0.3048)
			(end -0.120396 0.2794)
			(stroke
				(width 0.1)
				(type default)
			)
			(layer "B.Fab")
		)
		(fp_line
			(start -0.120396 0.2794)
			(end 0.12065 0.2794)
			(stroke
				(width 0.1)
				(type default)
			)
			(layer "B.Fab")
		)
		(fp_line
			(start -0.12065 -0.2794)
			(end -0.12065 -0.3048)
			(stroke
				(width 0.1)
				(type default)
			)
			(layer "B.Fab")
		)
		(fp_line
			(start -0.12065 -0.3048)
			(end -0.67945 -0.3048)
			(stroke
				(width 0.1)
				(type default)
			)
			(layer "B.Fab")
		)
		(fp_line
			(start -0.67945 0.3048)
			(end -0.120396 0.3048)
			(stroke
				(width 0.1)
				(type default)
			)
			(layer "B.Fab")
		)
		(fp_line
			(start -0.67945 -0.3048)
			(end -0.67945 0.3048)
			(stroke
				(width 0.1)
				(type default)
			)
			(layer "B.Fab")
		)
		(pad "1" smd circle
			(at 0.40005 0)
			(size 0 0)
			(layers "B.Cu" "B.Mask" "B.Paste")
			(net "PVDDCR_CPU1_P0")
		)
		(pad "2" smd circle
			(at -0.40005 0)
			(size 0 0)
			(layers "B.Cu" "B.Mask" "B.Paste")
			(net "GND")
		)
	)
	(footprint ""
		(layer "B.Cu")
		(at 86.059264 -408.517344 90)
		(property "Reference" "C6686"
			(at 0 0 90)
			(layer "B.SilkS")
			(hide yes)
			(effects
				(font
					(size 1.27 1.27)
				)
				(justify mirror)
			)
		)
		(property "Value" ""
			(at 0 0 90)
			(layer "B.Fab")
			(effects
				(font
					(size 1.27 1.27)
				)
				(justify mirror)
			)
		)
		(duplicate_pad_numbers_are_jumpers no)
		(fp_line
			(start 0.299974 -0.150114)
			(end -0.299974 -0.150114)
			(stroke
				(width 0.1)
				(type default)
			)
			(layer "B.Fab")
		)
		(fp_line
			(start -0.299974 -0.150114)
			(end -0.299974 0.150114)
			(stroke
				(width 0.1)
				(type default)
			)
			(layer "B.Fab")
		)
		(fp_line
			(start 0.299974 0.150114)
			(end 0.299974 -0.150114)
			(stroke
				(width 0.1)
				(type default)
			)
			(layer "B.Fab")
		)
		(fp_line
			(start -0.299974 0.150114)
			(end 0.299974 0.150114)
			(stroke
				(width 0.1)
				(type default)
			)
			(layer "B.Fab")
		)
		(pad "1" smd rect
			(at 0.2667 0 270)
			(size 0.3048 0.381)
			(layers "B.Cu" "B.Mask" "B.Paste")
			(net "P5E_CPU1_P1_TX_BUF_C_DN<12>")
		)
		(pad "2" smd rect
			(at -0.2667 0 270)
			(size 0.3048 0.381)
			(layers "B.Cu" "B.Mask" "B.Paste")
			(net "P5E_CPU1_P1_TX_BUF_DN<12>")
		)
	)
	(footprint ""
		(layer "B.Cu")
		(at 343.245948 -396.393162 -90)
		(property "Reference" "C597"
			(at 0 0 90)
			(layer "B.SilkS")
			(hide yes)
			(effects
				(font
					(size 1.27 1.27)
				)
				(justify mirror)
			)
		)
		(property "Value" ""
			(at 0 0 90)
			(layer "B.Fab")
			(effects
				(font
					(size 1.27 1.27)
				)
				(justify mirror)
			)
		)
		(duplicate_pad_numbers_are_jumpers no)
		(fp_line
			(start -0.299974 0.150114)
			(end 0.299974 0.150114)
			(stroke
				(width 0.1)
				(type default)
			)
			(layer "B.Fab")
		)
		(fp_line
			(start 0.299974 0.150114)
			(end 0.299974 -0.150114)
			(stroke
				(width 0.1)
				(type default)
			)
			(layer "B.Fab")
		)
		(fp_line
			(start -0.299974 -0.150114)
			(end -0.299974 0.150114)
			(stroke
				(width 0.1)
				(type default)
			)
			(layer "B.Fab")
		)
		(fp_line
			(start 0.299974 -0.150114)
			(end -0.299974 -0.150114)
			(stroke
				(width 0.1)
				(type default)
			)
			(layer "B.Fab")
		)
		(pad "1" smd rect
			(at 0.2667 0 90)
			(size 0.3048 0.381)
			(layers "B.Cu" "B.Mask" "B.Paste")
			(net "P1V8_CPU0_RT1_1A")
		)
		(pad "2" smd rect
			(at -0.2667 0 90)
			(size 0.3048 0.381)
			(layers "B.Cu" "B.Mask" "B.Paste")
			(net "GND")
		)
	)
	(footprint ""
		(layer "B.Cu")
		(at 427.558454 -191.32931 180)
		(property "Reference" "R299"
			(at 0 0 0)
			(layer "B.SilkS")
			(hide yes)
			(effects
				(font
					(size 1.27 1.27)
				)
				(justify mirror)
			)
		)
		(property "Value" ""
			(at 0 0 0)
			(layer "B.Fab")
			(effects
				(font
					(size 1.27 1.27)
				)
				(justify mirror)
			)
		)
		(duplicate_pad_numbers_are_jumpers no)
		(fp_line
			(start 0.7874 0.4064)
			(end 0.7874 -0.4064)
			(stroke
				(width 0.1524)
				(type default)
			)
			(layer "B.SilkS")
		)
		(fp_line
			(start 0.7874 -0.4064)
			(end -0.7874 -0.4064)
			(stroke
				(width 0.1524)
				(type default)
			)
			(layer "B.SilkS")
		)
		(fp_line
			(start -0.7874 0.4064)
			(end 0.7874 0.4064)
			(stroke
				(width 0.1524)
				(type default)
			)
			(layer "B.SilkS")
		)
		(fp_line
			(start -0.7874 -0.4064)
			(end -0.7874 0.4064)
			(stroke
				(width 0.1524)
				(type default)
			)
			(layer "B.SilkS")
		)
		(fp_line
			(start 0.67945 0.3048)
			(end 0.67945 -0.305054)
			(stroke
				(width 0.1)
				(type default)
			)
			(layer "B.Fab")
		)
		(fp_line
			(start 0.67945 -0.305054)
			(end 0.12065 -0.305054)
			(stroke
				(width 0.1)
				(type default)
			)
			(layer "B.Fab")
		)
		(fp_line
			(start 0.12065 0.3048)
			(end 0.67945 0.3048)
			(stroke
				(width 0.1)
				(type default)
			)
			(layer "B.Fab")
		)
		(fp_line
			(start 0.12065 0.2794)
			(end 0.12065 0.3048)
			(stroke
				(width 0.1)
				(type default)
			)
			(layer "B.Fab")
		)
		(fp_line
			(start 0.12065 -0.2794)
			(end -0.12065 -0.2794)
			(stroke
				(width 0.1)
				(type default)
			)
			(layer "B.Fab")
		)
		(fp_line
			(start 0.12065 -0.305054)
			(end 0.12065 -0.2794)
			(stroke
				(width 0.1)
				(type default)
			)
			(layer "B.Fab")
		)
		(fp_line
			(start -0.120396 0.3048)
			(end -0.120396 0.2794)
			(stroke
				(width 0.1)
				(type default)
			)
			(layer "B.Fab")
		)
		(fp_line
			(start -0.120396 0.2794)
			(end 0.12065 0.2794)
			(stroke
				(width 0.1)
				(type default)
			)
			(layer "B.Fab")
		)
		(fp_line
			(start -0.12065 -0.2794)
			(end -0.12065 -0.3048)
			(stroke
				(width 0.1)
				(type default)
			)
			(layer "B.Fab")
		)
		(fp_line
			(start -0.12065 -0.3048)
			(end -0.67945 -0.3048)
			(stroke
				(width 0.1)
				(type default)
			)
			(layer "B.Fab")
		)
		(fp_line
			(start -0.67945 0.3048)
			(end -0.120396 0.3048)
			(stroke
				(width 0.1)
				(type default)
			)
			(layer "B.Fab")
		)
		(fp_line
			(start -0.67945 -0.3048)
			(end -0.67945 0.3048)
			(stroke
				(width 0.1)
				(type default)
			)
			(layer "B.Fab")
		)
		(pad "1" smd circle
			(at 0.40005 0)
			(size 0 0)
			(layers "B.Cu" "B.Mask" "B.Paste")
			(net "PWRGD_CHI_CPU0_DIMM")
		)
		(pad "2" smd circle
			(at -0.40005 0)
			(size 0 0)
			(layers "B.Cu" "B.Mask" "B.Paste")
			(net "PWRGD_CHGL_CPU0")
		)
	)
	(footprint ""
		(layer "B.Cu")
		(at 186.22264 -133.208014 90)
		(property "Reference" "R6799"
			(at 0 0 90)
			(layer "B.SilkS")
			(hide yes)
			(effects
				(font
					(size 1.27 1.27)
				)
				(justify mirror)
			)
		)
		(property "Value" ""
			(at 0 0 90)
			(layer "B.Fab")
			(effects
				(font
					(size 1.27 1.27)
				)
				(justify mirror)
			)
		)
		(duplicate_pad_numbers_are_jumpers no)
		(fp_line
			(start 0.7874 -0.4064)
			(end -0.7874 -0.4064)
			(stroke
				(width 0.1524)
				(type default)
			)
			(layer "B.SilkS")
		)
		(fp_line
			(start -0.7874 -0.4064)
			(end -0.7874 0.4064)
			(stroke
				(width 0.1524)
				(type default)
			)
			(layer "B.SilkS")
		)
		(fp_line
			(start 0.7874 0.4064)
			(end 0.7874 -0.4064)
			(stroke
				(width 0.1524)
				(type default)
			)
			(layer "B.SilkS")
		)
		(fp_line
			(start -0.7874 0.4064)
			(end 0.7874 0.4064)
			(stroke
				(width 0.1524)
				(type default)
			)
			(layer "B.SilkS")
		)
		(fp_line
			(start 0.67945 -0.305054)
			(end 0.12065 -0.305054)
			(stroke
				(width 0.1)
				(type default)
			)
			(layer "B.Fab")
		)
		(fp_line
			(start 0.12065 -0.305054)
			(end 0.12065 -0.2794)
			(stroke
				(width 0.1)
				(type default)
			)
			(layer "B.Fab")
		)
		(fp_line
			(start -0.12065 -0.3048)
			(end -0.67945 -0.3048)
			(stroke
				(width 0.1)
				(type default)
			)
			(layer "B.Fab")
		)
		(fp_line
			(start -0.67945 -0.3048)
			(end -0.67945 0.3048)
			(stroke
				(width 0.1)
				(type default)
			)
			(layer "B.Fab")
		)
		(fp_line
			(start 0.12065 -0.2794)
			(end -0.12065 -0.2794)
			(stroke
				(width 0.1)
				(type default)
			)
			(layer "B.Fab")
		)
		(fp_line
			(start -0.12065 -0.2794)
			(end -0.12065 -0.3048)
			(stroke
				(width 0.1)
				(type default)
			)
			(layer "B.Fab")
		)
		(fp_line
			(start 0.12065 0.2794)
			(end 0.12065 0.3048)
			(stroke
				(width 0.1)
				(type default)
			)
			(layer "B.Fab")
		)
		(fp_line
			(start -0.120396 0.2794)
			(end 0.12065 0.2794)
			(stroke
				(width 0.1)
				(type default)
			)
			(layer "B.Fab")
		)
		(fp_line
			(start 0.67945 0.3048)
			(end 0.67945 -0.305054)
			(stroke
				(width 0.1)
				(type default)
			)
			(layer "B.Fab")
		)
		(fp_line
			(start 0.12065 0.3048)
			(end 0.67945 0.3048)
			(stroke
				(width 0.1)
				(type default)
			)
			(layer "B.Fab")
		)
		(fp_line
			(start -0.120396 0.3048)
			(end -0.120396 0.2794)
			(stroke
				(width 0.1)
				(type default)
			)
			(layer "B.Fab")
		)
		(fp_line
			(start -0.67945 0.3048)
			(end -0.120396 0.3048)
			(stroke
				(width 0.1)
				(type default)
			)
			(layer "B.Fab")
		)
		(pad "1" smd circle
			(at 0.40005 0 270)
			(size 0 0)
			(layers "B.Cu" "B.Mask" "B.Paste")
			(net "RST_RT_CPU1_P3_RESET_R_N")
		)
		(pad "2" smd circle
			(at -0.40005 0 270)
			(size 0 0)
			(layers "B.Cu" "B.Mask" "B.Paste")
			(net "RST_RT_CPU1_P3_RESET_R2_N")
		)
	)
	(footprint ""
		(layer "B.Cu")
		(at 116.116354 -178.658012 90)
		(property "Reference" "PC343"
			(at 6.671056 -0.439166 270)
			(unlocked yes)
			(layer "B.SilkS")
			(effects
				(font
					(size 0.7874 0.5842)
					(thickness 0.1524)
				)
				(justify left mirror)
			)
		)
		(property "Value" ""
			(at 0 0 90)
			(layer "B.Fab")
			(effects
				(font
					(size 1.27 1.27)
				)
				(justify mirror)
			)
		)
		(duplicate_pad_numbers_are_jumpers no)
		(fp_line
			(start 4.533392 -2.249932)
			(end -4.533392 -2.249932)
			(stroke
				(width 0.1524)
				(type default)
			)
			(layer "B.SilkS")
		)
		(fp_line
			(start -4.533392 -2.249932)
			(end -4.533392 2.249932)
			(stroke
				(width 0.1524)
				(type default)
			)
			(layer "B.SilkS")
		)
		(fp_line
			(start 4.533392 2.249932)
			(end 4.533392 -2.249932)
			(stroke
				(width 0.1524)
				(type default)
			)
			(layer "B.SilkS")
		)
		(fp_line
			(start -4.533392 2.249932)
			(end 4.533392 2.249932)
			(stroke
				(width 0.1524)
				(type default)
			)
			(layer "B.SilkS")
		)
		(fp_rect
			(start 4.533392 -2.326132)
			(end 5.39242 2.326132)
			(stroke
				(width 0)
				(type default)
			)
			(fill yes)
			(layer "B.SilkS")
		)
		(fp_line
			(start 3.750056 -2.249932)
			(end -3.750056 -2.249932)
			(stroke
				(width 0.1)
				(type default)
			)
			(layer "B.Fab")
		)
		(fp_line
			(start -3.750056 -2.249932)
			(end -3.750056 2.249932)
			(stroke
				(width 0.1)
				(type default)
			)
			(layer "B.Fab")
		)
		(fp_line
			(start 3.750056 2.249932)
			(end 3.750056 -2.249932)
			(stroke
				(width 0.1)
				(type default)
			)
			(layer "B.Fab")
		)
		(fp_line
			(start -3.750056 2.249932)
			(end 3.750056 2.249932)
			(stroke
				(width 0.1)
				(type default)
			)
			(layer "B.Fab")
		)
		(fp_text user "-"
			(at -4.8514 -0.14605 90)
			(unlocked yes)
			(layer "B.SilkS")
			(effects
				(font
					(size 1.905 1.4224)
					(thickness 0.1524)
				)
				(justify left mirror)
			)
		)
		(fp_text user "+"
			(at 6.322314 0.786384 0)
			(unlocked yes)
			(layer "B.SilkS")
			(effects
				(font
					(size 1.905 1.4224)
					(thickness 0.1524)
				)
				(justify left mirror)
			)
		)
		(fp_text user "-"
			(at -4.8514 -0.14605 90)
			(unlocked yes)
			(layer "B.Fab")
			(effects
				(font
					(size 1.905 1.4224)
					(thickness 0.1524)
				)
				(justify left mirror)
			)
		)
		(fp_text user "+"
			(at 6.322314 0.786384 0)
			(unlocked yes)
			(layer "B.Fab")
			(effects
				(font
					(size 1.905 1.4224)
					(thickness 0.1524)
				)
				(justify left mirror)
			)
		)
		(pad "1" smd rect
			(at 3.199892 0 270)
			(size 2.413 2.8194)
			(layers "B.Cu" "B.Mask" "B.Paste")
			(net "PVDDCR_SOC_P1")
		)
		(pad "2" smd rect
			(at -3.199892 0 270)
			(size 2.413 2.8194)
			(layers "B.Cu" "B.Mask" "B.Paste")
			(net "GND")
		)
	)
	(footprint ""
		(layer "B.Cu")
		(at 357.517192 -261.747762 90)
		(property "Reference" "C2153"
			(at 0 0 90)
			(layer "B.SilkS")
			(hide yes)
			(effects
				(font
					(size 1.27 1.27)
				)
				(justify mirror)
			)
		)
		(property "Value" ""
			(at 0 0 90)
			(layer "B.Fab")
			(effects
				(font
					(size 1.27 1.27)
				)
				(justify mirror)
			)
		)
		(duplicate_pad_numbers_are_jumpers no)
		(fp_line
			(start 0.7874 -0.4064)
			(end -0.7874 -0.4064)
			(stroke
				(width 0.1524)
				(type default)
			)
			(layer "B.SilkS")
		)
		(fp_line
			(start -0.7874 -0.4064)
			(end -0.7874 0.4064)
			(stroke
				(width 0.1524)
				(type default)
			)
			(layer "B.SilkS")
		)
		(fp_line
			(start 0.7874 0.4064)
			(end 0.7874 -0.4064)
			(stroke
				(width 0.1524)
				(type default)
			)
			(layer "B.SilkS")
		)
		(fp_line
			(start -0.7874 0.4064)
			(end 0.7874 0.4064)
			(stroke
				(width 0.1524)
				(type default)
			)
			(layer "B.SilkS")
		)
		(fp_line
			(start 0.67945 -0.305054)
			(end 0.12065 -0.305054)
			(stroke
				(width 0.1)
				(type default)
			)
			(layer "B.Fab")
		)
		(fp_line
			(start 0.12065 -0.305054)
			(end 0.12065 -0.2794)
			(stroke
				(width 0.1)
				(type default)
			)
			(layer "B.Fab")
		)
		(fp_line
			(start -0.12065 -0.3048)
			(end -0.67945 -0.3048)
			(stroke
				(width 0.1)
				(type default)
			)
			(layer "B.Fab")
		)
		(fp_line
			(start -0.67945 -0.3048)
			(end -0.67945 0.3048)
			(stroke
				(width 0.1)
				(type default)
			)
			(layer "B.Fab")
		)
		(fp_line
			(start 0.12065 -0.2794)
			(end -0.12065 -0.2794)
			(stroke
				(width 0.1)
				(type default)
			)
			(layer "B.Fab")
		)
		(fp_line
			(start -0.12065 -0.2794)
			(end -0.12065 -0.3048)
			(stroke
				(width 0.1)
				(type default)
			)
			(layer "B.Fab")
		)
		(fp_line
			(start 0.12065 0.2794)
			(end 0.12065 0.3048)
			(stroke
				(width 0.1)
				(type default)
			)
			(layer "B.Fab")
		)
		(fp_line
			(start -0.120396 0.2794)
			(end 0.12065 0.2794)
			(stroke
				(width 0.1)
				(type default)
			)
			(layer "B.Fab")
		)
		(fp_line
			(start 0.67945 0.3048)
			(end 0.67945 -0.305054)
			(stroke
				(width 0.1)
				(type default)
			)
			(layer "B.Fab")
		)
		(fp_line
			(start 0.12065 0.3048)
			(end 0.67945 0.3048)
			(stroke
				(width 0.1)
				(type default)
			)
			(layer "B.Fab")
		)
		(fp_line
			(start -0.120396 0.3048)
			(end -0.120396 0.2794)
			(stroke
				(width 0.1)
				(type default)
			)
			(layer "B.Fab")
		)
		(fp_line
			(start -0.67945 0.3048)
			(end -0.120396 0.3048)
			(stroke
				(width 0.1)
				(type default)
			)
			(layer "B.Fab")
		)
		(pad "1" smd circle
			(at 0.40005 0 270)
			(size 0 0)
			(layers "B.Cu" "B.Mask" "B.Paste")
			(net "PVDD11_S3_P0")
		)
		(pad "2" smd circle
			(at -0.40005 0 270)
			(size 0 0)
			(layers "B.Cu" "B.Mask" "B.Paste")
			(net "GND")
		)
	)
	(footprint ""
		(layer "B.Cu")
		(at 126.892304 -32.867092 -90)
		(property "Reference" "C6075"
			(at 0 0 90)
			(layer "B.SilkS")
			(hide yes)
			(effects
				(font
					(size 1.27 1.27)
				)
				(justify mirror)
			)
		)
		(property "Value" ""
			(at 0 0 90)
			(layer "B.Fab")
			(effects
				(font
					(size 1.27 1.27)
				)
				(justify mirror)
			)
		)
		(duplicate_pad_numbers_are_jumpers no)
		(fp_line
			(start -0.7874 0.4064)
			(end 0.7874 0.4064)
			(stroke
				(width 0.1524)
				(type default)
			)
			(layer "B.SilkS")
		)
		(fp_line
			(start 0.7874 0.4064)
			(end 0.7874 -0.4064)
			(stroke
				(width 0.1524)
				(type default)
			)
			(layer "B.SilkS")
		)
		(fp_line
			(start -0.7874 -0.4064)
			(end -0.7874 0.4064)
			(stroke
				(width 0.1524)
				(type default)
			)
			(layer "B.SilkS")
		)
		(fp_line
			(start 0.7874 -0.4064)
			(end -0.7874 -0.4064)
			(stroke
				(width 0.1524)
				(type default)
			)
			(layer "B.SilkS")
		)
		(fp_line
			(start -0.67945 0.3048)
			(end -0.120396 0.3048)
			(stroke
				(width 0.1)
				(type default)
			)
			(layer "B.Fab")
		)
		(fp_line
			(start -0.120396 0.3048)
			(end -0.120396 0.2794)
			(stroke
				(width 0.1)
				(type default)
			)
			(layer "B.Fab")
		)
		(fp_line
			(start 0.12065 0.3048)
			(end 0.67945 0.3048)
			(stroke
				(width 0.1)
				(type default)
			)
			(layer "B.Fab")
		)
		(fp_line
			(start 0.67945 0.3048)
			(end 0.67945 -0.305054)
			(stroke
				(width 0.1)
				(type default)
			)
			(layer "B.Fab")
		)
		(fp_line
			(start -0.120396 0.2794)
			(end 0.12065 0.2794)
			(stroke
				(width 0.1)
				(type default)
			)
			(layer "B.Fab")
		)
		(fp_line
			(start 0.12065 0.2794)
			(end 0.12065 0.3048)
			(stroke
				(width 0.1)
				(type default)
			)
			(layer "B.Fab")
		)
		(fp_line
			(start -0.12065 -0.2794)
			(end -0.12065 -0.3048)
			(stroke
				(width 0.1)
				(type default)
			)
			(layer "B.Fab")
		)
		(fp_line
			(start 0.12065 -0.2794)
			(end -0.12065 -0.2794)
			(stroke
				(width 0.1)
				(type default)
			)
			(layer "B.Fab")
		)
		(fp_line
			(start -0.67945 -0.3048)
			(end -0.67945 0.3048)
			(stroke
				(width 0.1)
				(type default)
			)
			(layer "B.Fab")
		)
		(fp_line
			(start -0.12065 -0.3048)
			(end -0.67945 -0.3048)
			(stroke
				(width 0.1)
				(type default)
			)
			(layer "B.Fab")
		)
		(fp_line
			(start 0.12065 -0.305054)
			(end 0.12065 -0.2794)
			(stroke
				(width 0.1)
				(type default)
			)
			(layer "B.Fab")
		)
		(fp_line
			(start 0.67945 -0.305054)
			(end 0.12065 -0.305054)
			(stroke
				(width 0.1)
				(type default)
			)
			(layer "B.Fab")
		)
		(pad "1" smd circle
			(at 0.40005 0 90)
			(size 0 0)
			(layers "B.Cu" "B.Mask" "B.Paste")
			(net "P1V2_AUX")
		)
		(pad "2" smd circle
			(at -0.40005 0 90)
			(size 0 0)
			(layers "B.Cu" "B.Mask" "B.Paste")
			(net "GND")
		)
	)
	(footprint ""
		(layer "B.Cu")
		(at 255.905 -340.76132 180)
		(property "Reference" "R799"
			(at 0 0 0)
			(layer "B.SilkS")
			(hide yes)
			(effects
				(font
					(size 1.27 1.27)
				)
				(justify mirror)
			)
		)
		(property "Value" ""
			(at 0 0 0)
			(layer "B.Fab")
			(effects
				(font
					(size 1.27 1.27)
				)
				(justify mirror)
			)
		)
		(duplicate_pad_numbers_are_jumpers no)
		(fp_line
			(start 0.32512 0.175006)
			(end 0.32512 -0.175006)
			(stroke
				(width 0.1)
				(type default)
			)
			(layer "B.Fab")
		)
		(fp_line
			(start 0.32512 -0.175006)
			(end -0.32512 -0.175006)
			(stroke
				(width 0.1)
				(type default)
			)
			(layer "B.Fab")
		)
		(fp_line
			(start -0.32512 0.175006)
			(end 0.32512 0.175006)
			(stroke
				(width 0.1)
				(type default)
			)
			(layer "B.Fab")
		)
		(fp_line
			(start -0.32512 -0.175006)
			(end -0.32512 0.175006)
			(stroke
				(width 0.1)
				(type default)
			)
			(layer "B.Fab")
		)
		(pad "1" smd rect
			(at 0.2667 0)
			(size 0.3048 0.381)
			(layers "B.Cu" "B.Mask" "B.Paste")
			(net "SMB_RT_CPU0_P0_ROM_MUX_2D_R_SCL")
		)
		(pad "2" smd rect
			(at -0.2667 0 180)
			(size 0.3048 0.381)
			(layers "B.Cu" "B.Mask" "B.Paste")
			(net "SMB_RT_CPU0_P0_ROM_MUX_2D_SCL")
		)
	)
	(footprint ""
		(layer "B.Cu")
		(at 157.226 -416.9664 180)
		(property "Reference" "R1468"
			(at 0 0 0)
			(layer "B.SilkS")
			(hide yes)
			(effects
				(font
					(size 1.27 1.27)
				)
				(justify mirror)
			)
		)
		(property "Value" ""
			(at 0 0 0)
			(layer "B.Fab")
			(effects
				(font
					(size 1.27 1.27)
				)
				(justify mirror)
			)
		)
		(duplicate_pad_numbers_are_jumpers no)
		(fp_line
			(start 0.32512 0.175006)
			(end 0.32512 -0.175006)
			(stroke
				(width 0.1)
				(type default)
			)
			(layer "B.Fab")
		)
		(fp_line
			(start 0.32512 -0.175006)
			(end -0.32512 -0.175006)
			(stroke
				(width 0.1)
				(type default)
			)
			(layer "B.Fab")
		)
		(fp_line
			(start -0.32512 0.175006)
			(end 0.32512 0.175006)
			(stroke
				(width 0.1)
				(type default)
			)
			(layer "B.Fab")
		)
		(fp_line
			(start -0.32512 -0.175006)
			(end -0.32512 0.175006)
			(stroke
				(width 0.1)
				(type default)
			)
			(layer "B.Fab")
		)
		(pad "1" smd rect
			(at 0.2667 0)
			(size 0.3048 0.381)
			(layers "B.Cu" "B.Mask" "B.Paste")
			(net "P1V8_CPU1_RT_1D")
		)
		(pad "2" smd rect
			(at -0.2667 0 180)
			(size 0.3048 0.381)
			(layers "B.Cu" "B.Mask" "B.Paste")
			(net "SMB_RT_CPU1_P2_ROM_MUX_1D_SDA")
		)
	)
	(footprint ""
		(layer "B.Cu")
		(at 16.367252 -421.594026 -90)
		(property "Reference" "C1865"
			(at 0 0 90)
			(layer "B.SilkS")
			(hide yes)
			(effects
				(font
					(size 1.27 1.27)
				)
				(justify mirror)
			)
		)
		(property "Value" ""
			(at 0 0 90)
			(layer "B.Fab")
			(effects
				(font
					(size 1.27 1.27)
				)
				(justify mirror)
			)
		)
		(duplicate_pad_numbers_are_jumpers no)
		(fp_line
			(start -0.7874 0.4064)
			(end 0.7874 0.4064)
			(stroke
				(width 0.1524)
				(type default)
			)
			(layer "B.SilkS")
		)
		(fp_line
			(start 0.7874 0.4064)
			(end 0.7874 -0.4064)
			(stroke
				(width 0.1524)
				(type default)
			)
			(layer "B.SilkS")
		)
		(fp_line
			(start -0.7874 -0.4064)
			(end -0.7874 0.4064)
			(stroke
				(width 0.1524)
				(type default)
			)
			(layer "B.SilkS")
		)
		(fp_line
			(start 0.7874 -0.4064)
			(end -0.7874 -0.4064)
			(stroke
				(width 0.1524)
				(type default)
			)
			(layer "B.SilkS")
		)
		(fp_line
			(start -0.67945 0.3048)
			(end -0.120396 0.3048)
			(stroke
				(width 0.1)
				(type default)
			)
			(layer "B.Fab")
		)
		(fp_line
			(start -0.120396 0.3048)
			(end -0.120396 0.2794)
			(stroke
				(width 0.1)
				(type default)
			)
			(layer "B.Fab")
		)
		(fp_line
			(start 0.12065 0.3048)
			(end 0.67945 0.3048)
			(stroke
				(width 0.1)
				(type default)
			)
			(layer "B.Fab")
		)
		(fp_line
			(start 0.67945 0.3048)
			(end 0.67945 -0.305054)
			(stroke
				(width 0.1)
				(type default)
			)
			(layer "B.Fab")
		)
		(fp_line
			(start -0.120396 0.2794)
			(end 0.12065 0.2794)
			(stroke
				(width 0.1)
				(type default)
			)
			(layer "B.Fab")
		)
		(fp_line
			(start 0.12065 0.2794)
			(end 0.12065 0.3048)
			(stroke
				(width 0.1)
				(type default)
			)
			(layer "B.Fab")
		)
		(fp_line
			(start -0.12065 -0.2794)
			(end -0.12065 -0.3048)
			(stroke
				(width 0.1)
				(type default)
			)
			(layer "B.Fab")
		)
		(fp_line
			(start 0.12065 -0.2794)
			(end -0.12065 -0.2794)
			(stroke
				(width 0.1)
				(type default)
			)
			(layer "B.Fab")
		)
		(fp_line
			(start -0.67945 -0.3048)
			(end -0.67945 0.3048)
			(stroke
				(width 0.1)
				(type default)
			)
			(layer "B.Fab")
		)
		(fp_line
			(start -0.12065 -0.3048)
			(end -0.67945 -0.3048)
			(stroke
				(width 0.1)
				(type default)
			)
			(layer "B.Fab")
		)
		(fp_line
			(start 0.12065 -0.305054)
			(end 0.12065 -0.2794)
			(stroke
				(width 0.1)
				(type default)
			)
			(layer "B.Fab")
		)
		(fp_line
			(start 0.67945 -0.305054)
			(end 0.12065 -0.305054)
			(stroke
				(width 0.1)
				(type default)
			)
			(layer "B.Fab")
		)
		(pad "1" smd circle
			(at 0.40005 0 90)
			(size 0 0)
			(layers "B.Cu" "B.Mask" "B.Paste")
			(net "P3V3_AUX")
		)
		(pad "2" smd circle
			(at -0.40005 0 90)
			(size 0 0)
			(layers "B.Cu" "B.Mask" "B.Paste")
			(net "GND")
		)
	)
	(footprint ""
		(layer "B.Cu")
		(at 455.111104 -65.768982 90)
		(property "Reference" "PC1599"
			(at 0 0 90)
			(layer "B.SilkS")
			(hide yes)
			(effects
				(font
					(size 1.27 1.27)
				)
				(justify mirror)
			)
		)
		(property "Value" ""
			(at 0 0 90)
			(layer "B.Fab")
			(effects
				(font
					(size 1.27 1.27)
				)
				(justify mirror)
			)
		)
		(duplicate_pad_numbers_are_jumpers no)
		(fp_line
			(start 1.524 -0.762)
			(end -1.524 -0.762)
			(stroke
				(width 0.1524)
				(type default)
			)
			(layer "B.SilkS")
		)
		(fp_line
			(start -1.524 -0.762)
			(end -1.524 0.762)
			(stroke
				(width 0.1524)
				(type default)
			)
			(layer "B.SilkS")
		)
		(fp_line
			(start 1.524 0.762)
			(end 1.524 -0.762)
			(stroke
				(width 0.1524)
				(type default)
			)
			(layer "B.SilkS")
		)
		(fp_line
			(start -1.524 0.762)
			(end 1.524 0.762)
			(stroke
				(width 0.1524)
				(type default)
			)
			(layer "B.SilkS")
		)
		(fp_line
			(start 1.1049 -0.724916)
			(end 1.1049 0.724916)
			(stroke
				(width 0.1)
				(type default)
			)
			(layer "B.Fab")
		)
		(fp_line
			(start -1.1049 -0.724916)
			(end 1.1049 -0.724916)
			(stroke
				(width 0.1)
				(type default)
			)
			(layer "B.Fab")
		)
		(fp_line
			(start 1.1049 0.724916)
			(end -1.1049 0.724916)
			(stroke
				(width 0.1)
				(type default)
			)
			(layer "B.Fab")
		)
		(fp_line
			(start -1.1049 0.724916)
			(end -1.1049 -0.724916)
			(stroke
				(width 0.1)
				(type default)
			)
			(layer "B.Fab")
		)
		(pad "1" smd rect
			(at 0.889 0 90)
			(size 1.016 1.27)
			(layers "B.Cu" "B.Mask" "B.Paste")
			(net "P3V3_AUX")
		)
		(pad "2" smd rect
			(at -0.889 0 90)
			(size 1.016 1.27)
			(layers "B.Cu" "B.Mask" "B.Paste")
			(net "GND")
		)
	)
	(footprint ""
		(layer "B.Cu")
		(at 449.910454 -191.32931 180)
		(property "Reference" "R302"
			(at 0 0 0)
			(layer "B.SilkS")
			(hide yes)
			(effects
				(font
					(size 1.27 1.27)
				)
				(justify mirror)
			)
		)
		(property "Value" ""
			(at 0 0 0)
			(layer "B.Fab")
			(effects
				(font
					(size 1.27 1.27)
				)
				(justify mirror)
			)
		)
		(duplicate_pad_numbers_are_jumpers no)
		(fp_line
			(start 0.7874 0.4064)
			(end 0.7874 -0.4064)
			(stroke
				(width 0.1524)
				(type default)
			)
			(layer "B.SilkS")
		)
		(fp_line
			(start 0.7874 -0.4064)
			(end -0.7874 -0.4064)
			(stroke
				(width 0.1524)
				(type default)
			)
			(layer "B.SilkS")
		)
		(fp_line
			(start -0.7874 0.4064)
			(end 0.7874 0.4064)
			(stroke
				(width 0.1524)
				(type default)
			)
			(layer "B.SilkS")
		)
		(fp_line
			(start -0.7874 -0.4064)
			(end -0.7874 0.4064)
			(stroke
				(width 0.1524)
				(type default)
			)
			(layer "B.SilkS")
		)
		(fp_line
			(start 0.67945 0.3048)
			(end 0.67945 -0.305054)
			(stroke
				(width 0.1)
				(type default)
			)
			(layer "B.Fab")
		)
		(fp_line
			(start 0.67945 -0.305054)
			(end 0.12065 -0.305054)
			(stroke
				(width 0.1)
				(type default)
			)
			(layer "B.Fab")
		)
		(fp_line
			(start 0.12065 0.3048)
			(end 0.67945 0.3048)
			(stroke
				(width 0.1)
				(type default)
			)
			(layer "B.Fab")
		)
		(fp_line
			(start 0.12065 0.2794)
			(end 0.12065 0.3048)
			(stroke
				(width 0.1)
				(type default)
			)
			(layer "B.Fab")
		)
		(fp_line
			(start 0.12065 -0.2794)
			(end -0.12065 -0.2794)
			(stroke
				(width 0.1)
				(type default)
			)
			(layer "B.Fab")
		)
		(fp_line
			(start 0.12065 -0.305054)
			(end 0.12065 -0.2794)
			(stroke
				(width 0.1)
				(type default)
			)
			(layer "B.Fab")
		)
		(fp_line
			(start -0.120396 0.3048)
			(end -0.120396 0.2794)
			(stroke
				(width 0.1)
				(type default)
			)
			(layer "B.Fab")
		)
		(fp_line
			(start -0.120396 0.2794)
			(end 0.12065 0.2794)
			(stroke
				(width 0.1)
				(type default)
			)
			(layer "B.Fab")
		)
		(fp_line
			(start -0.12065 -0.2794)
			(end -0.12065 -0.3048)
			(stroke
				(width 0.1)
				(type default)
			)
			(layer "B.Fab")
		)
		(fp_line
			(start -0.12065 -0.3048)
			(end -0.67945 -0.3048)
			(stroke
				(width 0.1)
				(type default)
			)
			(layer "B.Fab")
		)
		(fp_line
			(start -0.67945 0.3048)
			(end -0.120396 0.3048)
			(stroke
				(width 0.1)
				(type default)
			)
			(layer "B.Fab")
		)
		(fp_line
			(start -0.67945 -0.3048)
			(end -0.67945 0.3048)
			(stroke
				(width 0.1)
				(type default)
			)
			(layer "B.Fab")
		)
		(pad "1" smd circle
			(at 0.40005 0)
			(size 0 0)
			(layers "B.Cu" "B.Mask" "B.Paste")
			(net "PWRGD_CHL_CPU0_DIMM")
		)
		(pad "2" smd circle
			(at -0.40005 0)
			(size 0 0)
			(layers "B.Cu" "B.Mask" "B.Paste")
			(net "PWRGD_CHGL_CPU0")
		)
	)
	(footprint ""
		(layer "B.Cu")
		(at 254.635 -331.978 180)
		(property "Reference" "R851"
			(at 0 0 0)
			(layer "B.SilkS")
			(hide yes)
			(effects
				(font
					(size 1.27 1.27)
				)
				(justify mirror)
			)
		)
		(property "Value" ""
			(at 0 0 0)
			(layer "B.Fab")
			(effects
				(font
					(size 1.27 1.27)
				)
				(justify mirror)
			)
		)
		(duplicate_pad_numbers_are_jumpers no)
		(fp_line
			(start 0.32512 0.175006)
			(end 0.32512 -0.175006)
			(stroke
				(width 0.1)
				(type default)
			)
			(layer "B.Fab")
		)
		(fp_line
			(start 0.32512 -0.175006)
			(end -0.32512 -0.175006)
			(stroke
				(width 0.1)
				(type default)
			)
			(layer "B.Fab")
		)
		(fp_line
			(start -0.32512 0.175006)
			(end 0.32512 0.175006)
			(stroke
				(width 0.1)
				(type default)
			)
			(layer "B.Fab")
		)
		(fp_line
			(start -0.32512 -0.175006)
			(end -0.32512 0.175006)
			(stroke
				(width 0.1)
				(type default)
			)
			(layer "B.Fab")
		)
		(pad "1" smd rect
			(at 0.2667 0)
			(size 0.3048 0.381)
			(layers "B.Cu" "B.Mask" "B.Paste")
			(net "SMB_MUX_RT_ROM_SCL")
		)
		(pad "2" smd rect
			(at -0.2667 0 180)
			(size 0.3048 0.381)
			(layers "B.Cu" "B.Mask" "B.Paste")
			(net "SMB_MUX_RT_ROM_R1_SCL")
		)
	)
	(footprint ""
		(layer "B.Cu")
		(at 283.980636 -195.859146 180)
		(property "Reference" "R1676"
			(at 0 0 0)
			(layer "B.SilkS")
			(hide yes)
			(effects
				(font
					(size 1.27 1.27)
				)
				(justify mirror)
			)
		)
		(property "Value" ""
			(at 0 0 0)
			(layer "B.Fab")
			(effects
				(font
					(size 1.27 1.27)
				)
				(justify mirror)
			)
		)
		(duplicate_pad_numbers_are_jumpers no)
		(fp_line
			(start 0.7874 0.4064)
			(end 0.7874 -0.4064)
			(stroke
				(width 0.1524)
				(type default)
			)
			(layer "B.SilkS")
		)
		(fp_line
			(start 0.7874 -0.4064)
			(end -0.7874 -0.4064)
			(stroke
				(width 0.1524)
				(type default)
			)
			(layer "B.SilkS")
		)
		(fp_line
			(start -0.7874 0.4064)
			(end 0.7874 0.4064)
			(stroke
				(width 0.1524)
				(type default)
			)
			(layer "B.SilkS")
		)
		(fp_line
			(start -0.7874 -0.4064)
			(end -0.7874 0.4064)
			(stroke
				(width 0.1524)
				(type default)
			)
			(layer "B.SilkS")
		)
		(fp_line
			(start 0.67945 0.3048)
			(end 0.67945 -0.305054)
			(stroke
				(width 0.1)
				(type default)
			)
			(layer "B.Fab")
		)
		(fp_line
			(start 0.67945 -0.305054)
			(end 0.12065 -0.305054)
			(stroke
				(width 0.1)
				(type default)
			)
			(layer "B.Fab")
		)
		(fp_line
			(start 0.12065 0.3048)
			(end 0.67945 0.3048)
			(stroke
				(width 0.1)
				(type default)
			)
			(layer "B.Fab")
		)
		(fp_line
			(start 0.12065 0.2794)
			(end 0.12065 0.3048)
			(stroke
				(width 0.1)
				(type default)
			)
			(layer "B.Fab")
		)
		(fp_line
			(start 0.12065 -0.2794)
			(end -0.12065 -0.2794)
			(stroke
				(width 0.1)
				(type default)
			)
			(layer "B.Fab")
		)
		(fp_line
			(start 0.12065 -0.305054)
			(end 0.12065 -0.2794)
			(stroke
				(width 0.1)
				(type default)
			)
			(layer "B.Fab")
		)
		(fp_line
			(start -0.120396 0.3048)
			(end -0.120396 0.2794)
			(stroke
				(width 0.1)
				(type default)
			)
			(layer "B.Fab")
		)
		(fp_line
			(start -0.120396 0.2794)
			(end 0.12065 0.2794)
			(stroke
				(width 0.1)
				(type default)
			)
			(layer "B.Fab")
		)
		(fp_line
			(start -0.12065 -0.2794)
			(end -0.12065 -0.3048)
			(stroke
				(width 0.1)
				(type default)
			)
			(layer "B.Fab")
		)
		(fp_line
			(start -0.12065 -0.3048)
			(end -0.67945 -0.3048)
			(stroke
				(width 0.1)
				(type default)
			)
			(layer "B.Fab")
		)
		(fp_line
			(start -0.67945 0.3048)
			(end -0.120396 0.3048)
			(stroke
				(width 0.1)
				(type default)
			)
			(layer "B.Fab")
		)
		(fp_line
			(start -0.67945 -0.3048)
			(end -0.67945 0.3048)
			(stroke
				(width 0.1)
				(type default)
			)
			(layer "B.Fab")
		)
		(pad "1" smd circle
			(at 0.40005 0)
			(size 0 0)
			(layers "B.Cu" "B.Mask" "B.Paste")
			(net "I3C_SPD_DDRAF_CPU0_SDA")
		)
		(pad "2" smd circle
			(at -0.40005 0)
			(size 0 0)
			(layers "B.Cu" "B.Mask" "B.Paste")
			(net "I3C_SPD_DDRD_CPU0_SDA")
		)
	)
	(footprint ""
		(layer "B.Cu")
		(at 152.992836 -16.851122 -90)
		(property "Reference" "R3227"
			(at 0 0 90)
			(layer "B.SilkS")
			(hide yes)
			(effects
				(font
					(size 1.27 1.27)
				)
				(justify mirror)
			)
		)
		(property "Value" ""
			(at 0 0 90)
			(layer "B.Fab")
			(effects
				(font
					(size 1.27 1.27)
				)
				(justify mirror)
			)
		)
		(duplicate_pad_numbers_are_jumpers no)
		(fp_line
			(start -0.7874 0.4064)
			(end 0.7874 0.4064)
			(stroke
				(width 0.1524)
				(type default)
			)
			(layer "B.SilkS")
		)
		(fp_line
			(start 0.7874 0.4064)
			(end 0.7874 -0.4064)
			(stroke
				(width 0.1524)
				(type default)
			)
			(layer "B.SilkS")
		)
		(fp_line
			(start -0.7874 -0.4064)
			(end -0.7874 0.4064)
			(stroke
				(width 0.1524)
				(type default)
			)
			(layer "B.SilkS")
		)
		(fp_line
			(start 0.7874 -0.4064)
			(end -0.7874 -0.4064)
			(stroke
				(width 0.1524)
				(type default)
			)
			(layer "B.SilkS")
		)
		(fp_line
			(start -0.67945 0.3048)
			(end -0.120396 0.3048)
			(stroke
				(width 0.1)
				(type default)
			)
			(layer "B.Fab")
		)
		(fp_line
			(start -0.120396 0.3048)
			(end -0.120396 0.2794)
			(stroke
				(width 0.1)
				(type default)
			)
			(layer "B.Fab")
		)
		(fp_line
			(start 0.12065 0.3048)
			(end 0.67945 0.3048)
			(stroke
				(width 0.1)
				(type default)
			)
			(layer "B.Fab")
		)
		(fp_line
			(start 0.67945 0.3048)
			(end 0.67945 -0.305054)
			(stroke
				(width 0.1)
				(type default)
			)
			(layer "B.Fab")
		)
		(fp_line
			(start -0.120396 0.2794)
			(end 0.12065 0.2794)
			(stroke
				(width 0.1)
				(type default)
			)
			(layer "B.Fab")
		)
		(fp_line
			(start 0.12065 0.2794)
			(end 0.12065 0.3048)
			(stroke
				(width 0.1)
				(type default)
			)
			(layer "B.Fab")
		)
		(fp_line
			(start -0.12065 -0.2794)
			(end -0.12065 -0.3048)
			(stroke
				(width 0.1)
				(type default)
			)
			(layer "B.Fab")
		)
		(fp_line
			(start 0.12065 -0.2794)
			(end -0.12065 -0.2794)
			(stroke
				(width 0.1)
				(type default)
			)
			(layer "B.Fab")
		)
		(fp_line
			(start -0.67945 -0.3048)
			(end -0.67945 0.3048)
			(stroke
				(width 0.1)
				(type default)
			)
			(layer "B.Fab")
		)
		(fp_line
			(start -0.12065 -0.3048)
			(end -0.67945 -0.3048)
			(stroke
				(width 0.1)
				(type default)
			)
			(layer "B.Fab")
		)
		(fp_line
			(start 0.12065 -0.305054)
			(end 0.12065 -0.2794)
			(stroke
				(width 0.1)
				(type default)
			)
			(layer "B.Fab")
		)
		(fp_line
			(start 0.67945 -0.305054)
			(end 0.12065 -0.305054)
			(stroke
				(width 0.1)
				(type default)
			)
			(layer "B.Fab")
		)
		(pad "1" smd circle
			(at 0.40005 0 90)
			(size 0 0)
			(layers "B.Cu" "B.Mask" "B.Paste")
			(net "SMB_1_BMC_GPU_SDA")
		)
		(pad "2" smd circle
			(at -0.40005 0 90)
			(size 0 0)
			(layers "B.Cu" "B.Mask" "B.Paste")
			(net "P3V3_AUX")
		)
	)
	(footprint ""
		(layer "B.Cu")
		(at 354.915724 -340.002368 90)
		(property "Reference" "PC118_6"
			(at 0 0 90)
			(layer "B.SilkS")
			(hide yes)
			(effects
				(font
					(size 1.27 1.27)
				)
				(justify mirror)
			)
		)
		(property "Value" ""
			(at 0 0 90)
			(layer "B.Fab")
			(effects
				(font
					(size 1.27 1.27)
				)
				(justify mirror)
			)
		)
		(duplicate_pad_numbers_are_jumpers no)
		(fp_line
			(start 1.524 -0.762)
			(end -1.524 -0.762)
			(stroke
				(width 0.1524)
				(type default)
			)
			(layer "B.SilkS")
		)
		(fp_line
			(start -1.524 -0.762)
			(end -1.524 0.762)
			(stroke
				(width 0.1524)
				(type default)
			)
			(layer "B.SilkS")
		)
		(fp_line
			(start 1.524 0.762)
			(end 1.524 -0.762)
			(stroke
				(width 0.1524)
				(type default)
			)
			(layer "B.SilkS")
		)
		(fp_line
			(start -1.524 0.762)
			(end 1.524 0.762)
			(stroke
				(width 0.1524)
				(type default)
			)
			(layer "B.SilkS")
		)
		(fp_line
			(start 1.1049 -0.724916)
			(end 1.1049 0.724916)
			(stroke
				(width 0.1)
				(type default)
			)
			(layer "B.Fab")
		)
		(fp_line
			(start -1.1049 -0.724916)
			(end 1.1049 -0.724916)
			(stroke
				(width 0.1)
				(type default)
			)
			(layer "B.Fab")
		)
		(fp_line
			(start 1.1049 0.724916)
			(end -1.1049 0.724916)
			(stroke
				(width 0.1)
				(type default)
			)
			(layer "B.Fab")
		)
		(fp_line
			(start -1.1049 0.724916)
			(end -1.1049 -0.724916)
			(stroke
				(width 0.1)
				(type default)
			)
			(layer "B.Fab")
		)
		(pad "1" smd rect
			(at 0.889 0 90)
			(size 1.016 1.27)
			(layers "B.Cu" "B.Mask" "B.Paste")
			(net "SW_P12V_AUX_PVDDCR_CPU1_P0_FLT")
		)
		(pad "2" smd rect
			(at -0.889 0 90)
			(size 1.016 1.27)
			(layers "B.Cu" "B.Mask" "B.Paste")
			(net "GND")
		)
	)
	(footprint ""
		(layer "B.Cu")
		(at 305.423316 -426.466 180)
		(property "Reference" "R1445"
			(at 0 0 0)
			(layer "B.SilkS")
			(hide yes)
			(effects
				(font
					(size 1.27 1.27)
				)
				(justify mirror)
			)
		)
		(property "Value" ""
			(at 0 0 0)
			(layer "B.Fab")
			(effects
				(font
					(size 1.27 1.27)
				)
				(justify mirror)
			)
		)
		(duplicate_pad_numbers_are_jumpers no)
		(fp_line
			(start 0.32512 0.175006)
			(end 0.32512 -0.175006)
			(stroke
				(width 0.1)
				(type default)
			)
			(layer "B.Fab")
		)
		(fp_line
			(start 0.32512 -0.175006)
			(end -0.32512 -0.175006)
			(stroke
				(width 0.1)
				(type default)
			)
			(layer "B.Fab")
		)
		(fp_line
			(start -0.32512 0.175006)
			(end 0.32512 0.175006)
			(stroke
				(width 0.1)
				(type default)
			)
			(layer "B.Fab")
		)
		(fp_line
			(start -0.32512 -0.175006)
			(end -0.32512 0.175006)
			(stroke
				(width 0.1)
				(type default)
			)
			(layer "B.Fab")
		)
		(pad "1" smd rect
			(at 0.2667 0)
			(size 0.3048 0.381)
			(layers "B.Cu" "B.Mask" "B.Paste")
			(net "P1V8_CPU0_RT_1D")
		)
		(pad "2" smd rect
			(at -0.2667 0 180)
			(size 0.3048 0.381)
			(layers "B.Cu" "B.Mask" "B.Paste")
			(net "JTAG_TDO_RT_CPU0_P0")
		)
	)
	(footprint ""
		(layer "B.Cu")
		(at 171.196 -118.328948)
		(property "Reference" "R891"
			(at 0 0 0)
			(layer "B.SilkS")
			(hide yes)
			(effects
				(font
					(size 1.27 1.27)
				)
				(justify mirror)
			)
		)
		(property "Value" ""
			(at 0 0 0)
			(layer "B.Fab")
			(effects
				(font
					(size 1.27 1.27)
				)
				(justify mirror)
			)
		)
		(duplicate_pad_numbers_are_jumpers no)
		(fp_line
			(start -0.7874 -0.4064)
			(end -0.7874 0.4064)
			(stroke
				(width 0.1524)
				(type default)
			)
			(layer "B.SilkS")
		)
		(fp_line
			(start -0.7874 0.4064)
			(end 0.7874 0.4064)
			(stroke
				(width 0.1524)
				(type default)
			)
			(layer "B.SilkS")
		)
		(fp_line
			(start 0.7874 -0.4064)
			(end -0.7874 -0.4064)
			(stroke
				(width 0.1524)
				(type default)
			)
			(layer "B.SilkS")
		)
		(fp_line
			(start 0.7874 0.4064)
			(end 0.7874 -0.4064)
			(stroke
				(width 0.1524)
				(type default)
			)
			(layer "B.SilkS")
		)
		(fp_line
			(start -0.67945 -0.3048)
			(end -0.67945 0.3048)
			(stroke
				(width 0.1)
				(type default)
			)
			(layer "B.Fab")
		)
		(fp_line
			(start -0.67945 0.3048)
			(end -0.120396 0.3048)
			(stroke
				(width 0.1)
				(type default)
			)
			(layer "B.Fab")
		)
		(fp_line
			(start -0.12065 -0.3048)
			(end -0.67945 -0.3048)
			(stroke
				(width 0.1)
				(type default)
			)
			(layer "B.Fab")
		)
		(fp_line
			(start -0.12065 -0.2794)
			(end -0.12065 -0.3048)
			(stroke
				(width 0.1)
				(type default)
			)
			(layer "B.Fab")
		)
		(fp_line
			(start -0.120396 0.2794)
			(end 0.12065 0.2794)
			(stroke
				(width 0.1)
				(type default)
			)
			(layer "B.Fab")
		)
		(fp_line
			(start -0.120396 0.3048)
			(end -0.120396 0.2794)
			(stroke
				(width 0.1)
				(type default)
			)
			(layer "B.Fab")
		)
		(fp_line
			(start 0.12065 -0.305054)
			(end 0.12065 -0.2794)
			(stroke
				(width 0.1)
				(type default)
			)
			(layer "B.Fab")
		)
		(fp_line
			(start 0.12065 -0.2794)
			(end -0.12065 -0.2794)
			(stroke
				(width 0.1)
				(type default)
			)
			(layer "B.Fab")
		)
		(fp_line
			(start 0.12065 0.2794)
			(end 0.12065 0.3048)
			(stroke
				(width 0.1)
				(type default)
			)
			(layer "B.Fab")
		)
		(fp_line
			(start 0.12065 0.3048)
			(end 0.67945 0.3048)
			(stroke
				(width 0.1)
				(type default)
			)
			(layer "B.Fab")
		)
		(fp_line
			(start 0.67945 -0.305054)
			(end 0.12065 -0.305054)
			(stroke
				(width 0.1)
				(type default)
			)
			(layer "B.Fab")
		)
		(fp_line
			(start 0.67945 0.3048)
			(end 0.67945 -0.305054)
			(stroke
				(width 0.1)
				(type default)
			)
			(layer "B.Fab")
		)
		(pad "1" smd circle
			(at 0.40005 0 180)
			(size 0 0)
			(layers "B.Cu" "B.Mask" "B.Paste")
			(net "SCM_SPARE_1")
		)
		(pad "2" smd circle
			(at -0.40005 0 180)
			(size 0 0)
			(layers "B.Cu" "B.Mask" "B.Paste")
			(net "GND")
		)
	)
	(footprint ""
		(layer "B.Cu")
		(at 194.67957 -342.10244 -90)
		(property "Reference" "PC523_2"
			(at 0 0 90)
			(layer "B.SilkS")
			(hide yes)
			(effects
				(font
					(size 1.27 1.27)
				)
				(justify mirror)
			)
		)
		(property "Value" ""
			(at 0 0 90)
			(layer "B.Fab")
			(effects
				(font
					(size 1.27 1.27)
				)
				(justify mirror)
			)
		)
		(duplicate_pad_numbers_are_jumpers no)
		(fp_line
			(start -1.524 0.762)
			(end 1.524 0.762)
			(stroke
				(width 0.1524)
				(type default)
			)
			(layer "B.SilkS")
		)
		(fp_line
			(start 1.524 0.762)
			(end 1.524 -0.762)
			(stroke
				(width 0.1524)
				(type default)
			)
			(layer "B.SilkS")
		)
		(fp_line
			(start -1.524 -0.762)
			(end -1.524 0.762)
			(stroke
				(width 0.1524)
				(type default)
			)
			(layer "B.SilkS")
		)
		(fp_line
			(start 1.524 -0.762)
			(end -1.524 -0.762)
			(stroke
				(width 0.1524)
				(type default)
			)
			(layer "B.SilkS")
		)
		(fp_line
			(start -1.1049 0.724916)
			(end -1.1049 -0.724916)
			(stroke
				(width 0.1)
				(type default)
			)
			(layer "B.Fab")
		)
		(fp_line
			(start 1.1049 0.724916)
			(end -1.1049 0.724916)
			(stroke
				(width 0.1)
				(type default)
			)
			(layer "B.Fab")
		)
		(fp_line
			(start -1.1049 -0.724916)
			(end 1.1049 -0.724916)
			(stroke
				(width 0.1)
				(type default)
			)
			(layer "B.Fab")
		)
		(fp_line
			(start 1.1049 -0.724916)
			(end 1.1049 0.724916)
			(stroke
				(width 0.1)
				(type default)
			)
			(layer "B.Fab")
		)
		(pad "1" smd rect
			(at 0.889 0 270)
			(size 1.016 1.27)
			(layers "B.Cu" "B.Mask" "B.Paste")
			(net "PVDD11_S3_P1")
		)
		(pad "2" smd rect
			(at -0.889 0 270)
			(size 1.016 1.27)
			(layers "B.Cu" "B.Mask" "B.Paste")
			(net "GND")
		)
	)
	(footprint ""
		(layer "B.Cu")
		(at 105.695242 -412.03372 90)
		(property "Reference" "R2656"
			(at 0 0 90)
			(layer "B.SilkS")
			(hide yes)
			(effects
				(font
					(size 1.27 1.27)
				)
				(justify mirror)
			)
		)
		(property "Value" ""
			(at 0 0 90)
			(layer "B.Fab")
			(effects
				(font
					(size 1.27 1.27)
				)
				(justify mirror)
			)
		)
		(duplicate_pad_numbers_are_jumpers no)
		(fp_line
			(start 0.7874 -0.4064)
			(end -0.7874 -0.4064)
			(stroke
				(width 0.1524)
				(type default)
			)
			(layer "B.SilkS")
		)
		(fp_line
			(start -0.7874 -0.4064)
			(end -0.7874 0.4064)
			(stroke
				(width 0.1524)
				(type default)
			)
			(layer "B.SilkS")
		)
		(fp_line
			(start 0.7874 0.4064)
			(end 0.7874 -0.4064)
			(stroke
				(width 0.1524)
				(type default)
			)
			(layer "B.SilkS")
		)
		(fp_line
			(start -0.7874 0.4064)
			(end 0.7874 0.4064)
			(stroke
				(width 0.1524)
				(type default)
			)
			(layer "B.SilkS")
		)
		(fp_line
			(start 0.67945 -0.305054)
			(end 0.12065 -0.305054)
			(stroke
				(width 0.1)
				(type default)
			)
			(layer "B.Fab")
		)
		(fp_line
			(start 0.12065 -0.305054)
			(end 0.12065 -0.2794)
			(stroke
				(width 0.1)
				(type default)
			)
			(layer "B.Fab")
		)
		(fp_line
			(start -0.12065 -0.3048)
			(end -0.67945 -0.3048)
			(stroke
				(width 0.1)
				(type default)
			)
			(layer "B.Fab")
		)
		(fp_line
			(start -0.67945 -0.3048)
			(end -0.67945 0.3048)
			(stroke
				(width 0.1)
				(type default)
			)
			(layer "B.Fab")
		)
		(fp_line
			(start 0.12065 -0.2794)
			(end -0.12065 -0.2794)
			(stroke
				(width 0.1)
				(type default)
			)
			(layer "B.Fab")
		)
		(fp_line
			(start -0.12065 -0.2794)
			(end -0.12065 -0.3048)
			(stroke
				(width 0.1)
				(type default)
			)
			(layer "B.Fab")
		)
		(fp_line
			(start 0.12065 0.2794)
			(end 0.12065 0.3048)
			(stroke
				(width 0.1)
				(type default)
			)
			(layer "B.Fab")
		)
		(fp_line
			(start -0.120396 0.2794)
			(end 0.12065 0.2794)
			(stroke
				(width 0.1)
				(type default)
			)
			(layer "B.Fab")
		)
		(fp_line
			(start 0.67945 0.3048)
			(end 0.67945 -0.305054)
			(stroke
				(width 0.1)
				(type default)
			)
			(layer "B.Fab")
		)
		(fp_line
			(start 0.12065 0.3048)
			(end 0.67945 0.3048)
			(stroke
				(width 0.1)
				(type default)
			)
			(layer "B.Fab")
		)
		(fp_line
			(start -0.120396 0.3048)
			(end -0.120396 0.2794)
			(stroke
				(width 0.1)
				(type default)
			)
			(layer "B.Fab")
		)
		(fp_line
			(start -0.67945 0.3048)
			(end -0.120396 0.3048)
			(stroke
				(width 0.1)
				(type default)
			)
			(layer "B.Fab")
		)
		(pad "1" smd circle
			(at 0.40005 0 270)
			(size 0 0)
			(layers "B.Cu" "B.Mask" "B.Paste")
			(net "HGX_DETECT_N_ISO")
		)
		(pad "2" smd circle
			(at -0.40005 0 270)
			(size 0 0)
			(layers "B.Cu" "B.Mask" "B.Paste")
			(net "GND")
		)
	)
	(footprint ""
		(layer "B.Cu")
		(at 193.171318 -140.432536 90)
		(property "Reference" "R633"
			(at 0 0 90)
			(layer "B.SilkS")
			(hide yes)
			(effects
				(font
					(size 1.27 1.27)
				)
				(justify mirror)
			)
		)
		(property "Value" ""
			(at 0 0 90)
			(layer "B.Fab")
			(effects
				(font
					(size 1.27 1.27)
				)
				(justify mirror)
			)
		)
		(duplicate_pad_numbers_are_jumpers no)
		(fp_line
			(start 0.7874 -0.4064)
			(end -0.7874 -0.4064)
			(stroke
				(width 0.1524)
				(type default)
			)
			(layer "B.SilkS")
		)
		(fp_line
			(start -0.7874 -0.4064)
			(end -0.7874 0.4064)
			(stroke
				(width 0.1524)
				(type default)
			)
			(layer "B.SilkS")
		)
		(fp_line
			(start 0.7874 0.4064)
			(end 0.7874 -0.4064)
			(stroke
				(width 0.1524)
				(type default)
			)
			(layer "B.SilkS")
		)
		(fp_line
			(start -0.7874 0.4064)
			(end 0.7874 0.4064)
			(stroke
				(width 0.1524)
				(type default)
			)
			(layer "B.SilkS")
		)
		(fp_line
			(start 0.67945 -0.305054)
			(end 0.12065 -0.305054)
			(stroke
				(width 0.1)
				(type default)
			)
			(layer "B.Fab")
		)
		(fp_line
			(start 0.12065 -0.305054)
			(end 0.12065 -0.2794)
			(stroke
				(width 0.1)
				(type default)
			)
			(layer "B.Fab")
		)
		(fp_line
			(start -0.12065 -0.3048)
			(end -0.67945 -0.3048)
			(stroke
				(width 0.1)
				(type default)
			)
			(layer "B.Fab")
		)
		(fp_line
			(start -0.67945 -0.3048)
			(end -0.67945 0.3048)
			(stroke
				(width 0.1)
				(type default)
			)
			(layer "B.Fab")
		)
		(fp_line
			(start 0.12065 -0.2794)
			(end -0.12065 -0.2794)
			(stroke
				(width 0.1)
				(type default)
			)
			(layer "B.Fab")
		)
		(fp_line
			(start -0.12065 -0.2794)
			(end -0.12065 -0.3048)
			(stroke
				(width 0.1)
				(type default)
			)
			(layer "B.Fab")
		)
		(fp_line
			(start 0.12065 0.2794)
			(end 0.12065 0.3048)
			(stroke
				(width 0.1)
				(type default)
			)
			(layer "B.Fab")
		)
		(fp_line
			(start -0.120396 0.2794)
			(end 0.12065 0.2794)
			(stroke
				(width 0.1)
				(type default)
			)
			(layer "B.Fab")
		)
		(fp_line
			(start 0.67945 0.3048)
			(end 0.67945 -0.305054)
			(stroke
				(width 0.1)
				(type default)
			)
			(layer "B.Fab")
		)
		(fp_line
			(start 0.12065 0.3048)
			(end 0.67945 0.3048)
			(stroke
				(width 0.1)
				(type default)
			)
			(layer "B.Fab")
		)
		(fp_line
			(start -0.120396 0.3048)
			(end -0.120396 0.2794)
			(stroke
				(width 0.1)
				(type default)
			)
			(layer "B.Fab")
		)
		(fp_line
			(start -0.67945 0.3048)
			(end -0.120396 0.3048)
			(stroke
				(width 0.1)
				(type default)
			)
			(layer "B.Fab")
		)
		(pad "1" smd circle
			(at 0.40005 0 270)
			(size 0 0)
			(layers "B.Cu" "B.Mask" "B.Paste")
			(net "PVDD18_S5_P0")
		)
		(pad "2" smd circle
			(at -0.40005 0 270)
			(size 0 0)
			(layers "B.Cu" "B.Mask" "B.Paste")
			(net "SMB_CPU_5_SDA")
		)
	)
	(footprint ""
		(layer "B.Cu")
		(at 43.247564 -337.989672 -90)
		(property "Reference" "PC458_2"
			(at 0 0 90)
			(layer "B.SilkS")
			(hide yes)
			(effects
				(font
					(size 1.27 1.27)
				)
				(justify mirror)
			)
		)
		(property "Value" ""
			(at 0 0 90)
			(layer "B.Fab")
			(effects
				(font
					(size 1.27 1.27)
				)
				(justify mirror)
			)
		)
		(duplicate_pad_numbers_are_jumpers no)
		(fp_line
			(start -1.524 0.762)
			(end 1.524 0.762)
			(stroke
				(width 0.1524)
				(type default)
			)
			(layer "B.SilkS")
		)
		(fp_line
			(start 1.524 0.762)
			(end 1.524 -0.762)
			(stroke
				(width 0.1524)
				(type default)
			)
			(layer "B.SilkS")
		)
		(fp_line
			(start -1.524 -0.762)
			(end -1.524 0.762)
			(stroke
				(width 0.1524)
				(type default)
			)
			(layer "B.SilkS")
		)
		(fp_line
			(start 1.524 -0.762)
			(end -1.524 -0.762)
			(stroke
				(width 0.1524)
				(type default)
			)
			(layer "B.SilkS")
		)
		(fp_line
			(start -1.1049 0.724916)
			(end -1.1049 -0.724916)
			(stroke
				(width 0.1)
				(type default)
			)
			(layer "B.Fab")
		)
		(fp_line
			(start 1.1049 0.724916)
			(end -1.1049 0.724916)
			(stroke
				(width 0.1)
				(type default)
			)
			(layer "B.Fab")
		)
		(fp_line
			(start -1.1049 -0.724916)
			(end 1.1049 -0.724916)
			(stroke
				(width 0.1)
				(type default)
			)
			(layer "B.Fab")
		)
		(fp_line
			(start 1.1049 -0.724916)
			(end 1.1049 0.724916)
			(stroke
				(width 0.1)
				(type default)
			)
			(layer "B.Fab")
		)
		(pad "1" smd rect
			(at 0.889 0 270)
			(size 1.016 1.27)
			(layers "B.Cu" "B.Mask" "B.Paste")
			(net "PVDDIO_P1")
		)
		(pad "2" smd rect
			(at -0.889 0 270)
			(size 1.016 1.27)
			(layers "B.Cu" "B.Mask" "B.Paste")
			(net "GND")
		)
	)
	(footprint ""
		(layer "B.Cu")
		(at 14.097762 -192.362328 -90)
		(property "Reference" "R108"
			(at 0 0 90)
			(layer "B.SilkS")
			(hide yes)
			(effects
				(font
					(size 1.27 1.27)
				)
				(justify mirror)
			)
		)
		(property "Value" ""
			(at 0 0 90)
			(layer "B.Fab")
			(effects
				(font
					(size 1.27 1.27)
				)
				(justify mirror)
			)
		)
		(duplicate_pad_numbers_are_jumpers no)
		(fp_line
			(start -0.7874 0.4064)
			(end 0.7874 0.4064)
			(stroke
				(width 0.1524)
				(type default)
			)
			(layer "B.SilkS")
		)
		(fp_line
			(start 0.7874 0.4064)
			(end 0.7874 -0.4064)
			(stroke
				(width 0.1524)
				(type default)
			)
			(layer "B.SilkS")
		)
		(fp_line
			(start -0.7874 -0.4064)
			(end -0.7874 0.4064)
			(stroke
				(width 0.1524)
				(type default)
			)
			(layer "B.SilkS")
		)
		(fp_line
			(start 0.7874 -0.4064)
			(end -0.7874 -0.4064)
			(stroke
				(width 0.1524)
				(type default)
			)
			(layer "B.SilkS")
		)
		(fp_line
			(start -0.67945 0.3048)
			(end -0.120396 0.3048)
			(stroke
				(width 0.1)
				(type default)
			)
			(layer "B.Fab")
		)
		(fp_line
			(start -0.120396 0.3048)
			(end -0.120396 0.2794)
			(stroke
				(width 0.1)
				(type default)
			)
			(layer "B.Fab")
		)
		(fp_line
			(start 0.12065 0.3048)
			(end 0.67945 0.3048)
			(stroke
				(width 0.1)
				(type default)
			)
			(layer "B.Fab")
		)
		(fp_line
			(start 0.67945 0.3048)
			(end 0.67945 -0.305054)
			(stroke
				(width 0.1)
				(type default)
			)
			(layer "B.Fab")
		)
		(fp_line
			(start -0.120396 0.2794)
			(end 0.12065 0.2794)
			(stroke
				(width 0.1)
				(type default)
			)
			(layer "B.Fab")
		)
		(fp_line
			(start 0.12065 0.2794)
			(end 0.12065 0.3048)
			(stroke
				(width 0.1)
				(type default)
			)
			(layer "B.Fab")
		)
		(fp_line
			(start -0.12065 -0.2794)
			(end -0.12065 -0.3048)
			(stroke
				(width 0.1)
				(type default)
			)
			(layer "B.Fab")
		)
		(fp_line
			(start 0.12065 -0.2794)
			(end -0.12065 -0.2794)
			(stroke
				(width 0.1)
				(type default)
			)
			(layer "B.Fab")
		)
		(fp_line
			(start -0.67945 -0.3048)
			(end -0.67945 0.3048)
			(stroke
				(width 0.1)
				(type default)
			)
			(layer "B.Fab")
		)
		(fp_line
			(start -0.12065 -0.3048)
			(end -0.67945 -0.3048)
			(stroke
				(width 0.1)
				(type default)
			)
			(layer "B.Fab")
		)
		(fp_line
			(start 0.12065 -0.305054)
			(end 0.12065 -0.2794)
			(stroke
				(width 0.1)
				(type default)
			)
			(layer "B.Fab")
		)
		(fp_line
			(start 0.67945 -0.305054)
			(end 0.12065 -0.305054)
			(stroke
				(width 0.1)
				(type default)
			)
			(layer "B.Fab")
		)
		(pad "1" smd circle
			(at 0.40005 0 90)
			(size 0 0)
			(layers "B.Cu" "B.Mask" "B.Paste")
			(net "P3V3")
		)
		(pad "2" smd circle
			(at -0.40005 0 90)
			(size 0 0)
			(layers "B.Cu" "B.Mask" "B.Paste")
			(net "PWRGD_CHF_CPU1_DIMM")
		)
	)
	(footprint ""
		(layer "B.Cu")
		(at 517.258808 -142.892526 -90)
		(property "Reference" "X8011"
			(at 4.4577 -1.50495 270)
			(unlocked yes)
			(layer "B.SilkS")
			(effects
				(font
					(size 0.7874 0.5842)
					(thickness 0.1524)
				)
				(justify left mirror)
			)
		)
		(property "Value" ""
			(at 0 0 90)
			(layer "B.Fab")
			(effects
				(font
					(size 1.27 1.27)
				)
				(justify mirror)
			)
		)
		(property "Device Type" "TP_TDR_4P_FTS_TH-TP_TDR_4P_DIP,EMPTY,TP15"
			(at -1.30175 1.27 180)
			(unlocked yes)
			(layer "B.Fab")
			(hide yes)
			(effects
				(font
					(size 0.635 0.4064)
					(thickness 0.1524)
				)
				(justify mirror)
			)
		)
		(property "User Part Number" "N_A"
			(at -1.30175 1.27 180)
			(unlocked yes)
			(layer "Cmts.User")
			(hide yes)
			(effects
				(font
					(size 0.635 0.4064)
					(thickness 0.1524)
				)
				(justify mirror)
			)
		)
		(duplicate_pad_numbers_are_jumpers no)
		(fp_line
			(start -2.54 3.81)
			(end -2.54 3.6703)
			(stroke
				(width 0.1524)
				(type default)
			)
			(layer "B.SilkS")
		)
		(fp_line
			(start 0 3.81)
			(end -2.54 3.81)
			(stroke
				(width 0.1524)
				(type default)
			)
			(layer "B.SilkS")
		)
		(fp_line
			(start 0 3.175)
			(end 0 3.81)
			(stroke
				(width 0.1524)
				(type default)
			)
			(layer "B.SilkS")
		)
		(fp_line
			(start -2.54 1.4097)
			(end -2.54 1.1303)
			(stroke
				(width 0.1524)
				(type default)
			)
			(layer "B.SilkS")
		)
		(fp_line
			(start 0 0.635)
			(end 0 1.905)
			(stroke
				(width 0.1524)
				(type default)
			)
			(layer "B.SilkS")
		)
		(fp_line
			(start -2.54 -1.1303)
			(end -2.54 -1.27)
			(stroke
				(width 0.1524)
				(type default)
			)
			(layer "B.SilkS")
		)
		(fp_line
			(start -2.54 -1.27)
			(end 0 -1.27)
			(stroke
				(width 0.1524)
				(type default)
			)
			(layer "B.SilkS")
		)
		(fp_line
			(start 0 -1.27)
			(end 0 -0.635)
			(stroke
				(width 0.1524)
				(type default)
			)
			(layer "B.SilkS")
		)
		(fp_poly
			(pts
				(xy 0.761746 0) (xy 2.285746 -0.762) (xy 2.285746 0.762)
			)
			(stroke
				(width 0)
				(type default)
			)
			(fill yes)
			(layer "B.SilkS")
		)
		(fp_line
			(start -2.54 3.81)
			(end -2.54 -1.27)
			(stroke
				(width 0.1)
				(type default)
			)
			(layer "B.Fab")
		)
		(fp_line
			(start 0 3.81)
			(end -2.54 3.81)
			(stroke
				(width 0.1)
				(type default)
			)
			(layer "B.Fab")
		)
		(fp_line
			(start -2.54 -1.27)
			(end 0 -1.27)
			(stroke
				(width 0.1)
				(type default)
			)
			(layer "B.Fab")
		)
		(fp_line
			(start 0 -1.27)
			(end 0 3.81)
			(stroke
				(width 0.1)
				(type default)
			)
			(layer "B.Fab")
		)
		(fp_poly
			(pts
				(xy 0.761746 0) (xy 2.285746 -0.762) (xy 2.285746 0.762)
			)
			(stroke
				(width 0)
				(type default)
			)
			(fill yes)
			(layer "B.Fab")
		)
		(pad "1" thru_hole circle
			(at 0 0 90)
			(size 1.0033 1.0033)
			(drill 0.249936)
			(layers "*.Cu" "*.Mask")
			(remove_unused_layers no)
			(net "TDR_DIFF_85_IN4_DN")
			(clearance 0.10795)
			(padstack
				(mode front_inner_back)
				(layer "Inner"
					(shape circle)
					(size 0.8001 0.8001)
					(clearance 0.1524)
				)
				(layer "B.Cu"
					(shape circle)
					(size 1.0033 1.0033)
					(thermal_gap 0.10795)
					(clearance 0.10795)
				)
			)
		)
		(pad "2" thru_hole circle
			(at -2.54 0 90)
			(size 1.9939 1.9939)
			(drill 0.249936)
			(layers "*.Cu" "*.Mask")
			(remove_unused_layers no)
			(net "T1_GND")
			(clearance 0.10795)
			(padstack
				(mode front_inner_back)
				(layer "Inner"
					(shape circle)
					(size 0.8001 0.8001)
					(clearance 0.1524)
				)
				(layer "B.Cu"
					(shape circle)
					(size 1.9939 1.9939)
					(thermal_gap 0.10795)
					(clearance 0.10795)
				)
			)
		)
		(pad "3" thru_hole circle
			(at -2.54 2.54 90)
			(size 1.9939 1.9939)
			(drill 0.249936)
			(layers "*.Cu" "*.Mask")
			(remove_unused_layers no)
			(net "T1_GND")
			(clearance 0.10795)
			(padstack
				(mode front_inner_back)
				(layer "Inner"
					(shape circle)
					(size 0.8001 0.8001)
					(clearance 0.1524)
				)
				(layer "B.Cu"
					(shape circle)
					(size 1.9939 1.9939)
					(thermal_gap 0.10795)
					(clearance 0.10795)
				)
			)
		)
		(pad "4" thru_hole circle
			(at 0 2.54 90)
			(size 1.0033 1.0033)
			(drill 0.249936)
			(layers "*.Cu" "*.Mask")
			(remove_unused_layers no)
			(net "TDR_DIFF_85_IN4_DP")
			(clearance 0.10795)
			(padstack
				(mode front_inner_back)
				(layer "Inner"
					(shape circle)
					(size 0.8001 0.8001)
					(clearance 0.1524)
				)
				(layer "B.Cu"
					(shape circle)
					(size 1.0033 1.0033)
					(thermal_gap 0.10795)
					(clearance 0.10795)
				)
			)
		)
	)
	(footprint ""
		(layer "B.Cu")
		(at 171.196 -112.232948)
		(property "Reference" "R166"
			(at 0 0 0)
			(layer "B.SilkS")
			(hide yes)
			(effects
				(font
					(size 1.27 1.27)
				)
				(justify mirror)
			)
		)
		(property "Value" ""
			(at 0 0 0)
			(layer "B.Fab")
			(effects
				(font
					(size 1.27 1.27)
				)
				(justify mirror)
			)
		)
		(duplicate_pad_numbers_are_jumpers no)
		(fp_line
			(start -0.7874 -0.4064)
			(end -0.7874 0.4064)
			(stroke
				(width 0.1524)
				(type default)
			)
			(layer "B.SilkS")
		)
		(fp_line
			(start -0.7874 0.4064)
			(end 0.7874 0.4064)
			(stroke
				(width 0.1524)
				(type default)
			)
			(layer "B.SilkS")
		)
		(fp_line
			(start 0.7874 -0.4064)
			(end -0.7874 -0.4064)
			(stroke
				(width 0.1524)
				(type default)
			)
			(layer "B.SilkS")
		)
		(fp_line
			(start 0.7874 0.4064)
			(end 0.7874 -0.4064)
			(stroke
				(width 0.1524)
				(type default)
			)
			(layer "B.SilkS")
		)
		(fp_line
			(start -0.67945 -0.3048)
			(end -0.67945 0.3048)
			(stroke
				(width 0.1)
				(type default)
			)
			(layer "B.Fab")
		)
		(fp_line
			(start -0.67945 0.3048)
			(end -0.120396 0.3048)
			(stroke
				(width 0.1)
				(type default)
			)
			(layer "B.Fab")
		)
		(fp_line
			(start -0.12065 -0.3048)
			(end -0.67945 -0.3048)
			(stroke
				(width 0.1)
				(type default)
			)
			(layer "B.Fab")
		)
		(fp_line
			(start -0.12065 -0.2794)
			(end -0.12065 -0.3048)
			(stroke
				(width 0.1)
				(type default)
			)
			(layer "B.Fab")
		)
		(fp_line
			(start -0.120396 0.2794)
			(end 0.12065 0.2794)
			(stroke
				(width 0.1)
				(type default)
			)
			(layer "B.Fab")
		)
		(fp_line
			(start -0.120396 0.3048)
			(end -0.120396 0.2794)
			(stroke
				(width 0.1)
				(type default)
			)
			(layer "B.Fab")
		)
		(fp_line
			(start 0.12065 -0.305054)
			(end 0.12065 -0.2794)
			(stroke
				(width 0.1)
				(type default)
			)
			(layer "B.Fab")
		)
		(fp_line
			(start 0.12065 -0.2794)
			(end -0.12065 -0.2794)
			(stroke
				(width 0.1)
				(type default)
			)
			(layer "B.Fab")
		)
		(fp_line
			(start 0.12065 0.2794)
			(end 0.12065 0.3048)
			(stroke
				(width 0.1)
				(type default)
			)
			(layer "B.Fab")
		)
		(fp_line
			(start 0.12065 0.3048)
			(end 0.67945 0.3048)
			(stroke
				(width 0.1)
				(type default)
			)
			(layer "B.Fab")
		)
		(fp_line
			(start 0.67945 -0.305054)
			(end 0.12065 -0.305054)
			(stroke
				(width 0.1)
				(type default)
			)
			(layer "B.Fab")
		)
		(fp_line
			(start 0.67945 0.3048)
			(end 0.67945 -0.305054)
			(stroke
				(width 0.1)
				(type default)
			)
			(layer "B.Fab")
		)
		(pad "1" smd circle
			(at 0.40005 0 180)
			(size 0 0)
			(layers "B.Cu" "B.Mask" "B.Paste")
			(net "FM_I3C_CPU0_MUX1_R_SEL")
		)
		(pad "2" smd circle
			(at -0.40005 0 180)
			(size 0 0)
			(layers "B.Cu" "B.Mask" "B.Paste")
			(net "FM_I3C_CPU0_MUX1_SEL")
		)
	)
	(footprint ""
		(layer "B.Cu")
		(at 53.151532 -421.180768)
		(property "Reference" "R3321"
			(at 0 0 0)
			(layer "B.SilkS")
			(hide yes)
			(effects
				(font
					(size 1.27 1.27)
				)
				(justify mirror)
			)
		)
		(property "Value" ""
			(at 0 0 0)
			(layer "B.Fab")
			(effects
				(font
					(size 1.27 1.27)
				)
				(justify mirror)
			)
		)
		(duplicate_pad_numbers_are_jumpers no)
		(fp_line
			(start -0.7874 -0.4064)
			(end -0.7874 0.4064)
			(stroke
				(width 0.1524)
				(type default)
			)
			(layer "B.SilkS")
		)
		(fp_line
			(start -0.7874 0.4064)
			(end 0.7874 0.4064)
			(stroke
				(width 0.1524)
				(type default)
			)
			(layer "B.SilkS")
		)
		(fp_line
			(start 0.7874 -0.4064)
			(end -0.7874 -0.4064)
			(stroke
				(width 0.1524)
				(type default)
			)
			(layer "B.SilkS")
		)
		(fp_line
			(start 0.7874 0.4064)
			(end 0.7874 -0.4064)
			(stroke
				(width 0.1524)
				(type default)
			)
			(layer "B.SilkS")
		)
		(fp_line
			(start -0.67945 -0.3048)
			(end -0.67945 0.3048)
			(stroke
				(width 0.1)
				(type default)
			)
			(layer "B.Fab")
		)
		(fp_line
			(start -0.67945 0.3048)
			(end -0.120396 0.3048)
			(stroke
				(width 0.1)
				(type default)
			)
			(layer "B.Fab")
		)
		(fp_line
			(start -0.12065 -0.3048)
			(end -0.67945 -0.3048)
			(stroke
				(width 0.1)
				(type default)
			)
			(layer "B.Fab")
		)
		(fp_line
			(start -0.12065 -0.2794)
			(end -0.12065 -0.3048)
			(stroke
				(width 0.1)
				(type default)
			)
			(layer "B.Fab")
		)
		(fp_line
			(start -0.120396 0.2794)
			(end 0.12065 0.2794)
			(stroke
				(width 0.1)
				(type default)
			)
			(layer "B.Fab")
		)
		(fp_line
			(start -0.120396 0.3048)
			(end -0.120396 0.2794)
			(stroke
				(width 0.1)
				(type default)
			)
			(layer "B.Fab")
		)
		(fp_line
			(start 0.12065 -0.305054)
			(end 0.12065 -0.2794)
			(stroke
				(width 0.1)
				(type default)
			)
			(layer "B.Fab")
		)
		(fp_line
			(start 0.12065 -0.2794)
			(end -0.12065 -0.2794)
			(stroke
				(width 0.1)
				(type default)
			)
			(layer "B.Fab")
		)
		(fp_line
			(start 0.12065 0.2794)
			(end 0.12065 0.3048)
			(stroke
				(width 0.1)
				(type default)
			)
			(layer "B.Fab")
		)
		(fp_line
			(start 0.12065 0.3048)
			(end 0.67945 0.3048)
			(stroke
				(width 0.1)
				(type default)
			)
			(layer "B.Fab")
		)
		(fp_line
			(start 0.67945 -0.305054)
			(end 0.12065 -0.305054)
			(stroke
				(width 0.1)
				(type default)
			)
			(layer "B.Fab")
		)
		(fp_line
			(start 0.67945 0.3048)
			(end 0.67945 -0.305054)
			(stroke
				(width 0.1)
				(type default)
			)
			(layer "B.Fab")
		)
		(pad "1" smd circle
			(at 0.40005 0 180)
			(size 0 0)
			(layers "B.Cu" "B.Mask" "B.Paste")
			(net "P3V3_AUX")
		)
		(pad "2" smd circle
			(at -0.40005 0 180)
			(size 0 0)
			(layers "B.Cu" "B.Mask" "B.Paste")
			(net "GPU_FPGA_READY_ISO")
		)
	)
	(footprint ""
		(layer "B.Cu")
		(at 120.47855 -386.766562 90)
		(property "Reference" "C449"
			(at 0 0 90)
			(layer "B.SilkS")
			(hide yes)
			(effects
				(font
					(size 1.27 1.27)
				)
				(justify mirror)
			)
		)
		(property "Value" ""
			(at 0 0 90)
			(layer "B.Fab")
			(effects
				(font
					(size 1.27 1.27)
				)
				(justify mirror)
			)
		)
		(duplicate_pad_numbers_are_jumpers no)
		(fp_line
			(start 0.299974 -0.150114)
			(end -0.299974 -0.150114)
			(stroke
				(width 0.1)
				(type default)
			)
			(layer "B.Fab")
		)
		(fp_line
			(start -0.299974 -0.150114)
			(end -0.299974 0.150114)
			(stroke
				(width 0.1)
				(type default)
			)
			(layer "B.Fab")
		)
		(fp_line
			(start 0.299974 0.150114)
			(end 0.299974 -0.150114)
			(stroke
				(width 0.1)
				(type default)
			)
			(layer "B.Fab")
		)
		(fp_line
			(start -0.299974 0.150114)
			(end 0.299974 0.150114)
			(stroke
				(width 0.1)
				(type default)
			)
			(layer "B.Fab")
		)
		(pad "1" smd rect
			(at 0.2667 0 270)
			(size 0.3048 0.381)
			(layers "B.Cu" "B.Mask" "B.Paste")
			(net "P0V9_CPU1_RT_2D")
		)
		(pad "2" smd rect
			(at -0.2667 0 270)
			(size 0.3048 0.381)
			(layers "B.Cu" "B.Mask" "B.Paste")
			(net "GND")
		)
	)
	(footprint ""
		(layer "B.Cu")
		(at 245.7704 -331.2668 180)
		(property "Reference" "R1515"
			(at 0 0 0)
			(layer "B.SilkS")
			(hide yes)
			(effects
				(font
					(size 1.27 1.27)
				)
				(justify mirror)
			)
		)
		(property "Value" ""
			(at 0 0 0)
			(layer "B.Fab")
			(effects
				(font
					(size 1.27 1.27)
				)
				(justify mirror)
			)
		)
		(duplicate_pad_numbers_are_jumpers no)
		(fp_line
			(start 0.32512 0.175006)
			(end 0.32512 -0.175006)
			(stroke
				(width 0.1)
				(type default)
			)
			(layer "B.Fab")
		)
		(fp_line
			(start 0.32512 -0.175006)
			(end -0.32512 -0.175006)
			(stroke
				(width 0.1)
				(type default)
			)
			(layer "B.Fab")
		)
		(fp_line
			(start -0.32512 0.175006)
			(end 0.32512 0.175006)
			(stroke
				(width 0.1)
				(type default)
			)
			(layer "B.Fab")
		)
		(fp_line
			(start -0.32512 -0.175006)
			(end -0.32512 0.175006)
			(stroke
				(width 0.1)
				(type default)
			)
			(layer "B.Fab")
		)
		(pad "1" smd rect
			(at 0.2667 0)
			(size 0.3048 0.381)
			(layers "B.Cu" "B.Mask" "B.Paste")
			(net "SMB_MUX_RT_R1_SDA")
		)
		(pad "2" smd rect
			(at -0.2667 0 180)
			(size 0.3048 0.381)
			(layers "B.Cu" "B.Mask" "B.Paste")
			(net "SMB_MUX_RT_R2_SDA")
		)
	)
	(footprint ""
		(layer "B.Cu")
		(at 34.544 -362.966)
		(property "Reference" "PR231"
			(at 0 0 0)
			(layer "B.SilkS")
			(hide yes)
			(effects
				(font
					(size 1.27 1.27)
				)
				(justify mirror)
			)
		)
		(property "Value" ""
			(at 0 0 0)
			(layer "B.Fab")
			(effects
				(font
					(size 1.27 1.27)
				)
				(justify mirror)
			)
		)
		(duplicate_pad_numbers_are_jumpers no)
		(fp_line
			(start -0.7874 -0.4064)
			(end -0.7874 0.4064)
			(stroke
				(width 0.1524)
				(type default)
			)
			(layer "B.SilkS")
		)
		(fp_line
			(start -0.7874 0.4064)
			(end 0.7874 0.4064)
			(stroke
				(width 0.1524)
				(type default)
			)
			(layer "B.SilkS")
		)
		(fp_line
			(start 0.7874 -0.4064)
			(end -0.7874 -0.4064)
			(stroke
				(width 0.1524)
				(type default)
			)
			(layer "B.SilkS")
		)
		(fp_line
			(start 0.7874 0.4064)
			(end 0.7874 -0.4064)
			(stroke
				(width 0.1524)
				(type default)
			)
			(layer "B.SilkS")
		)
		(fp_line
			(start -0.67945 -0.3048)
			(end -0.67945 0.3048)
			(stroke
				(width 0.1)
				(type default)
			)
			(layer "B.Fab")
		)
		(fp_line
			(start -0.67945 0.3048)
			(end -0.120396 0.3048)
			(stroke
				(width 0.1)
				(type default)
			)
			(layer "B.Fab")
		)
		(fp_line
			(start -0.12065 -0.3048)
			(end -0.67945 -0.3048)
			(stroke
				(width 0.1)
				(type default)
			)
			(layer "B.Fab")
		)
		(fp_line
			(start -0.12065 -0.2794)
			(end -0.12065 -0.3048)
			(stroke
				(width 0.1)
				(type default)
			)
			(layer "B.Fab")
		)
		(fp_line
			(start -0.120396 0.2794)
			(end 0.12065 0.2794)
			(stroke
				(width 0.1)
				(type default)
			)
			(layer "B.Fab")
		)
		(fp_line
			(start -0.120396 0.3048)
			(end -0.120396 0.2794)
			(stroke
				(width 0.1)
				(type default)
			)
			(layer "B.Fab")
		)
		(fp_line
			(start 0.12065 -0.305054)
			(end 0.12065 -0.2794)
			(stroke
				(width 0.1)
				(type default)
			)
			(layer "B.Fab")
		)
		(fp_line
			(start 0.12065 -0.2794)
			(end -0.12065 -0.2794)
			(stroke
				(width 0.1)
				(type default)
			)
			(layer "B.Fab")
		)
		(fp_line
			(start 0.12065 0.2794)
			(end 0.12065 0.3048)
			(stroke
				(width 0.1)
				(type default)
			)
			(layer "B.Fab")
		)
		(fp_line
			(start 0.12065 0.3048)
			(end 0.67945 0.3048)
			(stroke
				(width 0.1)
				(type default)
			)
			(layer "B.Fab")
		)
		(fp_line
			(start 0.67945 -0.305054)
			(end 0.12065 -0.305054)
			(stroke
				(width 0.1)
				(type default)
			)
			(layer "B.Fab")
		)
		(fp_line
			(start 0.67945 0.3048)
			(end 0.67945 -0.305054)
			(stroke
				(width 0.1)
				(type default)
			)
			(layer "B.Fab")
		)
		(pad "1" smd circle
			(at 0.40005 0 180)
			(size 0 0)
			(layers "B.Cu" "B.Mask" "B.Paste")
			(net "PVDDCR_CPU1_P1_VMON")
		)
		(pad "2" smd circle
			(at -0.40005 0 180)
			(size 0 0)
			(layers "B.Cu" "B.Mask" "B.Paste")
			(net "GND")
		)
	)
	(footprint ""
		(layer "B.Cu")
		(at 369.425474 -182.676038 -90)
		(property "Reference" "PC486_2"
			(at 0 0 90)
			(layer "B.SilkS")
			(hide yes)
			(effects
				(font
					(size 1.27 1.27)
				)
				(justify mirror)
			)
		)
		(property "Value" ""
			(at 0 0 90)
			(layer "B.Fab")
			(effects
				(font
					(size 1.27 1.27)
				)
				(justify mirror)
			)
		)
		(duplicate_pad_numbers_are_jumpers no)
		(fp_line
			(start -1.524 0.762)
			(end 1.524 0.762)
			(stroke
				(width 0.1524)
				(type default)
			)
			(layer "B.SilkS")
		)
		(fp_line
			(start 1.524 0.762)
			(end 1.524 -0.762)
			(stroke
				(width 0.1524)
				(type default)
			)
			(layer "B.SilkS")
		)
		(fp_line
			(start -1.524 -0.762)
			(end -1.524 0.762)
			(stroke
				(width 0.1524)
				(type default)
			)
			(layer "B.SilkS")
		)
		(fp_line
			(start 1.524 -0.762)
			(end -1.524 -0.762)
			(stroke
				(width 0.1524)
				(type default)
			)
			(layer "B.SilkS")
		)
		(fp_line
			(start -1.1049 0.724916)
			(end -1.1049 -0.724916)
			(stroke
				(width 0.1)
				(type default)
			)
			(layer "B.Fab")
		)
		(fp_line
			(start 1.1049 0.724916)
			(end -1.1049 0.724916)
			(stroke
				(width 0.1)
				(type default)
			)
			(layer "B.Fab")
		)
		(fp_line
			(start -1.1049 -0.724916)
			(end 1.1049 -0.724916)
			(stroke
				(width 0.1)
				(type default)
			)
			(layer "B.Fab")
		)
		(fp_line
			(start 1.1049 -0.724916)
			(end 1.1049 0.724916)
			(stroke
				(width 0.1)
				(type default)
			)
			(layer "B.Fab")
		)
		(pad "1" smd rect
			(at 0.889 0 270)
			(size 1.016 1.27)
			(layers "B.Cu" "B.Mask" "B.Paste")
			(net "SW_P12V_AUX_PVDDCR_CPU0_P0_FLT")
		)
		(pad "2" smd rect
			(at -0.889 0 270)
			(size 1.016 1.27)
			(layers "B.Cu" "B.Mask" "B.Paste")
			(net "GND")
		)
	)
	(footprint ""
		(layer "B.Cu")
		(at 283.645356 -418.976302 180)
		(property "Reference" "C78"
			(at 0 0 0)
			(layer "B.SilkS")
			(hide yes)
			(effects
				(font
					(size 1.27 1.27)
				)
				(justify mirror)
			)
		)
		(property "Value" ""
			(at 0 0 0)
			(layer "B.Fab")
			(effects
				(font
					(size 1.27 1.27)
				)
				(justify mirror)
			)
		)
		(duplicate_pad_numbers_are_jumpers no)
		(fp_line
			(start 0.7874 0.4064)
			(end 0.7874 -0.4064)
			(stroke
				(width 0.1524)
				(type default)
			)
			(layer "B.SilkS")
		)
		(fp_line
			(start 0.7874 -0.4064)
			(end -0.7874 -0.4064)
			(stroke
				(width 0.1524)
				(type default)
			)
			(layer "B.SilkS")
		)
		(fp_line
			(start -0.7874 0.4064)
			(end 0.7874 0.4064)
			(stroke
				(width 0.1524)
				(type default)
			)
			(layer "B.SilkS")
		)
		(fp_line
			(start -0.7874 -0.4064)
			(end -0.7874 0.4064)
			(stroke
				(width 0.1524)
				(type default)
			)
			(layer "B.SilkS")
		)
		(fp_line
			(start 0.67945 0.3048)
			(end 0.67945 -0.305054)
			(stroke
				(width 0.1)
				(type default)
			)
			(layer "B.Fab")
		)
		(fp_line
			(start 0.67945 -0.305054)
			(end 0.12065 -0.305054)
			(stroke
				(width 0.1)
				(type default)
			)
			(layer "B.Fab")
		)
		(fp_line
			(start 0.12065 0.3048)
			(end 0.67945 0.3048)
			(stroke
				(width 0.1)
				(type default)
			)
			(layer "B.Fab")
		)
		(fp_line
			(start 0.12065 0.2794)
			(end 0.12065 0.3048)
			(stroke
				(width 0.1)
				(type default)
			)
			(layer "B.Fab")
		)
		(fp_line
			(start 0.12065 -0.2794)
			(end -0.12065 -0.2794)
			(stroke
				(width 0.1)
				(type default)
			)
			(layer "B.Fab")
		)
		(fp_line
			(start 0.12065 -0.305054)
			(end 0.12065 -0.2794)
			(stroke
				(width 0.1)
				(type default)
			)
			(layer "B.Fab")
		)
		(fp_line
			(start -0.120396 0.3048)
			(end -0.120396 0.2794)
			(stroke
				(width 0.1)
				(type default)
			)
			(layer "B.Fab")
		)
		(fp_line
			(start -0.120396 0.2794)
			(end 0.12065 0.2794)
			(stroke
				(width 0.1)
				(type default)
			)
			(layer "B.Fab")
		)
		(fp_line
			(start -0.12065 -0.2794)
			(end -0.12065 -0.3048)
			(stroke
				(width 0.1)
				(type default)
			)
			(layer "B.Fab")
		)
		(fp_line
			(start -0.12065 -0.3048)
			(end -0.67945 -0.3048)
			(stroke
				(width 0.1)
				(type default)
			)
			(layer "B.Fab")
		)
		(fp_line
			(start -0.67945 0.3048)
			(end -0.120396 0.3048)
			(stroke
				(width 0.1)
				(type default)
			)
			(layer "B.Fab")
		)
		(fp_line
			(start -0.67945 -0.3048)
			(end -0.67945 0.3048)
			(stroke
				(width 0.1)
				(type default)
			)
			(layer "B.Fab")
		)
		(pad "1" smd circle
			(at 0.40005 0)
			(size 0 0)
			(layers "B.Cu" "B.Mask" "B.Paste")
			(net "P3V3_9ZXL045_P0_VDDR")
		)
		(pad "2" smd circle
			(at -0.40005 0)
			(size 0 0)
			(layers "B.Cu" "B.Mask" "B.Paste")
			(net "GND")
		)
	)
	(footprint ""
		(layer "B.Cu")
		(at 216.10193 -324.647306 180)
		(property "Reference" "R1244"
			(at 0 0 0)
			(layer "B.SilkS")
			(hide yes)
			(effects
				(font
					(size 1.27 1.27)
				)
				(justify mirror)
			)
		)
		(property "Value" ""
			(at 0 0 0)
			(layer "B.Fab")
			(effects
				(font
					(size 1.27 1.27)
				)
				(justify mirror)
			)
		)
		(duplicate_pad_numbers_are_jumpers no)
		(fp_line
			(start 0.7874 0.4064)
			(end 0.7874 -0.4064)
			(stroke
				(width 0.1524)
				(type default)
			)
			(layer "B.SilkS")
		)
		(fp_line
			(start 0.7874 -0.4064)
			(end -0.7874 -0.4064)
			(stroke
				(width 0.1524)
				(type default)
			)
			(layer "B.SilkS")
		)
		(fp_line
			(start -0.7874 0.4064)
			(end 0.7874 0.4064)
			(stroke
				(width 0.1524)
				(type default)
			)
			(layer "B.SilkS")
		)
		(fp_line
			(start -0.7874 -0.4064)
			(end -0.7874 0.4064)
			(stroke
				(width 0.1524)
				(type default)
			)
			(layer "B.SilkS")
		)
		(fp_line
			(start 0.67945 0.3048)
			(end 0.67945 -0.305054)
			(stroke
				(width 0.1)
				(type default)
			)
			(layer "B.Fab")
		)
		(fp_line
			(start 0.67945 -0.305054)
			(end 0.12065 -0.305054)
			(stroke
				(width 0.1)
				(type default)
			)
			(layer "B.Fab")
		)
		(fp_line
			(start 0.12065 0.3048)
			(end 0.67945 0.3048)
			(stroke
				(width 0.1)
				(type default)
			)
			(layer "B.Fab")
		)
		(fp_line
			(start 0.12065 0.2794)
			(end 0.12065 0.3048)
			(stroke
				(width 0.1)
				(type default)
			)
			(layer "B.Fab")
		)
		(fp_line
			(start 0.12065 -0.2794)
			(end -0.12065 -0.2794)
			(stroke
				(width 0.1)
				(type default)
			)
			(layer "B.Fab")
		)
		(fp_line
			(start 0.12065 -0.305054)
			(end 0.12065 -0.2794)
			(stroke
				(width 0.1)
				(type default)
			)
			(layer "B.Fab")
		)
		(fp_line
			(start -0.120396 0.3048)
			(end -0.120396 0.2794)
			(stroke
				(width 0.1)
				(type default)
			)
			(layer "B.Fab")
		)
		(fp_line
			(start -0.120396 0.2794)
			(end 0.12065 0.2794)
			(stroke
				(width 0.1)
				(type default)
			)
			(layer "B.Fab")
		)
		(fp_line
			(start -0.12065 -0.2794)
			(end -0.12065 -0.3048)
			(stroke
				(width 0.1)
				(type default)
			)
			(layer "B.Fab")
		)
		(fp_line
			(start -0.12065 -0.3048)
			(end -0.67945 -0.3048)
			(stroke
				(width 0.1)
				(type default)
			)
			(layer "B.Fab")
		)
		(fp_line
			(start -0.67945 0.3048)
			(end -0.120396 0.3048)
			(stroke
				(width 0.1)
				(type default)
			)
			(layer "B.Fab")
		)
		(fp_line
			(start -0.67945 -0.3048)
			(end -0.67945 0.3048)
			(stroke
				(width 0.1)
				(type default)
			)
			(layer "B.Fab")
		)
		(pad "1" smd circle
			(at 0.40005 0)
			(size 0 0)
			(layers "B.Cu" "B.Mask" "B.Paste")
			(net "SMB_ADC_SCL_R")
		)
		(pad "2" smd circle
			(at -0.40005 0)
			(size 0 0)
			(layers "B.Cu" "B.Mask" "B.Paste")
			(net "SMB_SEN_TIC_2_3V3AUX_SCL")
		)
	)
	(footprint ""
		(layer "B.Cu")
		(at 156.61894 -390.560052 90)
		(property "Reference" "C372"
			(at 0 0 90)
			(layer "B.SilkS")
			(hide yes)
			(effects
				(font
					(size 1.27 1.27)
				)
				(justify mirror)
			)
		)
		(property "Value" ""
			(at 0 0 90)
			(layer "B.Fab")
			(effects
				(font
					(size 1.27 1.27)
				)
				(justify mirror)
			)
		)
		(duplicate_pad_numbers_are_jumpers no)
		(fp_line
			(start 0.7874 -0.4064)
			(end -0.7874 -0.4064)
			(stroke
				(width 0.1524)
				(type default)
			)
			(layer "B.SilkS")
		)
		(fp_line
			(start -0.7874 -0.4064)
			(end -0.7874 0.4064)
			(stroke
				(width 0.1524)
				(type default)
			)
			(layer "B.SilkS")
		)
		(fp_line
			(start 0.7874 0.4064)
			(end 0.7874 -0.4064)
			(stroke
				(width 0.1524)
				(type default)
			)
			(layer "B.SilkS")
		)
		(fp_line
			(start -0.7874 0.4064)
			(end 0.7874 0.4064)
			(stroke
				(width 0.1524)
				(type default)
			)
			(layer "B.SilkS")
		)
		(fp_line
			(start 0.67945 -0.305054)
			(end 0.12065 -0.305054)
			(stroke
				(width 0.1)
				(type default)
			)
			(layer "B.Fab")
		)
		(fp_line
			(start 0.12065 -0.305054)
			(end 0.12065 -0.2794)
			(stroke
				(width 0.1)
				(type default)
			)
			(layer "B.Fab")
		)
		(fp_line
			(start -0.12065 -0.3048)
			(end -0.67945 -0.3048)
			(stroke
				(width 0.1)
				(type default)
			)
			(layer "B.Fab")
		)
		(fp_line
			(start -0.67945 -0.3048)
			(end -0.67945 0.3048)
			(stroke
				(width 0.1)
				(type default)
			)
			(layer "B.Fab")
		)
		(fp_line
			(start 0.12065 -0.2794)
			(end -0.12065 -0.2794)
			(stroke
				(width 0.1)
				(type default)
			)
			(layer "B.Fab")
		)
		(fp_line
			(start -0.12065 -0.2794)
			(end -0.12065 -0.3048)
			(stroke
				(width 0.1)
				(type default)
			)
			(layer "B.Fab")
		)
		(fp_line
			(start 0.12065 0.2794)
			(end 0.12065 0.3048)
			(stroke
				(width 0.1)
				(type default)
			)
			(layer "B.Fab")
		)
		(fp_line
			(start -0.120396 0.2794)
			(end 0.12065 0.2794)
			(stroke
				(width 0.1)
				(type default)
			)
			(layer "B.Fab")
		)
		(fp_line
			(start 0.67945 0.3048)
			(end 0.67945 -0.305054)
			(stroke
				(width 0.1)
				(type default)
			)
			(layer "B.Fab")
		)
		(fp_line
			(start 0.12065 0.3048)
			(end 0.67945 0.3048)
			(stroke
				(width 0.1)
				(type default)
			)
			(layer "B.Fab")
		)
		(fp_line
			(start -0.120396 0.3048)
			(end -0.120396 0.2794)
			(stroke
				(width 0.1)
				(type default)
			)
			(layer "B.Fab")
		)
		(fp_line
			(start -0.67945 0.3048)
			(end -0.120396 0.3048)
			(stroke
				(width 0.1)
				(type default)
			)
			(layer "B.Fab")
		)
		(pad "1" smd circle
			(at 0.40005 0 270)
			(size 0 0)
			(layers "B.Cu" "B.Mask" "B.Paste")
			(net "P1V8_CPU1_RT2_1A")
		)
		(pad "2" smd circle
			(at -0.40005 0 270)
			(size 0 0)
			(layers "B.Cu" "B.Mask" "B.Paste")
			(net "GND")
		)
	)
	(footprint ""
		(layer "B.Cu")
		(at 409.146248 -396.393162 -90)
		(property "Reference" "C782"
			(at 0 0 90)
			(layer "B.SilkS")
			(hide yes)
			(effects
				(font
					(size 1.27 1.27)
				)
				(justify mirror)
			)
		)
		(property "Value" ""
			(at 0 0 90)
			(layer "B.Fab")
			(effects
				(font
					(size 1.27 1.27)
				)
				(justify mirror)
			)
		)
		(duplicate_pad_numbers_are_jumpers no)
		(fp_line
			(start -0.299974 0.150114)
			(end 0.299974 0.150114)
			(stroke
				(width 0.1)
				(type default)
			)
			(layer "B.Fab")
		)
		(fp_line
			(start 0.299974 0.150114)
			(end 0.299974 -0.150114)
			(stroke
				(width 0.1)
				(type default)
			)
			(layer "B.Fab")
		)
		(fp_line
			(start -0.299974 -0.150114)
			(end -0.299974 0.150114)
			(stroke
				(width 0.1)
				(type default)
			)
			(layer "B.Fab")
		)
		(fp_line
			(start 0.299974 -0.150114)
			(end -0.299974 -0.150114)
			(stroke
				(width 0.1)
				(type default)
			)
			(layer "B.Fab")
		)
		(pad "1" smd rect
			(at 0.2667 0 90)
			(size 0.3048 0.381)
			(layers "B.Cu" "B.Mask" "B.Paste")
			(net "P0V9_CPU0_RT_2D")
		)
		(pad "2" smd rect
			(at -0.2667 0 90)
			(size 0.3048 0.381)
			(layers "B.Cu" "B.Mask" "B.Paste")
			(net "GND")
		)
	)
	(footprint ""
		(layer "B.Cu")
		(at 164.902388 -13.65504 90)
		(property "Reference" "R2423"
			(at 0 0 90)
			(layer "B.SilkS")
			(hide yes)
			(effects
				(font
					(size 1.27 1.27)
				)
				(justify mirror)
			)
		)
		(property "Value" ""
			(at 0 0 90)
			(layer "B.Fab")
			(effects
				(font
					(size 1.27 1.27)
				)
				(justify mirror)
			)
		)
		(duplicate_pad_numbers_are_jumpers no)
		(fp_line
			(start 0.7874 -0.4064)
			(end -0.7874 -0.4064)
			(stroke
				(width 0.1524)
				(type default)
			)
			(layer "B.SilkS")
		)
		(fp_line
			(start -0.7874 -0.4064)
			(end -0.7874 0.4064)
			(stroke
				(width 0.1524)
				(type default)
			)
			(layer "B.SilkS")
		)
		(fp_line
			(start 0.7874 0.4064)
			(end 0.7874 -0.4064)
			(stroke
				(width 0.1524)
				(type default)
			)
			(layer "B.SilkS")
		)
		(fp_line
			(start -0.7874 0.4064)
			(end 0.7874 0.4064)
			(stroke
				(width 0.1524)
				(type default)
			)
			(layer "B.SilkS")
		)
		(fp_line
			(start 0.67945 -0.305054)
			(end 0.12065 -0.305054)
			(stroke
				(width 0.1)
				(type default)
			)
			(layer "B.Fab")
		)
		(fp_line
			(start 0.12065 -0.305054)
			(end 0.12065 -0.2794)
			(stroke
				(width 0.1)
				(type default)
			)
			(layer "B.Fab")
		)
		(fp_line
			(start -0.12065 -0.3048)
			(end -0.67945 -0.3048)
			(stroke
				(width 0.1)
				(type default)
			)
			(layer "B.Fab")
		)
		(fp_line
			(start -0.67945 -0.3048)
			(end -0.67945 0.3048)
			(stroke
				(width 0.1)
				(type default)
			)
			(layer "B.Fab")
		)
		(fp_line
			(start 0.12065 -0.2794)
			(end -0.12065 -0.2794)
			(stroke
				(width 0.1)
				(type default)
			)
			(layer "B.Fab")
		)
		(fp_line
			(start -0.12065 -0.2794)
			(end -0.12065 -0.3048)
			(stroke
				(width 0.1)
				(type default)
			)
			(layer "B.Fab")
		)
		(fp_line
			(start 0.12065 0.2794)
			(end 0.12065 0.3048)
			(stroke
				(width 0.1)
				(type default)
			)
			(layer "B.Fab")
		)
		(fp_line
			(start -0.120396 0.2794)
			(end 0.12065 0.2794)
			(stroke
				(width 0.1)
				(type default)
			)
			(layer "B.Fab")
		)
		(fp_line
			(start 0.67945 0.3048)
			(end 0.67945 -0.305054)
			(stroke
				(width 0.1)
				(type default)
			)
			(layer "B.Fab")
		)
		(fp_line
			(start 0.12065 0.3048)
			(end 0.67945 0.3048)
			(stroke
				(width 0.1)
				(type default)
			)
			(layer "B.Fab")
		)
		(fp_line
			(start -0.120396 0.3048)
			(end -0.120396 0.2794)
			(stroke
				(width 0.1)
				(type default)
			)
			(layer "B.Fab")
		)
		(fp_line
			(start -0.67945 0.3048)
			(end -0.120396 0.3048)
			(stroke
				(width 0.1)
				(type default)
			)
			(layer "B.Fab")
		)
		(pad "1" smd circle
			(at 0.40005 0 270)
			(size 0 0)
			(layers "B.Cu" "B.Mask" "B.Paste")
			(net "SMB_PMBUS_3V3AUX_SCL")
		)
		(pad "2" smd circle
			(at -0.40005 0 270)
			(size 0 0)
			(layers "B.Cu" "B.Mask" "B.Paste")
			(net "SMB_PMBUS_3V3AUX_SCL_R0")
		)
	)
	(footprint ""
		(layer "B.Cu")
		(at 206.429356 -386.152136 180)
		(property "Reference" "PR2525"
			(at 0 0 0)
			(layer "B.SilkS")
			(hide yes)
			(effects
				(font
					(size 1.27 1.27)
				)
				(justify mirror)
			)
		)
		(property "Value" ""
			(at 0 0 0)
			(layer "B.Fab")
			(effects
				(font
					(size 1.27 1.27)
				)
				(justify mirror)
			)
		)
		(duplicate_pad_numbers_are_jumpers no)
		(fp_line
			(start 0.7874 0.4064)
			(end 0.7874 -0.4064)
			(stroke
				(width 0.1524)
				(type default)
			)
			(layer "B.SilkS")
		)
		(fp_line
			(start 0.7874 -0.4064)
			(end -0.7874 -0.4064)
			(stroke
				(width 0.1524)
				(type default)
			)
			(layer "B.SilkS")
		)
		(fp_line
			(start -0.7874 0.4064)
			(end 0.7874 0.4064)
			(stroke
				(width 0.1524)
				(type default)
			)
			(layer "B.SilkS")
		)
		(fp_line
			(start -0.7874 -0.4064)
			(end -0.7874 0.4064)
			(stroke
				(width 0.1524)
				(type default)
			)
			(layer "B.SilkS")
		)
		(fp_line
			(start 0.67945 0.3048)
			(end 0.67945 -0.305054)
			(stroke
				(width 0.1)
				(type default)
			)
			(layer "B.Fab")
		)
		(fp_line
			(start 0.67945 -0.305054)
			(end 0.12065 -0.305054)
			(stroke
				(width 0.1)
				(type default)
			)
			(layer "B.Fab")
		)
		(fp_line
			(start 0.12065 0.3048)
			(end 0.67945 0.3048)
			(stroke
				(width 0.1)
				(type default)
			)
			(layer "B.Fab")
		)
		(fp_line
			(start 0.12065 0.2794)
			(end 0.12065 0.3048)
			(stroke
				(width 0.1)
				(type default)
			)
			(layer "B.Fab")
		)
		(fp_line
			(start 0.12065 -0.2794)
			(end -0.12065 -0.2794)
			(stroke
				(width 0.1)
				(type default)
			)
			(layer "B.Fab")
		)
		(fp_line
			(start 0.12065 -0.305054)
			(end 0.12065 -0.2794)
			(stroke
				(width 0.1)
				(type default)
			)
			(layer "B.Fab")
		)
		(fp_line
			(start -0.120396 0.3048)
			(end -0.120396 0.2794)
			(stroke
				(width 0.1)
				(type default)
			)
			(layer "B.Fab")
		)
		(fp_line
			(start -0.120396 0.2794)
			(end 0.12065 0.2794)
			(stroke
				(width 0.1)
				(type default)
			)
			(layer "B.Fab")
		)
		(fp_line
			(start -0.12065 -0.2794)
			(end -0.12065 -0.3048)
			(stroke
				(width 0.1)
				(type default)
			)
			(layer "B.Fab")
		)
		(fp_line
			(start -0.12065 -0.3048)
			(end -0.67945 -0.3048)
			(stroke
				(width 0.1)
				(type default)
			)
			(layer "B.Fab")
		)
		(fp_line
			(start -0.67945 0.3048)
			(end -0.120396 0.3048)
			(stroke
				(width 0.1)
				(type default)
			)
			(layer "B.Fab")
		)
		(fp_line
			(start -0.67945 -0.3048)
			(end -0.67945 0.3048)
			(stroke
				(width 0.1)
				(type default)
			)
			(layer "B.Fab")
		)
		(pad "1" smd circle
			(at 0.40005 0)
			(size 0 0)
			(layers "B.Cu" "B.Mask" "B.Paste")
			(net "P12V_HSC_SENSE2_N")
		)
		(pad "2" smd circle
			(at -0.40005 0)
			(size 0 0)
			(layers "B.Cu" "B.Mask" "B.Paste")
			(net "P12V_HSC_SENSE2_R2_N")
		)
	)
	(footprint ""
		(layer "B.Cu")
		(at 217.551762 -69.483478 180)
		(property "Reference" "R75"
			(at 0 0 0)
			(layer "B.SilkS")
			(hide yes)
			(effects
				(font
					(size 1.27 1.27)
				)
				(justify mirror)
			)
		)
		(property "Value" ""
			(at 0 0 0)
			(layer "B.Fab")
			(effects
				(font
					(size 1.27 1.27)
				)
				(justify mirror)
			)
		)
		(duplicate_pad_numbers_are_jumpers no)
		(fp_line
			(start 0.7874 0.4064)
			(end 0.7874 -0.4064)
			(stroke
				(width 0.1524)
				(type default)
			)
			(layer "B.SilkS")
		)
		(fp_line
			(start 0.7874 -0.4064)
			(end -0.7874 -0.4064)
			(stroke
				(width 0.1524)
				(type default)
			)
			(layer "B.SilkS")
		)
		(fp_line
			(start -0.7874 0.4064)
			(end 0.7874 0.4064)
			(stroke
				(width 0.1524)
				(type default)
			)
			(layer "B.SilkS")
		)
		(fp_line
			(start -0.7874 -0.4064)
			(end -0.7874 0.4064)
			(stroke
				(width 0.1524)
				(type default)
			)
			(layer "B.SilkS")
		)
		(fp_line
			(start 0.67945 0.3048)
			(end 0.67945 -0.305054)
			(stroke
				(width 0.1)
				(type default)
			)
			(layer "B.Fab")
		)
		(fp_line
			(start 0.67945 -0.305054)
			(end 0.12065 -0.305054)
			(stroke
				(width 0.1)
				(type default)
			)
			(layer "B.Fab")
		)
		(fp_line
			(start 0.12065 0.3048)
			(end 0.67945 0.3048)
			(stroke
				(width 0.1)
				(type default)
			)
			(layer "B.Fab")
		)
		(fp_line
			(start 0.12065 0.2794)
			(end 0.12065 0.3048)
			(stroke
				(width 0.1)
				(type default)
			)
			(layer "B.Fab")
		)
		(fp_line
			(start 0.12065 -0.2794)
			(end -0.12065 -0.2794)
			(stroke
				(width 0.1)
				(type default)
			)
			(layer "B.Fab")
		)
		(fp_line
			(start 0.12065 -0.305054)
			(end 0.12065 -0.2794)
			(stroke
				(width 0.1)
				(type default)
			)
			(layer "B.Fab")
		)
		(fp_line
			(start -0.120396 0.3048)
			(end -0.120396 0.2794)
			(stroke
				(width 0.1)
				(type default)
			)
			(layer "B.Fab")
		)
		(fp_line
			(start -0.120396 0.2794)
			(end 0.12065 0.2794)
			(stroke
				(width 0.1)
				(type default)
			)
			(layer "B.Fab")
		)
		(fp_line
			(start -0.12065 -0.2794)
			(end -0.12065 -0.3048)
			(stroke
				(width 0.1)
				(type default)
			)
			(layer "B.Fab")
		)
		(fp_line
			(start -0.12065 -0.3048)
			(end -0.67945 -0.3048)
			(stroke
				(width 0.1)
				(type default)
			)
			(layer "B.Fab")
		)
		(fp_line
			(start -0.67945 0.3048)
			(end -0.120396 0.3048)
			(stroke
				(width 0.1)
				(type default)
			)
			(layer "B.Fab")
		)
		(fp_line
			(start -0.67945 -0.3048)
			(end -0.67945 0.3048)
			(stroke
				(width 0.1)
				(type default)
			)
			(layer "B.Fab")
		)
		(pad "1" smd circle
			(at 0.40005 0)
			(size 0 0)
			(layers "B.Cu" "B.Mask" "B.Paste")
			(net "NCSI_BMC_TXD0_R")
		)
		(pad "2" smd circle
			(at -0.40005 0)
			(size 0 0)
			(layers "B.Cu" "B.Mask" "B.Paste")
			(net "RMII_BMC_OCP_TXD_0")
		)
	)
	(footprint ""
		(layer "B.Cu")
		(at 312.990992 -398.942052 90)
		(property "Reference" "C507"
			(at 0 0 90)
			(layer "B.SilkS")
			(hide yes)
			(effects
				(font
					(size 1.27 1.27)
				)
				(justify mirror)
			)
		)
		(property "Value" ""
			(at 0 0 90)
			(layer "B.Fab")
			(effects
				(font
					(size 1.27 1.27)
				)
				(justify mirror)
			)
		)
		(duplicate_pad_numbers_are_jumpers no)
		(fp_line
			(start 0.7874 -0.4064)
			(end -0.7874 -0.4064)
			(stroke
				(width 0.1524)
				(type default)
			)
			(layer "B.SilkS")
		)
		(fp_line
			(start -0.7874 -0.4064)
			(end -0.7874 0.4064)
			(stroke
				(width 0.1524)
				(type default)
			)
			(layer "B.SilkS")
		)
		(fp_line
			(start 0.7874 0.4064)
			(end 0.7874 -0.4064)
			(stroke
				(width 0.1524)
				(type default)
			)
			(layer "B.SilkS")
		)
		(fp_line
			(start -0.7874 0.4064)
			(end 0.7874 0.4064)
			(stroke
				(width 0.1524)
				(type default)
			)
			(layer "B.SilkS")
		)
		(fp_line
			(start 0.67945 -0.305054)
			(end 0.12065 -0.305054)
			(stroke
				(width 0.1)
				(type default)
			)
			(layer "B.Fab")
		)
		(fp_line
			(start 0.12065 -0.305054)
			(end 0.12065 -0.2794)
			(stroke
				(width 0.1)
				(type default)
			)
			(layer "B.Fab")
		)
		(fp_line
			(start -0.12065 -0.3048)
			(end -0.67945 -0.3048)
			(stroke
				(width 0.1)
				(type default)
			)
			(layer "B.Fab")
		)
		(fp_line
			(start -0.67945 -0.3048)
			(end -0.67945 0.3048)
			(stroke
				(width 0.1)
				(type default)
			)
			(layer "B.Fab")
		)
		(fp_line
			(start 0.12065 -0.2794)
			(end -0.12065 -0.2794)
			(stroke
				(width 0.1)
				(type default)
			)
			(layer "B.Fab")
		)
		(fp_line
			(start -0.12065 -0.2794)
			(end -0.12065 -0.3048)
			(stroke
				(width 0.1)
				(type default)
			)
			(layer "B.Fab")
		)
		(fp_line
			(start 0.12065 0.2794)
			(end 0.12065 0.3048)
			(stroke
				(width 0.1)
				(type default)
			)
			(layer "B.Fab")
		)
		(fp_line
			(start -0.120396 0.2794)
			(end 0.12065 0.2794)
			(stroke
				(width 0.1)
				(type default)
			)
			(layer "B.Fab")
		)
		(fp_line
			(start 0.67945 0.3048)
			(end 0.67945 -0.305054)
			(stroke
				(width 0.1)
				(type default)
			)
			(layer "B.Fab")
		)
		(fp_line
			(start 0.12065 0.3048)
			(end 0.67945 0.3048)
			(stroke
				(width 0.1)
				(type default)
			)
			(layer "B.Fab")
		)
		(fp_line
			(start -0.120396 0.3048)
			(end -0.120396 0.2794)
			(stroke
				(width 0.1)
				(type default)
			)
			(layer "B.Fab")
		)
		(fp_line
			(start -0.67945 0.3048)
			(end -0.120396 0.3048)
			(stroke
				(width 0.1)
				(type default)
			)
			(layer "B.Fab")
		)
		(pad "1" smd circle
			(at 0.40005 0 270)
			(size 0 0)
			(layers "B.Cu" "B.Mask" "B.Paste")
			(net "P1V8_CPU0_RT0_1A")
		)
		(pad "2" smd circle
			(at -0.40005 0 270)
			(size 0 0)
			(layers "B.Cu" "B.Mask" "B.Paste")
			(net "GND")
		)
	)
	(footprint ""
		(layer "B.Cu")
		(at 401.619974 -349.217742 -90)
		(property "Reference" "R6124"
			(at 0 0 90)
			(layer "B.SilkS")
			(hide yes)
			(effects
				(font
					(size 1.27 1.27)
				)
				(justify mirror)
			)
		)
		(property "Value" ""
			(at 0 0 90)
			(layer "B.Fab")
			(effects
				(font
					(size 1.27 1.27)
				)
				(justify mirror)
			)
		)
		(duplicate_pad_numbers_are_jumpers no)
		(fp_line
			(start -0.7874 0.4064)
			(end 0.7874 0.4064)
			(stroke
				(width 0.1524)
				(type default)
			)
			(layer "B.SilkS")
		)
		(fp_line
			(start 0.7874 0.4064)
			(end 0.7874 -0.4064)
			(stroke
				(width 0.1524)
				(type default)
			)
			(layer "B.SilkS")
		)
		(fp_line
			(start -0.7874 -0.4064)
			(end -0.7874 0.4064)
			(stroke
				(width 0.1524)
				(type default)
			)
			(layer "B.SilkS")
		)
		(fp_line
			(start 0.7874 -0.4064)
			(end -0.7874 -0.4064)
			(stroke
				(width 0.1524)
				(type default)
			)
			(layer "B.SilkS")
		)
		(fp_line
			(start -0.67945 0.3048)
			(end -0.120396 0.3048)
			(stroke
				(width 0.1)
				(type default)
			)
			(layer "B.Fab")
		)
		(fp_line
			(start -0.120396 0.3048)
			(end -0.120396 0.2794)
			(stroke
				(width 0.1)
				(type default)
			)
			(layer "B.Fab")
		)
		(fp_line
			(start 0.12065 0.3048)
			(end 0.67945 0.3048)
			(stroke
				(width 0.1)
				(type default)
			)
			(layer "B.Fab")
		)
		(fp_line
			(start 0.67945 0.3048)
			(end 0.67945 -0.305054)
			(stroke
				(width 0.1)
				(type default)
			)
			(layer "B.Fab")
		)
		(fp_line
			(start -0.120396 0.2794)
			(end 0.12065 0.2794)
			(stroke
				(width 0.1)
				(type default)
			)
			(layer "B.Fab")
		)
		(fp_line
			(start 0.12065 0.2794)
			(end 0.12065 0.3048)
			(stroke
				(width 0.1)
				(type default)
			)
			(layer "B.Fab")
		)
		(fp_line
			(start -0.12065 -0.2794)
			(end -0.12065 -0.3048)
			(stroke
				(width 0.1)
				(type default)
			)
			(layer "B.Fab")
		)
		(fp_line
			(start 0.12065 -0.2794)
			(end -0.12065 -0.2794)
			(stroke
				(width 0.1)
				(type default)
			)
			(layer "B.Fab")
		)
		(fp_line
			(start -0.67945 -0.3048)
			(end -0.67945 0.3048)
			(stroke
				(width 0.1)
				(type default)
			)
			(layer "B.Fab")
		)
		(fp_line
			(start -0.12065 -0.3048)
			(end -0.67945 -0.3048)
			(stroke
				(width 0.1)
				(type default)
			)
			(layer "B.Fab")
		)
		(fp_line
			(start 0.12065 -0.305054)
			(end 0.12065 -0.2794)
			(stroke
				(width 0.1)
				(type default)
			)
			(layer "B.Fab")
		)
		(fp_line
			(start 0.67945 -0.305054)
			(end 0.12065 -0.305054)
			(stroke
				(width 0.1)
				(type default)
			)
			(layer "B.Fab")
		)
		(pad "1" smd circle
			(at 0.40005 0 90)
			(size 0 0)
			(layers "B.Cu" "B.Mask" "B.Paste")
			(net "PVDD18_S5_P0")
		)
		(pad "2" smd circle
			(at -0.40005 0 90)
			(size 0 0)
			(layers "B.Cu" "B.Mask" "B.Paste")
			(net "FM_BOARD_SKU_ID0")
		)
	)
	(footprint ""
		(layer "B.Cu")
		(at 304.419 -360.426 180)
		(property "Reference" "R8070"
			(at 0 0 0)
			(layer "B.SilkS")
			(hide yes)
			(effects
				(font
					(size 1.27 1.27)
				)
				(justify mirror)
			)
		)
		(property "Value" ""
			(at 0 0 0)
			(layer "B.Fab")
			(effects
				(font
					(size 1.27 1.27)
				)
				(justify mirror)
			)
		)
		(duplicate_pad_numbers_are_jumpers no)
		(fp_line
			(start 0.7874 0.4064)
			(end 0.7874 -0.4064)
			(stroke
				(width 0.1524)
				(type default)
			)
			(layer "B.SilkS")
		)
		(fp_line
			(start 0.7874 -0.4064)
			(end -0.7874 -0.4064)
			(stroke
				(width 0.1524)
				(type default)
			)
			(layer "B.SilkS")
		)
		(fp_line
			(start -0.7874 0.4064)
			(end 0.7874 0.4064)
			(stroke
				(width 0.1524)
				(type default)
			)
			(layer "B.SilkS")
		)
		(fp_line
			(start -0.7874 -0.4064)
			(end -0.7874 0.4064)
			(stroke
				(width 0.1524)
				(type default)
			)
			(layer "B.SilkS")
		)
		(fp_line
			(start 0.67945 0.3048)
			(end 0.67945 -0.305054)
			(stroke
				(width 0.1)
				(type default)
			)
			(layer "B.Fab")
		)
		(fp_line
			(start 0.67945 -0.305054)
			(end 0.12065 -0.305054)
			(stroke
				(width 0.1)
				(type default)
			)
			(layer "B.Fab")
		)
		(fp_line
			(start 0.12065 0.3048)
			(end 0.67945 0.3048)
			(stroke
				(width 0.1)
				(type default)
			)
			(layer "B.Fab")
		)
		(fp_line
			(start 0.12065 0.2794)
			(end 0.12065 0.3048)
			(stroke
				(width 0.1)
				(type default)
			)
			(layer "B.Fab")
		)
		(fp_line
			(start 0.12065 -0.2794)
			(end -0.12065 -0.2794)
			(stroke
				(width 0.1)
				(type default)
			)
			(layer "B.Fab")
		)
		(fp_line
			(start 0.12065 -0.305054)
			(end 0.12065 -0.2794)
			(stroke
				(width 0.1)
				(type default)
			)
			(layer "B.Fab")
		)
		(fp_line
			(start -0.120396 0.3048)
			(end -0.120396 0.2794)
			(stroke
				(width 0.1)
				(type default)
			)
			(layer "B.Fab")
		)
		(fp_line
			(start -0.120396 0.2794)
			(end 0.12065 0.2794)
			(stroke
				(width 0.1)
				(type default)
			)
			(layer "B.Fab")
		)
		(fp_line
			(start -0.12065 -0.2794)
			(end -0.12065 -0.3048)
			(stroke
				(width 0.1)
				(type default)
			)
			(layer "B.Fab")
		)
		(fp_line
			(start -0.12065 -0.3048)
			(end -0.67945 -0.3048)
			(stroke
				(width 0.1)
				(type default)
			)
			(layer "B.Fab")
		)
		(fp_line
			(start -0.67945 0.3048)
			(end -0.120396 0.3048)
			(stroke
				(width 0.1)
				(type default)
			)
			(layer "B.Fab")
		)
		(fp_line
			(start -0.67945 -0.3048)
			(end -0.67945 0.3048)
			(stroke
				(width 0.1)
				(type default)
			)
			(layer "B.Fab")
		)
		(pad "1" smd circle
			(at 0.40005 0)
			(size 0 0)
			(layers "B.Cu" "B.Mask" "B.Paste")
			(net "PVDD18_S5_P0")
		)
		(pad "2" smd circle
			(at -0.40005 0)
			(size 0 0)
			(layers "B.Cu" "B.Mask" "B.Paste")
			(net "PVDDCR_CPU1_P0_RESET_N_R")
		)
	)
	(footprint ""
		(layer "B.Cu")
		(at 403.947122 -416.899344 90)
		(property "Reference" "C6617"
			(at 0 0 90)
			(layer "B.SilkS")
			(hide yes)
			(effects
				(font
					(size 1.27 1.27)
				)
				(justify mirror)
			)
		)
		(property "Value" ""
			(at 0 0 90)
			(layer "B.Fab")
			(effects
				(font
					(size 1.27 1.27)
				)
				(justify mirror)
			)
		)
		(duplicate_pad_numbers_are_jumpers no)
		(fp_line
			(start 0.299974 -0.150114)
			(end -0.299974 -0.150114)
			(stroke
				(width 0.1)
				(type default)
			)
			(layer "B.Fab")
		)
		(fp_line
			(start -0.299974 -0.150114)
			(end -0.299974 0.150114)
			(stroke
				(width 0.1)
				(type default)
			)
			(layer "B.Fab")
		)
		(fp_line
			(start 0.299974 0.150114)
			(end 0.299974 -0.150114)
			(stroke
				(width 0.1)
				(type default)
			)
			(layer "B.Fab")
		)
		(fp_line
			(start -0.299974 0.150114)
			(end 0.299974 0.150114)
			(stroke
				(width 0.1)
				(type default)
			)
			(layer "B.Fab")
		)
		(pad "1" smd rect
			(at 0.2667 0 270)
			(size 0.3048 0.381)
			(layers "B.Cu" "B.Mask" "B.Paste")
			(net "P5E_CPU0_P3_TX_BUF_C_DP<10>")
		)
		(pad "2" smd rect
			(at -0.2667 0 270)
			(size 0.3048 0.381)
			(layers "B.Cu" "B.Mask" "B.Paste")
			(net "P5E_CPU0_P3_TX_BUF_DP<10>")
		)
	)
	(footprint ""
		(layer "B.Cu")
		(at 498.693948 -147.924266 90)
		(property "Reference" "X28"
			(at 0.956564 2.769362 270)
			(unlocked yes)
			(layer "B.SilkS")
			(effects
				(font
					(size 0.7874 0.5842)
					(thickness 0.1524)
				)
				(justify left mirror)
			)
		)
		(property "Value" ""
			(at 0 0 90)
			(layer "B.Fab")
			(effects
				(font
					(size 1.27 1.27)
				)
				(justify mirror)
			)
		)
		(property "Device Type" "TP_TDR_4P_FTS_TH-TP_TDR_4P_DIP,EMPTY,TP15"
			(at -1.30175 1.27 0)
			(unlocked yes)
			(layer "B.Fab")
			(hide yes)
			(effects
				(font
					(size 0.635 0.4064)
					(thickness 0.1524)
				)
				(justify mirror)
			)
		)
		(property "User Part Number" "N_A"
			(at -1.30175 1.27 0)
			(unlocked yes)
			(layer "Cmts.User")
			(hide yes)
			(effects
				(font
					(size 0.635 0.4064)
					(thickness 0.1524)
				)
				(justify mirror)
			)
		)
		(duplicate_pad_numbers_are_jumpers no)
		(fp_line
			(start 0 -1.27)
			(end 0 -0.635)
			(stroke
				(width 0.1524)
				(type default)
			)
			(layer "B.SilkS")
		)
		(fp_line
			(start -2.54 -1.27)
			(end 0 -1.27)
			(stroke
				(width 0.1524)
				(type default)
			)
			(layer "B.SilkS")
		)
		(fp_line
			(start -2.54 -1.1303)
			(end -2.54 -1.27)
			(stroke
				(width 0.1524)
				(type default)
			)
			(layer "B.SilkS")
		)
		(fp_line
			(start 0 0.635)
			(end 0 1.905)
			(stroke
				(width 0.1524)
				(type default)
			)
			(layer "B.SilkS")
		)
		(fp_line
			(start -2.54 1.4097)
			(end -2.54 1.1303)
			(stroke
				(width 0.1524)
				(type default)
			)
			(layer "B.SilkS")
		)
		(fp_line
			(start 0 3.175)
			(end 0 3.81)
			(stroke
				(width 0.1524)
				(type default)
			)
			(layer "B.SilkS")
		)
		(fp_line
			(start 0 3.81)
			(end -2.54 3.81)
			(stroke
				(width 0.1524)
				(type default)
			)
			(layer "B.SilkS")
		)
		(fp_line
			(start -2.54 3.81)
			(end -2.54 3.6703)
			(stroke
				(width 0.1524)
				(type default)
			)
			(layer "B.SilkS")
		)
		(fp_poly
			(pts
				(xy 2.285746 -0.762) (xy 2.285746 0.762) (xy 0.761746 0)
			)
			(stroke
				(width 0)
				(type default)
			)
			(fill yes)
			(layer "B.SilkS")
		)
		(fp_line
			(start 0 -1.27)
			(end 0 3.81)
			(stroke
				(width 0.1)
				(type default)
			)
			(layer "B.Fab")
		)
		(fp_line
			(start -2.54 -1.27)
			(end 0 -1.27)
			(stroke
				(width 0.1)
				(type default)
			)
			(layer "B.Fab")
		)
		(fp_line
			(start 0 3.81)
			(end -2.54 3.81)
			(stroke
				(width 0.1)
				(type default)
			)
			(layer "B.Fab")
		)
		(fp_line
			(start -2.54 3.81)
			(end -2.54 -1.27)
			(stroke
				(width 0.1)
				(type default)
			)
			(layer "B.Fab")
		)
		(fp_poly
			(pts
				(xy 0.761746 0) (xy 2.285746 -0.762) (xy 2.285746 0.762)
			)
			(stroke
				(width 0)
				(type default)
			)
			(fill yes)
			(layer "B.Fab")
		)
		(pad "1" thru_hole circle
			(at 0 0 270)
			(size 1.0033 1.0033)
			(drill 0.249936)
			(layers "*.Cu" "*.Mask")
			(remove_unused_layers no)
			(net "TDR_DIFF_80_IN6_DN")
			(clearance 0.10795)
			(padstack
				(mode front_inner_back)
				(layer "Inner"
					(shape circle)
					(size 0.8001 0.8001)
					(clearance 0.1524)
				)
				(layer "B.Cu"
					(shape circle)
					(size 1.0033 1.0033)
					(thermal_gap 0.10795)
					(clearance 0.10795)
				)
			)
		)
		(pad "2" thru_hole circle
			(at -2.54 0 270)
			(size 1.9939 1.9939)
			(drill 0.249936)
			(layers "*.Cu" "*.Mask")
			(remove_unused_layers no)
			(net "T1_GND")
			(clearance 0.10795)
			(padstack
				(mode front_inner_back)
				(layer "Inner"
					(shape circle)
					(size 0.8001 0.8001)
					(clearance 0.1524)
				)
				(layer "B.Cu"
					(shape circle)
					(size 1.9939 1.9939)
					(thermal_gap 0.10795)
					(clearance 0.10795)
				)
			)
		)
		(pad "3" thru_hole circle
			(at -2.54 2.54 270)
			(size 1.9939 1.9939)
			(drill 0.249936)
			(layers "*.Cu" "*.Mask")
			(remove_unused_layers no)
			(net "T1_GND")
			(clearance 0.10795)
			(padstack
				(mode front_inner_back)
				(layer "Inner"
					(shape circle)
					(size 0.8001 0.8001)
					(clearance 0.1524)
				)
				(layer "B.Cu"
					(shape circle)
					(size 1.9939 1.9939)
					(thermal_gap 0.10795)
					(clearance 0.10795)
				)
			)
		)
		(pad "4" thru_hole circle
			(at 0 2.54 270)
			(size 1.0033 1.0033)
			(drill 0.249936)
			(layers "*.Cu" "*.Mask")
			(remove_unused_layers no)
			(net "TDR_DIFF_80_IN6_DP")
			(clearance 0.10795)
			(padstack
				(mode front_inner_back)
				(layer "Inner"
					(shape circle)
					(size 0.8001 0.8001)
					(clearance 0.1524)
				)
				(layer "B.Cu"
					(shape circle)
					(size 1.0033 1.0033)
					(thermal_gap 0.10795)
					(clearance 0.10795)
				)
			)
		)
	)
	(footprint ""
		(layer "B.Cu")
		(at 364.165896 -256.012188 -90)
		(property "Reference" "C2155"
			(at 0 0 90)
			(layer "B.SilkS")
			(hide yes)
			(effects
				(font
					(size 1.27 1.27)
				)
				(justify mirror)
			)
		)
		(property "Value" ""
			(at 0 0 90)
			(layer "B.Fab")
			(effects
				(font
					(size 1.27 1.27)
				)
				(justify mirror)
			)
		)
		(duplicate_pad_numbers_are_jumpers no)
		(fp_line
			(start -0.7874 0.4064)
			(end 0.7874 0.4064)
			(stroke
				(width 0.1524)
				(type default)
			)
			(layer "B.SilkS")
		)
		(fp_line
			(start 0.7874 0.4064)
			(end 0.7874 -0.4064)
			(stroke
				(width 0.1524)
				(type default)
			)
			(layer "B.SilkS")
		)
		(fp_line
			(start -0.7874 -0.4064)
			(end -0.7874 0.4064)
			(stroke
				(width 0.1524)
				(type default)
			)
			(layer "B.SilkS")
		)
		(fp_line
			(start 0.7874 -0.4064)
			(end -0.7874 -0.4064)
			(stroke
				(width 0.1524)
				(type default)
			)
			(layer "B.SilkS")
		)
		(fp_line
			(start -0.67945 0.3048)
			(end -0.120396 0.3048)
			(stroke
				(width 0.1)
				(type default)
			)
			(layer "B.Fab")
		)
		(fp_line
			(start -0.120396 0.3048)
			(end -0.120396 0.2794)
			(stroke
				(width 0.1)
				(type default)
			)
			(layer "B.Fab")
		)
		(fp_line
			(start 0.12065 0.3048)
			(end 0.67945 0.3048)
			(stroke
				(width 0.1)
				(type default)
			)
			(layer "B.Fab")
		)
		(fp_line
			(start 0.67945 0.3048)
			(end 0.67945 -0.305054)
			(stroke
				(width 0.1)
				(type default)
			)
			(layer "B.Fab")
		)
		(fp_line
			(start -0.120396 0.2794)
			(end 0.12065 0.2794)
			(stroke
				(width 0.1)
				(type default)
			)
			(layer "B.Fab")
		)
		(fp_line
			(start 0.12065 0.2794)
			(end 0.12065 0.3048)
			(stroke
				(width 0.1)
				(type default)
			)
			(layer "B.Fab")
		)
		(fp_line
			(start -0.12065 -0.2794)
			(end -0.12065 -0.3048)
			(stroke
				(width 0.1)
				(type default)
			)
			(layer "B.Fab")
		)
		(fp_line
			(start 0.12065 -0.2794)
			(end -0.12065 -0.2794)
			(stroke
				(width 0.1)
				(type default)
			)
			(layer "B.Fab")
		)
		(fp_line
			(start -0.67945 -0.3048)
			(end -0.67945 0.3048)
			(stroke
				(width 0.1)
				(type default)
			)
			(layer "B.Fab")
		)
		(fp_line
			(start -0.12065 -0.3048)
			(end -0.67945 -0.3048)
			(stroke
				(width 0.1)
				(type default)
			)
			(layer "B.Fab")
		)
		(fp_line
			(start 0.12065 -0.305054)
			(end 0.12065 -0.2794)
			(stroke
				(width 0.1)
				(type default)
			)
			(layer "B.Fab")
		)
		(fp_line
			(start 0.67945 -0.305054)
			(end 0.12065 -0.305054)
			(stroke
				(width 0.1)
				(type default)
			)
			(layer "B.Fab")
		)
		(pad "1" smd circle
			(at 0.40005 0 90)
			(size 0 0)
			(layers "B.Cu" "B.Mask" "B.Paste")
			(net "PVDDCR_SOC_P0")
		)
		(pad "2" smd circle
			(at -0.40005 0 90)
			(size 0 0)
			(layers "B.Cu" "B.Mask" "B.Paste")
			(net "GND")
		)
	)
	(footprint ""
		(layer "B.Cu")
		(at 113.17478 -408.618436 90)
		(property "Reference" "R695"
			(at 0 0 90)
			(layer "B.SilkS")
			(hide yes)
			(effects
				(font
					(size 1.27 1.27)
				)
				(justify mirror)
			)
		)
		(property "Value" ""
			(at 0 0 90)
			(layer "B.Fab")
			(effects
				(font
					(size 1.27 1.27)
				)
				(justify mirror)
			)
		)
		(duplicate_pad_numbers_are_jumpers no)
		(fp_line
			(start 0.32512 -0.175006)
			(end -0.32512 -0.175006)
			(stroke
				(width 0.1)
				(type default)
			)
			(layer "B.Fab")
		)
		(fp_line
			(start -0.32512 -0.175006)
			(end -0.32512 0.175006)
			(stroke
				(width 0.1)
				(type default)
			)
			(layer "B.Fab")
		)
		(fp_line
			(start 0.32512 0.175006)
			(end 0.32512 -0.175006)
			(stroke
				(width 0.1)
				(type default)
			)
			(layer "B.Fab")
		)
		(fp_line
			(start -0.32512 0.175006)
			(end 0.32512 0.175006)
			(stroke
				(width 0.1)
				(type default)
			)
			(layer "B.Fab")
		)
		(pad "1" smd rect
			(at 0.2667 0 270)
			(size 0.3048 0.381)
			(layers "B.Cu" "B.Mask" "B.Paste")
			(net "SMB_RT_CPU1_P3_ROM_MUX_1D_SCL")
		)
		(pad "2" smd rect
			(at -0.2667 0 90)
			(size 0.3048 0.381)
			(layers "B.Cu" "B.Mask" "B.Paste")
			(net "SMB_RT_CPU1_P3_ROM_MUX_1D_R_SCL")
		)
	)
	(footprint ""
		(layer "B.Cu")
		(at 291.52469 -194.893946 180)
		(property "Reference" "R1570"
			(at 0 0 0)
			(layer "B.SilkS")
			(hide yes)
			(effects
				(font
					(size 1.27 1.27)
				)
				(justify mirror)
			)
		)
		(property "Value" ""
			(at 0 0 0)
			(layer "B.Fab")
			(effects
				(font
					(size 1.27 1.27)
				)
				(justify mirror)
			)
		)
		(duplicate_pad_numbers_are_jumpers no)
		(fp_line
			(start 0.7874 0.4064)
			(end 0.7874 -0.4064)
			(stroke
				(width 0.1524)
				(type default)
			)
			(layer "B.SilkS")
		)
		(fp_line
			(start 0.7874 -0.4064)
			(end -0.7874 -0.4064)
			(stroke
				(width 0.1524)
				(type default)
			)
			(layer "B.SilkS")
		)
		(fp_line
			(start -0.7874 0.4064)
			(end 0.7874 0.4064)
			(stroke
				(width 0.1524)
				(type default)
			)
			(layer "B.SilkS")
		)
		(fp_line
			(start -0.7874 -0.4064)
			(end -0.7874 0.4064)
			(stroke
				(width 0.1524)
				(type default)
			)
			(layer "B.SilkS")
		)
		(fp_line
			(start 0.67945 0.3048)
			(end 0.67945 -0.305054)
			(stroke
				(width 0.1)
				(type default)
			)
			(layer "B.Fab")
		)
		(fp_line
			(start 0.67945 -0.305054)
			(end 0.12065 -0.305054)
			(stroke
				(width 0.1)
				(type default)
			)
			(layer "B.Fab")
		)
		(fp_line
			(start 0.12065 0.3048)
			(end 0.67945 0.3048)
			(stroke
				(width 0.1)
				(type default)
			)
			(layer "B.Fab")
		)
		(fp_line
			(start 0.12065 0.2794)
			(end 0.12065 0.3048)
			(stroke
				(width 0.1)
				(type default)
			)
			(layer "B.Fab")
		)
		(fp_line
			(start 0.12065 -0.2794)
			(end -0.12065 -0.2794)
			(stroke
				(width 0.1)
				(type default)
			)
			(layer "B.Fab")
		)
		(fp_line
			(start 0.12065 -0.305054)
			(end 0.12065 -0.2794)
			(stroke
				(width 0.1)
				(type default)
			)
			(layer "B.Fab")
		)
		(fp_line
			(start -0.120396 0.3048)
			(end -0.120396 0.2794)
			(stroke
				(width 0.1)
				(type default)
			)
			(layer "B.Fab")
		)
		(fp_line
			(start -0.120396 0.2794)
			(end 0.12065 0.2794)
			(stroke
				(width 0.1)
				(type default)
			)
			(layer "B.Fab")
		)
		(fp_line
			(start -0.12065 -0.2794)
			(end -0.12065 -0.3048)
			(stroke
				(width 0.1)
				(type default)
			)
			(layer "B.Fab")
		)
		(fp_line
			(start -0.12065 -0.3048)
			(end -0.67945 -0.3048)
			(stroke
				(width 0.1)
				(type default)
			)
			(layer "B.Fab")
		)
		(fp_line
			(start -0.67945 0.3048)
			(end -0.120396 0.3048)
			(stroke
				(width 0.1)
				(type default)
			)
			(layer "B.Fab")
		)
		(fp_line
			(start -0.67945 -0.3048)
			(end -0.67945 0.3048)
			(stroke
				(width 0.1)
				(type default)
			)
			(layer "B.Fab")
		)
		(pad "1" smd circle
			(at 0.40005 0)
			(size 0 0)
			(layers "B.Cu" "B.Mask" "B.Paste")
			(net "I3C_SPD_DDRAF_CPU0_SCL")
		)
		(pad "2" smd circle
			(at -0.40005 0)
			(size 0 0)
			(layers "B.Cu" "B.Mask" "B.Paste")
			(net "I3C_SPD_DDRC_CPU0_SCL")
		)
	)
	(footprint ""
		(layer "B.Cu")
		(at 90.209878 -145.90141)
		(property "Reference" "C8246"
			(at 0 0 0)
			(layer "B.SilkS")
			(hide yes)
			(effects
				(font
					(size 1.27 1.27)
				)
				(justify mirror)
			)
		)
		(property "Value" ""
			(at 0 0 0)
			(layer "B.Fab")
			(effects
				(font
					(size 1.27 1.27)
				)
				(justify mirror)
			)
		)
		(duplicate_pad_numbers_are_jumpers no)
		(fp_line
			(start -0.7874 -0.4064)
			(end -0.7874 0.4064)
			(stroke
				(width 0.1524)
				(type default)
			)
			(layer "B.SilkS")
		)
		(fp_line
			(start -0.7874 0.4064)
			(end 0.7874 0.4064)
			(stroke
				(width 0.1524)
				(type default)
			)
			(layer "B.SilkS")
		)
		(fp_line
			(start 0.7874 -0.4064)
			(end -0.7874 -0.4064)
			(stroke
				(width 0.1524)
				(type default)
			)
			(layer "B.SilkS")
		)
		(fp_line
			(start 0.7874 0.4064)
			(end 0.7874 -0.4064)
			(stroke
				(width 0.1524)
				(type default)
			)
			(layer "B.SilkS")
		)
		(fp_line
			(start -0.67945 -0.3048)
			(end -0.67945 0.3048)
			(stroke
				(width 0.1)
				(type default)
			)
			(layer "B.Fab")
		)
		(fp_line
			(start -0.67945 0.3048)
			(end -0.120396 0.3048)
			(stroke
				(width 0.1)
				(type default)
			)
			(layer "B.Fab")
		)
		(fp_line
			(start -0.12065 -0.3048)
			(end -0.67945 -0.3048)
			(stroke
				(width 0.1)
				(type default)
			)
			(layer "B.Fab")
		)
		(fp_line
			(start -0.12065 -0.2794)
			(end -0.12065 -0.3048)
			(stroke
				(width 0.1)
				(type default)
			)
			(layer "B.Fab")
		)
		(fp_line
			(start -0.120396 0.2794)
			(end 0.12065 0.2794)
			(stroke
				(width 0.1)
				(type default)
			)
			(layer "B.Fab")
		)
		(fp_line
			(start -0.120396 0.3048)
			(end -0.120396 0.2794)
			(stroke
				(width 0.1)
				(type default)
			)
			(layer "B.Fab")
		)
		(fp_line
			(start 0.12065 -0.305054)
			(end 0.12065 -0.2794)
			(stroke
				(width 0.1)
				(type default)
			)
			(layer "B.Fab")
		)
		(fp_line
			(start 0.12065 -0.2794)
			(end -0.12065 -0.2794)
			(stroke
				(width 0.1)
				(type default)
			)
			(layer "B.Fab")
		)
		(fp_line
			(start 0.12065 0.2794)
			(end 0.12065 0.3048)
			(stroke
				(width 0.1)
				(type default)
			)
			(layer "B.Fab")
		)
		(fp_line
			(start 0.12065 0.3048)
			(end 0.67945 0.3048)
			(stroke
				(width 0.1)
				(type default)
			)
			(layer "B.Fab")
		)
		(fp_line
			(start 0.67945 -0.305054)
			(end 0.12065 -0.305054)
			(stroke
				(width 0.1)
				(type default)
			)
			(layer "B.Fab")
		)
		(fp_line
			(start 0.67945 0.3048)
			(end 0.67945 -0.305054)
			(stroke
				(width 0.1)
				(type default)
			)
			(layer "B.Fab")
		)
		(pad "1" smd circle
			(at 0.40005 0 180)
			(size 0 0)
			(layers "B.Cu" "B.Mask" "B.Paste")
			(net "PWRGD_PVDDCR_SOC_P1_R")
		)
		(pad "2" smd circle
			(at -0.40005 0 180)
			(size 0 0)
			(layers "B.Cu" "B.Mask" "B.Paste")
			(net "GND")
		)
	)
	(footprint ""
		(layer "B.Cu")
		(at 104.716834 -249.368564 180)
		(property "Reference" "C2300"
			(at 0 0 0)
			(layer "B.SilkS")
			(hide yes)
			(effects
				(font
					(size 1.27 1.27)
				)
				(justify mirror)
			)
		)
		(property "Value" ""
			(at 0 0 0)
			(layer "B.Fab")
			(effects
				(font
					(size 1.27 1.27)
				)
				(justify mirror)
			)
		)
		(duplicate_pad_numbers_are_jumpers no)
		(fp_line
			(start 0.7874 0.4064)
			(end 0.7874 -0.4064)
			(stroke
				(width 0.1524)
				(type default)
			)
			(layer "B.SilkS")
		)
		(fp_line
			(start 0.7874 -0.4064)
			(end -0.7874 -0.4064)
			(stroke
				(width 0.1524)
				(type default)
			)
			(layer "B.SilkS")
		)
		(fp_line
			(start -0.7874 0.4064)
			(end 0.7874 0.4064)
			(stroke
				(width 0.1524)
				(type default)
			)
			(layer "B.SilkS")
		)
		(fp_line
			(start -0.7874 -0.4064)
			(end -0.7874 0.4064)
			(stroke
				(width 0.1524)
				(type default)
			)
			(layer "B.SilkS")
		)
		(fp_line
			(start 0.67945 0.3048)
			(end 0.67945 -0.305054)
			(stroke
				(width 0.1)
				(type default)
			)
			(layer "B.Fab")
		)
		(fp_line
			(start 0.67945 -0.305054)
			(end 0.12065 -0.305054)
			(stroke
				(width 0.1)
				(type default)
			)
			(layer "B.Fab")
		)
		(fp_line
			(start 0.12065 0.3048)
			(end 0.67945 0.3048)
			(stroke
				(width 0.1)
				(type default)
			)
			(layer "B.Fab")
		)
		(fp_line
			(start 0.12065 0.2794)
			(end 0.12065 0.3048)
			(stroke
				(width 0.1)
				(type default)
			)
			(layer "B.Fab")
		)
		(fp_line
			(start 0.12065 -0.2794)
			(end -0.12065 -0.2794)
			(stroke
				(width 0.1)
				(type default)
			)
			(layer "B.Fab")
		)
		(fp_line
			(start 0.12065 -0.305054)
			(end 0.12065 -0.2794)
			(stroke
				(width 0.1)
				(type default)
			)
			(layer "B.Fab")
		)
		(fp_line
			(start -0.120396 0.3048)
			(end -0.120396 0.2794)
			(stroke
				(width 0.1)
				(type default)
			)
			(layer "B.Fab")
		)
		(fp_line
			(start -0.120396 0.2794)
			(end 0.12065 0.2794)
			(stroke
				(width 0.1)
				(type default)
			)
			(layer "B.Fab")
		)
		(fp_line
			(start -0.12065 -0.2794)
			(end -0.12065 -0.3048)
			(stroke
				(width 0.1)
				(type default)
			)
			(layer "B.Fab")
		)
		(fp_line
			(start -0.12065 -0.3048)
			(end -0.67945 -0.3048)
			(stroke
				(width 0.1)
				(type default)
			)
			(layer "B.Fab")
		)
		(fp_line
			(start -0.67945 0.3048)
			(end -0.120396 0.3048)
			(stroke
				(width 0.1)
				(type default)
			)
			(layer "B.Fab")
		)
		(fp_line
			(start -0.67945 -0.3048)
			(end -0.67945 0.3048)
			(stroke
				(width 0.1)
				(type default)
			)
			(layer "B.Fab")
		)
		(pad "1" smd circle
			(at 0.40005 0)
			(size 0 0)
			(layers "B.Cu" "B.Mask" "B.Paste")
			(net "PVDDCR_CPU0_P1")
		)
		(pad "2" smd circle
			(at -0.40005 0)
			(size 0 0)
			(layers "B.Cu" "B.Mask" "B.Paste")
			(net "GND")
		)
	)
	(footprint ""
		(layer "B.Cu")
		(at 172.593 -98.135948 90)
		(property "Reference" "R6023"
			(at 0 0 90)
			(layer "B.SilkS")
			(hide yes)
			(effects
				(font
					(size 1.27 1.27)
				)
				(justify mirror)
			)
		)
		(property "Value" ""
			(at 0 0 90)
			(layer "B.Fab")
			(effects
				(font
					(size 1.27 1.27)
				)
				(justify mirror)
			)
		)
		(duplicate_pad_numbers_are_jumpers no)
		(fp_line
			(start 0.7874 -0.4064)
			(end -0.7874 -0.4064)
			(stroke
				(width 0.1524)
				(type default)
			)
			(layer "B.SilkS")
		)
		(fp_line
			(start -0.7874 -0.4064)
			(end -0.7874 0.4064)
			(stroke
				(width 0.1524)
				(type default)
			)
			(layer "B.SilkS")
		)
		(fp_line
			(start 0.7874 0.4064)
			(end 0.7874 -0.4064)
			(stroke
				(width 0.1524)
				(type default)
			)
			(layer "B.SilkS")
		)
		(fp_line
			(start -0.7874 0.4064)
			(end 0.7874 0.4064)
			(stroke
				(width 0.1524)
				(type default)
			)
			(layer "B.SilkS")
		)
		(fp_line
			(start 0.67945 -0.305054)
			(end 0.12065 -0.305054)
			(stroke
				(width 0.1)
				(type default)
			)
			(layer "B.Fab")
		)
		(fp_line
			(start 0.12065 -0.305054)
			(end 0.12065 -0.2794)
			(stroke
				(width 0.1)
				(type default)
			)
			(layer "B.Fab")
		)
		(fp_line
			(start -0.12065 -0.3048)
			(end -0.67945 -0.3048)
			(stroke
				(width 0.1)
				(type default)
			)
			(layer "B.Fab")
		)
		(fp_line
			(start -0.67945 -0.3048)
			(end -0.67945 0.3048)
			(stroke
				(width 0.1)
				(type default)
			)
			(layer "B.Fab")
		)
		(fp_line
			(start 0.12065 -0.2794)
			(end -0.12065 -0.2794)
			(stroke
				(width 0.1)
				(type default)
			)
			(layer "B.Fab")
		)
		(fp_line
			(start -0.12065 -0.2794)
			(end -0.12065 -0.3048)
			(stroke
				(width 0.1)
				(type default)
			)
			(layer "B.Fab")
		)
		(fp_line
			(start 0.12065 0.2794)
			(end 0.12065 0.3048)
			(stroke
				(width 0.1)
				(type default)
			)
			(layer "B.Fab")
		)
		(fp_line
			(start -0.120396 0.2794)
			(end 0.12065 0.2794)
			(stroke
				(width 0.1)
				(type default)
			)
			(layer "B.Fab")
		)
		(fp_line
			(start 0.67945 0.3048)
			(end 0.67945 -0.305054)
			(stroke
				(width 0.1)
				(type default)
			)
			(layer "B.Fab")
		)
		(fp_line
			(start 0.12065 0.3048)
			(end 0.67945 0.3048)
			(stroke
				(width 0.1)
				(type default)
			)
			(layer "B.Fab")
		)
		(fp_line
			(start -0.120396 0.3048)
			(end -0.120396 0.2794)
			(stroke
				(width 0.1)
				(type default)
			)
			(layer "B.Fab")
		)
		(fp_line
			(start -0.67945 0.3048)
			(end -0.120396 0.3048)
			(stroke
				(width 0.1)
				(type default)
			)
			(layer "B.Fab")
		)
		(pad "1" smd circle
			(at 0.40005 0 270)
			(size 0 0)
			(layers "B.Cu" "B.Mask" "B.Paste")
			(net "P3V3_AUX")
		)
		(pad "2" smd circle
			(at -0.40005 0 270)
			(size 0 0)
			(layers "B.Cu" "B.Mask" "B.Paste")
			(net "SGPIO_SCM_LD_<1>")
		)
	)
	(footprint ""
		(layer "B.Cu")
		(at 334.795876 -66.708782 90)
		(property "Reference" "R3091"
			(at 0 0 90)
			(layer "B.SilkS")
			(hide yes)
			(effects
				(font
					(size 1.27 1.27)
				)
				(justify mirror)
			)
		)
		(property "Value" ""
			(at 0 0 90)
			(layer "B.Fab")
			(effects
				(font
					(size 1.27 1.27)
				)
				(justify mirror)
			)
		)
		(duplicate_pad_numbers_are_jumpers no)
		(fp_line
			(start 0.7874 -0.4064)
			(end -0.7874 -0.4064)
			(stroke
				(width 0.1524)
				(type default)
			)
			(layer "B.SilkS")
		)
		(fp_line
			(start -0.7874 -0.4064)
			(end -0.7874 0.4064)
			(stroke
				(width 0.1524)
				(type default)
			)
			(layer "B.SilkS")
		)
		(fp_line
			(start 0.7874 0.4064)
			(end 0.7874 -0.4064)
			(stroke
				(width 0.1524)
				(type default)
			)
			(layer "B.SilkS")
		)
		(fp_line
			(start -0.7874 0.4064)
			(end 0.7874 0.4064)
			(stroke
				(width 0.1524)
				(type default)
			)
			(layer "B.SilkS")
		)
		(fp_line
			(start 0.67945 -0.305054)
			(end 0.12065 -0.305054)
			(stroke
				(width 0.1)
				(type default)
			)
			(layer "B.Fab")
		)
		(fp_line
			(start 0.12065 -0.305054)
			(end 0.12065 -0.2794)
			(stroke
				(width 0.1)
				(type default)
			)
			(layer "B.Fab")
		)
		(fp_line
			(start -0.12065 -0.3048)
			(end -0.67945 -0.3048)
			(stroke
				(width 0.1)
				(type default)
			)
			(layer "B.Fab")
		)
		(fp_line
			(start -0.67945 -0.3048)
			(end -0.67945 0.3048)
			(stroke
				(width 0.1)
				(type default)
			)
			(layer "B.Fab")
		)
		(fp_line
			(start 0.12065 -0.2794)
			(end -0.12065 -0.2794)
			(stroke
				(width 0.1)
				(type default)
			)
			(layer "B.Fab")
		)
		(fp_line
			(start -0.12065 -0.2794)
			(end -0.12065 -0.3048)
			(stroke
				(width 0.1)
				(type default)
			)
			(layer "B.Fab")
		)
		(fp_line
			(start 0.12065 0.2794)
			(end 0.12065 0.3048)
			(stroke
				(width 0.1)
				(type default)
			)
			(layer "B.Fab")
		)
		(fp_line
			(start -0.120396 0.2794)
			(end 0.12065 0.2794)
			(stroke
				(width 0.1)
				(type default)
			)
			(layer "B.Fab")
		)
		(fp_line
			(start 0.67945 0.3048)
			(end 0.67945 -0.305054)
			(stroke
				(width 0.1)
				(type default)
			)
			(layer "B.Fab")
		)
		(fp_line
			(start 0.12065 0.3048)
			(end 0.67945 0.3048)
			(stroke
				(width 0.1)
				(type default)
			)
			(layer "B.Fab")
		)
		(fp_line
			(start -0.120396 0.3048)
			(end -0.120396 0.2794)
			(stroke
				(width 0.1)
				(type default)
			)
			(layer "B.Fab")
		)
		(fp_line
			(start -0.67945 0.3048)
			(end -0.120396 0.3048)
			(stroke
				(width 0.1)
				(type default)
			)
			(layer "B.Fab")
		)
		(pad "1" smd circle
			(at 0.40005 0 270)
			(size 0 0)
			(layers "B.Cu" "B.Mask" "B.Paste")
			(net "LED_PWRGD_PVDD18_S5_P0_R")
		)
		(pad "2" smd circle
			(at -0.40005 0 270)
			(size 0 0)
			(layers "B.Cu" "B.Mask" "B.Paste")
			(net "P3V3_AUX")
		)
	)
	(footprint ""
		(layer "B.Cu")
		(at 151.275034 -201.977752 -90)
		(property "Reference" "C232"
			(at 0 0 90)
			(layer "B.SilkS")
			(hide yes)
			(effects
				(font
					(size 1.27 1.27)
				)
				(justify mirror)
			)
		)
		(property "Value" ""
			(at 0 0 90)
			(layer "B.Fab")
			(effects
				(font
					(size 1.27 1.27)
				)
				(justify mirror)
			)
		)
		(duplicate_pad_numbers_are_jumpers no)
		(fp_line
			(start -0.7874 0.4064)
			(end 0.7874 0.4064)
			(stroke
				(width 0.1524)
				(type default)
			)
			(layer "B.SilkS")
		)
		(fp_line
			(start 0.7874 0.4064)
			(end 0.7874 -0.4064)
			(stroke
				(width 0.1524)
				(type default)
			)
			(layer "B.SilkS")
		)
		(fp_line
			(start -0.7874 -0.4064)
			(end -0.7874 0.4064)
			(stroke
				(width 0.1524)
				(type default)
			)
			(layer "B.SilkS")
		)
		(fp_line
			(start 0.7874 -0.4064)
			(end -0.7874 -0.4064)
			(stroke
				(width 0.1524)
				(type default)
			)
			(layer "B.SilkS")
		)
		(fp_line
			(start -0.67945 0.3048)
			(end -0.120396 0.3048)
			(stroke
				(width 0.1)
				(type default)
			)
			(layer "B.Fab")
		)
		(fp_line
			(start -0.120396 0.3048)
			(end -0.120396 0.2794)
			(stroke
				(width 0.1)
				(type default)
			)
			(layer "B.Fab")
		)
		(fp_line
			(start 0.12065 0.3048)
			(end 0.67945 0.3048)
			(stroke
				(width 0.1)
				(type default)
			)
			(layer "B.Fab")
		)
		(fp_line
			(start 0.67945 0.3048)
			(end 0.67945 -0.305054)
			(stroke
				(width 0.1)
				(type default)
			)
			(layer "B.Fab")
		)
		(fp_line
			(start -0.120396 0.2794)
			(end 0.12065 0.2794)
			(stroke
				(width 0.1)
				(type default)
			)
			(layer "B.Fab")
		)
		(fp_line
			(start 0.12065 0.2794)
			(end 0.12065 0.3048)
			(stroke
				(width 0.1)
				(type default)
			)
			(layer "B.Fab")
		)
		(fp_line
			(start -0.12065 -0.2794)
			(end -0.12065 -0.3048)
			(stroke
				(width 0.1)
				(type default)
			)
			(layer "B.Fab")
		)
		(fp_line
			(start 0.12065 -0.2794)
			(end -0.12065 -0.2794)
			(stroke
				(width 0.1)
				(type default)
			)
			(layer "B.Fab")
		)
		(fp_line
			(start -0.67945 -0.3048)
			(end -0.67945 0.3048)
			(stroke
				(width 0.1)
				(type default)
			)
			(layer "B.Fab")
		)
		(fp_line
			(start -0.12065 -0.3048)
			(end -0.67945 -0.3048)
			(stroke
				(width 0.1)
				(type default)
			)
			(layer "B.Fab")
		)
		(fp_line
			(start 0.12065 -0.305054)
			(end 0.12065 -0.2794)
			(stroke
				(width 0.1)
				(type default)
			)
			(layer "B.Fab")
		)
		(fp_line
			(start 0.67945 -0.305054)
			(end 0.12065 -0.305054)
			(stroke
				(width 0.1)
				(type default)
			)
			(layer "B.Fab")
		)
		(pad "1" smd circle
			(at 0.40005 0 90)
			(size 0 0)
			(layers "B.Cu" "B.Mask" "B.Paste")
			(net "JTAG_CPU1_TRST_N")
		)
		(pad "2" smd circle
			(at -0.40005 0 90)
			(size 0 0)
			(layers "B.Cu" "B.Mask" "B.Paste")
			(net "GND")
		)
	)
	(footprint ""
		(layer "B.Cu")
		(at 53.391308 -390.560052 90)
		(property "Reference" "C256"
			(at 0 0 90)
			(layer "B.SilkS")
			(hide yes)
			(effects
				(font
					(size 1.27 1.27)
				)
				(justify mirror)
			)
		)
		(property "Value" ""
			(at 0 0 90)
			(layer "B.Fab")
			(effects
				(font
					(size 1.27 1.27)
				)
				(justify mirror)
			)
		)
		(duplicate_pad_numbers_are_jumpers no)
		(fp_line
			(start 0.7874 -0.4064)
			(end -0.7874 -0.4064)
			(stroke
				(width 0.1524)
				(type default)
			)
			(layer "B.SilkS")
		)
		(fp_line
			(start -0.7874 -0.4064)
			(end -0.7874 0.4064)
			(stroke
				(width 0.1524)
				(type default)
			)
			(layer "B.SilkS")
		)
		(fp_line
			(start 0.7874 0.4064)
			(end 0.7874 -0.4064)
			(stroke
				(width 0.1524)
				(type default)
			)
			(layer "B.SilkS")
		)
		(fp_line
			(start -0.7874 0.4064)
			(end 0.7874 0.4064)
			(stroke
				(width 0.1524)
				(type default)
			)
			(layer "B.SilkS")
		)
		(fp_line
			(start 0.67945 -0.305054)
			(end 0.12065 -0.305054)
			(stroke
				(width 0.1)
				(type default)
			)
			(layer "B.Fab")
		)
		(fp_line
			(start 0.12065 -0.305054)
			(end 0.12065 -0.2794)
			(stroke
				(width 0.1)
				(type default)
			)
			(layer "B.Fab")
		)
		(fp_line
			(start -0.12065 -0.3048)
			(end -0.67945 -0.3048)
			(stroke
				(width 0.1)
				(type default)
			)
			(layer "B.Fab")
		)
		(fp_line
			(start -0.67945 -0.3048)
			(end -0.67945 0.3048)
			(stroke
				(width 0.1)
				(type default)
			)
			(layer "B.Fab")
		)
		(fp_line
			(start 0.12065 -0.2794)
			(end -0.12065 -0.2794)
			(stroke
				(width 0.1)
				(type default)
			)
			(layer "B.Fab")
		)
		(fp_line
			(start -0.12065 -0.2794)
			(end -0.12065 -0.3048)
			(stroke
				(width 0.1)
				(type default)
			)
			(layer "B.Fab")
		)
		(fp_line
			(start 0.12065 0.2794)
			(end 0.12065 0.3048)
			(stroke
				(width 0.1)
				(type default)
			)
			(layer "B.Fab")
		)
		(fp_line
			(start -0.120396 0.2794)
			(end 0.12065 0.2794)
			(stroke
				(width 0.1)
				(type default)
			)
			(layer "B.Fab")
		)
		(fp_line
			(start 0.67945 0.3048)
			(end 0.67945 -0.305054)
			(stroke
				(width 0.1)
				(type default)
			)
			(layer "B.Fab")
		)
		(fp_line
			(start 0.12065 0.3048)
			(end 0.67945 0.3048)
			(stroke
				(width 0.1)
				(type default)
			)
			(layer "B.Fab")
		)
		(fp_line
			(start -0.120396 0.3048)
			(end -0.120396 0.2794)
			(stroke
				(width 0.1)
				(type default)
			)
			(layer "B.Fab")
		)
		(fp_line
			(start -0.67945 0.3048)
			(end -0.120396 0.3048)
			(stroke
				(width 0.1)
				(type default)
			)
			(layer "B.Fab")
		)
		(pad "1" smd circle
			(at 0.40005 0 270)
			(size 0 0)
			(layers "B.Cu" "B.Mask" "B.Paste")
			(net "P0V9_CPU1_RT_2D")
		)
		(pad "2" smd circle
			(at -0.40005 0 270)
			(size 0 0)
			(layers "B.Cu" "B.Mask" "B.Paste")
			(net "GND")
		)
	)
	(footprint ""
		(layer "B.Cu")
		(at 22.479 -363.347 180)
		(property "Reference" "R240"
			(at 0 0 0)
			(layer "B.SilkS")
			(hide yes)
			(effects
				(font
					(size 1.27 1.27)
				)
				(justify mirror)
			)
		)
		(property "Value" ""
			(at 0 0 0)
			(layer "B.Fab")
			(effects
				(font
					(size 1.27 1.27)
				)
				(justify mirror)
			)
		)
		(duplicate_pad_numbers_are_jumpers no)
		(fp_line
			(start 0.7874 0.4064)
			(end 0.7874 -0.4064)
			(stroke
				(width 0.1524)
				(type default)
			)
			(layer "B.SilkS")
		)
		(fp_line
			(start 0.7874 -0.4064)
			(end -0.7874 -0.4064)
			(stroke
				(width 0.1524)
				(type default)
			)
			(layer "B.SilkS")
		)
		(fp_line
			(start -0.7874 0.4064)
			(end 0.7874 0.4064)
			(stroke
				(width 0.1524)
				(type default)
			)
			(layer "B.SilkS")
		)
		(fp_line
			(start -0.7874 -0.4064)
			(end -0.7874 0.4064)
			(stroke
				(width 0.1524)
				(type default)
			)
			(layer "B.SilkS")
		)
		(fp_line
			(start 0.67945 0.3048)
			(end 0.67945 -0.305054)
			(stroke
				(width 0.1)
				(type default)
			)
			(layer "B.Fab")
		)
		(fp_line
			(start 0.67945 -0.305054)
			(end 0.12065 -0.305054)
			(stroke
				(width 0.1)
				(type default)
			)
			(layer "B.Fab")
		)
		(fp_line
			(start 0.12065 0.3048)
			(end 0.67945 0.3048)
			(stroke
				(width 0.1)
				(type default)
			)
			(layer "B.Fab")
		)
		(fp_line
			(start 0.12065 0.2794)
			(end 0.12065 0.3048)
			(stroke
				(width 0.1)
				(type default)
			)
			(layer "B.Fab")
		)
		(fp_line
			(start 0.12065 -0.2794)
			(end -0.12065 -0.2794)
			(stroke
				(width 0.1)
				(type default)
			)
			(layer "B.Fab")
		)
		(fp_line
			(start 0.12065 -0.305054)
			(end 0.12065 -0.2794)
			(stroke
				(width 0.1)
				(type default)
			)
			(layer "B.Fab")
		)
		(fp_line
			(start -0.120396 0.3048)
			(end -0.120396 0.2794)
			(stroke
				(width 0.1)
				(type default)
			)
			(layer "B.Fab")
		)
		(fp_line
			(start -0.120396 0.2794)
			(end 0.12065 0.2794)
			(stroke
				(width 0.1)
				(type default)
			)
			(layer "B.Fab")
		)
		(fp_line
			(start -0.12065 -0.2794)
			(end -0.12065 -0.3048)
			(stroke
				(width 0.1)
				(type default)
			)
			(layer "B.Fab")
		)
		(fp_line
			(start -0.12065 -0.3048)
			(end -0.67945 -0.3048)
			(stroke
				(width 0.1)
				(type default)
			)
			(layer "B.Fab")
		)
		(fp_line
			(start -0.67945 0.3048)
			(end -0.120396 0.3048)
			(stroke
				(width 0.1)
				(type default)
			)
			(layer "B.Fab")
		)
		(fp_line
			(start -0.67945 -0.3048)
			(end -0.67945 0.3048)
			(stroke
				(width 0.1)
				(type default)
			)
			(layer "B.Fab")
		)
		(pad "1" smd circle
			(at 0.40005 0)
			(size 0 0)
			(layers "B.Cu" "B.Mask" "B.Paste")
			(net "PVDDCR_CPU1_P1_RESET_N")
		)
		(pad "2" smd circle
			(at -0.40005 0)
			(size 0 0)
			(layers "B.Cu" "B.Mask" "B.Paste")
			(net "PVDDCR_CPU1_P1_RESET_N_R")
		)
	)
	(footprint ""
		(layer "B.Cu")
		(at 88.138 -146.939 180)
		(property "Reference" "PR8010"
			(at 0 0 0)
			(layer "B.SilkS")
			(hide yes)
			(effects
				(font
					(size 1.27 1.27)
				)
				(justify mirror)
			)
		)
		(property "Value" ""
			(at 0 0 0)
			(layer "B.Fab")
			(effects
				(font
					(size 1.27 1.27)
				)
				(justify mirror)
			)
		)
		(duplicate_pad_numbers_are_jumpers no)
		(fp_line
			(start 0.7874 0.4064)
			(end 0.7874 -0.4064)
			(stroke
				(width 0.1524)
				(type default)
			)
			(layer "B.SilkS")
		)
		(fp_line
			(start 0.7874 -0.4064)
			(end -0.7874 -0.4064)
			(stroke
				(width 0.1524)
				(type default)
			)
			(layer "B.SilkS")
		)
		(fp_line
			(start -0.7874 0.4064)
			(end 0.7874 0.4064)
			(stroke
				(width 0.1524)
				(type default)
			)
			(layer "B.SilkS")
		)
		(fp_line
			(start -0.7874 -0.4064)
			(end -0.7874 0.4064)
			(stroke
				(width 0.1524)
				(type default)
			)
			(layer "B.SilkS")
		)
		(fp_line
			(start 0.67945 0.3048)
			(end 0.67945 -0.305054)
			(stroke
				(width 0.1)
				(type default)
			)
			(layer "B.Fab")
		)
		(fp_line
			(start 0.67945 -0.305054)
			(end 0.12065 -0.305054)
			(stroke
				(width 0.1)
				(type default)
			)
			(layer "B.Fab")
		)
		(fp_line
			(start 0.12065 0.3048)
			(end 0.67945 0.3048)
			(stroke
				(width 0.1)
				(type default)
			)
			(layer "B.Fab")
		)
		(fp_line
			(start 0.12065 0.2794)
			(end 0.12065 0.3048)
			(stroke
				(width 0.1)
				(type default)
			)
			(layer "B.Fab")
		)
		(fp_line
			(start 0.12065 -0.2794)
			(end -0.12065 -0.2794)
			(stroke
				(width 0.1)
				(type default)
			)
			(layer "B.Fab")
		)
		(fp_line
			(start 0.12065 -0.305054)
			(end 0.12065 -0.2794)
			(stroke
				(width 0.1)
				(type default)
			)
			(layer "B.Fab")
		)
		(fp_line
			(start -0.120396 0.3048)
			(end -0.120396 0.2794)
			(stroke
				(width 0.1)
				(type default)
			)
			(layer "B.Fab")
		)
		(fp_line
			(start -0.120396 0.2794)
			(end 0.12065 0.2794)
			(stroke
				(width 0.1)
				(type default)
			)
			(layer "B.Fab")
		)
		(fp_line
			(start -0.12065 -0.2794)
			(end -0.12065 -0.3048)
			(stroke
				(width 0.1)
				(type default)
			)
			(layer "B.Fab")
		)
		(fp_line
			(start -0.12065 -0.3048)
			(end -0.67945 -0.3048)
			(stroke
				(width 0.1)
				(type default)
			)
			(layer "B.Fab")
		)
		(fp_line
			(start -0.67945 0.3048)
			(end -0.120396 0.3048)
			(stroke
				(width 0.1)
				(type default)
			)
			(layer "B.Fab")
		)
		(fp_line
			(start -0.67945 -0.3048)
			(end -0.67945 0.3048)
			(stroke
				(width 0.1)
				(type default)
			)
			(layer "B.Fab")
		)
		(pad "1" smd circle
			(at 0.40005 0)
			(size 0 0)
			(layers "B.Cu" "B.Mask" "B.Paste")
			(net "SVID_PVDDCR_CPU0_P1_SVD_R")
		)
		(pad "2" smd circle
			(at -0.40005 0)
			(size 0 0)
			(layers "B.Cu" "B.Mask" "B.Paste")
			(net "SVID_PVDDCR_CPU0_P1_SVD_R1")
		)
	)
	(footprint ""
		(layer "B.Cu")
		(at 68.916296 -387.084062 -90)
		(property "Reference" "C114"
			(at 0 0 90)
			(layer "B.SilkS")
			(hide yes)
			(effects
				(font
					(size 1.27 1.27)
				)
				(justify mirror)
			)
		)
		(property "Value" ""
			(at 0 0 90)
			(layer "B.Fab")
			(effects
				(font
					(size 1.27 1.27)
				)
				(justify mirror)
			)
		)
		(duplicate_pad_numbers_are_jumpers no)
		(fp_line
			(start -1.524 0.762)
			(end 1.524 0.762)
			(stroke
				(width 0.1524)
				(type default)
			)
			(layer "B.SilkS")
		)
		(fp_line
			(start 1.524 0.762)
			(end 1.524 -0.762)
			(stroke
				(width 0.1524)
				(type default)
			)
			(layer "B.SilkS")
		)
		(fp_line
			(start -1.524 -0.762)
			(end -1.524 0.762)
			(stroke
				(width 0.1524)
				(type default)
			)
			(layer "B.SilkS")
		)
		(fp_line
			(start 1.524 -0.762)
			(end -1.524 -0.762)
			(stroke
				(width 0.1524)
				(type default)
			)
			(layer "B.SilkS")
		)
		(fp_line
			(start -1.1049 0.724916)
			(end -1.1049 -0.724916)
			(stroke
				(width 0.1)
				(type default)
			)
			(layer "B.Fab")
		)
		(fp_line
			(start 1.1049 0.724916)
			(end -1.1049 0.724916)
			(stroke
				(width 0.1)
				(type default)
			)
			(layer "B.Fab")
		)
		(fp_line
			(start -1.1049 -0.724916)
			(end 1.1049 -0.724916)
			(stroke
				(width 0.1)
				(type default)
			)
			(layer "B.Fab")
		)
		(fp_line
			(start 1.1049 -0.724916)
			(end 1.1049 0.724916)
			(stroke
				(width 0.1)
				(type default)
			)
			(layer "B.Fab")
		)
		(pad "1" smd rect
			(at 0.889 0 270)
			(size 1.016 1.27)
			(layers "B.Cu" "B.Mask" "B.Paste")
			(net "P1V8_CPU1_RT0_1A")
		)
		(pad "2" smd rect
			(at -0.889 0 270)
			(size 1.016 1.27)
			(layers "B.Cu" "B.Mask" "B.Paste")
			(net "GND")
		)
	)
	(footprint ""
		(layer "B.Cu")
		(at 164.42817 -192.66027 180)
		(property "Reference" "C531"
			(at 0 0 0)
			(layer "B.SilkS")
			(hide yes)
			(effects
				(font
					(size 1.27 1.27)
				)
				(justify mirror)
			)
		)
		(property "Value" ""
			(at 0 0 0)
			(layer "B.Fab")
			(effects
				(font
					(size 1.27 1.27)
				)
				(justify mirror)
			)
		)
		(duplicate_pad_numbers_are_jumpers no)
		(fp_line
			(start 1.524 0.762)
			(end 1.524 -0.762)
			(stroke
				(width 0.1524)
				(type default)
			)
			(layer "B.SilkS")
		)
		(fp_line
			(start 1.524 -0.762)
			(end -1.524 -0.762)
			(stroke
				(width 0.1524)
				(type default)
			)
			(layer "B.SilkS")
		)
		(fp_line
			(start -1.524 0.762)
			(end 1.524 0.762)
			(stroke
				(width 0.1524)
				(type default)
			)
			(layer "B.SilkS")
		)
		(fp_line
			(start -1.524 -0.762)
			(end -1.524 0.762)
			(stroke
				(width 0.1524)
				(type default)
			)
			(layer "B.SilkS")
		)
		(fp_line
			(start 1.1049 0.724916)
			(end -1.1049 0.724916)
			(stroke
				(width 0.1)
				(type default)
			)
			(layer "B.Fab")
		)
		(fp_line
			(start 1.1049 -0.724916)
			(end 1.1049 0.724916)
			(stroke
				(width 0.1)
				(type default)
			)
			(layer "B.Fab")
		)
		(fp_line
			(start -1.1049 0.724916)
			(end -1.1049 -0.724916)
			(stroke
				(width 0.1)
				(type default)
			)
			(layer "B.Fab")
		)
		(fp_line
			(start -1.1049 -0.724916)
			(end 1.1049 -0.724916)
			(stroke
				(width 0.1)
				(type default)
			)
			(layer "B.Fab")
		)
		(pad "1" smd rect
			(at 0.889 0 180)
			(size 1.016 1.27)
			(layers "B.Cu" "B.Mask" "B.Paste")
			(net "P12V_MEM_CPU1")
		)
		(pad "2" smd rect
			(at -0.889 0 180)
			(size 1.016 1.27)
			(layers "B.Cu" "B.Mask" "B.Paste")
			(net "GND")
		)
	)
	(footprint ""
		(layer "B.Cu")
		(at 49.791366 -390.560052 90)
		(property "Reference" "C227"
			(at 0 0 90)
			(layer "B.SilkS")
			(hide yes)
			(effects
				(font
					(size 1.27 1.27)
				)
				(justify mirror)
			)
		)
		(property "Value" ""
			(at 0 0 90)
			(layer "B.Fab")
			(effects
				(font
					(size 1.27 1.27)
				)
				(justify mirror)
			)
		)
		(duplicate_pad_numbers_are_jumpers no)
		(fp_line
			(start 0.7874 -0.4064)
			(end -0.7874 -0.4064)
			(stroke
				(width 0.1524)
				(type default)
			)
			(layer "B.SilkS")
		)
		(fp_line
			(start -0.7874 -0.4064)
			(end -0.7874 0.4064)
			(stroke
				(width 0.1524)
				(type default)
			)
			(layer "B.SilkS")
		)
		(fp_line
			(start 0.7874 0.4064)
			(end 0.7874 -0.4064)
			(stroke
				(width 0.1524)
				(type default)
			)
			(layer "B.SilkS")
		)
		(fp_line
			(start -0.7874 0.4064)
			(end 0.7874 0.4064)
			(stroke
				(width 0.1524)
				(type default)
			)
			(layer "B.SilkS")
		)
		(fp_line
			(start 0.67945 -0.305054)
			(end 0.12065 -0.305054)
			(stroke
				(width 0.1)
				(type default)
			)
			(layer "B.Fab")
		)
		(fp_line
			(start 0.12065 -0.305054)
			(end 0.12065 -0.2794)
			(stroke
				(width 0.1)
				(type default)
			)
			(layer "B.Fab")
		)
		(fp_line
			(start -0.12065 -0.3048)
			(end -0.67945 -0.3048)
			(stroke
				(width 0.1)
				(type default)
			)
			(layer "B.Fab")
		)
		(fp_line
			(start -0.67945 -0.3048)
			(end -0.67945 0.3048)
			(stroke
				(width 0.1)
				(type default)
			)
			(layer "B.Fab")
		)
		(fp_line
			(start 0.12065 -0.2794)
			(end -0.12065 -0.2794)
			(stroke
				(width 0.1)
				(type default)
			)
			(layer "B.Fab")
		)
		(fp_line
			(start -0.12065 -0.2794)
			(end -0.12065 -0.3048)
			(stroke
				(width 0.1)
				(type default)
			)
			(layer "B.Fab")
		)
		(fp_line
			(start 0.12065 0.2794)
			(end 0.12065 0.3048)
			(stroke
				(width 0.1)
				(type default)
			)
			(layer "B.Fab")
		)
		(fp_line
			(start -0.120396 0.2794)
			(end 0.12065 0.2794)
			(stroke
				(width 0.1)
				(type default)
			)
			(layer "B.Fab")
		)
		(fp_line
			(start 0.67945 0.3048)
			(end 0.67945 -0.305054)
			(stroke
				(width 0.1)
				(type default)
			)
			(layer "B.Fab")
		)
		(fp_line
			(start 0.12065 0.3048)
			(end 0.67945 0.3048)
			(stroke
				(width 0.1)
				(type default)
			)
			(layer "B.Fab")
		)
		(fp_line
			(start -0.120396 0.3048)
			(end -0.120396 0.2794)
			(stroke
				(width 0.1)
				(type default)
			)
			(layer "B.Fab")
		)
		(fp_line
			(start -0.67945 0.3048)
			(end -0.120396 0.3048)
			(stroke
				(width 0.1)
				(type default)
			)
			(layer "B.Fab")
		)
		(pad "1" smd circle
			(at 0.40005 0 270)
			(size 0 0)
			(layers "B.Cu" "B.Mask" "B.Paste")
			(net "P0V9_CPU1_RT0_2A")
		)
		(pad "2" smd circle
			(at -0.40005 0 270)
			(size 0 0)
			(layers "B.Cu" "B.Mask" "B.Paste")
			(net "GND")
		)
	)
	(footprint ""
		(layer "B.Cu")
		(at 216.027 -335.153 90)
		(property "Reference" "R6719"
			(at 0 0 90)
			(layer "B.SilkS")
			(hide yes)
			(effects
				(font
					(size 1.27 1.27)
				)
				(justify mirror)
			)
		)
		(property "Value" ""
			(at 0 0 90)
			(layer "B.Fab")
			(effects
				(font
					(size 1.27 1.27)
				)
				(justify mirror)
			)
		)
		(duplicate_pad_numbers_are_jumpers no)
		(fp_line
			(start 0.32512 -0.175006)
			(end -0.32512 -0.175006)
			(stroke
				(width 0.1)
				(type default)
			)
			(layer "B.Fab")
		)
		(fp_line
			(start -0.32512 -0.175006)
			(end -0.32512 0.175006)
			(stroke
				(width 0.1)
				(type default)
			)
			(layer "B.Fab")
		)
		(fp_line
			(start 0.32512 0.175006)
			(end 0.32512 -0.175006)
			(stroke
				(width 0.1)
				(type default)
			)
			(layer "B.Fab")
		)
		(fp_line
			(start -0.32512 0.175006)
			(end 0.32512 0.175006)
			(stroke
				(width 0.1)
				(type default)
			)
			(layer "B.Fab")
		)
		(pad "1" smd rect
			(at 0.2667 0 270)
			(size 0.3048 0.381)
			(layers "B.Cu" "B.Mask" "B.Paste")
			(net "P1V8_CPU1_RT_1D")
		)
		(pad "2" smd rect
			(at -0.2667 0 90)
			(size 0.3048 0.381)
			(layers "B.Cu" "B.Mask" "B.Paste")
			(net "SMB_RT_CPU1_P0_R_SCL")
		)
	)
	(footprint ""
		(layer "B.Cu")
		(at 354.152454 -253.43231)
		(property "Reference" "C2569"
			(at 0 0 0)
			(layer "B.SilkS")
			(hide yes)
			(effects
				(font
					(size 1.27 1.27)
				)
				(justify mirror)
			)
		)
		(property "Value" ""
			(at 0 0 0)
			(layer "B.Fab")
			(effects
				(font
					(size 1.27 1.27)
				)
				(justify mirror)
			)
		)
		(duplicate_pad_numbers_are_jumpers no)
		(fp_line
			(start -0.7874 -0.4064)
			(end -0.7874 0.4064)
			(stroke
				(width 0.1524)
				(type default)
			)
			(layer "B.SilkS")
		)
		(fp_line
			(start -0.7874 0.4064)
			(end 0.7874 0.4064)
			(stroke
				(width 0.1524)
				(type default)
			)
			(layer "B.SilkS")
		)
		(fp_line
			(start 0.7874 -0.4064)
			(end -0.7874 -0.4064)
			(stroke
				(width 0.1524)
				(type default)
			)
			(layer "B.SilkS")
		)
		(fp_line
			(start 0.7874 0.4064)
			(end 0.7874 -0.4064)
			(stroke
				(width 0.1524)
				(type default)
			)
			(layer "B.SilkS")
		)
		(fp_line
			(start -0.67945 -0.3048)
			(end -0.67945 0.3048)
			(stroke
				(width 0.1)
				(type default)
			)
			(layer "B.Fab")
		)
		(fp_line
			(start -0.67945 0.3048)
			(end -0.120396 0.3048)
			(stroke
				(width 0.1)
				(type default)
			)
			(layer "B.Fab")
		)
		(fp_line
			(start -0.12065 -0.3048)
			(end -0.67945 -0.3048)
			(stroke
				(width 0.1)
				(type default)
			)
			(layer "B.Fab")
		)
		(fp_line
			(start -0.12065 -0.2794)
			(end -0.12065 -0.3048)
			(stroke
				(width 0.1)
				(type default)
			)
			(layer "B.Fab")
		)
		(fp_line
			(start -0.120396 0.2794)
			(end 0.12065 0.2794)
			(stroke
				(width 0.1)
				(type default)
			)
			(layer "B.Fab")
		)
		(fp_line
			(start -0.120396 0.3048)
			(end -0.120396 0.2794)
			(stroke
				(width 0.1)
				(type default)
			)
			(layer "B.Fab")
		)
		(fp_line
			(start 0.12065 -0.305054)
			(end 0.12065 -0.2794)
			(stroke
				(width 0.1)
				(type default)
			)
			(layer "B.Fab")
		)
		(fp_line
			(start 0.12065 -0.2794)
			(end -0.12065 -0.2794)
			(stroke
				(width 0.1)
				(type default)
			)
			(layer "B.Fab")
		)
		(fp_line
			(start 0.12065 0.2794)
			(end 0.12065 0.3048)
			(stroke
				(width 0.1)
				(type default)
			)
			(layer "B.Fab")
		)
		(fp_line
			(start 0.12065 0.3048)
			(end 0.67945 0.3048)
			(stroke
				(width 0.1)
				(type default)
			)
			(layer "B.Fab")
		)
		(fp_line
			(start 0.67945 -0.305054)
			(end 0.12065 -0.305054)
			(stroke
				(width 0.1)
				(type default)
			)
			(layer "B.Fab")
		)
		(fp_line
			(start 0.67945 0.3048)
			(end 0.67945 -0.305054)
			(stroke
				(width 0.1)
				(type default)
			)
			(layer "B.Fab")
		)
		(pad "1" smd circle
			(at 0.40005 0 180)
			(size 0 0)
			(layers "B.Cu" "B.Mask" "B.Paste")
			(net "PVDDCR_SOC_P0")
		)
		(pad "2" smd circle
			(at -0.40005 0 180)
			(size 0 0)
			(layers "B.Cu" "B.Mask" "B.Paste")
			(net "GND")
		)
	)
	(footprint ""
		(layer "B.Cu")
		(at 134.262114 -32.818578 180)
		(property "Reference" "C6053"
			(at 0 0 0)
			(layer "B.SilkS")
			(hide yes)
			(effects
				(font
					(size 1.27 1.27)
				)
				(justify mirror)
			)
		)
		(property "Value" ""
			(at 0 0 0)
			(layer "B.Fab")
			(effects
				(font
					(size 1.27 1.27)
				)
				(justify mirror)
			)
		)
		(duplicate_pad_numbers_are_jumpers no)
		(fp_line
			(start 0.7874 0.4064)
			(end 0.7874 -0.4064)
			(stroke
				(width 0.1524)
				(type default)
			)
			(layer "B.SilkS")
		)
		(fp_line
			(start 0.7874 -0.4064)
			(end -0.7874 -0.4064)
			(stroke
				(width 0.1524)
				(type default)
			)
			(layer "B.SilkS")
		)
		(fp_line
			(start -0.7874 0.4064)
			(end 0.7874 0.4064)
			(stroke
				(width 0.1524)
				(type default)
			)
			(layer "B.SilkS")
		)
		(fp_line
			(start -0.7874 -0.4064)
			(end -0.7874 0.4064)
			(stroke
				(width 0.1524)
				(type default)
			)
			(layer "B.SilkS")
		)
		(fp_line
			(start 0.67945 0.3048)
			(end 0.67945 -0.305054)
			(stroke
				(width 0.1)
				(type default)
			)
			(layer "B.Fab")
		)
		(fp_line
			(start 0.67945 -0.305054)
			(end 0.12065 -0.305054)
			(stroke
				(width 0.1)
				(type default)
			)
			(layer "B.Fab")
		)
		(fp_line
			(start 0.12065 0.3048)
			(end 0.67945 0.3048)
			(stroke
				(width 0.1)
				(type default)
			)
			(layer "B.Fab")
		)
		(fp_line
			(start 0.12065 0.2794)
			(end 0.12065 0.3048)
			(stroke
				(width 0.1)
				(type default)
			)
			(layer "B.Fab")
		)
		(fp_line
			(start 0.12065 -0.2794)
			(end -0.12065 -0.2794)
			(stroke
				(width 0.1)
				(type default)
			)
			(layer "B.Fab")
		)
		(fp_line
			(start 0.12065 -0.305054)
			(end 0.12065 -0.2794)
			(stroke
				(width 0.1)
				(type default)
			)
			(layer "B.Fab")
		)
		(fp_line
			(start -0.120396 0.3048)
			(end -0.120396 0.2794)
			(stroke
				(width 0.1)
				(type default)
			)
			(layer "B.Fab")
		)
		(fp_line
			(start -0.120396 0.2794)
			(end 0.12065 0.2794)
			(stroke
				(width 0.1)
				(type default)
			)
			(layer "B.Fab")
		)
		(fp_line
			(start -0.12065 -0.2794)
			(end -0.12065 -0.3048)
			(stroke
				(width 0.1)
				(type default)
			)
			(layer "B.Fab")
		)
		(fp_line
			(start -0.12065 -0.3048)
			(end -0.67945 -0.3048)
			(stroke
				(width 0.1)
				(type default)
			)
			(layer "B.Fab")
		)
		(fp_line
			(start -0.67945 0.3048)
			(end -0.120396 0.3048)
			(stroke
				(width 0.1)
				(type default)
			)
			(layer "B.Fab")
		)
		(fp_line
			(start -0.67945 -0.3048)
			(end -0.67945 0.3048)
			(stroke
				(width 0.1)
				(type default)
			)
			(layer "B.Fab")
		)
		(pad "1" smd circle
			(at 0.40005 0)
			(size 0 0)
			(layers "B.Cu" "B.Mask" "B.Paste")
			(net "P3V3_AUX")
		)
		(pad "2" smd circle
			(at -0.40005 0)
			(size 0 0)
			(layers "B.Cu" "B.Mask" "B.Paste")
			(net "GND")
		)
	)
	(footprint ""
		(layer "B.Cu")
		(at 325.861426 -400.19605 180)
		(property "Reference" "C550"
			(at 0 0 0)
			(layer "B.SilkS")
			(hide yes)
			(effects
				(font
					(size 1.27 1.27)
				)
				(justify mirror)
			)
		)
		(property "Value" ""
			(at 0 0 0)
			(layer "B.Fab")
			(effects
				(font
					(size 1.27 1.27)
				)
				(justify mirror)
			)
		)
		(duplicate_pad_numbers_are_jumpers no)
		(fp_line
			(start 1.524 0.762)
			(end 1.524 -0.762)
			(stroke
				(width 0.1524)
				(type default)
			)
			(layer "B.SilkS")
		)
		(fp_line
			(start 1.524 -0.762)
			(end -1.524 -0.762)
			(stroke
				(width 0.1524)
				(type default)
			)
			(layer "B.SilkS")
		)
		(fp_line
			(start -1.524 0.762)
			(end 1.524 0.762)
			(stroke
				(width 0.1524)
				(type default)
			)
			(layer "B.SilkS")
		)
		(fp_line
			(start -1.524 -0.762)
			(end -1.524 0.762)
			(stroke
				(width 0.1524)
				(type default)
			)
			(layer "B.SilkS")
		)
		(fp_line
			(start 1.1049 0.724916)
			(end -1.1049 0.724916)
			(stroke
				(width 0.1)
				(type default)
			)
			(layer "B.Fab")
		)
		(fp_line
			(start 1.1049 -0.724916)
			(end 1.1049 0.724916)
			(stroke
				(width 0.1)
				(type default)
			)
			(layer "B.Fab")
		)
		(fp_line
			(start -1.1049 0.724916)
			(end -1.1049 -0.724916)
			(stroke
				(width 0.1)
				(type default)
			)
			(layer "B.Fab")
		)
		(fp_line
			(start -1.1049 -0.724916)
			(end 1.1049 -0.724916)
			(stroke
				(width 0.1)
				(type default)
			)
			(layer "B.Fab")
		)
		(pad "1" smd rect
			(at 0.889 0 180)
			(size 1.016 1.27)
			(layers "B.Cu" "B.Mask" "B.Paste")
			(net "P0V9_CPU0_RT0_2A")
		)
		(pad "2" smd rect
			(at -0.889 0 180)
			(size 1.016 1.27)
			(layers "B.Cu" "B.Mask" "B.Paste")
			(net "GND")
		)
	)
	(footprint ""
		(layer "B.Cu")
		(at 178.241452 -133.2738)
		(property "Reference" "R16"
			(at 0 0 0)
			(layer "B.SilkS")
			(hide yes)
			(effects
				(font
					(size 1.27 1.27)
				)
				(justify mirror)
			)
		)
		(property "Value" ""
			(at 0 0 0)
			(layer "B.Fab")
			(effects
				(font
					(size 1.27 1.27)
				)
				(justify mirror)
			)
		)
		(duplicate_pad_numbers_are_jumpers no)
		(fp_line
			(start -0.7874 -0.4064)
			(end -0.7874 0.4064)
			(stroke
				(width 0.1524)
				(type default)
			)
			(layer "B.SilkS")
		)
		(fp_line
			(start -0.7874 0.4064)
			(end 0.7874 0.4064)
			(stroke
				(width 0.1524)
				(type default)
			)
			(layer "B.SilkS")
		)
		(fp_line
			(start 0.7874 -0.4064)
			(end -0.7874 -0.4064)
			(stroke
				(width 0.1524)
				(type default)
			)
			(layer "B.SilkS")
		)
		(fp_line
			(start 0.7874 0.4064)
			(end 0.7874 -0.4064)
			(stroke
				(width 0.1524)
				(type default)
			)
			(layer "B.SilkS")
		)
		(fp_line
			(start -0.67945 -0.3048)
			(end -0.67945 0.3048)
			(stroke
				(width 0.1)
				(type default)
			)
			(layer "B.Fab")
		)
		(fp_line
			(start -0.67945 0.3048)
			(end -0.120396 0.3048)
			(stroke
				(width 0.1)
				(type default)
			)
			(layer "B.Fab")
		)
		(fp_line
			(start -0.12065 -0.3048)
			(end -0.67945 -0.3048)
			(stroke
				(width 0.1)
				(type default)
			)
			(layer "B.Fab")
		)
		(fp_line
			(start -0.12065 -0.2794)
			(end -0.12065 -0.3048)
			(stroke
				(width 0.1)
				(type default)
			)
			(layer "B.Fab")
		)
		(fp_line
			(start -0.120396 0.2794)
			(end 0.12065 0.2794)
			(stroke
				(width 0.1)
				(type default)
			)
			(layer "B.Fab")
		)
		(fp_line
			(start -0.120396 0.3048)
			(end -0.120396 0.2794)
			(stroke
				(width 0.1)
				(type default)
			)
			(layer "B.Fab")
		)
		(fp_line
			(start 0.12065 -0.305054)
			(end 0.12065 -0.2794)
			(stroke
				(width 0.1)
				(type default)
			)
			(layer "B.Fab")
		)
		(fp_line
			(start 0.12065 -0.2794)
			(end -0.12065 -0.2794)
			(stroke
				(width 0.1)
				(type default)
			)
			(layer "B.Fab")
		)
		(fp_line
			(start 0.12065 0.2794)
			(end 0.12065 0.3048)
			(stroke
				(width 0.1)
				(type default)
			)
			(layer "B.Fab")
		)
		(fp_line
			(start 0.12065 0.3048)
			(end 0.67945 0.3048)
			(stroke
				(width 0.1)
				(type default)
			)
			(layer "B.Fab")
		)
		(fp_line
			(start 0.67945 -0.305054)
			(end 0.12065 -0.305054)
			(stroke
				(width 0.1)
				(type default)
			)
			(layer "B.Fab")
		)
		(fp_line
			(start 0.67945 0.3048)
			(end 0.67945 -0.305054)
			(stroke
				(width 0.1)
				(type default)
			)
			(layer "B.Fab")
		)
		(pad "1" smd circle
			(at 0.40005 0 180)
			(size 0 0)
			(layers "B.Cu" "B.Mask" "B.Paste")
			(net "RST_CPU0_PERST0_N")
		)
		(pad "2" smd circle
			(at -0.40005 0 180)
			(size 0 0)
			(layers "B.Cu" "B.Mask" "B.Paste")
			(net "GND")
		)
	)
	(footprint ""
		(layer "B.Cu")
		(at 387.291326 -398.942052 90)
		(property "Reference" "C1045"
			(at 0 0 90)
			(layer "B.SilkS")
			(hide yes)
			(effects
				(font
					(size 1.27 1.27)
				)
				(justify mirror)
			)
		)
		(property "Value" ""
			(at 0 0 90)
			(layer "B.Fab")
			(effects
				(font
					(size 1.27 1.27)
				)
				(justify mirror)
			)
		)
		(duplicate_pad_numbers_are_jumpers no)
		(fp_line
			(start 0.7874 -0.4064)
			(end -0.7874 -0.4064)
			(stroke
				(width 0.1524)
				(type default)
			)
			(layer "B.SilkS")
		)
		(fp_line
			(start -0.7874 -0.4064)
			(end -0.7874 0.4064)
			(stroke
				(width 0.1524)
				(type default)
			)
			(layer "B.SilkS")
		)
		(fp_line
			(start 0.7874 0.4064)
			(end 0.7874 -0.4064)
			(stroke
				(width 0.1524)
				(type default)
			)
			(layer "B.SilkS")
		)
		(fp_line
			(start -0.7874 0.4064)
			(end 0.7874 0.4064)
			(stroke
				(width 0.1524)
				(type default)
			)
			(layer "B.SilkS")
		)
		(fp_line
			(start 0.67945 -0.305054)
			(end 0.12065 -0.305054)
			(stroke
				(width 0.1)
				(type default)
			)
			(layer "B.Fab")
		)
		(fp_line
			(start 0.12065 -0.305054)
			(end 0.12065 -0.2794)
			(stroke
				(width 0.1)
				(type default)
			)
			(layer "B.Fab")
		)
		(fp_line
			(start -0.12065 -0.3048)
			(end -0.67945 -0.3048)
			(stroke
				(width 0.1)
				(type default)
			)
			(layer "B.Fab")
		)
		(fp_line
			(start -0.67945 -0.3048)
			(end -0.67945 0.3048)
			(stroke
				(width 0.1)
				(type default)
			)
			(layer "B.Fab")
		)
		(fp_line
			(start 0.12065 -0.2794)
			(end -0.12065 -0.2794)
			(stroke
				(width 0.1)
				(type default)
			)
			(layer "B.Fab")
		)
		(fp_line
			(start -0.12065 -0.2794)
			(end -0.12065 -0.3048)
			(stroke
				(width 0.1)
				(type default)
			)
			(layer "B.Fab")
		)
		(fp_line
			(start 0.12065 0.2794)
			(end 0.12065 0.3048)
			(stroke
				(width 0.1)
				(type default)
			)
			(layer "B.Fab")
		)
		(fp_line
			(start -0.120396 0.2794)
			(end 0.12065 0.2794)
			(stroke
				(width 0.1)
				(type default)
			)
			(layer "B.Fab")
		)
		(fp_line
			(start 0.67945 0.3048)
			(end 0.67945 -0.305054)
			(stroke
				(width 0.1)
				(type default)
			)
			(layer "B.Fab")
		)
		(fp_line
			(start 0.12065 0.3048)
			(end 0.67945 0.3048)
			(stroke
				(width 0.1)
				(type default)
			)
			(layer "B.Fab")
		)
		(fp_line
			(start -0.120396 0.3048)
			(end -0.120396 0.2794)
			(stroke
				(width 0.1)
				(type default)
			)
			(layer "B.Fab")
		)
		(fp_line
			(start -0.67945 0.3048)
			(end -0.120396 0.3048)
			(stroke
				(width 0.1)
				(type default)
			)
			(layer "B.Fab")
		)
		(pad "1" smd circle
			(at 0.40005 0 270)
			(size 0 0)
			(layers "B.Cu" "B.Mask" "B.Paste")
			(net "P0V9_CPU0_RT3_2A")
		)
		(pad "2" smd circle
			(at -0.40005 0 270)
			(size 0 0)
			(layers "B.Cu" "B.Mask" "B.Paste")
			(net "GND")
		)
	)
	(footprint ""
		(layer "B.Cu")
		(at 203.045314 -78.247748 180)
		(property "Reference" "R3244"
			(at 0 0 0)
			(layer "B.SilkS")
			(hide yes)
			(effects
				(font
					(size 1.27 1.27)
				)
				(justify mirror)
			)
		)
		(property "Value" ""
			(at 0 0 0)
			(layer "B.Fab")
			(effects
				(font
					(size 1.27 1.27)
				)
				(justify mirror)
			)
		)
		(duplicate_pad_numbers_are_jumpers no)
		(fp_line
			(start 0.7874 0.4064)
			(end 0.7874 -0.4064)
			(stroke
				(width 0.1524)
				(type default)
			)
			(layer "B.SilkS")
		)
		(fp_line
			(start 0.7874 -0.4064)
			(end -0.7874 -0.4064)
			(stroke
				(width 0.1524)
				(type default)
			)
			(layer "B.SilkS")
		)
		(fp_line
			(start -0.7874 0.4064)
			(end 0.7874 0.4064)
			(stroke
				(width 0.1524)
				(type default)
			)
			(layer "B.SilkS")
		)
		(fp_line
			(start -0.7874 -0.4064)
			(end -0.7874 0.4064)
			(stroke
				(width 0.1524)
				(type default)
			)
			(layer "B.SilkS")
		)
		(fp_line
			(start 0.67945 0.3048)
			(end 0.67945 -0.305054)
			(stroke
				(width 0.1)
				(type default)
			)
			(layer "B.Fab")
		)
		(fp_line
			(start 0.67945 -0.305054)
			(end 0.12065 -0.305054)
			(stroke
				(width 0.1)
				(type default)
			)
			(layer "B.Fab")
		)
		(fp_line
			(start 0.12065 0.3048)
			(end 0.67945 0.3048)
			(stroke
				(width 0.1)
				(type default)
			)
			(layer "B.Fab")
		)
		(fp_line
			(start 0.12065 0.2794)
			(end 0.12065 0.3048)
			(stroke
				(width 0.1)
				(type default)
			)
			(layer "B.Fab")
		)
		(fp_line
			(start 0.12065 -0.2794)
			(end -0.12065 -0.2794)
			(stroke
				(width 0.1)
				(type default)
			)
			(layer "B.Fab")
		)
		(fp_line
			(start 0.12065 -0.305054)
			(end 0.12065 -0.2794)
			(stroke
				(width 0.1)
				(type default)
			)
			(layer "B.Fab")
		)
		(fp_line
			(start -0.120396 0.3048)
			(end -0.120396 0.2794)
			(stroke
				(width 0.1)
				(type default)
			)
			(layer "B.Fab")
		)
		(fp_line
			(start -0.120396 0.2794)
			(end 0.12065 0.2794)
			(stroke
				(width 0.1)
				(type default)
			)
			(layer "B.Fab")
		)
		(fp_line
			(start -0.12065 -0.2794)
			(end -0.12065 -0.3048)
			(stroke
				(width 0.1)
				(type default)
			)
			(layer "B.Fab")
		)
		(fp_line
			(start -0.12065 -0.3048)
			(end -0.67945 -0.3048)
			(stroke
				(width 0.1)
				(type default)
			)
			(layer "B.Fab")
		)
		(fp_line
			(start -0.67945 0.3048)
			(end -0.120396 0.3048)
			(stroke
				(width 0.1)
				(type default)
			)
			(layer "B.Fab")
		)
		(fp_line
			(start -0.67945 -0.3048)
			(end -0.67945 0.3048)
			(stroke
				(width 0.1)
				(type default)
			)
			(layer "B.Fab")
		)
		(pad "1" smd circle
			(at 0.40005 0)
			(size 0 0)
			(layers "B.Cu" "B.Mask" "B.Paste")
			(net "OCP_V3_2_RBT_ARB_OUT")
		)
		(pad "2" smd circle
			(at -0.40005 0)
			(size 0 0)
			(layers "B.Cu" "B.Mask" "B.Paste")
			(net "OCP_V3_2_RBT_ARB_IN_R")
		)
	)
	(footprint ""
		(layer "B.Cu")
		(at 116.702078 -26.025856 90)
		(property "Reference" "C6120"
			(at 0 0 90)
			(layer "B.SilkS")
			(hide yes)
			(effects
				(font
					(size 1.27 1.27)
				)
				(justify mirror)
			)
		)
		(property "Value" ""
			(at 0 0 90)
			(layer "B.Fab")
			(effects
				(font
					(size 1.27 1.27)
				)
				(justify mirror)
			)
		)
		(duplicate_pad_numbers_are_jumpers no)
		(fp_line
			(start 0.7874 -0.4064)
			(end -0.7874 -0.4064)
			(stroke
				(width 0.1524)
				(type default)
			)
			(layer "B.SilkS")
		)
		(fp_line
			(start -0.7874 -0.4064)
			(end -0.7874 0.4064)
			(stroke
				(width 0.1524)
				(type default)
			)
			(layer "B.SilkS")
		)
		(fp_line
			(start 0.7874 0.4064)
			(end 0.7874 -0.4064)
			(stroke
				(width 0.1524)
				(type default)
			)
			(layer "B.SilkS")
		)
		(fp_line
			(start -0.7874 0.4064)
			(end 0.7874 0.4064)
			(stroke
				(width 0.1524)
				(type default)
			)
			(layer "B.SilkS")
		)
		(fp_line
			(start 0.67945 -0.305054)
			(end 0.12065 -0.305054)
			(stroke
				(width 0.1)
				(type default)
			)
			(layer "B.Fab")
		)
		(fp_line
			(start 0.12065 -0.305054)
			(end 0.12065 -0.2794)
			(stroke
				(width 0.1)
				(type default)
			)
			(layer "B.Fab")
		)
		(fp_line
			(start -0.12065 -0.3048)
			(end -0.67945 -0.3048)
			(stroke
				(width 0.1)
				(type default)
			)
			(layer "B.Fab")
		)
		(fp_line
			(start -0.67945 -0.3048)
			(end -0.67945 0.3048)
			(stroke
				(width 0.1)
				(type default)
			)
			(layer "B.Fab")
		)
		(fp_line
			(start 0.12065 -0.2794)
			(end -0.12065 -0.2794)
			(stroke
				(width 0.1)
				(type default)
			)
			(layer "B.Fab")
		)
		(fp_line
			(start -0.12065 -0.2794)
			(end -0.12065 -0.3048)
			(stroke
				(width 0.1)
				(type default)
			)
			(layer "B.Fab")
		)
		(fp_line
			(start 0.12065 0.2794)
			(end 0.12065 0.3048)
			(stroke
				(width 0.1)
				(type default)
			)
			(layer "B.Fab")
		)
		(fp_line
			(start -0.120396 0.2794)
			(end 0.12065 0.2794)
			(stroke
				(width 0.1)
				(type default)
			)
			(layer "B.Fab")
		)
		(fp_line
			(start 0.67945 0.3048)
			(end 0.67945 -0.305054)
			(stroke
				(width 0.1)
				(type default)
			)
			(layer "B.Fab")
		)
		(fp_line
			(start 0.12065 0.3048)
			(end 0.67945 0.3048)
			(stroke
				(width 0.1)
				(type default)
			)
			(layer "B.Fab")
		)
		(fp_line
			(start -0.120396 0.3048)
			(end -0.120396 0.2794)
			(stroke
				(width 0.1)
				(type default)
			)
			(layer "B.Fab")
		)
		(fp_line
			(start -0.67945 0.3048)
			(end -0.120396 0.3048)
			(stroke
				(width 0.1)
				(type default)
			)
			(layer "B.Fab")
		)
		(pad "1" smd circle
			(at 0.40005 0 270)
			(size 0 0)
			(layers "B.Cu" "B.Mask" "B.Paste")
			(net "P1V2_CPU0_USB2_DVDD12")
		)
		(pad "2" smd circle
			(at -0.40005 0 270)
			(size 0 0)
			(layers "B.Cu" "B.Mask" "B.Paste")
			(net "GND")
		)
	)
	(footprint ""
		(layer "B.Cu")
		(at 356.406958 -249.36831 180)
		(property "Reference" "C268"
			(at 0 0 0)
			(layer "B.SilkS")
			(hide yes)
			(effects
				(font
					(size 1.27 1.27)
				)
				(justify mirror)
			)
		)
		(property "Value" ""
			(at 0 0 0)
			(layer "B.Fab")
			(effects
				(font
					(size 1.27 1.27)
				)
				(justify mirror)
			)
		)
		(duplicate_pad_numbers_are_jumpers no)
		(fp_line
			(start 0.7874 0.4064)
			(end 0.7874 -0.4064)
			(stroke
				(width 0.1524)
				(type default)
			)
			(layer "B.SilkS")
		)
		(fp_line
			(start 0.7874 -0.4064)
			(end -0.7874 -0.4064)
			(stroke
				(width 0.1524)
				(type default)
			)
			(layer "B.SilkS")
		)
		(fp_line
			(start -0.7874 0.4064)
			(end 0.7874 0.4064)
			(stroke
				(width 0.1524)
				(type default)
			)
			(layer "B.SilkS")
		)
		(fp_line
			(start -0.7874 -0.4064)
			(end -0.7874 0.4064)
			(stroke
				(width 0.1524)
				(type default)
			)
			(layer "B.SilkS")
		)
		(fp_line
			(start 0.67945 0.3048)
			(end 0.67945 -0.305054)
			(stroke
				(width 0.1)
				(type default)
			)
			(layer "B.Fab")
		)
		(fp_line
			(start 0.67945 -0.305054)
			(end 0.12065 -0.305054)
			(stroke
				(width 0.1)
				(type default)
			)
			(layer "B.Fab")
		)
		(fp_line
			(start 0.12065 0.3048)
			(end 0.67945 0.3048)
			(stroke
				(width 0.1)
				(type default)
			)
			(layer "B.Fab")
		)
		(fp_line
			(start 0.12065 0.2794)
			(end 0.12065 0.3048)
			(stroke
				(width 0.1)
				(type default)
			)
			(layer "B.Fab")
		)
		(fp_line
			(start 0.12065 -0.2794)
			(end -0.12065 -0.2794)
			(stroke
				(width 0.1)
				(type default)
			)
			(layer "B.Fab")
		)
		(fp_line
			(start 0.12065 -0.305054)
			(end 0.12065 -0.2794)
			(stroke
				(width 0.1)
				(type default)
			)
			(layer "B.Fab")
		)
		(fp_line
			(start -0.120396 0.3048)
			(end -0.120396 0.2794)
			(stroke
				(width 0.1)
				(type default)
			)
			(layer "B.Fab")
		)
		(fp_line
			(start -0.120396 0.2794)
			(end 0.12065 0.2794)
			(stroke
				(width 0.1)
				(type default)
			)
			(layer "B.Fab")
		)
		(fp_line
			(start -0.12065 -0.2794)
			(end -0.12065 -0.3048)
			(stroke
				(width 0.1)
				(type default)
			)
			(layer "B.Fab")
		)
		(fp_line
			(start -0.12065 -0.3048)
			(end -0.67945 -0.3048)
			(stroke
				(width 0.1)
				(type default)
			)
			(layer "B.Fab")
		)
		(fp_line
			(start -0.67945 0.3048)
			(end -0.120396 0.3048)
			(stroke
				(width 0.1)
				(type default)
			)
			(layer "B.Fab")
		)
		(fp_line
			(start -0.67945 -0.3048)
			(end -0.67945 0.3048)
			(stroke
				(width 0.1)
				(type default)
			)
			(layer "B.Fab")
		)
		(pad "1" smd circle
			(at 0.40005 0)
			(size 0 0)
			(layers "B.Cu" "B.Mask" "B.Paste")
			(net "PVDDCR_CPU0_P0")
		)
		(pad "2" smd circle
			(at -0.40005 0)
			(size 0 0)
			(layers "B.Cu" "B.Mask" "B.Paste")
			(net "GND")
		)
	)
	(footprint ""
		(layer "B.Cu")
		(at 370.801646 -261.935976)
		(property "Reference" "C2590"
			(at 0 0 0)
			(layer "B.SilkS")
			(hide yes)
			(effects
				(font
					(size 1.27 1.27)
				)
				(justify mirror)
			)
		)
		(property "Value" ""
			(at 0 0 0)
			(layer "B.Fab")
			(effects
				(font
					(size 1.27 1.27)
				)
				(justify mirror)
			)
		)
		(duplicate_pad_numbers_are_jumpers no)
		(fp_line
			(start -0.7874 -0.4064)
			(end -0.7874 0.4064)
			(stroke
				(width 0.1524)
				(type default)
			)
			(layer "B.SilkS")
		)
		(fp_line
			(start -0.7874 0.4064)
			(end 0.7874 0.4064)
			(stroke
				(width 0.1524)
				(type default)
			)
			(layer "B.SilkS")
		)
		(fp_line
			(start 0.7874 -0.4064)
			(end -0.7874 -0.4064)
			(stroke
				(width 0.1524)
				(type default)
			)
			(layer "B.SilkS")
		)
		(fp_line
			(start 0.7874 0.4064)
			(end 0.7874 -0.4064)
			(stroke
				(width 0.1524)
				(type default)
			)
			(layer "B.SilkS")
		)
		(fp_line
			(start -0.67945 -0.3048)
			(end -0.67945 0.3048)
			(stroke
				(width 0.1)
				(type default)
			)
			(layer "B.Fab")
		)
		(fp_line
			(start -0.67945 0.3048)
			(end -0.120396 0.3048)
			(stroke
				(width 0.1)
				(type default)
			)
			(layer "B.Fab")
		)
		(fp_line
			(start -0.12065 -0.3048)
			(end -0.67945 -0.3048)
			(stroke
				(width 0.1)
				(type default)
			)
			(layer "B.Fab")
		)
		(fp_line
			(start -0.12065 -0.2794)
			(end -0.12065 -0.3048)
			(stroke
				(width 0.1)
				(type default)
			)
			(layer "B.Fab")
		)
		(fp_line
			(start -0.120396 0.2794)
			(end 0.12065 0.2794)
			(stroke
				(width 0.1)
				(type default)
			)
			(layer "B.Fab")
		)
		(fp_line
			(start -0.120396 0.3048)
			(end -0.120396 0.2794)
			(stroke
				(width 0.1)
				(type default)
			)
			(layer "B.Fab")
		)
		(fp_line
			(start 0.12065 -0.305054)
			(end 0.12065 -0.2794)
			(stroke
				(width 0.1)
				(type default)
			)
			(layer "B.Fab")
		)
		(fp_line
			(start 0.12065 -0.2794)
			(end -0.12065 -0.2794)
			(stroke
				(width 0.1)
				(type default)
			)
			(layer "B.Fab")
		)
		(fp_line
			(start 0.12065 0.2794)
			(end 0.12065 0.3048)
			(stroke
				(width 0.1)
				(type default)
			)
			(layer "B.Fab")
		)
		(fp_line
			(start 0.12065 0.3048)
			(end 0.67945 0.3048)
			(stroke
				(width 0.1)
				(type default)
			)
			(layer "B.Fab")
		)
		(fp_line
			(start 0.67945 -0.305054)
			(end 0.12065 -0.305054)
			(stroke
				(width 0.1)
				(type default)
			)
			(layer "B.Fab")
		)
		(fp_line
			(start 0.67945 0.3048)
			(end 0.67945 -0.305054)
			(stroke
				(width 0.1)
				(type default)
			)
			(layer "B.Fab")
		)
		(pad "1" smd circle
			(at 0.40005 0 180)
			(size 0 0)
			(layers "B.Cu" "B.Mask" "B.Paste")
			(net "PVDDCR_SOC_P0")
		)
		(pad "2" smd circle
			(at -0.40005 0 180)
			(size 0 0)
			(layers "B.Cu" "B.Mask" "B.Paste")
			(net "GND")
		)
	)
	(footprint ""
		(layer "B.Cu")
		(at 197.002908 -113.427256)
		(property "Reference" "R1282"
			(at 0 0 0)
			(layer "B.SilkS")
			(hide yes)
			(effects
				(font
					(size 1.27 1.27)
				)
				(justify mirror)
			)
		)
		(property "Value" ""
			(at 0 0 0)
			(layer "B.Fab")
			(effects
				(font
					(size 1.27 1.27)
				)
				(justify mirror)
			)
		)
		(duplicate_pad_numbers_are_jumpers no)
		(fp_line
			(start -0.7874 -0.4064)
			(end -0.7874 0.4064)
			(stroke
				(width 0.1524)
				(type default)
			)
			(layer "B.SilkS")
		)
		(fp_line
			(start -0.7874 0.4064)
			(end 0.7874 0.4064)
			(stroke
				(width 0.1524)
				(type default)
			)
			(layer "B.SilkS")
		)
		(fp_line
			(start 0.7874 -0.4064)
			(end -0.7874 -0.4064)
			(stroke
				(width 0.1524)
				(type default)
			)
			(layer "B.SilkS")
		)
		(fp_line
			(start 0.7874 0.4064)
			(end 0.7874 -0.4064)
			(stroke
				(width 0.1524)
				(type default)
			)
			(layer "B.SilkS")
		)
		(fp_line
			(start -0.67945 -0.3048)
			(end -0.67945 0.3048)
			(stroke
				(width 0.1)
				(type default)
			)
			(layer "B.Fab")
		)
		(fp_line
			(start -0.67945 0.3048)
			(end -0.120396 0.3048)
			(stroke
				(width 0.1)
				(type default)
			)
			(layer "B.Fab")
		)
		(fp_line
			(start -0.12065 -0.3048)
			(end -0.67945 -0.3048)
			(stroke
				(width 0.1)
				(type default)
			)
			(layer "B.Fab")
		)
		(fp_line
			(start -0.12065 -0.2794)
			(end -0.12065 -0.3048)
			(stroke
				(width 0.1)
				(type default)
			)
			(layer "B.Fab")
		)
		(fp_line
			(start -0.120396 0.2794)
			(end 0.12065 0.2794)
			(stroke
				(width 0.1)
				(type default)
			)
			(layer "B.Fab")
		)
		(fp_line
			(start -0.120396 0.3048)
			(end -0.120396 0.2794)
			(stroke
				(width 0.1)
				(type default)
			)
			(layer "B.Fab")
		)
		(fp_line
			(start 0.12065 -0.305054)
			(end 0.12065 -0.2794)
			(stroke
				(width 0.1)
				(type default)
			)
			(layer "B.Fab")
		)
		(fp_line
			(start 0.12065 -0.2794)
			(end -0.12065 -0.2794)
			(stroke
				(width 0.1)
				(type default)
			)
			(layer "B.Fab")
		)
		(fp_line
			(start 0.12065 0.2794)
			(end 0.12065 0.3048)
			(stroke
				(width 0.1)
				(type default)
			)
			(layer "B.Fab")
		)
		(fp_line
			(start 0.12065 0.3048)
			(end 0.67945 0.3048)
			(stroke
				(width 0.1)
				(type default)
			)
			(layer "B.Fab")
		)
		(fp_line
			(start 0.67945 -0.305054)
			(end 0.12065 -0.305054)
			(stroke
				(width 0.1)
				(type default)
			)
			(layer "B.Fab")
		)
		(fp_line
			(start 0.67945 0.3048)
			(end 0.67945 -0.305054)
			(stroke
				(width 0.1)
				(type default)
			)
			(layer "B.Fab")
		)
		(pad "1" smd circle
			(at 0.40005 0 180)
			(size 0 0)
			(layers "B.Cu" "B.Mask" "B.Paste")
			(net "FM_NCSI_OCP_SFF_R_OE")
		)
		(pad "2" smd circle
			(at -0.40005 0 180)
			(size 0 0)
			(layers "B.Cu" "B.Mask" "B.Paste")
			(net "FM_PLD_OCP_SFF_PWR_GOOD_R")
		)
	)
	(footprint ""
		(layer "B.Cu")
		(at 60.591192 -390.560052 90)
		(property "Reference" "C241"
			(at 0 0 90)
			(layer "B.SilkS")
			(hide yes)
			(effects
				(font
					(size 1.27 1.27)
				)
				(justify mirror)
			)
		)
		(property "Value" ""
			(at 0 0 90)
			(layer "B.Fab")
			(effects
				(font
					(size 1.27 1.27)
				)
				(justify mirror)
			)
		)
		(duplicate_pad_numbers_are_jumpers no)
		(fp_line
			(start 0.7874 -0.4064)
			(end -0.7874 -0.4064)
			(stroke
				(width 0.1524)
				(type default)
			)
			(layer "B.SilkS")
		)
		(fp_line
			(start -0.7874 -0.4064)
			(end -0.7874 0.4064)
			(stroke
				(width 0.1524)
				(type default)
			)
			(layer "B.SilkS")
		)
		(fp_line
			(start 0.7874 0.4064)
			(end 0.7874 -0.4064)
			(stroke
				(width 0.1524)
				(type default)
			)
			(layer "B.SilkS")
		)
		(fp_line
			(start -0.7874 0.4064)
			(end 0.7874 0.4064)
			(stroke
				(width 0.1524)
				(type default)
			)
			(layer "B.SilkS")
		)
		(fp_line
			(start 0.67945 -0.305054)
			(end 0.12065 -0.305054)
			(stroke
				(width 0.1)
				(type default)
			)
			(layer "B.Fab")
		)
		(fp_line
			(start 0.12065 -0.305054)
			(end 0.12065 -0.2794)
			(stroke
				(width 0.1)
				(type default)
			)
			(layer "B.Fab")
		)
		(fp_line
			(start -0.12065 -0.3048)
			(end -0.67945 -0.3048)
			(stroke
				(width 0.1)
				(type default)
			)
			(layer "B.Fab")
		)
		(fp_line
			(start -0.67945 -0.3048)
			(end -0.67945 0.3048)
			(stroke
				(width 0.1)
				(type default)
			)
			(layer "B.Fab")
		)
		(fp_line
			(start 0.12065 -0.2794)
			(end -0.12065 -0.2794)
			(stroke
				(width 0.1)
				(type default)
			)
			(layer "B.Fab")
		)
		(fp_line
			(start -0.12065 -0.2794)
			(end -0.12065 -0.3048)
			(stroke
				(width 0.1)
				(type default)
			)
			(layer "B.Fab")
		)
		(fp_line
			(start 0.12065 0.2794)
			(end 0.12065 0.3048)
			(stroke
				(width 0.1)
				(type default)
			)
			(layer "B.Fab")
		)
		(fp_line
			(start -0.120396 0.2794)
			(end 0.12065 0.2794)
			(stroke
				(width 0.1)
				(type default)
			)
			(layer "B.Fab")
		)
		(fp_line
			(start 0.67945 0.3048)
			(end 0.67945 -0.305054)
			(stroke
				(width 0.1)
				(type default)
			)
			(layer "B.Fab")
		)
		(fp_line
			(start 0.12065 0.3048)
			(end 0.67945 0.3048)
			(stroke
				(width 0.1)
				(type default)
			)
			(layer "B.Fab")
		)
		(fp_line
			(start -0.120396 0.3048)
			(end -0.120396 0.2794)
			(stroke
				(width 0.1)
				(type default)
			)
			(layer "B.Fab")
		)
		(fp_line
			(start -0.67945 0.3048)
			(end -0.120396 0.3048)
			(stroke
				(width 0.1)
				(type default)
			)
			(layer "B.Fab")
		)
		(pad "1" smd circle
			(at 0.40005 0 270)
			(size 0 0)
			(layers "B.Cu" "B.Mask" "B.Paste")
			(net "P0V9_CPU1_RT0_2A")
		)
		(pad "2" smd circle
			(at -0.40005 0 270)
			(size 0 0)
			(layers "B.Cu" "B.Mask" "B.Paste")
			(net "GND")
		)
	)
	(footprint ""
		(layer "B.Cu")
		(at 122.468386 -261.04723)
		(property "Reference" "C3917"
			(at 0 0 0)
			(layer "B.SilkS")
			(hide yes)
			(effects
				(font
					(size 1.27 1.27)
				)
				(justify mirror)
			)
		)
		(property "Value" ""
			(at 0 0 0)
			(layer "B.Fab")
			(effects
				(font
					(size 1.27 1.27)
				)
				(justify mirror)
			)
		)
		(duplicate_pad_numbers_are_jumpers no)
		(fp_line
			(start -0.7874 -0.4064)
			(end -0.7874 0.4064)
			(stroke
				(width 0.1524)
				(type default)
			)
			(layer "B.SilkS")
		)
		(fp_line
			(start -0.7874 0.4064)
			(end 0.7874 0.4064)
			(stroke
				(width 0.1524)
				(type default)
			)
			(layer "B.SilkS")
		)
		(fp_line
			(start 0.7874 -0.4064)
			(end -0.7874 -0.4064)
			(stroke
				(width 0.1524)
				(type default)
			)
			(layer "B.SilkS")
		)
		(fp_line
			(start 0.7874 0.4064)
			(end 0.7874 -0.4064)
			(stroke
				(width 0.1524)
				(type default)
			)
			(layer "B.SilkS")
		)
		(fp_line
			(start -0.67945 -0.3048)
			(end -0.67945 0.3048)
			(stroke
				(width 0.1)
				(type default)
			)
			(layer "B.Fab")
		)
		(fp_line
			(start -0.67945 0.3048)
			(end -0.120396 0.3048)
			(stroke
				(width 0.1)
				(type default)
			)
			(layer "B.Fab")
		)
		(fp_line
			(start -0.12065 -0.3048)
			(end -0.67945 -0.3048)
			(stroke
				(width 0.1)
				(type default)
			)
			(layer "B.Fab")
		)
		(fp_line
			(start -0.12065 -0.2794)
			(end -0.12065 -0.3048)
			(stroke
				(width 0.1)
				(type default)
			)
			(layer "B.Fab")
		)
		(fp_line
			(start -0.120396 0.2794)
			(end 0.12065 0.2794)
			(stroke
				(width 0.1)
				(type default)
			)
			(layer "B.Fab")
		)
		(fp_line
			(start -0.120396 0.3048)
			(end -0.120396 0.2794)
			(stroke
				(width 0.1)
				(type default)
			)
			(layer "B.Fab")
		)
		(fp_line
			(start 0.12065 -0.305054)
			(end 0.12065 -0.2794)
			(stroke
				(width 0.1)
				(type default)
			)
			(layer "B.Fab")
		)
		(fp_line
			(start 0.12065 -0.2794)
			(end -0.12065 -0.2794)
			(stroke
				(width 0.1)
				(type default)
			)
			(layer "B.Fab")
		)
		(fp_line
			(start 0.12065 0.2794)
			(end 0.12065 0.3048)
			(stroke
				(width 0.1)
				(type default)
			)
			(layer "B.Fab")
		)
		(fp_line
			(start 0.12065 0.3048)
			(end 0.67945 0.3048)
			(stroke
				(width 0.1)
				(type default)
			)
			(layer "B.Fab")
		)
		(fp_line
			(start 0.67945 -0.305054)
			(end 0.12065 -0.305054)
			(stroke
				(width 0.1)
				(type default)
			)
			(layer "B.Fab")
		)
		(fp_line
			(start 0.67945 0.3048)
			(end 0.67945 -0.305054)
			(stroke
				(width 0.1)
				(type default)
			)
			(layer "B.Fab")
		)
		(pad "1" smd circle
			(at 0.40005 0 180)
			(size 0 0)
			(layers "B.Cu" "B.Mask" "B.Paste")
			(net "PVDDCR_SOC_P1")
		)
		(pad "2" smd circle
			(at -0.40005 0 180)
			(size 0 0)
			(layers "B.Cu" "B.Mask" "B.Paste")
			(net "GND")
		)
	)
	(footprint ""
		(layer "B.Cu")
		(at 67.201034 -199.336152)
		(property "Reference" "R553"
			(at 0 0 0)
			(layer "B.SilkS")
			(hide yes)
			(effects
				(font
					(size 1.27 1.27)
				)
				(justify mirror)
			)
		)
		(property "Value" ""
			(at 0 0 0)
			(layer "B.Fab")
			(effects
				(font
					(size 1.27 1.27)
				)
				(justify mirror)
			)
		)
		(duplicate_pad_numbers_are_jumpers no)
		(fp_line
			(start -0.7874 -0.4064)
			(end -0.7874 0.4064)
			(stroke
				(width 0.1524)
				(type default)
			)
			(layer "B.SilkS")
		)
		(fp_line
			(start -0.7874 0.4064)
			(end 0.7874 0.4064)
			(stroke
				(width 0.1524)
				(type default)
			)
			(layer "B.SilkS")
		)
		(fp_line
			(start 0.7874 -0.4064)
			(end -0.7874 -0.4064)
			(stroke
				(width 0.1524)
				(type default)
			)
			(layer "B.SilkS")
		)
		(fp_line
			(start 0.7874 0.4064)
			(end 0.7874 -0.4064)
			(stroke
				(width 0.1524)
				(type default)
			)
			(layer "B.SilkS")
		)
		(fp_line
			(start -0.67945 -0.3048)
			(end -0.67945 0.3048)
			(stroke
				(width 0.1)
				(type default)
			)
			(layer "B.Fab")
		)
		(fp_line
			(start -0.67945 0.3048)
			(end -0.120396 0.3048)
			(stroke
				(width 0.1)
				(type default)
			)
			(layer "B.Fab")
		)
		(fp_line
			(start -0.12065 -0.3048)
			(end -0.67945 -0.3048)
			(stroke
				(width 0.1)
				(type default)
			)
			(layer "B.Fab")
		)
		(fp_line
			(start -0.12065 -0.2794)
			(end -0.12065 -0.3048)
			(stroke
				(width 0.1)
				(type default)
			)
			(layer "B.Fab")
		)
		(fp_line
			(start -0.120396 0.2794)
			(end 0.12065 0.2794)
			(stroke
				(width 0.1)
				(type default)
			)
			(layer "B.Fab")
		)
		(fp_line
			(start -0.120396 0.3048)
			(end -0.120396 0.2794)
			(stroke
				(width 0.1)
				(type default)
			)
			(layer "B.Fab")
		)
		(fp_line
			(start 0.12065 -0.305054)
			(end 0.12065 -0.2794)
			(stroke
				(width 0.1)
				(type default)
			)
			(layer "B.Fab")
		)
		(fp_line
			(start 0.12065 -0.2794)
			(end -0.12065 -0.2794)
			(stroke
				(width 0.1)
				(type default)
			)
			(layer "B.Fab")
		)
		(fp_line
			(start 0.12065 0.2794)
			(end 0.12065 0.3048)
			(stroke
				(width 0.1)
				(type default)
			)
			(layer "B.Fab")
		)
		(fp_line
			(start 0.12065 0.3048)
			(end 0.67945 0.3048)
			(stroke
				(width 0.1)
				(type default)
			)
			(layer "B.Fab")
		)
		(fp_line
			(start 0.67945 -0.305054)
			(end 0.12065 -0.305054)
			(stroke
				(width 0.1)
				(type default)
			)
			(layer "B.Fab")
		)
		(fp_line
			(start 0.67945 0.3048)
			(end 0.67945 -0.305054)
			(stroke
				(width 0.1)
				(type default)
			)
			(layer "B.Fab")
		)
		(pad "1" smd circle
			(at 0.40005 0 180)
			(size 0 0)
			(layers "B.Cu" "B.Mask" "B.Paste")
			(net "CPU1_NV_SAVE_N")
		)
		(pad "2" smd circle
			(at -0.40005 0 180)
			(size 0 0)
			(layers "B.Cu" "B.Mask" "B.Paste")
			(net "PVDD18_S5_P1")
		)
	)
	(footprint ""
		(layer "B.Cu")
		(at 92.185744 -408.517344 90)
		(property "Reference" "C6690"
			(at 0 0 90)
			(layer "B.SilkS")
			(hide yes)
			(effects
				(font
					(size 1.27 1.27)
				)
				(justify mirror)
			)
		)
		(property "Value" ""
			(at 0 0 90)
			(layer "B.Fab")
			(effects
				(font
					(size 1.27 1.27)
				)
				(justify mirror)
			)
		)
		(duplicate_pad_numbers_are_jumpers no)
		(fp_line
			(start 0.299974 -0.150114)
			(end -0.299974 -0.150114)
			(stroke
				(width 0.1)
				(type default)
			)
			(layer "B.Fab")
		)
		(fp_line
			(start -0.299974 -0.150114)
			(end -0.299974 0.150114)
			(stroke
				(width 0.1)
				(type default)
			)
			(layer "B.Fab")
		)
		(fp_line
			(start 0.299974 0.150114)
			(end 0.299974 -0.150114)
			(stroke
				(width 0.1)
				(type default)
			)
			(layer "B.Fab")
		)
		(fp_line
			(start -0.299974 0.150114)
			(end 0.299974 0.150114)
			(stroke
				(width 0.1)
				(type default)
			)
			(layer "B.Fab")
		)
		(pad "1" smd rect
			(at 0.2667 0 270)
			(size 0.3048 0.381)
			(layers "B.Cu" "B.Mask" "B.Paste")
			(net "P5E_CPU1_P1_TX_BUF_C_DN<14>")
		)
		(pad "2" smd rect
			(at -0.2667 0 270)
			(size 0.3048 0.381)
			(layers "B.Cu" "B.Mask" "B.Paste")
			(net "P5E_CPU1_P1_TX_BUF_DN<14>")
		)
	)
	(footprint ""
		(layer "B.Cu")
		(at 340.718902 -398.942052 90)
		(property "Reference" "C630"
			(at 0 0 90)
			(layer "B.SilkS")
			(hide yes)
			(effects
				(font
					(size 1.27 1.27)
				)
				(justify mirror)
			)
		)
		(property "Value" ""
			(at 0 0 90)
			(layer "B.Fab")
			(effects
				(font
					(size 1.27 1.27)
				)
				(justify mirror)
			)
		)
		(duplicate_pad_numbers_are_jumpers no)
		(fp_line
			(start 0.7874 -0.4064)
			(end -0.7874 -0.4064)
			(stroke
				(width 0.1524)
				(type default)
			)
			(layer "B.SilkS")
		)
		(fp_line
			(start -0.7874 -0.4064)
			(end -0.7874 0.4064)
			(stroke
				(width 0.1524)
				(type default)
			)
			(layer "B.SilkS")
		)
		(fp_line
			(start 0.7874 0.4064)
			(end 0.7874 -0.4064)
			(stroke
				(width 0.1524)
				(type default)
			)
			(layer "B.SilkS")
		)
		(fp_line
			(start -0.7874 0.4064)
			(end 0.7874 0.4064)
			(stroke
				(width 0.1524)
				(type default)
			)
			(layer "B.SilkS")
		)
		(fp_line
			(start 0.67945 -0.305054)
			(end 0.12065 -0.305054)
			(stroke
				(width 0.1)
				(type default)
			)
			(layer "B.Fab")
		)
		(fp_line
			(start 0.12065 -0.305054)
			(end 0.12065 -0.2794)
			(stroke
				(width 0.1)
				(type default)
			)
			(layer "B.Fab")
		)
		(fp_line
			(start -0.12065 -0.3048)
			(end -0.67945 -0.3048)
			(stroke
				(width 0.1)
				(type default)
			)
			(layer "B.Fab")
		)
		(fp_line
			(start -0.67945 -0.3048)
			(end -0.67945 0.3048)
			(stroke
				(width 0.1)
				(type default)
			)
			(layer "B.Fab")
		)
		(fp_line
			(start 0.12065 -0.2794)
			(end -0.12065 -0.2794)
			(stroke
				(width 0.1)
				(type default)
			)
			(layer "B.Fab")
		)
		(fp_line
			(start -0.12065 -0.2794)
			(end -0.12065 -0.3048)
			(stroke
				(width 0.1)
				(type default)
			)
			(layer "B.Fab")
		)
		(fp_line
			(start 0.12065 0.2794)
			(end 0.12065 0.3048)
			(stroke
				(width 0.1)
				(type default)
			)
			(layer "B.Fab")
		)
		(fp_line
			(start -0.120396 0.2794)
			(end 0.12065 0.2794)
			(stroke
				(width 0.1)
				(type default)
			)
			(layer "B.Fab")
		)
		(fp_line
			(start 0.67945 0.3048)
			(end 0.67945 -0.305054)
			(stroke
				(width 0.1)
				(type default)
			)
			(layer "B.Fab")
		)
		(fp_line
			(start 0.12065 0.3048)
			(end 0.67945 0.3048)
			(stroke
				(width 0.1)
				(type default)
			)
			(layer "B.Fab")
		)
		(fp_line
			(start -0.120396 0.3048)
			(end -0.120396 0.2794)
			(stroke
				(width 0.1)
				(type default)
			)
			(layer "B.Fab")
		)
		(fp_line
			(start -0.67945 0.3048)
			(end -0.120396 0.3048)
			(stroke
				(width 0.1)
				(type default)
			)
			(layer "B.Fab")
		)
		(pad "1" smd circle
			(at 0.40005 0 270)
			(size 0 0)
			(layers "B.Cu" "B.Mask" "B.Paste")
			(net "P0V9_CPU0_RT1_2A")
		)
		(pad "2" smd circle
			(at -0.40005 0 270)
			(size 0 0)
			(layers "B.Cu" "B.Mask" "B.Paste")
			(net "GND")
		)
	)
	(footprint ""
		(layer "B.Cu")
		(at 180.608986 -352.354642 -90)
		(property "Reference" "PR326"
			(at 0 0 90)
			(layer "B.SilkS")
			(hide yes)
			(effects
				(font
					(size 1.27 1.27)
				)
				(justify mirror)
			)
		)
		(property "Value" ""
			(at 0 0 90)
			(layer "B.Fab")
			(effects
				(font
					(size 1.27 1.27)
				)
				(justify mirror)
			)
		)
		(duplicate_pad_numbers_are_jumpers no)
		(fp_line
			(start -0.7874 0.4064)
			(end 0.7874 0.4064)
			(stroke
				(width 0.1524)
				(type default)
			)
			(layer "B.SilkS")
		)
		(fp_line
			(start 0.7874 0.4064)
			(end 0.7874 -0.4064)
			(stroke
				(width 0.1524)
				(type default)
			)
			(layer "B.SilkS")
		)
		(fp_line
			(start -0.7874 -0.4064)
			(end -0.7874 0.4064)
			(stroke
				(width 0.1524)
				(type default)
			)
			(layer "B.SilkS")
		)
		(fp_line
			(start 0.7874 -0.4064)
			(end -0.7874 -0.4064)
			(stroke
				(width 0.1524)
				(type default)
			)
			(layer "B.SilkS")
		)
		(fp_line
			(start -0.67945 0.3048)
			(end -0.120396 0.3048)
			(stroke
				(width 0.1)
				(type default)
			)
			(layer "B.Fab")
		)
		(fp_line
			(start -0.120396 0.3048)
			(end -0.120396 0.2794)
			(stroke
				(width 0.1)
				(type default)
			)
			(layer "B.Fab")
		)
		(fp_line
			(start 0.12065 0.3048)
			(end 0.67945 0.3048)
			(stroke
				(width 0.1)
				(type default)
			)
			(layer "B.Fab")
		)
		(fp_line
			(start 0.67945 0.3048)
			(end 0.67945 -0.305054)
			(stroke
				(width 0.1)
				(type default)
			)
			(layer "B.Fab")
		)
		(fp_line
			(start -0.120396 0.2794)
			(end 0.12065 0.2794)
			(stroke
				(width 0.1)
				(type default)
			)
			(layer "B.Fab")
		)
		(fp_line
			(start 0.12065 0.2794)
			(end 0.12065 0.3048)
			(stroke
				(width 0.1)
				(type default)
			)
			(layer "B.Fab")
		)
		(fp_line
			(start -0.12065 -0.2794)
			(end -0.12065 -0.3048)
			(stroke
				(width 0.1)
				(type default)
			)
			(layer "B.Fab")
		)
		(fp_line
			(start 0.12065 -0.2794)
			(end -0.12065 -0.2794)
			(stroke
				(width 0.1)
				(type default)
			)
			(layer "B.Fab")
		)
		(fp_line
			(start -0.67945 -0.3048)
			(end -0.67945 0.3048)
			(stroke
				(width 0.1)
				(type default)
			)
			(layer "B.Fab")
		)
		(fp_line
			(start -0.12065 -0.3048)
			(end -0.67945 -0.3048)
			(stroke
				(width 0.1)
				(type default)
			)
			(layer "B.Fab")
		)
		(fp_line
			(start 0.12065 -0.305054)
			(end 0.12065 -0.2794)
			(stroke
				(width 0.1)
				(type default)
			)
			(layer "B.Fab")
		)
		(fp_line
			(start 0.67945 -0.305054)
			(end 0.12065 -0.305054)
			(stroke
				(width 0.1)
				(type default)
			)
			(layer "B.Fab")
		)
		(pad "1" smd circle
			(at 0.40005 0 90)
			(size 0 0)
			(layers "B.Cu" "B.Mask" "B.Paste")
			(net "PVDD11_S3_P1_PVCC")
		)
		(pad "2" smd circle
			(at -0.40005 0 90)
			(size 0 0)
			(layers "B.Cu" "B.Mask" "B.Paste")
			(net "PVDD11_S3_P1_VCC1")
		)
	)
	(footprint ""
		(layer "B.Cu")
		(at 70.876668 -177.513234 -90)
		(property "Reference" "PC312_5"
			(at 0 0 90)
			(layer "B.SilkS")
			(hide yes)
			(effects
				(font
					(size 1.27 1.27)
				)
				(justify mirror)
			)
		)
		(property "Value" ""
			(at 0 0 90)
			(layer "B.Fab")
			(effects
				(font
					(size 1.27 1.27)
				)
				(justify mirror)
			)
		)
		(duplicate_pad_numbers_are_jumpers no)
		(fp_line
			(start -1.524 0.762)
			(end 1.524 0.762)
			(stroke
				(width 0.1524)
				(type default)
			)
			(layer "B.SilkS")
		)
		(fp_line
			(start 1.524 0.762)
			(end 1.524 -0.762)
			(stroke
				(width 0.1524)
				(type default)
			)
			(layer "B.SilkS")
		)
		(fp_line
			(start -1.524 -0.762)
			(end -1.524 0.762)
			(stroke
				(width 0.1524)
				(type default)
			)
			(layer "B.SilkS")
		)
		(fp_line
			(start 1.524 -0.762)
			(end -1.524 -0.762)
			(stroke
				(width 0.1524)
				(type default)
			)
			(layer "B.SilkS")
		)
		(fp_line
			(start -1.1049 0.724916)
			(end -1.1049 -0.724916)
			(stroke
				(width 0.1)
				(type default)
			)
			(layer "B.Fab")
		)
		(fp_line
			(start 1.1049 0.724916)
			(end -1.1049 0.724916)
			(stroke
				(width 0.1)
				(type default)
			)
			(layer "B.Fab")
		)
		(fp_line
			(start -1.1049 -0.724916)
			(end 1.1049 -0.724916)
			(stroke
				(width 0.1)
				(type default)
			)
			(layer "B.Fab")
		)
		(fp_line
			(start 1.1049 -0.724916)
			(end 1.1049 0.724916)
			(stroke
				(width 0.1)
				(type default)
			)
			(layer "B.Fab")
		)
		(pad "1" smd rect
			(at 0.889 0 270)
			(size 1.016 1.27)
			(layers "B.Cu" "B.Mask" "B.Paste")
			(net "SW_P12V_AUX_PVDDCR_CPU0_P1_FLT")
		)
		(pad "2" smd rect
			(at -0.889 0 270)
			(size 1.016 1.27)
			(layers "B.Cu" "B.Mask" "B.Paste")
			(net "GND")
		)
	)
	(footprint ""
		(layer "B.Cu")
		(at 306.385214 -347.77553 -90)
		(property "Reference" "PR87"
			(at 0 0 90)
			(layer "B.SilkS")
			(hide yes)
			(effects
				(font
					(size 1.27 1.27)
				)
				(justify mirror)
			)
		)
		(property "Value" ""
			(at 0 0 90)
			(layer "B.Fab")
			(effects
				(font
					(size 1.27 1.27)
				)
				(justify mirror)
			)
		)
		(duplicate_pad_numbers_are_jumpers no)
		(fp_line
			(start -0.7874 0.4064)
			(end 0.7874 0.4064)
			(stroke
				(width 0.1524)
				(type default)
			)
			(layer "B.SilkS")
		)
		(fp_line
			(start 0.7874 0.4064)
			(end 0.7874 -0.4064)
			(stroke
				(width 0.1524)
				(type default)
			)
			(layer "B.SilkS")
		)
		(fp_line
			(start -0.7874 -0.4064)
			(end -0.7874 0.4064)
			(stroke
				(width 0.1524)
				(type default)
			)
			(layer "B.SilkS")
		)
		(fp_line
			(start 0.7874 -0.4064)
			(end -0.7874 -0.4064)
			(stroke
				(width 0.1524)
				(type default)
			)
			(layer "B.SilkS")
		)
		(fp_line
			(start -0.67945 0.3048)
			(end -0.120396 0.3048)
			(stroke
				(width 0.1)
				(type default)
			)
			(layer "B.Fab")
		)
		(fp_line
			(start -0.120396 0.3048)
			(end -0.120396 0.2794)
			(stroke
				(width 0.1)
				(type default)
			)
			(layer "B.Fab")
		)
		(fp_line
			(start 0.12065 0.3048)
			(end 0.67945 0.3048)
			(stroke
				(width 0.1)
				(type default)
			)
			(layer "B.Fab")
		)
		(fp_line
			(start 0.67945 0.3048)
			(end 0.67945 -0.305054)
			(stroke
				(width 0.1)
				(type default)
			)
			(layer "B.Fab")
		)
		(fp_line
			(start -0.120396 0.2794)
			(end 0.12065 0.2794)
			(stroke
				(width 0.1)
				(type default)
			)
			(layer "B.Fab")
		)
		(fp_line
			(start 0.12065 0.2794)
			(end 0.12065 0.3048)
			(stroke
				(width 0.1)
				(type default)
			)
			(layer "B.Fab")
		)
		(fp_line
			(start -0.12065 -0.2794)
			(end -0.12065 -0.3048)
			(stroke
				(width 0.1)
				(type default)
			)
			(layer "B.Fab")
		)
		(fp_line
			(start 0.12065 -0.2794)
			(end -0.12065 -0.2794)
			(stroke
				(width 0.1)
				(type default)
			)
			(layer "B.Fab")
		)
		(fp_line
			(start -0.67945 -0.3048)
			(end -0.67945 0.3048)
			(stroke
				(width 0.1)
				(type default)
			)
			(layer "B.Fab")
		)
		(fp_line
			(start -0.12065 -0.3048)
			(end -0.67945 -0.3048)
			(stroke
				(width 0.1)
				(type default)
			)
			(layer "B.Fab")
		)
		(fp_line
			(start 0.12065 -0.305054)
			(end 0.12065 -0.2794)
			(stroke
				(width 0.1)
				(type default)
			)
			(layer "B.Fab")
		)
		(fp_line
			(start 0.67945 -0.305054)
			(end 0.12065 -0.305054)
			(stroke
				(width 0.1)
				(type default)
			)
			(layer "B.Fab")
		)
		(pad "1" smd circle
			(at 0.40005 0 90)
			(size 0 0)
			(layers "B.Cu" "B.Mask" "B.Paste")
			(net "PVDDCR_CPU1_P0_PVCC")
		)
		(pad "2" smd circle
			(at -0.40005 0 90)
			(size 0 0)
			(layers "B.Cu" "B.Mask" "B.Paste")
			(net "PVDDCR_CPU1_P0_VCC4")
		)
	)
	(footprint ""
		(layer "B.Cu")
		(at 33.219644 -349.386398 -90)
		(property "Reference" "PR374"
			(at 0 0 90)
			(layer "B.SilkS")
			(hide yes)
			(effects
				(font
					(size 1.27 1.27)
				)
				(justify mirror)
			)
		)
		(property "Value" ""
			(at 0 0 90)
			(layer "B.Fab")
			(effects
				(font
					(size 1.27 1.27)
				)
				(justify mirror)
			)
		)
		(duplicate_pad_numbers_are_jumpers no)
		(fp_line
			(start -0.7874 0.4064)
			(end 0.7874 0.4064)
			(stroke
				(width 0.1524)
				(type default)
			)
			(layer "B.SilkS")
		)
		(fp_line
			(start 0.7874 0.4064)
			(end 0.7874 -0.4064)
			(stroke
				(width 0.1524)
				(type default)
			)
			(layer "B.SilkS")
		)
		(fp_line
			(start -0.7874 -0.4064)
			(end -0.7874 0.4064)
			(stroke
				(width 0.1524)
				(type default)
			)
			(layer "B.SilkS")
		)
		(fp_line
			(start 0.7874 -0.4064)
			(end -0.7874 -0.4064)
			(stroke
				(width 0.1524)
				(type default)
			)
			(layer "B.SilkS")
		)
		(fp_line
			(start -0.67945 0.3048)
			(end -0.120396 0.3048)
			(stroke
				(width 0.1)
				(type default)
			)
			(layer "B.Fab")
		)
		(fp_line
			(start -0.120396 0.3048)
			(end -0.120396 0.2794)
			(stroke
				(width 0.1)
				(type default)
			)
			(layer "B.Fab")
		)
		(fp_line
			(start 0.12065 0.3048)
			(end 0.67945 0.3048)
			(stroke
				(width 0.1)
				(type default)
			)
			(layer "B.Fab")
		)
		(fp_line
			(start 0.67945 0.3048)
			(end 0.67945 -0.305054)
			(stroke
				(width 0.1)
				(type default)
			)
			(layer "B.Fab")
		)
		(fp_line
			(start -0.120396 0.2794)
			(end 0.12065 0.2794)
			(stroke
				(width 0.1)
				(type default)
			)
			(layer "B.Fab")
		)
		(fp_line
			(start 0.12065 0.2794)
			(end 0.12065 0.3048)
			(stroke
				(width 0.1)
				(type default)
			)
			(layer "B.Fab")
		)
		(fp_line
			(start -0.12065 -0.2794)
			(end -0.12065 -0.3048)
			(stroke
				(width 0.1)
				(type default)
			)
			(layer "B.Fab")
		)
		(fp_line
			(start 0.12065 -0.2794)
			(end -0.12065 -0.2794)
			(stroke
				(width 0.1)
				(type default)
			)
			(layer "B.Fab")
		)
		(fp_line
			(start -0.67945 -0.3048)
			(end -0.67945 0.3048)
			(stroke
				(width 0.1)
				(type default)
			)
			(layer "B.Fab")
		)
		(fp_line
			(start -0.12065 -0.3048)
			(end -0.67945 -0.3048)
			(stroke
				(width 0.1)
				(type default)
			)
			(layer "B.Fab")
		)
		(fp_line
			(start 0.12065 -0.305054)
			(end 0.12065 -0.2794)
			(stroke
				(width 0.1)
				(type default)
			)
			(layer "B.Fab")
		)
		(fp_line
			(start 0.67945 -0.305054)
			(end 0.12065 -0.305054)
			(stroke
				(width 0.1)
				(type default)
			)
			(layer "B.Fab")
		)
		(pad "1" smd circle
			(at 0.40005 0 90)
			(size 0 0)
			(layers "B.Cu" "B.Mask" "B.Paste")
			(net "PVDDIO_P1_VOS3")
		)
		(pad "2" smd circle
			(at -0.40005 0 90)
			(size 0 0)
			(layers "B.Cu" "B.Mask" "B.Paste")
			(net "PVDDIO_P1")
		)
	)
	(footprint ""
		(layer "B.Cu")
		(at 89.614502 -207.41005 90)
		(property "Reference" "R928"
			(at 0 0 90)
			(layer "B.SilkS")
			(hide yes)
			(effects
				(font
					(size 1.27 1.27)
				)
				(justify mirror)
			)
		)
		(property "Value" ""
			(at 0 0 90)
			(layer "B.Fab")
			(effects
				(font
					(size 1.27 1.27)
				)
				(justify mirror)
			)
		)
		(duplicate_pad_numbers_are_jumpers no)
		(fp_line
			(start 0.7874 -0.4064)
			(end -0.7874 -0.4064)
			(stroke
				(width 0.1524)
				(type default)
			)
			(layer "B.SilkS")
		)
		(fp_line
			(start -0.7874 -0.4064)
			(end -0.7874 0.4064)
			(stroke
				(width 0.1524)
				(type default)
			)
			(layer "B.SilkS")
		)
		(fp_line
			(start 0.7874 0.4064)
			(end 0.7874 -0.4064)
			(stroke
				(width 0.1524)
				(type default)
			)
			(layer "B.SilkS")
		)
		(fp_line
			(start -0.7874 0.4064)
			(end 0.7874 0.4064)
			(stroke
				(width 0.1524)
				(type default)
			)
			(layer "B.SilkS")
		)
		(fp_line
			(start 0.67945 -0.305054)
			(end 0.12065 -0.305054)
			(stroke
				(width 0.1)
				(type default)
			)
			(layer "B.Fab")
		)
		(fp_line
			(start 0.12065 -0.305054)
			(end 0.12065 -0.2794)
			(stroke
				(width 0.1)
				(type default)
			)
			(layer "B.Fab")
		)
		(fp_line
			(start -0.12065 -0.3048)
			(end -0.67945 -0.3048)
			(stroke
				(width 0.1)
				(type default)
			)
			(layer "B.Fab")
		)
		(fp_line
			(start -0.67945 -0.3048)
			(end -0.67945 0.3048)
			(stroke
				(width 0.1)
				(type default)
			)
			(layer "B.Fab")
		)
		(fp_line
			(start 0.12065 -0.2794)
			(end -0.12065 -0.2794)
			(stroke
				(width 0.1)
				(type default)
			)
			(layer "B.Fab")
		)
		(fp_line
			(start -0.12065 -0.2794)
			(end -0.12065 -0.3048)
			(stroke
				(width 0.1)
				(type default)
			)
			(layer "B.Fab")
		)
		(fp_line
			(start 0.12065 0.2794)
			(end 0.12065 0.3048)
			(stroke
				(width 0.1)
				(type default)
			)
			(layer "B.Fab")
		)
		(fp_line
			(start -0.120396 0.2794)
			(end 0.12065 0.2794)
			(stroke
				(width 0.1)
				(type default)
			)
			(layer "B.Fab")
		)
		(fp_line
			(start 0.67945 0.3048)
			(end 0.67945 -0.305054)
			(stroke
				(width 0.1)
				(type default)
			)
			(layer "B.Fab")
		)
		(fp_line
			(start 0.12065 0.3048)
			(end 0.67945 0.3048)
			(stroke
				(width 0.1)
				(type default)
			)
			(layer "B.Fab")
		)
		(fp_line
			(start -0.120396 0.3048)
			(end -0.120396 0.2794)
			(stroke
				(width 0.1)
				(type default)
			)
			(layer "B.Fab")
		)
		(fp_line
			(start -0.67945 0.3048)
			(end -0.120396 0.3048)
			(stroke
				(width 0.1)
				(type default)
			)
			(layer "B.Fab")
		)
		(pad "1" smd circle
			(at 0.40005 0 270)
			(size 0 0)
			(layers "B.Cu" "B.Mask" "B.Paste")
			(net "CPU1_XTRIG_R2_L7")
		)
		(pad "2" smd circle
			(at -0.40005 0 270)
			(size 0 0)
			(layers "B.Cu" "B.Mask" "B.Paste")
			(net "CPU1_XTRIG_L7")
		)
	)
	(footprint ""
		(layer "B.Cu")
		(at 123.970034 -271.853152 90)
		(property "Reference" "C2386"
			(at 0 0 90)
			(layer "B.SilkS")
			(hide yes)
			(effects
				(font
					(size 1.27 1.27)
				)
				(justify mirror)
			)
		)
		(property "Value" ""
			(at 0 0 90)
			(layer "B.Fab")
			(effects
				(font
					(size 1.27 1.27)
				)
				(justify mirror)
			)
		)
		(duplicate_pad_numbers_are_jumpers no)
		(fp_line
			(start 0.7874 -0.4064)
			(end -0.7874 -0.4064)
			(stroke
				(width 0.1524)
				(type default)
			)
			(layer "B.SilkS")
		)
		(fp_line
			(start -0.7874 -0.4064)
			(end -0.7874 0.4064)
			(stroke
				(width 0.1524)
				(type default)
			)
			(layer "B.SilkS")
		)
		(fp_line
			(start 0.7874 0.4064)
			(end 0.7874 -0.4064)
			(stroke
				(width 0.1524)
				(type default)
			)
			(layer "B.SilkS")
		)
		(fp_line
			(start -0.7874 0.4064)
			(end 0.7874 0.4064)
			(stroke
				(width 0.1524)
				(type default)
			)
			(layer "B.SilkS")
		)
		(fp_line
			(start 0.67945 -0.305054)
			(end 0.12065 -0.305054)
			(stroke
				(width 0.1)
				(type default)
			)
			(layer "B.Fab")
		)
		(fp_line
			(start 0.12065 -0.305054)
			(end 0.12065 -0.2794)
			(stroke
				(width 0.1)
				(type default)
			)
			(layer "B.Fab")
		)
		(fp_line
			(start -0.12065 -0.3048)
			(end -0.67945 -0.3048)
			(stroke
				(width 0.1)
				(type default)
			)
			(layer "B.Fab")
		)
		(fp_line
			(start -0.67945 -0.3048)
			(end -0.67945 0.3048)
			(stroke
				(width 0.1)
				(type default)
			)
			(layer "B.Fab")
		)
		(fp_line
			(start 0.12065 -0.2794)
			(end -0.12065 -0.2794)
			(stroke
				(width 0.1)
				(type default)
			)
			(layer "B.Fab")
		)
		(fp_line
			(start -0.12065 -0.2794)
			(end -0.12065 -0.3048)
			(stroke
				(width 0.1)
				(type default)
			)
			(layer "B.Fab")
		)
		(fp_line
			(start 0.12065 0.2794)
			(end 0.12065 0.3048)
			(stroke
				(width 0.1)
				(type default)
			)
			(layer "B.Fab")
		)
		(fp_line
			(start -0.120396 0.2794)
			(end 0.12065 0.2794)
			(stroke
				(width 0.1)
				(type default)
			)
			(layer "B.Fab")
		)
		(fp_line
			(start 0.67945 0.3048)
			(end 0.67945 -0.305054)
			(stroke
				(width 0.1)
				(type default)
			)
			(layer "B.Fab")
		)
		(fp_line
			(start 0.12065 0.3048)
			(end 0.67945 0.3048)
			(stroke
				(width 0.1)
				(type default)
			)
			(layer "B.Fab")
		)
		(fp_line
			(start -0.120396 0.3048)
			(end -0.120396 0.2794)
			(stroke
				(width 0.1)
				(type default)
			)
			(layer "B.Fab")
		)
		(fp_line
			(start -0.67945 0.3048)
			(end -0.120396 0.3048)
			(stroke
				(width 0.1)
				(type default)
			)
			(layer "B.Fab")
		)
		(pad "1" smd circle
			(at 0.40005 0 270)
			(size 0 0)
			(layers "B.Cu" "B.Mask" "B.Paste")
			(net "PVDDCR_CPU1_P1")
		)
		(pad "2" smd circle
			(at -0.40005 0 270)
			(size 0 0)
			(layers "B.Cu" "B.Mask" "B.Paste")
			(net "GND")
		)
	)
	(footprint ""
		(layer "B.Cu")
		(at 419.912038 -192.660016 180)
		(property "Reference" "C161"
			(at 0 0 0)
			(layer "B.SilkS")
			(hide yes)
			(effects
				(font
					(size 1.27 1.27)
				)
				(justify mirror)
			)
		)
		(property "Value" ""
			(at 0 0 0)
			(layer "B.Fab")
			(effects
				(font
					(size 1.27 1.27)
				)
				(justify mirror)
			)
		)
		(duplicate_pad_numbers_are_jumpers no)
		(fp_line
			(start 1.524 0.762)
			(end 1.524 -0.762)
			(stroke
				(width 0.1524)
				(type default)
			)
			(layer "B.SilkS")
		)
		(fp_line
			(start 1.524 -0.762)
			(end -1.524 -0.762)
			(stroke
				(width 0.1524)
				(type default)
			)
			(layer "B.SilkS")
		)
		(fp_line
			(start -1.524 0.762)
			(end 1.524 0.762)
			(stroke
				(width 0.1524)
				(type default)
			)
			(layer "B.SilkS")
		)
		(fp_line
			(start -1.524 -0.762)
			(end -1.524 0.762)
			(stroke
				(width 0.1524)
				(type default)
			)
			(layer "B.SilkS")
		)
		(fp_line
			(start 1.1049 0.724916)
			(end -1.1049 0.724916)
			(stroke
				(width 0.1)
				(type default)
			)
			(layer "B.Fab")
		)
		(fp_line
			(start 1.1049 -0.724916)
			(end 1.1049 0.724916)
			(stroke
				(width 0.1)
				(type default)
			)
			(layer "B.Fab")
		)
		(fp_line
			(start -1.1049 0.724916)
			(end -1.1049 -0.724916)
			(stroke
				(width 0.1)
				(type default)
			)
			(layer "B.Fab")
		)
		(fp_line
			(start -1.1049 -0.724916)
			(end 1.1049 -0.724916)
			(stroke
				(width 0.1)
				(type default)
			)
			(layer "B.Fab")
		)
		(pad "1" smd rect
			(at 0.889 0 180)
			(size 1.016 1.27)
			(layers "B.Cu" "B.Mask" "B.Paste")
			(net "P12V_MEM_CPU0")
		)
		(pad "2" smd rect
			(at -0.889 0 180)
			(size 1.016 1.27)
			(layers "B.Cu" "B.Mask" "B.Paste")
			(net "GND")
		)
	)
	(footprint ""
		(layer "B.Cu")
		(at 118.686834 -272.284952 180)
		(property "Reference" "C2356"
			(at 0 0 0)
			(layer "B.SilkS")
			(hide yes)
			(effects
				(font
					(size 1.27 1.27)
				)
				(justify mirror)
			)
		)
		(property "Value" ""
			(at 0 0 0)
			(layer "B.Fab")
			(effects
				(font
					(size 1.27 1.27)
				)
				(justify mirror)
			)
		)
		(duplicate_pad_numbers_are_jumpers no)
		(fp_line
			(start 0.7874 0.4064)
			(end 0.7874 -0.4064)
			(stroke
				(width 0.1524)
				(type default)
			)
			(layer "B.SilkS")
		)
		(fp_line
			(start 0.7874 -0.4064)
			(end -0.7874 -0.4064)
			(stroke
				(width 0.1524)
				(type default)
			)
			(layer "B.SilkS")
		)
		(fp_line
			(start -0.7874 0.4064)
			(end 0.7874 0.4064)
			(stroke
				(width 0.1524)
				(type default)
			)
			(layer "B.SilkS")
		)
		(fp_line
			(start -0.7874 -0.4064)
			(end -0.7874 0.4064)
			(stroke
				(width 0.1524)
				(type default)
			)
			(layer "B.SilkS")
		)
		(fp_line
			(start 0.67945 0.3048)
			(end 0.67945 -0.305054)
			(stroke
				(width 0.1)
				(type default)
			)
			(layer "B.Fab")
		)
		(fp_line
			(start 0.67945 -0.305054)
			(end 0.12065 -0.305054)
			(stroke
				(width 0.1)
				(type default)
			)
			(layer "B.Fab")
		)
		(fp_line
			(start 0.12065 0.3048)
			(end 0.67945 0.3048)
			(stroke
				(width 0.1)
				(type default)
			)
			(layer "B.Fab")
		)
		(fp_line
			(start 0.12065 0.2794)
			(end 0.12065 0.3048)
			(stroke
				(width 0.1)
				(type default)
			)
			(layer "B.Fab")
		)
		(fp_line
			(start 0.12065 -0.2794)
			(end -0.12065 -0.2794)
			(stroke
				(width 0.1)
				(type default)
			)
			(layer "B.Fab")
		)
		(fp_line
			(start 0.12065 -0.305054)
			(end 0.12065 -0.2794)
			(stroke
				(width 0.1)
				(type default)
			)
			(layer "B.Fab")
		)
		(fp_line
			(start -0.120396 0.3048)
			(end -0.120396 0.2794)
			(stroke
				(width 0.1)
				(type default)
			)
			(layer "B.Fab")
		)
		(fp_line
			(start -0.120396 0.2794)
			(end 0.12065 0.2794)
			(stroke
				(width 0.1)
				(type default)
			)
			(layer "B.Fab")
		)
		(fp_line
			(start -0.12065 -0.2794)
			(end -0.12065 -0.3048)
			(stroke
				(width 0.1)
				(type default)
			)
			(layer "B.Fab")
		)
		(fp_line
			(start -0.12065 -0.3048)
			(end -0.67945 -0.3048)
			(stroke
				(width 0.1)
				(type default)
			)
			(layer "B.Fab")
		)
		(fp_line
			(start -0.67945 0.3048)
			(end -0.120396 0.3048)
			(stroke
				(width 0.1)
				(type default)
			)
			(layer "B.Fab")
		)
		(fp_line
			(start -0.67945 -0.3048)
			(end -0.67945 0.3048)
			(stroke
				(width 0.1)
				(type default)
			)
			(layer "B.Fab")
		)
		(pad "1" smd circle
			(at 0.40005 0)
			(size 0 0)
			(layers "B.Cu" "B.Mask" "B.Paste")
			(net "PVDDCR_CPU1_P1")
		)
		(pad "2" smd circle
			(at -0.40005 0)
			(size 0 0)
			(layers "B.Cu" "B.Mask" "B.Paste")
			(net "GND")
		)
	)
	(footprint ""
		(layer "B.Cu")
		(at 347.008958 -249.36831 180)
		(property "Reference" "C2513"
			(at 0 0 0)
			(layer "B.SilkS")
			(hide yes)
			(effects
				(font
					(size 1.27 1.27)
				)
				(justify mirror)
			)
		)
		(property "Value" ""
			(at 0 0 0)
			(layer "B.Fab")
			(effects
				(font
					(size 1.27 1.27)
				)
				(justify mirror)
			)
		)
		(duplicate_pad_numbers_are_jumpers no)
		(fp_line
			(start 0.7874 0.4064)
			(end 0.7874 -0.4064)
			(stroke
				(width 0.1524)
				(type default)
			)
			(layer "B.SilkS")
		)
		(fp_line
			(start 0.7874 -0.4064)
			(end -0.7874 -0.4064)
			(stroke
				(width 0.1524)
				(type default)
			)
			(layer "B.SilkS")
		)
		(fp_line
			(start -0.7874 0.4064)
			(end 0.7874 0.4064)
			(stroke
				(width 0.1524)
				(type default)
			)
			(layer "B.SilkS")
		)
		(fp_line
			(start -0.7874 -0.4064)
			(end -0.7874 0.4064)
			(stroke
				(width 0.1524)
				(type default)
			)
			(layer "B.SilkS")
		)
		(fp_line
			(start 0.67945 0.3048)
			(end 0.67945 -0.305054)
			(stroke
				(width 0.1)
				(type default)
			)
			(layer "B.Fab")
		)
		(fp_line
			(start 0.67945 -0.305054)
			(end 0.12065 -0.305054)
			(stroke
				(width 0.1)
				(type default)
			)
			(layer "B.Fab")
		)
		(fp_line
			(start 0.12065 0.3048)
			(end 0.67945 0.3048)
			(stroke
				(width 0.1)
				(type default)
			)
			(layer "B.Fab")
		)
		(fp_line
			(start 0.12065 0.2794)
			(end 0.12065 0.3048)
			(stroke
				(width 0.1)
				(type default)
			)
			(layer "B.Fab")
		)
		(fp_line
			(start 0.12065 -0.2794)
			(end -0.12065 -0.2794)
			(stroke
				(width 0.1)
				(type default)
			)
			(layer "B.Fab")
		)
		(fp_line
			(start 0.12065 -0.305054)
			(end 0.12065 -0.2794)
			(stroke
				(width 0.1)
				(type default)
			)
			(layer "B.Fab")
		)
		(fp_line
			(start -0.120396 0.3048)
			(end -0.120396 0.2794)
			(stroke
				(width 0.1)
				(type default)
			)
			(layer "B.Fab")
		)
		(fp_line
			(start -0.120396 0.2794)
			(end 0.12065 0.2794)
			(stroke
				(width 0.1)
				(type default)
			)
			(layer "B.Fab")
		)
		(fp_line
			(start -0.12065 -0.2794)
			(end -0.12065 -0.3048)
			(stroke
				(width 0.1)
				(type default)
			)
			(layer "B.Fab")
		)
		(fp_line
			(start -0.12065 -0.3048)
			(end -0.67945 -0.3048)
			(stroke
				(width 0.1)
				(type default)
			)
			(layer "B.Fab")
		)
		(fp_line
			(start -0.67945 0.3048)
			(end -0.120396 0.3048)
			(stroke
				(width 0.1)
				(type default)
			)
			(layer "B.Fab")
		)
		(fp_line
			(start -0.67945 -0.3048)
			(end -0.67945 0.3048)
			(stroke
				(width 0.1)
				(type default)
			)
			(layer "B.Fab")
		)
		(pad "1" smd circle
			(at 0.40005 0)
			(size 0 0)
			(layers "B.Cu" "B.Mask" "B.Paste")
			(net "PVDD18_S5_P0")
		)
		(pad "2" smd circle
			(at -0.40005 0)
			(size 0 0)
			(layers "B.Cu" "B.Mask" "B.Paste")
			(net "GND")
		)
	)
	(footprint ""
		(layer "B.Cu")
		(at 298.901104 -427.261528 180)
		(property "Reference" "C1073"
			(at 0 0 0)
			(layer "B.SilkS")
			(hide yes)
			(effects
				(font
					(size 1.27 1.27)
				)
				(justify mirror)
			)
		)
		(property "Value" ""
			(at 0 0 0)
			(layer "B.Fab")
			(effects
				(font
					(size 1.27 1.27)
				)
				(justify mirror)
			)
		)
		(duplicate_pad_numbers_are_jumpers no)
		(fp_line
			(start 0.299974 0.150114)
			(end 0.299974 -0.150114)
			(stroke
				(width 0.1)
				(type default)
			)
			(layer "B.Fab")
		)
		(fp_line
			(start 0.299974 -0.150114)
			(end -0.299974 -0.150114)
			(stroke
				(width 0.1)
				(type default)
			)
			(layer "B.Fab")
		)
		(fp_line
			(start -0.299974 0.150114)
			(end 0.299974 0.150114)
			(stroke
				(width 0.1)
				(type default)
			)
			(layer "B.Fab")
		)
		(fp_line
			(start -0.299974 -0.150114)
			(end -0.299974 0.150114)
			(stroke
				(width 0.1)
				(type default)
			)
			(layer "B.Fab")
		)
		(pad "1" smd rect
			(at 0.2667 0)
			(size 0.3048 0.381)
			(layers "B.Cu" "B.Mask" "B.Paste")
			(net "P3V3_AUX")
		)
		(pad "2" smd rect
			(at -0.2667 0)
			(size 0.3048 0.381)
			(layers "B.Cu" "B.Mask" "B.Paste")
			(net "GND")
		)
	)
	(footprint ""
		(layer "B.Cu")
		(at 445.888618 -193.99631)
		(property "Reference" "C132"
			(at 0 0 0)
			(layer "B.SilkS")
			(hide yes)
			(effects
				(font
					(size 1.27 1.27)
				)
				(justify mirror)
			)
		)
		(property "Value" ""
			(at 0 0 0)
			(layer "B.Fab")
			(effects
				(font
					(size 1.27 1.27)
				)
				(justify mirror)
			)
		)
		(duplicate_pad_numbers_are_jumpers no)
		(fp_line
			(start -0.7874 -0.4064)
			(end -0.7874 0.4064)
			(stroke
				(width 0.1524)
				(type default)
			)
			(layer "B.SilkS")
		)
		(fp_line
			(start -0.7874 0.4064)
			(end 0.7874 0.4064)
			(stroke
				(width 0.1524)
				(type default)
			)
			(layer "B.SilkS")
		)
		(fp_line
			(start 0.7874 -0.4064)
			(end -0.7874 -0.4064)
			(stroke
				(width 0.1524)
				(type default)
			)
			(layer "B.SilkS")
		)
		(fp_line
			(start 0.7874 0.4064)
			(end 0.7874 -0.4064)
			(stroke
				(width 0.1524)
				(type default)
			)
			(layer "B.SilkS")
		)
		(fp_line
			(start -0.67945 -0.3048)
			(end -0.67945 0.3048)
			(stroke
				(width 0.1)
				(type default)
			)
			(layer "B.Fab")
		)
		(fp_line
			(start -0.67945 0.3048)
			(end -0.120396 0.3048)
			(stroke
				(width 0.1)
				(type default)
			)
			(layer "B.Fab")
		)
		(fp_line
			(start -0.12065 -0.3048)
			(end -0.67945 -0.3048)
			(stroke
				(width 0.1)
				(type default)
			)
			(layer "B.Fab")
		)
		(fp_line
			(start -0.12065 -0.2794)
			(end -0.12065 -0.3048)
			(stroke
				(width 0.1)
				(type default)
			)
			(layer "B.Fab")
		)
		(fp_line
			(start -0.120396 0.2794)
			(end 0.12065 0.2794)
			(stroke
				(width 0.1)
				(type default)
			)
			(layer "B.Fab")
		)
		(fp_line
			(start -0.120396 0.3048)
			(end -0.120396 0.2794)
			(stroke
				(width 0.1)
				(type default)
			)
			(layer "B.Fab")
		)
		(fp_line
			(start 0.12065 -0.305054)
			(end 0.12065 -0.2794)
			(stroke
				(width 0.1)
				(type default)
			)
			(layer "B.Fab")
		)
		(fp_line
			(start 0.12065 -0.2794)
			(end -0.12065 -0.2794)
			(stroke
				(width 0.1)
				(type default)
			)
			(layer "B.Fab")
		)
		(fp_line
			(start 0.12065 0.2794)
			(end 0.12065 0.3048)
			(stroke
				(width 0.1)
				(type default)
			)
			(layer "B.Fab")
		)
		(fp_line
			(start 0.12065 0.3048)
			(end 0.67945 0.3048)
			(stroke
				(width 0.1)
				(type default)
			)
			(layer "B.Fab")
		)
		(fp_line
			(start 0.67945 -0.305054)
			(end 0.12065 -0.305054)
			(stroke
				(width 0.1)
				(type default)
			)
			(layer "B.Fab")
		)
		(fp_line
			(start 0.67945 0.3048)
			(end 0.67945 -0.305054)
			(stroke
				(width 0.1)
				(type default)
			)
			(layer "B.Fab")
		)
		(pad "1" smd circle
			(at 0.40005 0 180)
			(size 0 0)
			(layers "B.Cu" "B.Mask" "B.Paste")
			(net "P3V3_AUX")
		)
		(pad "2" smd circle
			(at -0.40005 0 180)
			(size 0 0)
			(layers "B.Cu" "B.Mask" "B.Paste")
			(net "GND")
		)
	)
	(footprint ""
		(layer "B.Cu")
		(at 62.467744 -408.517344 90)
		(property "Reference" "C6669"
			(at 0 0 90)
			(layer "B.SilkS")
			(hide yes)
			(effects
				(font
					(size 1.27 1.27)
				)
				(justify mirror)
			)
		)
		(property "Value" ""
			(at 0 0 90)
			(layer "B.Fab")
			(effects
				(font
					(size 1.27 1.27)
				)
				(justify mirror)
			)
		)
		(duplicate_pad_numbers_are_jumpers no)
		(fp_line
			(start 0.299974 -0.150114)
			(end -0.299974 -0.150114)
			(stroke
				(width 0.1)
				(type default)
			)
			(layer "B.Fab")
		)
		(fp_line
			(start -0.299974 -0.150114)
			(end -0.299974 0.150114)
			(stroke
				(width 0.1)
				(type default)
			)
			(layer "B.Fab")
		)
		(fp_line
			(start 0.299974 0.150114)
			(end 0.299974 -0.150114)
			(stroke
				(width 0.1)
				(type default)
			)
			(layer "B.Fab")
		)
		(fp_line
			(start -0.299974 0.150114)
			(end 0.299974 0.150114)
			(stroke
				(width 0.1)
				(type default)
			)
			(layer "B.Fab")
		)
		(pad "1" smd rect
			(at 0.2667 0 270)
			(size 0.3048 0.381)
			(layers "B.Cu" "B.Mask" "B.Paste")
			(net "P5E_CPU1_P1_TX_BUF_C_DP<4>")
		)
		(pad "2" smd rect
			(at -0.2667 0 270)
			(size 0.3048 0.381)
			(layers "B.Cu" "B.Mask" "B.Paste")
			(net "P5E_CPU1_P1_TX_BUF_DP<4>")
		)
	)
	(footprint ""
		(layer "B.Cu")
		(at 172.456094 -413.776668)
		(property "Reference" "R2915"
			(at 0 0 0)
			(layer "B.SilkS")
			(hide yes)
			(effects
				(font
					(size 1.27 1.27)
				)
				(justify mirror)
			)
		)
		(property "Value" ""
			(at 0 0 0)
			(layer "B.Fab")
			(effects
				(font
					(size 1.27 1.27)
				)
				(justify mirror)
			)
		)
		(duplicate_pad_numbers_are_jumpers no)
		(fp_line
			(start -0.7874 -0.4064)
			(end -0.7874 0.4064)
			(stroke
				(width 0.1524)
				(type default)
			)
			(layer "B.SilkS")
		)
		(fp_line
			(start -0.7874 0.4064)
			(end 0.7874 0.4064)
			(stroke
				(width 0.1524)
				(type default)
			)
			(layer "B.SilkS")
		)
		(fp_line
			(start 0.7874 -0.4064)
			(end -0.7874 -0.4064)
			(stroke
				(width 0.1524)
				(type default)
			)
			(layer "B.SilkS")
		)
		(fp_line
			(start 0.7874 0.4064)
			(end 0.7874 -0.4064)
			(stroke
				(width 0.1524)
				(type default)
			)
			(layer "B.SilkS")
		)
		(fp_line
			(start -0.67945 -0.3048)
			(end -0.67945 0.3048)
			(stroke
				(width 0.1)
				(type default)
			)
			(layer "B.Fab")
		)
		(fp_line
			(start -0.67945 0.3048)
			(end -0.120396 0.3048)
			(stroke
				(width 0.1)
				(type default)
			)
			(layer "B.Fab")
		)
		(fp_line
			(start -0.12065 -0.3048)
			(end -0.67945 -0.3048)
			(stroke
				(width 0.1)
				(type default)
			)
			(layer "B.Fab")
		)
		(fp_line
			(start -0.12065 -0.2794)
			(end -0.12065 -0.3048)
			(stroke
				(width 0.1)
				(type default)
			)
			(layer "B.Fab")
		)
		(fp_line
			(start -0.120396 0.2794)
			(end 0.12065 0.2794)
			(stroke
				(width 0.1)
				(type default)
			)
			(layer "B.Fab")
		)
		(fp_line
			(start -0.120396 0.3048)
			(end -0.120396 0.2794)
			(stroke
				(width 0.1)
				(type default)
			)
			(layer "B.Fab")
		)
		(fp_line
			(start 0.12065 -0.305054)
			(end 0.12065 -0.2794)
			(stroke
				(width 0.1)
				(type default)
			)
			(layer "B.Fab")
		)
		(fp_line
			(start 0.12065 -0.2794)
			(end -0.12065 -0.2794)
			(stroke
				(width 0.1)
				(type default)
			)
			(layer "B.Fab")
		)
		(fp_line
			(start 0.12065 0.2794)
			(end 0.12065 0.3048)
			(stroke
				(width 0.1)
				(type default)
			)
			(layer "B.Fab")
		)
		(fp_line
			(start 0.12065 0.3048)
			(end 0.67945 0.3048)
			(stroke
				(width 0.1)
				(type default)
			)
			(layer "B.Fab")
		)
		(fp_line
			(start 0.67945 -0.305054)
			(end 0.12065 -0.305054)
			(stroke
				(width 0.1)
				(type default)
			)
			(layer "B.Fab")
		)
		(fp_line
			(start 0.67945 0.3048)
			(end 0.67945 -0.305054)
			(stroke
				(width 0.1)
				(type default)
			)
			(layer "B.Fab")
		)
		(pad "1" smd circle
			(at 0.40005 0 180)
			(size 0 0)
			(layers "B.Cu" "B.Mask" "B.Paste")
			(net "BMC_MONITER_R")
		)
		(pad "2" smd circle
			(at -0.40005 0 180)
			(size 0 0)
			(layers "B.Cu" "B.Mask" "B.Paste")
			(net "GND")
		)
	)
	(footprint ""
		(layer "B.Cu")
		(at 423.63009 -359.84434)
		(property "Reference" "R8116"
			(at 0 0 0)
			(layer "B.SilkS")
			(hide yes)
			(effects
				(font
					(size 1.27 1.27)
				)
				(justify mirror)
			)
		)
		(property "Value" ""
			(at 0 0 0)
			(layer "B.Fab")
			(effects
				(font
					(size 1.27 1.27)
				)
				(justify mirror)
			)
		)
		(duplicate_pad_numbers_are_jumpers no)
		(fp_line
			(start -0.7874 -0.4064)
			(end -0.7874 0.4064)
			(stroke
				(width 0.1524)
				(type default)
			)
			(layer "B.SilkS")
		)
		(fp_line
			(start -0.7874 0.4064)
			(end 0.7874 0.4064)
			(stroke
				(width 0.1524)
				(type default)
			)
			(layer "B.SilkS")
		)
		(fp_line
			(start 0.7874 -0.4064)
			(end -0.7874 -0.4064)
			(stroke
				(width 0.1524)
				(type default)
			)
			(layer "B.SilkS")
		)
		(fp_line
			(start 0.7874 0.4064)
			(end 0.7874 -0.4064)
			(stroke
				(width 0.1524)
				(type default)
			)
			(layer "B.SilkS")
		)
		(fp_line
			(start -0.67945 -0.3048)
			(end -0.67945 0.3048)
			(stroke
				(width 0.1)
				(type default)
			)
			(layer "B.Fab")
		)
		(fp_line
			(start -0.67945 0.3048)
			(end -0.120396 0.3048)
			(stroke
				(width 0.1)
				(type default)
			)
			(layer "B.Fab")
		)
		(fp_line
			(start -0.12065 -0.3048)
			(end -0.67945 -0.3048)
			(stroke
				(width 0.1)
				(type default)
			)
			(layer "B.Fab")
		)
		(fp_line
			(start -0.12065 -0.2794)
			(end -0.12065 -0.3048)
			(stroke
				(width 0.1)
				(type default)
			)
			(layer "B.Fab")
		)
		(fp_line
			(start -0.120396 0.2794)
			(end 0.12065 0.2794)
			(stroke
				(width 0.1)
				(type default)
			)
			(layer "B.Fab")
		)
		(fp_line
			(start -0.120396 0.3048)
			(end -0.120396 0.2794)
			(stroke
				(width 0.1)
				(type default)
			)
			(layer "B.Fab")
		)
		(fp_line
			(start 0.12065 -0.305054)
			(end 0.12065 -0.2794)
			(stroke
				(width 0.1)
				(type default)
			)
			(layer "B.Fab")
		)
		(fp_line
			(start 0.12065 -0.2794)
			(end -0.12065 -0.2794)
			(stroke
				(width 0.1)
				(type default)
			)
			(layer "B.Fab")
		)
		(fp_line
			(start 0.12065 0.2794)
			(end 0.12065 0.3048)
			(stroke
				(width 0.1)
				(type default)
			)
			(layer "B.Fab")
		)
		(fp_line
			(start 0.12065 0.3048)
			(end 0.67945 0.3048)
			(stroke
				(width 0.1)
				(type default)
			)
			(layer "B.Fab")
		)
		(fp_line
			(start 0.67945 -0.305054)
			(end 0.12065 -0.305054)
			(stroke
				(width 0.1)
				(type default)
			)
			(layer "B.Fab")
		)
		(fp_line
			(start 0.67945 0.3048)
			(end 0.67945 -0.305054)
			(stroke
				(width 0.1)
				(type default)
			)
			(layer "B.Fab")
		)
		(pad "1" smd circle
			(at 0.40005 0 180)
			(size 0 0)
			(layers "B.Cu" "B.Mask" "B.Paste")
			(net "PVDD11_S3_P0_OCP_N")
		)
		(pad "2" smd circle
			(at -0.40005 0 180)
			(size 0 0)
			(layers "B.Cu" "B.Mask" "B.Paste")
			(net "PVDD11_S3_P0_OCP_N_R")
		)
	)
	(footprint ""
		(layer "B.Cu")
		(at 232.857802 -248.53265)
		(property "Reference" "U4"
			(at 1.58496 -2.89687 0)
			(unlocked yes)
			(layer "B.SilkS")
			(effects
				(font
					(size 0.7874 0.5842)
					(thickness 0.1524)
				)
				(justify mirror)
			)
		)
		(property "Value" ""
			(at 0 0 0)
			(layer "B.Fab")
			(effects
				(font
					(size 1.27 1.27)
				)
				(justify mirror)
			)
		)
		(duplicate_pad_numbers_are_jumpers no)
		(fp_line
			(start -1.03378 -1.284478)
			(end -1.03378 1.284478)
			(stroke
				(width 0.1524)
				(type default)
			)
			(layer "B.SilkS")
		)
		(fp_line
			(start -1.03378 1.284478)
			(end 1.03378 1.284478)
			(stroke
				(width 0.1524)
				(type default)
			)
			(layer "B.SilkS")
		)
		(fp_line
			(start 1.03378 -1.284478)
			(end -1.03378 -1.284478)
			(stroke
				(width 0.1524)
				(type default)
			)
			(layer "B.SilkS")
		)
		(fp_line
			(start 1.03378 1.284478)
			(end 1.03378 -1.284478)
			(stroke
				(width 0.1524)
				(type default)
			)
			(layer "B.SilkS")
		)
		(fp_poly
			(pts
				(xy 1.806702 -1.052576) (xy 1.806702 -0.447548) (xy 1.201674 -0.750062)
			)
			(stroke
				(width 0)
				(type default)
			)
			(fill yes)
			(layer "B.SilkS")
		)
		(fp_line
			(start -0.774954 -1.02489)
			(end -0.774954 1.02489)
			(stroke
				(width 0.1)
				(type default)
			)
			(layer "B.Fab")
		)
		(fp_line
			(start -0.774954 1.02489)
			(end 0.774954 1.02489)
			(stroke
				(width 0.1)
				(type default)
			)
			(layer "B.Fab")
		)
		(fp_line
			(start 0.774954 -1.02489)
			(end -0.774954 -1.02489)
			(stroke
				(width 0.1)
				(type default)
			)
			(layer "B.Fab")
		)
		(fp_line
			(start 0.774954 1.02489)
			(end 0.774954 -1.02489)
			(stroke
				(width 0.1)
				(type default)
			)
			(layer "B.Fab")
		)
		(fp_poly
			(pts
				(xy 1.201674 -0.750062) (xy 1.806702 -0.447548) (xy 1.806702 -1.052576)
			)
			(stroke
				(width 0)
				(type default)
			)
			(fill yes)
			(layer "B.Fab")
		)
		(pad "1" smd rect
			(at 0.64008 -0.750062 90)
			(size 0.3048 0.5334)
			(layers "B.Cu" "B.Mask" "B.Paste")
			(net "SMB_APML_CPU0_MUX2_SCL")
		)
		(pad "2" smd rect
			(at 0.64008 -0.249936 90)
			(size 0.254 0.5334)
			(layers "B.Cu" "B.Mask" "B.Paste")
			(net "SMB_APML_CPU0_MUX2_SDA")
		)
		(pad "3" smd rect
			(at 0.64008 0.249936 90)
			(size 0.254 0.5334)
			(layers "B.Cu" "B.Mask" "B.Paste")
			(net "SMB_APML_CPU1_MUX2_SCL")
		)
		(pad "4" smd rect
			(at 0.64008 0.750062 90)
			(size 0.3048 0.5334)
			(layers "B.Cu" "B.Mask" "B.Paste")
			(net "SMB_APML_CPU1_MUX2_SDA")
		)
		(pad "5" smd rect
			(at 0 0.839978 180)
			(size 0.3302 0.635)
			(layers "B.Cu" "B.Mask" "B.Paste")
			(net "GND")
		)
		(pad "6" smd rect
			(at -0.64008 0.750062 90)
			(size 0.3048 0.5334)
			(layers "B.Cu" "B.Mask" "B.Paste")
			(net "FM_APML_MUX2_OE_N")
		)
		(pad "7" smd rect
			(at -0.64008 0.249936 90)
			(size 0.254 0.5334)
			(layers "B.Cu" "B.Mask" "B.Paste")
			(net "SMB_CPU0_CPU1_APML_MUX2_SDA")
		)
		(pad "8" smd rect
			(at -0.64008 -0.249936 90)
			(size 0.254 0.5334)
			(layers "B.Cu" "B.Mask" "B.Paste")
			(net "SMB_CPU0_CPU1_APML_MUX2_SCL")
		)
		(pad "9" smd rect
			(at -0.64008 -0.750062 90)
			(size 0.3048 0.5334)
			(layers "B.Cu" "B.Mask" "B.Paste")
			(net "FM_APML_MUX2_SEL")
		)
		(pad "10" smd rect
			(at 0 -0.839978 180)
			(size 0.3302 0.635)
			(layers "B.Cu" "B.Mask" "B.Paste")
			(net "P3V3_AUX")
		)
	)
	(footprint ""
		(layer "B.Cu")
		(at 200.406 -144.272 90)
		(property "Reference" "R8104"
			(at 0 0 90)
			(layer "B.SilkS")
			(hide yes)
			(effects
				(font
					(size 1.27 1.27)
				)
				(justify mirror)
			)
		)
		(property "Value" ""
			(at 0 0 90)
			(layer "B.Fab")
			(effects
				(font
					(size 1.27 1.27)
				)
				(justify mirror)
			)
		)
		(duplicate_pad_numbers_are_jumpers no)
		(fp_line
			(start 0.7874 -0.4064)
			(end -0.7874 -0.4064)
			(stroke
				(width 0.1524)
				(type default)
			)
			(layer "B.SilkS")
		)
		(fp_line
			(start -0.7874 -0.4064)
			(end -0.7874 0.4064)
			(stroke
				(width 0.1524)
				(type default)
			)
			(layer "B.SilkS")
		)
		(fp_line
			(start 0.7874 0.4064)
			(end 0.7874 -0.4064)
			(stroke
				(width 0.1524)
				(type default)
			)
			(layer "B.SilkS")
		)
		(fp_line
			(start -0.7874 0.4064)
			(end 0.7874 0.4064)
			(stroke
				(width 0.1524)
				(type default)
			)
			(layer "B.SilkS")
		)
		(fp_line
			(start 0.67945 -0.305054)
			(end 0.12065 -0.305054)
			(stroke
				(width 0.1)
				(type default)
			)
			(layer "B.Fab")
		)
		(fp_line
			(start 0.12065 -0.305054)
			(end 0.12065 -0.2794)
			(stroke
				(width 0.1)
				(type default)
			)
			(layer "B.Fab")
		)
		(fp_line
			(start -0.12065 -0.3048)
			(end -0.67945 -0.3048)
			(stroke
				(width 0.1)
				(type default)
			)
			(layer "B.Fab")
		)
		(fp_line
			(start -0.67945 -0.3048)
			(end -0.67945 0.3048)
			(stroke
				(width 0.1)
				(type default)
			)
			(layer "B.Fab")
		)
		(fp_line
			(start 0.12065 -0.2794)
			(end -0.12065 -0.2794)
			(stroke
				(width 0.1)
				(type default)
			)
			(layer "B.Fab")
		)
		(fp_line
			(start -0.12065 -0.2794)
			(end -0.12065 -0.3048)
			(stroke
				(width 0.1)
				(type default)
			)
			(layer "B.Fab")
		)
		(fp_line
			(start 0.12065 0.2794)
			(end 0.12065 0.3048)
			(stroke
				(width 0.1)
				(type default)
			)
			(layer "B.Fab")
		)
		(fp_line
			(start -0.120396 0.2794)
			(end 0.12065 0.2794)
			(stroke
				(width 0.1)
				(type default)
			)
			(layer "B.Fab")
		)
		(fp_line
			(start 0.67945 0.3048)
			(end 0.67945 -0.305054)
			(stroke
				(width 0.1)
				(type default)
			)
			(layer "B.Fab")
		)
		(fp_line
			(start 0.12065 0.3048)
			(end 0.67945 0.3048)
			(stroke
				(width 0.1)
				(type default)
			)
			(layer "B.Fab")
		)
		(fp_line
			(start -0.120396 0.3048)
			(end -0.120396 0.2794)
			(stroke
				(width 0.1)
				(type default)
			)
			(layer "B.Fab")
		)
		(fp_line
			(start -0.67945 0.3048)
			(end -0.120396 0.3048)
			(stroke
				(width 0.1)
				(type default)
			)
			(layer "B.Fab")
		)
		(pad "1" smd circle
			(at 0.40005 0 270)
			(size 0 0)
			(layers "B.Cu" "B.Mask" "B.Paste")
			(net "FM_AC_PWR_BTN_R_N")
		)
		(pad "2" smd circle
			(at -0.40005 0 270)
			(size 0 0)
			(layers "B.Cu" "B.Mask" "B.Paste")
			(net "FM_AC_PWR_BTN_PLD_N")
		)
	)
	(footprint ""
		(layer "B.Cu")
		(at 361.645454 -251.78131)
		(property "Reference" "C2536"
			(at 0 0 0)
			(layer "B.SilkS")
			(hide yes)
			(effects
				(font
					(size 1.27 1.27)
				)
				(justify mirror)
			)
		)
		(property "Value" ""
			(at 0 0 0)
			(layer "B.Fab")
			(effects
				(font
					(size 1.27 1.27)
				)
				(justify mirror)
			)
		)
		(duplicate_pad_numbers_are_jumpers no)
		(fp_line
			(start -0.7874 -0.4064)
			(end -0.7874 0.4064)
			(stroke
				(width 0.1524)
				(type default)
			)
			(layer "B.SilkS")
		)
		(fp_line
			(start -0.7874 0.4064)
			(end 0.7874 0.4064)
			(stroke
				(width 0.1524)
				(type default)
			)
			(layer "B.SilkS")
		)
		(fp_line
			(start 0.7874 -0.4064)
			(end -0.7874 -0.4064)
			(stroke
				(width 0.1524)
				(type default)
			)
			(layer "B.SilkS")
		)
		(fp_line
			(start 0.7874 0.4064)
			(end 0.7874 -0.4064)
			(stroke
				(width 0.1524)
				(type default)
			)
			(layer "B.SilkS")
		)
		(fp_line
			(start -0.67945 -0.3048)
			(end -0.67945 0.3048)
			(stroke
				(width 0.1)
				(type default)
			)
			(layer "B.Fab")
		)
		(fp_line
			(start -0.67945 0.3048)
			(end -0.120396 0.3048)
			(stroke
				(width 0.1)
				(type default)
			)
			(layer "B.Fab")
		)
		(fp_line
			(start -0.12065 -0.3048)
			(end -0.67945 -0.3048)
			(stroke
				(width 0.1)
				(type default)
			)
			(layer "B.Fab")
		)
		(fp_line
			(start -0.12065 -0.2794)
			(end -0.12065 -0.3048)
			(stroke
				(width 0.1)
				(type default)
			)
			(layer "B.Fab")
		)
		(fp_line
			(start -0.120396 0.2794)
			(end 0.12065 0.2794)
			(stroke
				(width 0.1)
				(type default)
			)
			(layer "B.Fab")
		)
		(fp_line
			(start -0.120396 0.3048)
			(end -0.120396 0.2794)
			(stroke
				(width 0.1)
				(type default)
			)
			(layer "B.Fab")
		)
		(fp_line
			(start 0.12065 -0.305054)
			(end 0.12065 -0.2794)
			(stroke
				(width 0.1)
				(type default)
			)
			(layer "B.Fab")
		)
		(fp_line
			(start 0.12065 -0.2794)
			(end -0.12065 -0.2794)
			(stroke
				(width 0.1)
				(type default)
			)
			(layer "B.Fab")
		)
		(fp_line
			(start 0.12065 0.2794)
			(end 0.12065 0.3048)
			(stroke
				(width 0.1)
				(type default)
			)
			(layer "B.Fab")
		)
		(fp_line
			(start 0.12065 0.3048)
			(end 0.67945 0.3048)
			(stroke
				(width 0.1)
				(type default)
			)
			(layer "B.Fab")
		)
		(fp_line
			(start 0.67945 -0.305054)
			(end 0.12065 -0.305054)
			(stroke
				(width 0.1)
				(type default)
			)
			(layer "B.Fab")
		)
		(fp_line
			(start 0.67945 0.3048)
			(end 0.67945 -0.305054)
			(stroke
				(width 0.1)
				(type default)
			)
			(layer "B.Fab")
		)
		(pad "1" smd circle
			(at 0.40005 0 180)
			(size 0 0)
			(layers "B.Cu" "B.Mask" "B.Paste")
			(net "PVDDCR_SOC_P0")
		)
		(pad "2" smd circle
			(at -0.40005 0 180)
			(size 0 0)
			(layers "B.Cu" "B.Mask" "B.Paste")
			(net "GND")
		)
	)
	(footprint ""
		(layer "B.Cu")
		(at 417.419028 -398.942052 90)
		(property "Reference" "C973"
			(at 0 0 90)
			(layer "B.SilkS")
			(hide yes)
			(effects
				(font
					(size 1.27 1.27)
				)
				(justify mirror)
			)
		)
		(property "Value" ""
			(at 0 0 90)
			(layer "B.Fab")
			(effects
				(font
					(size 1.27 1.27)
				)
				(justify mirror)
			)
		)
		(duplicate_pad_numbers_are_jumpers no)
		(fp_line
			(start 0.7874 -0.4064)
			(end -0.7874 -0.4064)
			(stroke
				(width 0.1524)
				(type default)
			)
			(layer "B.SilkS")
		)
		(fp_line
			(start -0.7874 -0.4064)
			(end -0.7874 0.4064)
			(stroke
				(width 0.1524)
				(type default)
			)
			(layer "B.SilkS")
		)
		(fp_line
			(start 0.7874 0.4064)
			(end 0.7874 -0.4064)
			(stroke
				(width 0.1524)
				(type default)
			)
			(layer "B.SilkS")
		)
		(fp_line
			(start -0.7874 0.4064)
			(end 0.7874 0.4064)
			(stroke
				(width 0.1524)
				(type default)
			)
			(layer "B.SilkS")
		)
		(fp_line
			(start 0.67945 -0.305054)
			(end 0.12065 -0.305054)
			(stroke
				(width 0.1)
				(type default)
			)
			(layer "B.Fab")
		)
		(fp_line
			(start 0.12065 -0.305054)
			(end 0.12065 -0.2794)
			(stroke
				(width 0.1)
				(type default)
			)
			(layer "B.Fab")
		)
		(fp_line
			(start -0.12065 -0.3048)
			(end -0.67945 -0.3048)
			(stroke
				(width 0.1)
				(type default)
			)
			(layer "B.Fab")
		)
		(fp_line
			(start -0.67945 -0.3048)
			(end -0.67945 0.3048)
			(stroke
				(width 0.1)
				(type default)
			)
			(layer "B.Fab")
		)
		(fp_line
			(start 0.12065 -0.2794)
			(end -0.12065 -0.2794)
			(stroke
				(width 0.1)
				(type default)
			)
			(layer "B.Fab")
		)
		(fp_line
			(start -0.12065 -0.2794)
			(end -0.12065 -0.3048)
			(stroke
				(width 0.1)
				(type default)
			)
			(layer "B.Fab")
		)
		(fp_line
			(start 0.12065 0.2794)
			(end 0.12065 0.3048)
			(stroke
				(width 0.1)
				(type default)
			)
			(layer "B.Fab")
		)
		(fp_line
			(start -0.120396 0.2794)
			(end 0.12065 0.2794)
			(stroke
				(width 0.1)
				(type default)
			)
			(layer "B.Fab")
		)
		(fp_line
			(start 0.67945 0.3048)
			(end 0.67945 -0.305054)
			(stroke
				(width 0.1)
				(type default)
			)
			(layer "B.Fab")
		)
		(fp_line
			(start 0.12065 0.3048)
			(end 0.67945 0.3048)
			(stroke
				(width 0.1)
				(type default)
			)
			(layer "B.Fab")
		)
		(fp_line
			(start -0.120396 0.3048)
			(end -0.120396 0.2794)
			(stroke
				(width 0.1)
				(type default)
			)
			(layer "B.Fab")
		)
		(fp_line
			(start -0.67945 0.3048)
			(end -0.120396 0.3048)
			(stroke
				(width 0.1)
				(type default)
			)
			(layer "B.Fab")
		)
		(pad "1" smd circle
			(at 0.40005 0 270)
			(size 0 0)
			(layers "B.Cu" "B.Mask" "B.Paste")
			(net "P0V9_CPU0_RT2_2A")
		)
		(pad "2" smd circle
			(at -0.40005 0 270)
			(size 0 0)
			(layers "B.Cu" "B.Mask" "B.Paste")
			(net "GND")
		)
	)
	(footprint ""
		(layer "B.Cu")
		(at 171.2849 -109.055408)
		(property "Reference" "R172"
			(at 0 0 0)
			(layer "B.SilkS")
			(hide yes)
			(effects
				(font
					(size 1.27 1.27)
				)
				(justify mirror)
			)
		)
		(property "Value" ""
			(at 0 0 0)
			(layer "B.Fab")
			(effects
				(font
					(size 1.27 1.27)
				)
				(justify mirror)
			)
		)
		(duplicate_pad_numbers_are_jumpers no)
		(fp_line
			(start -0.7874 -0.4064)
			(end -0.7874 0.4064)
			(stroke
				(width 0.1524)
				(type default)
			)
			(layer "B.SilkS")
		)
		(fp_line
			(start -0.7874 0.4064)
			(end 0.7874 0.4064)
			(stroke
				(width 0.1524)
				(type default)
			)
			(layer "B.SilkS")
		)
		(fp_line
			(start 0.7874 -0.4064)
			(end -0.7874 -0.4064)
			(stroke
				(width 0.1524)
				(type default)
			)
			(layer "B.SilkS")
		)
		(fp_line
			(start 0.7874 0.4064)
			(end 0.7874 -0.4064)
			(stroke
				(width 0.1524)
				(type default)
			)
			(layer "B.SilkS")
		)
		(fp_line
			(start -0.67945 -0.3048)
			(end -0.67945 0.3048)
			(stroke
				(width 0.1)
				(type default)
			)
			(layer "B.Fab")
		)
		(fp_line
			(start -0.67945 0.3048)
			(end -0.120396 0.3048)
			(stroke
				(width 0.1)
				(type default)
			)
			(layer "B.Fab")
		)
		(fp_line
			(start -0.12065 -0.3048)
			(end -0.67945 -0.3048)
			(stroke
				(width 0.1)
				(type default)
			)
			(layer "B.Fab")
		)
		(fp_line
			(start -0.12065 -0.2794)
			(end -0.12065 -0.3048)
			(stroke
				(width 0.1)
				(type default)
			)
			(layer "B.Fab")
		)
		(fp_line
			(start -0.120396 0.2794)
			(end 0.12065 0.2794)
			(stroke
				(width 0.1)
				(type default)
			)
			(layer "B.Fab")
		)
		(fp_line
			(start -0.120396 0.3048)
			(end -0.120396 0.2794)
			(stroke
				(width 0.1)
				(type default)
			)
			(layer "B.Fab")
		)
		(fp_line
			(start 0.12065 -0.305054)
			(end 0.12065 -0.2794)
			(stroke
				(width 0.1)
				(type default)
			)
			(layer "B.Fab")
		)
		(fp_line
			(start 0.12065 -0.2794)
			(end -0.12065 -0.2794)
			(stroke
				(width 0.1)
				(type default)
			)
			(layer "B.Fab")
		)
		(fp_line
			(start 0.12065 0.2794)
			(end 0.12065 0.3048)
			(stroke
				(width 0.1)
				(type default)
			)
			(layer "B.Fab")
		)
		(fp_line
			(start 0.12065 0.3048)
			(end 0.67945 0.3048)
			(stroke
				(width 0.1)
				(type default)
			)
			(layer "B.Fab")
		)
		(fp_line
			(start 0.67945 -0.305054)
			(end 0.12065 -0.305054)
			(stroke
				(width 0.1)
				(type default)
			)
			(layer "B.Fab")
		)
		(fp_line
			(start 0.67945 0.3048)
			(end 0.67945 -0.305054)
			(stroke
				(width 0.1)
				(type default)
			)
			(layer "B.Fab")
		)
		(pad "1" smd circle
			(at 0.40005 0 180)
			(size 0 0)
			(layers "B.Cu" "B.Mask" "B.Paste")
			(net "FM_I3C_CPU1_MUX1_R_SEL")
		)
		(pad "2" smd circle
			(at -0.40005 0 180)
			(size 0 0)
			(layers "B.Cu" "B.Mask" "B.Paste")
			(net "FM_I3C_CPU1_MUX1_SEL")
		)
	)
	(footprint ""
		(layer "B.Cu")
		(at 232.537 -333.883 -90)
		(property "Reference" "R6769"
			(at 0 0 90)
			(layer "B.SilkS")
			(hide yes)
			(effects
				(font
					(size 1.27 1.27)
				)
				(justify mirror)
			)
		)
		(property "Value" ""
			(at 0 0 90)
			(layer "B.Fab")
			(effects
				(font
					(size 1.27 1.27)
				)
				(justify mirror)
			)
		)
		(duplicate_pad_numbers_are_jumpers no)
		(fp_line
			(start -0.32512 0.175006)
			(end 0.32512 0.175006)
			(stroke
				(width 0.1)
				(type default)
			)
			(layer "B.Fab")
		)
		(fp_line
			(start 0.32512 0.175006)
			(end 0.32512 -0.175006)
			(stroke
				(width 0.1)
				(type default)
			)
			(layer "B.Fab")
		)
		(fp_line
			(start -0.32512 -0.175006)
			(end -0.32512 0.175006)
			(stroke
				(width 0.1)
				(type default)
			)
			(layer "B.Fab")
		)
		(fp_line
			(start 0.32512 -0.175006)
			(end -0.32512 -0.175006)
			(stroke
				(width 0.1)
				(type default)
			)
			(layer "B.Fab")
		)
		(pad "1" smd rect
			(at 0.2667 0 90)
			(size 0.3048 0.381)
			(layers "B.Cu" "B.Mask" "B.Paste")
			(net "P1V8_CPU0_RT_1D")
		)
		(pad "2" smd rect
			(at -0.2667 0 270)
			(size 0.3048 0.381)
			(layers "B.Cu" "B.Mask" "B.Paste")
			(net "SMB_RT_CPU0_P2_R_SCL")
		)
	)
	(footprint ""
		(layer "B.Cu")
		(at 324.916038 -395.466062 -90)
		(property "Reference" "C503"
			(at 0 0 90)
			(layer "B.SilkS")
			(hide yes)
			(effects
				(font
					(size 1.27 1.27)
				)
				(justify mirror)
			)
		)
		(property "Value" ""
			(at 0 0 90)
			(layer "B.Fab")
			(effects
				(font
					(size 1.27 1.27)
				)
				(justify mirror)
			)
		)
		(duplicate_pad_numbers_are_jumpers no)
		(fp_line
			(start -1.524 0.762)
			(end 1.524 0.762)
			(stroke
				(width 0.1524)
				(type default)
			)
			(layer "B.SilkS")
		)
		(fp_line
			(start 1.524 0.762)
			(end 1.524 -0.762)
			(stroke
				(width 0.1524)
				(type default)
			)
			(layer "B.SilkS")
		)
		(fp_line
			(start -1.524 -0.762)
			(end -1.524 0.762)
			(stroke
				(width 0.1524)
				(type default)
			)
			(layer "B.SilkS")
		)
		(fp_line
			(start 1.524 -0.762)
			(end -1.524 -0.762)
			(stroke
				(width 0.1524)
				(type default)
			)
			(layer "B.SilkS")
		)
		(fp_line
			(start -1.1049 0.724916)
			(end -1.1049 -0.724916)
			(stroke
				(width 0.1)
				(type default)
			)
			(layer "B.Fab")
		)
		(fp_line
			(start 1.1049 0.724916)
			(end -1.1049 0.724916)
			(stroke
				(width 0.1)
				(type default)
			)
			(layer "B.Fab")
		)
		(fp_line
			(start -1.1049 -0.724916)
			(end 1.1049 -0.724916)
			(stroke
				(width 0.1)
				(type default)
			)
			(layer "B.Fab")
		)
		(fp_line
			(start 1.1049 -0.724916)
			(end 1.1049 0.724916)
			(stroke
				(width 0.1)
				(type default)
			)
			(layer "B.Fab")
		)
		(pad "1" smd rect
			(at 0.889 0 270)
			(size 1.016 1.27)
			(layers "B.Cu" "B.Mask" "B.Paste")
			(net "P1V8_CPU0_RT0_1A")
		)
		(pad "2" smd rect
			(at -0.889 0 270)
			(size 1.016 1.27)
			(layers "B.Cu" "B.Mask" "B.Paste")
			(net "GND")
		)
	)
	(footprint ""
		(layer "B.Cu")
		(at 108.627164 -261.748016 90)
		(property "Reference" "C2494"
			(at 0 0 90)
			(layer "B.SilkS")
			(hide yes)
			(effects
				(font
					(size 1.27 1.27)
				)
				(justify mirror)
			)
		)
		(property "Value" ""
			(at 0 0 90)
			(layer "B.Fab")
			(effects
				(font
					(size 1.27 1.27)
				)
				(justify mirror)
			)
		)
		(duplicate_pad_numbers_are_jumpers no)
		(fp_line
			(start 0.7874 -0.4064)
			(end -0.7874 -0.4064)
			(stroke
				(width 0.1524)
				(type default)
			)
			(layer "B.SilkS")
		)
		(fp_line
			(start -0.7874 -0.4064)
			(end -0.7874 0.4064)
			(stroke
				(width 0.1524)
				(type default)
			)
			(layer "B.SilkS")
		)
		(fp_line
			(start 0.7874 0.4064)
			(end 0.7874 -0.4064)
			(stroke
				(width 0.1524)
				(type default)
			)
			(layer "B.SilkS")
		)
		(fp_line
			(start -0.7874 0.4064)
			(end 0.7874 0.4064)
			(stroke
				(width 0.1524)
				(type default)
			)
			(layer "B.SilkS")
		)
		(fp_line
			(start 0.67945 -0.305054)
			(end 0.12065 -0.305054)
			(stroke
				(width 0.1)
				(type default)
			)
			(layer "B.Fab")
		)
		(fp_line
			(start 0.12065 -0.305054)
			(end 0.12065 -0.2794)
			(stroke
				(width 0.1)
				(type default)
			)
			(layer "B.Fab")
		)
		(fp_line
			(start -0.12065 -0.3048)
			(end -0.67945 -0.3048)
			(stroke
				(width 0.1)
				(type default)
			)
			(layer "B.Fab")
		)
		(fp_line
			(start -0.67945 -0.3048)
			(end -0.67945 0.3048)
			(stroke
				(width 0.1)
				(type default)
			)
			(layer "B.Fab")
		)
		(fp_line
			(start 0.12065 -0.2794)
			(end -0.12065 -0.2794)
			(stroke
				(width 0.1)
				(type default)
			)
			(layer "B.Fab")
		)
		(fp_line
			(start -0.12065 -0.2794)
			(end -0.12065 -0.3048)
			(stroke
				(width 0.1)
				(type default)
			)
			(layer "B.Fab")
		)
		(fp_line
			(start 0.12065 0.2794)
			(end 0.12065 0.3048)
			(stroke
				(width 0.1)
				(type default)
			)
			(layer "B.Fab")
		)
		(fp_line
			(start -0.120396 0.2794)
			(end 0.12065 0.2794)
			(stroke
				(width 0.1)
				(type default)
			)
			(layer "B.Fab")
		)
		(fp_line
			(start 0.67945 0.3048)
			(end 0.67945 -0.305054)
			(stroke
				(width 0.1)
				(type default)
			)
			(layer "B.Fab")
		)
		(fp_line
			(start 0.12065 0.3048)
			(end 0.67945 0.3048)
			(stroke
				(width 0.1)
				(type default)
			)
			(layer "B.Fab")
		)
		(fp_line
			(start -0.120396 0.3048)
			(end -0.120396 0.2794)
			(stroke
				(width 0.1)
				(type default)
			)
			(layer "B.Fab")
		)
		(fp_line
			(start -0.67945 0.3048)
			(end -0.120396 0.3048)
			(stroke
				(width 0.1)
				(type default)
			)
			(layer "B.Fab")
		)
		(pad "1" smd circle
			(at 0.40005 0 270)
			(size 0 0)
			(layers "B.Cu" "B.Mask" "B.Paste")
			(net "PVDD11_S3_P1")
		)
		(pad "2" smd circle
			(at -0.40005 0 270)
			(size 0 0)
			(layers "B.Cu" "B.Mask" "B.Paste")
			(net "GND")
		)
	)
	(footprint ""
		(layer "B.Cu")
		(at 156.154374 -323.798692)
		(property "Reference" "R562"
			(at 0 0 0)
			(layer "B.SilkS")
			(hide yes)
			(effects
				(font
					(size 1.27 1.27)
				)
				(justify mirror)
			)
		)
		(property "Value" ""
			(at 0 0 0)
			(layer "B.Fab")
			(effects
				(font
					(size 1.27 1.27)
				)
				(justify mirror)
			)
		)
		(duplicate_pad_numbers_are_jumpers no)
		(fp_line
			(start -0.7874 -0.4064)
			(end -0.7874 0.4064)
			(stroke
				(width 0.1524)
				(type default)
			)
			(layer "B.SilkS")
		)
		(fp_line
			(start -0.7874 0.4064)
			(end 0.7874 0.4064)
			(stroke
				(width 0.1524)
				(type default)
			)
			(layer "B.SilkS")
		)
		(fp_line
			(start 0.7874 -0.4064)
			(end -0.7874 -0.4064)
			(stroke
				(width 0.1524)
				(type default)
			)
			(layer "B.SilkS")
		)
		(fp_line
			(start 0.7874 0.4064)
			(end 0.7874 -0.4064)
			(stroke
				(width 0.1524)
				(type default)
			)
			(layer "B.SilkS")
		)
		(fp_line
			(start -0.67945 -0.3048)
			(end -0.67945 0.3048)
			(stroke
				(width 0.1)
				(type default)
			)
			(layer "B.Fab")
		)
		(fp_line
			(start -0.67945 0.3048)
			(end -0.120396 0.3048)
			(stroke
				(width 0.1)
				(type default)
			)
			(layer "B.Fab")
		)
		(fp_line
			(start -0.12065 -0.3048)
			(end -0.67945 -0.3048)
			(stroke
				(width 0.1)
				(type default)
			)
			(layer "B.Fab")
		)
		(fp_line
			(start -0.12065 -0.2794)
			(end -0.12065 -0.3048)
			(stroke
				(width 0.1)
				(type default)
			)
			(layer "B.Fab")
		)
		(fp_line
			(start -0.120396 0.2794)
			(end 0.12065 0.2794)
			(stroke
				(width 0.1)
				(type default)
			)
			(layer "B.Fab")
		)
		(fp_line
			(start -0.120396 0.3048)
			(end -0.120396 0.2794)
			(stroke
				(width 0.1)
				(type default)
			)
			(layer "B.Fab")
		)
		(fp_line
			(start 0.12065 -0.305054)
			(end 0.12065 -0.2794)
			(stroke
				(width 0.1)
				(type default)
			)
			(layer "B.Fab")
		)
		(fp_line
			(start 0.12065 -0.2794)
			(end -0.12065 -0.2794)
			(stroke
				(width 0.1)
				(type default)
			)
			(layer "B.Fab")
		)
		(fp_line
			(start 0.12065 0.2794)
			(end 0.12065 0.3048)
			(stroke
				(width 0.1)
				(type default)
			)
			(layer "B.Fab")
		)
		(fp_line
			(start 0.12065 0.3048)
			(end 0.67945 0.3048)
			(stroke
				(width 0.1)
				(type default)
			)
			(layer "B.Fab")
		)
		(fp_line
			(start 0.67945 -0.305054)
			(end 0.12065 -0.305054)
			(stroke
				(width 0.1)
				(type default)
			)
			(layer "B.Fab")
		)
		(fp_line
			(start 0.67945 0.3048)
			(end 0.67945 -0.305054)
			(stroke
				(width 0.1)
				(type default)
			)
			(layer "B.Fab")
		)
		(pad "1" smd circle
			(at 0.40005 0 180)
			(size 0 0)
			(layers "B.Cu" "B.Mask" "B.Paste")
			(net "PVDD18_S5_P1")
		)
		(pad "2" smd circle
			(at -0.40005 0 180)
			(size 0 0)
			(layers "B.Cu" "B.Mask" "B.Paste")
			(net "CPU1_NMI_SYNC_FLOOD_N")
		)
	)
	(footprint ""
		(layer "B.Cu")
		(at 138.24204 -389.81126)
		(property "Reference" "PJ09_P1_P"
			(at 0 0 0)
			(layer "B.SilkS")
			(hide yes)
			(effects
				(font
					(size 1.27 1.27)
				)
				(justify mirror)
			)
		)
		(property "Value" ""
			(at 0 0 0)
			(layer "B.Fab")
			(effects
				(font
					(size 1.27 1.27)
				)
				(justify mirror)
			)
		)
		(duplicate_pad_numbers_are_jumpers no)
		(zone
			(layer "In15.Cu")
			(hatch none 0.5)
			(connect_pads
				(clearance 0)
			)
			(min_thickness 0.25)
			(keepout
				(tracks allowed)
				(vias not_allowed)
				(pads allowed)
				(copperpour not_allowed)
				(footprints allowed)
			)
			(placement
				(enabled no)
				(sheetname "")
			)
			(fill
				(thermal_gap 0.5)
				(thermal_bridge_width 0.5)
				(island_removal_mode 0)
			)
			(polygon
				(pts
					(xy 138.45794 -389.62076) (xy 138.02614 -389.62076) (xy 138.02614 -390.00176) (xy 138.45794 -390.00176)
				)
			)
		)
	)
	(footprint ""
		(layer "B.Cu")
		(at 111.11738 -175.506634 90)
		(property "Reference" "PR200"
			(at 0 0 90)
			(layer "B.SilkS")
			(hide yes)
			(effects
				(font
					(size 1.27 1.27)
				)
				(justify mirror)
			)
		)
		(property "Value" ""
			(at 0 0 90)
			(layer "B.Fab")
			(effects
				(font
					(size 1.27 1.27)
				)
				(justify mirror)
			)
		)
		(duplicate_pad_numbers_are_jumpers no)
		(fp_line
			(start 0.7874 -0.4064)
			(end -0.7874 -0.4064)
			(stroke
				(width 0.1524)
				(type default)
			)
			(layer "B.SilkS")
		)
		(fp_line
			(start -0.7874 -0.4064)
			(end -0.7874 0.4064)
			(stroke
				(width 0.1524)
				(type default)
			)
			(layer "B.SilkS")
		)
		(fp_line
			(start 0.7874 0.4064)
			(end 0.7874 -0.4064)
			(stroke
				(width 0.1524)
				(type default)
			)
			(layer "B.SilkS")
		)
		(fp_line
			(start -0.7874 0.4064)
			(end 0.7874 0.4064)
			(stroke
				(width 0.1524)
				(type default)
			)
			(layer "B.SilkS")
		)
		(fp_line
			(start 0.67945 -0.305054)
			(end 0.12065 -0.305054)
			(stroke
				(width 0.1)
				(type default)
			)
			(layer "B.Fab")
		)
		(fp_line
			(start 0.12065 -0.305054)
			(end 0.12065 -0.2794)
			(stroke
				(width 0.1)
				(type default)
			)
			(layer "B.Fab")
		)
		(fp_line
			(start -0.12065 -0.3048)
			(end -0.67945 -0.3048)
			(stroke
				(width 0.1)
				(type default)
			)
			(layer "B.Fab")
		)
		(fp_line
			(start -0.67945 -0.3048)
			(end -0.67945 0.3048)
			(stroke
				(width 0.1)
				(type default)
			)
			(layer "B.Fab")
		)
		(fp_line
			(start 0.12065 -0.2794)
			(end -0.12065 -0.2794)
			(stroke
				(width 0.1)
				(type default)
			)
			(layer "B.Fab")
		)
		(fp_line
			(start -0.12065 -0.2794)
			(end -0.12065 -0.3048)
			(stroke
				(width 0.1)
				(type default)
			)
			(layer "B.Fab")
		)
		(fp_line
			(start 0.12065 0.2794)
			(end 0.12065 0.3048)
			(stroke
				(width 0.1)
				(type default)
			)
			(layer "B.Fab")
		)
		(fp_line
			(start -0.120396 0.2794)
			(end 0.12065 0.2794)
			(stroke
				(width 0.1)
				(type default)
			)
			(layer "B.Fab")
		)
		(fp_line
			(start 0.67945 0.3048)
			(end 0.67945 -0.305054)
			(stroke
				(width 0.1)
				(type default)
			)
			(layer "B.Fab")
		)
		(fp_line
			(start 0.12065 0.3048)
			(end 0.67945 0.3048)
			(stroke
				(width 0.1)
				(type default)
			)
			(layer "B.Fab")
		)
		(fp_line
			(start -0.120396 0.3048)
			(end -0.120396 0.2794)
			(stroke
				(width 0.1)
				(type default)
			)
			(layer "B.Fab")
		)
		(fp_line
			(start -0.67945 0.3048)
			(end -0.120396 0.3048)
			(stroke
				(width 0.1)
				(type default)
			)
			(layer "B.Fab")
		)
		(pad "1" smd circle
			(at 0.40005 0 270)
			(size 0 0)
			(layers "B.Cu" "B.Mask" "B.Paste")
			(net "PVDDCR_CPU0_P1_VOS4")
		)
		(pad "2" smd circle
			(at -0.40005 0 270)
			(size 0 0)
			(layers "B.Cu" "B.Mask" "B.Paste")
			(net "PVDDCR_CPU0_P1")
		)
	)
	(footprint ""
		(layer "B.Cu")
		(at 135.694166 -408.517344 90)
		(property "Reference" "C6737"
			(at 0 0 90)
			(layer "B.SilkS")
			(hide yes)
			(effects
				(font
					(size 1.27 1.27)
				)
				(justify mirror)
			)
		)
		(property "Value" ""
			(at 0 0 90)
			(layer "B.Fab")
			(effects
				(font
					(size 1.27 1.27)
				)
				(justify mirror)
			)
		)
		(duplicate_pad_numbers_are_jumpers no)
		(fp_line
			(start 0.299974 -0.150114)
			(end -0.299974 -0.150114)
			(stroke
				(width 0.1)
				(type default)
			)
			(layer "B.Fab")
		)
		(fp_line
			(start -0.299974 -0.150114)
			(end -0.299974 0.150114)
			(stroke
				(width 0.1)
				(type default)
			)
			(layer "B.Fab")
		)
		(fp_line
			(start 0.299974 0.150114)
			(end 0.299974 -0.150114)
			(stroke
				(width 0.1)
				(type default)
			)
			(layer "B.Fab")
		)
		(fp_line
			(start -0.299974 0.150114)
			(end 0.299974 0.150114)
			(stroke
				(width 0.1)
				(type default)
			)
			(layer "B.Fab")
		)
		(pad "1" smd rect
			(at 0.2667 0 270)
			(size 0.3048 0.381)
			(layers "B.Cu" "B.Mask" "B.Paste")
			(net "P5E_CPU1_P3_TX_BUF_C_DP<6>")
		)
		(pad "2" smd rect
			(at -0.2667 0 270)
			(size 0.3048 0.381)
			(layers "B.Cu" "B.Mask" "B.Paste")
			(net "P5E_CPU1_P3_TX_BUF_DP<6>")
		)
	)
	(footprint ""
		(layer "B.Cu")
		(at 339.134958 -305.812952)
		(property "Reference" "R2318"
			(at 0 0 0)
			(layer "B.SilkS")
			(hide yes)
			(effects
				(font
					(size 1.27 1.27)
				)
				(justify mirror)
			)
		)
		(property "Value" ""
			(at 0 0 0)
			(layer "B.Fab")
			(effects
				(font
					(size 1.27 1.27)
				)
				(justify mirror)
			)
		)
		(duplicate_pad_numbers_are_jumpers no)
		(fp_line
			(start -0.7874 -0.4064)
			(end -0.7874 0.4064)
			(stroke
				(width 0.1524)
				(type default)
			)
			(layer "B.SilkS")
		)
		(fp_line
			(start -0.7874 0.4064)
			(end 0.7874 0.4064)
			(stroke
				(width 0.1524)
				(type default)
			)
			(layer "B.SilkS")
		)
		(fp_line
			(start 0.7874 -0.4064)
			(end -0.7874 -0.4064)
			(stroke
				(width 0.1524)
				(type default)
			)
			(layer "B.SilkS")
		)
		(fp_line
			(start 0.7874 0.4064)
			(end 0.7874 -0.4064)
			(stroke
				(width 0.1524)
				(type default)
			)
			(layer "B.SilkS")
		)
		(fp_line
			(start -0.67945 -0.3048)
			(end -0.67945 0.3048)
			(stroke
				(width 0.1)
				(type default)
			)
			(layer "B.Fab")
		)
		(fp_line
			(start -0.67945 0.3048)
			(end -0.120396 0.3048)
			(stroke
				(width 0.1)
				(type default)
			)
			(layer "B.Fab")
		)
		(fp_line
			(start -0.12065 -0.3048)
			(end -0.67945 -0.3048)
			(stroke
				(width 0.1)
				(type default)
			)
			(layer "B.Fab")
		)
		(fp_line
			(start -0.12065 -0.2794)
			(end -0.12065 -0.3048)
			(stroke
				(width 0.1)
				(type default)
			)
			(layer "B.Fab")
		)
		(fp_line
			(start -0.120396 0.2794)
			(end 0.12065 0.2794)
			(stroke
				(width 0.1)
				(type default)
			)
			(layer "B.Fab")
		)
		(fp_line
			(start -0.120396 0.3048)
			(end -0.120396 0.2794)
			(stroke
				(width 0.1)
				(type default)
			)
			(layer "B.Fab")
		)
		(fp_line
			(start 0.12065 -0.305054)
			(end 0.12065 -0.2794)
			(stroke
				(width 0.1)
				(type default)
			)
			(layer "B.Fab")
		)
		(fp_line
			(start 0.12065 -0.2794)
			(end -0.12065 -0.2794)
			(stroke
				(width 0.1)
				(type default)
			)
			(layer "B.Fab")
		)
		(fp_line
			(start 0.12065 0.2794)
			(end 0.12065 0.3048)
			(stroke
				(width 0.1)
				(type default)
			)
			(layer "B.Fab")
		)
		(fp_line
			(start 0.12065 0.3048)
			(end 0.67945 0.3048)
			(stroke
				(width 0.1)
				(type default)
			)
			(layer "B.Fab")
		)
		(fp_line
			(start 0.67945 -0.305054)
			(end 0.12065 -0.305054)
			(stroke
				(width 0.1)
				(type default)
			)
			(layer "B.Fab")
		)
		(fp_line
			(start 0.67945 0.3048)
			(end 0.67945 -0.305054)
			(stroke
				(width 0.1)
				(type default)
			)
			(layer "B.Fab")
		)
		(pad "1" smd circle
			(at 0.40005 0 180)
			(size 0 0)
			(layers "B.Cu" "B.Mask" "B.Paste")
			(net "UART_CPU0_SCM_UART1_R_TX")
		)
		(pad "2" smd circle
			(at -0.40005 0 180)
			(size 0 0)
			(layers "B.Cu" "B.Mask" "B.Paste")
			(net "UART_CPU0_SCM_UART1_TX")
		)
	)
	(footprint ""
		(layer "B.Cu")
		(at 369.646454 -255.84531)
		(property "Reference" "C2130"
			(at 0 0 0)
			(layer "B.SilkS")
			(hide yes)
			(effects
				(font
					(size 1.27 1.27)
				)
				(justify mirror)
			)
		)
		(property "Value" ""
			(at 0 0 0)
			(layer "B.Fab")
			(effects
				(font
					(size 1.27 1.27)
				)
				(justify mirror)
			)
		)
		(duplicate_pad_numbers_are_jumpers no)
		(fp_line
			(start -0.7874 -0.4064)
			(end -0.7874 0.4064)
			(stroke
				(width 0.1524)
				(type default)
			)
			(layer "B.SilkS")
		)
		(fp_line
			(start -0.7874 0.4064)
			(end 0.7874 0.4064)
			(stroke
				(width 0.1524)
				(type default)
			)
			(layer "B.SilkS")
		)
		(fp_line
			(start 0.7874 -0.4064)
			(end -0.7874 -0.4064)
			(stroke
				(width 0.1524)
				(type default)
			)
			(layer "B.SilkS")
		)
		(fp_line
			(start 0.7874 0.4064)
			(end 0.7874 -0.4064)
			(stroke
				(width 0.1524)
				(type default)
			)
			(layer "B.SilkS")
		)
		(fp_line
			(start -0.67945 -0.3048)
			(end -0.67945 0.3048)
			(stroke
				(width 0.1)
				(type default)
			)
			(layer "B.Fab")
		)
		(fp_line
			(start -0.67945 0.3048)
			(end -0.120396 0.3048)
			(stroke
				(width 0.1)
				(type default)
			)
			(layer "B.Fab")
		)
		(fp_line
			(start -0.12065 -0.3048)
			(end -0.67945 -0.3048)
			(stroke
				(width 0.1)
				(type default)
			)
			(layer "B.Fab")
		)
		(fp_line
			(start -0.12065 -0.2794)
			(end -0.12065 -0.3048)
			(stroke
				(width 0.1)
				(type default)
			)
			(layer "B.Fab")
		)
		(fp_line
			(start -0.120396 0.2794)
			(end 0.12065 0.2794)
			(stroke
				(width 0.1)
				(type default)
			)
			(layer "B.Fab")
		)
		(fp_line
			(start -0.120396 0.3048)
			(end -0.120396 0.2794)
			(stroke
				(width 0.1)
				(type default)
			)
			(layer "B.Fab")
		)
		(fp_line
			(start 0.12065 -0.305054)
			(end 0.12065 -0.2794)
			(stroke
				(width 0.1)
				(type default)
			)
			(layer "B.Fab")
		)
		(fp_line
			(start 0.12065 -0.2794)
			(end -0.12065 -0.2794)
			(stroke
				(width 0.1)
				(type default)
			)
			(layer "B.Fab")
		)
		(fp_line
			(start 0.12065 0.2794)
			(end 0.12065 0.3048)
			(stroke
				(width 0.1)
				(type default)
			)
			(layer "B.Fab")
		)
		(fp_line
			(start 0.12065 0.3048)
			(end 0.67945 0.3048)
			(stroke
				(width 0.1)
				(type default)
			)
			(layer "B.Fab")
		)
		(fp_line
			(start 0.67945 -0.305054)
			(end 0.12065 -0.305054)
			(stroke
				(width 0.1)
				(type default)
			)
			(layer "B.Fab")
		)
		(fp_line
			(start 0.67945 0.3048)
			(end 0.67945 -0.305054)
			(stroke
				(width 0.1)
				(type default)
			)
			(layer "B.Fab")
		)
		(pad "1" smd circle
			(at 0.40005 0 180)
			(size 0 0)
			(layers "B.Cu" "B.Mask" "B.Paste")
			(net "PVDDCR_SOC_P0")
		)
		(pad "2" smd circle
			(at -0.40005 0 180)
			(size 0 0)
			(layers "B.Cu" "B.Mask" "B.Paste")
			(net "GND")
		)
	)
	(footprint ""
		(layer "B.Cu")
		(at 457.347066 -397.05407 90)
		(property "Reference" "PC6580_2"
			(at 0 0 90)
			(layer "B.SilkS")
			(hide yes)
			(effects
				(font
					(size 1.27 1.27)
				)
				(justify mirror)
			)
		)
		(property "Value" ""
			(at 0 0 90)
			(layer "B.Fab")
			(effects
				(font
					(size 1.27 1.27)
				)
				(justify mirror)
			)
		)
		(duplicate_pad_numbers_are_jumpers no)
		(fp_line
			(start 1.524 -0.762)
			(end -1.524 -0.762)
			(stroke
				(width 0.1524)
				(type default)
			)
			(layer "B.SilkS")
		)
		(fp_line
			(start -1.524 -0.762)
			(end -1.524 0.762)
			(stroke
				(width 0.1524)
				(type default)
			)
			(layer "B.SilkS")
		)
		(fp_line
			(start 1.524 0.762)
			(end 1.524 -0.762)
			(stroke
				(width 0.1524)
				(type default)
			)
			(layer "B.SilkS")
		)
		(fp_line
			(start -1.524 0.762)
			(end 1.524 0.762)
			(stroke
				(width 0.1524)
				(type default)
			)
			(layer "B.SilkS")
		)
		(fp_line
			(start 1.1049 -0.724916)
			(end 1.1049 0.724916)
			(stroke
				(width 0.1)
				(type default)
			)
			(layer "B.Fab")
		)
		(fp_line
			(start -1.1049 -0.724916)
			(end 1.1049 -0.724916)
			(stroke
				(width 0.1)
				(type default)
			)
			(layer "B.Fab")
		)
		(fp_line
			(start 1.1049 0.724916)
			(end -1.1049 0.724916)
			(stroke
				(width 0.1)
				(type default)
			)
			(layer "B.Fab")
		)
		(fp_line
			(start -1.1049 0.724916)
			(end -1.1049 -0.724916)
			(stroke
				(width 0.1)
				(type default)
			)
			(layer "B.Fab")
		)
		(pad "1" smd rect
			(at 0.889 0 90)
			(size 1.016 1.27)
			(layers "B.Cu" "B.Mask" "B.Paste")
			(net "SW_P12V_AUX_P0V9_RETIMER_CPU0_FLT")
		)
		(pad "2" smd rect
			(at -0.889 0 90)
			(size 1.016 1.27)
			(layers "B.Cu" "B.Mask" "B.Paste")
			(net "GND")
		)
	)
	(footprint ""
		(layer "B.Cu")
		(at 186.806078 -97.085912 -90)
		(property "Reference" "R180"
			(at 0 0 90)
			(layer "B.SilkS")
			(hide yes)
			(effects
				(font
					(size 1.27 1.27)
				)
				(justify mirror)
			)
		)
		(property "Value" ""
			(at 0 0 90)
			(layer "B.Fab")
			(effects
				(font
					(size 1.27 1.27)
				)
				(justify mirror)
			)
		)
		(duplicate_pad_numbers_are_jumpers no)
		(fp_line
			(start -0.7874 0.4064)
			(end 0.7874 0.4064)
			(stroke
				(width 0.1524)
				(type default)
			)
			(layer "B.SilkS")
		)
		(fp_line
			(start 0.7874 0.4064)
			(end 0.7874 -0.4064)
			(stroke
				(width 0.1524)
				(type default)
			)
			(layer "B.SilkS")
		)
		(fp_line
			(start -0.7874 -0.4064)
			(end -0.7874 0.4064)
			(stroke
				(width 0.1524)
				(type default)
			)
			(layer "B.SilkS")
		)
		(fp_line
			(start 0.7874 -0.4064)
			(end -0.7874 -0.4064)
			(stroke
				(width 0.1524)
				(type default)
			)
			(layer "B.SilkS")
		)
		(fp_line
			(start -0.67945 0.3048)
			(end -0.120396 0.3048)
			(stroke
				(width 0.1)
				(type default)
			)
			(layer "B.Fab")
		)
		(fp_line
			(start -0.120396 0.3048)
			(end -0.120396 0.2794)
			(stroke
				(width 0.1)
				(type default)
			)
			(layer "B.Fab")
		)
		(fp_line
			(start 0.12065 0.3048)
			(end 0.67945 0.3048)
			(stroke
				(width 0.1)
				(type default)
			)
			(layer "B.Fab")
		)
		(fp_line
			(start 0.67945 0.3048)
			(end 0.67945 -0.305054)
			(stroke
				(width 0.1)
				(type default)
			)
			(layer "B.Fab")
		)
		(fp_line
			(start -0.120396 0.2794)
			(end 0.12065 0.2794)
			(stroke
				(width 0.1)
				(type default)
			)
			(layer "B.Fab")
		)
		(fp_line
			(start 0.12065 0.2794)
			(end 0.12065 0.3048)
			(stroke
				(width 0.1)
				(type default)
			)
			(layer "B.Fab")
		)
		(fp_line
			(start -0.12065 -0.2794)
			(end -0.12065 -0.3048)
			(stroke
				(width 0.1)
				(type default)
			)
			(layer "B.Fab")
		)
		(fp_line
			(start 0.12065 -0.2794)
			(end -0.12065 -0.2794)
			(stroke
				(width 0.1)
				(type default)
			)
			(layer "B.Fab")
		)
		(fp_line
			(start -0.67945 -0.3048)
			(end -0.67945 0.3048)
			(stroke
				(width 0.1)
				(type default)
			)
			(layer "B.Fab")
		)
		(fp_line
			(start -0.12065 -0.3048)
			(end -0.67945 -0.3048)
			(stroke
				(width 0.1)
				(type default)
			)
			(layer "B.Fab")
		)
		(fp_line
			(start 0.12065 -0.305054)
			(end 0.12065 -0.2794)
			(stroke
				(width 0.1)
				(type default)
			)
			(layer "B.Fab")
		)
		(fp_line
			(start 0.67945 -0.305054)
			(end 0.12065 -0.305054)
			(stroke
				(width 0.1)
				(type default)
			)
			(layer "B.Fab")
		)
		(pad "1" smd circle
			(at 0.40005 0 90)
			(size 0 0)
			(layers "B.Cu" "B.Mask" "B.Paste")
			(net "CPU0_SP5R1")
		)
		(pad "2" smd circle
			(at -0.40005 0 90)
			(size 0 0)
			(layers "B.Cu" "B.Mask" "B.Paste")
			(net "FM_CPU0_SP5R1")
		)
	)
	(footprint ""
		(layer "B.Cu")
		(at 179.793646 -32.688022 90)
		(property "Reference" "PC2340"
			(at 0 0 90)
			(layer "B.SilkS")
			(hide yes)
			(effects
				(font
					(size 1.27 1.27)
				)
				(justify mirror)
			)
		)
		(property "Value" ""
			(at 0 0 90)
			(layer "B.Fab")
			(effects
				(font
					(size 1.27 1.27)
				)
				(justify mirror)
			)
		)
		(duplicate_pad_numbers_are_jumpers no)
		(fp_line
			(start 0.7874 -0.4064)
			(end -0.7874 -0.4064)
			(stroke
				(width 0.1524)
				(type default)
			)
			(layer "B.SilkS")
		)
		(fp_line
			(start -0.7874 -0.4064)
			(end -0.7874 0.4064)
			(stroke
				(width 0.1524)
				(type default)
			)
			(layer "B.SilkS")
		)
		(fp_line
			(start 0.7874 0.4064)
			(end 0.7874 -0.4064)
			(stroke
				(width 0.1524)
				(type default)
			)
			(layer "B.SilkS")
		)
		(fp_line
			(start -0.7874 0.4064)
			(end 0.7874 0.4064)
			(stroke
				(width 0.1524)
				(type default)
			)
			(layer "B.SilkS")
		)
		(fp_line
			(start 0.67945 -0.305054)
			(end 0.12065 -0.305054)
			(stroke
				(width 0.1)
				(type default)
			)
			(layer "B.Fab")
		)
		(fp_line
			(start 0.12065 -0.305054)
			(end 0.12065 -0.2794)
			(stroke
				(width 0.1)
				(type default)
			)
			(layer "B.Fab")
		)
		(fp_line
			(start -0.12065 -0.3048)
			(end -0.67945 -0.3048)
			(stroke
				(width 0.1)
				(type default)
			)
			(layer "B.Fab")
		)
		(fp_line
			(start -0.67945 -0.3048)
			(end -0.67945 0.3048)
			(stroke
				(width 0.1)
				(type default)
			)
			(layer "B.Fab")
		)
		(fp_line
			(start 0.12065 -0.2794)
			(end -0.12065 -0.2794)
			(stroke
				(width 0.1)
				(type default)
			)
			(layer "B.Fab")
		)
		(fp_line
			(start -0.12065 -0.2794)
			(end -0.12065 -0.3048)
			(stroke
				(width 0.1)
				(type default)
			)
			(layer "B.Fab")
		)
		(fp_line
			(start 0.12065 0.2794)
			(end 0.12065 0.3048)
			(stroke
				(width 0.1)
				(type default)
			)
			(layer "B.Fab")
		)
		(fp_line
			(start -0.120396 0.2794)
			(end 0.12065 0.2794)
			(stroke
				(width 0.1)
				(type default)
			)
			(layer "B.Fab")
		)
		(fp_line
			(start 0.67945 0.3048)
			(end 0.67945 -0.305054)
			(stroke
				(width 0.1)
				(type default)
			)
			(layer "B.Fab")
		)
		(fp_line
			(start 0.12065 0.3048)
			(end 0.67945 0.3048)
			(stroke
				(width 0.1)
				(type default)
			)
			(layer "B.Fab")
		)
		(fp_line
			(start -0.120396 0.3048)
			(end -0.120396 0.2794)
			(stroke
				(width 0.1)
				(type default)
			)
			(layer "B.Fab")
		)
		(fp_line
			(start -0.67945 0.3048)
			(end -0.120396 0.3048)
			(stroke
				(width 0.1)
				(type default)
			)
			(layer "B.Fab")
		)
		(pad "1" smd circle
			(at 0.40005 0 270)
			(size 0 0)
			(layers "B.Cu" "B.Mask" "B.Paste")
			(net "P12V_SCM_ISET_R")
		)
		(pad "2" smd circle
			(at -0.40005 0 270)
			(size 0 0)
			(layers "B.Cu" "B.Mask" "B.Paste")
			(net "GND")
		)
	)
	(footprint ""
		(layer "B.Cu")
		(at 79.260954 -191.358012 90)
		(property "Reference" "PC302_3"
			(at 0 0 90)
			(layer "B.SilkS")
			(hide yes)
			(effects
				(font
					(size 1.27 1.27)
				)
				(justify mirror)
			)
		)
		(property "Value" ""
			(at 0 0 90)
			(layer "B.Fab")
			(effects
				(font
					(size 1.27 1.27)
				)
				(justify mirror)
			)
		)
		(duplicate_pad_numbers_are_jumpers no)
		(fp_line
			(start 1.524 -0.762)
			(end -1.524 -0.762)
			(stroke
				(width 0.1524)
				(type default)
			)
			(layer "B.SilkS")
		)
		(fp_line
			(start -1.524 -0.762)
			(end -1.524 0.762)
			(stroke
				(width 0.1524)
				(type default)
			)
			(layer "B.SilkS")
		)
		(fp_line
			(start 1.524 0.762)
			(end 1.524 -0.762)
			(stroke
				(width 0.1524)
				(type default)
			)
			(layer "B.SilkS")
		)
		(fp_line
			(start -1.524 0.762)
			(end 1.524 0.762)
			(stroke
				(width 0.1524)
				(type default)
			)
			(layer "B.SilkS")
		)
		(fp_line
			(start 1.1049 -0.724916)
			(end 1.1049 0.724916)
			(stroke
				(width 0.1)
				(type default)
			)
			(layer "B.Fab")
		)
		(fp_line
			(start -1.1049 -0.724916)
			(end 1.1049 -0.724916)
			(stroke
				(width 0.1)
				(type default)
			)
			(layer "B.Fab")
		)
		(fp_line
			(start 1.1049 0.724916)
			(end -1.1049 0.724916)
			(stroke
				(width 0.1)
				(type default)
			)
			(layer "B.Fab")
		)
		(fp_line
			(start -1.1049 0.724916)
			(end -1.1049 -0.724916)
			(stroke
				(width 0.1)
				(type default)
			)
			(layer "B.Fab")
		)
		(pad "1" smd rect
			(at 0.889 0 90)
			(size 1.016 1.27)
			(layers "B.Cu" "B.Mask" "B.Paste")
			(net "PVDDCR_CPU0_P1")
		)
		(pad "2" smd rect
			(at -0.889 0 90)
			(size 1.016 1.27)
			(layers "B.Cu" "B.Mask" "B.Paste")
			(net "GND")
		)
	)
	(footprint ""
		(layer "B.Cu")
		(at 109.512862 -388.846568)
		(property "Reference" "C475"
			(at 0 0 0)
			(layer "B.SilkS")
			(hide yes)
			(effects
				(font
					(size 1.27 1.27)
				)
				(justify mirror)
			)
		)
		(property "Value" ""
			(at 0 0 0)
			(layer "B.Fab")
			(effects
				(font
					(size 1.27 1.27)
				)
				(justify mirror)
			)
		)
		(duplicate_pad_numbers_are_jumpers no)
		(fp_line
			(start -1.524 -0.762)
			(end -1.524 0.762)
			(stroke
				(width 0.1524)
				(type default)
			)
			(layer "B.SilkS")
		)
		(fp_line
			(start -1.524 0.762)
			(end 1.524 0.762)
			(stroke
				(width 0.1524)
				(type default)
			)
			(layer "B.SilkS")
		)
		(fp_line
			(start 1.524 -0.762)
			(end -1.524 -0.762)
			(stroke
				(width 0.1524)
				(type default)
			)
			(layer "B.SilkS")
		)
		(fp_line
			(start 1.524 0.762)
			(end 1.524 -0.762)
			(stroke
				(width 0.1524)
				(type default)
			)
			(layer "B.SilkS")
		)
		(fp_line
			(start -1.1049 -0.724916)
			(end 1.1049 -0.724916)
			(stroke
				(width 0.1)
				(type default)
			)
			(layer "B.Fab")
		)
		(fp_line
			(start -1.1049 0.724916)
			(end -1.1049 -0.724916)
			(stroke
				(width 0.1)
				(type default)
			)
			(layer "B.Fab")
		)
		(fp_line
			(start 1.1049 -0.724916)
			(end 1.1049 0.724916)
			(stroke
				(width 0.1)
				(type default)
			)
			(layer "B.Fab")
		)
		(fp_line
			(start 1.1049 0.724916)
			(end -1.1049 0.724916)
			(stroke
				(width 0.1)
				(type default)
			)
			(layer "B.Fab")
		)
		(pad "1" smd rect
			(at 0.889 0)
			(size 1.016 1.27)
			(layers "B.Cu" "B.Mask" "B.Paste")
			(net "P0V9_CPU1_RT3_2A")
		)
		(pad "2" smd rect
			(at -0.889 0)
			(size 1.016 1.27)
			(layers "B.Cu" "B.Mask" "B.Paste")
			(net "GND")
		)
	)
	(footprint ""
		(layer "B.Cu")
		(at 145.3388 -13.762228 90)
		(property "Reference" "R1816"
			(at 0 0 90)
			(layer "B.SilkS")
			(hide yes)
			(effects
				(font
					(size 1.27 1.27)
				)
				(justify mirror)
			)
		)
		(property "Value" ""
			(at 0 0 90)
			(layer "B.Fab")
			(effects
				(font
					(size 1.27 1.27)
				)
				(justify mirror)
			)
		)
		(duplicate_pad_numbers_are_jumpers no)
		(fp_line
			(start 0.7874 -0.4064)
			(end -0.7874 -0.4064)
			(stroke
				(width 0.1524)
				(type default)
			)
			(layer "B.SilkS")
		)
		(fp_line
			(start -0.7874 -0.4064)
			(end -0.7874 0.4064)
			(stroke
				(width 0.1524)
				(type default)
			)
			(layer "B.SilkS")
		)
		(fp_line
			(start 0.7874 0.4064)
			(end 0.7874 -0.4064)
			(stroke
				(width 0.1524)
				(type default)
			)
			(layer "B.SilkS")
		)
		(fp_line
			(start -0.7874 0.4064)
			(end 0.7874 0.4064)
			(stroke
				(width 0.1524)
				(type default)
			)
			(layer "B.SilkS")
		)
		(fp_line
			(start 0.67945 -0.305054)
			(end 0.12065 -0.305054)
			(stroke
				(width 0.1)
				(type default)
			)
			(layer "B.Fab")
		)
		(fp_line
			(start 0.12065 -0.305054)
			(end 0.12065 -0.2794)
			(stroke
				(width 0.1)
				(type default)
			)
			(layer "B.Fab")
		)
		(fp_line
			(start -0.12065 -0.3048)
			(end -0.67945 -0.3048)
			(stroke
				(width 0.1)
				(type default)
			)
			(layer "B.Fab")
		)
		(fp_line
			(start -0.67945 -0.3048)
			(end -0.67945 0.3048)
			(stroke
				(width 0.1)
				(type default)
			)
			(layer "B.Fab")
		)
		(fp_line
			(start 0.12065 -0.2794)
			(end -0.12065 -0.2794)
			(stroke
				(width 0.1)
				(type default)
			)
			(layer "B.Fab")
		)
		(fp_line
			(start -0.12065 -0.2794)
			(end -0.12065 -0.3048)
			(stroke
				(width 0.1)
				(type default)
			)
			(layer "B.Fab")
		)
		(fp_line
			(start 0.12065 0.2794)
			(end 0.12065 0.3048)
			(stroke
				(width 0.1)
				(type default)
			)
			(layer "B.Fab")
		)
		(fp_line
			(start -0.120396 0.2794)
			(end 0.12065 0.2794)
			(stroke
				(width 0.1)
				(type default)
			)
			(layer "B.Fab")
		)
		(fp_line
			(start 0.67945 0.3048)
			(end 0.67945 -0.305054)
			(stroke
				(width 0.1)
				(type default)
			)
			(layer "B.Fab")
		)
		(fp_line
			(start 0.12065 0.3048)
			(end 0.67945 0.3048)
			(stroke
				(width 0.1)
				(type default)
			)
			(layer "B.Fab")
		)
		(fp_line
			(start -0.120396 0.3048)
			(end -0.120396 0.2794)
			(stroke
				(width 0.1)
				(type default)
			)
			(layer "B.Fab")
		)
		(fp_line
			(start -0.67945 0.3048)
			(end -0.120396 0.3048)
			(stroke
				(width 0.1)
				(type default)
			)
			(layer "B.Fab")
		)
		(pad "1" smd circle
			(at 0.40005 0 270)
			(size 0 0)
			(layers "B.Cu" "B.Mask" "B.Paste")
			(net "PWRGD_PS_PWROK")
		)
		(pad "2" smd circle
			(at -0.40005 0 270)
			(size 0 0)
			(layers "B.Cu" "B.Mask" "B.Paste")
			(net "PWRGD_PS_PWROK_R")
		)
	)
	(footprint ""
		(layer "B.Cu")
		(at 14.616176 -101.217984 90)
		(property "Reference" "C2035"
			(at 0 0 90)
			(layer "B.SilkS")
			(hide yes)
			(effects
				(font
					(size 1.27 1.27)
				)
				(justify mirror)
			)
		)
		(property "Value" ""
			(at 0 0 90)
			(layer "B.Fab")
			(effects
				(font
					(size 1.27 1.27)
				)
				(justify mirror)
			)
		)
		(duplicate_pad_numbers_are_jumpers no)
		(fp_line
			(start 0.7874 -0.4064)
			(end -0.7874 -0.4064)
			(stroke
				(width 0.1524)
				(type default)
			)
			(layer "B.SilkS")
		)
		(fp_line
			(start -0.7874 -0.4064)
			(end -0.7874 0.4064)
			(stroke
				(width 0.1524)
				(type default)
			)
			(layer "B.SilkS")
		)
		(fp_line
			(start 0.7874 0.4064)
			(end 0.7874 -0.4064)
			(stroke
				(width 0.1524)
				(type default)
			)
			(layer "B.SilkS")
		)
		(fp_line
			(start -0.7874 0.4064)
			(end 0.7874 0.4064)
			(stroke
				(width 0.1524)
				(type default)
			)
			(layer "B.SilkS")
		)
		(fp_line
			(start 0.67945 -0.305054)
			(end 0.12065 -0.305054)
			(stroke
				(width 0.1)
				(type default)
			)
			(layer "B.Fab")
		)
		(fp_line
			(start 0.12065 -0.305054)
			(end 0.12065 -0.2794)
			(stroke
				(width 0.1)
				(type default)
			)
			(layer "B.Fab")
		)
		(fp_line
			(start -0.12065 -0.3048)
			(end -0.67945 -0.3048)
			(stroke
				(width 0.1)
				(type default)
			)
			(layer "B.Fab")
		)
		(fp_line
			(start -0.67945 -0.3048)
			(end -0.67945 0.3048)
			(stroke
				(width 0.1)
				(type default)
			)
			(layer "B.Fab")
		)
		(fp_line
			(start 0.12065 -0.2794)
			(end -0.12065 -0.2794)
			(stroke
				(width 0.1)
				(type default)
			)
			(layer "B.Fab")
		)
		(fp_line
			(start -0.12065 -0.2794)
			(end -0.12065 -0.3048)
			(stroke
				(width 0.1)
				(type default)
			)
			(layer "B.Fab")
		)
		(fp_line
			(start 0.12065 0.2794)
			(end 0.12065 0.3048)
			(stroke
				(width 0.1)
				(type default)
			)
			(layer "B.Fab")
		)
		(fp_line
			(start -0.120396 0.2794)
			(end 0.12065 0.2794)
			(stroke
				(width 0.1)
				(type default)
			)
			(layer "B.Fab")
		)
		(fp_line
			(start 0.67945 0.3048)
			(end 0.67945 -0.305054)
			(stroke
				(width 0.1)
				(type default)
			)
			(layer "B.Fab")
		)
		(fp_line
			(start 0.12065 0.3048)
			(end 0.67945 0.3048)
			(stroke
				(width 0.1)
				(type default)
			)
			(layer "B.Fab")
		)
		(fp_line
			(start -0.120396 0.3048)
			(end -0.120396 0.2794)
			(stroke
				(width 0.1)
				(type default)
			)
			(layer "B.Fab")
		)
		(fp_line
			(start -0.67945 0.3048)
			(end -0.120396 0.3048)
			(stroke
				(width 0.1)
				(type default)
			)
			(layer "B.Fab")
		)
		(pad "1" smd circle
			(at 0.40005 0 270)
			(size 0 0)
			(layers "B.Cu" "B.Mask" "B.Paste")
			(net "P3V3_AUX_USB_HUB")
		)
		(pad "2" smd circle
			(at -0.40005 0 270)
			(size 0 0)
			(layers "B.Cu" "B.Mask" "B.Paste")
			(net "GND")
		)
	)
	(footprint ""
		(layer "B.Cu")
		(at 424.848782 -354.87229 -90)
		(property "Reference" "PC215_1"
			(at 0 0 90)
			(layer "B.SilkS")
			(hide yes)
			(effects
				(font
					(size 1.27 1.27)
				)
				(justify mirror)
			)
		)
		(property "Value" ""
			(at 0 0 90)
			(layer "B.Fab")
			(effects
				(font
					(size 1.27 1.27)
				)
				(justify mirror)
			)
		)
		(duplicate_pad_numbers_are_jumpers no)
		(fp_line
			(start -1.524 0.762)
			(end 1.524 0.762)
			(stroke
				(width 0.1524)
				(type default)
			)
			(layer "B.SilkS")
		)
		(fp_line
			(start 1.524 0.762)
			(end 1.524 -0.762)
			(stroke
				(width 0.1524)
				(type default)
			)
			(layer "B.SilkS")
		)
		(fp_line
			(start -1.524 -0.762)
			(end -1.524 0.762)
			(stroke
				(width 0.1524)
				(type default)
			)
			(layer "B.SilkS")
		)
		(fp_line
			(start 1.524 -0.762)
			(end -1.524 -0.762)
			(stroke
				(width 0.1524)
				(type default)
			)
			(layer "B.SilkS")
		)
		(fp_line
			(start -1.1049 0.724916)
			(end -1.1049 -0.724916)
			(stroke
				(width 0.1)
				(type default)
			)
			(layer "B.Fab")
		)
		(fp_line
			(start 1.1049 0.724916)
			(end -1.1049 0.724916)
			(stroke
				(width 0.1)
				(type default)
			)
			(layer "B.Fab")
		)
		(fp_line
			(start -1.1049 -0.724916)
			(end 1.1049 -0.724916)
			(stroke
				(width 0.1)
				(type default)
			)
			(layer "B.Fab")
		)
		(fp_line
			(start 1.1049 -0.724916)
			(end 1.1049 0.724916)
			(stroke
				(width 0.1)
				(type default)
			)
			(layer "B.Fab")
		)
		(pad "1" smd rect
			(at 0.889 0 270)
			(size 1.016 1.27)
			(layers "B.Cu" "B.Mask" "B.Paste")
			(net "SW_P12V_AUX_PVDD11_S3_P0_FLT")
		)
		(pad "2" smd rect
			(at -0.889 0 270)
			(size 1.016 1.27)
			(layers "B.Cu" "B.Mask" "B.Paste")
			(net "GND")
		)
	)
	(footprint ""
		(layer "B.Cu")
		(at 172.285914 -13.635228 -90)
		(property "Reference" "R3112"
			(at 0 0 90)
			(layer "B.SilkS")
			(hide yes)
			(effects
				(font
					(size 1.27 1.27)
				)
				(justify mirror)
			)
		)
		(property "Value" ""
			(at 0 0 90)
			(layer "B.Fab")
			(effects
				(font
					(size 1.27 1.27)
				)
				(justify mirror)
			)
		)
		(duplicate_pad_numbers_are_jumpers no)
		(fp_line
			(start -0.7874 0.4064)
			(end 0.7874 0.4064)
			(stroke
				(width 0.1524)
				(type default)
			)
			(layer "B.SilkS")
		)
		(fp_line
			(start 0.7874 0.4064)
			(end 0.7874 -0.4064)
			(stroke
				(width 0.1524)
				(type default)
			)
			(layer "B.SilkS")
		)
		(fp_line
			(start -0.7874 -0.4064)
			(end -0.7874 0.4064)
			(stroke
				(width 0.1524)
				(type default)
			)
			(layer "B.SilkS")
		)
		(fp_line
			(start 0.7874 -0.4064)
			(end -0.7874 -0.4064)
			(stroke
				(width 0.1524)
				(type default)
			)
			(layer "B.SilkS")
		)
		(fp_line
			(start -0.67945 0.3048)
			(end -0.120396 0.3048)
			(stroke
				(width 0.1)
				(type default)
			)
			(layer "B.Fab")
		)
		(fp_line
			(start -0.120396 0.3048)
			(end -0.120396 0.2794)
			(stroke
				(width 0.1)
				(type default)
			)
			(layer "B.Fab")
		)
		(fp_line
			(start 0.12065 0.3048)
			(end 0.67945 0.3048)
			(stroke
				(width 0.1)
				(type default)
			)
			(layer "B.Fab")
		)
		(fp_line
			(start 0.67945 0.3048)
			(end 0.67945 -0.305054)
			(stroke
				(width 0.1)
				(type default)
			)
			(layer "B.Fab")
		)
		(fp_line
			(start -0.120396 0.2794)
			(end 0.12065 0.2794)
			(stroke
				(width 0.1)
				(type default)
			)
			(layer "B.Fab")
		)
		(fp_line
			(start 0.12065 0.2794)
			(end 0.12065 0.3048)
			(stroke
				(width 0.1)
				(type default)
			)
			(layer "B.Fab")
		)
		(fp_line
			(start -0.12065 -0.2794)
			(end -0.12065 -0.3048)
			(stroke
				(width 0.1)
				(type default)
			)
			(layer "B.Fab")
		)
		(fp_line
			(start 0.12065 -0.2794)
			(end -0.12065 -0.2794)
			(stroke
				(width 0.1)
				(type default)
			)
			(layer "B.Fab")
		)
		(fp_line
			(start -0.67945 -0.3048)
			(end -0.67945 0.3048)
			(stroke
				(width 0.1)
				(type default)
			)
			(layer "B.Fab")
		)
		(fp_line
			(start -0.12065 -0.3048)
			(end -0.67945 -0.3048)
			(stroke
				(width 0.1)
				(type default)
			)
			(layer "B.Fab")
		)
		(fp_line
			(start 0.12065 -0.305054)
			(end 0.12065 -0.2794)
			(stroke
				(width 0.1)
				(type default)
			)
			(layer "B.Fab")
		)
		(fp_line
			(start 0.67945 -0.305054)
			(end 0.12065 -0.305054)
			(stroke
				(width 0.1)
				(type default)
			)
			(layer "B.Fab")
		)
		(pad "1" smd circle
			(at 0.40005 0 90)
			(size 0 0)
			(layers "B.Cu" "B.Mask" "B.Paste")
			(net "I3C_BMC_SWB_SCL")
		)
		(pad "2" smd circle
			(at -0.40005 0 90)
			(size 0 0)
			(layers "B.Cu" "B.Mask" "B.Paste")
			(net "I3C_BMC_SWB_R_SCL")
		)
	)
	(footprint ""
		(layer "B.Cu")
		(at 10.886694 -136.97839)
		(property "Reference" "C1883"
			(at 0 0 0)
			(layer "B.SilkS")
			(hide yes)
			(effects
				(font
					(size 1.27 1.27)
				)
				(justify mirror)
			)
		)
		(property "Value" ""
			(at 0 0 0)
			(layer "B.Fab")
			(effects
				(font
					(size 1.27 1.27)
				)
				(justify mirror)
			)
		)
		(duplicate_pad_numbers_are_jumpers no)
		(fp_line
			(start -1.524 -0.762)
			(end -1.524 0.762)
			(stroke
				(width 0.1524)
				(type default)
			)
			(layer "B.SilkS")
		)
		(fp_line
			(start -1.524 0.762)
			(end 1.524 0.762)
			(stroke
				(width 0.1524)
				(type default)
			)
			(layer "B.SilkS")
		)
		(fp_line
			(start 1.524 -0.762)
			(end -1.524 -0.762)
			(stroke
				(width 0.1524)
				(type default)
			)
			(layer "B.SilkS")
		)
		(fp_line
			(start 1.524 0.762)
			(end 1.524 -0.762)
			(stroke
				(width 0.1524)
				(type default)
			)
			(layer "B.SilkS")
		)
		(fp_line
			(start -1.1049 -0.724916)
			(end 1.1049 -0.724916)
			(stroke
				(width 0.1)
				(type default)
			)
			(layer "B.Fab")
		)
		(fp_line
			(start -1.1049 0.724916)
			(end -1.1049 -0.724916)
			(stroke
				(width 0.1)
				(type default)
			)
			(layer "B.Fab")
		)
		(fp_line
			(start 1.1049 -0.724916)
			(end 1.1049 0.724916)
			(stroke
				(width 0.1)
				(type default)
			)
			(layer "B.Fab")
		)
		(fp_line
			(start 1.1049 0.724916)
			(end -1.1049 0.724916)
			(stroke
				(width 0.1)
				(type default)
			)
			(layer "B.Fab")
		)
		(pad "1" smd rect
			(at 0.889 0)
			(size 1.016 1.27)
			(layers "B.Cu" "B.Mask" "B.Paste")
			(net "VFG3P3_CLK_GEN")
		)
		(pad "2" smd rect
			(at -0.889 0)
			(size 1.016 1.27)
			(layers "B.Cu" "B.Mask" "B.Paste")
			(net "GND")
		)
	)
	(footprint ""
		(layer "B.Cu")
		(at 304.419 -358.14 180)
		(property "Reference" "R8066"
			(at 0 0 0)
			(layer "B.SilkS")
			(hide yes)
			(effects
				(font
					(size 1.27 1.27)
				)
				(justify mirror)
			)
		)
		(property "Value" ""
			(at 0 0 0)
			(layer "B.Fab")
			(effects
				(font
					(size 1.27 1.27)
				)
				(justify mirror)
			)
		)
		(duplicate_pad_numbers_are_jumpers no)
		(fp_line
			(start 0.7874 0.4064)
			(end 0.7874 -0.4064)
			(stroke
				(width 0.1524)
				(type default)
			)
			(layer "B.SilkS")
		)
		(fp_line
			(start 0.7874 -0.4064)
			(end -0.7874 -0.4064)
			(stroke
				(width 0.1524)
				(type default)
			)
			(layer "B.SilkS")
		)
		(fp_line
			(start -0.7874 0.4064)
			(end 0.7874 0.4064)
			(stroke
				(width 0.1524)
				(type default)
			)
			(layer "B.SilkS")
		)
		(fp_line
			(start -0.7874 -0.4064)
			(end -0.7874 0.4064)
			(stroke
				(width 0.1524)
				(type default)
			)
			(layer "B.SilkS")
		)
		(fp_line
			(start 0.67945 0.3048)
			(end 0.67945 -0.305054)
			(stroke
				(width 0.1)
				(type default)
			)
			(layer "B.Fab")
		)
		(fp_line
			(start 0.67945 -0.305054)
			(end 0.12065 -0.305054)
			(stroke
				(width 0.1)
				(type default)
			)
			(layer "B.Fab")
		)
		(fp_line
			(start 0.12065 0.3048)
			(end 0.67945 0.3048)
			(stroke
				(width 0.1)
				(type default)
			)
			(layer "B.Fab")
		)
		(fp_line
			(start 0.12065 0.2794)
			(end 0.12065 0.3048)
			(stroke
				(width 0.1)
				(type default)
			)
			(layer "B.Fab")
		)
		(fp_line
			(start 0.12065 -0.2794)
			(end -0.12065 -0.2794)
			(stroke
				(width 0.1)
				(type default)
			)
			(layer "B.Fab")
		)
		(fp_line
			(start 0.12065 -0.305054)
			(end 0.12065 -0.2794)
			(stroke
				(width 0.1)
				(type default)
			)
			(layer "B.Fab")
		)
		(fp_line
			(start -0.120396 0.3048)
			(end -0.120396 0.2794)
			(stroke
				(width 0.1)
				(type default)
			)
			(layer "B.Fab")
		)
		(fp_line
			(start -0.120396 0.2794)
			(end 0.12065 0.2794)
			(stroke
				(width 0.1)
				(type default)
			)
			(layer "B.Fab")
		)
		(fp_line
			(start -0.12065 -0.2794)
			(end -0.12065 -0.3048)
			(stroke
				(width 0.1)
				(type default)
			)
			(layer "B.Fab")
		)
		(fp_line
			(start -0.12065 -0.3048)
			(end -0.67945 -0.3048)
			(stroke
				(width 0.1)
				(type default)
			)
			(layer "B.Fab")
		)
		(fp_line
			(start -0.67945 0.3048)
			(end -0.120396 0.3048)
			(stroke
				(width 0.1)
				(type default)
			)
			(layer "B.Fab")
		)
		(fp_line
			(start -0.67945 -0.3048)
			(end -0.67945 0.3048)
			(stroke
				(width 0.1)
				(type default)
			)
			(layer "B.Fab")
		)
		(pad "1" smd circle
			(at 0.40005 0)
			(size 0 0)
			(layers "B.Cu" "B.Mask" "B.Paste")
			(net "PWRGD_PVDDIO_P0")
		)
		(pad "2" smd circle
			(at -0.40005 0)
			(size 0 0)
			(layers "B.Cu" "B.Mask" "B.Paste")
			(net "PWRGD_PVDDIO_P0_R")
		)
	)
	(footprint ""
		(layer "B.Cu")
		(at 324.390512 -336.047334 -90)
		(property "Reference" "PR80"
			(at 0 0 90)
			(layer "B.SilkS")
			(hide yes)
			(effects
				(font
					(size 1.27 1.27)
				)
				(justify mirror)
			)
		)
		(property "Value" ""
			(at 0 0 90)
			(layer "B.Fab")
			(effects
				(font
					(size 1.27 1.27)
				)
				(justify mirror)
			)
		)
		(duplicate_pad_numbers_are_jumpers no)
		(fp_line
			(start -0.7874 0.4064)
			(end 0.7874 0.4064)
			(stroke
				(width 0.1524)
				(type default)
			)
			(layer "B.SilkS")
		)
		(fp_line
			(start 0.7874 0.4064)
			(end 0.7874 -0.4064)
			(stroke
				(width 0.1524)
				(type default)
			)
			(layer "B.SilkS")
		)
		(fp_line
			(start -0.7874 -0.4064)
			(end -0.7874 0.4064)
			(stroke
				(width 0.1524)
				(type default)
			)
			(layer "B.SilkS")
		)
		(fp_line
			(start 0.7874 -0.4064)
			(end -0.7874 -0.4064)
			(stroke
				(width 0.1524)
				(type default)
			)
			(layer "B.SilkS")
		)
		(fp_line
			(start -0.67945 0.3048)
			(end -0.120396 0.3048)
			(stroke
				(width 0.1)
				(type default)
			)
			(layer "B.Fab")
		)
		(fp_line
			(start -0.120396 0.3048)
			(end -0.120396 0.2794)
			(stroke
				(width 0.1)
				(type default)
			)
			(layer "B.Fab")
		)
		(fp_line
			(start 0.12065 0.3048)
			(end 0.67945 0.3048)
			(stroke
				(width 0.1)
				(type default)
			)
			(layer "B.Fab")
		)
		(fp_line
			(start 0.67945 0.3048)
			(end 0.67945 -0.305054)
			(stroke
				(width 0.1)
				(type default)
			)
			(layer "B.Fab")
		)
		(fp_line
			(start -0.120396 0.2794)
			(end 0.12065 0.2794)
			(stroke
				(width 0.1)
				(type default)
			)
			(layer "B.Fab")
		)
		(fp_line
			(start 0.12065 0.2794)
			(end 0.12065 0.3048)
			(stroke
				(width 0.1)
				(type default)
			)
			(layer "B.Fab")
		)
		(fp_line
			(start -0.12065 -0.2794)
			(end -0.12065 -0.3048)
			(stroke
				(width 0.1)
				(type default)
			)
			(layer "B.Fab")
		)
		(fp_line
			(start 0.12065 -0.2794)
			(end -0.12065 -0.2794)
			(stroke
				(width 0.1)
				(type default)
			)
			(layer "B.Fab")
		)
		(fp_line
			(start -0.67945 -0.3048)
			(end -0.67945 0.3048)
			(stroke
				(width 0.1)
				(type default)
			)
			(layer "B.Fab")
		)
		(fp_line
			(start -0.12065 -0.3048)
			(end -0.67945 -0.3048)
			(stroke
				(width 0.1)
				(type default)
			)
			(layer "B.Fab")
		)
		(fp_line
			(start 0.12065 -0.305054)
			(end 0.12065 -0.2794)
			(stroke
				(width 0.1)
				(type default)
			)
			(layer "B.Fab")
		)
		(fp_line
			(start 0.67945 -0.305054)
			(end 0.12065 -0.305054)
			(stroke
				(width 0.1)
				(type default)
			)
			(layer "B.Fab")
		)
		(pad "1" smd circle
			(at 0.40005 0 90)
			(size 0 0)
			(layers "B.Cu" "B.Mask" "B.Paste")
			(net "PVDDCR_CPU1_P0_PVCC")
		)
		(pad "2" smd circle
			(at -0.40005 0 90)
			(size 0 0)
			(layers "B.Cu" "B.Mask" "B.Paste")
			(net "PVDDCR_CPU1_P0_VCC2")
		)
	)
	(footprint ""
		(layer "B.Cu")
		(at 49.401476 -337.985354 -90)
		(property "Reference" "PC456_1"
			(at 0 0 90)
			(layer "B.SilkS")
			(hide yes)
			(effects
				(font
					(size 1.27 1.27)
				)
				(justify mirror)
			)
		)
		(property "Value" ""
			(at 0 0 90)
			(layer "B.Fab")
			(effects
				(font
					(size 1.27 1.27)
				)
				(justify mirror)
			)
		)
		(duplicate_pad_numbers_are_jumpers no)
		(fp_line
			(start -1.524 0.762)
			(end 1.524 0.762)
			(stroke
				(width 0.1524)
				(type default)
			)
			(layer "B.SilkS")
		)
		(fp_line
			(start 1.524 0.762)
			(end 1.524 -0.762)
			(stroke
				(width 0.1524)
				(type default)
			)
			(layer "B.SilkS")
		)
		(fp_line
			(start -1.524 -0.762)
			(end -1.524 0.762)
			(stroke
				(width 0.1524)
				(type default)
			)
			(layer "B.SilkS")
		)
		(fp_line
			(start 1.524 -0.762)
			(end -1.524 -0.762)
			(stroke
				(width 0.1524)
				(type default)
			)
			(layer "B.SilkS")
		)
		(fp_line
			(start -1.1049 0.724916)
			(end -1.1049 -0.724916)
			(stroke
				(width 0.1)
				(type default)
			)
			(layer "B.Fab")
		)
		(fp_line
			(start 1.1049 0.724916)
			(end -1.1049 0.724916)
			(stroke
				(width 0.1)
				(type default)
			)
			(layer "B.Fab")
		)
		(fp_line
			(start -1.1049 -0.724916)
			(end 1.1049 -0.724916)
			(stroke
				(width 0.1)
				(type default)
			)
			(layer "B.Fab")
		)
		(fp_line
			(start 1.1049 -0.724916)
			(end 1.1049 0.724916)
			(stroke
				(width 0.1)
				(type default)
			)
			(layer "B.Fab")
		)
		(pad "1" smd rect
			(at 0.889 0 270)
			(size 1.016 1.27)
			(layers "B.Cu" "B.Mask" "B.Paste")
			(net "PVDDIO_P1")
		)
		(pad "2" smd rect
			(at -0.889 0 270)
			(size 1.016 1.27)
			(layers "B.Cu" "B.Mask" "B.Paste")
			(net "GND")
		)
	)
	(footprint ""
		(layer "B.Cu")
		(at 423.139616 -495.255042)
		(property "Reference" "LBL_2"
			(at 0 0 0)
			(layer "B.SilkS")
			(hide yes)
			(effects
				(font
					(size 1.27 1.27)
				)
				(justify mirror)
			)
		)
		(property "Value" ""
			(at 0 0 0)
			(layer "B.Fab")
			(effects
				(font
					(size 1.27 1.27)
				)
				(justify mirror)
			)
		)
		(duplicate_pad_numbers_are_jumpers no)
		(pad "1" smd circle
			(at 0 0 180)
			(size 0.762 0.762)
			(layers "B.Cu" "B.Mask" "B.Paste")
			(net "Net_10851")
		)
	)
	(footprint ""
		(layer "B.Cu")
		(at 225.679 -332.105)
		(property "Reference" "C7500"
			(at 0 0 0)
			(layer "B.SilkS")
			(hide yes)
			(effects
				(font
					(size 1.27 1.27)
				)
				(justify mirror)
			)
		)
		(property "Value" ""
			(at 0 0 0)
			(layer "B.Fab")
			(effects
				(font
					(size 1.27 1.27)
				)
				(justify mirror)
			)
		)
		(duplicate_pad_numbers_are_jumpers no)
		(fp_line
			(start -0.299974 -0.150114)
			(end -0.299974 0.150114)
			(stroke
				(width 0.1)
				(type default)
			)
			(layer "B.Fab")
		)
		(fp_line
			(start -0.299974 0.150114)
			(end 0.299974 0.150114)
			(stroke
				(width 0.1)
				(type default)
			)
			(layer "B.Fab")
		)
		(fp_line
			(start 0.299974 -0.150114)
			(end -0.299974 -0.150114)
			(stroke
				(width 0.1)
				(type default)
			)
			(layer "B.Fab")
		)
		(fp_line
			(start 0.299974 0.150114)
			(end 0.299974 -0.150114)
			(stroke
				(width 0.1)
				(type default)
			)
			(layer "B.Fab")
		)
		(pad "1" smd rect
			(at 0.2667 0 180)
			(size 0.3048 0.381)
			(layers "B.Cu" "B.Mask" "B.Paste")
			(net "P1V8_AUX")
		)
		(pad "2" smd rect
			(at -0.2667 0 180)
			(size 0.3048 0.381)
			(layers "B.Cu" "B.Mask" "B.Paste")
			(net "GND")
		)
	)
	(footprint ""
		(layer "B.Cu")
		(at 185.458608 -113.462816 90)
		(property "Reference" "C362"
			(at 0 0 90)
			(layer "B.SilkS")
			(hide yes)
			(effects
				(font
					(size 1.27 1.27)
				)
				(justify mirror)
			)
		)
		(property "Value" ""
			(at 0 0 90)
			(layer "B.Fab")
			(effects
				(font
					(size 1.27 1.27)
				)
				(justify mirror)
			)
		)
		(duplicate_pad_numbers_are_jumpers no)
		(fp_line
			(start 0.69215 -0.2921)
			(end -0.69215 -0.2921)
			(stroke
				(width 0.1524)
				(type default)
			)
			(layer "B.SilkS")
		)
		(fp_line
			(start -0.69215 -0.2921)
			(end -0.69215 0.2921)
			(stroke
				(width 0.1524)
				(type default)
			)
			(layer "B.SilkS")
		)
		(fp_line
			(start 0.69215 0.2921)
			(end 0.69215 -0.2921)
			(stroke
				(width 0.1524)
				(type default)
			)
			(layer "B.SilkS")
		)
		(fp_line
			(start -0.69215 0.2921)
			(end 0.69215 0.2921)
			(stroke
				(width 0.1524)
				(type default)
			)
			(layer "B.SilkS")
		)
		(fp_line
			(start 0.51435 -0.2794)
			(end -0.51435 -0.2794)
			(stroke
				(width 0.1)
				(type default)
			)
			(layer "B.Fab")
		)
		(fp_line
			(start -0.51435 -0.2794)
			(end -0.51435 0.2794)
			(stroke
				(width 0.1)
				(type default)
			)
			(layer "B.Fab")
		)
		(fp_line
			(start 0.51435 0.2794)
			(end 0.51435 -0.2794)
			(stroke
				(width 0.1)
				(type default)
			)
			(layer "B.Fab")
		)
		(fp_line
			(start -0.51435 0.2794)
			(end 0.51435 0.2794)
			(stroke
				(width 0.1)
				(type default)
			)
			(layer "B.Fab")
		)
		(pad "1" smd circle
			(at 0.40005 0 270)
			(size 0 0)
			(layers "B.Cu" "B.Mask" "B.Paste")
			(net "P3V3_AUX")
		)
		(pad "2" smd circle
			(at -0.40005 0 270)
			(size 0 0)
			(layers "B.Cu" "B.Mask" "B.Paste")
			(net "GND")
		)
		(zone
			(layer "B.Cu")
			(hatch none 0.5)
			(connect_pads
				(clearance 0)
			)
			(min_thickness 0.25)
			(keepout
				(tracks not_allowed)
				(vias allowed)
				(pads allowed)
				(copperpour not_allowed)
				(footprints allowed)
			)
			(placement
				(enabled no)
				(sheetname "")
			)
			(fill
				(thermal_gap 0.5)
				(thermal_bridge_width 0.5)
				(island_removal_mode 0)
			)
			(polygon
				(pts
					(xy 185.312558 -113.362486) (xy 185.312558 -113.561876) (xy 185.370724 -113.653316) (xy 185.546238 -113.653316)
					(xy 185.604404 -113.561876) (xy 185.604404 -113.362486) (xy 185.546238 -113.272316) (xy 185.370978 -113.272316)
				)
			)
		)
	)
	(footprint ""
		(layer "B.Cu")
		(at 340.705948 -395.148562 90)
		(property "Reference" "C621"
			(at 0 0 90)
			(layer "B.SilkS")
			(hide yes)
			(effects
				(font
					(size 1.27 1.27)
				)
				(justify mirror)
			)
		)
		(property "Value" ""
			(at 0 0 90)
			(layer "B.Fab")
			(effects
				(font
					(size 1.27 1.27)
				)
				(justify mirror)
			)
		)
		(duplicate_pad_numbers_are_jumpers no)
		(fp_line
			(start 0.299974 -0.150114)
			(end -0.299974 -0.150114)
			(stroke
				(width 0.1)
				(type default)
			)
			(layer "B.Fab")
		)
		(fp_line
			(start -0.299974 -0.150114)
			(end -0.299974 0.150114)
			(stroke
				(width 0.1)
				(type default)
			)
			(layer "B.Fab")
		)
		(fp_line
			(start 0.299974 0.150114)
			(end 0.299974 -0.150114)
			(stroke
				(width 0.1)
				(type default)
			)
			(layer "B.Fab")
		)
		(fp_line
			(start -0.299974 0.150114)
			(end 0.299974 0.150114)
			(stroke
				(width 0.1)
				(type default)
			)
			(layer "B.Fab")
		)
		(pad "1" smd rect
			(at 0.2667 0 270)
			(size 0.3048 0.381)
			(layers "B.Cu" "B.Mask" "B.Paste")
			(net "P0V9_CPU0_RT1_2A_2D")
		)
		(pad "2" smd rect
			(at -0.2667 0 270)
			(size 0.3048 0.381)
			(layers "B.Cu" "B.Mask" "B.Paste")
			(net "GND")
		)
	)
	(footprint ""
		(layer "B.Cu")
		(at 182.88254 -20.378166 90)
		(property "Reference" "R3239"
			(at 0 0 90)
			(layer "B.SilkS")
			(hide yes)
			(effects
				(font
					(size 1.27 1.27)
				)
				(justify mirror)
			)
		)
		(property "Value" ""
			(at 0 0 90)
			(layer "B.Fab")
			(effects
				(font
					(size 1.27 1.27)
				)
				(justify mirror)
			)
		)
		(duplicate_pad_numbers_are_jumpers no)
		(fp_line
			(start 0.7874 -0.4064)
			(end -0.7874 -0.4064)
			(stroke
				(width 0.1524)
				(type default)
			)
			(layer "B.SilkS")
		)
		(fp_line
			(start -0.7874 -0.4064)
			(end -0.7874 0.4064)
			(stroke
				(width 0.1524)
				(type default)
			)
			(layer "B.SilkS")
		)
		(fp_line
			(start 0.7874 0.4064)
			(end 0.7874 -0.4064)
			(stroke
				(width 0.1524)
				(type default)
			)
			(layer "B.SilkS")
		)
		(fp_line
			(start -0.7874 0.4064)
			(end 0.7874 0.4064)
			(stroke
				(width 0.1524)
				(type default)
			)
			(layer "B.SilkS")
		)
		(fp_line
			(start 0.67945 -0.305054)
			(end 0.12065 -0.305054)
			(stroke
				(width 0.1)
				(type default)
			)
			(layer "B.Fab")
		)
		(fp_line
			(start 0.12065 -0.305054)
			(end 0.12065 -0.2794)
			(stroke
				(width 0.1)
				(type default)
			)
			(layer "B.Fab")
		)
		(fp_line
			(start -0.12065 -0.3048)
			(end -0.67945 -0.3048)
			(stroke
				(width 0.1)
				(type default)
			)
			(layer "B.Fab")
		)
		(fp_line
			(start -0.67945 -0.3048)
			(end -0.67945 0.3048)
			(stroke
				(width 0.1)
				(type default)
			)
			(layer "B.Fab")
		)
		(fp_line
			(start 0.12065 -0.2794)
			(end -0.12065 -0.2794)
			(stroke
				(width 0.1)
				(type default)
			)
			(layer "B.Fab")
		)
		(fp_line
			(start -0.12065 -0.2794)
			(end -0.12065 -0.3048)
			(stroke
				(width 0.1)
				(type default)
			)
			(layer "B.Fab")
		)
		(fp_line
			(start 0.12065 0.2794)
			(end 0.12065 0.3048)
			(stroke
				(width 0.1)
				(type default)
			)
			(layer "B.Fab")
		)
		(fp_line
			(start -0.120396 0.2794)
			(end 0.12065 0.2794)
			(stroke
				(width 0.1)
				(type default)
			)
			(layer "B.Fab")
		)
		(fp_line
			(start 0.67945 0.3048)
			(end 0.67945 -0.305054)
			(stroke
				(width 0.1)
				(type default)
			)
			(layer "B.Fab")
		)
		(fp_line
			(start 0.12065 0.3048)
			(end 0.67945 0.3048)
			(stroke
				(width 0.1)
				(type default)
			)
			(layer "B.Fab")
		)
		(fp_line
			(start -0.120396 0.3048)
			(end -0.120396 0.2794)
			(stroke
				(width 0.1)
				(type default)
			)
			(layer "B.Fab")
		)
		(fp_line
			(start -0.67945 0.3048)
			(end -0.120396 0.3048)
			(stroke
				(width 0.1)
				(type default)
			)
			(layer "B.Fab")
		)
		(pad "1" smd circle
			(at 0.40005 0 270)
			(size 0 0)
			(layers "B.Cu" "B.Mask" "B.Paste")
			(net "SMB_OCP_SFF_3V3AUX_SDA")
		)
		(pad "2" smd circle
			(at -0.40005 0 270)
			(size 0 0)
			(layers "B.Cu" "B.Mask" "B.Paste")
			(net "SMB_OCP_SFF_3V3AUX_SDA_R0")
		)
	)
	(footprint ""
		(layer "B.Cu")
		(at 182.294276 -407.219912 90)
		(property "Reference" "R3909"
			(at 0 0 90)
			(layer "B.SilkS")
			(hide yes)
			(effects
				(font
					(size 1.27 1.27)
				)
				(justify mirror)
			)
		)
		(property "Value" ""
			(at 0 0 90)
			(layer "B.Fab")
			(effects
				(font
					(size 1.27 1.27)
				)
				(justify mirror)
			)
		)
		(duplicate_pad_numbers_are_jumpers no)
		(fp_line
			(start 0.7874 -0.4064)
			(end -0.7874 -0.4064)
			(stroke
				(width 0.1524)
				(type default)
			)
			(layer "B.SilkS")
		)
		(fp_line
			(start -0.7874 -0.4064)
			(end -0.7874 0.4064)
			(stroke
				(width 0.1524)
				(type default)
			)
			(layer "B.SilkS")
		)
		(fp_line
			(start 0.7874 0.4064)
			(end 0.7874 -0.4064)
			(stroke
				(width 0.1524)
				(type default)
			)
			(layer "B.SilkS")
		)
		(fp_line
			(start -0.7874 0.4064)
			(end 0.7874 0.4064)
			(stroke
				(width 0.1524)
				(type default)
			)
			(layer "B.SilkS")
		)
		(fp_line
			(start 0.67945 -0.305054)
			(end 0.12065 -0.305054)
			(stroke
				(width 0.1)
				(type default)
			)
			(layer "B.Fab")
		)
		(fp_line
			(start 0.12065 -0.305054)
			(end 0.12065 -0.2794)
			(stroke
				(width 0.1)
				(type default)
			)
			(layer "B.Fab")
		)
		(fp_line
			(start -0.12065 -0.3048)
			(end -0.67945 -0.3048)
			(stroke
				(width 0.1)
				(type default)
			)
			(layer "B.Fab")
		)
		(fp_line
			(start -0.67945 -0.3048)
			(end -0.67945 0.3048)
			(stroke
				(width 0.1)
				(type default)
			)
			(layer "B.Fab")
		)
		(fp_line
			(start 0.12065 -0.2794)
			(end -0.12065 -0.2794)
			(stroke
				(width 0.1)
				(type default)
			)
			(layer "B.Fab")
		)
		(fp_line
			(start -0.12065 -0.2794)
			(end -0.12065 -0.3048)
			(stroke
				(width 0.1)
				(type default)
			)
			(layer "B.Fab")
		)
		(fp_line
			(start 0.12065 0.2794)
			(end 0.12065 0.3048)
			(stroke
				(width 0.1)
				(type default)
			)
			(layer "B.Fab")
		)
		(fp_line
			(start -0.120396 0.2794)
			(end 0.12065 0.2794)
			(stroke
				(width 0.1)
				(type default)
			)
			(layer "B.Fab")
		)
		(fp_line
			(start 0.67945 0.3048)
			(end 0.67945 -0.305054)
			(stroke
				(width 0.1)
				(type default)
			)
			(layer "B.Fab")
		)
		(fp_line
			(start 0.12065 0.3048)
			(end 0.67945 0.3048)
			(stroke
				(width 0.1)
				(type default)
			)
			(layer "B.Fab")
		)
		(fp_line
			(start -0.120396 0.3048)
			(end -0.120396 0.2794)
			(stroke
				(width 0.1)
				(type default)
			)
			(layer "B.Fab")
		)
		(fp_line
			(start -0.67945 0.3048)
			(end -0.120396 0.3048)
			(stroke
				(width 0.1)
				(type default)
			)
			(layer "B.Fab")
		)
		(pad "1" smd circle
			(at 0.40005 0 270)
			(size 0 0)
			(layers "B.Cu" "B.Mask" "B.Paste")
			(net "SMB_SML1_PMBUS_HSC_SCL")
		)
		(pad "2" smd circle
			(at -0.40005 0 270)
			(size 0 0)
			(layers "B.Cu" "B.Mask" "B.Paste")
			(net "SMB_SML1_PMBUS_HSC_L_SCL")
		)
	)
	(footprint ""
		(layer "B.Cu")
		(at 111.800386 -246.066564 90)
		(property "Reference" "C2321"
			(at 0 0 90)
			(layer "B.SilkS")
			(hide yes)
			(effects
				(font
					(size 1.27 1.27)
				)
				(justify mirror)
			)
		)
		(property "Value" ""
			(at 0 0 90)
			(layer "B.Fab")
			(effects
				(font
					(size 1.27 1.27)
				)
				(justify mirror)
			)
		)
		(duplicate_pad_numbers_are_jumpers no)
		(fp_line
			(start 0.7874 -0.4064)
			(end -0.7874 -0.4064)
			(stroke
				(width 0.1524)
				(type default)
			)
			(layer "B.SilkS")
		)
		(fp_line
			(start -0.7874 -0.4064)
			(end -0.7874 0.4064)
			(stroke
				(width 0.1524)
				(type default)
			)
			(layer "B.SilkS")
		)
		(fp_line
			(start 0.7874 0.4064)
			(end 0.7874 -0.4064)
			(stroke
				(width 0.1524)
				(type default)
			)
			(layer "B.SilkS")
		)
		(fp_line
			(start -0.7874 0.4064)
			(end 0.7874 0.4064)
			(stroke
				(width 0.1524)
				(type default)
			)
			(layer "B.SilkS")
		)
		(fp_line
			(start 0.67945 -0.305054)
			(end 0.12065 -0.305054)
			(stroke
				(width 0.1)
				(type default)
			)
			(layer "B.Fab")
		)
		(fp_line
			(start 0.12065 -0.305054)
			(end 0.12065 -0.2794)
			(stroke
				(width 0.1)
				(type default)
			)
			(layer "B.Fab")
		)
		(fp_line
			(start -0.12065 -0.3048)
			(end -0.67945 -0.3048)
			(stroke
				(width 0.1)
				(type default)
			)
			(layer "B.Fab")
		)
		(fp_line
			(start -0.67945 -0.3048)
			(end -0.67945 0.3048)
			(stroke
				(width 0.1)
				(type default)
			)
			(layer "B.Fab")
		)
		(fp_line
			(start 0.12065 -0.2794)
			(end -0.12065 -0.2794)
			(stroke
				(width 0.1)
				(type default)
			)
			(layer "B.Fab")
		)
		(fp_line
			(start -0.12065 -0.2794)
			(end -0.12065 -0.3048)
			(stroke
				(width 0.1)
				(type default)
			)
			(layer "B.Fab")
		)
		(fp_line
			(start 0.12065 0.2794)
			(end 0.12065 0.3048)
			(stroke
				(width 0.1)
				(type default)
			)
			(layer "B.Fab")
		)
		(fp_line
			(start -0.120396 0.2794)
			(end 0.12065 0.2794)
			(stroke
				(width 0.1)
				(type default)
			)
			(layer "B.Fab")
		)
		(fp_line
			(start 0.67945 0.3048)
			(end 0.67945 -0.305054)
			(stroke
				(width 0.1)
				(type default)
			)
			(layer "B.Fab")
		)
		(fp_line
			(start 0.12065 0.3048)
			(end 0.67945 0.3048)
			(stroke
				(width 0.1)
				(type default)
			)
			(layer "B.Fab")
		)
		(fp_line
			(start -0.120396 0.3048)
			(end -0.120396 0.2794)
			(stroke
				(width 0.1)
				(type default)
			)
			(layer "B.Fab")
		)
		(fp_line
			(start -0.67945 0.3048)
			(end -0.120396 0.3048)
			(stroke
				(width 0.1)
				(type default)
			)
			(layer "B.Fab")
		)
		(pad "1" smd circle
			(at 0.40005 0 270)
			(size 0 0)
			(layers "B.Cu" "B.Mask" "B.Paste")
			(net "PVDDCR_CPU0_P1")
		)
		(pad "2" smd circle
			(at -0.40005 0 270)
			(size 0 0)
			(layers "B.Cu" "B.Mask" "B.Paste")
			(net "GND")
		)
	)
	(footprint ""
		(layer "B.Cu")
		(at 123.865386 -268.418564)
		(property "Reference" "C2364"
			(at 0 0 0)
			(layer "B.SilkS")
			(hide yes)
			(effects
				(font
					(size 1.27 1.27)
				)
				(justify mirror)
			)
		)
		(property "Value" ""
			(at 0 0 0)
			(layer "B.Fab")
			(effects
				(font
					(size 1.27 1.27)
				)
				(justify mirror)
			)
		)
		(duplicate_pad_numbers_are_jumpers no)
		(fp_line
			(start -0.7874 -0.4064)
			(end -0.7874 0.4064)
			(stroke
				(width 0.1524)
				(type default)
			)
			(layer "B.SilkS")
		)
		(fp_line
			(start -0.7874 0.4064)
			(end 0.7874 0.4064)
			(stroke
				(width 0.1524)
				(type default)
			)
			(layer "B.SilkS")
		)
		(fp_line
			(start 0.7874 -0.4064)
			(end -0.7874 -0.4064)
			(stroke
				(width 0.1524)
				(type default)
			)
			(layer "B.SilkS")
		)
		(fp_line
			(start 0.7874 0.4064)
			(end 0.7874 -0.4064)
			(stroke
				(width 0.1524)
				(type default)
			)
			(layer "B.SilkS")
		)
		(fp_line
			(start -0.67945 -0.3048)
			(end -0.67945 0.3048)
			(stroke
				(width 0.1)
				(type default)
			)
			(layer "B.Fab")
		)
		(fp_line
			(start -0.67945 0.3048)
			(end -0.120396 0.3048)
			(stroke
				(width 0.1)
				(type default)
			)
			(layer "B.Fab")
		)
		(fp_line
			(start -0.12065 -0.3048)
			(end -0.67945 -0.3048)
			(stroke
				(width 0.1)
				(type default)
			)
			(layer "B.Fab")
		)
		(fp_line
			(start -0.12065 -0.2794)
			(end -0.12065 -0.3048)
			(stroke
				(width 0.1)
				(type default)
			)
			(layer "B.Fab")
		)
		(fp_line
			(start -0.120396 0.2794)
			(end 0.12065 0.2794)
			(stroke
				(width 0.1)
				(type default)
			)
			(layer "B.Fab")
		)
		(fp_line
			(start -0.120396 0.3048)
			(end -0.120396 0.2794)
			(stroke
				(width 0.1)
				(type default)
			)
			(layer "B.Fab")
		)
		(fp_line
			(start 0.12065 -0.305054)
			(end 0.12065 -0.2794)
			(stroke
				(width 0.1)
				(type default)
			)
			(layer "B.Fab")
		)
		(fp_line
			(start 0.12065 -0.2794)
			(end -0.12065 -0.2794)
			(stroke
				(width 0.1)
				(type default)
			)
			(layer "B.Fab")
		)
		(fp_line
			(start 0.12065 0.2794)
			(end 0.12065 0.3048)
			(stroke
				(width 0.1)
				(type default)
			)
			(layer "B.Fab")
		)
		(fp_line
			(start 0.12065 0.3048)
			(end 0.67945 0.3048)
			(stroke
				(width 0.1)
				(type default)
			)
			(layer "B.Fab")
		)
		(fp_line
			(start 0.67945 -0.305054)
			(end 0.12065 -0.305054)
			(stroke
				(width 0.1)
				(type default)
			)
			(layer "B.Fab")
		)
		(fp_line
			(start 0.67945 0.3048)
			(end 0.67945 -0.305054)
			(stroke
				(width 0.1)
				(type default)
			)
			(layer "B.Fab")
		)
		(pad "1" smd circle
			(at 0.40005 0 180)
			(size 0 0)
			(layers "B.Cu" "B.Mask" "B.Paste")
			(net "PVDDCR_CPU1_P1")
		)
		(pad "2" smd circle
			(at -0.40005 0 180)
			(size 0 0)
			(layers "B.Cu" "B.Mask" "B.Paste")
			(net "GND")
		)
	)
	(footprint ""
		(layer "B.Cu")
		(at 404.568152 -354.439728 -90)
		(property "Reference" "R6127"
			(at 0 0 90)
			(layer "B.SilkS")
			(hide yes)
			(effects
				(font
					(size 1.27 1.27)
				)
				(justify mirror)
			)
		)
		(property "Value" ""
			(at 0 0 90)
			(layer "B.Fab")
			(effects
				(font
					(size 1.27 1.27)
				)
				(justify mirror)
			)
		)
		(duplicate_pad_numbers_are_jumpers no)
		(fp_line
			(start -0.7874 0.4064)
			(end 0.7874 0.4064)
			(stroke
				(width 0.1524)
				(type default)
			)
			(layer "B.SilkS")
		)
		(fp_line
			(start 0.7874 0.4064)
			(end 0.7874 -0.4064)
			(stroke
				(width 0.1524)
				(type default)
			)
			(layer "B.SilkS")
		)
		(fp_line
			(start -0.7874 -0.4064)
			(end -0.7874 0.4064)
			(stroke
				(width 0.1524)
				(type default)
			)
			(layer "B.SilkS")
		)
		(fp_line
			(start 0.7874 -0.4064)
			(end -0.7874 -0.4064)
			(stroke
				(width 0.1524)
				(type default)
			)
			(layer "B.SilkS")
		)
		(fp_line
			(start -0.67945 0.3048)
			(end -0.120396 0.3048)
			(stroke
				(width 0.1)
				(type default)
			)
			(layer "B.Fab")
		)
		(fp_line
			(start -0.120396 0.3048)
			(end -0.120396 0.2794)
			(stroke
				(width 0.1)
				(type default)
			)
			(layer "B.Fab")
		)
		(fp_line
			(start 0.12065 0.3048)
			(end 0.67945 0.3048)
			(stroke
				(width 0.1)
				(type default)
			)
			(layer "B.Fab")
		)
		(fp_line
			(start 0.67945 0.3048)
			(end 0.67945 -0.305054)
			(stroke
				(width 0.1)
				(type default)
			)
			(layer "B.Fab")
		)
		(fp_line
			(start -0.120396 0.2794)
			(end 0.12065 0.2794)
			(stroke
				(width 0.1)
				(type default)
			)
			(layer "B.Fab")
		)
		(fp_line
			(start 0.12065 0.2794)
			(end 0.12065 0.3048)
			(stroke
				(width 0.1)
				(type default)
			)
			(layer "B.Fab")
		)
		(fp_line
			(start -0.12065 -0.2794)
			(end -0.12065 -0.3048)
			(stroke
				(width 0.1)
				(type default)
			)
			(layer "B.Fab")
		)
		(fp_line
			(start 0.12065 -0.2794)
			(end -0.12065 -0.2794)
			(stroke
				(width 0.1)
				(type default)
			)
			(layer "B.Fab")
		)
		(fp_line
			(start -0.67945 -0.3048)
			(end -0.67945 0.3048)
			(stroke
				(width 0.1)
				(type default)
			)
			(layer "B.Fab")
		)
		(fp_line
			(start -0.12065 -0.3048)
			(end -0.67945 -0.3048)
			(stroke
				(width 0.1)
				(type default)
			)
			(layer "B.Fab")
		)
		(fp_line
			(start 0.12065 -0.305054)
			(end 0.12065 -0.2794)
			(stroke
				(width 0.1)
				(type default)
			)
			(layer "B.Fab")
		)
		(fp_line
			(start 0.67945 -0.305054)
			(end 0.12065 -0.305054)
			(stroke
				(width 0.1)
				(type default)
			)
			(layer "B.Fab")
		)
		(pad "1" smd circle
			(at 0.40005 0 90)
			(size 0 0)
			(layers "B.Cu" "B.Mask" "B.Paste")
			(net "FM_BOARD_SKU_ID2")
		)
		(pad "2" smd circle
			(at -0.40005 0 90)
			(size 0 0)
			(layers "B.Cu" "B.Mask" "B.Paste")
			(net "GND")
		)
	)
	(footprint ""
		(layer "B.Cu")
		(at 514.718808 7.526274 90)
		(property "Reference" "X8005"
			(at 0.93726 -1.53035 270)
			(unlocked yes)
			(layer "B.SilkS")
			(effects
				(font
					(size 0.7874 0.5842)
					(thickness 0.1524)
				)
				(justify left mirror)
			)
		)
		(property "Value" ""
			(at 0 0 90)
			(layer "B.Fab")
			(effects
				(font
					(size 1.27 1.27)
				)
				(justify mirror)
			)
		)
		(property "Device Type" "TP_TDR_4P_FTS_TH-TP_TDR_4P_DIP,EMPTY,TP15"
			(at -1.30175 1.27 0)
			(unlocked yes)
			(layer "B.Fab")
			(hide yes)
			(effects
				(font
					(size 0.635 0.4064)
					(thickness 0.1524)
				)
				(justify mirror)
			)
		)
		(property "User Part Number" "N_A"
			(at -1.30175 1.27 0)
			(unlocked yes)
			(layer "Cmts.User")
			(hide yes)
			(effects
				(font
					(size 0.635 0.4064)
					(thickness 0.1524)
				)
				(justify mirror)
			)
		)
		(duplicate_pad_numbers_are_jumpers no)
		(fp_line
			(start 0 -1.27)
			(end 0 -0.635)
			(stroke
				(width 0.1524)
				(type default)
			)
			(layer "B.SilkS")
		)
		(fp_line
			(start -2.54 -1.27)
			(end 0 -1.27)
			(stroke
				(width 0.1524)
				(type default)
			)
			(layer "B.SilkS")
		)
		(fp_line
			(start -2.54 -1.1303)
			(end -2.54 -1.27)
			(stroke
				(width 0.1524)
				(type default)
			)
			(layer "B.SilkS")
		)
		(fp_line
			(start 0 0.635)
			(end 0 1.905)
			(stroke
				(width 0.1524)
				(type default)
			)
			(layer "B.SilkS")
		)
		(fp_line
			(start -2.54 1.4097)
			(end -2.54 1.1303)
			(stroke
				(width 0.1524)
				(type default)
			)
			(layer "B.SilkS")
		)
		(fp_line
			(start 0 3.175)
			(end 0 3.81)
			(stroke
				(width 0.1524)
				(type default)
			)
			(layer "B.SilkS")
		)
		(fp_line
			(start 0 3.81)
			(end -2.54 3.81)
			(stroke
				(width 0.1524)
				(type default)
			)
			(layer "B.SilkS")
		)
		(fp_line
			(start -2.54 3.81)
			(end -2.54 3.6703)
			(stroke
				(width 0.1524)
				(type default)
			)
			(layer "B.SilkS")
		)
		(fp_poly
			(pts
				(xy 0.761746 0) (xy 2.285746 -0.762) (xy 2.285746 0.762)
			)
			(stroke
				(width 0)
				(type default)
			)
			(fill yes)
			(layer "B.SilkS")
		)
		(fp_line
			(start 0 -1.27)
			(end 0 3.81)
			(stroke
				(width 0.1)
				(type default)
			)
			(layer "B.Fab")
		)
		(fp_line
			(start -2.54 -1.27)
			(end 0 -1.27)
			(stroke
				(width 0.1)
				(type default)
			)
			(layer "B.Fab")
		)
		(fp_line
			(start 0 3.81)
			(end -2.54 3.81)
			(stroke
				(width 0.1)
				(type default)
			)
			(layer "B.Fab")
		)
		(fp_line
			(start -2.54 3.81)
			(end -2.54 -1.27)
			(stroke
				(width 0.1)
				(type default)
			)
			(layer "B.Fab")
		)
		(fp_poly
			(pts
				(xy 0.761746 0) (xy 2.285746 -0.762) (xy 2.285746 0.762)
			)
			(stroke
				(width 0)
				(type default)
			)
			(fill yes)
			(layer "B.Fab")
		)
		(pad "1" thru_hole circle
			(at 0 0 270)
			(size 1.0033 1.0033)
			(drill 0.249936)
			(layers "*.Cu" "*.Mask")
			(remove_unused_layers no)
			(net "TDR_DIFF_85_IN4_DP")
			(clearance 0.10795)
			(padstack
				(mode front_inner_back)
				(layer "Inner"
					(shape circle)
					(size 0.8001 0.8001)
					(clearance 0.1524)
				)
				(layer "B.Cu"
					(shape circle)
					(size 1.0033 1.0033)
					(thermal_gap 0.10795)
					(clearance 0.10795)
				)
			)
		)
		(pad "2" thru_hole circle
			(at -2.54 0 270)
			(size 1.9939 1.9939)
			(drill 0.249936)
			(layers "*.Cu" "*.Mask")
			(remove_unused_layers no)
			(net "T1_GND")
			(clearance 0.10795)
			(padstack
				(mode front_inner_back)
				(layer "Inner"
					(shape circle)
					(size 0.8001 0.8001)
					(clearance 0.1524)
				)
				(layer "B.Cu"
					(shape circle)
					(size 1.9939 1.9939)
					(thermal_gap 0.10795)
					(clearance 0.10795)
				)
			)
		)
		(pad "3" thru_hole circle
			(at -2.54 2.54 270)
			(size 1.9939 1.9939)
			(drill 0.249936)
			(layers "*.Cu" "*.Mask")
			(remove_unused_layers no)
			(net "T1_GND")
			(clearance 0.10795)
			(padstack
				(mode front_inner_back)
				(layer "Inner"
					(shape circle)
					(size 0.8001 0.8001)
					(clearance 0.1524)
				)
				(layer "B.Cu"
					(shape circle)
					(size 1.9939 1.9939)
					(thermal_gap 0.10795)
					(clearance 0.10795)
				)
			)
		)
		(pad "4" thru_hole circle
			(at 0 2.54 270)
			(size 1.0033 1.0033)
			(drill 0.249936)
			(layers "*.Cu" "*.Mask")
			(remove_unused_layers no)
			(net "TDR_DIFF_85_IN4_DN")
			(clearance 0.10795)
			(padstack
				(mode front_inner_back)
				(layer "Inner"
					(shape circle)
					(size 0.8001 0.8001)
					(clearance 0.1524)
				)
				(layer "B.Cu"
					(shape circle)
					(size 1.0033 1.0033)
					(thermal_gap 0.10795)
					(clearance 0.10795)
				)
			)
		)
	)
	(footprint ""
		(layer "B.Cu")
		(at 385.3942 -191.33058 90)
		(property "Reference" "PC565_4"
			(at 0 0 90)
			(layer "B.SilkS")
			(hide yes)
			(effects
				(font
					(size 1.27 1.27)
				)
				(justify mirror)
			)
		)
		(property "Value" ""
			(at 0 0 90)
			(layer "B.Fab")
			(effects
				(font
					(size 1.27 1.27)
				)
				(justify mirror)
			)
		)
		(duplicate_pad_numbers_are_jumpers no)
		(fp_line
			(start 1.524 -0.762)
			(end -1.524 -0.762)
			(stroke
				(width 0.1524)
				(type default)
			)
			(layer "B.SilkS")
		)
		(fp_line
			(start -1.524 -0.762)
			(end -1.524 0.762)
			(stroke
				(width 0.1524)
				(type default)
			)
			(layer "B.SilkS")
		)
		(fp_line
			(start 1.524 0.762)
			(end 1.524 -0.762)
			(stroke
				(width 0.1524)
				(type default)
			)
			(layer "B.SilkS")
		)
		(fp_line
			(start -1.524 0.762)
			(end 1.524 0.762)
			(stroke
				(width 0.1524)
				(type default)
			)
			(layer "B.SilkS")
		)
		(fp_line
			(start 1.1049 -0.724916)
			(end 1.1049 0.724916)
			(stroke
				(width 0.1)
				(type default)
			)
			(layer "B.Fab")
		)
		(fp_line
			(start -1.1049 -0.724916)
			(end 1.1049 -0.724916)
			(stroke
				(width 0.1)
				(type default)
			)
			(layer "B.Fab")
		)
		(fp_line
			(start 1.1049 0.724916)
			(end -1.1049 0.724916)
			(stroke
				(width 0.1)
				(type default)
			)
			(layer "B.Fab")
		)
		(fp_line
			(start -1.1049 0.724916)
			(end -1.1049 -0.724916)
			(stroke
				(width 0.1)
				(type default)
			)
			(layer "B.Fab")
		)
		(pad "1" smd rect
			(at 0.889 0 90)
			(size 1.016 1.27)
			(layers "B.Cu" "B.Mask" "B.Paste")
			(net "PVDDCR_CPU0_P0")
		)
		(pad "2" smd rect
			(at -0.889 0 90)
			(size 1.016 1.27)
			(layers "B.Cu" "B.Mask" "B.Paste")
			(net "GND")
		)
	)
	(footprint ""
		(layer "B.Cu")
		(at 255.905 -334.01 180)
		(property "Reference" "R833"
			(at 0 0 0)
			(layer "B.SilkS")
			(hide yes)
			(effects
				(font
					(size 1.27 1.27)
				)
				(justify mirror)
			)
		)
		(property "Value" ""
			(at 0 0 0)
			(layer "B.Fab")
			(effects
				(font
					(size 1.27 1.27)
				)
				(justify mirror)
			)
		)
		(duplicate_pad_numbers_are_jumpers no)
		(fp_line
			(start 0.32512 0.175006)
			(end 0.32512 -0.175006)
			(stroke
				(width 0.1)
				(type default)
			)
			(layer "B.Fab")
		)
		(fp_line
			(start 0.32512 -0.175006)
			(end -0.32512 -0.175006)
			(stroke
				(width 0.1)
				(type default)
			)
			(layer "B.Fab")
		)
		(fp_line
			(start -0.32512 0.175006)
			(end 0.32512 0.175006)
			(stroke
				(width 0.1)
				(type default)
			)
			(layer "B.Fab")
		)
		(fp_line
			(start -0.32512 -0.175006)
			(end -0.32512 0.175006)
			(stroke
				(width 0.1)
				(type default)
			)
			(layer "B.Fab")
		)
		(pad "1" smd rect
			(at 0.2667 0)
			(size 0.3048 0.381)
			(layers "B.Cu" "B.Mask" "B.Paste")
			(net "SMB_RT_CPU0_P2_ROM_MUX_2D_R_SCL")
		)
		(pad "2" smd rect
			(at -0.2667 0 180)
			(size 0.3048 0.381)
			(layers "B.Cu" "B.Mask" "B.Paste")
			(net "SMB_RT_CPU0_P2_ROM_MUX_2D_SCL")
		)
	)
	(footprint ""
		(layer "B.Cu")
		(at 361.046014 -257.744976 180)
		(property "Reference" "C3888"
			(at 0 0 0)
			(layer "B.SilkS")
			(hide yes)
			(effects
				(font
					(size 1.27 1.27)
				)
				(justify mirror)
			)
		)
		(property "Value" ""
			(at 0 0 0)
			(layer "B.Fab")
			(effects
				(font
					(size 1.27 1.27)
				)
				(justify mirror)
			)
		)
		(duplicate_pad_numbers_are_jumpers no)
		(fp_line
			(start 0.7874 0.4064)
			(end 0.7874 -0.4064)
			(stroke
				(width 0.1524)
				(type default)
			)
			(layer "B.SilkS")
		)
		(fp_line
			(start 0.7874 -0.4064)
			(end -0.7874 -0.4064)
			(stroke
				(width 0.1524)
				(type default)
			)
			(layer "B.SilkS")
		)
		(fp_line
			(start -0.7874 0.4064)
			(end 0.7874 0.4064)
			(stroke
				(width 0.1524)
				(type default)
			)
			(layer "B.SilkS")
		)
		(fp_line
			(start -0.7874 -0.4064)
			(end -0.7874 0.4064)
			(stroke
				(width 0.1524)
				(type default)
			)
			(layer "B.SilkS")
		)
		(fp_line
			(start 0.67945 0.3048)
			(end 0.67945 -0.305054)
			(stroke
				(width 0.1)
				(type default)
			)
			(layer "B.Fab")
		)
		(fp_line
			(start 0.67945 -0.305054)
			(end 0.12065 -0.305054)
			(stroke
				(width 0.1)
				(type default)
			)
			(layer "B.Fab")
		)
		(fp_line
			(start 0.12065 0.3048)
			(end 0.67945 0.3048)
			(stroke
				(width 0.1)
				(type default)
			)
			(layer "B.Fab")
		)
		(fp_line
			(start 0.12065 0.2794)
			(end 0.12065 0.3048)
			(stroke
				(width 0.1)
				(type default)
			)
			(layer "B.Fab")
		)
		(fp_line
			(start 0.12065 -0.2794)
			(end -0.12065 -0.2794)
			(stroke
				(width 0.1)
				(type default)
			)
			(layer "B.Fab")
		)
		(fp_line
			(start 0.12065 -0.305054)
			(end 0.12065 -0.2794)
			(stroke
				(width 0.1)
				(type default)
			)
			(layer "B.Fab")
		)
		(fp_line
			(start -0.120396 0.3048)
			(end -0.120396 0.2794)
			(stroke
				(width 0.1)
				(type default)
			)
			(layer "B.Fab")
		)
		(fp_line
			(start -0.120396 0.2794)
			(end 0.12065 0.2794)
			(stroke
				(width 0.1)
				(type default)
			)
			(layer "B.Fab")
		)
		(fp_line
			(start -0.12065 -0.2794)
			(end -0.12065 -0.3048)
			(stroke
				(width 0.1)
				(type default)
			)
			(layer "B.Fab")
		)
		(fp_line
			(start -0.12065 -0.3048)
			(end -0.67945 -0.3048)
			(stroke
				(width 0.1)
				(type default)
			)
			(layer "B.Fab")
		)
		(fp_line
			(start -0.67945 0.3048)
			(end -0.120396 0.3048)
			(stroke
				(width 0.1)
				(type default)
			)
			(layer "B.Fab")
		)
		(fp_line
			(start -0.67945 -0.3048)
			(end -0.67945 0.3048)
			(stroke
				(width 0.1)
				(type default)
			)
			(layer "B.Fab")
		)
		(pad "1" smd circle
			(at 0.40005 0)
			(size 0 0)
			(layers "B.Cu" "B.Mask" "B.Paste")
			(net "PVDDCR_SOC_P0")
		)
		(pad "2" smd circle
			(at -0.40005 0)
			(size 0 0)
			(layers "B.Cu" "B.Mask" "B.Paste")
			(net "GND")
		)
	)
	(footprint ""
		(layer "B.Cu")
		(at 183.54802 -423.011092 90)
		(property "Reference" "R8108"
			(at 0 0 90)
			(layer "B.SilkS")
			(hide yes)
			(effects
				(font
					(size 1.27 1.27)
				)
				(justify mirror)
			)
		)
		(property "Value" ""
			(at 0 0 90)
			(layer "B.Fab")
			(effects
				(font
					(size 1.27 1.27)
				)
				(justify mirror)
			)
		)
		(duplicate_pad_numbers_are_jumpers no)
		(fp_line
			(start 0.7874 -0.4064)
			(end -0.7874 -0.4064)
			(stroke
				(width 0.1524)
				(type default)
			)
			(layer "B.SilkS")
		)
		(fp_line
			(start -0.7874 -0.4064)
			(end -0.7874 0.4064)
			(stroke
				(width 0.1524)
				(type default)
			)
			(layer "B.SilkS")
		)
		(fp_line
			(start 0.7874 0.4064)
			(end 0.7874 -0.4064)
			(stroke
				(width 0.1524)
				(type default)
			)
			(layer "B.SilkS")
		)
		(fp_line
			(start -0.7874 0.4064)
			(end 0.7874 0.4064)
			(stroke
				(width 0.1524)
				(type default)
			)
			(layer "B.SilkS")
		)
		(fp_line
			(start 0.67945 -0.305054)
			(end 0.12065 -0.305054)
			(stroke
				(width 0.1)
				(type default)
			)
			(layer "B.Fab")
		)
		(fp_line
			(start 0.12065 -0.305054)
			(end 0.12065 -0.2794)
			(stroke
				(width 0.1)
				(type default)
			)
			(layer "B.Fab")
		)
		(fp_line
			(start -0.12065 -0.3048)
			(end -0.67945 -0.3048)
			(stroke
				(width 0.1)
				(type default)
			)
			(layer "B.Fab")
		)
		(fp_line
			(start -0.67945 -0.3048)
			(end -0.67945 0.3048)
			(stroke
				(width 0.1)
				(type default)
			)
			(layer "B.Fab")
		)
		(fp_line
			(start 0.12065 -0.2794)
			(end -0.12065 -0.2794)
			(stroke
				(width 0.1)
				(type default)
			)
			(layer "B.Fab")
		)
		(fp_line
			(start -0.12065 -0.2794)
			(end -0.12065 -0.3048)
			(stroke
				(width 0.1)
				(type default)
			)
			(layer "B.Fab")
		)
		(fp_line
			(start 0.12065 0.2794)
			(end 0.12065 0.3048)
			(stroke
				(width 0.1)
				(type default)
			)
			(layer "B.Fab")
		)
		(fp_line
			(start -0.120396 0.2794)
			(end 0.12065 0.2794)
			(stroke
				(width 0.1)
				(type default)
			)
			(layer "B.Fab")
		)
		(fp_line
			(start 0.67945 0.3048)
			(end 0.67945 -0.305054)
			(stroke
				(width 0.1)
				(type default)
			)
			(layer "B.Fab")
		)
		(fp_line
			(start 0.12065 0.3048)
			(end 0.67945 0.3048)
			(stroke
				(width 0.1)
				(type default)
			)
			(layer "B.Fab")
		)
		(fp_line
			(start -0.120396 0.3048)
			(end -0.120396 0.2794)
			(stroke
				(width 0.1)
				(type default)
			)
			(layer "B.Fab")
		)
		(fp_line
			(start -0.67945 0.3048)
			(end -0.120396 0.3048)
			(stroke
				(width 0.1)
				(type default)
			)
			(layer "B.Fab")
		)
		(pad "1" smd circle
			(at 0.40005 0 270)
			(size 0 0)
			(layers "B.Cu" "B.Mask" "B.Paste")
			(net "HSC_CSOUT")
		)
		(pad "2" smd circle
			(at -0.40005 0 270)
			(size 0 0)
			(layers "B.Cu" "B.Mask" "B.Paste")
			(net "HSC_OC_VOL")
		)
	)
	(footprint ""
		(layer "B.Cu")
		(at 335.70037 -393.88288 -90)
		(property "Reference" "C622"
			(at 0 0 90)
			(layer "B.SilkS")
			(hide yes)
			(effects
				(font
					(size 1.27 1.27)
				)
				(justify mirror)
			)
		)
		(property "Value" ""
			(at 0 0 90)
			(layer "B.Fab")
			(effects
				(font
					(size 1.27 1.27)
				)
				(justify mirror)
			)
		)
		(duplicate_pad_numbers_are_jumpers no)
		(fp_line
			(start -0.299974 0.150114)
			(end 0.299974 0.150114)
			(stroke
				(width 0.1)
				(type default)
			)
			(layer "B.Fab")
		)
		(fp_line
			(start 0.299974 0.150114)
			(end 0.299974 -0.150114)
			(stroke
				(width 0.1)
				(type default)
			)
			(layer "B.Fab")
		)
		(fp_line
			(start -0.299974 -0.150114)
			(end -0.299974 0.150114)
			(stroke
				(width 0.1)
				(type default)
			)
			(layer "B.Fab")
		)
		(fp_line
			(start 0.299974 -0.150114)
			(end -0.299974 -0.150114)
			(stroke
				(width 0.1)
				(type default)
			)
			(layer "B.Fab")
		)
		(pad "1" smd rect
			(at 0.2667 0 90)
			(size 0.3048 0.381)
			(layers "B.Cu" "B.Mask" "B.Paste")
			(net "P0V9_CPU0_RT1_2A")
		)
		(pad "2" smd rect
			(at -0.2667 0 90)
			(size 0.3048 0.381)
			(layers "B.Cu" "B.Mask" "B.Paste")
			(net "GND")
		)
	)
	(footprint ""
		(layer "B.Cu")
		(at 121.685812 -257.930396)
		(property "Reference" "C3914"
			(at 0 0 0)
			(layer "B.SilkS")
			(hide yes)
			(effects
				(font
					(size 1.27 1.27)
				)
				(justify mirror)
			)
		)
		(property "Value" ""
			(at 0 0 0)
			(layer "B.Fab")
			(effects
				(font
					(size 1.27 1.27)
				)
				(justify mirror)
			)
		)
		(duplicate_pad_numbers_are_jumpers no)
		(fp_line
			(start -0.7874 -0.4064)
			(end -0.7874 0.4064)
			(stroke
				(width 0.1524)
				(type default)
			)
			(layer "B.SilkS")
		)
		(fp_line
			(start -0.7874 0.4064)
			(end 0.7874 0.4064)
			(stroke
				(width 0.1524)
				(type default)
			)
			(layer "B.SilkS")
		)
		(fp_line
			(start 0.7874 -0.4064)
			(end -0.7874 -0.4064)
			(stroke
				(width 0.1524)
				(type default)
			)
			(layer "B.SilkS")
		)
		(fp_line
			(start 0.7874 0.4064)
			(end 0.7874 -0.4064)
			(stroke
				(width 0.1524)
				(type default)
			)
			(layer "B.SilkS")
		)
		(fp_line
			(start -0.67945 -0.3048)
			(end -0.67945 0.3048)
			(stroke
				(width 0.1)
				(type default)
			)
			(layer "B.Fab")
		)
		(fp_line
			(start -0.67945 0.3048)
			(end -0.120396 0.3048)
			(stroke
				(width 0.1)
				(type default)
			)
			(layer "B.Fab")
		)
		(fp_line
			(start -0.12065 -0.3048)
			(end -0.67945 -0.3048)
			(stroke
				(width 0.1)
				(type default)
			)
			(layer "B.Fab")
		)
		(fp_line
			(start -0.12065 -0.2794)
			(end -0.12065 -0.3048)
			(stroke
				(width 0.1)
				(type default)
			)
			(layer "B.Fab")
		)
		(fp_line
			(start -0.120396 0.2794)
			(end 0.12065 0.2794)
			(stroke
				(width 0.1)
				(type default)
			)
			(layer "B.Fab")
		)
		(fp_line
			(start -0.120396 0.3048)
			(end -0.120396 0.2794)
			(stroke
				(width 0.1)
				(type default)
			)
			(layer "B.Fab")
		)
		(fp_line
			(start 0.12065 -0.305054)
			(end 0.12065 -0.2794)
			(stroke
				(width 0.1)
				(type default)
			)
			(layer "B.Fab")
		)
		(fp_line
			(start 0.12065 -0.2794)
			(end -0.12065 -0.2794)
			(stroke
				(width 0.1)
				(type default)
			)
			(layer "B.Fab")
		)
		(fp_line
			(start 0.12065 0.2794)
			(end 0.12065 0.3048)
			(stroke
				(width 0.1)
				(type default)
			)
			(layer "B.Fab")
		)
		(fp_line
			(start 0.12065 0.3048)
			(end 0.67945 0.3048)
			(stroke
				(width 0.1)
				(type default)
			)
			(layer "B.Fab")
		)
		(fp_line
			(start 0.67945 -0.305054)
			(end 0.12065 -0.305054)
			(stroke
				(width 0.1)
				(type default)
			)
			(layer "B.Fab")
		)
		(fp_line
			(start 0.67945 0.3048)
			(end 0.67945 -0.305054)
			(stroke
				(width 0.1)
				(type default)
			)
			(layer "B.Fab")
		)
		(pad "1" smd circle
			(at 0.40005 0 180)
			(size 0 0)
			(layers "B.Cu" "B.Mask" "B.Paste")
			(net "PVDDCR_SOC_P1")
		)
		(pad "2" smd circle
			(at -0.40005 0 180)
			(size 0 0)
			(layers "B.Cu" "B.Mask" "B.Paste")
			(net "GND")
		)
	)
	(footprint ""
		(layer "B.Cu")
		(at 401.485608 -174.505874 90)
		(property "Reference" "PR362"
			(at 0 0 90)
			(layer "B.SilkS")
			(hide yes)
			(effects
				(font
					(size 1.27 1.27)
				)
				(justify mirror)
			)
		)
		(property "Value" ""
			(at 0 0 90)
			(layer "B.Fab")
			(effects
				(font
					(size 1.27 1.27)
				)
				(justify mirror)
			)
		)
		(duplicate_pad_numbers_are_jumpers no)
		(fp_line
			(start 0.7874 -0.4064)
			(end -0.7874 -0.4064)
			(stroke
				(width 0.1524)
				(type default)
			)
			(layer "B.SilkS")
		)
		(fp_line
			(start -0.7874 -0.4064)
			(end -0.7874 0.4064)
			(stroke
				(width 0.1524)
				(type default)
			)
			(layer "B.SilkS")
		)
		(fp_line
			(start 0.7874 0.4064)
			(end 0.7874 -0.4064)
			(stroke
				(width 0.1524)
				(type default)
			)
			(layer "B.SilkS")
		)
		(fp_line
			(start -0.7874 0.4064)
			(end 0.7874 0.4064)
			(stroke
				(width 0.1524)
				(type default)
			)
			(layer "B.SilkS")
		)
		(fp_line
			(start 0.67945 -0.305054)
			(end 0.12065 -0.305054)
			(stroke
				(width 0.1)
				(type default)
			)
			(layer "B.Fab")
		)
		(fp_line
			(start 0.12065 -0.305054)
			(end 0.12065 -0.2794)
			(stroke
				(width 0.1)
				(type default)
			)
			(layer "B.Fab")
		)
		(fp_line
			(start -0.12065 -0.3048)
			(end -0.67945 -0.3048)
			(stroke
				(width 0.1)
				(type default)
			)
			(layer "B.Fab")
		)
		(fp_line
			(start -0.67945 -0.3048)
			(end -0.67945 0.3048)
			(stroke
				(width 0.1)
				(type default)
			)
			(layer "B.Fab")
		)
		(fp_line
			(start 0.12065 -0.2794)
			(end -0.12065 -0.2794)
			(stroke
				(width 0.1)
				(type default)
			)
			(layer "B.Fab")
		)
		(fp_line
			(start -0.12065 -0.2794)
			(end -0.12065 -0.3048)
			(stroke
				(width 0.1)
				(type default)
			)
			(layer "B.Fab")
		)
		(fp_line
			(start 0.12065 0.2794)
			(end 0.12065 0.3048)
			(stroke
				(width 0.1)
				(type default)
			)
			(layer "B.Fab")
		)
		(fp_line
			(start -0.120396 0.2794)
			(end 0.12065 0.2794)
			(stroke
				(width 0.1)
				(type default)
			)
			(layer "B.Fab")
		)
		(fp_line
			(start 0.67945 0.3048)
			(end 0.67945 -0.305054)
			(stroke
				(width 0.1)
				(type default)
			)
			(layer "B.Fab")
		)
		(fp_line
			(start 0.12065 0.3048)
			(end 0.67945 0.3048)
			(stroke
				(width 0.1)
				(type default)
			)
			(layer "B.Fab")
		)
		(fp_line
			(start -0.120396 0.3048)
			(end -0.120396 0.2794)
			(stroke
				(width 0.1)
				(type default)
			)
			(layer "B.Fab")
		)
		(fp_line
			(start -0.67945 0.3048)
			(end -0.120396 0.3048)
			(stroke
				(width 0.1)
				(type default)
			)
			(layer "B.Fab")
		)
		(pad "1" smd circle
			(at 0.40005 0 270)
			(size 0 0)
			(layers "B.Cu" "B.Mask" "B.Paste")
			(net "PVDDCR_SOC_P0_VOS1")
		)
		(pad "2" smd circle
			(at -0.40005 0 270)
			(size 0 0)
			(layers "B.Cu" "B.Mask" "B.Paste")
			(net "PVDDCR_SOC_P0")
		)
	)
	(footprint ""
		(layer "B.Cu")
		(at 20.743418 -409.04287 90)
		(property "Reference" "PR6812"
			(at 0 0 90)
			(layer "B.SilkS")
			(hide yes)
			(effects
				(font
					(size 1.27 1.27)
				)
				(justify mirror)
			)
		)
		(property "Value" ""
			(at 0 0 90)
			(layer "B.Fab")
			(effects
				(font
					(size 1.27 1.27)
				)
				(justify mirror)
			)
		)
		(duplicate_pad_numbers_are_jumpers no)
		(fp_line
			(start 0.7874 -0.4064)
			(end -0.7874 -0.4064)
			(stroke
				(width 0.1524)
				(type default)
			)
			(layer "B.SilkS")
		)
		(fp_line
			(start -0.7874 -0.4064)
			(end -0.7874 0.4064)
			(stroke
				(width 0.1524)
				(type default)
			)
			(layer "B.SilkS")
		)
		(fp_line
			(start 0.7874 0.4064)
			(end 0.7874 -0.4064)
			(stroke
				(width 0.1524)
				(type default)
			)
			(layer "B.SilkS")
		)
		(fp_line
			(start -0.7874 0.4064)
			(end 0.7874 0.4064)
			(stroke
				(width 0.1524)
				(type default)
			)
			(layer "B.SilkS")
		)
		(fp_line
			(start 0.67945 -0.305054)
			(end 0.12065 -0.305054)
			(stroke
				(width 0.1)
				(type default)
			)
			(layer "B.Fab")
		)
		(fp_line
			(start 0.12065 -0.305054)
			(end 0.12065 -0.2794)
			(stroke
				(width 0.1)
				(type default)
			)
			(layer "B.Fab")
		)
		(fp_line
			(start -0.12065 -0.3048)
			(end -0.67945 -0.3048)
			(stroke
				(width 0.1)
				(type default)
			)
			(layer "B.Fab")
		)
		(fp_line
			(start -0.67945 -0.3048)
			(end -0.67945 0.3048)
			(stroke
				(width 0.1)
				(type default)
			)
			(layer "B.Fab")
		)
		(fp_line
			(start 0.12065 -0.2794)
			(end -0.12065 -0.2794)
			(stroke
				(width 0.1)
				(type default)
			)
			(layer "B.Fab")
		)
		(fp_line
			(start -0.12065 -0.2794)
			(end -0.12065 -0.3048)
			(stroke
				(width 0.1)
				(type default)
			)
			(layer "B.Fab")
		)
		(fp_line
			(start 0.12065 0.2794)
			(end 0.12065 0.3048)
			(stroke
				(width 0.1)
				(type default)
			)
			(layer "B.Fab")
		)
		(fp_line
			(start -0.120396 0.2794)
			(end 0.12065 0.2794)
			(stroke
				(width 0.1)
				(type default)
			)
			(layer "B.Fab")
		)
		(fp_line
			(start 0.67945 0.3048)
			(end 0.67945 -0.305054)
			(stroke
				(width 0.1)
				(type default)
			)
			(layer "B.Fab")
		)
		(fp_line
			(start 0.12065 0.3048)
			(end 0.67945 0.3048)
			(stroke
				(width 0.1)
				(type default)
			)
			(layer "B.Fab")
		)
		(fp_line
			(start -0.120396 0.3048)
			(end -0.120396 0.2794)
			(stroke
				(width 0.1)
				(type default)
			)
			(layer "B.Fab")
		)
		(fp_line
			(start -0.67945 0.3048)
			(end -0.120396 0.3048)
			(stroke
				(width 0.1)
				(type default)
			)
			(layer "B.Fab")
		)
		(pad "1" smd circle
			(at 0.40005 0 270)
			(size 0 0)
			(layers "B.Cu" "B.Mask" "B.Paste")
			(net "P3V3_AUX")
		)
		(pad "2" smd circle
			(at -0.40005 0 270)
			(size 0 0)
			(layers "B.Cu" "B.Mask" "B.Paste")
			(net "TP_P0V9_RETIMER_CPU1_VRHOT")
		)
	)
	(footprint ""
		(layer "B.Cu")
		(at 108.355892 -259.845302 180)
		(property "Reference" "C2477"
			(at 0 0 0)
			(layer "B.SilkS")
			(hide yes)
			(effects
				(font
					(size 1.27 1.27)
				)
				(justify mirror)
			)
		)
		(property "Value" ""
			(at 0 0 0)
			(layer "B.Fab")
			(effects
				(font
					(size 1.27 1.27)
				)
				(justify mirror)
			)
		)
		(duplicate_pad_numbers_are_jumpers no)
		(fp_line
			(start 0.7874 0.4064)
			(end 0.7874 -0.4064)
			(stroke
				(width 0.1524)
				(type default)
			)
			(layer "B.SilkS")
		)
		(fp_line
			(start 0.7874 -0.4064)
			(end -0.7874 -0.4064)
			(stroke
				(width 0.1524)
				(type default)
			)
			(layer "B.SilkS")
		)
		(fp_line
			(start -0.7874 0.4064)
			(end 0.7874 0.4064)
			(stroke
				(width 0.1524)
				(type default)
			)
			(layer "B.SilkS")
		)
		(fp_line
			(start -0.7874 -0.4064)
			(end -0.7874 0.4064)
			(stroke
				(width 0.1524)
				(type default)
			)
			(layer "B.SilkS")
		)
		(fp_line
			(start 0.67945 0.3048)
			(end 0.67945 -0.305054)
			(stroke
				(width 0.1)
				(type default)
			)
			(layer "B.Fab")
		)
		(fp_line
			(start 0.67945 -0.305054)
			(end 0.12065 -0.305054)
			(stroke
				(width 0.1)
				(type default)
			)
			(layer "B.Fab")
		)
		(fp_line
			(start 0.12065 0.3048)
			(end 0.67945 0.3048)
			(stroke
				(width 0.1)
				(type default)
			)
			(layer "B.Fab")
		)
		(fp_line
			(start 0.12065 0.2794)
			(end 0.12065 0.3048)
			(stroke
				(width 0.1)
				(type default)
			)
			(layer "B.Fab")
		)
		(fp_line
			(start 0.12065 -0.2794)
			(end -0.12065 -0.2794)
			(stroke
				(width 0.1)
				(type default)
			)
			(layer "B.Fab")
		)
		(fp_line
			(start 0.12065 -0.305054)
			(end 0.12065 -0.2794)
			(stroke
				(width 0.1)
				(type default)
			)
			(layer "B.Fab")
		)
		(fp_line
			(start -0.120396 0.3048)
			(end -0.120396 0.2794)
			(stroke
				(width 0.1)
				(type default)
			)
			(layer "B.Fab")
		)
		(fp_line
			(start -0.120396 0.2794)
			(end 0.12065 0.2794)
			(stroke
				(width 0.1)
				(type default)
			)
			(layer "B.Fab")
		)
		(fp_line
			(start -0.12065 -0.2794)
			(end -0.12065 -0.3048)
			(stroke
				(width 0.1)
				(type default)
			)
			(layer "B.Fab")
		)
		(fp_line
			(start -0.12065 -0.3048)
			(end -0.67945 -0.3048)
			(stroke
				(width 0.1)
				(type default)
			)
			(layer "B.Fab")
		)
		(fp_line
			(start -0.67945 0.3048)
			(end -0.120396 0.3048)
			(stroke
				(width 0.1)
				(type default)
			)
			(layer "B.Fab")
		)
		(fp_line
			(start -0.67945 -0.3048)
			(end -0.67945 0.3048)
			(stroke
				(width 0.1)
				(type default)
			)
			(layer "B.Fab")
		)
		(pad "1" smd circle
			(at 0.40005 0)
			(size 0 0)
			(layers "B.Cu" "B.Mask" "B.Paste")
			(net "PVDDIO_P1")
		)
		(pad "2" smd circle
			(at -0.40005 0)
			(size 0 0)
			(layers "B.Cu" "B.Mask" "B.Paste")
			(net "GND")
		)
	)
	(footprint ""
		(layer "B.Cu")
		(at 88.177878 -148.94941)
		(property "Reference" "R8153"
			(at 0 0 0)
			(layer "B.SilkS")
			(hide yes)
			(effects
				(font
					(size 1.27 1.27)
				)
				(justify mirror)
			)
		)
		(property "Value" ""
			(at 0 0 0)
			(layer "B.Fab")
			(effects
				(font
					(size 1.27 1.27)
				)
				(justify mirror)
			)
		)
		(duplicate_pad_numbers_are_jumpers no)
		(fp_line
			(start -0.7874 -0.4064)
			(end -0.7874 0.4064)
			(stroke
				(width 0.1524)
				(type default)
			)
			(layer "B.SilkS")
		)
		(fp_line
			(start -0.7874 0.4064)
			(end 0.7874 0.4064)
			(stroke
				(width 0.1524)
				(type default)
			)
			(layer "B.SilkS")
		)
		(fp_line
			(start 0.7874 -0.4064)
			(end -0.7874 -0.4064)
			(stroke
				(width 0.1524)
				(type default)
			)
			(layer "B.SilkS")
		)
		(fp_line
			(start 0.7874 0.4064)
			(end 0.7874 -0.4064)
			(stroke
				(width 0.1524)
				(type default)
			)
			(layer "B.SilkS")
		)
		(fp_line
			(start -0.67945 -0.3048)
			(end -0.67945 0.3048)
			(stroke
				(width 0.1)
				(type default)
			)
			(layer "B.Fab")
		)
		(fp_line
			(start -0.67945 0.3048)
			(end -0.120396 0.3048)
			(stroke
				(width 0.1)
				(type default)
			)
			(layer "B.Fab")
		)
		(fp_line
			(start -0.12065 -0.3048)
			(end -0.67945 -0.3048)
			(stroke
				(width 0.1)
				(type default)
			)
			(layer "B.Fab")
		)
		(fp_line
			(start -0.12065 -0.2794)
			(end -0.12065 -0.3048)
			(stroke
				(width 0.1)
				(type default)
			)
			(layer "B.Fab")
		)
		(fp_line
			(start -0.120396 0.2794)
			(end 0.12065 0.2794)
			(stroke
				(width 0.1)
				(type default)
			)
			(layer "B.Fab")
		)
		(fp_line
			(start -0.120396 0.3048)
			(end -0.120396 0.2794)
			(stroke
				(width 0.1)
				(type default)
			)
			(layer "B.Fab")
		)
		(fp_line
			(start 0.12065 -0.305054)
			(end 0.12065 -0.2794)
			(stroke
				(width 0.1)
				(type default)
			)
			(layer "B.Fab")
		)
		(fp_line
			(start 0.12065 -0.2794)
			(end -0.12065 -0.2794)
			(stroke
				(width 0.1)
				(type default)
			)
			(layer "B.Fab")
		)
		(fp_line
			(start 0.12065 0.2794)
			(end 0.12065 0.3048)
			(stroke
				(width 0.1)
				(type default)
			)
			(layer "B.Fab")
		)
		(fp_line
			(start 0.12065 0.3048)
			(end 0.67945 0.3048)
			(stroke
				(width 0.1)
				(type default)
			)
			(layer "B.Fab")
		)
		(fp_line
			(start 0.67945 -0.305054)
			(end 0.12065 -0.305054)
			(stroke
				(width 0.1)
				(type default)
			)
			(layer "B.Fab")
		)
		(fp_line
			(start 0.67945 0.3048)
			(end 0.67945 -0.305054)
			(stroke
				(width 0.1)
				(type default)
			)
			(layer "B.Fab")
		)
		(pad "1" smd circle
			(at 0.40005 0 180)
			(size 0 0)
			(layers "B.Cu" "B.Mask" "B.Paste")
			(net "SVID_PVDDCR_CPU0_P1_SVTO")
		)
		(pad "2" smd circle
			(at -0.40005 0 180)
			(size 0 0)
			(layers "B.Cu" "B.Mask" "B.Paste")
			(net "GND")
		)
	)
	(footprint ""
		(layer "B.Cu")
		(at 280.855928 -338.005928 -90)
		(property "Reference" "PC192_3"
			(at 0 0 90)
			(layer "B.SilkS")
			(hide yes)
			(effects
				(font
					(size 1.27 1.27)
				)
				(justify mirror)
			)
		)
		(property "Value" ""
			(at 0 0 90)
			(layer "B.Fab")
			(effects
				(font
					(size 1.27 1.27)
				)
				(justify mirror)
			)
		)
		(duplicate_pad_numbers_are_jumpers no)
		(fp_line
			(start -1.524 0.762)
			(end 1.524 0.762)
			(stroke
				(width 0.1524)
				(type default)
			)
			(layer "B.SilkS")
		)
		(fp_line
			(start 1.524 0.762)
			(end 1.524 -0.762)
			(stroke
				(width 0.1524)
				(type default)
			)
			(layer "B.SilkS")
		)
		(fp_line
			(start -1.524 -0.762)
			(end -1.524 0.762)
			(stroke
				(width 0.1524)
				(type default)
			)
			(layer "B.SilkS")
		)
		(fp_line
			(start 1.524 -0.762)
			(end -1.524 -0.762)
			(stroke
				(width 0.1524)
				(type default)
			)
			(layer "B.SilkS")
		)
		(fp_line
			(start -1.1049 0.724916)
			(end -1.1049 -0.724916)
			(stroke
				(width 0.1)
				(type default)
			)
			(layer "B.Fab")
		)
		(fp_line
			(start 1.1049 0.724916)
			(end -1.1049 0.724916)
			(stroke
				(width 0.1)
				(type default)
			)
			(layer "B.Fab")
		)
		(fp_line
			(start -1.1049 -0.724916)
			(end 1.1049 -0.724916)
			(stroke
				(width 0.1)
				(type default)
			)
			(layer "B.Fab")
		)
		(fp_line
			(start 1.1049 -0.724916)
			(end 1.1049 0.724916)
			(stroke
				(width 0.1)
				(type default)
			)
			(layer "B.Fab")
		)
		(pad "1" smd rect
			(at 0.889 0 270)
			(size 1.016 1.27)
			(layers "B.Cu" "B.Mask" "B.Paste")
			(net "PVDDIO_P0")
		)
		(pad "2" smd rect
			(at -0.889 0 270)
			(size 1.016 1.27)
			(layers "B.Cu" "B.Mask" "B.Paste")
			(net "GND")
		)
	)
	(footprint ""
		(layer "B.Cu")
		(at 289.891216 -337.984846 -90)
		(property "Reference" "PC170_2"
			(at 0 0 90)
			(layer "B.SilkS")
			(hide yes)
			(effects
				(font
					(size 1.27 1.27)
				)
				(justify mirror)
			)
		)
		(property "Value" ""
			(at 0 0 90)
			(layer "B.Fab")
			(effects
				(font
					(size 1.27 1.27)
				)
				(justify mirror)
			)
		)
		(duplicate_pad_numbers_are_jumpers no)
		(fp_line
			(start -1.524 0.762)
			(end 1.524 0.762)
			(stroke
				(width 0.1524)
				(type default)
			)
			(layer "B.SilkS")
		)
		(fp_line
			(start 1.524 0.762)
			(end 1.524 -0.762)
			(stroke
				(width 0.1524)
				(type default)
			)
			(layer "B.SilkS")
		)
		(fp_line
			(start -1.524 -0.762)
			(end -1.524 0.762)
			(stroke
				(width 0.1524)
				(type default)
			)
			(layer "B.SilkS")
		)
		(fp_line
			(start 1.524 -0.762)
			(end -1.524 -0.762)
			(stroke
				(width 0.1524)
				(type default)
			)
			(layer "B.SilkS")
		)
		(fp_line
			(start -1.1049 0.724916)
			(end -1.1049 -0.724916)
			(stroke
				(width 0.1)
				(type default)
			)
			(layer "B.Fab")
		)
		(fp_line
			(start 1.1049 0.724916)
			(end -1.1049 0.724916)
			(stroke
				(width 0.1)
				(type default)
			)
			(layer "B.Fab")
		)
		(fp_line
			(start -1.1049 -0.724916)
			(end 1.1049 -0.724916)
			(stroke
				(width 0.1)
				(type default)
			)
			(layer "B.Fab")
		)
		(fp_line
			(start 1.1049 -0.724916)
			(end 1.1049 0.724916)
			(stroke
				(width 0.1)
				(type default)
			)
			(layer "B.Fab")
		)
		(pad "1" smd rect
			(at 0.889 0 270)
			(size 1.016 1.27)
			(layers "B.Cu" "B.Mask" "B.Paste")
			(net "PVDDIO_P0")
		)
		(pad "2" smd rect
			(at -0.889 0 270)
			(size 1.016 1.27)
			(layers "B.Cu" "B.Mask" "B.Paste")
			(net "GND")
		)
	)
	(footprint ""
		(layer "B.Cu")
		(at 164.363908 -113.013744)
		(property "Reference" "R6145"
			(at 0 0 0)
			(layer "B.SilkS")
			(hide yes)
			(effects
				(font
					(size 1.27 1.27)
				)
				(justify mirror)
			)
		)
		(property "Value" ""
			(at 0 0 0)
			(layer "B.Fab")
			(effects
				(font
					(size 1.27 1.27)
				)
				(justify mirror)
			)
		)
		(duplicate_pad_numbers_are_jumpers no)
		(fp_line
			(start -0.7874 -0.4064)
			(end -0.7874 0.4064)
			(stroke
				(width 0.1524)
				(type default)
			)
			(layer "B.SilkS")
		)
		(fp_line
			(start -0.7874 0.4064)
			(end 0.7874 0.4064)
			(stroke
				(width 0.1524)
				(type default)
			)
			(layer "B.SilkS")
		)
		(fp_line
			(start 0.7874 -0.4064)
			(end -0.7874 -0.4064)
			(stroke
				(width 0.1524)
				(type default)
			)
			(layer "B.SilkS")
		)
		(fp_line
			(start 0.7874 0.4064)
			(end 0.7874 -0.4064)
			(stroke
				(width 0.1524)
				(type default)
			)
			(layer "B.SilkS")
		)
		(fp_line
			(start -0.67945 -0.3048)
			(end -0.67945 0.3048)
			(stroke
				(width 0.1)
				(type default)
			)
			(layer "B.Fab")
		)
		(fp_line
			(start -0.67945 0.3048)
			(end -0.120396 0.3048)
			(stroke
				(width 0.1)
				(type default)
			)
			(layer "B.Fab")
		)
		(fp_line
			(start -0.12065 -0.3048)
			(end -0.67945 -0.3048)
			(stroke
				(width 0.1)
				(type default)
			)
			(layer "B.Fab")
		)
		(fp_line
			(start -0.12065 -0.2794)
			(end -0.12065 -0.3048)
			(stroke
				(width 0.1)
				(type default)
			)
			(layer "B.Fab")
		)
		(fp_line
			(start -0.120396 0.2794)
			(end 0.12065 0.2794)
			(stroke
				(width 0.1)
				(type default)
			)
			(layer "B.Fab")
		)
		(fp_line
			(start -0.120396 0.3048)
			(end -0.120396 0.2794)
			(stroke
				(width 0.1)
				(type default)
			)
			(layer "B.Fab")
		)
		(fp_line
			(start 0.12065 -0.305054)
			(end 0.12065 -0.2794)
			(stroke
				(width 0.1)
				(type default)
			)
			(layer "B.Fab")
		)
		(fp_line
			(start 0.12065 -0.2794)
			(end -0.12065 -0.2794)
			(stroke
				(width 0.1)
				(type default)
			)
			(layer "B.Fab")
		)
		(fp_line
			(start 0.12065 0.2794)
			(end 0.12065 0.3048)
			(stroke
				(width 0.1)
				(type default)
			)
			(layer "B.Fab")
		)
		(fp_line
			(start 0.12065 0.3048)
			(end 0.67945 0.3048)
			(stroke
				(width 0.1)
				(type default)
			)
			(layer "B.Fab")
		)
		(fp_line
			(start 0.67945 -0.305054)
			(end 0.12065 -0.305054)
			(stroke
				(width 0.1)
				(type default)
			)
			(layer "B.Fab")
		)
		(fp_line
			(start 0.67945 0.3048)
			(end 0.67945 -0.305054)
			(stroke
				(width 0.1)
				(type default)
			)
			(layer "B.Fab")
		)
		(pad "1" smd circle
			(at 0.40005 0 180)
			(size 0 0)
			(layers "B.Cu" "B.Mask" "B.Paste")
			(net "FM_BOARD_BMC_SKU_ID0")
		)
		(pad "2" smd circle
			(at -0.40005 0 180)
			(size 0 0)
			(layers "B.Cu" "B.Mask" "B.Paste")
			(net "GND")
		)
	)
	(footprint ""
		(layer "B.Cu")
		(at 40.240204 -192.66027 180)
		(property "Reference" "C178"
			(at 0 0 0)
			(layer "B.SilkS")
			(hide yes)
			(effects
				(font
					(size 1.27 1.27)
				)
				(justify mirror)
			)
		)
		(property "Value" ""
			(at 0 0 0)
			(layer "B.Fab")
			(effects
				(font
					(size 1.27 1.27)
				)
				(justify mirror)
			)
		)
		(duplicate_pad_numbers_are_jumpers no)
		(fp_line
			(start 1.524 0.762)
			(end 1.524 -0.762)
			(stroke
				(width 0.1524)
				(type default)
			)
			(layer "B.SilkS")
		)
		(fp_line
			(start 1.524 -0.762)
			(end -1.524 -0.762)
			(stroke
				(width 0.1524)
				(type default)
			)
			(layer "B.SilkS")
		)
		(fp_line
			(start -1.524 0.762)
			(end 1.524 0.762)
			(stroke
				(width 0.1524)
				(type default)
			)
			(layer "B.SilkS")
		)
		(fp_line
			(start -1.524 -0.762)
			(end -1.524 0.762)
			(stroke
				(width 0.1524)
				(type default)
			)
			(layer "B.SilkS")
		)
		(fp_line
			(start 1.1049 0.724916)
			(end -1.1049 0.724916)
			(stroke
				(width 0.1)
				(type default)
			)
			(layer "B.Fab")
		)
		(fp_line
			(start 1.1049 -0.724916)
			(end 1.1049 0.724916)
			(stroke
				(width 0.1)
				(type default)
			)
			(layer "B.Fab")
		)
		(fp_line
			(start -1.1049 0.724916)
			(end -1.1049 -0.724916)
			(stroke
				(width 0.1)
				(type default)
			)
			(layer "B.Fab")
		)
		(fp_line
			(start -1.1049 -0.724916)
			(end 1.1049 -0.724916)
			(stroke
				(width 0.1)
				(type default)
			)
			(layer "B.Fab")
		)
		(pad "1" smd rect
			(at 0.889 0 180)
			(size 1.016 1.27)
			(layers "B.Cu" "B.Mask" "B.Paste")
			(net "P12V_MEM_CPU1")
		)
		(pad "2" smd rect
			(at -0.889 0 180)
			(size 1.016 1.27)
			(layers "B.Cu" "B.Mask" "B.Paste")
			(net "GND")
		)
	)
	(footprint ""
		(layer "B.Cu")
		(at 103.173276 -387.084062 -90)
		(property "Reference" "C102"
			(at 0 0 90)
			(layer "B.SilkS")
			(hide yes)
			(effects
				(font
					(size 1.27 1.27)
				)
				(justify mirror)
			)
		)
		(property "Value" ""
			(at 0 0 90)
			(layer "B.Fab")
			(effects
				(font
					(size 1.27 1.27)
				)
				(justify mirror)
			)
		)
		(duplicate_pad_numbers_are_jumpers no)
		(fp_line
			(start -1.524 0.762)
			(end 1.524 0.762)
			(stroke
				(width 0.1524)
				(type default)
			)
			(layer "B.SilkS")
		)
		(fp_line
			(start 1.524 0.762)
			(end 1.524 -0.762)
			(stroke
				(width 0.1524)
				(type default)
			)
			(layer "B.SilkS")
		)
		(fp_line
			(start -1.524 -0.762)
			(end -1.524 0.762)
			(stroke
				(width 0.1524)
				(type default)
			)
			(layer "B.SilkS")
		)
		(fp_line
			(start 1.524 -0.762)
			(end -1.524 -0.762)
			(stroke
				(width 0.1524)
				(type default)
			)
			(layer "B.SilkS")
		)
		(fp_line
			(start -1.1049 0.724916)
			(end -1.1049 -0.724916)
			(stroke
				(width 0.1)
				(type default)
			)
			(layer "B.Fab")
		)
		(fp_line
			(start 1.1049 0.724916)
			(end -1.1049 0.724916)
			(stroke
				(width 0.1)
				(type default)
			)
			(layer "B.Fab")
		)
		(fp_line
			(start -1.1049 -0.724916)
			(end 1.1049 -0.724916)
			(stroke
				(width 0.1)
				(type default)
			)
			(layer "B.Fab")
		)
		(fp_line
			(start 1.1049 -0.724916)
			(end 1.1049 0.724916)
			(stroke
				(width 0.1)
				(type default)
			)
			(layer "B.Fab")
		)
		(pad "1" smd rect
			(at 0.889 0 270)
			(size 1.016 1.27)
			(layers "B.Cu" "B.Mask" "B.Paste")
			(net "P1V8_CPU1_RT_1D")
		)
		(pad "2" smd rect
			(at -0.889 0 270)
			(size 1.016 1.27)
			(layers "B.Cu" "B.Mask" "B.Paste")
			(net "GND")
		)
	)
	(footprint ""
		(layer "B.Cu")
		(at 54.665118 -350.660716 -90)
		(property "Reference" "PC442_1"
			(at 0 0 90)
			(layer "B.SilkS")
			(hide yes)
			(effects
				(font
					(size 1.27 1.27)
				)
				(justify mirror)
			)
		)
		(property "Value" ""
			(at 0 0 90)
			(layer "B.Fab")
			(effects
				(font
					(size 1.27 1.27)
				)
				(justify mirror)
			)
		)
		(duplicate_pad_numbers_are_jumpers no)
		(fp_line
			(start -1.524 0.762)
			(end 1.524 0.762)
			(stroke
				(width 0.1524)
				(type default)
			)
			(layer "B.SilkS")
		)
		(fp_line
			(start 1.524 0.762)
			(end 1.524 -0.762)
			(stroke
				(width 0.1524)
				(type default)
			)
			(layer "B.SilkS")
		)
		(fp_line
			(start -1.524 -0.762)
			(end -1.524 0.762)
			(stroke
				(width 0.1524)
				(type default)
			)
			(layer "B.SilkS")
		)
		(fp_line
			(start 1.524 -0.762)
			(end -1.524 -0.762)
			(stroke
				(width 0.1524)
				(type default)
			)
			(layer "B.SilkS")
		)
		(fp_line
			(start -1.1049 0.724916)
			(end -1.1049 -0.724916)
			(stroke
				(width 0.1)
				(type default)
			)
			(layer "B.Fab")
		)
		(fp_line
			(start 1.1049 0.724916)
			(end -1.1049 0.724916)
			(stroke
				(width 0.1)
				(type default)
			)
			(layer "B.Fab")
		)
		(fp_line
			(start -1.1049 -0.724916)
			(end 1.1049 -0.724916)
			(stroke
				(width 0.1)
				(type default)
			)
			(layer "B.Fab")
		)
		(fp_line
			(start 1.1049 -0.724916)
			(end 1.1049 0.724916)
			(stroke
				(width 0.1)
				(type default)
			)
			(layer "B.Fab")
		)
		(pad "1" smd rect
			(at 0.889 0 270)
			(size 1.016 1.27)
			(layers "B.Cu" "B.Mask" "B.Paste")
			(net "SW_P12V_AUX_PVDDIO_P1_FLT")
		)
		(pad "2" smd rect
			(at -0.889 0 270)
			(size 1.016 1.27)
			(layers "B.Cu" "B.Mask" "B.Paste")
			(net "GND")
		)
	)
	(footprint ""
		(layer "B.Cu")
		(at 24.890476 -337.985354 -90)
		(property "Reference" "PC634_4"
			(at 0 0 90)
			(layer "B.SilkS")
			(hide yes)
			(effects
				(font
					(size 1.27 1.27)
				)
				(justify mirror)
			)
		)
		(property "Value" ""
			(at 0 0 90)
			(layer "B.Fab")
			(effects
				(font
					(size 1.27 1.27)
				)
				(justify mirror)
			)
		)
		(duplicate_pad_numbers_are_jumpers no)
		(fp_line
			(start -1.524 0.762)
			(end 1.524 0.762)
			(stroke
				(width 0.1524)
				(type default)
			)
			(layer "B.SilkS")
		)
		(fp_line
			(start 1.524 0.762)
			(end 1.524 -0.762)
			(stroke
				(width 0.1524)
				(type default)
			)
			(layer "B.SilkS")
		)
		(fp_line
			(start -1.524 -0.762)
			(end -1.524 0.762)
			(stroke
				(width 0.1524)
				(type default)
			)
			(layer "B.SilkS")
		)
		(fp_line
			(start 1.524 -0.762)
			(end -1.524 -0.762)
			(stroke
				(width 0.1524)
				(type default)
			)
			(layer "B.SilkS")
		)
		(fp_line
			(start -1.1049 0.724916)
			(end -1.1049 -0.724916)
			(stroke
				(width 0.1)
				(type default)
			)
			(layer "B.Fab")
		)
		(fp_line
			(start 1.1049 0.724916)
			(end -1.1049 0.724916)
			(stroke
				(width 0.1)
				(type default)
			)
			(layer "B.Fab")
		)
		(fp_line
			(start -1.1049 -0.724916)
			(end 1.1049 -0.724916)
			(stroke
				(width 0.1)
				(type default)
			)
			(layer "B.Fab")
		)
		(fp_line
			(start 1.1049 -0.724916)
			(end 1.1049 0.724916)
			(stroke
				(width 0.1)
				(type default)
			)
			(layer "B.Fab")
		)
		(pad "1" smd rect
			(at 0.889 0 270)
			(size 1.016 1.27)
			(layers "B.Cu" "B.Mask" "B.Paste")
			(net "PVDDIO_P1")
		)
		(pad "2" smd rect
			(at -0.889 0 270)
			(size 1.016 1.27)
			(layers "B.Cu" "B.Mask" "B.Paste")
			(net "GND")
		)
	)
	(footprint ""
		(layer "B.Cu")
		(at 152.849834 -322.903342 -90)
		(property "Reference" "R730"
			(at 0 0 90)
			(layer "B.SilkS")
			(hide yes)
			(effects
				(font
					(size 1.27 1.27)
				)
				(justify mirror)
			)
		)
		(property "Value" ""
			(at 0 0 90)
			(layer "B.Fab")
			(effects
				(font
					(size 1.27 1.27)
				)
				(justify mirror)
			)
		)
		(duplicate_pad_numbers_are_jumpers no)
		(fp_line
			(start -0.7874 0.4064)
			(end 0.7874 0.4064)
			(stroke
				(width 0.1524)
				(type default)
			)
			(layer "B.SilkS")
		)
		(fp_line
			(start 0.7874 0.4064)
			(end 0.7874 -0.4064)
			(stroke
				(width 0.1524)
				(type default)
			)
			(layer "B.SilkS")
		)
		(fp_line
			(start -0.7874 -0.4064)
			(end -0.7874 0.4064)
			(stroke
				(width 0.1524)
				(type default)
			)
			(layer "B.SilkS")
		)
		(fp_line
			(start 0.7874 -0.4064)
			(end -0.7874 -0.4064)
			(stroke
				(width 0.1524)
				(type default)
			)
			(layer "B.SilkS")
		)
		(fp_line
			(start -0.67945 0.3048)
			(end -0.120396 0.3048)
			(stroke
				(width 0.1)
				(type default)
			)
			(layer "B.Fab")
		)
		(fp_line
			(start -0.120396 0.3048)
			(end -0.120396 0.2794)
			(stroke
				(width 0.1)
				(type default)
			)
			(layer "B.Fab")
		)
		(fp_line
			(start 0.12065 0.3048)
			(end 0.67945 0.3048)
			(stroke
				(width 0.1)
				(type default)
			)
			(layer "B.Fab")
		)
		(fp_line
			(start 0.67945 0.3048)
			(end 0.67945 -0.305054)
			(stroke
				(width 0.1)
				(type default)
			)
			(layer "B.Fab")
		)
		(fp_line
			(start -0.120396 0.2794)
			(end 0.12065 0.2794)
			(stroke
				(width 0.1)
				(type default)
			)
			(layer "B.Fab")
		)
		(fp_line
			(start 0.12065 0.2794)
			(end 0.12065 0.3048)
			(stroke
				(width 0.1)
				(type default)
			)
			(layer "B.Fab")
		)
		(fp_line
			(start -0.12065 -0.2794)
			(end -0.12065 -0.3048)
			(stroke
				(width 0.1)
				(type default)
			)
			(layer "B.Fab")
		)
		(fp_line
			(start 0.12065 -0.2794)
			(end -0.12065 -0.2794)
			(stroke
				(width 0.1)
				(type default)
			)
			(layer "B.Fab")
		)
		(fp_line
			(start -0.67945 -0.3048)
			(end -0.67945 0.3048)
			(stroke
				(width 0.1)
				(type default)
			)
			(layer "B.Fab")
		)
		(fp_line
			(start -0.12065 -0.3048)
			(end -0.67945 -0.3048)
			(stroke
				(width 0.1)
				(type default)
			)
			(layer "B.Fab")
		)
		(fp_line
			(start 0.12065 -0.305054)
			(end 0.12065 -0.2794)
			(stroke
				(width 0.1)
				(type default)
			)
			(layer "B.Fab")
		)
		(fp_line
			(start 0.67945 -0.305054)
			(end 0.12065 -0.305054)
			(stroke
				(width 0.1)
				(type default)
			)
			(layer "B.Fab")
		)
		(pad "1" smd circle
			(at 0.40005 0 90)
			(size 0 0)
			(layers "B.Cu" "B.Mask" "B.Paste")
			(net "PVDD18_S5_P1")
		)
		(pad "2" smd circle
			(at -0.40005 0 90)
			(size 0 0)
			(layers "B.Cu" "B.Mask" "B.Paste")
			(net "SPI_CPU1_CLK")
		)
	)
	(footprint ""
		(layer "B.Cu")
		(at 350.03867 -160.080198 90)
		(property "Reference" "PR430"
			(at 0 0 90)
			(layer "B.SilkS")
			(hide yes)
			(effects
				(font
					(size 1.27 1.27)
				)
				(justify mirror)
			)
		)
		(property "Value" ""
			(at 0 0 90)
			(layer "B.Fab")
			(effects
				(font
					(size 1.27 1.27)
				)
				(justify mirror)
			)
		)
		(duplicate_pad_numbers_are_jumpers no)
		(fp_line
			(start 0.7874 -0.4064)
			(end -0.7874 -0.4064)
			(stroke
				(width 0.1524)
				(type default)
			)
			(layer "B.SilkS")
		)
		(fp_line
			(start -0.7874 -0.4064)
			(end -0.7874 0.4064)
			(stroke
				(width 0.1524)
				(type default)
			)
			(layer "B.SilkS")
		)
		(fp_line
			(start 0.7874 0.4064)
			(end 0.7874 -0.4064)
			(stroke
				(width 0.1524)
				(type default)
			)
			(layer "B.SilkS")
		)
		(fp_line
			(start -0.7874 0.4064)
			(end 0.7874 0.4064)
			(stroke
				(width 0.1524)
				(type default)
			)
			(layer "B.SilkS")
		)
		(fp_line
			(start 0.67945 -0.305054)
			(end 0.12065 -0.305054)
			(stroke
				(width 0.1)
				(type default)
			)
			(layer "B.Fab")
		)
		(fp_line
			(start 0.12065 -0.305054)
			(end 0.12065 -0.2794)
			(stroke
				(width 0.1)
				(type default)
			)
			(layer "B.Fab")
		)
		(fp_line
			(start -0.12065 -0.3048)
			(end -0.67945 -0.3048)
			(stroke
				(width 0.1)
				(type default)
			)
			(layer "B.Fab")
		)
		(fp_line
			(start -0.67945 -0.3048)
			(end -0.67945 0.3048)
			(stroke
				(width 0.1)
				(type default)
			)
			(layer "B.Fab")
		)
		(fp_line
			(start 0.12065 -0.2794)
			(end -0.12065 -0.2794)
			(stroke
				(width 0.1)
				(type default)
			)
			(layer "B.Fab")
		)
		(fp_line
			(start -0.12065 -0.2794)
			(end -0.12065 -0.3048)
			(stroke
				(width 0.1)
				(type default)
			)
			(layer "B.Fab")
		)
		(fp_line
			(start 0.12065 0.2794)
			(end 0.12065 0.3048)
			(stroke
				(width 0.1)
				(type default)
			)
			(layer "B.Fab")
		)
		(fp_line
			(start -0.120396 0.2794)
			(end 0.12065 0.2794)
			(stroke
				(width 0.1)
				(type default)
			)
			(layer "B.Fab")
		)
		(fp_line
			(start 0.67945 0.3048)
			(end 0.67945 -0.305054)
			(stroke
				(width 0.1)
				(type default)
			)
			(layer "B.Fab")
		)
		(fp_line
			(start 0.12065 0.3048)
			(end 0.67945 0.3048)
			(stroke
				(width 0.1)
				(type default)
			)
			(layer "B.Fab")
		)
		(fp_line
			(start -0.120396 0.3048)
			(end -0.120396 0.2794)
			(stroke
				(width 0.1)
				(type default)
			)
			(layer "B.Fab")
		)
		(fp_line
			(start -0.67945 0.3048)
			(end -0.120396 0.3048)
			(stroke
				(width 0.1)
				(type default)
			)
			(layer "B.Fab")
		)
		(pad "1" smd circle
			(at 0.40005 0 270)
			(size 0 0)
			(layers "B.Cu" "B.Mask" "B.Paste")
			(net "PVDDCR_CPU0_P0_PVCC")
		)
		(pad "2" smd circle
			(at -0.40005 0 270)
			(size 0 0)
			(layers "B.Cu" "B.Mask" "B.Paste")
			(net "PVDDCR_CPU0_P0_VCC6")
		)
	)
	(footprint ""
		(layer "B.Cu")
		(at 198.438008 -111.380016)
		(property "Reference" "R224"
			(at 0 0 0)
			(layer "B.SilkS")
			(hide yes)
			(effects
				(font
					(size 1.27 1.27)
				)
				(justify mirror)
			)
		)
		(property "Value" ""
			(at 0 0 0)
			(layer "B.Fab")
			(effects
				(font
					(size 1.27 1.27)
				)
				(justify mirror)
			)
		)
		(duplicate_pad_numbers_are_jumpers no)
		(fp_line
			(start -0.7874 -0.4064)
			(end -0.7874 0.4064)
			(stroke
				(width 0.1524)
				(type default)
			)
			(layer "B.SilkS")
		)
		(fp_line
			(start -0.7874 0.4064)
			(end 0.7874 0.4064)
			(stroke
				(width 0.1524)
				(type default)
			)
			(layer "B.SilkS")
		)
		(fp_line
			(start 0.7874 -0.4064)
			(end -0.7874 -0.4064)
			(stroke
				(width 0.1524)
				(type default)
			)
			(layer "B.SilkS")
		)
		(fp_line
			(start 0.7874 0.4064)
			(end 0.7874 -0.4064)
			(stroke
				(width 0.1524)
				(type default)
			)
			(layer "B.SilkS")
		)
		(fp_line
			(start -0.67945 -0.3048)
			(end -0.67945 0.3048)
			(stroke
				(width 0.1)
				(type default)
			)
			(layer "B.Fab")
		)
		(fp_line
			(start -0.67945 0.3048)
			(end -0.120396 0.3048)
			(stroke
				(width 0.1)
				(type default)
			)
			(layer "B.Fab")
		)
		(fp_line
			(start -0.12065 -0.3048)
			(end -0.67945 -0.3048)
			(stroke
				(width 0.1)
				(type default)
			)
			(layer "B.Fab")
		)
		(fp_line
			(start -0.12065 -0.2794)
			(end -0.12065 -0.3048)
			(stroke
				(width 0.1)
				(type default)
			)
			(layer "B.Fab")
		)
		(fp_line
			(start -0.120396 0.2794)
			(end 0.12065 0.2794)
			(stroke
				(width 0.1)
				(type default)
			)
			(layer "B.Fab")
		)
		(fp_line
			(start -0.120396 0.3048)
			(end -0.120396 0.2794)
			(stroke
				(width 0.1)
				(type default)
			)
			(layer "B.Fab")
		)
		(fp_line
			(start 0.12065 -0.305054)
			(end 0.12065 -0.2794)
			(stroke
				(width 0.1)
				(type default)
			)
			(layer "B.Fab")
		)
		(fp_line
			(start 0.12065 -0.2794)
			(end -0.12065 -0.2794)
			(stroke
				(width 0.1)
				(type default)
			)
			(layer "B.Fab")
		)
		(fp_line
			(start 0.12065 0.2794)
			(end 0.12065 0.3048)
			(stroke
				(width 0.1)
				(type default)
			)
			(layer "B.Fab")
		)
		(fp_line
			(start 0.12065 0.3048)
			(end 0.67945 0.3048)
			(stroke
				(width 0.1)
				(type default)
			)
			(layer "B.Fab")
		)
		(fp_line
			(start 0.67945 -0.305054)
			(end 0.12065 -0.305054)
			(stroke
				(width 0.1)
				(type default)
			)
			(layer "B.Fab")
		)
		(fp_line
			(start 0.67945 0.3048)
			(end 0.67945 -0.305054)
			(stroke
				(width 0.1)
				(type default)
			)
			(layer "B.Fab")
		)
		(pad "1" smd circle
			(at 0.40005 0 180)
			(size 0 0)
			(layers "B.Cu" "B.Mask" "B.Paste")
			(net "PVDD33_S5_EN")
		)
		(pad "2" smd circle
			(at -0.40005 0 180)
			(size 0 0)
			(layers "B.Cu" "B.Mask" "B.Paste")
			(net "FM_PVDD33_S5_EN")
		)
	)
	(footprint ""
		(layer "B.Cu")
		(at 48.65624 -429.114966)
		(property "Reference" "Q107"
			(at 1.138682 -2.10185 0)
			(unlocked yes)
			(layer "B.SilkS")
			(effects
				(font
					(size 0.7874 0.5842)
					(thickness 0.1524)
				)
				(justify left mirror)
			)
		)
		(property "Value" ""
			(at 0 0 0)
			(layer "B.Fab")
			(effects
				(font
					(size 1.27 1.27)
				)
				(justify mirror)
			)
		)
		(duplicate_pad_numbers_are_jumpers no)
		(fp_line
			(start -1.332738 -1.100074)
			(end -1.332738 1.100074)
			(stroke
				(width 0.1524)
				(type default)
			)
			(layer "B.SilkS")
		)
		(fp_line
			(start -1.332738 1.100074)
			(end 1.332738 1.100074)
			(stroke
				(width 0.1524)
				(type default)
			)
			(layer "B.SilkS")
		)
		(fp_line
			(start -0.4826 -1.100074)
			(end -1.332738 -1.100074)
			(stroke
				(width 0.1524)
				(type default)
			)
			(layer "B.SilkS")
		)
		(fp_line
			(start 0 -0.541274)
			(end -0.4826 -1.100074)
			(stroke
				(width 0.1524)
				(type default)
			)
			(layer "B.SilkS")
		)
		(fp_line
			(start 0.4826 -1.100074)
			(end 0 -0.541274)
			(stroke
				(width 0.1524)
				(type default)
			)
			(layer "B.SilkS")
		)
		(fp_line
			(start 1.332738 -1.100074)
			(end 0.4826 -1.100074)
			(stroke
				(width 0.1524)
				(type default)
			)
			(layer "B.SilkS")
		)
		(fp_line
			(start 1.332738 1.100074)
			(end 1.332738 -1.100074)
			(stroke
				(width 0.1524)
				(type default)
			)
			(layer "B.SilkS")
		)
		(fp_poly
			(pts
				(xy 1.668272 -0.896112) (xy 2.452878 -0.870458) (xy 2.159508 -1.508252)
			)
			(stroke
				(width 0)
				(type default)
			)
			(fill yes)
			(layer "B.SilkS")
		)
		(fp_line
			(start -0.674878 -1.100074)
			(end -0.674878 1.100074)
			(stroke
				(width 0.1)
				(type default)
			)
			(layer "B.Fab")
		)
		(fp_line
			(start -0.674878 1.100074)
			(end 0.674878 1.100074)
			(stroke
				(width 0.1)
				(type default)
			)
			(layer "B.Fab")
		)
		(fp_line
			(start 0.674878 -1.100074)
			(end -0.674878 -1.100074)
			(stroke
				(width 0.1)
				(type default)
			)
			(layer "B.Fab")
		)
		(fp_line
			(start 0.674878 1.100074)
			(end 0.674878 -1.100074)
			(stroke
				(width 0.1)
				(type default)
			)
			(layer "B.Fab")
		)
		(fp_poly
			(pts
				(xy 2.2352 -0.298958) (xy 2.2352 -1.001014) (xy 1.533144 -0.649986)
			)
			(stroke
				(width 0)
				(type default)
			)
			(fill yes)
			(layer "B.Fab")
		)
		(pad "1" smd rect
			(at 0.94996 -0.649986 90)
			(size 0.4318 0.508)
			(layers "B.Cu" "B.Mask" "B.Paste")
			(net "GND")
		)
		(pad "2" smd rect
			(at 0.94996 0 90)
			(size 0.4318 0.508)
			(layers "B.Cu" "B.Mask" "B.Paste")
			(net "GPU_PRSNT_N")
		)
		(pad "3" smd rect
			(at 0.94996 0.649986 90)
			(size 0.4318 0.508)
			(layers "B.Cu" "B.Mask" "B.Paste")
			(net "GPU_PRSNT_N_ISO")
		)
		(pad "4" smd rect
			(at -0.94996 0.649986 90)
			(size 0.4318 0.508)
			(layers "B.Cu" "B.Mask" "B.Paste")
			(net "GND")
		)
		(pad "5" smd rect
			(at -0.94996 0 90)
			(size 0.4318 0.508)
			(layers "B.Cu" "B.Mask" "B.Paste")
			(net "GPU_PRSNT")
		)
		(pad "6" smd rect
			(at -0.94996 -0.649986 90)
			(size 0.4318 0.508)
			(layers "B.Cu" "B.Mask" "B.Paste")
			(net "GPU_PRSNT")
		)
	)
	(footprint ""
		(layer "B.Cu")
		(at 122.888248 -165.079934 -90)
		(property "Reference" "PC330_2"
			(at 0 0 90)
			(layer "B.SilkS")
			(hide yes)
			(effects
				(font
					(size 1.27 1.27)
				)
				(justify mirror)
			)
		)
		(property "Value" ""
			(at 0 0 90)
			(layer "B.Fab")
			(effects
				(font
					(size 1.27 1.27)
				)
				(justify mirror)
			)
		)
		(duplicate_pad_numbers_are_jumpers no)
		(fp_line
			(start -1.524 0.762)
			(end 1.524 0.762)
			(stroke
				(width 0.1524)
				(type default)
			)
			(layer "B.SilkS")
		)
		(fp_line
			(start 1.524 0.762)
			(end 1.524 -0.762)
			(stroke
				(width 0.1524)
				(type default)
			)
			(layer "B.SilkS")
		)
		(fp_line
			(start -1.524 -0.762)
			(end -1.524 0.762)
			(stroke
				(width 0.1524)
				(type default)
			)
			(layer "B.SilkS")
		)
		(fp_line
			(start 1.524 -0.762)
			(end -1.524 -0.762)
			(stroke
				(width 0.1524)
				(type default)
			)
			(layer "B.SilkS")
		)
		(fp_line
			(start -1.1049 0.724916)
			(end -1.1049 -0.724916)
			(stroke
				(width 0.1)
				(type default)
			)
			(layer "B.Fab")
		)
		(fp_line
			(start 1.1049 0.724916)
			(end -1.1049 0.724916)
			(stroke
				(width 0.1)
				(type default)
			)
			(layer "B.Fab")
		)
		(fp_line
			(start -1.1049 -0.724916)
			(end 1.1049 -0.724916)
			(stroke
				(width 0.1)
				(type default)
			)
			(layer "B.Fab")
		)
		(fp_line
			(start 1.1049 -0.724916)
			(end 1.1049 0.724916)
			(stroke
				(width 0.1)
				(type default)
			)
			(layer "B.Fab")
		)
		(pad "1" smd rect
			(at 0.889 0 270)
			(size 1.016 1.27)
			(layers "B.Cu" "B.Mask" "B.Paste")
			(net "SW_P12V_AUX_PVDDCR_SOC_P1_FLT")
		)
		(pad "2" smd rect
			(at -0.889 0 270)
			(size 1.016 1.27)
			(layers "B.Cu" "B.Mask" "B.Paste")
			(net "GND")
		)
	)
	(footprint ""
		(layer "B.Cu")
		(at 192.27292 -351.23882 90)
		(property "Reference" "PC516_2"
			(at 0 0 90)
			(layer "B.SilkS")
			(hide yes)
			(effects
				(font
					(size 1.27 1.27)
				)
				(justify mirror)
			)
		)
		(property "Value" ""
			(at 0 0 90)
			(layer "B.Fab")
			(effects
				(font
					(size 1.27 1.27)
				)
				(justify mirror)
			)
		)
		(duplicate_pad_numbers_are_jumpers no)
		(fp_line
			(start 1.524 -0.762)
			(end -1.524 -0.762)
			(stroke
				(width 0.1524)
				(type default)
			)
			(layer "B.SilkS")
		)
		(fp_line
			(start -1.524 -0.762)
			(end -1.524 0.762)
			(stroke
				(width 0.1524)
				(type default)
			)
			(layer "B.SilkS")
		)
		(fp_line
			(start 1.524 0.762)
			(end 1.524 -0.762)
			(stroke
				(width 0.1524)
				(type default)
			)
			(layer "B.SilkS")
		)
		(fp_line
			(start -1.524 0.762)
			(end 1.524 0.762)
			(stroke
				(width 0.1524)
				(type default)
			)
			(layer "B.SilkS")
		)
		(fp_line
			(start 1.1049 -0.724916)
			(end 1.1049 0.724916)
			(stroke
				(width 0.1)
				(type default)
			)
			(layer "B.Fab")
		)
		(fp_line
			(start -1.1049 -0.724916)
			(end 1.1049 -0.724916)
			(stroke
				(width 0.1)
				(type default)
			)
			(layer "B.Fab")
		)
		(fp_line
			(start 1.1049 0.724916)
			(end -1.1049 0.724916)
			(stroke
				(width 0.1)
				(type default)
			)
			(layer "B.Fab")
		)
		(fp_line
			(start -1.1049 0.724916)
			(end -1.1049 -0.724916)
			(stroke
				(width 0.1)
				(type default)
			)
			(layer "B.Fab")
		)
		(pad "1" smd rect
			(at 0.889 0 90)
			(size 1.016 1.27)
			(layers "B.Cu" "B.Mask" "B.Paste")
			(net "SW_P12V_AUX_PVDD11_S3_P1_FLT")
		)
		(pad "2" smd rect
			(at -0.889 0 90)
			(size 1.016 1.27)
			(layers "B.Cu" "B.Mask" "B.Paste")
			(net "GND")
		)
	)
	(footprint ""
		(layer "B.Cu")
		(at 367.995454 -268.41831)
		(property "Reference" "C2232"
			(at 0 0 0)
			(layer "B.SilkS")
			(hide yes)
			(effects
				(font
					(size 1.27 1.27)
				)
				(justify mirror)
			)
		)
		(property "Value" ""
			(at 0 0 0)
			(layer "B.Fab")
			(effects
				(font
					(size 1.27 1.27)
				)
				(justify mirror)
			)
		)
		(duplicate_pad_numbers_are_jumpers no)
		(fp_line
			(start -0.7874 -0.4064)
			(end -0.7874 0.4064)
			(stroke
				(width 0.1524)
				(type default)
			)
			(layer "B.SilkS")
		)
		(fp_line
			(start -0.7874 0.4064)
			(end 0.7874 0.4064)
			(stroke
				(width 0.1524)
				(type default)
			)
			(layer "B.SilkS")
		)
		(fp_line
			(start 0.7874 -0.4064)
			(end -0.7874 -0.4064)
			(stroke
				(width 0.1524)
				(type default)
			)
			(layer "B.SilkS")
		)
		(fp_line
			(start 0.7874 0.4064)
			(end 0.7874 -0.4064)
			(stroke
				(width 0.1524)
				(type default)
			)
			(layer "B.SilkS")
		)
		(fp_line
			(start -0.67945 -0.3048)
			(end -0.67945 0.3048)
			(stroke
				(width 0.1)
				(type default)
			)
			(layer "B.Fab")
		)
		(fp_line
			(start -0.67945 0.3048)
			(end -0.120396 0.3048)
			(stroke
				(width 0.1)
				(type default)
			)
			(layer "B.Fab")
		)
		(fp_line
			(start -0.12065 -0.3048)
			(end -0.67945 -0.3048)
			(stroke
				(width 0.1)
				(type default)
			)
			(layer "B.Fab")
		)
		(fp_line
			(start -0.12065 -0.2794)
			(end -0.12065 -0.3048)
			(stroke
				(width 0.1)
				(type default)
			)
			(layer "B.Fab")
		)
		(fp_line
			(start -0.120396 0.2794)
			(end 0.12065 0.2794)
			(stroke
				(width 0.1)
				(type default)
			)
			(layer "B.Fab")
		)
		(fp_line
			(start -0.120396 0.3048)
			(end -0.120396 0.2794)
			(stroke
				(width 0.1)
				(type default)
			)
			(layer "B.Fab")
		)
		(fp_line
			(start 0.12065 -0.305054)
			(end 0.12065 -0.2794)
			(stroke
				(width 0.1)
				(type default)
			)
			(layer "B.Fab")
		)
		(fp_line
			(start 0.12065 -0.2794)
			(end -0.12065 -0.2794)
			(stroke
				(width 0.1)
				(type default)
			)
			(layer "B.Fab")
		)
		(fp_line
			(start 0.12065 0.2794)
			(end 0.12065 0.3048)
			(stroke
				(width 0.1)
				(type default)
			)
			(layer "B.Fab")
		)
		(fp_line
			(start 0.12065 0.3048)
			(end 0.67945 0.3048)
			(stroke
				(width 0.1)
				(type default)
			)
			(layer "B.Fab")
		)
		(fp_line
			(start 0.67945 -0.305054)
			(end 0.12065 -0.305054)
			(stroke
				(width 0.1)
				(type default)
			)
			(layer "B.Fab")
		)
		(fp_line
			(start 0.67945 0.3048)
			(end 0.67945 -0.305054)
			(stroke
				(width 0.1)
				(type default)
			)
			(layer "B.Fab")
		)
		(pad "1" smd circle
			(at 0.40005 0 180)
			(size 0 0)
			(layers "B.Cu" "B.Mask" "B.Paste")
			(net "PVDDCR_CPU1_P0")
		)
		(pad "2" smd circle
			(at -0.40005 0 180)
			(size 0 0)
			(layers "B.Cu" "B.Mask" "B.Paste")
			(net "GND")
		)
	)
	(footprint ""
		(layer "B.Cu")
		(at 359.740454 -247.97131 90)
		(property "Reference" "C2193"
			(at 0 0 90)
			(layer "B.SilkS")
			(hide yes)
			(effects
				(font
					(size 1.27 1.27)
				)
				(justify mirror)
			)
		)
		(property "Value" ""
			(at 0 0 90)
			(layer "B.Fab")
			(effects
				(font
					(size 1.27 1.27)
				)
				(justify mirror)
			)
		)
		(duplicate_pad_numbers_are_jumpers no)
		(fp_line
			(start 0.7874 -0.4064)
			(end -0.7874 -0.4064)
			(stroke
				(width 0.1524)
				(type default)
			)
			(layer "B.SilkS")
		)
		(fp_line
			(start -0.7874 -0.4064)
			(end -0.7874 0.4064)
			(stroke
				(width 0.1524)
				(type default)
			)
			(layer "B.SilkS")
		)
		(fp_line
			(start 0.7874 0.4064)
			(end 0.7874 -0.4064)
			(stroke
				(width 0.1524)
				(type default)
			)
			(layer "B.SilkS")
		)
		(fp_line
			(start -0.7874 0.4064)
			(end 0.7874 0.4064)
			(stroke
				(width 0.1524)
				(type default)
			)
			(layer "B.SilkS")
		)
		(fp_line
			(start 0.67945 -0.305054)
			(end 0.12065 -0.305054)
			(stroke
				(width 0.1)
				(type default)
			)
			(layer "B.Fab")
		)
		(fp_line
			(start 0.12065 -0.305054)
			(end 0.12065 -0.2794)
			(stroke
				(width 0.1)
				(type default)
			)
			(layer "B.Fab")
		)
		(fp_line
			(start -0.12065 -0.3048)
			(end -0.67945 -0.3048)
			(stroke
				(width 0.1)
				(type default)
			)
			(layer "B.Fab")
		)
		(fp_line
			(start -0.67945 -0.3048)
			(end -0.67945 0.3048)
			(stroke
				(width 0.1)
				(type default)
			)
			(layer "B.Fab")
		)
		(fp_line
			(start 0.12065 -0.2794)
			(end -0.12065 -0.2794)
			(stroke
				(width 0.1)
				(type default)
			)
			(layer "B.Fab")
		)
		(fp_line
			(start -0.12065 -0.2794)
			(end -0.12065 -0.3048)
			(stroke
				(width 0.1)
				(type default)
			)
			(layer "B.Fab")
		)
		(fp_line
			(start 0.12065 0.2794)
			(end 0.12065 0.3048)
			(stroke
				(width 0.1)
				(type default)
			)
			(layer "B.Fab")
		)
		(fp_line
			(start -0.120396 0.2794)
			(end 0.12065 0.2794)
			(stroke
				(width 0.1)
				(type default)
			)
			(layer "B.Fab")
		)
		(fp_line
			(start 0.67945 0.3048)
			(end 0.67945 -0.305054)
			(stroke
				(width 0.1)
				(type default)
			)
			(layer "B.Fab")
		)
		(fp_line
			(start 0.12065 0.3048)
			(end 0.67945 0.3048)
			(stroke
				(width 0.1)
				(type default)
			)
			(layer "B.Fab")
		)
		(fp_line
			(start -0.120396 0.3048)
			(end -0.120396 0.2794)
			(stroke
				(width 0.1)
				(type default)
			)
			(layer "B.Fab")
		)
		(fp_line
			(start -0.67945 0.3048)
			(end -0.120396 0.3048)
			(stroke
				(width 0.1)
				(type default)
			)
			(layer "B.Fab")
		)
		(pad "1" smd circle
			(at 0.40005 0 270)
			(size 0 0)
			(layers "B.Cu" "B.Mask" "B.Paste")
			(net "PVDDCR_CPU0_P0")
		)
		(pad "2" smd circle
			(at -0.40005 0 270)
			(size 0 0)
			(layers "B.Cu" "B.Mask" "B.Paste")
			(net "GND")
		)
	)
	(footprint ""
		(layer "B.Cu")
		(at 371.551454 -258.830064)
		(property "Reference" "C2129"
			(at 0 0 0)
			(layer "B.SilkS")
			(hide yes)
			(effects
				(font
					(size 1.27 1.27)
				)
				(justify mirror)
			)
		)
		(property "Value" ""
			(at 0 0 0)
			(layer "B.Fab")
			(effects
				(font
					(size 1.27 1.27)
				)
				(justify mirror)
			)
		)
		(duplicate_pad_numbers_are_jumpers no)
		(fp_line
			(start -0.7874 -0.4064)
			(end -0.7874 0.4064)
			(stroke
				(width 0.1524)
				(type default)
			)
			(layer "B.SilkS")
		)
		(fp_line
			(start -0.7874 0.4064)
			(end 0.7874 0.4064)
			(stroke
				(width 0.1524)
				(type default)
			)
			(layer "B.SilkS")
		)
		(fp_line
			(start 0.7874 -0.4064)
			(end -0.7874 -0.4064)
			(stroke
				(width 0.1524)
				(type default)
			)
			(layer "B.SilkS")
		)
		(fp_line
			(start 0.7874 0.4064)
			(end 0.7874 -0.4064)
			(stroke
				(width 0.1524)
				(type default)
			)
			(layer "B.SilkS")
		)
		(fp_line
			(start -0.67945 -0.3048)
			(end -0.67945 0.3048)
			(stroke
				(width 0.1)
				(type default)
			)
			(layer "B.Fab")
		)
		(fp_line
			(start -0.67945 0.3048)
			(end -0.120396 0.3048)
			(stroke
				(width 0.1)
				(type default)
			)
			(layer "B.Fab")
		)
		(fp_line
			(start -0.12065 -0.3048)
			(end -0.67945 -0.3048)
			(stroke
				(width 0.1)
				(type default)
			)
			(layer "B.Fab")
		)
		(fp_line
			(start -0.12065 -0.2794)
			(end -0.12065 -0.3048)
			(stroke
				(width 0.1)
				(type default)
			)
			(layer "B.Fab")
		)
		(fp_line
			(start -0.120396 0.2794)
			(end 0.12065 0.2794)
			(stroke
				(width 0.1)
				(type default)
			)
			(layer "B.Fab")
		)
		(fp_line
			(start -0.120396 0.3048)
			(end -0.120396 0.2794)
			(stroke
				(width 0.1)
				(type default)
			)
			(layer "B.Fab")
		)
		(fp_line
			(start 0.12065 -0.305054)
			(end 0.12065 -0.2794)
			(stroke
				(width 0.1)
				(type default)
			)
			(layer "B.Fab")
		)
		(fp_line
			(start 0.12065 -0.2794)
			(end -0.12065 -0.2794)
			(stroke
				(width 0.1)
				(type default)
			)
			(layer "B.Fab")
		)
		(fp_line
			(start 0.12065 0.2794)
			(end 0.12065 0.3048)
			(stroke
				(width 0.1)
				(type default)
			)
			(layer "B.Fab")
		)
		(fp_line
			(start 0.12065 0.3048)
			(end 0.67945 0.3048)
			(stroke
				(width 0.1)
				(type default)
			)
			(layer "B.Fab")
		)
		(fp_line
			(start 0.67945 -0.305054)
			(end 0.12065 -0.305054)
			(stroke
				(width 0.1)
				(type default)
			)
			(layer "B.Fab")
		)
		(fp_line
			(start 0.67945 0.3048)
			(end 0.67945 -0.305054)
			(stroke
				(width 0.1)
				(type default)
			)
			(layer "B.Fab")
		)
		(pad "1" smd circle
			(at 0.40005 0 180)
			(size 0 0)
			(layers "B.Cu" "B.Mask" "B.Paste")
			(net "PVDDCR_SOC_P0")
		)
		(pad "2" smd circle
			(at -0.40005 0 180)
			(size 0 0)
			(layers "B.Cu" "B.Mask" "B.Paste")
			(net "GND")
		)
	)
	(footprint ""
		(layer "B.Cu")
		(at 171.440602 -8.062468 -90)
		(property "Reference" "R3243"
			(at 0 0 90)
			(layer "B.SilkS")
			(hide yes)
			(effects
				(font
					(size 1.27 1.27)
				)
				(justify mirror)
			)
		)
		(property "Value" ""
			(at 0 0 90)
			(layer "B.Fab")
			(effects
				(font
					(size 1.27 1.27)
				)
				(justify mirror)
			)
		)
		(duplicate_pad_numbers_are_jumpers no)
		(fp_line
			(start -0.7874 0.4064)
			(end 0.7874 0.4064)
			(stroke
				(width 0.1524)
				(type default)
			)
			(layer "B.SilkS")
		)
		(fp_line
			(start 0.7874 0.4064)
			(end 0.7874 -0.4064)
			(stroke
				(width 0.1524)
				(type default)
			)
			(layer "B.SilkS")
		)
		(fp_line
			(start -0.7874 -0.4064)
			(end -0.7874 0.4064)
			(stroke
				(width 0.1524)
				(type default)
			)
			(layer "B.SilkS")
		)
		(fp_line
			(start 0.7874 -0.4064)
			(end -0.7874 -0.4064)
			(stroke
				(width 0.1524)
				(type default)
			)
			(layer "B.SilkS")
		)
		(fp_line
			(start -0.67945 0.3048)
			(end -0.120396 0.3048)
			(stroke
				(width 0.1)
				(type default)
			)
			(layer "B.Fab")
		)
		(fp_line
			(start -0.120396 0.3048)
			(end -0.120396 0.2794)
			(stroke
				(width 0.1)
				(type default)
			)
			(layer "B.Fab")
		)
		(fp_line
			(start 0.12065 0.3048)
			(end 0.67945 0.3048)
			(stroke
				(width 0.1)
				(type default)
			)
			(layer "B.Fab")
		)
		(fp_line
			(start 0.67945 0.3048)
			(end 0.67945 -0.305054)
			(stroke
				(width 0.1)
				(type default)
			)
			(layer "B.Fab")
		)
		(fp_line
			(start -0.120396 0.2794)
			(end 0.12065 0.2794)
			(stroke
				(width 0.1)
				(type default)
			)
			(layer "B.Fab")
		)
		(fp_line
			(start 0.12065 0.2794)
			(end 0.12065 0.3048)
			(stroke
				(width 0.1)
				(type default)
			)
			(layer "B.Fab")
		)
		(fp_line
			(start -0.12065 -0.2794)
			(end -0.12065 -0.3048)
			(stroke
				(width 0.1)
				(type default)
			)
			(layer "B.Fab")
		)
		(fp_line
			(start 0.12065 -0.2794)
			(end -0.12065 -0.2794)
			(stroke
				(width 0.1)
				(type default)
			)
			(layer "B.Fab")
		)
		(fp_line
			(start -0.67945 -0.3048)
			(end -0.67945 0.3048)
			(stroke
				(width 0.1)
				(type default)
			)
			(layer "B.Fab")
		)
		(fp_line
			(start -0.12065 -0.3048)
			(end -0.67945 -0.3048)
			(stroke
				(width 0.1)
				(type default)
			)
			(layer "B.Fab")
		)
		(fp_line
			(start 0.12065 -0.305054)
			(end 0.12065 -0.2794)
			(stroke
				(width 0.1)
				(type default)
			)
			(layer "B.Fab")
		)
		(fp_line
			(start 0.67945 -0.305054)
			(end 0.12065 -0.305054)
			(stroke
				(width 0.1)
				(type default)
			)
			(layer "B.Fab")
		)
		(pad "1" smd circle
			(at 0.40005 0 90)
			(size 0 0)
			(layers "B.Cu" "B.Mask" "B.Paste")
			(net "SMB_OCP_V3_2_3V3AUX_SDA")
		)
		(pad "2" smd circle
			(at -0.40005 0 90)
			(size 0 0)
			(layers "B.Cu" "B.Mask" "B.Paste")
			(net "P3V3_AUX")
		)
	)
	(footprint ""
		(layer "B.Cu")
		(at 118.277386 -268.418564)
		(property "Reference" "C2375"
			(at 0 0 0)
			(layer "B.SilkS")
			(hide yes)
			(effects
				(font
					(size 1.27 1.27)
				)
				(justify mirror)
			)
		)
		(property "Value" ""
			(at 0 0 0)
			(layer "B.Fab")
			(effects
				(font
					(size 1.27 1.27)
				)
				(justify mirror)
			)
		)
		(duplicate_pad_numbers_are_jumpers no)
		(fp_line
			(start -0.7874 -0.4064)
			(end -0.7874 0.4064)
			(stroke
				(width 0.1524)
				(type default)
			)
			(layer "B.SilkS")
		)
		(fp_line
			(start -0.7874 0.4064)
			(end 0.7874 0.4064)
			(stroke
				(width 0.1524)
				(type default)
			)
			(layer "B.SilkS")
		)
		(fp_line
			(start 0.7874 -0.4064)
			(end -0.7874 -0.4064)
			(stroke
				(width 0.1524)
				(type default)
			)
			(layer "B.SilkS")
		)
		(fp_line
			(start 0.7874 0.4064)
			(end 0.7874 -0.4064)
			(stroke
				(width 0.1524)
				(type default)
			)
			(layer "B.SilkS")
		)
		(fp_line
			(start -0.67945 -0.3048)
			(end -0.67945 0.3048)
			(stroke
				(width 0.1)
				(type default)
			)
			(layer "B.Fab")
		)
		(fp_line
			(start -0.67945 0.3048)
			(end -0.120396 0.3048)
			(stroke
				(width 0.1)
				(type default)
			)
			(layer "B.Fab")
		)
		(fp_line
			(start -0.12065 -0.3048)
			(end -0.67945 -0.3048)
			(stroke
				(width 0.1)
				(type default)
			)
			(layer "B.Fab")
		)
		(fp_line
			(start -0.12065 -0.2794)
			(end -0.12065 -0.3048)
			(stroke
				(width 0.1)
				(type default)
			)
			(layer "B.Fab")
		)
		(fp_line
			(start -0.120396 0.2794)
			(end 0.12065 0.2794)
			(stroke
				(width 0.1)
				(type default)
			)
			(layer "B.Fab")
		)
		(fp_line
			(start -0.120396 0.3048)
			(end -0.120396 0.2794)
			(stroke
				(width 0.1)
				(type default)
			)
			(layer "B.Fab")
		)
		(fp_line
			(start 0.12065 -0.305054)
			(end 0.12065 -0.2794)
			(stroke
				(width 0.1)
				(type default)
			)
			(layer "B.Fab")
		)
		(fp_line
			(start 0.12065 -0.2794)
			(end -0.12065 -0.2794)
			(stroke
				(width 0.1)
				(type default)
			)
			(layer "B.Fab")
		)
		(fp_line
			(start 0.12065 0.2794)
			(end 0.12065 0.3048)
			(stroke
				(width 0.1)
				(type default)
			)
			(layer "B.Fab")
		)
		(fp_line
			(start 0.12065 0.3048)
			(end 0.67945 0.3048)
			(stroke
				(width 0.1)
				(type default)
			)
			(layer "B.Fab")
		)
		(fp_line
			(start 0.67945 -0.305054)
			(end 0.12065 -0.305054)
			(stroke
				(width 0.1)
				(type default)
			)
			(layer "B.Fab")
		)
		(fp_line
			(start 0.67945 0.3048)
			(end 0.67945 -0.305054)
			(stroke
				(width 0.1)
				(type default)
			)
			(layer "B.Fab")
		)
		(pad "1" smd circle
			(at 0.40005 0 180)
			(size 0 0)
			(layers "B.Cu" "B.Mask" "B.Paste")
			(net "PVDDCR_CPU1_P1")
		)
		(pad "2" smd circle
			(at -0.40005 0 180)
			(size 0 0)
			(layers "B.Cu" "B.Mask" "B.Paste")
			(net "GND")
		)
	)
	(footprint ""
		(layer "B.Cu")
		(at 211.69503 -57.078372 -90)
		(property "Reference" "R3752"
			(at 0 0 90)
			(layer "B.SilkS")
			(hide yes)
			(effects
				(font
					(size 1.27 1.27)
				)
				(justify mirror)
			)
		)
		(property "Value" ""
			(at 0 0 90)
			(layer "B.Fab")
			(effects
				(font
					(size 1.27 1.27)
				)
				(justify mirror)
			)
		)
		(duplicate_pad_numbers_are_jumpers no)
		(fp_line
			(start -0.7874 0.4064)
			(end 0.7874 0.4064)
			(stroke
				(width 0.1524)
				(type default)
			)
			(layer "B.SilkS")
		)
		(fp_line
			(start 0.7874 0.4064)
			(end 0.7874 -0.4064)
			(stroke
				(width 0.1524)
				(type default)
			)
			(layer "B.SilkS")
		)
		(fp_line
			(start -0.7874 -0.4064)
			(end -0.7874 0.4064)
			(stroke
				(width 0.1524)
				(type default)
			)
			(layer "B.SilkS")
		)
		(fp_line
			(start 0.7874 -0.4064)
			(end -0.7874 -0.4064)
			(stroke
				(width 0.1524)
				(type default)
			)
			(layer "B.SilkS")
		)
		(fp_line
			(start -0.67945 0.3048)
			(end -0.120396 0.3048)
			(stroke
				(width 0.1)
				(type default)
			)
			(layer "B.Fab")
		)
		(fp_line
			(start -0.120396 0.3048)
			(end -0.120396 0.2794)
			(stroke
				(width 0.1)
				(type default)
			)
			(layer "B.Fab")
		)
		(fp_line
			(start 0.12065 0.3048)
			(end 0.67945 0.3048)
			(stroke
				(width 0.1)
				(type default)
			)
			(layer "B.Fab")
		)
		(fp_line
			(start 0.67945 0.3048)
			(end 0.67945 -0.305054)
			(stroke
				(width 0.1)
				(type default)
			)
			(layer "B.Fab")
		)
		(fp_line
			(start -0.120396 0.2794)
			(end 0.12065 0.2794)
			(stroke
				(width 0.1)
				(type default)
			)
			(layer "B.Fab")
		)
		(fp_line
			(start 0.12065 0.2794)
			(end 0.12065 0.3048)
			(stroke
				(width 0.1)
				(type default)
			)
			(layer "B.Fab")
		)
		(fp_line
			(start -0.12065 -0.2794)
			(end -0.12065 -0.3048)
			(stroke
				(width 0.1)
				(type default)
			)
			(layer "B.Fab")
		)
		(fp_line
			(start 0.12065 -0.2794)
			(end -0.12065 -0.2794)
			(stroke
				(width 0.1)
				(type default)
			)
			(layer "B.Fab")
		)
		(fp_line
			(start -0.67945 -0.3048)
			(end -0.67945 0.3048)
			(stroke
				(width 0.1)
				(type default)
			)
			(layer "B.Fab")
		)
		(fp_line
			(start -0.12065 -0.3048)
			(end -0.67945 -0.3048)
			(stroke
				(width 0.1)
				(type default)
			)
			(layer "B.Fab")
		)
		(fp_line
			(start 0.12065 -0.305054)
			(end 0.12065 -0.2794)
			(stroke
				(width 0.1)
				(type default)
			)
			(layer "B.Fab")
		)
		(fp_line
			(start 0.67945 -0.305054)
			(end 0.12065 -0.305054)
			(stroke
				(width 0.1)
				(type default)
			)
			(layer "B.Fab")
		)
		(pad "1" smd circle
			(at 0.40005 0 90)
			(size 0 0)
			(layers "B.Cu" "B.Mask" "B.Paste")
			(net "E1S_0_P3V3_ADC_ALERT_R")
		)
		(pad "2" smd circle
			(at -0.40005 0 90)
			(size 0 0)
			(layers "B.Cu" "B.Mask" "B.Paste")
			(net "E1S_0_P3V3_P12V_ADC_R_ALERT")
		)
	)
	(footprint ""
		(layer "B.Cu")
		(at 291.578538 -426.06087 -90)
		(property "Reference" "R2706"
			(at 0 0 90)
			(layer "B.SilkS")
			(hide yes)
			(effects
				(font
					(size 1.27 1.27)
				)
				(justify mirror)
			)
		)
		(property "Value" ""
			(at 0 0 90)
			(layer "B.Fab")
			(effects
				(font
					(size 1.27 1.27)
				)
				(justify mirror)
			)
		)
		(duplicate_pad_numbers_are_jumpers no)
		(fp_line
			(start -0.7874 0.4064)
			(end 0.7874 0.4064)
			(stroke
				(width 0.1524)
				(type default)
			)
			(layer "B.SilkS")
		)
		(fp_line
			(start 0.7874 0.4064)
			(end 0.7874 -0.4064)
			(stroke
				(width 0.1524)
				(type default)
			)
			(layer "B.SilkS")
		)
		(fp_line
			(start -0.7874 -0.4064)
			(end -0.7874 0.4064)
			(stroke
				(width 0.1524)
				(type default)
			)
			(layer "B.SilkS")
		)
		(fp_line
			(start 0.7874 -0.4064)
			(end -0.7874 -0.4064)
			(stroke
				(width 0.1524)
				(type default)
			)
			(layer "B.SilkS")
		)
		(fp_line
			(start -0.67945 0.3048)
			(end -0.120396 0.3048)
			(stroke
				(width 0.1)
				(type default)
			)
			(layer "B.Fab")
		)
		(fp_line
			(start -0.120396 0.3048)
			(end -0.120396 0.2794)
			(stroke
				(width 0.1)
				(type default)
			)
			(layer "B.Fab")
		)
		(fp_line
			(start 0.12065 0.3048)
			(end 0.67945 0.3048)
			(stroke
				(width 0.1)
				(type default)
			)
			(layer "B.Fab")
		)
		(fp_line
			(start 0.67945 0.3048)
			(end 0.67945 -0.305054)
			(stroke
				(width 0.1)
				(type default)
			)
			(layer "B.Fab")
		)
		(fp_line
			(start -0.120396 0.2794)
			(end 0.12065 0.2794)
			(stroke
				(width 0.1)
				(type default)
			)
			(layer "B.Fab")
		)
		(fp_line
			(start 0.12065 0.2794)
			(end 0.12065 0.3048)
			(stroke
				(width 0.1)
				(type default)
			)
			(layer "B.Fab")
		)
		(fp_line
			(start -0.12065 -0.2794)
			(end -0.12065 -0.3048)
			(stroke
				(width 0.1)
				(type default)
			)
			(layer "B.Fab")
		)
		(fp_line
			(start 0.12065 -0.2794)
			(end -0.12065 -0.2794)
			(stroke
				(width 0.1)
				(type default)
			)
			(layer "B.Fab")
		)
		(fp_line
			(start -0.67945 -0.3048)
			(end -0.67945 0.3048)
			(stroke
				(width 0.1)
				(type default)
			)
			(layer "B.Fab")
		)
		(fp_line
			(start -0.12065 -0.3048)
			(end -0.67945 -0.3048)
			(stroke
				(width 0.1)
				(type default)
			)
			(layer "B.Fab")
		)
		(fp_line
			(start 0.12065 -0.305054)
			(end 0.12065 -0.2794)
			(stroke
				(width 0.1)
				(type default)
			)
			(layer "B.Fab")
		)
		(fp_line
			(start 0.67945 -0.305054)
			(end 0.12065 -0.305054)
			(stroke
				(width 0.1)
				(type default)
			)
			(layer "B.Fab")
		)
		(pad "1" smd circle
			(at 0.40005 0 90)
			(size 0 0)
			(layers "B.Cu" "B.Mask" "B.Paste")
			(net "I3C_BMC_SWB_R_SDA")
		)
		(pad "2" smd circle
			(at -0.40005 0 90)
			(size 0 0)
			(layers "B.Cu" "B.Mask" "B.Paste")
			(net "I3C_BMC_SWB_BUF_R_SDA")
		)
	)
	(footprint ""
		(layer "B.Cu")
		(at 408.124914 -389.49503 180)
		(property "Reference" "C7015"
			(at -1.360932 -3.149092 0)
			(unlocked yes)
			(layer "B.SilkS")
			(effects
				(font
					(size 0.7874 0.5842)
					(thickness 0.1524)
				)
				(justify left mirror)
			)
		)
		(property "Value" ""
			(at 0 0 0)
			(layer "B.Fab")
			(effects
				(font
					(size 1.27 1.27)
				)
				(justify mirror)
			)
		)
		(duplicate_pad_numbers_are_jumpers no)
		(fp_line
			(start 4.84378 -2.150618)
			(end 4.842256 2.163064)
			(stroke
				(width 0.1524)
				(type default)
			)
			(layer "B.SilkS")
		)
		(fp_line
			(start 4.84378 -2.150618)
			(end 4.53898 -2.150618)
			(stroke
				(width 0.1524)
				(type default)
			)
			(layer "B.SilkS")
		)
		(fp_line
			(start 4.83108 2.150364)
			(end 4.447794 2.149348)
			(stroke
				(width 0.1524)
				(type default)
			)
			(layer "B.SilkS")
		)
		(fp_line
			(start 4.69138 -2.150618)
			(end 4.692396 2.161032)
			(stroke
				(width 0.1524)
				(type default)
			)
			(layer "B.SilkS")
		)
		(fp_line
			(start 4.53898 2.15011)
			(end 4.53898 -2.15011)
			(stroke
				(width 0.1524)
				(type default)
			)
			(layer "B.SilkS")
		)
		(fp_line
			(start 4.53898 -2.15011)
			(end -4.53898 -2.15011)
			(stroke
				(width 0.1524)
				(type default)
			)
			(layer "B.SilkS")
		)
		(fp_line
			(start 4.53898 -2.150618)
			(end 4.539742 2.152142)
			(stroke
				(width 0.1524)
				(type default)
			)
			(layer "B.SilkS")
		)
		(fp_line
			(start -4.53898 2.15011)
			(end 4.53898 2.15011)
			(stroke
				(width 0.1524)
				(type default)
			)
			(layer "B.SilkS")
		)
		(fp_line
			(start -4.53898 -2.15011)
			(end -4.53898 2.15011)
			(stroke
				(width 0.1524)
				(type default)
			)
			(layer "B.SilkS")
		)
		(fp_line
			(start 3.64998 2.15011)
			(end 3.64998 -2.15011)
			(stroke
				(width 0.1)
				(type default)
			)
			(layer "B.Fab")
		)
		(fp_line
			(start 3.64998 -2.15011)
			(end -3.64998 -2.15011)
			(stroke
				(width 0.1)
				(type default)
			)
			(layer "B.Fab")
		)
		(fp_line
			(start -3.64998 2.15011)
			(end 3.64998 2.15011)
			(stroke
				(width 0.1)
				(type default)
			)
			(layer "B.Fab")
		)
		(fp_line
			(start -3.64998 -2.15011)
			(end -3.64998 2.15011)
			(stroke
				(width 0.1)
				(type default)
			)
			(layer "B.Fab")
		)
		(fp_text user "+"
			(at 4.444492 -3.049778 180)
			(unlocked yes)
			(layer "B.SilkS")
			(effects
				(font
					(size 1.905 1.4224)
					(thickness 0.1524)
				)
				(justify left mirror)
			)
		)
		(fp_text user "-"
			(at -2.781554 -2.878328 180)
			(unlocked yes)
			(layer "B.SilkS")
			(effects
				(font
					(size 1.905 1.4224)
					(thickness 0.1524)
				)
				(justify left mirror)
			)
		)
		(fp_text user "+"
			(at 6.214872 -0.337058 180)
			(unlocked yes)
			(layer "B.Fab")
			(effects
				(font
					(size 1.905 1.4224)
					(thickness 0.1524)
				)
				(justify left mirror)
			)
		)
		(fp_text user "-"
			(at -4.313174 -0.094488 180)
			(unlocked yes)
			(layer "B.Fab")
			(effects
				(font
					(size 1.905 1.4224)
					(thickness 0.1524)
				)
				(justify left mirror)
			)
		)
		(pad "1" smd rect
			(at 3.199892 0)
			(size 2.413 2.8194)
			(layers "B.Cu" "B.Mask" "B.Paste")
			(net "P0V9_CPU0_RT2_2A")
		)
		(pad "2" smd rect
			(at -3.199892 0)
			(size 2.413 2.8194)
			(layers "B.Cu" "B.Mask" "B.Paste")
			(net "GND")
		)
	)
	(footprint ""
		(layer "B.Cu")
		(at 504.058428 7.571994 90)
		(property "Reference" "X8025"
			(at 0.93726 -1.53035 270)
			(unlocked yes)
			(layer "B.SilkS")
			(effects
				(font
					(size 0.7874 0.5842)
					(thickness 0.1524)
				)
				(justify left mirror)
			)
		)
		(property "Value" ""
			(at 0 0 90)
			(layer "B.Fab")
			(effects
				(font
					(size 1.27 1.27)
				)
				(justify mirror)
			)
		)
		(property "Device Type" "TP_TDR_4P_FTS_TH-TP_TDR_4P_DIP,EMPTY,TP15"
			(at -1.30175 1.27 0)
			(unlocked yes)
			(layer "B.Fab")
			(hide yes)
			(effects
				(font
					(size 0.635 0.4064)
					(thickness 0.1524)
				)
				(justify mirror)
			)
		)
		(property "User Part Number" "N_A"
			(at -1.30175 1.27 0)
			(unlocked yes)
			(layer "Cmts.User")
			(hide yes)
			(effects
				(font
					(size 0.635 0.4064)
					(thickness 0.1524)
				)
				(justify mirror)
			)
		)
		(duplicate_pad_numbers_are_jumpers no)
		(fp_line
			(start 0 -1.27)
			(end 0 -0.635)
			(stroke
				(width 0.1524)
				(type default)
			)
			(layer "B.SilkS")
		)
		(fp_line
			(start -2.54 -1.27)
			(end 0 -1.27)
			(stroke
				(width 0.1524)
				(type default)
			)
			(layer "B.SilkS")
		)
		(fp_line
			(start -2.54 -1.1303)
			(end -2.54 -1.27)
			(stroke
				(width 0.1524)
				(type default)
			)
			(layer "B.SilkS")
		)
		(fp_line
			(start 0 0.635)
			(end 0 1.905)
			(stroke
				(width 0.1524)
				(type default)
			)
			(layer "B.SilkS")
		)
		(fp_line
			(start -2.54 1.4097)
			(end -2.54 1.1303)
			(stroke
				(width 0.1524)
				(type default)
			)
			(layer "B.SilkS")
		)
		(fp_line
			(start 0 3.175)
			(end 0 3.81)
			(stroke
				(width 0.1524)
				(type default)
			)
			(layer "B.SilkS")
		)
		(fp_line
			(start 0 3.81)
			(end -2.54 3.81)
			(stroke
				(width 0.1524)
				(type default)
			)
			(layer "B.SilkS")
		)
		(fp_line
			(start -2.54 3.81)
			(end -2.54 3.6703)
			(stroke
				(width 0.1524)
				(type default)
			)
			(layer "B.SilkS")
		)
		(fp_poly
			(pts
				(xy 0.761746 0) (xy 2.285746 -0.762) (xy 2.285746 0.762)
			)
			(stroke
				(width 0)
				(type default)
			)
			(fill yes)
			(layer "B.SilkS")
		)
		(fp_line
			(start 0 -1.27)
			(end 0 3.81)
			(stroke
				(width 0.1)
				(type default)
			)
			(layer "B.Fab")
		)
		(fp_line
			(start -2.54 -1.27)
			(end 0 -1.27)
			(stroke
				(width 0.1)
				(type default)
			)
			(layer "B.Fab")
		)
		(fp_line
			(start 0 3.81)
			(end -2.54 3.81)
			(stroke
				(width 0.1)
				(type default)
			)
			(layer "B.Fab")
		)
		(fp_line
			(start -2.54 3.81)
			(end -2.54 -1.27)
			(stroke
				(width 0.1)
				(type default)
			)
			(layer "B.Fab")
		)
		(fp_poly
			(pts
				(xy 0.761746 0) (xy 2.285746 -0.762) (xy 2.285746 0.762)
			)
			(stroke
				(width 0)
				(type default)
			)
			(fill yes)
			(layer "B.Fab")
		)
		(pad "1" thru_hole circle
			(at 0 0 270)
			(size 1.0033 1.0033)
			(drill 0.249936)
			(layers "*.Cu" "*.Mask")
			(remove_unused_layers no)
			(net "TDR_DIFF_85_IN5_DP")
			(clearance 0.10795)
			(padstack
				(mode front_inner_back)
				(layer "Inner"
					(shape circle)
					(size 0.8001 0.8001)
					(clearance 0.1524)
				)
				(layer "B.Cu"
					(shape circle)
					(size 1.0033 1.0033)
					(thermal_gap 0.10795)
					(clearance 0.10795)
				)
			)
		)
		(pad "2" thru_hole circle
			(at -2.54 0 270)
			(size 1.9939 1.9939)
			(drill 0.249936)
			(layers "*.Cu" "*.Mask")
			(remove_unused_layers no)
			(net "T1_GND")
			(clearance 0.10795)
			(padstack
				(mode front_inner_back)
				(layer "Inner"
					(shape circle)
					(size 0.8001 0.8001)
					(clearance 0.1524)
				)
				(layer "B.Cu"
					(shape circle)
					(size 1.9939 1.9939)
					(thermal_gap 0.10795)
					(clearance 0.10795)
				)
			)
		)
		(pad "3" thru_hole circle
			(at -2.54 2.54 270)
			(size 1.9939 1.9939)
			(drill 0.249936)
			(layers "*.Cu" "*.Mask")
			(remove_unused_layers no)
			(net "T1_GND")
			(clearance 0.10795)
			(padstack
				(mode front_inner_back)
				(layer "Inner"
					(shape circle)
					(size 0.8001 0.8001)
					(clearance 0.1524)
				)
				(layer "B.Cu"
					(shape circle)
					(size 1.9939 1.9939)
					(thermal_gap 0.10795)
					(clearance 0.10795)
				)
			)
		)
		(pad "4" thru_hole circle
			(at 0 2.54 270)
			(size 1.0033 1.0033)
			(drill 0.249936)
			(layers "*.Cu" "*.Mask")
			(remove_unused_layers no)
			(net "TDR_DIFF_85_IN5_DN")
			(clearance 0.10795)
			(padstack
				(mode front_inner_back)
				(layer "Inner"
					(shape circle)
					(size 0.8001 0.8001)
					(clearance 0.1524)
				)
				(layer "B.Cu"
					(shape circle)
					(size 1.0033 1.0033)
					(thermal_gap 0.10795)
					(clearance 0.10795)
				)
			)
		)
	)
	(footprint ""
		(layer "B.Cu")
		(at 102.253034 -254.504952 -60)
		(property "Reference" "C2421"
			(at 0 0 120)
			(layer "B.SilkS")
			(hide yes)
			(effects
				(font
					(size 1.27 1.27)
				)
				(justify mirror)
			)
		)
		(property "Value" ""
			(at 0 0 120)
			(layer "B.Fab")
			(effects
				(font
					(size 1.27 1.27)
				)
				(justify mirror)
			)
		)
		(duplicate_pad_numbers_are_jumpers no)
		(fp_line
			(start -0.787516 0.406438)
			(end 0.787425 0.40652)
			(stroke
				(width 0.1524)
				(type default)
			)
			(layer "B.SilkS")
		)
		(fp_line
			(start -0.787425 -0.40652)
			(end -0.787516 0.406438)
			(stroke
				(width 0.1524)
				(type default)
			)
			(layer "B.SilkS")
		)
		(fp_line
			(start 0.787425 0.40652)
			(end 0.787516 -0.406438)
			(stroke
				(width 0.1524)
				(type default)
			)
			(layer "B.SilkS")
		)
		(fp_line
			(start 0.787516 -0.406438)
			(end -0.787425 -0.40652)
			(stroke
				(width 0.1524)
				(type default)
			)
			(layer "B.SilkS")
		)
		(fp_line
			(start -0.679568 0.304811)
			(end -0.120258 0.304812)
			(stroke
				(width 0.1)
				(type default)
			)
			(layer "B.Fab")
		)
		(fp_line
			(start -0.120258 0.304812)
			(end -0.120334 0.279545)
			(stroke
				(width 0.1)
				(type default)
			)
			(layer "B.Fab")
		)
		(fp_line
			(start -0.120334 0.279545)
			(end 0.120587 0.279326)
			(stroke
				(width 0.1)
				(type default)
			)
			(layer "B.Fab")
		)
		(fp_line
			(start 0.120536 0.304813)
			(end 0.6795 0.304908)
			(stroke
				(width 0.1)
				(type default)
			)
			(layer "B.Fab")
		)
		(fp_line
			(start 0.120587 0.279326)
			(end 0.120536 0.304813)
			(stroke
				(width 0.1)
				(type default)
			)
			(layer "B.Fab")
		)
		(fp_line
			(start -0.6795 -0.304908)
			(end -0.679568 0.304811)
			(stroke
				(width 0.1)
				(type default)
			)
			(layer "B.Fab")
		)
		(fp_line
			(start 0.6795 0.304908)
			(end 0.679475 -0.305158)
			(stroke
				(width 0.1)
				(type default)
			)
			(layer "B.Fab")
		)
		(fp_line
			(start -0.120587 -0.279326)
			(end -0.120536 -0.304813)
			(stroke
				(width 0.1)
				(type default)
			)
			(layer "B.Fab")
		)
		(fp_line
			(start -0.120536 -0.304813)
			(end -0.6795 -0.304908)
			(stroke
				(width 0.1)
				(type default)
			)
			(layer "B.Fab")
		)
		(fp_line
			(start 0.120554 -0.279418)
			(end -0.120587 -0.279326)
			(stroke
				(width 0.1)
				(type default)
			)
			(layer "B.Fab")
		)
		(fp_line
			(start 0.120732 -0.305125)
			(end 0.120554 -0.279418)
			(stroke
				(width 0.1)
				(type default)
			)
			(layer "B.Fab")
		)
		(fp_line
			(start 0.679475 -0.305158)
			(end 0.120732 -0.305125)
			(stroke
				(width 0.1)
				(type default)
			)
			(layer "B.Fab")
		)
		(pad "1" smd circle
			(at 0.40005 0 120)
			(size 0 0)
			(layers "B.Cu" "B.Mask" "B.Paste")
			(net "PVDDCR_SOC_P1")
		)
		(pad "2" smd circle
			(at -0.40005 0 120)
			(size 0 0)
			(layers "B.Cu" "B.Mask" "B.Paste")
			(net "GND")
		)
	)
	(footprint ""
		(layer "B.Cu")
		(at 99.100386 -255.845564 180)
		(property "Reference" "C2293"
			(at 0 0 0)
			(layer "B.SilkS")
			(hide yes)
			(effects
				(font
					(size 1.27 1.27)
				)
				(justify mirror)
			)
		)
		(property "Value" ""
			(at 0 0 0)
			(layer "B.Fab")
			(effects
				(font
					(size 1.27 1.27)
				)
				(justify mirror)
			)
		)
		(duplicate_pad_numbers_are_jumpers no)
		(fp_line
			(start 0.7874 0.4064)
			(end 0.7874 -0.4064)
			(stroke
				(width 0.1524)
				(type default)
			)
			(layer "B.SilkS")
		)
		(fp_line
			(start 0.7874 -0.4064)
			(end -0.7874 -0.4064)
			(stroke
				(width 0.1524)
				(type default)
			)
			(layer "B.SilkS")
		)
		(fp_line
			(start -0.7874 0.4064)
			(end 0.7874 0.4064)
			(stroke
				(width 0.1524)
				(type default)
			)
			(layer "B.SilkS")
		)
		(fp_line
			(start -0.7874 -0.4064)
			(end -0.7874 0.4064)
			(stroke
				(width 0.1524)
				(type default)
			)
			(layer "B.SilkS")
		)
		(fp_line
			(start 0.67945 0.3048)
			(end 0.67945 -0.305054)
			(stroke
				(width 0.1)
				(type default)
			)
			(layer "B.Fab")
		)
		(fp_line
			(start 0.67945 -0.305054)
			(end 0.12065 -0.305054)
			(stroke
				(width 0.1)
				(type default)
			)
			(layer "B.Fab")
		)
		(fp_line
			(start 0.12065 0.3048)
			(end 0.67945 0.3048)
			(stroke
				(width 0.1)
				(type default)
			)
			(layer "B.Fab")
		)
		(fp_line
			(start 0.12065 0.2794)
			(end 0.12065 0.3048)
			(stroke
				(width 0.1)
				(type default)
			)
			(layer "B.Fab")
		)
		(fp_line
			(start 0.12065 -0.2794)
			(end -0.12065 -0.2794)
			(stroke
				(width 0.1)
				(type default)
			)
			(layer "B.Fab")
		)
		(fp_line
			(start 0.12065 -0.305054)
			(end 0.12065 -0.2794)
			(stroke
				(width 0.1)
				(type default)
			)
			(layer "B.Fab")
		)
		(fp_line
			(start -0.120396 0.3048)
			(end -0.120396 0.2794)
			(stroke
				(width 0.1)
				(type default)
			)
			(layer "B.Fab")
		)
		(fp_line
			(start -0.120396 0.2794)
			(end 0.12065 0.2794)
			(stroke
				(width 0.1)
				(type default)
			)
			(layer "B.Fab")
		)
		(fp_line
			(start -0.12065 -0.2794)
			(end -0.12065 -0.3048)
			(stroke
				(width 0.1)
				(type default)
			)
			(layer "B.Fab")
		)
		(fp_line
			(start -0.12065 -0.3048)
			(end -0.67945 -0.3048)
			(stroke
				(width 0.1)
				(type default)
			)
			(layer "B.Fab")
		)
		(fp_line
			(start -0.67945 0.3048)
			(end -0.120396 0.3048)
			(stroke
				(width 0.1)
				(type default)
			)
			(layer "B.Fab")
		)
		(fp_line
			(start -0.67945 -0.3048)
			(end -0.67945 0.3048)
			(stroke
				(width 0.1)
				(type default)
			)
			(layer "B.Fab")
		)
		(pad "1" smd circle
			(at 0.40005 0)
			(size 0 0)
			(layers "B.Cu" "B.Mask" "B.Paste")
			(net "PVDD18_S5_P1")
		)
		(pad "2" smd circle
			(at -0.40005 0)
			(size 0 0)
			(layers "B.Cu" "B.Mask" "B.Paste")
			(net "GND")
		)
	)
	(footprint ""
		(layer "B.Cu")
		(at 333.627476 -396.991078 90)
		(property "Reference" "C616"
			(at 0 0 90)
			(layer "B.SilkS")
			(hide yes)
			(effects
				(font
					(size 1.27 1.27)
				)
				(justify mirror)
			)
		)
		(property "Value" ""
			(at 0 0 90)
			(layer "B.Fab")
			(effects
				(font
					(size 1.27 1.27)
				)
				(justify mirror)
			)
		)
		(duplicate_pad_numbers_are_jumpers no)
		(fp_line
			(start 0.299974 -0.150114)
			(end -0.299974 -0.150114)
			(stroke
				(width 0.1)
				(type default)
			)
			(layer "B.Fab")
		)
		(fp_line
			(start -0.299974 -0.150114)
			(end -0.299974 0.150114)
			(stroke
				(width 0.1)
				(type default)
			)
			(layer "B.Fab")
		)
		(fp_line
			(start 0.299974 0.150114)
			(end 0.299974 -0.150114)
			(stroke
				(width 0.1)
				(type default)
			)
			(layer "B.Fab")
		)
		(fp_line
			(start -0.299974 0.150114)
			(end 0.299974 0.150114)
			(stroke
				(width 0.1)
				(type default)
			)
			(layer "B.Fab")
		)
		(pad "1" smd rect
			(at 0.2667 0 270)
			(size 0.3048 0.381)
			(layers "B.Cu" "B.Mask" "B.Paste")
			(net "P0V9_CPU0_RT1_2A")
		)
		(pad "2" smd rect
			(at -0.2667 0 270)
			(size 0.3048 0.381)
			(layers "B.Cu" "B.Mask" "B.Paste")
			(net "GND")
		)
	)
	(footprint ""
		(layer "B.Cu")
		(at 323.386958 -203.917296 -90)
		(property "Reference" "R396"
			(at 0 0 90)
			(layer "B.SilkS")
			(hide yes)
			(effects
				(font
					(size 1.27 1.27)
				)
				(justify mirror)
			)
		)
		(property "Value" ""
			(at 0 0 90)
			(layer "B.Fab")
			(effects
				(font
					(size 1.27 1.27)
				)
				(justify mirror)
			)
		)
		(duplicate_pad_numbers_are_jumpers no)
		(fp_line
			(start -0.7874 0.4064)
			(end 0.7874 0.4064)
			(stroke
				(width 0.1524)
				(type default)
			)
			(layer "B.SilkS")
		)
		(fp_line
			(start 0.7874 0.4064)
			(end 0.7874 -0.4064)
			(stroke
				(width 0.1524)
				(type default)
			)
			(layer "B.SilkS")
		)
		(fp_line
			(start -0.7874 -0.4064)
			(end -0.7874 0.4064)
			(stroke
				(width 0.1524)
				(type default)
			)
			(layer "B.SilkS")
		)
		(fp_line
			(start 0.7874 -0.4064)
			(end -0.7874 -0.4064)
			(stroke
				(width 0.1524)
				(type default)
			)
			(layer "B.SilkS")
		)
		(fp_line
			(start -0.67945 0.3048)
			(end -0.120396 0.3048)
			(stroke
				(width 0.1)
				(type default)
			)
			(layer "B.Fab")
		)
		(fp_line
			(start -0.120396 0.3048)
			(end -0.120396 0.2794)
			(stroke
				(width 0.1)
				(type default)
			)
			(layer "B.Fab")
		)
		(fp_line
			(start 0.12065 0.3048)
			(end 0.67945 0.3048)
			(stroke
				(width 0.1)
				(type default)
			)
			(layer "B.Fab")
		)
		(fp_line
			(start 0.67945 0.3048)
			(end 0.67945 -0.305054)
			(stroke
				(width 0.1)
				(type default)
			)
			(layer "B.Fab")
		)
		(fp_line
			(start -0.120396 0.2794)
			(end 0.12065 0.2794)
			(stroke
				(width 0.1)
				(type default)
			)
			(layer "B.Fab")
		)
		(fp_line
			(start 0.12065 0.2794)
			(end 0.12065 0.3048)
			(stroke
				(width 0.1)
				(type default)
			)
			(layer "B.Fab")
		)
		(fp_line
			(start -0.12065 -0.2794)
			(end -0.12065 -0.3048)
			(stroke
				(width 0.1)
				(type default)
			)
			(layer "B.Fab")
		)
		(fp_line
			(start 0.12065 -0.2794)
			(end -0.12065 -0.2794)
			(stroke
				(width 0.1)
				(type default)
			)
			(layer "B.Fab")
		)
		(fp_line
			(start -0.67945 -0.3048)
			(end -0.67945 0.3048)
			(stroke
				(width 0.1)
				(type default)
			)
			(layer "B.Fab")
		)
		(fp_line
			(start -0.12065 -0.3048)
			(end -0.67945 -0.3048)
			(stroke
				(width 0.1)
				(type default)
			)
			(layer "B.Fab")
		)
		(fp_line
			(start 0.12065 -0.305054)
			(end 0.12065 -0.2794)
			(stroke
				(width 0.1)
				(type default)
			)
			(layer "B.Fab")
		)
		(fp_line
			(start 0.67945 -0.305054)
			(end 0.12065 -0.305054)
			(stroke
				(width 0.1)
				(type default)
			)
			(layer "B.Fab")
		)
		(pad "1" smd circle
			(at 0.40005 0 90)
			(size 0 0)
			(layers "B.Cu" "B.Mask" "B.Paste")
			(net "P3V3_AUX")
		)
		(pad "2" smd circle
			(at -0.40005 0 90)
			(size 0 0)
			(layers "B.Cu" "B.Mask" "B.Paste")
			(net "CPU0_SP5R2")
		)
	)
	(footprint ""
		(layer "B.Cu")
		(at 12.234418 -414.37687 90)
		(property "Reference" "PR6808"
			(at 0 0 90)
			(layer "B.SilkS")
			(hide yes)
			(effects
				(font
					(size 1.27 1.27)
				)
				(justify mirror)
			)
		)
		(property "Value" ""
			(at 0 0 90)
			(layer "B.Fab")
			(effects
				(font
					(size 1.27 1.27)
				)
				(justify mirror)
			)
		)
		(duplicate_pad_numbers_are_jumpers no)
		(fp_line
			(start 0.7874 -0.4064)
			(end -0.7874 -0.4064)
			(stroke
				(width 0.1524)
				(type default)
			)
			(layer "B.SilkS")
		)
		(fp_line
			(start -0.7874 -0.4064)
			(end -0.7874 0.4064)
			(stroke
				(width 0.1524)
				(type default)
			)
			(layer "B.SilkS")
		)
		(fp_line
			(start 0.7874 0.4064)
			(end 0.7874 -0.4064)
			(stroke
				(width 0.1524)
				(type default)
			)
			(layer "B.SilkS")
		)
		(fp_line
			(start -0.7874 0.4064)
			(end 0.7874 0.4064)
			(stroke
				(width 0.1524)
				(type default)
			)
			(layer "B.SilkS")
		)
		(fp_line
			(start 0.67945 -0.305054)
			(end 0.12065 -0.305054)
			(stroke
				(width 0.1)
				(type default)
			)
			(layer "B.Fab")
		)
		(fp_line
			(start 0.12065 -0.305054)
			(end 0.12065 -0.2794)
			(stroke
				(width 0.1)
				(type default)
			)
			(layer "B.Fab")
		)
		(fp_line
			(start -0.12065 -0.3048)
			(end -0.67945 -0.3048)
			(stroke
				(width 0.1)
				(type default)
			)
			(layer "B.Fab")
		)
		(fp_line
			(start -0.67945 -0.3048)
			(end -0.67945 0.3048)
			(stroke
				(width 0.1)
				(type default)
			)
			(layer "B.Fab")
		)
		(fp_line
			(start 0.12065 -0.2794)
			(end -0.12065 -0.2794)
			(stroke
				(width 0.1)
				(type default)
			)
			(layer "B.Fab")
		)
		(fp_line
			(start -0.12065 -0.2794)
			(end -0.12065 -0.3048)
			(stroke
				(width 0.1)
				(type default)
			)
			(layer "B.Fab")
		)
		(fp_line
			(start 0.12065 0.2794)
			(end 0.12065 0.3048)
			(stroke
				(width 0.1)
				(type default)
			)
			(layer "B.Fab")
		)
		(fp_line
			(start -0.120396 0.2794)
			(end 0.12065 0.2794)
			(stroke
				(width 0.1)
				(type default)
			)
			(layer "B.Fab")
		)
		(fp_line
			(start 0.67945 0.3048)
			(end 0.67945 -0.305054)
			(stroke
				(width 0.1)
				(type default)
			)
			(layer "B.Fab")
		)
		(fp_line
			(start 0.12065 0.3048)
			(end 0.67945 0.3048)
			(stroke
				(width 0.1)
				(type default)
			)
			(layer "B.Fab")
		)
		(fp_line
			(start -0.120396 0.3048)
			(end -0.120396 0.2794)
			(stroke
				(width 0.1)
				(type default)
			)
			(layer "B.Fab")
		)
		(fp_line
			(start -0.67945 0.3048)
			(end -0.120396 0.3048)
			(stroke
				(width 0.1)
				(type default)
			)
			(layer "B.Fab")
		)
		(pad "1" smd circle
			(at 0.40005 0 270)
			(size 0 0)
			(layers "B.Cu" "B.Mask" "B.Paste")
			(net "P12V_AUX")
		)
		(pad "2" smd circle
			(at -0.40005 0 270)
			(size 0 0)
			(layers "B.Cu" "B.Mask" "B.Paste")
			(net "P0V9_RETIMER_CPU1_VMON")
		)
	)
	(footprint ""
		(layer "B.Cu")
		(at 131.27863 -386.766562 90)
		(property "Reference" "C470"
			(at 0 0 90)
			(layer "B.SilkS")
			(hide yes)
			(effects
				(font
					(size 1.27 1.27)
				)
				(justify mirror)
			)
		)
		(property "Value" ""
			(at 0 0 90)
			(layer "B.Fab")
			(effects
				(font
					(size 1.27 1.27)
				)
				(justify mirror)
			)
		)
		(duplicate_pad_numbers_are_jumpers no)
		(fp_line
			(start 0.299974 -0.150114)
			(end -0.299974 -0.150114)
			(stroke
				(width 0.1)
				(type default)
			)
			(layer "B.Fab")
		)
		(fp_line
			(start -0.299974 -0.150114)
			(end -0.299974 0.150114)
			(stroke
				(width 0.1)
				(type default)
			)
			(layer "B.Fab")
		)
		(fp_line
			(start 0.299974 0.150114)
			(end 0.299974 -0.150114)
			(stroke
				(width 0.1)
				(type default)
			)
			(layer "B.Fab")
		)
		(fp_line
			(start -0.299974 0.150114)
			(end 0.299974 0.150114)
			(stroke
				(width 0.1)
				(type default)
			)
			(layer "B.Fab")
		)
		(pad "1" smd rect
			(at 0.2667 0 270)
			(size 0.3048 0.381)
			(layers "B.Cu" "B.Mask" "B.Paste")
			(net "P0V9_CPU1_RT3_2A")
		)
		(pad "2" smd rect
			(at -0.2667 0 270)
			(size 0.3048 0.381)
			(layers "B.Cu" "B.Mask" "B.Paste")
			(net "GND")
		)
	)
	(footprint ""
		(layer "B.Cu")
		(at 92.992702 -181.616604 90)
		(property "Reference" "PR186"
			(at 0 0 90)
			(layer "B.SilkS")
			(hide yes)
			(effects
				(font
					(size 1.27 1.27)
				)
				(justify mirror)
			)
		)
		(property "Value" ""
			(at 0 0 90)
			(layer "B.Fab")
			(effects
				(font
					(size 1.27 1.27)
				)
				(justify mirror)
			)
		)
		(duplicate_pad_numbers_are_jumpers no)
		(fp_line
			(start 0.7874 -0.4064)
			(end -0.7874 -0.4064)
			(stroke
				(width 0.1524)
				(type default)
			)
			(layer "B.SilkS")
		)
		(fp_line
			(start -0.7874 -0.4064)
			(end -0.7874 0.4064)
			(stroke
				(width 0.1524)
				(type default)
			)
			(layer "B.SilkS")
		)
		(fp_line
			(start 0.7874 0.4064)
			(end 0.7874 -0.4064)
			(stroke
				(width 0.1524)
				(type default)
			)
			(layer "B.SilkS")
		)
		(fp_line
			(start -0.7874 0.4064)
			(end 0.7874 0.4064)
			(stroke
				(width 0.1524)
				(type default)
			)
			(layer "B.SilkS")
		)
		(fp_line
			(start 0.67945 -0.305054)
			(end 0.12065 -0.305054)
			(stroke
				(width 0.1)
				(type default)
			)
			(layer "B.Fab")
		)
		(fp_line
			(start 0.12065 -0.305054)
			(end 0.12065 -0.2794)
			(stroke
				(width 0.1)
				(type default)
			)
			(layer "B.Fab")
		)
		(fp_line
			(start -0.12065 -0.3048)
			(end -0.67945 -0.3048)
			(stroke
				(width 0.1)
				(type default)
			)
			(layer "B.Fab")
		)
		(fp_line
			(start -0.67945 -0.3048)
			(end -0.67945 0.3048)
			(stroke
				(width 0.1)
				(type default)
			)
			(layer "B.Fab")
		)
		(fp_line
			(start 0.12065 -0.2794)
			(end -0.12065 -0.2794)
			(stroke
				(width 0.1)
				(type default)
			)
			(layer "B.Fab")
		)
		(fp_line
			(start -0.12065 -0.2794)
			(end -0.12065 -0.3048)
			(stroke
				(width 0.1)
				(type default)
			)
			(layer "B.Fab")
		)
		(fp_line
			(start 0.12065 0.2794)
			(end 0.12065 0.3048)
			(stroke
				(width 0.1)
				(type default)
			)
			(layer "B.Fab")
		)
		(fp_line
			(start -0.120396 0.2794)
			(end 0.12065 0.2794)
			(stroke
				(width 0.1)
				(type default)
			)
			(layer "B.Fab")
		)
		(fp_line
			(start 0.67945 0.3048)
			(end 0.67945 -0.305054)
			(stroke
				(width 0.1)
				(type default)
			)
			(layer "B.Fab")
		)
		(fp_line
			(start 0.12065 0.3048)
			(end 0.67945 0.3048)
			(stroke
				(width 0.1)
				(type default)
			)
			(layer "B.Fab")
		)
		(fp_line
			(start -0.120396 0.3048)
			(end -0.120396 0.2794)
			(stroke
				(width 0.1)
				(type default)
			)
			(layer "B.Fab")
		)
		(fp_line
			(start -0.67945 0.3048)
			(end -0.120396 0.3048)
			(stroke
				(width 0.1)
				(type default)
			)
			(layer "B.Fab")
		)
		(pad "1" smd circle
			(at 0.40005 0 270)
			(size 0 0)
			(layers "B.Cu" "B.Mask" "B.Paste")
			(net "PVDDCR_CPU0_P1_PVCC")
		)
		(pad "2" smd circle
			(at -0.40005 0 270)
			(size 0 0)
			(layers "B.Cu" "B.Mask" "B.Paste")
			(net "PVDDCR_CPU0_P1_VCC2")
		)
	)
	(footprint ""
		(layer "B.Cu")
		(at 17.999456 -383.028698 -90)
		(property "Reference" "PC6642_2"
			(at 0 0 90)
			(layer "B.SilkS")
			(hide yes)
			(effects
				(font
					(size 1.27 1.27)
				)
				(justify mirror)
			)
		)
		(property "Value" ""
			(at 0 0 90)
			(layer "B.Fab")
			(effects
				(font
					(size 1.27 1.27)
				)
				(justify mirror)
			)
		)
		(duplicate_pad_numbers_are_jumpers no)
		(fp_line
			(start -1.524 0.762)
			(end 1.524 0.762)
			(stroke
				(width 0.1524)
				(type default)
			)
			(layer "B.SilkS")
		)
		(fp_line
			(start 1.524 0.762)
			(end 1.524 -0.762)
			(stroke
				(width 0.1524)
				(type default)
			)
			(layer "B.SilkS")
		)
		(fp_line
			(start -1.524 -0.762)
			(end -1.524 0.762)
			(stroke
				(width 0.1524)
				(type default)
			)
			(layer "B.SilkS")
		)
		(fp_line
			(start 1.524 -0.762)
			(end -1.524 -0.762)
			(stroke
				(width 0.1524)
				(type default)
			)
			(layer "B.SilkS")
		)
		(fp_line
			(start -1.1049 0.724916)
			(end -1.1049 -0.724916)
			(stroke
				(width 0.1)
				(type default)
			)
			(layer "B.Fab")
		)
		(fp_line
			(start 1.1049 0.724916)
			(end -1.1049 0.724916)
			(stroke
				(width 0.1)
				(type default)
			)
			(layer "B.Fab")
		)
		(fp_line
			(start -1.1049 -0.724916)
			(end 1.1049 -0.724916)
			(stroke
				(width 0.1)
				(type default)
			)
			(layer "B.Fab")
		)
		(fp_line
			(start 1.1049 -0.724916)
			(end 1.1049 0.724916)
			(stroke
				(width 0.1)
				(type default)
			)
			(layer "B.Fab")
		)
		(pad "1" smd rect
			(at 0.889 0 270)
			(size 1.016 1.27)
			(layers "B.Cu" "B.Mask" "B.Paste")
			(net "P0V9_CPU1_RT_2D")
		)
		(pad "2" smd rect
			(at -0.889 0 270)
			(size 1.016 1.27)
			(layers "B.Cu" "B.Mask" "B.Paste")
			(net "GND")
		)
	)
	(footprint ""
		(layer "B.Cu")
		(at 229.616 -216.662 180)
		(property "Reference" "R290"
			(at 0 0 0)
			(layer "B.SilkS")
			(hide yes)
			(effects
				(font
					(size 1.27 1.27)
				)
				(justify mirror)
			)
		)
		(property "Value" ""
			(at 0 0 0)
			(layer "B.Fab")
			(effects
				(font
					(size 1.27 1.27)
				)
				(justify mirror)
			)
		)
		(duplicate_pad_numbers_are_jumpers no)
		(fp_line
			(start 0.7874 0.4064)
			(end 0.7874 -0.4064)
			(stroke
				(width 0.1524)
				(type default)
			)
			(layer "B.SilkS")
		)
		(fp_line
			(start 0.7874 -0.4064)
			(end -0.7874 -0.4064)
			(stroke
				(width 0.1524)
				(type default)
			)
			(layer "B.SilkS")
		)
		(fp_line
			(start -0.7874 0.4064)
			(end 0.7874 0.4064)
			(stroke
				(width 0.1524)
				(type default)
			)
			(layer "B.SilkS")
		)
		(fp_line
			(start -0.7874 -0.4064)
			(end -0.7874 0.4064)
			(stroke
				(width 0.1524)
				(type default)
			)
			(layer "B.SilkS")
		)
		(fp_line
			(start 0.67945 0.3048)
			(end 0.67945 -0.305054)
			(stroke
				(width 0.1)
				(type default)
			)
			(layer "B.Fab")
		)
		(fp_line
			(start 0.67945 -0.305054)
			(end 0.12065 -0.305054)
			(stroke
				(width 0.1)
				(type default)
			)
			(layer "B.Fab")
		)
		(fp_line
			(start 0.12065 0.3048)
			(end 0.67945 0.3048)
			(stroke
				(width 0.1)
				(type default)
			)
			(layer "B.Fab")
		)
		(fp_line
			(start 0.12065 0.2794)
			(end 0.12065 0.3048)
			(stroke
				(width 0.1)
				(type default)
			)
			(layer "B.Fab")
		)
		(fp_line
			(start 0.12065 -0.2794)
			(end -0.12065 -0.2794)
			(stroke
				(width 0.1)
				(type default)
			)
			(layer "B.Fab")
		)
		(fp_line
			(start 0.12065 -0.305054)
			(end 0.12065 -0.2794)
			(stroke
				(width 0.1)
				(type default)
			)
			(layer "B.Fab")
		)
		(fp_line
			(start -0.120396 0.3048)
			(end -0.120396 0.2794)
			(stroke
				(width 0.1)
				(type default)
			)
			(layer "B.Fab")
		)
		(fp_line
			(start -0.120396 0.2794)
			(end 0.12065 0.2794)
			(stroke
				(width 0.1)
				(type default)
			)
			(layer "B.Fab")
		)
		(fp_line
			(start -0.12065 -0.2794)
			(end -0.12065 -0.3048)
			(stroke
				(width 0.1)
				(type default)
			)
			(layer "B.Fab")
		)
		(fp_line
			(start -0.12065 -0.3048)
			(end -0.67945 -0.3048)
			(stroke
				(width 0.1)
				(type default)
			)
			(layer "B.Fab")
		)
		(fp_line
			(start -0.67945 0.3048)
			(end -0.120396 0.3048)
			(stroke
				(width 0.1)
				(type default)
			)
			(layer "B.Fab")
		)
		(fp_line
			(start -0.67945 -0.3048)
			(end -0.67945 0.3048)
			(stroke
				(width 0.1)
				(type default)
			)
			(layer "B.Fab")
		)
		(pad "1" smd circle
			(at 0.40005 0)
			(size 0 0)
			(layers "B.Cu" "B.Mask" "B.Paste")
			(net "PVDD11_S3_P0")
		)
		(pad "2" smd circle
			(at -0.40005 0)
			(size 0 0)
			(layers "B.Cu" "B.Mask" "B.Paste")
			(net "SMB_CPU0_CPU1_APML_BUF2_SDA_R2")
		)
	)
	(footprint ""
		(layer "B.Cu")
		(at 137.928604 -64.036702 -90)
		(property "Reference" "R6090"
			(at 0 0 90)
			(layer "B.SilkS")
			(hide yes)
			(effects
				(font
					(size 1.27 1.27)
				)
				(justify mirror)
			)
		)
		(property "Value" ""
			(at 0 0 90)
			(layer "B.Fab")
			(effects
				(font
					(size 1.27 1.27)
				)
				(justify mirror)
			)
		)
		(duplicate_pad_numbers_are_jumpers no)
		(fp_line
			(start -0.7874 0.4064)
			(end 0.7874 0.4064)
			(stroke
				(width 0.1524)
				(type default)
			)
			(layer "B.SilkS")
		)
		(fp_line
			(start 0.7874 0.4064)
			(end 0.7874 -0.4064)
			(stroke
				(width 0.1524)
				(type default)
			)
			(layer "B.SilkS")
		)
		(fp_line
			(start -0.7874 -0.4064)
			(end -0.7874 0.4064)
			(stroke
				(width 0.1524)
				(type default)
			)
			(layer "B.SilkS")
		)
		(fp_line
			(start 0.7874 -0.4064)
			(end -0.7874 -0.4064)
			(stroke
				(width 0.1524)
				(type default)
			)
			(layer "B.SilkS")
		)
		(fp_line
			(start -0.67945 0.3048)
			(end -0.120396 0.3048)
			(stroke
				(width 0.1)
				(type default)
			)
			(layer "B.Fab")
		)
		(fp_line
			(start -0.120396 0.3048)
			(end -0.120396 0.2794)
			(stroke
				(width 0.1)
				(type default)
			)
			(layer "B.Fab")
		)
		(fp_line
			(start 0.12065 0.3048)
			(end 0.67945 0.3048)
			(stroke
				(width 0.1)
				(type default)
			)
			(layer "B.Fab")
		)
		(fp_line
			(start 0.67945 0.3048)
			(end 0.67945 -0.305054)
			(stroke
				(width 0.1)
				(type default)
			)
			(layer "B.Fab")
		)
		(fp_line
			(start -0.120396 0.2794)
			(end 0.12065 0.2794)
			(stroke
				(width 0.1)
				(type default)
			)
			(layer "B.Fab")
		)
		(fp_line
			(start 0.12065 0.2794)
			(end 0.12065 0.3048)
			(stroke
				(width 0.1)
				(type default)
			)
			(layer "B.Fab")
		)
		(fp_line
			(start -0.12065 -0.2794)
			(end -0.12065 -0.3048)
			(stroke
				(width 0.1)
				(type default)
			)
			(layer "B.Fab")
		)
		(fp_line
			(start 0.12065 -0.2794)
			(end -0.12065 -0.2794)
			(stroke
				(width 0.1)
				(type default)
			)
			(layer "B.Fab")
		)
		(fp_line
			(start -0.67945 -0.3048)
			(end -0.67945 0.3048)
			(stroke
				(width 0.1)
				(type default)
			)
			(layer "B.Fab")
		)
		(fp_line
			(start -0.12065 -0.3048)
			(end -0.67945 -0.3048)
			(stroke
				(width 0.1)
				(type default)
			)
			(layer "B.Fab")
		)
		(fp_line
			(start 0.12065 -0.305054)
			(end 0.12065 -0.2794)
			(stroke
				(width 0.1)
				(type default)
			)
			(layer "B.Fab")
		)
		(fp_line
			(start 0.67945 -0.305054)
			(end 0.12065 -0.305054)
			(stroke
				(width 0.1)
				(type default)
			)
			(layer "B.Fab")
		)
		(pad "1" smd circle
			(at 0.40005 0 90)
			(size 0 0)
			(layers "B.Cu" "B.Mask" "B.Paste")
			(net "JTAG_SCM_PLD_TCK")
		)
		(pad "2" smd circle
			(at -0.40005 0 90)
			(size 0 0)
			(layers "B.Cu" "B.Mask" "B.Paste")
			(net "GND")
		)
	)
	(footprint ""
		(layer "B.Cu")
		(at 193.929 -100.294948 90)
		(property "Reference" "R1304"
			(at 0 0 90)
			(layer "B.SilkS")
			(hide yes)
			(effects
				(font
					(size 1.27 1.27)
				)
				(justify mirror)
			)
		)
		(property "Value" ""
			(at 0 0 90)
			(layer "B.Fab")
			(effects
				(font
					(size 1.27 1.27)
				)
				(justify mirror)
			)
		)
		(duplicate_pad_numbers_are_jumpers no)
		(fp_line
			(start 0.7874 -0.4064)
			(end -0.7874 -0.4064)
			(stroke
				(width 0.1524)
				(type default)
			)
			(layer "B.SilkS")
		)
		(fp_line
			(start -0.7874 -0.4064)
			(end -0.7874 0.4064)
			(stroke
				(width 0.1524)
				(type default)
			)
			(layer "B.SilkS")
		)
		(fp_line
			(start 0.7874 0.4064)
			(end 0.7874 -0.4064)
			(stroke
				(width 0.1524)
				(type default)
			)
			(layer "B.SilkS")
		)
		(fp_line
			(start -0.7874 0.4064)
			(end 0.7874 0.4064)
			(stroke
				(width 0.1524)
				(type default)
			)
			(layer "B.SilkS")
		)
		(fp_line
			(start 0.67945 -0.305054)
			(end 0.12065 -0.305054)
			(stroke
				(width 0.1)
				(type default)
			)
			(layer "B.Fab")
		)
		(fp_line
			(start 0.12065 -0.305054)
			(end 0.12065 -0.2794)
			(stroke
				(width 0.1)
				(type default)
			)
			(layer "B.Fab")
		)
		(fp_line
			(start -0.12065 -0.3048)
			(end -0.67945 -0.3048)
			(stroke
				(width 0.1)
				(type default)
			)
			(layer "B.Fab")
		)
		(fp_line
			(start -0.67945 -0.3048)
			(end -0.67945 0.3048)
			(stroke
				(width 0.1)
				(type default)
			)
			(layer "B.Fab")
		)
		(fp_line
			(start 0.12065 -0.2794)
			(end -0.12065 -0.2794)
			(stroke
				(width 0.1)
				(type default)
			)
			(layer "B.Fab")
		)
		(fp_line
			(start -0.12065 -0.2794)
			(end -0.12065 -0.3048)
			(stroke
				(width 0.1)
				(type default)
			)
			(layer "B.Fab")
		)
		(fp_line
			(start 0.12065 0.2794)
			(end 0.12065 0.3048)
			(stroke
				(width 0.1)
				(type default)
			)
			(layer "B.Fab")
		)
		(fp_line
			(start -0.120396 0.2794)
			(end 0.12065 0.2794)
			(stroke
				(width 0.1)
				(type default)
			)
			(layer "B.Fab")
		)
		(fp_line
			(start 0.67945 0.3048)
			(end 0.67945 -0.305054)
			(stroke
				(width 0.1)
				(type default)
			)
			(layer "B.Fab")
		)
		(fp_line
			(start 0.12065 0.3048)
			(end 0.67945 0.3048)
			(stroke
				(width 0.1)
				(type default)
			)
			(layer "B.Fab")
		)
		(fp_line
			(start -0.120396 0.3048)
			(end -0.120396 0.2794)
			(stroke
				(width 0.1)
				(type default)
			)
			(layer "B.Fab")
		)
		(fp_line
			(start -0.67945 0.3048)
			(end -0.120396 0.3048)
			(stroke
				(width 0.1)
				(type default)
			)
			(layer "B.Fab")
		)
		(pad "1" smd circle
			(at 0.40005 0 270)
			(size 0 0)
			(layers "B.Cu" "B.Mask" "B.Paste")
			(net "E1S_0_PRSNT_N")
		)
		(pad "2" smd circle
			(at -0.40005 0 270)
			(size 0 0)
			(layers "B.Cu" "B.Mask" "B.Paste")
			(net "P3V3_AUX")
		)
	)
	(footprint ""
		(layer "B.Cu")
		(at 51.328574 -422.777666)
		(property "Reference" "R3511"
			(at 0 0 0)
			(layer "B.SilkS")
			(hide yes)
			(effects
				(font
					(size 1.27 1.27)
				)
				(justify mirror)
			)
		)
		(property "Value" ""
			(at 0 0 0)
			(layer "B.Fab")
			(effects
				(font
					(size 1.27 1.27)
				)
				(justify mirror)
			)
		)
		(duplicate_pad_numbers_are_jumpers no)
		(fp_line
			(start -0.7874 -0.4064)
			(end -0.7874 0.4064)
			(stroke
				(width 0.1524)
				(type default)
			)
			(layer "B.SilkS")
		)
		(fp_line
			(start -0.7874 0.4064)
			(end 0.7874 0.4064)
			(stroke
				(width 0.1524)
				(type default)
			)
			(layer "B.SilkS")
		)
		(fp_line
			(start 0.7874 -0.4064)
			(end -0.7874 -0.4064)
			(stroke
				(width 0.1524)
				(type default)
			)
			(layer "B.SilkS")
		)
		(fp_line
			(start 0.7874 0.4064)
			(end 0.7874 -0.4064)
			(stroke
				(width 0.1524)
				(type default)
			)
			(layer "B.SilkS")
		)
		(fp_line
			(start -0.67945 -0.3048)
			(end -0.67945 0.3048)
			(stroke
				(width 0.1)
				(type default)
			)
			(layer "B.Fab")
		)
		(fp_line
			(start -0.67945 0.3048)
			(end -0.120396 0.3048)
			(stroke
				(width 0.1)
				(type default)
			)
			(layer "B.Fab")
		)
		(fp_line
			(start -0.12065 -0.3048)
			(end -0.67945 -0.3048)
			(stroke
				(width 0.1)
				(type default)
			)
			(layer "B.Fab")
		)
		(fp_line
			(start -0.12065 -0.2794)
			(end -0.12065 -0.3048)
			(stroke
				(width 0.1)
				(type default)
			)
			(layer "B.Fab")
		)
		(fp_line
			(start -0.120396 0.2794)
			(end 0.12065 0.2794)
			(stroke
				(width 0.1)
				(type default)
			)
			(layer "B.Fab")
		)
		(fp_line
			(start -0.120396 0.3048)
			(end -0.120396 0.2794)
			(stroke
				(width 0.1)
				(type default)
			)
			(layer "B.Fab")
		)
		(fp_line
			(start 0.12065 -0.305054)
			(end 0.12065 -0.2794)
			(stroke
				(width 0.1)
				(type default)
			)
			(layer "B.Fab")
		)
		(fp_line
			(start 0.12065 -0.2794)
			(end -0.12065 -0.2794)
			(stroke
				(width 0.1)
				(type default)
			)
			(layer "B.Fab")
		)
		(fp_line
			(start 0.12065 0.2794)
			(end 0.12065 0.3048)
			(stroke
				(width 0.1)
				(type default)
			)
			(layer "B.Fab")
		)
		(fp_line
			(start 0.12065 0.3048)
			(end 0.67945 0.3048)
			(stroke
				(width 0.1)
				(type default)
			)
			(layer "B.Fab")
		)
		(fp_line
			(start 0.67945 -0.305054)
			(end 0.12065 -0.305054)
			(stroke
				(width 0.1)
				(type default)
			)
			(layer "B.Fab")
		)
		(fp_line
			(start 0.67945 0.3048)
			(end 0.67945 -0.305054)
			(stroke
				(width 0.1)
				(type default)
			)
			(layer "B.Fab")
		)
		(pad "1" smd circle
			(at 0.40005 0 180)
			(size 0 0)
			(layers "B.Cu" "B.Mask" "B.Paste")
			(net "GPU_FPGA_READY")
		)
		(pad "2" smd circle
			(at -0.40005 0 180)
			(size 0 0)
			(layers "B.Cu" "B.Mask" "B.Paste")
			(net "GND")
		)
	)
	(footprint ""
		(layer "B.Cu")
		(at 383.69113 -398.942052 90)
		(property "Reference" "C1034"
			(at 0 0 90)
			(layer "B.SilkS")
			(hide yes)
			(effects
				(font
					(size 1.27 1.27)
				)
				(justify mirror)
			)
		)
		(property "Value" ""
			(at 0 0 90)
			(layer "B.Fab")
			(effects
				(font
					(size 1.27 1.27)
				)
				(justify mirror)
			)
		)
		(duplicate_pad_numbers_are_jumpers no)
		(fp_line
			(start 0.7874 -0.4064)
			(end -0.7874 -0.4064)
			(stroke
				(width 0.1524)
				(type default)
			)
			(layer "B.SilkS")
		)
		(fp_line
			(start -0.7874 -0.4064)
			(end -0.7874 0.4064)
			(stroke
				(width 0.1524)
				(type default)
			)
			(layer "B.SilkS")
		)
		(fp_line
			(start 0.7874 0.4064)
			(end 0.7874 -0.4064)
			(stroke
				(width 0.1524)
				(type default)
			)
			(layer "B.SilkS")
		)
		(fp_line
			(start -0.7874 0.4064)
			(end 0.7874 0.4064)
			(stroke
				(width 0.1524)
				(type default)
			)
			(layer "B.SilkS")
		)
		(fp_line
			(start 0.67945 -0.305054)
			(end 0.12065 -0.305054)
			(stroke
				(width 0.1)
				(type default)
			)
			(layer "B.Fab")
		)
		(fp_line
			(start 0.12065 -0.305054)
			(end 0.12065 -0.2794)
			(stroke
				(width 0.1)
				(type default)
			)
			(layer "B.Fab")
		)
		(fp_line
			(start -0.12065 -0.3048)
			(end -0.67945 -0.3048)
			(stroke
				(width 0.1)
				(type default)
			)
			(layer "B.Fab")
		)
		(fp_line
			(start -0.67945 -0.3048)
			(end -0.67945 0.3048)
			(stroke
				(width 0.1)
				(type default)
			)
			(layer "B.Fab")
		)
		(fp_line
			(start 0.12065 -0.2794)
			(end -0.12065 -0.2794)
			(stroke
				(width 0.1)
				(type default)
			)
			(layer "B.Fab")
		)
		(fp_line
			(start -0.12065 -0.2794)
			(end -0.12065 -0.3048)
			(stroke
				(width 0.1)
				(type default)
			)
			(layer "B.Fab")
		)
		(fp_line
			(start 0.12065 0.2794)
			(end 0.12065 0.3048)
			(stroke
				(width 0.1)
				(type default)
			)
			(layer "B.Fab")
		)
		(fp_line
			(start -0.120396 0.2794)
			(end 0.12065 0.2794)
			(stroke
				(width 0.1)
				(type default)
			)
			(layer "B.Fab")
		)
		(fp_line
			(start 0.67945 0.3048)
			(end 0.67945 -0.305054)
			(stroke
				(width 0.1)
				(type default)
			)
			(layer "B.Fab")
		)
		(fp_line
			(start 0.12065 0.3048)
			(end 0.67945 0.3048)
			(stroke
				(width 0.1)
				(type default)
			)
			(layer "B.Fab")
		)
		(fp_line
			(start -0.120396 0.3048)
			(end -0.120396 0.2794)
			(stroke
				(width 0.1)
				(type default)
			)
			(layer "B.Fab")
		)
		(fp_line
			(start -0.67945 0.3048)
			(end -0.120396 0.3048)
			(stroke
				(width 0.1)
				(type default)
			)
			(layer "B.Fab")
		)
		(pad "1" smd circle
			(at 0.40005 0 270)
			(size 0 0)
			(layers "B.Cu" "B.Mask" "B.Paste")
			(net "P0V9_CPU0_RT3_2A")
		)
		(pad "2" smd circle
			(at -0.40005 0 270)
			(size 0 0)
			(layers "B.Cu" "B.Mask" "B.Paste")
			(net "GND")
		)
	)
	(footprint ""
		(layer "B.Cu")
		(at 58.178446 -386.766562 90)
		(property "Reference" "C125"
			(at 0 0 90)
			(layer "B.SilkS")
			(hide yes)
			(effects
				(font
					(size 1.27 1.27)
				)
				(justify mirror)
			)
		)
		(property "Value" ""
			(at 0 0 90)
			(layer "B.Fab")
			(effects
				(font
					(size 1.27 1.27)
				)
				(justify mirror)
			)
		)
		(duplicate_pad_numbers_are_jumpers no)
		(fp_line
			(start 0.299974 -0.150114)
			(end -0.299974 -0.150114)
			(stroke
				(width 0.1)
				(type default)
			)
			(layer "B.Fab")
		)
		(fp_line
			(start -0.299974 -0.150114)
			(end -0.299974 0.150114)
			(stroke
				(width 0.1)
				(type default)
			)
			(layer "B.Fab")
		)
		(fp_line
			(start 0.299974 0.150114)
			(end 0.299974 -0.150114)
			(stroke
				(width 0.1)
				(type default)
			)
			(layer "B.Fab")
		)
		(fp_line
			(start -0.299974 0.150114)
			(end 0.299974 0.150114)
			(stroke
				(width 0.1)
				(type default)
			)
			(layer "B.Fab")
		)
		(pad "1" smd rect
			(at 0.2667 0 270)
			(size 0.3048 0.381)
			(layers "B.Cu" "B.Mask" "B.Paste")
			(net "P1V8_CPU1_RT0_1A_1D")
		)
		(pad "2" smd rect
			(at -0.2667 0 270)
			(size 0.3048 0.381)
			(layers "B.Cu" "B.Mask" "B.Paste")
			(net "GND")
		)
	)
	(footprint ""
		(layer "B.Cu")
		(at 15.433294 -110.987586 90)
		(property "Reference" "C5234"
			(at 0 0 90)
			(layer "B.SilkS")
			(hide yes)
			(effects
				(font
					(size 1.27 1.27)
				)
				(justify mirror)
			)
		)
		(property "Value" ""
			(at 0 0 90)
			(layer "B.Fab")
			(effects
				(font
					(size 1.27 1.27)
				)
				(justify mirror)
			)
		)
		(duplicate_pad_numbers_are_jumpers no)
		(fp_line
			(start 0.7874 -0.4064)
			(end -0.7874 -0.4064)
			(stroke
				(width 0.1524)
				(type default)
			)
			(layer "B.SilkS")
		)
		(fp_line
			(start -0.7874 -0.4064)
			(end -0.7874 0.4064)
			(stroke
				(width 0.1524)
				(type default)
			)
			(layer "B.SilkS")
		)
		(fp_line
			(start 0.7874 0.4064)
			(end 0.7874 -0.4064)
			(stroke
				(width 0.1524)
				(type default)
			)
			(layer "B.SilkS")
		)
		(fp_line
			(start -0.7874 0.4064)
			(end 0.7874 0.4064)
			(stroke
				(width 0.1524)
				(type default)
			)
			(layer "B.SilkS")
		)
		(fp_line
			(start 0.67945 -0.305054)
			(end 0.12065 -0.305054)
			(stroke
				(width 0.1)
				(type default)
			)
			(layer "B.Fab")
		)
		(fp_line
			(start 0.12065 -0.305054)
			(end 0.12065 -0.2794)
			(stroke
				(width 0.1)
				(type default)
			)
			(layer "B.Fab")
		)
		(fp_line
			(start -0.12065 -0.3048)
			(end -0.67945 -0.3048)
			(stroke
				(width 0.1)
				(type default)
			)
			(layer "B.Fab")
		)
		(fp_line
			(start -0.67945 -0.3048)
			(end -0.67945 0.3048)
			(stroke
				(width 0.1)
				(type default)
			)
			(layer "B.Fab")
		)
		(fp_line
			(start 0.12065 -0.2794)
			(end -0.12065 -0.2794)
			(stroke
				(width 0.1)
				(type default)
			)
			(layer "B.Fab")
		)
		(fp_line
			(start -0.12065 -0.2794)
			(end -0.12065 -0.3048)
			(stroke
				(width 0.1)
				(type default)
			)
			(layer "B.Fab")
		)
		(fp_line
			(start 0.12065 0.2794)
			(end 0.12065 0.3048)
			(stroke
				(width 0.1)
				(type default)
			)
			(layer "B.Fab")
		)
		(fp_line
			(start -0.120396 0.2794)
			(end 0.12065 0.2794)
			(stroke
				(width 0.1)
				(type default)
			)
			(layer "B.Fab")
		)
		(fp_line
			(start 0.67945 0.3048)
			(end 0.67945 -0.305054)
			(stroke
				(width 0.1)
				(type default)
			)
			(layer "B.Fab")
		)
		(fp_line
			(start 0.12065 0.3048)
			(end 0.67945 0.3048)
			(stroke
				(width 0.1)
				(type default)
			)
			(layer "B.Fab")
		)
		(fp_line
			(start -0.120396 0.3048)
			(end -0.120396 0.2794)
			(stroke
				(width 0.1)
				(type default)
			)
			(layer "B.Fab")
		)
		(fp_line
			(start -0.67945 0.3048)
			(end -0.120396 0.3048)
			(stroke
				(width 0.1)
				(type default)
			)
			(layer "B.Fab")
		)
		(pad "1" smd circle
			(at 0.40005 0 270)
			(size 0 0)
			(layers "B.Cu" "B.Mask" "B.Paste")
			(net "P3V3_AUX")
		)
		(pad "2" smd circle
			(at -0.40005 0 270)
			(size 0 0)
			(layers "B.Cu" "B.Mask" "B.Paste")
			(net "GND")
		)
	)
	(footprint ""
		(layer "B.Cu")
		(at 101.894386 -262.703564)
		(property "Reference" "C2465"
			(at 0 0 0)
			(layer "B.SilkS")
			(hide yes)
			(effects
				(font
					(size 1.27 1.27)
				)
				(justify mirror)
			)
		)
		(property "Value" ""
			(at 0 0 0)
			(layer "B.Fab")
			(effects
				(font
					(size 1.27 1.27)
				)
				(justify mirror)
			)
		)
		(duplicate_pad_numbers_are_jumpers no)
		(fp_line
			(start -0.7874 -0.4064)
			(end -0.7874 0.4064)
			(stroke
				(width 0.1524)
				(type default)
			)
			(layer "B.SilkS")
		)
		(fp_line
			(start -0.7874 0.4064)
			(end 0.7874 0.4064)
			(stroke
				(width 0.1524)
				(type default)
			)
			(layer "B.SilkS")
		)
		(fp_line
			(start 0.7874 -0.4064)
			(end -0.7874 -0.4064)
			(stroke
				(width 0.1524)
				(type default)
			)
			(layer "B.SilkS")
		)
		(fp_line
			(start 0.7874 0.4064)
			(end 0.7874 -0.4064)
			(stroke
				(width 0.1524)
				(type default)
			)
			(layer "B.SilkS")
		)
		(fp_line
			(start -0.67945 -0.3048)
			(end -0.67945 0.3048)
			(stroke
				(width 0.1)
				(type default)
			)
			(layer "B.Fab")
		)
		(fp_line
			(start -0.67945 0.3048)
			(end -0.120396 0.3048)
			(stroke
				(width 0.1)
				(type default)
			)
			(layer "B.Fab")
		)
		(fp_line
			(start -0.12065 -0.3048)
			(end -0.67945 -0.3048)
			(stroke
				(width 0.1)
				(type default)
			)
			(layer "B.Fab")
		)
		(fp_line
			(start -0.12065 -0.2794)
			(end -0.12065 -0.3048)
			(stroke
				(width 0.1)
				(type default)
			)
			(layer "B.Fab")
		)
		(fp_line
			(start -0.120396 0.2794)
			(end 0.12065 0.2794)
			(stroke
				(width 0.1)
				(type default)
			)
			(layer "B.Fab")
		)
		(fp_line
			(start -0.120396 0.3048)
			(end -0.120396 0.2794)
			(stroke
				(width 0.1)
				(type default)
			)
			(layer "B.Fab")
		)
		(fp_line
			(start 0.12065 -0.305054)
			(end 0.12065 -0.2794)
			(stroke
				(width 0.1)
				(type default)
			)
			(layer "B.Fab")
		)
		(fp_line
			(start 0.12065 -0.2794)
			(end -0.12065 -0.2794)
			(stroke
				(width 0.1)
				(type default)
			)
			(layer "B.Fab")
		)
		(fp_line
			(start 0.12065 0.2794)
			(end 0.12065 0.3048)
			(stroke
				(width 0.1)
				(type default)
			)
			(layer "B.Fab")
		)
		(fp_line
			(start 0.12065 0.3048)
			(end 0.67945 0.3048)
			(stroke
				(width 0.1)
				(type default)
			)
			(layer "B.Fab")
		)
		(fp_line
			(start 0.67945 -0.305054)
			(end 0.12065 -0.305054)
			(stroke
				(width 0.1)
				(type default)
			)
			(layer "B.Fab")
		)
		(fp_line
			(start 0.67945 0.3048)
			(end 0.67945 -0.305054)
			(stroke
				(width 0.1)
				(type default)
			)
			(layer "B.Fab")
		)
		(pad "1" smd circle
			(at 0.40005 0 180)
			(size 0 0)
			(layers "B.Cu" "B.Mask" "B.Paste")
			(net "PVDDCR_SOC_P1")
		)
		(pad "2" smd circle
			(at -0.40005 0 180)
			(size 0 0)
			(layers "B.Cu" "B.Mask" "B.Paste")
			(net "GND")
		)
	)
	(footprint ""
		(layer "B.Cu")
		(at 197.93712 -331.027786 -90)
		(property "Reference" "PC135"
			(at 0 0 90)
			(layer "B.SilkS")
			(hide yes)
			(effects
				(font
					(size 1.27 1.27)
				)
				(justify mirror)
			)
		)
		(property "Value" ""
			(at 0 0 90)
			(layer "B.Fab")
			(effects
				(font
					(size 1.27 1.27)
				)
				(justify mirror)
			)
		)
		(duplicate_pad_numbers_are_jumpers no)
		(fp_line
			(start -1.524 0.762)
			(end 1.524 0.762)
			(stroke
				(width 0.1524)
				(type default)
			)
			(layer "B.SilkS")
		)
		(fp_line
			(start 1.524 0.762)
			(end 1.524 -0.762)
			(stroke
				(width 0.1524)
				(type default)
			)
			(layer "B.SilkS")
		)
		(fp_line
			(start -1.524 -0.762)
			(end -1.524 0.762)
			(stroke
				(width 0.1524)
				(type default)
			)
			(layer "B.SilkS")
		)
		(fp_line
			(start 1.524 -0.762)
			(end -1.524 -0.762)
			(stroke
				(width 0.1524)
				(type default)
			)
			(layer "B.SilkS")
		)
		(fp_line
			(start -1.1049 0.724916)
			(end -1.1049 -0.724916)
			(stroke
				(width 0.1)
				(type default)
			)
			(layer "B.Fab")
		)
		(fp_line
			(start 1.1049 0.724916)
			(end -1.1049 0.724916)
			(stroke
				(width 0.1)
				(type default)
			)
			(layer "B.Fab")
		)
		(fp_line
			(start -1.1049 -0.724916)
			(end 1.1049 -0.724916)
			(stroke
				(width 0.1)
				(type default)
			)
			(layer "B.Fab")
		)
		(fp_line
			(start 1.1049 -0.724916)
			(end 1.1049 0.724916)
			(stroke
				(width 0.1)
				(type default)
			)
			(layer "B.Fab")
		)
		(pad "1" smd rect
			(at 0.889 0 270)
			(size 1.016 1.27)
			(layers "B.Cu" "B.Mask" "B.Paste")
			(net "PVDD_33_S5")
		)
		(pad "2" smd rect
			(at -0.889 0 270)
			(size 1.016 1.27)
			(layers "B.Cu" "B.Mask" "B.Paste")
			(net "GND")
		)
	)
	(footprint ""
		(layer "B.Cu")
		(at 110.856014 -257.74523 180)
		(property "Reference" "C2433"
			(at 0 0 0)
			(layer "B.SilkS")
			(hide yes)
			(effects
				(font
					(size 1.27 1.27)
				)
				(justify mirror)
			)
		)
		(property "Value" ""
			(at 0 0 0)
			(layer "B.Fab")
			(effects
				(font
					(size 1.27 1.27)
				)
				(justify mirror)
			)
		)
		(duplicate_pad_numbers_are_jumpers no)
		(fp_line
			(start 0.7874 0.4064)
			(end 0.7874 -0.4064)
			(stroke
				(width 0.1524)
				(type default)
			)
			(layer "B.SilkS")
		)
		(fp_line
			(start 0.7874 -0.4064)
			(end -0.7874 -0.4064)
			(stroke
				(width 0.1524)
				(type default)
			)
			(layer "B.SilkS")
		)
		(fp_line
			(start -0.7874 0.4064)
			(end 0.7874 0.4064)
			(stroke
				(width 0.1524)
				(type default)
			)
			(layer "B.SilkS")
		)
		(fp_line
			(start -0.7874 -0.4064)
			(end -0.7874 0.4064)
			(stroke
				(width 0.1524)
				(type default)
			)
			(layer "B.SilkS")
		)
		(fp_line
			(start 0.67945 0.3048)
			(end 0.67945 -0.305054)
			(stroke
				(width 0.1)
				(type default)
			)
			(layer "B.Fab")
		)
		(fp_line
			(start 0.67945 -0.305054)
			(end 0.12065 -0.305054)
			(stroke
				(width 0.1)
				(type default)
			)
			(layer "B.Fab")
		)
		(fp_line
			(start 0.12065 0.3048)
			(end 0.67945 0.3048)
			(stroke
				(width 0.1)
				(type default)
			)
			(layer "B.Fab")
		)
		(fp_line
			(start 0.12065 0.2794)
			(end 0.12065 0.3048)
			(stroke
				(width 0.1)
				(type default)
			)
			(layer "B.Fab")
		)
		(fp_line
			(start 0.12065 -0.2794)
			(end -0.12065 -0.2794)
			(stroke
				(width 0.1)
				(type default)
			)
			(layer "B.Fab")
		)
		(fp_line
			(start 0.12065 -0.305054)
			(end 0.12065 -0.2794)
			(stroke
				(width 0.1)
				(type default)
			)
			(layer "B.Fab")
		)
		(fp_line
			(start -0.120396 0.3048)
			(end -0.120396 0.2794)
			(stroke
				(width 0.1)
				(type default)
			)
			(layer "B.Fab")
		)
		(fp_line
			(start -0.120396 0.2794)
			(end 0.12065 0.2794)
			(stroke
				(width 0.1)
				(type default)
			)
			(layer "B.Fab")
		)
		(fp_line
			(start -0.12065 -0.2794)
			(end -0.12065 -0.3048)
			(stroke
				(width 0.1)
				(type default)
			)
			(layer "B.Fab")
		)
		(fp_line
			(start -0.12065 -0.3048)
			(end -0.67945 -0.3048)
			(stroke
				(width 0.1)
				(type default)
			)
			(layer "B.Fab")
		)
		(fp_line
			(start -0.67945 0.3048)
			(end -0.120396 0.3048)
			(stroke
				(width 0.1)
				(type default)
			)
			(layer "B.Fab")
		)
		(fp_line
			(start -0.67945 -0.3048)
			(end -0.67945 0.3048)
			(stroke
				(width 0.1)
				(type default)
			)
			(layer "B.Fab")
		)
		(pad "1" smd circle
			(at 0.40005 0)
			(size 0 0)
			(layers "B.Cu" "B.Mask" "B.Paste")
			(net "PVDDCR_SOC_P1")
		)
		(pad "2" smd circle
			(at -0.40005 0)
			(size 0 0)
			(layers "B.Cu" "B.Mask" "B.Paste")
			(net "GND")
		)
	)
	(footprint ""
		(layer "B.Cu")
		(at 195.359782 -193.996564)
		(property "Reference" "R114"
			(at 0 0 0)
			(layer "B.SilkS")
			(hide yes)
			(effects
				(font
					(size 1.27 1.27)
				)
				(justify mirror)
			)
		)
		(property "Value" ""
			(at 0 0 0)
			(layer "B.Fab")
			(effects
				(font
					(size 1.27 1.27)
				)
				(justify mirror)
			)
		)
		(duplicate_pad_numbers_are_jumpers no)
		(fp_line
			(start -0.7874 -0.4064)
			(end -0.7874 0.4064)
			(stroke
				(width 0.1524)
				(type default)
			)
			(layer "B.SilkS")
		)
		(fp_line
			(start -0.7874 0.4064)
			(end 0.7874 0.4064)
			(stroke
				(width 0.1524)
				(type default)
			)
			(layer "B.SilkS")
		)
		(fp_line
			(start 0.7874 -0.4064)
			(end -0.7874 -0.4064)
			(stroke
				(width 0.1524)
				(type default)
			)
			(layer "B.SilkS")
		)
		(fp_line
			(start 0.7874 0.4064)
			(end 0.7874 -0.4064)
			(stroke
				(width 0.1524)
				(type default)
			)
			(layer "B.SilkS")
		)
		(fp_line
			(start -0.67945 -0.3048)
			(end -0.67945 0.3048)
			(stroke
				(width 0.1)
				(type default)
			)
			(layer "B.Fab")
		)
		(fp_line
			(start -0.67945 0.3048)
			(end -0.120396 0.3048)
			(stroke
				(width 0.1)
				(type default)
			)
			(layer "B.Fab")
		)
		(fp_line
			(start -0.12065 -0.3048)
			(end -0.67945 -0.3048)
			(stroke
				(width 0.1)
				(type default)
			)
			(layer "B.Fab")
		)
		(fp_line
			(start -0.12065 -0.2794)
			(end -0.12065 -0.3048)
			(stroke
				(width 0.1)
				(type default)
			)
			(layer "B.Fab")
		)
		(fp_line
			(start -0.120396 0.2794)
			(end 0.12065 0.2794)
			(stroke
				(width 0.1)
				(type default)
			)
			(layer "B.Fab")
		)
		(fp_line
			(start -0.120396 0.3048)
			(end -0.120396 0.2794)
			(stroke
				(width 0.1)
				(type default)
			)
			(layer "B.Fab")
		)
		(fp_line
			(start 0.12065 -0.305054)
			(end 0.12065 -0.2794)
			(stroke
				(width 0.1)
				(type default)
			)
			(layer "B.Fab")
		)
		(fp_line
			(start 0.12065 -0.2794)
			(end -0.12065 -0.2794)
			(stroke
				(width 0.1)
				(type default)
			)
			(layer "B.Fab")
		)
		(fp_line
			(start 0.12065 0.2794)
			(end 0.12065 0.3048)
			(stroke
				(width 0.1)
				(type default)
			)
			(layer "B.Fab")
		)
		(fp_line
			(start 0.12065 0.3048)
			(end 0.67945 0.3048)
			(stroke
				(width 0.1)
				(type default)
			)
			(layer "B.Fab")
		)
		(fp_line
			(start 0.67945 -0.305054)
			(end 0.12065 -0.305054)
			(stroke
				(width 0.1)
				(type default)
			)
			(layer "B.Fab")
		)
		(fp_line
			(start 0.67945 0.3048)
			(end 0.67945 -0.305054)
			(stroke
				(width 0.1)
				(type default)
			)
			(layer "B.Fab")
		)
		(pad "1" smd circle
			(at 0.40005 0 180)
			(size 0 0)
			(layers "B.Cu" "B.Mask" "B.Paste")
			(net "P3V3")
		)
		(pad "2" smd circle
			(at -0.40005 0 180)
			(size 0 0)
			(layers "B.Cu" "B.Mask" "B.Paste")
			(net "PWRGD_CHK_CPU1_DIMM")
		)
	)
	(footprint ""
		(layer "B.Cu")
		(at 365.836454 -249.36831)
		(property "Reference" "C10179"
			(at 0 0 0)
			(layer "B.SilkS")
			(hide yes)
			(effects
				(font
					(size 1.27 1.27)
				)
				(justify mirror)
			)
		)
		(property "Value" ""
			(at 0 0 0)
			(layer "B.Fab")
			(effects
				(font
					(size 1.27 1.27)
				)
				(justify mirror)
			)
		)
		(duplicate_pad_numbers_are_jumpers no)
		(fp_line
			(start -0.7874 -0.4064)
			(end -0.7874 0.4064)
			(stroke
				(width 0.1524)
				(type default)
			)
			(layer "B.SilkS")
		)
		(fp_line
			(start -0.7874 0.4064)
			(end 0.7874 0.4064)
			(stroke
				(width 0.1524)
				(type default)
			)
			(layer "B.SilkS")
		)
		(fp_line
			(start 0.7874 -0.4064)
			(end -0.7874 -0.4064)
			(stroke
				(width 0.1524)
				(type default)
			)
			(layer "B.SilkS")
		)
		(fp_line
			(start 0.7874 0.4064)
			(end 0.7874 -0.4064)
			(stroke
				(width 0.1524)
				(type default)
			)
			(layer "B.SilkS")
		)
		(fp_line
			(start -0.67945 -0.3048)
			(end -0.67945 0.3048)
			(stroke
				(width 0.1)
				(type default)
			)
			(layer "B.Fab")
		)
		(fp_line
			(start -0.67945 0.3048)
			(end -0.120396 0.3048)
			(stroke
				(width 0.1)
				(type default)
			)
			(layer "B.Fab")
		)
		(fp_line
			(start -0.12065 -0.3048)
			(end -0.67945 -0.3048)
			(stroke
				(width 0.1)
				(type default)
			)
			(layer "B.Fab")
		)
		(fp_line
			(start -0.12065 -0.2794)
			(end -0.12065 -0.3048)
			(stroke
				(width 0.1)
				(type default)
			)
			(layer "B.Fab")
		)
		(fp_line
			(start -0.120396 0.2794)
			(end 0.12065 0.2794)
			(stroke
				(width 0.1)
				(type default)
			)
			(layer "B.Fab")
		)
		(fp_line
			(start -0.120396 0.3048)
			(end -0.120396 0.2794)
			(stroke
				(width 0.1)
				(type default)
			)
			(layer "B.Fab")
		)
		(fp_line
			(start 0.12065 -0.305054)
			(end 0.12065 -0.2794)
			(stroke
				(width 0.1)
				(type default)
			)
			(layer "B.Fab")
		)
		(fp_line
			(start 0.12065 -0.2794)
			(end -0.12065 -0.2794)
			(stroke
				(width 0.1)
				(type default)
			)
			(layer "B.Fab")
		)
		(fp_line
			(start 0.12065 0.2794)
			(end 0.12065 0.3048)
			(stroke
				(width 0.1)
				(type default)
			)
			(layer "B.Fab")
		)
		(fp_line
			(start 0.12065 0.3048)
			(end 0.67945 0.3048)
			(stroke
				(width 0.1)
				(type default)
			)
			(layer "B.Fab")
		)
		(fp_line
			(start 0.67945 -0.305054)
			(end 0.12065 -0.305054)
			(stroke
				(width 0.1)
				(type default)
			)
			(layer "B.Fab")
		)
		(fp_line
			(start 0.67945 0.3048)
			(end 0.67945 -0.305054)
			(stroke
				(width 0.1)
				(type default)
			)
			(layer "B.Fab")
		)
		(pad "1" smd circle
			(at 0.40005 0 180)
			(size 0 0)
			(layers "B.Cu" "B.Mask" "B.Paste")
			(net "PVDDCR_CPU0_P0")
		)
		(pad "2" smd circle
			(at -0.40005 0 180)
			(size 0 0)
			(layers "B.Cu" "B.Mask" "B.Paste")
			(net "GND")
		)
	)
	(footprint ""
		(layer "B.Cu")
		(at 138.24204 -389.43026)
		(property "Reference" "PJ09_P1_N"
			(at 0 0 0)
			(layer "B.SilkS")
			(hide yes)
			(effects
				(font
					(size 1.27 1.27)
				)
				(justify mirror)
			)
		)
		(property "Value" ""
			(at 0 0 0)
			(layer "B.Fab")
			(effects
				(font
					(size 1.27 1.27)
				)
				(justify mirror)
			)
		)
		(duplicate_pad_numbers_are_jumpers no)
		(zone
			(layer "In15.Cu")
			(hatch none 0.5)
			(connect_pads
				(clearance 0)
			)
			(min_thickness 0.25)
			(keepout
				(tracks allowed)
				(vias not_allowed)
				(pads allowed)
				(copperpour not_allowed)
				(footprints allowed)
			)
			(placement
				(enabled no)
				(sheetname "")
			)
			(fill
				(thermal_gap 0.5)
				(thermal_bridge_width 0.5)
				(island_removal_mode 0)
			)
			(polygon
				(pts
					(xy 138.45794 -389.23976) (xy 138.02614 -389.23976) (xy 138.02614 -389.62076) (xy 138.45794 -389.62076)
				)
			)
		)
	)
	(footprint ""
		(layer "B.Cu")
		(at 128.505204 -35.686492 180)
		(property "Reference" "C6054"
			(at 0 0 0)
			(layer "B.SilkS")
			(hide yes)
			(effects
				(font
					(size 1.27 1.27)
				)
				(justify mirror)
			)
		)
		(property "Value" ""
			(at 0 0 0)
			(layer "B.Fab")
			(effects
				(font
					(size 1.27 1.27)
				)
				(justify mirror)
			)
		)
		(duplicate_pad_numbers_are_jumpers no)
		(fp_line
			(start 0.7874 0.4064)
			(end 0.7874 -0.4064)
			(stroke
				(width 0.1524)
				(type default)
			)
			(layer "B.SilkS")
		)
		(fp_line
			(start 0.7874 -0.4064)
			(end -0.7874 -0.4064)
			(stroke
				(width 0.1524)
				(type default)
			)
			(layer "B.SilkS")
		)
		(fp_line
			(start -0.7874 0.4064)
			(end 0.7874 0.4064)
			(stroke
				(width 0.1524)
				(type default)
			)
			(layer "B.SilkS")
		)
		(fp_line
			(start -0.7874 -0.4064)
			(end -0.7874 0.4064)
			(stroke
				(width 0.1524)
				(type default)
			)
			(layer "B.SilkS")
		)
		(fp_line
			(start 0.67945 0.3048)
			(end 0.67945 -0.305054)
			(stroke
				(width 0.1)
				(type default)
			)
			(layer "B.Fab")
		)
		(fp_line
			(start 0.67945 -0.305054)
			(end 0.12065 -0.305054)
			(stroke
				(width 0.1)
				(type default)
			)
			(layer "B.Fab")
		)
		(fp_line
			(start 0.12065 0.3048)
			(end 0.67945 0.3048)
			(stroke
				(width 0.1)
				(type default)
			)
			(layer "B.Fab")
		)
		(fp_line
			(start 0.12065 0.2794)
			(end 0.12065 0.3048)
			(stroke
				(width 0.1)
				(type default)
			)
			(layer "B.Fab")
		)
		(fp_line
			(start 0.12065 -0.2794)
			(end -0.12065 -0.2794)
			(stroke
				(width 0.1)
				(type default)
			)
			(layer "B.Fab")
		)
		(fp_line
			(start 0.12065 -0.305054)
			(end 0.12065 -0.2794)
			(stroke
				(width 0.1)
				(type default)
			)
			(layer "B.Fab")
		)
		(fp_line
			(start -0.120396 0.3048)
			(end -0.120396 0.2794)
			(stroke
				(width 0.1)
				(type default)
			)
			(layer "B.Fab")
		)
		(fp_line
			(start -0.120396 0.2794)
			(end 0.12065 0.2794)
			(stroke
				(width 0.1)
				(type default)
			)
			(layer "B.Fab")
		)
		(fp_line
			(start -0.12065 -0.2794)
			(end -0.12065 -0.3048)
			(stroke
				(width 0.1)
				(type default)
			)
			(layer "B.Fab")
		)
		(fp_line
			(start -0.12065 -0.3048)
			(end -0.67945 -0.3048)
			(stroke
				(width 0.1)
				(type default)
			)
			(layer "B.Fab")
		)
		(fp_line
			(start -0.67945 0.3048)
			(end -0.120396 0.3048)
			(stroke
				(width 0.1)
				(type default)
			)
			(layer "B.Fab")
		)
		(fp_line
			(start -0.67945 -0.3048)
			(end -0.67945 0.3048)
			(stroke
				(width 0.1)
				(type default)
			)
			(layer "B.Fab")
		)
		(pad "1" smd circle
			(at 0.40005 0)
			(size 0 0)
			(layers "B.Cu" "B.Mask" "B.Paste")
			(net "P1V2_AUX")
		)
		(pad "2" smd circle
			(at -0.40005 0)
			(size 0 0)
			(layers "B.Cu" "B.Mask" "B.Paste")
			(net "GND")
		)
	)
	(footprint ""
		(layer "B.Cu")
		(at 72.825864 -11.26871 90)
		(property "Reference" "R3163"
			(at 0 0 90)
			(layer "B.SilkS")
			(hide yes)
			(effects
				(font
					(size 1.27 1.27)
				)
				(justify mirror)
			)
		)
		(property "Value" ""
			(at 0 0 90)
			(layer "B.Fab")
			(effects
				(font
					(size 1.27 1.27)
				)
				(justify mirror)
			)
		)
		(duplicate_pad_numbers_are_jumpers no)
		(fp_line
			(start 0.7874 -0.4064)
			(end -0.7874 -0.4064)
			(stroke
				(width 0.1524)
				(type default)
			)
			(layer "B.SilkS")
		)
		(fp_line
			(start -0.7874 -0.4064)
			(end -0.7874 0.4064)
			(stroke
				(width 0.1524)
				(type default)
			)
			(layer "B.SilkS")
		)
		(fp_line
			(start 0.7874 0.4064)
			(end 0.7874 -0.4064)
			(stroke
				(width 0.1524)
				(type default)
			)
			(layer "B.SilkS")
		)
		(fp_line
			(start -0.7874 0.4064)
			(end 0.7874 0.4064)
			(stroke
				(width 0.1524)
				(type default)
			)
			(layer "B.SilkS")
		)
		(fp_line
			(start 0.67945 -0.305054)
			(end 0.12065 -0.305054)
			(stroke
				(width 0.1)
				(type default)
			)
			(layer "B.Fab")
		)
		(fp_line
			(start 0.12065 -0.305054)
			(end 0.12065 -0.2794)
			(stroke
				(width 0.1)
				(type default)
			)
			(layer "B.Fab")
		)
		(fp_line
			(start -0.12065 -0.3048)
			(end -0.67945 -0.3048)
			(stroke
				(width 0.1)
				(type default)
			)
			(layer "B.Fab")
		)
		(fp_line
			(start -0.67945 -0.3048)
			(end -0.67945 0.3048)
			(stroke
				(width 0.1)
				(type default)
			)
			(layer "B.Fab")
		)
		(fp_line
			(start 0.12065 -0.2794)
			(end -0.12065 -0.2794)
			(stroke
				(width 0.1)
				(type default)
			)
			(layer "B.Fab")
		)
		(fp_line
			(start -0.12065 -0.2794)
			(end -0.12065 -0.3048)
			(stroke
				(width 0.1)
				(type default)
			)
			(layer "B.Fab")
		)
		(fp_line
			(start 0.12065 0.2794)
			(end 0.12065 0.3048)
			(stroke
				(width 0.1)
				(type default)
			)
			(layer "B.Fab")
		)
		(fp_line
			(start -0.120396 0.2794)
			(end 0.12065 0.2794)
			(stroke
				(width 0.1)
				(type default)
			)
			(layer "B.Fab")
		)
		(fp_line
			(start 0.67945 0.3048)
			(end 0.67945 -0.305054)
			(stroke
				(width 0.1)
				(type default)
			)
			(layer "B.Fab")
		)
		(fp_line
			(start 0.12065 0.3048)
			(end 0.67945 0.3048)
			(stroke
				(width 0.1)
				(type default)
			)
			(layer "B.Fab")
		)
		(fp_line
			(start -0.120396 0.3048)
			(end -0.120396 0.2794)
			(stroke
				(width 0.1)
				(type default)
			)
			(layer "B.Fab")
		)
		(fp_line
			(start -0.67945 0.3048)
			(end -0.120396 0.3048)
			(stroke
				(width 0.1)
				(type default)
			)
			(layer "B.Fab")
		)
		(pad "1" smd circle
			(at 0.40005 0 270)
			(size 0 0)
			(layers "B.Cu" "B.Mask" "B.Paste")
			(net "OCP_V3_2_ID0")
		)
		(pad "2" smd circle
			(at -0.40005 0 270)
			(size 0 0)
			(layers "B.Cu" "B.Mask" "B.Paste")
			(net "GND")
		)
	)
	(footprint ""
		(layer "B.Cu")
		(at 348.418912 -257.930142 180)
		(property "Reference" "C2643"
			(at 0 0 0)
			(layer "B.SilkS")
			(hide yes)
			(effects
				(font
					(size 1.27 1.27)
				)
				(justify mirror)
			)
		)
		(property "Value" ""
			(at 0 0 0)
			(layer "B.Fab")
			(effects
				(font
					(size 1.27 1.27)
				)
				(justify mirror)
			)
		)
		(duplicate_pad_numbers_are_jumpers no)
		(fp_line
			(start 0.7874 0.4064)
			(end 0.7874 -0.4064)
			(stroke
				(width 0.1524)
				(type default)
			)
			(layer "B.SilkS")
		)
		(fp_line
			(start 0.7874 -0.4064)
			(end -0.7874 -0.4064)
			(stroke
				(width 0.1524)
				(type default)
			)
			(layer "B.SilkS")
		)
		(fp_line
			(start -0.7874 0.4064)
			(end 0.7874 0.4064)
			(stroke
				(width 0.1524)
				(type default)
			)
			(layer "B.SilkS")
		)
		(fp_line
			(start -0.7874 -0.4064)
			(end -0.7874 0.4064)
			(stroke
				(width 0.1524)
				(type default)
			)
			(layer "B.SilkS")
		)
		(fp_line
			(start 0.67945 0.3048)
			(end 0.67945 -0.305054)
			(stroke
				(width 0.1)
				(type default)
			)
			(layer "B.Fab")
		)
		(fp_line
			(start 0.67945 -0.305054)
			(end 0.12065 -0.305054)
			(stroke
				(width 0.1)
				(type default)
			)
			(layer "B.Fab")
		)
		(fp_line
			(start 0.12065 0.3048)
			(end 0.67945 0.3048)
			(stroke
				(width 0.1)
				(type default)
			)
			(layer "B.Fab")
		)
		(fp_line
			(start 0.12065 0.2794)
			(end 0.12065 0.3048)
			(stroke
				(width 0.1)
				(type default)
			)
			(layer "B.Fab")
		)
		(fp_line
			(start 0.12065 -0.2794)
			(end -0.12065 -0.2794)
			(stroke
				(width 0.1)
				(type default)
			)
			(layer "B.Fab")
		)
		(fp_line
			(start 0.12065 -0.305054)
			(end 0.12065 -0.2794)
			(stroke
				(width 0.1)
				(type default)
			)
			(layer "B.Fab")
		)
		(fp_line
			(start -0.120396 0.3048)
			(end -0.120396 0.2794)
			(stroke
				(width 0.1)
				(type default)
			)
			(layer "B.Fab")
		)
		(fp_line
			(start -0.120396 0.2794)
			(end 0.12065 0.2794)
			(stroke
				(width 0.1)
				(type default)
			)
			(layer "B.Fab")
		)
		(fp_line
			(start -0.12065 -0.2794)
			(end -0.12065 -0.3048)
			(stroke
				(width 0.1)
				(type default)
			)
			(layer "B.Fab")
		)
		(fp_line
			(start -0.12065 -0.3048)
			(end -0.67945 -0.3048)
			(stroke
				(width 0.1)
				(type default)
			)
			(layer "B.Fab")
		)
		(fp_line
			(start -0.67945 0.3048)
			(end -0.120396 0.3048)
			(stroke
				(width 0.1)
				(type default)
			)
			(layer "B.Fab")
		)
		(fp_line
			(start -0.67945 -0.3048)
			(end -0.67945 0.3048)
			(stroke
				(width 0.1)
				(type default)
			)
			(layer "B.Fab")
		)
		(pad "1" smd circle
			(at 0.40005 0)
			(size 0 0)
			(layers "B.Cu" "B.Mask" "B.Paste")
			(net "PVDDIO_P0")
		)
		(pad "2" smd circle
			(at -0.40005 0)
			(size 0 0)
			(layers "B.Cu" "B.Mask" "B.Paste")
			(net "GND")
		)
	)
	(footprint ""
		(layer "B.Cu")
		(at 203.045314 -77.231748)
		(property "Reference" "R3209"
			(at 0 0 0)
			(layer "B.SilkS")
			(hide yes)
			(effects
				(font
					(size 1.27 1.27)
				)
				(justify mirror)
			)
		)
		(property "Value" ""
			(at 0 0 0)
			(layer "B.Fab")
			(effects
				(font
					(size 1.27 1.27)
				)
				(justify mirror)
			)
		)
		(duplicate_pad_numbers_are_jumpers no)
		(fp_line
			(start -0.7874 -0.4064)
			(end -0.7874 0.4064)
			(stroke
				(width 0.1524)
				(type default)
			)
			(layer "B.SilkS")
		)
		(fp_line
			(start -0.7874 0.4064)
			(end 0.7874 0.4064)
			(stroke
				(width 0.1524)
				(type default)
			)
			(layer "B.SilkS")
		)
		(fp_line
			(start 0.7874 -0.4064)
			(end -0.7874 -0.4064)
			(stroke
				(width 0.1524)
				(type default)
			)
			(layer "B.SilkS")
		)
		(fp_line
			(start 0.7874 0.4064)
			(end 0.7874 -0.4064)
			(stroke
				(width 0.1524)
				(type default)
			)
			(layer "B.SilkS")
		)
		(fp_line
			(start -0.67945 -0.3048)
			(end -0.67945 0.3048)
			(stroke
				(width 0.1)
				(type default)
			)
			(layer "B.Fab")
		)
		(fp_line
			(start -0.67945 0.3048)
			(end -0.120396 0.3048)
			(stroke
				(width 0.1)
				(type default)
			)
			(layer "B.Fab")
		)
		(fp_line
			(start -0.12065 -0.3048)
			(end -0.67945 -0.3048)
			(stroke
				(width 0.1)
				(type default)
			)
			(layer "B.Fab")
		)
		(fp_line
			(start -0.12065 -0.2794)
			(end -0.12065 -0.3048)
			(stroke
				(width 0.1)
				(type default)
			)
			(layer "B.Fab")
		)
		(fp_line
			(start -0.120396 0.2794)
			(end 0.12065 0.2794)
			(stroke
				(width 0.1)
				(type default)
			)
			(layer "B.Fab")
		)
		(fp_line
			(start -0.120396 0.3048)
			(end -0.120396 0.2794)
			(stroke
				(width 0.1)
				(type default)
			)
			(layer "B.Fab")
		)
		(fp_line
			(start 0.12065 -0.305054)
			(end 0.12065 -0.2794)
			(stroke
				(width 0.1)
				(type default)
			)
			(layer "B.Fab")
		)
		(fp_line
			(start 0.12065 -0.2794)
			(end -0.12065 -0.2794)
			(stroke
				(width 0.1)
				(type default)
			)
			(layer "B.Fab")
		)
		(fp_line
			(start 0.12065 0.2794)
			(end 0.12065 0.3048)
			(stroke
				(width 0.1)
				(type default)
			)
			(layer "B.Fab")
		)
		(fp_line
			(start 0.12065 0.3048)
			(end 0.67945 0.3048)
			(stroke
				(width 0.1)
				(type default)
			)
			(layer "B.Fab")
		)
		(fp_line
			(start 0.67945 -0.305054)
			(end 0.12065 -0.305054)
			(stroke
				(width 0.1)
				(type default)
			)
			(layer "B.Fab")
		)
		(fp_line
			(start 0.67945 0.3048)
			(end 0.67945 -0.305054)
			(stroke
				(width 0.1)
				(type default)
			)
			(layer "B.Fab")
		)
		(pad "1" smd circle
			(at 0.40005 0 180)
			(size 0 0)
			(layers "B.Cu" "B.Mask" "B.Paste")
			(net "OCP_V3_2_RBT_ARB_IN_R")
		)
		(pad "2" smd circle
			(at -0.40005 0 180)
			(size 0 0)
			(layers "B.Cu" "B.Mask" "B.Paste")
			(net "OCP_V3_2_RBT_ARB_IN")
		)
	)
	(footprint ""
		(layer "B.Cu")
		(at 102.580948 -382.8796 180)
		(property "Reference" "R6733"
			(at 0 0 0)
			(layer "B.SilkS")
			(hide yes)
			(effects
				(font
					(size 1.27 1.27)
				)
				(justify mirror)
			)
		)
		(property "Value" ""
			(at 0 0 0)
			(layer "B.Fab")
			(effects
				(font
					(size 1.27 1.27)
				)
				(justify mirror)
			)
		)
		(duplicate_pad_numbers_are_jumpers no)
		(fp_line
			(start 0.32512 0.175006)
			(end 0.32512 -0.175006)
			(stroke
				(width 0.1)
				(type default)
			)
			(layer "B.Fab")
		)
		(fp_line
			(start 0.32512 -0.175006)
			(end -0.32512 -0.175006)
			(stroke
				(width 0.1)
				(type default)
			)
			(layer "B.Fab")
		)
		(fp_line
			(start -0.32512 0.175006)
			(end 0.32512 0.175006)
			(stroke
				(width 0.1)
				(type default)
			)
			(layer "B.Fab")
		)
		(fp_line
			(start -0.32512 -0.175006)
			(end -0.32512 0.175006)
			(stroke
				(width 0.1)
				(type default)
			)
			(layer "B.Fab")
		)
		(pad "1" smd rect
			(at 0.2667 0)
			(size 0.3048 0.381)
			(layers "B.Cu" "B.Mask" "B.Paste")
			(net "NCF_CPU1_P1_GND")
		)
		(pad "2" smd rect
			(at -0.2667 0 180)
			(size 0.3048 0.381)
			(layers "B.Cu" "B.Mask" "B.Paste")
			(net "GND")
		)
	)
	(footprint ""
		(layer "B.Cu")
		(at 136.936226 -390.073134 180)
		(property "Reference" "C466"
			(at 0 0 0)
			(layer "B.SilkS")
			(hide yes)
			(effects
				(font
					(size 1.27 1.27)
				)
				(justify mirror)
			)
		)
		(property "Value" ""
			(at 0 0 0)
			(layer "B.Fab")
			(effects
				(font
					(size 1.27 1.27)
				)
				(justify mirror)
			)
		)
		(duplicate_pad_numbers_are_jumpers no)
		(fp_line
			(start 1.524 0.762)
			(end 1.524 -0.762)
			(stroke
				(width 0.1524)
				(type default)
			)
			(layer "B.SilkS")
		)
		(fp_line
			(start 1.524 -0.762)
			(end -1.524 -0.762)
			(stroke
				(width 0.1524)
				(type default)
			)
			(layer "B.SilkS")
		)
		(fp_line
			(start -1.524 0.762)
			(end 1.524 0.762)
			(stroke
				(width 0.1524)
				(type default)
			)
			(layer "B.SilkS")
		)
		(fp_line
			(start -1.524 -0.762)
			(end -1.524 0.762)
			(stroke
				(width 0.1524)
				(type default)
			)
			(layer "B.SilkS")
		)
		(fp_line
			(start 1.1049 0.724916)
			(end -1.1049 0.724916)
			(stroke
				(width 0.1)
				(type default)
			)
			(layer "B.Fab")
		)
		(fp_line
			(start 1.1049 -0.724916)
			(end 1.1049 0.724916)
			(stroke
				(width 0.1)
				(type default)
			)
			(layer "B.Fab")
		)
		(fp_line
			(start -1.1049 0.724916)
			(end -1.1049 -0.724916)
			(stroke
				(width 0.1)
				(type default)
			)
			(layer "B.Fab")
		)
		(fp_line
			(start -1.1049 -0.724916)
			(end 1.1049 -0.724916)
			(stroke
				(width 0.1)
				(type default)
			)
			(layer "B.Fab")
		)
		(pad "1" smd rect
			(at 0.889 0 180)
			(size 1.016 1.27)
			(layers "B.Cu" "B.Mask" "B.Paste")
			(net "P0V9_CPU1_RT3_2A")
		)
		(pad "2" smd rect
			(at -0.889 0 180)
			(size 1.016 1.27)
			(layers "B.Cu" "B.Mask" "B.Paste")
			(net "GND")
		)
	)
	(footprint ""
		(layer "B.Cu")
		(at 153.159206 -408.517344 90)
		(property "Reference" "C6750"
			(at 0 0 90)
			(layer "B.SilkS")
			(hide yes)
			(effects
				(font
					(size 1.27 1.27)
				)
				(justify mirror)
			)
		)
		(property "Value" ""
			(at 0 0 90)
			(layer "B.Fab")
			(effects
				(font
					(size 1.27 1.27)
				)
				(justify mirror)
			)
		)
		(duplicate_pad_numbers_are_jumpers no)
		(fp_line
			(start 0.299974 -0.150114)
			(end -0.299974 -0.150114)
			(stroke
				(width 0.1)
				(type default)
			)
			(layer "B.Fab")
		)
		(fp_line
			(start -0.299974 -0.150114)
			(end -0.299974 0.150114)
			(stroke
				(width 0.1)
				(type default)
			)
			(layer "B.Fab")
		)
		(fp_line
			(start 0.299974 0.150114)
			(end 0.299974 -0.150114)
			(stroke
				(width 0.1)
				(type default)
			)
			(layer "B.Fab")
		)
		(fp_line
			(start -0.299974 0.150114)
			(end 0.299974 0.150114)
			(stroke
				(width 0.1)
				(type default)
			)
			(layer "B.Fab")
		)
		(pad "1" smd rect
			(at 0.2667 0 270)
			(size 0.3048 0.381)
			(layers "B.Cu" "B.Mask" "B.Paste")
			(net "P5E_CPU1_P3_TX_BUF_C_DN<12>")
		)
		(pad "2" smd rect
			(at -0.2667 0 270)
			(size 0.3048 0.381)
			(layers "B.Cu" "B.Mask" "B.Paste")
			(net "P5E_CPU1_P3_TX_BUF_DN<12>")
		)
	)
	(footprint ""
		(layer "B.Cu")
		(at 60.718446 -388.011162 -90)
		(property "Reference" "C198"
			(at 0 0 90)
			(layer "B.SilkS")
			(hide yes)
			(effects
				(font
					(size 1.27 1.27)
				)
				(justify mirror)
			)
		)
		(property "Value" ""
			(at 0 0 90)
			(layer "B.Fab")
			(effects
				(font
					(size 1.27 1.27)
				)
				(justify mirror)
			)
		)
		(duplicate_pad_numbers_are_jumpers no)
		(fp_line
			(start -0.299974 0.150114)
			(end 0.299974 0.150114)
			(stroke
				(width 0.1)
				(type default)
			)
			(layer "B.Fab")
		)
		(fp_line
			(start 0.299974 0.150114)
			(end 0.299974 -0.150114)
			(stroke
				(width 0.1)
				(type default)
			)
			(layer "B.Fab")
		)
		(fp_line
			(start -0.299974 -0.150114)
			(end -0.299974 0.150114)
			(stroke
				(width 0.1)
				(type default)
			)
			(layer "B.Fab")
		)
		(fp_line
			(start 0.299974 -0.150114)
			(end -0.299974 -0.150114)
			(stroke
				(width 0.1)
				(type default)
			)
			(layer "B.Fab")
		)
		(pad "1" smd rect
			(at 0.2667 0 90)
			(size 0.3048 0.381)
			(layers "B.Cu" "B.Mask" "B.Paste")
			(net "P0V9_CPU1_RT0_2A_2D")
		)
		(pad "2" smd rect
			(at -0.2667 0 90)
			(size 0.3048 0.381)
			(layers "B.Cu" "B.Mask" "B.Paste")
			(net "GND")
		)
	)
	(footprint ""
		(layer "B.Cu")
		(at 301.099728 -396.991078 90)
		(property "Reference" "C576"
			(at 0 0 90)
			(layer "B.SilkS")
			(hide yes)
			(effects
				(font
					(size 1.27 1.27)
				)
				(justify mirror)
			)
		)
		(property "Value" ""
			(at 0 0 90)
			(layer "B.Fab")
			(effects
				(font
					(size 1.27 1.27)
				)
				(justify mirror)
			)
		)
		(duplicate_pad_numbers_are_jumpers no)
		(fp_line
			(start 0.299974 -0.150114)
			(end -0.299974 -0.150114)
			(stroke
				(width 0.1)
				(type default)
			)
			(layer "B.Fab")
		)
		(fp_line
			(start -0.299974 -0.150114)
			(end -0.299974 0.150114)
			(stroke
				(width 0.1)
				(type default)
			)
			(layer "B.Fab")
		)
		(fp_line
			(start 0.299974 0.150114)
			(end 0.299974 -0.150114)
			(stroke
				(width 0.1)
				(type default)
			)
			(layer "B.Fab")
		)
		(fp_line
			(start -0.299974 0.150114)
			(end 0.299974 0.150114)
			(stroke
				(width 0.1)
				(type default)
			)
			(layer "B.Fab")
		)
		(pad "1" smd rect
			(at 0.2667 0 270)
			(size 0.3048 0.381)
			(layers "B.Cu" "B.Mask" "B.Paste")
			(net "P0V9_CPU0_RT0_2A")
		)
		(pad "2" smd rect
			(at -0.2667 0 270)
			(size 0.3048 0.381)
			(layers "B.Cu" "B.Mask" "B.Paste")
			(net "GND")
		)
	)
	(footprint ""
		(layer "B.Cu")
		(at 378.019056 -182.867554 -90)
		(property "Reference" "PC556_3"
			(at 0 0 90)
			(layer "B.SilkS")
			(hide yes)
			(effects
				(font
					(size 1.27 1.27)
				)
				(justify mirror)
			)
		)
		(property "Value" ""
			(at 0 0 90)
			(layer "B.Fab")
			(effects
				(font
					(size 1.27 1.27)
				)
				(justify mirror)
			)
		)
		(duplicate_pad_numbers_are_jumpers no)
		(fp_line
			(start -1.524 0.762)
			(end 1.524 0.762)
			(stroke
				(width 0.1524)
				(type default)
			)
			(layer "B.SilkS")
		)
		(fp_line
			(start 1.524 0.762)
			(end 1.524 -0.762)
			(stroke
				(width 0.1524)
				(type default)
			)
			(layer "B.SilkS")
		)
		(fp_line
			(start -1.524 -0.762)
			(end -1.524 0.762)
			(stroke
				(width 0.1524)
				(type default)
			)
			(layer "B.SilkS")
		)
		(fp_line
			(start 1.524 -0.762)
			(end -1.524 -0.762)
			(stroke
				(width 0.1524)
				(type default)
			)
			(layer "B.SilkS")
		)
		(fp_line
			(start -1.1049 0.724916)
			(end -1.1049 -0.724916)
			(stroke
				(width 0.1)
				(type default)
			)
			(layer "B.Fab")
		)
		(fp_line
			(start 1.1049 0.724916)
			(end -1.1049 0.724916)
			(stroke
				(width 0.1)
				(type default)
			)
			(layer "B.Fab")
		)
		(fp_line
			(start -1.1049 -0.724916)
			(end 1.1049 -0.724916)
			(stroke
				(width 0.1)
				(type default)
			)
			(layer "B.Fab")
		)
		(fp_line
			(start 1.1049 -0.724916)
			(end 1.1049 0.724916)
			(stroke
				(width 0.1)
				(type default)
			)
			(layer "B.Fab")
		)
		(pad "1" smd rect
			(at 0.889 0 270)
			(size 1.016 1.27)
			(layers "B.Cu" "B.Mask" "B.Paste")
			(net "SW_P12V_AUX_PVDDCR_CPU0_P0_FLT")
		)
		(pad "2" smd rect
			(at -0.889 0 270)
			(size 1.016 1.27)
			(layers "B.Cu" "B.Mask" "B.Paste")
			(net "GND")
		)
	)
	(footprint ""
		(layer "B.Cu")
		(at 55.778654 -386.766562 90)
		(property "Reference" "C133"
			(at 0 0 90)
			(layer "B.SilkS")
			(hide yes)
			(effects
				(font
					(size 1.27 1.27)
				)
				(justify mirror)
			)
		)
		(property "Value" ""
			(at 0 0 90)
			(layer "B.Fab")
			(effects
				(font
					(size 1.27 1.27)
				)
				(justify mirror)
			)
		)
		(duplicate_pad_numbers_are_jumpers no)
		(fp_line
			(start 0.299974 -0.150114)
			(end -0.299974 -0.150114)
			(stroke
				(width 0.1)
				(type default)
			)
			(layer "B.Fab")
		)
		(fp_line
			(start -0.299974 -0.150114)
			(end -0.299974 0.150114)
			(stroke
				(width 0.1)
				(type default)
			)
			(layer "B.Fab")
		)
		(fp_line
			(start 0.299974 0.150114)
			(end 0.299974 -0.150114)
			(stroke
				(width 0.1)
				(type default)
			)
			(layer "B.Fab")
		)
		(fp_line
			(start -0.299974 0.150114)
			(end 0.299974 0.150114)
			(stroke
				(width 0.1)
				(type default)
			)
			(layer "B.Fab")
		)
		(pad "1" smd rect
			(at 0.2667 0 270)
			(size 0.3048 0.381)
			(layers "B.Cu" "B.Mask" "B.Paste")
			(net "P1V8_CPU1_RT0_1A")
		)
		(pad "2" smd rect
			(at -0.2667 0 270)
			(size 0.3048 0.381)
			(layers "B.Cu" "B.Mask" "B.Paste")
			(net "GND")
		)
	)
	(footprint ""
		(layer "B.Cu")
		(at 167.772588 -195.8594 180)
		(property "Reference" "R1705"
			(at 0 0 0)
			(layer "B.SilkS")
			(hide yes)
			(effects
				(font
					(size 1.27 1.27)
				)
				(justify mirror)
			)
		)
		(property "Value" ""
			(at 0 0 0)
			(layer "B.Fab")
			(effects
				(font
					(size 1.27 1.27)
				)
				(justify mirror)
			)
		)
		(duplicate_pad_numbers_are_jumpers no)
		(fp_line
			(start 0.7874 0.4064)
			(end 0.7874 -0.4064)
			(stroke
				(width 0.1524)
				(type default)
			)
			(layer "B.SilkS")
		)
		(fp_line
			(start 0.7874 -0.4064)
			(end -0.7874 -0.4064)
			(stroke
				(width 0.1524)
				(type default)
			)
			(layer "B.SilkS")
		)
		(fp_line
			(start -0.7874 0.4064)
			(end 0.7874 0.4064)
			(stroke
				(width 0.1524)
				(type default)
			)
			(layer "B.SilkS")
		)
		(fp_line
			(start -0.7874 -0.4064)
			(end -0.7874 0.4064)
			(stroke
				(width 0.1524)
				(type default)
			)
			(layer "B.SilkS")
		)
		(fp_line
			(start 0.67945 0.3048)
			(end 0.67945 -0.305054)
			(stroke
				(width 0.1)
				(type default)
			)
			(layer "B.Fab")
		)
		(fp_line
			(start 0.67945 -0.305054)
			(end 0.12065 -0.305054)
			(stroke
				(width 0.1)
				(type default)
			)
			(layer "B.Fab")
		)
		(fp_line
			(start 0.12065 0.3048)
			(end 0.67945 0.3048)
			(stroke
				(width 0.1)
				(type default)
			)
			(layer "B.Fab")
		)
		(fp_line
			(start 0.12065 0.2794)
			(end 0.12065 0.3048)
			(stroke
				(width 0.1)
				(type default)
			)
			(layer "B.Fab")
		)
		(fp_line
			(start 0.12065 -0.2794)
			(end -0.12065 -0.2794)
			(stroke
				(width 0.1)
				(type default)
			)
			(layer "B.Fab")
		)
		(fp_line
			(start 0.12065 -0.305054)
			(end 0.12065 -0.2794)
			(stroke
				(width 0.1)
				(type default)
			)
			(layer "B.Fab")
		)
		(fp_line
			(start -0.120396 0.3048)
			(end -0.120396 0.2794)
			(stroke
				(width 0.1)
				(type default)
			)
			(layer "B.Fab")
		)
		(fp_line
			(start -0.120396 0.2794)
			(end 0.12065 0.2794)
			(stroke
				(width 0.1)
				(type default)
			)
			(layer "B.Fab")
		)
		(fp_line
			(start -0.12065 -0.2794)
			(end -0.12065 -0.3048)
			(stroke
				(width 0.1)
				(type default)
			)
			(layer "B.Fab")
		)
		(fp_line
			(start -0.12065 -0.3048)
			(end -0.67945 -0.3048)
			(stroke
				(width 0.1)
				(type default)
			)
			(layer "B.Fab")
		)
		(fp_line
			(start -0.67945 0.3048)
			(end -0.120396 0.3048)
			(stroke
				(width 0.1)
				(type default)
			)
			(layer "B.Fab")
		)
		(fp_line
			(start -0.67945 -0.3048)
			(end -0.67945 0.3048)
			(stroke
				(width 0.1)
				(type default)
			)
			(layer "B.Fab")
		)
		(pad "1" smd circle
			(at 0.40005 0)
			(size 0 0)
			(layers "B.Cu" "B.Mask" "B.Paste")
			(net "I3C_SPD_DDRGL_CPU1_SDA")
		)
		(pad "2" smd circle
			(at -0.40005 0)
			(size 0 0)
			(layers "B.Cu" "B.Mask" "B.Paste")
			(net "I3C_SPD_DDRG_CPU1_SDA")
		)
	)
	(footprint ""
		(layer "B.Cu")
		(at 417.546282 -396.393162 -90)
		(property "Reference" "C982"
			(at 0 0 90)
			(layer "B.SilkS")
			(hide yes)
			(effects
				(font
					(size 1.27 1.27)
				)
				(justify mirror)
			)
		)
		(property "Value" ""
			(at 0 0 90)
			(layer "B.Fab")
			(effects
				(font
					(size 1.27 1.27)
				)
				(justify mirror)
			)
		)
		(duplicate_pad_numbers_are_jumpers no)
		(fp_line
			(start -0.299974 0.150114)
			(end 0.299974 0.150114)
			(stroke
				(width 0.1)
				(type default)
			)
			(layer "B.Fab")
		)
		(fp_line
			(start 0.299974 0.150114)
			(end 0.299974 -0.150114)
			(stroke
				(width 0.1)
				(type default)
			)
			(layer "B.Fab")
		)
		(fp_line
			(start -0.299974 -0.150114)
			(end -0.299974 0.150114)
			(stroke
				(width 0.1)
				(type default)
			)
			(layer "B.Fab")
		)
		(fp_line
			(start 0.299974 -0.150114)
			(end -0.299974 -0.150114)
			(stroke
				(width 0.1)
				(type default)
			)
			(layer "B.Fab")
		)
		(pad "1" smd rect
			(at 0.2667 0 90)
			(size 0.3048 0.381)
			(layers "B.Cu" "B.Mask" "B.Paste")
			(net "P0V9_CPU0_RT2_2A")
		)
		(pad "2" smd rect
			(at -0.2667 0 90)
			(size 0.3048 0.381)
			(layers "B.Cu" "B.Mask" "B.Paste")
			(net "GND")
		)
	)
	(footprint ""
		(layer "B.Cu")
		(at 391.585958 -321.179952)
		(property "Reference" "R473"
			(at 0 0 0)
			(layer "B.SilkS")
			(hide yes)
			(effects
				(font
					(size 1.27 1.27)
				)
				(justify mirror)
			)
		)
		(property "Value" ""
			(at 0 0 0)
			(layer "B.Fab")
			(effects
				(font
					(size 1.27 1.27)
				)
				(justify mirror)
			)
		)
		(duplicate_pad_numbers_are_jumpers no)
		(fp_line
			(start -0.7874 -0.4064)
			(end -0.7874 0.4064)
			(stroke
				(width 0.1524)
				(type default)
			)
			(layer "B.SilkS")
		)
		(fp_line
			(start -0.7874 0.4064)
			(end 0.7874 0.4064)
			(stroke
				(width 0.1524)
				(type default)
			)
			(layer "B.SilkS")
		)
		(fp_line
			(start 0.7874 -0.4064)
			(end -0.7874 -0.4064)
			(stroke
				(width 0.1524)
				(type default)
			)
			(layer "B.SilkS")
		)
		(fp_line
			(start 0.7874 0.4064)
			(end 0.7874 -0.4064)
			(stroke
				(width 0.1524)
				(type default)
			)
			(layer "B.SilkS")
		)
		(fp_line
			(start -0.67945 -0.3048)
			(end -0.67945 0.3048)
			(stroke
				(width 0.1)
				(type default)
			)
			(layer "B.Fab")
		)
		(fp_line
			(start -0.67945 0.3048)
			(end -0.120396 0.3048)
			(stroke
				(width 0.1)
				(type default)
			)
			(layer "B.Fab")
		)
		(fp_line
			(start -0.12065 -0.3048)
			(end -0.67945 -0.3048)
			(stroke
				(width 0.1)
				(type default)
			)
			(layer "B.Fab")
		)
		(fp_line
			(start -0.12065 -0.2794)
			(end -0.12065 -0.3048)
			(stroke
				(width 0.1)
				(type default)
			)
			(layer "B.Fab")
		)
		(fp_line
			(start -0.120396 0.2794)
			(end 0.12065 0.2794)
			(stroke
				(width 0.1)
				(type default)
			)
			(layer "B.Fab")
		)
		(fp_line
			(start -0.120396 0.3048)
			(end -0.120396 0.2794)
			(stroke
				(width 0.1)
				(type default)
			)
			(layer "B.Fab")
		)
		(fp_line
			(start 0.12065 -0.305054)
			(end 0.12065 -0.2794)
			(stroke
				(width 0.1)
				(type default)
			)
			(layer "B.Fab")
		)
		(fp_line
			(start 0.12065 -0.2794)
			(end -0.12065 -0.2794)
			(stroke
				(width 0.1)
				(type default)
			)
			(layer "B.Fab")
		)
		(fp_line
			(start 0.12065 0.2794)
			(end 0.12065 0.3048)
			(stroke
				(width 0.1)
				(type default)
			)
			(layer "B.Fab")
		)
		(fp_line
			(start 0.12065 0.3048)
			(end 0.67945 0.3048)
			(stroke
				(width 0.1)
				(type default)
			)
			(layer "B.Fab")
		)
		(fp_line
			(start 0.67945 -0.305054)
			(end 0.12065 -0.305054)
			(stroke
				(width 0.1)
				(type default)
			)
			(layer "B.Fab")
		)
		(fp_line
			(start 0.67945 0.3048)
			(end 0.67945 -0.305054)
			(stroke
				(width 0.1)
				(type default)
			)
			(layer "B.Fab")
		)
		(pad "1" smd circle
			(at 0.40005 0 180)
			(size 0 0)
			(layers "B.Cu" "B.Mask" "B.Paste")
			(net "CLK_ESPI_CPU0_CLK1")
		)
		(pad "2" smd circle
			(at -0.40005 0 180)
			(size 0 0)
			(layers "B.Cu" "B.Mask" "B.Paste")
			(net "CLK_ESPI_CPU0_R_CLK1")
		)
	)
	(footprint ""
		(layer "B.Cu")
		(at 209.441034 -73.168002 180)
		(property "Reference" "C641"
			(at 0 0 0)
			(layer "B.SilkS")
			(hide yes)
			(effects
				(font
					(size 1.27 1.27)
				)
				(justify mirror)
			)
		)
		(property "Value" ""
			(at 0 0 0)
			(layer "B.Fab")
			(effects
				(font
					(size 1.27 1.27)
				)
				(justify mirror)
			)
		)
		(duplicate_pad_numbers_are_jumpers no)
		(fp_line
			(start 0.7874 0.4064)
			(end 0.7874 -0.4064)
			(stroke
				(width 0.1524)
				(type default)
			)
			(layer "B.SilkS")
		)
		(fp_line
			(start 0.7874 -0.4064)
			(end -0.7874 -0.4064)
			(stroke
				(width 0.1524)
				(type default)
			)
			(layer "B.SilkS")
		)
		(fp_line
			(start -0.7874 0.4064)
			(end 0.7874 0.4064)
			(stroke
				(width 0.1524)
				(type default)
			)
			(layer "B.SilkS")
		)
		(fp_line
			(start -0.7874 -0.4064)
			(end -0.7874 0.4064)
			(stroke
				(width 0.1524)
				(type default)
			)
			(layer "B.SilkS")
		)
		(fp_line
			(start 0.67945 0.3048)
			(end 0.67945 -0.305054)
			(stroke
				(width 0.1)
				(type default)
			)
			(layer "B.Fab")
		)
		(fp_line
			(start 0.67945 -0.305054)
			(end 0.12065 -0.305054)
			(stroke
				(width 0.1)
				(type default)
			)
			(layer "B.Fab")
		)
		(fp_line
			(start 0.12065 0.3048)
			(end 0.67945 0.3048)
			(stroke
				(width 0.1)
				(type default)
			)
			(layer "B.Fab")
		)
		(fp_line
			(start 0.12065 0.2794)
			(end 0.12065 0.3048)
			(stroke
				(width 0.1)
				(type default)
			)
			(layer "B.Fab")
		)
		(fp_line
			(start 0.12065 -0.2794)
			(end -0.12065 -0.2794)
			(stroke
				(width 0.1)
				(type default)
			)
			(layer "B.Fab")
		)
		(fp_line
			(start 0.12065 -0.305054)
			(end 0.12065 -0.2794)
			(stroke
				(width 0.1)
				(type default)
			)
			(layer "B.Fab")
		)
		(fp_line
			(start -0.120396 0.3048)
			(end -0.120396 0.2794)
			(stroke
				(width 0.1)
				(type default)
			)
			(layer "B.Fab")
		)
		(fp_line
			(start -0.120396 0.2794)
			(end 0.12065 0.2794)
			(stroke
				(width 0.1)
				(type default)
			)
			(layer "B.Fab")
		)
		(fp_line
			(start -0.12065 -0.2794)
			(end -0.12065 -0.3048)
			(stroke
				(width 0.1)
				(type default)
			)
			(layer "B.Fab")
		)
		(fp_line
			(start -0.12065 -0.3048)
			(end -0.67945 -0.3048)
			(stroke
				(width 0.1)
				(type default)
			)
			(layer "B.Fab")
		)
		(fp_line
			(start -0.67945 0.3048)
			(end -0.120396 0.3048)
			(stroke
				(width 0.1)
				(type default)
			)
			(layer "B.Fab")
		)
		(fp_line
			(start -0.67945 -0.3048)
			(end -0.67945 0.3048)
			(stroke
				(width 0.1)
				(type default)
			)
			(layer "B.Fab")
		)
		(pad "1" smd circle
			(at 0.40005 0)
			(size 0 0)
			(layers "B.Cu" "B.Mask" "B.Paste")
			(net "P3V3_AUX")
		)
		(pad "2" smd circle
			(at -0.40005 0)
			(size 0 0)
			(layers "B.Cu" "B.Mask" "B.Paste")
			(net "GND")
		)
	)
	(footprint ""
		(layer "B.Cu")
		(at 383.38887 -181.684676 90)
		(property "Reference" "PR344"
			(at 0 0 90)
			(layer "B.SilkS")
			(hide yes)
			(effects
				(font
					(size 1.27 1.27)
				)
				(justify mirror)
			)
		)
		(property "Value" ""
			(at 0 0 90)
			(layer "B.Fab")
			(effects
				(font
					(size 1.27 1.27)
				)
				(justify mirror)
			)
		)
		(duplicate_pad_numbers_are_jumpers no)
		(fp_line
			(start 0.7874 -0.4064)
			(end -0.7874 -0.4064)
			(stroke
				(width 0.1524)
				(type default)
			)
			(layer "B.SilkS")
		)
		(fp_line
			(start -0.7874 -0.4064)
			(end -0.7874 0.4064)
			(stroke
				(width 0.1524)
				(type default)
			)
			(layer "B.SilkS")
		)
		(fp_line
			(start 0.7874 0.4064)
			(end 0.7874 -0.4064)
			(stroke
				(width 0.1524)
				(type default)
			)
			(layer "B.SilkS")
		)
		(fp_line
			(start -0.7874 0.4064)
			(end 0.7874 0.4064)
			(stroke
				(width 0.1524)
				(type default)
			)
			(layer "B.SilkS")
		)
		(fp_line
			(start 0.67945 -0.305054)
			(end 0.12065 -0.305054)
			(stroke
				(width 0.1)
				(type default)
			)
			(layer "B.Fab")
		)
		(fp_line
			(start 0.12065 -0.305054)
			(end 0.12065 -0.2794)
			(stroke
				(width 0.1)
				(type default)
			)
			(layer "B.Fab")
		)
		(fp_line
			(start -0.12065 -0.3048)
			(end -0.67945 -0.3048)
			(stroke
				(width 0.1)
				(type default)
			)
			(layer "B.Fab")
		)
		(fp_line
			(start -0.67945 -0.3048)
			(end -0.67945 0.3048)
			(stroke
				(width 0.1)
				(type default)
			)
			(layer "B.Fab")
		)
		(fp_line
			(start 0.12065 -0.2794)
			(end -0.12065 -0.2794)
			(stroke
				(width 0.1)
				(type default)
			)
			(layer "B.Fab")
		)
		(fp_line
			(start -0.12065 -0.2794)
			(end -0.12065 -0.3048)
			(stroke
				(width 0.1)
				(type default)
			)
			(layer "B.Fab")
		)
		(fp_line
			(start 0.12065 0.2794)
			(end 0.12065 0.3048)
			(stroke
				(width 0.1)
				(type default)
			)
			(layer "B.Fab")
		)
		(fp_line
			(start -0.120396 0.2794)
			(end 0.12065 0.2794)
			(stroke
				(width 0.1)
				(type default)
			)
			(layer "B.Fab")
		)
		(fp_line
			(start 0.67945 0.3048)
			(end 0.67945 -0.305054)
			(stroke
				(width 0.1)
				(type default)
			)
			(layer "B.Fab")
		)
		(fp_line
			(start 0.12065 0.3048)
			(end 0.67945 0.3048)
			(stroke
				(width 0.1)
				(type default)
			)
			(layer "B.Fab")
		)
		(fp_line
			(start -0.120396 0.3048)
			(end -0.120396 0.2794)
			(stroke
				(width 0.1)
				(type default)
			)
			(layer "B.Fab")
		)
		(fp_line
			(start -0.67945 0.3048)
			(end -0.120396 0.3048)
			(stroke
				(width 0.1)
				(type default)
			)
			(layer "B.Fab")
		)
		(pad "1" smd circle
			(at 0.40005 0 270)
			(size 0 0)
			(layers "B.Cu" "B.Mask" "B.Paste")
			(net "PVDDCR_CPU0_P0_PVCC")
		)
		(pad "2" smd circle
			(at -0.40005 0 270)
			(size 0 0)
			(layers "B.Cu" "B.Mask" "B.Paste")
			(net "PVDDCR_CPU0_P0_VCC3")
		)
	)
	(footprint ""
		(layer "B.Cu")
		(at 237.236 -219.075 90)
		(property "Reference" "C26"
			(at 0 0 90)
			(layer "B.SilkS")
			(hide yes)
			(effects
				(font
					(size 1.27 1.27)
				)
				(justify mirror)
			)
		)
		(property "Value" ""
			(at 0 0 90)
			(layer "B.Fab")
			(effects
				(font
					(size 1.27 1.27)
				)
				(justify mirror)
			)
		)
		(duplicate_pad_numbers_are_jumpers no)
		(fp_line
			(start 0.7874 -0.4064)
			(end -0.7874 -0.4064)
			(stroke
				(width 0.1524)
				(type default)
			)
			(layer "B.SilkS")
		)
		(fp_line
			(start -0.7874 -0.4064)
			(end -0.7874 0.4064)
			(stroke
				(width 0.1524)
				(type default)
			)
			(layer "B.SilkS")
		)
		(fp_line
			(start 0.7874 0.4064)
			(end 0.7874 -0.4064)
			(stroke
				(width 0.1524)
				(type default)
			)
			(layer "B.SilkS")
		)
		(fp_line
			(start -0.7874 0.4064)
			(end 0.7874 0.4064)
			(stroke
				(width 0.1524)
				(type default)
			)
			(layer "B.SilkS")
		)
		(fp_line
			(start 0.67945 -0.305054)
			(end 0.12065 -0.305054)
			(stroke
				(width 0.1)
				(type default)
			)
			(layer "B.Fab")
		)
		(fp_line
			(start 0.12065 -0.305054)
			(end 0.12065 -0.2794)
			(stroke
				(width 0.1)
				(type default)
			)
			(layer "B.Fab")
		)
		(fp_line
			(start -0.12065 -0.3048)
			(end -0.67945 -0.3048)
			(stroke
				(width 0.1)
				(type default)
			)
			(layer "B.Fab")
		)
		(fp_line
			(start -0.67945 -0.3048)
			(end -0.67945 0.3048)
			(stroke
				(width 0.1)
				(type default)
			)
			(layer "B.Fab")
		)
		(fp_line
			(start 0.12065 -0.2794)
			(end -0.12065 -0.2794)
			(stroke
				(width 0.1)
				(type default)
			)
			(layer "B.Fab")
		)
		(fp_line
			(start -0.12065 -0.2794)
			(end -0.12065 -0.3048)
			(stroke
				(width 0.1)
				(type default)
			)
			(layer "B.Fab")
		)
		(fp_line
			(start 0.12065 0.2794)
			(end 0.12065 0.3048)
			(stroke
				(width 0.1)
				(type default)
			)
			(layer "B.Fab")
		)
		(fp_line
			(start -0.120396 0.2794)
			(end 0.12065 0.2794)
			(stroke
				(width 0.1)
				(type default)
			)
			(layer "B.Fab")
		)
		(fp_line
			(start 0.67945 0.3048)
			(end 0.67945 -0.305054)
			(stroke
				(width 0.1)
				(type default)
			)
			(layer "B.Fab")
		)
		(fp_line
			(start 0.12065 0.3048)
			(end 0.67945 0.3048)
			(stroke
				(width 0.1)
				(type default)
			)
			(layer "B.Fab")
		)
		(fp_line
			(start -0.120396 0.3048)
			(end -0.120396 0.2794)
			(stroke
				(width 0.1)
				(type default)
			)
			(layer "B.Fab")
		)
		(fp_line
			(start -0.67945 0.3048)
			(end -0.120396 0.3048)
			(stroke
				(width 0.1)
				(type default)
			)
			(layer "B.Fab")
		)
		(pad "1" smd circle
			(at 0.40005 0 270)
			(size 0 0)
			(layers "B.Cu" "B.Mask" "B.Paste")
			(net "P3V3")
		)
		(pad "2" smd circle
			(at -0.40005 0 270)
			(size 0 0)
			(layers "B.Cu" "B.Mask" "B.Paste")
			(net "GND")
		)
	)
	(footprint ""
		(layer "B.Cu")
		(at 101.41839 -340.998556 -90)
		(property "Reference" "PR427"
			(at 0 0 90)
			(layer "B.SilkS")
			(hide yes)
			(effects
				(font
					(size 1.27 1.27)
				)
				(justify mirror)
			)
		)
		(property "Value" ""
			(at 0 0 90)
			(layer "B.Fab")
			(effects
				(font
					(size 1.27 1.27)
				)
				(justify mirror)
			)
		)
		(duplicate_pad_numbers_are_jumpers no)
		(fp_line
			(start -0.7874 0.4064)
			(end 0.7874 0.4064)
			(stroke
				(width 0.1524)
				(type default)
			)
			(layer "B.SilkS")
		)
		(fp_line
			(start 0.7874 0.4064)
			(end 0.7874 -0.4064)
			(stroke
				(width 0.1524)
				(type default)
			)
			(layer "B.SilkS")
		)
		(fp_line
			(start -0.7874 -0.4064)
			(end -0.7874 0.4064)
			(stroke
				(width 0.1524)
				(type default)
			)
			(layer "B.SilkS")
		)
		(fp_line
			(start 0.7874 -0.4064)
			(end -0.7874 -0.4064)
			(stroke
				(width 0.1524)
				(type default)
			)
			(layer "B.SilkS")
		)
		(fp_line
			(start -0.67945 0.3048)
			(end -0.120396 0.3048)
			(stroke
				(width 0.1)
				(type default)
			)
			(layer "B.Fab")
		)
		(fp_line
			(start -0.120396 0.3048)
			(end -0.120396 0.2794)
			(stroke
				(width 0.1)
				(type default)
			)
			(layer "B.Fab")
		)
		(fp_line
			(start 0.12065 0.3048)
			(end 0.67945 0.3048)
			(stroke
				(width 0.1)
				(type default)
			)
			(layer "B.Fab")
		)
		(fp_line
			(start 0.67945 0.3048)
			(end 0.67945 -0.305054)
			(stroke
				(width 0.1)
				(type default)
			)
			(layer "B.Fab")
		)
		(fp_line
			(start -0.120396 0.2794)
			(end 0.12065 0.2794)
			(stroke
				(width 0.1)
				(type default)
			)
			(layer "B.Fab")
		)
		(fp_line
			(start 0.12065 0.2794)
			(end 0.12065 0.3048)
			(stroke
				(width 0.1)
				(type default)
			)
			(layer "B.Fab")
		)
		(fp_line
			(start -0.12065 -0.2794)
			(end -0.12065 -0.3048)
			(stroke
				(width 0.1)
				(type default)
			)
			(layer "B.Fab")
		)
		(fp_line
			(start 0.12065 -0.2794)
			(end -0.12065 -0.2794)
			(stroke
				(width 0.1)
				(type default)
			)
			(layer "B.Fab")
		)
		(fp_line
			(start -0.67945 -0.3048)
			(end -0.67945 0.3048)
			(stroke
				(width 0.1)
				(type default)
			)
			(layer "B.Fab")
		)
		(fp_line
			(start -0.12065 -0.3048)
			(end -0.67945 -0.3048)
			(stroke
				(width 0.1)
				(type default)
			)
			(layer "B.Fab")
		)
		(fp_line
			(start 0.12065 -0.305054)
			(end 0.12065 -0.2794)
			(stroke
				(width 0.1)
				(type default)
			)
			(layer "B.Fab")
		)
		(fp_line
			(start 0.67945 -0.305054)
			(end 0.12065 -0.305054)
			(stroke
				(width 0.1)
				(type default)
			)
			(layer "B.Fab")
		)
		(pad "1" smd circle
			(at 0.40005 0 90)
			(size 0 0)
			(layers "B.Cu" "B.Mask" "B.Paste")
			(net "PVDDCR_CPU1_P1_PVCC")
		)
		(pad "2" smd circle
			(at -0.40005 0 90)
			(size 0 0)
			(layers "B.Cu" "B.Mask" "B.Paste")
			(net "PVDDCR_CPU1_P1_VCC6")
		)
	)
	(footprint ""
		(layer "B.Cu")
		(at 200.023222 -123.831096 180)
		(property "Reference" "R2846"
			(at 0 0 0)
			(layer "B.SilkS")
			(hide yes)
			(effects
				(font
					(size 1.27 1.27)
				)
				(justify mirror)
			)
		)
		(property "Value" ""
			(at 0 0 0)
			(layer "B.Fab")
			(effects
				(font
					(size 1.27 1.27)
				)
				(justify mirror)
			)
		)
		(duplicate_pad_numbers_are_jumpers no)
		(fp_line
			(start 0.7874 0.4064)
			(end 0.7874 -0.4064)
			(stroke
				(width 0.1524)
				(type default)
			)
			(layer "B.SilkS")
		)
		(fp_line
			(start 0.7874 -0.4064)
			(end -0.7874 -0.4064)
			(stroke
				(width 0.1524)
				(type default)
			)
			(layer "B.SilkS")
		)
		(fp_line
			(start -0.7874 0.4064)
			(end 0.7874 0.4064)
			(stroke
				(width 0.1524)
				(type default)
			)
			(layer "B.SilkS")
		)
		(fp_line
			(start -0.7874 -0.4064)
			(end -0.7874 0.4064)
			(stroke
				(width 0.1524)
				(type default)
			)
			(layer "B.SilkS")
		)
		(fp_line
			(start 0.67945 0.3048)
			(end 0.67945 -0.305054)
			(stroke
				(width 0.1)
				(type default)
			)
			(layer "B.Fab")
		)
		(fp_line
			(start 0.67945 -0.305054)
			(end 0.12065 -0.305054)
			(stroke
				(width 0.1)
				(type default)
			)
			(layer "B.Fab")
		)
		(fp_line
			(start 0.12065 0.3048)
			(end 0.67945 0.3048)
			(stroke
				(width 0.1)
				(type default)
			)
			(layer "B.Fab")
		)
		(fp_line
			(start 0.12065 0.2794)
			(end 0.12065 0.3048)
			(stroke
				(width 0.1)
				(type default)
			)
			(layer "B.Fab")
		)
		(fp_line
			(start 0.12065 -0.2794)
			(end -0.12065 -0.2794)
			(stroke
				(width 0.1)
				(type default)
			)
			(layer "B.Fab")
		)
		(fp_line
			(start 0.12065 -0.305054)
			(end 0.12065 -0.2794)
			(stroke
				(width 0.1)
				(type default)
			)
			(layer "B.Fab")
		)
		(fp_line
			(start -0.120396 0.3048)
			(end -0.120396 0.2794)
			(stroke
				(width 0.1)
				(type default)
			)
			(layer "B.Fab")
		)
		(fp_line
			(start -0.120396 0.2794)
			(end 0.12065 0.2794)
			(stroke
				(width 0.1)
				(type default)
			)
			(layer "B.Fab")
		)
		(fp_line
			(start -0.12065 -0.2794)
			(end -0.12065 -0.3048)
			(stroke
				(width 0.1)
				(type default)
			)
			(layer "B.Fab")
		)
		(fp_line
			(start -0.12065 -0.3048)
			(end -0.67945 -0.3048)
			(stroke
				(width 0.1)
				(type default)
			)
			(layer "B.Fab")
		)
		(fp_line
			(start -0.67945 0.3048)
			(end -0.120396 0.3048)
			(stroke
				(width 0.1)
				(type default)
			)
			(layer "B.Fab")
		)
		(fp_line
			(start -0.67945 -0.3048)
			(end -0.67945 0.3048)
			(stroke
				(width 0.1)
				(type default)
			)
			(layer "B.Fab")
		)
		(pad "1" smd circle
			(at 0.40005 0)
			(size 0 0)
			(layers "B.Cu" "B.Mask" "B.Paste")
			(net "BIC_MONITER_ISO_R")
		)
		(pad "2" smd circle
			(at -0.40005 0)
			(size 0 0)
			(layers "B.Cu" "B.Mask" "B.Paste")
			(net "BIC_MONITER_ISO")
		)
	)
	(footprint ""
		(layer "B.Cu")
		(at 113.105946 -259.845302 180)
		(property "Reference" "C2505"
			(at 0 0 0)
			(layer "B.SilkS")
			(hide yes)
			(effects
				(font
					(size 1.27 1.27)
				)
				(justify mirror)
			)
		)
		(property "Value" ""
			(at 0 0 0)
			(layer "B.Fab")
			(effects
				(font
					(size 1.27 1.27)
				)
				(justify mirror)
			)
		)
		(duplicate_pad_numbers_are_jumpers no)
		(fp_line
			(start 0.7874 0.4064)
			(end 0.7874 -0.4064)
			(stroke
				(width 0.1524)
				(type default)
			)
			(layer "B.SilkS")
		)
		(fp_line
			(start 0.7874 -0.4064)
			(end -0.7874 -0.4064)
			(stroke
				(width 0.1524)
				(type default)
			)
			(layer "B.SilkS")
		)
		(fp_line
			(start -0.7874 0.4064)
			(end 0.7874 0.4064)
			(stroke
				(width 0.1524)
				(type default)
			)
			(layer "B.SilkS")
		)
		(fp_line
			(start -0.7874 -0.4064)
			(end -0.7874 0.4064)
			(stroke
				(width 0.1524)
				(type default)
			)
			(layer "B.SilkS")
		)
		(fp_line
			(start 0.67945 0.3048)
			(end 0.67945 -0.305054)
			(stroke
				(width 0.1)
				(type default)
			)
			(layer "B.Fab")
		)
		(fp_line
			(start 0.67945 -0.305054)
			(end 0.12065 -0.305054)
			(stroke
				(width 0.1)
				(type default)
			)
			(layer "B.Fab")
		)
		(fp_line
			(start 0.12065 0.3048)
			(end 0.67945 0.3048)
			(stroke
				(width 0.1)
				(type default)
			)
			(layer "B.Fab")
		)
		(fp_line
			(start 0.12065 0.2794)
			(end 0.12065 0.3048)
			(stroke
				(width 0.1)
				(type default)
			)
			(layer "B.Fab")
		)
		(fp_line
			(start 0.12065 -0.2794)
			(end -0.12065 -0.2794)
			(stroke
				(width 0.1)
				(type default)
			)
			(layer "B.Fab")
		)
		(fp_line
			(start 0.12065 -0.305054)
			(end 0.12065 -0.2794)
			(stroke
				(width 0.1)
				(type default)
			)
			(layer "B.Fab")
		)
		(fp_line
			(start -0.120396 0.3048)
			(end -0.120396 0.2794)
			(stroke
				(width 0.1)
				(type default)
			)
			(layer "B.Fab")
		)
		(fp_line
			(start -0.120396 0.2794)
			(end 0.12065 0.2794)
			(stroke
				(width 0.1)
				(type default)
			)
			(layer "B.Fab")
		)
		(fp_line
			(start -0.12065 -0.2794)
			(end -0.12065 -0.3048)
			(stroke
				(width 0.1)
				(type default)
			)
			(layer "B.Fab")
		)
		(fp_line
			(start -0.12065 -0.3048)
			(end -0.67945 -0.3048)
			(stroke
				(width 0.1)
				(type default)
			)
			(layer "B.Fab")
		)
		(fp_line
			(start -0.67945 0.3048)
			(end -0.120396 0.3048)
			(stroke
				(width 0.1)
				(type default)
			)
			(layer "B.Fab")
		)
		(fp_line
			(start -0.67945 -0.3048)
			(end -0.67945 0.3048)
			(stroke
				(width 0.1)
				(type default)
			)
			(layer "B.Fab")
		)
		(pad "1" smd circle
			(at 0.40005 0)
			(size 0 0)
			(layers "B.Cu" "B.Mask" "B.Paste")
			(net "PVDD11_S3_P1")
		)
		(pad "2" smd circle
			(at -0.40005 0)
			(size 0 0)
			(layers "B.Cu" "B.Mask" "B.Paste")
			(net "GND")
		)
	)
	(footprint ""
		(layer "B.Cu")
		(at 117.895624 -258.405376)
		(property "Reference" "C2476"
			(at 0 0 0)
			(layer "B.SilkS")
			(hide yes)
			(effects
				(font
					(size 1.27 1.27)
				)
				(justify mirror)
			)
		)
		(property "Value" ""
			(at 0 0 0)
			(layer "B.Fab")
			(effects
				(font
					(size 1.27 1.27)
				)
				(justify mirror)
			)
		)
		(duplicate_pad_numbers_are_jumpers no)
		(fp_line
			(start -0.7874 -0.4064)
			(end -0.7874 0.4064)
			(stroke
				(width 0.1524)
				(type default)
			)
			(layer "B.SilkS")
		)
		(fp_line
			(start -0.7874 0.4064)
			(end 0.7874 0.4064)
			(stroke
				(width 0.1524)
				(type default)
			)
			(layer "B.SilkS")
		)
		(fp_line
			(start 0.7874 -0.4064)
			(end -0.7874 -0.4064)
			(stroke
				(width 0.1524)
				(type default)
			)
			(layer "B.SilkS")
		)
		(fp_line
			(start 0.7874 0.4064)
			(end 0.7874 -0.4064)
			(stroke
				(width 0.1524)
				(type default)
			)
			(layer "B.SilkS")
		)
		(fp_line
			(start -0.67945 -0.3048)
			(end -0.67945 0.3048)
			(stroke
				(width 0.1)
				(type default)
			)
			(layer "B.Fab")
		)
		(fp_line
			(start -0.67945 0.3048)
			(end -0.120396 0.3048)
			(stroke
				(width 0.1)
				(type default)
			)
			(layer "B.Fab")
		)
		(fp_line
			(start -0.12065 -0.3048)
			(end -0.67945 -0.3048)
			(stroke
				(width 0.1)
				(type default)
			)
			(layer "B.Fab")
		)
		(fp_line
			(start -0.12065 -0.2794)
			(end -0.12065 -0.3048)
			(stroke
				(width 0.1)
				(type default)
			)
			(layer "B.Fab")
		)
		(fp_line
			(start -0.120396 0.2794)
			(end 0.12065 0.2794)
			(stroke
				(width 0.1)
				(type default)
			)
			(layer "B.Fab")
		)
		(fp_line
			(start -0.120396 0.3048)
			(end -0.120396 0.2794)
			(stroke
				(width 0.1)
				(type default)
			)
			(layer "B.Fab")
		)
		(fp_line
			(start 0.12065 -0.305054)
			(end 0.12065 -0.2794)
			(stroke
				(width 0.1)
				(type default)
			)
			(layer "B.Fab")
		)
		(fp_line
			(start 0.12065 -0.2794)
			(end -0.12065 -0.2794)
			(stroke
				(width 0.1)
				(type default)
			)
			(layer "B.Fab")
		)
		(fp_line
			(start 0.12065 0.2794)
			(end 0.12065 0.3048)
			(stroke
				(width 0.1)
				(type default)
			)
			(layer "B.Fab")
		)
		(fp_line
			(start 0.12065 0.3048)
			(end 0.67945 0.3048)
			(stroke
				(width 0.1)
				(type default)
			)
			(layer "B.Fab")
		)
		(fp_line
			(start 0.67945 -0.305054)
			(end 0.12065 -0.305054)
			(stroke
				(width 0.1)
				(type default)
			)
			(layer "B.Fab")
		)
		(fp_line
			(start 0.67945 0.3048)
			(end 0.67945 -0.305054)
			(stroke
				(width 0.1)
				(type default)
			)
			(layer "B.Fab")
		)
		(pad "1" smd circle
			(at 0.40005 0 180)
			(size 0 0)
			(layers "B.Cu" "B.Mask" "B.Paste")
			(net "PVDDCR_SOC_P1")
		)
		(pad "2" smd circle
			(at -0.40005 0 180)
			(size 0 0)
			(layers "B.Cu" "B.Mask" "B.Paste")
			(net "GND")
		)
	)
	(footprint ""
		(layer "B.Cu")
		(at 351.248726 -416.899344 90)
		(property "Reference" "C6564"
			(at 0 0 90)
			(layer "B.SilkS")
			(hide yes)
			(effects
				(font
					(size 1.27 1.27)
				)
				(justify mirror)
			)
		)
		(property "Value" ""
			(at 0 0 90)
			(layer "B.Fab")
			(effects
				(font
					(size 1.27 1.27)
				)
				(justify mirror)
			)
		)
		(duplicate_pad_numbers_are_jumpers no)
		(fp_line
			(start 0.299974 -0.150114)
			(end -0.299974 -0.150114)
			(stroke
				(width 0.1)
				(type default)
			)
			(layer "B.Fab")
		)
		(fp_line
			(start -0.299974 -0.150114)
			(end -0.299974 0.150114)
			(stroke
				(width 0.1)
				(type default)
			)
			(layer "B.Fab")
		)
		(fp_line
			(start 0.299974 0.150114)
			(end 0.299974 -0.150114)
			(stroke
				(width 0.1)
				(type default)
			)
			(layer "B.Fab")
		)
		(fp_line
			(start -0.299974 0.150114)
			(end 0.299974 0.150114)
			(stroke
				(width 0.1)
				(type default)
			)
			(layer "B.Fab")
		)
		(pad "1" smd rect
			(at 0.2667 0 270)
			(size 0.3048 0.381)
			(layers "B.Cu" "B.Mask" "B.Paste")
			(net "P5E_CPU0_P1_TX_BUF_C_DN<15>")
		)
		(pad "2" smd rect
			(at -0.2667 0 270)
			(size 0.3048 0.381)
			(layers "B.Cu" "B.Mask" "B.Paste")
			(net "P5E_CPU0_P1_TX_BUF_DN<15>")
		)
	)
	(footprint ""
		(layer "B.Cu")
		(at 109.095794 -383.7432 180)
		(property "Reference" "R909"
			(at 0 0 0)
			(layer "B.SilkS")
			(hide yes)
			(effects
				(font
					(size 1.27 1.27)
				)
				(justify mirror)
			)
		)
		(property "Value" ""
			(at 0 0 0)
			(layer "B.Fab")
			(effects
				(font
					(size 1.27 1.27)
				)
				(justify mirror)
			)
		)
		(duplicate_pad_numbers_are_jumpers no)
		(fp_line
			(start 0.32512 0.175006)
			(end 0.32512 -0.175006)
			(stroke
				(width 0.1)
				(type default)
			)
			(layer "B.Fab")
		)
		(fp_line
			(start 0.32512 -0.175006)
			(end -0.32512 -0.175006)
			(stroke
				(width 0.1)
				(type default)
			)
			(layer "B.Fab")
		)
		(fp_line
			(start -0.32512 0.175006)
			(end 0.32512 0.175006)
			(stroke
				(width 0.1)
				(type default)
			)
			(layer "B.Fab")
		)
		(fp_line
			(start -0.32512 -0.175006)
			(end -0.32512 0.175006)
			(stroke
				(width 0.1)
				(type default)
			)
			(layer "B.Fab")
		)
		(pad "1" smd rect
			(at 0.2667 0)
			(size 0.3048 0.381)
			(layers "B.Cu" "B.Mask" "B.Paste")
			(net "P1V8_CPU1_RT_1D")
		)
		(pad "2" smd rect
			(at -0.2667 0 180)
			(size 0.3048 0.381)
			(layers "B.Cu" "B.Mask" "B.Paste")
			(net "RT_CPU1_P3_SCAN_MODE")
		)
	)
	(footprint ""
		(layer "B.Cu")
		(at 88.446356 -388.011162 -90)
		(property "Reference" "C202"
			(at 0 0 90)
			(layer "B.SilkS")
			(hide yes)
			(effects
				(font
					(size 1.27 1.27)
				)
				(justify mirror)
			)
		)
		(property "Value" ""
			(at 0 0 90)
			(layer "B.Fab")
			(effects
				(font
					(size 1.27 1.27)
				)
				(justify mirror)
			)
		)
		(duplicate_pad_numbers_are_jumpers no)
		(fp_line
			(start -0.299974 0.150114)
			(end 0.299974 0.150114)
			(stroke
				(width 0.1)
				(type default)
			)
			(layer "B.Fab")
		)
		(fp_line
			(start 0.299974 0.150114)
			(end 0.299974 -0.150114)
			(stroke
				(width 0.1)
				(type default)
			)
			(layer "B.Fab")
		)
		(fp_line
			(start -0.299974 -0.150114)
			(end -0.299974 0.150114)
			(stroke
				(width 0.1)
				(type default)
			)
			(layer "B.Fab")
		)
		(fp_line
			(start 0.299974 -0.150114)
			(end -0.299974 -0.150114)
			(stroke
				(width 0.1)
				(type default)
			)
			(layer "B.Fab")
		)
		(pad "1" smd rect
			(at 0.2667 0 90)
			(size 0.3048 0.381)
			(layers "B.Cu" "B.Mask" "B.Paste")
			(net "P1V8_CPU1_RT1_1A")
		)
		(pad "2" smd rect
			(at -0.2667 0 90)
			(size 0.3048 0.381)
			(layers "B.Cu" "B.Mask" "B.Paste")
			(net "GND")
		)
	)
	(footprint ""
		(layer "B.Cu")
		(at 450.088 -192.660016 180)
		(property "Reference" "C171"
			(at 0 0 0)
			(layer "B.SilkS")
			(hide yes)
			(effects
				(font
					(size 1.27 1.27)
				)
				(justify mirror)
			)
		)
		(property "Value" ""
			(at 0 0 0)
			(layer "B.Fab")
			(effects
				(font
					(size 1.27 1.27)
				)
				(justify mirror)
			)
		)
		(duplicate_pad_numbers_are_jumpers no)
		(fp_line
			(start 1.524 0.762)
			(end 1.524 -0.762)
			(stroke
				(width 0.1524)
				(type default)
			)
			(layer "B.SilkS")
		)
		(fp_line
			(start 1.524 -0.762)
			(end -1.524 -0.762)
			(stroke
				(width 0.1524)
				(type default)
			)
			(layer "B.SilkS")
		)
		(fp_line
			(start -1.524 0.762)
			(end 1.524 0.762)
			(stroke
				(width 0.1524)
				(type default)
			)
			(layer "B.SilkS")
		)
		(fp_line
			(start -1.524 -0.762)
			(end -1.524 0.762)
			(stroke
				(width 0.1524)
				(type default)
			)
			(layer "B.SilkS")
		)
		(fp_line
			(start 1.1049 0.724916)
			(end -1.1049 0.724916)
			(stroke
				(width 0.1)
				(type default)
			)
			(layer "B.Fab")
		)
		(fp_line
			(start 1.1049 -0.724916)
			(end 1.1049 0.724916)
			(stroke
				(width 0.1)
				(type default)
			)
			(layer "B.Fab")
		)
		(fp_line
			(start -1.1049 0.724916)
			(end -1.1049 -0.724916)
			(stroke
				(width 0.1)
				(type default)
			)
			(layer "B.Fab")
		)
		(fp_line
			(start -1.1049 -0.724916)
			(end 1.1049 -0.724916)
			(stroke
				(width 0.1)
				(type default)
			)
			(layer "B.Fab")
		)
		(pad "1" smd rect
			(at 0.889 0 180)
			(size 1.016 1.27)
			(layers "B.Cu" "B.Mask" "B.Paste")
			(net "P12V_MEM_CPU0")
		)
		(pad "2" smd rect
			(at -0.889 0 180)
			(size 1.016 1.27)
			(layers "B.Cu" "B.Mask" "B.Paste")
			(net "GND")
		)
	)
	(footprint ""
		(layer "B.Cu")
		(at 83.045554 -189.461648 90)
		(property "Reference" "PC277"
			(at 5.774436 -1.099566 270)
			(unlocked yes)
			(layer "B.SilkS")
			(effects
				(font
					(size 0.7874 0.5842)
					(thickness 0.1524)
				)
				(justify left mirror)
			)
		)
		(property "Value" ""
			(at 0 0 90)
			(layer "B.Fab")
			(effects
				(font
					(size 1.27 1.27)
				)
				(justify mirror)
			)
		)
		(duplicate_pad_numbers_are_jumpers no)
		(fp_line
			(start 4.533392 -2.249932)
			(end -4.533392 -2.249932)
			(stroke
				(width 0.1524)
				(type default)
			)
			(layer "B.SilkS")
		)
		(fp_line
			(start -4.533392 -2.249932)
			(end -4.533392 2.249932)
			(stroke
				(width 0.1524)
				(type default)
			)
			(layer "B.SilkS")
		)
		(fp_line
			(start 4.533392 2.249932)
			(end 4.533392 -2.249932)
			(stroke
				(width 0.1524)
				(type default)
			)
			(layer "B.SilkS")
		)
		(fp_line
			(start -4.533392 2.249932)
			(end 4.533392 2.249932)
			(stroke
				(width 0.1524)
				(type default)
			)
			(layer "B.SilkS")
		)
		(fp_rect
			(start 4.533392 -2.326132)
			(end 5.39242 2.326132)
			(stroke
				(width 0)
				(type default)
			)
			(fill yes)
			(layer "B.SilkS")
		)
		(fp_line
			(start 3.750056 -2.249932)
			(end -3.750056 -2.249932)
			(stroke
				(width 0.1)
				(type default)
			)
			(layer "B.Fab")
		)
		(fp_line
			(start -3.750056 -2.249932)
			(end -3.750056 2.249932)
			(stroke
				(width 0.1)
				(type default)
			)
			(layer "B.Fab")
		)
		(fp_line
			(start 3.750056 2.249932)
			(end 3.750056 -2.249932)
			(stroke
				(width 0.1)
				(type default)
			)
			(layer "B.Fab")
		)
		(fp_line
			(start -3.750056 2.249932)
			(end 3.750056 2.249932)
			(stroke
				(width 0.1)
				(type default)
			)
			(layer "B.Fab")
		)
		(fp_text user "-"
			(at -4.8514 -0.14605 90)
			(unlocked yes)
			(layer "B.SilkS")
			(effects
				(font
					(size 1.905 1.4224)
					(thickness 0.1524)
				)
				(justify left mirror)
			)
		)
		(fp_text user "+"
			(at 6.322314 0.786384 0)
			(unlocked yes)
			(layer "B.SilkS")
			(effects
				(font
					(size 1.905 1.4224)
					(thickness 0.1524)
				)
				(justify left mirror)
			)
		)
		(fp_text user "-"
			(at -4.8514 -0.14605 90)
			(unlocked yes)
			(layer "B.Fab")
			(effects
				(font
					(size 1.905 1.4224)
					(thickness 0.1524)
				)
				(justify left mirror)
			)
		)
		(fp_text user "+"
			(at 6.322314 0.786384 0)
			(unlocked yes)
			(layer "B.Fab")
			(effects
				(font
					(size 1.905 1.4224)
					(thickness 0.1524)
				)
				(justify left mirror)
			)
		)
		(pad "1" smd rect
			(at 3.199892 0 270)
			(size 2.413 2.8194)
			(layers "B.Cu" "B.Mask" "B.Paste")
			(net "PVDDCR_CPU0_P1")
		)
		(pad "2" smd rect
			(at -3.199892 0 270)
			(size 2.413 2.8194)
			(layers "B.Cu" "B.Mask" "B.Paste")
			(net "GND")
		)
	)
	(footprint ""
		(layer "B.Cu")
		(at 384.113278 -141.218158 180)
		(property "Reference" "PC469"
			(at 0 0 0)
			(layer "B.SilkS")
			(hide yes)
			(effects
				(font
					(size 1.27 1.27)
				)
				(justify mirror)
			)
		)
		(property "Value" ""
			(at 0 0 0)
			(layer "B.Fab")
			(effects
				(font
					(size 1.27 1.27)
				)
				(justify mirror)
			)
		)
		(duplicate_pad_numbers_are_jumpers no)
		(fp_line
			(start 0.7874 0.4064)
			(end 0.7874 -0.4064)
			(stroke
				(width 0.1524)
				(type default)
			)
			(layer "B.SilkS")
		)
		(fp_line
			(start 0.7874 -0.4064)
			(end -0.7874 -0.4064)
			(stroke
				(width 0.1524)
				(type default)
			)
			(layer "B.SilkS")
		)
		(fp_line
			(start -0.7874 0.4064)
			(end 0.7874 0.4064)
			(stroke
				(width 0.1524)
				(type default)
			)
			(layer "B.SilkS")
		)
		(fp_line
			(start -0.7874 -0.4064)
			(end -0.7874 0.4064)
			(stroke
				(width 0.1524)
				(type default)
			)
			(layer "B.SilkS")
		)
		(fp_line
			(start 0.67945 0.3048)
			(end 0.67945 -0.305054)
			(stroke
				(width 0.1)
				(type default)
			)
			(layer "B.Fab")
		)
		(fp_line
			(start 0.67945 -0.305054)
			(end 0.12065 -0.305054)
			(stroke
				(width 0.1)
				(type default)
			)
			(layer "B.Fab")
		)
		(fp_line
			(start 0.12065 0.3048)
			(end 0.67945 0.3048)
			(stroke
				(width 0.1)
				(type default)
			)
			(layer "B.Fab")
		)
		(fp_line
			(start 0.12065 0.2794)
			(end 0.12065 0.3048)
			(stroke
				(width 0.1)
				(type default)
			)
			(layer "B.Fab")
		)
		(fp_line
			(start 0.12065 -0.2794)
			(end -0.12065 -0.2794)
			(stroke
				(width 0.1)
				(type default)
			)
			(layer "B.Fab")
		)
		(fp_line
			(start 0.12065 -0.305054)
			(end 0.12065 -0.2794)
			(stroke
				(width 0.1)
				(type default)
			)
			(layer "B.Fab")
		)
		(fp_line
			(start -0.120396 0.3048)
			(end -0.120396 0.2794)
			(stroke
				(width 0.1)
				(type default)
			)
			(layer "B.Fab")
		)
		(fp_line
			(start -0.120396 0.2794)
			(end 0.12065 0.2794)
			(stroke
				(width 0.1)
				(type default)
			)
			(layer "B.Fab")
		)
		(fp_line
			(start -0.12065 -0.2794)
			(end -0.12065 -0.3048)
			(stroke
				(width 0.1)
				(type default)
			)
			(layer "B.Fab")
		)
		(fp_line
			(start -0.12065 -0.3048)
			(end -0.67945 -0.3048)
			(stroke
				(width 0.1)
				(type default)
			)
			(layer "B.Fab")
		)
		(fp_line
			(start -0.67945 0.3048)
			(end -0.120396 0.3048)
			(stroke
				(width 0.1)
				(type default)
			)
			(layer "B.Fab")
		)
		(fp_line
			(start -0.67945 -0.3048)
			(end -0.67945 0.3048)
			(stroke
				(width 0.1)
				(type default)
			)
			(layer "B.Fab")
		)
		(pad "1" smd circle
			(at 0.40005 0)
			(size 0 0)
			(layers "B.Cu" "B.Mask" "B.Paste")
			(net "PVDDCR_CPU0_P0_TEMP0")
		)
		(pad "2" smd circle
			(at -0.40005 0)
			(size 0 0)
			(layers "B.Cu" "B.Mask" "B.Paste")
			(net "GND")
		)
	)
	(footprint ""
		(layer "B.Cu")
		(at 367.101628 -423.57675 180)
		(property "Reference" "R688"
			(at 0 0 0)
			(layer "B.SilkS")
			(hide yes)
			(effects
				(font
					(size 1.27 1.27)
				)
				(justify mirror)
			)
		)
		(property "Value" ""
			(at 0 0 0)
			(layer "B.Fab")
			(effects
				(font
					(size 1.27 1.27)
				)
				(justify mirror)
			)
		)
		(duplicate_pad_numbers_are_jumpers no)
		(fp_line
			(start 0.32512 0.175006)
			(end 0.32512 -0.175006)
			(stroke
				(width 0.1)
				(type default)
			)
			(layer "B.Fab")
		)
		(fp_line
			(start 0.32512 -0.175006)
			(end -0.32512 -0.175006)
			(stroke
				(width 0.1)
				(type default)
			)
			(layer "B.Fab")
		)
		(fp_line
			(start -0.32512 0.175006)
			(end 0.32512 0.175006)
			(stroke
				(width 0.1)
				(type default)
			)
			(layer "B.Fab")
		)
		(fp_line
			(start -0.32512 -0.175006)
			(end -0.32512 0.175006)
			(stroke
				(width 0.1)
				(type default)
			)
			(layer "B.Fab")
		)
		(pad "1" smd rect
			(at 0.2667 0)
			(size 0.3048 0.381)
			(layers "B.Cu" "B.Mask" "B.Paste")
			(net "SMB_RT_CPU0_P3_ROM_R_SDA")
		)
		(pad "2" smd rect
			(at -0.2667 0 180)
			(size 0.3048 0.381)
			(layers "B.Cu" "B.Mask" "B.Paste")
			(net "SMB_RT_CPU0_P3_ROM_SDA")
		)
	)
	(footprint ""
		(layer "B.Cu")
		(at 234.4801 -226.822 180)
		(property "Reference" "R140"
			(at 0 0 0)
			(layer "B.SilkS")
			(hide yes)
			(effects
				(font
					(size 1.27 1.27)
				)
				(justify mirror)
			)
		)
		(property "Value" ""
			(at 0 0 0)
			(layer "B.Fab")
			(effects
				(font
					(size 1.27 1.27)
				)
				(justify mirror)
			)
		)
		(duplicate_pad_numbers_are_jumpers no)
		(fp_line
			(start 0.7874 0.4064)
			(end 0.7874 -0.4064)
			(stroke
				(width 0.1524)
				(type default)
			)
			(layer "B.SilkS")
		)
		(fp_line
			(start 0.7874 -0.4064)
			(end -0.7874 -0.4064)
			(stroke
				(width 0.1524)
				(type default)
			)
			(layer "B.SilkS")
		)
		(fp_line
			(start -0.7874 0.4064)
			(end 0.7874 0.4064)
			(stroke
				(width 0.1524)
				(type default)
			)
			(layer "B.SilkS")
		)
		(fp_line
			(start -0.7874 -0.4064)
			(end -0.7874 0.4064)
			(stroke
				(width 0.1524)
				(type default)
			)
			(layer "B.SilkS")
		)
		(fp_line
			(start 0.67945 0.3048)
			(end 0.67945 -0.305054)
			(stroke
				(width 0.1)
				(type default)
			)
			(layer "B.Fab")
		)
		(fp_line
			(start 0.67945 -0.305054)
			(end 0.12065 -0.305054)
			(stroke
				(width 0.1)
				(type default)
			)
			(layer "B.Fab")
		)
		(fp_line
			(start 0.12065 0.3048)
			(end 0.67945 0.3048)
			(stroke
				(width 0.1)
				(type default)
			)
			(layer "B.Fab")
		)
		(fp_line
			(start 0.12065 0.2794)
			(end 0.12065 0.3048)
			(stroke
				(width 0.1)
				(type default)
			)
			(layer "B.Fab")
		)
		(fp_line
			(start 0.12065 -0.2794)
			(end -0.12065 -0.2794)
			(stroke
				(width 0.1)
				(type default)
			)
			(layer "B.Fab")
		)
		(fp_line
			(start 0.12065 -0.305054)
			(end 0.12065 -0.2794)
			(stroke
				(width 0.1)
				(type default)
			)
			(layer "B.Fab")
		)
		(fp_line
			(start -0.120396 0.3048)
			(end -0.120396 0.2794)
			(stroke
				(width 0.1)
				(type default)
			)
			(layer "B.Fab")
		)
		(fp_line
			(start -0.120396 0.2794)
			(end 0.12065 0.2794)
			(stroke
				(width 0.1)
				(type default)
			)
			(layer "B.Fab")
		)
		(fp_line
			(start -0.12065 -0.2794)
			(end -0.12065 -0.3048)
			(stroke
				(width 0.1)
				(type default)
			)
			(layer "B.Fab")
		)
		(fp_line
			(start -0.12065 -0.3048)
			(end -0.67945 -0.3048)
			(stroke
				(width 0.1)
				(type default)
			)
			(layer "B.Fab")
		)
		(fp_line
			(start -0.67945 0.3048)
			(end -0.120396 0.3048)
			(stroke
				(width 0.1)
				(type default)
			)
			(layer "B.Fab")
		)
		(fp_line
			(start -0.67945 -0.3048)
			(end -0.67945 0.3048)
			(stroke
				(width 0.1)
				(type default)
			)
			(layer "B.Fab")
		)
		(pad "1" smd rect
			(at 0.40005 0 180)
			(size 0.4572 0.508)
			(layers "B.Cu" "B.Mask" "B.Paste")
			(net "SMB_CPU0_CPU1_APML_SCL")
		)
		(pad "2" smd rect
			(at -0.40005 0 180)
			(size 0.4572 0.508)
			(layers "B.Cu" "B.Mask" "B.Paste")
			(net "SMB_CPU0_CPU1_APML_BUF1_SCL")
		)
	)
	(footprint ""
		(layer "B.Cu")
		(at 45.099986 -388.609078 90)
		(property "Reference" "C281"
			(at 0 0 90)
			(layer "B.SilkS")
			(hide yes)
			(effects
				(font
					(size 1.27 1.27)
				)
				(justify mirror)
			)
		)
		(property "Value" ""
			(at 0 0 90)
			(layer "B.Fab")
			(effects
				(font
					(size 1.27 1.27)
				)
				(justify mirror)
			)
		)
		(duplicate_pad_numbers_are_jumpers no)
		(fp_line
			(start 0.299974 -0.150114)
			(end -0.299974 -0.150114)
			(stroke
				(width 0.1)
				(type default)
			)
			(layer "B.Fab")
		)
		(fp_line
			(start -0.299974 -0.150114)
			(end -0.299974 0.150114)
			(stroke
				(width 0.1)
				(type default)
			)
			(layer "B.Fab")
		)
		(fp_line
			(start 0.299974 0.150114)
			(end 0.299974 -0.150114)
			(stroke
				(width 0.1)
				(type default)
			)
			(layer "B.Fab")
		)
		(fp_line
			(start -0.299974 0.150114)
			(end 0.299974 0.150114)
			(stroke
				(width 0.1)
				(type default)
			)
			(layer "B.Fab")
		)
		(pad "1" smd rect
			(at 0.2667 0 270)
			(size 0.3048 0.381)
			(layers "B.Cu" "B.Mask" "B.Paste")
			(net "P0V9_CPU1_RT0_2A")
		)
		(pad "2" smd rect
			(at -0.2667 0 270)
			(size 0.3048 0.381)
			(layers "B.Cu" "B.Mask" "B.Paste")
			(net "GND")
		)
	)
	(footprint ""
		(layer "B.Cu")
		(at 366.36579 -393.04468 180)
		(property "Reference" "R1118"
			(at 0 0 0)
			(layer "B.SilkS")
			(hide yes)
			(effects
				(font
					(size 1.27 1.27)
				)
				(justify mirror)
			)
		)
		(property "Value" ""
			(at 0 0 0)
			(layer "B.Fab")
			(effects
				(font
					(size 1.27 1.27)
				)
				(justify mirror)
			)
		)
		(duplicate_pad_numbers_are_jumpers no)
		(fp_line
			(start 0.32512 0.175006)
			(end 0.32512 -0.175006)
			(stroke
				(width 0.1)
				(type default)
			)
			(layer "B.Fab")
		)
		(fp_line
			(start 0.32512 -0.175006)
			(end -0.32512 -0.175006)
			(stroke
				(width 0.1)
				(type default)
			)
			(layer "B.Fab")
		)
		(fp_line
			(start -0.32512 0.175006)
			(end 0.32512 0.175006)
			(stroke
				(width 0.1)
				(type default)
			)
			(layer "B.Fab")
		)
		(fp_line
			(start -0.32512 -0.175006)
			(end -0.32512 0.175006)
			(stroke
				(width 0.1)
				(type default)
			)
			(layer "B.Fab")
		)
		(pad "1" smd rect
			(at 0.2667 0)
			(size 0.3048 0.381)
			(layers "B.Cu" "B.Mask" "B.Paste")
			(net "TEST1_RT_CPU0_P3")
		)
		(pad "2" smd rect
			(at -0.2667 0 180)
			(size 0.3048 0.381)
			(layers "B.Cu" "B.Mask" "B.Paste")
			(net "GND")
		)
	)
	(footprint ""
		(layer "B.Cu")
		(at 273.847814 -193.99631)
		(property "Reference" "R93"
			(at 0 0 0)
			(layer "B.SilkS")
			(hide yes)
			(effects
				(font
					(size 1.27 1.27)
				)
				(justify mirror)
			)
		)
		(property "Value" ""
			(at 0 0 0)
			(layer "B.Fab")
			(effects
				(font
					(size 1.27 1.27)
				)
				(justify mirror)
			)
		)
		(duplicate_pad_numbers_are_jumpers no)
		(fp_line
			(start -0.7874 -0.4064)
			(end -0.7874 0.4064)
			(stroke
				(width 0.1524)
				(type default)
			)
			(layer "B.SilkS")
		)
		(fp_line
			(start -0.7874 0.4064)
			(end 0.7874 0.4064)
			(stroke
				(width 0.1524)
				(type default)
			)
			(layer "B.SilkS")
		)
		(fp_line
			(start 0.7874 -0.4064)
			(end -0.7874 -0.4064)
			(stroke
				(width 0.1524)
				(type default)
			)
			(layer "B.SilkS")
		)
		(fp_line
			(start 0.7874 0.4064)
			(end 0.7874 -0.4064)
			(stroke
				(width 0.1524)
				(type default)
			)
			(layer "B.SilkS")
		)
		(fp_line
			(start -0.67945 -0.3048)
			(end -0.67945 0.3048)
			(stroke
				(width 0.1)
				(type default)
			)
			(layer "B.Fab")
		)
		(fp_line
			(start -0.67945 0.3048)
			(end -0.120396 0.3048)
			(stroke
				(width 0.1)
				(type default)
			)
			(layer "B.Fab")
		)
		(fp_line
			(start -0.12065 -0.3048)
			(end -0.67945 -0.3048)
			(stroke
				(width 0.1)
				(type default)
			)
			(layer "B.Fab")
		)
		(fp_line
			(start -0.12065 -0.2794)
			(end -0.12065 -0.3048)
			(stroke
				(width 0.1)
				(type default)
			)
			(layer "B.Fab")
		)
		(fp_line
			(start -0.120396 0.2794)
			(end 0.12065 0.2794)
			(stroke
				(width 0.1)
				(type default)
			)
			(layer "B.Fab")
		)
		(fp_line
			(start -0.120396 0.3048)
			(end -0.120396 0.2794)
			(stroke
				(width 0.1)
				(type default)
			)
			(layer "B.Fab")
		)
		(fp_line
			(start 0.12065 -0.305054)
			(end 0.12065 -0.2794)
			(stroke
				(width 0.1)
				(type default)
			)
			(layer "B.Fab")
		)
		(fp_line
			(start 0.12065 -0.2794)
			(end -0.12065 -0.2794)
			(stroke
				(width 0.1)
				(type default)
			)
			(layer "B.Fab")
		)
		(fp_line
			(start 0.12065 0.2794)
			(end 0.12065 0.3048)
			(stroke
				(width 0.1)
				(type default)
			)
			(layer "B.Fab")
		)
		(fp_line
			(start 0.12065 0.3048)
			(end 0.67945 0.3048)
			(stroke
				(width 0.1)
				(type default)
			)
			(layer "B.Fab")
		)
		(fp_line
			(start 0.67945 -0.305054)
			(end 0.12065 -0.305054)
			(stroke
				(width 0.1)
				(type default)
			)
			(layer "B.Fab")
		)
		(fp_line
			(start 0.67945 0.3048)
			(end 0.67945 -0.305054)
			(stroke
				(width 0.1)
				(type default)
			)
			(layer "B.Fab")
		)
		(pad "1" smd circle
			(at 0.40005 0 180)
			(size 0 0)
			(layers "B.Cu" "B.Mask" "B.Paste")
			(net "P3V3")
		)
		(pad "2" smd circle
			(at -0.40005 0 180)
			(size 0 0)
			(layers "B.Cu" "B.Mask" "B.Paste")
			(net "PWRGD_CHE_CPU0_DIMM")
		)
	)
	(footprint ""
		(layer "B.Cu")
		(at 371.134386 -214.523828 90)
		(property "Reference" "R4536"
			(at 0 0 90)
			(layer "B.SilkS")
			(hide yes)
			(effects
				(font
					(size 1.27 1.27)
				)
				(justify mirror)
			)
		)
		(property "Value" ""
			(at 0 0 90)
			(layer "B.Fab")
			(effects
				(font
					(size 1.27 1.27)
				)
				(justify mirror)
			)
		)
		(duplicate_pad_numbers_are_jumpers no)
		(fp_line
			(start 0.7874 -0.4064)
			(end -0.7874 -0.4064)
			(stroke
				(width 0.1524)
				(type default)
			)
			(layer "B.SilkS")
		)
		(fp_line
			(start -0.7874 -0.4064)
			(end -0.7874 -0.014986)
			(stroke
				(width 0.1524)
				(type default)
			)
			(layer "B.SilkS")
		)
		(fp_line
			(start 0.7874 -0.040386)
			(end 0.7874 -0.4064)
			(stroke
				(width 0.1524)
				(type default)
			)
			(layer "B.SilkS")
		)
		(fp_line
			(start -0.351028 0.4064)
			(end 0.512572 0.4064)
			(stroke
				(width 0.1524)
				(type default)
			)
			(layer "B.SilkS")
		)
		(fp_line
			(start 0.67945 -0.305054)
			(end 0.12065 -0.305054)
			(stroke
				(width 0.1)
				(type default)
			)
			(layer "B.Fab")
		)
		(fp_line
			(start 0.12065 -0.305054)
			(end 0.12065 -0.2794)
			(stroke
				(width 0.1)
				(type default)
			)
			(layer "B.Fab")
		)
		(fp_line
			(start -0.12065 -0.3048)
			(end -0.67945 -0.3048)
			(stroke
				(width 0.1)
				(type default)
			)
			(layer "B.Fab")
		)
		(fp_line
			(start -0.67945 -0.3048)
			(end -0.67945 0.3048)
			(stroke
				(width 0.1)
				(type default)
			)
			(layer "B.Fab")
		)
		(fp_line
			(start 0.12065 -0.2794)
			(end -0.12065 -0.2794)
			(stroke
				(width 0.1)
				(type default)
			)
			(layer "B.Fab")
		)
		(fp_line
			(start -0.12065 -0.2794)
			(end -0.12065 -0.3048)
			(stroke
				(width 0.1)
				(type default)
			)
			(layer "B.Fab")
		)
		(fp_line
			(start 0.12065 0.2794)
			(end 0.12065 0.3048)
			(stroke
				(width 0.1)
				(type default)
			)
			(layer "B.Fab")
		)
		(fp_line
			(start -0.120396 0.2794)
			(end 0.12065 0.2794)
			(stroke
				(width 0.1)
				(type default)
			)
			(layer "B.Fab")
		)
		(fp_line
			(start 0.67945 0.3048)
			(end 0.67945 -0.305054)
			(stroke
				(width 0.1)
				(type default)
			)
			(layer "B.Fab")
		)
		(fp_line
			(start 0.12065 0.3048)
			(end 0.67945 0.3048)
			(stroke
				(width 0.1)
				(type default)
			)
			(layer "B.Fab")
		)
		(fp_line
			(start -0.120396 0.3048)
			(end -0.120396 0.2794)
			(stroke
				(width 0.1)
				(type default)
			)
			(layer "B.Fab")
		)
		(fp_line
			(start -0.67945 0.3048)
			(end -0.120396 0.3048)
			(stroke
				(width 0.1)
				(type default)
			)
			(layer "B.Fab")
		)
		(pad "1" smd circle
			(at 0.40005 0 270)
			(size 0 0)
			(layers "B.Cu" "B.Mask" "B.Paste")
			(net "CLK_100M_CPU0_CLK01_R_DN")
		)
		(pad "2" smd circle
			(at -0.40005 0 270)
			(size 0 0)
			(layers "B.Cu" "B.Mask" "B.Paste")
			(net "CLK_100M_CPU0_CLK01_DN")
		)
	)
	(footprint ""
		(layer "B.Cu")
		(at 115.678458 -386.766562 90)
		(property "Reference" "C491"
			(at 0 0 90)
			(layer "B.SilkS")
			(hide yes)
			(effects
				(font
					(size 1.27 1.27)
				)
				(justify mirror)
			)
		)
		(property "Value" ""
			(at 0 0 90)
			(layer "B.Fab")
			(effects
				(font
					(size 1.27 1.27)
				)
				(justify mirror)
			)
		)
		(duplicate_pad_numbers_are_jumpers no)
		(fp_line
			(start 0.299974 -0.150114)
			(end -0.299974 -0.150114)
			(stroke
				(width 0.1)
				(type default)
			)
			(layer "B.Fab")
		)
		(fp_line
			(start -0.299974 -0.150114)
			(end -0.299974 0.150114)
			(stroke
				(width 0.1)
				(type default)
			)
			(layer "B.Fab")
		)
		(fp_line
			(start 0.299974 0.150114)
			(end 0.299974 -0.150114)
			(stroke
				(width 0.1)
				(type default)
			)
			(layer "B.Fab")
		)
		(fp_line
			(start -0.299974 0.150114)
			(end 0.299974 0.150114)
			(stroke
				(width 0.1)
				(type default)
			)
			(layer "B.Fab")
		)
		(pad "1" smd rect
			(at 0.2667 0 270)
			(size 0.3048 0.381)
			(layers "B.Cu" "B.Mask" "B.Paste")
			(net "P0V9_CPU1_RT3_2A")
		)
		(pad "2" smd rect
			(at -0.2667 0 270)
			(size 0.3048 0.381)
			(layers "B.Cu" "B.Mask" "B.Paste")
			(net "GND")
		)
	)
	(footprint ""
		(layer "B.Cu")
		(at 397.830802 -314.366148 180)
		(property "Reference" "C214"
			(at 0 0 0)
			(layer "B.SilkS")
			(hide yes)
			(effects
				(font
					(size 1.27 1.27)
				)
				(justify mirror)
			)
		)
		(property "Value" ""
			(at 0 0 0)
			(layer "B.Fab")
			(effects
				(font
					(size 1.27 1.27)
				)
				(justify mirror)
			)
		)
		(duplicate_pad_numbers_are_jumpers no)
		(fp_line
			(start 0.7874 0.4064)
			(end 0.7874 -0.4064)
			(stroke
				(width 0.1524)
				(type default)
			)
			(layer "B.SilkS")
		)
		(fp_line
			(start 0.7874 -0.4064)
			(end -0.7874 -0.4064)
			(stroke
				(width 0.1524)
				(type default)
			)
			(layer "B.SilkS")
		)
		(fp_line
			(start -0.7874 0.4064)
			(end 0.7874 0.4064)
			(stroke
				(width 0.1524)
				(type default)
			)
			(layer "B.SilkS")
		)
		(fp_line
			(start -0.7874 -0.4064)
			(end -0.7874 0.4064)
			(stroke
				(width 0.1524)
				(type default)
			)
			(layer "B.SilkS")
		)
		(fp_line
			(start 0.67945 0.3048)
			(end 0.67945 -0.305054)
			(stroke
				(width 0.1)
				(type default)
			)
			(layer "B.Fab")
		)
		(fp_line
			(start 0.67945 -0.305054)
			(end 0.12065 -0.305054)
			(stroke
				(width 0.1)
				(type default)
			)
			(layer "B.Fab")
		)
		(fp_line
			(start 0.12065 0.3048)
			(end 0.67945 0.3048)
			(stroke
				(width 0.1)
				(type default)
			)
			(layer "B.Fab")
		)
		(fp_line
			(start 0.12065 0.2794)
			(end 0.12065 0.3048)
			(stroke
				(width 0.1)
				(type default)
			)
			(layer "B.Fab")
		)
		(fp_line
			(start 0.12065 -0.2794)
			(end -0.12065 -0.2794)
			(stroke
				(width 0.1)
				(type default)
			)
			(layer "B.Fab")
		)
		(fp_line
			(start 0.12065 -0.305054)
			(end 0.12065 -0.2794)
			(stroke
				(width 0.1)
				(type default)
			)
			(layer "B.Fab")
		)
		(fp_line
			(start -0.120396 0.3048)
			(end -0.120396 0.2794)
			(stroke
				(width 0.1)
				(type default)
			)
			(layer "B.Fab")
		)
		(fp_line
			(start -0.120396 0.2794)
			(end 0.12065 0.2794)
			(stroke
				(width 0.1)
				(type default)
			)
			(layer "B.Fab")
		)
		(fp_line
			(start -0.12065 -0.2794)
			(end -0.12065 -0.3048)
			(stroke
				(width 0.1)
				(type default)
			)
			(layer "B.Fab")
		)
		(fp_line
			(start -0.12065 -0.3048)
			(end -0.67945 -0.3048)
			(stroke
				(width 0.1)
				(type default)
			)
			(layer "B.Fab")
		)
		(fp_line
			(start -0.67945 0.3048)
			(end -0.120396 0.3048)
			(stroke
				(width 0.1)
				(type default)
			)
			(layer "B.Fab")
		)
		(fp_line
			(start -0.67945 -0.3048)
			(end -0.67945 0.3048)
			(stroke
				(width 0.1)
				(type default)
			)
			(layer "B.Fab")
		)
		(pad "1" smd circle
			(at 0.40005 0)
			(size 0 0)
			(layers "B.Cu" "B.Mask" "B.Paste")
			(net "XTAL_CPU0_X48M_X2_R")
		)
		(pad "2" smd circle
			(at -0.40005 0)
			(size 0 0)
			(layers "B.Cu" "B.Mask" "B.Paste")
			(net "GND")
		)
	)
	(footprint ""
		(layer "B.Cu")
		(at 445.647318 -244.08511)
		(property "Reference" "R385"
			(at 0 0 0)
			(layer "B.SilkS")
			(hide yes)
			(effects
				(font
					(size 1.27 1.27)
				)
				(justify mirror)
			)
		)
		(property "Value" ""
			(at 0 0 0)
			(layer "B.Fab")
			(effects
				(font
					(size 1.27 1.27)
				)
				(justify mirror)
			)
		)
		(duplicate_pad_numbers_are_jumpers no)
		(fp_line
			(start -0.7874 -0.4064)
			(end -0.7874 0.4064)
			(stroke
				(width 0.1524)
				(type default)
			)
			(layer "B.SilkS")
		)
		(fp_line
			(start -0.7874 0.4064)
			(end 0.7874 0.4064)
			(stroke
				(width 0.1524)
				(type default)
			)
			(layer "B.SilkS")
		)
		(fp_line
			(start 0.7874 -0.4064)
			(end -0.7874 -0.4064)
			(stroke
				(width 0.1524)
				(type default)
			)
			(layer "B.SilkS")
		)
		(fp_line
			(start 0.7874 0.4064)
			(end 0.7874 -0.4064)
			(stroke
				(width 0.1524)
				(type default)
			)
			(layer "B.SilkS")
		)
		(fp_line
			(start -0.67945 -0.3048)
			(end -0.67945 0.3048)
			(stroke
				(width 0.1)
				(type default)
			)
			(layer "B.Fab")
		)
		(fp_line
			(start -0.67945 0.3048)
			(end -0.120396 0.3048)
			(stroke
				(width 0.1)
				(type default)
			)
			(layer "B.Fab")
		)
		(fp_line
			(start -0.12065 -0.3048)
			(end -0.67945 -0.3048)
			(stroke
				(width 0.1)
				(type default)
			)
			(layer "B.Fab")
		)
		(fp_line
			(start -0.12065 -0.2794)
			(end -0.12065 -0.3048)
			(stroke
				(width 0.1)
				(type default)
			)
			(layer "B.Fab")
		)
		(fp_line
			(start -0.120396 0.2794)
			(end 0.12065 0.2794)
			(stroke
				(width 0.1)
				(type default)
			)
			(layer "B.Fab")
		)
		(fp_line
			(start -0.120396 0.3048)
			(end -0.120396 0.2794)
			(stroke
				(width 0.1)
				(type default)
			)
			(layer "B.Fab")
		)
		(fp_line
			(start 0.12065 -0.305054)
			(end 0.12065 -0.2794)
			(stroke
				(width 0.1)
				(type default)
			)
			(layer "B.Fab")
		)
		(fp_line
			(start 0.12065 -0.2794)
			(end -0.12065 -0.2794)
			(stroke
				(width 0.1)
				(type default)
			)
			(layer "B.Fab")
		)
		(fp_line
			(start 0.12065 0.2794)
			(end 0.12065 0.3048)
			(stroke
				(width 0.1)
				(type default)
			)
			(layer "B.Fab")
		)
		(fp_line
			(start 0.12065 0.3048)
			(end 0.67945 0.3048)
			(stroke
				(width 0.1)
				(type default)
			)
			(layer "B.Fab")
		)
		(fp_line
			(start 0.67945 -0.305054)
			(end 0.12065 -0.305054)
			(stroke
				(width 0.1)
				(type default)
			)
			(layer "B.Fab")
		)
		(fp_line
			(start 0.67945 0.3048)
			(end 0.67945 -0.305054)
			(stroke
				(width 0.1)
				(type default)
			)
			(layer "B.Fab")
		)
		(pad "1" smd circle
			(at 0.40005 0 180)
			(size 0 0)
			(layers "B.Cu" "B.Mask" "B.Paste")
			(net "M_K_CPU0_ALERT_N")
		)
		(pad "2" smd circle
			(at -0.40005 0 180)
			(size 0 0)
			(layers "B.Cu" "B.Mask" "B.Paste")
			(net "M_K_CPU0_ALERT_R_N")
		)
	)
	(footprint ""
		(layer "B.Cu")
		(at 342.046052 -396.393162 -90)
		(property "Reference" "C608"
			(at 0 0 90)
			(layer "B.SilkS")
			(hide yes)
			(effects
				(font
					(size 1.27 1.27)
				)
				(justify mirror)
			)
		)
		(property "Value" ""
			(at 0 0 90)
			(layer "B.Fab")
			(effects
				(font
					(size 1.27 1.27)
				)
				(justify mirror)
			)
		)
		(duplicate_pad_numbers_are_jumpers no)
		(fp_line
			(start -0.299974 0.150114)
			(end 0.299974 0.150114)
			(stroke
				(width 0.1)
				(type default)
			)
			(layer "B.Fab")
		)
		(fp_line
			(start 0.299974 0.150114)
			(end 0.299974 -0.150114)
			(stroke
				(width 0.1)
				(type default)
			)
			(layer "B.Fab")
		)
		(fp_line
			(start -0.299974 -0.150114)
			(end -0.299974 0.150114)
			(stroke
				(width 0.1)
				(type default)
			)
			(layer "B.Fab")
		)
		(fp_line
			(start 0.299974 -0.150114)
			(end -0.299974 -0.150114)
			(stroke
				(width 0.1)
				(type default)
			)
			(layer "B.Fab")
		)
		(pad "1" smd rect
			(at 0.2667 0 90)
			(size 0.3048 0.381)
			(layers "B.Cu" "B.Mask" "B.Paste")
			(net "P0V9_CPU0_RT_2D")
		)
		(pad "2" smd rect
			(at -0.2667 0 90)
			(size 0.3048 0.381)
			(layers "B.Cu" "B.Mask" "B.Paste")
			(net "GND")
		)
	)
	(footprint ""
		(layer "B.Cu")
		(at 352.247454 -253.43231)
		(property "Reference" "C2582"
			(at 0 0 0)
			(layer "B.SilkS")
			(hide yes)
			(effects
				(font
					(size 1.27 1.27)
				)
				(justify mirror)
			)
		)
		(property "Value" ""
			(at 0 0 0)
			(layer "B.Fab")
			(effects
				(font
					(size 1.27 1.27)
				)
				(justify mirror)
			)
		)
		(duplicate_pad_numbers_are_jumpers no)
		(fp_line
			(start -0.7874 -0.4064)
			(end -0.7874 0.4064)
			(stroke
				(width 0.1524)
				(type default)
			)
			(layer "B.SilkS")
		)
		(fp_line
			(start -0.7874 0.4064)
			(end 0.7874 0.4064)
			(stroke
				(width 0.1524)
				(type default)
			)
			(layer "B.SilkS")
		)
		(fp_line
			(start 0.7874 -0.4064)
			(end -0.7874 -0.4064)
			(stroke
				(width 0.1524)
				(type default)
			)
			(layer "B.SilkS")
		)
		(fp_line
			(start 0.7874 0.4064)
			(end 0.7874 -0.4064)
			(stroke
				(width 0.1524)
				(type default)
			)
			(layer "B.SilkS")
		)
		(fp_line
			(start -0.67945 -0.3048)
			(end -0.67945 0.3048)
			(stroke
				(width 0.1)
				(type default)
			)
			(layer "B.Fab")
		)
		(fp_line
			(start -0.67945 0.3048)
			(end -0.120396 0.3048)
			(stroke
				(width 0.1)
				(type default)
			)
			(layer "B.Fab")
		)
		(fp_line
			(start -0.12065 -0.3048)
			(end -0.67945 -0.3048)
			(stroke
				(width 0.1)
				(type default)
			)
			(layer "B.Fab")
		)
		(fp_line
			(start -0.12065 -0.2794)
			(end -0.12065 -0.3048)
			(stroke
				(width 0.1)
				(type default)
			)
			(layer "B.Fab")
		)
		(fp_line
			(start -0.120396 0.2794)
			(end 0.12065 0.2794)
			(stroke
				(width 0.1)
				(type default)
			)
			(layer "B.Fab")
		)
		(fp_line
			(start -0.120396 0.3048)
			(end -0.120396 0.2794)
			(stroke
				(width 0.1)
				(type default)
			)
			(layer "B.Fab")
		)
		(fp_line
			(start 0.12065 -0.305054)
			(end 0.12065 -0.2794)
			(stroke
				(width 0.1)
				(type default)
			)
			(layer "B.Fab")
		)
		(fp_line
			(start 0.12065 -0.2794)
			(end -0.12065 -0.2794)
			(stroke
				(width 0.1)
				(type default)
			)
			(layer "B.Fab")
		)
		(fp_line
			(start 0.12065 0.2794)
			(end 0.12065 0.3048)
			(stroke
				(width 0.1)
				(type default)
			)
			(layer "B.Fab")
		)
		(fp_line
			(start 0.12065 0.3048)
			(end 0.67945 0.3048)
			(stroke
				(width 0.1)
				(type default)
			)
			(layer "B.Fab")
		)
		(fp_line
			(start 0.67945 -0.305054)
			(end 0.12065 -0.305054)
			(stroke
				(width 0.1)
				(type default)
			)
			(layer "B.Fab")
		)
		(fp_line
			(start 0.67945 0.3048)
			(end 0.67945 -0.305054)
			(stroke
				(width 0.1)
				(type default)
			)
			(layer "B.Fab")
		)
		(pad "1" smd circle
			(at 0.40005 0 180)
			(size 0 0)
			(layers "B.Cu" "B.Mask" "B.Paste")
			(net "PVDDCR_SOC_P0")
		)
		(pad "2" smd circle
			(at -0.40005 0 180)
			(size 0 0)
			(layers "B.Cu" "B.Mask" "B.Paste")
			(net "GND")
		)
	)
	(footprint ""
		(layer "B.Cu")
		(at 373.202454 -266.00531)
		(property "Reference" "C2639"
			(at 0 0 0)
			(layer "B.SilkS")
			(hide yes)
			(effects
				(font
					(size 1.27 1.27)
				)
				(justify mirror)
			)
		)
		(property "Value" ""
			(at 0 0 0)
			(layer "B.Fab")
			(effects
				(font
					(size 1.27 1.27)
				)
				(justify mirror)
			)
		)
		(duplicate_pad_numbers_are_jumpers no)
		(fp_line
			(start -0.7874 -0.4064)
			(end -0.7874 0.4064)
			(stroke
				(width 0.1524)
				(type default)
			)
			(layer "B.SilkS")
		)
		(fp_line
			(start -0.7874 0.4064)
			(end 0.7874 0.4064)
			(stroke
				(width 0.1524)
				(type default)
			)
			(layer "B.SilkS")
		)
		(fp_line
			(start 0.7874 -0.4064)
			(end -0.7874 -0.4064)
			(stroke
				(width 0.1524)
				(type default)
			)
			(layer "B.SilkS")
		)
		(fp_line
			(start 0.7874 0.4064)
			(end 0.7874 -0.4064)
			(stroke
				(width 0.1524)
				(type default)
			)
			(layer "B.SilkS")
		)
		(fp_line
			(start -0.67945 -0.3048)
			(end -0.67945 0.3048)
			(stroke
				(width 0.1)
				(type default)
			)
			(layer "B.Fab")
		)
		(fp_line
			(start -0.67945 0.3048)
			(end -0.120396 0.3048)
			(stroke
				(width 0.1)
				(type default)
			)
			(layer "B.Fab")
		)
		(fp_line
			(start -0.12065 -0.3048)
			(end -0.67945 -0.3048)
			(stroke
				(width 0.1)
				(type default)
			)
			(layer "B.Fab")
		)
		(fp_line
			(start -0.12065 -0.2794)
			(end -0.12065 -0.3048)
			(stroke
				(width 0.1)
				(type default)
			)
			(layer "B.Fab")
		)
		(fp_line
			(start -0.120396 0.2794)
			(end 0.12065 0.2794)
			(stroke
				(width 0.1)
				(type default)
			)
			(layer "B.Fab")
		)
		(fp_line
			(start -0.120396 0.3048)
			(end -0.120396 0.2794)
			(stroke
				(width 0.1)
				(type default)
			)
			(layer "B.Fab")
		)
		(fp_line
			(start 0.12065 -0.305054)
			(end 0.12065 -0.2794)
			(stroke
				(width 0.1)
				(type default)
			)
			(layer "B.Fab")
		)
		(fp_line
			(start 0.12065 -0.2794)
			(end -0.12065 -0.2794)
			(stroke
				(width 0.1)
				(type default)
			)
			(layer "B.Fab")
		)
		(fp_line
			(start 0.12065 0.2794)
			(end 0.12065 0.3048)
			(stroke
				(width 0.1)
				(type default)
			)
			(layer "B.Fab")
		)
		(fp_line
			(start 0.12065 0.3048)
			(end 0.67945 0.3048)
			(stroke
				(width 0.1)
				(type default)
			)
			(layer "B.Fab")
		)
		(fp_line
			(start 0.67945 -0.305054)
			(end 0.12065 -0.305054)
			(stroke
				(width 0.1)
				(type default)
			)
			(layer "B.Fab")
		)
		(fp_line
			(start 0.67945 0.3048)
			(end 0.67945 -0.305054)
			(stroke
				(width 0.1)
				(type default)
			)
			(layer "B.Fab")
		)
		(pad "1" smd circle
			(at 0.40005 0 180)
			(size 0 0)
			(layers "B.Cu" "B.Mask" "B.Paste")
			(net "PVDD11_S3_P0")
		)
		(pad "2" smd circle
			(at -0.40005 0 180)
			(size 0 0)
			(layers "B.Cu" "B.Mask" "B.Paste")
			(net "GND")
		)
	)
	(footprint ""
		(layer "B.Cu")
		(at 160.69183 -17.79016)
		(property "Reference" "R4150"
			(at 0 0 0)
			(layer "B.SilkS")
			(hide yes)
			(effects
				(font
					(size 1.27 1.27)
				)
				(justify mirror)
			)
		)
		(property "Value" ""
			(at 0 0 0)
			(layer "B.Fab")
			(effects
				(font
					(size 1.27 1.27)
				)
				(justify mirror)
			)
		)
		(duplicate_pad_numbers_are_jumpers no)
		(fp_line
			(start -0.7874 -0.4064)
			(end -0.7874 0.4064)
			(stroke
				(width 0.1524)
				(type default)
			)
			(layer "B.SilkS")
		)
		(fp_line
			(start -0.7874 0.4064)
			(end 0.7874 0.4064)
			(stroke
				(width 0.1524)
				(type default)
			)
			(layer "B.SilkS")
		)
		(fp_line
			(start 0.7874 -0.4064)
			(end -0.7874 -0.4064)
			(stroke
				(width 0.1524)
				(type default)
			)
			(layer "B.SilkS")
		)
		(fp_line
			(start 0.7874 0.4064)
			(end 0.7874 -0.4064)
			(stroke
				(width 0.1524)
				(type default)
			)
			(layer "B.SilkS")
		)
		(fp_line
			(start -0.67945 -0.3048)
			(end -0.67945 0.3048)
			(stroke
				(width 0.1)
				(type default)
			)
			(layer "B.Fab")
		)
		(fp_line
			(start -0.67945 0.3048)
			(end -0.120396 0.3048)
			(stroke
				(width 0.1)
				(type default)
			)
			(layer "B.Fab")
		)
		(fp_line
			(start -0.12065 -0.3048)
			(end -0.67945 -0.3048)
			(stroke
				(width 0.1)
				(type default)
			)
			(layer "B.Fab")
		)
		(fp_line
			(start -0.12065 -0.2794)
			(end -0.12065 -0.3048)
			(stroke
				(width 0.1)
				(type default)
			)
			(layer "B.Fab")
		)
		(fp_line
			(start -0.120396 0.2794)
			(end 0.12065 0.2794)
			(stroke
				(width 0.1)
				(type default)
			)
			(layer "B.Fab")
		)
		(fp_line
			(start -0.120396 0.3048)
			(end -0.120396 0.2794)
			(stroke
				(width 0.1)
				(type default)
			)
			(layer "B.Fab")
		)
		(fp_line
			(start 0.12065 -0.305054)
			(end 0.12065 -0.2794)
			(stroke
				(width 0.1)
				(type default)
			)
			(layer "B.Fab")
		)
		(fp_line
			(start 0.12065 -0.2794)
			(end -0.12065 -0.2794)
			(stroke
				(width 0.1)
				(type default)
			)
			(layer "B.Fab")
		)
		(fp_line
			(start 0.12065 0.2794)
			(end 0.12065 0.3048)
			(stroke
				(width 0.1)
				(type default)
			)
			(layer "B.Fab")
		)
		(fp_line
			(start 0.12065 0.3048)
			(end 0.67945 0.3048)
			(stroke
				(width 0.1)
				(type default)
			)
			(layer "B.Fab")
		)
		(fp_line
			(start 0.67945 -0.305054)
			(end 0.12065 -0.305054)
			(stroke
				(width 0.1)
				(type default)
			)
			(layer "B.Fab")
		)
		(fp_line
			(start 0.67945 0.3048)
			(end 0.67945 -0.305054)
			(stroke
				(width 0.1)
				(type default)
			)
			(layer "B.Fab")
		)
		(pad "1" smd circle
			(at 0.40005 0 180)
			(size 0 0)
			(layers "B.Cu" "B.Mask" "B.Paste")
			(net "SMB_1_PLD_3V3AUX_SDA")
		)
		(pad "2" smd circle
			(at -0.40005 0 180)
			(size 0 0)
			(layers "B.Cu" "B.Mask" "B.Paste")
			(net "SMB_1_PLD_3V3AUX_SDA_R1")
		)
	)
	(footprint ""
		(layer "B.Cu")
		(at 184.332372 -113.462816 90)
		(property "Reference" "C359"
			(at 0 0 90)
			(layer "B.SilkS")
			(hide yes)
			(effects
				(font
					(size 1.27 1.27)
				)
				(justify mirror)
			)
		)
		(property "Value" ""
			(at 0 0 90)
			(layer "B.Fab")
			(effects
				(font
					(size 1.27 1.27)
				)
				(justify mirror)
			)
		)
		(duplicate_pad_numbers_are_jumpers no)
		(fp_line
			(start 0.69215 -0.2921)
			(end -0.69215 -0.2921)
			(stroke
				(width 0.1524)
				(type default)
			)
			(layer "B.SilkS")
		)
		(fp_line
			(start -0.69215 -0.2921)
			(end -0.69215 0.2921)
			(stroke
				(width 0.1524)
				(type default)
			)
			(layer "B.SilkS")
		)
		(fp_line
			(start 0.69215 0.2921)
			(end 0.69215 -0.2921)
			(stroke
				(width 0.1524)
				(type default)
			)
			(layer "B.SilkS")
		)
		(fp_line
			(start -0.69215 0.2921)
			(end 0.69215 0.2921)
			(stroke
				(width 0.1524)
				(type default)
			)
			(layer "B.SilkS")
		)
		(fp_line
			(start 0.51435 -0.2794)
			(end -0.51435 -0.2794)
			(stroke
				(width 0.1)
				(type default)
			)
			(layer "B.Fab")
		)
		(fp_line
			(start -0.51435 -0.2794)
			(end -0.51435 0.2794)
			(stroke
				(width 0.1)
				(type default)
			)
			(layer "B.Fab")
		)
		(fp_line
			(start 0.51435 0.2794)
			(end 0.51435 -0.2794)
			(stroke
				(width 0.1)
				(type default)
			)
			(layer "B.Fab")
		)
		(fp_line
			(start -0.51435 0.2794)
			(end 0.51435 0.2794)
			(stroke
				(width 0.1)
				(type default)
			)
			(layer "B.Fab")
		)
		(pad "1" smd circle
			(at 0.40005 0 270)
			(size 0 0)
			(layers "B.Cu" "B.Mask" "B.Paste")
			(net "P3V3_AUX")
		)
		(pad "2" smd circle
			(at -0.40005 0 270)
			(size 0 0)
			(layers "B.Cu" "B.Mask" "B.Paste")
			(net "GND")
		)
		(zone
			(layer "B.Cu")
			(hatch none 0.5)
			(connect_pads
				(clearance 0)
			)
			(min_thickness 0.25)
			(keepout
				(tracks not_allowed)
				(vias allowed)
				(pads allowed)
				(copperpour not_allowed)
				(footprints allowed)
			)
			(placement
				(enabled no)
				(sheetname "")
			)
			(fill
				(thermal_gap 0.5)
				(thermal_bridge_width 0.5)
				(island_removal_mode 0)
			)
			(polygon
				(pts
					(xy 184.186322 -113.362486) (xy 184.186322 -113.561876) (xy 184.244488 -113.653316) (xy 184.420002 -113.653316)
					(xy 184.478168 -113.561876) (xy 184.478168 -113.362486) (xy 184.420002 -113.272316) (xy 184.244742 -113.272316)
				)
			)
		)
	)
	(footprint ""
		(layer "B.Cu")
		(at 314.965588 -2.537206 180)
		(property "Reference" "J115"
			(at 4.61264 -1.551178 270)
			(unlocked yes)
			(layer "B.SilkS")
			(effects
				(font
					(size 0.7874 0.5842)
					(thickness 0.1524)
				)
				(justify left mirror)
			)
		)
		(property "Value" ""
			(at 0 0 0)
			(layer "B.Fab")
			(effects
				(font
					(size 1.27 1.27)
				)
				(justify mirror)
			)
		)
		(duplicate_pad_numbers_are_jumpers no)
		(fp_line
			(start 1.2192 2.06756)
			(end 1.2192 -2.06756)
			(stroke
				(width 0.1524)
				(type default)
			)
			(layer "B.SilkS")
		)
		(fp_line
			(start 1.2192 -2.06756)
			(end -1.2192 -2.06756)
			(stroke
				(width 0.1524)
				(type default)
			)
			(layer "B.SilkS")
		)
		(fp_line
			(start -1.2192 2.06756)
			(end 1.2192 2.06756)
			(stroke
				(width 0.1524)
				(type default)
			)
			(layer "B.SilkS")
		)
		(fp_line
			(start -1.2192 -2.06756)
			(end -1.2192 2.06756)
			(stroke
				(width 0.1524)
				(type default)
			)
			(layer "B.SilkS")
		)
		(pad "" np_thru_hole circle
			(at -3.4671 -1.27 90)
			(size 1.0414 1.0414)
			(drill 1.0414)
			(layers "*.Cu" "*.Mask")
			(clearance 0.381)
			(thermal_gap 0.381)
		)
		(pad "" np_thru_hole circle
			(at -3.4671 1.27 90)
			(size 1.0414 1.0414)
			(drill 1.0414)
			(layers "*.Cu" "*.Mask")
			(clearance 0.381)
			(thermal_gap 0.381)
		)
		(pad "" np_thru_hole circle
			(at 2.8829 -1.27 90)
			(size 1.0414 1.0414)
			(drill 1.0414)
			(layers "*.Cu" "*.Mask")
			(clearance 0.381)
			(thermal_gap 0.381)
		)
		(pad "" np_thru_hole circle
			(at 2.8829 1.27 90)
			(size 1.0414 1.0414)
			(drill 1.0414)
			(layers "*.Cu" "*.Mask")
			(clearance 0.381)
			(thermal_gap 0.381)
		)
		(pad "1" smd rect
			(at -0.8255 -0.249936 90)
			(size 0.3048 0.508)
			(layers "B.Cu" "B.Mask" "B.Paste")
			(net "DELTA_L_85_5INCH_IN6_DP")
		)
		(pad "2" smd rect
			(at -0.8255 0.249936 90)
			(size 0.3048 0.508)
			(layers "B.Cu" "B.Mask" "B.Paste")
			(net "DELTA_L_85_5INCH_IN6_DN")
		)
		(pad "3" smd circle
			(at 0 0)
			(size 0 0)
			(layers "B.Cu" "B.Mask" "B.Paste")
			(net "DELTA_L_GND_1")
		)
		(zone
			(layers "F.Cu" "B.Cu" "In1.Cu" "In2.Cu" "In3.Cu" "In4.Cu" "In5.Cu" "In6.Cu"
				"In7.Cu" "In8.Cu" "In9.Cu" "In10.Cu" "In11.Cu" "In12.Cu" "In13.Cu" "In14.Cu"
				"In15.Cu" "In16.Cu"
			)
			(hatch none 0.5)
			(connect_pads
				(clearance 0)
			)
			(min_thickness 0.25)
			(keepout
				(tracks not_allowed)
				(vias allowed)
				(pads allowed)
				(copperpour not_allowed)
				(footprints allowed)
			)
			(placement
				(enabled no)
				(sheetname "")
			)
			(fill
				(thermal_gap 0.5)
				(thermal_bridge_width 0.5)
				(island_removal_mode 0)
			)
			(polygon
				(pts
					(arc
						(start 313.009788 -3.807206)
						(mid 311.155588 -3.807206)
						(end 313.009788 -3.807206)
					)
				)
			)
		)
		(zone
			(layers "F.Cu" "B.Cu" "In1.Cu" "In2.Cu" "In3.Cu" "In4.Cu" "In5.Cu" "In6.Cu"
				"In7.Cu" "In8.Cu" "In9.Cu" "In10.Cu" "In11.Cu" "In12.Cu" "In13.Cu" "In14.Cu"
				"In15.Cu" "In16.Cu"
			)
			(hatch none 0.5)
			(connect_pads
				(clearance 0)
			)
			(min_thickness 0.25)
			(keepout
				(tracks not_allowed)
				(vias allowed)
				(pads allowed)
				(copperpour not_allowed)
				(footprints allowed)
			)
			(placement
				(enabled no)
				(sheetname "")
			)
			(fill
				(thermal_gap 0.5)
				(thermal_bridge_width 0.5)
				(island_removal_mode 0)
			)
			(polygon
				(pts
					(arc
						(start 313.009788 -1.267206)
						(mid 311.155588 -1.267206)
						(end 313.009788 -1.267206)
					)
				)
			)
		)
		(zone
			(layers "F.Cu" "B.Cu" "In1.Cu" "In2.Cu" "In3.Cu" "In4.Cu" "In5.Cu" "In6.Cu"
				"In7.Cu" "In8.Cu" "In9.Cu" "In10.Cu" "In11.Cu" "In12.Cu" "In13.Cu" "In14.Cu"
				"In15.Cu" "In16.Cu"
			)
			(hatch none 0.5)
			(connect_pads
				(clearance 0)
			)
			(min_thickness 0.25)
			(keepout
				(tracks not_allowed)
				(vias allowed)
				(pads allowed)
				(copperpour not_allowed)
				(footprints allowed)
			)
			(placement
				(enabled no)
				(sheetname "")
			)
			(fill
				(thermal_gap 0.5)
				(thermal_bridge_width 0.5)
				(island_removal_mode 0)
			)
			(polygon
				(pts
					(arc
						(start 319.359788 -3.807206)
						(mid 317.505588 -3.807206)
						(end 319.359788 -3.807206)
					)
				)
			)
		)
		(zone
			(layers "F.Cu" "B.Cu" "In1.Cu" "In2.Cu" "In3.Cu" "In4.Cu" "In5.Cu" "In6.Cu"
				"In7.Cu" "In8.Cu" "In9.Cu" "In10.Cu" "In11.Cu" "In12.Cu" "In13.Cu" "In14.Cu"
				"In15.Cu" "In16.Cu"
			)
			(hatch none 0.5)
			(connect_pads
				(clearance 0)
			)
			(min_thickness 0.25)
			(keepout
				(tracks not_allowed)
				(vias allowed)
				(pads allowed)
				(copperpour not_allowed)
				(footprints allowed)
			)
			(placement
				(enabled no)
				(sheetname "")
			)
			(fill
				(thermal_gap 0.5)
				(thermal_bridge_width 0.5)
				(island_removal_mode 0)
			)
			(polygon
				(pts
					(arc
						(start 319.359788 -1.267206)
						(mid 317.505588 -1.267206)
						(end 319.359788 -1.267206)
					)
				)
			)
		)
		(zone
			(layer "B.Cu")
			(hatch none 0.5)
			(connect_pads
				(clearance 0)
			)
			(min_thickness 0.25)
			(keepout
				(tracks not_allowed)
				(vias allowed)
				(pads allowed)
				(copperpour not_allowed)
				(footprints allowed)
			)
			(placement
				(enabled no)
				(sheetname "")
			)
			(fill
				(thermal_gap 0.5)
				(thermal_bridge_width 0.5)
				(island_removal_mode 0)
			)
			(polygon
				(pts
					(xy 316.083188 -1.988566) (xy 316.083188 -2.08407) (xy 315.486288 -2.08407) (xy 315.486288 -2.49047)
					(xy 316.083188 -2.49047) (xy 316.083188 -2.583942) (xy 315.486288 -2.583942) (xy 315.486288 -2.990342)
					(xy 316.083188 -2.990342) (xy 316.083188 -3.085846) (xy 315.384688 -3.085846) (xy 315.384688 -1.988566)
				)
			)
		)
	)
	(footprint ""
		(layer "B.Cu")
		(at 233.807 -334.01 180)
		(property "Reference" "R1067"
			(at 0 0 0)
			(layer "B.SilkS")
			(hide yes)
			(effects
				(font
					(size 1.27 1.27)
				)
				(justify mirror)
			)
		)
		(property "Value" ""
			(at 0 0 0)
			(layer "B.Fab")
			(effects
				(font
					(size 1.27 1.27)
				)
				(justify mirror)
			)
		)
		(duplicate_pad_numbers_are_jumpers no)
		(fp_line
			(start 0.32512 0.175006)
			(end 0.32512 -0.175006)
			(stroke
				(width 0.1)
				(type default)
			)
			(layer "B.Fab")
		)
		(fp_line
			(start 0.32512 -0.175006)
			(end -0.32512 -0.175006)
			(stroke
				(width 0.1)
				(type default)
			)
			(layer "B.Fab")
		)
		(fp_line
			(start -0.32512 0.175006)
			(end 0.32512 0.175006)
			(stroke
				(width 0.1)
				(type default)
			)
			(layer "B.Fab")
		)
		(fp_line
			(start -0.32512 -0.175006)
			(end -0.32512 0.175006)
			(stroke
				(width 0.1)
				(type default)
			)
			(layer "B.Fab")
		)
		(pad "1" smd rect
			(at 0.2667 0)
			(size 0.3048 0.381)
			(layers "B.Cu" "B.Mask" "B.Paste")
			(net "SMB_RT_CPU0_P2_R_SCL")
		)
		(pad "2" smd rect
			(at -0.2667 0 180)
			(size 0.3048 0.381)
			(layers "B.Cu" "B.Mask" "B.Paste")
			(net "SMB_RT_CPU0_P2_R2_SCL")
		)
	)
	(footprint ""
		(layer "B.Cu")
		(at 396.611856 -173.394878 90)
		(property "Reference" "PC587_1"
			(at 0 0 90)
			(layer "B.SilkS")
			(hide yes)
			(effects
				(font
					(size 1.27 1.27)
				)
				(justify mirror)
			)
		)
		(property "Value" ""
			(at 0 0 90)
			(layer "B.Fab")
			(effects
				(font
					(size 1.27 1.27)
				)
				(justify mirror)
			)
		)
		(duplicate_pad_numbers_are_jumpers no)
		(fp_line
			(start 1.524 -0.762)
			(end -1.524 -0.762)
			(stroke
				(width 0.1524)
				(type default)
			)
			(layer "B.SilkS")
		)
		(fp_line
			(start -1.524 -0.762)
			(end -1.524 0.762)
			(stroke
				(width 0.1524)
				(type default)
			)
			(layer "B.SilkS")
		)
		(fp_line
			(start 1.524 0.762)
			(end 1.524 -0.762)
			(stroke
				(width 0.1524)
				(type default)
			)
			(layer "B.SilkS")
		)
		(fp_line
			(start -1.524 0.762)
			(end 1.524 0.762)
			(stroke
				(width 0.1524)
				(type default)
			)
			(layer "B.SilkS")
		)
		(fp_line
			(start 1.1049 -0.724916)
			(end 1.1049 0.724916)
			(stroke
				(width 0.1)
				(type default)
			)
			(layer "B.Fab")
		)
		(fp_line
			(start -1.1049 -0.724916)
			(end 1.1049 -0.724916)
			(stroke
				(width 0.1)
				(type default)
			)
			(layer "B.Fab")
		)
		(fp_line
			(start 1.1049 0.724916)
			(end -1.1049 0.724916)
			(stroke
				(width 0.1)
				(type default)
			)
			(layer "B.Fab")
		)
		(fp_line
			(start -1.1049 0.724916)
			(end -1.1049 -0.724916)
			(stroke
				(width 0.1)
				(type default)
			)
			(layer "B.Fab")
		)
		(pad "1" smd rect
			(at 0.889 0 90)
			(size 1.016 1.27)
			(layers "B.Cu" "B.Mask" "B.Paste")
			(net "SW_P12V_AUX_PVDDCR_SOC_P0_FLT")
		)
		(pad "2" smd rect
			(at -0.889 0 90)
			(size 1.016 1.27)
			(layers "B.Cu" "B.Mask" "B.Paste")
			(net "GND")
		)
	)
	(footprint ""
		(layer "B.Cu")
		(at 435.050946 -26.886408 90)
		(property "Reference" "R1897"
			(at 0 0 90)
			(layer "B.SilkS")
			(hide yes)
			(effects
				(font
					(size 1.27 1.27)
				)
				(justify mirror)
			)
		)
		(property "Value" ""
			(at 0 0 90)
			(layer "B.Fab")
			(effects
				(font
					(size 1.27 1.27)
				)
				(justify mirror)
			)
		)
		(duplicate_pad_numbers_are_jumpers no)
		(fp_line
			(start 0.7874 -0.4064)
			(end -0.7874 -0.4064)
			(stroke
				(width 0.1524)
				(type default)
			)
			(layer "B.SilkS")
		)
		(fp_line
			(start -0.7874 -0.4064)
			(end -0.7874 0.4064)
			(stroke
				(width 0.1524)
				(type default)
			)
			(layer "B.SilkS")
		)
		(fp_line
			(start 0.7874 0.4064)
			(end 0.7874 -0.4064)
			(stroke
				(width 0.1524)
				(type default)
			)
			(layer "B.SilkS")
		)
		(fp_line
			(start -0.7874 0.4064)
			(end 0.7874 0.4064)
			(stroke
				(width 0.1524)
				(type default)
			)
			(layer "B.SilkS")
		)
		(fp_line
			(start 0.67945 -0.305054)
			(end 0.12065 -0.305054)
			(stroke
				(width 0.1)
				(type default)
			)
			(layer "B.Fab")
		)
		(fp_line
			(start 0.12065 -0.305054)
			(end 0.12065 -0.2794)
			(stroke
				(width 0.1)
				(type default)
			)
			(layer "B.Fab")
		)
		(fp_line
			(start -0.12065 -0.3048)
			(end -0.67945 -0.3048)
			(stroke
				(width 0.1)
				(type default)
			)
			(layer "B.Fab")
		)
		(fp_line
			(start -0.67945 -0.3048)
			(end -0.67945 0.3048)
			(stroke
				(width 0.1)
				(type default)
			)
			(layer "B.Fab")
		)
		(fp_line
			(start 0.12065 -0.2794)
			(end -0.12065 -0.2794)
			(stroke
				(width 0.1)
				(type default)
			)
			(layer "B.Fab")
		)
		(fp_line
			(start -0.12065 -0.2794)
			(end -0.12065 -0.3048)
			(stroke
				(width 0.1)
				(type default)
			)
			(layer "B.Fab")
		)
		(fp_line
			(start 0.12065 0.2794)
			(end 0.12065 0.3048)
			(stroke
				(width 0.1)
				(type default)
			)
			(layer "B.Fab")
		)
		(fp_line
			(start -0.120396 0.2794)
			(end 0.12065 0.2794)
			(stroke
				(width 0.1)
				(type default)
			)
			(layer "B.Fab")
		)
		(fp_line
			(start 0.67945 0.3048)
			(end 0.67945 -0.305054)
			(stroke
				(width 0.1)
				(type default)
			)
			(layer "B.Fab")
		)
		(fp_line
			(start 0.12065 0.3048)
			(end 0.67945 0.3048)
			(stroke
				(width 0.1)
				(type default)
			)
			(layer "B.Fab")
		)
		(fp_line
			(start -0.120396 0.3048)
			(end -0.120396 0.2794)
			(stroke
				(width 0.1)
				(type default)
			)
			(layer "B.Fab")
		)
		(fp_line
			(start -0.67945 0.3048)
			(end -0.120396 0.3048)
			(stroke
				(width 0.1)
				(type default)
			)
			(layer "B.Fab")
		)
		(pad "1" smd circle
			(at 0.40005 0 270)
			(size 0 0)
			(layers "B.Cu" "B.Mask" "B.Paste")
			(net "OCP_SFF_ISO_BIF1_EN")
		)
		(pad "2" smd circle
			(at -0.40005 0 270)
			(size 0 0)
			(layers "B.Cu" "B.Mask" "B.Paste")
			(net "GND")
		)
	)
	(footprint ""
		(layer "B.Cu")
		(at 106.466386 -267.529564)
		(property "Reference" "C2403"
			(at 0 0 0)
			(layer "B.SilkS")
			(hide yes)
			(effects
				(font
					(size 1.27 1.27)
				)
				(justify mirror)
			)
		)
		(property "Value" ""
			(at 0 0 0)
			(layer "B.Fab")
			(effects
				(font
					(size 1.27 1.27)
				)
				(justify mirror)
			)
		)
		(duplicate_pad_numbers_are_jumpers no)
		(fp_line
			(start -0.7874 -0.4064)
			(end -0.7874 0.4064)
			(stroke
				(width 0.1524)
				(type default)
			)
			(layer "B.SilkS")
		)
		(fp_line
			(start -0.7874 0.4064)
			(end 0.7874 0.4064)
			(stroke
				(width 0.1524)
				(type default)
			)
			(layer "B.SilkS")
		)
		(fp_line
			(start 0.7874 -0.4064)
			(end -0.7874 -0.4064)
			(stroke
				(width 0.1524)
				(type default)
			)
			(layer "B.SilkS")
		)
		(fp_line
			(start 0.7874 0.4064)
			(end 0.7874 -0.4064)
			(stroke
				(width 0.1524)
				(type default)
			)
			(layer "B.SilkS")
		)
		(fp_line
			(start -0.67945 -0.3048)
			(end -0.67945 0.3048)
			(stroke
				(width 0.1)
				(type default)
			)
			(layer "B.Fab")
		)
		(fp_line
			(start -0.67945 0.3048)
			(end -0.120396 0.3048)
			(stroke
				(width 0.1)
				(type default)
			)
			(layer "B.Fab")
		)
		(fp_line
			(start -0.12065 -0.3048)
			(end -0.67945 -0.3048)
			(stroke
				(width 0.1)
				(type default)
			)
			(layer "B.Fab")
		)
		(fp_line
			(start -0.12065 -0.2794)
			(end -0.12065 -0.3048)
			(stroke
				(width 0.1)
				(type default)
			)
			(layer "B.Fab")
		)
		(fp_line
			(start -0.120396 0.2794)
			(end 0.12065 0.2794)
			(stroke
				(width 0.1)
				(type default)
			)
			(layer "B.Fab")
		)
		(fp_line
			(start -0.120396 0.3048)
			(end -0.120396 0.2794)
			(stroke
				(width 0.1)
				(type default)
			)
			(layer "B.Fab")
		)
		(fp_line
			(start 0.12065 -0.305054)
			(end 0.12065 -0.2794)
			(stroke
				(width 0.1)
				(type default)
			)
			(layer "B.Fab")
		)
		(fp_line
			(start 0.12065 -0.2794)
			(end -0.12065 -0.2794)
			(stroke
				(width 0.1)
				(type default)
			)
			(layer "B.Fab")
		)
		(fp_line
			(start 0.12065 0.2794)
			(end 0.12065 0.3048)
			(stroke
				(width 0.1)
				(type default)
			)
			(layer "B.Fab")
		)
		(fp_line
			(start 0.12065 0.3048)
			(end 0.67945 0.3048)
			(stroke
				(width 0.1)
				(type default)
			)
			(layer "B.Fab")
		)
		(fp_line
			(start 0.67945 -0.305054)
			(end 0.12065 -0.305054)
			(stroke
				(width 0.1)
				(type default)
			)
			(layer "B.Fab")
		)
		(fp_line
			(start 0.67945 0.3048)
			(end 0.67945 -0.305054)
			(stroke
				(width 0.1)
				(type default)
			)
			(layer "B.Fab")
		)
		(pad "1" smd circle
			(at 0.40005 0 180)
			(size 0 0)
			(layers "B.Cu" "B.Mask" "B.Paste")
			(net "PVDDCR_CPU1_P1")
		)
		(pad "2" smd circle
			(at -0.40005 0 180)
			(size 0 0)
			(layers "B.Cu" "B.Mask" "B.Paste")
			(net "GND")
		)
	)
	(footprint ""
		(layer "B.Cu")
		(at 428.98695 -34.737548 180)
		(property "Reference" "R1356"
			(at 0 0 0)
			(layer "B.SilkS")
			(hide yes)
			(effects
				(font
					(size 1.27 1.27)
				)
				(justify mirror)
			)
		)
		(property "Value" ""
			(at 0 0 0)
			(layer "B.Fab")
			(effects
				(font
					(size 1.27 1.27)
				)
				(justify mirror)
			)
		)
		(duplicate_pad_numbers_are_jumpers no)
		(fp_line
			(start 0.7874 0.4064)
			(end 0.7874 -0.4064)
			(stroke
				(width 0.1524)
				(type default)
			)
			(layer "B.SilkS")
		)
		(fp_line
			(start 0.7874 -0.4064)
			(end -0.7874 -0.4064)
			(stroke
				(width 0.1524)
				(type default)
			)
			(layer "B.SilkS")
		)
		(fp_line
			(start -0.7874 0.4064)
			(end 0.7874 0.4064)
			(stroke
				(width 0.1524)
				(type default)
			)
			(layer "B.SilkS")
		)
		(fp_line
			(start -0.7874 -0.4064)
			(end -0.7874 0.4064)
			(stroke
				(width 0.1524)
				(type default)
			)
			(layer "B.SilkS")
		)
		(fp_line
			(start 0.67945 0.3048)
			(end 0.67945 -0.305054)
			(stroke
				(width 0.1)
				(type default)
			)
			(layer "B.Fab")
		)
		(fp_line
			(start 0.67945 -0.305054)
			(end 0.12065 -0.305054)
			(stroke
				(width 0.1)
				(type default)
			)
			(layer "B.Fab")
		)
		(fp_line
			(start 0.12065 0.3048)
			(end 0.67945 0.3048)
			(stroke
				(width 0.1)
				(type default)
			)
			(layer "B.Fab")
		)
		(fp_line
			(start 0.12065 0.2794)
			(end 0.12065 0.3048)
			(stroke
				(width 0.1)
				(type default)
			)
			(layer "B.Fab")
		)
		(fp_line
			(start 0.12065 -0.2794)
			(end -0.12065 -0.2794)
			(stroke
				(width 0.1)
				(type default)
			)
			(layer "B.Fab")
		)
		(fp_line
			(start 0.12065 -0.305054)
			(end 0.12065 -0.2794)
			(stroke
				(width 0.1)
				(type default)
			)
			(layer "B.Fab")
		)
		(fp_line
			(start -0.120396 0.3048)
			(end -0.120396 0.2794)
			(stroke
				(width 0.1)
				(type default)
			)
			(layer "B.Fab")
		)
		(fp_line
			(start -0.120396 0.2794)
			(end 0.12065 0.2794)
			(stroke
				(width 0.1)
				(type default)
			)
			(layer "B.Fab")
		)
		(fp_line
			(start -0.12065 -0.2794)
			(end -0.12065 -0.3048)
			(stroke
				(width 0.1)
				(type default)
			)
			(layer "B.Fab")
		)
		(fp_line
			(start -0.12065 -0.3048)
			(end -0.67945 -0.3048)
			(stroke
				(width 0.1)
				(type default)
			)
			(layer "B.Fab")
		)
		(fp_line
			(start -0.67945 0.3048)
			(end -0.120396 0.3048)
			(stroke
				(width 0.1)
				(type default)
			)
			(layer "B.Fab")
		)
		(fp_line
			(start -0.67945 -0.3048)
			(end -0.67945 0.3048)
			(stroke
				(width 0.1)
				(type default)
			)
			(layer "B.Fab")
		)
		(pad "1" smd circle
			(at 0.40005 0)
			(size 0 0)
			(layers "B.Cu" "B.Mask" "B.Paste")
			(net "P3V3_AUX")
		)
		(pad "2" smd circle
			(at -0.40005 0)
			(size 0 0)
			(layers "B.Cu" "B.Mask" "B.Paste")
			(net "FM_PRSNT_CPU0_N")
		)
	)
	(footprint ""
		(layer "B.Cu")
		(at 77.6224 -174.960534 90)
		(property "Reference" "PR204"
			(at 0 0 90)
			(layer "B.SilkS")
			(hide yes)
			(effects
				(font
					(size 1.27 1.27)
				)
				(justify mirror)
			)
		)
		(property "Value" ""
			(at 0 0 90)
			(layer "B.Fab")
			(effects
				(font
					(size 1.27 1.27)
				)
				(justify mirror)
			)
		)
		(duplicate_pad_numbers_are_jumpers no)
		(fp_line
			(start 0.7874 -0.4064)
			(end -0.7874 -0.4064)
			(stroke
				(width 0.1524)
				(type default)
			)
			(layer "B.SilkS")
		)
		(fp_line
			(start -0.7874 -0.4064)
			(end -0.7874 0.4064)
			(stroke
				(width 0.1524)
				(type default)
			)
			(layer "B.SilkS")
		)
		(fp_line
			(start 0.7874 0.4064)
			(end 0.7874 -0.4064)
			(stroke
				(width 0.1524)
				(type default)
			)
			(layer "B.SilkS")
		)
		(fp_line
			(start -0.7874 0.4064)
			(end 0.7874 0.4064)
			(stroke
				(width 0.1524)
				(type default)
			)
			(layer "B.SilkS")
		)
		(fp_line
			(start 0.67945 -0.305054)
			(end 0.12065 -0.305054)
			(stroke
				(width 0.1)
				(type default)
			)
			(layer "B.Fab")
		)
		(fp_line
			(start 0.12065 -0.305054)
			(end 0.12065 -0.2794)
			(stroke
				(width 0.1)
				(type default)
			)
			(layer "B.Fab")
		)
		(fp_line
			(start -0.12065 -0.3048)
			(end -0.67945 -0.3048)
			(stroke
				(width 0.1)
				(type default)
			)
			(layer "B.Fab")
		)
		(fp_line
			(start -0.67945 -0.3048)
			(end -0.67945 0.3048)
			(stroke
				(width 0.1)
				(type default)
			)
			(layer "B.Fab")
		)
		(fp_line
			(start 0.12065 -0.2794)
			(end -0.12065 -0.2794)
			(stroke
				(width 0.1)
				(type default)
			)
			(layer "B.Fab")
		)
		(fp_line
			(start -0.12065 -0.2794)
			(end -0.12065 -0.3048)
			(stroke
				(width 0.1)
				(type default)
			)
			(layer "B.Fab")
		)
		(fp_line
			(start 0.12065 0.2794)
			(end 0.12065 0.3048)
			(stroke
				(width 0.1)
				(type default)
			)
			(layer "B.Fab")
		)
		(fp_line
			(start -0.120396 0.2794)
			(end 0.12065 0.2794)
			(stroke
				(width 0.1)
				(type default)
			)
			(layer "B.Fab")
		)
		(fp_line
			(start 0.67945 0.3048)
			(end 0.67945 -0.305054)
			(stroke
				(width 0.1)
				(type default)
			)
			(layer "B.Fab")
		)
		(fp_line
			(start 0.12065 0.3048)
			(end 0.67945 0.3048)
			(stroke
				(width 0.1)
				(type default)
			)
			(layer "B.Fab")
		)
		(fp_line
			(start -0.120396 0.3048)
			(end -0.120396 0.2794)
			(stroke
				(width 0.1)
				(type default)
			)
			(layer "B.Fab")
		)
		(fp_line
			(start -0.67945 0.3048)
			(end -0.120396 0.3048)
			(stroke
				(width 0.1)
				(type default)
			)
			(layer "B.Fab")
		)
		(pad "1" smd circle
			(at 0.40005 0 270)
			(size 0 0)
			(layers "B.Cu" "B.Mask" "B.Paste")
			(net "PVDDCR_CPU0_P1_VOS5")
		)
		(pad "2" smd circle
			(at -0.40005 0 270)
			(size 0 0)
			(layers "B.Cu" "B.Mask" "B.Paste")
			(net "PVDDCR_CPU0_P1")
		)
	)
	(footprint ""
		(layer "B.Cu")
		(at 147.032726 -408.517344 90)
		(property "Reference" "C6746"
			(at 0 0 90)
			(layer "B.SilkS")
			(hide yes)
			(effects
				(font
					(size 1.27 1.27)
				)
				(justify mirror)
			)
		)
		(property "Value" ""
			(at 0 0 90)
			(layer "B.Fab")
			(effects
				(font
					(size 1.27 1.27)
				)
				(justify mirror)
			)
		)
		(duplicate_pad_numbers_are_jumpers no)
		(fp_line
			(start 0.299974 -0.150114)
			(end -0.299974 -0.150114)
			(stroke
				(width 0.1)
				(type default)
			)
			(layer "B.Fab")
		)
		(fp_line
			(start -0.299974 -0.150114)
			(end -0.299974 0.150114)
			(stroke
				(width 0.1)
				(type default)
			)
			(layer "B.Fab")
		)
		(fp_line
			(start 0.299974 0.150114)
			(end 0.299974 -0.150114)
			(stroke
				(width 0.1)
				(type default)
			)
			(layer "B.Fab")
		)
		(fp_line
			(start -0.299974 0.150114)
			(end 0.299974 0.150114)
			(stroke
				(width 0.1)
				(type default)
			)
			(layer "B.Fab")
		)
		(pad "1" smd rect
			(at 0.2667 0 270)
			(size 0.3048 0.381)
			(layers "B.Cu" "B.Mask" "B.Paste")
			(net "P5E_CPU1_P3_TX_BUF_C_DN<10>")
		)
		(pad "2" smd rect
			(at -0.2667 0 270)
			(size 0.3048 0.381)
			(layers "B.Cu" "B.Mask" "B.Paste")
			(net "P5E_CPU1_P3_TX_BUF_DN<10>")
		)
	)
	(footprint ""
		(layer "B.Cu")
		(at 174.98568 -24.653748)
		(property "Reference" "PC2240"
			(at 0 0 0)
			(layer "B.SilkS")
			(hide yes)
			(effects
				(font
					(size 1.27 1.27)
				)
				(justify mirror)
			)
		)
		(property "Value" ""
			(at 0 0 0)
			(layer "B.Fab")
			(effects
				(font
					(size 1.27 1.27)
				)
				(justify mirror)
			)
		)
		(duplicate_pad_numbers_are_jumpers no)
		(fp_line
			(start -1.524 -0.762)
			(end -1.524 0.762)
			(stroke
				(width 0.1524)
				(type default)
			)
			(layer "B.SilkS")
		)
		(fp_line
			(start -1.524 0.762)
			(end 1.524 0.762)
			(stroke
				(width 0.1524)
				(type default)
			)
			(layer "B.SilkS")
		)
		(fp_line
			(start 1.524 -0.762)
			(end -1.524 -0.762)
			(stroke
				(width 0.1524)
				(type default)
			)
			(layer "B.SilkS")
		)
		(fp_line
			(start 1.524 0.762)
			(end 1.524 -0.762)
			(stroke
				(width 0.1524)
				(type default)
			)
			(layer "B.SilkS")
		)
		(fp_line
			(start -1.1049 -0.724916)
			(end 1.1049 -0.724916)
			(stroke
				(width 0.1)
				(type default)
			)
			(layer "B.Fab")
		)
		(fp_line
			(start -1.1049 0.724916)
			(end -1.1049 -0.724916)
			(stroke
				(width 0.1)
				(type default)
			)
			(layer "B.Fab")
		)
		(fp_line
			(start 1.1049 -0.724916)
			(end 1.1049 0.724916)
			(stroke
				(width 0.1)
				(type default)
			)
			(layer "B.Fab")
		)
		(fp_line
			(start 1.1049 0.724916)
			(end -1.1049 0.724916)
			(stroke
				(width 0.1)
				(type default)
			)
			(layer "B.Fab")
		)
		(pad "1" smd rect
			(at 0.889 0)
			(size 1.016 1.27)
			(layers "B.Cu" "B.Mask" "B.Paste")
			(net "P12V_SCM_R")
		)
		(pad "2" smd rect
			(at -0.889 0)
			(size 1.016 1.27)
			(layers "B.Cu" "B.Mask" "B.Paste")
			(net "GND")
		)
	)
	(footprint ""
		(layer "B.Cu")
		(at 97.902522 -150.698962 -90)
		(property "Reference" "PR436"
			(at 0 0 90)
			(layer "B.SilkS")
			(hide yes)
			(effects
				(font
					(size 1.27 1.27)
				)
				(justify mirror)
			)
		)
		(property "Value" ""
			(at 0 0 90)
			(layer "B.Fab")
			(effects
				(font
					(size 1.27 1.27)
				)
				(justify mirror)
			)
		)
		(duplicate_pad_numbers_are_jumpers no)
		(fp_line
			(start -0.7874 0.4064)
			(end 0.7874 0.4064)
			(stroke
				(width 0.1524)
				(type default)
			)
			(layer "B.SilkS")
		)
		(fp_line
			(start 0.7874 0.4064)
			(end 0.7874 -0.4064)
			(stroke
				(width 0.1524)
				(type default)
			)
			(layer "B.SilkS")
		)
		(fp_line
			(start -0.7874 -0.4064)
			(end -0.7874 0.4064)
			(stroke
				(width 0.1524)
				(type default)
			)
			(layer "B.SilkS")
		)
		(fp_line
			(start 0.7874 -0.4064)
			(end -0.7874 -0.4064)
			(stroke
				(width 0.1524)
				(type default)
			)
			(layer "B.SilkS")
		)
		(fp_line
			(start -0.67945 0.3048)
			(end -0.120396 0.3048)
			(stroke
				(width 0.1)
				(type default)
			)
			(layer "B.Fab")
		)
		(fp_line
			(start -0.120396 0.3048)
			(end -0.120396 0.2794)
			(stroke
				(width 0.1)
				(type default)
			)
			(layer "B.Fab")
		)
		(fp_line
			(start 0.12065 0.3048)
			(end 0.67945 0.3048)
			(stroke
				(width 0.1)
				(type default)
			)
			(layer "B.Fab")
		)
		(fp_line
			(start 0.67945 0.3048)
			(end 0.67945 -0.305054)
			(stroke
				(width 0.1)
				(type default)
			)
			(layer "B.Fab")
		)
		(fp_line
			(start -0.120396 0.2794)
			(end 0.12065 0.2794)
			(stroke
				(width 0.1)
				(type default)
			)
			(layer "B.Fab")
		)
		(fp_line
			(start 0.12065 0.2794)
			(end 0.12065 0.3048)
			(stroke
				(width 0.1)
				(type default)
			)
			(layer "B.Fab")
		)
		(fp_line
			(start -0.12065 -0.2794)
			(end -0.12065 -0.3048)
			(stroke
				(width 0.1)
				(type default)
			)
			(layer "B.Fab")
		)
		(fp_line
			(start 0.12065 -0.2794)
			(end -0.12065 -0.2794)
			(stroke
				(width 0.1)
				(type default)
			)
			(layer "B.Fab")
		)
		(fp_line
			(start -0.67945 -0.3048)
			(end -0.67945 0.3048)
			(stroke
				(width 0.1)
				(type default)
			)
			(layer "B.Fab")
		)
		(fp_line
			(start -0.12065 -0.3048)
			(end -0.67945 -0.3048)
			(stroke
				(width 0.1)
				(type default)
			)
			(layer "B.Fab")
		)
		(fp_line
			(start 0.12065 -0.305054)
			(end 0.12065 -0.2794)
			(stroke
				(width 0.1)
				(type default)
			)
			(layer "B.Fab")
		)
		(fp_line
			(start 0.67945 -0.305054)
			(end 0.12065 -0.305054)
			(stroke
				(width 0.1)
				(type default)
			)
			(layer "B.Fab")
		)
		(pad "1" smd circle
			(at 0.40005 0 90)
			(size 0 0)
			(layers "B.Cu" "B.Mask" "B.Paste")
			(net "NC_PVDDCR_CPU0_P1_IMON8")
		)
		(pad "2" smd circle
			(at -0.40005 0 90)
			(size 0 0)
			(layers "B.Cu" "B.Mask" "B.Paste")
			(net "GND")
		)
	)
	(footprint ""
		(layer "B.Cu")
		(at 394.765276 -177.294794 -90)
		(property "Reference" "PC591_1"
			(at 0 0 90)
			(layer "B.SilkS")
			(hide yes)
			(effects
				(font
					(size 1.27 1.27)
				)
				(justify mirror)
			)
		)
		(property "Value" ""
			(at 0 0 90)
			(layer "B.Fab")
			(effects
				(font
					(size 1.27 1.27)
				)
				(justify mirror)
			)
		)
		(duplicate_pad_numbers_are_jumpers no)
		(fp_line
			(start -1.524 0.762)
			(end 1.524 0.762)
			(stroke
				(width 0.1524)
				(type default)
			)
			(layer "B.SilkS")
		)
		(fp_line
			(start 1.524 0.762)
			(end 1.524 -0.762)
			(stroke
				(width 0.1524)
				(type default)
			)
			(layer "B.SilkS")
		)
		(fp_line
			(start -1.524 -0.762)
			(end -1.524 0.762)
			(stroke
				(width 0.1524)
				(type default)
			)
			(layer "B.SilkS")
		)
		(fp_line
			(start 1.524 -0.762)
			(end -1.524 -0.762)
			(stroke
				(width 0.1524)
				(type default)
			)
			(layer "B.SilkS")
		)
		(fp_line
			(start -1.1049 0.724916)
			(end -1.1049 -0.724916)
			(stroke
				(width 0.1)
				(type default)
			)
			(layer "B.Fab")
		)
		(fp_line
			(start 1.1049 0.724916)
			(end -1.1049 0.724916)
			(stroke
				(width 0.1)
				(type default)
			)
			(layer "B.Fab")
		)
		(fp_line
			(start -1.1049 -0.724916)
			(end 1.1049 -0.724916)
			(stroke
				(width 0.1)
				(type default)
			)
			(layer "B.Fab")
		)
		(fp_line
			(start 1.1049 -0.724916)
			(end 1.1049 0.724916)
			(stroke
				(width 0.1)
				(type default)
			)
			(layer "B.Fab")
		)
		(pad "1" smd rect
			(at 0.889 0 270)
			(size 1.016 1.27)
			(layers "B.Cu" "B.Mask" "B.Paste")
			(net "SW_P12V_AUX_PVDDCR_SOC_P0_FLT")
		)
		(pad "2" smd rect
			(at -0.889 0 270)
			(size 1.016 1.27)
			(layers "B.Cu" "B.Mask" "B.Paste")
			(net "GND")
		)
	)
	(footprint ""
		(layer "B.Cu")
		(at 300.538388 -2.537206)
		(property "Reference" "J86"
			(at 4.532122 1.115568 270)
			(unlocked yes)
			(layer "B.SilkS")
			(effects
				(font
					(size 0.7874 0.5842)
					(thickness 0.1524)
				)
				(justify left mirror)
			)
		)
		(property "Value" ""
			(at 0 0 0)
			(layer "B.Fab")
			(effects
				(font
					(size 1.27 1.27)
				)
				(justify mirror)
			)
		)
		(duplicate_pad_numbers_are_jumpers no)
		(fp_line
			(start -1.2192 -2.06756)
			(end -1.2192 2.06756)
			(stroke
				(width 0.1524)
				(type default)
			)
			(layer "B.SilkS")
		)
		(fp_line
			(start -1.2192 2.06756)
			(end 1.2192 2.06756)
			(stroke
				(width 0.1524)
				(type default)
			)
			(layer "B.SilkS")
		)
		(fp_line
			(start 1.2192 -2.06756)
			(end -1.2192 -2.06756)
			(stroke
				(width 0.1524)
				(type default)
			)
			(layer "B.SilkS")
		)
		(fp_line
			(start 1.2192 2.06756)
			(end 1.2192 -2.06756)
			(stroke
				(width 0.1524)
				(type default)
			)
			(layer "B.SilkS")
		)
		(pad "" np_thru_hole circle
			(at -3.4671 -1.27 270)
			(size 1.0414 1.0414)
			(drill 1.0414)
			(layers "*.Cu" "*.Mask")
			(clearance 0.381)
			(thermal_gap 0.381)
		)
		(pad "" np_thru_hole circle
			(at -3.4671 1.27 270)
			(size 1.0414 1.0414)
			(drill 1.0414)
			(layers "*.Cu" "*.Mask")
			(clearance 0.381)
			(thermal_gap 0.381)
		)
		(pad "" np_thru_hole circle
			(at 2.8829 -1.27 270)
			(size 1.0414 1.0414)
			(drill 1.0414)
			(layers "*.Cu" "*.Mask")
			(clearance 0.381)
			(thermal_gap 0.381)
		)
		(pad "" np_thru_hole circle
			(at 2.8829 1.27 270)
			(size 1.0414 1.0414)
			(drill 1.0414)
			(layers "*.Cu" "*.Mask")
			(clearance 0.381)
			(thermal_gap 0.381)
		)
		(pad "1" smd rect
			(at -0.8255 -0.249936 270)
			(size 0.3048 0.508)
			(layers "B.Cu" "B.Mask" "B.Paste")
			(net "DELTA_L_85_10INCH_IN4_DN")
		)
		(pad "2" smd rect
			(at -0.8255 0.249936 270)
			(size 0.3048 0.508)
			(layers "B.Cu" "B.Mask" "B.Paste")
			(net "DELTA_L_85_10INCH_IN4_DP")
		)
		(pad "3" smd circle
			(at 0 0 180)
			(size 0 0)
			(layers "B.Cu" "B.Mask" "B.Paste")
			(net "DELTA_L_GND_1")
		)
		(zone
			(layers "F.Cu" "B.Cu" "In1.Cu" "In2.Cu" "In3.Cu" "In4.Cu" "In5.Cu" "In6.Cu"
				"In7.Cu" "In8.Cu" "In9.Cu" "In10.Cu" "In11.Cu" "In12.Cu" "In13.Cu" "In14.Cu"
				"In15.Cu" "In16.Cu"
			)
			(hatch none 0.5)
			(connect_pads
				(clearance 0)
			)
			(min_thickness 0.25)
			(keepout
				(tracks not_allowed)
				(vias allowed)
				(pads allowed)
				(copperpour not_allowed)
				(footprints allowed)
			)
			(placement
				(enabled no)
				(sheetname "")
			)
			(fill
				(thermal_gap 0.5)
				(thermal_bridge_width 0.5)
				(island_removal_mode 0)
			)
			(polygon
				(pts
					(arc
						(start 297.998388 -3.807206)
						(mid 296.144188 -3.807206)
						(end 297.998388 -3.807206)
					)
				)
			)
		)
		(zone
			(layers "F.Cu" "B.Cu" "In1.Cu" "In2.Cu" "In3.Cu" "In4.Cu" "In5.Cu" "In6.Cu"
				"In7.Cu" "In8.Cu" "In9.Cu" "In10.Cu" "In11.Cu" "In12.Cu" "In13.Cu" "In14.Cu"
				"In15.Cu" "In16.Cu"
			)
			(hatch none 0.5)
			(connect_pads
				(clearance 0)
			)
			(min_thickness 0.25)
			(keepout
				(tracks not_allowed)
				(vias allowed)
				(pads allowed)
				(copperpour not_allowed)
				(footprints allowed)
			)
			(placement
				(enabled no)
				(sheetname "")
			)
			(fill
				(thermal_gap 0.5)
				(thermal_bridge_width 0.5)
				(island_removal_mode 0)
			)
			(polygon
				(pts
					(arc
						(start 297.998388 -1.267206)
						(mid 296.144188 -1.267206)
						(end 297.998388 -1.267206)
					)
				)
			)
		)
		(zone
			(layers "F.Cu" "B.Cu" "In1.Cu" "In2.Cu" "In3.Cu" "In4.Cu" "In5.Cu" "In6.Cu"
				"In7.Cu" "In8.Cu" "In9.Cu" "In10.Cu" "In11.Cu" "In12.Cu" "In13.Cu" "In14.Cu"
				"In15.Cu" "In16.Cu"
			)
			(hatch none 0.5)
			(connect_pads
				(clearance 0)
			)
			(min_thickness 0.25)
			(keepout
				(tracks not_allowed)
				(vias allowed)
				(pads allowed)
				(copperpour not_allowed)
				(footprints allowed)
			)
			(placement
				(enabled no)
				(sheetname "")
			)
			(fill
				(thermal_gap 0.5)
				(thermal_bridge_width 0.5)
				(island_removal_mode 0)
			)
			(polygon
				(pts
					(arc
						(start 304.348388 -3.807206)
						(mid 302.494188 -3.807206)
						(end 304.348388 -3.807206)
					)
				)
			)
		)
		(zone
			(layers "F.Cu" "B.Cu" "In1.Cu" "In2.Cu" "In3.Cu" "In4.Cu" "In5.Cu" "In6.Cu"
				"In7.Cu" "In8.Cu" "In9.Cu" "In10.Cu" "In11.Cu" "In12.Cu" "In13.Cu" "In14.Cu"
				"In15.Cu" "In16.Cu"
			)
			(hatch none 0.5)
			(connect_pads
				(clearance 0)
			)
			(min_thickness 0.25)
			(keepout
				(tracks not_allowed)
				(vias allowed)
				(pads allowed)
				(copperpour not_allowed)
				(footprints allowed)
			)
			(placement
				(enabled no)
				(sheetname "")
			)
			(fill
				(thermal_gap 0.5)
				(thermal_bridge_width 0.5)
				(island_removal_mode 0)
			)
			(polygon
				(pts
					(arc
						(start 304.348388 -1.267206)
						(mid 302.494188 -1.267206)
						(end 304.348388 -1.267206)
					)
				)
			)
		)
		(zone
			(layer "B.Cu")
			(hatch none 0.5)
			(connect_pads
				(clearance 0)
			)
			(min_thickness 0.25)
			(keepout
				(tracks not_allowed)
				(vias allowed)
				(pads allowed)
				(copperpour not_allowed)
				(footprints allowed)
			)
			(placement
				(enabled no)
				(sheetname "")
			)
			(fill
				(thermal_gap 0.5)
				(thermal_bridge_width 0.5)
				(island_removal_mode 0)
			)
			(polygon
				(pts
					(xy 299.420788 -3.085846) (xy 299.420788 -2.990342) (xy 300.017688 -2.990342) (xy 300.017688 -2.583942)
					(xy 299.420788 -2.583942) (xy 299.420788 -2.49047) (xy 300.017688 -2.49047) (xy 300.017688 -2.08407)
					(xy 299.420788 -2.08407) (xy 299.420788 -1.988566) (xy 300.119288 -1.988566) (xy 300.119288 -3.085846)
				)
			)
		)
	)
	(footprint ""
		(layer "B.Cu")
		(at 163.74618 -117.33022 180)
		(property "Reference" "R407"
			(at 0 0 0)
			(layer "B.SilkS")
			(hide yes)
			(effects
				(font
					(size 1.27 1.27)
				)
				(justify mirror)
			)
		)
		(property "Value" ""
			(at 0 0 0)
			(layer "B.Fab")
			(effects
				(font
					(size 1.27 1.27)
				)
				(justify mirror)
			)
		)
		(duplicate_pad_numbers_are_jumpers no)
		(fp_line
			(start 0.7874 0.4064)
			(end 0.7874 -0.4064)
			(stroke
				(width 0.1524)
				(type default)
			)
			(layer "B.SilkS")
		)
		(fp_line
			(start 0.7874 -0.4064)
			(end -0.7874 -0.4064)
			(stroke
				(width 0.1524)
				(type default)
			)
			(layer "B.SilkS")
		)
		(fp_line
			(start -0.7874 0.4064)
			(end 0.7874 0.4064)
			(stroke
				(width 0.1524)
				(type default)
			)
			(layer "B.SilkS")
		)
		(fp_line
			(start -0.7874 -0.4064)
			(end -0.7874 0.4064)
			(stroke
				(width 0.1524)
				(type default)
			)
			(layer "B.SilkS")
		)
		(fp_line
			(start 0.67945 0.3048)
			(end 0.67945 -0.305054)
			(stroke
				(width 0.1)
				(type default)
			)
			(layer "B.Fab")
		)
		(fp_line
			(start 0.67945 -0.305054)
			(end 0.12065 -0.305054)
			(stroke
				(width 0.1)
				(type default)
			)
			(layer "B.Fab")
		)
		(fp_line
			(start 0.12065 0.3048)
			(end 0.67945 0.3048)
			(stroke
				(width 0.1)
				(type default)
			)
			(layer "B.Fab")
		)
		(fp_line
			(start 0.12065 0.2794)
			(end 0.12065 0.3048)
			(stroke
				(width 0.1)
				(type default)
			)
			(layer "B.Fab")
		)
		(fp_line
			(start 0.12065 -0.2794)
			(end -0.12065 -0.2794)
			(stroke
				(width 0.1)
				(type default)
			)
			(layer "B.Fab")
		)
		(fp_line
			(start 0.12065 -0.305054)
			(end 0.12065 -0.2794)
			(stroke
				(width 0.1)
				(type default)
			)
			(layer "B.Fab")
		)
		(fp_line
			(start -0.120396 0.3048)
			(end -0.120396 0.2794)
			(stroke
				(width 0.1)
				(type default)
			)
			(layer "B.Fab")
		)
		(fp_line
			(start -0.120396 0.2794)
			(end 0.12065 0.2794)
			(stroke
				(width 0.1)
				(type default)
			)
			(layer "B.Fab")
		)
		(fp_line
			(start -0.12065 -0.2794)
			(end -0.12065 -0.3048)
			(stroke
				(width 0.1)
				(type default)
			)
			(layer "B.Fab")
		)
		(fp_line
			(start -0.12065 -0.3048)
			(end -0.67945 -0.3048)
			(stroke
				(width 0.1)
				(type default)
			)
			(layer "B.Fab")
		)
		(fp_line
			(start -0.67945 0.3048)
			(end -0.120396 0.3048)
			(stroke
				(width 0.1)
				(type default)
			)
			(layer "B.Fab")
		)
		(fp_line
			(start -0.67945 -0.3048)
			(end -0.67945 0.3048)
			(stroke
				(width 0.1)
				(type default)
			)
			(layer "B.Fab")
		)
		(pad "1" smd circle
			(at 0.40005 0)
			(size 0 0)
			(layers "B.Cu" "B.Mask" "B.Paste")
			(net "P12V_OCP_V3_2_PLD_PWRGD")
		)
		(pad "2" smd circle
			(at -0.40005 0)
			(size 0 0)
			(layers "B.Cu" "B.Mask" "B.Paste")
			(net "HP_LVC3_OCP_V3_2_P12V_PWRGD_R")
		)
	)
	(footprint ""
		(layer "B.Cu")
		(at 455.084688 -13.102844 90)
		(property "Reference" "R1930"
			(at 0 0 90)
			(layer "B.SilkS")
			(hide yes)
			(effects
				(font
					(size 1.27 1.27)
				)
				(justify mirror)
			)
		)
		(property "Value" ""
			(at 0 0 90)
			(layer "B.Fab")
			(effects
				(font
					(size 1.27 1.27)
				)
				(justify mirror)
			)
		)
		(duplicate_pad_numbers_are_jumpers no)
		(fp_line
			(start 0.7874 -0.4064)
			(end -0.7874 -0.4064)
			(stroke
				(width 0.1524)
				(type default)
			)
			(layer "B.SilkS")
		)
		(fp_line
			(start -0.7874 -0.4064)
			(end -0.7874 0.4064)
			(stroke
				(width 0.1524)
				(type default)
			)
			(layer "B.SilkS")
		)
		(fp_line
			(start 0.7874 0.4064)
			(end 0.7874 -0.4064)
			(stroke
				(width 0.1524)
				(type default)
			)
			(layer "B.SilkS")
		)
		(fp_line
			(start -0.7874 0.4064)
			(end 0.7874 0.4064)
			(stroke
				(width 0.1524)
				(type default)
			)
			(layer "B.SilkS")
		)
		(fp_line
			(start 0.67945 -0.305054)
			(end 0.12065 -0.305054)
			(stroke
				(width 0.1)
				(type default)
			)
			(layer "B.Fab")
		)
		(fp_line
			(start 0.12065 -0.305054)
			(end 0.12065 -0.2794)
			(stroke
				(width 0.1)
				(type default)
			)
			(layer "B.Fab")
		)
		(fp_line
			(start -0.12065 -0.3048)
			(end -0.67945 -0.3048)
			(stroke
				(width 0.1)
				(type default)
			)
			(layer "B.Fab")
		)
		(fp_line
			(start -0.67945 -0.3048)
			(end -0.67945 0.3048)
			(stroke
				(width 0.1)
				(type default)
			)
			(layer "B.Fab")
		)
		(fp_line
			(start 0.12065 -0.2794)
			(end -0.12065 -0.2794)
			(stroke
				(width 0.1)
				(type default)
			)
			(layer "B.Fab")
		)
		(fp_line
			(start -0.12065 -0.2794)
			(end -0.12065 -0.3048)
			(stroke
				(width 0.1)
				(type default)
			)
			(layer "B.Fab")
		)
		(fp_line
			(start 0.12065 0.2794)
			(end 0.12065 0.3048)
			(stroke
				(width 0.1)
				(type default)
			)
			(layer "B.Fab")
		)
		(fp_line
			(start -0.120396 0.2794)
			(end 0.12065 0.2794)
			(stroke
				(width 0.1)
				(type default)
			)
			(layer "B.Fab")
		)
		(fp_line
			(start 0.67945 0.3048)
			(end 0.67945 -0.305054)
			(stroke
				(width 0.1)
				(type default)
			)
			(layer "B.Fab")
		)
		(fp_line
			(start 0.12065 0.3048)
			(end 0.67945 0.3048)
			(stroke
				(width 0.1)
				(type default)
			)
			(layer "B.Fab")
		)
		(fp_line
			(start -0.120396 0.3048)
			(end -0.120396 0.2794)
			(stroke
				(width 0.1)
				(type default)
			)
			(layer "B.Fab")
		)
		(fp_line
			(start -0.67945 0.3048)
			(end -0.120396 0.3048)
			(stroke
				(width 0.1)
				(type default)
			)
			(layer "B.Fab")
		)
		(pad "1" smd circle
			(at 0.40005 0 270)
			(size 0 0)
			(layers "B.Cu" "B.Mask" "B.Paste")
			(net "GND")
		)
		(pad "2" smd circle
			(at -0.40005 0 270)
			(size 0 0)
			(layers "B.Cu" "B.Mask" "B.Paste")
			(net "OCP_SFF_MAIN_PWR_EN")
		)
	)
	(footprint ""
		(layer "B.Cu")
		(at 48.555148 -194.885564 180)
		(property "Reference" "R770"
			(at 0 0 0)
			(layer "B.SilkS")
			(hide yes)
			(effects
				(font
					(size 1.27 1.27)
				)
				(justify mirror)
			)
		)
		(property "Value" ""
			(at 0 0 0)
			(layer "B.Fab")
			(effects
				(font
					(size 1.27 1.27)
				)
				(justify mirror)
			)
		)
		(duplicate_pad_numbers_are_jumpers no)
		(fp_line
			(start 0.7874 0.4064)
			(end 0.7874 -0.4064)
			(stroke
				(width 0.1524)
				(type default)
			)
			(layer "B.SilkS")
		)
		(fp_line
			(start 0.7874 -0.4064)
			(end -0.7874 -0.4064)
			(stroke
				(width 0.1524)
				(type default)
			)
			(layer "B.SilkS")
		)
		(fp_line
			(start -0.7874 0.4064)
			(end 0.7874 0.4064)
			(stroke
				(width 0.1524)
				(type default)
			)
			(layer "B.SilkS")
		)
		(fp_line
			(start -0.7874 -0.4064)
			(end -0.7874 0.4064)
			(stroke
				(width 0.1524)
				(type default)
			)
			(layer "B.SilkS")
		)
		(fp_line
			(start 0.67945 0.3048)
			(end 0.67945 -0.305054)
			(stroke
				(width 0.1)
				(type default)
			)
			(layer "B.Fab")
		)
		(fp_line
			(start 0.67945 -0.305054)
			(end 0.12065 -0.305054)
			(stroke
				(width 0.1)
				(type default)
			)
			(layer "B.Fab")
		)
		(fp_line
			(start 0.12065 0.3048)
			(end 0.67945 0.3048)
			(stroke
				(width 0.1)
				(type default)
			)
			(layer "B.Fab")
		)
		(fp_line
			(start 0.12065 0.2794)
			(end 0.12065 0.3048)
			(stroke
				(width 0.1)
				(type default)
			)
			(layer "B.Fab")
		)
		(fp_line
			(start 0.12065 -0.2794)
			(end -0.12065 -0.2794)
			(stroke
				(width 0.1)
				(type default)
			)
			(layer "B.Fab")
		)
		(fp_line
			(start 0.12065 -0.305054)
			(end 0.12065 -0.2794)
			(stroke
				(width 0.1)
				(type default)
			)
			(layer "B.Fab")
		)
		(fp_line
			(start -0.120396 0.3048)
			(end -0.120396 0.2794)
			(stroke
				(width 0.1)
				(type default)
			)
			(layer "B.Fab")
		)
		(fp_line
			(start -0.120396 0.2794)
			(end 0.12065 0.2794)
			(stroke
				(width 0.1)
				(type default)
			)
			(layer "B.Fab")
		)
		(fp_line
			(start -0.12065 -0.2794)
			(end -0.12065 -0.3048)
			(stroke
				(width 0.1)
				(type default)
			)
			(layer "B.Fab")
		)
		(fp_line
			(start -0.12065 -0.3048)
			(end -0.67945 -0.3048)
			(stroke
				(width 0.1)
				(type default)
			)
			(layer "B.Fab")
		)
		(fp_line
			(start -0.67945 0.3048)
			(end -0.120396 0.3048)
			(stroke
				(width 0.1)
				(type default)
			)
			(layer "B.Fab")
		)
		(fp_line
			(start -0.67945 -0.3048)
			(end -0.67945 0.3048)
			(stroke
				(width 0.1)
				(type default)
			)
			(layer "B.Fab")
		)
		(pad "1" smd circle
			(at 0.40005 0)
			(size 0 0)
			(layers "B.Cu" "B.Mask" "B.Paste")
			(net "PD_CHB_CPU1_DIMM_SAA")
		)
		(pad "2" smd circle
			(at -0.40005 0)
			(size 0 0)
			(layers "B.Cu" "B.Mask" "B.Paste")
			(net "GND")
		)
	)
	(footprint ""
		(layer "B.Cu")
		(at 384.89128 -398.942052 90)
		(property "Reference" "C1023"
			(at 0 0 90)
			(layer "B.SilkS")
			(hide yes)
			(effects
				(font
					(size 1.27 1.27)
				)
				(justify mirror)
			)
		)
		(property "Value" ""
			(at 0 0 90)
			(layer "B.Fab")
			(effects
				(font
					(size 1.27 1.27)
				)
				(justify mirror)
			)
		)
		(duplicate_pad_numbers_are_jumpers no)
		(fp_line
			(start 0.7874 -0.4064)
			(end -0.7874 -0.4064)
			(stroke
				(width 0.1524)
				(type default)
			)
			(layer "B.SilkS")
		)
		(fp_line
			(start -0.7874 -0.4064)
			(end -0.7874 0.4064)
			(stroke
				(width 0.1524)
				(type default)
			)
			(layer "B.SilkS")
		)
		(fp_line
			(start 0.7874 0.4064)
			(end 0.7874 -0.4064)
			(stroke
				(width 0.1524)
				(type default)
			)
			(layer "B.SilkS")
		)
		(fp_line
			(start -0.7874 0.4064)
			(end 0.7874 0.4064)
			(stroke
				(width 0.1524)
				(type default)
			)
			(layer "B.SilkS")
		)
		(fp_line
			(start 0.67945 -0.305054)
			(end 0.12065 -0.305054)
			(stroke
				(width 0.1)
				(type default)
			)
			(layer "B.Fab")
		)
		(fp_line
			(start 0.12065 -0.305054)
			(end 0.12065 -0.2794)
			(stroke
				(width 0.1)
				(type default)
			)
			(layer "B.Fab")
		)
		(fp_line
			(start -0.12065 -0.3048)
			(end -0.67945 -0.3048)
			(stroke
				(width 0.1)
				(type default)
			)
			(layer "B.Fab")
		)
		(fp_line
			(start -0.67945 -0.3048)
			(end -0.67945 0.3048)
			(stroke
				(width 0.1)
				(type default)
			)
			(layer "B.Fab")
		)
		(fp_line
			(start 0.12065 -0.2794)
			(end -0.12065 -0.2794)
			(stroke
				(width 0.1)
				(type default)
			)
			(layer "B.Fab")
		)
		(fp_line
			(start -0.12065 -0.2794)
			(end -0.12065 -0.3048)
			(stroke
				(width 0.1)
				(type default)
			)
			(layer "B.Fab")
		)
		(fp_line
			(start 0.12065 0.2794)
			(end 0.12065 0.3048)
			(stroke
				(width 0.1)
				(type default)
			)
			(layer "B.Fab")
		)
		(fp_line
			(start -0.120396 0.2794)
			(end 0.12065 0.2794)
			(stroke
				(width 0.1)
				(type default)
			)
			(layer "B.Fab")
		)
		(fp_line
			(start 0.67945 0.3048)
			(end 0.67945 -0.305054)
			(stroke
				(width 0.1)
				(type default)
			)
			(layer "B.Fab")
		)
		(fp_line
			(start 0.12065 0.3048)
			(end 0.67945 0.3048)
			(stroke
				(width 0.1)
				(type default)
			)
			(layer "B.Fab")
		)
		(fp_line
			(start -0.120396 0.3048)
			(end -0.120396 0.2794)
			(stroke
				(width 0.1)
				(type default)
			)
			(layer "B.Fab")
		)
		(fp_line
			(start -0.67945 0.3048)
			(end -0.120396 0.3048)
			(stroke
				(width 0.1)
				(type default)
			)
			(layer "B.Fab")
		)
		(pad "1" smd circle
			(at 0.40005 0 270)
			(size 0 0)
			(layers "B.Cu" "B.Mask" "B.Paste")
			(net "P0V9_CPU0_RT3_2A")
		)
		(pad "2" smd circle
			(at -0.40005 0 270)
			(size 0 0)
			(layers "B.Cu" "B.Mask" "B.Paste")
			(net "GND")
		)
	)
	(footprint ""
		(layer "B.Cu")
		(at 113.705386 -251.781564)
		(property "Reference" "C2281"
			(at 0 0 0)
			(layer "B.SilkS")
			(hide yes)
			(effects
				(font
					(size 1.27 1.27)
				)
				(justify mirror)
			)
		)
		(property "Value" ""
			(at 0 0 0)
			(layer "B.Fab")
			(effects
				(font
					(size 1.27 1.27)
				)
				(justify mirror)
			)
		)
		(duplicate_pad_numbers_are_jumpers no)
		(fp_line
			(start -0.7874 -0.4064)
			(end -0.7874 0.4064)
			(stroke
				(width 0.1524)
				(type default)
			)
			(layer "B.SilkS")
		)
		(fp_line
			(start -0.7874 0.4064)
			(end 0.7874 0.4064)
			(stroke
				(width 0.1524)
				(type default)
			)
			(layer "B.SilkS")
		)
		(fp_line
			(start 0.7874 -0.4064)
			(end -0.7874 -0.4064)
			(stroke
				(width 0.1524)
				(type default)
			)
			(layer "B.SilkS")
		)
		(fp_line
			(start 0.7874 0.4064)
			(end 0.7874 -0.4064)
			(stroke
				(width 0.1524)
				(type default)
			)
			(layer "B.SilkS")
		)
		(fp_line
			(start -0.67945 -0.3048)
			(end -0.67945 0.3048)
			(stroke
				(width 0.1)
				(type default)
			)
			(layer "B.Fab")
		)
		(fp_line
			(start -0.67945 0.3048)
			(end -0.120396 0.3048)
			(stroke
				(width 0.1)
				(type default)
			)
			(layer "B.Fab")
		)
		(fp_line
			(start -0.12065 -0.3048)
			(end -0.67945 -0.3048)
			(stroke
				(width 0.1)
				(type default)
			)
			(layer "B.Fab")
		)
		(fp_line
			(start -0.12065 -0.2794)
			(end -0.12065 -0.3048)
			(stroke
				(width 0.1)
				(type default)
			)
			(layer "B.Fab")
		)
		(fp_line
			(start -0.120396 0.2794)
			(end 0.12065 0.2794)
			(stroke
				(width 0.1)
				(type default)
			)
			(layer "B.Fab")
		)
		(fp_line
			(start -0.120396 0.3048)
			(end -0.120396 0.2794)
			(stroke
				(width 0.1)
				(type default)
			)
			(layer "B.Fab")
		)
		(fp_line
			(start 0.12065 -0.305054)
			(end 0.12065 -0.2794)
			(stroke
				(width 0.1)
				(type default)
			)
			(layer "B.Fab")
		)
		(fp_line
			(start 0.12065 -0.2794)
			(end -0.12065 -0.2794)
			(stroke
				(width 0.1)
				(type default)
			)
			(layer "B.Fab")
		)
		(fp_line
			(start 0.12065 0.2794)
			(end 0.12065 0.3048)
			(stroke
				(width 0.1)
				(type default)
			)
			(layer "B.Fab")
		)
		(fp_line
			(start 0.12065 0.3048)
			(end 0.67945 0.3048)
			(stroke
				(width 0.1)
				(type default)
			)
			(layer "B.Fab")
		)
		(fp_line
			(start 0.67945 -0.305054)
			(end 0.12065 -0.305054)
			(stroke
				(width 0.1)
				(type default)
			)
			(layer "B.Fab")
		)
		(fp_line
			(start 0.67945 0.3048)
			(end 0.67945 -0.305054)
			(stroke
				(width 0.1)
				(type default)
			)
			(layer "B.Fab")
		)
		(pad "1" smd circle
			(at 0.40005 0 180)
			(size 0 0)
			(layers "B.Cu" "B.Mask" "B.Paste")
			(net "PVDDCR_SOC_P1")
		)
		(pad "2" smd circle
			(at -0.40005 0 180)
			(size 0 0)
			(layers "B.Cu" "B.Mask" "B.Paste")
			(net "GND")
		)
	)
	(footprint ""
		(layer "B.Cu")
		(at 332.316836 -76.35875 180)
		(property "Reference" "Q83"
			(at -2.243328 2.223008 0)
			(unlocked yes)
			(layer "B.SilkS")
			(effects
				(font
					(size 0.7874 0.5842)
					(thickness 0.1524)
				)
				(justify left mirror)
			)
		)
		(property "Value" ""
			(at 0 0 0)
			(layer "B.Fab")
			(effects
				(font
					(size 1.27 1.27)
				)
				(justify mirror)
			)
		)
		(duplicate_pad_numbers_are_jumpers no)
		(fp_line
			(start 1.332738 1.100074)
			(end 1.332738 -1.100074)
			(stroke
				(width 0.1524)
				(type default)
			)
			(layer "B.SilkS")
		)
		(fp_line
			(start 1.332738 -1.100074)
			(end 0.4826 -1.100074)
			(stroke
				(width 0.1524)
				(type default)
			)
			(layer "B.SilkS")
		)
		(fp_line
			(start 0.4826 -1.100074)
			(end 0 -0.541274)
			(stroke
				(width 0.1524)
				(type default)
			)
			(layer "B.SilkS")
		)
		(fp_line
			(start 0 -0.541274)
			(end -0.4826 -1.100074)
			(stroke
				(width 0.1524)
				(type default)
			)
			(layer "B.SilkS")
		)
		(fp_line
			(start -0.4826 -1.100074)
			(end -1.332738 -1.100074)
			(stroke
				(width 0.1524)
				(type default)
			)
			(layer "B.SilkS")
		)
		(fp_line
			(start -1.332738 1.100074)
			(end 1.332738 1.100074)
			(stroke
				(width 0.1524)
				(type default)
			)
			(layer "B.SilkS")
		)
		(fp_line
			(start -1.332738 -1.100074)
			(end -1.332738 1.100074)
			(stroke
				(width 0.1524)
				(type default)
			)
			(layer "B.SilkS")
		)
		(fp_poly
			(pts
				(xy 1.864106 -0.627888) (xy 2.566162 -0.978916) (xy 2.566162 -0.27686)
			)
			(stroke
				(width 0)
				(type default)
			)
			(fill yes)
			(layer "B.SilkS")
		)
		(fp_line
			(start 0.674878 1.100074)
			(end 0.674878 -1.100074)
			(stroke
				(width 0.1)
				(type default)
			)
			(layer "B.Fab")
		)
		(fp_line
			(start 0.674878 -1.100074)
			(end -0.674878 -1.100074)
			(stroke
				(width 0.1)
				(type default)
			)
			(layer "B.Fab")
		)
		(fp_line
			(start -0.674878 1.100074)
			(end 0.674878 1.100074)
			(stroke
				(width 0.1)
				(type default)
			)
			(layer "B.Fab")
		)
		(fp_line
			(start -0.674878 -1.100074)
			(end -0.674878 1.100074)
			(stroke
				(width 0.1)
				(type default)
			)
			(layer "B.Fab")
		)
		(fp_poly
			(pts
				(xy 2.2352 -0.298958) (xy 2.2352 -1.001014) (xy 1.533144 -0.649986)
			)
			(stroke
				(width 0)
				(type default)
			)
			(fill yes)
			(layer "B.Fab")
		)
		(pad "1" smd rect
			(at 0.94996 -0.649986 270)
			(size 0.4318 0.508)
			(layers "B.Cu" "B.Mask" "B.Paste")
			(net "GND")
		)
		(pad "2" smd rect
			(at 0.94996 0 270)
			(size 0.4318 0.508)
			(layers "B.Cu" "B.Mask" "B.Paste")
			(net "FM_LED_PWRGD_PVDD18_S5_P0")
		)
		(pad "3" smd rect
			(at 0.94996 0.649986 270)
			(size 0.4318 0.508)
			(layers "B.Cu" "B.Mask" "B.Paste")
			(net "NC_Q83_D2")
		)
		(pad "4" smd rect
			(at -0.94996 0.649986 270)
			(size 0.4318 0.508)
			(layers "B.Cu" "B.Mask" "B.Paste")
			(net "NC_Q83_S2")
		)
		(pad "5" smd rect
			(at -0.94996 0 270)
			(size 0.4318 0.508)
			(layers "B.Cu" "B.Mask" "B.Paste")
			(net "NC_Q83_G2")
		)
		(pad "6" smd rect
			(at -0.94996 -0.649986 270)
			(size 0.4318 0.508)
			(layers "B.Cu" "B.Mask" "B.Paste")
			(net "LED_PWRGD_PVDD18_S5_P0_D")
		)
	)
	(footprint ""
		(layer "B.Cu")
		(at 24.404574 -373.339614 90)
		(property "Reference" "PC6814"
			(at -3.896614 2.873756 270)
			(unlocked yes)
			(layer "B.SilkS")
			(effects
				(font
					(size 0.7874 0.5842)
					(thickness 0.1524)
				)
				(justify left mirror)
			)
		)
		(property "Value" ""
			(at 0 0 90)
			(layer "B.Fab")
			(effects
				(font
					(size 1.27 1.27)
				)
				(justify mirror)
			)
		)
		(duplicate_pad_numbers_are_jumpers no)
		(fp_line
			(start 4.84378 -2.150618)
			(end 4.53898 -2.150618)
			(stroke
				(width 0.1524)
				(type default)
			)
			(layer "B.SilkS")
		)
		(fp_line
			(start 4.84378 -2.150618)
			(end 4.842256 2.163064)
			(stroke
				(width 0.1524)
				(type default)
			)
			(layer "B.SilkS")
		)
		(fp_line
			(start 4.69138 -2.150618)
			(end 4.692396 2.161032)
			(stroke
				(width 0.1524)
				(type default)
			)
			(layer "B.SilkS")
		)
		(fp_line
			(start 4.53898 -2.150618)
			(end 4.539742 2.152142)
			(stroke
				(width 0.1524)
				(type default)
			)
			(layer "B.SilkS")
		)
		(fp_line
			(start 4.53898 -2.15011)
			(end -3.871214 -2.15011)
			(stroke
				(width 0.1524)
				(type default)
			)
			(layer "B.SilkS")
		)
		(fp_line
			(start -4.53898 -1.849374)
			(end -4.53898 2.15011)
			(stroke
				(width 0.1524)
				(type default)
			)
			(layer "B.SilkS")
		)
		(fp_line
			(start 4.53898 2.15011)
			(end 4.53898 -2.15011)
			(stroke
				(width 0.1524)
				(type default)
			)
			(layer "B.SilkS")
		)
		(fp_line
			(start -4.53898 2.15011)
			(end 4.53898 2.15011)
			(stroke
				(width 0.1524)
				(type default)
			)
			(layer "B.SilkS")
		)
		(fp_line
			(start 4.83108 2.150364)
			(end 4.447794 2.149348)
			(stroke
				(width 0.1524)
				(type default)
			)
			(layer "B.SilkS")
		)
		(fp_line
			(start 3.64998 -2.15011)
			(end -3.64998 -2.15011)
			(stroke
				(width 0.1)
				(type default)
			)
			(layer "B.Fab")
		)
		(fp_line
			(start -3.64998 -2.15011)
			(end -3.64998 2.15011)
			(stroke
				(width 0.1)
				(type default)
			)
			(layer "B.Fab")
		)
		(fp_line
			(start 3.64998 2.15011)
			(end 3.64998 -2.15011)
			(stroke
				(width 0.1)
				(type default)
			)
			(layer "B.Fab")
		)
		(fp_line
			(start -3.64998 2.15011)
			(end 3.64998 2.15011)
			(stroke
				(width 0.1)
				(type default)
			)
			(layer "B.Fab")
		)
		(fp_text user "-"
			(at -4.313174 -0.094488 90)
			(unlocked yes)
			(layer "B.SilkS")
			(effects
				(font
					(size 1.905 1.4224)
					(thickness 0.1524)
				)
				(justify left mirror)
			)
		)
		(fp_text user "+"
			(at 6.839712 1.525778 90)
			(unlocked yes)
			(layer "B.SilkS")
			(effects
				(font
					(size 1.905 1.4224)
					(thickness 0.1524)
				)
				(justify left mirror)
			)
		)
		(fp_text user "+"
			(at 6.214872 -0.337058 90)
			(unlocked yes)
			(layer "B.Fab")
			(effects
				(font
					(size 1.905 1.4224)
					(thickness 0.1524)
				)
				(justify left mirror)
			)
		)
		(fp_text user "-"
			(at -4.313174 -0.094488 90)
			(unlocked yes)
			(layer "B.Fab")
			(effects
				(font
					(size 1.905 1.4224)
					(thickness 0.1524)
				)
				(justify left mirror)
			)
		)
		(pad "1" smd rect
			(at 3.199892 0 270)
			(size 2.413 2.8194)
			(layers "B.Cu" "B.Mask" "B.Paste")
			(net "P0V9_CPU1_RT_2D")
		)
		(pad "2" smd rect
			(at -3.199892 0 270)
			(size 2.413 2.8194)
			(layers "B.Cu" "B.Mask" "B.Paste")
			(net "GND")
		)
	)
	(footprint ""
		(layer "B.Cu")
		(at 145.197068 -381.50419)
		(property "Reference" "C7028"
			(at 0 0 0)
			(layer "B.SilkS")
			(hide yes)
			(effects
				(font
					(size 1.27 1.27)
				)
				(justify mirror)
			)
		)
		(property "Value" ""
			(at 0 0 0)
			(layer "B.Fab")
			(effects
				(font
					(size 1.27 1.27)
				)
				(justify mirror)
			)
		)
		(duplicate_pad_numbers_are_jumpers no)
		(fp_line
			(start -1.524 -0.762)
			(end -1.524 0.762)
			(stroke
				(width 0.1524)
				(type default)
			)
			(layer "B.SilkS")
		)
		(fp_line
			(start -1.524 0.762)
			(end 1.524 0.762)
			(stroke
				(width 0.1524)
				(type default)
			)
			(layer "B.SilkS")
		)
		(fp_line
			(start 1.524 -0.762)
			(end -1.524 -0.762)
			(stroke
				(width 0.1524)
				(type default)
			)
			(layer "B.SilkS")
		)
		(fp_line
			(start 1.524 0.762)
			(end 1.524 -0.762)
			(stroke
				(width 0.1524)
				(type default)
			)
			(layer "B.SilkS")
		)
		(fp_line
			(start -1.1049 -0.724916)
			(end 1.1049 -0.724916)
			(stroke
				(width 0.1)
				(type default)
			)
			(layer "B.Fab")
		)
		(fp_line
			(start -1.1049 0.724916)
			(end -1.1049 -0.724916)
			(stroke
				(width 0.1)
				(type default)
			)
			(layer "B.Fab")
		)
		(fp_line
			(start 1.1049 -0.724916)
			(end 1.1049 0.724916)
			(stroke
				(width 0.1)
				(type default)
			)
			(layer "B.Fab")
		)
		(fp_line
			(start 1.1049 0.724916)
			(end -1.1049 0.724916)
			(stroke
				(width 0.1)
				(type default)
			)
			(layer "B.Fab")
		)
		(pad "1" smd rect
			(at 0.889 0)
			(size 1.016 1.27)
			(layers "B.Cu" "B.Mask" "B.Paste")
			(net "P0V9_CPU1_RT2_2A")
		)
		(pad "2" smd rect
			(at -0.889 0)
			(size 1.016 1.27)
			(layers "B.Cu" "B.Mask" "B.Paste")
			(net "GND")
		)
	)
	(footprint ""
		(layer "B.Cu")
		(at 371.551454 -259.729986)
		(property "Reference" "C2542"
			(at 0 0 0)
			(layer "B.SilkS")
			(hide yes)
			(effects
				(font
					(size 1.27 1.27)
				)
				(justify mirror)
			)
		)
		(property "Value" ""
			(at 0 0 0)
			(layer "B.Fab")
			(effects
				(font
					(size 1.27 1.27)
				)
				(justify mirror)
			)
		)
		(duplicate_pad_numbers_are_jumpers no)
		(fp_line
			(start -0.7874 -0.4064)
			(end -0.7874 0.4064)
			(stroke
				(width 0.1524)
				(type default)
			)
			(layer "B.SilkS")
		)
		(fp_line
			(start -0.7874 0.4064)
			(end 0.7874 0.4064)
			(stroke
				(width 0.1524)
				(type default)
			)
			(layer "B.SilkS")
		)
		(fp_line
			(start 0.7874 -0.4064)
			(end -0.7874 -0.4064)
			(stroke
				(width 0.1524)
				(type default)
			)
			(layer "B.SilkS")
		)
		(fp_line
			(start 0.7874 0.4064)
			(end 0.7874 -0.4064)
			(stroke
				(width 0.1524)
				(type default)
			)
			(layer "B.SilkS")
		)
		(fp_line
			(start -0.67945 -0.3048)
			(end -0.67945 0.3048)
			(stroke
				(width 0.1)
				(type default)
			)
			(layer "B.Fab")
		)
		(fp_line
			(start -0.67945 0.3048)
			(end -0.120396 0.3048)
			(stroke
				(width 0.1)
				(type default)
			)
			(layer "B.Fab")
		)
		(fp_line
			(start -0.12065 -0.3048)
			(end -0.67945 -0.3048)
			(stroke
				(width 0.1)
				(type default)
			)
			(layer "B.Fab")
		)
		(fp_line
			(start -0.12065 -0.2794)
			(end -0.12065 -0.3048)
			(stroke
				(width 0.1)
				(type default)
			)
			(layer "B.Fab")
		)
		(fp_line
			(start -0.120396 0.2794)
			(end 0.12065 0.2794)
			(stroke
				(width 0.1)
				(type default)
			)
			(layer "B.Fab")
		)
		(fp_line
			(start -0.120396 0.3048)
			(end -0.120396 0.2794)
			(stroke
				(width 0.1)
				(type default)
			)
			(layer "B.Fab")
		)
		(fp_line
			(start 0.12065 -0.305054)
			(end 0.12065 -0.2794)
			(stroke
				(width 0.1)
				(type default)
			)
			(layer "B.Fab")
		)
		(fp_line
			(start 0.12065 -0.2794)
			(end -0.12065 -0.2794)
			(stroke
				(width 0.1)
				(type default)
			)
			(layer "B.Fab")
		)
		(fp_line
			(start 0.12065 0.2794)
			(end 0.12065 0.3048)
			(stroke
				(width 0.1)
				(type default)
			)
			(layer "B.Fab")
		)
		(fp_line
			(start 0.12065 0.3048)
			(end 0.67945 0.3048)
			(stroke
				(width 0.1)
				(type default)
			)
			(layer "B.Fab")
		)
		(fp_line
			(start 0.67945 -0.305054)
			(end 0.12065 -0.305054)
			(stroke
				(width 0.1)
				(type default)
			)
			(layer "B.Fab")
		)
		(fp_line
			(start 0.67945 0.3048)
			(end 0.67945 -0.305054)
			(stroke
				(width 0.1)
				(type default)
			)
			(layer "B.Fab")
		)
		(pad "1" smd circle
			(at 0.40005 0 180)
			(size 0 0)
			(layers "B.Cu" "B.Mask" "B.Paste")
			(net "PVDDCR_SOC_P0")
		)
		(pad "2" smd circle
			(at -0.40005 0 180)
			(size 0 0)
			(layers "B.Cu" "B.Mask" "B.Paste")
			(net "GND")
		)
	)
	(footprint ""
		(layer "B.Cu")
		(at 123.611386 -250.892564)
		(property "Reference" "C2312"
			(at 0 0 0)
			(layer "B.SilkS")
			(hide yes)
			(effects
				(font
					(size 1.27 1.27)
				)
				(justify mirror)
			)
		)
		(property "Value" ""
			(at 0 0 0)
			(layer "B.Fab")
			(effects
				(font
					(size 1.27 1.27)
				)
				(justify mirror)
			)
		)
		(duplicate_pad_numbers_are_jumpers no)
		(fp_line
			(start -0.7874 -0.4064)
			(end -0.7874 0.4064)
			(stroke
				(width 0.1524)
				(type default)
			)
			(layer "B.SilkS")
		)
		(fp_line
			(start -0.7874 0.4064)
			(end 0.7874 0.4064)
			(stroke
				(width 0.1524)
				(type default)
			)
			(layer "B.SilkS")
		)
		(fp_line
			(start 0.7874 -0.4064)
			(end -0.7874 -0.4064)
			(stroke
				(width 0.1524)
				(type default)
			)
			(layer "B.SilkS")
		)
		(fp_line
			(start 0.7874 0.4064)
			(end 0.7874 -0.4064)
			(stroke
				(width 0.1524)
				(type default)
			)
			(layer "B.SilkS")
		)
		(fp_line
			(start -0.67945 -0.3048)
			(end -0.67945 0.3048)
			(stroke
				(width 0.1)
				(type default)
			)
			(layer "B.Fab")
		)
		(fp_line
			(start -0.67945 0.3048)
			(end -0.120396 0.3048)
			(stroke
				(width 0.1)
				(type default)
			)
			(layer "B.Fab")
		)
		(fp_line
			(start -0.12065 -0.3048)
			(end -0.67945 -0.3048)
			(stroke
				(width 0.1)
				(type default)
			)
			(layer "B.Fab")
		)
		(fp_line
			(start -0.12065 -0.2794)
			(end -0.12065 -0.3048)
			(stroke
				(width 0.1)
				(type default)
			)
			(layer "B.Fab")
		)
		(fp_line
			(start -0.120396 0.2794)
			(end 0.12065 0.2794)
			(stroke
				(width 0.1)
				(type default)
			)
			(layer "B.Fab")
		)
		(fp_line
			(start -0.120396 0.3048)
			(end -0.120396 0.2794)
			(stroke
				(width 0.1)
				(type default)
			)
			(layer "B.Fab")
		)
		(fp_line
			(start 0.12065 -0.305054)
			(end 0.12065 -0.2794)
			(stroke
				(width 0.1)
				(type default)
			)
			(layer "B.Fab")
		)
		(fp_line
			(start 0.12065 -0.2794)
			(end -0.12065 -0.2794)
			(stroke
				(width 0.1)
				(type default)
			)
			(layer "B.Fab")
		)
		(fp_line
			(start 0.12065 0.2794)
			(end 0.12065 0.3048)
			(stroke
				(width 0.1)
				(type default)
			)
			(layer "B.Fab")
		)
		(fp_line
			(start 0.12065 0.3048)
			(end 0.67945 0.3048)
			(stroke
				(width 0.1)
				(type default)
			)
			(layer "B.Fab")
		)
		(fp_line
			(start 0.67945 -0.305054)
			(end 0.12065 -0.305054)
			(stroke
				(width 0.1)
				(type default)
			)
			(layer "B.Fab")
		)
		(fp_line
			(start 0.67945 0.3048)
			(end 0.67945 -0.305054)
			(stroke
				(width 0.1)
				(type default)
			)
			(layer "B.Fab")
		)
		(pad "1" smd circle
			(at 0.40005 0 180)
			(size 0 0)
			(layers "B.Cu" "B.Mask" "B.Paste")
			(net "PVDDCR_CPU0_P1")
		)
		(pad "2" smd circle
			(at -0.40005 0 180)
			(size 0 0)
			(layers "B.Cu" "B.Mask" "B.Paste")
			(net "GND")
		)
	)
	(footprint ""
		(layer "B.Cu")
		(at 72.462644 -389.673084 90)
		(property "Reference" "C323"
			(at 0 0 90)
			(layer "B.SilkS")
			(hide yes)
			(effects
				(font
					(size 1.27 1.27)
				)
				(justify mirror)
			)
		)
		(property "Value" ""
			(at 0 0 90)
			(layer "B.Fab")
			(effects
				(font
					(size 1.27 1.27)
				)
				(justify mirror)
			)
		)
		(duplicate_pad_numbers_are_jumpers no)
		(fp_line
			(start 1.524 -0.762)
			(end -1.524 -0.762)
			(stroke
				(width 0.1524)
				(type default)
			)
			(layer "B.SilkS")
		)
		(fp_line
			(start -1.524 -0.762)
			(end -1.524 0.762)
			(stroke
				(width 0.1524)
				(type default)
			)
			(layer "B.SilkS")
		)
		(fp_line
			(start 1.524 0.762)
			(end 1.524 -0.762)
			(stroke
				(width 0.1524)
				(type default)
			)
			(layer "B.SilkS")
		)
		(fp_line
			(start -1.524 0.762)
			(end 1.524 0.762)
			(stroke
				(width 0.1524)
				(type default)
			)
			(layer "B.SilkS")
		)
		(fp_line
			(start 1.1049 -0.724916)
			(end 1.1049 0.724916)
			(stroke
				(width 0.1)
				(type default)
			)
			(layer "B.Fab")
		)
		(fp_line
			(start -1.1049 -0.724916)
			(end 1.1049 -0.724916)
			(stroke
				(width 0.1)
				(type default)
			)
			(layer "B.Fab")
		)
		(fp_line
			(start 1.1049 0.724916)
			(end -1.1049 0.724916)
			(stroke
				(width 0.1)
				(type default)
			)
			(layer "B.Fab")
		)
		(fp_line
			(start -1.1049 0.724916)
			(end -1.1049 -0.724916)
			(stroke
				(width 0.1)
				(type default)
			)
			(layer "B.Fab")
		)
		(pad "1" smd rect
			(at 0.889 0 90)
			(size 1.016 1.27)
			(layers "B.Cu" "B.Mask" "B.Paste")
			(net "P0V9_CPU1_RT_2D")
		)
		(pad "2" smd rect
			(at -0.889 0 90)
			(size 1.016 1.27)
			(layers "B.Cu" "B.Mask" "B.Paste")
			(net "GND")
		)
	)
	(footprint ""
		(layer "B.Cu")
		(at 110.365794 -385.58216 180)
		(property "Reference" "R919"
			(at 0 0 0)
			(layer "B.SilkS")
			(hide yes)
			(effects
				(font
					(size 1.27 1.27)
				)
				(justify mirror)
			)
		)
		(property "Value" ""
			(at 0 0 0)
			(layer "B.Fab")
			(effects
				(font
					(size 1.27 1.27)
				)
				(justify mirror)
			)
		)
		(duplicate_pad_numbers_are_jumpers no)
		(fp_line
			(start 0.32512 0.175006)
			(end 0.32512 -0.175006)
			(stroke
				(width 0.1)
				(type default)
			)
			(layer "B.Fab")
		)
		(fp_line
			(start 0.32512 -0.175006)
			(end -0.32512 -0.175006)
			(stroke
				(width 0.1)
				(type default)
			)
			(layer "B.Fab")
		)
		(fp_line
			(start -0.32512 0.175006)
			(end 0.32512 0.175006)
			(stroke
				(width 0.1)
				(type default)
			)
			(layer "B.Fab")
		)
		(fp_line
			(start -0.32512 -0.175006)
			(end -0.32512 0.175006)
			(stroke
				(width 0.1)
				(type default)
			)
			(layer "B.Fab")
		)
		(pad "1" smd rect
			(at 0.2667 0)
			(size 0.3048 0.381)
			(layers "B.Cu" "B.Mask" "B.Paste")
			(net "TEST0_RT_CPU1_P3")
		)
		(pad "2" smd rect
			(at -0.2667 0 180)
			(size 0.3048 0.381)
			(layers "B.Cu" "B.Mask" "B.Paste")
			(net "GND")
		)
	)
	(footprint ""
		(layer "B.Cu")
		(at 231.648 -336.169 -90)
		(property "Reference" "R6767"
			(at 0 0 90)
			(layer "B.SilkS")
			(hide yes)
			(effects
				(font
					(size 1.27 1.27)
				)
				(justify mirror)
			)
		)
		(property "Value" ""
			(at 0 0 90)
			(layer "B.Fab")
			(effects
				(font
					(size 1.27 1.27)
				)
				(justify mirror)
			)
		)
		(duplicate_pad_numbers_are_jumpers no)
		(fp_line
			(start -0.32512 0.175006)
			(end 0.32512 0.175006)
			(stroke
				(width 0.1)
				(type default)
			)
			(layer "B.Fab")
		)
		(fp_line
			(start 0.32512 0.175006)
			(end 0.32512 -0.175006)
			(stroke
				(width 0.1)
				(type default)
			)
			(layer "B.Fab")
		)
		(fp_line
			(start -0.32512 -0.175006)
			(end -0.32512 0.175006)
			(stroke
				(width 0.1)
				(type default)
			)
			(layer "B.Fab")
		)
		(fp_line
			(start 0.32512 -0.175006)
			(end -0.32512 -0.175006)
			(stroke
				(width 0.1)
				(type default)
			)
			(layer "B.Fab")
		)
		(pad "1" smd rect
			(at 0.2667 0 90)
			(size 0.3048 0.381)
			(layers "B.Cu" "B.Mask" "B.Paste")
			(net "P1V8_CPU0_RT_1D")
		)
		(pad "2" smd rect
			(at -0.2667 0 270)
			(size 0.3048 0.381)
			(layers "B.Cu" "B.Mask" "B.Paste")
			(net "SMB_RT_CPU0_P3_R_SCL")
		)
	)
	(footprint ""
		(layer "B.Cu")
		(at 181.57063 -133.838696 -90)
		(property "Reference" "R1285"
			(at 0 0 90)
			(layer "B.SilkS")
			(hide yes)
			(effects
				(font
					(size 1.27 1.27)
				)
				(justify mirror)
			)
		)
		(property "Value" ""
			(at 0 0 90)
			(layer "B.Fab")
			(effects
				(font
					(size 1.27 1.27)
				)
				(justify mirror)
			)
		)
		(duplicate_pad_numbers_are_jumpers no)
		(fp_line
			(start -0.7874 0.4064)
			(end 0.7874 0.4064)
			(stroke
				(width 0.1524)
				(type default)
			)
			(layer "B.SilkS")
		)
		(fp_line
			(start 0.7874 0.4064)
			(end 0.7874 -0.4064)
			(stroke
				(width 0.1524)
				(type default)
			)
			(layer "B.SilkS")
		)
		(fp_line
			(start -0.7874 -0.4064)
			(end -0.7874 0.4064)
			(stroke
				(width 0.1524)
				(type default)
			)
			(layer "B.SilkS")
		)
		(fp_line
			(start 0.7874 -0.4064)
			(end -0.7874 -0.4064)
			(stroke
				(width 0.1524)
				(type default)
			)
			(layer "B.SilkS")
		)
		(fp_line
			(start -0.67945 0.3048)
			(end -0.120396 0.3048)
			(stroke
				(width 0.1)
				(type default)
			)
			(layer "B.Fab")
		)
		(fp_line
			(start -0.120396 0.3048)
			(end -0.120396 0.2794)
			(stroke
				(width 0.1)
				(type default)
			)
			(layer "B.Fab")
		)
		(fp_line
			(start 0.12065 0.3048)
			(end 0.67945 0.3048)
			(stroke
				(width 0.1)
				(type default)
			)
			(layer "B.Fab")
		)
		(fp_line
			(start 0.67945 0.3048)
			(end 0.67945 -0.305054)
			(stroke
				(width 0.1)
				(type default)
			)
			(layer "B.Fab")
		)
		(fp_line
			(start -0.120396 0.2794)
			(end 0.12065 0.2794)
			(stroke
				(width 0.1)
				(type default)
			)
			(layer "B.Fab")
		)
		(fp_line
			(start 0.12065 0.2794)
			(end 0.12065 0.3048)
			(stroke
				(width 0.1)
				(type default)
			)
			(layer "B.Fab")
		)
		(fp_line
			(start -0.12065 -0.2794)
			(end -0.12065 -0.3048)
			(stroke
				(width 0.1)
				(type default)
			)
			(layer "B.Fab")
		)
		(fp_line
			(start 0.12065 -0.2794)
			(end -0.12065 -0.2794)
			(stroke
				(width 0.1)
				(type default)
			)
			(layer "B.Fab")
		)
		(fp_line
			(start -0.67945 -0.3048)
			(end -0.67945 0.3048)
			(stroke
				(width 0.1)
				(type default)
			)
			(layer "B.Fab")
		)
		(fp_line
			(start -0.12065 -0.3048)
			(end -0.67945 -0.3048)
			(stroke
				(width 0.1)
				(type default)
			)
			(layer "B.Fab")
		)
		(fp_line
			(start 0.12065 -0.305054)
			(end 0.12065 -0.2794)
			(stroke
				(width 0.1)
				(type default)
			)
			(layer "B.Fab")
		)
		(fp_line
			(start 0.67945 -0.305054)
			(end 0.12065 -0.305054)
			(stroke
				(width 0.1)
				(type default)
			)
			(layer "B.Fab")
		)
		(pad "1" smd circle
			(at 0.40005 0 90)
			(size 0 0)
			(layers "B.Cu" "B.Mask" "B.Paste")
			(net "FM_P1_PCC0_N")
		)
		(pad "2" smd circle
			(at -0.40005 0 90)
			(size 0 0)
			(layers "B.Cu" "B.Mask" "B.Paste")
			(net "PVDD18_S5_P1")
		)
	)
	(footprint ""
		(layer "B.Cu")
		(at 335.932526 -416.899344 90)
		(property "Reference" "C6554"
			(at 0 0 90)
			(layer "B.SilkS")
			(hide yes)
			(effects
				(font
					(size 1.27 1.27)
				)
				(justify mirror)
			)
		)
		(property "Value" ""
			(at 0 0 90)
			(layer "B.Fab")
			(effects
				(font
					(size 1.27 1.27)
				)
				(justify mirror)
			)
		)
		(duplicate_pad_numbers_are_jumpers no)
		(fp_line
			(start 0.299974 -0.150114)
			(end -0.299974 -0.150114)
			(stroke
				(width 0.1)
				(type default)
			)
			(layer "B.Fab")
		)
		(fp_line
			(start -0.299974 -0.150114)
			(end -0.299974 0.150114)
			(stroke
				(width 0.1)
				(type default)
			)
			(layer "B.Fab")
		)
		(fp_line
			(start 0.299974 0.150114)
			(end 0.299974 -0.150114)
			(stroke
				(width 0.1)
				(type default)
			)
			(layer "B.Fab")
		)
		(fp_line
			(start -0.299974 0.150114)
			(end 0.299974 0.150114)
			(stroke
				(width 0.1)
				(type default)
			)
			(layer "B.Fab")
		)
		(pad "1" smd rect
			(at 0.2667 0 270)
			(size 0.3048 0.381)
			(layers "B.Cu" "B.Mask" "B.Paste")
			(net "P5E_CPU0_P1_TX_BUF_C_DN<10>")
		)
		(pad "2" smd rect
			(at -0.2667 0 270)
			(size 0.3048 0.381)
			(layers "B.Cu" "B.Mask" "B.Paste")
			(net "P5E_CPU0_P1_TX_BUF_DN<10>")
		)
	)
	(footprint ""
		(layer "B.Cu")
		(at 296.222928 -337.980528 -90)
		(property "Reference" "PC166_1"
			(at 0 0 90)
			(layer "B.SilkS")
			(hide yes)
			(effects
				(font
					(size 1.27 1.27)
				)
				(justify mirror)
			)
		)
		(property "Value" ""
			(at 0 0 90)
			(layer "B.Fab")
			(effects
				(font
					(size 1.27 1.27)
				)
				(justify mirror)
			)
		)
		(duplicate_pad_numbers_are_jumpers no)
		(fp_line
			(start -1.524 0.762)
			(end 1.524 0.762)
			(stroke
				(width 0.1524)
				(type default)
			)
			(layer "B.SilkS")
		)
		(fp_line
			(start 1.524 0.762)
			(end 1.524 -0.762)
			(stroke
				(width 0.1524)
				(type default)
			)
			(layer "B.SilkS")
		)
		(fp_line
			(start -1.524 -0.762)
			(end -1.524 0.762)
			(stroke
				(width 0.1524)
				(type default)
			)
			(layer "B.SilkS")
		)
		(fp_line
			(start 1.524 -0.762)
			(end -1.524 -0.762)
			(stroke
				(width 0.1524)
				(type default)
			)
			(layer "B.SilkS")
		)
		(fp_line
			(start -1.1049 0.724916)
			(end -1.1049 -0.724916)
			(stroke
				(width 0.1)
				(type default)
			)
			(layer "B.Fab")
		)
		(fp_line
			(start 1.1049 0.724916)
			(end -1.1049 0.724916)
			(stroke
				(width 0.1)
				(type default)
			)
			(layer "B.Fab")
		)
		(fp_line
			(start -1.1049 -0.724916)
			(end 1.1049 -0.724916)
			(stroke
				(width 0.1)
				(type default)
			)
			(layer "B.Fab")
		)
		(fp_line
			(start 1.1049 -0.724916)
			(end 1.1049 0.724916)
			(stroke
				(width 0.1)
				(type default)
			)
			(layer "B.Fab")
		)
		(pad "1" smd rect
			(at 0.889 0 270)
			(size 1.016 1.27)
			(layers "B.Cu" "B.Mask" "B.Paste")
			(net "PVDDIO_P0")
		)
		(pad "2" smd rect
			(at -0.889 0 270)
			(size 1.016 1.27)
			(layers "B.Cu" "B.Mask" "B.Paste")
			(net "GND")
		)
	)
	(footprint ""
		(layer "B.Cu")
		(at 117.094 -417.957 -90)
		(property "Reference" "R3502"
			(at 0 0 90)
			(layer "B.SilkS")
			(hide yes)
			(effects
				(font
					(size 1.27 1.27)
				)
				(justify mirror)
			)
		)
		(property "Value" ""
			(at 0 0 90)
			(layer "B.Fab")
			(effects
				(font
					(size 1.27 1.27)
				)
				(justify mirror)
			)
		)
		(duplicate_pad_numbers_are_jumpers no)
		(fp_line
			(start -0.7874 0.4064)
			(end 0.7874 0.4064)
			(stroke
				(width 0.1524)
				(type default)
			)
			(layer "B.SilkS")
		)
		(fp_line
			(start 0.7874 0.4064)
			(end 0.7874 -0.4064)
			(stroke
				(width 0.1524)
				(type default)
			)
			(layer "B.SilkS")
		)
		(fp_line
			(start -0.7874 -0.4064)
			(end -0.7874 0.4064)
			(stroke
				(width 0.1524)
				(type default)
			)
			(layer "B.SilkS")
		)
		(fp_line
			(start 0.7874 -0.4064)
			(end -0.7874 -0.4064)
			(stroke
				(width 0.1524)
				(type default)
			)
			(layer "B.SilkS")
		)
		(fp_line
			(start -0.67945 0.3048)
			(end -0.120396 0.3048)
			(stroke
				(width 0.1)
				(type default)
			)
			(layer "B.Fab")
		)
		(fp_line
			(start -0.120396 0.3048)
			(end -0.120396 0.2794)
			(stroke
				(width 0.1)
				(type default)
			)
			(layer "B.Fab")
		)
		(fp_line
			(start 0.12065 0.3048)
			(end 0.67945 0.3048)
			(stroke
				(width 0.1)
				(type default)
			)
			(layer "B.Fab")
		)
		(fp_line
			(start 0.67945 0.3048)
			(end 0.67945 -0.305054)
			(stroke
				(width 0.1)
				(type default)
			)
			(layer "B.Fab")
		)
		(fp_line
			(start -0.120396 0.2794)
			(end 0.12065 0.2794)
			(stroke
				(width 0.1)
				(type default)
			)
			(layer "B.Fab")
		)
		(fp_line
			(start 0.12065 0.2794)
			(end 0.12065 0.3048)
			(stroke
				(width 0.1)
				(type default)
			)
			(layer "B.Fab")
		)
		(fp_line
			(start -0.12065 -0.2794)
			(end -0.12065 -0.3048)
			(stroke
				(width 0.1)
				(type default)
			)
			(layer "B.Fab")
		)
		(fp_line
			(start 0.12065 -0.2794)
			(end -0.12065 -0.2794)
			(stroke
				(width 0.1)
				(type default)
			)
			(layer "B.Fab")
		)
		(fp_line
			(start -0.67945 -0.3048)
			(end -0.67945 0.3048)
			(stroke
				(width 0.1)
				(type default)
			)
			(layer "B.Fab")
		)
		(fp_line
			(start -0.12065 -0.3048)
			(end -0.67945 -0.3048)
			(stroke
				(width 0.1)
				(type default)
			)
			(layer "B.Fab")
		)
		(fp_line
			(start 0.12065 -0.305054)
			(end 0.12065 -0.2794)
			(stroke
				(width 0.1)
				(type default)
			)
			(layer "B.Fab")
		)
		(fp_line
			(start 0.67945 -0.305054)
			(end 0.12065 -0.305054)
			(stroke
				(width 0.1)
				(type default)
			)
			(layer "B.Fab")
		)
		(pad "1" smd circle
			(at 0.40005 0 90)
			(size 0 0)
			(layers "B.Cu" "B.Mask" "B.Paste")
			(net "GPU_FPGA_EROT_FATALERR_N")
		)
		(pad "2" smd circle
			(at -0.40005 0 90)
			(size 0 0)
			(layers "B.Cu" "B.Mask" "B.Paste")
			(net "GND")
		)
	)
	(footprint ""
		(layer "B.Cu")
		(at 249.428 -246.634)
		(property "Reference" "ME14"
			(at 0 0 0)
			(layer "B.SilkS")
			(hide yes)
			(effects
				(font
					(size 1.27 1.27)
				)
				(justify mirror)
			)
		)
		(property "Value" ""
			(at 0 0 0)
			(layer "B.Fab")
			(effects
				(font
					(size 1.27 1.27)
				)
				(justify mirror)
			)
		)
		(duplicate_pad_numbers_are_jumpers no)
		(zone
			(layer "B.Cu")
			(hatch none 0.5)
			(connect_pads
				(clearance 0)
			)
			(min_thickness 0.25)
			(keepout
				(tracks allowed)
				(vias allowed)
				(pads allowed)
				(copperpour allowed)
				(footprints not_allowed)
			)
			(placement
				(enabled no)
				(sheetname "")
			)
			(fill
				(thermal_gap 0.5)
				(thermal_bridge_width 0.5)
				(island_removal_mode 0)
			)
			(polygon
				(pts
					(arc
						(start 259.42798 -246.634)
						(mid 239.42802 -246.634)
						(end 259.42798 -246.634)
					)
				)
			)
		)
	)
	(footprint ""
		(layer "B.Cu")
		(at 126.375668 -37.47643)
		(property "Reference" "C6074"
			(at 0 0 0)
			(layer "B.SilkS")
			(hide yes)
			(effects
				(font
					(size 1.27 1.27)
				)
				(justify mirror)
			)
		)
		(property "Value" ""
			(at 0 0 0)
			(layer "B.Fab")
			(effects
				(font
					(size 1.27 1.27)
				)
				(justify mirror)
			)
		)
		(duplicate_pad_numbers_are_jumpers no)
		(fp_line
			(start -0.7874 -0.4064)
			(end -0.7874 0.4064)
			(stroke
				(width 0.1524)
				(type default)
			)
			(layer "B.SilkS")
		)
		(fp_line
			(start -0.7874 0.4064)
			(end 0.7874 0.4064)
			(stroke
				(width 0.1524)
				(type default)
			)
			(layer "B.SilkS")
		)
		(fp_line
			(start 0.7874 -0.4064)
			(end -0.7874 -0.4064)
			(stroke
				(width 0.1524)
				(type default)
			)
			(layer "B.SilkS")
		)
		(fp_line
			(start 0.7874 0.4064)
			(end 0.7874 -0.4064)
			(stroke
				(width 0.1524)
				(type default)
			)
			(layer "B.SilkS")
		)
		(fp_line
			(start -0.67945 -0.3048)
			(end -0.67945 0.3048)
			(stroke
				(width 0.1)
				(type default)
			)
			(layer "B.Fab")
		)
		(fp_line
			(start -0.67945 0.3048)
			(end -0.120396 0.3048)
			(stroke
				(width 0.1)
				(type default)
			)
			(layer "B.Fab")
		)
		(fp_line
			(start -0.12065 -0.3048)
			(end -0.67945 -0.3048)
			(stroke
				(width 0.1)
				(type default)
			)
			(layer "B.Fab")
		)
		(fp_line
			(start -0.12065 -0.2794)
			(end -0.12065 -0.3048)
			(stroke
				(width 0.1)
				(type default)
			)
			(layer "B.Fab")
		)
		(fp_line
			(start -0.120396 0.2794)
			(end 0.12065 0.2794)
			(stroke
				(width 0.1)
				(type default)
			)
			(layer "B.Fab")
		)
		(fp_line
			(start -0.120396 0.3048)
			(end -0.120396 0.2794)
			(stroke
				(width 0.1)
				(type default)
			)
			(layer "B.Fab")
		)
		(fp_line
			(start 0.12065 -0.305054)
			(end 0.12065 -0.2794)
			(stroke
				(width 0.1)
				(type default)
			)
			(layer "B.Fab")
		)
		(fp_line
			(start 0.12065 -0.2794)
			(end -0.12065 -0.2794)
			(stroke
				(width 0.1)
				(type default)
			)
			(layer "B.Fab")
		)
		(fp_line
			(start 0.12065 0.2794)
			(end 0.12065 0.3048)
			(stroke
				(width 0.1)
				(type default)
			)
			(layer "B.Fab")
		)
		(fp_line
			(start 0.12065 0.3048)
			(end 0.67945 0.3048)
			(stroke
				(width 0.1)
				(type default)
			)
			(layer "B.Fab")
		)
		(fp_line
			(start 0.67945 -0.305054)
			(end 0.12065 -0.305054)
			(stroke
				(width 0.1)
				(type default)
			)
			(layer "B.Fab")
		)
		(fp_line
			(start 0.67945 0.3048)
			(end 0.67945 -0.305054)
			(stroke
				(width 0.1)
				(type default)
			)
			(layer "B.Fab")
		)
		(pad "1" smd circle
			(at 0.40005 0 180)
			(size 0 0)
			(layers "B.Cu" "B.Mask" "B.Paste")
			(net "P1V2_AUX")
		)
		(pad "2" smd circle
			(at -0.40005 0 180)
			(size 0 0)
			(layers "B.Cu" "B.Mask" "B.Paste")
			(net "GND")
		)
	)
	(footprint ""
		(layer "B.Cu")
		(at 183.932322 -115.022376)
		(property "Reference" "C1176"
			(at 0 0 0)
			(layer "B.SilkS")
			(hide yes)
			(effects
				(font
					(size 1.27 1.27)
				)
				(justify mirror)
			)
		)
		(property "Value" ""
			(at 0 0 0)
			(layer "B.Fab")
			(effects
				(font
					(size 1.27 1.27)
				)
				(justify mirror)
			)
		)
		(duplicate_pad_numbers_are_jumpers no)
		(fp_line
			(start -0.69215 -0.2921)
			(end -0.69215 0.2921)
			(stroke
				(width 0.1524)
				(type default)
			)
			(layer "B.SilkS")
		)
		(fp_line
			(start -0.69215 0.2921)
			(end 0.69215 0.2921)
			(stroke
				(width 0.1524)
				(type default)
			)
			(layer "B.SilkS")
		)
		(fp_line
			(start 0.69215 -0.2921)
			(end -0.69215 -0.2921)
			(stroke
				(width 0.1524)
				(type default)
			)
			(layer "B.SilkS")
		)
		(fp_line
			(start 0.69215 0.2921)
			(end 0.69215 -0.2921)
			(stroke
				(width 0.1524)
				(type default)
			)
			(layer "B.SilkS")
		)
		(fp_line
			(start -0.51435 -0.2794)
			(end -0.51435 0.2794)
			(stroke
				(width 0.1)
				(type default)
			)
			(layer "B.Fab")
		)
		(fp_line
			(start -0.51435 0.2794)
			(end 0.51435 0.2794)
			(stroke
				(width 0.1)
				(type default)
			)
			(layer "B.Fab")
		)
		(fp_line
			(start 0.51435 -0.2794)
			(end -0.51435 -0.2794)
			(stroke
				(width 0.1)
				(type default)
			)
			(layer "B.Fab")
		)
		(fp_line
			(start 0.51435 0.2794)
			(end 0.51435 -0.2794)
			(stroke
				(width 0.1)
				(type default)
			)
			(layer "B.Fab")
		)
		(pad "1" smd circle
			(at 0.40005 0 180)
			(size 0 0)
			(layers "B.Cu" "B.Mask" "B.Paste")
			(net "P3V3_AUX")
		)
		(pad "2" smd circle
			(at -0.40005 0 180)
			(size 0 0)
			(layers "B.Cu" "B.Mask" "B.Paste")
			(net "GND")
		)
		(zone
			(layer "B.Cu")
			(hatch none 0.5)
			(connect_pads
				(clearance 0)
			)
			(min_thickness 0.25)
			(keepout
				(tracks not_allowed)
				(vias allowed)
				(pads allowed)
				(copperpour not_allowed)
				(footprints allowed)
			)
			(placement
				(enabled no)
				(sheetname "")
			)
			(fill
				(thermal_gap 0.5)
				(thermal_bridge_width 0.5)
				(island_removal_mode 0)
			)
			(polygon
				(pts
					(xy 183.741822 -114.934746) (xy 183.741822 -115.110006) (xy 183.831992 -115.168426) (xy 184.031382 -115.168426)
					(xy 184.122822 -115.11026) (xy 184.122822 -114.934746) (xy 184.031382 -114.87658) (xy 183.831992 -114.87658)
				)
			)
		)
	)
	(footprint ""
		(layer "B.Cu")
		(at 145.124678 -318.208152 180)
		(property "Reference" "R1501"
			(at 0 0 0)
			(layer "B.SilkS")
			(hide yes)
			(effects
				(font
					(size 1.27 1.27)
				)
				(justify mirror)
			)
		)
		(property "Value" ""
			(at 0 0 0)
			(layer "B.Fab")
			(effects
				(font
					(size 1.27 1.27)
				)
				(justify mirror)
			)
		)
		(duplicate_pad_numbers_are_jumpers no)
		(fp_line
			(start 0.7874 0.4064)
			(end 0.7874 -0.4064)
			(stroke
				(width 0.1524)
				(type default)
			)
			(layer "B.SilkS")
		)
		(fp_line
			(start 0.7874 -0.4064)
			(end -0.7874 -0.4064)
			(stroke
				(width 0.1524)
				(type default)
			)
			(layer "B.SilkS")
		)
		(fp_line
			(start -0.7874 0.4064)
			(end 0.7874 0.4064)
			(stroke
				(width 0.1524)
				(type default)
			)
			(layer "B.SilkS")
		)
		(fp_line
			(start -0.7874 -0.4064)
			(end -0.7874 0.4064)
			(stroke
				(width 0.1524)
				(type default)
			)
			(layer "B.SilkS")
		)
		(fp_line
			(start 0.67945 0.3048)
			(end 0.67945 -0.305054)
			(stroke
				(width 0.1)
				(type default)
			)
			(layer "B.Fab")
		)
		(fp_line
			(start 0.67945 -0.305054)
			(end 0.12065 -0.305054)
			(stroke
				(width 0.1)
				(type default)
			)
			(layer "B.Fab")
		)
		(fp_line
			(start 0.12065 0.3048)
			(end 0.67945 0.3048)
			(stroke
				(width 0.1)
				(type default)
			)
			(layer "B.Fab")
		)
		(fp_line
			(start 0.12065 0.2794)
			(end 0.12065 0.3048)
			(stroke
				(width 0.1)
				(type default)
			)
			(layer "B.Fab")
		)
		(fp_line
			(start 0.12065 -0.2794)
			(end -0.12065 -0.2794)
			(stroke
				(width 0.1)
				(type default)
			)
			(layer "B.Fab")
		)
		(fp_line
			(start 0.12065 -0.305054)
			(end 0.12065 -0.2794)
			(stroke
				(width 0.1)
				(type default)
			)
			(layer "B.Fab")
		)
		(fp_line
			(start -0.120396 0.3048)
			(end -0.120396 0.2794)
			(stroke
				(width 0.1)
				(type default)
			)
			(layer "B.Fab")
		)
		(fp_line
			(start -0.120396 0.2794)
			(end 0.12065 0.2794)
			(stroke
				(width 0.1)
				(type default)
			)
			(layer "B.Fab")
		)
		(fp_line
			(start -0.12065 -0.2794)
			(end -0.12065 -0.3048)
			(stroke
				(width 0.1)
				(type default)
			)
			(layer "B.Fab")
		)
		(fp_line
			(start -0.12065 -0.3048)
			(end -0.67945 -0.3048)
			(stroke
				(width 0.1)
				(type default)
			)
			(layer "B.Fab")
		)
		(fp_line
			(start -0.67945 0.3048)
			(end -0.120396 0.3048)
			(stroke
				(width 0.1)
				(type default)
			)
			(layer "B.Fab")
		)
		(fp_line
			(start -0.67945 -0.3048)
			(end -0.67945 0.3048)
			(stroke
				(width 0.1)
				(type default)
			)
			(layer "B.Fab")
		)
		(pad "1" smd circle
			(at 0.40005 0)
			(size 0 0)
			(layers "B.Cu" "B.Mask" "B.Paste")
			(net "PVDD18_S5_P1")
		)
		(pad "2" smd circle
			(at -0.40005 0)
			(size 0 0)
			(layers "B.Cu" "B.Mask" "B.Paste")
			(net "CLK_CPU1_RTCCLK")
		)
	)
	(footprint ""
		(layer "B.Cu")
		(at 229.997 -240.03)
		(property "Reference" "R143"
			(at 0 0 0)
			(layer "B.SilkS")
			(hide yes)
			(effects
				(font
					(size 1.27 1.27)
				)
				(justify mirror)
			)
		)
		(property "Value" ""
			(at 0 0 0)
			(layer "B.Fab")
			(effects
				(font
					(size 1.27 1.27)
				)
				(justify mirror)
			)
		)
		(duplicate_pad_numbers_are_jumpers no)
		(fp_line
			(start -0.7874 -0.4064)
			(end -0.7874 0.4064)
			(stroke
				(width 0.1524)
				(type default)
			)
			(layer "B.SilkS")
		)
		(fp_line
			(start -0.7874 0.4064)
			(end 0.7874 0.4064)
			(stroke
				(width 0.1524)
				(type default)
			)
			(layer "B.SilkS")
		)
		(fp_line
			(start 0.7874 -0.4064)
			(end -0.7874 -0.4064)
			(stroke
				(width 0.1524)
				(type default)
			)
			(layer "B.SilkS")
		)
		(fp_line
			(start 0.7874 0.4064)
			(end 0.7874 -0.4064)
			(stroke
				(width 0.1524)
				(type default)
			)
			(layer "B.SilkS")
		)
		(fp_line
			(start -0.67945 -0.3048)
			(end -0.67945 0.3048)
			(stroke
				(width 0.1)
				(type default)
			)
			(layer "B.Fab")
		)
		(fp_line
			(start -0.67945 0.3048)
			(end -0.120396 0.3048)
			(stroke
				(width 0.1)
				(type default)
			)
			(layer "B.Fab")
		)
		(fp_line
			(start -0.12065 -0.3048)
			(end -0.67945 -0.3048)
			(stroke
				(width 0.1)
				(type default)
			)
			(layer "B.Fab")
		)
		(fp_line
			(start -0.12065 -0.2794)
			(end -0.12065 -0.3048)
			(stroke
				(width 0.1)
				(type default)
			)
			(layer "B.Fab")
		)
		(fp_line
			(start -0.120396 0.2794)
			(end 0.12065 0.2794)
			(stroke
				(width 0.1)
				(type default)
			)
			(layer "B.Fab")
		)
		(fp_line
			(start -0.120396 0.3048)
			(end -0.120396 0.2794)
			(stroke
				(width 0.1)
				(type default)
			)
			(layer "B.Fab")
		)
		(fp_line
			(start 0.12065 -0.305054)
			(end 0.12065 -0.2794)
			(stroke
				(width 0.1)
				(type default)
			)
			(layer "B.Fab")
		)
		(fp_line
			(start 0.12065 -0.2794)
			(end -0.12065 -0.2794)
			(stroke
				(width 0.1)
				(type default)
			)
			(layer "B.Fab")
		)
		(fp_line
			(start 0.12065 0.2794)
			(end 0.12065 0.3048)
			(stroke
				(width 0.1)
				(type default)
			)
			(layer "B.Fab")
		)
		(fp_line
			(start 0.12065 0.3048)
			(end 0.67945 0.3048)
			(stroke
				(width 0.1)
				(type default)
			)
			(layer "B.Fab")
		)
		(fp_line
			(start 0.67945 -0.305054)
			(end 0.12065 -0.305054)
			(stroke
				(width 0.1)
				(type default)
			)
			(layer "B.Fab")
		)
		(fp_line
			(start 0.67945 0.3048)
			(end 0.67945 -0.305054)
			(stroke
				(width 0.1)
				(type default)
			)
			(layer "B.Fab")
		)
		(pad "1" smd circle
			(at 0.40005 0 180)
			(size 0 0)
			(layers "B.Cu" "B.Mask" "B.Paste")
			(net "SMB_CPU0_CPU1_APML_MUX1_SDA")
		)
		(pad "2" smd circle
			(at -0.40005 0 180)
			(size 0 0)
			(layers "B.Cu" "B.Mask" "B.Paste")
			(net "SMB_APML_CPU0_R_SDA")
		)
	)
	(footprint ""
		(layer "B.Cu")
		(at 358.467152 -261.747762 90)
		(property "Reference" "C2617"
			(at 0 0 90)
			(layer "B.SilkS")
			(hide yes)
			(effects
				(font
					(size 1.27 1.27)
				)
				(justify mirror)
			)
		)
		(property "Value" ""
			(at 0 0 90)
			(layer "B.Fab")
			(effects
				(font
					(size 1.27 1.27)
				)
				(justify mirror)
			)
		)
		(duplicate_pad_numbers_are_jumpers no)
		(fp_line
			(start 0.7874 -0.4064)
			(end -0.7874 -0.4064)
			(stroke
				(width 0.1524)
				(type default)
			)
			(layer "B.SilkS")
		)
		(fp_line
			(start -0.7874 -0.4064)
			(end -0.7874 0.4064)
			(stroke
				(width 0.1524)
				(type default)
			)
			(layer "B.SilkS")
		)
		(fp_line
			(start 0.7874 0.4064)
			(end 0.7874 -0.4064)
			(stroke
				(width 0.1524)
				(type default)
			)
			(layer "B.SilkS")
		)
		(fp_line
			(start -0.7874 0.4064)
			(end 0.7874 0.4064)
			(stroke
				(width 0.1524)
				(type default)
			)
			(layer "B.SilkS")
		)
		(fp_line
			(start 0.67945 -0.305054)
			(end 0.12065 -0.305054)
			(stroke
				(width 0.1)
				(type default)
			)
			(layer "B.Fab")
		)
		(fp_line
			(start 0.12065 -0.305054)
			(end 0.12065 -0.2794)
			(stroke
				(width 0.1)
				(type default)
			)
			(layer "B.Fab")
		)
		(fp_line
			(start -0.12065 -0.3048)
			(end -0.67945 -0.3048)
			(stroke
				(width 0.1)
				(type default)
			)
			(layer "B.Fab")
		)
		(fp_line
			(start -0.67945 -0.3048)
			(end -0.67945 0.3048)
			(stroke
				(width 0.1)
				(type default)
			)
			(layer "B.Fab")
		)
		(fp_line
			(start 0.12065 -0.2794)
			(end -0.12065 -0.2794)
			(stroke
				(width 0.1)
				(type default)
			)
			(layer "B.Fab")
		)
		(fp_line
			(start -0.12065 -0.2794)
			(end -0.12065 -0.3048)
			(stroke
				(width 0.1)
				(type default)
			)
			(layer "B.Fab")
		)
		(fp_line
			(start 0.12065 0.2794)
			(end 0.12065 0.3048)
			(stroke
				(width 0.1)
				(type default)
			)
			(layer "B.Fab")
		)
		(fp_line
			(start -0.120396 0.2794)
			(end 0.12065 0.2794)
			(stroke
				(width 0.1)
				(type default)
			)
			(layer "B.Fab")
		)
		(fp_line
			(start 0.67945 0.3048)
			(end 0.67945 -0.305054)
			(stroke
				(width 0.1)
				(type default)
			)
			(layer "B.Fab")
		)
		(fp_line
			(start 0.12065 0.3048)
			(end 0.67945 0.3048)
			(stroke
				(width 0.1)
				(type default)
			)
			(layer "B.Fab")
		)
		(fp_line
			(start -0.120396 0.3048)
			(end -0.120396 0.2794)
			(stroke
				(width 0.1)
				(type default)
			)
			(layer "B.Fab")
		)
		(fp_line
			(start -0.67945 0.3048)
			(end -0.120396 0.3048)
			(stroke
				(width 0.1)
				(type default)
			)
			(layer "B.Fab")
		)
		(pad "1" smd circle
			(at 0.40005 0 270)
			(size 0 0)
			(layers "B.Cu" "B.Mask" "B.Paste")
			(net "PVDD11_S3_P0")
		)
		(pad "2" smd circle
			(at -0.40005 0 270)
			(size 0 0)
			(layers "B.Cu" "B.Mask" "B.Paste")
			(net "GND")
		)
	)
	(footprint ""
		(layer "B.Cu")
		(at 308.191154 -398.942052 90)
		(property "Reference" "C568"
			(at 0 0 90)
			(layer "B.SilkS")
			(hide yes)
			(effects
				(font
					(size 1.27 1.27)
				)
				(justify mirror)
			)
		)
		(property "Value" ""
			(at 0 0 90)
			(layer "B.Fab")
			(effects
				(font
					(size 1.27 1.27)
				)
				(justify mirror)
			)
		)
		(duplicate_pad_numbers_are_jumpers no)
		(fp_line
			(start 0.7874 -0.4064)
			(end -0.7874 -0.4064)
			(stroke
				(width 0.1524)
				(type default)
			)
			(layer "B.SilkS")
		)
		(fp_line
			(start -0.7874 -0.4064)
			(end -0.7874 0.4064)
			(stroke
				(width 0.1524)
				(type default)
			)
			(layer "B.SilkS")
		)
		(fp_line
			(start 0.7874 0.4064)
			(end 0.7874 -0.4064)
			(stroke
				(width 0.1524)
				(type default)
			)
			(layer "B.SilkS")
		)
		(fp_line
			(start -0.7874 0.4064)
			(end 0.7874 0.4064)
			(stroke
				(width 0.1524)
				(type default)
			)
			(layer "B.SilkS")
		)
		(fp_line
			(start 0.67945 -0.305054)
			(end 0.12065 -0.305054)
			(stroke
				(width 0.1)
				(type default)
			)
			(layer "B.Fab")
		)
		(fp_line
			(start 0.12065 -0.305054)
			(end 0.12065 -0.2794)
			(stroke
				(width 0.1)
				(type default)
			)
			(layer "B.Fab")
		)
		(fp_line
			(start -0.12065 -0.3048)
			(end -0.67945 -0.3048)
			(stroke
				(width 0.1)
				(type default)
			)
			(layer "B.Fab")
		)
		(fp_line
			(start -0.67945 -0.3048)
			(end -0.67945 0.3048)
			(stroke
				(width 0.1)
				(type default)
			)
			(layer "B.Fab")
		)
		(fp_line
			(start 0.12065 -0.2794)
			(end -0.12065 -0.2794)
			(stroke
				(width 0.1)
				(type default)
			)
			(layer "B.Fab")
		)
		(fp_line
			(start -0.12065 -0.2794)
			(end -0.12065 -0.3048)
			(stroke
				(width 0.1)
				(type default)
			)
			(layer "B.Fab")
		)
		(fp_line
			(start 0.12065 0.2794)
			(end 0.12065 0.3048)
			(stroke
				(width 0.1)
				(type default)
			)
			(layer "B.Fab")
		)
		(fp_line
			(start -0.120396 0.2794)
			(end 0.12065 0.2794)
			(stroke
				(width 0.1)
				(type default)
			)
			(layer "B.Fab")
		)
		(fp_line
			(start 0.67945 0.3048)
			(end 0.67945 -0.305054)
			(stroke
				(width 0.1)
				(type default)
			)
			(layer "B.Fab")
		)
		(fp_line
			(start 0.12065 0.3048)
			(end 0.67945 0.3048)
			(stroke
				(width 0.1)
				(type default)
			)
			(layer "B.Fab")
		)
		(fp_line
			(start -0.120396 0.3048)
			(end -0.120396 0.2794)
			(stroke
				(width 0.1)
				(type default)
			)
			(layer "B.Fab")
		)
		(fp_line
			(start -0.67945 0.3048)
			(end -0.120396 0.3048)
			(stroke
				(width 0.1)
				(type default)
			)
			(layer "B.Fab")
		)
		(pad "1" smd circle
			(at 0.40005 0 270)
			(size 0 0)
			(layers "B.Cu" "B.Mask" "B.Paste")
			(net "P0V9_CPU0_RT0_2A")
		)
		(pad "2" smd circle
			(at -0.40005 0 270)
			(size 0 0)
			(layers "B.Cu" "B.Mask" "B.Paste")
			(net "GND")
		)
	)
	(footprint ""
		(layer "B.Cu")
		(at 381.291338 -398.942052 90)
		(property "Reference" "C1032"
			(at 0 0 90)
			(layer "B.SilkS")
			(hide yes)
			(effects
				(font
					(size 1.27 1.27)
				)
				(justify mirror)
			)
		)
		(property "Value" ""
			(at 0 0 90)
			(layer "B.Fab")
			(effects
				(font
					(size 1.27 1.27)
				)
				(justify mirror)
			)
		)
		(duplicate_pad_numbers_are_jumpers no)
		(fp_line
			(start 0.7874 -0.4064)
			(end -0.7874 -0.4064)
			(stroke
				(width 0.1524)
				(type default)
			)
			(layer "B.SilkS")
		)
		(fp_line
			(start -0.7874 -0.4064)
			(end -0.7874 0.4064)
			(stroke
				(width 0.1524)
				(type default)
			)
			(layer "B.SilkS")
		)
		(fp_line
			(start 0.7874 0.4064)
			(end 0.7874 -0.4064)
			(stroke
				(width 0.1524)
				(type default)
			)
			(layer "B.SilkS")
		)
		(fp_line
			(start -0.7874 0.4064)
			(end 0.7874 0.4064)
			(stroke
				(width 0.1524)
				(type default)
			)
			(layer "B.SilkS")
		)
		(fp_line
			(start 0.67945 -0.305054)
			(end 0.12065 -0.305054)
			(stroke
				(width 0.1)
				(type default)
			)
			(layer "B.Fab")
		)
		(fp_line
			(start 0.12065 -0.305054)
			(end 0.12065 -0.2794)
			(stroke
				(width 0.1)
				(type default)
			)
			(layer "B.Fab")
		)
		(fp_line
			(start -0.12065 -0.3048)
			(end -0.67945 -0.3048)
			(stroke
				(width 0.1)
				(type default)
			)
			(layer "B.Fab")
		)
		(fp_line
			(start -0.67945 -0.3048)
			(end -0.67945 0.3048)
			(stroke
				(width 0.1)
				(type default)
			)
			(layer "B.Fab")
		)
		(fp_line
			(start 0.12065 -0.2794)
			(end -0.12065 -0.2794)
			(stroke
				(width 0.1)
				(type default)
			)
			(layer "B.Fab")
		)
		(fp_line
			(start -0.12065 -0.2794)
			(end -0.12065 -0.3048)
			(stroke
				(width 0.1)
				(type default)
			)
			(layer "B.Fab")
		)
		(fp_line
			(start 0.12065 0.2794)
			(end 0.12065 0.3048)
			(stroke
				(width 0.1)
				(type default)
			)
			(layer "B.Fab")
		)
		(fp_line
			(start -0.120396 0.2794)
			(end 0.12065 0.2794)
			(stroke
				(width 0.1)
				(type default)
			)
			(layer "B.Fab")
		)
		(fp_line
			(start 0.67945 0.3048)
			(end 0.67945 -0.305054)
			(stroke
				(width 0.1)
				(type default)
			)
			(layer "B.Fab")
		)
		(fp_line
			(start 0.12065 0.3048)
			(end 0.67945 0.3048)
			(stroke
				(width 0.1)
				(type default)
			)
			(layer "B.Fab")
		)
		(fp_line
			(start -0.120396 0.3048)
			(end -0.120396 0.2794)
			(stroke
				(width 0.1)
				(type default)
			)
			(layer "B.Fab")
		)
		(fp_line
			(start -0.67945 0.3048)
			(end -0.120396 0.3048)
			(stroke
				(width 0.1)
				(type default)
			)
			(layer "B.Fab")
		)
		(pad "1" smd circle
			(at 0.40005 0 270)
			(size 0 0)
			(layers "B.Cu" "B.Mask" "B.Paste")
			(net "P0V9_CPU0_RT_2D")
		)
		(pad "2" smd circle
			(at -0.40005 0 270)
			(size 0 0)
			(layers "B.Cu" "B.Mask" "B.Paste")
			(net "GND")
		)
	)
	(footprint ""
		(layer "B.Cu")
		(at 449.443602 -422.01211 180)
		(property "Reference" "PR6814"
			(at 0 0 0)
			(layer "B.SilkS")
			(hide yes)
			(effects
				(font
					(size 1.27 1.27)
				)
				(justify mirror)
			)
		)
		(property "Value" ""
			(at 0 0 0)
			(layer "B.Fab")
			(effects
				(font
					(size 1.27 1.27)
				)
				(justify mirror)
			)
		)
		(duplicate_pad_numbers_are_jumpers no)
		(fp_line
			(start 0.7874 0.4064)
			(end 0.7874 -0.4064)
			(stroke
				(width 0.1524)
				(type default)
			)
			(layer "B.SilkS")
		)
		(fp_line
			(start 0.7874 -0.4064)
			(end -0.7874 -0.4064)
			(stroke
				(width 0.1524)
				(type default)
			)
			(layer "B.SilkS")
		)
		(fp_line
			(start -0.7874 0.4064)
			(end 0.7874 0.4064)
			(stroke
				(width 0.1524)
				(type default)
			)
			(layer "B.SilkS")
		)
		(fp_line
			(start -0.7874 -0.4064)
			(end -0.7874 0.4064)
			(stroke
				(width 0.1524)
				(type default)
			)
			(layer "B.SilkS")
		)
		(fp_line
			(start 0.67945 0.3048)
			(end 0.67945 -0.305054)
			(stroke
				(width 0.1)
				(type default)
			)
			(layer "B.Fab")
		)
		(fp_line
			(start 0.67945 -0.305054)
			(end 0.12065 -0.305054)
			(stroke
				(width 0.1)
				(type default)
			)
			(layer "B.Fab")
		)
		(fp_line
			(start 0.12065 0.3048)
			(end 0.67945 0.3048)
			(stroke
				(width 0.1)
				(type default)
			)
			(layer "B.Fab")
		)
		(fp_line
			(start 0.12065 0.2794)
			(end 0.12065 0.3048)
			(stroke
				(width 0.1)
				(type default)
			)
			(layer "B.Fab")
		)
		(fp_line
			(start 0.12065 -0.2794)
			(end -0.12065 -0.2794)
			(stroke
				(width 0.1)
				(type default)
			)
			(layer "B.Fab")
		)
		(fp_line
			(start 0.12065 -0.305054)
			(end 0.12065 -0.2794)
			(stroke
				(width 0.1)
				(type default)
			)
			(layer "B.Fab")
		)
		(fp_line
			(start -0.120396 0.3048)
			(end -0.120396 0.2794)
			(stroke
				(width 0.1)
				(type default)
			)
			(layer "B.Fab")
		)
		(fp_line
			(start -0.120396 0.2794)
			(end 0.12065 0.2794)
			(stroke
				(width 0.1)
				(type default)
			)
			(layer "B.Fab")
		)
		(fp_line
			(start -0.12065 -0.2794)
			(end -0.12065 -0.3048)
			(stroke
				(width 0.1)
				(type default)
			)
			(layer "B.Fab")
		)
		(fp_line
			(start -0.12065 -0.3048)
			(end -0.67945 -0.3048)
			(stroke
				(width 0.1)
				(type default)
			)
			(layer "B.Fab")
		)
		(fp_line
			(start -0.67945 0.3048)
			(end -0.120396 0.3048)
			(stroke
				(width 0.1)
				(type default)
			)
			(layer "B.Fab")
		)
		(fp_line
			(start -0.67945 -0.3048)
			(end -0.67945 0.3048)
			(stroke
				(width 0.1)
				(type default)
			)
			(layer "B.Fab")
		)
		(pad "1" smd circle
			(at 0.40005 0)
			(size 0 0)
			(layers "B.Cu" "B.Mask" "B.Paste")
			(net "P0V9_RETIMER_CPU0_TEMP0")
		)
		(pad "2" smd circle
			(at -0.40005 0)
			(size 0 0)
			(layers "B.Cu" "B.Mask" "B.Paste")
			(net "GND")
		)
	)
	(footprint ""
		(layer "B.Cu")
		(at 43.576748 -193.971164)
		(property "Reference" "C144"
			(at 0 0 0)
			(layer "B.SilkS")
			(hide yes)
			(effects
				(font
					(size 1.27 1.27)
				)
				(justify mirror)
			)
		)
		(property "Value" ""
			(at 0 0 0)
			(layer "B.Fab")
			(effects
				(font
					(size 1.27 1.27)
				)
				(justify mirror)
			)
		)
		(duplicate_pad_numbers_are_jumpers no)
		(fp_line
			(start -0.7874 -0.4064)
			(end -0.7874 0.4064)
			(stroke
				(width 0.1524)
				(type default)
			)
			(layer "B.SilkS")
		)
		(fp_line
			(start -0.7874 0.4064)
			(end 0.7874 0.4064)
			(stroke
				(width 0.1524)
				(type default)
			)
			(layer "B.SilkS")
		)
		(fp_line
			(start 0.7874 -0.4064)
			(end -0.7874 -0.4064)
			(stroke
				(width 0.1524)
				(type default)
			)
			(layer "B.SilkS")
		)
		(fp_line
			(start 0.7874 0.4064)
			(end 0.7874 -0.4064)
			(stroke
				(width 0.1524)
				(type default)
			)
			(layer "B.SilkS")
		)
		(fp_line
			(start -0.67945 -0.3048)
			(end -0.67945 0.3048)
			(stroke
				(width 0.1)
				(type default)
			)
			(layer "B.Fab")
		)
		(fp_line
			(start -0.67945 0.3048)
			(end -0.120396 0.3048)
			(stroke
				(width 0.1)
				(type default)
			)
			(layer "B.Fab")
		)
		(fp_line
			(start -0.12065 -0.3048)
			(end -0.67945 -0.3048)
			(stroke
				(width 0.1)
				(type default)
			)
			(layer "B.Fab")
		)
		(fp_line
			(start -0.12065 -0.2794)
			(end -0.12065 -0.3048)
			(stroke
				(width 0.1)
				(type default)
			)
			(layer "B.Fab")
		)
		(fp_line
			(start -0.120396 0.2794)
			(end 0.12065 0.2794)
			(stroke
				(width 0.1)
				(type default)
			)
			(layer "B.Fab")
		)
		(fp_line
			(start -0.120396 0.3048)
			(end -0.120396 0.2794)
			(stroke
				(width 0.1)
				(type default)
			)
			(layer "B.Fab")
		)
		(fp_line
			(start 0.12065 -0.305054)
			(end 0.12065 -0.2794)
			(stroke
				(width 0.1)
				(type default)
			)
			(layer "B.Fab")
		)
		(fp_line
			(start 0.12065 -0.2794)
			(end -0.12065 -0.2794)
			(stroke
				(width 0.1)
				(type default)
			)
			(layer "B.Fab")
		)
		(fp_line
			(start 0.12065 0.2794)
			(end 0.12065 0.3048)
			(stroke
				(width 0.1)
				(type default)
			)
			(layer "B.Fab")
		)
		(fp_line
			(start 0.12065 0.3048)
			(end 0.67945 0.3048)
			(stroke
				(width 0.1)
				(type default)
			)
			(layer "B.Fab")
		)
		(fp_line
			(start 0.67945 -0.305054)
			(end 0.12065 -0.305054)
			(stroke
				(width 0.1)
				(type default)
			)
			(layer "B.Fab")
		)
		(fp_line
			(start 0.67945 0.3048)
			(end 0.67945 -0.305054)
			(stroke
				(width 0.1)
				(type default)
			)
			(layer "B.Fab")
		)
		(pad "1" smd circle
			(at 0.40005 0 180)
			(size 0 0)
			(layers "B.Cu" "B.Mask" "B.Paste")
			(net "P3V3_AUX")
		)
		(pad "2" smd circle
			(at -0.40005 0 180)
			(size 0 0)
			(layers "B.Cu" "B.Mask" "B.Paste")
			(net "GND")
		)
	)
	(footprint ""
		(layer "B.Cu")
		(at 152.124918 -381.11303 180)
		(property "Reference" "C7027"
			(at -1.683004 -3.177032 0)
			(unlocked yes)
			(layer "B.SilkS")
			(effects
				(font
					(size 0.7874 0.5842)
					(thickness 0.1524)
				)
				(justify left mirror)
			)
		)
		(property "Value" ""
			(at 0 0 0)
			(layer "B.Fab")
			(effects
				(font
					(size 1.27 1.27)
				)
				(justify mirror)
			)
		)
		(duplicate_pad_numbers_are_jumpers no)
		(fp_line
			(start 4.84378 -2.150618)
			(end 4.842256 2.163064)
			(stroke
				(width 0.1524)
				(type default)
			)
			(layer "B.SilkS")
		)
		(fp_line
			(start 4.84378 -2.150618)
			(end 4.53898 -2.150618)
			(stroke
				(width 0.1524)
				(type default)
			)
			(layer "B.SilkS")
		)
		(fp_line
			(start 4.83108 2.150364)
			(end 4.447794 2.149348)
			(stroke
				(width 0.1524)
				(type default)
			)
			(layer "B.SilkS")
		)
		(fp_line
			(start 4.69138 -2.150618)
			(end 4.692396 2.161032)
			(stroke
				(width 0.1524)
				(type default)
			)
			(layer "B.SilkS")
		)
		(fp_line
			(start 4.53898 2.15011)
			(end 4.53898 -2.15011)
			(stroke
				(width 0.1524)
				(type default)
			)
			(layer "B.SilkS")
		)
		(fp_line
			(start 4.53898 -2.15011)
			(end -4.53898 -2.15011)
			(stroke
				(width 0.1524)
				(type default)
			)
			(layer "B.SilkS")
		)
		(fp_line
			(start 4.53898 -2.150618)
			(end 4.539742 2.152142)
			(stroke
				(width 0.1524)
				(type default)
			)
			(layer "B.SilkS")
		)
		(fp_line
			(start -4.53898 2.15011)
			(end 4.53898 2.15011)
			(stroke
				(width 0.1524)
				(type default)
			)
			(layer "B.SilkS")
		)
		(fp_line
			(start -4.53898 -2.15011)
			(end -4.53898 2.15011)
			(stroke
				(width 0.1524)
				(type default)
			)
			(layer "B.SilkS")
		)
		(fp_line
			(start 3.64998 2.15011)
			(end 3.64998 -2.15011)
			(stroke
				(width 0.1)
				(type default)
			)
			(layer "B.Fab")
		)
		(fp_line
			(start 3.64998 -2.15011)
			(end -3.64998 -2.15011)
			(stroke
				(width 0.1)
				(type default)
			)
			(layer "B.Fab")
		)
		(fp_line
			(start -3.64998 2.15011)
			(end 3.64998 2.15011)
			(stroke
				(width 0.1)
				(type default)
			)
			(layer "B.Fab")
		)
		(fp_line
			(start -3.64998 -2.15011)
			(end -3.64998 2.15011)
			(stroke
				(width 0.1)
				(type default)
			)
			(layer "B.Fab")
		)
		(fp_text user "+"
			(at 4.185412 -3.072638 180)
			(unlocked yes)
			(layer "B.SilkS")
			(effects
				(font
					(size 1.905 1.4224)
					(thickness 0.1524)
				)
				(justify left mirror)
			)
		)
		(fp_text user "-"
			(at -2.944114 -2.830068 180)
			(unlocked yes)
			(layer "B.SilkS")
			(effects
				(font
					(size 1.905 1.4224)
					(thickness 0.1524)
				)
				(justify left mirror)
			)
		)
		(fp_text user "+"
			(at 6.214872 -0.337058 180)
			(unlocked yes)
			(layer "B.Fab")
			(effects
				(font
					(size 1.905 1.4224)
					(thickness 0.1524)
				)
				(justify left mirror)
			)
		)
		(fp_text user "-"
			(at -4.313174 -0.094488 180)
			(unlocked yes)
			(layer "B.Fab")
			(effects
				(font
					(size 1.905 1.4224)
					(thickness 0.1524)
				)
				(justify left mirror)
			)
		)
		(pad "1" smd rect
			(at 3.199892 0)
			(size 2.413 2.8194)
			(layers "B.Cu" "B.Mask" "B.Paste")
			(net "P0V9_CPU1_RT2_2A")
		)
		(pad "2" smd rect
			(at -3.199892 0)
			(size 2.413 2.8194)
			(layers "B.Cu" "B.Mask" "B.Paste")
			(net "GND")
		)
	)
	(footprint ""
		(layer "B.Cu")
		(at 405.241252 -349.195644 -90)
		(property "Reference" "R6122"
			(at 0 0 90)
			(layer "B.SilkS")
			(hide yes)
			(effects
				(font
					(size 1.27 1.27)
				)
				(justify mirror)
			)
		)
		(property "Value" ""
			(at 0 0 90)
			(layer "B.Fab")
			(effects
				(font
					(size 1.27 1.27)
				)
				(justify mirror)
			)
		)
		(duplicate_pad_numbers_are_jumpers no)
		(fp_line
			(start -0.7874 0.4064)
			(end 0.7874 0.4064)
			(stroke
				(width 0.1524)
				(type default)
			)
			(layer "B.SilkS")
		)
		(fp_line
			(start 0.7874 0.4064)
			(end 0.7874 -0.4064)
			(stroke
				(width 0.1524)
				(type default)
			)
			(layer "B.SilkS")
		)
		(fp_line
			(start -0.7874 -0.4064)
			(end -0.7874 0.4064)
			(stroke
				(width 0.1524)
				(type default)
			)
			(layer "B.SilkS")
		)
		(fp_line
			(start 0.7874 -0.4064)
			(end -0.7874 -0.4064)
			(stroke
				(width 0.1524)
				(type default)
			)
			(layer "B.SilkS")
		)
		(fp_line
			(start -0.67945 0.3048)
			(end -0.120396 0.3048)
			(stroke
				(width 0.1)
				(type default)
			)
			(layer "B.Fab")
		)
		(fp_line
			(start -0.120396 0.3048)
			(end -0.120396 0.2794)
			(stroke
				(width 0.1)
				(type default)
			)
			(layer "B.Fab")
		)
		(fp_line
			(start 0.12065 0.3048)
			(end 0.67945 0.3048)
			(stroke
				(width 0.1)
				(type default)
			)
			(layer "B.Fab")
		)
		(fp_line
			(start 0.67945 0.3048)
			(end 0.67945 -0.305054)
			(stroke
				(width 0.1)
				(type default)
			)
			(layer "B.Fab")
		)
		(fp_line
			(start -0.120396 0.2794)
			(end 0.12065 0.2794)
			(stroke
				(width 0.1)
				(type default)
			)
			(layer "B.Fab")
		)
		(fp_line
			(start 0.12065 0.2794)
			(end 0.12065 0.3048)
			(stroke
				(width 0.1)
				(type default)
			)
			(layer "B.Fab")
		)
		(fp_line
			(start -0.12065 -0.2794)
			(end -0.12065 -0.3048)
			(stroke
				(width 0.1)
				(type default)
			)
			(layer "B.Fab")
		)
		(fp_line
			(start 0.12065 -0.2794)
			(end -0.12065 -0.2794)
			(stroke
				(width 0.1)
				(type default)
			)
			(layer "B.Fab")
		)
		(fp_line
			(start -0.67945 -0.3048)
			(end -0.67945 0.3048)
			(stroke
				(width 0.1)
				(type default)
			)
			(layer "B.Fab")
		)
		(fp_line
			(start -0.12065 -0.3048)
			(end -0.67945 -0.3048)
			(stroke
				(width 0.1)
				(type default)
			)
			(layer "B.Fab")
		)
		(fp_line
			(start 0.12065 -0.305054)
			(end 0.12065 -0.2794)
			(stroke
				(width 0.1)
				(type default)
			)
			(layer "B.Fab")
		)
		(fp_line
			(start 0.67945 -0.305054)
			(end 0.12065 -0.305054)
			(stroke
				(width 0.1)
				(type default)
			)
			(layer "B.Fab")
		)
		(pad "1" smd circle
			(at 0.40005 0 90)
			(size 0 0)
			(layers "B.Cu" "B.Mask" "B.Paste")
			(net "PVDD18_S5_P0")
		)
		(pad "2" smd circle
			(at -0.40005 0 90)
			(size 0 0)
			(layers "B.Cu" "B.Mask" "B.Paste")
			(net "FM_BOARD_SKU_ID2")
		)
	)
	(footprint ""
		(layer "B.Cu")
		(at 68.547234 -201.545952 90)
		(property "Reference" "R556"
			(at 0 0 90)
			(layer "B.SilkS")
			(hide yes)
			(effects
				(font
					(size 1.27 1.27)
				)
				(justify mirror)
			)
		)
		(property "Value" ""
			(at 0 0 90)
			(layer "B.Fab")
			(effects
				(font
					(size 1.27 1.27)
				)
				(justify mirror)
			)
		)
		(duplicate_pad_numbers_are_jumpers no)
		(fp_line
			(start 0.7874 -0.4064)
			(end -0.7874 -0.4064)
			(stroke
				(width 0.1524)
				(type default)
			)
			(layer "B.SilkS")
		)
		(fp_line
			(start -0.7874 -0.4064)
			(end -0.7874 0.4064)
			(stroke
				(width 0.1524)
				(type default)
			)
			(layer "B.SilkS")
		)
		(fp_line
			(start 0.7874 0.4064)
			(end 0.7874 -0.4064)
			(stroke
				(width 0.1524)
				(type default)
			)
			(layer "B.SilkS")
		)
		(fp_line
			(start -0.7874 0.4064)
			(end 0.7874 0.4064)
			(stroke
				(width 0.1524)
				(type default)
			)
			(layer "B.SilkS")
		)
		(fp_line
			(start 0.67945 -0.305054)
			(end 0.12065 -0.305054)
			(stroke
				(width 0.1)
				(type default)
			)
			(layer "B.Fab")
		)
		(fp_line
			(start 0.12065 -0.305054)
			(end 0.12065 -0.2794)
			(stroke
				(width 0.1)
				(type default)
			)
			(layer "B.Fab")
		)
		(fp_line
			(start -0.12065 -0.3048)
			(end -0.67945 -0.3048)
			(stroke
				(width 0.1)
				(type default)
			)
			(layer "B.Fab")
		)
		(fp_line
			(start -0.67945 -0.3048)
			(end -0.67945 0.3048)
			(stroke
				(width 0.1)
				(type default)
			)
			(layer "B.Fab")
		)
		(fp_line
			(start 0.12065 -0.2794)
			(end -0.12065 -0.2794)
			(stroke
				(width 0.1)
				(type default)
			)
			(layer "B.Fab")
		)
		(fp_line
			(start -0.12065 -0.2794)
			(end -0.12065 -0.3048)
			(stroke
				(width 0.1)
				(type default)
			)
			(layer "B.Fab")
		)
		(fp_line
			(start 0.12065 0.2794)
			(end 0.12065 0.3048)
			(stroke
				(width 0.1)
				(type default)
			)
			(layer "B.Fab")
		)
		(fp_line
			(start -0.120396 0.2794)
			(end 0.12065 0.2794)
			(stroke
				(width 0.1)
				(type default)
			)
			(layer "B.Fab")
		)
		(fp_line
			(start 0.67945 0.3048)
			(end 0.67945 -0.305054)
			(stroke
				(width 0.1)
				(type default)
			)
			(layer "B.Fab")
		)
		(fp_line
			(start 0.12065 0.3048)
			(end 0.67945 0.3048)
			(stroke
				(width 0.1)
				(type default)
			)
			(layer "B.Fab")
		)
		(fp_line
			(start -0.120396 0.3048)
			(end -0.120396 0.2794)
			(stroke
				(width 0.1)
				(type default)
			)
			(layer "B.Fab")
		)
		(fp_line
			(start -0.67945 0.3048)
			(end -0.120396 0.3048)
			(stroke
				(width 0.1)
				(type default)
			)
			(layer "B.Fab")
		)
		(pad "1" smd circle
			(at 0.40005 0 270)
			(size 0 0)
			(layers "B.Cu" "B.Mask" "B.Paste")
			(net "PVDD18_S5_P1")
		)
		(pad "2" smd circle
			(at -0.40005 0 270)
			(size 0 0)
			(layers "B.Cu" "B.Mask" "B.Paste")
			(net "RST_CPU1_RESETL_N")
		)
	)
	(footprint ""
		(layer "B.Cu")
		(at 368.630962 -214.287608 180)
		(property "Reference" "PR303"
			(at 0 0 0)
			(layer "B.SilkS")
			(hide yes)
			(effects
				(font
					(size 1.27 1.27)
				)
				(justify mirror)
			)
		)
		(property "Value" ""
			(at 0 0 0)
			(layer "B.Fab")
			(effects
				(font
					(size 1.27 1.27)
				)
				(justify mirror)
			)
		)
		(duplicate_pad_numbers_are_jumpers no)
		(fp_line
			(start 0.7874 0.4064)
			(end 0.7874 -0.4064)
			(stroke
				(width 0.1524)
				(type default)
			)
			(layer "B.SilkS")
		)
		(fp_line
			(start 0.7874 -0.4064)
			(end -0.7874 -0.4064)
			(stroke
				(width 0.1524)
				(type default)
			)
			(layer "B.SilkS")
		)
		(fp_line
			(start -0.7874 0.4064)
			(end 0.7874 0.4064)
			(stroke
				(width 0.1524)
				(type default)
			)
			(layer "B.SilkS")
		)
		(fp_line
			(start -0.7874 -0.4064)
			(end -0.7874 0.4064)
			(stroke
				(width 0.1524)
				(type default)
			)
			(layer "B.SilkS")
		)
		(fp_line
			(start 0.67945 0.3048)
			(end 0.67945 -0.305054)
			(stroke
				(width 0.1)
				(type default)
			)
			(layer "B.Fab")
		)
		(fp_line
			(start 0.67945 -0.305054)
			(end 0.12065 -0.305054)
			(stroke
				(width 0.1)
				(type default)
			)
			(layer "B.Fab")
		)
		(fp_line
			(start 0.12065 0.3048)
			(end 0.67945 0.3048)
			(stroke
				(width 0.1)
				(type default)
			)
			(layer "B.Fab")
		)
		(fp_line
			(start 0.12065 0.2794)
			(end 0.12065 0.3048)
			(stroke
				(width 0.1)
				(type default)
			)
			(layer "B.Fab")
		)
		(fp_line
			(start 0.12065 -0.2794)
			(end -0.12065 -0.2794)
			(stroke
				(width 0.1)
				(type default)
			)
			(layer "B.Fab")
		)
		(fp_line
			(start 0.12065 -0.305054)
			(end 0.12065 -0.2794)
			(stroke
				(width 0.1)
				(type default)
			)
			(layer "B.Fab")
		)
		(fp_line
			(start -0.120396 0.3048)
			(end -0.120396 0.2794)
			(stroke
				(width 0.1)
				(type default)
			)
			(layer "B.Fab")
		)
		(fp_line
			(start -0.120396 0.2794)
			(end 0.12065 0.2794)
			(stroke
				(width 0.1)
				(type default)
			)
			(layer "B.Fab")
		)
		(fp_line
			(start -0.12065 -0.2794)
			(end -0.12065 -0.3048)
			(stroke
				(width 0.1)
				(type default)
			)
			(layer "B.Fab")
		)
		(fp_line
			(start -0.12065 -0.3048)
			(end -0.67945 -0.3048)
			(stroke
				(width 0.1)
				(type default)
			)
			(layer "B.Fab")
		)
		(fp_line
			(start -0.67945 0.3048)
			(end -0.120396 0.3048)
			(stroke
				(width 0.1)
				(type default)
			)
			(layer "B.Fab")
		)
		(fp_line
			(start -0.67945 -0.3048)
			(end -0.67945 0.3048)
			(stroke
				(width 0.1)
				(type default)
			)
			(layer "B.Fab")
		)
		(pad "1" smd circle
			(at 0.40005 0)
			(size 0 0)
			(layers "B.Cu" "B.Mask" "B.Paste")
			(net "SVID_PVDDCR_CPU0_P0_SVD_R")
		)
		(pad "2" smd circle
			(at -0.40005 0)
			(size 0 0)
			(layers "B.Cu" "B.Mask" "B.Paste")
			(net "SVID_PVDDCR_CPU0_P0_SVD")
		)
	)
	(footprint ""
		(layer "B.Cu")
		(at 106.085386 -268.418564)
		(property "Reference" "C2383"
			(at 0 0 0)
			(layer "B.SilkS")
			(hide yes)
			(effects
				(font
					(size 1.27 1.27)
				)
				(justify mirror)
			)
		)
		(property "Value" ""
			(at 0 0 0)
			(layer "B.Fab")
			(effects
				(font
					(size 1.27 1.27)
				)
				(justify mirror)
			)
		)
		(duplicate_pad_numbers_are_jumpers no)
		(fp_line
			(start -0.7874 -0.4064)
			(end -0.7874 0.4064)
			(stroke
				(width 0.1524)
				(type default)
			)
			(layer "B.SilkS")
		)
		(fp_line
			(start -0.7874 0.4064)
			(end 0.7874 0.4064)
			(stroke
				(width 0.1524)
				(type default)
			)
			(layer "B.SilkS")
		)
		(fp_line
			(start 0.7874 -0.4064)
			(end -0.7874 -0.4064)
			(stroke
				(width 0.1524)
				(type default)
			)
			(layer "B.SilkS")
		)
		(fp_line
			(start 0.7874 0.4064)
			(end 0.7874 -0.4064)
			(stroke
				(width 0.1524)
				(type default)
			)
			(layer "B.SilkS")
		)
		(fp_line
			(start -0.67945 -0.3048)
			(end -0.67945 0.3048)
			(stroke
				(width 0.1)
				(type default)
			)
			(layer "B.Fab")
		)
		(fp_line
			(start -0.67945 0.3048)
			(end -0.120396 0.3048)
			(stroke
				(width 0.1)
				(type default)
			)
			(layer "B.Fab")
		)
		(fp_line
			(start -0.12065 -0.3048)
			(end -0.67945 -0.3048)
			(stroke
				(width 0.1)
				(type default)
			)
			(layer "B.Fab")
		)
		(fp_line
			(start -0.12065 -0.2794)
			(end -0.12065 -0.3048)
			(stroke
				(width 0.1)
				(type default)
			)
			(layer "B.Fab")
		)
		(fp_line
			(start -0.120396 0.2794)
			(end 0.12065 0.2794)
			(stroke
				(width 0.1)
				(type default)
			)
			(layer "B.Fab")
		)
		(fp_line
			(start -0.120396 0.3048)
			(end -0.120396 0.2794)
			(stroke
				(width 0.1)
				(type default)
			)
			(layer "B.Fab")
		)
		(fp_line
			(start 0.12065 -0.305054)
			(end 0.12065 -0.2794)
			(stroke
				(width 0.1)
				(type default)
			)
			(layer "B.Fab")
		)
		(fp_line
			(start 0.12065 -0.2794)
			(end -0.12065 -0.2794)
			(stroke
				(width 0.1)
				(type default)
			)
			(layer "B.Fab")
		)
		(fp_line
			(start 0.12065 0.2794)
			(end 0.12065 0.3048)
			(stroke
				(width 0.1)
				(type default)
			)
			(layer "B.Fab")
		)
		(fp_line
			(start 0.12065 0.3048)
			(end 0.67945 0.3048)
			(stroke
				(width 0.1)
				(type default)
			)
			(layer "B.Fab")
		)
		(fp_line
			(start 0.67945 -0.305054)
			(end 0.12065 -0.305054)
			(stroke
				(width 0.1)
				(type default)
			)
			(layer "B.Fab")
		)
		(fp_line
			(start 0.67945 0.3048)
			(end 0.67945 -0.305054)
			(stroke
				(width 0.1)
				(type default)
			)
			(layer "B.Fab")
		)
		(pad "1" smd circle
			(at 0.40005 0 180)
			(size 0 0)
			(layers "B.Cu" "B.Mask" "B.Paste")
			(net "PVDDCR_CPU1_P1")
		)
		(pad "2" smd circle
			(at -0.40005 0 180)
			(size 0 0)
			(layers "B.Cu" "B.Mask" "B.Paste")
			(net "GND")
		)
	)
	(footprint ""
		(layer "B.Cu")
		(at 343.960958 -306.828952 180)
		(property "Reference" "R207"
			(at 0 0 0)
			(layer "B.SilkS")
			(hide yes)
			(effects
				(font
					(size 1.27 1.27)
				)
				(justify mirror)
			)
		)
		(property "Value" ""
			(at 0 0 0)
			(layer "B.Fab")
			(effects
				(font
					(size 1.27 1.27)
				)
				(justify mirror)
			)
		)
		(duplicate_pad_numbers_are_jumpers no)
		(fp_line
			(start 0.7874 0.4064)
			(end 0.7874 -0.4064)
			(stroke
				(width 0.1524)
				(type default)
			)
			(layer "B.SilkS")
		)
		(fp_line
			(start 0.7874 -0.4064)
			(end -0.7874 -0.4064)
			(stroke
				(width 0.1524)
				(type default)
			)
			(layer "B.SilkS")
		)
		(fp_line
			(start -0.7874 0.4064)
			(end 0.7874 0.4064)
			(stroke
				(width 0.1524)
				(type default)
			)
			(layer "B.SilkS")
		)
		(fp_line
			(start -0.7874 -0.4064)
			(end -0.7874 0.4064)
			(stroke
				(width 0.1524)
				(type default)
			)
			(layer "B.SilkS")
		)
		(fp_line
			(start 0.67945 0.3048)
			(end 0.67945 -0.305054)
			(stroke
				(width 0.1)
				(type default)
			)
			(layer "B.Fab")
		)
		(fp_line
			(start 0.67945 -0.305054)
			(end 0.12065 -0.305054)
			(stroke
				(width 0.1)
				(type default)
			)
			(layer "B.Fab")
		)
		(fp_line
			(start 0.12065 0.3048)
			(end 0.67945 0.3048)
			(stroke
				(width 0.1)
				(type default)
			)
			(layer "B.Fab")
		)
		(fp_line
			(start 0.12065 0.2794)
			(end 0.12065 0.3048)
			(stroke
				(width 0.1)
				(type default)
			)
			(layer "B.Fab")
		)
		(fp_line
			(start 0.12065 -0.2794)
			(end -0.12065 -0.2794)
			(stroke
				(width 0.1)
				(type default)
			)
			(layer "B.Fab")
		)
		(fp_line
			(start 0.12065 -0.305054)
			(end 0.12065 -0.2794)
			(stroke
				(width 0.1)
				(type default)
			)
			(layer "B.Fab")
		)
		(fp_line
			(start -0.120396 0.3048)
			(end -0.120396 0.2794)
			(stroke
				(width 0.1)
				(type default)
			)
			(layer "B.Fab")
		)
		(fp_line
			(start -0.120396 0.2794)
			(end 0.12065 0.2794)
			(stroke
				(width 0.1)
				(type default)
			)
			(layer "B.Fab")
		)
		(fp_line
			(start -0.12065 -0.2794)
			(end -0.12065 -0.3048)
			(stroke
				(width 0.1)
				(type default)
			)
			(layer "B.Fab")
		)
		(fp_line
			(start -0.12065 -0.3048)
			(end -0.67945 -0.3048)
			(stroke
				(width 0.1)
				(type default)
			)
			(layer "B.Fab")
		)
		(fp_line
			(start -0.67945 0.3048)
			(end -0.120396 0.3048)
			(stroke
				(width 0.1)
				(type default)
			)
			(layer "B.Fab")
		)
		(fp_line
			(start -0.67945 -0.3048)
			(end -0.67945 0.3048)
			(stroke
				(width 0.1)
				(type default)
			)
			(layer "B.Fab")
		)
		(pad "1" smd circle
			(at 0.40005 0)
			(size 0 0)
			(layers "B.Cu" "B.Mask" "B.Paste")
			(net "FM_INT_CPU0_HP_UBM_N")
		)
		(pad "2" smd circle
			(at -0.40005 0)
			(size 0 0)
			(layers "B.Cu" "B.Mask" "B.Paste")
			(net "PVDD18_S5_P0")
		)
	)
	(footprint ""
		(layer "B.Cu")
		(at 75.7936 -383.7432 180)
		(property "Reference" "R756"
			(at 0 0 0)
			(layer "B.SilkS")
			(hide yes)
			(effects
				(font
					(size 1.27 1.27)
				)
				(justify mirror)
			)
		)
		(property "Value" ""
			(at 0 0 0)
			(layer "B.Fab")
			(effects
				(font
					(size 1.27 1.27)
				)
				(justify mirror)
			)
		)
		(duplicate_pad_numbers_are_jumpers no)
		(fp_line
			(start 0.32512 0.175006)
			(end 0.32512 -0.175006)
			(stroke
				(width 0.1)
				(type default)
			)
			(layer "B.Fab")
		)
		(fp_line
			(start 0.32512 -0.175006)
			(end -0.32512 -0.175006)
			(stroke
				(width 0.1)
				(type default)
			)
			(layer "B.Fab")
		)
		(fp_line
			(start -0.32512 0.175006)
			(end 0.32512 0.175006)
			(stroke
				(width 0.1)
				(type default)
			)
			(layer "B.Fab")
		)
		(fp_line
			(start -0.32512 -0.175006)
			(end -0.32512 0.175006)
			(stroke
				(width 0.1)
				(type default)
			)
			(layer "B.Fab")
		)
		(pad "1" smd rect
			(at 0.2667 0)
			(size 0.3048 0.381)
			(layers "B.Cu" "B.Mask" "B.Paste")
			(net "RT_CPU1_P1_SCAN_MODE")
		)
		(pad "2" smd rect
			(at -0.2667 0 180)
			(size 0.3048 0.381)
			(layers "B.Cu" "B.Mask" "B.Paste")
			(net "GND")
		)
	)
	(footprint ""
		(layer "B.Cu")
		(at 216.916 -340.741 -90)
		(property "Reference" "R6752"
			(at 0 0 90)
			(layer "B.SilkS")
			(hide yes)
			(effects
				(font
					(size 1.27 1.27)
				)
				(justify mirror)
			)
		)
		(property "Value" ""
			(at 0 0 90)
			(layer "B.Fab")
			(effects
				(font
					(size 1.27 1.27)
				)
				(justify mirror)
			)
		)
		(duplicate_pad_numbers_are_jumpers no)
		(fp_line
			(start -0.32512 0.175006)
			(end 0.32512 0.175006)
			(stroke
				(width 0.1)
				(type default)
			)
			(layer "B.Fab")
		)
		(fp_line
			(start 0.32512 0.175006)
			(end 0.32512 -0.175006)
			(stroke
				(width 0.1)
				(type default)
			)
			(layer "B.Fab")
		)
		(fp_line
			(start -0.32512 -0.175006)
			(end -0.32512 0.175006)
			(stroke
				(width 0.1)
				(type default)
			)
			(layer "B.Fab")
		)
		(fp_line
			(start 0.32512 -0.175006)
			(end -0.32512 -0.175006)
			(stroke
				(width 0.1)
				(type default)
			)
			(layer "B.Fab")
		)
		(pad "1" smd rect
			(at 0.2667 0 90)
			(size 0.3048 0.381)
			(layers "B.Cu" "B.Mask" "B.Paste")
			(net "P1V8_CPU1_RT_1D")
		)
		(pad "2" smd rect
			(at -0.2667 0 270)
			(size 0.3048 0.381)
			(layers "B.Cu" "B.Mask" "B.Paste")
			(net "SMB_RT_CPU1_P2_R_SDA")
		)
	)
	(footprint ""
		(layer "B.Cu")
		(at 374.440958 -208.530952 -90)
		(property "Reference" "R400"
			(at 0 0 90)
			(layer "B.SilkS")
			(hide yes)
			(effects
				(font
					(size 1.27 1.27)
				)
				(justify mirror)
			)
		)
		(property "Value" ""
			(at 0 0 90)
			(layer "B.Fab")
			(effects
				(font
					(size 1.27 1.27)
				)
				(justify mirror)
			)
		)
		(duplicate_pad_numbers_are_jumpers no)
		(fp_line
			(start -0.7874 0.4064)
			(end 0.7874 0.4064)
			(stroke
				(width 0.1524)
				(type default)
			)
			(layer "B.SilkS")
		)
		(fp_line
			(start 0.7874 0.4064)
			(end 0.7874 -0.4064)
			(stroke
				(width 0.1524)
				(type default)
			)
			(layer "B.SilkS")
		)
		(fp_line
			(start -0.7874 -0.4064)
			(end -0.7874 0.4064)
			(stroke
				(width 0.1524)
				(type default)
			)
			(layer "B.SilkS")
		)
		(fp_line
			(start 0.7874 -0.4064)
			(end -0.7874 -0.4064)
			(stroke
				(width 0.1524)
				(type default)
			)
			(layer "B.SilkS")
		)
		(fp_line
			(start -0.67945 0.3048)
			(end -0.120396 0.3048)
			(stroke
				(width 0.1)
				(type default)
			)
			(layer "B.Fab")
		)
		(fp_line
			(start -0.120396 0.3048)
			(end -0.120396 0.2794)
			(stroke
				(width 0.1)
				(type default)
			)
			(layer "B.Fab")
		)
		(fp_line
			(start 0.12065 0.3048)
			(end 0.67945 0.3048)
			(stroke
				(width 0.1)
				(type default)
			)
			(layer "B.Fab")
		)
		(fp_line
			(start 0.67945 0.3048)
			(end 0.67945 -0.305054)
			(stroke
				(width 0.1)
				(type default)
			)
			(layer "B.Fab")
		)
		(fp_line
			(start -0.120396 0.2794)
			(end 0.12065 0.2794)
			(stroke
				(width 0.1)
				(type default)
			)
			(layer "B.Fab")
		)
		(fp_line
			(start 0.12065 0.2794)
			(end 0.12065 0.3048)
			(stroke
				(width 0.1)
				(type default)
			)
			(layer "B.Fab")
		)
		(fp_line
			(start -0.12065 -0.2794)
			(end -0.12065 -0.3048)
			(stroke
				(width 0.1)
				(type default)
			)
			(layer "B.Fab")
		)
		(fp_line
			(start 0.12065 -0.2794)
			(end -0.12065 -0.2794)
			(stroke
				(width 0.1)
				(type default)
			)
			(layer "B.Fab")
		)
		(fp_line
			(start -0.67945 -0.3048)
			(end -0.67945 0.3048)
			(stroke
				(width 0.1)
				(type default)
			)
			(layer "B.Fab")
		)
		(fp_line
			(start -0.12065 -0.3048)
			(end -0.67945 -0.3048)
			(stroke
				(width 0.1)
				(type default)
			)
			(layer "B.Fab")
		)
		(fp_line
			(start 0.12065 -0.305054)
			(end 0.12065 -0.2794)
			(stroke
				(width 0.1)
				(type default)
			)
			(layer "B.Fab")
		)
		(fp_line
			(start 0.67945 -0.305054)
			(end 0.12065 -0.305054)
			(stroke
				(width 0.1)
				(type default)
			)
			(layer "B.Fab")
		)
		(pad "1" smd circle
			(at 0.40005 0 90)
			(size 0 0)
			(layers "B.Cu" "B.Mask" "B.Paste")
			(net "PVDD18_S5_P0")
		)
		(pad "2" smd circle
			(at -0.40005 0 90)
			(size 0 0)
			(layers "B.Cu" "B.Mask" "B.Paste")
			(net "JTAG_CPU0_TRST_N")
		)
	)
	(footprint ""
		(layer "B.Cu")
		(at 362.988606 -401.624546 180)
		(property "Reference" "R1094"
			(at 0 0 0)
			(layer "B.SilkS")
			(hide yes)
			(effects
				(font
					(size 1.27 1.27)
				)
				(justify mirror)
			)
		)
		(property "Value" ""
			(at 0 0 0)
			(layer "B.Fab")
			(effects
				(font
					(size 1.27 1.27)
				)
				(justify mirror)
			)
		)
		(duplicate_pad_numbers_are_jumpers no)
		(fp_line
			(start 1.2954 0.5842)
			(end 1.2954 -0.5842)
			(stroke
				(width 0.1524)
				(type default)
			)
			(layer "B.SilkS")
		)
		(fp_line
			(start 1.2954 -0.5842)
			(end -1.2954 -0.5842)
			(stroke
				(width 0.1524)
				(type default)
			)
			(layer "B.SilkS")
		)
		(fp_line
			(start -1.2954 0.5842)
			(end 1.2954 0.5842)
			(stroke
				(width 0.1524)
				(type default)
			)
			(layer "B.SilkS")
		)
		(fp_line
			(start -1.2954 -0.5842)
			(end -1.2954 0.5842)
			(stroke
				(width 0.1524)
				(type default)
			)
			(layer "B.SilkS")
		)
		(fp_line
			(start 1.1938 0.4064)
			(end 1.1938 -0.406654)
			(stroke
				(width 0.1)
				(type default)
			)
			(layer "B.Fab")
		)
		(fp_line
			(start 1.1938 -0.406654)
			(end 0.8636 -0.406654)
			(stroke
				(width 0.1)
				(type default)
			)
			(layer "B.Fab")
		)
		(fp_line
			(start 0.8636 0.4572)
			(end 0.8636 0.4318)
			(stroke
				(width 0.1)
				(type default)
			)
			(layer "B.Fab")
		)
		(fp_line
			(start 0.8636 0.4318)
			(end 0.8636 0.4064)
			(stroke
				(width 0.1)
				(type default)
			)
			(layer "B.Fab")
		)
		(fp_line
			(start 0.8636 0.4064)
			(end 1.1938 0.4064)
			(stroke
				(width 0.1)
				(type default)
			)
			(layer "B.Fab")
		)
		(fp_line
			(start 0.8636 -0.406654)
			(end 0.8636 -0.4572)
			(stroke
				(width 0.1)
				(type default)
			)
			(layer "B.Fab")
		)
		(fp_line
			(start 0.8636 -0.4572)
			(end -0.8636 -0.4572)
			(stroke
				(width 0.1)
				(type default)
			)
			(layer "B.Fab")
		)
		(fp_line
			(start -0.8636 0.4572)
			(end 0.8636 0.4572)
			(stroke
				(width 0.1)
				(type default)
			)
			(layer "B.Fab")
		)
		(fp_line
			(start -0.8636 0.4064)
			(end -0.8636 0.4572)
			(stroke
				(width 0.1)
				(type default)
			)
			(layer "B.Fab")
		)
		(fp_line
			(start -0.8636 -0.406654)
			(end -1.1938 -0.406654)
			(stroke
				(width 0.1)
				(type default)
			)
			(layer "B.Fab")
		)
		(fp_line
			(start -0.8636 -0.4572)
			(end -0.8636 -0.406654)
			(stroke
				(width 0.1)
				(type default)
			)
			(layer "B.Fab")
		)
		(fp_line
			(start -1.1938 0.4064)
			(end -0.8636 0.4064)
			(stroke
				(width 0.1)
				(type default)
			)
			(layer "B.Fab")
		)
		(fp_line
			(start -1.1938 -0.406654)
			(end -1.1938 0.4064)
			(stroke
				(width 0.1)
				(type default)
			)
			(layer "B.Fab")
		)
		(pad "1" smd rect
			(at 0.7366 0 90)
			(size 0.7112 0.8128)
			(layers "B.Cu" "B.Mask" "B.Paste")
			(net "P0V9_CPU0_RT_2D")
		)
		(pad "2" smd rect
			(at -0.7366 0 90)
			(size 0.7112 0.8128)
			(layers "B.Cu" "B.Mask" "B.Paste")
			(net "P0V9_CPU0_RT3_2A_2D")
		)
	)
	(footprint ""
		(layer "B.Cu")
		(at 350.596454 -267.52931)
		(property "Reference" "C2205"
			(at 0 0 0)
			(layer "B.SilkS")
			(hide yes)
			(effects
				(font
					(size 1.27 1.27)
				)
				(justify mirror)
			)
		)
		(property "Value" ""
			(at 0 0 0)
			(layer "B.Fab")
			(effects
				(font
					(size 1.27 1.27)
				)
				(justify mirror)
			)
		)
		(duplicate_pad_numbers_are_jumpers no)
		(fp_line
			(start -0.7874 -0.4064)
			(end -0.7874 0.4064)
			(stroke
				(width 0.1524)
				(type default)
			)
			(layer "B.SilkS")
		)
		(fp_line
			(start -0.7874 0.4064)
			(end 0.7874 0.4064)
			(stroke
				(width 0.1524)
				(type default)
			)
			(layer "B.SilkS")
		)
		(fp_line
			(start 0.7874 -0.4064)
			(end -0.7874 -0.4064)
			(stroke
				(width 0.1524)
				(type default)
			)
			(layer "B.SilkS")
		)
		(fp_line
			(start 0.7874 0.4064)
			(end 0.7874 -0.4064)
			(stroke
				(width 0.1524)
				(type default)
			)
			(layer "B.SilkS")
		)
		(fp_line
			(start -0.67945 -0.3048)
			(end -0.67945 0.3048)
			(stroke
				(width 0.1)
				(type default)
			)
			(layer "B.Fab")
		)
		(fp_line
			(start -0.67945 0.3048)
			(end -0.120396 0.3048)
			(stroke
				(width 0.1)
				(type default)
			)
			(layer "B.Fab")
		)
		(fp_line
			(start -0.12065 -0.3048)
			(end -0.67945 -0.3048)
			(stroke
				(width 0.1)
				(type default)
			)
			(layer "B.Fab")
		)
		(fp_line
			(start -0.12065 -0.2794)
			(end -0.12065 -0.3048)
			(stroke
				(width 0.1)
				(type default)
			)
			(layer "B.Fab")
		)
		(fp_line
			(start -0.120396 0.2794)
			(end 0.12065 0.2794)
			(stroke
				(width 0.1)
				(type default)
			)
			(layer "B.Fab")
		)
		(fp_line
			(start -0.120396 0.3048)
			(end -0.120396 0.2794)
			(stroke
				(width 0.1)
				(type default)
			)
			(layer "B.Fab")
		)
		(fp_line
			(start 0.12065 -0.305054)
			(end 0.12065 -0.2794)
			(stroke
				(width 0.1)
				(type default)
			)
			(layer "B.Fab")
		)
		(fp_line
			(start 0.12065 -0.2794)
			(end -0.12065 -0.2794)
			(stroke
				(width 0.1)
				(type default)
			)
			(layer "B.Fab")
		)
		(fp_line
			(start 0.12065 0.2794)
			(end 0.12065 0.3048)
			(stroke
				(width 0.1)
				(type default)
			)
			(layer "B.Fab")
		)
		(fp_line
			(start 0.12065 0.3048)
			(end 0.67945 0.3048)
			(stroke
				(width 0.1)
				(type default)
			)
			(layer "B.Fab")
		)
		(fp_line
			(start 0.67945 -0.305054)
			(end 0.12065 -0.305054)
			(stroke
				(width 0.1)
				(type default)
			)
			(layer "B.Fab")
		)
		(fp_line
			(start 0.67945 0.3048)
			(end 0.67945 -0.305054)
			(stroke
				(width 0.1)
				(type default)
			)
			(layer "B.Fab")
		)
		(pad "1" smd circle
			(at 0.40005 0 180)
			(size 0 0)
			(layers "B.Cu" "B.Mask" "B.Paste")
			(net "PVDDCR_CPU1_P0")
		)
		(pad "2" smd circle
			(at -0.40005 0 180)
			(size 0 0)
			(layers "B.Cu" "B.Mask" "B.Paste")
			(net "GND")
		)
	)
	(footprint ""
		(layer "B.Cu")
		(at 359.740454 -249.87631 90)
		(property "Reference" "C2186"
			(at 0 0 90)
			(layer "B.SilkS")
			(hide yes)
			(effects
				(font
					(size 1.27 1.27)
				)
				(justify mirror)
			)
		)
		(property "Value" ""
			(at 0 0 90)
			(layer "B.Fab")
			(effects
				(font
					(size 1.27 1.27)
				)
				(justify mirror)
			)
		)
		(duplicate_pad_numbers_are_jumpers no)
		(fp_line
			(start 0.7874 -0.4064)
			(end -0.7874 -0.4064)
			(stroke
				(width 0.1524)
				(type default)
			)
			(layer "B.SilkS")
		)
		(fp_line
			(start -0.7874 -0.4064)
			(end -0.7874 0.4064)
			(stroke
				(width 0.1524)
				(type default)
			)
			(layer "B.SilkS")
		)
		(fp_line
			(start 0.7874 0.4064)
			(end 0.7874 -0.4064)
			(stroke
				(width 0.1524)
				(type default)
			)
			(layer "B.SilkS")
		)
		(fp_line
			(start -0.7874 0.4064)
			(end 0.7874 0.4064)
			(stroke
				(width 0.1524)
				(type default)
			)
			(layer "B.SilkS")
		)
		(fp_line
			(start 0.67945 -0.305054)
			(end 0.12065 -0.305054)
			(stroke
				(width 0.1)
				(type default)
			)
			(layer "B.Fab")
		)
		(fp_line
			(start 0.12065 -0.305054)
			(end 0.12065 -0.2794)
			(stroke
				(width 0.1)
				(type default)
			)
			(layer "B.Fab")
		)
		(fp_line
			(start -0.12065 -0.3048)
			(end -0.67945 -0.3048)
			(stroke
				(width 0.1)
				(type default)
			)
			(layer "B.Fab")
		)
		(fp_line
			(start -0.67945 -0.3048)
			(end -0.67945 0.3048)
			(stroke
				(width 0.1)
				(type default)
			)
			(layer "B.Fab")
		)
		(fp_line
			(start 0.12065 -0.2794)
			(end -0.12065 -0.2794)
			(stroke
				(width 0.1)
				(type default)
			)
			(layer "B.Fab")
		)
		(fp_line
			(start -0.12065 -0.2794)
			(end -0.12065 -0.3048)
			(stroke
				(width 0.1)
				(type default)
			)
			(layer "B.Fab")
		)
		(fp_line
			(start 0.12065 0.2794)
			(end 0.12065 0.3048)
			(stroke
				(width 0.1)
				(type default)
			)
			(layer "B.Fab")
		)
		(fp_line
			(start -0.120396 0.2794)
			(end 0.12065 0.2794)
			(stroke
				(width 0.1)
				(type default)
			)
			(layer "B.Fab")
		)
		(fp_line
			(start 0.67945 0.3048)
			(end 0.67945 -0.305054)
			(stroke
				(width 0.1)
				(type default)
			)
			(layer "B.Fab")
		)
		(fp_line
			(start 0.12065 0.3048)
			(end 0.67945 0.3048)
			(stroke
				(width 0.1)
				(type default)
			)
			(layer "B.Fab")
		)
		(fp_line
			(start -0.120396 0.3048)
			(end -0.120396 0.2794)
			(stroke
				(width 0.1)
				(type default)
			)
			(layer "B.Fab")
		)
		(fp_line
			(start -0.67945 0.3048)
			(end -0.120396 0.3048)
			(stroke
				(width 0.1)
				(type default)
			)
			(layer "B.Fab")
		)
		(pad "1" smd circle
			(at 0.40005 0 270)
			(size 0 0)
			(layers "B.Cu" "B.Mask" "B.Paste")
			(net "PVDDCR_CPU0_P0")
		)
		(pad "2" smd circle
			(at -0.40005 0 270)
			(size 0 0)
			(layers "B.Cu" "B.Mask" "B.Paste")
			(net "GND")
		)
	)
	(footprint ""
		(layer "B.Cu")
		(at 164.325554 -349.228156)
		(property "Reference" "PR6"
			(at 0 0 0)
			(layer "B.SilkS")
			(hide yes)
			(effects
				(font
					(size 1.27 1.27)
				)
				(justify mirror)
			)
		)
		(property "Value" ""
			(at 0 0 0)
			(layer "B.Fab")
			(effects
				(font
					(size 1.27 1.27)
				)
				(justify mirror)
			)
		)
		(duplicate_pad_numbers_are_jumpers no)
		(fp_line
			(start -0.7874 -0.4064)
			(end -0.7874 0.4064)
			(stroke
				(width 0.1524)
				(type default)
			)
			(layer "B.SilkS")
		)
		(fp_line
			(start -0.7874 0.4064)
			(end 0.7874 0.4064)
			(stroke
				(width 0.1524)
				(type default)
			)
			(layer "B.SilkS")
		)
		(fp_line
			(start 0.7874 -0.4064)
			(end -0.7874 -0.4064)
			(stroke
				(width 0.1524)
				(type default)
			)
			(layer "B.SilkS")
		)
		(fp_line
			(start 0.7874 0.4064)
			(end 0.7874 -0.4064)
			(stroke
				(width 0.1524)
				(type default)
			)
			(layer "B.SilkS")
		)
		(fp_line
			(start -0.67945 -0.3048)
			(end -0.67945 0.3048)
			(stroke
				(width 0.1)
				(type default)
			)
			(layer "B.Fab")
		)
		(fp_line
			(start -0.67945 0.3048)
			(end -0.120396 0.3048)
			(stroke
				(width 0.1)
				(type default)
			)
			(layer "B.Fab")
		)
		(fp_line
			(start -0.12065 -0.3048)
			(end -0.67945 -0.3048)
			(stroke
				(width 0.1)
				(type default)
			)
			(layer "B.Fab")
		)
		(fp_line
			(start -0.12065 -0.2794)
			(end -0.12065 -0.3048)
			(stroke
				(width 0.1)
				(type default)
			)
			(layer "B.Fab")
		)
		(fp_line
			(start -0.120396 0.2794)
			(end 0.12065 0.2794)
			(stroke
				(width 0.1)
				(type default)
			)
			(layer "B.Fab")
		)
		(fp_line
			(start -0.120396 0.3048)
			(end -0.120396 0.2794)
			(stroke
				(width 0.1)
				(type default)
			)
			(layer "B.Fab")
		)
		(fp_line
			(start 0.12065 -0.305054)
			(end 0.12065 -0.2794)
			(stroke
				(width 0.1)
				(type default)
			)
			(layer "B.Fab")
		)
		(fp_line
			(start 0.12065 -0.2794)
			(end -0.12065 -0.2794)
			(stroke
				(width 0.1)
				(type default)
			)
			(layer "B.Fab")
		)
		(fp_line
			(start 0.12065 0.2794)
			(end 0.12065 0.3048)
			(stroke
				(width 0.1)
				(type default)
			)
			(layer "B.Fab")
		)
		(fp_line
			(start 0.12065 0.3048)
			(end 0.67945 0.3048)
			(stroke
				(width 0.1)
				(type default)
			)
			(layer "B.Fab")
		)
		(fp_line
			(start 0.67945 -0.305054)
			(end 0.12065 -0.305054)
			(stroke
				(width 0.1)
				(type default)
			)
			(layer "B.Fab")
		)
		(fp_line
			(start 0.67945 0.3048)
			(end 0.67945 -0.305054)
			(stroke
				(width 0.1)
				(type default)
			)
			(layer "B.Fab")
		)
		(pad "1" smd circle
			(at 0.40005 0 180)
			(size 0 0)
			(layers "B.Cu" "B.Mask" "B.Paste")
			(net "PVDD11_S3_P1_VMON")
		)
		(pad "2" smd circle
			(at -0.40005 0 180)
			(size 0 0)
			(layers "B.Cu" "B.Mask" "B.Paste")
			(net "GND")
		)
	)
	(footprint ""
		(layer "B.Cu")
		(at 315.585094 -41.13784 90)
		(property "Reference" "R3942"
			(at 0 0 90)
			(layer "B.SilkS")
			(hide yes)
			(effects
				(font
					(size 1.27 1.27)
				)
				(justify mirror)
			)
		)
		(property "Value" ""
			(at 0 0 90)
			(layer "B.Fab")
			(effects
				(font
					(size 1.27 1.27)
				)
				(justify mirror)
			)
		)
		(duplicate_pad_numbers_are_jumpers no)
		(fp_line
			(start 0.7874 -0.4064)
			(end -0.7874 -0.4064)
			(stroke
				(width 0.1524)
				(type default)
			)
			(layer "B.SilkS")
		)
		(fp_line
			(start -0.7874 -0.4064)
			(end -0.7874 0.4064)
			(stroke
				(width 0.1524)
				(type default)
			)
			(layer "B.SilkS")
		)
		(fp_line
			(start 0.7874 0.4064)
			(end 0.7874 -0.4064)
			(stroke
				(width 0.1524)
				(type default)
			)
			(layer "B.SilkS")
		)
		(fp_line
			(start -0.7874 0.4064)
			(end 0.7874 0.4064)
			(stroke
				(width 0.1524)
				(type default)
			)
			(layer "B.SilkS")
		)
		(fp_line
			(start 0.67945 -0.305054)
			(end 0.12065 -0.305054)
			(stroke
				(width 0.1)
				(type default)
			)
			(layer "B.Fab")
		)
		(fp_line
			(start 0.12065 -0.305054)
			(end 0.12065 -0.2794)
			(stroke
				(width 0.1)
				(type default)
			)
			(layer "B.Fab")
		)
		(fp_line
			(start -0.12065 -0.3048)
			(end -0.67945 -0.3048)
			(stroke
				(width 0.1)
				(type default)
			)
			(layer "B.Fab")
		)
		(fp_line
			(start -0.67945 -0.3048)
			(end -0.67945 0.3048)
			(stroke
				(width 0.1)
				(type default)
			)
			(layer "B.Fab")
		)
		(fp_line
			(start 0.12065 -0.2794)
			(end -0.12065 -0.2794)
			(stroke
				(width 0.1)
				(type default)
			)
			(layer "B.Fab")
		)
		(fp_line
			(start -0.12065 -0.2794)
			(end -0.12065 -0.3048)
			(stroke
				(width 0.1)
				(type default)
			)
			(layer "B.Fab")
		)
		(fp_line
			(start 0.12065 0.2794)
			(end 0.12065 0.3048)
			(stroke
				(width 0.1)
				(type default)
			)
			(layer "B.Fab")
		)
		(fp_line
			(start -0.120396 0.2794)
			(end 0.12065 0.2794)
			(stroke
				(width 0.1)
				(type default)
			)
			(layer "B.Fab")
		)
		(fp_line
			(start 0.67945 0.3048)
			(end 0.67945 -0.305054)
			(stroke
				(width 0.1)
				(type default)
			)
			(layer "B.Fab")
		)
		(fp_line
			(start 0.12065 0.3048)
			(end 0.67945 0.3048)
			(stroke
				(width 0.1)
				(type default)
			)
			(layer "B.Fab")
		)
		(fp_line
			(start -0.120396 0.3048)
			(end -0.120396 0.2794)
			(stroke
				(width 0.1)
				(type default)
			)
			(layer "B.Fab")
		)
		(fp_line
			(start -0.67945 0.3048)
			(end -0.120396 0.3048)
			(stroke
				(width 0.1)
				(type default)
			)
			(layer "B.Fab")
		)
		(pad "1" smd rect
			(at 0.40005 0 90)
			(size 0.4572 0.508)
			(layers "B.Cu" "B.Mask" "B.Paste")
			(net "P12V_E1S_0_ISENSE_MPS_TIC")
		)
		(pad "2" smd rect
			(at -0.40005 0 90)
			(size 0.4572 0.508)
			(layers "B.Cu" "B.Mask" "B.Paste")
			(net "P12V_E1S_0_ISENSE_TIC")
		)
	)
	(footprint ""
		(layer "B.Cu")
		(at 152.202642 -76.72324)
		(property "Reference" "PC850"
			(at 0 0 0)
			(layer "B.SilkS")
			(hide yes)
			(effects
				(font
					(size 1.27 1.27)
				)
				(justify mirror)
			)
		)
		(property "Value" ""
			(at 0 0 0)
			(layer "B.Fab")
			(effects
				(font
					(size 1.27 1.27)
				)
				(justify mirror)
			)
		)
		(duplicate_pad_numbers_are_jumpers no)
		(fp_line
			(start -1.524 -0.762)
			(end -1.524 0.762)
			(stroke
				(width 0.1524)
				(type default)
			)
			(layer "B.SilkS")
		)
		(fp_line
			(start -1.524 0.762)
			(end 1.524 0.762)
			(stroke
				(width 0.1524)
				(type default)
			)
			(layer "B.SilkS")
		)
		(fp_line
			(start 1.524 -0.762)
			(end -1.524 -0.762)
			(stroke
				(width 0.1524)
				(type default)
			)
			(layer "B.SilkS")
		)
		(fp_line
			(start 1.524 0.762)
			(end 1.524 -0.762)
			(stroke
				(width 0.1524)
				(type default)
			)
			(layer "B.SilkS")
		)
		(fp_line
			(start -1.1049 -0.724916)
			(end 1.1049 -0.724916)
			(stroke
				(width 0.1)
				(type default)
			)
			(layer "B.Fab")
		)
		(fp_line
			(start -1.1049 0.724916)
			(end -1.1049 -0.724916)
			(stroke
				(width 0.1)
				(type default)
			)
			(layer "B.Fab")
		)
		(fp_line
			(start 1.1049 -0.724916)
			(end 1.1049 0.724916)
			(stroke
				(width 0.1)
				(type default)
			)
			(layer "B.Fab")
		)
		(fp_line
			(start 1.1049 0.724916)
			(end -1.1049 0.724916)
			(stroke
				(width 0.1)
				(type default)
			)
			(layer "B.Fab")
		)
		(pad "1" smd rect
			(at 0.889 0)
			(size 1.016 1.27)
			(layers "B.Cu" "B.Mask" "B.Paste")
			(net "P1V8_AUX")
		)
		(pad "2" smd rect
			(at -0.889 0)
			(size 1.016 1.27)
			(layers "B.Cu" "B.Mask" "B.Paste")
			(net "GND")
		)
	)
	(footprint ""
		(layer "B.Cu")
		(at 116.880386 -269.307564)
		(property "Reference" "C2365"
			(at 0 0 0)
			(layer "B.SilkS")
			(hide yes)
			(effects
				(font
					(size 1.27 1.27)
				)
				(justify mirror)
			)
		)
		(property "Value" ""
			(at 0 0 0)
			(layer "B.Fab")
			(effects
				(font
					(size 1.27 1.27)
				)
				(justify mirror)
			)
		)
		(duplicate_pad_numbers_are_jumpers no)
		(fp_line
			(start -0.7874 -0.4064)
			(end -0.7874 0.4064)
			(stroke
				(width 0.1524)
				(type default)
			)
			(layer "B.SilkS")
		)
		(fp_line
			(start -0.7874 0.4064)
			(end 0.7874 0.4064)
			(stroke
				(width 0.1524)
				(type default)
			)
			(layer "B.SilkS")
		)
		(fp_line
			(start 0.7874 -0.4064)
			(end -0.7874 -0.4064)
			(stroke
				(width 0.1524)
				(type default)
			)
			(layer "B.SilkS")
		)
		(fp_line
			(start 0.7874 0.4064)
			(end 0.7874 -0.4064)
			(stroke
				(width 0.1524)
				(type default)
			)
			(layer "B.SilkS")
		)
		(fp_line
			(start -0.67945 -0.3048)
			(end -0.67945 0.3048)
			(stroke
				(width 0.1)
				(type default)
			)
			(layer "B.Fab")
		)
		(fp_line
			(start -0.67945 0.3048)
			(end -0.120396 0.3048)
			(stroke
				(width 0.1)
				(type default)
			)
			(layer "B.Fab")
		)
		(fp_line
			(start -0.12065 -0.3048)
			(end -0.67945 -0.3048)
			(stroke
				(width 0.1)
				(type default)
			)
			(layer "B.Fab")
		)
		(fp_line
			(start -0.12065 -0.2794)
			(end -0.12065 -0.3048)
			(stroke
				(width 0.1)
				(type default)
			)
			(layer "B.Fab")
		)
		(fp_line
			(start -0.120396 0.2794)
			(end 0.12065 0.2794)
			(stroke
				(width 0.1)
				(type default)
			)
			(layer "B.Fab")
		)
		(fp_line
			(start -0.120396 0.3048)
			(end -0.120396 0.2794)
			(stroke
				(width 0.1)
				(type default)
			)
			(layer "B.Fab")
		)
		(fp_line
			(start 0.12065 -0.305054)
			(end 0.12065 -0.2794)
			(stroke
				(width 0.1)
				(type default)
			)
			(layer "B.Fab")
		)
		(fp_line
			(start 0.12065 -0.2794)
			(end -0.12065 -0.2794)
			(stroke
				(width 0.1)
				(type default)
			)
			(layer "B.Fab")
		)
		(fp_line
			(start 0.12065 0.2794)
			(end 0.12065 0.3048)
			(stroke
				(width 0.1)
				(type default)
			)
			(layer "B.Fab")
		)
		(fp_line
			(start 0.12065 0.3048)
			(end 0.67945 0.3048)
			(stroke
				(width 0.1)
				(type default)
			)
			(layer "B.Fab")
		)
		(fp_line
			(start 0.67945 -0.305054)
			(end 0.12065 -0.305054)
			(stroke
				(width 0.1)
				(type default)
			)
			(layer "B.Fab")
		)
		(fp_line
			(start 0.67945 0.3048)
			(end 0.67945 -0.305054)
			(stroke
				(width 0.1)
				(type default)
			)
			(layer "B.Fab")
		)
		(pad "1" smd circle
			(at 0.40005 0 180)
			(size 0 0)
			(layers "B.Cu" "B.Mask" "B.Paste")
			(net "PVDDCR_CPU1_P1")
		)
		(pad "2" smd circle
			(at -0.40005 0 180)
			(size 0 0)
			(layers "B.Cu" "B.Mask" "B.Paste")
			(net "GND")
		)
	)
	(footprint ""
		(layer "B.Cu")
		(at 365.064294 -184.48909 90)
		(property "Reference" "PC494"
			(at 5.894324 -1.181862 270)
			(unlocked yes)
			(layer "B.SilkS")
			(effects
				(font
					(size 0.7874 0.5842)
					(thickness 0.1524)
				)
				(justify left mirror)
			)
		)
		(property "Value" ""
			(at 0 0 90)
			(layer "B.Fab")
			(effects
				(font
					(size 1.27 1.27)
				)
				(justify mirror)
			)
		)
		(duplicate_pad_numbers_are_jumpers no)
		(fp_line
			(start 4.533392 -2.249932)
			(end -4.533392 -2.249932)
			(stroke
				(width 0.1524)
				(type default)
			)
			(layer "B.SilkS")
		)
		(fp_line
			(start -4.533392 -2.249932)
			(end -4.533392 2.249932)
			(stroke
				(width 0.1524)
				(type default)
			)
			(layer "B.SilkS")
		)
		(fp_line
			(start 4.533392 2.249932)
			(end 4.533392 -2.249932)
			(stroke
				(width 0.1524)
				(type default)
			)
			(layer "B.SilkS")
		)
		(fp_line
			(start -4.533392 2.249932)
			(end 4.533392 2.249932)
			(stroke
				(width 0.1524)
				(type default)
			)
			(layer "B.SilkS")
		)
		(fp_rect
			(start 4.533392 -2.326132)
			(end 5.39242 2.326132)
			(stroke
				(width 0)
				(type default)
			)
			(fill yes)
			(layer "B.SilkS")
		)
		(fp_line
			(start 3.750056 -2.249932)
			(end -3.750056 -2.249932)
			(stroke
				(width 0.1)
				(type default)
			)
			(layer "B.Fab")
		)
		(fp_line
			(start -3.750056 -2.249932)
			(end -3.750056 2.249932)
			(stroke
				(width 0.1)
				(type default)
			)
			(layer "B.Fab")
		)
		(fp_line
			(start 3.750056 2.249932)
			(end 3.750056 -2.249932)
			(stroke
				(width 0.1)
				(type default)
			)
			(layer "B.Fab")
		)
		(fp_line
			(start -3.750056 2.249932)
			(end 3.750056 2.249932)
			(stroke
				(width 0.1)
				(type default)
			)
			(layer "B.Fab")
		)
		(fp_text user "-"
			(at -4.8514 -0.14605 90)
			(unlocked yes)
			(layer "B.SilkS")
			(effects
				(font
					(size 1.905 1.4224)
					(thickness 0.1524)
				)
				(justify left mirror)
			)
		)
		(fp_text user "+"
			(at 6.322314 0.786384 0)
			(unlocked yes)
			(layer "B.SilkS")
			(effects
				(font
					(size 1.905 1.4224)
					(thickness 0.1524)
				)
				(justify left mirror)
			)
		)
		(fp_text user "-"
			(at -4.8514 -0.14605 90)
			(unlocked yes)
			(layer "B.Fab")
			(effects
				(font
					(size 1.905 1.4224)
					(thickness 0.1524)
				)
				(justify left mirror)
			)
		)
		(fp_text user "+"
			(at 6.322314 0.786384 0)
			(unlocked yes)
			(layer "B.Fab")
			(effects
				(font
					(size 1.905 1.4224)
					(thickness 0.1524)
				)
				(justify left mirror)
			)
		)
		(pad "1" smd rect
			(at 3.199892 0 270)
			(size 2.413 2.8194)
			(layers "B.Cu" "B.Mask" "B.Paste")
			(net "PVDDCR_CPU0_P0")
		)
		(pad "2" smd rect
			(at -3.199892 0 270)
			(size 2.413 2.8194)
			(layers "B.Cu" "B.Mask" "B.Paste")
			(net "GND")
		)
	)
	(footprint ""
		(layer "B.Cu")
		(at 191.160146 -192.66027)
		(property "Reference" "C536"
			(at 0 0 0)
			(layer "B.SilkS")
			(hide yes)
			(effects
				(font
					(size 1.27 1.27)
				)
				(justify mirror)
			)
		)
		(property "Value" ""
			(at 0 0 0)
			(layer "B.Fab")
			(effects
				(font
					(size 1.27 1.27)
				)
				(justify mirror)
			)
		)
		(duplicate_pad_numbers_are_jumpers no)
		(fp_line
			(start -1.524 -0.762)
			(end -1.524 0.762)
			(stroke
				(width 0.1524)
				(type default)
			)
			(layer "B.SilkS")
		)
		(fp_line
			(start -1.524 0.762)
			(end 1.524 0.762)
			(stroke
				(width 0.1524)
				(type default)
			)
			(layer "B.SilkS")
		)
		(fp_line
			(start 1.524 -0.762)
			(end -1.524 -0.762)
			(stroke
				(width 0.1524)
				(type default)
			)
			(layer "B.SilkS")
		)
		(fp_line
			(start 1.524 0.762)
			(end 1.524 -0.762)
			(stroke
				(width 0.1524)
				(type default)
			)
			(layer "B.SilkS")
		)
		(fp_line
			(start -1.1049 -0.724916)
			(end 1.1049 -0.724916)
			(stroke
				(width 0.1)
				(type default)
			)
			(layer "B.Fab")
		)
		(fp_line
			(start -1.1049 0.724916)
			(end -1.1049 -0.724916)
			(stroke
				(width 0.1)
				(type default)
			)
			(layer "B.Fab")
		)
		(fp_line
			(start 1.1049 -0.724916)
			(end 1.1049 0.724916)
			(stroke
				(width 0.1)
				(type default)
			)
			(layer "B.Fab")
		)
		(fp_line
			(start 1.1049 0.724916)
			(end -1.1049 0.724916)
			(stroke
				(width 0.1)
				(type default)
			)
			(layer "B.Fab")
		)
		(pad "1" smd rect
			(at 0.889 0)
			(size 1.016 1.27)
			(layers "B.Cu" "B.Mask" "B.Paste")
			(net "P12V_MEM_CPU1")
		)
		(pad "2" smd rect
			(at -0.889 0)
			(size 1.016 1.27)
			(layers "B.Cu" "B.Mask" "B.Paste")
			(net "GND")
		)
	)
	(footprint ""
		(layer "B.Cu")
		(at 137.352278 -384.575558)
		(property "Reference" "L9"
			(at 0 0 0)
			(layer "B.SilkS")
			(hide yes)
			(effects
				(font
					(size 1.27 1.27)
				)
				(justify mirror)
			)
		)
		(property "Value" ""
			(at 0 0 0)
			(layer "B.Fab")
			(effects
				(font
					(size 1.27 1.27)
				)
				(justify mirror)
			)
		)
		(duplicate_pad_numbers_are_jumpers no)
		(fp_line
			(start -1.63576 -0.8128)
			(end -1.63576 0.8128)
			(stroke
				(width 0.1524)
				(type default)
			)
			(layer "B.SilkS")
		)
		(fp_line
			(start -1.63576 0.8128)
			(end 1.63576 0.8128)
			(stroke
				(width 0.1524)
				(type default)
			)
			(layer "B.SilkS")
		)
		(fp_line
			(start 1.63576 -0.8128)
			(end -1.63576 -0.8128)
			(stroke
				(width 0.1524)
				(type default)
			)
			(layer "B.SilkS")
		)
		(fp_line
			(start 1.63576 -0.8128)
			(end 1.63576 0.8128)
			(stroke
				(width 0.1524)
				(type default)
			)
			(layer "B.SilkS")
		)
		(fp_line
			(start -1.560576 -0.738632)
			(end 1.56083 -0.738632)
			(stroke
				(width 0.1)
				(type default)
			)
			(layer "B.Fab")
		)
		(fp_line
			(start -1.560576 0.7366)
			(end -1.560576 -0.738632)
			(stroke
				(width 0.1)
				(type default)
			)
			(layer "B.Fab")
		)
		(fp_line
			(start -1.524 0.7366)
			(end -1.560576 0.7366)
			(stroke
				(width 0.1)
				(type default)
			)
			(layer "B.Fab")
		)
		(fp_line
			(start 1.524 0.7366)
			(end -1.524 0.7366)
			(stroke
				(width 0.1)
				(type default)
			)
			(layer "B.Fab")
		)
		(fp_line
			(start 1.56083 -0.738632)
			(end 1.56083 0.7366)
			(stroke
				(width 0.1)
				(type default)
			)
			(layer "B.Fab")
		)
		(fp_line
			(start 1.56083 0.7366)
			(end 1.524 0.7366)
			(stroke
				(width 0.1)
				(type default)
			)
			(layer "B.Fab")
		)
		(pad "1" smd rect
			(at 0.94996 0)
			(size 1.1176 1.3716)
			(layers "B.Cu" "B.Mask" "B.Paste")
			(net "P1V8_CPU1_RT_1D")
		)
		(pad "2" smd rect
			(at -0.94996 0)
			(size 1.1176 1.3716)
			(layers "B.Cu" "B.Mask" "B.Paste")
			(net "P1V8_CPU1_RT3_1A")
		)
	)
	(footprint ""
		(layer "B.Cu")
		(at 368.54892 -425.775882 90)
		(property "Reference" "R839"
			(at 0 0 90)
			(layer "B.SilkS")
			(hide yes)
			(effects
				(font
					(size 1.27 1.27)
				)
				(justify mirror)
			)
		)
		(property "Value" ""
			(at 0 0 90)
			(layer "B.Fab")
			(effects
				(font
					(size 1.27 1.27)
				)
				(justify mirror)
			)
		)
		(duplicate_pad_numbers_are_jumpers no)
		(fp_line
			(start 0.32512 -0.175006)
			(end -0.32512 -0.175006)
			(stroke
				(width 0.1)
				(type default)
			)
			(layer "B.Fab")
		)
		(fp_line
			(start -0.32512 -0.175006)
			(end -0.32512 0.175006)
			(stroke
				(width 0.1)
				(type default)
			)
			(layer "B.Fab")
		)
		(fp_line
			(start 0.32512 0.175006)
			(end 0.32512 -0.175006)
			(stroke
				(width 0.1)
				(type default)
			)
			(layer "B.Fab")
		)
		(fp_line
			(start -0.32512 0.175006)
			(end 0.32512 0.175006)
			(stroke
				(width 0.1)
				(type default)
			)
			(layer "B.Fab")
		)
		(pad "1" smd rect
			(at 0.2667 0 270)
			(size 0.3048 0.381)
			(layers "B.Cu" "B.Mask" "B.Paste")
			(net "P1V8_CPU0_RT_1D")
		)
		(pad "2" smd rect
			(at -0.2667 0 90)
			(size 0.3048 0.381)
			(layers "B.Cu" "B.Mask" "B.Paste")
			(net "SMB_RT_CPU0_P3_ROM_R_SCL")
		)
	)
	(footprint ""
		(layer "B.Cu")
		(at 64.178688 -386.766562 90)
		(property "Reference" "C285"
			(at 0 0 90)
			(layer "B.SilkS")
			(hide yes)
			(effects
				(font
					(size 1.27 1.27)
				)
				(justify mirror)
			)
		)
		(property "Value" ""
			(at 0 0 90)
			(layer "B.Fab")
			(effects
				(font
					(size 1.27 1.27)
				)
				(justify mirror)
			)
		)
		(duplicate_pad_numbers_are_jumpers no)
		(fp_line
			(start 0.299974 -0.150114)
			(end -0.299974 -0.150114)
			(stroke
				(width 0.1)
				(type default)
			)
			(layer "B.Fab")
		)
		(fp_line
			(start -0.299974 -0.150114)
			(end -0.299974 0.150114)
			(stroke
				(width 0.1)
				(type default)
			)
			(layer "B.Fab")
		)
		(fp_line
			(start 0.299974 0.150114)
			(end 0.299974 -0.150114)
			(stroke
				(width 0.1)
				(type default)
			)
			(layer "B.Fab")
		)
		(fp_line
			(start -0.299974 0.150114)
			(end 0.299974 0.150114)
			(stroke
				(width 0.1)
				(type default)
			)
			(layer "B.Fab")
		)
		(pad "1" smd rect
			(at 0.2667 0 270)
			(size 0.3048 0.381)
			(layers "B.Cu" "B.Mask" "B.Paste")
			(net "P0V9_CPU1_RT0_2A")
		)
		(pad "2" smd rect
			(at -0.2667 0 270)
			(size 0.3048 0.381)
			(layers "B.Cu" "B.Mask" "B.Paste")
			(net "GND")
		)
	)
	(footprint ""
		(layer "B.Cu")
		(at 176.543208 -127.643636 180)
		(property "Reference" "R255"
			(at 0 0 0)
			(layer "B.SilkS")
			(hide yes)
			(effects
				(font
					(size 1.27 1.27)
				)
				(justify mirror)
			)
		)
		(property "Value" ""
			(at 0 0 0)
			(layer "B.Fab")
			(effects
				(font
					(size 1.27 1.27)
				)
				(justify mirror)
			)
		)
		(duplicate_pad_numbers_are_jumpers no)
		(fp_line
			(start 0.7874 0.4064)
			(end 0.7874 -0.4064)
			(stroke
				(width 0.1524)
				(type default)
			)
			(layer "B.SilkS")
		)
		(fp_line
			(start 0.7874 -0.4064)
			(end -0.7874 -0.4064)
			(stroke
				(width 0.1524)
				(type default)
			)
			(layer "B.SilkS")
		)
		(fp_line
			(start -0.7874 0.4064)
			(end 0.7874 0.4064)
			(stroke
				(width 0.1524)
				(type default)
			)
			(layer "B.SilkS")
		)
		(fp_line
			(start -0.7874 -0.4064)
			(end -0.7874 0.4064)
			(stroke
				(width 0.1524)
				(type default)
			)
			(layer "B.SilkS")
		)
		(fp_line
			(start 0.67945 0.3048)
			(end 0.67945 -0.305054)
			(stroke
				(width 0.1)
				(type default)
			)
			(layer "B.Fab")
		)
		(fp_line
			(start 0.67945 -0.305054)
			(end 0.12065 -0.305054)
			(stroke
				(width 0.1)
				(type default)
			)
			(layer "B.Fab")
		)
		(fp_line
			(start 0.12065 0.3048)
			(end 0.67945 0.3048)
			(stroke
				(width 0.1)
				(type default)
			)
			(layer "B.Fab")
		)
		(fp_line
			(start 0.12065 0.2794)
			(end 0.12065 0.3048)
			(stroke
				(width 0.1)
				(type default)
			)
			(layer "B.Fab")
		)
		(fp_line
			(start 0.12065 -0.2794)
			(end -0.12065 -0.2794)
			(stroke
				(width 0.1)
				(type default)
			)
			(layer "B.Fab")
		)
		(fp_line
			(start 0.12065 -0.305054)
			(end 0.12065 -0.2794)
			(stroke
				(width 0.1)
				(type default)
			)
			(layer "B.Fab")
		)
		(fp_line
			(start -0.120396 0.3048)
			(end -0.120396 0.2794)
			(stroke
				(width 0.1)
				(type default)
			)
			(layer "B.Fab")
		)
		(fp_line
			(start -0.120396 0.2794)
			(end 0.12065 0.2794)
			(stroke
				(width 0.1)
				(type default)
			)
			(layer "B.Fab")
		)
		(fp_line
			(start -0.12065 -0.2794)
			(end -0.12065 -0.3048)
			(stroke
				(width 0.1)
				(type default)
			)
			(layer "B.Fab")
		)
		(fp_line
			(start -0.12065 -0.3048)
			(end -0.67945 -0.3048)
			(stroke
				(width 0.1)
				(type default)
			)
			(layer "B.Fab")
		)
		(fp_line
			(start -0.67945 0.3048)
			(end -0.120396 0.3048)
			(stroke
				(width 0.1)
				(type default)
			)
			(layer "B.Fab")
		)
		(fp_line
			(start -0.67945 -0.3048)
			(end -0.67945 0.3048)
			(stroke
				(width 0.1)
				(type default)
			)
			(layer "B.Fab")
		)
		(pad "1" smd circle
			(at 0.40005 0)
			(size 0 0)
			(layers "B.Cu" "B.Mask" "B.Paste")
			(net "RST_CPU0_PERST1_N")
		)
		(pad "2" smd circle
			(at -0.40005 0)
			(size 0 0)
			(layers "B.Cu" "B.Mask" "B.Paste")
			(net "RST_CPU0_PERST1_R_N")
		)
	)
	(footprint ""
		(layer "B.Cu")
		(at 394.335 -185.63336 90)
		(property "Reference" "PC604_1"
			(at 0 0 90)
			(layer "B.SilkS")
			(hide yes)
			(effects
				(font
					(size 1.27 1.27)
				)
				(justify mirror)
			)
		)
		(property "Value" ""
			(at 0 0 90)
			(layer "B.Fab")
			(effects
				(font
					(size 1.27 1.27)
				)
				(justify mirror)
			)
		)
		(duplicate_pad_numbers_are_jumpers no)
		(fp_line
			(start 1.524 -0.762)
			(end -1.524 -0.762)
			(stroke
				(width 0.1524)
				(type default)
			)
			(layer "B.SilkS")
		)
		(fp_line
			(start -1.524 -0.762)
			(end -1.524 0.762)
			(stroke
				(width 0.1524)
				(type default)
			)
			(layer "B.SilkS")
		)
		(fp_line
			(start 1.524 0.762)
			(end 1.524 -0.762)
			(stroke
				(width 0.1524)
				(type default)
			)
			(layer "B.SilkS")
		)
		(fp_line
			(start -1.524 0.762)
			(end 1.524 0.762)
			(stroke
				(width 0.1524)
				(type default)
			)
			(layer "B.SilkS")
		)
		(fp_line
			(start 1.1049 -0.724916)
			(end 1.1049 0.724916)
			(stroke
				(width 0.1)
				(type default)
			)
			(layer "B.Fab")
		)
		(fp_line
			(start -1.1049 -0.724916)
			(end 1.1049 -0.724916)
			(stroke
				(width 0.1)
				(type default)
			)
			(layer "B.Fab")
		)
		(fp_line
			(start 1.1049 0.724916)
			(end -1.1049 0.724916)
			(stroke
				(width 0.1)
				(type default)
			)
			(layer "B.Fab")
		)
		(fp_line
			(start -1.1049 0.724916)
			(end -1.1049 -0.724916)
			(stroke
				(width 0.1)
				(type default)
			)
			(layer "B.Fab")
		)
		(pad "1" smd rect
			(at 0.889 0 90)
			(size 1.016 1.27)
			(layers "B.Cu" "B.Mask" "B.Paste")
			(net "PVDDCR_SOC_P0")
		)
		(pad "2" smd rect
			(at -0.889 0 90)
			(size 1.016 1.27)
			(layers "B.Cu" "B.Mask" "B.Paste")
			(net "GND")
		)
	)
	(footprint ""
		(layer "B.Cu")
		(at 113.919 -417.576)
		(property "Reference" "Q108"
			(at 0.311658 -2.625598 0)
			(unlocked yes)
			(layer "B.SilkS")
			(effects
				(font
					(size 0.7874 0.5842)
					(thickness 0.1524)
				)
				(justify left mirror)
			)
		)
		(property "Value" ""
			(at 0 0 0)
			(layer "B.Fab")
			(effects
				(font
					(size 1.27 1.27)
				)
				(justify mirror)
			)
		)
		(duplicate_pad_numbers_are_jumpers no)
		(fp_line
			(start -1.332738 -1.100074)
			(end -1.332738 1.100074)
			(stroke
				(width 0.1524)
				(type default)
			)
			(layer "B.SilkS")
		)
		(fp_line
			(start -1.332738 1.100074)
			(end 1.332738 1.100074)
			(stroke
				(width 0.1524)
				(type default)
			)
			(layer "B.SilkS")
		)
		(fp_line
			(start -0.4826 -1.100074)
			(end -1.332738 -1.100074)
			(stroke
				(width 0.1524)
				(type default)
			)
			(layer "B.SilkS")
		)
		(fp_line
			(start 0 -0.541274)
			(end -0.4826 -1.100074)
			(stroke
				(width 0.1524)
				(type default)
			)
			(layer "B.SilkS")
		)
		(fp_line
			(start 0.4826 -1.100074)
			(end 0 -0.541274)
			(stroke
				(width 0.1524)
				(type default)
			)
			(layer "B.SilkS")
		)
		(fp_line
			(start 1.332738 -1.100074)
			(end 0.4826 -1.100074)
			(stroke
				(width 0.1524)
				(type default)
			)
			(layer "B.SilkS")
		)
		(fp_line
			(start 1.332738 1.100074)
			(end 1.332738 -1.100074)
			(stroke
				(width 0.1524)
				(type default)
			)
			(layer "B.SilkS")
		)
		(fp_poly
			(pts
				(xy 0.914146 -1.289558) (xy 1.257554 -1.99517) (xy 0.555752 -1.987804)
			)
			(stroke
				(width 0)
				(type default)
			)
			(fill yes)
			(layer "B.SilkS")
		)
		(fp_line
			(start -0.674878 -1.100074)
			(end -0.674878 1.100074)
			(stroke
				(width 0.1)
				(type default)
			)
			(layer "B.Fab")
		)
		(fp_line
			(start -0.674878 1.100074)
			(end 0.674878 1.100074)
			(stroke
				(width 0.1)
				(type default)
			)
			(layer "B.Fab")
		)
		(fp_line
			(start 0.674878 -1.100074)
			(end -0.674878 -1.100074)
			(stroke
				(width 0.1)
				(type default)
			)
			(layer "B.Fab")
		)
		(fp_line
			(start 0.674878 1.100074)
			(end 0.674878 -1.100074)
			(stroke
				(width 0.1)
				(type default)
			)
			(layer "B.Fab")
		)
		(fp_poly
			(pts
				(xy 2.2352 -0.298958) (xy 2.2352 -1.001014) (xy 1.533144 -0.649986)
			)
			(stroke
				(width 0)
				(type default)
			)
			(fill yes)
			(layer "B.Fab")
		)
		(pad "1" smd rect
			(at 0.94996 -0.649986 90)
			(size 0.4318 0.508)
			(layers "B.Cu" "B.Mask" "B.Paste")
			(net "GND")
		)
		(pad "2" smd rect
			(at 0.94996 0 90)
			(size 0.4318 0.508)
			(layers "B.Cu" "B.Mask" "B.Paste")
			(net "GPU_FPGA_EROT_FATALERR_N")
		)
		(pad "3" smd rect
			(at 0.94996 0.649986 90)
			(size 0.4318 0.508)
			(layers "B.Cu" "B.Mask" "B.Paste")
			(net "GPU_FPGA_EROT_FATALERR_ISO_N")
		)
		(pad "4" smd rect
			(at -0.94996 0.649986 90)
			(size 0.4318 0.508)
			(layers "B.Cu" "B.Mask" "B.Paste")
			(net "GND")
		)
		(pad "5" smd rect
			(at -0.94996 0 90)
			(size 0.4318 0.508)
			(layers "B.Cu" "B.Mask" "B.Paste")
			(net "GPU_FPGA_EROT_FATALERR")
		)
		(pad "6" smd rect
			(at -0.94996 -0.649986 90)
			(size 0.4318 0.508)
			(layers "B.Cu" "B.Mask" "B.Paste")
			(net "GPU_FPGA_EROT_FATALERR")
		)
	)
	(footprint ""
		(layer "B.Cu")
		(at 231.648 -337.439 90)
		(property "Reference" "R6766"
			(at 0 0 90)
			(layer "B.SilkS")
			(hide yes)
			(effects
				(font
					(size 1.27 1.27)
				)
				(justify mirror)
			)
		)
		(property "Value" ""
			(at 0 0 90)
			(layer "B.Fab")
			(effects
				(font
					(size 1.27 1.27)
				)
				(justify mirror)
			)
		)
		(duplicate_pad_numbers_are_jumpers no)
		(fp_line
			(start 0.32512 -0.175006)
			(end -0.32512 -0.175006)
			(stroke
				(width 0.1)
				(type default)
			)
			(layer "B.Fab")
		)
		(fp_line
			(start -0.32512 -0.175006)
			(end -0.32512 0.175006)
			(stroke
				(width 0.1)
				(type default)
			)
			(layer "B.Fab")
		)
		(fp_line
			(start 0.32512 0.175006)
			(end 0.32512 -0.175006)
			(stroke
				(width 0.1)
				(type default)
			)
			(layer "B.Fab")
		)
		(fp_line
			(start -0.32512 0.175006)
			(end 0.32512 0.175006)
			(stroke
				(width 0.1)
				(type default)
			)
			(layer "B.Fab")
		)
		(pad "1" smd rect
			(at 0.2667 0 270)
			(size 0.3048 0.381)
			(layers "B.Cu" "B.Mask" "B.Paste")
			(net "P1V8_CPU0_RT_1D")
		)
		(pad "2" smd rect
			(at -0.2667 0 90)
			(size 0.3048 0.381)
			(layers "B.Cu" "B.Mask" "B.Paste")
			(net "SMB_RT_CPU0_P3_R_SDA")
		)
	)
	(footprint ""
		(layer "B.Cu")
		(at 65.530984 -408.517344 90)
		(property "Reference" "C6671"
			(at 0 0 90)
			(layer "B.SilkS")
			(hide yes)
			(effects
				(font
					(size 1.27 1.27)
				)
				(justify mirror)
			)
		)
		(property "Value" ""
			(at 0 0 90)
			(layer "B.Fab")
			(effects
				(font
					(size 1.27 1.27)
				)
				(justify mirror)
			)
		)
		(duplicate_pad_numbers_are_jumpers no)
		(fp_line
			(start 0.299974 -0.150114)
			(end -0.299974 -0.150114)
			(stroke
				(width 0.1)
				(type default)
			)
			(layer "B.Fab")
		)
		(fp_line
			(start -0.299974 -0.150114)
			(end -0.299974 0.150114)
			(stroke
				(width 0.1)
				(type default)
			)
			(layer "B.Fab")
		)
		(fp_line
			(start 0.299974 0.150114)
			(end 0.299974 -0.150114)
			(stroke
				(width 0.1)
				(type default)
			)
			(layer "B.Fab")
		)
		(fp_line
			(start -0.299974 0.150114)
			(end 0.299974 0.150114)
			(stroke
				(width 0.1)
				(type default)
			)
			(layer "B.Fab")
		)
		(pad "1" smd rect
			(at 0.2667 0 270)
			(size 0.3048 0.381)
			(layers "B.Cu" "B.Mask" "B.Paste")
			(net "P5E_CPU1_P1_TX_BUF_C_DP<5>")
		)
		(pad "2" smd rect
			(at -0.2667 0 270)
			(size 0.3048 0.381)
			(layers "B.Cu" "B.Mask" "B.Paste")
			(net "P5E_CPU1_P1_TX_BUF_DP<5>")
		)
	)
	(footprint ""
		(layer "B.Cu")
		(at 247.651778 -315.95568 -90)
		(property "Reference" "PC6509"
			(at 0 0 90)
			(layer "B.SilkS")
			(hide yes)
			(effects
				(font
					(size 1.27 1.27)
				)
				(justify mirror)
			)
		)
		(property "Value" ""
			(at 0 0 90)
			(layer "B.Fab")
			(effects
				(font
					(size 1.27 1.27)
				)
				(justify mirror)
			)
		)
		(duplicate_pad_numbers_are_jumpers no)
		(fp_line
			(start -1.524 0.762)
			(end 1.524 0.762)
			(stroke
				(width 0.1524)
				(type default)
			)
			(layer "B.SilkS")
		)
		(fp_line
			(start 1.524 0.762)
			(end 1.524 -0.762)
			(stroke
				(width 0.1524)
				(type default)
			)
			(layer "B.SilkS")
		)
		(fp_line
			(start -1.524 -0.762)
			(end -1.524 0.762)
			(stroke
				(width 0.1524)
				(type default)
			)
			(layer "B.SilkS")
		)
		(fp_line
			(start 1.524 -0.762)
			(end -1.524 -0.762)
			(stroke
				(width 0.1524)
				(type default)
			)
			(layer "B.SilkS")
		)
		(fp_line
			(start -1.1049 0.724916)
			(end -1.1049 -0.724916)
			(stroke
				(width 0.1)
				(type default)
			)
			(layer "B.Fab")
		)
		(fp_line
			(start 1.1049 0.724916)
			(end -1.1049 0.724916)
			(stroke
				(width 0.1)
				(type default)
			)
			(layer "B.Fab")
		)
		(fp_line
			(start -1.1049 -0.724916)
			(end 1.1049 -0.724916)
			(stroke
				(width 0.1)
				(type default)
			)
			(layer "B.Fab")
		)
		(fp_line
			(start 1.1049 -0.724916)
			(end 1.1049 0.724916)
			(stroke
				(width 0.1)
				(type default)
			)
			(layer "B.Fab")
		)
		(pad "1" smd rect
			(at 0.889 0 270)
			(size 1.016 1.27)
			(layers "B.Cu" "B.Mask" "B.Paste")
			(net "P1V8_CPU0_RT_1D")
		)
		(pad "2" smd rect
			(at -0.889 0 270)
			(size 1.016 1.27)
			(layers "B.Cu" "B.Mask" "B.Paste")
			(net "GND")
		)
	)
	(footprint ""
		(layer "B.Cu")
		(at 102.783386 -269.307564)
		(property "Reference" "C2393"
			(at 0 0 0)
			(layer "B.SilkS")
			(hide yes)
			(effects
				(font
					(size 1.27 1.27)
				)
				(justify mirror)
			)
		)
		(property "Value" ""
			(at 0 0 0)
			(layer "B.Fab")
			(effects
				(font
					(size 1.27 1.27)
				)
				(justify mirror)
			)
		)
		(duplicate_pad_numbers_are_jumpers no)
		(fp_line
			(start -0.7874 -0.4064)
			(end -0.7874 0.4064)
			(stroke
				(width 0.1524)
				(type default)
			)
			(layer "B.SilkS")
		)
		(fp_line
			(start -0.7874 0.4064)
			(end 0.7874 0.4064)
			(stroke
				(width 0.1524)
				(type default)
			)
			(layer "B.SilkS")
		)
		(fp_line
			(start 0.7874 -0.4064)
			(end -0.7874 -0.4064)
			(stroke
				(width 0.1524)
				(type default)
			)
			(layer "B.SilkS")
		)
		(fp_line
			(start 0.7874 0.4064)
			(end 0.7874 -0.4064)
			(stroke
				(width 0.1524)
				(type default)
			)
			(layer "B.SilkS")
		)
		(fp_line
			(start -0.67945 -0.3048)
			(end -0.67945 0.3048)
			(stroke
				(width 0.1)
				(type default)
			)
			(layer "B.Fab")
		)
		(fp_line
			(start -0.67945 0.3048)
			(end -0.120396 0.3048)
			(stroke
				(width 0.1)
				(type default)
			)
			(layer "B.Fab")
		)
		(fp_line
			(start -0.12065 -0.3048)
			(end -0.67945 -0.3048)
			(stroke
				(width 0.1)
				(type default)
			)
			(layer "B.Fab")
		)
		(fp_line
			(start -0.12065 -0.2794)
			(end -0.12065 -0.3048)
			(stroke
				(width 0.1)
				(type default)
			)
			(layer "B.Fab")
		)
		(fp_line
			(start -0.120396 0.2794)
			(end 0.12065 0.2794)
			(stroke
				(width 0.1)
				(type default)
			)
			(layer "B.Fab")
		)
		(fp_line
			(start -0.120396 0.3048)
			(end -0.120396 0.2794)
			(stroke
				(width 0.1)
				(type default)
			)
			(layer "B.Fab")
		)
		(fp_line
			(start 0.12065 -0.305054)
			(end 0.12065 -0.2794)
			(stroke
				(width 0.1)
				(type default)
			)
			(layer "B.Fab")
		)
		(fp_line
			(start 0.12065 -0.2794)
			(end -0.12065 -0.2794)
			(stroke
				(width 0.1)
				(type default)
			)
			(layer "B.Fab")
		)
		(fp_line
			(start 0.12065 0.2794)
			(end 0.12065 0.3048)
			(stroke
				(width 0.1)
				(type default)
			)
			(layer "B.Fab")
		)
		(fp_line
			(start 0.12065 0.3048)
			(end 0.67945 0.3048)
			(stroke
				(width 0.1)
				(type default)
			)
			(layer "B.Fab")
		)
		(fp_line
			(start 0.67945 -0.305054)
			(end 0.12065 -0.305054)
			(stroke
				(width 0.1)
				(type default)
			)
			(layer "B.Fab")
		)
		(fp_line
			(start 0.67945 0.3048)
			(end 0.67945 -0.305054)
			(stroke
				(width 0.1)
				(type default)
			)
			(layer "B.Fab")
		)
		(pad "1" smd circle
			(at 0.40005 0 180)
			(size 0 0)
			(layers "B.Cu" "B.Mask" "B.Paste")
			(net "PVDDCR_CPU1_P1")
		)
		(pad "2" smd circle
			(at -0.40005 0 180)
			(size 0 0)
			(layers "B.Cu" "B.Mask" "B.Paste")
			(net "GND")
		)
	)
	(footprint ""
		(layer "B.Cu")
		(at 113.587276 -391.340848 -90)
		(property "Reference" "C469"
			(at 0 0 90)
			(layer "B.SilkS")
			(hide yes)
			(effects
				(font
					(size 1.27 1.27)
				)
				(justify mirror)
			)
		)
		(property "Value" ""
			(at 0 0 90)
			(layer "B.Fab")
			(effects
				(font
					(size 1.27 1.27)
				)
				(justify mirror)
			)
		)
		(duplicate_pad_numbers_are_jumpers no)
		(fp_line
			(start -0.7874 0.4064)
			(end 0.7874 0.4064)
			(stroke
				(width 0.1524)
				(type default)
			)
			(layer "B.SilkS")
		)
		(fp_line
			(start 0.7874 0.4064)
			(end 0.7874 -0.4064)
			(stroke
				(width 0.1524)
				(type default)
			)
			(layer "B.SilkS")
		)
		(fp_line
			(start -0.7874 -0.4064)
			(end -0.7874 0.4064)
			(stroke
				(width 0.1524)
				(type default)
			)
			(layer "B.SilkS")
		)
		(fp_line
			(start 0.7874 -0.4064)
			(end -0.7874 -0.4064)
			(stroke
				(width 0.1524)
				(type default)
			)
			(layer "B.SilkS")
		)
		(fp_line
			(start -0.67945 0.3048)
			(end -0.120396 0.3048)
			(stroke
				(width 0.1)
				(type default)
			)
			(layer "B.Fab")
		)
		(fp_line
			(start -0.120396 0.3048)
			(end -0.120396 0.2794)
			(stroke
				(width 0.1)
				(type default)
			)
			(layer "B.Fab")
		)
		(fp_line
			(start 0.12065 0.3048)
			(end 0.67945 0.3048)
			(stroke
				(width 0.1)
				(type default)
			)
			(layer "B.Fab")
		)
		(fp_line
			(start 0.67945 0.3048)
			(end 0.67945 -0.305054)
			(stroke
				(width 0.1)
				(type default)
			)
			(layer "B.Fab")
		)
		(fp_line
			(start -0.120396 0.2794)
			(end 0.12065 0.2794)
			(stroke
				(width 0.1)
				(type default)
			)
			(layer "B.Fab")
		)
		(fp_line
			(start 0.12065 0.2794)
			(end 0.12065 0.3048)
			(stroke
				(width 0.1)
				(type default)
			)
			(layer "B.Fab")
		)
		(fp_line
			(start -0.12065 -0.2794)
			(end -0.12065 -0.3048)
			(stroke
				(width 0.1)
				(type default)
			)
			(layer "B.Fab")
		)
		(fp_line
			(start 0.12065 -0.2794)
			(end -0.12065 -0.2794)
			(stroke
				(width 0.1)
				(type default)
			)
			(layer "B.Fab")
		)
		(fp_line
			(start -0.67945 -0.3048)
			(end -0.67945 0.3048)
			(stroke
				(width 0.1)
				(type default)
			)
			(layer "B.Fab")
		)
		(fp_line
			(start -0.12065 -0.3048)
			(end -0.67945 -0.3048)
			(stroke
				(width 0.1)
				(type default)
			)
			(layer "B.Fab")
		)
		(fp_line
			(start 0.12065 -0.305054)
			(end 0.12065 -0.2794)
			(stroke
				(width 0.1)
				(type default)
			)
			(layer "B.Fab")
		)
		(fp_line
			(start 0.67945 -0.305054)
			(end 0.12065 -0.305054)
			(stroke
				(width 0.1)
				(type default)
			)
			(layer "B.Fab")
		)
		(pad "1" smd circle
			(at 0.40005 0 90)
			(size 0 0)
			(layers "B.Cu" "B.Mask" "B.Paste")
			(net "P0V9_CPU1_RT3_2A")
		)
		(pad "2" smd circle
			(at -0.40005 0 90)
			(size 0 0)
			(layers "B.Cu" "B.Mask" "B.Paste")
			(net "GND")
		)
	)
	(footprint ""
		(layer "B.Cu")
		(at 235.086398 -213.258654)
		(property "Reference" "R257"
			(at 0 0 0)
			(layer "B.SilkS")
			(hide yes)
			(effects
				(font
					(size 1.27 1.27)
				)
				(justify mirror)
			)
		)
		(property "Value" ""
			(at 0 0 0)
			(layer "B.Fab")
			(effects
				(font
					(size 1.27 1.27)
				)
				(justify mirror)
			)
		)
		(duplicate_pad_numbers_are_jumpers no)
		(fp_line
			(start -0.7874 -0.4064)
			(end -0.7874 0.4064)
			(stroke
				(width 0.1524)
				(type default)
			)
			(layer "B.SilkS")
		)
		(fp_line
			(start -0.7874 0.4064)
			(end 0.7874 0.4064)
			(stroke
				(width 0.1524)
				(type default)
			)
			(layer "B.SilkS")
		)
		(fp_line
			(start 0.7874 -0.4064)
			(end -0.7874 -0.4064)
			(stroke
				(width 0.1524)
				(type default)
			)
			(layer "B.SilkS")
		)
		(fp_line
			(start 0.7874 0.4064)
			(end 0.7874 -0.4064)
			(stroke
				(width 0.1524)
				(type default)
			)
			(layer "B.SilkS")
		)
		(fp_line
			(start -0.67945 -0.3048)
			(end -0.67945 0.3048)
			(stroke
				(width 0.1)
				(type default)
			)
			(layer "B.Fab")
		)
		(fp_line
			(start -0.67945 0.3048)
			(end -0.120396 0.3048)
			(stroke
				(width 0.1)
				(type default)
			)
			(layer "B.Fab")
		)
		(fp_line
			(start -0.12065 -0.3048)
			(end -0.67945 -0.3048)
			(stroke
				(width 0.1)
				(type default)
			)
			(layer "B.Fab")
		)
		(fp_line
			(start -0.12065 -0.2794)
			(end -0.12065 -0.3048)
			(stroke
				(width 0.1)
				(type default)
			)
			(layer "B.Fab")
		)
		(fp_line
			(start -0.120396 0.2794)
			(end 0.12065 0.2794)
			(stroke
				(width 0.1)
				(type default)
			)
			(layer "B.Fab")
		)
		(fp_line
			(start -0.120396 0.3048)
			(end -0.120396 0.2794)
			(stroke
				(width 0.1)
				(type default)
			)
			(layer "B.Fab")
		)
		(fp_line
			(start 0.12065 -0.305054)
			(end 0.12065 -0.2794)
			(stroke
				(width 0.1)
				(type default)
			)
			(layer "B.Fab")
		)
		(fp_line
			(start 0.12065 -0.2794)
			(end -0.12065 -0.2794)
			(stroke
				(width 0.1)
				(type default)
			)
			(layer "B.Fab")
		)
		(fp_line
			(start 0.12065 0.2794)
			(end 0.12065 0.3048)
			(stroke
				(width 0.1)
				(type default)
			)
			(layer "B.Fab")
		)
		(fp_line
			(start 0.12065 0.3048)
			(end 0.67945 0.3048)
			(stroke
				(width 0.1)
				(type default)
			)
			(layer "B.Fab")
		)
		(fp_line
			(start 0.67945 -0.305054)
			(end 0.12065 -0.305054)
			(stroke
				(width 0.1)
				(type default)
			)
			(layer "B.Fab")
		)
		(fp_line
			(start 0.67945 0.3048)
			(end 0.67945 -0.305054)
			(stroke
				(width 0.1)
				(type default)
			)
			(layer "B.Fab")
		)
		(pad "1" smd rect
			(at 0.40005 0)
			(size 0.4572 0.508)
			(layers "B.Cu" "B.Mask" "B.Paste")
			(net "SMB_CPU0_CPU1_APML_BUF1_SDA_R2")
		)
		(pad "2" smd rect
			(at -0.40005 0)
			(size 0.4572 0.508)
			(layers "B.Cu" "B.Mask" "B.Paste")
			(net "SMB_CPU0_CPU1_APML_SDA_R2")
		)
	)
	(footprint ""
		(layer "B.Cu")
		(at 370.427758 -269.30731)
		(property "Reference" "C2228"
			(at 0 0 0)
			(layer "B.SilkS")
			(hide yes)
			(effects
				(font
					(size 1.27 1.27)
				)
				(justify mirror)
			)
		)
		(property "Value" ""
			(at 0 0 0)
			(layer "B.Fab")
			(effects
				(font
					(size 1.27 1.27)
				)
				(justify mirror)
			)
		)
		(duplicate_pad_numbers_are_jumpers no)
		(fp_line
			(start -0.7874 -0.4064)
			(end -0.7874 0.4064)
			(stroke
				(width 0.1524)
				(type default)
			)
			(layer "B.SilkS")
		)
		(fp_line
			(start -0.7874 0.4064)
			(end 0.7874 0.4064)
			(stroke
				(width 0.1524)
				(type default)
			)
			(layer "B.SilkS")
		)
		(fp_line
			(start 0.7874 -0.4064)
			(end -0.7874 -0.4064)
			(stroke
				(width 0.1524)
				(type default)
			)
			(layer "B.SilkS")
		)
		(fp_line
			(start 0.7874 0.4064)
			(end 0.7874 -0.4064)
			(stroke
				(width 0.1524)
				(type default)
			)
			(layer "B.SilkS")
		)
		(fp_line
			(start -0.67945 -0.3048)
			(end -0.67945 0.3048)
			(stroke
				(width 0.1)
				(type default)
			)
			(layer "B.Fab")
		)
		(fp_line
			(start -0.67945 0.3048)
			(end -0.120396 0.3048)
			(stroke
				(width 0.1)
				(type default)
			)
			(layer "B.Fab")
		)
		(fp_line
			(start -0.12065 -0.3048)
			(end -0.67945 -0.3048)
			(stroke
				(width 0.1)
				(type default)
			)
			(layer "B.Fab")
		)
		(fp_line
			(start -0.12065 -0.2794)
			(end -0.12065 -0.3048)
			(stroke
				(width 0.1)
				(type default)
			)
			(layer "B.Fab")
		)
		(fp_line
			(start -0.120396 0.2794)
			(end 0.12065 0.2794)
			(stroke
				(width 0.1)
				(type default)
			)
			(layer "B.Fab")
		)
		(fp_line
			(start -0.120396 0.3048)
			(end -0.120396 0.2794)
			(stroke
				(width 0.1)
				(type default)
			)
			(layer "B.Fab")
		)
		(fp_line
			(start 0.12065 -0.305054)
			(end 0.12065 -0.2794)
			(stroke
				(width 0.1)
				(type default)
			)
			(layer "B.Fab")
		)
		(fp_line
			(start 0.12065 -0.2794)
			(end -0.12065 -0.2794)
			(stroke
				(width 0.1)
				(type default)
			)
			(layer "B.Fab")
		)
		(fp_line
			(start 0.12065 0.2794)
			(end 0.12065 0.3048)
			(stroke
				(width 0.1)
				(type default)
			)
			(layer "B.Fab")
		)
		(fp_line
			(start 0.12065 0.3048)
			(end 0.67945 0.3048)
			(stroke
				(width 0.1)
				(type default)
			)
			(layer "B.Fab")
		)
		(fp_line
			(start 0.67945 -0.305054)
			(end 0.12065 -0.305054)
			(stroke
				(width 0.1)
				(type default)
			)
			(layer "B.Fab")
		)
		(fp_line
			(start 0.67945 0.3048)
			(end 0.67945 -0.305054)
			(stroke
				(width 0.1)
				(type default)
			)
			(layer "B.Fab")
		)
		(pad "1" smd circle
			(at 0.40005 0 180)
			(size 0 0)
			(layers "B.Cu" "B.Mask" "B.Paste")
			(net "PVDDCR_CPU1_P0")
		)
		(pad "2" smd circle
			(at -0.40005 0 180)
			(size 0 0)
			(layers "B.Cu" "B.Mask" "B.Paste")
			(net "GND")
		)
	)
	(footprint ""
		(layer "B.Cu")
		(at 306.214526 -416.899344 90)
		(property "Reference" "C6533"
			(at 0 0 90)
			(layer "B.SilkS")
			(hide yes)
			(effects
				(font
					(size 1.27 1.27)
				)
				(justify mirror)
			)
		)
		(property "Value" ""
			(at 0 0 90)
			(layer "B.Fab")
			(effects
				(font
					(size 1.27 1.27)
				)
				(justify mirror)
			)
		)
		(duplicate_pad_numbers_are_jumpers no)
		(fp_line
			(start 0.299974 -0.150114)
			(end -0.299974 -0.150114)
			(stroke
				(width 0.1)
				(type default)
			)
			(layer "B.Fab")
		)
		(fp_line
			(start -0.299974 -0.150114)
			(end -0.299974 0.150114)
			(stroke
				(width 0.1)
				(type default)
			)
			(layer "B.Fab")
		)
		(fp_line
			(start 0.299974 0.150114)
			(end 0.299974 -0.150114)
			(stroke
				(width 0.1)
				(type default)
			)
			(layer "B.Fab")
		)
		(fp_line
			(start -0.299974 0.150114)
			(end 0.299974 0.150114)
			(stroke
				(width 0.1)
				(type default)
			)
			(layer "B.Fab")
		)
		(pad "1" smd rect
			(at 0.2667 0 270)
			(size 0.3048 0.381)
			(layers "B.Cu" "B.Mask" "B.Paste")
			(net "P5E_CPU0_P1_TX_BUF_C_DP<0>")
		)
		(pad "2" smd rect
			(at -0.2667 0 270)
			(size 0.3048 0.381)
			(layers "B.Cu" "B.Mask" "B.Paste")
			(net "P5E_CPU0_P1_TX_BUF_DP<0>")
		)
	)
	(footprint ""
		(layer "B.Cu")
		(at 424.783758 -391.686288 180)
		(property "Reference" "R1083"
			(at 0 0 0)
			(layer "B.SilkS")
			(hide yes)
			(effects
				(font
					(size 1.27 1.27)
				)
				(justify mirror)
			)
		)
		(property "Value" ""
			(at 0 0 0)
			(layer "B.Fab")
			(effects
				(font
					(size 1.27 1.27)
				)
				(justify mirror)
			)
		)
		(duplicate_pad_numbers_are_jumpers no)
		(fp_line
			(start 0.32512 0.175006)
			(end 0.32512 -0.175006)
			(stroke
				(width 0.1)
				(type default)
			)
			(layer "B.Fab")
		)
		(fp_line
			(start 0.32512 -0.175006)
			(end -0.32512 -0.175006)
			(stroke
				(width 0.1)
				(type default)
			)
			(layer "B.Fab")
		)
		(fp_line
			(start -0.32512 0.175006)
			(end 0.32512 0.175006)
			(stroke
				(width 0.1)
				(type default)
			)
			(layer "B.Fab")
		)
		(fp_line
			(start -0.32512 -0.175006)
			(end -0.32512 0.175006)
			(stroke
				(width 0.1)
				(type default)
			)
			(layer "B.Fab")
		)
		(pad "1" smd rect
			(at 0.2667 0)
			(size 0.3048 0.381)
			(layers "B.Cu" "B.Mask" "B.Paste")
			(net "NCF_CPU0_P2_GND")
		)
		(pad "2" smd rect
			(at -0.2667 0 180)
			(size 0.3048 0.381)
			(layers "B.Cu" "B.Mask" "B.Paste")
			(net "GND")
		)
	)
	(footprint ""
		(layer "B.Cu")
		(at 339.566758 -214.880952 90)
		(property "Reference" "R435"
			(at 0 0 90)
			(layer "B.SilkS")
			(hide yes)
			(effects
				(font
					(size 1.27 1.27)
				)
				(justify mirror)
			)
		)
		(property "Value" ""
			(at 0 0 90)
			(layer "B.Fab")
			(effects
				(font
					(size 1.27 1.27)
				)
				(justify mirror)
			)
		)
		(duplicate_pad_numbers_are_jumpers no)
		(fp_line
			(start 0.384048 -0.4064)
			(end -0.377952 -0.4064)
			(stroke
				(width 0.1524)
				(type default)
			)
			(layer "B.SilkS")
		)
		(fp_line
			(start -0.7874 0.132842)
			(end -0.7874 0.4064)
			(stroke
				(width 0.1524)
				(type default)
			)
			(layer "B.SilkS")
		)
		(fp_line
			(start 0.7874 0.4064)
			(end 0.7874 0.005842)
			(stroke
				(width 0.1524)
				(type default)
			)
			(layer "B.SilkS")
		)
		(fp_line
			(start -0.7874 0.4064)
			(end 0.7874 0.4064)
			(stroke
				(width 0.1524)
				(type default)
			)
			(layer "B.SilkS")
		)
		(fp_line
			(start 0.67945 -0.305054)
			(end 0.12065 -0.305054)
			(stroke
				(width 0.1)
				(type default)
			)
			(layer "B.Fab")
		)
		(fp_line
			(start 0.12065 -0.305054)
			(end 0.12065 -0.2794)
			(stroke
				(width 0.1)
				(type default)
			)
			(layer "B.Fab")
		)
		(fp_line
			(start -0.12065 -0.3048)
			(end -0.67945 -0.3048)
			(stroke
				(width 0.1)
				(type default)
			)
			(layer "B.Fab")
		)
		(fp_line
			(start -0.67945 -0.3048)
			(end -0.67945 0.3048)
			(stroke
				(width 0.1)
				(type default)
			)
			(layer "B.Fab")
		)
		(fp_line
			(start 0.12065 -0.2794)
			(end -0.12065 -0.2794)
			(stroke
				(width 0.1)
				(type default)
			)
			(layer "B.Fab")
		)
		(fp_line
			(start -0.12065 -0.2794)
			(end -0.12065 -0.3048)
			(stroke
				(width 0.1)
				(type default)
			)
			(layer "B.Fab")
		)
		(fp_line
			(start 0.12065 0.2794)
			(end 0.12065 0.3048)
			(stroke
				(width 0.1)
				(type default)
			)
			(layer "B.Fab")
		)
		(fp_line
			(start -0.120396 0.2794)
			(end 0.12065 0.2794)
			(stroke
				(width 0.1)
				(type default)
			)
			(layer "B.Fab")
		)
		(fp_line
			(start 0.67945 0.3048)
			(end 0.67945 -0.305054)
			(stroke
				(width 0.1)
				(type default)
			)
			(layer "B.Fab")
		)
		(fp_line
			(start 0.12065 0.3048)
			(end 0.67945 0.3048)
			(stroke
				(width 0.1)
				(type default)
			)
			(layer "B.Fab")
		)
		(fp_line
			(start -0.120396 0.3048)
			(end -0.120396 0.2794)
			(stroke
				(width 0.1)
				(type default)
			)
			(layer "B.Fab")
		)
		(fp_line
			(start -0.67945 0.3048)
			(end -0.120396 0.3048)
			(stroke
				(width 0.1)
				(type default)
			)
			(layer "B.Fab")
		)
		(pad "1" smd circle
			(at 0.40005 0 270)
			(size 0 0)
			(layers "B.Cu" "B.Mask" "B.Paste")
			(net "CLK_100M_REF_OUT_DP")
		)
		(pad "2" smd circle
			(at -0.40005 0 270)
			(size 0 0)
			(layers "B.Cu" "B.Mask" "B.Paste")
			(net "CLK_100M_REF_IN_DP")
		)
	)
	(footprint ""
		(layer "B.Cu")
		(at 126.618492 -388.011162 -90)
		(property "Reference" "C458"
			(at 0 0 90)
			(layer "B.SilkS")
			(hide yes)
			(effects
				(font
					(size 1.27 1.27)
				)
				(justify mirror)
			)
		)
		(property "Value" ""
			(at 0 0 90)
			(layer "B.Fab")
			(effects
				(font
					(size 1.27 1.27)
				)
				(justify mirror)
			)
		)
		(duplicate_pad_numbers_are_jumpers no)
		(fp_line
			(start -0.299974 0.150114)
			(end 0.299974 0.150114)
			(stroke
				(width 0.1)
				(type default)
			)
			(layer "B.Fab")
		)
		(fp_line
			(start 0.299974 0.150114)
			(end 0.299974 -0.150114)
			(stroke
				(width 0.1)
				(type default)
			)
			(layer "B.Fab")
		)
		(fp_line
			(start -0.299974 -0.150114)
			(end -0.299974 0.150114)
			(stroke
				(width 0.1)
				(type default)
			)
			(layer "B.Fab")
		)
		(fp_line
			(start 0.299974 -0.150114)
			(end -0.299974 -0.150114)
			(stroke
				(width 0.1)
				(type default)
			)
			(layer "B.Fab")
		)
		(pad "1" smd rect
			(at 0.2667 0 90)
			(size 0.3048 0.381)
			(layers "B.Cu" "B.Mask" "B.Paste")
			(net "P0V9_CPU1_RT_2D")
		)
		(pad "2" smd rect
			(at -0.2667 0 90)
			(size 0.3048 0.381)
			(layers "B.Cu" "B.Mask" "B.Paste")
			(net "GND")
		)
	)
	(footprint ""
		(layer "B.Cu")
		(at 98.60534 -254.956564)
		(property "Reference" "C2661"
			(at 0 0 0)
			(layer "B.SilkS")
			(hide yes)
			(effects
				(font
					(size 1.27 1.27)
				)
				(justify mirror)
			)
		)
		(property "Value" ""
			(at 0 0 0)
			(layer "B.Fab")
			(effects
				(font
					(size 1.27 1.27)
				)
				(justify mirror)
			)
		)
		(duplicate_pad_numbers_are_jumpers no)
		(fp_line
			(start -0.7874 -0.4064)
			(end -0.7874 0.4064)
			(stroke
				(width 0.1524)
				(type default)
			)
			(layer "B.SilkS")
		)
		(fp_line
			(start -0.7874 0.4064)
			(end 0.7874 0.4064)
			(stroke
				(width 0.1524)
				(type default)
			)
			(layer "B.SilkS")
		)
		(fp_line
			(start 0.7874 -0.4064)
			(end -0.7874 -0.4064)
			(stroke
				(width 0.1524)
				(type default)
			)
			(layer "B.SilkS")
		)
		(fp_line
			(start 0.7874 0.4064)
			(end 0.7874 -0.4064)
			(stroke
				(width 0.1524)
				(type default)
			)
			(layer "B.SilkS")
		)
		(fp_line
			(start -0.67945 -0.3048)
			(end -0.67945 0.3048)
			(stroke
				(width 0.1)
				(type default)
			)
			(layer "B.Fab")
		)
		(fp_line
			(start -0.67945 0.3048)
			(end -0.120396 0.3048)
			(stroke
				(width 0.1)
				(type default)
			)
			(layer "B.Fab")
		)
		(fp_line
			(start -0.12065 -0.3048)
			(end -0.67945 -0.3048)
			(stroke
				(width 0.1)
				(type default)
			)
			(layer "B.Fab")
		)
		(fp_line
			(start -0.12065 -0.2794)
			(end -0.12065 -0.3048)
			(stroke
				(width 0.1)
				(type default)
			)
			(layer "B.Fab")
		)
		(fp_line
			(start -0.120396 0.2794)
			(end 0.12065 0.2794)
			(stroke
				(width 0.1)
				(type default)
			)
			(layer "B.Fab")
		)
		(fp_line
			(start -0.120396 0.3048)
			(end -0.120396 0.2794)
			(stroke
				(width 0.1)
				(type default)
			)
			(layer "B.Fab")
		)
		(fp_line
			(start 0.12065 -0.305054)
			(end 0.12065 -0.2794)
			(stroke
				(width 0.1)
				(type default)
			)
			(layer "B.Fab")
		)
		(fp_line
			(start 0.12065 -0.2794)
			(end -0.12065 -0.2794)
			(stroke
				(width 0.1)
				(type default)
			)
			(layer "B.Fab")
		)
		(fp_line
			(start 0.12065 0.2794)
			(end 0.12065 0.3048)
			(stroke
				(width 0.1)
				(type default)
			)
			(layer "B.Fab")
		)
		(fp_line
			(start 0.12065 0.3048)
			(end 0.67945 0.3048)
			(stroke
				(width 0.1)
				(type default)
			)
			(layer "B.Fab")
		)
		(fp_line
			(start 0.67945 -0.305054)
			(end 0.12065 -0.305054)
			(stroke
				(width 0.1)
				(type default)
			)
			(layer "B.Fab")
		)
		(fp_line
			(start 0.67945 0.3048)
			(end 0.67945 -0.305054)
			(stroke
				(width 0.1)
				(type default)
			)
			(layer "B.Fab")
		)
		(pad "1" smd circle
			(at 0.40005 0 180)
			(size 0 0)
			(layers "B.Cu" "B.Mask" "B.Paste")
			(net "PVDD18_S5_P1")
		)
		(pad "2" smd circle
			(at -0.40005 0 180)
			(size 0 0)
			(layers "B.Cu" "B.Mask" "B.Paste")
			(net "GND")
		)
	)
	(footprint ""
		(layer "B.Cu")
		(at 121.678446 -386.766562 90)
		(property "Reference" "C446"
			(at 0 0 90)
			(layer "B.SilkS")
			(hide yes)
			(effects
				(font
					(size 1.27 1.27)
				)
				(justify mirror)
			)
		)
		(property "Value" ""
			(at 0 0 90)
			(layer "B.Fab")
			(effects
				(font
					(size 1.27 1.27)
				)
				(justify mirror)
			)
		)
		(duplicate_pad_numbers_are_jumpers no)
		(fp_line
			(start 0.299974 -0.150114)
			(end -0.299974 -0.150114)
			(stroke
				(width 0.1)
				(type default)
			)
			(layer "B.Fab")
		)
		(fp_line
			(start -0.299974 -0.150114)
			(end -0.299974 0.150114)
			(stroke
				(width 0.1)
				(type default)
			)
			(layer "B.Fab")
		)
		(fp_line
			(start 0.299974 0.150114)
			(end 0.299974 -0.150114)
			(stroke
				(width 0.1)
				(type default)
			)
			(layer "B.Fab")
		)
		(fp_line
			(start -0.299974 0.150114)
			(end 0.299974 0.150114)
			(stroke
				(width 0.1)
				(type default)
			)
			(layer "B.Fab")
		)
		(pad "1" smd rect
			(at 0.2667 0 270)
			(size 0.3048 0.381)
			(layers "B.Cu" "B.Mask" "B.Paste")
			(net "P1V8_CPU1_RT3_1A")
		)
		(pad "2" smd rect
			(at -0.2667 0 270)
			(size 0.3048 0.381)
			(layers "B.Cu" "B.Mask" "B.Paste")
			(net "GND")
		)
	)
	(footprint ""
		(layer "B.Cu")
		(at 335.618836 -151.069294 90)
		(property "Reference" "PC260"
			(at 0 0 90)
			(layer "B.SilkS")
			(hide yes)
			(effects
				(font
					(size 1.27 1.27)
				)
				(justify mirror)
			)
		)
		(property "Value" ""
			(at 0 0 90)
			(layer "B.Fab")
			(effects
				(font
					(size 1.27 1.27)
				)
				(justify mirror)
			)
		)
		(duplicate_pad_numbers_are_jumpers no)
		(fp_line
			(start 1.524 -0.762)
			(end -1.524 -0.762)
			(stroke
				(width 0.1524)
				(type default)
			)
			(layer "B.SilkS")
		)
		(fp_line
			(start -1.524 -0.762)
			(end -1.524 0.762)
			(stroke
				(width 0.1524)
				(type default)
			)
			(layer "B.SilkS")
		)
		(fp_line
			(start 1.524 0.762)
			(end 1.524 -0.762)
			(stroke
				(width 0.1524)
				(type default)
			)
			(layer "B.SilkS")
		)
		(fp_line
			(start -1.524 0.762)
			(end 1.524 0.762)
			(stroke
				(width 0.1524)
				(type default)
			)
			(layer "B.SilkS")
		)
		(fp_line
			(start 1.1049 -0.724916)
			(end 1.1049 0.724916)
			(stroke
				(width 0.1)
				(type default)
			)
			(layer "B.Fab")
		)
		(fp_line
			(start -1.1049 -0.724916)
			(end 1.1049 -0.724916)
			(stroke
				(width 0.1)
				(type default)
			)
			(layer "B.Fab")
		)
		(fp_line
			(start 1.1049 0.724916)
			(end -1.1049 0.724916)
			(stroke
				(width 0.1)
				(type default)
			)
			(layer "B.Fab")
		)
		(fp_line
			(start -1.1049 0.724916)
			(end -1.1049 -0.724916)
			(stroke
				(width 0.1)
				(type default)
			)
			(layer "B.Fab")
		)
		(pad "1" smd rect
			(at 0.889 0 90)
			(size 1.016 1.27)
			(layers "B.Cu" "B.Mask" "B.Paste")
			(net "PVDD18_S5_P0")
		)
		(pad "2" smd rect
			(at -0.889 0 90)
			(size 1.016 1.27)
			(layers "B.Cu" "B.Mask" "B.Paste")
			(net "GND")
		)
	)
	(footprint ""
		(layer "B.Cu")
		(at 451.577456 -52.849526 -90)
		(property "Reference" "PC8071"
			(at 0 0 90)
			(layer "B.SilkS")
			(hide yes)
			(effects
				(font
					(size 1.27 1.27)
				)
				(justify mirror)
			)
		)
		(property "Value" ""
			(at 0 0 90)
			(layer "B.Fab")
			(effects
				(font
					(size 1.27 1.27)
				)
				(justify mirror)
			)
		)
		(duplicate_pad_numbers_are_jumpers no)
		(fp_line
			(start -1.524 0.762)
			(end 1.524 0.762)
			(stroke
				(width 0.1524)
				(type default)
			)
			(layer "B.SilkS")
		)
		(fp_line
			(start 1.524 0.762)
			(end 1.524 -0.762)
			(stroke
				(width 0.1524)
				(type default)
			)
			(layer "B.SilkS")
		)
		(fp_line
			(start -1.524 -0.762)
			(end -1.524 0.762)
			(stroke
				(width 0.1524)
				(type default)
			)
			(layer "B.SilkS")
		)
		(fp_line
			(start 1.524 -0.762)
			(end -1.524 -0.762)
			(stroke
				(width 0.1524)
				(type default)
			)
			(layer "B.SilkS")
		)
		(fp_line
			(start -1.1049 0.724916)
			(end -1.1049 -0.724916)
			(stroke
				(width 0.1)
				(type default)
			)
			(layer "B.Fab")
		)
		(fp_line
			(start 1.1049 0.724916)
			(end -1.1049 0.724916)
			(stroke
				(width 0.1)
				(type default)
			)
			(layer "B.Fab")
		)
		(fp_line
			(start -1.1049 -0.724916)
			(end 1.1049 -0.724916)
			(stroke
				(width 0.1)
				(type default)
			)
			(layer "B.Fab")
		)
		(fp_line
			(start 1.1049 -0.724916)
			(end 1.1049 0.724916)
			(stroke
				(width 0.1)
				(type default)
			)
			(layer "B.Fab")
		)
		(pad "1" smd rect
			(at 0.889 0 270)
			(size 1.016 1.27)
			(layers "B.Cu" "B.Mask" "B.Paste")
			(net "SW_P3V3_AUX_FLT")
		)
		(pad "2" smd rect
			(at -0.889 0 270)
			(size 1.016 1.27)
			(layers "B.Cu" "B.Mask" "B.Paste")
			(net "GND")
		)
	)
	(footprint ""
		(layer "B.Cu")
		(at 398.893538 -393.96416 180)
		(property "Reference" "R1074"
			(at 0 0 0)
			(layer "B.SilkS")
			(hide yes)
			(effects
				(font
					(size 1.27 1.27)
				)
				(justify mirror)
			)
		)
		(property "Value" ""
			(at 0 0 0)
			(layer "B.Fab")
			(effects
				(font
					(size 1.27 1.27)
				)
				(justify mirror)
			)
		)
		(duplicate_pad_numbers_are_jumpers no)
		(fp_line
			(start 0.32512 0.175006)
			(end 0.32512 -0.175006)
			(stroke
				(width 0.1)
				(type default)
			)
			(layer "B.Fab")
		)
		(fp_line
			(start 0.32512 -0.175006)
			(end -0.32512 -0.175006)
			(stroke
				(width 0.1)
				(type default)
			)
			(layer "B.Fab")
		)
		(fp_line
			(start -0.32512 0.175006)
			(end 0.32512 0.175006)
			(stroke
				(width 0.1)
				(type default)
			)
			(layer "B.Fab")
		)
		(fp_line
			(start -0.32512 -0.175006)
			(end -0.32512 0.175006)
			(stroke
				(width 0.1)
				(type default)
			)
			(layer "B.Fab")
		)
		(pad "1" smd rect
			(at 0.2667 0)
			(size 0.3048 0.381)
			(layers "B.Cu" "B.Mask" "B.Paste")
			(net "TEST0_RT_CPU0_P2")
		)
		(pad "2" smd rect
			(at -0.2667 0 180)
			(size 0.3048 0.381)
			(layers "B.Cu" "B.Mask" "B.Paste")
			(net "GND")
		)
	)
	(footprint ""
		(layer "B.Cu")
		(at 115.610386 -251.781564)
		(property "Reference" "C2413"
			(at 0 0 0)
			(layer "B.SilkS")
			(hide yes)
			(effects
				(font
					(size 1.27 1.27)
				)
				(justify mirror)
			)
		)
		(property "Value" ""
			(at 0 0 0)
			(layer "B.Fab")
			(effects
				(font
					(size 1.27 1.27)
				)
				(justify mirror)
			)
		)
		(duplicate_pad_numbers_are_jumpers no)
		(fp_line
			(start -0.7874 -0.4064)
			(end -0.7874 0.4064)
			(stroke
				(width 0.1524)
				(type default)
			)
			(layer "B.SilkS")
		)
		(fp_line
			(start -0.7874 0.4064)
			(end 0.7874 0.4064)
			(stroke
				(width 0.1524)
				(type default)
			)
			(layer "B.SilkS")
		)
		(fp_line
			(start 0.7874 -0.4064)
			(end -0.7874 -0.4064)
			(stroke
				(width 0.1524)
				(type default)
			)
			(layer "B.SilkS")
		)
		(fp_line
			(start 0.7874 0.4064)
			(end 0.7874 -0.4064)
			(stroke
				(width 0.1524)
				(type default)
			)
			(layer "B.SilkS")
		)
		(fp_line
			(start -0.67945 -0.3048)
			(end -0.67945 0.3048)
			(stroke
				(width 0.1)
				(type default)
			)
			(layer "B.Fab")
		)
		(fp_line
			(start -0.67945 0.3048)
			(end -0.120396 0.3048)
			(stroke
				(width 0.1)
				(type default)
			)
			(layer "B.Fab")
		)
		(fp_line
			(start -0.12065 -0.3048)
			(end -0.67945 -0.3048)
			(stroke
				(width 0.1)
				(type default)
			)
			(layer "B.Fab")
		)
		(fp_line
			(start -0.12065 -0.2794)
			(end -0.12065 -0.3048)
			(stroke
				(width 0.1)
				(type default)
			)
			(layer "B.Fab")
		)
		(fp_line
			(start -0.120396 0.2794)
			(end 0.12065 0.2794)
			(stroke
				(width 0.1)
				(type default)
			)
			(layer "B.Fab")
		)
		(fp_line
			(start -0.120396 0.3048)
			(end -0.120396 0.2794)
			(stroke
				(width 0.1)
				(type default)
			)
			(layer "B.Fab")
		)
		(fp_line
			(start 0.12065 -0.305054)
			(end 0.12065 -0.2794)
			(stroke
				(width 0.1)
				(type default)
			)
			(layer "B.Fab")
		)
		(fp_line
			(start 0.12065 -0.2794)
			(end -0.12065 -0.2794)
			(stroke
				(width 0.1)
				(type default)
			)
			(layer "B.Fab")
		)
		(fp_line
			(start 0.12065 0.2794)
			(end 0.12065 0.3048)
			(stroke
				(width 0.1)
				(type default)
			)
			(layer "B.Fab")
		)
		(fp_line
			(start 0.12065 0.3048)
			(end 0.67945 0.3048)
			(stroke
				(width 0.1)
				(type default)
			)
			(layer "B.Fab")
		)
		(fp_line
			(start 0.67945 -0.305054)
			(end 0.12065 -0.305054)
			(stroke
				(width 0.1)
				(type default)
			)
			(layer "B.Fab")
		)
		(fp_line
			(start 0.67945 0.3048)
			(end 0.67945 -0.305054)
			(stroke
				(width 0.1)
				(type default)
			)
			(layer "B.Fab")
		)
		(pad "1" smd circle
			(at 0.40005 0 180)
			(size 0 0)
			(layers "B.Cu" "B.Mask" "B.Paste")
			(net "PVDDCR_SOC_P1")
		)
		(pad "2" smd circle
			(at -0.40005 0 180)
			(size 0 0)
			(layers "B.Cu" "B.Mask" "B.Paste")
			(net "GND")
		)
	)
	(footprint ""
		(layer "B.Cu")
		(at 164.338 -424.60037 -90)
		(property "Reference" "R1513"
			(at 0 0 90)
			(layer "B.SilkS")
			(hide yes)
			(effects
				(font
					(size 1.27 1.27)
				)
				(justify mirror)
			)
		)
		(property "Value" ""
			(at 0 0 90)
			(layer "B.Fab")
			(effects
				(font
					(size 1.27 1.27)
				)
				(justify mirror)
			)
		)
		(duplicate_pad_numbers_are_jumpers no)
		(fp_line
			(start -0.32512 0.175006)
			(end 0.32512 0.175006)
			(stroke
				(width 0.1)
				(type default)
			)
			(layer "B.Fab")
		)
		(fp_line
			(start 0.32512 0.175006)
			(end 0.32512 -0.175006)
			(stroke
				(width 0.1)
				(type default)
			)
			(layer "B.Fab")
		)
		(fp_line
			(start -0.32512 -0.175006)
			(end -0.32512 0.175006)
			(stroke
				(width 0.1)
				(type default)
			)
			(layer "B.Fab")
		)
		(fp_line
			(start 0.32512 -0.175006)
			(end -0.32512 -0.175006)
			(stroke
				(width 0.1)
				(type default)
			)
			(layer "B.Fab")
		)
		(pad "1" smd rect
			(at 0.2667 0 90)
			(size 0.3048 0.381)
			(layers "B.Cu" "B.Mask" "B.Paste")
			(net "P1V8_CPU1_RT_1D")
		)
		(pad "2" smd rect
			(at -0.2667 0 270)
			(size 0.3048 0.381)
			(layers "B.Cu" "B.Mask" "B.Paste")
			(net "JTAG_TCK_RT_CPU1_P3")
		)
	)
	(footprint ""
		(layer "B.Cu")
		(at 48.578516 -386.766562 90)
		(property "Reference" "C243"
			(at 0 0 90)
			(layer "B.SilkS")
			(hide yes)
			(effects
				(font
					(size 1.27 1.27)
				)
				(justify mirror)
			)
		)
		(property "Value" ""
			(at 0 0 90)
			(layer "B.Fab")
			(effects
				(font
					(size 1.27 1.27)
				)
				(justify mirror)
			)
		)
		(duplicate_pad_numbers_are_jumpers no)
		(fp_line
			(start 0.299974 -0.150114)
			(end -0.299974 -0.150114)
			(stroke
				(width 0.1)
				(type default)
			)
			(layer "B.Fab")
		)
		(fp_line
			(start -0.299974 -0.150114)
			(end -0.299974 0.150114)
			(stroke
				(width 0.1)
				(type default)
			)
			(layer "B.Fab")
		)
		(fp_line
			(start 0.299974 0.150114)
			(end 0.299974 -0.150114)
			(stroke
				(width 0.1)
				(type default)
			)
			(layer "B.Fab")
		)
		(fp_line
			(start -0.299974 0.150114)
			(end 0.299974 0.150114)
			(stroke
				(width 0.1)
				(type default)
			)
			(layer "B.Fab")
		)
		(pad "1" smd rect
			(at 0.2667 0 270)
			(size 0.3048 0.381)
			(layers "B.Cu" "B.Mask" "B.Paste")
			(net "P0V9_CPU1_RT0_2A")
		)
		(pad "2" smd rect
			(at -0.2667 0 270)
			(size 0.3048 0.381)
			(layers "B.Cu" "B.Mask" "B.Paste")
			(net "GND")
		)
	)
	(footprint ""
		(layer "B.Cu")
		(at 124.373386 -261.04723)
		(property "Reference" "C3913"
			(at 0 0 0)
			(layer "B.SilkS")
			(hide yes)
			(effects
				(font
					(size 1.27 1.27)
				)
				(justify mirror)
			)
		)
		(property "Value" ""
			(at 0 0 0)
			(layer "B.Fab")
			(effects
				(font
					(size 1.27 1.27)
				)
				(justify mirror)
			)
		)
		(duplicate_pad_numbers_are_jumpers no)
		(fp_line
			(start -0.7874 -0.4064)
			(end -0.7874 0.4064)
			(stroke
				(width 0.1524)
				(type default)
			)
			(layer "B.SilkS")
		)
		(fp_line
			(start -0.7874 0.4064)
			(end 0.7874 0.4064)
			(stroke
				(width 0.1524)
				(type default)
			)
			(layer "B.SilkS")
		)
		(fp_line
			(start 0.7874 -0.4064)
			(end -0.7874 -0.4064)
			(stroke
				(width 0.1524)
				(type default)
			)
			(layer "B.SilkS")
		)
		(fp_line
			(start 0.7874 0.4064)
			(end 0.7874 -0.4064)
			(stroke
				(width 0.1524)
				(type default)
			)
			(layer "B.SilkS")
		)
		(fp_line
			(start -0.67945 -0.3048)
			(end -0.67945 0.3048)
			(stroke
				(width 0.1)
				(type default)
			)
			(layer "B.Fab")
		)
		(fp_line
			(start -0.67945 0.3048)
			(end -0.120396 0.3048)
			(stroke
				(width 0.1)
				(type default)
			)
			(layer "B.Fab")
		)
		(fp_line
			(start -0.12065 -0.3048)
			(end -0.67945 -0.3048)
			(stroke
				(width 0.1)
				(type default)
			)
			(layer "B.Fab")
		)
		(fp_line
			(start -0.12065 -0.2794)
			(end -0.12065 -0.3048)
			(stroke
				(width 0.1)
				(type default)
			)
			(layer "B.Fab")
		)
		(fp_line
			(start -0.120396 0.2794)
			(end 0.12065 0.2794)
			(stroke
				(width 0.1)
				(type default)
			)
			(layer "B.Fab")
		)
		(fp_line
			(start -0.120396 0.3048)
			(end -0.120396 0.2794)
			(stroke
				(width 0.1)
				(type default)
			)
			(layer "B.Fab")
		)
		(fp_line
			(start 0.12065 -0.305054)
			(end 0.12065 -0.2794)
			(stroke
				(width 0.1)
				(type default)
			)
			(layer "B.Fab")
		)
		(fp_line
			(start 0.12065 -0.2794)
			(end -0.12065 -0.2794)
			(stroke
				(width 0.1)
				(type default)
			)
			(layer "B.Fab")
		)
		(fp_line
			(start 0.12065 0.2794)
			(end 0.12065 0.3048)
			(stroke
				(width 0.1)
				(type default)
			)
			(layer "B.Fab")
		)
		(fp_line
			(start 0.12065 0.3048)
			(end 0.67945 0.3048)
			(stroke
				(width 0.1)
				(type default)
			)
			(layer "B.Fab")
		)
		(fp_line
			(start 0.67945 -0.305054)
			(end 0.12065 -0.305054)
			(stroke
				(width 0.1)
				(type default)
			)
			(layer "B.Fab")
		)
		(fp_line
			(start 0.67945 0.3048)
			(end 0.67945 -0.305054)
			(stroke
				(width 0.1)
				(type default)
			)
			(layer "B.Fab")
		)
		(pad "1" smd circle
			(at 0.40005 0 180)
			(size 0 0)
			(layers "B.Cu" "B.Mask" "B.Paste")
			(net "PVDDCR_SOC_P1")
		)
		(pad "2" smd circle
			(at -0.40005 0 180)
			(size 0 0)
			(layers "B.Cu" "B.Mask" "B.Paste")
			(net "GND")
		)
	)
	(footprint ""
		(layer "B.Cu")
		(at 184.719468 -425.467526 -90)
		(property "Reference" "R8112"
			(at 0 0 90)
			(layer "B.SilkS")
			(hide yes)
			(effects
				(font
					(size 1.27 1.27)
				)
				(justify mirror)
			)
		)
		(property "Value" ""
			(at 0 0 90)
			(layer "B.Fab")
			(effects
				(font
					(size 1.27 1.27)
				)
				(justify mirror)
			)
		)
		(duplicate_pad_numbers_are_jumpers no)
		(fp_line
			(start -0.7874 0.4064)
			(end 0.7874 0.4064)
			(stroke
				(width 0.1524)
				(type default)
			)
			(layer "B.SilkS")
		)
		(fp_line
			(start 0.7874 0.4064)
			(end 0.7874 -0.4064)
			(stroke
				(width 0.1524)
				(type default)
			)
			(layer "B.SilkS")
		)
		(fp_line
			(start -0.7874 -0.4064)
			(end -0.7874 0.4064)
			(stroke
				(width 0.1524)
				(type default)
			)
			(layer "B.SilkS")
		)
		(fp_line
			(start 0.7874 -0.4064)
			(end -0.7874 -0.4064)
			(stroke
				(width 0.1524)
				(type default)
			)
			(layer "B.SilkS")
		)
		(fp_line
			(start -0.67945 0.3048)
			(end -0.120396 0.3048)
			(stroke
				(width 0.1)
				(type default)
			)
			(layer "B.Fab")
		)
		(fp_line
			(start -0.120396 0.3048)
			(end -0.120396 0.2794)
			(stroke
				(width 0.1)
				(type default)
			)
			(layer "B.Fab")
		)
		(fp_line
			(start 0.12065 0.3048)
			(end 0.67945 0.3048)
			(stroke
				(width 0.1)
				(type default)
			)
			(layer "B.Fab")
		)
		(fp_line
			(start 0.67945 0.3048)
			(end 0.67945 -0.305054)
			(stroke
				(width 0.1)
				(type default)
			)
			(layer "B.Fab")
		)
		(fp_line
			(start -0.120396 0.2794)
			(end 0.12065 0.2794)
			(stroke
				(width 0.1)
				(type default)
			)
			(layer "B.Fab")
		)
		(fp_line
			(start 0.12065 0.2794)
			(end 0.12065 0.3048)
			(stroke
				(width 0.1)
				(type default)
			)
			(layer "B.Fab")
		)
		(fp_line
			(start -0.12065 -0.2794)
			(end -0.12065 -0.3048)
			(stroke
				(width 0.1)
				(type default)
			)
			(layer "B.Fab")
		)
		(fp_line
			(start 0.12065 -0.2794)
			(end -0.12065 -0.2794)
			(stroke
				(width 0.1)
				(type default)
			)
			(layer "B.Fab")
		)
		(fp_line
			(start -0.67945 -0.3048)
			(end -0.67945 0.3048)
			(stroke
				(width 0.1)
				(type default)
			)
			(layer "B.Fab")
		)
		(fp_line
			(start -0.12065 -0.3048)
			(end -0.67945 -0.3048)
			(stroke
				(width 0.1)
				(type default)
			)
			(layer "B.Fab")
		)
		(fp_line
			(start 0.12065 -0.305054)
			(end 0.12065 -0.2794)
			(stroke
				(width 0.1)
				(type default)
			)
			(layer "B.Fab")
		)
		(fp_line
			(start 0.67945 -0.305054)
			(end 0.12065 -0.305054)
			(stroke
				(width 0.1)
				(type default)
			)
			(layer "B.Fab")
		)
		(pad "1" smd circle
			(at 0.40005 0 90)
			(size 0 0)
			(layers "B.Cu" "B.Mask" "B.Paste")
			(net "HSC_OC_VOL")
		)
		(pad "2" smd circle
			(at -0.40005 0 90)
			(size 0 0)
			(layers "B.Cu" "B.Mask" "B.Paste")
			(net "HSC_D_OC_R2")
		)
	)
	(footprint ""
		(layer "B.Cu")
		(at 40.045386 -190.948564 180)
		(property "Reference" "R305"
			(at 0 0 0)
			(layer "B.SilkS")
			(hide yes)
			(effects
				(font
					(size 1.27 1.27)
				)
				(justify mirror)
			)
		)
		(property "Value" ""
			(at 0 0 0)
			(layer "B.Fab")
			(effects
				(font
					(size 1.27 1.27)
				)
				(justify mirror)
			)
		)
		(duplicate_pad_numbers_are_jumpers no)
		(fp_line
			(start 0.7874 0.4064)
			(end 0.7874 -0.4064)
			(stroke
				(width 0.1524)
				(type default)
			)
			(layer "B.SilkS")
		)
		(fp_line
			(start 0.7874 -0.4064)
			(end -0.7874 -0.4064)
			(stroke
				(width 0.1524)
				(type default)
			)
			(layer "B.SilkS")
		)
		(fp_line
			(start -0.7874 0.4064)
			(end 0.7874 0.4064)
			(stroke
				(width 0.1524)
				(type default)
			)
			(layer "B.SilkS")
		)
		(fp_line
			(start -0.7874 -0.4064)
			(end -0.7874 0.4064)
			(stroke
				(width 0.1524)
				(type default)
			)
			(layer "B.SilkS")
		)
		(fp_line
			(start 0.67945 0.3048)
			(end 0.67945 -0.305054)
			(stroke
				(width 0.1)
				(type default)
			)
			(layer "B.Fab")
		)
		(fp_line
			(start 0.67945 -0.305054)
			(end 0.12065 -0.305054)
			(stroke
				(width 0.1)
				(type default)
			)
			(layer "B.Fab")
		)
		(fp_line
			(start 0.12065 0.3048)
			(end 0.67945 0.3048)
			(stroke
				(width 0.1)
				(type default)
			)
			(layer "B.Fab")
		)
		(fp_line
			(start 0.12065 0.2794)
			(end 0.12065 0.3048)
			(stroke
				(width 0.1)
				(type default)
			)
			(layer "B.Fab")
		)
		(fp_line
			(start 0.12065 -0.2794)
			(end -0.12065 -0.2794)
			(stroke
				(width 0.1)
				(type default)
			)
			(layer "B.Fab")
		)
		(fp_line
			(start 0.12065 -0.305054)
			(end 0.12065 -0.2794)
			(stroke
				(width 0.1)
				(type default)
			)
			(layer "B.Fab")
		)
		(fp_line
			(start -0.120396 0.3048)
			(end -0.120396 0.2794)
			(stroke
				(width 0.1)
				(type default)
			)
			(layer "B.Fab")
		)
		(fp_line
			(start -0.120396 0.2794)
			(end 0.12065 0.2794)
			(stroke
				(width 0.1)
				(type default)
			)
			(layer "B.Fab")
		)
		(fp_line
			(start -0.12065 -0.2794)
			(end -0.12065 -0.3048)
			(stroke
				(width 0.1)
				(type default)
			)
			(layer "B.Fab")
		)
		(fp_line
			(start -0.12065 -0.3048)
			(end -0.67945 -0.3048)
			(stroke
				(width 0.1)
				(type default)
			)
			(layer "B.Fab")
		)
		(fp_line
			(start -0.67945 0.3048)
			(end -0.120396 0.3048)
			(stroke
				(width 0.1)
				(type default)
			)
			(layer "B.Fab")
		)
		(fp_line
			(start -0.67945 -0.3048)
			(end -0.67945 0.3048)
			(stroke
				(width 0.1)
				(type default)
			)
			(layer "B.Fab")
		)
		(pad "1" smd circle
			(at 0.40005 0)
			(size 0 0)
			(layers "B.Cu" "B.Mask" "B.Paste")
			(net "PWRGD_CHC_CPU1_DIMM")
		)
		(pad "2" smd circle
			(at -0.40005 0)
			(size 0 0)
			(layers "B.Cu" "B.Mask" "B.Paste")
			(net "PWRGD_CHAF_CPU1")
		)
	)
	(footprint ""
		(layer "B.Cu")
		(at 184.05983 -13.60043 -90)
		(property "Reference" "R6006"
			(at 0 0 90)
			(layer "B.SilkS")
			(hide yes)
			(effects
				(font
					(size 1.27 1.27)
				)
				(justify mirror)
			)
		)
		(property "Value" ""
			(at 0 0 90)
			(layer "B.Fab")
			(effects
				(font
					(size 1.27 1.27)
				)
				(justify mirror)
			)
		)
		(duplicate_pad_numbers_are_jumpers no)
		(fp_line
			(start -0.7874 0.4064)
			(end 0.7874 0.4064)
			(stroke
				(width 0.1524)
				(type default)
			)
			(layer "B.SilkS")
		)
		(fp_line
			(start 0.7874 0.4064)
			(end 0.7874 -0.4064)
			(stroke
				(width 0.1524)
				(type default)
			)
			(layer "B.SilkS")
		)
		(fp_line
			(start -0.7874 -0.4064)
			(end -0.7874 0.4064)
			(stroke
				(width 0.1524)
				(type default)
			)
			(layer "B.SilkS")
		)
		(fp_line
			(start 0.7874 -0.4064)
			(end -0.7874 -0.4064)
			(stroke
				(width 0.1524)
				(type default)
			)
			(layer "B.SilkS")
		)
		(fp_line
			(start -0.67945 0.3048)
			(end -0.120396 0.3048)
			(stroke
				(width 0.1)
				(type default)
			)
			(layer "B.Fab")
		)
		(fp_line
			(start -0.120396 0.3048)
			(end -0.120396 0.2794)
			(stroke
				(width 0.1)
				(type default)
			)
			(layer "B.Fab")
		)
		(fp_line
			(start 0.12065 0.3048)
			(end 0.67945 0.3048)
			(stroke
				(width 0.1)
				(type default)
			)
			(layer "B.Fab")
		)
		(fp_line
			(start 0.67945 0.3048)
			(end 0.67945 -0.305054)
			(stroke
				(width 0.1)
				(type default)
			)
			(layer "B.Fab")
		)
		(fp_line
			(start -0.120396 0.2794)
			(end 0.12065 0.2794)
			(stroke
				(width 0.1)
				(type default)
			)
			(layer "B.Fab")
		)
		(fp_line
			(start 0.12065 0.2794)
			(end 0.12065 0.3048)
			(stroke
				(width 0.1)
				(type default)
			)
			(layer "B.Fab")
		)
		(fp_line
			(start -0.12065 -0.2794)
			(end -0.12065 -0.3048)
			(stroke
				(width 0.1)
				(type default)
			)
			(layer "B.Fab")
		)
		(fp_line
			(start 0.12065 -0.2794)
			(end -0.12065 -0.2794)
			(stroke
				(width 0.1)
				(type default)
			)
			(layer "B.Fab")
		)
		(fp_line
			(start -0.67945 -0.3048)
			(end -0.67945 0.3048)
			(stroke
				(width 0.1)
				(type default)
			)
			(layer "B.Fab")
		)
		(fp_line
			(start -0.12065 -0.3048)
			(end -0.67945 -0.3048)
			(stroke
				(width 0.1)
				(type default)
			)
			(layer "B.Fab")
		)
		(fp_line
			(start 0.12065 -0.305054)
			(end 0.12065 -0.2794)
			(stroke
				(width 0.1)
				(type default)
			)
			(layer "B.Fab")
		)
		(fp_line
			(start 0.67945 -0.305054)
			(end 0.12065 -0.305054)
			(stroke
				(width 0.1)
				(type default)
			)
			(layer "B.Fab")
		)
		(pad "1" smd circle
			(at 0.40005 0 90)
			(size 0 0)
			(layers "B.Cu" "B.Mask" "B.Paste")
			(net "I3C_SCM_3_SCL")
		)
		(pad "2" smd circle
			(at -0.40005 0 90)
			(size 0 0)
			(layers "B.Cu" "B.Mask" "B.Paste")
			(net "I3C_SCM_3_R_SCL")
		)
	)
	(footprint ""
		(layer "B.Cu")
		(at 138.757406 -408.517344 90)
		(property "Reference" "C6739"
			(at 0 0 90)
			(layer "B.SilkS")
			(hide yes)
			(effects
				(font
					(size 1.27 1.27)
				)
				(justify mirror)
			)
		)
		(property "Value" ""
			(at 0 0 90)
			(layer "B.Fab")
			(effects
				(font
					(size 1.27 1.27)
				)
				(justify mirror)
			)
		)
		(duplicate_pad_numbers_are_jumpers no)
		(fp_line
			(start 0.299974 -0.150114)
			(end -0.299974 -0.150114)
			(stroke
				(width 0.1)
				(type default)
			)
			(layer "B.Fab")
		)
		(fp_line
			(start -0.299974 -0.150114)
			(end -0.299974 0.150114)
			(stroke
				(width 0.1)
				(type default)
			)
			(layer "B.Fab")
		)
		(fp_line
			(start 0.299974 0.150114)
			(end 0.299974 -0.150114)
			(stroke
				(width 0.1)
				(type default)
			)
			(layer "B.Fab")
		)
		(fp_line
			(start -0.299974 0.150114)
			(end 0.299974 0.150114)
			(stroke
				(width 0.1)
				(type default)
			)
			(layer "B.Fab")
		)
		(pad "1" smd rect
			(at 0.2667 0 270)
			(size 0.3048 0.381)
			(layers "B.Cu" "B.Mask" "B.Paste")
			(net "P5E_CPU1_P3_TX_BUF_C_DP<7>")
		)
		(pad "2" smd rect
			(at -0.2667 0 270)
			(size 0.3048 0.381)
			(layers "B.Cu" "B.Mask" "B.Paste")
			(net "P5E_CPU1_P3_TX_BUF_DP<7>")
		)
	)
	(footprint ""
		(layer "B.Cu")
		(at 52.782978 -431.904902 -90)
		(property "Reference" "R3439"
			(at 0 0 90)
			(layer "B.SilkS")
			(hide yes)
			(effects
				(font
					(size 1.27 1.27)
				)
				(justify mirror)
			)
		)
		(property "Value" ""
			(at 0 0 90)
			(layer "B.Fab")
			(effects
				(font
					(size 1.27 1.27)
				)
				(justify mirror)
			)
		)
		(duplicate_pad_numbers_are_jumpers no)
		(fp_line
			(start -0.7874 0.4064)
			(end 0.7874 0.4064)
			(stroke
				(width 0.1524)
				(type default)
			)
			(layer "B.SilkS")
		)
		(fp_line
			(start 0.7874 0.4064)
			(end 0.7874 -0.4064)
			(stroke
				(width 0.1524)
				(type default)
			)
			(layer "B.SilkS")
		)
		(fp_line
			(start -0.7874 -0.4064)
			(end -0.7874 0.4064)
			(stroke
				(width 0.1524)
				(type default)
			)
			(layer "B.SilkS")
		)
		(fp_line
			(start 0.7874 -0.4064)
			(end -0.7874 -0.4064)
			(stroke
				(width 0.1524)
				(type default)
			)
			(layer "B.SilkS")
		)
		(fp_line
			(start -0.67945 0.3048)
			(end -0.120396 0.3048)
			(stroke
				(width 0.1)
				(type default)
			)
			(layer "B.Fab")
		)
		(fp_line
			(start -0.120396 0.3048)
			(end -0.120396 0.2794)
			(stroke
				(width 0.1)
				(type default)
			)
			(layer "B.Fab")
		)
		(fp_line
			(start 0.12065 0.3048)
			(end 0.67945 0.3048)
			(stroke
				(width 0.1)
				(type default)
			)
			(layer "B.Fab")
		)
		(fp_line
			(start 0.67945 0.3048)
			(end 0.67945 -0.305054)
			(stroke
				(width 0.1)
				(type default)
			)
			(layer "B.Fab")
		)
		(fp_line
			(start -0.120396 0.2794)
			(end 0.12065 0.2794)
			(stroke
				(width 0.1)
				(type default)
			)
			(layer "B.Fab")
		)
		(fp_line
			(start 0.12065 0.2794)
			(end 0.12065 0.3048)
			(stroke
				(width 0.1)
				(type default)
			)
			(layer "B.Fab")
		)
		(fp_line
			(start -0.12065 -0.2794)
			(end -0.12065 -0.3048)
			(stroke
				(width 0.1)
				(type default)
			)
			(layer "B.Fab")
		)
		(fp_line
			(start 0.12065 -0.2794)
			(end -0.12065 -0.2794)
			(stroke
				(width 0.1)
				(type default)
			)
			(layer "B.Fab")
		)
		(fp_line
			(start -0.67945 -0.3048)
			(end -0.67945 0.3048)
			(stroke
				(width 0.1)
				(type default)
			)
			(layer "B.Fab")
		)
		(fp_line
			(start -0.12065 -0.3048)
			(end -0.67945 -0.3048)
			(stroke
				(width 0.1)
				(type default)
			)
			(layer "B.Fab")
		)
		(fp_line
			(start 0.12065 -0.305054)
			(end 0.12065 -0.2794)
			(stroke
				(width 0.1)
				(type default)
			)
			(layer "B.Fab")
		)
		(fp_line
			(start 0.67945 -0.305054)
			(end 0.12065 -0.305054)
			(stroke
				(width 0.1)
				(type default)
			)
			(layer "B.Fab")
		)
		(pad "1" smd circle
			(at 0.40005 0 90)
			(size 0 0)
			(layers "B.Cu" "B.Mask" "B.Paste")
			(net "P3V3_AUX")
		)
		(pad "2" smd circle
			(at -0.40005 0 90)
			(size 0 0)
			(layers "B.Cu" "B.Mask" "B.Paste")
			(net "GPU_FPGA_THERM_OVERT_ISO_N")
		)
	)
	(footprint ""
		(layer "B.Cu")
		(at 176.3776 -13.762228 90)
		(property "Reference" "R4507"
			(at 0 0 90)
			(layer "B.SilkS")
			(hide yes)
			(effects
				(font
					(size 1.27 1.27)
				)
				(justify mirror)
			)
		)
		(property "Value" ""
			(at 0 0 90)
			(layer "B.Fab")
			(effects
				(font
					(size 1.27 1.27)
				)
				(justify mirror)
			)
		)
		(duplicate_pad_numbers_are_jumpers no)
		(fp_line
			(start 0.7874 -0.4064)
			(end -0.7874 -0.4064)
			(stroke
				(width 0.1524)
				(type default)
			)
			(layer "B.SilkS")
		)
		(fp_line
			(start -0.7874 -0.4064)
			(end -0.7874 0.4064)
			(stroke
				(width 0.1524)
				(type default)
			)
			(layer "B.SilkS")
		)
		(fp_line
			(start 0.7874 0.4064)
			(end 0.7874 -0.4064)
			(stroke
				(width 0.1524)
				(type default)
			)
			(layer "B.SilkS")
		)
		(fp_line
			(start -0.7874 0.4064)
			(end 0.7874 0.4064)
			(stroke
				(width 0.1524)
				(type default)
			)
			(layer "B.SilkS")
		)
		(fp_line
			(start 0.67945 -0.305054)
			(end 0.12065 -0.305054)
			(stroke
				(width 0.1)
				(type default)
			)
			(layer "B.Fab")
		)
		(fp_line
			(start 0.12065 -0.305054)
			(end 0.12065 -0.2794)
			(stroke
				(width 0.1)
				(type default)
			)
			(layer "B.Fab")
		)
		(fp_line
			(start -0.12065 -0.3048)
			(end -0.67945 -0.3048)
			(stroke
				(width 0.1)
				(type default)
			)
			(layer "B.Fab")
		)
		(fp_line
			(start -0.67945 -0.3048)
			(end -0.67945 0.3048)
			(stroke
				(width 0.1)
				(type default)
			)
			(layer "B.Fab")
		)
		(fp_line
			(start 0.12065 -0.2794)
			(end -0.12065 -0.2794)
			(stroke
				(width 0.1)
				(type default)
			)
			(layer "B.Fab")
		)
		(fp_line
			(start -0.12065 -0.2794)
			(end -0.12065 -0.3048)
			(stroke
				(width 0.1)
				(type default)
			)
			(layer "B.Fab")
		)
		(fp_line
			(start 0.12065 0.2794)
			(end 0.12065 0.3048)
			(stroke
				(width 0.1)
				(type default)
			)
			(layer "B.Fab")
		)
		(fp_line
			(start -0.120396 0.2794)
			(end 0.12065 0.2794)
			(stroke
				(width 0.1)
				(type default)
			)
			(layer "B.Fab")
		)
		(fp_line
			(start 0.67945 0.3048)
			(end 0.67945 -0.305054)
			(stroke
				(width 0.1)
				(type default)
			)
			(layer "B.Fab")
		)
		(fp_line
			(start 0.12065 0.3048)
			(end 0.67945 0.3048)
			(stroke
				(width 0.1)
				(type default)
			)
			(layer "B.Fab")
		)
		(fp_line
			(start -0.120396 0.3048)
			(end -0.120396 0.2794)
			(stroke
				(width 0.1)
				(type default)
			)
			(layer "B.Fab")
		)
		(fp_line
			(start -0.67945 0.3048)
			(end -0.120396 0.3048)
			(stroke
				(width 0.1)
				(type default)
			)
			(layer "B.Fab")
		)
		(pad "1" smd circle
			(at 0.40005 0 270)
			(size 0 0)
			(layers "B.Cu" "B.Mask" "B.Paste")
			(net "SMB_CPU0_CPU1_SEC_SDA")
		)
		(pad "2" smd circle
			(at -0.40005 0 270)
			(size 0 0)
			(layers "B.Cu" "B.Mask" "B.Paste")
			(net "SMB_CPU0_CPU1_SEC_SDA_R")
		)
	)
	(footprint ""
		(layer "B.Cu")
		(at 63.385954 -177.349912 90)
		(property "Reference" "PC316_5"
			(at 0 0 90)
			(layer "B.SilkS")
			(hide yes)
			(effects
				(font
					(size 1.27 1.27)
				)
				(justify mirror)
			)
		)
		(property "Value" ""
			(at 0 0 90)
			(layer "B.Fab")
			(effects
				(font
					(size 1.27 1.27)
				)
				(justify mirror)
			)
		)
		(duplicate_pad_numbers_are_jumpers no)
		(fp_line
			(start 1.524 -0.762)
			(end -1.524 -0.762)
			(stroke
				(width 0.1524)
				(type default)
			)
			(layer "B.SilkS")
		)
		(fp_line
			(start -1.524 -0.762)
			(end -1.524 0.762)
			(stroke
				(width 0.1524)
				(type default)
			)
			(layer "B.SilkS")
		)
		(fp_line
			(start 1.524 0.762)
			(end 1.524 -0.762)
			(stroke
				(width 0.1524)
				(type default)
			)
			(layer "B.SilkS")
		)
		(fp_line
			(start -1.524 0.762)
			(end 1.524 0.762)
			(stroke
				(width 0.1524)
				(type default)
			)
			(layer "B.SilkS")
		)
		(fp_line
			(start 1.1049 -0.724916)
			(end 1.1049 0.724916)
			(stroke
				(width 0.1)
				(type default)
			)
			(layer "B.Fab")
		)
		(fp_line
			(start -1.1049 -0.724916)
			(end 1.1049 -0.724916)
			(stroke
				(width 0.1)
				(type default)
			)
			(layer "B.Fab")
		)
		(fp_line
			(start 1.1049 0.724916)
			(end -1.1049 0.724916)
			(stroke
				(width 0.1)
				(type default)
			)
			(layer "B.Fab")
		)
		(fp_line
			(start -1.1049 0.724916)
			(end -1.1049 -0.724916)
			(stroke
				(width 0.1)
				(type default)
			)
			(layer "B.Fab")
		)
		(pad "1" smd rect
			(at 0.889 0 90)
			(size 1.016 1.27)
			(layers "B.Cu" "B.Mask" "B.Paste")
			(net "PVDDCR_CPU0_P1")
		)
		(pad "2" smd rect
			(at -0.889 0 90)
			(size 1.016 1.27)
			(layers "B.Cu" "B.Mask" "B.Paste")
			(net "GND")
		)
	)
	(footprint ""
		(layer "B.Cu")
		(at 398.893538 -393.04468 180)
		(property "Reference" "R1076"
			(at 0 0 0)
			(layer "B.SilkS")
			(hide yes)
			(effects
				(font
					(size 1.27 1.27)
				)
				(justify mirror)
			)
		)
		(property "Value" ""
			(at 0 0 0)
			(layer "B.Fab")
			(effects
				(font
					(size 1.27 1.27)
				)
				(justify mirror)
			)
		)
		(duplicate_pad_numbers_are_jumpers no)
		(fp_line
			(start 0.32512 0.175006)
			(end 0.32512 -0.175006)
			(stroke
				(width 0.1)
				(type default)
			)
			(layer "B.Fab")
		)
		(fp_line
			(start 0.32512 -0.175006)
			(end -0.32512 -0.175006)
			(stroke
				(width 0.1)
				(type default)
			)
			(layer "B.Fab")
		)
		(fp_line
			(start -0.32512 0.175006)
			(end 0.32512 0.175006)
			(stroke
				(width 0.1)
				(type default)
			)
			(layer "B.Fab")
		)
		(fp_line
			(start -0.32512 -0.175006)
			(end -0.32512 0.175006)
			(stroke
				(width 0.1)
				(type default)
			)
			(layer "B.Fab")
		)
		(pad "1" smd rect
			(at 0.2667 0)
			(size 0.3048 0.381)
			(layers "B.Cu" "B.Mask" "B.Paste")
			(net "TEST1_RT_CPU0_P2")
		)
		(pad "2" smd rect
			(at -0.2667 0 180)
			(size 0.3048 0.381)
			(layers "B.Cu" "B.Mask" "B.Paste")
			(net "GND")
		)
	)
	(footprint ""
		(layer "B.Cu")
		(at 396.168372 -395.127988 -90)
		(property "Reference" "C994"
			(at 0 0 90)
			(layer "B.SilkS")
			(hide yes)
			(effects
				(font
					(size 1.27 1.27)
				)
				(justify mirror)
			)
		)
		(property "Value" ""
			(at 0 0 90)
			(layer "B.Fab")
			(effects
				(font
					(size 1.27 1.27)
				)
				(justify mirror)
			)
		)
		(duplicate_pad_numbers_are_jumpers no)
		(fp_line
			(start -0.7874 0.4064)
			(end 0.7874 0.4064)
			(stroke
				(width 0.1524)
				(type default)
			)
			(layer "B.SilkS")
		)
		(fp_line
			(start 0.7874 0.4064)
			(end 0.7874 -0.4064)
			(stroke
				(width 0.1524)
				(type default)
			)
			(layer "B.SilkS")
		)
		(fp_line
			(start -0.7874 -0.4064)
			(end -0.7874 0.4064)
			(stroke
				(width 0.1524)
				(type default)
			)
			(layer "B.SilkS")
		)
		(fp_line
			(start 0.7874 -0.4064)
			(end -0.7874 -0.4064)
			(stroke
				(width 0.1524)
				(type default)
			)
			(layer "B.SilkS")
		)
		(fp_line
			(start -0.67945 0.3048)
			(end -0.120396 0.3048)
			(stroke
				(width 0.1)
				(type default)
			)
			(layer "B.Fab")
		)
		(fp_line
			(start -0.120396 0.3048)
			(end -0.120396 0.2794)
			(stroke
				(width 0.1)
				(type default)
			)
			(layer "B.Fab")
		)
		(fp_line
			(start 0.12065 0.3048)
			(end 0.67945 0.3048)
			(stroke
				(width 0.1)
				(type default)
			)
			(layer "B.Fab")
		)
		(fp_line
			(start 0.67945 0.3048)
			(end 0.67945 -0.305054)
			(stroke
				(width 0.1)
				(type default)
			)
			(layer "B.Fab")
		)
		(fp_line
			(start -0.120396 0.2794)
			(end 0.12065 0.2794)
			(stroke
				(width 0.1)
				(type default)
			)
			(layer "B.Fab")
		)
		(fp_line
			(start 0.12065 0.2794)
			(end 0.12065 0.3048)
			(stroke
				(width 0.1)
				(type default)
			)
			(layer "B.Fab")
		)
		(fp_line
			(start -0.12065 -0.2794)
			(end -0.12065 -0.3048)
			(stroke
				(width 0.1)
				(type default)
			)
			(layer "B.Fab")
		)
		(fp_line
			(start 0.12065 -0.2794)
			(end -0.12065 -0.2794)
			(stroke
				(width 0.1)
				(type default)
			)
			(layer "B.Fab")
		)
		(fp_line
			(start -0.67945 -0.3048)
			(end -0.67945 0.3048)
			(stroke
				(width 0.1)
				(type default)
			)
			(layer "B.Fab")
		)
		(fp_line
			(start -0.12065 -0.3048)
			(end -0.67945 -0.3048)
			(stroke
				(width 0.1)
				(type default)
			)
			(layer "B.Fab")
		)
		(fp_line
			(start 0.12065 -0.305054)
			(end 0.12065 -0.2794)
			(stroke
				(width 0.1)
				(type default)
			)
			(layer "B.Fab")
		)
		(fp_line
			(start 0.67945 -0.305054)
			(end 0.12065 -0.305054)
			(stroke
				(width 0.1)
				(type default)
			)
			(layer "B.Fab")
		)
		(pad "1" smd circle
			(at 0.40005 0 90)
			(size 0 0)
			(layers "B.Cu" "B.Mask" "B.Paste")
			(net "P1V8_CPU0_RT_1D")
		)
		(pad "2" smd circle
			(at -0.40005 0 90)
			(size 0 0)
			(layers "B.Cu" "B.Mask" "B.Paste")
			(net "GND")
		)
	)
	(footprint ""
		(layer "B.Cu")
		(at 191.271144 -77.27823 -90)
		(property "Reference" "R3237"
			(at 0 0 90)
			(layer "B.SilkS")
			(hide yes)
			(effects
				(font
					(size 1.27 1.27)
				)
				(justify mirror)
			)
		)
		(property "Value" ""
			(at 0 0 90)
			(layer "B.Fab")
			(effects
				(font
					(size 1.27 1.27)
				)
				(justify mirror)
			)
		)
		(duplicate_pad_numbers_are_jumpers no)
		(fp_line
			(start -0.7874 0.4064)
			(end 0.7874 0.4064)
			(stroke
				(width 0.1524)
				(type default)
			)
			(layer "B.SilkS")
		)
		(fp_line
			(start 0.7874 0.4064)
			(end 0.7874 -0.4064)
			(stroke
				(width 0.1524)
				(type default)
			)
			(layer "B.SilkS")
		)
		(fp_line
			(start -0.7874 -0.4064)
			(end -0.7874 0.4064)
			(stroke
				(width 0.1524)
				(type default)
			)
			(layer "B.SilkS")
		)
		(fp_line
			(start 0.7874 -0.4064)
			(end -0.7874 -0.4064)
			(stroke
				(width 0.1524)
				(type default)
			)
			(layer "B.SilkS")
		)
		(fp_line
			(start -0.67945 0.3048)
			(end -0.120396 0.3048)
			(stroke
				(width 0.1)
				(type default)
			)
			(layer "B.Fab")
		)
		(fp_line
			(start -0.120396 0.3048)
			(end -0.120396 0.2794)
			(stroke
				(width 0.1)
				(type default)
			)
			(layer "B.Fab")
		)
		(fp_line
			(start 0.12065 0.3048)
			(end 0.67945 0.3048)
			(stroke
				(width 0.1)
				(type default)
			)
			(layer "B.Fab")
		)
		(fp_line
			(start 0.67945 0.3048)
			(end 0.67945 -0.305054)
			(stroke
				(width 0.1)
				(type default)
			)
			(layer "B.Fab")
		)
		(fp_line
			(start -0.120396 0.2794)
			(end 0.12065 0.2794)
			(stroke
				(width 0.1)
				(type default)
			)
			(layer "B.Fab")
		)
		(fp_line
			(start 0.12065 0.2794)
			(end 0.12065 0.3048)
			(stroke
				(width 0.1)
				(type default)
			)
			(layer "B.Fab")
		)
		(fp_line
			(start -0.12065 -0.2794)
			(end -0.12065 -0.3048)
			(stroke
				(width 0.1)
				(type default)
			)
			(layer "B.Fab")
		)
		(fp_line
			(start 0.12065 -0.2794)
			(end -0.12065 -0.2794)
			(stroke
				(width 0.1)
				(type default)
			)
			(layer "B.Fab")
		)
		(fp_line
			(start -0.67945 -0.3048)
			(end -0.67945 0.3048)
			(stroke
				(width 0.1)
				(type default)
			)
			(layer "B.Fab")
		)
		(fp_line
			(start -0.12065 -0.3048)
			(end -0.67945 -0.3048)
			(stroke
				(width 0.1)
				(type default)
			)
			(layer "B.Fab")
		)
		(fp_line
			(start 0.12065 -0.305054)
			(end 0.12065 -0.2794)
			(stroke
				(width 0.1)
				(type default)
			)
			(layer "B.Fab")
		)
		(fp_line
			(start 0.67945 -0.305054)
			(end 0.12065 -0.305054)
			(stroke
				(width 0.1)
				(type default)
			)
			(layer "B.Fab")
		)
		(pad "1" smd circle
			(at 0.40005 0 90)
			(size 0 0)
			(layers "B.Cu" "B.Mask" "B.Paste")
			(net "OCP_SFF_RBT_ARB_OUT")
		)
		(pad "2" smd circle
			(at -0.40005 0 90)
			(size 0 0)
			(layers "B.Cu" "B.Mask" "B.Paste")
			(net "OCP_SFF_RBT_ARB_IN_R")
		)
	)
	(footprint ""
		(layer "B.Cu")
		(at 115.864386 -264.354564)
		(property "Reference" "C2496"
			(at 0 0 0)
			(layer "B.SilkS")
			(hide yes)
			(effects
				(font
					(size 1.27 1.27)
				)
				(justify mirror)
			)
		)
		(property "Value" ""
			(at 0 0 0)
			(layer "B.Fab")
			(effects
				(font
					(size 1.27 1.27)
				)
				(justify mirror)
			)
		)
		(duplicate_pad_numbers_are_jumpers no)
		(fp_line
			(start -0.7874 -0.4064)
			(end -0.7874 0.4064)
			(stroke
				(width 0.1524)
				(type default)
			)
			(layer "B.SilkS")
		)
		(fp_line
			(start -0.7874 0.4064)
			(end 0.7874 0.4064)
			(stroke
				(width 0.1524)
				(type default)
			)
			(layer "B.SilkS")
		)
		(fp_line
			(start 0.7874 -0.4064)
			(end -0.7874 -0.4064)
			(stroke
				(width 0.1524)
				(type default)
			)
			(layer "B.SilkS")
		)
		(fp_line
			(start 0.7874 0.4064)
			(end 0.7874 -0.4064)
			(stroke
				(width 0.1524)
				(type default)
			)
			(layer "B.SilkS")
		)
		(fp_line
			(start -0.67945 -0.3048)
			(end -0.67945 0.3048)
			(stroke
				(width 0.1)
				(type default)
			)
			(layer "B.Fab")
		)
		(fp_line
			(start -0.67945 0.3048)
			(end -0.120396 0.3048)
			(stroke
				(width 0.1)
				(type default)
			)
			(layer "B.Fab")
		)
		(fp_line
			(start -0.12065 -0.3048)
			(end -0.67945 -0.3048)
			(stroke
				(width 0.1)
				(type default)
			)
			(layer "B.Fab")
		)
		(fp_line
			(start -0.12065 -0.2794)
			(end -0.12065 -0.3048)
			(stroke
				(width 0.1)
				(type default)
			)
			(layer "B.Fab")
		)
		(fp_line
			(start -0.120396 0.2794)
			(end 0.12065 0.2794)
			(stroke
				(width 0.1)
				(type default)
			)
			(layer "B.Fab")
		)
		(fp_line
			(start -0.120396 0.3048)
			(end -0.120396 0.2794)
			(stroke
				(width 0.1)
				(type default)
			)
			(layer "B.Fab")
		)
		(fp_line
			(start 0.12065 -0.305054)
			(end 0.12065 -0.2794)
			(stroke
				(width 0.1)
				(type default)
			)
			(layer "B.Fab")
		)
		(fp_line
			(start 0.12065 -0.2794)
			(end -0.12065 -0.2794)
			(stroke
				(width 0.1)
				(type default)
			)
			(layer "B.Fab")
		)
		(fp_line
			(start 0.12065 0.2794)
			(end 0.12065 0.3048)
			(stroke
				(width 0.1)
				(type default)
			)
			(layer "B.Fab")
		)
		(fp_line
			(start 0.12065 0.3048)
			(end 0.67945 0.3048)
			(stroke
				(width 0.1)
				(type default)
			)
			(layer "B.Fab")
		)
		(fp_line
			(start 0.67945 -0.305054)
			(end 0.12065 -0.305054)
			(stroke
				(width 0.1)
				(type default)
			)
			(layer "B.Fab")
		)
		(fp_line
			(start 0.67945 0.3048)
			(end 0.67945 -0.305054)
			(stroke
				(width 0.1)
				(type default)
			)
			(layer "B.Fab")
		)
		(pad "1" smd circle
			(at 0.40005 0 180)
			(size 0 0)
			(layers "B.Cu" "B.Mask" "B.Paste")
			(net "PVDD11_S3_P1")
		)
		(pad "2" smd circle
			(at -0.40005 0 180)
			(size 0 0)
			(layers "B.Cu" "B.Mask" "B.Paste")
			(net "GND")
		)
	)
	(footprint ""
		(layer "B.Cu")
		(at 175.316642 -194.8942 180)
		(property "Reference" "R1587"
			(at 0 0 0)
			(layer "B.SilkS")
			(hide yes)
			(effects
				(font
					(size 1.27 1.27)
				)
				(justify mirror)
			)
		)
		(property "Value" ""
			(at 0 0 0)
			(layer "B.Fab")
			(effects
				(font
					(size 1.27 1.27)
				)
				(justify mirror)
			)
		)
		(duplicate_pad_numbers_are_jumpers no)
		(fp_line
			(start 0.7874 0.4064)
			(end 0.7874 -0.4064)
			(stroke
				(width 0.1524)
				(type default)
			)
			(layer "B.SilkS")
		)
		(fp_line
			(start 0.7874 -0.4064)
			(end -0.7874 -0.4064)
			(stroke
				(width 0.1524)
				(type default)
			)
			(layer "B.SilkS")
		)
		(fp_line
			(start -0.7874 0.4064)
			(end 0.7874 0.4064)
			(stroke
				(width 0.1524)
				(type default)
			)
			(layer "B.SilkS")
		)
		(fp_line
			(start -0.7874 -0.4064)
			(end -0.7874 0.4064)
			(stroke
				(width 0.1524)
				(type default)
			)
			(layer "B.SilkS")
		)
		(fp_line
			(start 0.67945 0.3048)
			(end 0.67945 -0.305054)
			(stroke
				(width 0.1)
				(type default)
			)
			(layer "B.Fab")
		)
		(fp_line
			(start 0.67945 -0.305054)
			(end 0.12065 -0.305054)
			(stroke
				(width 0.1)
				(type default)
			)
			(layer "B.Fab")
		)
		(fp_line
			(start 0.12065 0.3048)
			(end 0.67945 0.3048)
			(stroke
				(width 0.1)
				(type default)
			)
			(layer "B.Fab")
		)
		(fp_line
			(start 0.12065 0.2794)
			(end 0.12065 0.3048)
			(stroke
				(width 0.1)
				(type default)
			)
			(layer "B.Fab")
		)
		(fp_line
			(start 0.12065 -0.2794)
			(end -0.12065 -0.2794)
			(stroke
				(width 0.1)
				(type default)
			)
			(layer "B.Fab")
		)
		(fp_line
			(start 0.12065 -0.305054)
			(end 0.12065 -0.2794)
			(stroke
				(width 0.1)
				(type default)
			)
			(layer "B.Fab")
		)
		(fp_line
			(start -0.120396 0.3048)
			(end -0.120396 0.2794)
			(stroke
				(width 0.1)
				(type default)
			)
			(layer "B.Fab")
		)
		(fp_line
			(start -0.120396 0.2794)
			(end 0.12065 0.2794)
			(stroke
				(width 0.1)
				(type default)
			)
			(layer "B.Fab")
		)
		(fp_line
			(start -0.12065 -0.2794)
			(end -0.12065 -0.3048)
			(stroke
				(width 0.1)
				(type default)
			)
			(layer "B.Fab")
		)
		(fp_line
			(start -0.12065 -0.3048)
			(end -0.67945 -0.3048)
			(stroke
				(width 0.1)
				(type default)
			)
			(layer "B.Fab")
		)
		(fp_line
			(start -0.67945 0.3048)
			(end -0.120396 0.3048)
			(stroke
				(width 0.1)
				(type default)
			)
			(layer "B.Fab")
		)
		(fp_line
			(start -0.67945 -0.3048)
			(end -0.67945 0.3048)
			(stroke
				(width 0.1)
				(type default)
			)
			(layer "B.Fab")
		)
		(pad "1" smd circle
			(at 0.40005 0)
			(size 0 0)
			(layers "B.Cu" "B.Mask" "B.Paste")
			(net "I3C_SPD_DDRGL_CPU1_SCL")
		)
		(pad "2" smd circle
			(at -0.40005 0)
			(size 0 0)
			(layers "B.Cu" "B.Mask" "B.Paste")
			(net "I3C_SPD_DDRH_CPU1_SCL")
		)
	)
	(footprint ""
		(layer "B.Cu")
		(at 372.937278 -146.552158 180)
		(property "Reference" "R8304"
			(at 0 0 0)
			(layer "B.SilkS")
			(hide yes)
			(effects
				(font
					(size 1.27 1.27)
				)
				(justify mirror)
			)
		)
		(property "Value" ""
			(at 0 0 0)
			(layer "B.Fab")
			(effects
				(font
					(size 1.27 1.27)
				)
				(justify mirror)
			)
		)
		(duplicate_pad_numbers_are_jumpers no)
		(fp_line
			(start 0.7874 0.4064)
			(end 0.7874 -0.4064)
			(stroke
				(width 0.1524)
				(type default)
			)
			(layer "B.SilkS")
		)
		(fp_line
			(start 0.7874 -0.4064)
			(end -0.7874 -0.4064)
			(stroke
				(width 0.1524)
				(type default)
			)
			(layer "B.SilkS")
		)
		(fp_line
			(start -0.7874 0.4064)
			(end 0.7874 0.4064)
			(stroke
				(width 0.1524)
				(type default)
			)
			(layer "B.SilkS")
		)
		(fp_line
			(start -0.7874 -0.4064)
			(end -0.7874 0.4064)
			(stroke
				(width 0.1524)
				(type default)
			)
			(layer "B.SilkS")
		)
		(fp_line
			(start 0.67945 0.3048)
			(end 0.67945 -0.305054)
			(stroke
				(width 0.1)
				(type default)
			)
			(layer "B.Fab")
		)
		(fp_line
			(start 0.67945 -0.305054)
			(end 0.12065 -0.305054)
			(stroke
				(width 0.1)
				(type default)
			)
			(layer "B.Fab")
		)
		(fp_line
			(start 0.12065 0.3048)
			(end 0.67945 0.3048)
			(stroke
				(width 0.1)
				(type default)
			)
			(layer "B.Fab")
		)
		(fp_line
			(start 0.12065 0.2794)
			(end 0.12065 0.3048)
			(stroke
				(width 0.1)
				(type default)
			)
			(layer "B.Fab")
		)
		(fp_line
			(start 0.12065 -0.2794)
			(end -0.12065 -0.2794)
			(stroke
				(width 0.1)
				(type default)
			)
			(layer "B.Fab")
		)
		(fp_line
			(start 0.12065 -0.305054)
			(end 0.12065 -0.2794)
			(stroke
				(width 0.1)
				(type default)
			)
			(layer "B.Fab")
		)
		(fp_line
			(start -0.120396 0.3048)
			(end -0.120396 0.2794)
			(stroke
				(width 0.1)
				(type default)
			)
			(layer "B.Fab")
		)
		(fp_line
			(start -0.120396 0.2794)
			(end 0.12065 0.2794)
			(stroke
				(width 0.1)
				(type default)
			)
			(layer "B.Fab")
		)
		(fp_line
			(start -0.12065 -0.2794)
			(end -0.12065 -0.3048)
			(stroke
				(width 0.1)
				(type default)
			)
			(layer "B.Fab")
		)
		(fp_line
			(start -0.12065 -0.3048)
			(end -0.67945 -0.3048)
			(stroke
				(width 0.1)
				(type default)
			)
			(layer "B.Fab")
		)
		(fp_line
			(start -0.67945 0.3048)
			(end -0.120396 0.3048)
			(stroke
				(width 0.1)
				(type default)
			)
			(layer "B.Fab")
		)
		(fp_line
			(start -0.67945 -0.3048)
			(end -0.67945 0.3048)
			(stroke
				(width 0.1)
				(type default)
			)
			(layer "B.Fab")
		)
		(pad "1" smd circle
			(at 0.40005 0)
			(size 0 0)
			(layers "B.Cu" "B.Mask" "B.Paste")
			(net "SVID_PVDDCR_CPU0_P0_SVTO")
		)
		(pad "2" smd circle
			(at -0.40005 0)
			(size 0 0)
			(layers "B.Cu" "B.Mask" "B.Paste")
			(net "SVID_PVDDCR_CPU0_P0_SVTO_R")
		)
	)
	(footprint ""
		(layer "B.Cu")
		(at 346.987876 -66.708782 90)
		(property "Reference" "R3097"
			(at 0 0 90)
			(layer "B.SilkS")
			(hide yes)
			(effects
				(font
					(size 1.27 1.27)
				)
				(justify mirror)
			)
		)
		(property "Value" ""
			(at 0 0 90)
			(layer "B.Fab")
			(effects
				(font
					(size 1.27 1.27)
				)
				(justify mirror)
			)
		)
		(duplicate_pad_numbers_are_jumpers no)
		(fp_line
			(start 0.7874 -0.4064)
			(end -0.7874 -0.4064)
			(stroke
				(width 0.1524)
				(type default)
			)
			(layer "B.SilkS")
		)
		(fp_line
			(start -0.7874 -0.4064)
			(end -0.7874 0.4064)
			(stroke
				(width 0.1524)
				(type default)
			)
			(layer "B.SilkS")
		)
		(fp_line
			(start 0.7874 0.4064)
			(end 0.7874 -0.4064)
			(stroke
				(width 0.1524)
				(type default)
			)
			(layer "B.SilkS")
		)
		(fp_line
			(start -0.7874 0.4064)
			(end 0.7874 0.4064)
			(stroke
				(width 0.1524)
				(type default)
			)
			(layer "B.SilkS")
		)
		(fp_line
			(start 0.67945 -0.305054)
			(end 0.12065 -0.305054)
			(stroke
				(width 0.1)
				(type default)
			)
			(layer "B.Fab")
		)
		(fp_line
			(start 0.12065 -0.305054)
			(end 0.12065 -0.2794)
			(stroke
				(width 0.1)
				(type default)
			)
			(layer "B.Fab")
		)
		(fp_line
			(start -0.12065 -0.3048)
			(end -0.67945 -0.3048)
			(stroke
				(width 0.1)
				(type default)
			)
			(layer "B.Fab")
		)
		(fp_line
			(start -0.67945 -0.3048)
			(end -0.67945 0.3048)
			(stroke
				(width 0.1)
				(type default)
			)
			(layer "B.Fab")
		)
		(fp_line
			(start 0.12065 -0.2794)
			(end -0.12065 -0.2794)
			(stroke
				(width 0.1)
				(type default)
			)
			(layer "B.Fab")
		)
		(fp_line
			(start -0.12065 -0.2794)
			(end -0.12065 -0.3048)
			(stroke
				(width 0.1)
				(type default)
			)
			(layer "B.Fab")
		)
		(fp_line
			(start 0.12065 0.2794)
			(end 0.12065 0.3048)
			(stroke
				(width 0.1)
				(type default)
			)
			(layer "B.Fab")
		)
		(fp_line
			(start -0.120396 0.2794)
			(end 0.12065 0.2794)
			(stroke
				(width 0.1)
				(type default)
			)
			(layer "B.Fab")
		)
		(fp_line
			(start 0.67945 0.3048)
			(end 0.67945 -0.305054)
			(stroke
				(width 0.1)
				(type default)
			)
			(layer "B.Fab")
		)
		(fp_line
			(start 0.12065 0.3048)
			(end 0.67945 0.3048)
			(stroke
				(width 0.1)
				(type default)
			)
			(layer "B.Fab")
		)
		(fp_line
			(start -0.120396 0.3048)
			(end -0.120396 0.2794)
			(stroke
				(width 0.1)
				(type default)
			)
			(layer "B.Fab")
		)
		(fp_line
			(start -0.67945 0.3048)
			(end -0.120396 0.3048)
			(stroke
				(width 0.1)
				(type default)
			)
			(layer "B.Fab")
		)
		(pad "1" smd circle
			(at 0.40005 0 270)
			(size 0 0)
			(layers "B.Cu" "B.Mask" "B.Paste")
			(net "LED_PWRGD_PVDD18_S5_P1_R")
		)
		(pad "2" smd circle
			(at -0.40005 0 270)
			(size 0 0)
			(layers "B.Cu" "B.Mask" "B.Paste")
			(net "P3V3_AUX")
		)
	)
	(footprint ""
		(layer "B.Cu")
		(at 301.48657 -350.65589 -90)
		(property "Reference" "PC154_1"
			(at 0 0 90)
			(layer "B.SilkS")
			(hide yes)
			(effects
				(font
					(size 1.27 1.27)
				)
				(justify mirror)
			)
		)
		(property "Value" ""
			(at 0 0 90)
			(layer "B.Fab")
			(effects
				(font
					(size 1.27 1.27)
				)
				(justify mirror)
			)
		)
		(duplicate_pad_numbers_are_jumpers no)
		(fp_line
			(start -1.524 0.762)
			(end 1.524 0.762)
			(stroke
				(width 0.1524)
				(type default)
			)
			(layer "B.SilkS")
		)
		(fp_line
			(start 1.524 0.762)
			(end 1.524 -0.762)
			(stroke
				(width 0.1524)
				(type default)
			)
			(layer "B.SilkS")
		)
		(fp_line
			(start -1.524 -0.762)
			(end -1.524 0.762)
			(stroke
				(width 0.1524)
				(type default)
			)
			(layer "B.SilkS")
		)
		(fp_line
			(start 1.524 -0.762)
			(end -1.524 -0.762)
			(stroke
				(width 0.1524)
				(type default)
			)
			(layer "B.SilkS")
		)
		(fp_line
			(start -1.1049 0.724916)
			(end -1.1049 -0.724916)
			(stroke
				(width 0.1)
				(type default)
			)
			(layer "B.Fab")
		)
		(fp_line
			(start 1.1049 0.724916)
			(end -1.1049 0.724916)
			(stroke
				(width 0.1)
				(type default)
			)
			(layer "B.Fab")
		)
		(fp_line
			(start -1.1049 -0.724916)
			(end 1.1049 -0.724916)
			(stroke
				(width 0.1)
				(type default)
			)
			(layer "B.Fab")
		)
		(fp_line
			(start 1.1049 -0.724916)
			(end 1.1049 0.724916)
			(stroke
				(width 0.1)
				(type default)
			)
			(layer "B.Fab")
		)
		(pad "1" smd rect
			(at 0.889 0 270)
			(size 1.016 1.27)
			(layers "B.Cu" "B.Mask" "B.Paste")
			(net "SW_P12V_AUX_PVDDIO_P0_FLT")
		)
		(pad "2" smd rect
			(at -0.889 0 270)
			(size 1.016 1.27)
			(layers "B.Cu" "B.Mask" "B.Paste")
			(net "GND")
		)
	)
	(footprint ""
		(layer "B.Cu")
		(at 48.555148 -193.996564)
		(property "Reference" "R104"
			(at 0 0 0)
			(layer "B.SilkS")
			(hide yes)
			(effects
				(font
					(size 1.27 1.27)
				)
				(justify mirror)
			)
		)
		(property "Value" ""
			(at 0 0 0)
			(layer "B.Fab")
			(effects
				(font
					(size 1.27 1.27)
				)
				(justify mirror)
			)
		)
		(duplicate_pad_numbers_are_jumpers no)
		(fp_line
			(start -0.7874 -0.4064)
			(end -0.7874 0.4064)
			(stroke
				(width 0.1524)
				(type default)
			)
			(layer "B.SilkS")
		)
		(fp_line
			(start -0.7874 0.4064)
			(end 0.7874 0.4064)
			(stroke
				(width 0.1524)
				(type default)
			)
			(layer "B.SilkS")
		)
		(fp_line
			(start 0.7874 -0.4064)
			(end -0.7874 -0.4064)
			(stroke
				(width 0.1524)
				(type default)
			)
			(layer "B.SilkS")
		)
		(fp_line
			(start 0.7874 0.4064)
			(end 0.7874 -0.4064)
			(stroke
				(width 0.1524)
				(type default)
			)
			(layer "B.SilkS")
		)
		(fp_line
			(start -0.67945 -0.3048)
			(end -0.67945 0.3048)
			(stroke
				(width 0.1)
				(type default)
			)
			(layer "B.Fab")
		)
		(fp_line
			(start -0.67945 0.3048)
			(end -0.120396 0.3048)
			(stroke
				(width 0.1)
				(type default)
			)
			(layer "B.Fab")
		)
		(fp_line
			(start -0.12065 -0.3048)
			(end -0.67945 -0.3048)
			(stroke
				(width 0.1)
				(type default)
			)
			(layer "B.Fab")
		)
		(fp_line
			(start -0.12065 -0.2794)
			(end -0.12065 -0.3048)
			(stroke
				(width 0.1)
				(type default)
			)
			(layer "B.Fab")
		)
		(fp_line
			(start -0.120396 0.2794)
			(end 0.12065 0.2794)
			(stroke
				(width 0.1)
				(type default)
			)
			(layer "B.Fab")
		)
		(fp_line
			(start -0.120396 0.3048)
			(end -0.120396 0.2794)
			(stroke
				(width 0.1)
				(type default)
			)
			(layer "B.Fab")
		)
		(fp_line
			(start 0.12065 -0.305054)
			(end 0.12065 -0.2794)
			(stroke
				(width 0.1)
				(type default)
			)
			(layer "B.Fab")
		)
		(fp_line
			(start 0.12065 -0.2794)
			(end -0.12065 -0.2794)
			(stroke
				(width 0.1)
				(type default)
			)
			(layer "B.Fab")
		)
		(fp_line
			(start 0.12065 0.2794)
			(end 0.12065 0.3048)
			(stroke
				(width 0.1)
				(type default)
			)
			(layer "B.Fab")
		)
		(fp_line
			(start 0.12065 0.3048)
			(end 0.67945 0.3048)
			(stroke
				(width 0.1)
				(type default)
			)
			(layer "B.Fab")
		)
		(fp_line
			(start 0.67945 -0.305054)
			(end 0.12065 -0.305054)
			(stroke
				(width 0.1)
				(type default)
			)
			(layer "B.Fab")
		)
		(fp_line
			(start 0.67945 0.3048)
			(end 0.67945 -0.305054)
			(stroke
				(width 0.1)
				(type default)
			)
			(layer "B.Fab")
		)
		(pad "1" smd circle
			(at 0.40005 0 180)
			(size 0 0)
			(layers "B.Cu" "B.Mask" "B.Paste")
			(net "P3V3")
		)
		(pad "2" smd circle
			(at -0.40005 0 180)
			(size 0 0)
			(layers "B.Cu" "B.Mask" "B.Paste")
			(net "PWRGD_CHB_CPU1_DIMM")
		)
	)
	(footprint ""
		(layer "B.Cu")
		(at 372.937278 -144.520158 180)
		(property "Reference" "PR8006"
			(at 0 0 0)
			(layer "B.SilkS")
			(hide yes)
			(effects
				(font
					(size 1.27 1.27)
				)
				(justify mirror)
			)
		)
		(property "Value" ""
			(at 0 0 0)
			(layer "B.Fab")
			(effects
				(font
					(size 1.27 1.27)
				)
				(justify mirror)
			)
		)
		(duplicate_pad_numbers_are_jumpers no)
		(fp_line
			(start 0.7874 0.4064)
			(end 0.7874 -0.4064)
			(stroke
				(width 0.1524)
				(type default)
			)
			(layer "B.SilkS")
		)
		(fp_line
			(start 0.7874 -0.4064)
			(end -0.7874 -0.4064)
			(stroke
				(width 0.1524)
				(type default)
			)
			(layer "B.SilkS")
		)
		(fp_line
			(start -0.7874 0.4064)
			(end 0.7874 0.4064)
			(stroke
				(width 0.1524)
				(type default)
			)
			(layer "B.SilkS")
		)
		(fp_line
			(start -0.7874 -0.4064)
			(end -0.7874 0.4064)
			(stroke
				(width 0.1524)
				(type default)
			)
			(layer "B.SilkS")
		)
		(fp_line
			(start 0.67945 0.3048)
			(end 0.67945 -0.305054)
			(stroke
				(width 0.1)
				(type default)
			)
			(layer "B.Fab")
		)
		(fp_line
			(start 0.67945 -0.305054)
			(end 0.12065 -0.305054)
			(stroke
				(width 0.1)
				(type default)
			)
			(layer "B.Fab")
		)
		(fp_line
			(start 0.12065 0.3048)
			(end 0.67945 0.3048)
			(stroke
				(width 0.1)
				(type default)
			)
			(layer "B.Fab")
		)
		(fp_line
			(start 0.12065 0.2794)
			(end 0.12065 0.3048)
			(stroke
				(width 0.1)
				(type default)
			)
			(layer "B.Fab")
		)
		(fp_line
			(start 0.12065 -0.2794)
			(end -0.12065 -0.2794)
			(stroke
				(width 0.1)
				(type default)
			)
			(layer "B.Fab")
		)
		(fp_line
			(start 0.12065 -0.305054)
			(end 0.12065 -0.2794)
			(stroke
				(width 0.1)
				(type default)
			)
			(layer "B.Fab")
		)
		(fp_line
			(start -0.120396 0.3048)
			(end -0.120396 0.2794)
			(stroke
				(width 0.1)
				(type default)
			)
			(layer "B.Fab")
		)
		(fp_line
			(start -0.120396 0.2794)
			(end 0.12065 0.2794)
			(stroke
				(width 0.1)
				(type default)
			)
			(layer "B.Fab")
		)
		(fp_line
			(start -0.12065 -0.2794)
			(end -0.12065 -0.3048)
			(stroke
				(width 0.1)
				(type default)
			)
			(layer "B.Fab")
		)
		(fp_line
			(start -0.12065 -0.3048)
			(end -0.67945 -0.3048)
			(stroke
				(width 0.1)
				(type default)
			)
			(layer "B.Fab")
		)
		(fp_line
			(start -0.67945 0.3048)
			(end -0.120396 0.3048)
			(stroke
				(width 0.1)
				(type default)
			)
			(layer "B.Fab")
		)
		(fp_line
			(start -0.67945 -0.3048)
			(end -0.67945 0.3048)
			(stroke
				(width 0.1)
				(type default)
			)
			(layer "B.Fab")
		)
		(pad "1" smd circle
			(at 0.40005 0)
			(size 0 0)
			(layers "B.Cu" "B.Mask" "B.Paste")
			(net "SVID_PVDDCR_CPU0_P0_SVD_R")
		)
		(pad "2" smd circle
			(at -0.40005 0)
			(size 0 0)
			(layers "B.Cu" "B.Mask" "B.Paste")
			(net "SVID_PVDDCR_CPU0_P0_SVD_R1")
		)
	)
	(footprint ""
		(layer "B.Cu")
		(at 429.40224 -108.867448 90)
		(property "Reference" "R3785"
			(at 0 0 90)
			(layer "B.SilkS")
			(hide yes)
			(effects
				(font
					(size 1.27 1.27)
				)
				(justify mirror)
			)
		)
		(property "Value" ""
			(at 0 0 90)
			(layer "B.Fab")
			(effects
				(font
					(size 1.27 1.27)
				)
				(justify mirror)
			)
		)
		(duplicate_pad_numbers_are_jumpers no)
		(fp_line
			(start 0.7874 -0.4064)
			(end -0.7874 -0.4064)
			(stroke
				(width 0.1524)
				(type default)
			)
			(layer "B.SilkS")
		)
		(fp_line
			(start -0.7874 -0.4064)
			(end -0.7874 0.4064)
			(stroke
				(width 0.1524)
				(type default)
			)
			(layer "B.SilkS")
		)
		(fp_line
			(start 0.7874 0.4064)
			(end 0.7874 -0.4064)
			(stroke
				(width 0.1524)
				(type default)
			)
			(layer "B.SilkS")
		)
		(fp_line
			(start -0.7874 0.4064)
			(end 0.7874 0.4064)
			(stroke
				(width 0.1524)
				(type default)
			)
			(layer "B.SilkS")
		)
		(fp_line
			(start 0.67945 -0.305054)
			(end 0.12065 -0.305054)
			(stroke
				(width 0.1)
				(type default)
			)
			(layer "B.Fab")
		)
		(fp_line
			(start 0.12065 -0.305054)
			(end 0.12065 -0.2794)
			(stroke
				(width 0.1)
				(type default)
			)
			(layer "B.Fab")
		)
		(fp_line
			(start -0.12065 -0.3048)
			(end -0.67945 -0.3048)
			(stroke
				(width 0.1)
				(type default)
			)
			(layer "B.Fab")
		)
		(fp_line
			(start -0.67945 -0.3048)
			(end -0.67945 0.3048)
			(stroke
				(width 0.1)
				(type default)
			)
			(layer "B.Fab")
		)
		(fp_line
			(start 0.12065 -0.2794)
			(end -0.12065 -0.2794)
			(stroke
				(width 0.1)
				(type default)
			)
			(layer "B.Fab")
		)
		(fp_line
			(start -0.12065 -0.2794)
			(end -0.12065 -0.3048)
			(stroke
				(width 0.1)
				(type default)
			)
			(layer "B.Fab")
		)
		(fp_line
			(start 0.12065 0.2794)
			(end 0.12065 0.3048)
			(stroke
				(width 0.1)
				(type default)
			)
			(layer "B.Fab")
		)
		(fp_line
			(start -0.120396 0.2794)
			(end 0.12065 0.2794)
			(stroke
				(width 0.1)
				(type default)
			)
			(layer "B.Fab")
		)
		(fp_line
			(start 0.67945 0.3048)
			(end 0.67945 -0.305054)
			(stroke
				(width 0.1)
				(type default)
			)
			(layer "B.Fab")
		)
		(fp_line
			(start 0.12065 0.3048)
			(end 0.67945 0.3048)
			(stroke
				(width 0.1)
				(type default)
			)
			(layer "B.Fab")
		)
		(fp_line
			(start -0.120396 0.3048)
			(end -0.120396 0.2794)
			(stroke
				(width 0.1)
				(type default)
			)
			(layer "B.Fab")
		)
		(fp_line
			(start -0.67945 0.3048)
			(end -0.120396 0.3048)
			(stroke
				(width 0.1)
				(type default)
			)
			(layer "B.Fab")
		)
		(pad "1" smd circle
			(at 0.40005 0 270)
			(size 0 0)
			(layers "B.Cu" "B.Mask" "B.Paste")
			(net "P3V3_OCP_UV_1_R1")
		)
		(pad "2" smd circle
			(at -0.40005 0 270)
			(size 0 0)
			(layers "B.Cu" "B.Mask" "B.Paste")
			(net "P3V3_OCP_UV_1")
		)
	)
	(footprint ""
		(layer "B.Cu")
		(at 36.040568 -195.8848 180)
		(property "Reference" "R1699"
			(at 0 0 0)
			(layer "B.SilkS")
			(hide yes)
			(effects
				(font
					(size 1.27 1.27)
				)
				(justify mirror)
			)
		)
		(property "Value" ""
			(at 0 0 0)
			(layer "B.Fab")
			(effects
				(font
					(size 1.27 1.27)
				)
				(justify mirror)
			)
		)
		(duplicate_pad_numbers_are_jumpers no)
		(fp_line
			(start 0.7874 0.4064)
			(end 0.7874 -0.4064)
			(stroke
				(width 0.1524)
				(type default)
			)
			(layer "B.SilkS")
		)
		(fp_line
			(start 0.7874 -0.4064)
			(end -0.7874 -0.4064)
			(stroke
				(width 0.1524)
				(type default)
			)
			(layer "B.SilkS")
		)
		(fp_line
			(start -0.7874 0.4064)
			(end 0.7874 0.4064)
			(stroke
				(width 0.1524)
				(type default)
			)
			(layer "B.SilkS")
		)
		(fp_line
			(start -0.7874 -0.4064)
			(end -0.7874 0.4064)
			(stroke
				(width 0.1524)
				(type default)
			)
			(layer "B.SilkS")
		)
		(fp_line
			(start 0.67945 0.3048)
			(end 0.67945 -0.305054)
			(stroke
				(width 0.1)
				(type default)
			)
			(layer "B.Fab")
		)
		(fp_line
			(start 0.67945 -0.305054)
			(end 0.12065 -0.305054)
			(stroke
				(width 0.1)
				(type default)
			)
			(layer "B.Fab")
		)
		(fp_line
			(start 0.12065 0.3048)
			(end 0.67945 0.3048)
			(stroke
				(width 0.1)
				(type default)
			)
			(layer "B.Fab")
		)
		(fp_line
			(start 0.12065 0.2794)
			(end 0.12065 0.3048)
			(stroke
				(width 0.1)
				(type default)
			)
			(layer "B.Fab")
		)
		(fp_line
			(start 0.12065 -0.2794)
			(end -0.12065 -0.2794)
			(stroke
				(width 0.1)
				(type default)
			)
			(layer "B.Fab")
		)
		(fp_line
			(start 0.12065 -0.305054)
			(end 0.12065 -0.2794)
			(stroke
				(width 0.1)
				(type default)
			)
			(layer "B.Fab")
		)
		(fp_line
			(start -0.120396 0.3048)
			(end -0.120396 0.2794)
			(stroke
				(width 0.1)
				(type default)
			)
			(layer "B.Fab")
		)
		(fp_line
			(start -0.120396 0.2794)
			(end 0.12065 0.2794)
			(stroke
				(width 0.1)
				(type default)
			)
			(layer "B.Fab")
		)
		(fp_line
			(start -0.12065 -0.2794)
			(end -0.12065 -0.3048)
			(stroke
				(width 0.1)
				(type default)
			)
			(layer "B.Fab")
		)
		(fp_line
			(start -0.12065 -0.3048)
			(end -0.67945 -0.3048)
			(stroke
				(width 0.1)
				(type default)
			)
			(layer "B.Fab")
		)
		(fp_line
			(start -0.67945 0.3048)
			(end -0.120396 0.3048)
			(stroke
				(width 0.1)
				(type default)
			)
			(layer "B.Fab")
		)
		(fp_line
			(start -0.67945 -0.3048)
			(end -0.67945 0.3048)
			(stroke
				(width 0.1)
				(type default)
			)
			(layer "B.Fab")
		)
		(pad "1" smd circle
			(at 0.40005 0)
			(size 0 0)
			(layers "B.Cu" "B.Mask" "B.Paste")
			(net "I3C_SPD_DDRAF_CPU1_SDA")
		)
		(pad "2" smd circle
			(at -0.40005 0)
			(size 0 0)
			(layers "B.Cu" "B.Mask" "B.Paste")
			(net "I3C_SPD_DDRD_CPU1_SDA")
		)
	)
	(footprint ""
		(layer "B.Cu")
		(at 170.39082 -425.053506 -90)
		(property "Reference" "R1198"
			(at 0 0 90)
			(layer "B.SilkS")
			(hide yes)
			(effects
				(font
					(size 1.27 1.27)
				)
				(justify mirror)
			)
		)
		(property "Value" ""
			(at 0 0 90)
			(layer "B.Fab")
			(effects
				(font
					(size 1.27 1.27)
				)
				(justify mirror)
			)
		)
		(duplicate_pad_numbers_are_jumpers no)
		(fp_line
			(start -0.32512 0.175006)
			(end 0.32512 0.175006)
			(stroke
				(width 0.1)
				(type default)
			)
			(layer "B.Fab")
		)
		(fp_line
			(start 0.32512 0.175006)
			(end 0.32512 -0.175006)
			(stroke
				(width 0.1)
				(type default)
			)
			(layer "B.Fab")
		)
		(fp_line
			(start -0.32512 -0.175006)
			(end -0.32512 0.175006)
			(stroke
				(width 0.1)
				(type default)
			)
			(layer "B.Fab")
		)
		(fp_line
			(start 0.32512 -0.175006)
			(end -0.32512 -0.175006)
			(stroke
				(width 0.1)
				(type default)
			)
			(layer "B.Fab")
		)
		(pad "1" smd rect
			(at 0.2667 0 90)
			(size 0.3048 0.381)
			(layers "B.Cu" "B.Mask" "B.Paste")
			(net "RST_SMB_RT_ROM_R1_N")
		)
		(pad "2" smd rect
			(at -0.2667 0 270)
			(size 0.3048 0.381)
			(layers "B.Cu" "B.Mask" "B.Paste")
			(net "FM_SMB_RT_ROM_MUX3_SEL")
		)
	)
	(footprint ""
		(layer "B.Cu")
		(at 398.04721 -398.969484)
		(property "Reference" "C966"
			(at 0 0 0)
			(layer "B.SilkS")
			(hide yes)
			(effects
				(font
					(size 1.27 1.27)
				)
				(justify mirror)
			)
		)
		(property "Value" ""
			(at 0 0 0)
			(layer "B.Fab")
			(effects
				(font
					(size 1.27 1.27)
				)
				(justify mirror)
			)
		)
		(duplicate_pad_numbers_are_jumpers no)
		(fp_line
			(start -1.524 -0.762)
			(end -1.524 0.762)
			(stroke
				(width 0.1524)
				(type default)
			)
			(layer "B.SilkS")
		)
		(fp_line
			(start -1.524 0.762)
			(end 1.524 0.762)
			(stroke
				(width 0.1524)
				(type default)
			)
			(layer "B.SilkS")
		)
		(fp_line
			(start 1.524 -0.762)
			(end -1.524 -0.762)
			(stroke
				(width 0.1524)
				(type default)
			)
			(layer "B.SilkS")
		)
		(fp_line
			(start 1.524 0.762)
			(end 1.524 -0.762)
			(stroke
				(width 0.1524)
				(type default)
			)
			(layer "B.SilkS")
		)
		(fp_line
			(start -1.1049 -0.724916)
			(end 1.1049 -0.724916)
			(stroke
				(width 0.1)
				(type default)
			)
			(layer "B.Fab")
		)
		(fp_line
			(start -1.1049 0.724916)
			(end -1.1049 -0.724916)
			(stroke
				(width 0.1)
				(type default)
			)
			(layer "B.Fab")
		)
		(fp_line
			(start 1.1049 -0.724916)
			(end 1.1049 0.724916)
			(stroke
				(width 0.1)
				(type default)
			)
			(layer "B.Fab")
		)
		(fp_line
			(start 1.1049 0.724916)
			(end -1.1049 0.724916)
			(stroke
				(width 0.1)
				(type default)
			)
			(layer "B.Fab")
		)
		(pad "1" smd rect
			(at 0.889 0)
			(size 1.016 1.27)
			(layers "B.Cu" "B.Mask" "B.Paste")
			(net "P0V9_CPU0_RT2_2A")
		)
		(pad "2" smd rect
			(at -0.889 0)
			(size 1.016 1.27)
			(layers "B.Cu" "B.Mask" "B.Paste")
			(net "GND")
		)
	)
	(footprint ""
		(layer "B.Cu")
		(at 311.733184 -338.082128 -90)
		(property "Reference" "PC130_3"
			(at 0 0 90)
			(layer "B.SilkS")
			(hide yes)
			(effects
				(font
					(size 1.27 1.27)
				)
				(justify mirror)
			)
		)
		(property "Value" ""
			(at 0 0 90)
			(layer "B.Fab")
			(effects
				(font
					(size 1.27 1.27)
				)
				(justify mirror)
			)
		)
		(duplicate_pad_numbers_are_jumpers no)
		(fp_line
			(start -1.524 0.762)
			(end 1.524 0.762)
			(stroke
				(width 0.1524)
				(type default)
			)
			(layer "B.SilkS")
		)
		(fp_line
			(start 1.524 0.762)
			(end 1.524 -0.762)
			(stroke
				(width 0.1524)
				(type default)
			)
			(layer "B.SilkS")
		)
		(fp_line
			(start -1.524 -0.762)
			(end -1.524 0.762)
			(stroke
				(width 0.1524)
				(type default)
			)
			(layer "B.SilkS")
		)
		(fp_line
			(start 1.524 -0.762)
			(end -1.524 -0.762)
			(stroke
				(width 0.1524)
				(type default)
			)
			(layer "B.SilkS")
		)
		(fp_line
			(start -1.1049 0.724916)
			(end -1.1049 -0.724916)
			(stroke
				(width 0.1)
				(type default)
			)
			(layer "B.Fab")
		)
		(fp_line
			(start 1.1049 0.724916)
			(end -1.1049 0.724916)
			(stroke
				(width 0.1)
				(type default)
			)
			(layer "B.Fab")
		)
		(fp_line
			(start -1.1049 -0.724916)
			(end 1.1049 -0.724916)
			(stroke
				(width 0.1)
				(type default)
			)
			(layer "B.Fab")
		)
		(fp_line
			(start 1.1049 -0.724916)
			(end 1.1049 0.724916)
			(stroke
				(width 0.1)
				(type default)
			)
			(layer "B.Fab")
		)
		(pad "1" smd rect
			(at 0.889 0 270)
			(size 1.016 1.27)
			(layers "B.Cu" "B.Mask" "B.Paste")
			(net "PVDDCR_CPU1_P0")
		)
		(pad "2" smd rect
			(at -0.889 0 270)
			(size 1.016 1.27)
			(layers "B.Cu" "B.Mask" "B.Paste")
			(net "GND")
		)
	)
	(footprint ""
		(layer "B.Cu")
		(at 176.264316 -32.137858 -90)
		(property "Reference" "PR4540"
			(at 0 0 90)
			(layer "B.SilkS")
			(hide yes)
			(effects
				(font
					(size 1.27 1.27)
				)
				(justify mirror)
			)
		)
		(property "Value" ""
			(at 0 0 90)
			(layer "B.Fab")
			(effects
				(font
					(size 1.27 1.27)
				)
				(justify mirror)
			)
		)
		(duplicate_pad_numbers_are_jumpers no)
		(fp_line
			(start -0.7874 0.4064)
			(end 0.7874 0.4064)
			(stroke
				(width 0.1524)
				(type default)
			)
			(layer "B.SilkS")
		)
		(fp_line
			(start 0.7874 0.4064)
			(end 0.7874 -0.4064)
			(stroke
				(width 0.1524)
				(type default)
			)
			(layer "B.SilkS")
		)
		(fp_line
			(start -0.7874 -0.4064)
			(end -0.7874 0.4064)
			(stroke
				(width 0.1524)
				(type default)
			)
			(layer "B.SilkS")
		)
		(fp_line
			(start 0.7874 -0.4064)
			(end -0.7874 -0.4064)
			(stroke
				(width 0.1524)
				(type default)
			)
			(layer "B.SilkS")
		)
		(fp_line
			(start -0.67945 0.3048)
			(end -0.120396 0.3048)
			(stroke
				(width 0.1)
				(type default)
			)
			(layer "B.Fab")
		)
		(fp_line
			(start -0.120396 0.3048)
			(end -0.120396 0.2794)
			(stroke
				(width 0.1)
				(type default)
			)
			(layer "B.Fab")
		)
		(fp_line
			(start 0.12065 0.3048)
			(end 0.67945 0.3048)
			(stroke
				(width 0.1)
				(type default)
			)
			(layer "B.Fab")
		)
		(fp_line
			(start 0.67945 0.3048)
			(end 0.67945 -0.305054)
			(stroke
				(width 0.1)
				(type default)
			)
			(layer "B.Fab")
		)
		(fp_line
			(start -0.120396 0.2794)
			(end 0.12065 0.2794)
			(stroke
				(width 0.1)
				(type default)
			)
			(layer "B.Fab")
		)
		(fp_line
			(start 0.12065 0.2794)
			(end 0.12065 0.3048)
			(stroke
				(width 0.1)
				(type default)
			)
			(layer "B.Fab")
		)
		(fp_line
			(start -0.12065 -0.2794)
			(end -0.12065 -0.3048)
			(stroke
				(width 0.1)
				(type default)
			)
			(layer "B.Fab")
		)
		(fp_line
			(start 0.12065 -0.2794)
			(end -0.12065 -0.2794)
			(stroke
				(width 0.1)
				(type default)
			)
			(layer "B.Fab")
		)
		(fp_line
			(start -0.67945 -0.3048)
			(end -0.67945 0.3048)
			(stroke
				(width 0.1)
				(type default)
			)
			(layer "B.Fab")
		)
		(fp_line
			(start -0.12065 -0.3048)
			(end -0.67945 -0.3048)
			(stroke
				(width 0.1)
				(type default)
			)
			(layer "B.Fab")
		)
		(fp_line
			(start 0.12065 -0.305054)
			(end 0.12065 -0.2794)
			(stroke
				(width 0.1)
				(type default)
			)
			(layer "B.Fab")
		)
		(fp_line
			(start 0.67945 -0.305054)
			(end 0.12065 -0.305054)
			(stroke
				(width 0.1)
				(type default)
			)
			(layer "B.Fab")
		)
		(pad "1" smd circle
			(at 0.40005 0 90)
			(size 0 0)
			(layers "B.Cu" "B.Mask" "B.Paste")
			(net "P12V_SCM_ISET")
		)
		(pad "2" smd circle
			(at -0.40005 0 90)
			(size 0 0)
			(layers "B.Cu" "B.Mask" "B.Paste")
			(net "P12V_SCM_ISET_R")
		)
	)
	(footprint ""
		(layer "B.Cu")
		(at 119.293386 -251.781564)
		(property "Reference" "C2259"
			(at 0 0 0)
			(layer "B.SilkS")
			(hide yes)
			(effects
				(font
					(size 1.27 1.27)
				)
				(justify mirror)
			)
		)
		(property "Value" ""
			(at 0 0 0)
			(layer "B.Fab")
			(effects
				(font
					(size 1.27 1.27)
				)
				(justify mirror)
			)
		)
		(duplicate_pad_numbers_are_jumpers no)
		(fp_line
			(start -0.7874 -0.4064)
			(end -0.7874 0.4064)
			(stroke
				(width 0.1524)
				(type default)
			)
			(layer "B.SilkS")
		)
		(fp_line
			(start -0.7874 0.4064)
			(end 0.7874 0.4064)
			(stroke
				(width 0.1524)
				(type default)
			)
			(layer "B.SilkS")
		)
		(fp_line
			(start 0.7874 -0.4064)
			(end -0.7874 -0.4064)
			(stroke
				(width 0.1524)
				(type default)
			)
			(layer "B.SilkS")
		)
		(fp_line
			(start 0.7874 0.4064)
			(end 0.7874 -0.4064)
			(stroke
				(width 0.1524)
				(type default)
			)
			(layer "B.SilkS")
		)
		(fp_line
			(start -0.67945 -0.3048)
			(end -0.67945 0.3048)
			(stroke
				(width 0.1)
				(type default)
			)
			(layer "B.Fab")
		)
		(fp_line
			(start -0.67945 0.3048)
			(end -0.120396 0.3048)
			(stroke
				(width 0.1)
				(type default)
			)
			(layer "B.Fab")
		)
		(fp_line
			(start -0.12065 -0.3048)
			(end -0.67945 -0.3048)
			(stroke
				(width 0.1)
				(type default)
			)
			(layer "B.Fab")
		)
		(fp_line
			(start -0.12065 -0.2794)
			(end -0.12065 -0.3048)
			(stroke
				(width 0.1)
				(type default)
			)
			(layer "B.Fab")
		)
		(fp_line
			(start -0.120396 0.2794)
			(end 0.12065 0.2794)
			(stroke
				(width 0.1)
				(type default)
			)
			(layer "B.Fab")
		)
		(fp_line
			(start -0.120396 0.3048)
			(end -0.120396 0.2794)
			(stroke
				(width 0.1)
				(type default)
			)
			(layer "B.Fab")
		)
		(fp_line
			(start 0.12065 -0.305054)
			(end 0.12065 -0.2794)
			(stroke
				(width 0.1)
				(type default)
			)
			(layer "B.Fab")
		)
		(fp_line
			(start 0.12065 -0.2794)
			(end -0.12065 -0.2794)
			(stroke
				(width 0.1)
				(type default)
			)
			(layer "B.Fab")
		)
		(fp_line
			(start 0.12065 0.2794)
			(end 0.12065 0.3048)
			(stroke
				(width 0.1)
				(type default)
			)
			(layer "B.Fab")
		)
		(fp_line
			(start 0.12065 0.3048)
			(end 0.67945 0.3048)
			(stroke
				(width 0.1)
				(type default)
			)
			(layer "B.Fab")
		)
		(fp_line
			(start 0.67945 -0.305054)
			(end 0.12065 -0.305054)
			(stroke
				(width 0.1)
				(type default)
			)
			(layer "B.Fab")
		)
		(fp_line
			(start 0.67945 0.3048)
			(end 0.67945 -0.305054)
			(stroke
				(width 0.1)
				(type default)
			)
			(layer "B.Fab")
		)
		(pad "1" smd circle
			(at 0.40005 0 180)
			(size 0 0)
			(layers "B.Cu" "B.Mask" "B.Paste")
			(net "PVDDCR_SOC_P1")
		)
		(pad "2" smd circle
			(at -0.40005 0 180)
			(size 0 0)
			(layers "B.Cu" "B.Mask" "B.Paste")
			(net "GND")
		)
	)
	(footprint ""
		(layer "B.Cu")
		(at 105.960164 -262.205216)
		(property "Reference" "C2489"
			(at 0 0 0)
			(layer "B.SilkS")
			(hide yes)
			(effects
				(font
					(size 1.27 1.27)
				)
				(justify mirror)
			)
		)
		(property "Value" ""
			(at 0 0 0)
			(layer "B.Fab")
			(effects
				(font
					(size 1.27 1.27)
				)
				(justify mirror)
			)
		)
		(duplicate_pad_numbers_are_jumpers no)
		(fp_line
			(start -0.7874 -0.4064)
			(end -0.7874 0.4064)
			(stroke
				(width 0.1524)
				(type default)
			)
			(layer "B.SilkS")
		)
		(fp_line
			(start -0.7874 0.4064)
			(end 0.7874 0.4064)
			(stroke
				(width 0.1524)
				(type default)
			)
			(layer "B.SilkS")
		)
		(fp_line
			(start 0.7874 -0.4064)
			(end -0.7874 -0.4064)
			(stroke
				(width 0.1524)
				(type default)
			)
			(layer "B.SilkS")
		)
		(fp_line
			(start 0.7874 0.4064)
			(end 0.7874 -0.4064)
			(stroke
				(width 0.1524)
				(type default)
			)
			(layer "B.SilkS")
		)
		(fp_line
			(start -0.67945 -0.3048)
			(end -0.67945 0.3048)
			(stroke
				(width 0.1)
				(type default)
			)
			(layer "B.Fab")
		)
		(fp_line
			(start -0.67945 0.3048)
			(end -0.120396 0.3048)
			(stroke
				(width 0.1)
				(type default)
			)
			(layer "B.Fab")
		)
		(fp_line
			(start -0.12065 -0.3048)
			(end -0.67945 -0.3048)
			(stroke
				(width 0.1)
				(type default)
			)
			(layer "B.Fab")
		)
		(fp_line
			(start -0.12065 -0.2794)
			(end -0.12065 -0.3048)
			(stroke
				(width 0.1)
				(type default)
			)
			(layer "B.Fab")
		)
		(fp_line
			(start -0.120396 0.2794)
			(end 0.12065 0.2794)
			(stroke
				(width 0.1)
				(type default)
			)
			(layer "B.Fab")
		)
		(fp_line
			(start -0.120396 0.3048)
			(end -0.120396 0.2794)
			(stroke
				(width 0.1)
				(type default)
			)
			(layer "B.Fab")
		)
		(fp_line
			(start 0.12065 -0.305054)
			(end 0.12065 -0.2794)
			(stroke
				(width 0.1)
				(type default)
			)
			(layer "B.Fab")
		)
		(fp_line
			(start 0.12065 -0.2794)
			(end -0.12065 -0.2794)
			(stroke
				(width 0.1)
				(type default)
			)
			(layer "B.Fab")
		)
		(fp_line
			(start 0.12065 0.2794)
			(end 0.12065 0.3048)
			(stroke
				(width 0.1)
				(type default)
			)
			(layer "B.Fab")
		)
		(fp_line
			(start 0.12065 0.3048)
			(end 0.67945 0.3048)
			(stroke
				(width 0.1)
				(type default)
			)
			(layer "B.Fab")
		)
		(fp_line
			(start 0.67945 -0.305054)
			(end 0.12065 -0.305054)
			(stroke
				(width 0.1)
				(type default)
			)
			(layer "B.Fab")
		)
		(fp_line
			(start 0.67945 0.3048)
			(end 0.67945 -0.305054)
			(stroke
				(width 0.1)
				(type default)
			)
			(layer "B.Fab")
		)
		(pad "1" smd circle
			(at 0.40005 0 180)
			(size 0 0)
			(layers "B.Cu" "B.Mask" "B.Paste")
			(net "PVDD11_S3_P1")
		)
		(pad "2" smd circle
			(at -0.40005 0 180)
			(size 0 0)
			(layers "B.Cu" "B.Mask" "B.Paste")
			(net "GND")
		)
	)
	(footprint ""
		(layer "B.Cu")
		(at 116.225828 -256.012442 -90)
		(property "Reference" "C2458"
			(at 0 0 90)
			(layer "B.SilkS")
			(hide yes)
			(effects
				(font
					(size 1.27 1.27)
				)
				(justify mirror)
			)
		)
		(property "Value" ""
			(at 0 0 90)
			(layer "B.Fab")
			(effects
				(font
					(size 1.27 1.27)
				)
				(justify mirror)
			)
		)
		(duplicate_pad_numbers_are_jumpers no)
		(fp_line
			(start -0.7874 0.4064)
			(end 0.7874 0.4064)
			(stroke
				(width 0.1524)
				(type default)
			)
			(layer "B.SilkS")
		)
		(fp_line
			(start 0.7874 0.4064)
			(end 0.7874 -0.4064)
			(stroke
				(width 0.1524)
				(type default)
			)
			(layer "B.SilkS")
		)
		(fp_line
			(start -0.7874 -0.4064)
			(end -0.7874 0.4064)
			(stroke
				(width 0.1524)
				(type default)
			)
			(layer "B.SilkS")
		)
		(fp_line
			(start 0.7874 -0.4064)
			(end -0.7874 -0.4064)
			(stroke
				(width 0.1524)
				(type default)
			)
			(layer "B.SilkS")
		)
		(fp_line
			(start -0.67945 0.3048)
			(end -0.120396 0.3048)
			(stroke
				(width 0.1)
				(type default)
			)
			(layer "B.Fab")
		)
		(fp_line
			(start -0.120396 0.3048)
			(end -0.120396 0.2794)
			(stroke
				(width 0.1)
				(type default)
			)
			(layer "B.Fab")
		)
		(fp_line
			(start 0.12065 0.3048)
			(end 0.67945 0.3048)
			(stroke
				(width 0.1)
				(type default)
			)
			(layer "B.Fab")
		)
		(fp_line
			(start 0.67945 0.3048)
			(end 0.67945 -0.305054)
			(stroke
				(width 0.1)
				(type default)
			)
			(layer "B.Fab")
		)
		(fp_line
			(start -0.120396 0.2794)
			(end 0.12065 0.2794)
			(stroke
				(width 0.1)
				(type default)
			)
			(layer "B.Fab")
		)
		(fp_line
			(start 0.12065 0.2794)
			(end 0.12065 0.3048)
			(stroke
				(width 0.1)
				(type default)
			)
			(layer "B.Fab")
		)
		(fp_line
			(start -0.12065 -0.2794)
			(end -0.12065 -0.3048)
			(stroke
				(width 0.1)
				(type default)
			)
			(layer "B.Fab")
		)
		(fp_line
			(start 0.12065 -0.2794)
			(end -0.12065 -0.2794)
			(stroke
				(width 0.1)
				(type default)
			)
			(layer "B.Fab")
		)
		(fp_line
			(start -0.67945 -0.3048)
			(end -0.67945 0.3048)
			(stroke
				(width 0.1)
				(type default)
			)
			(layer "B.Fab")
		)
		(fp_line
			(start -0.12065 -0.3048)
			(end -0.67945 -0.3048)
			(stroke
				(width 0.1)
				(type default)
			)
			(layer "B.Fab")
		)
		(fp_line
			(start 0.12065 -0.305054)
			(end 0.12065 -0.2794)
			(stroke
				(width 0.1)
				(type default)
			)
			(layer "B.Fab")
		)
		(fp_line
			(start 0.67945 -0.305054)
			(end 0.12065 -0.305054)
			(stroke
				(width 0.1)
				(type default)
			)
			(layer "B.Fab")
		)
		(pad "1" smd circle
			(at 0.40005 0 90)
			(size 0 0)
			(layers "B.Cu" "B.Mask" "B.Paste")
			(net "PVDDCR_SOC_P1")
		)
		(pad "2" smd circle
			(at -0.40005 0 90)
			(size 0 0)
			(layers "B.Cu" "B.Mask" "B.Paste")
			(net "GND")
		)
	)
	(footprint ""
		(layer "B.Cu")
		(at 164.07257 -120.364758)
		(property "Reference" "R6093"
			(at 0 0 0)
			(layer "B.SilkS")
			(hide yes)
			(effects
				(font
					(size 1.27 1.27)
				)
				(justify mirror)
			)
		)
		(property "Value" ""
			(at 0 0 0)
			(layer "B.Fab")
			(effects
				(font
					(size 1.27 1.27)
				)
				(justify mirror)
			)
		)
		(duplicate_pad_numbers_are_jumpers no)
		(fp_line
			(start -0.7874 -0.4064)
			(end -0.7874 0.4064)
			(stroke
				(width 0.1524)
				(type default)
			)
			(layer "B.SilkS")
		)
		(fp_line
			(start -0.7874 0.4064)
			(end 0.7874 0.4064)
			(stroke
				(width 0.1524)
				(type default)
			)
			(layer "B.SilkS")
		)
		(fp_line
			(start 0.7874 -0.4064)
			(end -0.7874 -0.4064)
			(stroke
				(width 0.1524)
				(type default)
			)
			(layer "B.SilkS")
		)
		(fp_line
			(start 0.7874 0.4064)
			(end 0.7874 -0.4064)
			(stroke
				(width 0.1524)
				(type default)
			)
			(layer "B.SilkS")
		)
		(fp_line
			(start -0.67945 -0.3048)
			(end -0.67945 0.3048)
			(stroke
				(width 0.1)
				(type default)
			)
			(layer "B.Fab")
		)
		(fp_line
			(start -0.67945 0.3048)
			(end -0.120396 0.3048)
			(stroke
				(width 0.1)
				(type default)
			)
			(layer "B.Fab")
		)
		(fp_line
			(start -0.12065 -0.3048)
			(end -0.67945 -0.3048)
			(stroke
				(width 0.1)
				(type default)
			)
			(layer "B.Fab")
		)
		(fp_line
			(start -0.12065 -0.2794)
			(end -0.12065 -0.3048)
			(stroke
				(width 0.1)
				(type default)
			)
			(layer "B.Fab")
		)
		(fp_line
			(start -0.120396 0.2794)
			(end 0.12065 0.2794)
			(stroke
				(width 0.1)
				(type default)
			)
			(layer "B.Fab")
		)
		(fp_line
			(start -0.120396 0.3048)
			(end -0.120396 0.2794)
			(stroke
				(width 0.1)
				(type default)
			)
			(layer "B.Fab")
		)
		(fp_line
			(start 0.12065 -0.305054)
			(end 0.12065 -0.2794)
			(stroke
				(width 0.1)
				(type default)
			)
			(layer "B.Fab")
		)
		(fp_line
			(start 0.12065 -0.2794)
			(end -0.12065 -0.2794)
			(stroke
				(width 0.1)
				(type default)
			)
			(layer "B.Fab")
		)
		(fp_line
			(start 0.12065 0.2794)
			(end 0.12065 0.3048)
			(stroke
				(width 0.1)
				(type default)
			)
			(layer "B.Fab")
		)
		(fp_line
			(start 0.12065 0.3048)
			(end 0.67945 0.3048)
			(stroke
				(width 0.1)
				(type default)
			)
			(layer "B.Fab")
		)
		(fp_line
			(start 0.67945 -0.305054)
			(end 0.12065 -0.305054)
			(stroke
				(width 0.1)
				(type default)
			)
			(layer "B.Fab")
		)
		(fp_line
			(start 0.67945 0.3048)
			(end 0.67945 -0.305054)
			(stroke
				(width 0.1)
				(type default)
			)
			(layer "B.Fab")
		)
		(pad "1" smd circle
			(at 0.40005 0 180)
			(size 0 0)
			(layers "B.Cu" "B.Mask" "B.Paste")
			(net "SCM_SYS_PWROK_R")
		)
		(pad "2" smd circle
			(at -0.40005 0 180)
			(size 0 0)
			(layers "B.Cu" "B.Mask" "B.Paste")
			(net "SCM_SYS_PWROK_R2")
		)
	)
	(footprint ""
		(layer "B.Cu")
		(at 311.387236 -197.836028 -90)
		(property "Reference" "R6082"
			(at 0 0 90)
			(layer "B.SilkS")
			(hide yes)
			(effects
				(font
					(size 1.27 1.27)
				)
				(justify mirror)
			)
		)
		(property "Value" ""
			(at 0 0 90)
			(layer "B.Fab")
			(effects
				(font
					(size 1.27 1.27)
				)
				(justify mirror)
			)
		)
		(duplicate_pad_numbers_are_jumpers no)
		(fp_line
			(start -0.7874 0.4064)
			(end 0.7874 0.4064)
			(stroke
				(width 0.1524)
				(type default)
			)
			(layer "B.SilkS")
		)
		(fp_line
			(start 0.7874 0.4064)
			(end 0.7874 -0.4064)
			(stroke
				(width 0.1524)
				(type default)
			)
			(layer "B.SilkS")
		)
		(fp_line
			(start -0.7874 -0.4064)
			(end -0.7874 0.4064)
			(stroke
				(width 0.1524)
				(type default)
			)
			(layer "B.SilkS")
		)
		(fp_line
			(start 0.7874 -0.4064)
			(end -0.7874 -0.4064)
			(stroke
				(width 0.1524)
				(type default)
			)
			(layer "B.SilkS")
		)
		(fp_line
			(start -0.67945 0.3048)
			(end -0.120396 0.3048)
			(stroke
				(width 0.1)
				(type default)
			)
			(layer "B.Fab")
		)
		(fp_line
			(start -0.120396 0.3048)
			(end -0.120396 0.2794)
			(stroke
				(width 0.1)
				(type default)
			)
			(layer "B.Fab")
		)
		(fp_line
			(start 0.12065 0.3048)
			(end 0.67945 0.3048)
			(stroke
				(width 0.1)
				(type default)
			)
			(layer "B.Fab")
		)
		(fp_line
			(start 0.67945 0.3048)
			(end 0.67945 -0.305054)
			(stroke
				(width 0.1)
				(type default)
			)
			(layer "B.Fab")
		)
		(fp_line
			(start -0.120396 0.2794)
			(end 0.12065 0.2794)
			(stroke
				(width 0.1)
				(type default)
			)
			(layer "B.Fab")
		)
		(fp_line
			(start 0.12065 0.2794)
			(end 0.12065 0.3048)
			(stroke
				(width 0.1)
				(type default)
			)
			(layer "B.Fab")
		)
		(fp_line
			(start -0.12065 -0.2794)
			(end -0.12065 -0.3048)
			(stroke
				(width 0.1)
				(type default)
			)
			(layer "B.Fab")
		)
		(fp_line
			(start 0.12065 -0.2794)
			(end -0.12065 -0.2794)
			(stroke
				(width 0.1)
				(type default)
			)
			(layer "B.Fab")
		)
		(fp_line
			(start -0.67945 -0.3048)
			(end -0.67945 0.3048)
			(stroke
				(width 0.1)
				(type default)
			)
			(layer "B.Fab")
		)
		(fp_line
			(start -0.12065 -0.3048)
			(end -0.67945 -0.3048)
			(stroke
				(width 0.1)
				(type default)
			)
			(layer "B.Fab")
		)
		(fp_line
			(start 0.12065 -0.305054)
			(end 0.12065 -0.2794)
			(stroke
				(width 0.1)
				(type default)
			)
			(layer "B.Fab")
		)
		(fp_line
			(start 0.67945 -0.305054)
			(end 0.12065 -0.305054)
			(stroke
				(width 0.1)
				(type default)
			)
			(layer "B.Fab")
		)
		(pad "1" smd circle
			(at 0.40005 0 90)
			(size 0 0)
			(layers "B.Cu" "B.Mask" "B.Paste")
			(net "PVDD11_S3_P0")
		)
		(pad "2" smd circle
			(at -0.40005 0 90)
			(size 0 0)
			(layers "B.Cu" "B.Mask" "B.Paste")
			(net "SMB_CPU0_2_SDA")
		)
	)
	(footprint ""
		(layer "B.Cu")
		(at 255.757426 -325.056754 180)
		(property "Reference" "C1085"
			(at 0 0 0)
			(layer "B.SilkS")
			(hide yes)
			(effects
				(font
					(size 1.27 1.27)
				)
				(justify mirror)
			)
		)
		(property "Value" ""
			(at 0 0 0)
			(layer "B.Fab")
			(effects
				(font
					(size 1.27 1.27)
				)
				(justify mirror)
			)
		)
		(duplicate_pad_numbers_are_jumpers no)
		(fp_line
			(start 0.7874 0.4064)
			(end 0.7874 -0.4064)
			(stroke
				(width 0.1524)
				(type default)
			)
			(layer "B.SilkS")
		)
		(fp_line
			(start 0.7874 -0.4064)
			(end -0.7874 -0.4064)
			(stroke
				(width 0.1524)
				(type default)
			)
			(layer "B.SilkS")
		)
		(fp_line
			(start -0.7874 0.4064)
			(end 0.7874 0.4064)
			(stroke
				(width 0.1524)
				(type default)
			)
			(layer "B.SilkS")
		)
		(fp_line
			(start -0.7874 -0.4064)
			(end -0.7874 0.4064)
			(stroke
				(width 0.1524)
				(type default)
			)
			(layer "B.SilkS")
		)
		(fp_line
			(start 0.67945 0.3048)
			(end 0.67945 -0.305054)
			(stroke
				(width 0.1)
				(type default)
			)
			(layer "B.Fab")
		)
		(fp_line
			(start 0.67945 -0.305054)
			(end 0.12065 -0.305054)
			(stroke
				(width 0.1)
				(type default)
			)
			(layer "B.Fab")
		)
		(fp_line
			(start 0.12065 0.3048)
			(end 0.67945 0.3048)
			(stroke
				(width 0.1)
				(type default)
			)
			(layer "B.Fab")
		)
		(fp_line
			(start 0.12065 0.2794)
			(end 0.12065 0.3048)
			(stroke
				(width 0.1)
				(type default)
			)
			(layer "B.Fab")
		)
		(fp_line
			(start 0.12065 -0.2794)
			(end -0.12065 -0.2794)
			(stroke
				(width 0.1)
				(type default)
			)
			(layer "B.Fab")
		)
		(fp_line
			(start 0.12065 -0.305054)
			(end 0.12065 -0.2794)
			(stroke
				(width 0.1)
				(type default)
			)
			(layer "B.Fab")
		)
		(fp_line
			(start -0.120396 0.3048)
			(end -0.120396 0.2794)
			(stroke
				(width 0.1)
				(type default)
			)
			(layer "B.Fab")
		)
		(fp_line
			(start -0.120396 0.2794)
			(end 0.12065 0.2794)
			(stroke
				(width 0.1)
				(type default)
			)
			(layer "B.Fab")
		)
		(fp_line
			(start -0.12065 -0.2794)
			(end -0.12065 -0.3048)
			(stroke
				(width 0.1)
				(type default)
			)
			(layer "B.Fab")
		)
		(fp_line
			(start -0.12065 -0.3048)
			(end -0.67945 -0.3048)
			(stroke
				(width 0.1)
				(type default)
			)
			(layer "B.Fab")
		)
		(fp_line
			(start -0.67945 0.3048)
			(end -0.120396 0.3048)
			(stroke
				(width 0.1)
				(type default)
			)
			(layer "B.Fab")
		)
		(fp_line
			(start -0.67945 -0.3048)
			(end -0.67945 0.3048)
			(stroke
				(width 0.1)
				(type default)
			)
			(layer "B.Fab")
		)
		(pad "1" smd circle
			(at 0.40005 0)
			(size 0 0)
			(layers "B.Cu" "B.Mask" "B.Paste")
			(net "P5V_AUX_ADC_MAM")
		)
		(pad "2" smd circle
			(at -0.40005 0)
			(size 0 0)
			(layers "B.Cu" "B.Mask" "B.Paste")
			(net "GND")
		)
	)
	(footprint ""
		(layer "B.Cu")
		(at 157.81909 -390.560052 90)
		(property "Reference" "C408"
			(at 0 0 90)
			(layer "B.SilkS")
			(hide yes)
			(effects
				(font
					(size 1.27 1.27)
				)
				(justify mirror)
			)
		)
		(property "Value" ""
			(at 0 0 90)
			(layer "B.Fab")
			(effects
				(font
					(size 1.27 1.27)
				)
				(justify mirror)
			)
		)
		(duplicate_pad_numbers_are_jumpers no)
		(fp_line
			(start 0.7874 -0.4064)
			(end -0.7874 -0.4064)
			(stroke
				(width 0.1524)
				(type default)
			)
			(layer "B.SilkS")
		)
		(fp_line
			(start -0.7874 -0.4064)
			(end -0.7874 0.4064)
			(stroke
				(width 0.1524)
				(type default)
			)
			(layer "B.SilkS")
		)
		(fp_line
			(start 0.7874 0.4064)
			(end 0.7874 -0.4064)
			(stroke
				(width 0.1524)
				(type default)
			)
			(layer "B.SilkS")
		)
		(fp_line
			(start -0.7874 0.4064)
			(end 0.7874 0.4064)
			(stroke
				(width 0.1524)
				(type default)
			)
			(layer "B.SilkS")
		)
		(fp_line
			(start 0.67945 -0.305054)
			(end 0.12065 -0.305054)
			(stroke
				(width 0.1)
				(type default)
			)
			(layer "B.Fab")
		)
		(fp_line
			(start 0.12065 -0.305054)
			(end 0.12065 -0.2794)
			(stroke
				(width 0.1)
				(type default)
			)
			(layer "B.Fab")
		)
		(fp_line
			(start -0.12065 -0.3048)
			(end -0.67945 -0.3048)
			(stroke
				(width 0.1)
				(type default)
			)
			(layer "B.Fab")
		)
		(fp_line
			(start -0.67945 -0.3048)
			(end -0.67945 0.3048)
			(stroke
				(width 0.1)
				(type default)
			)
			(layer "B.Fab")
		)
		(fp_line
			(start 0.12065 -0.2794)
			(end -0.12065 -0.2794)
			(stroke
				(width 0.1)
				(type default)
			)
			(layer "B.Fab")
		)
		(fp_line
			(start -0.12065 -0.2794)
			(end -0.12065 -0.3048)
			(stroke
				(width 0.1)
				(type default)
			)
			(layer "B.Fab")
		)
		(fp_line
			(start 0.12065 0.2794)
			(end 0.12065 0.3048)
			(stroke
				(width 0.1)
				(type default)
			)
			(layer "B.Fab")
		)
		(fp_line
			(start -0.120396 0.2794)
			(end 0.12065 0.2794)
			(stroke
				(width 0.1)
				(type default)
			)
			(layer "B.Fab")
		)
		(fp_line
			(start 0.67945 0.3048)
			(end 0.67945 -0.305054)
			(stroke
				(width 0.1)
				(type default)
			)
			(layer "B.Fab")
		)
		(fp_line
			(start 0.12065 0.3048)
			(end 0.67945 0.3048)
			(stroke
				(width 0.1)
				(type default)
			)
			(layer "B.Fab")
		)
		(fp_line
			(start -0.120396 0.3048)
			(end -0.120396 0.2794)
			(stroke
				(width 0.1)
				(type default)
			)
			(layer "B.Fab")
		)
		(fp_line
			(start -0.67945 0.3048)
			(end -0.120396 0.3048)
			(stroke
				(width 0.1)
				(type default)
			)
			(layer "B.Fab")
		)
		(pad "1" smd circle
			(at 0.40005 0 270)
			(size 0 0)
			(layers "B.Cu" "B.Mask" "B.Paste")
			(net "P0V9_CPU1_RT_2D")
		)
		(pad "2" smd circle
			(at -0.40005 0 270)
			(size 0 0)
			(layers "B.Cu" "B.Mask" "B.Paste")
			(net "GND")
		)
	)
	(footprint ""
		(layer "B.Cu")
		(at 402.322538 -322.170552)
		(property "Reference" "R5027"
			(at 0 0 0)
			(layer "B.SilkS")
			(hide yes)
			(effects
				(font
					(size 1.27 1.27)
				)
				(justify mirror)
			)
		)
		(property "Value" ""
			(at 0 0 0)
			(layer "B.Fab")
			(effects
				(font
					(size 1.27 1.27)
				)
				(justify mirror)
			)
		)
		(duplicate_pad_numbers_are_jumpers no)
		(fp_line
			(start -0.7874 -0.4064)
			(end -0.7874 0.4064)
			(stroke
				(width 0.1524)
				(type default)
			)
			(layer "B.SilkS")
		)
		(fp_line
			(start -0.7874 0.4064)
			(end 0.7874 0.4064)
			(stroke
				(width 0.1524)
				(type default)
			)
			(layer "B.SilkS")
		)
		(fp_line
			(start 0.7874 -0.4064)
			(end -0.7874 -0.4064)
			(stroke
				(width 0.1524)
				(type default)
			)
			(layer "B.SilkS")
		)
		(fp_line
			(start 0.7874 0.4064)
			(end 0.7874 -0.4064)
			(stroke
				(width 0.1524)
				(type default)
			)
			(layer "B.SilkS")
		)
		(fp_line
			(start -0.67945 -0.3048)
			(end -0.67945 0.3048)
			(stroke
				(width 0.1)
				(type default)
			)
			(layer "B.Fab")
		)
		(fp_line
			(start -0.67945 0.3048)
			(end -0.120396 0.3048)
			(stroke
				(width 0.1)
				(type default)
			)
			(layer "B.Fab")
		)
		(fp_line
			(start -0.12065 -0.3048)
			(end -0.67945 -0.3048)
			(stroke
				(width 0.1)
				(type default)
			)
			(layer "B.Fab")
		)
		(fp_line
			(start -0.12065 -0.2794)
			(end -0.12065 -0.3048)
			(stroke
				(width 0.1)
				(type default)
			)
			(layer "B.Fab")
		)
		(fp_line
			(start -0.120396 0.2794)
			(end 0.12065 0.2794)
			(stroke
				(width 0.1)
				(type default)
			)
			(layer "B.Fab")
		)
		(fp_line
			(start -0.120396 0.3048)
			(end -0.120396 0.2794)
			(stroke
				(width 0.1)
				(type default)
			)
			(layer "B.Fab")
		)
		(fp_line
			(start 0.12065 -0.305054)
			(end 0.12065 -0.2794)
			(stroke
				(width 0.1)
				(type default)
			)
			(layer "B.Fab")
		)
		(fp_line
			(start 0.12065 -0.2794)
			(end -0.12065 -0.2794)
			(stroke
				(width 0.1)
				(type default)
			)
			(layer "B.Fab")
		)
		(fp_line
			(start 0.12065 0.2794)
			(end 0.12065 0.3048)
			(stroke
				(width 0.1)
				(type default)
			)
			(layer "B.Fab")
		)
		(fp_line
			(start 0.12065 0.3048)
			(end 0.67945 0.3048)
			(stroke
				(width 0.1)
				(type default)
			)
			(layer "B.Fab")
		)
		(fp_line
			(start 0.67945 -0.305054)
			(end 0.12065 -0.305054)
			(stroke
				(width 0.1)
				(type default)
			)
			(layer "B.Fab")
		)
		(fp_line
			(start 0.67945 0.3048)
			(end 0.67945 -0.305054)
			(stroke
				(width 0.1)
				(type default)
			)
			(layer "B.Fab")
		)
		(pad "1" smd circle
			(at 0.40005 0 180)
			(size 0 0)
			(layers "B.Cu" "B.Mask" "B.Paste")
			(net "GND")
		)
		(pad "2" smd circle
			(at -0.40005 0 180)
			(size 0 0)
			(layers "B.Cu" "B.Mask" "B.Paste")
			(net "IRQ_SMI_ACTIVE_N")
		)
	)
	(footprint ""
		(layer "B.Cu")
		(at 320.571876 -66.708782 90)
		(property "Reference" "R3075"
			(at 0 0 90)
			(layer "B.SilkS")
			(hide yes)
			(effects
				(font
					(size 1.27 1.27)
				)
				(justify mirror)
			)
		)
		(property "Value" ""
			(at 0 0 90)
			(layer "B.Fab")
			(effects
				(font
					(size 1.27 1.27)
				)
				(justify mirror)
			)
		)
		(duplicate_pad_numbers_are_jumpers no)
		(fp_line
			(start 0.7874 -0.4064)
			(end -0.7874 -0.4064)
			(stroke
				(width 0.1524)
				(type default)
			)
			(layer "B.SilkS")
		)
		(fp_line
			(start -0.7874 -0.4064)
			(end -0.7874 0.4064)
			(stroke
				(width 0.1524)
				(type default)
			)
			(layer "B.SilkS")
		)
		(fp_line
			(start 0.7874 0.4064)
			(end 0.7874 -0.4064)
			(stroke
				(width 0.1524)
				(type default)
			)
			(layer "B.SilkS")
		)
		(fp_line
			(start -0.7874 0.4064)
			(end 0.7874 0.4064)
			(stroke
				(width 0.1524)
				(type default)
			)
			(layer "B.SilkS")
		)
		(fp_line
			(start 0.67945 -0.305054)
			(end 0.12065 -0.305054)
			(stroke
				(width 0.1)
				(type default)
			)
			(layer "B.Fab")
		)
		(fp_line
			(start 0.12065 -0.305054)
			(end 0.12065 -0.2794)
			(stroke
				(width 0.1)
				(type default)
			)
			(layer "B.Fab")
		)
		(fp_line
			(start -0.12065 -0.3048)
			(end -0.67945 -0.3048)
			(stroke
				(width 0.1)
				(type default)
			)
			(layer "B.Fab")
		)
		(fp_line
			(start -0.67945 -0.3048)
			(end -0.67945 0.3048)
			(stroke
				(width 0.1)
				(type default)
			)
			(layer "B.Fab")
		)
		(fp_line
			(start 0.12065 -0.2794)
			(end -0.12065 -0.2794)
			(stroke
				(width 0.1)
				(type default)
			)
			(layer "B.Fab")
		)
		(fp_line
			(start -0.12065 -0.2794)
			(end -0.12065 -0.3048)
			(stroke
				(width 0.1)
				(type default)
			)
			(layer "B.Fab")
		)
		(fp_line
			(start 0.12065 0.2794)
			(end 0.12065 0.3048)
			(stroke
				(width 0.1)
				(type default)
			)
			(layer "B.Fab")
		)
		(fp_line
			(start -0.120396 0.2794)
			(end 0.12065 0.2794)
			(stroke
				(width 0.1)
				(type default)
			)
			(layer "B.Fab")
		)
		(fp_line
			(start 0.67945 0.3048)
			(end 0.67945 -0.305054)
			(stroke
				(width 0.1)
				(type default)
			)
			(layer "B.Fab")
		)
		(fp_line
			(start 0.12065 0.3048)
			(end 0.67945 0.3048)
			(stroke
				(width 0.1)
				(type default)
			)
			(layer "B.Fab")
		)
		(fp_line
			(start -0.120396 0.3048)
			(end -0.120396 0.2794)
			(stroke
				(width 0.1)
				(type default)
			)
			(layer "B.Fab")
		)
		(fp_line
			(start -0.67945 0.3048)
			(end -0.120396 0.3048)
			(stroke
				(width 0.1)
				(type default)
			)
			(layer "B.Fab")
		)
		(pad "1" smd circle
			(at 0.40005 0 270)
			(size 0 0)
			(layers "B.Cu" "B.Mask" "B.Paste")
			(net "LED_PWRGD_PS_PWROK_PLD")
		)
		(pad "2" smd circle
			(at -0.40005 0 270)
			(size 0 0)
			(layers "B.Cu" "B.Mask" "B.Paste")
			(net "P3V3_AUX")
		)
	)
	(footprint ""
		(layer "B.Cu")
		(at 62.563248 -168.86682 -90)
		(property "Reference" "PC132_6"
			(at 0 0 90)
			(layer "B.SilkS")
			(hide yes)
			(effects
				(font
					(size 1.27 1.27)
				)
				(justify mirror)
			)
		)
		(property "Value" ""
			(at 0 0 90)
			(layer "B.Fab")
			(effects
				(font
					(size 1.27 1.27)
				)
				(justify mirror)
			)
		)
		(duplicate_pad_numbers_are_jumpers no)
		(fp_line
			(start -1.524 0.762)
			(end 1.524 0.762)
			(stroke
				(width 0.1524)
				(type default)
			)
			(layer "B.SilkS")
		)
		(fp_line
			(start 1.524 0.762)
			(end 1.524 -0.762)
			(stroke
				(width 0.1524)
				(type default)
			)
			(layer "B.SilkS")
		)
		(fp_line
			(start -1.524 -0.762)
			(end -1.524 0.762)
			(stroke
				(width 0.1524)
				(type default)
			)
			(layer "B.SilkS")
		)
		(fp_line
			(start 1.524 -0.762)
			(end -1.524 -0.762)
			(stroke
				(width 0.1524)
				(type default)
			)
			(layer "B.SilkS")
		)
		(fp_line
			(start -1.1049 0.724916)
			(end -1.1049 -0.724916)
			(stroke
				(width 0.1)
				(type default)
			)
			(layer "B.Fab")
		)
		(fp_line
			(start 1.1049 0.724916)
			(end -1.1049 0.724916)
			(stroke
				(width 0.1)
				(type default)
			)
			(layer "B.Fab")
		)
		(fp_line
			(start -1.1049 -0.724916)
			(end 1.1049 -0.724916)
			(stroke
				(width 0.1)
				(type default)
			)
			(layer "B.Fab")
		)
		(fp_line
			(start 1.1049 -0.724916)
			(end 1.1049 0.724916)
			(stroke
				(width 0.1)
				(type default)
			)
			(layer "B.Fab")
		)
		(pad "1" smd rect
			(at 0.889 0 270)
			(size 1.016 1.27)
			(layers "B.Cu" "B.Mask" "B.Paste")
			(net "SW_P12V_AUX_PVDDCR_CPU0_P1_FLT")
		)
		(pad "2" smd rect
			(at -0.889 0 270)
			(size 1.016 1.27)
			(layers "B.Cu" "B.Mask" "B.Paste")
			(net "GND")
		)
	)
	(footprint ""
		(layer "B.Cu")
		(at 372.400322 -416.899344 90)
		(property "Reference" "C6598"
			(at 0 0 90)
			(layer "B.SilkS")
			(hide yes)
			(effects
				(font
					(size 1.27 1.27)
				)
				(justify mirror)
			)
		)
		(property "Value" ""
			(at 0 0 90)
			(layer "B.Fab")
			(effects
				(font
					(size 1.27 1.27)
				)
				(justify mirror)
			)
		)
		(duplicate_pad_numbers_are_jumpers no)
		(fp_line
			(start 0.299974 -0.150114)
			(end -0.299974 -0.150114)
			(stroke
				(width 0.1)
				(type default)
			)
			(layer "B.Fab")
		)
		(fp_line
			(start -0.299974 -0.150114)
			(end -0.299974 0.150114)
			(stroke
				(width 0.1)
				(type default)
			)
			(layer "B.Fab")
		)
		(fp_line
			(start 0.299974 0.150114)
			(end 0.299974 -0.150114)
			(stroke
				(width 0.1)
				(type default)
			)
			(layer "B.Fab")
		)
		(fp_line
			(start -0.299974 0.150114)
			(end 0.299974 0.150114)
			(stroke
				(width 0.1)
				(type default)
			)
			(layer "B.Fab")
		)
		(pad "1" smd rect
			(at 0.2667 0 270)
			(size 0.3048 0.381)
			(layers "B.Cu" "B.Mask" "B.Paste")
			(net "P5E_CPU0_P3_TX_BUF_C_DN<0>")
		)
		(pad "2" smd rect
			(at -0.2667 0 270)
			(size 0.3048 0.381)
			(layers "B.Cu" "B.Mask" "B.Paste")
			(net "P5E_CPU0_P3_TX_BUF_DN<0>")
		)
	)
	(footprint ""
		(layer "B.Cu")
		(at 454.02246 -11.705844)
		(property "Reference" "R38"
			(at 0 0 0)
			(layer "B.SilkS")
			(hide yes)
			(effects
				(font
					(size 1.27 1.27)
				)
				(justify mirror)
			)
		)
		(property "Value" ""
			(at 0 0 0)
			(layer "B.Fab")
			(effects
				(font
					(size 1.27 1.27)
				)
				(justify mirror)
			)
		)
		(duplicate_pad_numbers_are_jumpers no)
		(fp_line
			(start -0.7874 -0.4064)
			(end -0.7874 0.4064)
			(stroke
				(width 0.1524)
				(type default)
			)
			(layer "B.SilkS")
		)
		(fp_line
			(start -0.7874 0.4064)
			(end 0.7874 0.4064)
			(stroke
				(width 0.1524)
				(type default)
			)
			(layer "B.SilkS")
		)
		(fp_line
			(start 0.7874 -0.4064)
			(end -0.7874 -0.4064)
			(stroke
				(width 0.1524)
				(type default)
			)
			(layer "B.SilkS")
		)
		(fp_line
			(start 0.7874 0.4064)
			(end 0.7874 -0.4064)
			(stroke
				(width 0.1524)
				(type default)
			)
			(layer "B.SilkS")
		)
		(fp_line
			(start -0.67945 -0.3048)
			(end -0.67945 0.3048)
			(stroke
				(width 0.1)
				(type default)
			)
			(layer "B.Fab")
		)
		(fp_line
			(start -0.67945 0.3048)
			(end -0.120396 0.3048)
			(stroke
				(width 0.1)
				(type default)
			)
			(layer "B.Fab")
		)
		(fp_line
			(start -0.12065 -0.3048)
			(end -0.67945 -0.3048)
			(stroke
				(width 0.1)
				(type default)
			)
			(layer "B.Fab")
		)
		(fp_line
			(start -0.12065 -0.2794)
			(end -0.12065 -0.3048)
			(stroke
				(width 0.1)
				(type default)
			)
			(layer "B.Fab")
		)
		(fp_line
			(start -0.120396 0.2794)
			(end 0.12065 0.2794)
			(stroke
				(width 0.1)
				(type default)
			)
			(layer "B.Fab")
		)
		(fp_line
			(start -0.120396 0.3048)
			(end -0.120396 0.2794)
			(stroke
				(width 0.1)
				(type default)
			)
			(layer "B.Fab")
		)
		(fp_line
			(start 0.12065 -0.305054)
			(end 0.12065 -0.2794)
			(stroke
				(width 0.1)
				(type default)
			)
			(layer "B.Fab")
		)
		(fp_line
			(start 0.12065 -0.2794)
			(end -0.12065 -0.2794)
			(stroke
				(width 0.1)
				(type default)
			)
			(layer "B.Fab")
		)
		(fp_line
			(start 0.12065 0.2794)
			(end 0.12065 0.3048)
			(stroke
				(width 0.1)
				(type default)
			)
			(layer "B.Fab")
		)
		(fp_line
			(start 0.12065 0.3048)
			(end 0.67945 0.3048)
			(stroke
				(width 0.1)
				(type default)
			)
			(layer "B.Fab")
		)
		(fp_line
			(start 0.67945 -0.305054)
			(end 0.12065 -0.305054)
			(stroke
				(width 0.1)
				(type default)
			)
			(layer "B.Fab")
		)
		(fp_line
			(start 0.67945 0.3048)
			(end 0.67945 -0.305054)
			(stroke
				(width 0.1)
				(type default)
			)
			(layer "B.Fab")
		)
		(pad "1" smd circle
			(at 0.40005 0 180)
			(size 0 0)
			(layers "B.Cu" "B.Mask" "B.Paste")
			(net "OCP_SFF_MAIN_PWR_EN")
		)
		(pad "2" smd circle
			(at -0.40005 0 180)
			(size 0 0)
			(layers "B.Cu" "B.Mask" "B.Paste")
			(net "OCP_SFF_MAIN_PWR_EN_R")
		)
	)
	(footprint ""
		(layer "B.Cu")
		(at 91.493594 -301.716948 180)
		(property "Reference" "R521"
			(at 0 0 0)
			(layer "B.SilkS")
			(hide yes)
			(effects
				(font
					(size 1.27 1.27)
				)
				(justify mirror)
			)
		)
		(property "Value" ""
			(at 0 0 0)
			(layer "B.Fab")
			(effects
				(font
					(size 1.27 1.27)
				)
				(justify mirror)
			)
		)
		(duplicate_pad_numbers_are_jumpers no)
		(fp_line
			(start 0.7874 0.4064)
			(end 0.7874 -0.4064)
			(stroke
				(width 0.1524)
				(type default)
			)
			(layer "B.SilkS")
		)
		(fp_line
			(start 0.7874 -0.4064)
			(end -0.7874 -0.4064)
			(stroke
				(width 0.1524)
				(type default)
			)
			(layer "B.SilkS")
		)
		(fp_line
			(start -0.7874 0.4064)
			(end 0.7874 0.4064)
			(stroke
				(width 0.1524)
				(type default)
			)
			(layer "B.SilkS")
		)
		(fp_line
			(start -0.7874 -0.4064)
			(end -0.7874 0.4064)
			(stroke
				(width 0.1524)
				(type default)
			)
			(layer "B.SilkS")
		)
		(fp_line
			(start 0.67945 0.3048)
			(end 0.67945 -0.305054)
			(stroke
				(width 0.1)
				(type default)
			)
			(layer "B.Fab")
		)
		(fp_line
			(start 0.67945 -0.305054)
			(end 0.12065 -0.305054)
			(stroke
				(width 0.1)
				(type default)
			)
			(layer "B.Fab")
		)
		(fp_line
			(start 0.12065 0.3048)
			(end 0.67945 0.3048)
			(stroke
				(width 0.1)
				(type default)
			)
			(layer "B.Fab")
		)
		(fp_line
			(start 0.12065 0.2794)
			(end 0.12065 0.3048)
			(stroke
				(width 0.1)
				(type default)
			)
			(layer "B.Fab")
		)
		(fp_line
			(start 0.12065 -0.2794)
			(end -0.12065 -0.2794)
			(stroke
				(width 0.1)
				(type default)
			)
			(layer "B.Fab")
		)
		(fp_line
			(start 0.12065 -0.305054)
			(end 0.12065 -0.2794)
			(stroke
				(width 0.1)
				(type default)
			)
			(layer "B.Fab")
		)
		(fp_line
			(start -0.120396 0.3048)
			(end -0.120396 0.2794)
			(stroke
				(width 0.1)
				(type default)
			)
			(layer "B.Fab")
		)
		(fp_line
			(start -0.120396 0.2794)
			(end 0.12065 0.2794)
			(stroke
				(width 0.1)
				(type default)
			)
			(layer "B.Fab")
		)
		(fp_line
			(start -0.12065 -0.2794)
			(end -0.12065 -0.3048)
			(stroke
				(width 0.1)
				(type default)
			)
			(layer "B.Fab")
		)
		(fp_line
			(start -0.12065 -0.3048)
			(end -0.67945 -0.3048)
			(stroke
				(width 0.1)
				(type default)
			)
			(layer "B.Fab")
		)
		(fp_line
			(start -0.67945 0.3048)
			(end -0.120396 0.3048)
			(stroke
				(width 0.1)
				(type default)
			)
			(layer "B.Fab")
		)
		(fp_line
			(start -0.67945 -0.3048)
			(end -0.67945 0.3048)
			(stroke
				(width 0.1)
				(type default)
			)
			(layer "B.Fab")
		)
		(pad "1" smd circle
			(at 0.40005 0)
			(size 0 0)
			(layers "B.Cu" "B.Mask" "B.Paste")
			(net "CPU1_SA1")
		)
		(pad "2" smd circle
			(at -0.40005 0)
			(size 0 0)
			(layers "B.Cu" "B.Mask" "B.Paste")
			(net "GND")
		)
	)
	(footprint ""
		(layer "B.Cu")
		(at 125.800866 -156.378148 -90)
		(property "Reference" "PC8011"
			(at 0 0 90)
			(layer "B.SilkS")
			(hide yes)
			(effects
				(font
					(size 1.27 1.27)
				)
				(justify mirror)
			)
		)
		(property "Value" ""
			(at 0 0 90)
			(layer "B.Fab")
			(effects
				(font
					(size 1.27 1.27)
				)
				(justify mirror)
			)
		)
		(duplicate_pad_numbers_are_jumpers no)
		(fp_line
			(start -1.524 0.762)
			(end 1.524 0.762)
			(stroke
				(width 0.1524)
				(type default)
			)
			(layer "B.SilkS")
		)
		(fp_line
			(start 1.524 0.762)
			(end 1.524 -0.762)
			(stroke
				(width 0.1524)
				(type default)
			)
			(layer "B.SilkS")
		)
		(fp_line
			(start -1.524 -0.762)
			(end -1.524 0.762)
			(stroke
				(width 0.1524)
				(type default)
			)
			(layer "B.SilkS")
		)
		(fp_line
			(start 1.524 -0.762)
			(end -1.524 -0.762)
			(stroke
				(width 0.1524)
				(type default)
			)
			(layer "B.SilkS")
		)
		(fp_line
			(start -1.1049 0.724916)
			(end -1.1049 -0.724916)
			(stroke
				(width 0.1)
				(type default)
			)
			(layer "B.Fab")
		)
		(fp_line
			(start 1.1049 0.724916)
			(end -1.1049 0.724916)
			(stroke
				(width 0.1)
				(type default)
			)
			(layer "B.Fab")
		)
		(fp_line
			(start -1.1049 -0.724916)
			(end 1.1049 -0.724916)
			(stroke
				(width 0.1)
				(type default)
			)
			(layer "B.Fab")
		)
		(fp_line
			(start 1.1049 -0.724916)
			(end 1.1049 0.724916)
			(stroke
				(width 0.1)
				(type default)
			)
			(layer "B.Fab")
		)
		(pad "1" smd rect
			(at 0.889 0 270)
			(size 1.016 1.27)
			(layers "B.Cu" "B.Mask" "B.Paste")
			(net "SW_P12V_AUX_PVDDCR_SOC_P1_FLT")
		)
		(pad "2" smd rect
			(at -0.889 0 270)
			(size 1.016 1.27)
			(layers "B.Cu" "B.Mask" "B.Paste")
			(net "GND")
		)
	)
	(footprint ""
		(layer "B.Cu")
		(at 101.385878 -141.58341 180)
		(property "Reference" "PC6"
			(at 0 0 0)
			(layer "B.SilkS")
			(hide yes)
			(effects
				(font
					(size 1.27 1.27)
				)
				(justify mirror)
			)
		)
		(property "Value" ""
			(at 0 0 0)
			(layer "B.Fab")
			(effects
				(font
					(size 1.27 1.27)
				)
				(justify mirror)
			)
		)
		(duplicate_pad_numbers_are_jumpers no)
		(fp_line
			(start 0.7874 0.4064)
			(end 0.7874 -0.4064)
			(stroke
				(width 0.1524)
				(type default)
			)
			(layer "B.SilkS")
		)
		(fp_line
			(start 0.7874 -0.4064)
			(end -0.7874 -0.4064)
			(stroke
				(width 0.1524)
				(type default)
			)
			(layer "B.SilkS")
		)
		(fp_line
			(start -0.7874 0.4064)
			(end 0.7874 0.4064)
			(stroke
				(width 0.1524)
				(type default)
			)
			(layer "B.SilkS")
		)
		(fp_line
			(start -0.7874 -0.4064)
			(end -0.7874 0.4064)
			(stroke
				(width 0.1524)
				(type default)
			)
			(layer "B.SilkS")
		)
		(fp_line
			(start 0.67945 0.3048)
			(end 0.67945 -0.305054)
			(stroke
				(width 0.1)
				(type default)
			)
			(layer "B.Fab")
		)
		(fp_line
			(start 0.67945 -0.305054)
			(end 0.12065 -0.305054)
			(stroke
				(width 0.1)
				(type default)
			)
			(layer "B.Fab")
		)
		(fp_line
			(start 0.12065 0.3048)
			(end 0.67945 0.3048)
			(stroke
				(width 0.1)
				(type default)
			)
			(layer "B.Fab")
		)
		(fp_line
			(start 0.12065 0.2794)
			(end 0.12065 0.3048)
			(stroke
				(width 0.1)
				(type default)
			)
			(layer "B.Fab")
		)
		(fp_line
			(start 0.12065 -0.2794)
			(end -0.12065 -0.2794)
			(stroke
				(width 0.1)
				(type default)
			)
			(layer "B.Fab")
		)
		(fp_line
			(start 0.12065 -0.305054)
			(end 0.12065 -0.2794)
			(stroke
				(width 0.1)
				(type default)
			)
			(layer "B.Fab")
		)
		(fp_line
			(start -0.120396 0.3048)
			(end -0.120396 0.2794)
			(stroke
				(width 0.1)
				(type default)
			)
			(layer "B.Fab")
		)
		(fp_line
			(start -0.120396 0.2794)
			(end 0.12065 0.2794)
			(stroke
				(width 0.1)
				(type default)
			)
			(layer "B.Fab")
		)
		(fp_line
			(start -0.12065 -0.2794)
			(end -0.12065 -0.3048)
			(stroke
				(width 0.1)
				(type default)
			)
			(layer "B.Fab")
		)
		(fp_line
			(start -0.12065 -0.3048)
			(end -0.67945 -0.3048)
			(stroke
				(width 0.1)
				(type default)
			)
			(layer "B.Fab")
		)
		(fp_line
			(start -0.67945 0.3048)
			(end -0.120396 0.3048)
			(stroke
				(width 0.1)
				(type default)
			)
			(layer "B.Fab")
		)
		(fp_line
			(start -0.67945 -0.3048)
			(end -0.67945 0.3048)
			(stroke
				(width 0.1)
				(type default)
			)
			(layer "B.Fab")
		)
		(pad "1" smd circle
			(at 0.40005 0)
			(size 0 0)
			(layers "B.Cu" "B.Mask" "B.Paste")
			(net "PVDDCR_CPU0_P1_VINSEN")
		)
		(pad "2" smd circle
			(at -0.40005 0)
			(size 0 0)
			(layers "B.Cu" "B.Mask" "B.Paste")
			(net "GND")
		)
	)
	(footprint ""
		(layer "B.Cu")
		(at 382.208278 -137.535158 90)
		(property "Reference" "PC470"
			(at 0 0 90)
			(layer "B.SilkS")
			(hide yes)
			(effects
				(font
					(size 1.27 1.27)
				)
				(justify mirror)
			)
		)
		(property "Value" ""
			(at 0 0 90)
			(layer "B.Fab")
			(effects
				(font
					(size 1.27 1.27)
				)
				(justify mirror)
			)
		)
		(duplicate_pad_numbers_are_jumpers no)
		(fp_line
			(start 0.7874 -0.4064)
			(end -0.7874 -0.4064)
			(stroke
				(width 0.1524)
				(type default)
			)
			(layer "B.SilkS")
		)
		(fp_line
			(start -0.7874 -0.4064)
			(end -0.7874 0.4064)
			(stroke
				(width 0.1524)
				(type default)
			)
			(layer "B.SilkS")
		)
		(fp_line
			(start 0.7874 0.4064)
			(end 0.7874 -0.4064)
			(stroke
				(width 0.1524)
				(type default)
			)
			(layer "B.SilkS")
		)
		(fp_line
			(start -0.7874 0.4064)
			(end 0.7874 0.4064)
			(stroke
				(width 0.1524)
				(type default)
			)
			(layer "B.SilkS")
		)
		(fp_line
			(start 0.67945 -0.305054)
			(end 0.12065 -0.305054)
			(stroke
				(width 0.1)
				(type default)
			)
			(layer "B.Fab")
		)
		(fp_line
			(start 0.12065 -0.305054)
			(end 0.12065 -0.2794)
			(stroke
				(width 0.1)
				(type default)
			)
			(layer "B.Fab")
		)
		(fp_line
			(start -0.12065 -0.3048)
			(end -0.67945 -0.3048)
			(stroke
				(width 0.1)
				(type default)
			)
			(layer "B.Fab")
		)
		(fp_line
			(start -0.67945 -0.3048)
			(end -0.67945 0.3048)
			(stroke
				(width 0.1)
				(type default)
			)
			(layer "B.Fab")
		)
		(fp_line
			(start 0.12065 -0.2794)
			(end -0.12065 -0.2794)
			(stroke
				(width 0.1)
				(type default)
			)
			(layer "B.Fab")
		)
		(fp_line
			(start -0.12065 -0.2794)
			(end -0.12065 -0.3048)
			(stroke
				(width 0.1)
				(type default)
			)
			(layer "B.Fab")
		)
		(fp_line
			(start 0.12065 0.2794)
			(end 0.12065 0.3048)
			(stroke
				(width 0.1)
				(type default)
			)
			(layer "B.Fab")
		)
		(fp_line
			(start -0.120396 0.2794)
			(end 0.12065 0.2794)
			(stroke
				(width 0.1)
				(type default)
			)
			(layer "B.Fab")
		)
		(fp_line
			(start 0.67945 0.3048)
			(end 0.67945 -0.305054)
			(stroke
				(width 0.1)
				(type default)
			)
			(layer "B.Fab")
		)
		(fp_line
			(start 0.12065 0.3048)
			(end 0.67945 0.3048)
			(stroke
				(width 0.1)
				(type default)
			)
			(layer "B.Fab")
		)
		(fp_line
			(start -0.120396 0.3048)
			(end -0.120396 0.2794)
			(stroke
				(width 0.1)
				(type default)
			)
			(layer "B.Fab")
		)
		(fp_line
			(start -0.67945 0.3048)
			(end -0.120396 0.3048)
			(stroke
				(width 0.1)
				(type default)
			)
			(layer "B.Fab")
		)
		(pad "1" smd circle
			(at 0.40005 0 270)
			(size 0 0)
			(layers "B.Cu" "B.Mask" "B.Paste")
			(net "PVDDCR_CPU0_P0_VCCS")
		)
		(pad "2" smd circle
			(at -0.40005 0 270)
			(size 0 0)
			(layers "B.Cu" "B.Mask" "B.Paste")
			(net "GND")
		)
	)
	(footprint ""
		(layer "B.Cu")
		(at 375.597166 -389.49503 180)
		(property "Reference" "C7017"
			(at -1.554988 -3.243072 0)
			(unlocked yes)
			(layer "B.SilkS")
			(effects
				(font
					(size 0.7874 0.5842)
					(thickness 0.1524)
				)
				(justify left mirror)
			)
		)
		(property "Value" ""
			(at 0 0 0)
			(layer "B.Fab")
			(effects
				(font
					(size 1.27 1.27)
				)
				(justify mirror)
			)
		)
		(duplicate_pad_numbers_are_jumpers no)
		(fp_line
			(start 4.84378 -2.150618)
			(end 4.842256 2.163064)
			(stroke
				(width 0.1524)
				(type default)
			)
			(layer "B.SilkS")
		)
		(fp_line
			(start 4.84378 -2.150618)
			(end 4.53898 -2.150618)
			(stroke
				(width 0.1524)
				(type default)
			)
			(layer "B.SilkS")
		)
		(fp_line
			(start 4.83108 2.150364)
			(end 4.447794 2.149348)
			(stroke
				(width 0.1524)
				(type default)
			)
			(layer "B.SilkS")
		)
		(fp_line
			(start 4.69138 -2.150618)
			(end 4.692396 2.161032)
			(stroke
				(width 0.1524)
				(type default)
			)
			(layer "B.SilkS")
		)
		(fp_line
			(start 4.53898 2.15011)
			(end 4.53898 -2.15011)
			(stroke
				(width 0.1524)
				(type default)
			)
			(layer "B.SilkS")
		)
		(fp_line
			(start 4.53898 -2.15011)
			(end -4.53898 -2.15011)
			(stroke
				(width 0.1524)
				(type default)
			)
			(layer "B.SilkS")
		)
		(fp_line
			(start 4.53898 -2.150618)
			(end 4.539742 2.152142)
			(stroke
				(width 0.1524)
				(type default)
			)
			(layer "B.SilkS")
		)
		(fp_line
			(start -4.53898 2.15011)
			(end 4.53898 2.15011)
			(stroke
				(width 0.1524)
				(type default)
			)
			(layer "B.SilkS")
		)
		(fp_line
			(start -4.53898 -2.15011)
			(end -4.53898 2.15011)
			(stroke
				(width 0.1524)
				(type default)
			)
			(layer "B.SilkS")
		)
		(fp_line
			(start 3.64998 2.15011)
			(end 3.64998 -2.15011)
			(stroke
				(width 0.1)
				(type default)
			)
			(layer "B.Fab")
		)
		(fp_line
			(start 3.64998 -2.15011)
			(end -3.64998 -2.15011)
			(stroke
				(width 0.1)
				(type default)
			)
			(layer "B.Fab")
		)
		(fp_line
			(start -3.64998 2.15011)
			(end 3.64998 2.15011)
			(stroke
				(width 0.1)
				(type default)
			)
			(layer "B.Fab")
		)
		(fp_line
			(start -3.64998 -2.15011)
			(end -3.64998 2.15011)
			(stroke
				(width 0.1)
				(type default)
			)
			(layer "B.Fab")
		)
		(fp_text user "+"
			(at 4.233672 -3.049778 180)
			(unlocked yes)
			(layer "B.SilkS")
			(effects
				(font
					(size 1.905 1.4224)
					(thickness 0.1524)
				)
				(justify left mirror)
			)
		)
		(fp_text user "-"
			(at -2.707894 -2.736088 180)
			(unlocked yes)
			(layer "B.SilkS")
			(effects
				(font
					(size 1.905 1.4224)
					(thickness 0.1524)
				)
				(justify left mirror)
			)
		)
		(fp_text user "+"
			(at 6.214872 -0.337058 180)
			(unlocked yes)
			(layer "B.Fab")
			(effects
				(font
					(size 1.905 1.4224)
					(thickness 0.1524)
				)
				(justify left mirror)
			)
		)
		(fp_text user "-"
			(at -4.313174 -0.094488 180)
			(unlocked yes)
			(layer "B.Fab")
			(effects
				(font
					(size 1.905 1.4224)
					(thickness 0.1524)
				)
				(justify left mirror)
			)
		)
		(pad "1" smd rect
			(at 3.199892 0)
			(size 2.413 2.8194)
			(layers "B.Cu" "B.Mask" "B.Paste")
			(net "P0V9_CPU0_RT3_2A")
		)
		(pad "2" smd rect
			(at -3.199892 0)
			(size 2.413 2.8194)
			(layers "B.Cu" "B.Mask" "B.Paste")
			(net "GND")
		)
	)
	(footprint ""
		(layer "B.Cu")
		(at 180.162962 -13.896594 90)
		(property "Reference" "R3778"
			(at 0 0 90)
			(layer "B.SilkS")
			(hide yes)
			(effects
				(font
					(size 1.27 1.27)
				)
				(justify mirror)
			)
		)
		(property "Value" ""
			(at 0 0 90)
			(layer "B.Fab")
			(effects
				(font
					(size 1.27 1.27)
				)
				(justify mirror)
			)
		)
		(duplicate_pad_numbers_are_jumpers no)
		(fp_line
			(start 0.7874 -0.4064)
			(end -0.7874 -0.4064)
			(stroke
				(width 0.1524)
				(type default)
			)
			(layer "B.SilkS")
		)
		(fp_line
			(start -0.7874 -0.4064)
			(end -0.7874 0.4064)
			(stroke
				(width 0.1524)
				(type default)
			)
			(layer "B.SilkS")
		)
		(fp_line
			(start 0.7874 0.4064)
			(end 0.7874 -0.4064)
			(stroke
				(width 0.1524)
				(type default)
			)
			(layer "B.SilkS")
		)
		(fp_line
			(start -0.7874 0.4064)
			(end 0.7874 0.4064)
			(stroke
				(width 0.1524)
				(type default)
			)
			(layer "B.SilkS")
		)
		(fp_line
			(start 0.67945 -0.305054)
			(end 0.12065 -0.305054)
			(stroke
				(width 0.1)
				(type default)
			)
			(layer "B.Fab")
		)
		(fp_line
			(start 0.12065 -0.305054)
			(end 0.12065 -0.2794)
			(stroke
				(width 0.1)
				(type default)
			)
			(layer "B.Fab")
		)
		(fp_line
			(start -0.12065 -0.3048)
			(end -0.67945 -0.3048)
			(stroke
				(width 0.1)
				(type default)
			)
			(layer "B.Fab")
		)
		(fp_line
			(start -0.67945 -0.3048)
			(end -0.67945 0.3048)
			(stroke
				(width 0.1)
				(type default)
			)
			(layer "B.Fab")
		)
		(fp_line
			(start 0.12065 -0.2794)
			(end -0.12065 -0.2794)
			(stroke
				(width 0.1)
				(type default)
			)
			(layer "B.Fab")
		)
		(fp_line
			(start -0.12065 -0.2794)
			(end -0.12065 -0.3048)
			(stroke
				(width 0.1)
				(type default)
			)
			(layer "B.Fab")
		)
		(fp_line
			(start 0.12065 0.2794)
			(end 0.12065 0.3048)
			(stroke
				(width 0.1)
				(type default)
			)
			(layer "B.Fab")
		)
		(fp_line
			(start -0.120396 0.2794)
			(end 0.12065 0.2794)
			(stroke
				(width 0.1)
				(type default)
			)
			(layer "B.Fab")
		)
		(fp_line
			(start 0.67945 0.3048)
			(end 0.67945 -0.305054)
			(stroke
				(width 0.1)
				(type default)
			)
			(layer "B.Fab")
		)
		(fp_line
			(start 0.12065 0.3048)
			(end 0.67945 0.3048)
			(stroke
				(width 0.1)
				(type default)
			)
			(layer "B.Fab")
		)
		(fp_line
			(start -0.120396 0.3048)
			(end -0.120396 0.2794)
			(stroke
				(width 0.1)
				(type default)
			)
			(layer "B.Fab")
		)
		(fp_line
			(start -0.67945 0.3048)
			(end -0.120396 0.3048)
			(stroke
				(width 0.1)
				(type default)
			)
			(layer "B.Fab")
		)
		(pad "1" smd circle
			(at 0.40005 0 270)
			(size 0 0)
			(layers "B.Cu" "B.Mask" "B.Paste")
			(net "FM_SOL_UART_CH_SEL_R")
		)
		(pad "2" smd circle
			(at -0.40005 0 270)
			(size 0 0)
			(layers "B.Cu" "B.Mask" "B.Paste")
			(net "FM_SOL_UART_CH_SEL")
		)
	)
	(footprint ""
		(layer "B.Cu")
		(at 95.248984 -408.517344 90)
		(property "Reference" "C6692"
			(at 0 0 90)
			(layer "B.SilkS")
			(hide yes)
			(effects
				(font
					(size 1.27 1.27)
				)
				(justify mirror)
			)
		)
		(property "Value" ""
			(at 0 0 90)
			(layer "B.Fab")
			(effects
				(font
					(size 1.27 1.27)
				)
				(justify mirror)
			)
		)
		(duplicate_pad_numbers_are_jumpers no)
		(fp_line
			(start 0.299974 -0.150114)
			(end -0.299974 -0.150114)
			(stroke
				(width 0.1)
				(type default)
			)
			(layer "B.Fab")
		)
		(fp_line
			(start -0.299974 -0.150114)
			(end -0.299974 0.150114)
			(stroke
				(width 0.1)
				(type default)
			)
			(layer "B.Fab")
		)
		(fp_line
			(start 0.299974 0.150114)
			(end 0.299974 -0.150114)
			(stroke
				(width 0.1)
				(type default)
			)
			(layer "B.Fab")
		)
		(fp_line
			(start -0.299974 0.150114)
			(end 0.299974 0.150114)
			(stroke
				(width 0.1)
				(type default)
			)
			(layer "B.Fab")
		)
		(pad "1" smd rect
			(at 0.2667 0 270)
			(size 0.3048 0.381)
			(layers "B.Cu" "B.Mask" "B.Paste")
			(net "P5E_CPU1_P1_TX_BUF_C_DN<15>")
		)
		(pad "2" smd rect
			(at -0.2667 0 270)
			(size 0.3048 0.381)
			(layers "B.Cu" "B.Mask" "B.Paste")
			(net "P5E_CPU1_P1_TX_BUF_DN<15>")
		)
	)
	(footprint ""
		(layer "B.Cu")
		(at 245.873778 -315.95568 -90)
		(property "Reference" "PC6512"
			(at 0 0 90)
			(layer "B.SilkS")
			(hide yes)
			(effects
				(font
					(size 1.27 1.27)
				)
				(justify mirror)
			)
		)
		(property "Value" ""
			(at 0 0 90)
			(layer "B.Fab")
			(effects
				(font
					(size 1.27 1.27)
				)
				(justify mirror)
			)
		)
		(duplicate_pad_numbers_are_jumpers no)
		(fp_line
			(start -1.524 0.762)
			(end 1.524 0.762)
			(stroke
				(width 0.1524)
				(type default)
			)
			(layer "B.SilkS")
		)
		(fp_line
			(start 1.524 0.762)
			(end 1.524 -0.762)
			(stroke
				(width 0.1524)
				(type default)
			)
			(layer "B.SilkS")
		)
		(fp_line
			(start -1.524 -0.762)
			(end -1.524 0.762)
			(stroke
				(width 0.1524)
				(type default)
			)
			(layer "B.SilkS")
		)
		(fp_line
			(start 1.524 -0.762)
			(end -1.524 -0.762)
			(stroke
				(width 0.1524)
				(type default)
			)
			(layer "B.SilkS")
		)
		(fp_line
			(start -1.1049 0.724916)
			(end -1.1049 -0.724916)
			(stroke
				(width 0.1)
				(type default)
			)
			(layer "B.Fab")
		)
		(fp_line
			(start 1.1049 0.724916)
			(end -1.1049 0.724916)
			(stroke
				(width 0.1)
				(type default)
			)
			(layer "B.Fab")
		)
		(fp_line
			(start -1.1049 -0.724916)
			(end 1.1049 -0.724916)
			(stroke
				(width 0.1)
				(type default)
			)
			(layer "B.Fab")
		)
		(fp_line
			(start 1.1049 -0.724916)
			(end 1.1049 0.724916)
			(stroke
				(width 0.1)
				(type default)
			)
			(layer "B.Fab")
		)
		(pad "1" smd rect
			(at 0.889 0 270)
			(size 1.016 1.27)
			(layers "B.Cu" "B.Mask" "B.Paste")
			(net "P1V8_CPU0_RT_1D")
		)
		(pad "2" smd rect
			(at -0.889 0 270)
			(size 1.016 1.27)
			(layers "B.Cu" "B.Mask" "B.Paste")
			(net "GND")
		)
	)
	(footprint ""
		(layer "B.Cu")
		(at 161.276284 -192.907412 -90)
		(property "Reference" "R567"
			(at 0 0 90)
			(layer "B.SilkS")
			(hide yes)
			(effects
				(font
					(size 1.27 1.27)
				)
				(justify mirror)
			)
		)
		(property "Value" ""
			(at 0 0 90)
			(layer "B.Fab")
			(effects
				(font
					(size 1.27 1.27)
				)
				(justify mirror)
			)
		)
		(duplicate_pad_numbers_are_jumpers no)
		(fp_line
			(start -0.7874 0.4064)
			(end 0.7874 0.4064)
			(stroke
				(width 0.1524)
				(type default)
			)
			(layer "B.SilkS")
		)
		(fp_line
			(start 0.7874 0.4064)
			(end 0.7874 -0.4064)
			(stroke
				(width 0.1524)
				(type default)
			)
			(layer "B.SilkS")
		)
		(fp_line
			(start -0.7874 -0.4064)
			(end -0.7874 0.4064)
			(stroke
				(width 0.1524)
				(type default)
			)
			(layer "B.SilkS")
		)
		(fp_line
			(start 0.7874 -0.4064)
			(end -0.7874 -0.4064)
			(stroke
				(width 0.1524)
				(type default)
			)
			(layer "B.SilkS")
		)
		(fp_line
			(start -0.67945 0.3048)
			(end -0.120396 0.3048)
			(stroke
				(width 0.1)
				(type default)
			)
			(layer "B.Fab")
		)
		(fp_line
			(start -0.120396 0.3048)
			(end -0.120396 0.2794)
			(stroke
				(width 0.1)
				(type default)
			)
			(layer "B.Fab")
		)
		(fp_line
			(start 0.12065 0.3048)
			(end 0.67945 0.3048)
			(stroke
				(width 0.1)
				(type default)
			)
			(layer "B.Fab")
		)
		(fp_line
			(start 0.67945 0.3048)
			(end 0.67945 -0.305054)
			(stroke
				(width 0.1)
				(type default)
			)
			(layer "B.Fab")
		)
		(fp_line
			(start -0.120396 0.2794)
			(end 0.12065 0.2794)
			(stroke
				(width 0.1)
				(type default)
			)
			(layer "B.Fab")
		)
		(fp_line
			(start 0.12065 0.2794)
			(end 0.12065 0.3048)
			(stroke
				(width 0.1)
				(type default)
			)
			(layer "B.Fab")
		)
		(fp_line
			(start -0.12065 -0.2794)
			(end -0.12065 -0.3048)
			(stroke
				(width 0.1)
				(type default)
			)
			(layer "B.Fab")
		)
		(fp_line
			(start 0.12065 -0.2794)
			(end -0.12065 -0.2794)
			(stroke
				(width 0.1)
				(type default)
			)
			(layer "B.Fab")
		)
		(fp_line
			(start -0.67945 -0.3048)
			(end -0.67945 0.3048)
			(stroke
				(width 0.1)
				(type default)
			)
			(layer "B.Fab")
		)
		(fp_line
			(start -0.12065 -0.3048)
			(end -0.67945 -0.3048)
			(stroke
				(width 0.1)
				(type default)
			)
			(layer "B.Fab")
		)
		(fp_line
			(start 0.12065 -0.305054)
			(end 0.12065 -0.2794)
			(stroke
				(width 0.1)
				(type default)
			)
			(layer "B.Fab")
		)
		(fp_line
			(start 0.67945 -0.305054)
			(end 0.12065 -0.305054)
			(stroke
				(width 0.1)
				(type default)
			)
			(layer "B.Fab")
		)
		(pad "1" smd rect
			(at 0.40005 0 270)
			(size 0.4572 0.508)
			(layers "B.Cu" "B.Mask" "B.Paste")
			(net "I3C_1_SPD_DDRGL_CPU1_SDA")
		)
		(pad "2" smd rect
			(at -0.40005 0 270)
			(size 0.4572 0.508)
			(layers "B.Cu" "B.Mask" "B.Paste")
			(net "I3C_1_SPD_DDRGL_CPU1_R_SDA")
		)
	)
	(footprint ""
		(layer "B.Cu")
		(at 307.118258 -396.393162 -90)
		(property "Reference" "C558"
			(at 0 0 90)
			(layer "B.SilkS")
			(hide yes)
			(effects
				(font
					(size 1.27 1.27)
				)
				(justify mirror)
			)
		)
		(property "Value" ""
			(at 0 0 90)
			(layer "B.Fab")
			(effects
				(font
					(size 1.27 1.27)
				)
				(justify mirror)
			)
		)
		(duplicate_pad_numbers_are_jumpers no)
		(fp_line
			(start -0.299974 0.150114)
			(end 0.299974 0.150114)
			(stroke
				(width 0.1)
				(type default)
			)
			(layer "B.Fab")
		)
		(fp_line
			(start 0.299974 0.150114)
			(end 0.299974 -0.150114)
			(stroke
				(width 0.1)
				(type default)
			)
			(layer "B.Fab")
		)
		(fp_line
			(start -0.299974 -0.150114)
			(end -0.299974 0.150114)
			(stroke
				(width 0.1)
				(type default)
			)
			(layer "B.Fab")
		)
		(fp_line
			(start 0.299974 -0.150114)
			(end -0.299974 -0.150114)
			(stroke
				(width 0.1)
				(type default)
			)
			(layer "B.Fab")
		)
		(pad "1" smd rect
			(at 0.2667 0 90)
			(size 0.3048 0.381)
			(layers "B.Cu" "B.Mask" "B.Paste")
			(net "P0V9_CPU0_RT0_2A")
		)
		(pad "2" smd rect
			(at -0.2667 0 90)
			(size 0.3048 0.381)
			(layers "B.Cu" "B.Mask" "B.Paste")
			(net "GND")
		)
	)
	(footprint ""
		(layer "B.Cu")
		(at 98.454464 -266.640564)
		(property "Reference" "C2659"
			(at 0 0 0)
			(layer "B.SilkS")
			(hide yes)
			(effects
				(font
					(size 1.27 1.27)
				)
				(justify mirror)
			)
		)
		(property "Value" ""
			(at 0 0 0)
			(layer "B.Fab")
			(effects
				(font
					(size 1.27 1.27)
				)
				(justify mirror)
			)
		)
		(duplicate_pad_numbers_are_jumpers no)
		(fp_line
			(start -0.7874 -0.4064)
			(end -0.7874 0.4064)
			(stroke
				(width 0.1524)
				(type default)
			)
			(layer "B.SilkS")
		)
		(fp_line
			(start -0.7874 0.4064)
			(end 0.7874 0.4064)
			(stroke
				(width 0.1524)
				(type default)
			)
			(layer "B.SilkS")
		)
		(fp_line
			(start 0.7874 -0.4064)
			(end -0.7874 -0.4064)
			(stroke
				(width 0.1524)
				(type default)
			)
			(layer "B.SilkS")
		)
		(fp_line
			(start 0.7874 0.4064)
			(end 0.7874 -0.4064)
			(stroke
				(width 0.1524)
				(type default)
			)
			(layer "B.SilkS")
		)
		(fp_line
			(start -0.67945 -0.3048)
			(end -0.67945 0.3048)
			(stroke
				(width 0.1)
				(type default)
			)
			(layer "B.Fab")
		)
		(fp_line
			(start -0.67945 0.3048)
			(end -0.120396 0.3048)
			(stroke
				(width 0.1)
				(type default)
			)
			(layer "B.Fab")
		)
		(fp_line
			(start -0.12065 -0.3048)
			(end -0.67945 -0.3048)
			(stroke
				(width 0.1)
				(type default)
			)
			(layer "B.Fab")
		)
		(fp_line
			(start -0.12065 -0.2794)
			(end -0.12065 -0.3048)
			(stroke
				(width 0.1)
				(type default)
			)
			(layer "B.Fab")
		)
		(fp_line
			(start -0.120396 0.2794)
			(end 0.12065 0.2794)
			(stroke
				(width 0.1)
				(type default)
			)
			(layer "B.Fab")
		)
		(fp_line
			(start -0.120396 0.3048)
			(end -0.120396 0.2794)
			(stroke
				(width 0.1)
				(type default)
			)
			(layer "B.Fab")
		)
		(fp_line
			(start 0.12065 -0.305054)
			(end 0.12065 -0.2794)
			(stroke
				(width 0.1)
				(type default)
			)
			(layer "B.Fab")
		)
		(fp_line
			(start 0.12065 -0.2794)
			(end -0.12065 -0.2794)
			(stroke
				(width 0.1)
				(type default)
			)
			(layer "B.Fab")
		)
		(fp_line
			(start 0.12065 0.2794)
			(end 0.12065 0.3048)
			(stroke
				(width 0.1)
				(type default)
			)
			(layer "B.Fab")
		)
		(fp_line
			(start 0.12065 0.3048)
			(end 0.67945 0.3048)
			(stroke
				(width 0.1)
				(type default)
			)
			(layer "B.Fab")
		)
		(fp_line
			(start 0.67945 -0.305054)
			(end 0.12065 -0.305054)
			(stroke
				(width 0.1)
				(type default)
			)
			(layer "B.Fab")
		)
		(fp_line
			(start 0.67945 0.3048)
			(end 0.67945 -0.305054)
			(stroke
				(width 0.1)
				(type default)
			)
			(layer "B.Fab")
		)
		(pad "1" smd circle
			(at 0.40005 0 180)
			(size 0 0)
			(layers "B.Cu" "B.Mask" "B.Paste")
			(net "PVDD_33_S5")
		)
		(pad "2" smd circle
			(at -0.40005 0 180)
			(size 0 0)
			(layers "B.Cu" "B.Mask" "B.Paste")
			(net "GND")
		)
	)
	(footprint ""
		(layer "B.Cu")
		(at 134.262114 -33.834578 180)
		(property "Reference" "C6048"
			(at 0 0 0)
			(layer "B.SilkS")
			(hide yes)
			(effects
				(font
					(size 1.27 1.27)
				)
				(justify mirror)
			)
		)
		(property "Value" ""
			(at 0 0 0)
			(layer "B.Fab")
			(effects
				(font
					(size 1.27 1.27)
				)
				(justify mirror)
			)
		)
		(duplicate_pad_numbers_are_jumpers no)
		(fp_line
			(start 0.7874 0.4064)
			(end 0.7874 -0.4064)
			(stroke
				(width 0.1524)
				(type default)
			)
			(layer "B.SilkS")
		)
		(fp_line
			(start 0.7874 -0.4064)
			(end -0.7874 -0.4064)
			(stroke
				(width 0.1524)
				(type default)
			)
			(layer "B.SilkS")
		)
		(fp_line
			(start -0.7874 0.4064)
			(end 0.7874 0.4064)
			(stroke
				(width 0.1524)
				(type default)
			)
			(layer "B.SilkS")
		)
		(fp_line
			(start -0.7874 -0.4064)
			(end -0.7874 0.4064)
			(stroke
				(width 0.1524)
				(type default)
			)
			(layer "B.SilkS")
		)
		(fp_line
			(start 0.67945 0.3048)
			(end 0.67945 -0.305054)
			(stroke
				(width 0.1)
				(type default)
			)
			(layer "B.Fab")
		)
		(fp_line
			(start 0.67945 -0.305054)
			(end 0.12065 -0.305054)
			(stroke
				(width 0.1)
				(type default)
			)
			(layer "B.Fab")
		)
		(fp_line
			(start 0.12065 0.3048)
			(end 0.67945 0.3048)
			(stroke
				(width 0.1)
				(type default)
			)
			(layer "B.Fab")
		)
		(fp_line
			(start 0.12065 0.2794)
			(end 0.12065 0.3048)
			(stroke
				(width 0.1)
				(type default)
			)
			(layer "B.Fab")
		)
		(fp_line
			(start 0.12065 -0.2794)
			(end -0.12065 -0.2794)
			(stroke
				(width 0.1)
				(type default)
			)
			(layer "B.Fab")
		)
		(fp_line
			(start 0.12065 -0.305054)
			(end 0.12065 -0.2794)
			(stroke
				(width 0.1)
				(type default)
			)
			(layer "B.Fab")
		)
		(fp_line
			(start -0.120396 0.3048)
			(end -0.120396 0.2794)
			(stroke
				(width 0.1)
				(type default)
			)
			(layer "B.Fab")
		)
		(fp_line
			(start -0.120396 0.2794)
			(end 0.12065 0.2794)
			(stroke
				(width 0.1)
				(type default)
			)
			(layer "B.Fab")
		)
		(fp_line
			(start -0.12065 -0.2794)
			(end -0.12065 -0.3048)
			(stroke
				(width 0.1)
				(type default)
			)
			(layer "B.Fab")
		)
		(fp_line
			(start -0.12065 -0.3048)
			(end -0.67945 -0.3048)
			(stroke
				(width 0.1)
				(type default)
			)
			(layer "B.Fab")
		)
		(fp_line
			(start -0.67945 0.3048)
			(end -0.120396 0.3048)
			(stroke
				(width 0.1)
				(type default)
			)
			(layer "B.Fab")
		)
		(fp_line
			(start -0.67945 -0.3048)
			(end -0.67945 0.3048)
			(stroke
				(width 0.1)
				(type default)
			)
			(layer "B.Fab")
		)
		(pad "1" smd circle
			(at 0.40005 0)
			(size 0 0)
			(layers "B.Cu" "B.Mask" "B.Paste")
			(net "P3V3_AUX")
		)
		(pad "2" smd circle
			(at -0.40005 0)
			(size 0 0)
			(layers "B.Cu" "B.Mask" "B.Paste")
			(net "GND")
		)
	)
	(footprint ""
		(layer "B.Cu")
		(at 51.766978 -433.682902 90)
		(property "Reference" "R3498"
			(at 0 0 90)
			(layer "B.SilkS")
			(hide yes)
			(effects
				(font
					(size 1.27 1.27)
				)
				(justify mirror)
			)
		)
		(property "Value" ""
			(at 0 0 90)
			(layer "B.Fab")
			(effects
				(font
					(size 1.27 1.27)
				)
				(justify mirror)
			)
		)
		(duplicate_pad_numbers_are_jumpers no)
		(fp_line
			(start 0.7874 -0.4064)
			(end -0.7874 -0.4064)
			(stroke
				(width 0.1524)
				(type default)
			)
			(layer "B.SilkS")
		)
		(fp_line
			(start -0.7874 -0.4064)
			(end -0.7874 0.4064)
			(stroke
				(width 0.1524)
				(type default)
			)
			(layer "B.SilkS")
		)
		(fp_line
			(start 0.7874 0.4064)
			(end 0.7874 -0.4064)
			(stroke
				(width 0.1524)
				(type default)
			)
			(layer "B.SilkS")
		)
		(fp_line
			(start -0.7874 0.4064)
			(end 0.7874 0.4064)
			(stroke
				(width 0.1524)
				(type default)
			)
			(layer "B.SilkS")
		)
		(fp_line
			(start 0.67945 -0.305054)
			(end 0.12065 -0.305054)
			(stroke
				(width 0.1)
				(type default)
			)
			(layer "B.Fab")
		)
		(fp_line
			(start 0.12065 -0.305054)
			(end 0.12065 -0.2794)
			(stroke
				(width 0.1)
				(type default)
			)
			(layer "B.Fab")
		)
		(fp_line
			(start -0.12065 -0.3048)
			(end -0.67945 -0.3048)
			(stroke
				(width 0.1)
				(type default)
			)
			(layer "B.Fab")
		)
		(fp_line
			(start -0.67945 -0.3048)
			(end -0.67945 0.3048)
			(stroke
				(width 0.1)
				(type default)
			)
			(layer "B.Fab")
		)
		(fp_line
			(start 0.12065 -0.2794)
			(end -0.12065 -0.2794)
			(stroke
				(width 0.1)
				(type default)
			)
			(layer "B.Fab")
		)
		(fp_line
			(start -0.12065 -0.2794)
			(end -0.12065 -0.3048)
			(stroke
				(width 0.1)
				(type default)
			)
			(layer "B.Fab")
		)
		(fp_line
			(start 0.12065 0.2794)
			(end 0.12065 0.3048)
			(stroke
				(width 0.1)
				(type default)
			)
			(layer "B.Fab")
		)
		(fp_line
			(start -0.120396 0.2794)
			(end 0.12065 0.2794)
			(stroke
				(width 0.1)
				(type default)
			)
			(layer "B.Fab")
		)
		(fp_line
			(start 0.67945 0.3048)
			(end 0.67945 -0.305054)
			(stroke
				(width 0.1)
				(type default)
			)
			(layer "B.Fab")
		)
		(fp_line
			(start 0.12065 0.3048)
			(end 0.67945 0.3048)
			(stroke
				(width 0.1)
				(type default)
			)
			(layer "B.Fab")
		)
		(fp_line
			(start -0.120396 0.3048)
			(end -0.120396 0.2794)
			(stroke
				(width 0.1)
				(type default)
			)
			(layer "B.Fab")
		)
		(fp_line
			(start -0.67945 0.3048)
			(end -0.120396 0.3048)
			(stroke
				(width 0.1)
				(type default)
			)
			(layer "B.Fab")
		)
		(pad "1" smd circle
			(at 0.40005 0 270)
			(size 0 0)
			(layers "B.Cu" "B.Mask" "B.Paste")
			(net "P3V3_AUX")
		)
		(pad "2" smd circle
			(at -0.40005 0 270)
			(size 0 0)
			(layers "B.Cu" "B.Mask" "B.Paste")
			(net "GPU_FPGA_THERM_OVERT_N")
		)
	)
	(footprint ""
		(layer "B.Cu")
		(at 112.054386 -264.862564)
		(property "Reference" "C3905"
			(at 0 0 0)
			(layer "B.SilkS")
			(hide yes)
			(effects
				(font
					(size 1.27 1.27)
				)
				(justify mirror)
			)
		)
		(property "Value" ""
			(at 0 0 0)
			(layer "B.Fab")
			(effects
				(font
					(size 1.27 1.27)
				)
				(justify mirror)
			)
		)
		(duplicate_pad_numbers_are_jumpers no)
		(fp_line
			(start -0.7874 -0.4064)
			(end -0.7874 0.4064)
			(stroke
				(width 0.1524)
				(type default)
			)
			(layer "B.SilkS")
		)
		(fp_line
			(start -0.7874 0.4064)
			(end 0.7874 0.4064)
			(stroke
				(width 0.1524)
				(type default)
			)
			(layer "B.SilkS")
		)
		(fp_line
			(start 0.7874 -0.4064)
			(end -0.7874 -0.4064)
			(stroke
				(width 0.1524)
				(type default)
			)
			(layer "B.SilkS")
		)
		(fp_line
			(start 0.7874 0.4064)
			(end 0.7874 -0.4064)
			(stroke
				(width 0.1524)
				(type default)
			)
			(layer "B.SilkS")
		)
		(fp_line
			(start -0.67945 -0.3048)
			(end -0.67945 0.3048)
			(stroke
				(width 0.1)
				(type default)
			)
			(layer "B.Fab")
		)
		(fp_line
			(start -0.67945 0.3048)
			(end -0.120396 0.3048)
			(stroke
				(width 0.1)
				(type default)
			)
			(layer "B.Fab")
		)
		(fp_line
			(start -0.12065 -0.3048)
			(end -0.67945 -0.3048)
			(stroke
				(width 0.1)
				(type default)
			)
			(layer "B.Fab")
		)
		(fp_line
			(start -0.12065 -0.2794)
			(end -0.12065 -0.3048)
			(stroke
				(width 0.1)
				(type default)
			)
			(layer "B.Fab")
		)
		(fp_line
			(start -0.120396 0.2794)
			(end 0.12065 0.2794)
			(stroke
				(width 0.1)
				(type default)
			)
			(layer "B.Fab")
		)
		(fp_line
			(start -0.120396 0.3048)
			(end -0.120396 0.2794)
			(stroke
				(width 0.1)
				(type default)
			)
			(layer "B.Fab")
		)
		(fp_line
			(start 0.12065 -0.305054)
			(end 0.12065 -0.2794)
			(stroke
				(width 0.1)
				(type default)
			)
			(layer "B.Fab")
		)
		(fp_line
			(start 0.12065 -0.2794)
			(end -0.12065 -0.2794)
			(stroke
				(width 0.1)
				(type default)
			)
			(layer "B.Fab")
		)
		(fp_line
			(start 0.12065 0.2794)
			(end 0.12065 0.3048)
			(stroke
				(width 0.1)
				(type default)
			)
			(layer "B.Fab")
		)
		(fp_line
			(start 0.12065 0.3048)
			(end 0.67945 0.3048)
			(stroke
				(width 0.1)
				(type default)
			)
			(layer "B.Fab")
		)
		(fp_line
			(start 0.67945 -0.305054)
			(end 0.12065 -0.305054)
			(stroke
				(width 0.1)
				(type default)
			)
			(layer "B.Fab")
		)
		(fp_line
			(start 0.67945 0.3048)
			(end 0.67945 -0.305054)
			(stroke
				(width 0.1)
				(type default)
			)
			(layer "B.Fab")
		)
		(pad "1" smd circle
			(at 0.40005 0 180)
			(size 0 0)
			(layers "B.Cu" "B.Mask" "B.Paste")
			(net "PVDD11_S3_P1")
		)
		(pad "2" smd circle
			(at -0.40005 0 180)
			(size 0 0)
			(layers "B.Cu" "B.Mask" "B.Paste")
			(net "GND")
		)
	)
	(footprint ""
		(layer "B.Cu")
		(at 354.046028 -396.393162 -90)
		(property "Reference" "C614"
			(at 0 0 90)
			(layer "B.SilkS")
			(hide yes)
			(effects
				(font
					(size 1.27 1.27)
				)
				(justify mirror)
			)
		)
		(property "Value" ""
			(at 0 0 90)
			(layer "B.Fab")
			(effects
				(font
					(size 1.27 1.27)
				)
				(justify mirror)
			)
		)
		(duplicate_pad_numbers_are_jumpers no)
		(fp_line
			(start -0.299974 0.150114)
			(end 0.299974 0.150114)
			(stroke
				(width 0.1)
				(type default)
			)
			(layer "B.Fab")
		)
		(fp_line
			(start 0.299974 0.150114)
			(end 0.299974 -0.150114)
			(stroke
				(width 0.1)
				(type default)
			)
			(layer "B.Fab")
		)
		(fp_line
			(start -0.299974 -0.150114)
			(end -0.299974 0.150114)
			(stroke
				(width 0.1)
				(type default)
			)
			(layer "B.Fab")
		)
		(fp_line
			(start 0.299974 -0.150114)
			(end -0.299974 -0.150114)
			(stroke
				(width 0.1)
				(type default)
			)
			(layer "B.Fab")
		)
		(pad "1" smd rect
			(at 0.2667 0 90)
			(size 0.3048 0.381)
			(layers "B.Cu" "B.Mask" "B.Paste")
			(net "P0V9_CPU0_RT1_2A")
		)
		(pad "2" smd rect
			(at -0.2667 0 90)
			(size 0.3048 0.381)
			(layers "B.Cu" "B.Mask" "B.Paste")
			(net "GND")
		)
	)
	(footprint ""
		(layer "B.Cu")
		(at 295.402 -426.339 180)
		(property "Reference" "R835"
			(at 0 0 0)
			(layer "B.SilkS")
			(hide yes)
			(effects
				(font
					(size 1.27 1.27)
				)
				(justify mirror)
			)
		)
		(property "Value" ""
			(at 0 0 0)
			(layer "B.Fab")
			(effects
				(font
					(size 1.27 1.27)
				)
				(justify mirror)
			)
		)
		(duplicate_pad_numbers_are_jumpers no)
		(fp_line
			(start 0.32512 0.175006)
			(end 0.32512 -0.175006)
			(stroke
				(width 0.1)
				(type default)
			)
			(layer "B.Fab")
		)
		(fp_line
			(start 0.32512 -0.175006)
			(end -0.32512 -0.175006)
			(stroke
				(width 0.1)
				(type default)
			)
			(layer "B.Fab")
		)
		(fp_line
			(start -0.32512 0.175006)
			(end 0.32512 0.175006)
			(stroke
				(width 0.1)
				(type default)
			)
			(layer "B.Fab")
		)
		(fp_line
			(start -0.32512 -0.175006)
			(end -0.32512 0.175006)
			(stroke
				(width 0.1)
				(type default)
			)
			(layer "B.Fab")
		)
		(pad "1" smd rect
			(at 0.2667 0)
			(size 0.3048 0.381)
			(layers "B.Cu" "B.Mask" "B.Paste")
			(net "P1V8_CPU0_RT_1D")
		)
		(pad "2" smd rect
			(at -0.2667 0 180)
			(size 0.3048 0.381)
			(layers "B.Cu" "B.Mask" "B.Paste")
			(net "SMB_RT_CPU0_P0_ROM_R_SCL")
		)
	)
	(footprint ""
		(layer "B.Cu")
		(at 413.136842 -416.899344 90)
		(property "Reference" "C6623"
			(at 0 0 90)
			(layer "B.SilkS")
			(hide yes)
			(effects
				(font
					(size 1.27 1.27)
				)
				(justify mirror)
			)
		)
		(property "Value" ""
			(at 0 0 90)
			(layer "B.Fab")
			(effects
				(font
					(size 1.27 1.27)
				)
				(justify mirror)
			)
		)
		(duplicate_pad_numbers_are_jumpers no)
		(fp_line
			(start 0.299974 -0.150114)
			(end -0.299974 -0.150114)
			(stroke
				(width 0.1)
				(type default)
			)
			(layer "B.Fab")
		)
		(fp_line
			(start -0.299974 -0.150114)
			(end -0.299974 0.150114)
			(stroke
				(width 0.1)
				(type default)
			)
			(layer "B.Fab")
		)
		(fp_line
			(start 0.299974 0.150114)
			(end 0.299974 -0.150114)
			(stroke
				(width 0.1)
				(type default)
			)
			(layer "B.Fab")
		)
		(fp_line
			(start -0.299974 0.150114)
			(end 0.299974 0.150114)
			(stroke
				(width 0.1)
				(type default)
			)
			(layer "B.Fab")
		)
		(pad "1" smd rect
			(at 0.2667 0 270)
			(size 0.3048 0.381)
			(layers "B.Cu" "B.Mask" "B.Paste")
			(net "P5E_CPU0_P3_TX_BUF_C_DP<13>")
		)
		(pad "2" smd rect
			(at -0.2667 0 270)
			(size 0.3048 0.381)
			(layers "B.Cu" "B.Mask" "B.Paste")
			(net "P5E_CPU0_P3_TX_BUF_DP<13>")
		)
	)
	(footprint ""
		(layer "B.Cu")
		(at 86.652354 -191.358012 90)
		(property "Reference" "PC283_1"
			(at 0 0 90)
			(layer "B.SilkS")
			(hide yes)
			(effects
				(font
					(size 1.27 1.27)
				)
				(justify mirror)
			)
		)
		(property "Value" ""
			(at 0 0 90)
			(layer "B.Fab")
			(effects
				(font
					(size 1.27 1.27)
				)
				(justify mirror)
			)
		)
		(duplicate_pad_numbers_are_jumpers no)
		(fp_line
			(start 1.524 -0.762)
			(end -1.524 -0.762)
			(stroke
				(width 0.1524)
				(type default)
			)
			(layer "B.SilkS")
		)
		(fp_line
			(start -1.524 -0.762)
			(end -1.524 0.762)
			(stroke
				(width 0.1524)
				(type default)
			)
			(layer "B.SilkS")
		)
		(fp_line
			(start 1.524 0.762)
			(end 1.524 -0.762)
			(stroke
				(width 0.1524)
				(type default)
			)
			(layer "B.SilkS")
		)
		(fp_line
			(start -1.524 0.762)
			(end 1.524 0.762)
			(stroke
				(width 0.1524)
				(type default)
			)
			(layer "B.SilkS")
		)
		(fp_line
			(start 1.1049 -0.724916)
			(end 1.1049 0.724916)
			(stroke
				(width 0.1)
				(type default)
			)
			(layer "B.Fab")
		)
		(fp_line
			(start -1.1049 -0.724916)
			(end 1.1049 -0.724916)
			(stroke
				(width 0.1)
				(type default)
			)
			(layer "B.Fab")
		)
		(fp_line
			(start 1.1049 0.724916)
			(end -1.1049 0.724916)
			(stroke
				(width 0.1)
				(type default)
			)
			(layer "B.Fab")
		)
		(fp_line
			(start -1.1049 0.724916)
			(end -1.1049 -0.724916)
			(stroke
				(width 0.1)
				(type default)
			)
			(layer "B.Fab")
		)
		(pad "1" smd rect
			(at 0.889 0 90)
			(size 1.016 1.27)
			(layers "B.Cu" "B.Mask" "B.Paste")
			(net "PVDDCR_CPU0_P1")
		)
		(pad "2" smd rect
			(at -0.889 0 90)
			(size 1.016 1.27)
			(layers "B.Cu" "B.Mask" "B.Paste")
			(net "GND")
		)
	)
	(footprint ""
		(layer "B.Cu")
		(at 6.649974 -373.339614 90)
		(property "Reference" "PC6628"
			(at -3.388614 -2.993644 270)
			(unlocked yes)
			(layer "B.SilkS")
			(effects
				(font
					(size 0.7874 0.5842)
					(thickness 0.1524)
				)
				(justify left mirror)
			)
		)
		(property "Value" ""
			(at 0 0 90)
			(layer "B.Fab")
			(effects
				(font
					(size 1.27 1.27)
				)
				(justify mirror)
			)
		)
		(duplicate_pad_numbers_are_jumpers no)
		(fp_line
			(start 4.84378 -2.150618)
			(end 4.53898 -2.150618)
			(stroke
				(width 0.1524)
				(type default)
			)
			(layer "B.SilkS")
		)
		(fp_line
			(start 4.84378 -2.150618)
			(end 4.842256 2.163064)
			(stroke
				(width 0.1524)
				(type default)
			)
			(layer "B.SilkS")
		)
		(fp_line
			(start 4.69138 -2.150618)
			(end 4.692396 2.161032)
			(stroke
				(width 0.1524)
				(type default)
			)
			(layer "B.SilkS")
		)
		(fp_line
			(start 4.53898 -2.150618)
			(end 4.539742 2.152142)
			(stroke
				(width 0.1524)
				(type default)
			)
			(layer "B.SilkS")
		)
		(fp_line
			(start 4.53898 -2.15011)
			(end -3.820414 -2.15011)
			(stroke
				(width 0.1524)
				(type default)
			)
			(layer "B.SilkS")
		)
		(fp_line
			(start -4.53898 -1.950974)
			(end -4.53898 2.15011)
			(stroke
				(width 0.1524)
				(type default)
			)
			(layer "B.SilkS")
		)
		(fp_line
			(start 4.53898 2.15011)
			(end 4.53898 -2.15011)
			(stroke
				(width 0.1524)
				(type default)
			)
			(layer "B.SilkS")
		)
		(fp_line
			(start -4.53898 2.15011)
			(end 4.53898 2.15011)
			(stroke
				(width 0.1524)
				(type default)
			)
			(layer "B.SilkS")
		)
		(fp_line
			(start 4.83108 2.150364)
			(end 4.447794 2.149348)
			(stroke
				(width 0.1524)
				(type default)
			)
			(layer "B.SilkS")
		)
		(fp_line
			(start 3.64998 -2.15011)
			(end -3.64998 -2.15011)
			(stroke
				(width 0.1)
				(type default)
			)
			(layer "B.Fab")
		)
		(fp_line
			(start -3.64998 -2.15011)
			(end -3.64998 2.15011)
			(stroke
				(width 0.1)
				(type default)
			)
			(layer "B.Fab")
		)
		(fp_line
			(start 3.64998 2.15011)
			(end 3.64998 -2.15011)
			(stroke
				(width 0.1)
				(type default)
			)
			(layer "B.Fab")
		)
		(fp_line
			(start -3.64998 2.15011)
			(end 3.64998 2.15011)
			(stroke
				(width 0.1)
				(type default)
			)
			(layer "B.Fab")
		)
		(fp_text user "-"
			(at -4.404614 -1.919224 90)
			(unlocked yes)
			(layer "B.SilkS")
			(effects
				(font
					(size 1.905 1.4224)
					(thickness 0.1524)
				)
				(justify left mirror)
			)
		)
		(fp_text user "+"
			(at 6.214872 -0.337058 90)
			(unlocked yes)
			(layer "B.SilkS")
			(effects
				(font
					(size 1.905 1.4224)
					(thickness 0.1524)
				)
				(justify left mirror)
			)
		)
		(fp_text user "+"
			(at 6.214872 -0.337058 90)
			(unlocked yes)
			(layer "B.Fab")
			(effects
				(font
					(size 1.905 1.4224)
					(thickness 0.1524)
				)
				(justify left mirror)
			)
		)
		(fp_text user "-"
			(at -4.313174 -0.094488 90)
			(unlocked yes)
			(layer "B.Fab")
			(effects
				(font
					(size 1.905 1.4224)
					(thickness 0.1524)
				)
				(justify left mirror)
			)
		)
		(pad "1" smd rect
			(at 3.199892 0 270)
			(size 2.413 2.8194)
			(layers "B.Cu" "B.Mask" "B.Paste")
			(net "P0V9_CPU1_RT_2D")
		)
		(pad "2" smd rect
			(at -3.199892 0 270)
			(size 2.413 2.8194)
			(layers "B.Cu" "B.Mask" "B.Paste")
			(net "GND")
		)
	)
	(footprint ""
		(layer "B.Cu")
		(at 371.551454 -252.54331)
		(property "Reference" "C2151"
			(at 0 0 0)
			(layer "B.SilkS")
			(hide yes)
			(effects
				(font
					(size 1.27 1.27)
				)
				(justify mirror)
			)
		)
		(property "Value" ""
			(at 0 0 0)
			(layer "B.Fab")
			(effects
				(font
					(size 1.27 1.27)
				)
				(justify mirror)
			)
		)
		(duplicate_pad_numbers_are_jumpers no)
		(fp_line
			(start -0.7874 -0.4064)
			(end -0.7874 0.4064)
			(stroke
				(width 0.1524)
				(type default)
			)
			(layer "B.SilkS")
		)
		(fp_line
			(start -0.7874 0.4064)
			(end 0.7874 0.4064)
			(stroke
				(width 0.1524)
				(type default)
			)
			(layer "B.SilkS")
		)
		(fp_line
			(start 0.7874 -0.4064)
			(end -0.7874 -0.4064)
			(stroke
				(width 0.1524)
				(type default)
			)
			(layer "B.SilkS")
		)
		(fp_line
			(start 0.7874 0.4064)
			(end 0.7874 -0.4064)
			(stroke
				(width 0.1524)
				(type default)
			)
			(layer "B.SilkS")
		)
		(fp_line
			(start -0.67945 -0.3048)
			(end -0.67945 0.3048)
			(stroke
				(width 0.1)
				(type default)
			)
			(layer "B.Fab")
		)
		(fp_line
			(start -0.67945 0.3048)
			(end -0.120396 0.3048)
			(stroke
				(width 0.1)
				(type default)
			)
			(layer "B.Fab")
		)
		(fp_line
			(start -0.12065 -0.3048)
			(end -0.67945 -0.3048)
			(stroke
				(width 0.1)
				(type default)
			)
			(layer "B.Fab")
		)
		(fp_line
			(start -0.12065 -0.2794)
			(end -0.12065 -0.3048)
			(stroke
				(width 0.1)
				(type default)
			)
			(layer "B.Fab")
		)
		(fp_line
			(start -0.120396 0.2794)
			(end 0.12065 0.2794)
			(stroke
				(width 0.1)
				(type default)
			)
			(layer "B.Fab")
		)
		(fp_line
			(start -0.120396 0.3048)
			(end -0.120396 0.2794)
			(stroke
				(width 0.1)
				(type default)
			)
			(layer "B.Fab")
		)
		(fp_line
			(start 0.12065 -0.305054)
			(end 0.12065 -0.2794)
			(stroke
				(width 0.1)
				(type default)
			)
			(layer "B.Fab")
		)
		(fp_line
			(start 0.12065 -0.2794)
			(end -0.12065 -0.2794)
			(stroke
				(width 0.1)
				(type default)
			)
			(layer "B.Fab")
		)
		(fp_line
			(start 0.12065 0.2794)
			(end 0.12065 0.3048)
			(stroke
				(width 0.1)
				(type default)
			)
			(layer "B.Fab")
		)
		(fp_line
			(start 0.12065 0.3048)
			(end 0.67945 0.3048)
			(stroke
				(width 0.1)
				(type default)
			)
			(layer "B.Fab")
		)
		(fp_line
			(start 0.67945 -0.305054)
			(end 0.12065 -0.305054)
			(stroke
				(width 0.1)
				(type default)
			)
			(layer "B.Fab")
		)
		(fp_line
			(start 0.67945 0.3048)
			(end 0.67945 -0.305054)
			(stroke
				(width 0.1)
				(type default)
			)
			(layer "B.Fab")
		)
		(pad "1" smd circle
			(at 0.40005 0 180)
			(size 0 0)
			(layers "B.Cu" "B.Mask" "B.Paste")
			(net "PVDDCR_SOC_P0")
		)
		(pad "2" smd circle
			(at -0.40005 0 180)
			(size 0 0)
			(layers "B.Cu" "B.Mask" "B.Paste")
			(net "GND")
		)
	)
	(footprint ""
		(layer "B.Cu")
		(at 302.487076 -399.722848 -90)
		(property "Reference" "C554"
			(at 0 0 90)
			(layer "B.SilkS")
			(hide yes)
			(effects
				(font
					(size 1.27 1.27)
				)
				(justify mirror)
			)
		)
		(property "Value" ""
			(at 0 0 90)
			(layer "B.Fab")
			(effects
				(font
					(size 1.27 1.27)
				)
				(justify mirror)
			)
		)
		(duplicate_pad_numbers_are_jumpers no)
		(fp_line
			(start -0.7874 0.4064)
			(end 0.7874 0.4064)
			(stroke
				(width 0.1524)
				(type default)
			)
			(layer "B.SilkS")
		)
		(fp_line
			(start 0.7874 0.4064)
			(end 0.7874 -0.4064)
			(stroke
				(width 0.1524)
				(type default)
			)
			(layer "B.SilkS")
		)
		(fp_line
			(start -0.7874 -0.4064)
			(end -0.7874 0.4064)
			(stroke
				(width 0.1524)
				(type default)
			)
			(layer "B.SilkS")
		)
		(fp_line
			(start 0.7874 -0.4064)
			(end -0.7874 -0.4064)
			(stroke
				(width 0.1524)
				(type default)
			)
			(layer "B.SilkS")
		)
		(fp_line
			(start -0.67945 0.3048)
			(end -0.120396 0.3048)
			(stroke
				(width 0.1)
				(type default)
			)
			(layer "B.Fab")
		)
		(fp_line
			(start -0.120396 0.3048)
			(end -0.120396 0.2794)
			(stroke
				(width 0.1)
				(type default)
			)
			(layer "B.Fab")
		)
		(fp_line
			(start 0.12065 0.3048)
			(end 0.67945 0.3048)
			(stroke
				(width 0.1)
				(type default)
			)
			(layer "B.Fab")
		)
		(fp_line
			(start 0.67945 0.3048)
			(end 0.67945 -0.305054)
			(stroke
				(width 0.1)
				(type default)
			)
			(layer "B.Fab")
		)
		(fp_line
			(start -0.120396 0.2794)
			(end 0.12065 0.2794)
			(stroke
				(width 0.1)
				(type default)
			)
			(layer "B.Fab")
		)
		(fp_line
			(start 0.12065 0.2794)
			(end 0.12065 0.3048)
			(stroke
				(width 0.1)
				(type default)
			)
			(layer "B.Fab")
		)
		(fp_line
			(start -0.12065 -0.2794)
			(end -0.12065 -0.3048)
			(stroke
				(width 0.1)
				(type default)
			)
			(layer "B.Fab")
		)
		(fp_line
			(start 0.12065 -0.2794)
			(end -0.12065 -0.2794)
			(stroke
				(width 0.1)
				(type default)
			)
			(layer "B.Fab")
		)
		(fp_line
			(start -0.67945 -0.3048)
			(end -0.67945 0.3048)
			(stroke
				(width 0.1)
				(type default)
			)
			(layer "B.Fab")
		)
		(fp_line
			(start -0.12065 -0.3048)
			(end -0.67945 -0.3048)
			(stroke
				(width 0.1)
				(type default)
			)
			(layer "B.Fab")
		)
		(fp_line
			(start 0.12065 -0.305054)
			(end 0.12065 -0.2794)
			(stroke
				(width 0.1)
				(type default)
			)
			(layer "B.Fab")
		)
		(fp_line
			(start 0.67945 -0.305054)
			(end 0.12065 -0.305054)
			(stroke
				(width 0.1)
				(type default)
			)
			(layer "B.Fab")
		)
		(pad "1" smd circle
			(at 0.40005 0 90)
			(size 0 0)
			(layers "B.Cu" "B.Mask" "B.Paste")
			(net "P0V9_CPU0_RT0_2A")
		)
		(pad "2" smd circle
			(at -0.40005 0 90)
			(size 0 0)
			(layers "B.Cu" "B.Mask" "B.Paste")
			(net "GND")
		)
	)
	(footprint ""
		(layer "B.Cu")
		(at 109.949996 -26.952448 90)
		(property "Reference" "C6103"
			(at 0 0 90)
			(layer "B.SilkS")
			(hide yes)
			(effects
				(font
					(size 1.27 1.27)
				)
				(justify mirror)
			)
		)
		(property "Value" ""
			(at 0 0 90)
			(layer "B.Fab")
			(effects
				(font
					(size 1.27 1.27)
				)
				(justify mirror)
			)
		)
		(duplicate_pad_numbers_are_jumpers no)
		(fp_line
			(start 0.7874 -0.4064)
			(end -0.7874 -0.4064)
			(stroke
				(width 0.1524)
				(type default)
			)
			(layer "B.SilkS")
		)
		(fp_line
			(start -0.7874 -0.4064)
			(end -0.7874 0.4064)
			(stroke
				(width 0.1524)
				(type default)
			)
			(layer "B.SilkS")
		)
		(fp_line
			(start 0.7874 0.4064)
			(end 0.7874 -0.4064)
			(stroke
				(width 0.1524)
				(type default)
			)
			(layer "B.SilkS")
		)
		(fp_line
			(start -0.7874 0.4064)
			(end 0.7874 0.4064)
			(stroke
				(width 0.1524)
				(type default)
			)
			(layer "B.SilkS")
		)
		(fp_line
			(start 0.67945 -0.305054)
			(end 0.12065 -0.305054)
			(stroke
				(width 0.1)
				(type default)
			)
			(layer "B.Fab")
		)
		(fp_line
			(start 0.12065 -0.305054)
			(end 0.12065 -0.2794)
			(stroke
				(width 0.1)
				(type default)
			)
			(layer "B.Fab")
		)
		(fp_line
			(start -0.12065 -0.3048)
			(end -0.67945 -0.3048)
			(stroke
				(width 0.1)
				(type default)
			)
			(layer "B.Fab")
		)
		(fp_line
			(start -0.67945 -0.3048)
			(end -0.67945 0.3048)
			(stroke
				(width 0.1)
				(type default)
			)
			(layer "B.Fab")
		)
		(fp_line
			(start 0.12065 -0.2794)
			(end -0.12065 -0.2794)
			(stroke
				(width 0.1)
				(type default)
			)
			(layer "B.Fab")
		)
		(fp_line
			(start -0.12065 -0.2794)
			(end -0.12065 -0.3048)
			(stroke
				(width 0.1)
				(type default)
			)
			(layer "B.Fab")
		)
		(fp_line
			(start 0.12065 0.2794)
			(end 0.12065 0.3048)
			(stroke
				(width 0.1)
				(type default)
			)
			(layer "B.Fab")
		)
		(fp_line
			(start -0.120396 0.2794)
			(end 0.12065 0.2794)
			(stroke
				(width 0.1)
				(type default)
			)
			(layer "B.Fab")
		)
		(fp_line
			(start 0.67945 0.3048)
			(end 0.67945 -0.305054)
			(stroke
				(width 0.1)
				(type default)
			)
			(layer "B.Fab")
		)
		(fp_line
			(start 0.12065 0.3048)
			(end 0.67945 0.3048)
			(stroke
				(width 0.1)
				(type default)
			)
			(layer "B.Fab")
		)
		(fp_line
			(start -0.120396 0.3048)
			(end -0.120396 0.2794)
			(stroke
				(width 0.1)
				(type default)
			)
			(layer "B.Fab")
		)
		(fp_line
			(start -0.67945 0.3048)
			(end -0.120396 0.3048)
			(stroke
				(width 0.1)
				(type default)
			)
			(layer "B.Fab")
		)
		(pad "1" smd circle
			(at 0.40005 0 270)
			(size 0 0)
			(layers "B.Cu" "B.Mask" "B.Paste")
			(net "P3V3_AUX_CPU0_USB2_AVDD33")
		)
		(pad "2" smd circle
			(at -0.40005 0 270)
			(size 0 0)
			(layers "B.Cu" "B.Mask" "B.Paste")
			(net "GND")
		)
	)
	(footprint ""
		(layer "B.Cu")
		(at 119.2784 -386.766562 90)
		(property "Reference" "C456"
			(at 0 0 90)
			(layer "B.SilkS")
			(hide yes)
			(effects
				(font
					(size 1.27 1.27)
				)
				(justify mirror)
			)
		)
		(property "Value" ""
			(at 0 0 90)
			(layer "B.Fab")
			(effects
				(font
					(size 1.27 1.27)
				)
				(justify mirror)
			)
		)
		(duplicate_pad_numbers_are_jumpers no)
		(fp_line
			(start 0.299974 -0.150114)
			(end -0.299974 -0.150114)
			(stroke
				(width 0.1)
				(type default)
			)
			(layer "B.Fab")
		)
		(fp_line
			(start -0.299974 -0.150114)
			(end -0.299974 0.150114)
			(stroke
				(width 0.1)
				(type default)
			)
			(layer "B.Fab")
		)
		(fp_line
			(start 0.299974 0.150114)
			(end 0.299974 -0.150114)
			(stroke
				(width 0.1)
				(type default)
			)
			(layer "B.Fab")
		)
		(fp_line
			(start -0.299974 0.150114)
			(end 0.299974 0.150114)
			(stroke
				(width 0.1)
				(type default)
			)
			(layer "B.Fab")
		)
		(pad "1" smd rect
			(at 0.2667 0 270)
			(size 0.3048 0.381)
			(layers "B.Cu" "B.Mask" "B.Paste")
			(net "P0V9_CPU1_RT3_2A_2D")
		)
		(pad "2" smd rect
			(at -0.2667 0 270)
			(size 0.3048 0.381)
			(layers "B.Cu" "B.Mask" "B.Paste")
			(net "GND")
		)
	)
	(footprint ""
		(layer "B.Cu")
		(at 197.269608 -121.753376 180)
		(property "Reference" "R3476"
			(at 0 0 0)
			(layer "B.SilkS")
			(hide yes)
			(effects
				(font
					(size 1.27 1.27)
				)
				(justify mirror)
			)
		)
		(property "Value" ""
			(at 0 0 0)
			(layer "B.Fab")
			(effects
				(font
					(size 1.27 1.27)
				)
				(justify mirror)
			)
		)
		(duplicate_pad_numbers_are_jumpers no)
		(fp_line
			(start 0.7874 0.4064)
			(end 0.7874 -0.4064)
			(stroke
				(width 0.1524)
				(type default)
			)
			(layer "B.SilkS")
		)
		(fp_line
			(start 0.7874 -0.4064)
			(end -0.7874 -0.4064)
			(stroke
				(width 0.1524)
				(type default)
			)
			(layer "B.SilkS")
		)
		(fp_line
			(start -0.7874 0.4064)
			(end 0.7874 0.4064)
			(stroke
				(width 0.1524)
				(type default)
			)
			(layer "B.SilkS")
		)
		(fp_line
			(start -0.7874 -0.4064)
			(end -0.7874 0.4064)
			(stroke
				(width 0.1524)
				(type default)
			)
			(layer "B.SilkS")
		)
		(fp_line
			(start 0.67945 0.3048)
			(end 0.67945 -0.305054)
			(stroke
				(width 0.1)
				(type default)
			)
			(layer "B.Fab")
		)
		(fp_line
			(start 0.67945 -0.305054)
			(end 0.12065 -0.305054)
			(stroke
				(width 0.1)
				(type default)
			)
			(layer "B.Fab")
		)
		(fp_line
			(start 0.12065 0.3048)
			(end 0.67945 0.3048)
			(stroke
				(width 0.1)
				(type default)
			)
			(layer "B.Fab")
		)
		(fp_line
			(start 0.12065 0.2794)
			(end 0.12065 0.3048)
			(stroke
				(width 0.1)
				(type default)
			)
			(layer "B.Fab")
		)
		(fp_line
			(start 0.12065 -0.2794)
			(end -0.12065 -0.2794)
			(stroke
				(width 0.1)
				(type default)
			)
			(layer "B.Fab")
		)
		(fp_line
			(start 0.12065 -0.305054)
			(end 0.12065 -0.2794)
			(stroke
				(width 0.1)
				(type default)
			)
			(layer "B.Fab")
		)
		(fp_line
			(start -0.120396 0.3048)
			(end -0.120396 0.2794)
			(stroke
				(width 0.1)
				(type default)
			)
			(layer "B.Fab")
		)
		(fp_line
			(start -0.120396 0.2794)
			(end 0.12065 0.2794)
			(stroke
				(width 0.1)
				(type default)
			)
			(layer "B.Fab")
		)
		(fp_line
			(start -0.12065 -0.2794)
			(end -0.12065 -0.3048)
			(stroke
				(width 0.1)
				(type default)
			)
			(layer "B.Fab")
		)
		(fp_line
			(start -0.12065 -0.3048)
			(end -0.67945 -0.3048)
			(stroke
				(width 0.1)
				(type default)
			)
			(layer "B.Fab")
		)
		(fp_line
			(start -0.67945 0.3048)
			(end -0.120396 0.3048)
			(stroke
				(width 0.1)
				(type default)
			)
			(layer "B.Fab")
		)
		(fp_line
			(start -0.67945 -0.3048)
			(end -0.67945 0.3048)
			(stroke
				(width 0.1)
				(type default)
			)
			(layer "B.Fab")
		)
		(pad "1" smd circle
			(at 0.40005 0)
			(size 0 0)
			(layers "B.Cu" "B.Mask" "B.Paste")
			(net "GPU_FPGA_THERM_OVERT_ISO_R_N")
		)
		(pad "2" smd circle
			(at -0.40005 0)
			(size 0 0)
			(layers "B.Cu" "B.Mask" "B.Paste")
			(net "GPU_FPGA_THERM_OVERT_ISO_N")
		)
	)
	(footprint ""
		(layer "B.Cu")
		(at 107.101386 -248.479564 180)
		(property "Reference" "C2314"
			(at 0 0 0)
			(layer "B.SilkS")
			(hide yes)
			(effects
				(font
					(size 1.27 1.27)
				)
				(justify mirror)
			)
		)
		(property "Value" ""
			(at 0 0 0)
			(layer "B.Fab")
			(effects
				(font
					(size 1.27 1.27)
				)
				(justify mirror)
			)
		)
		(duplicate_pad_numbers_are_jumpers no)
		(fp_line
			(start 0.7874 0.4064)
			(end 0.7874 -0.4064)
			(stroke
				(width 0.1524)
				(type default)
			)
			(layer "B.SilkS")
		)
		(fp_line
			(start 0.7874 -0.4064)
			(end -0.7874 -0.4064)
			(stroke
				(width 0.1524)
				(type default)
			)
			(layer "B.SilkS")
		)
		(fp_line
			(start -0.7874 0.4064)
			(end 0.7874 0.4064)
			(stroke
				(width 0.1524)
				(type default)
			)
			(layer "B.SilkS")
		)
		(fp_line
			(start -0.7874 -0.4064)
			(end -0.7874 0.4064)
			(stroke
				(width 0.1524)
				(type default)
			)
			(layer "B.SilkS")
		)
		(fp_line
			(start 0.67945 0.3048)
			(end 0.67945 -0.305054)
			(stroke
				(width 0.1)
				(type default)
			)
			(layer "B.Fab")
		)
		(fp_line
			(start 0.67945 -0.305054)
			(end 0.12065 -0.305054)
			(stroke
				(width 0.1)
				(type default)
			)
			(layer "B.Fab")
		)
		(fp_line
			(start 0.12065 0.3048)
			(end 0.67945 0.3048)
			(stroke
				(width 0.1)
				(type default)
			)
			(layer "B.Fab")
		)
		(fp_line
			(start 0.12065 0.2794)
			(end 0.12065 0.3048)
			(stroke
				(width 0.1)
				(type default)
			)
			(layer "B.Fab")
		)
		(fp_line
			(start 0.12065 -0.2794)
			(end -0.12065 -0.2794)
			(stroke
				(width 0.1)
				(type default)
			)
			(layer "B.Fab")
		)
		(fp_line
			(start 0.12065 -0.305054)
			(end 0.12065 -0.2794)
			(stroke
				(width 0.1)
				(type default)
			)
			(layer "B.Fab")
		)
		(fp_line
			(start -0.120396 0.3048)
			(end -0.120396 0.2794)
			(stroke
				(width 0.1)
				(type default)
			)
			(layer "B.Fab")
		)
		(fp_line
			(start -0.120396 0.2794)
			(end 0.12065 0.2794)
			(stroke
				(width 0.1)
				(type default)
			)
			(layer "B.Fab")
		)
		(fp_line
			(start -0.12065 -0.2794)
			(end -0.12065 -0.3048)
			(stroke
				(width 0.1)
				(type default)
			)
			(layer "B.Fab")
		)
		(fp_line
			(start -0.12065 -0.3048)
			(end -0.67945 -0.3048)
			(stroke
				(width 0.1)
				(type default)
			)
			(layer "B.Fab")
		)
		(fp_line
			(start -0.67945 0.3048)
			(end -0.120396 0.3048)
			(stroke
				(width 0.1)
				(type default)
			)
			(layer "B.Fab")
		)
		(fp_line
			(start -0.67945 -0.3048)
			(end -0.67945 0.3048)
			(stroke
				(width 0.1)
				(type default)
			)
			(layer "B.Fab")
		)
		(pad "1" smd circle
			(at 0.40005 0)
			(size 0 0)
			(layers "B.Cu" "B.Mask" "B.Paste")
			(net "PVDDCR_CPU0_P1")
		)
		(pad "2" smd circle
			(at -0.40005 0)
			(size 0 0)
			(layers "B.Cu" "B.Mask" "B.Paste")
			(net "GND")
		)
	)
	(footprint ""
		(layer "B.Cu")
		(at 228.505258 -323.263768 180)
		(property "Reference" "C1092"
			(at 0 0 0)
			(layer "B.SilkS")
			(hide yes)
			(effects
				(font
					(size 1.27 1.27)
				)
				(justify mirror)
			)
		)
		(property "Value" ""
			(at 0 0 0)
			(layer "B.Fab")
			(effects
				(font
					(size 1.27 1.27)
				)
				(justify mirror)
			)
		)
		(duplicate_pad_numbers_are_jumpers no)
		(fp_line
			(start 0.7874 0.4064)
			(end 0.7874 -0.4064)
			(stroke
				(width 0.1524)
				(type default)
			)
			(layer "B.SilkS")
		)
		(fp_line
			(start 0.7874 -0.4064)
			(end -0.7874 -0.4064)
			(stroke
				(width 0.1524)
				(type default)
			)
			(layer "B.SilkS")
		)
		(fp_line
			(start -0.7874 0.4064)
			(end 0.7874 0.4064)
			(stroke
				(width 0.1524)
				(type default)
			)
			(layer "B.SilkS")
		)
		(fp_line
			(start -0.7874 -0.4064)
			(end -0.7874 0.4064)
			(stroke
				(width 0.1524)
				(type default)
			)
			(layer "B.SilkS")
		)
		(fp_line
			(start 0.67945 0.3048)
			(end 0.67945 -0.305054)
			(stroke
				(width 0.1)
				(type default)
			)
			(layer "B.Fab")
		)
		(fp_line
			(start 0.67945 -0.305054)
			(end 0.12065 -0.305054)
			(stroke
				(width 0.1)
				(type default)
			)
			(layer "B.Fab")
		)
		(fp_line
			(start 0.12065 0.3048)
			(end 0.67945 0.3048)
			(stroke
				(width 0.1)
				(type default)
			)
			(layer "B.Fab")
		)
		(fp_line
			(start 0.12065 0.2794)
			(end 0.12065 0.3048)
			(stroke
				(width 0.1)
				(type default)
			)
			(layer "B.Fab")
		)
		(fp_line
			(start 0.12065 -0.2794)
			(end -0.12065 -0.2794)
			(stroke
				(width 0.1)
				(type default)
			)
			(layer "B.Fab")
		)
		(fp_line
			(start 0.12065 -0.305054)
			(end 0.12065 -0.2794)
			(stroke
				(width 0.1)
				(type default)
			)
			(layer "B.Fab")
		)
		(fp_line
			(start -0.120396 0.3048)
			(end -0.120396 0.2794)
			(stroke
				(width 0.1)
				(type default)
			)
			(layer "B.Fab")
		)
		(fp_line
			(start -0.120396 0.2794)
			(end 0.12065 0.2794)
			(stroke
				(width 0.1)
				(type default)
			)
			(layer "B.Fab")
		)
		(fp_line
			(start -0.12065 -0.2794)
			(end -0.12065 -0.3048)
			(stroke
				(width 0.1)
				(type default)
			)
			(layer "B.Fab")
		)
		(fp_line
			(start -0.12065 -0.3048)
			(end -0.67945 -0.3048)
			(stroke
				(width 0.1)
				(type default)
			)
			(layer "B.Fab")
		)
		(fp_line
			(start -0.67945 0.3048)
			(end -0.120396 0.3048)
			(stroke
				(width 0.1)
				(type default)
			)
			(layer "B.Fab")
		)
		(fp_line
			(start -0.67945 -0.3048)
			(end -0.67945 0.3048)
			(stroke
				(width 0.1)
				(type default)
			)
			(layer "B.Fab")
		)
		(pad "1" smd circle
			(at 0.40005 0)
			(size 0 0)
			(layers "B.Cu" "B.Mask" "B.Paste")
			(net "P1V8_AUX_ADC_TIC")
		)
		(pad "2" smd circle
			(at -0.40005 0)
			(size 0 0)
			(layers "B.Cu" "B.Mask" "B.Paste")
			(net "GND")
		)
	)
	(footprint ""
		(layer "B.Cu")
		(at 106.621834 -249.368564 180)
		(property "Reference" "C2294"
			(at 0 0 0)
			(layer "B.SilkS")
			(hide yes)
			(effects
				(font
					(size 1.27 1.27)
				)
				(justify mirror)
			)
		)
		(property "Value" ""
			(at 0 0 0)
			(layer "B.Fab")
			(effects
				(font
					(size 1.27 1.27)
				)
				(justify mirror)
			)
		)
		(duplicate_pad_numbers_are_jumpers no)
		(fp_line
			(start 0.7874 0.4064)
			(end 0.7874 -0.4064)
			(stroke
				(width 0.1524)
				(type default)
			)
			(layer "B.SilkS")
		)
		(fp_line
			(start 0.7874 -0.4064)
			(end -0.7874 -0.4064)
			(stroke
				(width 0.1524)
				(type default)
			)
			(layer "B.SilkS")
		)
		(fp_line
			(start -0.7874 0.4064)
			(end 0.7874 0.4064)
			(stroke
				(width 0.1524)
				(type default)
			)
			(layer "B.SilkS")
		)
		(fp_line
			(start -0.7874 -0.4064)
			(end -0.7874 0.4064)
			(stroke
				(width 0.1524)
				(type default)
			)
			(layer "B.SilkS")
		)
		(fp_line
			(start 0.67945 0.3048)
			(end 0.67945 -0.305054)
			(stroke
				(width 0.1)
				(type default)
			)
			(layer "B.Fab")
		)
		(fp_line
			(start 0.67945 -0.305054)
			(end 0.12065 -0.305054)
			(stroke
				(width 0.1)
				(type default)
			)
			(layer "B.Fab")
		)
		(fp_line
			(start 0.12065 0.3048)
			(end 0.67945 0.3048)
			(stroke
				(width 0.1)
				(type default)
			)
			(layer "B.Fab")
		)
		(fp_line
			(start 0.12065 0.2794)
			(end 0.12065 0.3048)
			(stroke
				(width 0.1)
				(type default)
			)
			(layer "B.Fab")
		)
		(fp_line
			(start 0.12065 -0.2794)
			(end -0.12065 -0.2794)
			(stroke
				(width 0.1)
				(type default)
			)
			(layer "B.Fab")
		)
		(fp_line
			(start 0.12065 -0.305054)
			(end 0.12065 -0.2794)
			(stroke
				(width 0.1)
				(type default)
			)
			(layer "B.Fab")
		)
		(fp_line
			(start -0.120396 0.3048)
			(end -0.120396 0.2794)
			(stroke
				(width 0.1)
				(type default)
			)
			(layer "B.Fab")
		)
		(fp_line
			(start -0.120396 0.2794)
			(end 0.12065 0.2794)
			(stroke
				(width 0.1)
				(type default)
			)
			(layer "B.Fab")
		)
		(fp_line
			(start -0.12065 -0.2794)
			(end -0.12065 -0.3048)
			(stroke
				(width 0.1)
				(type default)
			)
			(layer "B.Fab")
		)
		(fp_line
			(start -0.12065 -0.3048)
			(end -0.67945 -0.3048)
			(stroke
				(width 0.1)
				(type default)
			)
			(layer "B.Fab")
		)
		(fp_line
			(start -0.67945 0.3048)
			(end -0.120396 0.3048)
			(stroke
				(width 0.1)
				(type default)
			)
			(layer "B.Fab")
		)
		(fp_line
			(start -0.67945 -0.3048)
			(end -0.67945 0.3048)
			(stroke
				(width 0.1)
				(type default)
			)
			(layer "B.Fab")
		)
		(pad "1" smd circle
			(at 0.40005 0)
			(size 0 0)
			(layers "B.Cu" "B.Mask" "B.Paste")
			(net "PVDDCR_CPU0_P1")
		)
		(pad "2" smd circle
			(at -0.40005 0)
			(size 0 0)
			(layers "B.Cu" "B.Mask" "B.Paste")
			(net "GND")
		)
	)
	(footprint ""
		(layer "B.Cu")
		(at 104.180386 -268.418564)
		(property "Reference" "C2350"
			(at 0 0 0)
			(layer "B.SilkS")
			(hide yes)
			(effects
				(font
					(size 1.27 1.27)
				)
				(justify mirror)
			)
		)
		(property "Value" ""
			(at 0 0 0)
			(layer "B.Fab")
			(effects
				(font
					(size 1.27 1.27)
				)
				(justify mirror)
			)
		)
		(duplicate_pad_numbers_are_jumpers no)
		(fp_line
			(start -0.7874 -0.4064)
			(end -0.7874 0.4064)
			(stroke
				(width 0.1524)
				(type default)
			)
			(layer "B.SilkS")
		)
		(fp_line
			(start -0.7874 0.4064)
			(end 0.7874 0.4064)
			(stroke
				(width 0.1524)
				(type default)
			)
			(layer "B.SilkS")
		)
		(fp_line
			(start 0.7874 -0.4064)
			(end -0.7874 -0.4064)
			(stroke
				(width 0.1524)
				(type default)
			)
			(layer "B.SilkS")
		)
		(fp_line
			(start 0.7874 0.4064)
			(end 0.7874 -0.4064)
			(stroke
				(width 0.1524)
				(type default)
			)
			(layer "B.SilkS")
		)
		(fp_line
			(start -0.67945 -0.3048)
			(end -0.67945 0.3048)
			(stroke
				(width 0.1)
				(type default)
			)
			(layer "B.Fab")
		)
		(fp_line
			(start -0.67945 0.3048)
			(end -0.120396 0.3048)
			(stroke
				(width 0.1)
				(type default)
			)
			(layer "B.Fab")
		)
		(fp_line
			(start -0.12065 -0.3048)
			(end -0.67945 -0.3048)
			(stroke
				(width 0.1)
				(type default)
			)
			(layer "B.Fab")
		)
		(fp_line
			(start -0.12065 -0.2794)
			(end -0.12065 -0.3048)
			(stroke
				(width 0.1)
				(type default)
			)
			(layer "B.Fab")
		)
		(fp_line
			(start -0.120396 0.2794)
			(end 0.12065 0.2794)
			(stroke
				(width 0.1)
				(type default)
			)
			(layer "B.Fab")
		)
		(fp_line
			(start -0.120396 0.3048)
			(end -0.120396 0.2794)
			(stroke
				(width 0.1)
				(type default)
			)
			(layer "B.Fab")
		)
		(fp_line
			(start 0.12065 -0.305054)
			(end 0.12065 -0.2794)
			(stroke
				(width 0.1)
				(type default)
			)
			(layer "B.Fab")
		)
		(fp_line
			(start 0.12065 -0.2794)
			(end -0.12065 -0.2794)
			(stroke
				(width 0.1)
				(type default)
			)
			(layer "B.Fab")
		)
		(fp_line
			(start 0.12065 0.2794)
			(end 0.12065 0.3048)
			(stroke
				(width 0.1)
				(type default)
			)
			(layer "B.Fab")
		)
		(fp_line
			(start 0.12065 0.3048)
			(end 0.67945 0.3048)
			(stroke
				(width 0.1)
				(type default)
			)
			(layer "B.Fab")
		)
		(fp_line
			(start 0.67945 -0.305054)
			(end 0.12065 -0.305054)
			(stroke
				(width 0.1)
				(type default)
			)
			(layer "B.Fab")
		)
		(fp_line
			(start 0.67945 0.3048)
			(end 0.67945 -0.305054)
			(stroke
				(width 0.1)
				(type default)
			)
			(layer "B.Fab")
		)
		(pad "1" smd circle
			(at 0.40005 0 180)
			(size 0 0)
			(layers "B.Cu" "B.Mask" "B.Paste")
			(net "PVDDCR_CPU1_P1")
		)
		(pad "2" smd circle
			(at -0.40005 0 180)
			(size 0 0)
			(layers "B.Cu" "B.Mask" "B.Paste")
			(net "GND")
		)
	)
	(footprint ""
		(layer "B.Cu")
		(at 366.288574 -2.537206)
		(property "Reference" "J117"
			(at 4.34594 1.464056 270)
			(unlocked yes)
			(layer "B.SilkS")
			(effects
				(font
					(size 0.7874 0.5842)
					(thickness 0.1524)
				)
				(justify left mirror)
			)
		)
		(property "Value" ""
			(at 0 0 0)
			(layer "B.Fab")
			(effects
				(font
					(size 1.27 1.27)
				)
				(justify mirror)
			)
		)
		(duplicate_pad_numbers_are_jumpers no)
		(fp_line
			(start -1.2192 -2.06756)
			(end -1.2192 2.06756)
			(stroke
				(width 0.1524)
				(type default)
			)
			(layer "B.SilkS")
		)
		(fp_line
			(start -1.2192 2.06756)
			(end 1.2192 2.06756)
			(stroke
				(width 0.1524)
				(type default)
			)
			(layer "B.SilkS")
		)
		(fp_line
			(start 1.2192 -2.06756)
			(end -1.2192 -2.06756)
			(stroke
				(width 0.1524)
				(type default)
			)
			(layer "B.SilkS")
		)
		(fp_line
			(start 1.2192 2.06756)
			(end 1.2192 -2.06756)
			(stroke
				(width 0.1524)
				(type default)
			)
			(layer "B.SilkS")
		)
		(pad "" np_thru_hole circle
			(at -3.4671 -1.27 270)
			(size 1.0414 1.0414)
			(drill 1.0414)
			(layers "*.Cu" "*.Mask")
			(clearance 0.381)
			(thermal_gap 0.381)
		)
		(pad "" np_thru_hole circle
			(at -3.4671 1.27 270)
			(size 1.0414 1.0414)
			(drill 1.0414)
			(layers "*.Cu" "*.Mask")
			(clearance 0.381)
			(thermal_gap 0.381)
		)
		(pad "" np_thru_hole circle
			(at 2.8829 -1.27 270)
			(size 1.0414 1.0414)
			(drill 1.0414)
			(layers "*.Cu" "*.Mask")
			(clearance 0.381)
			(thermal_gap 0.381)
		)
		(pad "" np_thru_hole circle
			(at 2.8829 1.27 270)
			(size 1.0414 1.0414)
			(drill 1.0414)
			(layers "*.Cu" "*.Mask")
			(clearance 0.381)
			(thermal_gap 0.381)
		)
		(pad "1" smd rect
			(at -0.8255 -0.249936 270)
			(size 0.3048 0.508)
			(layers "B.Cu" "B.Mask" "B.Paste")
			(net "DELTA_L_85_5INCH_IN6_DN")
		)
		(pad "2" smd rect
			(at -0.8255 0.249936 270)
			(size 0.3048 0.508)
			(layers "B.Cu" "B.Mask" "B.Paste")
			(net "DELTA_L_85_5INCH_IN6_DP")
		)
		(pad "3" smd circle
			(at 0 0 180)
			(size 0 0)
			(layers "B.Cu" "B.Mask" "B.Paste")
			(net "DELTA_L_GND_1")
		)
		(zone
			(layers "F.Cu" "B.Cu" "In1.Cu" "In2.Cu" "In3.Cu" "In4.Cu" "In5.Cu" "In6.Cu"
				"In7.Cu" "In8.Cu" "In9.Cu" "In10.Cu" "In11.Cu" "In12.Cu" "In13.Cu" "In14.Cu"
				"In15.Cu" "In16.Cu"
			)
			(hatch none 0.5)
			(connect_pads
				(clearance 0)
			)
			(min_thickness 0.25)
			(keepout
				(tracks not_allowed)
				(vias allowed)
				(pads allowed)
				(copperpour not_allowed)
				(footprints allowed)
			)
			(placement
				(enabled no)
				(sheetname "")
			)
			(fill
				(thermal_gap 0.5)
				(thermal_bridge_width 0.5)
				(island_removal_mode 0)
			)
			(polygon
				(pts
					(arc
						(start 363.748574 -3.807206)
						(mid 361.894374 -3.807206)
						(end 363.748574 -3.807206)
					)
				)
			)
		)
		(zone
			(layers "F.Cu" "B.Cu" "In1.Cu" "In2.Cu" "In3.Cu" "In4.Cu" "In5.Cu" "In6.Cu"
				"In7.Cu" "In8.Cu" "In9.Cu" "In10.Cu" "In11.Cu" "In12.Cu" "In13.Cu" "In14.Cu"
				"In15.Cu" "In16.Cu"
			)
			(hatch none 0.5)
			(connect_pads
				(clearance 0)
			)
			(min_thickness 0.25)
			(keepout
				(tracks not_allowed)
				(vias allowed)
				(pads allowed)
				(copperpour not_allowed)
				(footprints allowed)
			)
			(placement
				(enabled no)
				(sheetname "")
			)
			(fill
				(thermal_gap 0.5)
				(thermal_bridge_width 0.5)
				(island_removal_mode 0)
			)
			(polygon
				(pts
					(arc
						(start 363.748574 -1.267206)
						(mid 361.894374 -1.267206)
						(end 363.748574 -1.267206)
					)
				)
			)
		)
		(zone
			(layers "F.Cu" "B.Cu" "In1.Cu" "In2.Cu" "In3.Cu" "In4.Cu" "In5.Cu" "In6.Cu"
				"In7.Cu" "In8.Cu" "In9.Cu" "In10.Cu" "In11.Cu" "In12.Cu" "In13.Cu" "In14.Cu"
				"In15.Cu" "In16.Cu"
			)
			(hatch none 0.5)
			(connect_pads
				(clearance 0)
			)
			(min_thickness 0.25)
			(keepout
				(tracks not_allowed)
				(vias allowed)
				(pads allowed)
				(copperpour not_allowed)
				(footprints allowed)
			)
			(placement
				(enabled no)
				(sheetname "")
			)
			(fill
				(thermal_gap 0.5)
				(thermal_bridge_width 0.5)
				(island_removal_mode 0)
			)
			(polygon
				(pts
					(arc
						(start 370.098574 -3.807206)
						(mid 368.244374 -3.807206)
						(end 370.098574 -3.807206)
					)
				)
			)
		)
		(zone
			(layers "F.Cu" "B.Cu" "In1.Cu" "In2.Cu" "In3.Cu" "In4.Cu" "In5.Cu" "In6.Cu"
				"In7.Cu" "In8.Cu" "In9.Cu" "In10.Cu" "In11.Cu" "In12.Cu" "In13.Cu" "In14.Cu"
				"In15.Cu" "In16.Cu"
			)
			(hatch none 0.5)
			(connect_pads
				(clearance 0)
			)
			(min_thickness 0.25)
			(keepout
				(tracks not_allowed)
				(vias allowed)
				(pads allowed)
				(copperpour not_allowed)
				(footprints allowed)
			)
			(placement
				(enabled no)
				(sheetname "")
			)
			(fill
				(thermal_gap 0.5)
				(thermal_bridge_width 0.5)
				(island_removal_mode 0)
			)
			(polygon
				(pts
					(arc
						(start 370.098574 -1.267206)
						(mid 368.244374 -1.267206)
						(end 370.098574 -1.267206)
					)
				)
			)
		)
		(zone
			(layer "B.Cu")
			(hatch none 0.5)
			(connect_pads
				(clearance 0)
			)
			(min_thickness 0.25)
			(keepout
				(tracks not_allowed)
				(vias allowed)
				(pads allowed)
				(copperpour not_allowed)
				(footprints allowed)
			)
			(placement
				(enabled no)
				(sheetname "")
			)
			(fill
				(thermal_gap 0.5)
				(thermal_bridge_width 0.5)
				(island_removal_mode 0)
			)
			(polygon
				(pts
					(xy 365.170974 -3.085846) (xy 365.170974 -2.990342) (xy 365.767874 -2.990342) (xy 365.767874 -2.583942)
					(xy 365.170974 -2.583942) (xy 365.170974 -2.49047) (xy 365.767874 -2.49047) (xy 365.767874 -2.08407)
					(xy 365.170974 -2.08407) (xy 365.170974 -1.988566) (xy 365.869474 -1.988566) (xy 365.869474 -3.085846)
				)
			)
		)
	)
	(footprint ""
		(layer "B.Cu")
		(at 197.269608 -108.545376)
		(property "Reference" "R286"
			(at 0 0 0)
			(layer "B.SilkS")
			(hide yes)
			(effects
				(font
					(size 1.27 1.27)
				)
				(justify mirror)
			)
		)
		(property "Value" ""
			(at 0 0 0)
			(layer "B.Fab")
			(effects
				(font
					(size 1.27 1.27)
				)
				(justify mirror)
			)
		)
		(duplicate_pad_numbers_are_jumpers no)
		(fp_line
			(start -0.7874 -0.4064)
			(end -0.7874 0.4064)
			(stroke
				(width 0.1524)
				(type default)
			)
			(layer "B.SilkS")
		)
		(fp_line
			(start -0.7874 0.4064)
			(end 0.7874 0.4064)
			(stroke
				(width 0.1524)
				(type default)
			)
			(layer "B.SilkS")
		)
		(fp_line
			(start 0.7874 -0.4064)
			(end -0.7874 -0.4064)
			(stroke
				(width 0.1524)
				(type default)
			)
			(layer "B.SilkS")
		)
		(fp_line
			(start 0.7874 0.4064)
			(end 0.7874 -0.4064)
			(stroke
				(width 0.1524)
				(type default)
			)
			(layer "B.SilkS")
		)
		(fp_line
			(start -0.67945 -0.3048)
			(end -0.67945 0.3048)
			(stroke
				(width 0.1)
				(type default)
			)
			(layer "B.Fab")
		)
		(fp_line
			(start -0.67945 0.3048)
			(end -0.120396 0.3048)
			(stroke
				(width 0.1)
				(type default)
			)
			(layer "B.Fab")
		)
		(fp_line
			(start -0.12065 -0.3048)
			(end -0.67945 -0.3048)
			(stroke
				(width 0.1)
				(type default)
			)
			(layer "B.Fab")
		)
		(fp_line
			(start -0.12065 -0.2794)
			(end -0.12065 -0.3048)
			(stroke
				(width 0.1)
				(type default)
			)
			(layer "B.Fab")
		)
		(fp_line
			(start -0.120396 0.2794)
			(end 0.12065 0.2794)
			(stroke
				(width 0.1)
				(type default)
			)
			(layer "B.Fab")
		)
		(fp_line
			(start -0.120396 0.3048)
			(end -0.120396 0.2794)
			(stroke
				(width 0.1)
				(type default)
			)
			(layer "B.Fab")
		)
		(fp_line
			(start 0.12065 -0.305054)
			(end 0.12065 -0.2794)
			(stroke
				(width 0.1)
				(type default)
			)
			(layer "B.Fab")
		)
		(fp_line
			(start 0.12065 -0.2794)
			(end -0.12065 -0.2794)
			(stroke
				(width 0.1)
				(type default)
			)
			(layer "B.Fab")
		)
		(fp_line
			(start 0.12065 0.2794)
			(end 0.12065 0.3048)
			(stroke
				(width 0.1)
				(type default)
			)
			(layer "B.Fab")
		)
		(fp_line
			(start 0.12065 0.3048)
			(end 0.67945 0.3048)
			(stroke
				(width 0.1)
				(type default)
			)
			(layer "B.Fab")
		)
		(fp_line
			(start 0.67945 -0.305054)
			(end 0.12065 -0.305054)
			(stroke
				(width 0.1)
				(type default)
			)
			(layer "B.Fab")
		)
		(fp_line
			(start 0.67945 0.3048)
			(end 0.67945 -0.305054)
			(stroke
				(width 0.1)
				(type default)
			)
			(layer "B.Fab")
		)
		(pad "1" smd circle
			(at 0.40005 0 180)
			(size 0 0)
			(layers "B.Cu" "B.Mask" "B.Paste")
			(net "PWRGD_PVDDCR_CPU1_P1")
		)
		(pad "2" smd circle
			(at -0.40005 0 180)
			(size 0 0)
			(layers "B.Cu" "B.Mask" "B.Paste")
			(net "FM_PWRGD_PVDDCR_CPU1_P1")
		)
	)
	(footprint ""
		(layer "B.Cu")
		(at 430.80051 -193.99631)
		(property "Reference" "C124"
			(at 0 0 0)
			(layer "B.SilkS")
			(hide yes)
			(effects
				(font
					(size 1.27 1.27)
				)
				(justify mirror)
			)
		)
		(property "Value" ""
			(at 0 0 0)
			(layer "B.Fab")
			(effects
				(font
					(size 1.27 1.27)
				)
				(justify mirror)
			)
		)
		(duplicate_pad_numbers_are_jumpers no)
		(fp_line
			(start -0.7874 -0.4064)
			(end -0.7874 0.4064)
			(stroke
				(width 0.1524)
				(type default)
			)
			(layer "B.SilkS")
		)
		(fp_line
			(start -0.7874 0.4064)
			(end 0.7874 0.4064)
			(stroke
				(width 0.1524)
				(type default)
			)
			(layer "B.SilkS")
		)
		(fp_line
			(start 0.7874 -0.4064)
			(end -0.7874 -0.4064)
			(stroke
				(width 0.1524)
				(type default)
			)
			(layer "B.SilkS")
		)
		(fp_line
			(start 0.7874 0.4064)
			(end 0.7874 -0.4064)
			(stroke
				(width 0.1524)
				(type default)
			)
			(layer "B.SilkS")
		)
		(fp_line
			(start -0.67945 -0.3048)
			(end -0.67945 0.3048)
			(stroke
				(width 0.1)
				(type default)
			)
			(layer "B.Fab")
		)
		(fp_line
			(start -0.67945 0.3048)
			(end -0.120396 0.3048)
			(stroke
				(width 0.1)
				(type default)
			)
			(layer "B.Fab")
		)
		(fp_line
			(start -0.12065 -0.3048)
			(end -0.67945 -0.3048)
			(stroke
				(width 0.1)
				(type default)
			)
			(layer "B.Fab")
		)
		(fp_line
			(start -0.12065 -0.2794)
			(end -0.12065 -0.3048)
			(stroke
				(width 0.1)
				(type default)
			)
			(layer "B.Fab")
		)
		(fp_line
			(start -0.120396 0.2794)
			(end 0.12065 0.2794)
			(stroke
				(width 0.1)
				(type default)
			)
			(layer "B.Fab")
		)
		(fp_line
			(start -0.120396 0.3048)
			(end -0.120396 0.2794)
			(stroke
				(width 0.1)
				(type default)
			)
			(layer "B.Fab")
		)
		(fp_line
			(start 0.12065 -0.305054)
			(end 0.12065 -0.2794)
			(stroke
				(width 0.1)
				(type default)
			)
			(layer "B.Fab")
		)
		(fp_line
			(start 0.12065 -0.2794)
			(end -0.12065 -0.2794)
			(stroke
				(width 0.1)
				(type default)
			)
			(layer "B.Fab")
		)
		(fp_line
			(start 0.12065 0.2794)
			(end 0.12065 0.3048)
			(stroke
				(width 0.1)
				(type default)
			)
			(layer "B.Fab")
		)
		(fp_line
			(start 0.12065 0.3048)
			(end 0.67945 0.3048)
			(stroke
				(width 0.1)
				(type default)
			)
			(layer "B.Fab")
		)
		(fp_line
			(start 0.67945 -0.305054)
			(end 0.12065 -0.305054)
			(stroke
				(width 0.1)
				(type default)
			)
			(layer "B.Fab")
		)
		(fp_line
			(start 0.67945 0.3048)
			(end 0.67945 -0.305054)
			(stroke
				(width 0.1)
				(type default)
			)
			(layer "B.Fab")
		)
		(pad "1" smd circle
			(at 0.40005 0 180)
			(size 0 0)
			(layers "B.Cu" "B.Mask" "B.Paste")
			(net "P3V3_AUX")
		)
		(pad "2" smd circle
			(at -0.40005 0 180)
			(size 0 0)
			(layers "B.Cu" "B.Mask" "B.Paste")
			(net "GND")
		)
	)
	(footprint ""
		(layer "B.Cu")
		(at 439.782966 -425.184824 -90)
		(property "Reference" "PR6616"
			(at 0 0 90)
			(layer "B.SilkS")
			(hide yes)
			(effects
				(font
					(size 1.27 1.27)
				)
				(justify mirror)
			)
		)
		(property "Value" ""
			(at 0 0 90)
			(layer "B.Fab")
			(effects
				(font
					(size 1.27 1.27)
				)
				(justify mirror)
			)
		)
		(duplicate_pad_numbers_are_jumpers no)
		(fp_line
			(start -0.7874 0.4064)
			(end 0.7874 0.4064)
			(stroke
				(width 0.1524)
				(type default)
			)
			(layer "B.SilkS")
		)
		(fp_line
			(start 0.7874 0.4064)
			(end 0.7874 -0.4064)
			(stroke
				(width 0.1524)
				(type default)
			)
			(layer "B.SilkS")
		)
		(fp_line
			(start -0.7874 -0.4064)
			(end -0.7874 0.4064)
			(stroke
				(width 0.1524)
				(type default)
			)
			(layer "B.SilkS")
		)
		(fp_line
			(start 0.7874 -0.4064)
			(end -0.7874 -0.4064)
			(stroke
				(width 0.1524)
				(type default)
			)
			(layer "B.SilkS")
		)
		(fp_line
			(start -0.67945 0.3048)
			(end -0.120396 0.3048)
			(stroke
				(width 0.1)
				(type default)
			)
			(layer "B.Fab")
		)
		(fp_line
			(start -0.120396 0.3048)
			(end -0.120396 0.2794)
			(stroke
				(width 0.1)
				(type default)
			)
			(layer "B.Fab")
		)
		(fp_line
			(start 0.12065 0.3048)
			(end 0.67945 0.3048)
			(stroke
				(width 0.1)
				(type default)
			)
			(layer "B.Fab")
		)
		(fp_line
			(start 0.67945 0.3048)
			(end 0.67945 -0.305054)
			(stroke
				(width 0.1)
				(type default)
			)
			(layer "B.Fab")
		)
		(fp_line
			(start -0.120396 0.2794)
			(end 0.12065 0.2794)
			(stroke
				(width 0.1)
				(type default)
			)
			(layer "B.Fab")
		)
		(fp_line
			(start 0.12065 0.2794)
			(end 0.12065 0.3048)
			(stroke
				(width 0.1)
				(type default)
			)
			(layer "B.Fab")
		)
		(fp_line
			(start -0.12065 -0.2794)
			(end -0.12065 -0.3048)
			(stroke
				(width 0.1)
				(type default)
			)
			(layer "B.Fab")
		)
		(fp_line
			(start 0.12065 -0.2794)
			(end -0.12065 -0.2794)
			(stroke
				(width 0.1)
				(type default)
			)
			(layer "B.Fab")
		)
		(fp_line
			(start -0.67945 -0.3048)
			(end -0.67945 0.3048)
			(stroke
				(width 0.1)
				(type default)
			)
			(layer "B.Fab")
		)
		(fp_line
			(start -0.12065 -0.3048)
			(end -0.67945 -0.3048)
			(stroke
				(width 0.1)
				(type default)
			)
			(layer "B.Fab")
		)
		(fp_line
			(start 0.12065 -0.305054)
			(end 0.12065 -0.2794)
			(stroke
				(width 0.1)
				(type default)
			)
			(layer "B.Fab")
		)
		(fp_line
			(start 0.67945 -0.305054)
			(end 0.12065 -0.305054)
			(stroke
				(width 0.1)
				(type default)
			)
			(layer "B.Fab")
		)
		(pad "1" smd circle
			(at 0.40005 0 90)
			(size 0 0)
			(layers "B.Cu" "B.Mask" "B.Paste")
			(net "P0V9_RETIMER_CPU0_VRHOT")
		)
		(pad "2" smd circle
			(at -0.40005 0 90)
			(size 0 0)
			(layers "B.Cu" "B.Mask" "B.Paste")
			(net "TP_P0V9_RETIMER_CPU0_VRHOT")
		)
	)
	(footprint ""
		(layer "B.Cu")
		(at 329.806046 -416.899344 90)
		(property "Reference" "C6550"
			(at 0 0 90)
			(layer "B.SilkS")
			(hide yes)
			(effects
				(font
					(size 1.27 1.27)
				)
				(justify mirror)
			)
		)
		(property "Value" ""
			(at 0 0 90)
			(layer "B.Fab")
			(effects
				(font
					(size 1.27 1.27)
				)
				(justify mirror)
			)
		)
		(duplicate_pad_numbers_are_jumpers no)
		(fp_line
			(start 0.299974 -0.150114)
			(end -0.299974 -0.150114)
			(stroke
				(width 0.1)
				(type default)
			)
			(layer "B.Fab")
		)
		(fp_line
			(start -0.299974 -0.150114)
			(end -0.299974 0.150114)
			(stroke
				(width 0.1)
				(type default)
			)
			(layer "B.Fab")
		)
		(fp_line
			(start 0.299974 0.150114)
			(end 0.299974 -0.150114)
			(stroke
				(width 0.1)
				(type default)
			)
			(layer "B.Fab")
		)
		(fp_line
			(start -0.299974 0.150114)
			(end 0.299974 0.150114)
			(stroke
				(width 0.1)
				(type default)
			)
			(layer "B.Fab")
		)
		(pad "1" smd rect
			(at 0.2667 0 270)
			(size 0.3048 0.381)
			(layers "B.Cu" "B.Mask" "B.Paste")
			(net "P5E_CPU0_P1_TX_BUF_C_DN<8>")
		)
		(pad "2" smd rect
			(at -0.2667 0 270)
			(size 0.3048 0.381)
			(layers "B.Cu" "B.Mask" "B.Paste")
			(net "P5E_CPU0_P1_TX_BUF_DN<8>")
		)
	)
	(footprint ""
		(layer "B.Cu")
		(at 182.860696 -194.8942 180)
		(property "Reference" "R1588"
			(at 0 0 0)
			(layer "B.SilkS")
			(hide yes)
			(effects
				(font
					(size 1.27 1.27)
				)
				(justify mirror)
			)
		)
		(property "Value" ""
			(at 0 0 0)
			(layer "B.Fab")
			(effects
				(font
					(size 1.27 1.27)
				)
				(justify mirror)
			)
		)
		(duplicate_pad_numbers_are_jumpers no)
		(fp_line
			(start 0.7874 0.4064)
			(end 0.7874 -0.4064)
			(stroke
				(width 0.1524)
				(type default)
			)
			(layer "B.SilkS")
		)
		(fp_line
			(start 0.7874 -0.4064)
			(end -0.7874 -0.4064)
			(stroke
				(width 0.1524)
				(type default)
			)
			(layer "B.SilkS")
		)
		(fp_line
			(start -0.7874 0.4064)
			(end 0.7874 0.4064)
			(stroke
				(width 0.1524)
				(type default)
			)
			(layer "B.SilkS")
		)
		(fp_line
			(start -0.7874 -0.4064)
			(end -0.7874 0.4064)
			(stroke
				(width 0.1524)
				(type default)
			)
			(layer "B.SilkS")
		)
		(fp_line
			(start 0.67945 0.3048)
			(end 0.67945 -0.305054)
			(stroke
				(width 0.1)
				(type default)
			)
			(layer "B.Fab")
		)
		(fp_line
			(start 0.67945 -0.305054)
			(end 0.12065 -0.305054)
			(stroke
				(width 0.1)
				(type default)
			)
			(layer "B.Fab")
		)
		(fp_line
			(start 0.12065 0.3048)
			(end 0.67945 0.3048)
			(stroke
				(width 0.1)
				(type default)
			)
			(layer "B.Fab")
		)
		(fp_line
			(start 0.12065 0.2794)
			(end 0.12065 0.3048)
			(stroke
				(width 0.1)
				(type default)
			)
			(layer "B.Fab")
		)
		(fp_line
			(start 0.12065 -0.2794)
			(end -0.12065 -0.2794)
			(stroke
				(width 0.1)
				(type default)
			)
			(layer "B.Fab")
		)
		(fp_line
			(start 0.12065 -0.305054)
			(end 0.12065 -0.2794)
			(stroke
				(width 0.1)
				(type default)
			)
			(layer "B.Fab")
		)
		(fp_line
			(start -0.120396 0.3048)
			(end -0.120396 0.2794)
			(stroke
				(width 0.1)
				(type default)
			)
			(layer "B.Fab")
		)
		(fp_line
			(start -0.120396 0.2794)
			(end 0.12065 0.2794)
			(stroke
				(width 0.1)
				(type default)
			)
			(layer "B.Fab")
		)
		(fp_line
			(start -0.12065 -0.2794)
			(end -0.12065 -0.3048)
			(stroke
				(width 0.1)
				(type default)
			)
			(layer "B.Fab")
		)
		(fp_line
			(start -0.12065 -0.3048)
			(end -0.67945 -0.3048)
			(stroke
				(width 0.1)
				(type default)
			)
			(layer "B.Fab")
		)
		(fp_line
			(start -0.67945 0.3048)
			(end -0.120396 0.3048)
			(stroke
				(width 0.1)
				(type default)
			)
			(layer "B.Fab")
		)
		(fp_line
			(start -0.67945 -0.3048)
			(end -0.67945 0.3048)
			(stroke
				(width 0.1)
				(type default)
			)
			(layer "B.Fab")
		)
		(pad "1" smd circle
			(at 0.40005 0)
			(size 0 0)
			(layers "B.Cu" "B.Mask" "B.Paste")
			(net "I3C_SPD_DDRGL_CPU1_SCL")
		)
		(pad "2" smd circle
			(at -0.40005 0)
			(size 0 0)
			(layers "B.Cu" "B.Mask" "B.Paste")
			(net "I3C_SPD_DDRI_CPU1_SCL")
		)
	)
	(footprint ""
		(layer "B.Cu")
		(at 153.990802 -16.851122 -90)
		(property "Reference" "R3226"
			(at 0 0 90)
			(layer "B.SilkS")
			(hide yes)
			(effects
				(font
					(size 1.27 1.27)
				)
				(justify mirror)
			)
		)
		(property "Value" ""
			(at 0 0 90)
			(layer "B.Fab")
			(effects
				(font
					(size 1.27 1.27)
				)
				(justify mirror)
			)
		)
		(duplicate_pad_numbers_are_jumpers no)
		(fp_line
			(start -0.7874 0.4064)
			(end 0.7874 0.4064)
			(stroke
				(width 0.1524)
				(type default)
			)
			(layer "B.SilkS")
		)
		(fp_line
			(start 0.7874 0.4064)
			(end 0.7874 -0.4064)
			(stroke
				(width 0.1524)
				(type default)
			)
			(layer "B.SilkS")
		)
		(fp_line
			(start -0.7874 -0.4064)
			(end -0.7874 0.4064)
			(stroke
				(width 0.1524)
				(type default)
			)
			(layer "B.SilkS")
		)
		(fp_line
			(start 0.7874 -0.4064)
			(end -0.7874 -0.4064)
			(stroke
				(width 0.1524)
				(type default)
			)
			(layer "B.SilkS")
		)
		(fp_line
			(start -0.67945 0.3048)
			(end -0.120396 0.3048)
			(stroke
				(width 0.1)
				(type default)
			)
			(layer "B.Fab")
		)
		(fp_line
			(start -0.120396 0.3048)
			(end -0.120396 0.2794)
			(stroke
				(width 0.1)
				(type default)
			)
			(layer "B.Fab")
		)
		(fp_line
			(start 0.12065 0.3048)
			(end 0.67945 0.3048)
			(stroke
				(width 0.1)
				(type default)
			)
			(layer "B.Fab")
		)
		(fp_line
			(start 0.67945 0.3048)
			(end 0.67945 -0.305054)
			(stroke
				(width 0.1)
				(type default)
			)
			(layer "B.Fab")
		)
		(fp_line
			(start -0.120396 0.2794)
			(end 0.12065 0.2794)
			(stroke
				(width 0.1)
				(type default)
			)
			(layer "B.Fab")
		)
		(fp_line
			(start 0.12065 0.2794)
			(end 0.12065 0.3048)
			(stroke
				(width 0.1)
				(type default)
			)
			(layer "B.Fab")
		)
		(fp_line
			(start -0.12065 -0.2794)
			(end -0.12065 -0.3048)
			(stroke
				(width 0.1)
				(type default)
			)
			(layer "B.Fab")
		)
		(fp_line
			(start 0.12065 -0.2794)
			(end -0.12065 -0.2794)
			(stroke
				(width 0.1)
				(type default)
			)
			(layer "B.Fab")
		)
		(fp_line
			(start -0.67945 -0.3048)
			(end -0.67945 0.3048)
			(stroke
				(width 0.1)
				(type default)
			)
			(layer "B.Fab")
		)
		(fp_line
			(start -0.12065 -0.3048)
			(end -0.67945 -0.3048)
			(stroke
				(width 0.1)
				(type default)
			)
			(layer "B.Fab")
		)
		(fp_line
			(start 0.12065 -0.305054)
			(end 0.12065 -0.2794)
			(stroke
				(width 0.1)
				(type default)
			)
			(layer "B.Fab")
		)
		(fp_line
			(start 0.67945 -0.305054)
			(end 0.12065 -0.305054)
			(stroke
				(width 0.1)
				(type default)
			)
			(layer "B.Fab")
		)
		(pad "1" smd circle
			(at 0.40005 0 90)
			(size 0 0)
			(layers "B.Cu" "B.Mask" "B.Paste")
			(net "SMB_1_BMC_GPU_SCL")
		)
		(pad "2" smd circle
			(at -0.40005 0 90)
			(size 0 0)
			(layers "B.Cu" "B.Mask" "B.Paste")
			(net "P3V3_AUX")
		)
	)
	(footprint ""
		(layer "B.Cu")
		(at 51.120548 -195.926964 180)
		(property "Reference" "R1696"
			(at 0 0 0)
			(layer "B.SilkS")
			(hide yes)
			(effects
				(font
					(size 1.27 1.27)
				)
				(justify mirror)
			)
		)
		(property "Value" ""
			(at 0 0 0)
			(layer "B.Fab")
			(effects
				(font
					(size 1.27 1.27)
				)
				(justify mirror)
			)
		)
		(duplicate_pad_numbers_are_jumpers no)
		(fp_line
			(start 0.7874 0.4064)
			(end 0.7874 -0.4064)
			(stroke
				(width 0.1524)
				(type default)
			)
			(layer "B.SilkS")
		)
		(fp_line
			(start 0.7874 -0.4064)
			(end -0.7874 -0.4064)
			(stroke
				(width 0.1524)
				(type default)
			)
			(layer "B.SilkS")
		)
		(fp_line
			(start -0.7874 0.4064)
			(end 0.7874 0.4064)
			(stroke
				(width 0.1524)
				(type default)
			)
			(layer "B.SilkS")
		)
		(fp_line
			(start -0.7874 -0.4064)
			(end -0.7874 0.4064)
			(stroke
				(width 0.1524)
				(type default)
			)
			(layer "B.SilkS")
		)
		(fp_line
			(start 0.67945 0.3048)
			(end 0.67945 -0.305054)
			(stroke
				(width 0.1)
				(type default)
			)
			(layer "B.Fab")
		)
		(fp_line
			(start 0.67945 -0.305054)
			(end 0.12065 -0.305054)
			(stroke
				(width 0.1)
				(type default)
			)
			(layer "B.Fab")
		)
		(fp_line
			(start 0.12065 0.3048)
			(end 0.67945 0.3048)
			(stroke
				(width 0.1)
				(type default)
			)
			(layer "B.Fab")
		)
		(fp_line
			(start 0.12065 0.2794)
			(end 0.12065 0.3048)
			(stroke
				(width 0.1)
				(type default)
			)
			(layer "B.Fab")
		)
		(fp_line
			(start 0.12065 -0.2794)
			(end -0.12065 -0.2794)
			(stroke
				(width 0.1)
				(type default)
			)
			(layer "B.Fab")
		)
		(fp_line
			(start 0.12065 -0.305054)
			(end 0.12065 -0.2794)
			(stroke
				(width 0.1)
				(type default)
			)
			(layer "B.Fab")
		)
		(fp_line
			(start -0.120396 0.3048)
			(end -0.120396 0.2794)
			(stroke
				(width 0.1)
				(type default)
			)
			(layer "B.Fab")
		)
		(fp_line
			(start -0.120396 0.2794)
			(end 0.12065 0.2794)
			(stroke
				(width 0.1)
				(type default)
			)
			(layer "B.Fab")
		)
		(fp_line
			(start -0.12065 -0.2794)
			(end -0.12065 -0.3048)
			(stroke
				(width 0.1)
				(type default)
			)
			(layer "B.Fab")
		)
		(fp_line
			(start -0.12065 -0.3048)
			(end -0.67945 -0.3048)
			(stroke
				(width 0.1)
				(type default)
			)
			(layer "B.Fab")
		)
		(fp_line
			(start -0.67945 0.3048)
			(end -0.120396 0.3048)
			(stroke
				(width 0.1)
				(type default)
			)
			(layer "B.Fab")
		)
		(fp_line
			(start -0.67945 -0.3048)
			(end -0.67945 0.3048)
			(stroke
				(width 0.1)
				(type default)
			)
			(layer "B.Fab")
		)
		(pad "1" smd circle
			(at 0.40005 0)
			(size 0 0)
			(layers "B.Cu" "B.Mask" "B.Paste")
			(net "I3C_SPD_DDRAF_CPU1_SDA")
		)
		(pad "2" smd circle
			(at -0.40005 0)
			(size 0 0)
			(layers "B.Cu" "B.Mask" "B.Paste")
			(net "I3C_SPD_DDRB_CPU1_SDA")
		)
	)
	(footprint ""
		(layer "B.Cu")
		(at 418.128958 -342.007952 -90)
		(property "Reference" "PC225_2"
			(at 0 0 90)
			(layer "B.SilkS")
			(hide yes)
			(effects
				(font
					(size 1.27 1.27)
				)
				(justify mirror)
			)
		)
		(property "Value" ""
			(at 0 0 90)
			(layer "B.Fab")
			(effects
				(font
					(size 1.27 1.27)
				)
				(justify mirror)
			)
		)
		(duplicate_pad_numbers_are_jumpers no)
		(fp_line
			(start -1.524 0.762)
			(end 1.524 0.762)
			(stroke
				(width 0.1524)
				(type default)
			)
			(layer "B.SilkS")
		)
		(fp_line
			(start 1.524 0.762)
			(end 1.524 -0.762)
			(stroke
				(width 0.1524)
				(type default)
			)
			(layer "B.SilkS")
		)
		(fp_line
			(start -1.524 -0.762)
			(end -1.524 0.762)
			(stroke
				(width 0.1524)
				(type default)
			)
			(layer "B.SilkS")
		)
		(fp_line
			(start 1.524 -0.762)
			(end -1.524 -0.762)
			(stroke
				(width 0.1524)
				(type default)
			)
			(layer "B.SilkS")
		)
		(fp_line
			(start -1.1049 0.724916)
			(end -1.1049 -0.724916)
			(stroke
				(width 0.1)
				(type default)
			)
			(layer "B.Fab")
		)
		(fp_line
			(start 1.1049 0.724916)
			(end -1.1049 0.724916)
			(stroke
				(width 0.1)
				(type default)
			)
			(layer "B.Fab")
		)
		(fp_line
			(start -1.1049 -0.724916)
			(end 1.1049 -0.724916)
			(stroke
				(width 0.1)
				(type default)
			)
			(layer "B.Fab")
		)
		(fp_line
			(start 1.1049 -0.724916)
			(end 1.1049 0.724916)
			(stroke
				(width 0.1)
				(type default)
			)
			(layer "B.Fab")
		)
		(pad "1" smd rect
			(at 0.889 0 270)
			(size 1.016 1.27)
			(layers "B.Cu" "B.Mask" "B.Paste")
			(net "PVDD11_S3_P0")
		)
		(pad "2" smd rect
			(at -0.889 0 270)
			(size 1.016 1.27)
			(layers "B.Cu" "B.Mask" "B.Paste")
			(net "GND")
		)
	)
	(footprint ""
		(layer "B.Cu")
		(at 93.11894 -390.560052 90)
		(property "Reference" "C343"
			(at 0 0 90)
			(layer "B.SilkS")
			(hide yes)
			(effects
				(font
					(size 1.27 1.27)
				)
				(justify mirror)
			)
		)
		(property "Value" ""
			(at 0 0 90)
			(layer "B.Fab")
			(effects
				(font
					(size 1.27 1.27)
				)
				(justify mirror)
			)
		)
		(duplicate_pad_numbers_are_jumpers no)
		(fp_line
			(start 0.7874 -0.4064)
			(end -0.7874 -0.4064)
			(stroke
				(width 0.1524)
				(type default)
			)
			(layer "B.SilkS")
		)
		(fp_line
			(start -0.7874 -0.4064)
			(end -0.7874 0.4064)
			(stroke
				(width 0.1524)
				(type default)
			)
			(layer "B.SilkS")
		)
		(fp_line
			(start 0.7874 0.4064)
			(end 0.7874 -0.4064)
			(stroke
				(width 0.1524)
				(type default)
			)
			(layer "B.SilkS")
		)
		(fp_line
			(start -0.7874 0.4064)
			(end 0.7874 0.4064)
			(stroke
				(width 0.1524)
				(type default)
			)
			(layer "B.SilkS")
		)
		(fp_line
			(start 0.67945 -0.305054)
			(end 0.12065 -0.305054)
			(stroke
				(width 0.1)
				(type default)
			)
			(layer "B.Fab")
		)
		(fp_line
			(start 0.12065 -0.305054)
			(end 0.12065 -0.2794)
			(stroke
				(width 0.1)
				(type default)
			)
			(layer "B.Fab")
		)
		(fp_line
			(start -0.12065 -0.3048)
			(end -0.67945 -0.3048)
			(stroke
				(width 0.1)
				(type default)
			)
			(layer "B.Fab")
		)
		(fp_line
			(start -0.67945 -0.3048)
			(end -0.67945 0.3048)
			(stroke
				(width 0.1)
				(type default)
			)
			(layer "B.Fab")
		)
		(fp_line
			(start 0.12065 -0.2794)
			(end -0.12065 -0.2794)
			(stroke
				(width 0.1)
				(type default)
			)
			(layer "B.Fab")
		)
		(fp_line
			(start -0.12065 -0.2794)
			(end -0.12065 -0.3048)
			(stroke
				(width 0.1)
				(type default)
			)
			(layer "B.Fab")
		)
		(fp_line
			(start 0.12065 0.2794)
			(end 0.12065 0.3048)
			(stroke
				(width 0.1)
				(type default)
			)
			(layer "B.Fab")
		)
		(fp_line
			(start -0.120396 0.2794)
			(end 0.12065 0.2794)
			(stroke
				(width 0.1)
				(type default)
			)
			(layer "B.Fab")
		)
		(fp_line
			(start 0.67945 0.3048)
			(end 0.67945 -0.305054)
			(stroke
				(width 0.1)
				(type default)
			)
			(layer "B.Fab")
		)
		(fp_line
			(start 0.12065 0.3048)
			(end 0.67945 0.3048)
			(stroke
				(width 0.1)
				(type default)
			)
			(layer "B.Fab")
		)
		(fp_line
			(start -0.120396 0.3048)
			(end -0.120396 0.2794)
			(stroke
				(width 0.1)
				(type default)
			)
			(layer "B.Fab")
		)
		(fp_line
			(start -0.67945 0.3048)
			(end -0.120396 0.3048)
			(stroke
				(width 0.1)
				(type default)
			)
			(layer "B.Fab")
		)
		(pad "1" smd circle
			(at 0.40005 0 270)
			(size 0 0)
			(layers "B.Cu" "B.Mask" "B.Paste")
			(net "P0V9_CPU1_RT1_2A")
		)
		(pad "2" smd circle
			(at -0.40005 0 270)
			(size 0 0)
			(layers "B.Cu" "B.Mask" "B.Paste")
			(net "GND")
		)
	)
	(footprint ""
		(layer "B.Cu")
		(at 45.336968 -244.085364 180)
		(property "Reference" "R502"
			(at 0 0 0)
			(layer "B.SilkS")
			(hide yes)
			(effects
				(font
					(size 1.27 1.27)
				)
				(justify mirror)
			)
		)
		(property "Value" ""
			(at 0 0 0)
			(layer "B.Fab")
			(effects
				(font
					(size 1.27 1.27)
				)
				(justify mirror)
			)
		)
		(duplicate_pad_numbers_are_jumpers no)
		(fp_line
			(start 0.7874 0.4064)
			(end 0.7874 -0.4064)
			(stroke
				(width 0.1524)
				(type default)
			)
			(layer "B.SilkS")
		)
		(fp_line
			(start 0.7874 -0.4064)
			(end -0.7874 -0.4064)
			(stroke
				(width 0.1524)
				(type default)
			)
			(layer "B.SilkS")
		)
		(fp_line
			(start -0.7874 0.4064)
			(end 0.7874 0.4064)
			(stroke
				(width 0.1524)
				(type default)
			)
			(layer "B.SilkS")
		)
		(fp_line
			(start -0.7874 -0.4064)
			(end -0.7874 0.4064)
			(stroke
				(width 0.1524)
				(type default)
			)
			(layer "B.SilkS")
		)
		(fp_line
			(start 0.67945 0.3048)
			(end 0.67945 -0.305054)
			(stroke
				(width 0.1)
				(type default)
			)
			(layer "B.Fab")
		)
		(fp_line
			(start 0.67945 -0.305054)
			(end 0.12065 -0.305054)
			(stroke
				(width 0.1)
				(type default)
			)
			(layer "B.Fab")
		)
		(fp_line
			(start 0.12065 0.3048)
			(end 0.67945 0.3048)
			(stroke
				(width 0.1)
				(type default)
			)
			(layer "B.Fab")
		)
		(fp_line
			(start 0.12065 0.2794)
			(end 0.12065 0.3048)
			(stroke
				(width 0.1)
				(type default)
			)
			(layer "B.Fab")
		)
		(fp_line
			(start 0.12065 -0.2794)
			(end -0.12065 -0.2794)
			(stroke
				(width 0.1)
				(type default)
			)
			(layer "B.Fab")
		)
		(fp_line
			(start 0.12065 -0.305054)
			(end 0.12065 -0.2794)
			(stroke
				(width 0.1)
				(type default)
			)
			(layer "B.Fab")
		)
		(fp_line
			(start -0.120396 0.3048)
			(end -0.120396 0.2794)
			(stroke
				(width 0.1)
				(type default)
			)
			(layer "B.Fab")
		)
		(fp_line
			(start -0.120396 0.2794)
			(end 0.12065 0.2794)
			(stroke
				(width 0.1)
				(type default)
			)
			(layer "B.Fab")
		)
		(fp_line
			(start -0.12065 -0.2794)
			(end -0.12065 -0.3048)
			(stroke
				(width 0.1)
				(type default)
			)
			(layer "B.Fab")
		)
		(fp_line
			(start -0.12065 -0.3048)
			(end -0.67945 -0.3048)
			(stroke
				(width 0.1)
				(type default)
			)
			(layer "B.Fab")
		)
		(fp_line
			(start -0.67945 0.3048)
			(end -0.120396 0.3048)
			(stroke
				(width 0.1)
				(type default)
			)
			(layer "B.Fab")
		)
		(fp_line
			(start -0.67945 -0.3048)
			(end -0.67945 0.3048)
			(stroke
				(width 0.1)
				(type default)
			)
			(layer "B.Fab")
		)
		(pad "1" smd circle
			(at 0.40005 0)
			(size 0 0)
			(layers "B.Cu" "B.Mask" "B.Paste")
			(net "M_C_CPU1_ALERT_N")
		)
		(pad "2" smd circle
			(at -0.40005 0)
			(size 0 0)
			(layers "B.Cu" "B.Mask" "B.Paste")
			(net "M_C_CPU1_ALERT_R_N")
		)
	)
	(footprint ""
		(layer "B.Cu")
		(at 418.606224 -395.148562 90)
		(property "Reference" "C788"
			(at 0 0 90)
			(layer "B.SilkS")
			(hide yes)
			(effects
				(font
					(size 1.27 1.27)
				)
				(justify mirror)
			)
		)
		(property "Value" ""
			(at 0 0 90)
			(layer "B.Fab")
			(effects
				(font
					(size 1.27 1.27)
				)
				(justify mirror)
			)
		)
		(duplicate_pad_numbers_are_jumpers no)
		(fp_line
			(start 0.299974 -0.150114)
			(end -0.299974 -0.150114)
			(stroke
				(width 0.1)
				(type default)
			)
			(layer "B.Fab")
		)
		(fp_line
			(start -0.299974 -0.150114)
			(end -0.299974 0.150114)
			(stroke
				(width 0.1)
				(type default)
			)
			(layer "B.Fab")
		)
		(fp_line
			(start 0.299974 0.150114)
			(end 0.299974 -0.150114)
			(stroke
				(width 0.1)
				(type default)
			)
			(layer "B.Fab")
		)
		(fp_line
			(start -0.299974 0.150114)
			(end 0.299974 0.150114)
			(stroke
				(width 0.1)
				(type default)
			)
			(layer "B.Fab")
		)
		(pad "1" smd rect
			(at 0.2667 0 270)
			(size 0.3048 0.381)
			(layers "B.Cu" "B.Mask" "B.Paste")
			(net "P0V9_CPU0_RT2_2A")
		)
		(pad "2" smd rect
			(at -0.2667 0 270)
			(size 0.3048 0.381)
			(layers "B.Cu" "B.Mask" "B.Paste")
			(net "GND")
		)
	)
	(footprint ""
		(layer "B.Cu")
		(at 182.332376 -113.862866 180)
		(property "Reference" "C357"
			(at 0 0 0)
			(layer "B.SilkS")
			(hide yes)
			(effects
				(font
					(size 1.27 1.27)
				)
				(justify mirror)
			)
		)
		(property "Value" ""
			(at 0 0 0)
			(layer "B.Fab")
			(effects
				(font
					(size 1.27 1.27)
				)
				(justify mirror)
			)
		)
		(duplicate_pad_numbers_are_jumpers no)
		(fp_line
			(start 0.69215 0.2921)
			(end 0.69215 -0.2921)
			(stroke
				(width 0.1524)
				(type default)
			)
			(layer "B.SilkS")
		)
		(fp_line
			(start 0.69215 -0.2921)
			(end -0.69215 -0.2921)
			(stroke
				(width 0.1524)
				(type default)
			)
			(layer "B.SilkS")
		)
		(fp_line
			(start -0.69215 0.2921)
			(end 0.69215 0.2921)
			(stroke
				(width 0.1524)
				(type default)
			)
			(layer "B.SilkS")
		)
		(fp_line
			(start -0.69215 -0.2921)
			(end -0.69215 0.2921)
			(stroke
				(width 0.1524)
				(type default)
			)
			(layer "B.SilkS")
		)
		(fp_line
			(start 0.51435 0.2794)
			(end 0.51435 -0.2794)
			(stroke
				(width 0.1)
				(type default)
			)
			(layer "B.Fab")
		)
		(fp_line
			(start 0.51435 -0.2794)
			(end -0.51435 -0.2794)
			(stroke
				(width 0.1)
				(type default)
			)
			(layer "B.Fab")
		)
		(fp_line
			(start -0.51435 0.2794)
			(end 0.51435 0.2794)
			(stroke
				(width 0.1)
				(type default)
			)
			(layer "B.Fab")
		)
		(fp_line
			(start -0.51435 -0.2794)
			(end -0.51435 0.2794)
			(stroke
				(width 0.1)
				(type default)
			)
			(layer "B.Fab")
		)
		(pad "1" smd circle
			(at 0.40005 0)
			(size 0 0)
			(layers "B.Cu" "B.Mask" "B.Paste")
			(net "P3V3_AUX")
		)
		(pad "2" smd circle
			(at -0.40005 0)
			(size 0 0)
			(layers "B.Cu" "B.Mask" "B.Paste")
			(net "GND")
		)
		(zone
			(layer "B.Cu")
			(hatch none 0.5)
			(connect_pads
				(clearance 0)
			)
			(min_thickness 0.25)
			(keepout
				(tracks not_allowed)
				(vias allowed)
				(pads allowed)
				(copperpour not_allowed)
				(footprints allowed)
			)
			(placement
				(enabled no)
				(sheetname "")
			)
			(fill
				(thermal_gap 0.5)
				(thermal_bridge_width 0.5)
				(island_removal_mode 0)
			)
			(polygon
				(pts
					(xy 182.141876 -113.774982) (xy 182.141876 -113.950496) (xy 182.233316 -114.008662) (xy 182.432706 -114.008662)
					(xy 182.522876 -113.950496) (xy 182.522876 -113.775236) (xy 182.432706 -113.716816) (xy 182.233316 -113.716816)
				)
			)
		)
	)
	(footprint ""
		(layer "B.Cu")
		(at 308.363366 -416.899344 90)
		(property "Reference" "C6536"
			(at 0 0 90)
			(layer "B.SilkS")
			(hide yes)
			(effects
				(font
					(size 1.27 1.27)
				)
				(justify mirror)
			)
		)
		(property "Value" ""
			(at 0 0 90)
			(layer "B.Fab")
			(effects
				(font
					(size 1.27 1.27)
				)
				(justify mirror)
			)
		)
		(duplicate_pad_numbers_are_jumpers no)
		(fp_line
			(start 0.299974 -0.150114)
			(end -0.299974 -0.150114)
			(stroke
				(width 0.1)
				(type default)
			)
			(layer "B.Fab")
		)
		(fp_line
			(start -0.299974 -0.150114)
			(end -0.299974 0.150114)
			(stroke
				(width 0.1)
				(type default)
			)
			(layer "B.Fab")
		)
		(fp_line
			(start 0.299974 0.150114)
			(end 0.299974 -0.150114)
			(stroke
				(width 0.1)
				(type default)
			)
			(layer "B.Fab")
		)
		(fp_line
			(start -0.299974 0.150114)
			(end 0.299974 0.150114)
			(stroke
				(width 0.1)
				(type default)
			)
			(layer "B.Fab")
		)
		(pad "1" smd rect
			(at 0.2667 0 270)
			(size 0.3048 0.381)
			(layers "B.Cu" "B.Mask" "B.Paste")
			(net "P5E_CPU0_P1_TX_BUF_C_DN<1>")
		)
		(pad "2" smd rect
			(at -0.2667 0 270)
			(size 0.3048 0.381)
			(layers "B.Cu" "B.Mask" "B.Paste")
			(net "P5E_CPU0_P1_TX_BUF_DN<1>")
		)
	)
	(footprint ""
		(layer "B.Cu")
		(at 376.472958 -208.530952 90)
		(property "Reference" "C210"
			(at 0 0 90)
			(layer "B.SilkS")
			(hide yes)
			(effects
				(font
					(size 1.27 1.27)
				)
				(justify mirror)
			)
		)
		(property "Value" ""
			(at 0 0 90)
			(layer "B.Fab")
			(effects
				(font
					(size 1.27 1.27)
				)
				(justify mirror)
			)
		)
		(duplicate_pad_numbers_are_jumpers no)
		(fp_line
			(start 0.7874 -0.4064)
			(end -0.7874 -0.4064)
			(stroke
				(width 0.1524)
				(type default)
			)
			(layer "B.SilkS")
		)
		(fp_line
			(start -0.7874 -0.4064)
			(end -0.7874 0.4064)
			(stroke
				(width 0.1524)
				(type default)
			)
			(layer "B.SilkS")
		)
		(fp_line
			(start 0.7874 0.4064)
			(end 0.7874 -0.4064)
			(stroke
				(width 0.1524)
				(type default)
			)
			(layer "B.SilkS")
		)
		(fp_line
			(start -0.7874 0.4064)
			(end 0.7874 0.4064)
			(stroke
				(width 0.1524)
				(type default)
			)
			(layer "B.SilkS")
		)
		(fp_line
			(start 0.67945 -0.305054)
			(end 0.12065 -0.305054)
			(stroke
				(width 0.1)
				(type default)
			)
			(layer "B.Fab")
		)
		(fp_line
			(start 0.12065 -0.305054)
			(end 0.12065 -0.2794)
			(stroke
				(width 0.1)
				(type default)
			)
			(layer "B.Fab")
		)
		(fp_line
			(start -0.12065 -0.3048)
			(end -0.67945 -0.3048)
			(stroke
				(width 0.1)
				(type default)
			)
			(layer "B.Fab")
		)
		(fp_line
			(start -0.67945 -0.3048)
			(end -0.67945 0.3048)
			(stroke
				(width 0.1)
				(type default)
			)
			(layer "B.Fab")
		)
		(fp_line
			(start 0.12065 -0.2794)
			(end -0.12065 -0.2794)
			(stroke
				(width 0.1)
				(type default)
			)
			(layer "B.Fab")
		)
		(fp_line
			(start -0.12065 -0.2794)
			(end -0.12065 -0.3048)
			(stroke
				(width 0.1)
				(type default)
			)
			(layer "B.Fab")
		)
		(fp_line
			(start 0.12065 0.2794)
			(end 0.12065 0.3048)
			(stroke
				(width 0.1)
				(type default)
			)
			(layer "B.Fab")
		)
		(fp_line
			(start -0.120396 0.2794)
			(end 0.12065 0.2794)
			(stroke
				(width 0.1)
				(type default)
			)
			(layer "B.Fab")
		)
		(fp_line
			(start 0.67945 0.3048)
			(end 0.67945 -0.305054)
			(stroke
				(width 0.1)
				(type default)
			)
			(layer "B.Fab")
		)
		(fp_line
			(start 0.12065 0.3048)
			(end 0.67945 0.3048)
			(stroke
				(width 0.1)
				(type default)
			)
			(layer "B.Fab")
		)
		(fp_line
			(start -0.120396 0.3048)
			(end -0.120396 0.2794)
			(stroke
				(width 0.1)
				(type default)
			)
			(layer "B.Fab")
		)
		(fp_line
			(start -0.67945 0.3048)
			(end -0.120396 0.3048)
			(stroke
				(width 0.1)
				(type default)
			)
			(layer "B.Fab")
		)
		(pad "1" smd circle
			(at 0.40005 0 270)
			(size 0 0)
			(layers "B.Cu" "B.Mask" "B.Paste")
			(net "JTAG_CPU0_TCK")
		)
		(pad "2" smd circle
			(at -0.40005 0 270)
			(size 0 0)
			(layers "B.Cu" "B.Mask" "B.Paste")
			(net "GND")
		)
	)
	(footprint ""
		(layer "B.Cu")
		(at 348.101158 -271.878552 90)
		(property "Reference" "C2233"
			(at 0 0 90)
			(layer "B.SilkS")
			(hide yes)
			(effects
				(font
					(size 1.27 1.27)
				)
				(justify mirror)
			)
		)
		(property "Value" ""
			(at 0 0 90)
			(layer "B.Fab")
			(effects
				(font
					(size 1.27 1.27)
				)
				(justify mirror)
			)
		)
		(duplicate_pad_numbers_are_jumpers no)
		(fp_line
			(start 0.7874 -0.4064)
			(end -0.7874 -0.4064)
			(stroke
				(width 0.1524)
				(type default)
			)
			(layer "B.SilkS")
		)
		(fp_line
			(start -0.7874 -0.4064)
			(end -0.7874 0.4064)
			(stroke
				(width 0.1524)
				(type default)
			)
			(layer "B.SilkS")
		)
		(fp_line
			(start 0.7874 0.4064)
			(end 0.7874 -0.4064)
			(stroke
				(width 0.1524)
				(type default)
			)
			(layer "B.SilkS")
		)
		(fp_line
			(start -0.7874 0.4064)
			(end 0.7874 0.4064)
			(stroke
				(width 0.1524)
				(type default)
			)
			(layer "B.SilkS")
		)
		(fp_line
			(start 0.67945 -0.305054)
			(end 0.12065 -0.305054)
			(stroke
				(width 0.1)
				(type default)
			)
			(layer "B.Fab")
		)
		(fp_line
			(start 0.12065 -0.305054)
			(end 0.12065 -0.2794)
			(stroke
				(width 0.1)
				(type default)
			)
			(layer "B.Fab")
		)
		(fp_line
			(start -0.12065 -0.3048)
			(end -0.67945 -0.3048)
			(stroke
				(width 0.1)
				(type default)
			)
			(layer "B.Fab")
		)
		(fp_line
			(start -0.67945 -0.3048)
			(end -0.67945 0.3048)
			(stroke
				(width 0.1)
				(type default)
			)
			(layer "B.Fab")
		)
		(fp_line
			(start 0.12065 -0.2794)
			(end -0.12065 -0.2794)
			(stroke
				(width 0.1)
				(type default)
			)
			(layer "B.Fab")
		)
		(fp_line
			(start -0.12065 -0.2794)
			(end -0.12065 -0.3048)
			(stroke
				(width 0.1)
				(type default)
			)
			(layer "B.Fab")
		)
		(fp_line
			(start 0.12065 0.2794)
			(end 0.12065 0.3048)
			(stroke
				(width 0.1)
				(type default)
			)
			(layer "B.Fab")
		)
		(fp_line
			(start -0.120396 0.2794)
			(end 0.12065 0.2794)
			(stroke
				(width 0.1)
				(type default)
			)
			(layer "B.Fab")
		)
		(fp_line
			(start 0.67945 0.3048)
			(end 0.67945 -0.305054)
			(stroke
				(width 0.1)
				(type default)
			)
			(layer "B.Fab")
		)
		(fp_line
			(start 0.12065 0.3048)
			(end 0.67945 0.3048)
			(stroke
				(width 0.1)
				(type default)
			)
			(layer "B.Fab")
		)
		(fp_line
			(start -0.120396 0.3048)
			(end -0.120396 0.2794)
			(stroke
				(width 0.1)
				(type default)
			)
			(layer "B.Fab")
		)
		(fp_line
			(start -0.67945 0.3048)
			(end -0.120396 0.3048)
			(stroke
				(width 0.1)
				(type default)
			)
			(layer "B.Fab")
		)
		(pad "1" smd circle
			(at 0.40005 0 270)
			(size 0 0)
			(layers "B.Cu" "B.Mask" "B.Paste")
			(net "PVDDCR_CPU1_P0")
		)
		(pad "2" smd circle
			(at -0.40005 0 270)
			(size 0 0)
			(layers "B.Cu" "B.Mask" "B.Paste")
			(net "GND")
		)
	)
	(footprint ""
		(layer "B.Cu")
		(at 77.973682 -328.24547 -90)
		(property "Reference" "PC388"
			(at 9.98347 -1.374648 270)
			(unlocked yes)
			(layer "B.SilkS")
			(effects
				(font
					(size 0.7874 0.5842)
					(thickness 0.1524)
				)
				(justify left mirror)
			)
		)
		(property "Value" ""
			(at 0 0 90)
			(layer "B.Fab")
			(effects
				(font
					(size 1.27 1.27)
				)
				(justify mirror)
			)
		)
		(duplicate_pad_numbers_are_jumpers no)
		(fp_line
			(start -4.533392 2.249932)
			(end 4.533392 2.249932)
			(stroke
				(width 0.1524)
				(type default)
			)
			(layer "B.SilkS")
		)
		(fp_line
			(start 4.533392 2.249932)
			(end 4.533392 -2.249932)
			(stroke
				(width 0.1524)
				(type default)
			)
			(layer "B.SilkS")
		)
		(fp_line
			(start -4.533392 -2.249932)
			(end -4.533392 2.249932)
			(stroke
				(width 0.1524)
				(type default)
			)
			(layer "B.SilkS")
		)
		(fp_line
			(start 4.533392 -2.249932)
			(end -4.533392 -2.249932)
			(stroke
				(width 0.1524)
				(type default)
			)
			(layer "B.SilkS")
		)
		(fp_rect
			(start 5.39242 2.326132)
			(end 4.533392 -2.326132)
			(stroke
				(width 0)
				(type default)
			)
			(fill yes)
			(layer "B.SilkS")
		)
		(fp_line
			(start -3.750056 2.249932)
			(end 3.750056 2.249932)
			(stroke
				(width 0.1)
				(type default)
			)
			(layer "B.Fab")
		)
		(fp_line
			(start 3.750056 2.249932)
			(end 3.750056 -2.249932)
			(stroke
				(width 0.1)
				(type default)
			)
			(layer "B.Fab")
		)
		(fp_line
			(start -3.750056 -2.249932)
			(end -3.750056 2.249932)
			(stroke
				(width 0.1)
				(type default)
			)
			(layer "B.Fab")
		)
		(fp_line
			(start 3.750056 -2.249932)
			(end -3.750056 -2.249932)
			(stroke
				(width 0.1)
				(type default)
			)
			(layer "B.Fab")
		)
		(fp_text user "-"
			(at -4.712462 1.477264 270)
			(unlocked yes)
			(layer "B.SilkS")
			(effects
				(font
					(size 1.905 1.4224)
					(thickness 0.1524)
				)
				(justify left mirror)
			)
		)
		(fp_text user "+"
			(at 6.265418 0.05207 180)
			(unlocked yes)
			(layer "B.SilkS")
			(effects
				(font
					(size 1.905 1.4224)
					(thickness 0.1524)
				)
				(justify left mirror)
			)
		)
		(fp_text user "+"
			(at 6.322314 0.786384 180)
			(unlocked yes)
			(layer "B.Fab")
			(effects
				(font
					(size 1.905 1.4224)
					(thickness 0.1524)
				)
				(justify left mirror)
			)
		)
		(fp_text user "-"
			(at -4.8514 -0.14605 270)
			(unlocked yes)
			(layer "B.Fab")
			(effects
				(font
					(size 1.905 1.4224)
					(thickness 0.1524)
				)
				(justify left mirror)
			)
		)
		(pad "1" smd rect
			(at 3.199892 0 90)
			(size 2.413 2.8194)
			(layers "B.Cu" "B.Mask" "B.Paste")
			(net "PVDDCR_CPU1_P1")
		)
		(pad "2" smd rect
			(at -3.199892 0 90)
			(size 2.413 2.8194)
			(layers "B.Cu" "B.Mask" "B.Paste")
			(net "GND")
		)
	)
	(footprint ""
		(layer "B.Cu")
		(at 403.981158 -329.003152)
		(property "Reference" "R748"
			(at 0 0 0)
			(layer "B.SilkS")
			(hide yes)
			(effects
				(font
					(size 1.27 1.27)
				)
				(justify mirror)
			)
		)
		(property "Value" ""
			(at 0 0 0)
			(layer "B.Fab")
			(effects
				(font
					(size 1.27 1.27)
				)
				(justify mirror)
			)
		)
		(duplicate_pad_numbers_are_jumpers no)
		(fp_line
			(start -0.7874 -0.4064)
			(end -0.7874 0.4064)
			(stroke
				(width 0.1524)
				(type default)
			)
			(layer "B.SilkS")
		)
		(fp_line
			(start -0.7874 0.4064)
			(end 0.7874 0.4064)
			(stroke
				(width 0.1524)
				(type default)
			)
			(layer "B.SilkS")
		)
		(fp_line
			(start 0.7874 -0.4064)
			(end -0.7874 -0.4064)
			(stroke
				(width 0.1524)
				(type default)
			)
			(layer "B.SilkS")
		)
		(fp_line
			(start 0.7874 0.4064)
			(end 0.7874 -0.4064)
			(stroke
				(width 0.1524)
				(type default)
			)
			(layer "B.SilkS")
		)
		(fp_line
			(start -0.67945 -0.3048)
			(end -0.67945 0.3048)
			(stroke
				(width 0.1)
				(type default)
			)
			(layer "B.Fab")
		)
		(fp_line
			(start -0.67945 0.3048)
			(end -0.120396 0.3048)
			(stroke
				(width 0.1)
				(type default)
			)
			(layer "B.Fab")
		)
		(fp_line
			(start -0.12065 -0.3048)
			(end -0.67945 -0.3048)
			(stroke
				(width 0.1)
				(type default)
			)
			(layer "B.Fab")
		)
		(fp_line
			(start -0.12065 -0.2794)
			(end -0.12065 -0.3048)
			(stroke
				(width 0.1)
				(type default)
			)
			(layer "B.Fab")
		)
		(fp_line
			(start -0.120396 0.2794)
			(end 0.12065 0.2794)
			(stroke
				(width 0.1)
				(type default)
			)
			(layer "B.Fab")
		)
		(fp_line
			(start -0.120396 0.3048)
			(end -0.120396 0.2794)
			(stroke
				(width 0.1)
				(type default)
			)
			(layer "B.Fab")
		)
		(fp_line
			(start 0.12065 -0.305054)
			(end 0.12065 -0.2794)
			(stroke
				(width 0.1)
				(type default)
			)
			(layer "B.Fab")
		)
		(fp_line
			(start 0.12065 -0.2794)
			(end -0.12065 -0.2794)
			(stroke
				(width 0.1)
				(type default)
			)
			(layer "B.Fab")
		)
		(fp_line
			(start 0.12065 0.2794)
			(end 0.12065 0.3048)
			(stroke
				(width 0.1)
				(type default)
			)
			(layer "B.Fab")
		)
		(fp_line
			(start 0.12065 0.3048)
			(end 0.67945 0.3048)
			(stroke
				(width 0.1)
				(type default)
			)
			(layer "B.Fab")
		)
		(fp_line
			(start 0.67945 -0.305054)
			(end 0.12065 -0.305054)
			(stroke
				(width 0.1)
				(type default)
			)
			(layer "B.Fab")
		)
		(fp_line
			(start 0.67945 0.3048)
			(end 0.67945 -0.305054)
			(stroke
				(width 0.1)
				(type default)
			)
			(layer "B.Fab")
		)
		(pad "1" smd circle
			(at 0.40005 0 180)
			(size 0 0)
			(layers "B.Cu" "B.Mask" "B.Paste")
			(net "GND")
		)
		(pad "2" smd circle
			(at -0.40005 0 180)
			(size 0 0)
			(layers "B.Cu" "B.Mask" "B.Paste")
			(net "CPU0_ROM_TYPE_SELECT")
		)
	)
	(footprint ""
		(layer "B.Cu")
		(at 364.167166 -261.747762 90)
		(property "Reference" "C3891"
			(at 0 0 90)
			(layer "B.SilkS")
			(hide yes)
			(effects
				(font
					(size 1.27 1.27)
				)
				(justify mirror)
			)
		)
		(property "Value" ""
			(at 0 0 90)
			(layer "B.Fab")
			(effects
				(font
					(size 1.27 1.27)
				)
				(justify mirror)
			)
		)
		(duplicate_pad_numbers_are_jumpers no)
		(fp_line
			(start 0.7874 -0.4064)
			(end -0.7874 -0.4064)
			(stroke
				(width 0.1524)
				(type default)
			)
			(layer "B.SilkS")
		)
		(fp_line
			(start -0.7874 -0.4064)
			(end -0.7874 0.4064)
			(stroke
				(width 0.1524)
				(type default)
			)
			(layer "B.SilkS")
		)
		(fp_line
			(start 0.7874 0.4064)
			(end 0.7874 -0.4064)
			(stroke
				(width 0.1524)
				(type default)
			)
			(layer "B.SilkS")
		)
		(fp_line
			(start -0.7874 0.4064)
			(end 0.7874 0.4064)
			(stroke
				(width 0.1524)
				(type default)
			)
			(layer "B.SilkS")
		)
		(fp_line
			(start 0.67945 -0.305054)
			(end 0.12065 -0.305054)
			(stroke
				(width 0.1)
				(type default)
			)
			(layer "B.Fab")
		)
		(fp_line
			(start 0.12065 -0.305054)
			(end 0.12065 -0.2794)
			(stroke
				(width 0.1)
				(type default)
			)
			(layer "B.Fab")
		)
		(fp_line
			(start -0.12065 -0.3048)
			(end -0.67945 -0.3048)
			(stroke
				(width 0.1)
				(type default)
			)
			(layer "B.Fab")
		)
		(fp_line
			(start -0.67945 -0.3048)
			(end -0.67945 0.3048)
			(stroke
				(width 0.1)
				(type default)
			)
			(layer "B.Fab")
		)
		(fp_line
			(start 0.12065 -0.2794)
			(end -0.12065 -0.2794)
			(stroke
				(width 0.1)
				(type default)
			)
			(layer "B.Fab")
		)
		(fp_line
			(start -0.12065 -0.2794)
			(end -0.12065 -0.3048)
			(stroke
				(width 0.1)
				(type default)
			)
			(layer "B.Fab")
		)
		(fp_line
			(start 0.12065 0.2794)
			(end 0.12065 0.3048)
			(stroke
				(width 0.1)
				(type default)
			)
			(layer "B.Fab")
		)
		(fp_line
			(start -0.120396 0.2794)
			(end 0.12065 0.2794)
			(stroke
				(width 0.1)
				(type default)
			)
			(layer "B.Fab")
		)
		(fp_line
			(start 0.67945 0.3048)
			(end 0.67945 -0.305054)
			(stroke
				(width 0.1)
				(type default)
			)
			(layer "B.Fab")
		)
		(fp_line
			(start 0.12065 0.3048)
			(end 0.67945 0.3048)
			(stroke
				(width 0.1)
				(type default)
			)
			(layer "B.Fab")
		)
		(fp_line
			(start -0.120396 0.3048)
			(end -0.120396 0.2794)
			(stroke
				(width 0.1)
				(type default)
			)
			(layer "B.Fab")
		)
		(fp_line
			(start -0.67945 0.3048)
			(end -0.120396 0.3048)
			(stroke
				(width 0.1)
				(type default)
			)
			(layer "B.Fab")
		)
		(pad "1" smd circle
			(at 0.40005 0 270)
			(size 0 0)
			(layers "B.Cu" "B.Mask" "B.Paste")
			(net "PVDD11_S3_P0")
		)
		(pad "2" smd circle
			(at -0.40005 0 270)
			(size 0 0)
			(layers "B.Cu" "B.Mask" "B.Paste")
			(net "GND")
		)
	)
	(footprint ""
		(layer "B.Cu")
		(at 336.827876 -66.708782 90)
		(property "Reference" "R3093"
			(at 0 0 90)
			(layer "B.SilkS")
			(hide yes)
			(effects
				(font
					(size 1.27 1.27)
				)
				(justify mirror)
			)
		)
		(property "Value" ""
			(at 0 0 90)
			(layer "B.Fab")
			(effects
				(font
					(size 1.27 1.27)
				)
				(justify mirror)
			)
		)
		(duplicate_pad_numbers_are_jumpers no)
		(fp_line
			(start 0.7874 -0.4064)
			(end -0.7874 -0.4064)
			(stroke
				(width 0.1524)
				(type default)
			)
			(layer "B.SilkS")
		)
		(fp_line
			(start -0.7874 -0.4064)
			(end -0.7874 0.4064)
			(stroke
				(width 0.1524)
				(type default)
			)
			(layer "B.SilkS")
		)
		(fp_line
			(start 0.7874 0.4064)
			(end 0.7874 -0.4064)
			(stroke
				(width 0.1524)
				(type default)
			)
			(layer "B.SilkS")
		)
		(fp_line
			(start -0.7874 0.4064)
			(end 0.7874 0.4064)
			(stroke
				(width 0.1524)
				(type default)
			)
			(layer "B.SilkS")
		)
		(fp_line
			(start 0.67945 -0.305054)
			(end 0.12065 -0.305054)
			(stroke
				(width 0.1)
				(type default)
			)
			(layer "B.Fab")
		)
		(fp_line
			(start 0.12065 -0.305054)
			(end 0.12065 -0.2794)
			(stroke
				(width 0.1)
				(type default)
			)
			(layer "B.Fab")
		)
		(fp_line
			(start -0.12065 -0.3048)
			(end -0.67945 -0.3048)
			(stroke
				(width 0.1)
				(type default)
			)
			(layer "B.Fab")
		)
		(fp_line
			(start -0.67945 -0.3048)
			(end -0.67945 0.3048)
			(stroke
				(width 0.1)
				(type default)
			)
			(layer "B.Fab")
		)
		(fp_line
			(start 0.12065 -0.2794)
			(end -0.12065 -0.2794)
			(stroke
				(width 0.1)
				(type default)
			)
			(layer "B.Fab")
		)
		(fp_line
			(start -0.12065 -0.2794)
			(end -0.12065 -0.3048)
			(stroke
				(width 0.1)
				(type default)
			)
			(layer "B.Fab")
		)
		(fp_line
			(start 0.12065 0.2794)
			(end 0.12065 0.3048)
			(stroke
				(width 0.1)
				(type default)
			)
			(layer "B.Fab")
		)
		(fp_line
			(start -0.120396 0.2794)
			(end 0.12065 0.2794)
			(stroke
				(width 0.1)
				(type default)
			)
			(layer "B.Fab")
		)
		(fp_line
			(start 0.67945 0.3048)
			(end 0.67945 -0.305054)
			(stroke
				(width 0.1)
				(type default)
			)
			(layer "B.Fab")
		)
		(fp_line
			(start 0.12065 0.3048)
			(end 0.67945 0.3048)
			(stroke
				(width 0.1)
				(type default)
			)
			(layer "B.Fab")
		)
		(fp_line
			(start -0.120396 0.3048)
			(end -0.120396 0.2794)
			(stroke
				(width 0.1)
				(type default)
			)
			(layer "B.Fab")
		)
		(fp_line
			(start -0.67945 0.3048)
			(end -0.120396 0.3048)
			(stroke
				(width 0.1)
				(type default)
			)
			(layer "B.Fab")
		)
		(pad "1" smd circle
			(at 0.40005 0 270)
			(size 0 0)
			(layers "B.Cu" "B.Mask" "B.Paste")
			(net "LED_PWRGD_PVDDCR_CPU0_P1_R")
		)
		(pad "2" smd circle
			(at -0.40005 0 270)
			(size 0 0)
			(layers "B.Cu" "B.Mask" "B.Paste")
			(net "P3V3_AUX")
		)
	)
	(footprint ""
		(layer "B.Cu")
		(at 162.606228 -386.766562 90)
		(property "Reference" "C391"
			(at 0 0 90)
			(layer "B.SilkS")
			(hide yes)
			(effects
				(font
					(size 1.27 1.27)
				)
				(justify mirror)
			)
		)
		(property "Value" ""
			(at 0 0 90)
			(layer "B.Fab")
			(effects
				(font
					(size 1.27 1.27)
				)
				(justify mirror)
			)
		)
		(duplicate_pad_numbers_are_jumpers no)
		(fp_line
			(start 0.299974 -0.150114)
			(end -0.299974 -0.150114)
			(stroke
				(width 0.1)
				(type default)
			)
			(layer "B.Fab")
		)
		(fp_line
			(start -0.299974 -0.150114)
			(end -0.299974 0.150114)
			(stroke
				(width 0.1)
				(type default)
			)
			(layer "B.Fab")
		)
		(fp_line
			(start 0.299974 0.150114)
			(end 0.299974 -0.150114)
			(stroke
				(width 0.1)
				(type default)
			)
			(layer "B.Fab")
		)
		(fp_line
			(start -0.299974 0.150114)
			(end 0.299974 0.150114)
			(stroke
				(width 0.1)
				(type default)
			)
			(layer "B.Fab")
		)
		(pad "1" smd rect
			(at 0.2667 0 270)
			(size 0.3048 0.381)
			(layers "B.Cu" "B.Mask" "B.Paste")
			(net "P0V9_CPU1_RT2_2A")
		)
		(pad "2" smd rect
			(at -0.2667 0 270)
			(size 0.3048 0.381)
			(layers "B.Cu" "B.Mask" "B.Paste")
			(net "GND")
		)
	)
	(footprint ""
		(layer "B.Cu")
		(at 281.391614 -193.99631)
		(property "Reference" "R92"
			(at 0 0 0)
			(layer "B.SilkS")
			(hide yes)
			(effects
				(font
					(size 1.27 1.27)
				)
				(justify mirror)
			)
		)
		(property "Value" ""
			(at 0 0 0)
			(layer "B.Fab")
			(effects
				(font
					(size 1.27 1.27)
				)
				(justify mirror)
			)
		)
		(duplicate_pad_numbers_are_jumpers no)
		(fp_line
			(start -0.7874 -0.4064)
			(end -0.7874 0.4064)
			(stroke
				(width 0.1524)
				(type default)
			)
			(layer "B.SilkS")
		)
		(fp_line
			(start -0.7874 0.4064)
			(end 0.7874 0.4064)
			(stroke
				(width 0.1524)
				(type default)
			)
			(layer "B.SilkS")
		)
		(fp_line
			(start 0.7874 -0.4064)
			(end -0.7874 -0.4064)
			(stroke
				(width 0.1524)
				(type default)
			)
			(layer "B.SilkS")
		)
		(fp_line
			(start 0.7874 0.4064)
			(end 0.7874 -0.4064)
			(stroke
				(width 0.1524)
				(type default)
			)
			(layer "B.SilkS")
		)
		(fp_line
			(start -0.67945 -0.3048)
			(end -0.67945 0.3048)
			(stroke
				(width 0.1)
				(type default)
			)
			(layer "B.Fab")
		)
		(fp_line
			(start -0.67945 0.3048)
			(end -0.120396 0.3048)
			(stroke
				(width 0.1)
				(type default)
			)
			(layer "B.Fab")
		)
		(fp_line
			(start -0.12065 -0.3048)
			(end -0.67945 -0.3048)
			(stroke
				(width 0.1)
				(type default)
			)
			(layer "B.Fab")
		)
		(fp_line
			(start -0.12065 -0.2794)
			(end -0.12065 -0.3048)
			(stroke
				(width 0.1)
				(type default)
			)
			(layer "B.Fab")
		)
		(fp_line
			(start -0.120396 0.2794)
			(end 0.12065 0.2794)
			(stroke
				(width 0.1)
				(type default)
			)
			(layer "B.Fab")
		)
		(fp_line
			(start -0.120396 0.3048)
			(end -0.120396 0.2794)
			(stroke
				(width 0.1)
				(type default)
			)
			(layer "B.Fab")
		)
		(fp_line
			(start 0.12065 -0.305054)
			(end 0.12065 -0.2794)
			(stroke
				(width 0.1)
				(type default)
			)
			(layer "B.Fab")
		)
		(fp_line
			(start 0.12065 -0.2794)
			(end -0.12065 -0.2794)
			(stroke
				(width 0.1)
				(type default)
			)
			(layer "B.Fab")
		)
		(fp_line
			(start 0.12065 0.2794)
			(end 0.12065 0.3048)
			(stroke
				(width 0.1)
				(type default)
			)
			(layer "B.Fab")
		)
		(fp_line
			(start 0.12065 0.3048)
			(end 0.67945 0.3048)
			(stroke
				(width 0.1)
				(type default)
			)
			(layer "B.Fab")
		)
		(fp_line
			(start 0.67945 -0.305054)
			(end 0.12065 -0.305054)
			(stroke
				(width 0.1)
				(type default)
			)
			(layer "B.Fab")
		)
		(fp_line
			(start 0.67945 0.3048)
			(end 0.67945 -0.305054)
			(stroke
				(width 0.1)
				(type default)
			)
			(layer "B.Fab")
		)
		(pad "1" smd circle
			(at 0.40005 0 180)
			(size 0 0)
			(layers "B.Cu" "B.Mask" "B.Paste")
			(net "P3V3")
		)
		(pad "2" smd circle
			(at -0.40005 0 180)
			(size 0 0)
			(layers "B.Cu" "B.Mask" "B.Paste")
			(net "PWRGD_CHD_CPU0_DIMM")
		)
	)
	(footprint ""
		(layer "B.Cu")
		(at 62.996318 -346.788994 90)
		(property "Reference" "PC409_4"
			(at 0 0 90)
			(layer "B.SilkS")
			(hide yes)
			(effects
				(font
					(size 1.27 1.27)
				)
				(justify mirror)
			)
		)
		(property "Value" ""
			(at 0 0 90)
			(layer "B.Fab")
			(effects
				(font
					(size 1.27 1.27)
				)
				(justify mirror)
			)
		)
		(duplicate_pad_numbers_are_jumpers no)
		(fp_line
			(start 1.524 -0.762)
			(end -1.524 -0.762)
			(stroke
				(width 0.1524)
				(type default)
			)
			(layer "B.SilkS")
		)
		(fp_line
			(start -1.524 -0.762)
			(end -1.524 0.762)
			(stroke
				(width 0.1524)
				(type default)
			)
			(layer "B.SilkS")
		)
		(fp_line
			(start 1.524 0.762)
			(end 1.524 -0.762)
			(stroke
				(width 0.1524)
				(type default)
			)
			(layer "B.SilkS")
		)
		(fp_line
			(start -1.524 0.762)
			(end 1.524 0.762)
			(stroke
				(width 0.1524)
				(type default)
			)
			(layer "B.SilkS")
		)
		(fp_line
			(start 1.1049 -0.724916)
			(end 1.1049 0.724916)
			(stroke
				(width 0.1)
				(type default)
			)
			(layer "B.Fab")
		)
		(fp_line
			(start -1.1049 -0.724916)
			(end 1.1049 -0.724916)
			(stroke
				(width 0.1)
				(type default)
			)
			(layer "B.Fab")
		)
		(fp_line
			(start 1.1049 0.724916)
			(end -1.1049 0.724916)
			(stroke
				(width 0.1)
				(type default)
			)
			(layer "B.Fab")
		)
		(fp_line
			(start -1.1049 0.724916)
			(end -1.1049 -0.724916)
			(stroke
				(width 0.1)
				(type default)
			)
			(layer "B.Fab")
		)
		(pad "1" smd rect
			(at 0.889 0 90)
			(size 1.016 1.27)
			(layers "B.Cu" "B.Mask" "B.Paste")
			(net "SW_P12V_AUX_PVDDCR_CPU1_P1_FLT")
		)
		(pad "2" smd rect
			(at -0.889 0 90)
			(size 1.016 1.27)
			(layers "B.Cu" "B.Mask" "B.Paste")
			(net "GND")
		)
	)
	(footprint ""
		(layer "B.Cu")
		(at 134.779766 -408.517344 90)
		(property "Reference" "C6738"
			(at 0 0 90)
			(layer "B.SilkS")
			(hide yes)
			(effects
				(font
					(size 1.27 1.27)
				)
				(justify mirror)
			)
		)
		(property "Value" ""
			(at 0 0 90)
			(layer "B.Fab")
			(effects
				(font
					(size 1.27 1.27)
				)
				(justify mirror)
			)
		)
		(duplicate_pad_numbers_are_jumpers no)
		(fp_line
			(start 0.299974 -0.150114)
			(end -0.299974 -0.150114)
			(stroke
				(width 0.1)
				(type default)
			)
			(layer "B.Fab")
		)
		(fp_line
			(start -0.299974 -0.150114)
			(end -0.299974 0.150114)
			(stroke
				(width 0.1)
				(type default)
			)
			(layer "B.Fab")
		)
		(fp_line
			(start 0.299974 0.150114)
			(end 0.299974 -0.150114)
			(stroke
				(width 0.1)
				(type default)
			)
			(layer "B.Fab")
		)
		(fp_line
			(start -0.299974 0.150114)
			(end 0.299974 0.150114)
			(stroke
				(width 0.1)
				(type default)
			)
			(layer "B.Fab")
		)
		(pad "1" smd rect
			(at 0.2667 0 270)
			(size 0.3048 0.381)
			(layers "B.Cu" "B.Mask" "B.Paste")
			(net "P5E_CPU1_P3_TX_BUF_C_DN<6>")
		)
		(pad "2" smd rect
			(at -0.2667 0 270)
			(size 0.3048 0.381)
			(layers "B.Cu" "B.Mask" "B.Paste")
			(net "P5E_CPU1_P3_TX_BUF_DN<6>")
		)
	)
	(footprint ""
		(layer "B.Cu")
		(at 277.192232 -192.660016)
		(property "Reference" "C151"
			(at 0 0 0)
			(layer "B.SilkS")
			(hide yes)
			(effects
				(font
					(size 1.27 1.27)
				)
				(justify mirror)
			)
		)
		(property "Value" ""
			(at 0 0 0)
			(layer "B.Fab")
			(effects
				(font
					(size 1.27 1.27)
				)
				(justify mirror)
			)
		)
		(duplicate_pad_numbers_are_jumpers no)
		(fp_line
			(start -1.524 -0.762)
			(end -1.524 0.762)
			(stroke
				(width 0.1524)
				(type default)
			)
			(layer "B.SilkS")
		)
		(fp_line
			(start -1.524 0.762)
			(end 1.524 0.762)
			(stroke
				(width 0.1524)
				(type default)
			)
			(layer "B.SilkS")
		)
		(fp_line
			(start 1.524 -0.762)
			(end -1.524 -0.762)
			(stroke
				(width 0.1524)
				(type default)
			)
			(layer "B.SilkS")
		)
		(fp_line
			(start 1.524 0.762)
			(end 1.524 -0.762)
			(stroke
				(width 0.1524)
				(type default)
			)
			(layer "B.SilkS")
		)
		(fp_line
			(start -1.1049 -0.724916)
			(end 1.1049 -0.724916)
			(stroke
				(width 0.1)
				(type default)
			)
			(layer "B.Fab")
		)
		(fp_line
			(start -1.1049 0.724916)
			(end -1.1049 -0.724916)
			(stroke
				(width 0.1)
				(type default)
			)
			(layer "B.Fab")
		)
		(fp_line
			(start 1.1049 -0.724916)
			(end 1.1049 0.724916)
			(stroke
				(width 0.1)
				(type default)
			)
			(layer "B.Fab")
		)
		(fp_line
			(start 1.1049 0.724916)
			(end -1.1049 0.724916)
			(stroke
				(width 0.1)
				(type default)
			)
			(layer "B.Fab")
		)
		(pad "1" smd rect
			(at 0.889 0)
			(size 1.016 1.27)
			(layers "B.Cu" "B.Mask" "B.Paste")
			(net "P12V_MEM_CPU0")
		)
		(pad "2" smd rect
			(at -0.889 0)
			(size 1.016 1.27)
			(layers "B.Cu" "B.Mask" "B.Paste")
			(net "GND")
		)
	)
	(footprint ""
		(layer "B.Cu")
		(at 230.886 -331.724 180)
		(property "Reference" "R6780"
			(at 0 0 0)
			(layer "B.SilkS")
			(hide yes)
			(effects
				(font
					(size 1.27 1.27)
				)
				(justify mirror)
			)
		)
		(property "Value" ""
			(at 0 0 0)
			(layer "B.Fab")
			(effects
				(font
					(size 1.27 1.27)
				)
				(justify mirror)
			)
		)
		(duplicate_pad_numbers_are_jumpers no)
		(fp_line
			(start 0.32512 0.175006)
			(end 0.32512 -0.175006)
			(stroke
				(width 0.1)
				(type default)
			)
			(layer "B.Fab")
		)
		(fp_line
			(start 0.32512 -0.175006)
			(end -0.32512 -0.175006)
			(stroke
				(width 0.1)
				(type default)
			)
			(layer "B.Fab")
		)
		(fp_line
			(start -0.32512 0.175006)
			(end 0.32512 0.175006)
			(stroke
				(width 0.1)
				(type default)
			)
			(layer "B.Fab")
		)
		(fp_line
			(start -0.32512 -0.175006)
			(end -0.32512 0.175006)
			(stroke
				(width 0.1)
				(type default)
			)
			(layer "B.Fab")
		)
		(pad "1" smd rect
			(at 0.2667 0)
			(size 0.3048 0.381)
			(layers "B.Cu" "B.Mask" "B.Paste")
			(net "SMB_MUX_RT_SCL")
		)
		(pad "2" smd rect
			(at -0.2667 0 180)
			(size 0.3048 0.381)
			(layers "B.Cu" "B.Mask" "B.Paste")
			(net "SMB_MUX_RT_R1_SCL")
		)
	)
	(footprint ""
		(layer "B.Cu")
		(at 89.122504 -408.517344 90)
		(property "Reference" "C6688"
			(at 0 0 90)
			(layer "B.SilkS")
			(hide yes)
			(effects
				(font
					(size 1.27 1.27)
				)
				(justify mirror)
			)
		)
		(property "Value" ""
			(at 0 0 90)
			(layer "B.Fab")
			(effects
				(font
					(size 1.27 1.27)
				)
				(justify mirror)
			)
		)
		(duplicate_pad_numbers_are_jumpers no)
		(fp_line
			(start 0.299974 -0.150114)
			(end -0.299974 -0.150114)
			(stroke
				(width 0.1)
				(type default)
			)
			(layer "B.Fab")
		)
		(fp_line
			(start -0.299974 -0.150114)
			(end -0.299974 0.150114)
			(stroke
				(width 0.1)
				(type default)
			)
			(layer "B.Fab")
		)
		(fp_line
			(start 0.299974 0.150114)
			(end 0.299974 -0.150114)
			(stroke
				(width 0.1)
				(type default)
			)
			(layer "B.Fab")
		)
		(fp_line
			(start -0.299974 0.150114)
			(end 0.299974 0.150114)
			(stroke
				(width 0.1)
				(type default)
			)
			(layer "B.Fab")
		)
		(pad "1" smd rect
			(at 0.2667 0 270)
			(size 0.3048 0.381)
			(layers "B.Cu" "B.Mask" "B.Paste")
			(net "P5E_CPU1_P1_TX_BUF_C_DN<13>")
		)
		(pad "2" smd rect
			(at -0.2667 0 270)
			(size 0.3048 0.381)
			(layers "B.Cu" "B.Mask" "B.Paste")
			(net "P5E_CPU1_P1_TX_BUF_DN<13>")
		)
	)
	(footprint ""
		(layer "B.Cu")
		(at 356.29596 -259.845048 180)
		(property "Reference" "C2131"
			(at 0 0 0)
			(layer "B.SilkS")
			(hide yes)
			(effects
				(font
					(size 1.27 1.27)
				)
				(justify mirror)
			)
		)
		(property "Value" ""
			(at 0 0 0)
			(layer "B.Fab")
			(effects
				(font
					(size 1.27 1.27)
				)
				(justify mirror)
			)
		)
		(duplicate_pad_numbers_are_jumpers no)
		(fp_line
			(start 0.7874 0.4064)
			(end 0.7874 -0.4064)
			(stroke
				(width 0.1524)
				(type default)
			)
			(layer "B.SilkS")
		)
		(fp_line
			(start 0.7874 -0.4064)
			(end -0.7874 -0.4064)
			(stroke
				(width 0.1524)
				(type default)
			)
			(layer "B.SilkS")
		)
		(fp_line
			(start -0.7874 0.4064)
			(end 0.7874 0.4064)
			(stroke
				(width 0.1524)
				(type default)
			)
			(layer "B.SilkS")
		)
		(fp_line
			(start -0.7874 -0.4064)
			(end -0.7874 0.4064)
			(stroke
				(width 0.1524)
				(type default)
			)
			(layer "B.SilkS")
		)
		(fp_line
			(start 0.67945 0.3048)
			(end 0.67945 -0.305054)
			(stroke
				(width 0.1)
				(type default)
			)
			(layer "B.Fab")
		)
		(fp_line
			(start 0.67945 -0.305054)
			(end 0.12065 -0.305054)
			(stroke
				(width 0.1)
				(type default)
			)
			(layer "B.Fab")
		)
		(fp_line
			(start 0.12065 0.3048)
			(end 0.67945 0.3048)
			(stroke
				(width 0.1)
				(type default)
			)
			(layer "B.Fab")
		)
		(fp_line
			(start 0.12065 0.2794)
			(end 0.12065 0.3048)
			(stroke
				(width 0.1)
				(type default)
			)
			(layer "B.Fab")
		)
		(fp_line
			(start 0.12065 -0.2794)
			(end -0.12065 -0.2794)
			(stroke
				(width 0.1)
				(type default)
			)
			(layer "B.Fab")
		)
		(fp_line
			(start 0.12065 -0.305054)
			(end 0.12065 -0.2794)
			(stroke
				(width 0.1)
				(type default)
			)
			(layer "B.Fab")
		)
		(fp_line
			(start -0.120396 0.3048)
			(end -0.120396 0.2794)
			(stroke
				(width 0.1)
				(type default)
			)
			(layer "B.Fab")
		)
		(fp_line
			(start -0.120396 0.2794)
			(end 0.12065 0.2794)
			(stroke
				(width 0.1)
				(type default)
			)
			(layer "B.Fab")
		)
		(fp_line
			(start -0.12065 -0.2794)
			(end -0.12065 -0.3048)
			(stroke
				(width 0.1)
				(type default)
			)
			(layer "B.Fab")
		)
		(fp_line
			(start -0.12065 -0.3048)
			(end -0.67945 -0.3048)
			(stroke
				(width 0.1)
				(type default)
			)
			(layer "B.Fab")
		)
		(fp_line
			(start -0.67945 0.3048)
			(end -0.120396 0.3048)
			(stroke
				(width 0.1)
				(type default)
			)
			(layer "B.Fab")
		)
		(fp_line
			(start -0.67945 -0.3048)
			(end -0.67945 0.3048)
			(stroke
				(width 0.1)
				(type default)
			)
			(layer "B.Fab")
		)
		(pad "1" smd circle
			(at 0.40005 0)
			(size 0 0)
			(layers "B.Cu" "B.Mask" "B.Paste")
			(net "PVDDIO_P0")
		)
		(pad "2" smd circle
			(at -0.40005 0)
			(size 0 0)
			(layers "B.Cu" "B.Mask" "B.Paste")
			(net "GND")
		)
	)
	(footprint ""
		(layer "B.Cu")
		(at 354.818696 -165.72992 90)
		(property "Reference" "PC571_5"
			(at 0 0 90)
			(layer "B.SilkS")
			(hide yes)
			(effects
				(font
					(size 1.27 1.27)
				)
				(justify mirror)
			)
		)
		(property "Value" ""
			(at 0 0 90)
			(layer "B.Fab")
			(effects
				(font
					(size 1.27 1.27)
				)
				(justify mirror)
			)
		)
		(duplicate_pad_numbers_are_jumpers no)
		(fp_line
			(start 1.524 -0.762)
			(end -1.524 -0.762)
			(stroke
				(width 0.1524)
				(type default)
			)
			(layer "B.SilkS")
		)
		(fp_line
			(start -1.524 -0.762)
			(end -1.524 0.762)
			(stroke
				(width 0.1524)
				(type default)
			)
			(layer "B.SilkS")
		)
		(fp_line
			(start 1.524 0.762)
			(end 1.524 -0.762)
			(stroke
				(width 0.1524)
				(type default)
			)
			(layer "B.SilkS")
		)
		(fp_line
			(start -1.524 0.762)
			(end 1.524 0.762)
			(stroke
				(width 0.1524)
				(type default)
			)
			(layer "B.SilkS")
		)
		(fp_line
			(start 1.1049 -0.724916)
			(end 1.1049 0.724916)
			(stroke
				(width 0.1)
				(type default)
			)
			(layer "B.Fab")
		)
		(fp_line
			(start -1.1049 -0.724916)
			(end 1.1049 -0.724916)
			(stroke
				(width 0.1)
				(type default)
			)
			(layer "B.Fab")
		)
		(fp_line
			(start 1.1049 0.724916)
			(end -1.1049 0.724916)
			(stroke
				(width 0.1)
				(type default)
			)
			(layer "B.Fab")
		)
		(fp_line
			(start -1.1049 0.724916)
			(end -1.1049 -0.724916)
			(stroke
				(width 0.1)
				(type default)
			)
			(layer "B.Fab")
		)
		(pad "1" smd rect
			(at 0.889 0 90)
			(size 1.016 1.27)
			(layers "B.Cu" "B.Mask" "B.Paste")
			(net "SW_P12V_AUX_PVDDCR_CPU0_P0_FLT")
		)
		(pad "2" smd rect
			(at -0.889 0 90)
			(size 1.016 1.27)
			(layers "B.Cu" "B.Mask" "B.Paste")
			(net "GND")
		)
	)
	(footprint ""
		(layer "B.Cu")
		(at 106.48823 -250.891294 180)
		(property "Reference" "C2327"
			(at 0 0 0)
			(layer "B.SilkS")
			(hide yes)
			(effects
				(font
					(size 1.27 1.27)
				)
				(justify mirror)
			)
		)
		(property "Value" ""
			(at 0 0 0)
			(layer "B.Fab")
			(effects
				(font
					(size 1.27 1.27)
				)
				(justify mirror)
			)
		)
		(duplicate_pad_numbers_are_jumpers no)
		(fp_line
			(start 0.7874 0.4064)
			(end 0.7874 -0.4064)
			(stroke
				(width 0.1524)
				(type default)
			)
			(layer "B.SilkS")
		)
		(fp_line
			(start 0.7874 -0.4064)
			(end -0.7874 -0.4064)
			(stroke
				(width 0.1524)
				(type default)
			)
			(layer "B.SilkS")
		)
		(fp_line
			(start -0.7874 0.4064)
			(end 0.7874 0.4064)
			(stroke
				(width 0.1524)
				(type default)
			)
			(layer "B.SilkS")
		)
		(fp_line
			(start -0.7874 -0.4064)
			(end -0.7874 0.4064)
			(stroke
				(width 0.1524)
				(type default)
			)
			(layer "B.SilkS")
		)
		(fp_line
			(start 0.67945 0.3048)
			(end 0.67945 -0.305054)
			(stroke
				(width 0.1)
				(type default)
			)
			(layer "B.Fab")
		)
		(fp_line
			(start 0.67945 -0.305054)
			(end 0.12065 -0.305054)
			(stroke
				(width 0.1)
				(type default)
			)
			(layer "B.Fab")
		)
		(fp_line
			(start 0.12065 0.3048)
			(end 0.67945 0.3048)
			(stroke
				(width 0.1)
				(type default)
			)
			(layer "B.Fab")
		)
		(fp_line
			(start 0.12065 0.2794)
			(end 0.12065 0.3048)
			(stroke
				(width 0.1)
				(type default)
			)
			(layer "B.Fab")
		)
		(fp_line
			(start 0.12065 -0.2794)
			(end -0.12065 -0.2794)
			(stroke
				(width 0.1)
				(type default)
			)
			(layer "B.Fab")
		)
		(fp_line
			(start 0.12065 -0.305054)
			(end 0.12065 -0.2794)
			(stroke
				(width 0.1)
				(type default)
			)
			(layer "B.Fab")
		)
		(fp_line
			(start -0.120396 0.3048)
			(end -0.120396 0.2794)
			(stroke
				(width 0.1)
				(type default)
			)
			(layer "B.Fab")
		)
		(fp_line
			(start -0.120396 0.2794)
			(end 0.12065 0.2794)
			(stroke
				(width 0.1)
				(type default)
			)
			(layer "B.Fab")
		)
		(fp_line
			(start -0.12065 -0.2794)
			(end -0.12065 -0.3048)
			(stroke
				(width 0.1)
				(type default)
			)
			(layer "B.Fab")
		)
		(fp_line
			(start -0.12065 -0.3048)
			(end -0.67945 -0.3048)
			(stroke
				(width 0.1)
				(type default)
			)
			(layer "B.Fab")
		)
		(fp_line
			(start -0.67945 0.3048)
			(end -0.120396 0.3048)
			(stroke
				(width 0.1)
				(type default)
			)
			(layer "B.Fab")
		)
		(fp_line
			(start -0.67945 -0.3048)
			(end -0.67945 0.3048)
			(stroke
				(width 0.1)
				(type default)
			)
			(layer "B.Fab")
		)
		(pad "1" smd circle
			(at 0.40005 0)
			(size 0 0)
			(layers "B.Cu" "B.Mask" "B.Paste")
			(net "PVDDCR_CPU0_P1")
		)
		(pad "2" smd circle
			(at -0.40005 0)
			(size 0 0)
			(layers "B.Cu" "B.Mask" "B.Paste")
			(net "GND")
		)
	)
	(footprint ""
		(layer "B.Cu")
		(at 113.451386 -246.447564 -60)
		(property "Reference" "C2342"
			(at 0 0 120)
			(layer "B.SilkS")
			(hide yes)
			(effects
				(font
					(size 1.27 1.27)
				)
				(justify mirror)
			)
		)
		(property "Value" ""
			(at 0 0 120)
			(layer "B.Fab")
			(effects
				(font
					(size 1.27 1.27)
				)
				(justify mirror)
			)
		)
		(duplicate_pad_numbers_are_jumpers no)
		(fp_line
			(start -0.787516 0.406438)
			(end 0.787425 0.40652)
			(stroke
				(width 0.1524)
				(type default)
			)
			(layer "B.SilkS")
		)
		(fp_line
			(start -0.787425 -0.40652)
			(end -0.787516 0.406438)
			(stroke
				(width 0.1524)
				(type default)
			)
			(layer "B.SilkS")
		)
		(fp_line
			(start 0.787425 0.40652)
			(end 0.787516 -0.406438)
			(stroke
				(width 0.1524)
				(type default)
			)
			(layer "B.SilkS")
		)
		(fp_line
			(start 0.787516 -0.406438)
			(end -0.787425 -0.40652)
			(stroke
				(width 0.1524)
				(type default)
			)
			(layer "B.SilkS")
		)
		(fp_line
			(start -0.679568 0.304811)
			(end -0.120258 0.304812)
			(stroke
				(width 0.1)
				(type default)
			)
			(layer "B.Fab")
		)
		(fp_line
			(start -0.120258 0.304812)
			(end -0.120334 0.279545)
			(stroke
				(width 0.1)
				(type default)
			)
			(layer "B.Fab")
		)
		(fp_line
			(start -0.120334 0.279545)
			(end 0.120587 0.279326)
			(stroke
				(width 0.1)
				(type default)
			)
			(layer "B.Fab")
		)
		(fp_line
			(start 0.120536 0.304813)
			(end 0.6795 0.304908)
			(stroke
				(width 0.1)
				(type default)
			)
			(layer "B.Fab")
		)
		(fp_line
			(start 0.120587 0.279326)
			(end 0.120536 0.304813)
			(stroke
				(width 0.1)
				(type default)
			)
			(layer "B.Fab")
		)
		(fp_line
			(start -0.6795 -0.304908)
			(end -0.679568 0.304811)
			(stroke
				(width 0.1)
				(type default)
			)
			(layer "B.Fab")
		)
		(fp_line
			(start 0.6795 0.304908)
			(end 0.679475 -0.305158)
			(stroke
				(width 0.1)
				(type default)
			)
			(layer "B.Fab")
		)
		(fp_line
			(start -0.120587 -0.279326)
			(end -0.120536 -0.304813)
			(stroke
				(width 0.1)
				(type default)
			)
			(layer "B.Fab")
		)
		(fp_line
			(start -0.120536 -0.304813)
			(end -0.6795 -0.304908)
			(stroke
				(width 0.1)
				(type default)
			)
			(layer "B.Fab")
		)
		(fp_line
			(start 0.120554 -0.279418)
			(end -0.120587 -0.279326)
			(stroke
				(width 0.1)
				(type default)
			)
			(layer "B.Fab")
		)
		(fp_line
			(start 0.120732 -0.305125)
			(end 0.120554 -0.279418)
			(stroke
				(width 0.1)
				(type default)
			)
			(layer "B.Fab")
		)
		(fp_line
			(start 0.679475 -0.305158)
			(end 0.120732 -0.305125)
			(stroke
				(width 0.1)
				(type default)
			)
			(layer "B.Fab")
		)
		(pad "1" smd circle
			(at 0.40005 0 120)
			(size 0 0)
			(layers "B.Cu" "B.Mask" "B.Paste")
			(net "PVDDCR_CPU0_P1")
		)
		(pad "2" smd circle
			(at -0.40005 0 120)
			(size 0 0)
			(layers "B.Cu" "B.Mask" "B.Paste")
			(net "GND")
		)
	)
	(footprint ""
		(layer "B.Cu")
		(at 20.480782 -412.850584 180)
		(property "Reference" "PR6802"
			(at 0 0 0)
			(layer "B.SilkS")
			(hide yes)
			(effects
				(font
					(size 1.27 1.27)
				)
				(justify mirror)
			)
		)
		(property "Value" ""
			(at 0 0 0)
			(layer "B.Fab")
			(effects
				(font
					(size 1.27 1.27)
				)
				(justify mirror)
			)
		)
		(duplicate_pad_numbers_are_jumpers no)
		(fp_line
			(start 0.7874 0.4064)
			(end 0.7874 -0.4064)
			(stroke
				(width 0.1524)
				(type default)
			)
			(layer "B.SilkS")
		)
		(fp_line
			(start 0.7874 -0.4064)
			(end -0.7874 -0.4064)
			(stroke
				(width 0.1524)
				(type default)
			)
			(layer "B.SilkS")
		)
		(fp_line
			(start -0.7874 0.4064)
			(end 0.7874 0.4064)
			(stroke
				(width 0.1524)
				(type default)
			)
			(layer "B.SilkS")
		)
		(fp_line
			(start -0.7874 -0.4064)
			(end -0.7874 0.4064)
			(stroke
				(width 0.1524)
				(type default)
			)
			(layer "B.SilkS")
		)
		(fp_line
			(start 0.67945 0.3048)
			(end 0.67945 -0.305054)
			(stroke
				(width 0.1)
				(type default)
			)
			(layer "B.Fab")
		)
		(fp_line
			(start 0.67945 -0.305054)
			(end 0.12065 -0.305054)
			(stroke
				(width 0.1)
				(type default)
			)
			(layer "B.Fab")
		)
		(fp_line
			(start 0.12065 0.3048)
			(end 0.67945 0.3048)
			(stroke
				(width 0.1)
				(type default)
			)
			(layer "B.Fab")
		)
		(fp_line
			(start 0.12065 0.2794)
			(end 0.12065 0.3048)
			(stroke
				(width 0.1)
				(type default)
			)
			(layer "B.Fab")
		)
		(fp_line
			(start 0.12065 -0.2794)
			(end -0.12065 -0.2794)
			(stroke
				(width 0.1)
				(type default)
			)
			(layer "B.Fab")
		)
		(fp_line
			(start 0.12065 -0.305054)
			(end 0.12065 -0.2794)
			(stroke
				(width 0.1)
				(type default)
			)
			(layer "B.Fab")
		)
		(fp_line
			(start -0.120396 0.3048)
			(end -0.120396 0.2794)
			(stroke
				(width 0.1)
				(type default)
			)
			(layer "B.Fab")
		)
		(fp_line
			(start -0.120396 0.2794)
			(end 0.12065 0.2794)
			(stroke
				(width 0.1)
				(type default)
			)
			(layer "B.Fab")
		)
		(fp_line
			(start -0.12065 -0.2794)
			(end -0.12065 -0.3048)
			(stroke
				(width 0.1)
				(type default)
			)
			(layer "B.Fab")
		)
		(fp_line
			(start -0.12065 -0.3048)
			(end -0.67945 -0.3048)
			(stroke
				(width 0.1)
				(type default)
			)
			(layer "B.Fab")
		)
		(fp_line
			(start -0.67945 0.3048)
			(end -0.120396 0.3048)
			(stroke
				(width 0.1)
				(type default)
			)
			(layer "B.Fab")
		)
		(fp_line
			(start -0.67945 -0.3048)
			(end -0.67945 0.3048)
			(stroke
				(width 0.1)
				(type default)
			)
			(layer "B.Fab")
		)
		(pad "1" smd circle
			(at 0.40005 0)
			(size 0 0)
			(layers "B.Cu" "B.Mask" "B.Paste")
			(net "TP_P0V9_RETIMER_CPU1_SVID_ALERT_N")
		)
		(pad "2" smd circle
			(at -0.40005 0)
			(size 0 0)
			(layers "B.Cu" "B.Mask" "B.Paste")
			(net "GND")
		)
	)
	(footprint ""
		(layer "B.Cu")
		(at 304.436018 -409.560014 90)
		(property "Reference" "PJ09_P0_N"
			(at 0 0 90)
			(layer "B.SilkS")
			(hide yes)
			(effects
				(font
					(size 1.27 1.27)
				)
				(justify mirror)
			)
		)
		(property "Value" ""
			(at 0 0 90)
			(layer "B.Fab")
			(effects
				(font
					(size 1.27 1.27)
				)
				(justify mirror)
			)
		)
		(duplicate_pad_numbers_are_jumpers no)
		(zone
			(layer "In11.Cu")
			(hatch none 0.5)
			(connect_pads
				(clearance 0)
			)
			(min_thickness 0.25)
			(keepout
				(tracks allowed)
				(vias not_allowed)
				(pads allowed)
				(copperpour not_allowed)
				(footprints allowed)
			)
			(placement
				(enabled no)
				(sheetname "")
			)
			(fill
				(thermal_gap 0.5)
				(thermal_bridge_width 0.5)
				(island_removal_mode 0)
			)
			(polygon
				(pts
					(xy 304.626518 -409.775914) (xy 304.626518 -409.344114) (xy 304.245518 -409.344114) (xy 304.245518 -409.775914)
				)
			)
		)
	)
	(footprint ""
		(layer "B.Cu")
		(at 77.94625 -387.05028)
		(property "Reference" "C301"
			(at 0 0 0)
			(layer "B.SilkS")
			(hide yes)
			(effects
				(font
					(size 1.27 1.27)
				)
				(justify mirror)
			)
		)
		(property "Value" ""
			(at 0 0 0)
			(layer "B.Fab")
			(effects
				(font
					(size 1.27 1.27)
				)
				(justify mirror)
			)
		)
		(duplicate_pad_numbers_are_jumpers no)
		(fp_line
			(start -0.299974 -0.150114)
			(end -0.299974 0.150114)
			(stroke
				(width 0.1)
				(type default)
			)
			(layer "B.Fab")
		)
		(fp_line
			(start -0.299974 0.150114)
			(end 0.299974 0.150114)
			(stroke
				(width 0.1)
				(type default)
			)
			(layer "B.Fab")
		)
		(fp_line
			(start 0.299974 -0.150114)
			(end -0.299974 -0.150114)
			(stroke
				(width 0.1)
				(type default)
			)
			(layer "B.Fab")
		)
		(fp_line
			(start 0.299974 0.150114)
			(end 0.299974 -0.150114)
			(stroke
				(width 0.1)
				(type default)
			)
			(layer "B.Fab")
		)
		(pad "1" smd rect
			(at 0.2667 0 180)
			(size 0.3048 0.381)
			(layers "B.Cu" "B.Mask" "B.Paste")
			(net "P0V9_CPU1_RT1_2A")
		)
		(pad "2" smd rect
			(at -0.2667 0 180)
			(size 0.3048 0.381)
			(layers "B.Cu" "B.Mask" "B.Paste")
			(net "GND")
		)
	)
	(footprint ""
		(layer "B.Cu")
		(at 128.18618 -37.09543 -90)
		(property "Reference" "C6062"
			(at 0 0 90)
			(layer "B.SilkS")
			(hide yes)
			(effects
				(font
					(size 1.27 1.27)
				)
				(justify mirror)
			)
		)
		(property "Value" ""
			(at 0 0 90)
			(layer "B.Fab")
			(effects
				(font
					(size 1.27 1.27)
				)
				(justify mirror)
			)
		)
		(duplicate_pad_numbers_are_jumpers no)
		(fp_line
			(start -0.7874 0.4064)
			(end 0.7874 0.4064)
			(stroke
				(width 0.1524)
				(type default)
			)
			(layer "B.SilkS")
		)
		(fp_line
			(start 0.7874 0.4064)
			(end 0.7874 -0.4064)
			(stroke
				(width 0.1524)
				(type default)
			)
			(layer "B.SilkS")
		)
		(fp_line
			(start -0.7874 -0.4064)
			(end -0.7874 0.4064)
			(stroke
				(width 0.1524)
				(type default)
			)
			(layer "B.SilkS")
		)
		(fp_line
			(start 0.7874 -0.4064)
			(end -0.7874 -0.4064)
			(stroke
				(width 0.1524)
				(type default)
			)
			(layer "B.SilkS")
		)
		(fp_line
			(start -0.67945 0.3048)
			(end -0.120396 0.3048)
			(stroke
				(width 0.1)
				(type default)
			)
			(layer "B.Fab")
		)
		(fp_line
			(start -0.120396 0.3048)
			(end -0.120396 0.2794)
			(stroke
				(width 0.1)
				(type default)
			)
			(layer "B.Fab")
		)
		(fp_line
			(start 0.12065 0.3048)
			(end 0.67945 0.3048)
			(stroke
				(width 0.1)
				(type default)
			)
			(layer "B.Fab")
		)
		(fp_line
			(start 0.67945 0.3048)
			(end 0.67945 -0.305054)
			(stroke
				(width 0.1)
				(type default)
			)
			(layer "B.Fab")
		)
		(fp_line
			(start -0.120396 0.2794)
			(end 0.12065 0.2794)
			(stroke
				(width 0.1)
				(type default)
			)
			(layer "B.Fab")
		)
		(fp_line
			(start 0.12065 0.2794)
			(end 0.12065 0.3048)
			(stroke
				(width 0.1)
				(type default)
			)
			(layer "B.Fab")
		)
		(fp_line
			(start -0.12065 -0.2794)
			(end -0.12065 -0.3048)
			(stroke
				(width 0.1)
				(type default)
			)
			(layer "B.Fab")
		)
		(fp_line
			(start 0.12065 -0.2794)
			(end -0.12065 -0.2794)
			(stroke
				(width 0.1)
				(type default)
			)
			(layer "B.Fab")
		)
		(fp_line
			(start -0.67945 -0.3048)
			(end -0.67945 0.3048)
			(stroke
				(width 0.1)
				(type default)
			)
			(layer "B.Fab")
		)
		(fp_line
			(start -0.12065 -0.3048)
			(end -0.67945 -0.3048)
			(stroke
				(width 0.1)
				(type default)
			)
			(layer "B.Fab")
		)
		(fp_line
			(start 0.12065 -0.305054)
			(end 0.12065 -0.2794)
			(stroke
				(width 0.1)
				(type default)
			)
			(layer "B.Fab")
		)
		(fp_line
			(start 0.67945 -0.305054)
			(end 0.12065 -0.305054)
			(stroke
				(width 0.1)
				(type default)
			)
			(layer "B.Fab")
		)
		(pad "1" smd circle
			(at 0.40005 0 90)
			(size 0 0)
			(layers "B.Cu" "B.Mask" "B.Paste")
			(net "P1V2_AUX")
		)
		(pad "2" smd circle
			(at -0.40005 0 90)
			(size 0 0)
			(layers "B.Cu" "B.Mask" "B.Paste")
			(net "GND")
		)
	)
	(footprint ""
		(layer "B.Cu")
		(at 28.50388 -402.540724 -90)
		(property "Reference" "PC6818"
			(at 0 0 90)
			(layer "B.SilkS")
			(hide yes)
			(effects
				(font
					(size 1.27 1.27)
				)
				(justify mirror)
			)
		)
		(property "Value" ""
			(at 0 0 90)
			(layer "B.Fab")
			(effects
				(font
					(size 1.27 1.27)
				)
				(justify mirror)
			)
		)
		(duplicate_pad_numbers_are_jumpers no)
		(fp_line
			(start -1.524 0.762)
			(end 1.524 0.762)
			(stroke
				(width 0.1524)
				(type default)
			)
			(layer "B.SilkS")
		)
		(fp_line
			(start 1.524 0.762)
			(end 1.524 -0.762)
			(stroke
				(width 0.1524)
				(type default)
			)
			(layer "B.SilkS")
		)
		(fp_line
			(start -1.524 -0.762)
			(end -1.524 0.762)
			(stroke
				(width 0.1524)
				(type default)
			)
			(layer "B.SilkS")
		)
		(fp_line
			(start 1.524 -0.762)
			(end -1.524 -0.762)
			(stroke
				(width 0.1524)
				(type default)
			)
			(layer "B.SilkS")
		)
		(fp_line
			(start -1.1049 0.724916)
			(end -1.1049 -0.724916)
			(stroke
				(width 0.1)
				(type default)
			)
			(layer "B.Fab")
		)
		(fp_line
			(start 1.1049 0.724916)
			(end -1.1049 0.724916)
			(stroke
				(width 0.1)
				(type default)
			)
			(layer "B.Fab")
		)
		(fp_line
			(start -1.1049 -0.724916)
			(end 1.1049 -0.724916)
			(stroke
				(width 0.1)
				(type default)
			)
			(layer "B.Fab")
		)
		(fp_line
			(start 1.1049 -0.724916)
			(end 1.1049 0.724916)
			(stroke
				(width 0.1)
				(type default)
			)
			(layer "B.Fab")
		)
		(pad "1" smd rect
			(at 0.889 0 270)
			(size 1.016 1.27)
			(layers "B.Cu" "B.Mask" "B.Paste")
			(net "SW_P12V_AUX_P0V9_RETIMER_CPU1_FLT")
		)
		(pad "2" smd rect
			(at -0.889 0 270)
			(size 1.016 1.27)
			(layers "B.Cu" "B.Mask" "B.Paste")
			(net "GND")
		)
	)
	(footprint ""
		(layer "B.Cu")
		(at 10.066782 -407.262584)
		(property "Reference" "PR6813"
			(at 0 0 0)
			(layer "B.SilkS")
			(hide yes)
			(effects
				(font
					(size 1.27 1.27)
				)
				(justify mirror)
			)
		)
		(property "Value" ""
			(at 0 0 0)
			(layer "B.Fab")
			(effects
				(font
					(size 1.27 1.27)
				)
				(justify mirror)
			)
		)
		(duplicate_pad_numbers_are_jumpers no)
		(fp_line
			(start -0.7874 -0.4064)
			(end -0.7874 0.4064)
			(stroke
				(width 0.1524)
				(type default)
			)
			(layer "B.SilkS")
		)
		(fp_line
			(start -0.7874 0.4064)
			(end 0.7874 0.4064)
			(stroke
				(width 0.1524)
				(type default)
			)
			(layer "B.SilkS")
		)
		(fp_line
			(start 0.7874 -0.4064)
			(end -0.7874 -0.4064)
			(stroke
				(width 0.1524)
				(type default)
			)
			(layer "B.SilkS")
		)
		(fp_line
			(start 0.7874 0.4064)
			(end 0.7874 -0.4064)
			(stroke
				(width 0.1524)
				(type default)
			)
			(layer "B.SilkS")
		)
		(fp_line
			(start -0.67945 -0.3048)
			(end -0.67945 0.3048)
			(stroke
				(width 0.1)
				(type default)
			)
			(layer "B.Fab")
		)
		(fp_line
			(start -0.67945 0.3048)
			(end -0.120396 0.3048)
			(stroke
				(width 0.1)
				(type default)
			)
			(layer "B.Fab")
		)
		(fp_line
			(start -0.12065 -0.3048)
			(end -0.67945 -0.3048)
			(stroke
				(width 0.1)
				(type default)
			)
			(layer "B.Fab")
		)
		(fp_line
			(start -0.12065 -0.2794)
			(end -0.12065 -0.3048)
			(stroke
				(width 0.1)
				(type default)
			)
			(layer "B.Fab")
		)
		(fp_line
			(start -0.120396 0.2794)
			(end 0.12065 0.2794)
			(stroke
				(width 0.1)
				(type default)
			)
			(layer "B.Fab")
		)
		(fp_line
			(start -0.120396 0.3048)
			(end -0.120396 0.2794)
			(stroke
				(width 0.1)
				(type default)
			)
			(layer "B.Fab")
		)
		(fp_line
			(start 0.12065 -0.305054)
			(end 0.12065 -0.2794)
			(stroke
				(width 0.1)
				(type default)
			)
			(layer "B.Fab")
		)
		(fp_line
			(start 0.12065 -0.2794)
			(end -0.12065 -0.2794)
			(stroke
				(width 0.1)
				(type default)
			)
			(layer "B.Fab")
		)
		(fp_line
			(start 0.12065 0.2794)
			(end 0.12065 0.3048)
			(stroke
				(width 0.1)
				(type default)
			)
			(layer "B.Fab")
		)
		(fp_line
			(start 0.12065 0.3048)
			(end 0.67945 0.3048)
			(stroke
				(width 0.1)
				(type default)
			)
			(layer "B.Fab")
		)
		(fp_line
			(start 0.67945 -0.305054)
			(end 0.12065 -0.305054)
			(stroke
				(width 0.1)
				(type default)
			)
			(layer "B.Fab")
		)
		(fp_line
			(start 0.67945 0.3048)
			(end 0.67945 -0.305054)
			(stroke
				(width 0.1)
				(type default)
			)
			(layer "B.Fab")
		)
		(pad "1" smd circle
			(at 0.40005 0 180)
			(size 0 0)
			(layers "B.Cu" "B.Mask" "B.Paste")
			(net "P0V9_RETIMER_CPU1_VINSEN")
		)
		(pad "2" smd circle
			(at -0.40005 0 180)
			(size 0 0)
			(layers "B.Cu" "B.Mask" "B.Paste")
			(net "GND")
		)
	)
	(footprint ""
		(layer "B.Cu")
		(at 350.306132 -395.148562 90)
		(property "Reference" "C618"
			(at 0 0 90)
			(layer "B.SilkS")
			(hide yes)
			(effects
				(font
					(size 1.27 1.27)
				)
				(justify mirror)
			)
		)
		(property "Value" ""
			(at 0 0 90)
			(layer "B.Fab")
			(effects
				(font
					(size 1.27 1.27)
				)
				(justify mirror)
			)
		)
		(duplicate_pad_numbers_are_jumpers no)
		(fp_line
			(start 0.299974 -0.150114)
			(end -0.299974 -0.150114)
			(stroke
				(width 0.1)
				(type default)
			)
			(layer "B.Fab")
		)
		(fp_line
			(start -0.299974 -0.150114)
			(end -0.299974 0.150114)
			(stroke
				(width 0.1)
				(type default)
			)
			(layer "B.Fab")
		)
		(fp_line
			(start 0.299974 0.150114)
			(end 0.299974 -0.150114)
			(stroke
				(width 0.1)
				(type default)
			)
			(layer "B.Fab")
		)
		(fp_line
			(start -0.299974 0.150114)
			(end 0.299974 0.150114)
			(stroke
				(width 0.1)
				(type default)
			)
			(layer "B.Fab")
		)
		(pad "1" smd rect
			(at 0.2667 0 270)
			(size 0.3048 0.381)
			(layers "B.Cu" "B.Mask" "B.Paste")
			(net "P0V9_CPU0_RT1_2A")
		)
		(pad "2" smd rect
			(at -0.2667 0 270)
			(size 0.3048 0.381)
			(layers "B.Cu" "B.Mask" "B.Paste")
			(net "GND")
		)
	)
	(footprint ""
		(layer "B.Cu")
		(at 424.684444 -426.718222 -90)
		(property "Reference" "R1431"
			(at 0 0 90)
			(layer "B.SilkS")
			(hide yes)
			(effects
				(font
					(size 1.27 1.27)
				)
				(justify mirror)
			)
		)
		(property "Value" ""
			(at 0 0 90)
			(layer "B.Fab")
			(effects
				(font
					(size 1.27 1.27)
				)
				(justify mirror)
			)
		)
		(duplicate_pad_numbers_are_jumpers no)
		(fp_line
			(start -0.32512 0.175006)
			(end 0.32512 0.175006)
			(stroke
				(width 0.1)
				(type default)
			)
			(layer "B.Fab")
		)
		(fp_line
			(start 0.32512 0.175006)
			(end 0.32512 -0.175006)
			(stroke
				(width 0.1)
				(type default)
			)
			(layer "B.Fab")
		)
		(fp_line
			(start -0.32512 -0.175006)
			(end -0.32512 0.175006)
			(stroke
				(width 0.1)
				(type default)
			)
			(layer "B.Fab")
		)
		(fp_line
			(start 0.32512 -0.175006)
			(end -0.32512 -0.175006)
			(stroke
				(width 0.1)
				(type default)
			)
			(layer "B.Fab")
		)
		(pad "1" smd rect
			(at 0.2667 0 90)
			(size 0.3048 0.381)
			(layers "B.Cu" "B.Mask" "B.Paste")
			(net "P1V8_CPU0_RT_1D")
		)
		(pad "2" smd rect
			(at -0.2667 0 270)
			(size 0.3048 0.381)
			(layers "B.Cu" "B.Mask" "B.Paste")
			(net "SMB_RT_CPU0_P2_ROM_MUX_1D_SDA")
		)
	)
	(footprint ""
		(layer "B.Cu")
		(at 43.265852 -383.49936 180)
		(property "Reference" "R6723"
			(at 0 0 0)
			(layer "B.SilkS")
			(hide yes)
			(effects
				(font
					(size 1.27 1.27)
				)
				(justify mirror)
			)
		)
		(property "Value" ""
			(at 0 0 0)
			(layer "B.Fab")
			(effects
				(font
					(size 1.27 1.27)
				)
				(justify mirror)
			)
		)
		(duplicate_pad_numbers_are_jumpers no)
		(fp_line
			(start 0.32512 0.175006)
			(end 0.32512 -0.175006)
			(stroke
				(width 0.1)
				(type default)
			)
			(layer "B.Fab")
		)
		(fp_line
			(start 0.32512 -0.175006)
			(end -0.32512 -0.175006)
			(stroke
				(width 0.1)
				(type default)
			)
			(layer "B.Fab")
		)
		(fp_line
			(start -0.32512 0.175006)
			(end 0.32512 0.175006)
			(stroke
				(width 0.1)
				(type default)
			)
			(layer "B.Fab")
		)
		(fp_line
			(start -0.32512 -0.175006)
			(end -0.32512 0.175006)
			(stroke
				(width 0.1)
				(type default)
			)
			(layer "B.Fab")
		)
		(pad "1" smd rect
			(at 0.2667 0)
			(size 0.3048 0.381)
			(layers "B.Cu" "B.Mask" "B.Paste")
			(net "RT_CPU1_P0_SCAN_MODE")
		)
		(pad "2" smd rect
			(at -0.2667 0 180)
			(size 0.3048 0.381)
			(layers "B.Cu" "B.Mask" "B.Paste")
			(net "GND")
		)
	)
	(footprint ""
		(layer "B.Cu")
		(at 190.114428 -140.46454 90)
		(property "Reference" "R632"
			(at 0 0 90)
			(layer "B.SilkS")
			(hide yes)
			(effects
				(font
					(size 1.27 1.27)
				)
				(justify mirror)
			)
		)
		(property "Value" ""
			(at 0 0 90)
			(layer "B.Fab")
			(effects
				(font
					(size 1.27 1.27)
				)
				(justify mirror)
			)
		)
		(duplicate_pad_numbers_are_jumpers no)
		(fp_line
			(start 0.7874 -0.4064)
			(end -0.7874 -0.4064)
			(stroke
				(width 0.1524)
				(type default)
			)
			(layer "B.SilkS")
		)
		(fp_line
			(start -0.7874 -0.4064)
			(end -0.7874 0.4064)
			(stroke
				(width 0.1524)
				(type default)
			)
			(layer "B.SilkS")
		)
		(fp_line
			(start 0.7874 0.4064)
			(end 0.7874 -0.4064)
			(stroke
				(width 0.1524)
				(type default)
			)
			(layer "B.SilkS")
		)
		(fp_line
			(start -0.7874 0.4064)
			(end 0.7874 0.4064)
			(stroke
				(width 0.1524)
				(type default)
			)
			(layer "B.SilkS")
		)
		(fp_line
			(start 0.67945 -0.305054)
			(end 0.12065 -0.305054)
			(stroke
				(width 0.1)
				(type default)
			)
			(layer "B.Fab")
		)
		(fp_line
			(start 0.12065 -0.305054)
			(end 0.12065 -0.2794)
			(stroke
				(width 0.1)
				(type default)
			)
			(layer "B.Fab")
		)
		(fp_line
			(start -0.12065 -0.3048)
			(end -0.67945 -0.3048)
			(stroke
				(width 0.1)
				(type default)
			)
			(layer "B.Fab")
		)
		(fp_line
			(start -0.67945 -0.3048)
			(end -0.67945 0.3048)
			(stroke
				(width 0.1)
				(type default)
			)
			(layer "B.Fab")
		)
		(fp_line
			(start 0.12065 -0.2794)
			(end -0.12065 -0.2794)
			(stroke
				(width 0.1)
				(type default)
			)
			(layer "B.Fab")
		)
		(fp_line
			(start -0.12065 -0.2794)
			(end -0.12065 -0.3048)
			(stroke
				(width 0.1)
				(type default)
			)
			(layer "B.Fab")
		)
		(fp_line
			(start 0.12065 0.2794)
			(end 0.12065 0.3048)
			(stroke
				(width 0.1)
				(type default)
			)
			(layer "B.Fab")
		)
		(fp_line
			(start -0.120396 0.2794)
			(end 0.12065 0.2794)
			(stroke
				(width 0.1)
				(type default)
			)
			(layer "B.Fab")
		)
		(fp_line
			(start 0.67945 0.3048)
			(end 0.67945 -0.305054)
			(stroke
				(width 0.1)
				(type default)
			)
			(layer "B.Fab")
		)
		(fp_line
			(start 0.12065 0.3048)
			(end 0.67945 0.3048)
			(stroke
				(width 0.1)
				(type default)
			)
			(layer "B.Fab")
		)
		(fp_line
			(start -0.120396 0.3048)
			(end -0.120396 0.2794)
			(stroke
				(width 0.1)
				(type default)
			)
			(layer "B.Fab")
		)
		(fp_line
			(start -0.67945 0.3048)
			(end -0.120396 0.3048)
			(stroke
				(width 0.1)
				(type default)
			)
			(layer "B.Fab")
		)
		(pad "1" smd circle
			(at 0.40005 0 270)
			(size 0 0)
			(layers "B.Cu" "B.Mask" "B.Paste")
			(net "PVDD18_S5_P0")
		)
		(pad "2" smd circle
			(at -0.40005 0 270)
			(size 0 0)
			(layers "B.Cu" "B.Mask" "B.Paste")
			(net "SMB_CPU_5_SCL")
		)
	)
	(footprint ""
		(layer "B.Cu")
		(at 110.276386 -267.529564)
		(property "Reference" "C2359"
			(at 0 0 0)
			(layer "B.SilkS")
			(hide yes)
			(effects
				(font
					(size 1.27 1.27)
				)
				(justify mirror)
			)
		)
		(property "Value" ""
			(at 0 0 0)
			(layer "B.Fab")
			(effects
				(font
					(size 1.27 1.27)
				)
				(justify mirror)
			)
		)
		(duplicate_pad_numbers_are_jumpers no)
		(fp_line
			(start -0.7874 -0.4064)
			(end -0.7874 0.4064)
			(stroke
				(width 0.1524)
				(type default)
			)
			(layer "B.SilkS")
		)
		(fp_line
			(start -0.7874 0.4064)
			(end 0.7874 0.4064)
			(stroke
				(width 0.1524)
				(type default)
			)
			(layer "B.SilkS")
		)
		(fp_line
			(start 0.7874 -0.4064)
			(end -0.7874 -0.4064)
			(stroke
				(width 0.1524)
				(type default)
			)
			(layer "B.SilkS")
		)
		(fp_line
			(start 0.7874 0.4064)
			(end 0.7874 -0.4064)
			(stroke
				(width 0.1524)
				(type default)
			)
			(layer "B.SilkS")
		)
		(fp_line
			(start -0.67945 -0.3048)
			(end -0.67945 0.3048)
			(stroke
				(width 0.1)
				(type default)
			)
			(layer "B.Fab")
		)
		(fp_line
			(start -0.67945 0.3048)
			(end -0.120396 0.3048)
			(stroke
				(width 0.1)
				(type default)
			)
			(layer "B.Fab")
		)
		(fp_line
			(start -0.12065 -0.3048)
			(end -0.67945 -0.3048)
			(stroke
				(width 0.1)
				(type default)
			)
			(layer "B.Fab")
		)
		(fp_line
			(start -0.12065 -0.2794)
			(end -0.12065 -0.3048)
			(stroke
				(width 0.1)
				(type default)
			)
			(layer "B.Fab")
		)
		(fp_line
			(start -0.120396 0.2794)
			(end 0.12065 0.2794)
			(stroke
				(width 0.1)
				(type default)
			)
			(layer "B.Fab")
		)
		(fp_line
			(start -0.120396 0.3048)
			(end -0.120396 0.2794)
			(stroke
				(width 0.1)
				(type default)
			)
			(layer "B.Fab")
		)
		(fp_line
			(start 0.12065 -0.305054)
			(end 0.12065 -0.2794)
			(stroke
				(width 0.1)
				(type default)
			)
			(layer "B.Fab")
		)
		(fp_line
			(start 0.12065 -0.2794)
			(end -0.12065 -0.2794)
			(stroke
				(width 0.1)
				(type default)
			)
			(layer "B.Fab")
		)
		(fp_line
			(start 0.12065 0.2794)
			(end 0.12065 0.3048)
			(stroke
				(width 0.1)
				(type default)
			)
			(layer "B.Fab")
		)
		(fp_line
			(start 0.12065 0.3048)
			(end 0.67945 0.3048)
			(stroke
				(width 0.1)
				(type default)
			)
			(layer "B.Fab")
		)
		(fp_line
			(start 0.67945 -0.305054)
			(end 0.12065 -0.305054)
			(stroke
				(width 0.1)
				(type default)
			)
			(layer "B.Fab")
		)
		(fp_line
			(start 0.67945 0.3048)
			(end 0.67945 -0.305054)
			(stroke
				(width 0.1)
				(type default)
			)
			(layer "B.Fab")
		)
		(pad "1" smd circle
			(at 0.40005 0 180)
			(size 0 0)
			(layers "B.Cu" "B.Mask" "B.Paste")
			(net "PVDDCR_CPU1_P1")
		)
		(pad "2" smd circle
			(at -0.40005 0 180)
			(size 0 0)
			(layers "B.Cu" "B.Mask" "B.Paste")
			(net "GND")
		)
	)
	(footprint ""
		(layer "B.Cu")
		(at 100.497386 -256.734564 180)
		(property "Reference" "C2498"
			(at 0 0 0)
			(layer "B.SilkS")
			(hide yes)
			(effects
				(font
					(size 1.27 1.27)
				)
				(justify mirror)
			)
		)
		(property "Value" ""
			(at 0 0 0)
			(layer "B.Fab")
			(effects
				(font
					(size 1.27 1.27)
				)
				(justify mirror)
			)
		)
		(duplicate_pad_numbers_are_jumpers no)
		(fp_line
			(start 0.7874 0.4064)
			(end 0.7874 -0.4064)
			(stroke
				(width 0.1524)
				(type default)
			)
			(layer "B.SilkS")
		)
		(fp_line
			(start 0.7874 -0.4064)
			(end -0.7874 -0.4064)
			(stroke
				(width 0.1524)
				(type default)
			)
			(layer "B.SilkS")
		)
		(fp_line
			(start -0.7874 0.4064)
			(end 0.7874 0.4064)
			(stroke
				(width 0.1524)
				(type default)
			)
			(layer "B.SilkS")
		)
		(fp_line
			(start -0.7874 -0.4064)
			(end -0.7874 0.4064)
			(stroke
				(width 0.1524)
				(type default)
			)
			(layer "B.SilkS")
		)
		(fp_line
			(start 0.67945 0.3048)
			(end 0.67945 -0.305054)
			(stroke
				(width 0.1)
				(type default)
			)
			(layer "B.Fab")
		)
		(fp_line
			(start 0.67945 -0.305054)
			(end 0.12065 -0.305054)
			(stroke
				(width 0.1)
				(type default)
			)
			(layer "B.Fab")
		)
		(fp_line
			(start 0.12065 0.3048)
			(end 0.67945 0.3048)
			(stroke
				(width 0.1)
				(type default)
			)
			(layer "B.Fab")
		)
		(fp_line
			(start 0.12065 0.2794)
			(end 0.12065 0.3048)
			(stroke
				(width 0.1)
				(type default)
			)
			(layer "B.Fab")
		)
		(fp_line
			(start 0.12065 -0.2794)
			(end -0.12065 -0.2794)
			(stroke
				(width 0.1)
				(type default)
			)
			(layer "B.Fab")
		)
		(fp_line
			(start 0.12065 -0.305054)
			(end 0.12065 -0.2794)
			(stroke
				(width 0.1)
				(type default)
			)
			(layer "B.Fab")
		)
		(fp_line
			(start -0.120396 0.3048)
			(end -0.120396 0.2794)
			(stroke
				(width 0.1)
				(type default)
			)
			(layer "B.Fab")
		)
		(fp_line
			(start -0.120396 0.2794)
			(end 0.12065 0.2794)
			(stroke
				(width 0.1)
				(type default)
			)
			(layer "B.Fab")
		)
		(fp_line
			(start -0.12065 -0.2794)
			(end -0.12065 -0.3048)
			(stroke
				(width 0.1)
				(type default)
			)
			(layer "B.Fab")
		)
		(fp_line
			(start -0.12065 -0.3048)
			(end -0.67945 -0.3048)
			(stroke
				(width 0.1)
				(type default)
			)
			(layer "B.Fab")
		)
		(fp_line
			(start -0.67945 0.3048)
			(end -0.120396 0.3048)
			(stroke
				(width 0.1)
				(type default)
			)
			(layer "B.Fab")
		)
		(fp_line
			(start -0.67945 -0.3048)
			(end -0.67945 0.3048)
			(stroke
				(width 0.1)
				(type default)
			)
			(layer "B.Fab")
		)
		(pad "1" smd circle
			(at 0.40005 0)
			(size 0 0)
			(layers "B.Cu" "B.Mask" "B.Paste")
			(net "PVDDIO_P1")
		)
		(pad "2" smd circle
			(at -0.40005 0)
			(size 0 0)
			(layers "B.Cu" "B.Mask" "B.Paste")
			(net "GND")
		)
	)
	(footprint ""
		(layer "B.Cu")
		(at 393.637008 -322.195952)
		(property "Reference" "R739"
			(at 0 0 0)
			(layer "B.SilkS")
			(hide yes)
			(effects
				(font
					(size 1.27 1.27)
				)
				(justify mirror)
			)
		)
		(property "Value" ""
			(at 0 0 0)
			(layer "B.Fab")
			(effects
				(font
					(size 1.27 1.27)
				)
				(justify mirror)
			)
		)
		(duplicate_pad_numbers_are_jumpers no)
		(fp_line
			(start -0.7874 -0.4064)
			(end -0.7874 0.4064)
			(stroke
				(width 0.1524)
				(type default)
			)
			(layer "B.SilkS")
		)
		(fp_line
			(start -0.7874 0.4064)
			(end 0.7874 0.4064)
			(stroke
				(width 0.1524)
				(type default)
			)
			(layer "B.SilkS")
		)
		(fp_line
			(start 0.7874 -0.4064)
			(end -0.7874 -0.4064)
			(stroke
				(width 0.1524)
				(type default)
			)
			(layer "B.SilkS")
		)
		(fp_line
			(start 0.7874 0.4064)
			(end 0.7874 -0.4064)
			(stroke
				(width 0.1524)
				(type default)
			)
			(layer "B.SilkS")
		)
		(fp_line
			(start -0.67945 -0.3048)
			(end -0.67945 0.3048)
			(stroke
				(width 0.1)
				(type default)
			)
			(layer "B.Fab")
		)
		(fp_line
			(start -0.67945 0.3048)
			(end -0.120396 0.3048)
			(stroke
				(width 0.1)
				(type default)
			)
			(layer "B.Fab")
		)
		(fp_line
			(start -0.12065 -0.3048)
			(end -0.67945 -0.3048)
			(stroke
				(width 0.1)
				(type default)
			)
			(layer "B.Fab")
		)
		(fp_line
			(start -0.12065 -0.2794)
			(end -0.12065 -0.3048)
			(stroke
				(width 0.1)
				(type default)
			)
			(layer "B.Fab")
		)
		(fp_line
			(start -0.120396 0.2794)
			(end 0.12065 0.2794)
			(stroke
				(width 0.1)
				(type default)
			)
			(layer "B.Fab")
		)
		(fp_line
			(start -0.120396 0.3048)
			(end -0.120396 0.2794)
			(stroke
				(width 0.1)
				(type default)
			)
			(layer "B.Fab")
		)
		(fp_line
			(start 0.12065 -0.305054)
			(end 0.12065 -0.2794)
			(stroke
				(width 0.1)
				(type default)
			)
			(layer "B.Fab")
		)
		(fp_line
			(start 0.12065 -0.2794)
			(end -0.12065 -0.2794)
			(stroke
				(width 0.1)
				(type default)
			)
			(layer "B.Fab")
		)
		(fp_line
			(start 0.12065 0.2794)
			(end 0.12065 0.3048)
			(stroke
				(width 0.1)
				(type default)
			)
			(layer "B.Fab")
		)
		(fp_line
			(start 0.12065 0.3048)
			(end 0.67945 0.3048)
			(stroke
				(width 0.1)
				(type default)
			)
			(layer "B.Fab")
		)
		(fp_line
			(start 0.67945 -0.305054)
			(end 0.12065 -0.305054)
			(stroke
				(width 0.1)
				(type default)
			)
			(layer "B.Fab")
		)
		(fp_line
			(start 0.67945 0.3048)
			(end 0.67945 -0.305054)
			(stroke
				(width 0.1)
				(type default)
			)
			(layer "B.Fab")
		)
		(pad "1" smd circle
			(at 0.40005 0 180)
			(size 0 0)
			(layers "B.Cu" "B.Mask" "B.Paste")
			(net "PVDD18_S5_P0")
		)
		(pad "2" smd circle
			(at -0.40005 0 180)
			(size 0 0)
			(layers "B.Cu" "B.Mask" "B.Paste")
			(net "CLK_ESPI_CPU0_CLK1")
		)
	)
	(footprint ""
		(layer "B.Cu")
		(at 435.549802 -12.104116 180)
		(property "Reference" "C1238"
			(at 0 0 0)
			(layer "B.SilkS")
			(hide yes)
			(effects
				(font
					(size 1.27 1.27)
				)
				(justify mirror)
			)
		)
		(property "Value" ""
			(at 0 0 0)
			(layer "B.Fab")
			(effects
				(font
					(size 1.27 1.27)
				)
				(justify mirror)
			)
		)
		(duplicate_pad_numbers_are_jumpers no)
		(fp_line
			(start 0.7874 0.4064)
			(end 0.7874 -0.4064)
			(stroke
				(width 0.1524)
				(type default)
			)
			(layer "B.SilkS")
		)
		(fp_line
			(start 0.7874 -0.4064)
			(end -0.7874 -0.4064)
			(stroke
				(width 0.1524)
				(type default)
			)
			(layer "B.SilkS")
		)
		(fp_line
			(start -0.7874 0.4064)
			(end 0.7874 0.4064)
			(stroke
				(width 0.1524)
				(type default)
			)
			(layer "B.SilkS")
		)
		(fp_line
			(start -0.7874 -0.4064)
			(end -0.7874 0.4064)
			(stroke
				(width 0.1524)
				(type default)
			)
			(layer "B.SilkS")
		)
		(fp_line
			(start 0.67945 0.3048)
			(end 0.67945 -0.305054)
			(stroke
				(width 0.1)
				(type default)
			)
			(layer "B.Fab")
		)
		(fp_line
			(start 0.67945 -0.305054)
			(end 0.12065 -0.305054)
			(stroke
				(width 0.1)
				(type default)
			)
			(layer "B.Fab")
		)
		(fp_line
			(start 0.12065 0.3048)
			(end 0.67945 0.3048)
			(stroke
				(width 0.1)
				(type default)
			)
			(layer "B.Fab")
		)
		(fp_line
			(start 0.12065 0.2794)
			(end 0.12065 0.3048)
			(stroke
				(width 0.1)
				(type default)
			)
			(layer "B.Fab")
		)
		(fp_line
			(start 0.12065 -0.2794)
			(end -0.12065 -0.2794)
			(stroke
				(width 0.1)
				(type default)
			)
			(layer "B.Fab")
		)
		(fp_line
			(start 0.12065 -0.305054)
			(end 0.12065 -0.2794)
			(stroke
				(width 0.1)
				(type default)
			)
			(layer "B.Fab")
		)
		(fp_line
			(start -0.120396 0.3048)
			(end -0.120396 0.2794)
			(stroke
				(width 0.1)
				(type default)
			)
			(layer "B.Fab")
		)
		(fp_line
			(start -0.120396 0.2794)
			(end 0.12065 0.2794)
			(stroke
				(width 0.1)
				(type default)
			)
			(layer "B.Fab")
		)
		(fp_line
			(start -0.12065 -0.2794)
			(end -0.12065 -0.3048)
			(stroke
				(width 0.1)
				(type default)
			)
			(layer "B.Fab")
		)
		(fp_line
			(start -0.12065 -0.3048)
			(end -0.67945 -0.3048)
			(stroke
				(width 0.1)
				(type default)
			)
			(layer "B.Fab")
		)
		(fp_line
			(start -0.67945 0.3048)
			(end -0.120396 0.3048)
			(stroke
				(width 0.1)
				(type default)
			)
			(layer "B.Fab")
		)
		(fp_line
			(start -0.67945 -0.3048)
			(end -0.67945 0.3048)
			(stroke
				(width 0.1)
				(type default)
			)
			(layer "B.Fab")
		)
		(pad "1" smd circle
			(at 0.40005 0)
			(size 0 0)
			(layers "B.Cu" "B.Mask" "B.Paste")
			(net "P3V3_OCP_SFF")
		)
		(pad "2" smd circle
			(at -0.40005 0)
			(size 0 0)
			(layers "B.Cu" "B.Mask" "B.Paste")
			(net "GND")
		)
	)
	(footprint ""
		(layer "B.Cu")
		(at 162.348926 -408.517344 90)
		(property "Reference" "C6756"
			(at 0 0 90)
			(layer "B.SilkS")
			(hide yes)
			(effects
				(font
					(size 1.27 1.27)
				)
				(justify mirror)
			)
		)
		(property "Value" ""
			(at 0 0 90)
			(layer "B.Fab")
			(effects
				(font
					(size 1.27 1.27)
				)
				(justify mirror)
			)
		)
		(duplicate_pad_numbers_are_jumpers no)
		(fp_line
			(start 0.299974 -0.150114)
			(end -0.299974 -0.150114)
			(stroke
				(width 0.1)
				(type default)
			)
			(layer "B.Fab")
		)
		(fp_line
			(start -0.299974 -0.150114)
			(end -0.299974 0.150114)
			(stroke
				(width 0.1)
				(type default)
			)
			(layer "B.Fab")
		)
		(fp_line
			(start 0.299974 0.150114)
			(end 0.299974 -0.150114)
			(stroke
				(width 0.1)
				(type default)
			)
			(layer "B.Fab")
		)
		(fp_line
			(start -0.299974 0.150114)
			(end 0.299974 0.150114)
			(stroke
				(width 0.1)
				(type default)
			)
			(layer "B.Fab")
		)
		(pad "1" smd rect
			(at 0.2667 0 270)
			(size 0.3048 0.381)
			(layers "B.Cu" "B.Mask" "B.Paste")
			(net "P5E_CPU1_P3_TX_BUF_C_DN<15>")
		)
		(pad "2" smd rect
			(at -0.2667 0 270)
			(size 0.3048 0.381)
			(layers "B.Cu" "B.Mask" "B.Paste")
			(net "P5E_CPU1_P3_TX_BUF_DN<15>")
		)
	)
	(footprint ""
		(layer "B.Cu")
		(at 449.79971 -423.935398 180)
		(property "Reference" "PR6618"
			(at 0 0 0)
			(layer "B.SilkS")
			(hide yes)
			(effects
				(font
					(size 1.27 1.27)
				)
				(justify mirror)
			)
		)
		(property "Value" ""
			(at 0 0 0)
			(layer "B.Fab")
			(effects
				(font
					(size 1.27 1.27)
				)
				(justify mirror)
			)
		)
		(duplicate_pad_numbers_are_jumpers no)
		(fp_line
			(start 0.7874 0.4064)
			(end 0.7874 -0.4064)
			(stroke
				(width 0.1524)
				(type default)
			)
			(layer "B.SilkS")
		)
		(fp_line
			(start 0.7874 -0.4064)
			(end -0.7874 -0.4064)
			(stroke
				(width 0.1524)
				(type default)
			)
			(layer "B.SilkS")
		)
		(fp_line
			(start -0.7874 0.4064)
			(end 0.7874 0.4064)
			(stroke
				(width 0.1524)
				(type default)
			)
			(layer "B.SilkS")
		)
		(fp_line
			(start -0.7874 -0.4064)
			(end -0.7874 0.4064)
			(stroke
				(width 0.1524)
				(type default)
			)
			(layer "B.SilkS")
		)
		(fp_line
			(start 0.67945 0.3048)
			(end 0.67945 -0.305054)
			(stroke
				(width 0.1)
				(type default)
			)
			(layer "B.Fab")
		)
		(fp_line
			(start 0.67945 -0.305054)
			(end 0.12065 -0.305054)
			(stroke
				(width 0.1)
				(type default)
			)
			(layer "B.Fab")
		)
		(fp_line
			(start 0.12065 0.3048)
			(end 0.67945 0.3048)
			(stroke
				(width 0.1)
				(type default)
			)
			(layer "B.Fab")
		)
		(fp_line
			(start 0.12065 0.2794)
			(end 0.12065 0.3048)
			(stroke
				(width 0.1)
				(type default)
			)
			(layer "B.Fab")
		)
		(fp_line
			(start 0.12065 -0.2794)
			(end -0.12065 -0.2794)
			(stroke
				(width 0.1)
				(type default)
			)
			(layer "B.Fab")
		)
		(fp_line
			(start 0.12065 -0.305054)
			(end 0.12065 -0.2794)
			(stroke
				(width 0.1)
				(type default)
			)
			(layer "B.Fab")
		)
		(fp_line
			(start -0.120396 0.3048)
			(end -0.120396 0.2794)
			(stroke
				(width 0.1)
				(type default)
			)
			(layer "B.Fab")
		)
		(fp_line
			(start -0.120396 0.2794)
			(end 0.12065 0.2794)
			(stroke
				(width 0.1)
				(type default)
			)
			(layer "B.Fab")
		)
		(fp_line
			(start -0.12065 -0.2794)
			(end -0.12065 -0.3048)
			(stroke
				(width 0.1)
				(type default)
			)
			(layer "B.Fab")
		)
		(fp_line
			(start -0.12065 -0.3048)
			(end -0.67945 -0.3048)
			(stroke
				(width 0.1)
				(type default)
			)
			(layer "B.Fab")
		)
		(fp_line
			(start -0.67945 0.3048)
			(end -0.120396 0.3048)
			(stroke
				(width 0.1)
				(type default)
			)
			(layer "B.Fab")
		)
		(fp_line
			(start -0.67945 -0.3048)
			(end -0.67945 0.3048)
			(stroke
				(width 0.1)
				(type default)
			)
			(layer "B.Fab")
		)
		(pad "1" smd circle
			(at 0.40005 0)
			(size 0 0)
			(layers "B.Cu" "B.Mask" "B.Paste")
			(net "P0V9_RETIMER_CPU0_TEMP1_R")
		)
		(pad "2" smd circle
			(at -0.40005 0)
			(size 0 0)
			(layers "B.Cu" "B.Mask" "B.Paste")
			(net "GND")
		)
	)
	(footprint ""
		(layer "B.Cu")
		(at 69.861684 -391.81405 180)
		(property "Reference" "C220"
			(at 0 0 0)
			(layer "B.SilkS")
			(hide yes)
			(effects
				(font
					(size 1.27 1.27)
				)
				(justify mirror)
			)
		)
		(property "Value" ""
			(at 0 0 0)
			(layer "B.Fab")
			(effects
				(font
					(size 1.27 1.27)
				)
				(justify mirror)
			)
		)
		(duplicate_pad_numbers_are_jumpers no)
		(fp_line
			(start 1.524 0.762)
			(end 1.524 -0.762)
			(stroke
				(width 0.1524)
				(type default)
			)
			(layer "B.SilkS")
		)
		(fp_line
			(start 1.524 -0.762)
			(end -1.524 -0.762)
			(stroke
				(width 0.1524)
				(type default)
			)
			(layer "B.SilkS")
		)
		(fp_line
			(start -1.524 0.762)
			(end 1.524 0.762)
			(stroke
				(width 0.1524)
				(type default)
			)
			(layer "B.SilkS")
		)
		(fp_line
			(start -1.524 -0.762)
			(end -1.524 0.762)
			(stroke
				(width 0.1524)
				(type default)
			)
			(layer "B.SilkS")
		)
		(fp_line
			(start 1.1049 0.724916)
			(end -1.1049 0.724916)
			(stroke
				(width 0.1)
				(type default)
			)
			(layer "B.Fab")
		)
		(fp_line
			(start 1.1049 -0.724916)
			(end 1.1049 0.724916)
			(stroke
				(width 0.1)
				(type default)
			)
			(layer "B.Fab")
		)
		(fp_line
			(start -1.1049 0.724916)
			(end -1.1049 -0.724916)
			(stroke
				(width 0.1)
				(type default)
			)
			(layer "B.Fab")
		)
		(fp_line
			(start -1.1049 -0.724916)
			(end 1.1049 -0.724916)
			(stroke
				(width 0.1)
				(type default)
			)
			(layer "B.Fab")
		)
		(pad "1" smd rect
			(at 0.889 0 180)
			(size 1.016 1.27)
			(layers "B.Cu" "B.Mask" "B.Paste")
			(net "P0V9_CPU1_RT0_2A")
		)
		(pad "2" smd rect
			(at -0.889 0 180)
			(size 1.016 1.27)
			(layers "B.Cu" "B.Mask" "B.Paste")
			(net "GND")
		)
	)
	(footprint ""
		(layer "B.Cu")
		(at 430.55921 -244.08511)
		(property "Reference" "R383"
			(at 0 0 0)
			(layer "B.SilkS")
			(hide yes)
			(effects
				(font
					(size 1.27 1.27)
				)
				(justify mirror)
			)
		)
		(property "Value" ""
			(at 0 0 0)
			(layer "B.Fab")
			(effects
				(font
					(size 1.27 1.27)
				)
				(justify mirror)
			)
		)
		(duplicate_pad_numbers_are_jumpers no)
		(fp_line
			(start -0.7874 -0.4064)
			(end -0.7874 0.4064)
			(stroke
				(width 0.1524)
				(type default)
			)
			(layer "B.SilkS")
		)
		(fp_line
			(start -0.7874 0.4064)
			(end 0.7874 0.4064)
			(stroke
				(width 0.1524)
				(type default)
			)
			(layer "B.SilkS")
		)
		(fp_line
			(start 0.7874 -0.4064)
			(end -0.7874 -0.4064)
			(stroke
				(width 0.1524)
				(type default)
			)
			(layer "B.SilkS")
		)
		(fp_line
			(start 0.7874 0.4064)
			(end 0.7874 -0.4064)
			(stroke
				(width 0.1524)
				(type default)
			)
			(layer "B.SilkS")
		)
		(fp_line
			(start -0.67945 -0.3048)
			(end -0.67945 0.3048)
			(stroke
				(width 0.1)
				(type default)
			)
			(layer "B.Fab")
		)
		(fp_line
			(start -0.67945 0.3048)
			(end -0.120396 0.3048)
			(stroke
				(width 0.1)
				(type default)
			)
			(layer "B.Fab")
		)
		(fp_line
			(start -0.12065 -0.3048)
			(end -0.67945 -0.3048)
			(stroke
				(width 0.1)
				(type default)
			)
			(layer "B.Fab")
		)
		(fp_line
			(start -0.12065 -0.2794)
			(end -0.12065 -0.3048)
			(stroke
				(width 0.1)
				(type default)
			)
			(layer "B.Fab")
		)
		(fp_line
			(start -0.120396 0.2794)
			(end 0.12065 0.2794)
			(stroke
				(width 0.1)
				(type default)
			)
			(layer "B.Fab")
		)
		(fp_line
			(start -0.120396 0.3048)
			(end -0.120396 0.2794)
			(stroke
				(width 0.1)
				(type default)
			)
			(layer "B.Fab")
		)
		(fp_line
			(start 0.12065 -0.305054)
			(end 0.12065 -0.2794)
			(stroke
				(width 0.1)
				(type default)
			)
			(layer "B.Fab")
		)
		(fp_line
			(start 0.12065 -0.2794)
			(end -0.12065 -0.2794)
			(stroke
				(width 0.1)
				(type default)
			)
			(layer "B.Fab")
		)
		(fp_line
			(start 0.12065 0.2794)
			(end 0.12065 0.3048)
			(stroke
				(width 0.1)
				(type default)
			)
			(layer "B.Fab")
		)
		(fp_line
			(start 0.12065 0.3048)
			(end 0.67945 0.3048)
			(stroke
				(width 0.1)
				(type default)
			)
			(layer "B.Fab")
		)
		(fp_line
			(start 0.67945 -0.305054)
			(end 0.12065 -0.305054)
			(stroke
				(width 0.1)
				(type default)
			)
			(layer "B.Fab")
		)
		(fp_line
			(start 0.67945 0.3048)
			(end 0.67945 -0.305054)
			(stroke
				(width 0.1)
				(type default)
			)
			(layer "B.Fab")
		)
		(pad "1" smd circle
			(at 0.40005 0 180)
			(size 0 0)
			(layers "B.Cu" "B.Mask" "B.Paste")
			(net "M_I_CPU0_ALERT_N")
		)
		(pad "2" smd circle
			(at -0.40005 0 180)
			(size 0 0)
			(layers "B.Cu" "B.Mask" "B.Paste")
			(net "M_I_CPU0_ALERT_R_N")
		)
	)
	(footprint ""
		(layer "B.Cu")
		(at 372.313454 -261.046976)
		(property "Reference" "C2548"
			(at 0 0 0)
			(layer "B.SilkS")
			(hide yes)
			(effects
				(font
					(size 1.27 1.27)
				)
				(justify mirror)
			)
		)
		(property "Value" ""
			(at 0 0 0)
			(layer "B.Fab")
			(effects
				(font
					(size 1.27 1.27)
				)
				(justify mirror)
			)
		)
		(duplicate_pad_numbers_are_jumpers no)
		(fp_line
			(start -0.7874 -0.4064)
			(end -0.7874 0.4064)
			(stroke
				(width 0.1524)
				(type default)
			)
			(layer "B.SilkS")
		)
		(fp_line
			(start -0.7874 0.4064)
			(end 0.7874 0.4064)
			(stroke
				(width 0.1524)
				(type default)
			)
			(layer "B.SilkS")
		)
		(fp_line
			(start 0.7874 -0.4064)
			(end -0.7874 -0.4064)
			(stroke
				(width 0.1524)
				(type default)
			)
			(layer "B.SilkS")
		)
		(fp_line
			(start 0.7874 0.4064)
			(end 0.7874 -0.4064)
			(stroke
				(width 0.1524)
				(type default)
			)
			(layer "B.SilkS")
		)
		(fp_line
			(start -0.67945 -0.3048)
			(end -0.67945 0.3048)
			(stroke
				(width 0.1)
				(type default)
			)
			(layer "B.Fab")
		)
		(fp_line
			(start -0.67945 0.3048)
			(end -0.120396 0.3048)
			(stroke
				(width 0.1)
				(type default)
			)
			(layer "B.Fab")
		)
		(fp_line
			(start -0.12065 -0.3048)
			(end -0.67945 -0.3048)
			(stroke
				(width 0.1)
				(type default)
			)
			(layer "B.Fab")
		)
		(fp_line
			(start -0.12065 -0.2794)
			(end -0.12065 -0.3048)
			(stroke
				(width 0.1)
				(type default)
			)
			(layer "B.Fab")
		)
		(fp_line
			(start -0.120396 0.2794)
			(end 0.12065 0.2794)
			(stroke
				(width 0.1)
				(type default)
			)
			(layer "B.Fab")
		)
		(fp_line
			(start -0.120396 0.3048)
			(end -0.120396 0.2794)
			(stroke
				(width 0.1)
				(type default)
			)
			(layer "B.Fab")
		)
		(fp_line
			(start 0.12065 -0.305054)
			(end 0.12065 -0.2794)
			(stroke
				(width 0.1)
				(type default)
			)
			(layer "B.Fab")
		)
		(fp_line
			(start 0.12065 -0.2794)
			(end -0.12065 -0.2794)
			(stroke
				(width 0.1)
				(type default)
			)
			(layer "B.Fab")
		)
		(fp_line
			(start 0.12065 0.2794)
			(end 0.12065 0.3048)
			(stroke
				(width 0.1)
				(type default)
			)
			(layer "B.Fab")
		)
		(fp_line
			(start 0.12065 0.3048)
			(end 0.67945 0.3048)
			(stroke
				(width 0.1)
				(type default)
			)
			(layer "B.Fab")
		)
		(fp_line
			(start 0.67945 -0.305054)
			(end 0.12065 -0.305054)
			(stroke
				(width 0.1)
				(type default)
			)
			(layer "B.Fab")
		)
		(fp_line
			(start 0.67945 0.3048)
			(end 0.67945 -0.305054)
			(stroke
				(width 0.1)
				(type default)
			)
			(layer "B.Fab")
		)
		(pad "1" smd circle
			(at 0.40005 0 180)
			(size 0 0)
			(layers "B.Cu" "B.Mask" "B.Paste")
			(net "PVDDCR_SOC_P0")
		)
		(pad "2" smd circle
			(at -0.40005 0 180)
			(size 0 0)
			(layers "B.Cu" "B.Mask" "B.Paste")
			(net "GND")
		)
	)
	(footprint ""
		(layer "B.Cu")
		(at 356.311454 -266.00531)
		(property "Reference" "C3890"
			(at 0 0 0)
			(layer "B.SilkS")
			(hide yes)
			(effects
				(font
					(size 1.27 1.27)
				)
				(justify mirror)
			)
		)
		(property "Value" ""
			(at 0 0 0)
			(layer "B.Fab")
			(effects
				(font
					(size 1.27 1.27)
				)
				(justify mirror)
			)
		)
		(duplicate_pad_numbers_are_jumpers no)
		(fp_line
			(start -0.7874 -0.4064)
			(end -0.7874 0.4064)
			(stroke
				(width 0.1524)
				(type default)
			)
			(layer "B.SilkS")
		)
		(fp_line
			(start -0.7874 0.4064)
			(end 0.7874 0.4064)
			(stroke
				(width 0.1524)
				(type default)
			)
			(layer "B.SilkS")
		)
		(fp_line
			(start 0.7874 -0.4064)
			(end -0.7874 -0.4064)
			(stroke
				(width 0.1524)
				(type default)
			)
			(layer "B.SilkS")
		)
		(fp_line
			(start 0.7874 0.4064)
			(end 0.7874 -0.4064)
			(stroke
				(width 0.1524)
				(type default)
			)
			(layer "B.SilkS")
		)
		(fp_line
			(start -0.67945 -0.3048)
			(end -0.67945 0.3048)
			(stroke
				(width 0.1)
				(type default)
			)
			(layer "B.Fab")
		)
		(fp_line
			(start -0.67945 0.3048)
			(end -0.120396 0.3048)
			(stroke
				(width 0.1)
				(type default)
			)
			(layer "B.Fab")
		)
		(fp_line
			(start -0.12065 -0.3048)
			(end -0.67945 -0.3048)
			(stroke
				(width 0.1)
				(type default)
			)
			(layer "B.Fab")
		)
		(fp_line
			(start -0.12065 -0.2794)
			(end -0.12065 -0.3048)
			(stroke
				(width 0.1)
				(type default)
			)
			(layer "B.Fab")
		)
		(fp_line
			(start -0.120396 0.2794)
			(end 0.12065 0.2794)
			(stroke
				(width 0.1)
				(type default)
			)
			(layer "B.Fab")
		)
		(fp_line
			(start -0.120396 0.3048)
			(end -0.120396 0.2794)
			(stroke
				(width 0.1)
				(type default)
			)
			(layer "B.Fab")
		)
		(fp_line
			(start 0.12065 -0.305054)
			(end 0.12065 -0.2794)
			(stroke
				(width 0.1)
				(type default)
			)
			(layer "B.Fab")
		)
		(fp_line
			(start 0.12065 -0.2794)
			(end -0.12065 -0.2794)
			(stroke
				(width 0.1)
				(type default)
			)
			(layer "B.Fab")
		)
		(fp_line
			(start 0.12065 0.2794)
			(end 0.12065 0.3048)
			(stroke
				(width 0.1)
				(type default)
			)
			(layer "B.Fab")
		)
		(fp_line
			(start 0.12065 0.3048)
			(end 0.67945 0.3048)
			(stroke
				(width 0.1)
				(type default)
			)
			(layer "B.Fab")
		)
		(fp_line
			(start 0.67945 -0.305054)
			(end 0.12065 -0.305054)
			(stroke
				(width 0.1)
				(type default)
			)
			(layer "B.Fab")
		)
		(fp_line
			(start 0.67945 0.3048)
			(end 0.67945 -0.305054)
			(stroke
				(width 0.1)
				(type default)
			)
			(layer "B.Fab")
		)
		(pad "1" smd circle
			(at 0.40005 0 180)
			(size 0 0)
			(layers "B.Cu" "B.Mask" "B.Paste")
			(net "PVDD11_S3_P0")
		)
		(pad "2" smd circle
			(at -0.40005 0 180)
			(size 0 0)
			(layers "B.Cu" "B.Mask" "B.Paste")
			(net "GND")
		)
	)
	(footprint ""
		(layer "B.Cu")
		(at 119.291354 -390.560052 90)
		(property "Reference" "C487"
			(at 0 0 90)
			(layer "B.SilkS")
			(hide yes)
			(effects
				(font
					(size 1.27 1.27)
				)
				(justify mirror)
			)
		)
		(property "Value" ""
			(at 0 0 90)
			(layer "B.Fab")
			(effects
				(font
					(size 1.27 1.27)
				)
				(justify mirror)
			)
		)
		(duplicate_pad_numbers_are_jumpers no)
		(fp_line
			(start 0.7874 -0.4064)
			(end -0.7874 -0.4064)
			(stroke
				(width 0.1524)
				(type default)
			)
			(layer "B.SilkS")
		)
		(fp_line
			(start -0.7874 -0.4064)
			(end -0.7874 0.4064)
			(stroke
				(width 0.1524)
				(type default)
			)
			(layer "B.SilkS")
		)
		(fp_line
			(start 0.7874 0.4064)
			(end 0.7874 -0.4064)
			(stroke
				(width 0.1524)
				(type default)
			)
			(layer "B.SilkS")
		)
		(fp_line
			(start -0.7874 0.4064)
			(end 0.7874 0.4064)
			(stroke
				(width 0.1524)
				(type default)
			)
			(layer "B.SilkS")
		)
		(fp_line
			(start 0.67945 -0.305054)
			(end 0.12065 -0.305054)
			(stroke
				(width 0.1)
				(type default)
			)
			(layer "B.Fab")
		)
		(fp_line
			(start 0.12065 -0.305054)
			(end 0.12065 -0.2794)
			(stroke
				(width 0.1)
				(type default)
			)
			(layer "B.Fab")
		)
		(fp_line
			(start -0.12065 -0.3048)
			(end -0.67945 -0.3048)
			(stroke
				(width 0.1)
				(type default)
			)
			(layer "B.Fab")
		)
		(fp_line
			(start -0.67945 -0.3048)
			(end -0.67945 0.3048)
			(stroke
				(width 0.1)
				(type default)
			)
			(layer "B.Fab")
		)
		(fp_line
			(start 0.12065 -0.2794)
			(end -0.12065 -0.2794)
			(stroke
				(width 0.1)
				(type default)
			)
			(layer "B.Fab")
		)
		(fp_line
			(start -0.12065 -0.2794)
			(end -0.12065 -0.3048)
			(stroke
				(width 0.1)
				(type default)
			)
			(layer "B.Fab")
		)
		(fp_line
			(start 0.12065 0.2794)
			(end 0.12065 0.3048)
			(stroke
				(width 0.1)
				(type default)
			)
			(layer "B.Fab")
		)
		(fp_line
			(start -0.120396 0.2794)
			(end 0.12065 0.2794)
			(stroke
				(width 0.1)
				(type default)
			)
			(layer "B.Fab")
		)
		(fp_line
			(start 0.67945 0.3048)
			(end 0.67945 -0.305054)
			(stroke
				(width 0.1)
				(type default)
			)
			(layer "B.Fab")
		)
		(fp_line
			(start 0.12065 0.3048)
			(end 0.67945 0.3048)
			(stroke
				(width 0.1)
				(type default)
			)
			(layer "B.Fab")
		)
		(fp_line
			(start -0.120396 0.3048)
			(end -0.120396 0.2794)
			(stroke
				(width 0.1)
				(type default)
			)
			(layer "B.Fab")
		)
		(fp_line
			(start -0.67945 0.3048)
			(end -0.120396 0.3048)
			(stroke
				(width 0.1)
				(type default)
			)
			(layer "B.Fab")
		)
		(pad "1" smd circle
			(at 0.40005 0 270)
			(size 0 0)
			(layers "B.Cu" "B.Mask" "B.Paste")
			(net "P0V9_CPU1_RT3_2A")
		)
		(pad "2" smd circle
			(at -0.40005 0 270)
			(size 0 0)
			(layers "B.Cu" "B.Mask" "B.Paste")
			(net "GND")
		)
	)
	(footprint ""
		(layer "B.Cu")
		(at 106.212386 -251.781564)
		(property "Reference" "C2448"
			(at 0 0 0)
			(layer "B.SilkS")
			(hide yes)
			(effects
				(font
					(size 1.27 1.27)
				)
				(justify mirror)
			)
		)
		(property "Value" ""
			(at 0 0 0)
			(layer "B.Fab")
			(effects
				(font
					(size 1.27 1.27)
				)
				(justify mirror)
			)
		)
		(duplicate_pad_numbers_are_jumpers no)
		(fp_line
			(start -0.7874 -0.4064)
			(end -0.7874 0.4064)
			(stroke
				(width 0.1524)
				(type default)
			)
			(layer "B.SilkS")
		)
		(fp_line
			(start -0.7874 0.4064)
			(end 0.7874 0.4064)
			(stroke
				(width 0.1524)
				(type default)
			)
			(layer "B.SilkS")
		)
		(fp_line
			(start 0.7874 -0.4064)
			(end -0.7874 -0.4064)
			(stroke
				(width 0.1524)
				(type default)
			)
			(layer "B.SilkS")
		)
		(fp_line
			(start 0.7874 0.4064)
			(end 0.7874 -0.4064)
			(stroke
				(width 0.1524)
				(type default)
			)
			(layer "B.SilkS")
		)
		(fp_line
			(start -0.67945 -0.3048)
			(end -0.67945 0.3048)
			(stroke
				(width 0.1)
				(type default)
			)
			(layer "B.Fab")
		)
		(fp_line
			(start -0.67945 0.3048)
			(end -0.120396 0.3048)
			(stroke
				(width 0.1)
				(type default)
			)
			(layer "B.Fab")
		)
		(fp_line
			(start -0.12065 -0.3048)
			(end -0.67945 -0.3048)
			(stroke
				(width 0.1)
				(type default)
			)
			(layer "B.Fab")
		)
		(fp_line
			(start -0.12065 -0.2794)
			(end -0.12065 -0.3048)
			(stroke
				(width 0.1)
				(type default)
			)
			(layer "B.Fab")
		)
		(fp_line
			(start -0.120396 0.2794)
			(end 0.12065 0.2794)
			(stroke
				(width 0.1)
				(type default)
			)
			(layer "B.Fab")
		)
		(fp_line
			(start -0.120396 0.3048)
			(end -0.120396 0.2794)
			(stroke
				(width 0.1)
				(type default)
			)
			(layer "B.Fab")
		)
		(fp_line
			(start 0.12065 -0.305054)
			(end 0.12065 -0.2794)
			(stroke
				(width 0.1)
				(type default)
			)
			(layer "B.Fab")
		)
		(fp_line
			(start 0.12065 -0.2794)
			(end -0.12065 -0.2794)
			(stroke
				(width 0.1)
				(type default)
			)
			(layer "B.Fab")
		)
		(fp_line
			(start 0.12065 0.2794)
			(end 0.12065 0.3048)
			(stroke
				(width 0.1)
				(type default)
			)
			(layer "B.Fab")
		)
		(fp_line
			(start 0.12065 0.3048)
			(end 0.67945 0.3048)
			(stroke
				(width 0.1)
				(type default)
			)
			(layer "B.Fab")
		)
		(fp_line
			(start 0.67945 -0.305054)
			(end 0.12065 -0.305054)
			(stroke
				(width 0.1)
				(type default)
			)
			(layer "B.Fab")
		)
		(fp_line
			(start 0.67945 0.3048)
			(end 0.67945 -0.305054)
			(stroke
				(width 0.1)
				(type default)
			)
			(layer "B.Fab")
		)
		(pad "1" smd circle
			(at 0.40005 0 180)
			(size 0 0)
			(layers "B.Cu" "B.Mask" "B.Paste")
			(net "PVDDCR_SOC_P1")
		)
		(pad "2" smd circle
			(at -0.40005 0 180)
			(size 0 0)
			(layers "B.Cu" "B.Mask" "B.Paste")
			(net "GND")
		)
	)
	(footprint ""
		(layer "B.Cu")
		(at 105.224834 -245.487952)
		(property "Reference" "C2309"
			(at 0 0 0)
			(layer "B.SilkS")
			(hide yes)
			(effects
				(font
					(size 1.27 1.27)
				)
				(justify mirror)
			)
		)
		(property "Value" ""
			(at 0 0 0)
			(layer "B.Fab")
			(effects
				(font
					(size 1.27 1.27)
				)
				(justify mirror)
			)
		)
		(duplicate_pad_numbers_are_jumpers no)
		(fp_line
			(start -0.7874 -0.4064)
			(end -0.7874 0.4064)
			(stroke
				(width 0.1524)
				(type default)
			)
			(layer "B.SilkS")
		)
		(fp_line
			(start -0.7874 0.4064)
			(end 0.7874 0.4064)
			(stroke
				(width 0.1524)
				(type default)
			)
			(layer "B.SilkS")
		)
		(fp_line
			(start 0.7874 -0.4064)
			(end -0.7874 -0.4064)
			(stroke
				(width 0.1524)
				(type default)
			)
			(layer "B.SilkS")
		)
		(fp_line
			(start 0.7874 0.4064)
			(end 0.7874 -0.4064)
			(stroke
				(width 0.1524)
				(type default)
			)
			(layer "B.SilkS")
		)
		(fp_line
			(start -0.67945 -0.3048)
			(end -0.67945 0.3048)
			(stroke
				(width 0.1)
				(type default)
			)
			(layer "B.Fab")
		)
		(fp_line
			(start -0.67945 0.3048)
			(end -0.120396 0.3048)
			(stroke
				(width 0.1)
				(type default)
			)
			(layer "B.Fab")
		)
		(fp_line
			(start -0.12065 -0.3048)
			(end -0.67945 -0.3048)
			(stroke
				(width 0.1)
				(type default)
			)
			(layer "B.Fab")
		)
		(fp_line
			(start -0.12065 -0.2794)
			(end -0.12065 -0.3048)
			(stroke
				(width 0.1)
				(type default)
			)
			(layer "B.Fab")
		)
		(fp_line
			(start -0.120396 0.2794)
			(end 0.12065 0.2794)
			(stroke
				(width 0.1)
				(type default)
			)
			(layer "B.Fab")
		)
		(fp_line
			(start -0.120396 0.3048)
			(end -0.120396 0.2794)
			(stroke
				(width 0.1)
				(type default)
			)
			(layer "B.Fab")
		)
		(fp_line
			(start 0.12065 -0.305054)
			(end 0.12065 -0.2794)
			(stroke
				(width 0.1)
				(type default)
			)
			(layer "B.Fab")
		)
		(fp_line
			(start 0.12065 -0.2794)
			(end -0.12065 -0.2794)
			(stroke
				(width 0.1)
				(type default)
			)
			(layer "B.Fab")
		)
		(fp_line
			(start 0.12065 0.2794)
			(end 0.12065 0.3048)
			(stroke
				(width 0.1)
				(type default)
			)
			(layer "B.Fab")
		)
		(fp_line
			(start 0.12065 0.3048)
			(end 0.67945 0.3048)
			(stroke
				(width 0.1)
				(type default)
			)
			(layer "B.Fab")
		)
		(fp_line
			(start 0.67945 -0.305054)
			(end 0.12065 -0.305054)
			(stroke
				(width 0.1)
				(type default)
			)
			(layer "B.Fab")
		)
		(fp_line
			(start 0.67945 0.3048)
			(end 0.67945 -0.305054)
			(stroke
				(width 0.1)
				(type default)
			)
			(layer "B.Fab")
		)
		(pad "1" smd circle
			(at 0.40005 0 180)
			(size 0 0)
			(layers "B.Cu" "B.Mask" "B.Paste")
			(net "PVDDCR_CPU0_P1")
		)
		(pad "2" smd circle
			(at -0.40005 0 180)
			(size 0 0)
			(layers "B.Cu" "B.Mask" "B.Paste")
			(net "GND")
		)
	)
	(footprint ""
		(layer "B.Cu")
		(at 404.206202 -395.148562 90)
		(property "Reference" "C797"
			(at 0 0 90)
			(layer "B.SilkS")
			(hide yes)
			(effects
				(font
					(size 1.27 1.27)
				)
				(justify mirror)
			)
		)
		(property "Value" ""
			(at 0 0 90)
			(layer "B.Fab")
			(effects
				(font
					(size 1.27 1.27)
				)
				(justify mirror)
			)
		)
		(duplicate_pad_numbers_are_jumpers no)
		(fp_line
			(start 0.299974 -0.150114)
			(end -0.299974 -0.150114)
			(stroke
				(width 0.1)
				(type default)
			)
			(layer "B.Fab")
		)
		(fp_line
			(start -0.299974 -0.150114)
			(end -0.299974 0.150114)
			(stroke
				(width 0.1)
				(type default)
			)
			(layer "B.Fab")
		)
		(fp_line
			(start 0.299974 0.150114)
			(end 0.299974 -0.150114)
			(stroke
				(width 0.1)
				(type default)
			)
			(layer "B.Fab")
		)
		(fp_line
			(start -0.299974 0.150114)
			(end 0.299974 0.150114)
			(stroke
				(width 0.1)
				(type default)
			)
			(layer "B.Fab")
		)
		(pad "1" smd rect
			(at 0.2667 0 270)
			(size 0.3048 0.381)
			(layers "B.Cu" "B.Mask" "B.Paste")
			(net "P0V9_CPU0_RT2_2A")
		)
		(pad "2" smd rect
			(at -0.2667 0 270)
			(size 0.3048 0.381)
			(layers "B.Cu" "B.Mask" "B.Paste")
			(net "GND")
		)
	)
	(footprint ""
		(layer "B.Cu")
		(at 369.62588 -257.930142)
		(property "Reference" "C2544"
			(at 0 0 0)
			(layer "B.SilkS")
			(hide yes)
			(effects
				(font
					(size 1.27 1.27)
				)
				(justify mirror)
			)
		)
		(property "Value" ""
			(at 0 0 0)
			(layer "B.Fab")
			(effects
				(font
					(size 1.27 1.27)
				)
				(justify mirror)
			)
		)
		(duplicate_pad_numbers_are_jumpers no)
		(fp_line
			(start -0.7874 -0.4064)
			(end -0.7874 0.4064)
			(stroke
				(width 0.1524)
				(type default)
			)
			(layer "B.SilkS")
		)
		(fp_line
			(start -0.7874 0.4064)
			(end 0.7874 0.4064)
			(stroke
				(width 0.1524)
				(type default)
			)
			(layer "B.SilkS")
		)
		(fp_line
			(start 0.7874 -0.4064)
			(end -0.7874 -0.4064)
			(stroke
				(width 0.1524)
				(type default)
			)
			(layer "B.SilkS")
		)
		(fp_line
			(start 0.7874 0.4064)
			(end 0.7874 -0.4064)
			(stroke
				(width 0.1524)
				(type default)
			)
			(layer "B.SilkS")
		)
		(fp_line
			(start -0.67945 -0.3048)
			(end -0.67945 0.3048)
			(stroke
				(width 0.1)
				(type default)
			)
			(layer "B.Fab")
		)
		(fp_line
			(start -0.67945 0.3048)
			(end -0.120396 0.3048)
			(stroke
				(width 0.1)
				(type default)
			)
			(layer "B.Fab")
		)
		(fp_line
			(start -0.12065 -0.3048)
			(end -0.67945 -0.3048)
			(stroke
				(width 0.1)
				(type default)
			)
			(layer "B.Fab")
		)
		(fp_line
			(start -0.12065 -0.2794)
			(end -0.12065 -0.3048)
			(stroke
				(width 0.1)
				(type default)
			)
			(layer "B.Fab")
		)
		(fp_line
			(start -0.120396 0.2794)
			(end 0.12065 0.2794)
			(stroke
				(width 0.1)
				(type default)
			)
			(layer "B.Fab")
		)
		(fp_line
			(start -0.120396 0.3048)
			(end -0.120396 0.2794)
			(stroke
				(width 0.1)
				(type default)
			)
			(layer "B.Fab")
		)
		(fp_line
			(start 0.12065 -0.305054)
			(end 0.12065 -0.2794)
			(stroke
				(width 0.1)
				(type default)
			)
			(layer "B.Fab")
		)
		(fp_line
			(start 0.12065 -0.2794)
			(end -0.12065 -0.2794)
			(stroke
				(width 0.1)
				(type default)
			)
			(layer "B.Fab")
		)
		(fp_line
			(start 0.12065 0.2794)
			(end 0.12065 0.3048)
			(stroke
				(width 0.1)
				(type default)
			)
			(layer "B.Fab")
		)
		(fp_line
			(start 0.12065 0.3048)
			(end 0.67945 0.3048)
			(stroke
				(width 0.1)
				(type default)
			)
			(layer "B.Fab")
		)
		(fp_line
			(start 0.67945 -0.305054)
			(end 0.12065 -0.305054)
			(stroke
				(width 0.1)
				(type default)
			)
			(layer "B.Fab")
		)
		(fp_line
			(start 0.67945 0.3048)
			(end 0.67945 -0.305054)
			(stroke
				(width 0.1)
				(type default)
			)
			(layer "B.Fab")
		)
		(pad "1" smd circle
			(at 0.40005 0 180)
			(size 0 0)
			(layers "B.Cu" "B.Mask" "B.Paste")
			(net "PVDDCR_SOC_P0")
		)
		(pad "2" smd circle
			(at -0.40005 0 180)
			(size 0 0)
			(layers "B.Cu" "B.Mask" "B.Paste")
			(net "GND")
		)
	)
	(footprint ""
		(layer "B.Cu")
		(at 254.635 -339.63864 180)
		(property "Reference" "R1371"
			(at 0 0 0)
			(layer "B.SilkS")
			(hide yes)
			(effects
				(font
					(size 1.27 1.27)
				)
				(justify mirror)
			)
		)
		(property "Value" ""
			(at 0 0 0)
			(layer "B.Fab")
			(effects
				(font
					(size 1.27 1.27)
				)
				(justify mirror)
			)
		)
		(duplicate_pad_numbers_are_jumpers no)
		(fp_line
			(start 0.32512 0.175006)
			(end 0.32512 -0.175006)
			(stroke
				(width 0.1)
				(type default)
			)
			(layer "B.Fab")
		)
		(fp_line
			(start 0.32512 -0.175006)
			(end -0.32512 -0.175006)
			(stroke
				(width 0.1)
				(type default)
			)
			(layer "B.Fab")
		)
		(fp_line
			(start -0.32512 0.175006)
			(end 0.32512 0.175006)
			(stroke
				(width 0.1)
				(type default)
			)
			(layer "B.Fab")
		)
		(fp_line
			(start -0.32512 -0.175006)
			(end -0.32512 0.175006)
			(stroke
				(width 0.1)
				(type default)
			)
			(layer "B.Fab")
		)
		(pad "1" smd rect
			(at 0.2667 0)
			(size 0.3048 0.381)
			(layers "B.Cu" "B.Mask" "B.Paste")
			(net "P1V8_CPU0_RT_1D")
		)
		(pad "2" smd rect
			(at -0.2667 0 180)
			(size 0.3048 0.381)
			(layers "B.Cu" "B.Mask" "B.Paste")
			(net "SMB_RT_CPU0_P1_ROM_MUX_2D_R_SDA")
		)
	)
	(footprint ""
		(layer "B.Cu")
		(at 418.998908 -428.682912 180)
		(property "Reference" "R1209"
			(at 0 0 0)
			(layer "B.SilkS")
			(hide yes)
			(effects
				(font
					(size 1.27 1.27)
				)
				(justify mirror)
			)
		)
		(property "Value" ""
			(at 0 0 0)
			(layer "B.Fab")
			(effects
				(font
					(size 1.27 1.27)
				)
				(justify mirror)
			)
		)
		(duplicate_pad_numbers_are_jumpers no)
		(fp_line
			(start 0.32512 0.175006)
			(end 0.32512 -0.175006)
			(stroke
				(width 0.1)
				(type default)
			)
			(layer "B.Fab")
		)
		(fp_line
			(start 0.32512 -0.175006)
			(end -0.32512 -0.175006)
			(stroke
				(width 0.1)
				(type default)
			)
			(layer "B.Fab")
		)
		(fp_line
			(start -0.32512 0.175006)
			(end 0.32512 0.175006)
			(stroke
				(width 0.1)
				(type default)
			)
			(layer "B.Fab")
		)
		(fp_line
			(start -0.32512 -0.175006)
			(end -0.32512 0.175006)
			(stroke
				(width 0.1)
				(type default)
			)
			(layer "B.Fab")
		)
		(pad "1" smd rect
			(at 0.2667 0)
			(size 0.3048 0.381)
			(layers "B.Cu" "B.Mask" "B.Paste")
			(net "RST_SMB_RT_ROM_R1_N")
		)
		(pad "2" smd rect
			(at -0.2667 0 180)
			(size 0.3048 0.381)
			(layers "B.Cu" "B.Mask" "B.Paste")
			(net "FM_SMB_RT_ROM_MUX8_SEL")
		)
	)
	(footprint ""
		(layer "B.Cu")
		(at 231.829102 -329.365102 180)
		(property "Reference" "R1249"
			(at 0 0 0)
			(layer "B.SilkS")
			(hide yes)
			(effects
				(font
					(size 1.27 1.27)
				)
				(justify mirror)
			)
		)
		(property "Value" ""
			(at 0 0 0)
			(layer "B.Fab")
			(effects
				(font
					(size 1.27 1.27)
				)
				(justify mirror)
			)
		)
		(duplicate_pad_numbers_are_jumpers no)
		(fp_line
			(start 0.7874 0.4064)
			(end 0.7874 -0.4064)
			(stroke
				(width 0.1524)
				(type default)
			)
			(layer "B.SilkS")
		)
		(fp_line
			(start 0.7874 -0.4064)
			(end -0.7874 -0.4064)
			(stroke
				(width 0.1524)
				(type default)
			)
			(layer "B.SilkS")
		)
		(fp_line
			(start -0.7874 0.4064)
			(end 0.7874 0.4064)
			(stroke
				(width 0.1524)
				(type default)
			)
			(layer "B.SilkS")
		)
		(fp_line
			(start -0.7874 -0.4064)
			(end -0.7874 0.4064)
			(stroke
				(width 0.1524)
				(type default)
			)
			(layer "B.SilkS")
		)
		(fp_line
			(start 0.67945 0.3048)
			(end 0.67945 -0.305054)
			(stroke
				(width 0.1)
				(type default)
			)
			(layer "B.Fab")
		)
		(fp_line
			(start 0.67945 -0.305054)
			(end 0.12065 -0.305054)
			(stroke
				(width 0.1)
				(type default)
			)
			(layer "B.Fab")
		)
		(fp_line
			(start 0.12065 0.3048)
			(end 0.67945 0.3048)
			(stroke
				(width 0.1)
				(type default)
			)
			(layer "B.Fab")
		)
		(fp_line
			(start 0.12065 0.2794)
			(end 0.12065 0.3048)
			(stroke
				(width 0.1)
				(type default)
			)
			(layer "B.Fab")
		)
		(fp_line
			(start 0.12065 -0.2794)
			(end -0.12065 -0.2794)
			(stroke
				(width 0.1)
				(type default)
			)
			(layer "B.Fab")
		)
		(fp_line
			(start 0.12065 -0.305054)
			(end 0.12065 -0.2794)
			(stroke
				(width 0.1)
				(type default)
			)
			(layer "B.Fab")
		)
		(fp_line
			(start -0.120396 0.3048)
			(end -0.120396 0.2794)
			(stroke
				(width 0.1)
				(type default)
			)
			(layer "B.Fab")
		)
		(fp_line
			(start -0.120396 0.2794)
			(end 0.12065 0.2794)
			(stroke
				(width 0.1)
				(type default)
			)
			(layer "B.Fab")
		)
		(fp_line
			(start -0.12065 -0.2794)
			(end -0.12065 -0.3048)
			(stroke
				(width 0.1)
				(type default)
			)
			(layer "B.Fab")
		)
		(fp_line
			(start -0.12065 -0.3048)
			(end -0.67945 -0.3048)
			(stroke
				(width 0.1)
				(type default)
			)
			(layer "B.Fab")
		)
		(fp_line
			(start -0.67945 0.3048)
			(end -0.120396 0.3048)
			(stroke
				(width 0.1)
				(type default)
			)
			(layer "B.Fab")
		)
		(fp_line
			(start -0.67945 -0.3048)
			(end -0.67945 0.3048)
			(stroke
				(width 0.1)
				(type default)
			)
			(layer "B.Fab")
		)
		(pad "1" smd rect
			(at 0.40005 0 180)
			(size 0.4572 0.508)
			(layers "B.Cu" "B.Mask" "B.Paste")
			(net "PVDD18_S5_P1_ADC")
		)
		(pad "2" smd rect
			(at -0.40005 0 180)
			(size 0.4572 0.508)
			(layers "B.Cu" "B.Mask" "B.Paste")
			(net "PVDD18_S5_P1_ADC_MAM")
		)
	)
	(footprint ""
		(layer "B.Cu")
		(at 423.256456 -194.88531 180)
		(property "Reference" "R1575"
			(at 0 0 0)
			(layer "B.SilkS")
			(hide yes)
			(effects
				(font
					(size 1.27 1.27)
				)
				(justify mirror)
			)
		)
		(property "Value" ""
			(at 0 0 0)
			(layer "B.Fab")
			(effects
				(font
					(size 1.27 1.27)
				)
				(justify mirror)
			)
		)
		(duplicate_pad_numbers_are_jumpers no)
		(fp_line
			(start 0.7874 0.4064)
			(end 0.7874 -0.4064)
			(stroke
				(width 0.1524)
				(type default)
			)
			(layer "B.SilkS")
		)
		(fp_line
			(start 0.7874 -0.4064)
			(end -0.7874 -0.4064)
			(stroke
				(width 0.1524)
				(type default)
			)
			(layer "B.SilkS")
		)
		(fp_line
			(start -0.7874 0.4064)
			(end 0.7874 0.4064)
			(stroke
				(width 0.1524)
				(type default)
			)
			(layer "B.SilkS")
		)
		(fp_line
			(start -0.7874 -0.4064)
			(end -0.7874 0.4064)
			(stroke
				(width 0.1524)
				(type default)
			)
			(layer "B.SilkS")
		)
		(fp_line
			(start 0.67945 0.3048)
			(end 0.67945 -0.305054)
			(stroke
				(width 0.1)
				(type default)
			)
			(layer "B.Fab")
		)
		(fp_line
			(start 0.67945 -0.305054)
			(end 0.12065 -0.305054)
			(stroke
				(width 0.1)
				(type default)
			)
			(layer "B.Fab")
		)
		(fp_line
			(start 0.12065 0.3048)
			(end 0.67945 0.3048)
			(stroke
				(width 0.1)
				(type default)
			)
			(layer "B.Fab")
		)
		(fp_line
			(start 0.12065 0.2794)
			(end 0.12065 0.3048)
			(stroke
				(width 0.1)
				(type default)
			)
			(layer "B.Fab")
		)
		(fp_line
			(start 0.12065 -0.2794)
			(end -0.12065 -0.2794)
			(stroke
				(width 0.1)
				(type default)
			)
			(layer "B.Fab")
		)
		(fp_line
			(start 0.12065 -0.305054)
			(end 0.12065 -0.2794)
			(stroke
				(width 0.1)
				(type default)
			)
			(layer "B.Fab")
		)
		(fp_line
			(start -0.120396 0.3048)
			(end -0.120396 0.2794)
			(stroke
				(width 0.1)
				(type default)
			)
			(layer "B.Fab")
		)
		(fp_line
			(start -0.120396 0.2794)
			(end 0.12065 0.2794)
			(stroke
				(width 0.1)
				(type default)
			)
			(layer "B.Fab")
		)
		(fp_line
			(start -0.12065 -0.2794)
			(end -0.12065 -0.3048)
			(stroke
				(width 0.1)
				(type default)
			)
			(layer "B.Fab")
		)
		(fp_line
			(start -0.12065 -0.3048)
			(end -0.67945 -0.3048)
			(stroke
				(width 0.1)
				(type default)
			)
			(layer "B.Fab")
		)
		(fp_line
			(start -0.67945 0.3048)
			(end -0.120396 0.3048)
			(stroke
				(width 0.1)
				(type default)
			)
			(layer "B.Fab")
		)
		(fp_line
			(start -0.67945 -0.3048)
			(end -0.67945 0.3048)
			(stroke
				(width 0.1)
				(type default)
			)
			(layer "B.Fab")
		)
		(pad "1" smd circle
			(at 0.40005 0)
			(size 0 0)
			(layers "B.Cu" "B.Mask" "B.Paste")
			(net "I3C_SPD_DDRGL_CPU0_SCL")
		)
		(pad "2" smd circle
			(at -0.40005 0)
			(size 0 0)
			(layers "B.Cu" "B.Mask" "B.Paste")
			(net "I3C_SPD_DDRH_CPU0_SCL")
		)
	)
	(footprint ""
		(layer "B.Cu")
		(at 197.523608 -105.497376)
		(property "Reference" "R229"
			(at 0 0 0)
			(layer "B.SilkS")
			(hide yes)
			(effects
				(font
					(size 1.27 1.27)
				)
				(justify mirror)
			)
		)
		(property "Value" ""
			(at 0 0 0)
			(layer "B.Fab")
			(effects
				(font
					(size 1.27 1.27)
				)
				(justify mirror)
			)
		)
		(duplicate_pad_numbers_are_jumpers no)
		(fp_line
			(start -0.7874 -0.4064)
			(end -0.7874 0.4064)
			(stroke
				(width 0.1524)
				(type default)
			)
			(layer "B.SilkS")
		)
		(fp_line
			(start -0.7874 0.4064)
			(end 0.7874 0.4064)
			(stroke
				(width 0.1524)
				(type default)
			)
			(layer "B.SilkS")
		)
		(fp_line
			(start 0.7874 -0.4064)
			(end -0.7874 -0.4064)
			(stroke
				(width 0.1524)
				(type default)
			)
			(layer "B.SilkS")
		)
		(fp_line
			(start 0.7874 0.4064)
			(end 0.7874 -0.4064)
			(stroke
				(width 0.1524)
				(type default)
			)
			(layer "B.SilkS")
		)
		(fp_line
			(start -0.67945 -0.3048)
			(end -0.67945 0.3048)
			(stroke
				(width 0.1)
				(type default)
			)
			(layer "B.Fab")
		)
		(fp_line
			(start -0.67945 0.3048)
			(end -0.120396 0.3048)
			(stroke
				(width 0.1)
				(type default)
			)
			(layer "B.Fab")
		)
		(fp_line
			(start -0.12065 -0.3048)
			(end -0.67945 -0.3048)
			(stroke
				(width 0.1)
				(type default)
			)
			(layer "B.Fab")
		)
		(fp_line
			(start -0.12065 -0.2794)
			(end -0.12065 -0.3048)
			(stroke
				(width 0.1)
				(type default)
			)
			(layer "B.Fab")
		)
		(fp_line
			(start -0.120396 0.2794)
			(end 0.12065 0.2794)
			(stroke
				(width 0.1)
				(type default)
			)
			(layer "B.Fab")
		)
		(fp_line
			(start -0.120396 0.3048)
			(end -0.120396 0.2794)
			(stroke
				(width 0.1)
				(type default)
			)
			(layer "B.Fab")
		)
		(fp_line
			(start 0.12065 -0.305054)
			(end 0.12065 -0.2794)
			(stroke
				(width 0.1)
				(type default)
			)
			(layer "B.Fab")
		)
		(fp_line
			(start 0.12065 -0.2794)
			(end -0.12065 -0.2794)
			(stroke
				(width 0.1)
				(type default)
			)
			(layer "B.Fab")
		)
		(fp_line
			(start 0.12065 0.2794)
			(end 0.12065 0.3048)
			(stroke
				(width 0.1)
				(type default)
			)
			(layer "B.Fab")
		)
		(fp_line
			(start 0.12065 0.3048)
			(end 0.67945 0.3048)
			(stroke
				(width 0.1)
				(type default)
			)
			(layer "B.Fab")
		)
		(fp_line
			(start 0.67945 -0.305054)
			(end 0.12065 -0.305054)
			(stroke
				(width 0.1)
				(type default)
			)
			(layer "B.Fab")
		)
		(fp_line
			(start 0.67945 0.3048)
			(end 0.67945 -0.305054)
			(stroke
				(width 0.1)
				(type default)
			)
			(layer "B.Fab")
		)
		(pad "1" smd circle
			(at 0.40005 0 180)
			(size 0 0)
			(layers "B.Cu" "B.Mask" "B.Paste")
			(net "PVDDIO_P0_EN")
		)
		(pad "2" smd circle
			(at -0.40005 0 180)
			(size 0 0)
			(layers "B.Cu" "B.Mask" "B.Paste")
			(net "FM_PVDDIO_P0_EN")
		)
	)
	(footprint ""
		(layer "B.Cu")
		(at 101.414834 -245.487952 180)
		(property "Reference" "C2346"
			(at 0 0 0)
			(layer "B.SilkS")
			(hide yes)
			(effects
				(font
					(size 1.27 1.27)
				)
				(justify mirror)
			)
		)
		(property "Value" ""
			(at 0 0 0)
			(layer "B.Fab")
			(effects
				(font
					(size 1.27 1.27)
				)
				(justify mirror)
			)
		)
		(duplicate_pad_numbers_are_jumpers no)
		(fp_line
			(start 0.7874 0.4064)
			(end 0.7874 -0.4064)
			(stroke
				(width 0.1524)
				(type default)
			)
			(layer "B.SilkS")
		)
		(fp_line
			(start 0.7874 -0.4064)
			(end -0.7874 -0.4064)
			(stroke
				(width 0.1524)
				(type default)
			)
			(layer "B.SilkS")
		)
		(fp_line
			(start -0.7874 0.4064)
			(end 0.7874 0.4064)
			(stroke
				(width 0.1524)
				(type default)
			)
			(layer "B.SilkS")
		)
		(fp_line
			(start -0.7874 -0.4064)
			(end -0.7874 0.4064)
			(stroke
				(width 0.1524)
				(type default)
			)
			(layer "B.SilkS")
		)
		(fp_line
			(start 0.67945 0.3048)
			(end 0.67945 -0.305054)
			(stroke
				(width 0.1)
				(type default)
			)
			(layer "B.Fab")
		)
		(fp_line
			(start 0.67945 -0.305054)
			(end 0.12065 -0.305054)
			(stroke
				(width 0.1)
				(type default)
			)
			(layer "B.Fab")
		)
		(fp_line
			(start 0.12065 0.3048)
			(end 0.67945 0.3048)
			(stroke
				(width 0.1)
				(type default)
			)
			(layer "B.Fab")
		)
		(fp_line
			(start 0.12065 0.2794)
			(end 0.12065 0.3048)
			(stroke
				(width 0.1)
				(type default)
			)
			(layer "B.Fab")
		)
		(fp_line
			(start 0.12065 -0.2794)
			(end -0.12065 -0.2794)
			(stroke
				(width 0.1)
				(type default)
			)
			(layer "B.Fab")
		)
		(fp_line
			(start 0.12065 -0.305054)
			(end 0.12065 -0.2794)
			(stroke
				(width 0.1)
				(type default)
			)
			(layer "B.Fab")
		)
		(fp_line
			(start -0.120396 0.3048)
			(end -0.120396 0.2794)
			(stroke
				(width 0.1)
				(type default)
			)
			(layer "B.Fab")
		)
		(fp_line
			(start -0.120396 0.2794)
			(end 0.12065 0.2794)
			(stroke
				(width 0.1)
				(type default)
			)
			(layer "B.Fab")
		)
		(fp_line
			(start -0.12065 -0.2794)
			(end -0.12065 -0.3048)
			(stroke
				(width 0.1)
				(type default)
			)
			(layer "B.Fab")
		)
		(fp_line
			(start -0.12065 -0.3048)
			(end -0.67945 -0.3048)
			(stroke
				(width 0.1)
				(type default)
			)
			(layer "B.Fab")
		)
		(fp_line
			(start -0.67945 0.3048)
			(end -0.120396 0.3048)
			(stroke
				(width 0.1)
				(type default)
			)
			(layer "B.Fab")
		)
		(fp_line
			(start -0.67945 -0.3048)
			(end -0.67945 0.3048)
			(stroke
				(width 0.1)
				(type default)
			)
			(layer "B.Fab")
		)
		(pad "1" smd circle
			(at 0.40005 0)
			(size 0 0)
			(layers "B.Cu" "B.Mask" "B.Paste")
			(net "PVDDCR_CPU0_P1")
		)
		(pad "2" smd circle
			(at -0.40005 0)
			(size 0 0)
			(layers "B.Cu" "B.Mask" "B.Paste")
			(net "GND")
		)
	)
	(footprint ""
		(layer "B.Cu")
		(at 422.19245 -428.757334 180)
		(property "Reference" "C1071"
			(at 0 0 0)
			(layer "B.SilkS")
			(hide yes)
			(effects
				(font
					(size 1.27 1.27)
				)
				(justify mirror)
			)
		)
		(property "Value" ""
			(at 0 0 0)
			(layer "B.Fab")
			(effects
				(font
					(size 1.27 1.27)
				)
				(justify mirror)
			)
		)
		(duplicate_pad_numbers_are_jumpers no)
		(fp_line
			(start 0.299974 0.150114)
			(end 0.299974 -0.150114)
			(stroke
				(width 0.1)
				(type default)
			)
			(layer "B.Fab")
		)
		(fp_line
			(start 0.299974 -0.150114)
			(end -0.299974 -0.150114)
			(stroke
				(width 0.1)
				(type default)
			)
			(layer "B.Fab")
		)
		(fp_line
			(start -0.299974 0.150114)
			(end 0.299974 0.150114)
			(stroke
				(width 0.1)
				(type default)
			)
			(layer "B.Fab")
		)
		(fp_line
			(start -0.299974 -0.150114)
			(end -0.299974 0.150114)
			(stroke
				(width 0.1)
				(type default)
			)
			(layer "B.Fab")
		)
		(pad "1" smd rect
			(at 0.2667 0)
			(size 0.3048 0.381)
			(layers "B.Cu" "B.Mask" "B.Paste")
			(net "P3V3_AUX")
		)
		(pad "2" smd rect
			(at -0.2667 0)
			(size 0.3048 0.381)
			(layers "B.Cu" "B.Mask" "B.Paste")
			(net "GND")
		)
	)
	(footprint ""
		(layer "B.Cu")
		(at 479.088958 -437.516778 180)
		(property "Reference" "DB11"
			(at 2.581402 -8.320786 270)
			(unlocked yes)
			(layer "B.SilkS")
			(effects
				(font
					(size 0.7874 0.5842)
					(thickness 0.1524)
				)
				(justify left mirror)
			)
		)
		(property "Value" ""
			(at 0 0 0)
			(layer "B.Fab")
			(effects
				(font
					(size 1.27 1.27)
				)
				(justify mirror)
			)
		)
		(duplicate_pad_numbers_are_jumpers no)
		(fp_line
			(start 3.330702 -4.771136)
			(end -3.330702 -4.771136)
			(stroke
				(width 0.1524)
				(type default)
			)
			(layer "B.SilkS")
		)
		(fp_line
			(start 0 4.011168)
			(end 3.330702 -4.771136)
			(stroke
				(width 0.1524)
				(type default)
			)
			(layer "B.SilkS")
		)
		(fp_line
			(start -3.330702 -4.771136)
			(end 0 4.011168)
			(stroke
				(width 0.1524)
				(type default)
			)
			(layer "B.SilkS")
		)
		(fp_line
			(start 3.330702 -4.771136)
			(end -3.330702 -4.771136)
			(stroke
				(width 0.1)
				(type default)
			)
			(layer "B.Fab")
		)
		(fp_line
			(start 0 4.011168)
			(end 3.330702 -4.771136)
			(stroke
				(width 0.1)
				(type default)
			)
			(layer "B.Fab")
		)
		(fp_line
			(start -3.330702 -4.771136)
			(end 0 4.011168)
			(stroke
				(width 0.1)
				(type default)
			)
			(layer "B.Fab")
		)
		(pad "1" thru_hole circle
			(at 0 0)
			(size 2.159 2.159)
			(drill 1.7018)
			(layers "*.Cu" "*.Mask")
			(remove_unused_layers no)
			(net "T1_GND")
			(clearance 0.0254)
			(thermal_gap 0.0254)
		)
		(pad "2" thru_hole circle
			(at 1.27 -3.348736)
			(size 2.159 2.159)
			(drill 1.7018)
			(layers "*.Cu" "*.Mask")
			(remove_unused_layers no)
			(net "TDR_SE_50_OHM_IN4")
			(clearance 0.0254)
			(thermal_gap 0.0254)
		)
		(pad "3" thru_hole circle
			(at -1.27 -3.348736)
			(size 2.159 2.159)
			(drill 1.7018)
			(layers "*.Cu" "*.Mask")
			(remove_unused_layers no)
			(net "TDR_SE_50_OHM_IN4")
			(clearance 0.0254)
			(thermal_gap 0.0254)
		)
	)
	(footprint ""
		(layer "B.Cu")
		(at 347.040454 -255.84531 180)
		(property "Reference" "C2524"
			(at 0 0 0)
			(layer "B.SilkS")
			(hide yes)
			(effects
				(font
					(size 1.27 1.27)
				)
				(justify mirror)
			)
		)
		(property "Value" ""
			(at 0 0 0)
			(layer "B.Fab")
			(effects
				(font
					(size 1.27 1.27)
				)
				(justify mirror)
			)
		)
		(duplicate_pad_numbers_are_jumpers no)
		(fp_line
			(start 0.7874 0.4064)
			(end 0.7874 -0.4064)
			(stroke
				(width 0.1524)
				(type default)
			)
			(layer "B.SilkS")
		)
		(fp_line
			(start 0.7874 -0.4064)
			(end -0.7874 -0.4064)
			(stroke
				(width 0.1524)
				(type default)
			)
			(layer "B.SilkS")
		)
		(fp_line
			(start -0.7874 0.4064)
			(end 0.7874 0.4064)
			(stroke
				(width 0.1524)
				(type default)
			)
			(layer "B.SilkS")
		)
		(fp_line
			(start -0.7874 -0.4064)
			(end -0.7874 0.4064)
			(stroke
				(width 0.1524)
				(type default)
			)
			(layer "B.SilkS")
		)
		(fp_line
			(start 0.67945 0.3048)
			(end 0.67945 -0.305054)
			(stroke
				(width 0.1)
				(type default)
			)
			(layer "B.Fab")
		)
		(fp_line
			(start 0.67945 -0.305054)
			(end 0.12065 -0.305054)
			(stroke
				(width 0.1)
				(type default)
			)
			(layer "B.Fab")
		)
		(fp_line
			(start 0.12065 0.3048)
			(end 0.67945 0.3048)
			(stroke
				(width 0.1)
				(type default)
			)
			(layer "B.Fab")
		)
		(fp_line
			(start 0.12065 0.2794)
			(end 0.12065 0.3048)
			(stroke
				(width 0.1)
				(type default)
			)
			(layer "B.Fab")
		)
		(fp_line
			(start 0.12065 -0.2794)
			(end -0.12065 -0.2794)
			(stroke
				(width 0.1)
				(type default)
			)
			(layer "B.Fab")
		)
		(fp_line
			(start 0.12065 -0.305054)
			(end 0.12065 -0.2794)
			(stroke
				(width 0.1)
				(type default)
			)
			(layer "B.Fab")
		)
		(fp_line
			(start -0.120396 0.3048)
			(end -0.120396 0.2794)
			(stroke
				(width 0.1)
				(type default)
			)
			(layer "B.Fab")
		)
		(fp_line
			(start -0.120396 0.2794)
			(end 0.12065 0.2794)
			(stroke
				(width 0.1)
				(type default)
			)
			(layer "B.Fab")
		)
		(fp_line
			(start -0.12065 -0.2794)
			(end -0.12065 -0.3048)
			(stroke
				(width 0.1)
				(type default)
			)
			(layer "B.Fab")
		)
		(fp_line
			(start -0.12065 -0.3048)
			(end -0.67945 -0.3048)
			(stroke
				(width 0.1)
				(type default)
			)
			(layer "B.Fab")
		)
		(fp_line
			(start -0.67945 0.3048)
			(end -0.120396 0.3048)
			(stroke
				(width 0.1)
				(type default)
			)
			(layer "B.Fab")
		)
		(fp_line
			(start -0.67945 -0.3048)
			(end -0.67945 0.3048)
			(stroke
				(width 0.1)
				(type default)
			)
			(layer "B.Fab")
		)
		(pad "1" smd circle
			(at 0.40005 0)
			(size 0 0)
			(layers "B.Cu" "B.Mask" "B.Paste")
			(net "PVDD18_S5_P0")
		)
		(pad "2" smd circle
			(at -0.40005 0)
			(size 0 0)
			(layers "B.Cu" "B.Mask" "B.Paste")
			(net "GND")
		)
	)
	(footprint ""
		(layer "B.Cu")
		(at 387.278626 -395.148562 90)
		(property "Reference" "C1027"
			(at 0 0 90)
			(layer "B.SilkS")
			(hide yes)
			(effects
				(font
					(size 1.27 1.27)
				)
				(justify mirror)
			)
		)
		(property "Value" ""
			(at 0 0 90)
			(layer "B.Fab")
			(effects
				(font
					(size 1.27 1.27)
				)
				(justify mirror)
			)
		)
		(duplicate_pad_numbers_are_jumpers no)
		(fp_line
			(start 0.299974 -0.150114)
			(end -0.299974 -0.150114)
			(stroke
				(width 0.1)
				(type default)
			)
			(layer "B.Fab")
		)
		(fp_line
			(start -0.299974 -0.150114)
			(end -0.299974 0.150114)
			(stroke
				(width 0.1)
				(type default)
			)
			(layer "B.Fab")
		)
		(fp_line
			(start 0.299974 0.150114)
			(end 0.299974 -0.150114)
			(stroke
				(width 0.1)
				(type default)
			)
			(layer "B.Fab")
		)
		(fp_line
			(start -0.299974 0.150114)
			(end 0.299974 0.150114)
			(stroke
				(width 0.1)
				(type default)
			)
			(layer "B.Fab")
		)
		(pad "1" smd rect
			(at 0.2667 0 270)
			(size 0.3048 0.381)
			(layers "B.Cu" "B.Mask" "B.Paste")
			(net "P0V9_CPU0_RT3_2A")
		)
		(pad "2" smd rect
			(at -0.2667 0 270)
			(size 0.3048 0.381)
			(layers "B.Cu" "B.Mask" "B.Paste")
			(net "GND")
		)
	)
	(footprint ""
		(layer "B.Cu")
		(at 184.480708 -422.208452 90)
		(property "Reference" "C8015"
			(at 0 0 90)
			(layer "B.SilkS")
			(hide yes)
			(effects
				(font
					(size 1.27 1.27)
				)
				(justify mirror)
			)
		)
		(property "Value" ""
			(at 0 0 90)
			(layer "B.Fab")
			(effects
				(font
					(size 1.27 1.27)
				)
				(justify mirror)
			)
		)
		(duplicate_pad_numbers_are_jumpers no)
		(fp_line
			(start 0.7874 -0.4064)
			(end -0.7874 -0.4064)
			(stroke
				(width 0.1524)
				(type default)
			)
			(layer "B.SilkS")
		)
		(fp_line
			(start -0.7874 -0.4064)
			(end -0.7874 0.4064)
			(stroke
				(width 0.1524)
				(type default)
			)
			(layer "B.SilkS")
		)
		(fp_line
			(start 0.7874 0.4064)
			(end 0.7874 -0.4064)
			(stroke
				(width 0.1524)
				(type default)
			)
			(layer "B.SilkS")
		)
		(fp_line
			(start -0.7874 0.4064)
			(end 0.7874 0.4064)
			(stroke
				(width 0.1524)
				(type default)
			)
			(layer "B.SilkS")
		)
		(fp_line
			(start 0.67945 -0.305054)
			(end 0.12065 -0.305054)
			(stroke
				(width 0.1)
				(type default)
			)
			(layer "B.Fab")
		)
		(fp_line
			(start 0.12065 -0.305054)
			(end 0.12065 -0.2794)
			(stroke
				(width 0.1)
				(type default)
			)
			(layer "B.Fab")
		)
		(fp_line
			(start -0.12065 -0.3048)
			(end -0.67945 -0.3048)
			(stroke
				(width 0.1)
				(type default)
			)
			(layer "B.Fab")
		)
		(fp_line
			(start -0.67945 -0.3048)
			(end -0.67945 0.3048)
			(stroke
				(width 0.1)
				(type default)
			)
			(layer "B.Fab")
		)
		(fp_line
			(start 0.12065 -0.2794)
			(end -0.12065 -0.2794)
			(stroke
				(width 0.1)
				(type default)
			)
			(layer "B.Fab")
		)
		(fp_line
			(start -0.12065 -0.2794)
			(end -0.12065 -0.3048)
			(stroke
				(width 0.1)
				(type default)
			)
			(layer "B.Fab")
		)
		(fp_line
			(start 0.12065 0.2794)
			(end 0.12065 0.3048)
			(stroke
				(width 0.1)
				(type default)
			)
			(layer "B.Fab")
		)
		(fp_line
			(start -0.120396 0.2794)
			(end 0.12065 0.2794)
			(stroke
				(width 0.1)
				(type default)
			)
			(layer "B.Fab")
		)
		(fp_line
			(start 0.67945 0.3048)
			(end 0.67945 -0.305054)
			(stroke
				(width 0.1)
				(type default)
			)
			(layer "B.Fab")
		)
		(fp_line
			(start 0.12065 0.3048)
			(end 0.67945 0.3048)
			(stroke
				(width 0.1)
				(type default)
			)
			(layer "B.Fab")
		)
		(fp_line
			(start -0.120396 0.3048)
			(end -0.120396 0.2794)
			(stroke
				(width 0.1)
				(type default)
			)
			(layer "B.Fab")
		)
		(fp_line
			(start -0.67945 0.3048)
			(end -0.120396 0.3048)
			(stroke
				(width 0.1)
				(type default)
			)
			(layer "B.Fab")
		)
		(pad "1" smd circle
			(at 0.40005 0 270)
			(size 0 0)
			(layers "B.Cu" "B.Mask" "B.Paste")
			(net "HSC_OC_VOL")
		)
		(pad "2" smd circle
			(at -0.40005 0 270)
			(size 0 0)
			(layers "B.Cu" "B.Mask" "B.Paste")
			(net "GND")
		)
	)
	(footprint ""
		(layer "B.Cu")
		(at 231.034082 -328.25182)
		(property "Reference" "R1254"
			(at 0 0 0)
			(layer "B.SilkS")
			(hide yes)
			(effects
				(font
					(size 1.27 1.27)
				)
				(justify mirror)
			)
		)
		(property "Value" ""
			(at 0 0 0)
			(layer "B.Fab")
			(effects
				(font
					(size 1.27 1.27)
				)
				(justify mirror)
			)
		)
		(duplicate_pad_numbers_are_jumpers no)
		(fp_line
			(start -0.7874 -0.4064)
			(end -0.7874 0.4064)
			(stroke
				(width 0.1524)
				(type default)
			)
			(layer "B.SilkS")
		)
		(fp_line
			(start -0.7874 0.4064)
			(end 0.7874 0.4064)
			(stroke
				(width 0.1524)
				(type default)
			)
			(layer "B.SilkS")
		)
		(fp_line
			(start 0.7874 -0.4064)
			(end -0.7874 -0.4064)
			(stroke
				(width 0.1524)
				(type default)
			)
			(layer "B.SilkS")
		)
		(fp_line
			(start 0.7874 0.4064)
			(end 0.7874 -0.4064)
			(stroke
				(width 0.1524)
				(type default)
			)
			(layer "B.SilkS")
		)
		(fp_line
			(start -0.67945 -0.3048)
			(end -0.67945 0.3048)
			(stroke
				(width 0.1)
				(type default)
			)
			(layer "B.Fab")
		)
		(fp_line
			(start -0.67945 0.3048)
			(end -0.120396 0.3048)
			(stroke
				(width 0.1)
				(type default)
			)
			(layer "B.Fab")
		)
		(fp_line
			(start -0.12065 -0.3048)
			(end -0.67945 -0.3048)
			(stroke
				(width 0.1)
				(type default)
			)
			(layer "B.Fab")
		)
		(fp_line
			(start -0.12065 -0.2794)
			(end -0.12065 -0.3048)
			(stroke
				(width 0.1)
				(type default)
			)
			(layer "B.Fab")
		)
		(fp_line
			(start -0.120396 0.2794)
			(end 0.12065 0.2794)
			(stroke
				(width 0.1)
				(type default)
			)
			(layer "B.Fab")
		)
		(fp_line
			(start -0.120396 0.3048)
			(end -0.120396 0.2794)
			(stroke
				(width 0.1)
				(type default)
			)
			(layer "B.Fab")
		)
		(fp_line
			(start 0.12065 -0.305054)
			(end 0.12065 -0.2794)
			(stroke
				(width 0.1)
				(type default)
			)
			(layer "B.Fab")
		)
		(fp_line
			(start 0.12065 -0.2794)
			(end -0.12065 -0.2794)
			(stroke
				(width 0.1)
				(type default)
			)
			(layer "B.Fab")
		)
		(fp_line
			(start 0.12065 0.2794)
			(end 0.12065 0.3048)
			(stroke
				(width 0.1)
				(type default)
			)
			(layer "B.Fab")
		)
		(fp_line
			(start 0.12065 0.3048)
			(end 0.67945 0.3048)
			(stroke
				(width 0.1)
				(type default)
			)
			(layer "B.Fab")
		)
		(fp_line
			(start 0.67945 -0.305054)
			(end 0.12065 -0.305054)
			(stroke
				(width 0.1)
				(type default)
			)
			(layer "B.Fab")
		)
		(fp_line
			(start 0.67945 0.3048)
			(end 0.67945 -0.305054)
			(stroke
				(width 0.1)
				(type default)
			)
			(layer "B.Fab")
		)
		(pad "1" smd rect
			(at 0.40005 0)
			(size 0.4572 0.508)
			(layers "B.Cu" "B.Mask" "B.Paste")
			(net "PVDD18_S5_P0_ADC")
		)
		(pad "2" smd rect
			(at -0.40005 0)
			(size 0.4572 0.508)
			(layers "B.Cu" "B.Mask" "B.Paste")
			(net "PVDD18_S5_P0_ADC_TIC")
		)
	)
	(footprint ""
		(layer "B.Cu")
		(at 163.886388 -13.65504 90)
		(property "Reference" "R2424"
			(at 0 0 90)
			(layer "B.SilkS")
			(hide yes)
			(effects
				(font
					(size 1.27 1.27)
				)
				(justify mirror)
			)
		)
		(property "Value" ""
			(at 0 0 90)
			(layer "B.Fab")
			(effects
				(font
					(size 1.27 1.27)
				)
				(justify mirror)
			)
		)
		(duplicate_pad_numbers_are_jumpers no)
		(fp_line
			(start 0.7874 -0.4064)
			(end -0.7874 -0.4064)
			(stroke
				(width 0.1524)
				(type default)
			)
			(layer "B.SilkS")
		)
		(fp_line
			(start -0.7874 -0.4064)
			(end -0.7874 0.4064)
			(stroke
				(width 0.1524)
				(type default)
			)
			(layer "B.SilkS")
		)
		(fp_line
			(start 0.7874 0.4064)
			(end 0.7874 -0.4064)
			(stroke
				(width 0.1524)
				(type default)
			)
			(layer "B.SilkS")
		)
		(fp_line
			(start -0.7874 0.4064)
			(end 0.7874 0.4064)
			(stroke
				(width 0.1524)
				(type default)
			)
			(layer "B.SilkS")
		)
		(fp_line
			(start 0.67945 -0.305054)
			(end 0.12065 -0.305054)
			(stroke
				(width 0.1)
				(type default)
			)
			(layer "B.Fab")
		)
		(fp_line
			(start 0.12065 -0.305054)
			(end 0.12065 -0.2794)
			(stroke
				(width 0.1)
				(type default)
			)
			(layer "B.Fab")
		)
		(fp_line
			(start -0.12065 -0.3048)
			(end -0.67945 -0.3048)
			(stroke
				(width 0.1)
				(type default)
			)
			(layer "B.Fab")
		)
		(fp_line
			(start -0.67945 -0.3048)
			(end -0.67945 0.3048)
			(stroke
				(width 0.1)
				(type default)
			)
			(layer "B.Fab")
		)
		(fp_line
			(start 0.12065 -0.2794)
			(end -0.12065 -0.2794)
			(stroke
				(width 0.1)
				(type default)
			)
			(layer "B.Fab")
		)
		(fp_line
			(start -0.12065 -0.2794)
			(end -0.12065 -0.3048)
			(stroke
				(width 0.1)
				(type default)
			)
			(layer "B.Fab")
		)
		(fp_line
			(start 0.12065 0.2794)
			(end 0.12065 0.3048)
			(stroke
				(width 0.1)
				(type default)
			)
			(layer "B.Fab")
		)
		(fp_line
			(start -0.120396 0.2794)
			(end 0.12065 0.2794)
			(stroke
				(width 0.1)
				(type default)
			)
			(layer "B.Fab")
		)
		(fp_line
			(start 0.67945 0.3048)
			(end 0.67945 -0.305054)
			(stroke
				(width 0.1)
				(type default)
			)
			(layer "B.Fab")
		)
		(fp_line
			(start 0.12065 0.3048)
			(end 0.67945 0.3048)
			(stroke
				(width 0.1)
				(type default)
			)
			(layer "B.Fab")
		)
		(fp_line
			(start -0.120396 0.3048)
			(end -0.120396 0.2794)
			(stroke
				(width 0.1)
				(type default)
			)
			(layer "B.Fab")
		)
		(fp_line
			(start -0.67945 0.3048)
			(end -0.120396 0.3048)
			(stroke
				(width 0.1)
				(type default)
			)
			(layer "B.Fab")
		)
		(pad "1" smd circle
			(at 0.40005 0 270)
			(size 0 0)
			(layers "B.Cu" "B.Mask" "B.Paste")
			(net "SMB_PMBUS_3V3AUX_SDA")
		)
		(pad "2" smd circle
			(at -0.40005 0 270)
			(size 0 0)
			(layers "B.Cu" "B.Mask" "B.Paste")
			(net "SMB_PMBUS_3V3AUX_SDA_R0")
		)
	)
	(footprint ""
		(layer "B.Cu")
		(at 233.68 -330.708 180)
		(property "Reference" "R6785"
			(at 0 0 0)
			(layer "B.SilkS")
			(hide yes)
			(effects
				(font
					(size 1.27 1.27)
				)
				(justify mirror)
			)
		)
		(property "Value" ""
			(at 0 0 0)
			(layer "B.Fab")
			(effects
				(font
					(size 1.27 1.27)
				)
				(justify mirror)
			)
		)
		(duplicate_pad_numbers_are_jumpers no)
		(fp_line
			(start 0.7874 0.4064)
			(end 0.7874 -0.4064)
			(stroke
				(width 0.1524)
				(type default)
			)
			(layer "B.SilkS")
		)
		(fp_line
			(start 0.7874 -0.4064)
			(end -0.7874 -0.4064)
			(stroke
				(width 0.1524)
				(type default)
			)
			(layer "B.SilkS")
		)
		(fp_line
			(start -0.7874 0.4064)
			(end 0.7874 0.4064)
			(stroke
				(width 0.1524)
				(type default)
			)
			(layer "B.SilkS")
		)
		(fp_line
			(start -0.7874 -0.4064)
			(end -0.7874 0.4064)
			(stroke
				(width 0.1524)
				(type default)
			)
			(layer "B.SilkS")
		)
		(fp_line
			(start 0.67945 0.3048)
			(end 0.67945 -0.305054)
			(stroke
				(width 0.1)
				(type default)
			)
			(layer "B.Fab")
		)
		(fp_line
			(start 0.67945 -0.305054)
			(end 0.12065 -0.305054)
			(stroke
				(width 0.1)
				(type default)
			)
			(layer "B.Fab")
		)
		(fp_line
			(start 0.12065 0.3048)
			(end 0.67945 0.3048)
			(stroke
				(width 0.1)
				(type default)
			)
			(layer "B.Fab")
		)
		(fp_line
			(start 0.12065 0.2794)
			(end 0.12065 0.3048)
			(stroke
				(width 0.1)
				(type default)
			)
			(layer "B.Fab")
		)
		(fp_line
			(start 0.12065 -0.2794)
			(end -0.12065 -0.2794)
			(stroke
				(width 0.1)
				(type default)
			)
			(layer "B.Fab")
		)
		(fp_line
			(start 0.12065 -0.305054)
			(end 0.12065 -0.2794)
			(stroke
				(width 0.1)
				(type default)
			)
			(layer "B.Fab")
		)
		(fp_line
			(start -0.120396 0.3048)
			(end -0.120396 0.2794)
			(stroke
				(width 0.1)
				(type default)
			)
			(layer "B.Fab")
		)
		(fp_line
			(start -0.120396 0.2794)
			(end 0.12065 0.2794)
			(stroke
				(width 0.1)
				(type default)
			)
			(layer "B.Fab")
		)
		(fp_line
			(start -0.12065 -0.2794)
			(end -0.12065 -0.3048)
			(stroke
				(width 0.1)
				(type default)
			)
			(layer "B.Fab")
		)
		(fp_line
			(start -0.12065 -0.3048)
			(end -0.67945 -0.3048)
			(stroke
				(width 0.1)
				(type default)
			)
			(layer "B.Fab")
		)
		(fp_line
			(start -0.67945 0.3048)
			(end -0.120396 0.3048)
			(stroke
				(width 0.1)
				(type default)
			)
			(layer "B.Fab")
		)
		(fp_line
			(start -0.67945 -0.3048)
			(end -0.67945 0.3048)
			(stroke
				(width 0.1)
				(type default)
			)
			(layer "B.Fab")
		)
		(pad "1" smd circle
			(at 0.40005 0)
			(size 0 0)
			(layers "B.Cu" "B.Mask" "B.Paste")
			(net "SMB_MUX_RT_R1_SDA")
		)
		(pad "2" smd circle
			(at -0.40005 0)
			(size 0 0)
			(layers "B.Cu" "B.Mask" "B.Paste")
			(net "SMB_SML1_PMBUS_HSC_SDA")
		)
	)
	(footprint ""
		(layer "B.Cu")
		(at 396.157958 -313.477148 180)
		(property "Reference" "R432"
			(at 0 0 0)
			(layer "B.SilkS")
			(hide yes)
			(effects
				(font
					(size 1.27 1.27)
				)
				(justify mirror)
			)
		)
		(property "Value" ""
			(at 0 0 0)
			(layer "B.Fab")
			(effects
				(font
					(size 1.27 1.27)
				)
				(justify mirror)
			)
		)
		(duplicate_pad_numbers_are_jumpers no)
		(fp_line
			(start 0.7874 0.4064)
			(end 0.7874 -0.4064)
			(stroke
				(width 0.1524)
				(type default)
			)
			(layer "B.SilkS")
		)
		(fp_line
			(start 0.7874 -0.4064)
			(end -0.7874 -0.4064)
			(stroke
				(width 0.1524)
				(type default)
			)
			(layer "B.SilkS")
		)
		(fp_line
			(start -0.7874 0.4064)
			(end 0.7874 0.4064)
			(stroke
				(width 0.1524)
				(type default)
			)
			(layer "B.SilkS")
		)
		(fp_line
			(start -0.7874 -0.4064)
			(end -0.7874 0.4064)
			(stroke
				(width 0.1524)
				(type default)
			)
			(layer "B.SilkS")
		)
		(fp_line
			(start 0.67945 0.3048)
			(end 0.67945 -0.305054)
			(stroke
				(width 0.1)
				(type default)
			)
			(layer "B.Fab")
		)
		(fp_line
			(start 0.67945 -0.305054)
			(end 0.12065 -0.305054)
			(stroke
				(width 0.1)
				(type default)
			)
			(layer "B.Fab")
		)
		(fp_line
			(start 0.12065 0.3048)
			(end 0.67945 0.3048)
			(stroke
				(width 0.1)
				(type default)
			)
			(layer "B.Fab")
		)
		(fp_line
			(start 0.12065 0.2794)
			(end 0.12065 0.3048)
			(stroke
				(width 0.1)
				(type default)
			)
			(layer "B.Fab")
		)
		(fp_line
			(start 0.12065 -0.2794)
			(end -0.12065 -0.2794)
			(stroke
				(width 0.1)
				(type default)
			)
			(layer "B.Fab")
		)
		(fp_line
			(start 0.12065 -0.305054)
			(end 0.12065 -0.2794)
			(stroke
				(width 0.1)
				(type default)
			)
			(layer "B.Fab")
		)
		(fp_line
			(start -0.120396 0.3048)
			(end -0.120396 0.2794)
			(stroke
				(width 0.1)
				(type default)
			)
			(layer "B.Fab")
		)
		(fp_line
			(start -0.120396 0.2794)
			(end 0.12065 0.2794)
			(stroke
				(width 0.1)
				(type default)
			)
			(layer "B.Fab")
		)
		(fp_line
			(start -0.12065 -0.2794)
			(end -0.12065 -0.3048)
			(stroke
				(width 0.1)
				(type default)
			)
			(layer "B.Fab")
		)
		(fp_line
			(start -0.12065 -0.3048)
			(end -0.67945 -0.3048)
			(stroke
				(width 0.1)
				(type default)
			)
			(layer "B.Fab")
		)
		(fp_line
			(start -0.67945 0.3048)
			(end -0.120396 0.3048)
			(stroke
				(width 0.1)
				(type default)
			)
			(layer "B.Fab")
		)
		(fp_line
			(start -0.67945 -0.3048)
			(end -0.67945 0.3048)
			(stroke
				(width 0.1)
				(type default)
			)
			(layer "B.Fab")
		)
		(pad "1" smd circle
			(at 0.40005 0)
			(size 0 0)
			(layers "B.Cu" "B.Mask" "B.Paste")
			(net "XTAL_CPU0_X48M_X1")
		)
		(pad "2" smd circle
			(at -0.40005 0)
			(size 0 0)
			(layers "B.Cu" "B.Mask" "B.Paste")
			(net "XTAL_CPU0_X48M_X2_R")
		)
	)
	(footprint ""
		(layer "B.Cu")
		(at 159.383984 -20.056094 90)
		(property "Reference" "R6037"
			(at 0 0 90)
			(layer "B.SilkS")
			(hide yes)
			(effects
				(font
					(size 1.27 1.27)
				)
				(justify mirror)
			)
		)
		(property "Value" ""
			(at 0 0 90)
			(layer "B.Fab")
			(effects
				(font
					(size 1.27 1.27)
				)
				(justify mirror)
			)
		)
		(duplicate_pad_numbers_are_jumpers no)
		(fp_line
			(start 0.7874 -0.4064)
			(end -0.7874 -0.4064)
			(stroke
				(width 0.1524)
				(type default)
			)
			(layer "B.SilkS")
		)
		(fp_line
			(start -0.7874 -0.4064)
			(end -0.7874 0.4064)
			(stroke
				(width 0.1524)
				(type default)
			)
			(layer "B.SilkS")
		)
		(fp_line
			(start 0.7874 0.4064)
			(end 0.7874 -0.4064)
			(stroke
				(width 0.1524)
				(type default)
			)
			(layer "B.SilkS")
		)
		(fp_line
			(start -0.7874 0.4064)
			(end 0.7874 0.4064)
			(stroke
				(width 0.1524)
				(type default)
			)
			(layer "B.SilkS")
		)
		(fp_line
			(start 0.67945 -0.305054)
			(end 0.12065 -0.305054)
			(stroke
				(width 0.1)
				(type default)
			)
			(layer "B.Fab")
		)
		(fp_line
			(start 0.12065 -0.305054)
			(end 0.12065 -0.2794)
			(stroke
				(width 0.1)
				(type default)
			)
			(layer "B.Fab")
		)
		(fp_line
			(start -0.12065 -0.3048)
			(end -0.67945 -0.3048)
			(stroke
				(width 0.1)
				(type default)
			)
			(layer "B.Fab")
		)
		(fp_line
			(start -0.67945 -0.3048)
			(end -0.67945 0.3048)
			(stroke
				(width 0.1)
				(type default)
			)
			(layer "B.Fab")
		)
		(fp_line
			(start 0.12065 -0.2794)
			(end -0.12065 -0.2794)
			(stroke
				(width 0.1)
				(type default)
			)
			(layer "B.Fab")
		)
		(fp_line
			(start -0.12065 -0.2794)
			(end -0.12065 -0.3048)
			(stroke
				(width 0.1)
				(type default)
			)
			(layer "B.Fab")
		)
		(fp_line
			(start 0.12065 0.2794)
			(end 0.12065 0.3048)
			(stroke
				(width 0.1)
				(type default)
			)
			(layer "B.Fab")
		)
		(fp_line
			(start -0.120396 0.2794)
			(end 0.12065 0.2794)
			(stroke
				(width 0.1)
				(type default)
			)
			(layer "B.Fab")
		)
		(fp_line
			(start 0.67945 0.3048)
			(end 0.67945 -0.305054)
			(stroke
				(width 0.1)
				(type default)
			)
			(layer "B.Fab")
		)
		(fp_line
			(start 0.12065 0.3048)
			(end 0.67945 0.3048)
			(stroke
				(width 0.1)
				(type default)
			)
			(layer "B.Fab")
		)
		(fp_line
			(start -0.120396 0.3048)
			(end -0.120396 0.2794)
			(stroke
				(width 0.1)
				(type default)
			)
			(layer "B.Fab")
		)
		(fp_line
			(start -0.67945 0.3048)
			(end -0.120396 0.3048)
			(stroke
				(width 0.1)
				(type default)
			)
			(layer "B.Fab")
		)
		(pad "1" smd circle
			(at 0.40005 0 270)
			(size 0 0)
			(layers "B.Cu" "B.Mask" "B.Paste")
			(net "SMB_1_PLD_3V3AUX_SDA")
		)
		(pad "2" smd circle
			(at -0.40005 0 270)
			(size 0 0)
			(layers "B.Cu" "B.Mask" "B.Paste")
			(net "P3V3_AUX")
		)
	)
	(footprint ""
		(layer "B.Cu")
		(at 73.841864 -11.26871 90)
		(property "Reference" "R3176"
			(at 0 0 90)
			(layer "B.SilkS")
			(hide yes)
			(effects
				(font
					(size 1.27 1.27)
				)
				(justify mirror)
			)
		)
		(property "Value" ""
			(at 0 0 90)
			(layer "B.Fab")
			(effects
				(font
					(size 1.27 1.27)
				)
				(justify mirror)
			)
		)
		(duplicate_pad_numbers_are_jumpers no)
		(fp_line
			(start 0.7874 -0.4064)
			(end -0.7874 -0.4064)
			(stroke
				(width 0.1524)
				(type default)
			)
			(layer "B.SilkS")
		)
		(fp_line
			(start -0.7874 -0.4064)
			(end -0.7874 0.4064)
			(stroke
				(width 0.1524)
				(type default)
			)
			(layer "B.SilkS")
		)
		(fp_line
			(start 0.7874 0.4064)
			(end 0.7874 -0.4064)
			(stroke
				(width 0.1524)
				(type default)
			)
			(layer "B.SilkS")
		)
		(fp_line
			(start -0.7874 0.4064)
			(end 0.7874 0.4064)
			(stroke
				(width 0.1524)
				(type default)
			)
			(layer "B.SilkS")
		)
		(fp_line
			(start 0.67945 -0.305054)
			(end 0.12065 -0.305054)
			(stroke
				(width 0.1)
				(type default)
			)
			(layer "B.Fab")
		)
		(fp_line
			(start 0.12065 -0.305054)
			(end 0.12065 -0.2794)
			(stroke
				(width 0.1)
				(type default)
			)
			(layer "B.Fab")
		)
		(fp_line
			(start -0.12065 -0.3048)
			(end -0.67945 -0.3048)
			(stroke
				(width 0.1)
				(type default)
			)
			(layer "B.Fab")
		)
		(fp_line
			(start -0.67945 -0.3048)
			(end -0.67945 0.3048)
			(stroke
				(width 0.1)
				(type default)
			)
			(layer "B.Fab")
		)
		(fp_line
			(start 0.12065 -0.2794)
			(end -0.12065 -0.2794)
			(stroke
				(width 0.1)
				(type default)
			)
			(layer "B.Fab")
		)
		(fp_line
			(start -0.12065 -0.2794)
			(end -0.12065 -0.3048)
			(stroke
				(width 0.1)
				(type default)
			)
			(layer "B.Fab")
		)
		(fp_line
			(start 0.12065 0.2794)
			(end 0.12065 0.3048)
			(stroke
				(width 0.1)
				(type default)
			)
			(layer "B.Fab")
		)
		(fp_line
			(start -0.120396 0.2794)
			(end 0.12065 0.2794)
			(stroke
				(width 0.1)
				(type default)
			)
			(layer "B.Fab")
		)
		(fp_line
			(start 0.67945 0.3048)
			(end 0.67945 -0.305054)
			(stroke
				(width 0.1)
				(type default)
			)
			(layer "B.Fab")
		)
		(fp_line
			(start 0.12065 0.3048)
			(end 0.67945 0.3048)
			(stroke
				(width 0.1)
				(type default)
			)
			(layer "B.Fab")
		)
		(fp_line
			(start -0.120396 0.3048)
			(end -0.120396 0.2794)
			(stroke
				(width 0.1)
				(type default)
			)
			(layer "B.Fab")
		)
		(fp_line
			(start -0.67945 0.3048)
			(end -0.120396 0.3048)
			(stroke
				(width 0.1)
				(type default)
			)
			(layer "B.Fab")
		)
		(pad "1" smd circle
			(at 0.40005 0 270)
			(size 0 0)
			(layers "B.Cu" "B.Mask" "B.Paste")
			(net "SGPIO_OCP_V3_2_CLK")
		)
		(pad "2" smd circle
			(at -0.40005 0 270)
			(size 0 0)
			(layers "B.Cu" "B.Mask" "B.Paste")
			(net "P3V3_OCP_V3_2")
		)
	)
	(footprint ""
		(layer "B.Cu")
		(at 58.3184 -388.011162 -90)
		(property "Reference" "C130"
			(at 0 0 90)
			(layer "B.SilkS")
			(hide yes)
			(effects
				(font
					(size 1.27 1.27)
				)
				(justify mirror)
			)
		)
		(property "Value" ""
			(at 0 0 90)
			(layer "B.Fab")
			(effects
				(font
					(size 1.27 1.27)
				)
				(justify mirror)
			)
		)
		(duplicate_pad_numbers_are_jumpers no)
		(fp_line
			(start -0.299974 0.150114)
			(end 0.299974 0.150114)
			(stroke
				(width 0.1)
				(type default)
			)
			(layer "B.Fab")
		)
		(fp_line
			(start 0.299974 0.150114)
			(end 0.299974 -0.150114)
			(stroke
				(width 0.1)
				(type default)
			)
			(layer "B.Fab")
		)
		(fp_line
			(start -0.299974 -0.150114)
			(end -0.299974 0.150114)
			(stroke
				(width 0.1)
				(type default)
			)
			(layer "B.Fab")
		)
		(fp_line
			(start 0.299974 -0.150114)
			(end -0.299974 -0.150114)
			(stroke
				(width 0.1)
				(type default)
			)
			(layer "B.Fab")
		)
		(pad "1" smd rect
			(at 0.2667 0 90)
			(size 0.3048 0.381)
			(layers "B.Cu" "B.Mask" "B.Paste")
			(net "P1V8_CPU1_RT0_1A_1D")
		)
		(pad "2" smd rect
			(at -0.2667 0 90)
			(size 0.3048 0.381)
			(layers "B.Cu" "B.Mask" "B.Paste")
			(net "GND")
		)
	)
	(footprint ""
		(layer "B.Cu")
		(at 390.020048 -314.180474 -90)
		(property "Reference" "R573"
			(at 0 0 90)
			(layer "B.SilkS")
			(hide yes)
			(effects
				(font
					(size 1.27 1.27)
				)
				(justify mirror)
			)
		)
		(property "Value" ""
			(at 0 0 90)
			(layer "B.Fab")
			(effects
				(font
					(size 1.27 1.27)
				)
				(justify mirror)
			)
		)
		(duplicate_pad_numbers_are_jumpers no)
		(fp_line
			(start -0.7874 0.4064)
			(end 0.7874 0.4064)
			(stroke
				(width 0.1524)
				(type default)
			)
			(layer "B.SilkS")
		)
		(fp_line
			(start 0.7874 0.4064)
			(end 0.7874 -0.4064)
			(stroke
				(width 0.1524)
				(type default)
			)
			(layer "B.SilkS")
		)
		(fp_line
			(start -0.7874 -0.4064)
			(end -0.7874 0.4064)
			(stroke
				(width 0.1524)
				(type default)
			)
			(layer "B.SilkS")
		)
		(fp_line
			(start 0.7874 -0.4064)
			(end -0.7874 -0.4064)
			(stroke
				(width 0.1524)
				(type default)
			)
			(layer "B.SilkS")
		)
		(fp_line
			(start -0.67945 0.3048)
			(end -0.120396 0.3048)
			(stroke
				(width 0.1)
				(type default)
			)
			(layer "B.Fab")
		)
		(fp_line
			(start -0.120396 0.3048)
			(end -0.120396 0.2794)
			(stroke
				(width 0.1)
				(type default)
			)
			(layer "B.Fab")
		)
		(fp_line
			(start 0.12065 0.3048)
			(end 0.67945 0.3048)
			(stroke
				(width 0.1)
				(type default)
			)
			(layer "B.Fab")
		)
		(fp_line
			(start 0.67945 0.3048)
			(end 0.67945 -0.305054)
			(stroke
				(width 0.1)
				(type default)
			)
			(layer "B.Fab")
		)
		(fp_line
			(start -0.120396 0.2794)
			(end 0.12065 0.2794)
			(stroke
				(width 0.1)
				(type default)
			)
			(layer "B.Fab")
		)
		(fp_line
			(start 0.12065 0.2794)
			(end 0.12065 0.3048)
			(stroke
				(width 0.1)
				(type default)
			)
			(layer "B.Fab")
		)
		(fp_line
			(start -0.12065 -0.2794)
			(end -0.12065 -0.3048)
			(stroke
				(width 0.1)
				(type default)
			)
			(layer "B.Fab")
		)
		(fp_line
			(start 0.12065 -0.2794)
			(end -0.12065 -0.2794)
			(stroke
				(width 0.1)
				(type default)
			)
			(layer "B.Fab")
		)
		(fp_line
			(start -0.67945 -0.3048)
			(end -0.67945 0.3048)
			(stroke
				(width 0.1)
				(type default)
			)
			(layer "B.Fab")
		)
		(fp_line
			(start -0.12065 -0.3048)
			(end -0.67945 -0.3048)
			(stroke
				(width 0.1)
				(type default)
			)
			(layer "B.Fab")
		)
		(fp_line
			(start 0.12065 -0.305054)
			(end 0.12065 -0.2794)
			(stroke
				(width 0.1)
				(type default)
			)
			(layer "B.Fab")
		)
		(fp_line
			(start 0.67945 -0.305054)
			(end 0.12065 -0.305054)
			(stroke
				(width 0.1)
				(type default)
			)
			(layer "B.Fab")
		)
		(pad "1" smd circle
			(at 0.40005 0 90)
			(size 0 0)
			(layers "B.Cu" "B.Mask" "B.Paste")
			(net "CLK_CPU0_RTCCLK")
		)
		(pad "2" smd circle
			(at -0.40005 0 90)
			(size 0 0)
			(layers "B.Cu" "B.Mask" "B.Paste")
			(net "XTAL_CPU1_X32K_X1")
		)
	)
	(footprint ""
		(layer "B.Cu")
		(at 372.937278 -141.472158 180)
		(property "Reference" "R315"
			(at 0 0 0)
			(layer "B.SilkS")
			(hide yes)
			(effects
				(font
					(size 1.27 1.27)
				)
				(justify mirror)
			)
		)
		(property "Value" ""
			(at 0 0 0)
			(layer "B.Fab")
			(effects
				(font
					(size 1.27 1.27)
				)
				(justify mirror)
			)
		)
		(duplicate_pad_numbers_are_jumpers no)
		(fp_line
			(start 0.7874 0.4064)
			(end 0.7874 -0.4064)
			(stroke
				(width 0.1524)
				(type default)
			)
			(layer "B.SilkS")
		)
		(fp_line
			(start 0.7874 -0.4064)
			(end -0.7874 -0.4064)
			(stroke
				(width 0.1524)
				(type default)
			)
			(layer "B.SilkS")
		)
		(fp_line
			(start -0.7874 0.4064)
			(end 0.7874 0.4064)
			(stroke
				(width 0.1524)
				(type default)
			)
			(layer "B.SilkS")
		)
		(fp_line
			(start -0.7874 -0.4064)
			(end -0.7874 0.4064)
			(stroke
				(width 0.1524)
				(type default)
			)
			(layer "B.SilkS")
		)
		(fp_line
			(start 0.67945 0.3048)
			(end 0.67945 -0.305054)
			(stroke
				(width 0.1)
				(type default)
			)
			(layer "B.Fab")
		)
		(fp_line
			(start 0.67945 -0.305054)
			(end 0.12065 -0.305054)
			(stroke
				(width 0.1)
				(type default)
			)
			(layer "B.Fab")
		)
		(fp_line
			(start 0.12065 0.3048)
			(end 0.67945 0.3048)
			(stroke
				(width 0.1)
				(type default)
			)
			(layer "B.Fab")
		)
		(fp_line
			(start 0.12065 0.2794)
			(end 0.12065 0.3048)
			(stroke
				(width 0.1)
				(type default)
			)
			(layer "B.Fab")
		)
		(fp_line
			(start 0.12065 -0.2794)
			(end -0.12065 -0.2794)
			(stroke
				(width 0.1)
				(type default)
			)
			(layer "B.Fab")
		)
		(fp_line
			(start 0.12065 -0.305054)
			(end 0.12065 -0.2794)
			(stroke
				(width 0.1)
				(type default)
			)
			(layer "B.Fab")
		)
		(fp_line
			(start -0.120396 0.3048)
			(end -0.120396 0.2794)
			(stroke
				(width 0.1)
				(type default)
			)
			(layer "B.Fab")
		)
		(fp_line
			(start -0.120396 0.2794)
			(end 0.12065 0.2794)
			(stroke
				(width 0.1)
				(type default)
			)
			(layer "B.Fab")
		)
		(fp_line
			(start -0.12065 -0.2794)
			(end -0.12065 -0.3048)
			(stroke
				(width 0.1)
				(type default)
			)
			(layer "B.Fab")
		)
		(fp_line
			(start -0.12065 -0.3048)
			(end -0.67945 -0.3048)
			(stroke
				(width 0.1)
				(type default)
			)
			(layer "B.Fab")
		)
		(fp_line
			(start -0.67945 0.3048)
			(end -0.120396 0.3048)
			(stroke
				(width 0.1)
				(type default)
			)
			(layer "B.Fab")
		)
		(fp_line
			(start -0.67945 -0.3048)
			(end -0.67945 0.3048)
			(stroke
				(width 0.1)
				(type default)
			)
			(layer "B.Fab")
		)
		(pad "1" smd circle
			(at 0.40005 0)
			(size 0 0)
			(layers "B.Cu" "B.Mask" "B.Paste")
			(net "PVDDCR_CPU0_P0_RESET_N")
		)
		(pad "2" smd circle
			(at -0.40005 0)
			(size 0 0)
			(layers "B.Cu" "B.Mask" "B.Paste")
			(net "PVDDCR_CPU0_P0_RESET_N_R")
		)
	)
	(footprint ""
		(layer "B.Cu")
		(at 8.19277 -112.04702)
		(property "Reference" "C5232"
			(at 0 0 0)
			(layer "B.SilkS")
			(hide yes)
			(effects
				(font
					(size 1.27 1.27)
				)
				(justify mirror)
			)
		)
		(property "Value" ""
			(at 0 0 0)
			(layer "B.Fab")
			(effects
				(font
					(size 1.27 1.27)
				)
				(justify mirror)
			)
		)
		(duplicate_pad_numbers_are_jumpers no)
		(fp_line
			(start -0.7874 -0.4064)
			(end -0.7874 0.4064)
			(stroke
				(width 0.1524)
				(type default)
			)
			(layer "B.SilkS")
		)
		(fp_line
			(start -0.7874 0.4064)
			(end 0.7874 0.4064)
			(stroke
				(width 0.1524)
				(type default)
			)
			(layer "B.SilkS")
		)
		(fp_line
			(start 0.7874 -0.4064)
			(end -0.7874 -0.4064)
			(stroke
				(width 0.1524)
				(type default)
			)
			(layer "B.SilkS")
		)
		(fp_line
			(start 0.7874 0.4064)
			(end 0.7874 -0.4064)
			(stroke
				(width 0.1524)
				(type default)
			)
			(layer "B.SilkS")
		)
		(fp_line
			(start -0.67945 -0.3048)
			(end -0.67945 0.3048)
			(stroke
				(width 0.1)
				(type default)
			)
			(layer "B.Fab")
		)
		(fp_line
			(start -0.67945 0.3048)
			(end -0.120396 0.3048)
			(stroke
				(width 0.1)
				(type default)
			)
			(layer "B.Fab")
		)
		(fp_line
			(start -0.12065 -0.3048)
			(end -0.67945 -0.3048)
			(stroke
				(width 0.1)
				(type default)
			)
			(layer "B.Fab")
		)
		(fp_line
			(start -0.12065 -0.2794)
			(end -0.12065 -0.3048)
			(stroke
				(width 0.1)
				(type default)
			)
			(layer "B.Fab")
		)
		(fp_line
			(start -0.120396 0.2794)
			(end 0.12065 0.2794)
			(stroke
				(width 0.1)
				(type default)
			)
			(layer "B.Fab")
		)
		(fp_line
			(start -0.120396 0.3048)
			(end -0.120396 0.2794)
			(stroke
				(width 0.1)
				(type default)
			)
			(layer "B.Fab")
		)
		(fp_line
			(start 0.12065 -0.305054)
			(end 0.12065 -0.2794)
			(stroke
				(width 0.1)
				(type default)
			)
			(layer "B.Fab")
		)
		(fp_line
			(start 0.12065 -0.2794)
			(end -0.12065 -0.2794)
			(stroke
				(width 0.1)
				(type default)
			)
			(layer "B.Fab")
		)
		(fp_line
			(start 0.12065 0.2794)
			(end 0.12065 0.3048)
			(stroke
				(width 0.1)
				(type default)
			)
			(layer "B.Fab")
		)
		(fp_line
			(start 0.12065 0.3048)
			(end 0.67945 0.3048)
			(stroke
				(width 0.1)
				(type default)
			)
			(layer "B.Fab")
		)
		(fp_line
			(start 0.67945 -0.305054)
			(end 0.12065 -0.305054)
			(stroke
				(width 0.1)
				(type default)
			)
			(layer "B.Fab")
		)
		(fp_line
			(start 0.67945 0.3048)
			(end 0.67945 -0.305054)
			(stroke
				(width 0.1)
				(type default)
			)
			(layer "B.Fab")
		)
		(pad "1" smd circle
			(at 0.40005 0 180)
			(size 0 0)
			(layers "B.Cu" "B.Mask" "B.Paste")
			(net "PD_U5201_RSTN")
		)
		(pad "2" smd circle
			(at -0.40005 0 180)
			(size 0 0)
			(layers "B.Cu" "B.Mask" "B.Paste")
			(net "GND")
		)
	)
	(footprint ""
		(layer "B.Cu")
		(at 390.779762 -416.899344 90)
		(property "Reference" "C6610"
			(at 0 0 90)
			(layer "B.SilkS")
			(hide yes)
			(effects
				(font
					(size 1.27 1.27)
				)
				(justify mirror)
			)
		)
		(property "Value" ""
			(at 0 0 90)
			(layer "B.Fab")
			(effects
				(font
					(size 1.27 1.27)
				)
				(justify mirror)
			)
		)
		(duplicate_pad_numbers_are_jumpers no)
		(fp_line
			(start 0.299974 -0.150114)
			(end -0.299974 -0.150114)
			(stroke
				(width 0.1)
				(type default)
			)
			(layer "B.Fab")
		)
		(fp_line
			(start -0.299974 -0.150114)
			(end -0.299974 0.150114)
			(stroke
				(width 0.1)
				(type default)
			)
			(layer "B.Fab")
		)
		(fp_line
			(start 0.299974 0.150114)
			(end 0.299974 -0.150114)
			(stroke
				(width 0.1)
				(type default)
			)
			(layer "B.Fab")
		)
		(fp_line
			(start -0.299974 0.150114)
			(end 0.299974 0.150114)
			(stroke
				(width 0.1)
				(type default)
			)
			(layer "B.Fab")
		)
		(pad "1" smd rect
			(at 0.2667 0 270)
			(size 0.3048 0.381)
			(layers "B.Cu" "B.Mask" "B.Paste")
			(net "P5E_CPU0_P3_TX_BUF_C_DN<6>")
		)
		(pad "2" smd rect
			(at -0.2667 0 270)
			(size 0.3048 0.381)
			(layers "B.Cu" "B.Mask" "B.Paste")
			(net "P5E_CPU0_P3_TX_BUF_DN<6>")
		)
	)
	(footprint ""
		(layer "B.Cu")
		(at 110.149386 -266.005564)
		(property "Reference" "C2285"
			(at 0 0 0)
			(layer "B.SilkS")
			(hide yes)
			(effects
				(font
					(size 1.27 1.27)
				)
				(justify mirror)
			)
		)
		(property "Value" ""
			(at 0 0 0)
			(layer "B.Fab")
			(effects
				(font
					(size 1.27 1.27)
				)
				(justify mirror)
			)
		)
		(duplicate_pad_numbers_are_jumpers no)
		(fp_line
			(start -0.7874 -0.4064)
			(end -0.7874 0.4064)
			(stroke
				(width 0.1524)
				(type default)
			)
			(layer "B.SilkS")
		)
		(fp_line
			(start -0.7874 0.4064)
			(end 0.7874 0.4064)
			(stroke
				(width 0.1524)
				(type default)
			)
			(layer "B.SilkS")
		)
		(fp_line
			(start 0.7874 -0.4064)
			(end -0.7874 -0.4064)
			(stroke
				(width 0.1524)
				(type default)
			)
			(layer "B.SilkS")
		)
		(fp_line
			(start 0.7874 0.4064)
			(end 0.7874 -0.4064)
			(stroke
				(width 0.1524)
				(type default)
			)
			(layer "B.SilkS")
		)
		(fp_line
			(start -0.67945 -0.3048)
			(end -0.67945 0.3048)
			(stroke
				(width 0.1)
				(type default)
			)
			(layer "B.Fab")
		)
		(fp_line
			(start -0.67945 0.3048)
			(end -0.120396 0.3048)
			(stroke
				(width 0.1)
				(type default)
			)
			(layer "B.Fab")
		)
		(fp_line
			(start -0.12065 -0.3048)
			(end -0.67945 -0.3048)
			(stroke
				(width 0.1)
				(type default)
			)
			(layer "B.Fab")
		)
		(fp_line
			(start -0.12065 -0.2794)
			(end -0.12065 -0.3048)
			(stroke
				(width 0.1)
				(type default)
			)
			(layer "B.Fab")
		)
		(fp_line
			(start -0.120396 0.2794)
			(end 0.12065 0.2794)
			(stroke
				(width 0.1)
				(type default)
			)
			(layer "B.Fab")
		)
		(fp_line
			(start -0.120396 0.3048)
			(end -0.120396 0.2794)
			(stroke
				(width 0.1)
				(type default)
			)
			(layer "B.Fab")
		)
		(fp_line
			(start 0.12065 -0.305054)
			(end 0.12065 -0.2794)
			(stroke
				(width 0.1)
				(type default)
			)
			(layer "B.Fab")
		)
		(fp_line
			(start 0.12065 -0.2794)
			(end -0.12065 -0.2794)
			(stroke
				(width 0.1)
				(type default)
			)
			(layer "B.Fab")
		)
		(fp_line
			(start 0.12065 0.2794)
			(end 0.12065 0.3048)
			(stroke
				(width 0.1)
				(type default)
			)
			(layer "B.Fab")
		)
		(fp_line
			(start 0.12065 0.3048)
			(end 0.67945 0.3048)
			(stroke
				(width 0.1)
				(type default)
			)
			(layer "B.Fab")
		)
		(fp_line
			(start 0.67945 -0.305054)
			(end 0.12065 -0.305054)
			(stroke
				(width 0.1)
				(type default)
			)
			(layer "B.Fab")
		)
		(fp_line
			(start 0.67945 0.3048)
			(end 0.67945 -0.305054)
			(stroke
				(width 0.1)
				(type default)
			)
			(layer "B.Fab")
		)
		(pad "1" smd circle
			(at 0.40005 0 180)
			(size 0 0)
			(layers "B.Cu" "B.Mask" "B.Paste")
			(net "PVDD11_S3_P1")
		)
		(pad "2" smd circle
			(at -0.40005 0 180)
			(size 0 0)
			(layers "B.Cu" "B.Mask" "B.Paste")
			(net "GND")
		)
	)
	(footprint ""
		(layer "B.Cu")
		(at 109.766862 -177.112676 90)
		(property "Reference" "PR194"
			(at 0 0 90)
			(layer "B.SilkS")
			(hide yes)
			(effects
				(font
					(size 1.27 1.27)
				)
				(justify mirror)
			)
		)
		(property "Value" ""
			(at 0 0 90)
			(layer "B.Fab")
			(effects
				(font
					(size 1.27 1.27)
				)
				(justify mirror)
			)
		)
		(duplicate_pad_numbers_are_jumpers no)
		(fp_line
			(start 0.7874 -0.4064)
			(end -0.7874 -0.4064)
			(stroke
				(width 0.1524)
				(type default)
			)
			(layer "B.SilkS")
		)
		(fp_line
			(start -0.7874 -0.4064)
			(end -0.7874 0.4064)
			(stroke
				(width 0.1524)
				(type default)
			)
			(layer "B.SilkS")
		)
		(fp_line
			(start 0.7874 0.4064)
			(end 0.7874 -0.4064)
			(stroke
				(width 0.1524)
				(type default)
			)
			(layer "B.SilkS")
		)
		(fp_line
			(start -0.7874 0.4064)
			(end 0.7874 0.4064)
			(stroke
				(width 0.1524)
				(type default)
			)
			(layer "B.SilkS")
		)
		(fp_line
			(start 0.67945 -0.305054)
			(end 0.12065 -0.305054)
			(stroke
				(width 0.1)
				(type default)
			)
			(layer "B.Fab")
		)
		(fp_line
			(start 0.12065 -0.305054)
			(end 0.12065 -0.2794)
			(stroke
				(width 0.1)
				(type default)
			)
			(layer "B.Fab")
		)
		(fp_line
			(start -0.12065 -0.3048)
			(end -0.67945 -0.3048)
			(stroke
				(width 0.1)
				(type default)
			)
			(layer "B.Fab")
		)
		(fp_line
			(start -0.67945 -0.3048)
			(end -0.67945 0.3048)
			(stroke
				(width 0.1)
				(type default)
			)
			(layer "B.Fab")
		)
		(fp_line
			(start 0.12065 -0.2794)
			(end -0.12065 -0.2794)
			(stroke
				(width 0.1)
				(type default)
			)
			(layer "B.Fab")
		)
		(fp_line
			(start -0.12065 -0.2794)
			(end -0.12065 -0.3048)
			(stroke
				(width 0.1)
				(type default)
			)
			(layer "B.Fab")
		)
		(fp_line
			(start 0.12065 0.2794)
			(end 0.12065 0.3048)
			(stroke
				(width 0.1)
				(type default)
			)
			(layer "B.Fab")
		)
		(fp_line
			(start -0.120396 0.2794)
			(end 0.12065 0.2794)
			(stroke
				(width 0.1)
				(type default)
			)
			(layer "B.Fab")
		)
		(fp_line
			(start 0.67945 0.3048)
			(end 0.67945 -0.305054)
			(stroke
				(width 0.1)
				(type default)
			)
			(layer "B.Fab")
		)
		(fp_line
			(start 0.12065 0.3048)
			(end 0.67945 0.3048)
			(stroke
				(width 0.1)
				(type default)
			)
			(layer "B.Fab")
		)
		(fp_line
			(start -0.120396 0.3048)
			(end -0.120396 0.2794)
			(stroke
				(width 0.1)
				(type default)
			)
			(layer "B.Fab")
		)
		(fp_line
			(start -0.67945 0.3048)
			(end -0.120396 0.3048)
			(stroke
				(width 0.1)
				(type default)
			)
			(layer "B.Fab")
		)
		(pad "1" smd circle
			(at 0.40005 0 270)
			(size 0 0)
			(layers "B.Cu" "B.Mask" "B.Paste")
			(net "PVDDCR_CPU0_P1_PVCC")
		)
		(pad "2" smd circle
			(at -0.40005 0 270)
			(size 0 0)
			(layers "B.Cu" "B.Mask" "B.Paste")
			(net "PVDDCR_CPU0_P1_VCC4")
		)
	)
	(footprint ""
		(layer "B.Cu")
		(at 406.698958 -325.878952 180)
		(property "Reference" "R434"
			(at 0 0 0)
			(layer "B.SilkS")
			(hide yes)
			(effects
				(font
					(size 1.27 1.27)
				)
				(justify mirror)
			)
		)
		(property "Value" ""
			(at 0 0 0)
			(layer "B.Fab")
			(effects
				(font
					(size 1.27 1.27)
				)
				(justify mirror)
			)
		)
		(duplicate_pad_numbers_are_jumpers no)
		(fp_line
			(start 0.7874 0.4064)
			(end 0.7874 -0.4064)
			(stroke
				(width 0.1524)
				(type default)
			)
			(layer "B.SilkS")
		)
		(fp_line
			(start 0.7874 -0.4064)
			(end -0.7874 -0.4064)
			(stroke
				(width 0.1524)
				(type default)
			)
			(layer "B.SilkS")
		)
		(fp_line
			(start -0.7874 0.4064)
			(end 0.7874 0.4064)
			(stroke
				(width 0.1524)
				(type default)
			)
			(layer "B.SilkS")
		)
		(fp_line
			(start -0.7874 -0.4064)
			(end -0.7874 0.4064)
			(stroke
				(width 0.1524)
				(type default)
			)
			(layer "B.SilkS")
		)
		(fp_line
			(start 0.67945 0.3048)
			(end 0.67945 -0.305054)
			(stroke
				(width 0.1)
				(type default)
			)
			(layer "B.Fab")
		)
		(fp_line
			(start 0.67945 -0.305054)
			(end 0.12065 -0.305054)
			(stroke
				(width 0.1)
				(type default)
			)
			(layer "B.Fab")
		)
		(fp_line
			(start 0.12065 0.3048)
			(end 0.67945 0.3048)
			(stroke
				(width 0.1)
				(type default)
			)
			(layer "B.Fab")
		)
		(fp_line
			(start 0.12065 0.2794)
			(end 0.12065 0.3048)
			(stroke
				(width 0.1)
				(type default)
			)
			(layer "B.Fab")
		)
		(fp_line
			(start 0.12065 -0.2794)
			(end -0.12065 -0.2794)
			(stroke
				(width 0.1)
				(type default)
			)
			(layer "B.Fab")
		)
		(fp_line
			(start 0.12065 -0.305054)
			(end 0.12065 -0.2794)
			(stroke
				(width 0.1)
				(type default)
			)
			(layer "B.Fab")
		)
		(fp_line
			(start -0.120396 0.3048)
			(end -0.120396 0.2794)
			(stroke
				(width 0.1)
				(type default)
			)
			(layer "B.Fab")
		)
		(fp_line
			(start -0.120396 0.2794)
			(end 0.12065 0.2794)
			(stroke
				(width 0.1)
				(type default)
			)
			(layer "B.Fab")
		)
		(fp_line
			(start -0.12065 -0.2794)
			(end -0.12065 -0.3048)
			(stroke
				(width 0.1)
				(type default)
			)
			(layer "B.Fab")
		)
		(fp_line
			(start -0.12065 -0.3048)
			(end -0.67945 -0.3048)
			(stroke
				(width 0.1)
				(type default)
			)
			(layer "B.Fab")
		)
		(fp_line
			(start -0.67945 0.3048)
			(end -0.120396 0.3048)
			(stroke
				(width 0.1)
				(type default)
			)
			(layer "B.Fab")
		)
		(fp_line
			(start -0.67945 -0.3048)
			(end -0.67945 0.3048)
			(stroke
				(width 0.1)
				(type default)
			)
			(layer "B.Fab")
		)
		(pad "1" smd circle
			(at 0.40005 0)
			(size 0 0)
			(layers "B.Cu" "B.Mask" "B.Paste")
			(net "CPU0_PWR_GD_OUT")
		)
		(pad "2" smd circle
			(at -0.40005 0)
			(size 0 0)
			(layers "B.Cu" "B.Mask" "B.Paste")
			(net "CPU1_PWR_GD_IN")
		)
	)
	(footprint ""
		(layer "B.Cu")
		(at 103.632 -415.925 -90)
		(property "Reference" "R4544"
			(at 0 0 90)
			(layer "B.SilkS")
			(hide yes)
			(effects
				(font
					(size 1.27 1.27)
				)
				(justify mirror)
			)
		)
		(property "Value" ""
			(at 0 0 90)
			(layer "B.Fab")
			(effects
				(font
					(size 1.27 1.27)
				)
				(justify mirror)
			)
		)
		(duplicate_pad_numbers_are_jumpers no)
		(fp_line
			(start -0.7874 0.4064)
			(end 0.7874 0.4064)
			(stroke
				(width 0.1524)
				(type default)
			)
			(layer "B.SilkS")
		)
		(fp_line
			(start 0.7874 0.4064)
			(end 0.7874 -0.4064)
			(stroke
				(width 0.1524)
				(type default)
			)
			(layer "B.SilkS")
		)
		(fp_line
			(start -0.7874 -0.4064)
			(end -0.7874 0.4064)
			(stroke
				(width 0.1524)
				(type default)
			)
			(layer "B.SilkS")
		)
		(fp_line
			(start 0.7874 -0.4064)
			(end -0.7874 -0.4064)
			(stroke
				(width 0.1524)
				(type default)
			)
			(layer "B.SilkS")
		)
		(fp_line
			(start -0.67945 0.3048)
			(end -0.120396 0.3048)
			(stroke
				(width 0.1)
				(type default)
			)
			(layer "B.Fab")
		)
		(fp_line
			(start -0.120396 0.3048)
			(end -0.120396 0.2794)
			(stroke
				(width 0.1)
				(type default)
			)
			(layer "B.Fab")
		)
		(fp_line
			(start 0.12065 0.3048)
			(end 0.67945 0.3048)
			(stroke
				(width 0.1)
				(type default)
			)
			(layer "B.Fab")
		)
		(fp_line
			(start 0.67945 0.3048)
			(end 0.67945 -0.305054)
			(stroke
				(width 0.1)
				(type default)
			)
			(layer "B.Fab")
		)
		(fp_line
			(start -0.120396 0.2794)
			(end 0.12065 0.2794)
			(stroke
				(width 0.1)
				(type default)
			)
			(layer "B.Fab")
		)
		(fp_line
			(start 0.12065 0.2794)
			(end 0.12065 0.3048)
			(stroke
				(width 0.1)
				(type default)
			)
			(layer "B.Fab")
		)
		(fp_line
			(start -0.12065 -0.2794)
			(end -0.12065 -0.3048)
			(stroke
				(width 0.1)
				(type default)
			)
			(layer "B.Fab")
		)
		(fp_line
			(start 0.12065 -0.2794)
			(end -0.12065 -0.2794)
			(stroke
				(width 0.1)
				(type default)
			)
			(layer "B.Fab")
		)
		(fp_line
			(start -0.67945 -0.3048)
			(end -0.67945 0.3048)
			(stroke
				(width 0.1)
				(type default)
			)
			(layer "B.Fab")
		)
		(fp_line
			(start -0.12065 -0.3048)
			(end -0.67945 -0.3048)
			(stroke
				(width 0.1)
				(type default)
			)
			(layer "B.Fab")
		)
		(fp_line
			(start 0.12065 -0.305054)
			(end 0.12065 -0.2794)
			(stroke
				(width 0.1)
				(type default)
			)
			(layer "B.Fab")
		)
		(fp_line
			(start 0.67945 -0.305054)
			(end 0.12065 -0.305054)
			(stroke
				(width 0.1)
				(type default)
			)
			(layer "B.Fab")
		)
		(pad "1" smd circle
			(at 0.40005 0 90)
			(size 0 0)
			(layers "B.Cu" "B.Mask" "B.Paste")
			(net "HGX_DETECT_N")
		)
		(pad "2" smd circle
			(at -0.40005 0 90)
			(size 0 0)
			(layers "B.Cu" "B.Mask" "B.Paste")
			(net "GND")
		)
	)
	(footprint ""
		(layer "B.Cu")
		(at 205.25105 -244.085364)
		(property "Reference" "R511"
			(at 0 0 0)
			(layer "B.SilkS")
			(hide yes)
			(effects
				(font
					(size 1.27 1.27)
				)
				(justify mirror)
			)
		)
		(property "Value" ""
			(at 0 0 0)
			(layer "B.Fab")
			(effects
				(font
					(size 1.27 1.27)
				)
				(justify mirror)
			)
		)
		(duplicate_pad_numbers_are_jumpers no)
		(fp_line
			(start -0.7874 -0.4064)
			(end -0.7874 0.4064)
			(stroke
				(width 0.1524)
				(type default)
			)
			(layer "B.SilkS")
		)
		(fp_line
			(start -0.7874 0.4064)
			(end 0.7874 0.4064)
			(stroke
				(width 0.1524)
				(type default)
			)
			(layer "B.SilkS")
		)
		(fp_line
			(start 0.7874 -0.4064)
			(end -0.7874 -0.4064)
			(stroke
				(width 0.1524)
				(type default)
			)
			(layer "B.SilkS")
		)
		(fp_line
			(start 0.7874 0.4064)
			(end 0.7874 -0.4064)
			(stroke
				(width 0.1524)
				(type default)
			)
			(layer "B.SilkS")
		)
		(fp_line
			(start -0.67945 -0.3048)
			(end -0.67945 0.3048)
			(stroke
				(width 0.1)
				(type default)
			)
			(layer "B.Fab")
		)
		(fp_line
			(start -0.67945 0.3048)
			(end -0.120396 0.3048)
			(stroke
				(width 0.1)
				(type default)
			)
			(layer "B.Fab")
		)
		(fp_line
			(start -0.12065 -0.3048)
			(end -0.67945 -0.3048)
			(stroke
				(width 0.1)
				(type default)
			)
			(layer "B.Fab")
		)
		(fp_line
			(start -0.12065 -0.2794)
			(end -0.12065 -0.3048)
			(stroke
				(width 0.1)
				(type default)
			)
			(layer "B.Fab")
		)
		(fp_line
			(start -0.120396 0.2794)
			(end 0.12065 0.2794)
			(stroke
				(width 0.1)
				(type default)
			)
			(layer "B.Fab")
		)
		(fp_line
			(start -0.120396 0.3048)
			(end -0.120396 0.2794)
			(stroke
				(width 0.1)
				(type default)
			)
			(layer "B.Fab")
		)
		(fp_line
			(start 0.12065 -0.305054)
			(end 0.12065 -0.2794)
			(stroke
				(width 0.1)
				(type default)
			)
			(layer "B.Fab")
		)
		(fp_line
			(start 0.12065 -0.2794)
			(end -0.12065 -0.2794)
			(stroke
				(width 0.1)
				(type default)
			)
			(layer "B.Fab")
		)
		(fp_line
			(start 0.12065 0.2794)
			(end 0.12065 0.3048)
			(stroke
				(width 0.1)
				(type default)
			)
			(layer "B.Fab")
		)
		(fp_line
			(start 0.12065 0.3048)
			(end 0.67945 0.3048)
			(stroke
				(width 0.1)
				(type default)
			)
			(layer "B.Fab")
		)
		(fp_line
			(start 0.67945 -0.305054)
			(end 0.12065 -0.305054)
			(stroke
				(width 0.1)
				(type default)
			)
			(layer "B.Fab")
		)
		(fp_line
			(start 0.67945 0.3048)
			(end 0.67945 -0.305054)
			(stroke
				(width 0.1)
				(type default)
			)
			(layer "B.Fab")
		)
		(pad "1" smd circle
			(at 0.40005 0 180)
			(size 0 0)
			(layers "B.Cu" "B.Mask" "B.Paste")
			(net "M_L_CPU1_ALERT_N")
		)
		(pad "2" smd circle
			(at -0.40005 0 180)
			(size 0 0)
			(layers "B.Cu" "B.Mask" "B.Paste")
			(net "M_L_CPU1_ALERT_R_N")
		)
	)
	(footprint ""
		(layer "B.Cu")
		(at 121.706386 -249.368564)
		(property "Reference" "C2325"
			(at 0 0 0)
			(layer "B.SilkS")
			(hide yes)
			(effects
				(font
					(size 1.27 1.27)
				)
				(justify mirror)
			)
		)
		(property "Value" ""
			(at 0 0 0)
			(layer "B.Fab")
			(effects
				(font
					(size 1.27 1.27)
				)
				(justify mirror)
			)
		)
		(duplicate_pad_numbers_are_jumpers no)
		(fp_line
			(start -0.7874 -0.4064)
			(end -0.7874 0.4064)
			(stroke
				(width 0.1524)
				(type default)
			)
			(layer "B.SilkS")
		)
		(fp_line
			(start -0.7874 0.4064)
			(end 0.7874 0.4064)
			(stroke
				(width 0.1524)
				(type default)
			)
			(layer "B.SilkS")
		)
		(fp_line
			(start 0.7874 -0.4064)
			(end -0.7874 -0.4064)
			(stroke
				(width 0.1524)
				(type default)
			)
			(layer "B.SilkS")
		)
		(fp_line
			(start 0.7874 0.4064)
			(end 0.7874 -0.4064)
			(stroke
				(width 0.1524)
				(type default)
			)
			(layer "B.SilkS")
		)
		(fp_line
			(start -0.67945 -0.3048)
			(end -0.67945 0.3048)
			(stroke
				(width 0.1)
				(type default)
			)
			(layer "B.Fab")
		)
		(fp_line
			(start -0.67945 0.3048)
			(end -0.120396 0.3048)
			(stroke
				(width 0.1)
				(type default)
			)
			(layer "B.Fab")
		)
		(fp_line
			(start -0.12065 -0.3048)
			(end -0.67945 -0.3048)
			(stroke
				(width 0.1)
				(type default)
			)
			(layer "B.Fab")
		)
		(fp_line
			(start -0.12065 -0.2794)
			(end -0.12065 -0.3048)
			(stroke
				(width 0.1)
				(type default)
			)
			(layer "B.Fab")
		)
		(fp_line
			(start -0.120396 0.2794)
			(end 0.12065 0.2794)
			(stroke
				(width 0.1)
				(type default)
			)
			(layer "B.Fab")
		)
		(fp_line
			(start -0.120396 0.3048)
			(end -0.120396 0.2794)
			(stroke
				(width 0.1)
				(type default)
			)
			(layer "B.Fab")
		)
		(fp_line
			(start 0.12065 -0.305054)
			(end 0.12065 -0.2794)
			(stroke
				(width 0.1)
				(type default)
			)
			(layer "B.Fab")
		)
		(fp_line
			(start 0.12065 -0.2794)
			(end -0.12065 -0.2794)
			(stroke
				(width 0.1)
				(type default)
			)
			(layer "B.Fab")
		)
		(fp_line
			(start 0.12065 0.2794)
			(end 0.12065 0.3048)
			(stroke
				(width 0.1)
				(type default)
			)
			(layer "B.Fab")
		)
		(fp_line
			(start 0.12065 0.3048)
			(end 0.67945 0.3048)
			(stroke
				(width 0.1)
				(type default)
			)
			(layer "B.Fab")
		)
		(fp_line
			(start 0.67945 -0.305054)
			(end 0.12065 -0.305054)
			(stroke
				(width 0.1)
				(type default)
			)
			(layer "B.Fab")
		)
		(fp_line
			(start 0.67945 0.3048)
			(end 0.67945 -0.305054)
			(stroke
				(width 0.1)
				(type default)
			)
			(layer "B.Fab")
		)
		(pad "1" smd circle
			(at 0.40005 0 180)
			(size 0 0)
			(layers "B.Cu" "B.Mask" "B.Paste")
			(net "PVDDCR_CPU0_P1")
		)
		(pad "2" smd circle
			(at -0.40005 0 180)
			(size 0 0)
			(layers "B.Cu" "B.Mask" "B.Paste")
			(net "GND")
		)
	)
	(footprint ""
		(layer "B.Cu")
		(at 131.849114 -31.421578 -90)
		(property "Reference" "C6051"
			(at 0 0 90)
			(layer "B.SilkS")
			(hide yes)
			(effects
				(font
					(size 1.27 1.27)
				)
				(justify mirror)
			)
		)
		(property "Value" ""
			(at 0 0 90)
			(layer "B.Fab")
			(effects
				(font
					(size 1.27 1.27)
				)
				(justify mirror)
			)
		)
		(duplicate_pad_numbers_are_jumpers no)
		(fp_line
			(start -0.7874 0.4064)
			(end 0.7874 0.4064)
			(stroke
				(width 0.1524)
				(type default)
			)
			(layer "B.SilkS")
		)
		(fp_line
			(start 0.7874 0.4064)
			(end 0.7874 -0.4064)
			(stroke
				(width 0.1524)
				(type default)
			)
			(layer "B.SilkS")
		)
		(fp_line
			(start -0.7874 -0.4064)
			(end -0.7874 0.4064)
			(stroke
				(width 0.1524)
				(type default)
			)
			(layer "B.SilkS")
		)
		(fp_line
			(start 0.7874 -0.4064)
			(end -0.7874 -0.4064)
			(stroke
				(width 0.1524)
				(type default)
			)
			(layer "B.SilkS")
		)
		(fp_line
			(start -0.67945 0.3048)
			(end -0.120396 0.3048)
			(stroke
				(width 0.1)
				(type default)
			)
			(layer "B.Fab")
		)
		(fp_line
			(start -0.120396 0.3048)
			(end -0.120396 0.2794)
			(stroke
				(width 0.1)
				(type default)
			)
			(layer "B.Fab")
		)
		(fp_line
			(start 0.12065 0.3048)
			(end 0.67945 0.3048)
			(stroke
				(width 0.1)
				(type default)
			)
			(layer "B.Fab")
		)
		(fp_line
			(start 0.67945 0.3048)
			(end 0.67945 -0.305054)
			(stroke
				(width 0.1)
				(type default)
			)
			(layer "B.Fab")
		)
		(fp_line
			(start -0.120396 0.2794)
			(end 0.12065 0.2794)
			(stroke
				(width 0.1)
				(type default)
			)
			(layer "B.Fab")
		)
		(fp_line
			(start 0.12065 0.2794)
			(end 0.12065 0.3048)
			(stroke
				(width 0.1)
				(type default)
			)
			(layer "B.Fab")
		)
		(fp_line
			(start -0.12065 -0.2794)
			(end -0.12065 -0.3048)
			(stroke
				(width 0.1)
				(type default)
			)
			(layer "B.Fab")
		)
		(fp_line
			(start 0.12065 -0.2794)
			(end -0.12065 -0.2794)
			(stroke
				(width 0.1)
				(type default)
			)
			(layer "B.Fab")
		)
		(fp_line
			(start -0.67945 -0.3048)
			(end -0.67945 0.3048)
			(stroke
				(width 0.1)
				(type default)
			)
			(layer "B.Fab")
		)
		(fp_line
			(start -0.12065 -0.3048)
			(end -0.67945 -0.3048)
			(stroke
				(width 0.1)
				(type default)
			)
			(layer "B.Fab")
		)
		(fp_line
			(start 0.12065 -0.305054)
			(end 0.12065 -0.2794)
			(stroke
				(width 0.1)
				(type default)
			)
			(layer "B.Fab")
		)
		(fp_line
			(start 0.67945 -0.305054)
			(end 0.12065 -0.305054)
			(stroke
				(width 0.1)
				(type default)
			)
			(layer "B.Fab")
		)
		(pad "1" smd circle
			(at 0.40005 0 90)
			(size 0 0)
			(layers "B.Cu" "B.Mask" "B.Paste")
			(net "P3V3_AUX")
		)
		(pad "2" smd circle
			(at -0.40005 0 90)
			(size 0 0)
			(layers "B.Cu" "B.Mask" "B.Paste")
			(net "GND")
		)
	)
	(footprint ""
		(layer "B.Cu")
		(at 359.721404 -253.43231 180)
		(property "Reference" "C2144"
			(at 0 0 0)
			(layer "B.SilkS")
			(hide yes)
			(effects
				(font
					(size 1.27 1.27)
				)
				(justify mirror)
			)
		)
		(property "Value" ""
			(at 0 0 0)
			(layer "B.Fab")
			(effects
				(font
					(size 1.27 1.27)
				)
				(justify mirror)
			)
		)
		(duplicate_pad_numbers_are_jumpers no)
		(fp_line
			(start 0.7874 0.4064)
			(end 0.7874 -0.4064)
			(stroke
				(width 0.1524)
				(type default)
			)
			(layer "B.SilkS")
		)
		(fp_line
			(start 0.7874 -0.4064)
			(end -0.7874 -0.4064)
			(stroke
				(width 0.1524)
				(type default)
			)
			(layer "B.SilkS")
		)
		(fp_line
			(start -0.7874 0.4064)
			(end 0.7874 0.4064)
			(stroke
				(width 0.1524)
				(type default)
			)
			(layer "B.SilkS")
		)
		(fp_line
			(start -0.7874 -0.4064)
			(end -0.7874 0.4064)
			(stroke
				(width 0.1524)
				(type default)
			)
			(layer "B.SilkS")
		)
		(fp_line
			(start 0.67945 0.3048)
			(end 0.67945 -0.305054)
			(stroke
				(width 0.1)
				(type default)
			)
			(layer "B.Fab")
		)
		(fp_line
			(start 0.67945 -0.305054)
			(end 0.12065 -0.305054)
			(stroke
				(width 0.1)
				(type default)
			)
			(layer "B.Fab")
		)
		(fp_line
			(start 0.12065 0.3048)
			(end 0.67945 0.3048)
			(stroke
				(width 0.1)
				(type default)
			)
			(layer "B.Fab")
		)
		(fp_line
			(start 0.12065 0.2794)
			(end 0.12065 0.3048)
			(stroke
				(width 0.1)
				(type default)
			)
			(layer "B.Fab")
		)
		(fp_line
			(start 0.12065 -0.2794)
			(end -0.12065 -0.2794)
			(stroke
				(width 0.1)
				(type default)
			)
			(layer "B.Fab")
		)
		(fp_line
			(start 0.12065 -0.305054)
			(end 0.12065 -0.2794)
			(stroke
				(width 0.1)
				(type default)
			)
			(layer "B.Fab")
		)
		(fp_line
			(start -0.120396 0.3048)
			(end -0.120396 0.2794)
			(stroke
				(width 0.1)
				(type default)
			)
			(layer "B.Fab")
		)
		(fp_line
			(start -0.120396 0.2794)
			(end 0.12065 0.2794)
			(stroke
				(width 0.1)
				(type default)
			)
			(layer "B.Fab")
		)
		(fp_line
			(start -0.12065 -0.2794)
			(end -0.12065 -0.3048)
			(stroke
				(width 0.1)
				(type default)
			)
			(layer "B.Fab")
		)
		(fp_line
			(start -0.12065 -0.3048)
			(end -0.67945 -0.3048)
			(stroke
				(width 0.1)
				(type default)
			)
			(layer "B.Fab")
		)
		(fp_line
			(start -0.67945 0.3048)
			(end -0.120396 0.3048)
			(stroke
				(width 0.1)
				(type default)
			)
			(layer "B.Fab")
		)
		(fp_line
			(start -0.67945 -0.3048)
			(end -0.67945 0.3048)
			(stroke
				(width 0.1)
				(type default)
			)
			(layer "B.Fab")
		)
		(pad "1" smd circle
			(at 0.40005 0)
			(size 0 0)
			(layers "B.Cu" "B.Mask" "B.Paste")
			(net "PVDDCR_SOC_P0")
		)
		(pad "2" smd circle
			(at -0.40005 0)
			(size 0 0)
			(layers "B.Cu" "B.Mask" "B.Paste")
			(net "GND")
		)
	)
	(footprint ""
		(layer "B.Cu")
		(at 100.271834 -263.521952)
		(property "Reference" "C2105"
			(at 0 0 0)
			(layer "B.SilkS")
			(hide yes)
			(effects
				(font
					(size 1.27 1.27)
				)
				(justify mirror)
			)
		)
		(property "Value" ""
			(at 0 0 0)
			(layer "B.Fab")
			(effects
				(font
					(size 1.27 1.27)
				)
				(justify mirror)
			)
		)
		(duplicate_pad_numbers_are_jumpers no)
		(fp_line
			(start -0.7874 -0.4064)
			(end -0.7874 0.4064)
			(stroke
				(width 0.1524)
				(type default)
			)
			(layer "B.SilkS")
		)
		(fp_line
			(start -0.7874 0.4064)
			(end 0.7874 0.4064)
			(stroke
				(width 0.1524)
				(type default)
			)
			(layer "B.SilkS")
		)
		(fp_line
			(start 0.7874 -0.4064)
			(end -0.7874 -0.4064)
			(stroke
				(width 0.1524)
				(type default)
			)
			(layer "B.SilkS")
		)
		(fp_line
			(start 0.7874 0.4064)
			(end 0.7874 -0.4064)
			(stroke
				(width 0.1524)
				(type default)
			)
			(layer "B.SilkS")
		)
		(fp_line
			(start -0.67945 -0.3048)
			(end -0.67945 0.3048)
			(stroke
				(width 0.1)
				(type default)
			)
			(layer "B.Fab")
		)
		(fp_line
			(start -0.67945 0.3048)
			(end -0.120396 0.3048)
			(stroke
				(width 0.1)
				(type default)
			)
			(layer "B.Fab")
		)
		(fp_line
			(start -0.12065 -0.3048)
			(end -0.67945 -0.3048)
			(stroke
				(width 0.1)
				(type default)
			)
			(layer "B.Fab")
		)
		(fp_line
			(start -0.12065 -0.2794)
			(end -0.12065 -0.3048)
			(stroke
				(width 0.1)
				(type default)
			)
			(layer "B.Fab")
		)
		(fp_line
			(start -0.120396 0.2794)
			(end 0.12065 0.2794)
			(stroke
				(width 0.1)
				(type default)
			)
			(layer "B.Fab")
		)
		(fp_line
			(start -0.120396 0.3048)
			(end -0.120396 0.2794)
			(stroke
				(width 0.1)
				(type default)
			)
			(layer "B.Fab")
		)
		(fp_line
			(start 0.12065 -0.305054)
			(end 0.12065 -0.2794)
			(stroke
				(width 0.1)
				(type default)
			)
			(layer "B.Fab")
		)
		(fp_line
			(start 0.12065 -0.2794)
			(end -0.12065 -0.2794)
			(stroke
				(width 0.1)
				(type default)
			)
			(layer "B.Fab")
		)
		(fp_line
			(start 0.12065 0.2794)
			(end 0.12065 0.3048)
			(stroke
				(width 0.1)
				(type default)
			)
			(layer "B.Fab")
		)
		(fp_line
			(start 0.12065 0.3048)
			(end 0.67945 0.3048)
			(stroke
				(width 0.1)
				(type default)
			)
			(layer "B.Fab")
		)
		(fp_line
			(start 0.67945 -0.305054)
			(end 0.12065 -0.305054)
			(stroke
				(width 0.1)
				(type default)
			)
			(layer "B.Fab")
		)
		(fp_line
			(start 0.67945 0.3048)
			(end 0.67945 -0.305054)
			(stroke
				(width 0.1)
				(type default)
			)
			(layer "B.Fab")
		)
		(pad "1" smd circle
			(at 0.40005 0 180)
			(size 0 0)
			(layers "B.Cu" "B.Mask" "B.Paste")
			(net "PVDDIO_P1")
		)
		(pad "2" smd circle
			(at -0.40005 0 180)
			(size 0 0)
			(layers "B.Cu" "B.Mask" "B.Paste")
			(net "GND")
		)
	)
	(footprint ""
		(layer "B.Cu")
		(at 328.052176 -395.127988 -90)
		(property "Reference" "C511"
			(at 0 0 90)
			(layer "B.SilkS")
			(hide yes)
			(effects
				(font
					(size 1.27 1.27)
				)
				(justify mirror)
			)
		)
		(property "Value" ""
			(at 0 0 90)
			(layer "B.Fab")
			(effects
				(font
					(size 1.27 1.27)
				)
				(justify mirror)
			)
		)
		(duplicate_pad_numbers_are_jumpers no)
		(fp_line
			(start -0.7874 0.4064)
			(end 0.7874 0.4064)
			(stroke
				(width 0.1524)
				(type default)
			)
			(layer "B.SilkS")
		)
		(fp_line
			(start 0.7874 0.4064)
			(end 0.7874 -0.4064)
			(stroke
				(width 0.1524)
				(type default)
			)
			(layer "B.SilkS")
		)
		(fp_line
			(start -0.7874 -0.4064)
			(end -0.7874 0.4064)
			(stroke
				(width 0.1524)
				(type default)
			)
			(layer "B.SilkS")
		)
		(fp_line
			(start 0.7874 -0.4064)
			(end -0.7874 -0.4064)
			(stroke
				(width 0.1524)
				(type default)
			)
			(layer "B.SilkS")
		)
		(fp_line
			(start -0.67945 0.3048)
			(end -0.120396 0.3048)
			(stroke
				(width 0.1)
				(type default)
			)
			(layer "B.Fab")
		)
		(fp_line
			(start -0.120396 0.3048)
			(end -0.120396 0.2794)
			(stroke
				(width 0.1)
				(type default)
			)
			(layer "B.Fab")
		)
		(fp_line
			(start 0.12065 0.3048)
			(end 0.67945 0.3048)
			(stroke
				(width 0.1)
				(type default)
			)
			(layer "B.Fab")
		)
		(fp_line
			(start 0.67945 0.3048)
			(end 0.67945 -0.305054)
			(stroke
				(width 0.1)
				(type default)
			)
			(layer "B.Fab")
		)
		(fp_line
			(start -0.120396 0.2794)
			(end 0.12065 0.2794)
			(stroke
				(width 0.1)
				(type default)
			)
			(layer "B.Fab")
		)
		(fp_line
			(start 0.12065 0.2794)
			(end 0.12065 0.3048)
			(stroke
				(width 0.1)
				(type default)
			)
			(layer "B.Fab")
		)
		(fp_line
			(start -0.12065 -0.2794)
			(end -0.12065 -0.3048)
			(stroke
				(width 0.1)
				(type default)
			)
			(layer "B.Fab")
		)
		(fp_line
			(start 0.12065 -0.2794)
			(end -0.12065 -0.2794)
			(stroke
				(width 0.1)
				(type default)
			)
			(layer "B.Fab")
		)
		(fp_line
			(start -0.67945 -0.3048)
			(end -0.67945 0.3048)
			(stroke
				(width 0.1)
				(type default)
			)
			(layer "B.Fab")
		)
		(fp_line
			(start -0.12065 -0.3048)
			(end -0.67945 -0.3048)
			(stroke
				(width 0.1)
				(type default)
			)
			(layer "B.Fab")
		)
		(fp_line
			(start 0.12065 -0.305054)
			(end 0.12065 -0.2794)
			(stroke
				(width 0.1)
				(type default)
			)
			(layer "B.Fab")
		)
		(fp_line
			(start 0.67945 -0.305054)
			(end 0.12065 -0.305054)
			(stroke
				(width 0.1)
				(type default)
			)
			(layer "B.Fab")
		)
		(pad "1" smd circle
			(at 0.40005 0 90)
			(size 0 0)
			(layers "B.Cu" "B.Mask" "B.Paste")
			(net "P1V8_CPU0_RT_1D")
		)
		(pad "2" smd circle
			(at -0.40005 0 90)
			(size 0 0)
			(layers "B.Cu" "B.Mask" "B.Paste")
			(net "GND")
		)
	)
	(footprint ""
		(layer "B.Cu")
		(at 323.679566 -416.899344 90)
		(property "Reference" "C6546"
			(at 0 0 90)
			(layer "B.SilkS")
			(hide yes)
			(effects
				(font
					(size 1.27 1.27)
				)
				(justify mirror)
			)
		)
		(property "Value" ""
			(at 0 0 90)
			(layer "B.Fab")
			(effects
				(font
					(size 1.27 1.27)
				)
				(justify mirror)
			)
		)
		(duplicate_pad_numbers_are_jumpers no)
		(fp_line
			(start 0.299974 -0.150114)
			(end -0.299974 -0.150114)
			(stroke
				(width 0.1)
				(type default)
			)
			(layer "B.Fab")
		)
		(fp_line
			(start -0.299974 -0.150114)
			(end -0.299974 0.150114)
			(stroke
				(width 0.1)
				(type default)
			)
			(layer "B.Fab")
		)
		(fp_line
			(start 0.299974 0.150114)
			(end 0.299974 -0.150114)
			(stroke
				(width 0.1)
				(type default)
			)
			(layer "B.Fab")
		)
		(fp_line
			(start -0.299974 0.150114)
			(end 0.299974 0.150114)
			(stroke
				(width 0.1)
				(type default)
			)
			(layer "B.Fab")
		)
		(pad "1" smd rect
			(at 0.2667 0 270)
			(size 0.3048 0.381)
			(layers "B.Cu" "B.Mask" "B.Paste")
			(net "P5E_CPU0_P1_TX_BUF_C_DN<6>")
		)
		(pad "2" smd rect
			(at -0.2667 0 270)
			(size 0.3048 0.381)
			(layers "B.Cu" "B.Mask" "B.Paste")
			(net "P5E_CPU0_P1_TX_BUF_DN<6>")
		)
	)
	(footprint ""
		(layer "B.Cu")
		(at 67.201034 -198.269352)
		(property "Reference" "R558"
			(at 0 0 0)
			(layer "B.SilkS")
			(hide yes)
			(effects
				(font
					(size 1.27 1.27)
				)
				(justify mirror)
			)
		)
		(property "Value" ""
			(at 0 0 0)
			(layer "B.Fab")
			(effects
				(font
					(size 1.27 1.27)
				)
				(justify mirror)
			)
		)
		(duplicate_pad_numbers_are_jumpers no)
		(fp_line
			(start -0.7874 -0.4064)
			(end -0.7874 0.4064)
			(stroke
				(width 0.1524)
				(type default)
			)
			(layer "B.SilkS")
		)
		(fp_line
			(start -0.7874 0.4064)
			(end 0.7874 0.4064)
			(stroke
				(width 0.1524)
				(type default)
			)
			(layer "B.SilkS")
		)
		(fp_line
			(start 0.7874 -0.4064)
			(end -0.7874 -0.4064)
			(stroke
				(width 0.1524)
				(type default)
			)
			(layer "B.SilkS")
		)
		(fp_line
			(start 0.7874 0.4064)
			(end 0.7874 -0.4064)
			(stroke
				(width 0.1524)
				(type default)
			)
			(layer "B.SilkS")
		)
		(fp_line
			(start -0.67945 -0.3048)
			(end -0.67945 0.3048)
			(stroke
				(width 0.1)
				(type default)
			)
			(layer "B.Fab")
		)
		(fp_line
			(start -0.67945 0.3048)
			(end -0.120396 0.3048)
			(stroke
				(width 0.1)
				(type default)
			)
			(layer "B.Fab")
		)
		(fp_line
			(start -0.12065 -0.3048)
			(end -0.67945 -0.3048)
			(stroke
				(width 0.1)
				(type default)
			)
			(layer "B.Fab")
		)
		(fp_line
			(start -0.12065 -0.2794)
			(end -0.12065 -0.3048)
			(stroke
				(width 0.1)
				(type default)
			)
			(layer "B.Fab")
		)
		(fp_line
			(start -0.120396 0.2794)
			(end 0.12065 0.2794)
			(stroke
				(width 0.1)
				(type default)
			)
			(layer "B.Fab")
		)
		(fp_line
			(start -0.120396 0.3048)
			(end -0.120396 0.2794)
			(stroke
				(width 0.1)
				(type default)
			)
			(layer "B.Fab")
		)
		(fp_line
			(start 0.12065 -0.305054)
			(end 0.12065 -0.2794)
			(stroke
				(width 0.1)
				(type default)
			)
			(layer "B.Fab")
		)
		(fp_line
			(start 0.12065 -0.2794)
			(end -0.12065 -0.2794)
			(stroke
				(width 0.1)
				(type default)
			)
			(layer "B.Fab")
		)
		(fp_line
			(start 0.12065 0.2794)
			(end 0.12065 0.3048)
			(stroke
				(width 0.1)
				(type default)
			)
			(layer "B.Fab")
		)
		(fp_line
			(start 0.12065 0.3048)
			(end 0.67945 0.3048)
			(stroke
				(width 0.1)
				(type default)
			)
			(layer "B.Fab")
		)
		(fp_line
			(start 0.67945 -0.305054)
			(end 0.12065 -0.305054)
			(stroke
				(width 0.1)
				(type default)
			)
			(layer "B.Fab")
		)
		(fp_line
			(start 0.67945 0.3048)
			(end 0.67945 -0.305054)
			(stroke
				(width 0.1)
				(type default)
			)
			(layer "B.Fab")
		)
		(pad "1" smd circle
			(at 0.40005 0 180)
			(size 0 0)
			(layers "B.Cu" "B.Mask" "B.Paste")
			(net "CPU1_FORCE_SELFREFRESH")
		)
		(pad "2" smd circle
			(at -0.40005 0 180)
			(size 0 0)
			(layers "B.Cu" "B.Mask" "B.Paste")
			(net "PVDD18_S5_P1")
		)
	)
	(footprint ""
		(layer "B.Cu")
		(at 108.117386 -253.432564)
		(property "Reference" "C2258"
			(at 0 0 0)
			(layer "B.SilkS")
			(hide yes)
			(effects
				(font
					(size 1.27 1.27)
				)
				(justify mirror)
			)
		)
		(property "Value" ""
			(at 0 0 0)
			(layer "B.Fab")
			(effects
				(font
					(size 1.27 1.27)
				)
				(justify mirror)
			)
		)
		(duplicate_pad_numbers_are_jumpers no)
		(fp_line
			(start -0.7874 -0.4064)
			(end -0.7874 0.4064)
			(stroke
				(width 0.1524)
				(type default)
			)
			(layer "B.SilkS")
		)
		(fp_line
			(start -0.7874 0.4064)
			(end 0.7874 0.4064)
			(stroke
				(width 0.1524)
				(type default)
			)
			(layer "B.SilkS")
		)
		(fp_line
			(start 0.7874 -0.4064)
			(end -0.7874 -0.4064)
			(stroke
				(width 0.1524)
				(type default)
			)
			(layer "B.SilkS")
		)
		(fp_line
			(start 0.7874 0.4064)
			(end 0.7874 -0.4064)
			(stroke
				(width 0.1524)
				(type default)
			)
			(layer "B.SilkS")
		)
		(fp_line
			(start -0.67945 -0.3048)
			(end -0.67945 0.3048)
			(stroke
				(width 0.1)
				(type default)
			)
			(layer "B.Fab")
		)
		(fp_line
			(start -0.67945 0.3048)
			(end -0.120396 0.3048)
			(stroke
				(width 0.1)
				(type default)
			)
			(layer "B.Fab")
		)
		(fp_line
			(start -0.12065 -0.3048)
			(end -0.67945 -0.3048)
			(stroke
				(width 0.1)
				(type default)
			)
			(layer "B.Fab")
		)
		(fp_line
			(start -0.12065 -0.2794)
			(end -0.12065 -0.3048)
			(stroke
				(width 0.1)
				(type default)
			)
			(layer "B.Fab")
		)
		(fp_line
			(start -0.120396 0.2794)
			(end 0.12065 0.2794)
			(stroke
				(width 0.1)
				(type default)
			)
			(layer "B.Fab")
		)
		(fp_line
			(start -0.120396 0.3048)
			(end -0.120396 0.2794)
			(stroke
				(width 0.1)
				(type default)
			)
			(layer "B.Fab")
		)
		(fp_line
			(start 0.12065 -0.305054)
			(end 0.12065 -0.2794)
			(stroke
				(width 0.1)
				(type default)
			)
			(layer "B.Fab")
		)
		(fp_line
			(start 0.12065 -0.2794)
			(end -0.12065 -0.2794)
			(stroke
				(width 0.1)
				(type default)
			)
			(layer "B.Fab")
		)
		(fp_line
			(start 0.12065 0.2794)
			(end 0.12065 0.3048)
			(stroke
				(width 0.1)
				(type default)
			)
			(layer "B.Fab")
		)
		(fp_line
			(start 0.12065 0.3048)
			(end 0.67945 0.3048)
			(stroke
				(width 0.1)
				(type default)
			)
			(layer "B.Fab")
		)
		(fp_line
			(start 0.67945 -0.305054)
			(end 0.12065 -0.305054)
			(stroke
				(width 0.1)
				(type default)
			)
			(layer "B.Fab")
		)
		(fp_line
			(start 0.67945 0.3048)
			(end 0.67945 -0.305054)
			(stroke
				(width 0.1)
				(type default)
			)
			(layer "B.Fab")
		)
		(pad "1" smd circle
			(at 0.40005 0 180)
			(size 0 0)
			(layers "B.Cu" "B.Mask" "B.Paste")
			(net "PVDDCR_SOC_P1")
		)
		(pad "2" smd circle
			(at -0.40005 0 180)
			(size 0 0)
			(layers "B.Cu" "B.Mask" "B.Paste")
			(net "GND")
		)
	)
	(footprint ""
		(layer "B.Cu")
		(at 65.378584 -386.766562 90)
		(property "Reference" "C188"
			(at 0 0 90)
			(layer "B.SilkS")
			(hide yes)
			(effects
				(font
					(size 1.27 1.27)
				)
				(justify mirror)
			)
		)
		(property "Value" ""
			(at 0 0 90)
			(layer "B.Fab")
			(effects
				(font
					(size 1.27 1.27)
				)
				(justify mirror)
			)
		)
		(duplicate_pad_numbers_are_jumpers no)
		(fp_line
			(start 0.299974 -0.150114)
			(end -0.299974 -0.150114)
			(stroke
				(width 0.1)
				(type default)
			)
			(layer "B.Fab")
		)
		(fp_line
			(start -0.299974 -0.150114)
			(end -0.299974 0.150114)
			(stroke
				(width 0.1)
				(type default)
			)
			(layer "B.Fab")
		)
		(fp_line
			(start 0.299974 0.150114)
			(end 0.299974 -0.150114)
			(stroke
				(width 0.1)
				(type default)
			)
			(layer "B.Fab")
		)
		(fp_line
			(start -0.299974 0.150114)
			(end 0.299974 0.150114)
			(stroke
				(width 0.1)
				(type default)
			)
			(layer "B.Fab")
		)
		(pad "1" smd rect
			(at 0.2667 0 270)
			(size 0.3048 0.381)
			(layers "B.Cu" "B.Mask" "B.Paste")
			(net "P0V9_CPU1_RT0_2A")
		)
		(pad "2" smd rect
			(at -0.2667 0 270)
			(size 0.3048 0.381)
			(layers "B.Cu" "B.Mask" "B.Paste")
			(net "GND")
		)
	)
	(footprint ""
		(layer "B.Cu")
		(at 230.891842 -315.95568 -90)
		(property "Reference" "PC6529"
			(at 0 0 90)
			(layer "B.SilkS")
			(hide yes)
			(effects
				(font
					(size 1.27 1.27)
				)
				(justify mirror)
			)
		)
		(property "Value" ""
			(at 0 0 90)
			(layer "B.Fab")
			(effects
				(font
					(size 1.27 1.27)
				)
				(justify mirror)
			)
		)
		(duplicate_pad_numbers_are_jumpers no)
		(fp_line
			(start -1.524 0.762)
			(end 1.524 0.762)
			(stroke
				(width 0.1524)
				(type default)
			)
			(layer "B.SilkS")
		)
		(fp_line
			(start 1.524 0.762)
			(end 1.524 -0.762)
			(stroke
				(width 0.1524)
				(type default)
			)
			(layer "B.SilkS")
		)
		(fp_line
			(start -1.524 -0.762)
			(end -1.524 0.762)
			(stroke
				(width 0.1524)
				(type default)
			)
			(layer "B.SilkS")
		)
		(fp_line
			(start 1.524 -0.762)
			(end -1.524 -0.762)
			(stroke
				(width 0.1524)
				(type default)
			)
			(layer "B.SilkS")
		)
		(fp_line
			(start -1.1049 0.724916)
			(end -1.1049 -0.724916)
			(stroke
				(width 0.1)
				(type default)
			)
			(layer "B.Fab")
		)
		(fp_line
			(start 1.1049 0.724916)
			(end -1.1049 0.724916)
			(stroke
				(width 0.1)
				(type default)
			)
			(layer "B.Fab")
		)
		(fp_line
			(start -1.1049 -0.724916)
			(end 1.1049 -0.724916)
			(stroke
				(width 0.1)
				(type default)
			)
			(layer "B.Fab")
		)
		(fp_line
			(start 1.1049 -0.724916)
			(end 1.1049 0.724916)
			(stroke
				(width 0.1)
				(type default)
			)
			(layer "B.Fab")
		)
		(pad "1" smd rect
			(at 0.889 0 270)
			(size 1.016 1.27)
			(layers "B.Cu" "B.Mask" "B.Paste")
			(net "P1V8_CPU1_RT_1D")
		)
		(pad "2" smd rect
			(at -0.889 0 270)
			(size 1.016 1.27)
			(layers "B.Cu" "B.Mask" "B.Paste")
			(net "GND")
		)
	)
	(footprint ""
		(layer "B.Cu")
		(at 46.434502 -422.527984 90)
		(property "Reference" "R3320"
			(at 0 0 90)
			(layer "B.SilkS")
			(hide yes)
			(effects
				(font
					(size 1.27 1.27)
				)
				(justify mirror)
			)
		)
		(property "Value" ""
			(at 0 0 90)
			(layer "B.Fab")
			(effects
				(font
					(size 1.27 1.27)
				)
				(justify mirror)
			)
		)
		(duplicate_pad_numbers_are_jumpers no)
		(fp_line
			(start 0.7874 -0.4064)
			(end -0.7874 -0.4064)
			(stroke
				(width 0.1524)
				(type default)
			)
			(layer "B.SilkS")
		)
		(fp_line
			(start -0.7874 -0.4064)
			(end -0.7874 0.4064)
			(stroke
				(width 0.1524)
				(type default)
			)
			(layer "B.SilkS")
		)
		(fp_line
			(start 0.7874 0.4064)
			(end 0.7874 -0.4064)
			(stroke
				(width 0.1524)
				(type default)
			)
			(layer "B.SilkS")
		)
		(fp_line
			(start -0.7874 0.4064)
			(end 0.7874 0.4064)
			(stroke
				(width 0.1524)
				(type default)
			)
			(layer "B.SilkS")
		)
		(fp_line
			(start 0.67945 -0.305054)
			(end 0.12065 -0.305054)
			(stroke
				(width 0.1)
				(type default)
			)
			(layer "B.Fab")
		)
		(fp_line
			(start 0.12065 -0.305054)
			(end 0.12065 -0.2794)
			(stroke
				(width 0.1)
				(type default)
			)
			(layer "B.Fab")
		)
		(fp_line
			(start -0.12065 -0.3048)
			(end -0.67945 -0.3048)
			(stroke
				(width 0.1)
				(type default)
			)
			(layer "B.Fab")
		)
		(fp_line
			(start -0.67945 -0.3048)
			(end -0.67945 0.3048)
			(stroke
				(width 0.1)
				(type default)
			)
			(layer "B.Fab")
		)
		(fp_line
			(start 0.12065 -0.2794)
			(end -0.12065 -0.2794)
			(stroke
				(width 0.1)
				(type default)
			)
			(layer "B.Fab")
		)
		(fp_line
			(start -0.12065 -0.2794)
			(end -0.12065 -0.3048)
			(stroke
				(width 0.1)
				(type default)
			)
			(layer "B.Fab")
		)
		(fp_line
			(start 0.12065 0.2794)
			(end 0.12065 0.3048)
			(stroke
				(width 0.1)
				(type default)
			)
			(layer "B.Fab")
		)
		(fp_line
			(start -0.120396 0.2794)
			(end 0.12065 0.2794)
			(stroke
				(width 0.1)
				(type default)
			)
			(layer "B.Fab")
		)
		(fp_line
			(start 0.67945 0.3048)
			(end 0.67945 -0.305054)
			(stroke
				(width 0.1)
				(type default)
			)
			(layer "B.Fab")
		)
		(fp_line
			(start 0.12065 0.3048)
			(end 0.67945 0.3048)
			(stroke
				(width 0.1)
				(type default)
			)
			(layer "B.Fab")
		)
		(fp_line
			(start -0.120396 0.3048)
			(end -0.120396 0.2794)
			(stroke
				(width 0.1)
				(type default)
			)
			(layer "B.Fab")
		)
		(fp_line
			(start -0.67945 0.3048)
			(end -0.120396 0.3048)
			(stroke
				(width 0.1)
				(type default)
			)
			(layer "B.Fab")
		)
		(pad "1" smd circle
			(at 0.40005 0 270)
			(size 0 0)
			(layers "B.Cu" "B.Mask" "B.Paste")
			(net "P3V3_AUX")
		)
		(pad "2" smd circle
			(at -0.40005 0 270)
			(size 0 0)
			(layers "B.Cu" "B.Mask" "B.Paste")
			(net "GPU_FPGA_READY_N")
		)
	)
	(footprint ""
		(layer "B.Cu")
		(at 125.278388 -386.766562 90)
		(property "Reference" "C441"
			(at 0 0 90)
			(layer "B.SilkS")
			(hide yes)
			(effects
				(font
					(size 1.27 1.27)
				)
				(justify mirror)
			)
		)
		(property "Value" ""
			(at 0 0 90)
			(layer "B.Fab")
			(effects
				(font
					(size 1.27 1.27)
				)
				(justify mirror)
			)
		)
		(duplicate_pad_numbers_are_jumpers no)
		(fp_line
			(start 0.299974 -0.150114)
			(end -0.299974 -0.150114)
			(stroke
				(width 0.1)
				(type default)
			)
			(layer "B.Fab")
		)
		(fp_line
			(start -0.299974 -0.150114)
			(end -0.299974 0.150114)
			(stroke
				(width 0.1)
				(type default)
			)
			(layer "B.Fab")
		)
		(fp_line
			(start 0.299974 0.150114)
			(end 0.299974 -0.150114)
			(stroke
				(width 0.1)
				(type default)
			)
			(layer "B.Fab")
		)
		(fp_line
			(start -0.299974 0.150114)
			(end 0.299974 0.150114)
			(stroke
				(width 0.1)
				(type default)
			)
			(layer "B.Fab")
		)
		(pad "1" smd rect
			(at 0.2667 0 270)
			(size 0.3048 0.381)
			(layers "B.Cu" "B.Mask" "B.Paste")
			(net "P1V8_CPU1_RT3_1A_1D")
		)
		(pad "2" smd rect
			(at -0.2667 0 270)
			(size 0.3048 0.381)
			(layers "B.Cu" "B.Mask" "B.Paste")
			(net "GND")
		)
	)
	(footprint ""
		(layer "B.Cu")
		(at 398.893538 -392.1252 180)
		(property "Reference" "R1064"
			(at 0 0 0)
			(layer "B.SilkS")
			(hide yes)
			(effects
				(font
					(size 1.27 1.27)
				)
				(justify mirror)
			)
		)
		(property "Value" ""
			(at 0 0 0)
			(layer "B.Fab")
			(effects
				(font
					(size 1.27 1.27)
				)
				(justify mirror)
			)
		)
		(duplicate_pad_numbers_are_jumpers no)
		(fp_line
			(start 0.32512 0.175006)
			(end 0.32512 -0.175006)
			(stroke
				(width 0.1)
				(type default)
			)
			(layer "B.Fab")
		)
		(fp_line
			(start 0.32512 -0.175006)
			(end -0.32512 -0.175006)
			(stroke
				(width 0.1)
				(type default)
			)
			(layer "B.Fab")
		)
		(fp_line
			(start -0.32512 0.175006)
			(end 0.32512 0.175006)
			(stroke
				(width 0.1)
				(type default)
			)
			(layer "B.Fab")
		)
		(fp_line
			(start -0.32512 -0.175006)
			(end -0.32512 0.175006)
			(stroke
				(width 0.1)
				(type default)
			)
			(layer "B.Fab")
		)
		(pad "1" smd rect
			(at 0.2667 0)
			(size 0.3048 0.381)
			(layers "B.Cu" "B.Mask" "B.Paste")
			(net "RT_CPU0_P2_SCAN_MODE")
		)
		(pad "2" smd rect
			(at -0.2667 0 180)
			(size 0.3048 0.381)
			(layers "B.Cu" "B.Mask" "B.Paste")
			(net "GND")
		)
	)
	(footprint ""
		(layer "B.Cu")
		(at 181.534562 -97.123504 -90)
		(property "Reference" "R489"
			(at 0 0 90)
			(layer "B.SilkS")
			(hide yes)
			(effects
				(font
					(size 1.27 1.27)
				)
				(justify mirror)
			)
		)
		(property "Value" ""
			(at 0 0 90)
			(layer "B.Fab")
			(effects
				(font
					(size 1.27 1.27)
				)
				(justify mirror)
			)
		)
		(duplicate_pad_numbers_are_jumpers no)
		(fp_line
			(start -0.7874 0.4064)
			(end 0.7874 0.4064)
			(stroke
				(width 0.1524)
				(type default)
			)
			(layer "B.SilkS")
		)
		(fp_line
			(start 0.7874 0.4064)
			(end 0.7874 -0.4064)
			(stroke
				(width 0.1524)
				(type default)
			)
			(layer "B.SilkS")
		)
		(fp_line
			(start -0.7874 -0.4064)
			(end -0.7874 0.4064)
			(stroke
				(width 0.1524)
				(type default)
			)
			(layer "B.SilkS")
		)
		(fp_line
			(start 0.7874 -0.4064)
			(end -0.7874 -0.4064)
			(stroke
				(width 0.1524)
				(type default)
			)
			(layer "B.SilkS")
		)
		(fp_line
			(start -0.67945 0.3048)
			(end -0.120396 0.3048)
			(stroke
				(width 0.1)
				(type default)
			)
			(layer "B.Fab")
		)
		(fp_line
			(start -0.120396 0.3048)
			(end -0.120396 0.2794)
			(stroke
				(width 0.1)
				(type default)
			)
			(layer "B.Fab")
		)
		(fp_line
			(start 0.12065 0.3048)
			(end 0.67945 0.3048)
			(stroke
				(width 0.1)
				(type default)
			)
			(layer "B.Fab")
		)
		(fp_line
			(start 0.67945 0.3048)
			(end 0.67945 -0.305054)
			(stroke
				(width 0.1)
				(type default)
			)
			(layer "B.Fab")
		)
		(fp_line
			(start -0.120396 0.2794)
			(end 0.12065 0.2794)
			(stroke
				(width 0.1)
				(type default)
			)
			(layer "B.Fab")
		)
		(fp_line
			(start 0.12065 0.2794)
			(end 0.12065 0.3048)
			(stroke
				(width 0.1)
				(type default)
			)
			(layer "B.Fab")
		)
		(fp_line
			(start -0.12065 -0.2794)
			(end -0.12065 -0.3048)
			(stroke
				(width 0.1)
				(type default)
			)
			(layer "B.Fab")
		)
		(fp_line
			(start 0.12065 -0.2794)
			(end -0.12065 -0.2794)
			(stroke
				(width 0.1)
				(type default)
			)
			(layer "B.Fab")
		)
		(fp_line
			(start -0.67945 -0.3048)
			(end -0.67945 0.3048)
			(stroke
				(width 0.1)
				(type default)
			)
			(layer "B.Fab")
		)
		(fp_line
			(start -0.12065 -0.3048)
			(end -0.67945 -0.3048)
			(stroke
				(width 0.1)
				(type default)
			)
			(layer "B.Fab")
		)
		(fp_line
			(start 0.12065 -0.305054)
			(end 0.12065 -0.2794)
			(stroke
				(width 0.1)
				(type default)
			)
			(layer "B.Fab")
		)
		(fp_line
			(start 0.67945 -0.305054)
			(end 0.12065 -0.305054)
			(stroke
				(width 0.1)
				(type default)
			)
			(layer "B.Fab")
		)
		(pad "1" smd circle
			(at 0.40005 0 90)
			(size 0 0)
			(layers "B.Cu" "B.Mask" "B.Paste")
			(net "CPU0_THERMTRIP_N")
		)
		(pad "2" smd circle
			(at -0.40005 0 90)
			(size 0 0)
			(layers "B.Cu" "B.Mask" "B.Paste")
			(net "CPU0_THERMTRIP_R_N")
		)
	)
	(footprint ""
		(layer "B.Cu")
		(at 89.518998 -390.560052 90)
		(property "Reference" "C199"
			(at 0 0 90)
			(layer "B.SilkS")
			(hide yes)
			(effects
				(font
					(size 1.27 1.27)
				)
				(justify mirror)
			)
		)
		(property "Value" ""
			(at 0 0 90)
			(layer "B.Fab")
			(effects
				(font
					(size 1.27 1.27)
				)
				(justify mirror)
			)
		)
		(duplicate_pad_numbers_are_jumpers no)
		(fp_line
			(start 0.7874 -0.4064)
			(end -0.7874 -0.4064)
			(stroke
				(width 0.1524)
				(type default)
			)
			(layer "B.SilkS")
		)
		(fp_line
			(start -0.7874 -0.4064)
			(end -0.7874 0.4064)
			(stroke
				(width 0.1524)
				(type default)
			)
			(layer "B.SilkS")
		)
		(fp_line
			(start 0.7874 0.4064)
			(end 0.7874 -0.4064)
			(stroke
				(width 0.1524)
				(type default)
			)
			(layer "B.SilkS")
		)
		(fp_line
			(start -0.7874 0.4064)
			(end 0.7874 0.4064)
			(stroke
				(width 0.1524)
				(type default)
			)
			(layer "B.SilkS")
		)
		(fp_line
			(start 0.67945 -0.305054)
			(end 0.12065 -0.305054)
			(stroke
				(width 0.1)
				(type default)
			)
			(layer "B.Fab")
		)
		(fp_line
			(start 0.12065 -0.305054)
			(end 0.12065 -0.2794)
			(stroke
				(width 0.1)
				(type default)
			)
			(layer "B.Fab")
		)
		(fp_line
			(start -0.12065 -0.3048)
			(end -0.67945 -0.3048)
			(stroke
				(width 0.1)
				(type default)
			)
			(layer "B.Fab")
		)
		(fp_line
			(start -0.67945 -0.3048)
			(end -0.67945 0.3048)
			(stroke
				(width 0.1)
				(type default)
			)
			(layer "B.Fab")
		)
		(fp_line
			(start 0.12065 -0.2794)
			(end -0.12065 -0.2794)
			(stroke
				(width 0.1)
				(type default)
			)
			(layer "B.Fab")
		)
		(fp_line
			(start -0.12065 -0.2794)
			(end -0.12065 -0.3048)
			(stroke
				(width 0.1)
				(type default)
			)
			(layer "B.Fab")
		)
		(fp_line
			(start 0.12065 0.2794)
			(end 0.12065 0.3048)
			(stroke
				(width 0.1)
				(type default)
			)
			(layer "B.Fab")
		)
		(fp_line
			(start -0.120396 0.2794)
			(end 0.12065 0.2794)
			(stroke
				(width 0.1)
				(type default)
			)
			(layer "B.Fab")
		)
		(fp_line
			(start 0.67945 0.3048)
			(end 0.67945 -0.305054)
			(stroke
				(width 0.1)
				(type default)
			)
			(layer "B.Fab")
		)
		(fp_line
			(start 0.12065 0.3048)
			(end 0.67945 0.3048)
			(stroke
				(width 0.1)
				(type default)
			)
			(layer "B.Fab")
		)
		(fp_line
			(start -0.120396 0.3048)
			(end -0.120396 0.2794)
			(stroke
				(width 0.1)
				(type default)
			)
			(layer "B.Fab")
		)
		(fp_line
			(start -0.67945 0.3048)
			(end -0.120396 0.3048)
			(stroke
				(width 0.1)
				(type default)
			)
			(layer "B.Fab")
		)
		(pad "1" smd circle
			(at 0.40005 0 270)
			(size 0 0)
			(layers "B.Cu" "B.Mask" "B.Paste")
			(net "P1V8_CPU1_RT1_1A")
		)
		(pad "2" smd circle
			(at -0.40005 0 270)
			(size 0 0)
			(layers "B.Cu" "B.Mask" "B.Paste")
			(net "GND")
		)
	)
	(footprint ""
		(layer "B.Cu")
		(at 102.389432 -390.073134 180)
		(property "Reference" "C317"
			(at 0 0 0)
			(layer "B.SilkS")
			(hide yes)
			(effects
				(font
					(size 1.27 1.27)
				)
				(justify mirror)
			)
		)
		(property "Value" ""
			(at 0 0 0)
			(layer "B.Fab")
			(effects
				(font
					(size 1.27 1.27)
				)
				(justify mirror)
			)
		)
		(duplicate_pad_numbers_are_jumpers no)
		(fp_line
			(start 1.524 0.762)
			(end 1.524 -0.762)
			(stroke
				(width 0.1524)
				(type default)
			)
			(layer "B.SilkS")
		)
		(fp_line
			(start 1.524 -0.762)
			(end -1.524 -0.762)
			(stroke
				(width 0.1524)
				(type default)
			)
			(layer "B.SilkS")
		)
		(fp_line
			(start -1.524 0.762)
			(end 1.524 0.762)
			(stroke
				(width 0.1524)
				(type default)
			)
			(layer "B.SilkS")
		)
		(fp_line
			(start -1.524 -0.762)
			(end -1.524 0.762)
			(stroke
				(width 0.1524)
				(type default)
			)
			(layer "B.SilkS")
		)
		(fp_line
			(start 1.1049 0.724916)
			(end -1.1049 0.724916)
			(stroke
				(width 0.1)
				(type default)
			)
			(layer "B.Fab")
		)
		(fp_line
			(start 1.1049 -0.724916)
			(end 1.1049 0.724916)
			(stroke
				(width 0.1)
				(type default)
			)
			(layer "B.Fab")
		)
		(fp_line
			(start -1.1049 0.724916)
			(end -1.1049 -0.724916)
			(stroke
				(width 0.1)
				(type default)
			)
			(layer "B.Fab")
		)
		(fp_line
			(start -1.1049 -0.724916)
			(end 1.1049 -0.724916)
			(stroke
				(width 0.1)
				(type default)
			)
			(layer "B.Fab")
		)
		(pad "1" smd rect
			(at 0.889 0 180)
			(size 1.016 1.27)
			(layers "B.Cu" "B.Mask" "B.Paste")
			(net "P0V9_CPU1_RT1_2A")
		)
		(pad "2" smd rect
			(at -0.889 0 180)
			(size 1.016 1.27)
			(layers "B.Cu" "B.Mask" "B.Paste")
			(net "GND")
		)
	)
	(footprint ""
		(layer "B.Cu")
		(at 168.367202 -14.4653 -90)
		(property "Reference" "R1386"
			(at 0 0 90)
			(layer "B.SilkS")
			(hide yes)
			(effects
				(font
					(size 1.27 1.27)
				)
				(justify mirror)
			)
		)
		(property "Value" ""
			(at 0 0 90)
			(layer "B.Fab")
			(effects
				(font
					(size 1.27 1.27)
				)
				(justify mirror)
			)
		)
		(duplicate_pad_numbers_are_jumpers no)
		(fp_line
			(start -0.7874 0.4064)
			(end 0.7874 0.4064)
			(stroke
				(width 0.1524)
				(type default)
			)
			(layer "B.SilkS")
		)
		(fp_line
			(start 0.7874 0.4064)
			(end 0.7874 -0.4064)
			(stroke
				(width 0.1524)
				(type default)
			)
			(layer "B.SilkS")
		)
		(fp_line
			(start -0.7874 -0.4064)
			(end -0.7874 0.4064)
			(stroke
				(width 0.1524)
				(type default)
			)
			(layer "B.SilkS")
		)
		(fp_line
			(start 0.7874 -0.4064)
			(end -0.7874 -0.4064)
			(stroke
				(width 0.1524)
				(type default)
			)
			(layer "B.SilkS")
		)
		(fp_line
			(start -0.67945 0.3048)
			(end -0.120396 0.3048)
			(stroke
				(width 0.1)
				(type default)
			)
			(layer "B.Fab")
		)
		(fp_line
			(start -0.120396 0.3048)
			(end -0.120396 0.2794)
			(stroke
				(width 0.1)
				(type default)
			)
			(layer "B.Fab")
		)
		(fp_line
			(start 0.12065 0.3048)
			(end 0.67945 0.3048)
			(stroke
				(width 0.1)
				(type default)
			)
			(layer "B.Fab")
		)
		(fp_line
			(start 0.67945 0.3048)
			(end 0.67945 -0.305054)
			(stroke
				(width 0.1)
				(type default)
			)
			(layer "B.Fab")
		)
		(fp_line
			(start -0.120396 0.2794)
			(end 0.12065 0.2794)
			(stroke
				(width 0.1)
				(type default)
			)
			(layer "B.Fab")
		)
		(fp_line
			(start 0.12065 0.2794)
			(end 0.12065 0.3048)
			(stroke
				(width 0.1)
				(type default)
			)
			(layer "B.Fab")
		)
		(fp_line
			(start -0.12065 -0.2794)
			(end -0.12065 -0.3048)
			(stroke
				(width 0.1)
				(type default)
			)
			(layer "B.Fab")
		)
		(fp_line
			(start 0.12065 -0.2794)
			(end -0.12065 -0.2794)
			(stroke
				(width 0.1)
				(type default)
			)
			(layer "B.Fab")
		)
		(fp_line
			(start -0.67945 -0.3048)
			(end -0.67945 0.3048)
			(stroke
				(width 0.1)
				(type default)
			)
			(layer "B.Fab")
		)
		(fp_line
			(start -0.12065 -0.3048)
			(end -0.67945 -0.3048)
			(stroke
				(width 0.1)
				(type default)
			)
			(layer "B.Fab")
		)
		(fp_line
			(start 0.12065 -0.305054)
			(end 0.12065 -0.2794)
			(stroke
				(width 0.1)
				(type default)
			)
			(layer "B.Fab")
		)
		(fp_line
			(start 0.67945 -0.305054)
			(end 0.12065 -0.305054)
			(stroke
				(width 0.1)
				(type default)
			)
			(layer "B.Fab")
		)
		(pad "1" smd circle
			(at 0.40005 0 90)
			(size 0 0)
			(layers "B.Cu" "B.Mask" "B.Paste")
			(net "SMB_PMBUS_3V3AUX_SCL")
		)
		(pad "2" smd circle
			(at -0.40005 0 90)
			(size 0 0)
			(layers "B.Cu" "B.Mask" "B.Paste")
			(net "P3V3_AUX")
		)
	)
	(footprint ""
		(layer "B.Cu")
		(at 370.905278 -147.568158)
		(property "Reference" "PR283"
			(at 0 0 0)
			(layer "B.SilkS")
			(hide yes)
			(effects
				(font
					(size 1.27 1.27)
				)
				(justify mirror)
			)
		)
		(property "Value" ""
			(at 0 0 0)
			(layer "B.Fab")
			(effects
				(font
					(size 1.27 1.27)
				)
				(justify mirror)
			)
		)
		(duplicate_pad_numbers_are_jumpers no)
		(fp_line
			(start -0.7874 -0.4064)
			(end -0.7874 0.4064)
			(stroke
				(width 0.1524)
				(type default)
			)
			(layer "B.SilkS")
		)
		(fp_line
			(start -0.7874 0.4064)
			(end 0.7874 0.4064)
			(stroke
				(width 0.1524)
				(type default)
			)
			(layer "B.SilkS")
		)
		(fp_line
			(start 0.7874 -0.4064)
			(end -0.7874 -0.4064)
			(stroke
				(width 0.1524)
				(type default)
			)
			(layer "B.SilkS")
		)
		(fp_line
			(start 0.7874 0.4064)
			(end 0.7874 -0.4064)
			(stroke
				(width 0.1524)
				(type default)
			)
			(layer "B.SilkS")
		)
		(fp_line
			(start -0.67945 -0.3048)
			(end -0.67945 0.3048)
			(stroke
				(width 0.1)
				(type default)
			)
			(layer "B.Fab")
		)
		(fp_line
			(start -0.67945 0.3048)
			(end -0.120396 0.3048)
			(stroke
				(width 0.1)
				(type default)
			)
			(layer "B.Fab")
		)
		(fp_line
			(start -0.12065 -0.3048)
			(end -0.67945 -0.3048)
			(stroke
				(width 0.1)
				(type default)
			)
			(layer "B.Fab")
		)
		(fp_line
			(start -0.12065 -0.2794)
			(end -0.12065 -0.3048)
			(stroke
				(width 0.1)
				(type default)
			)
			(layer "B.Fab")
		)
		(fp_line
			(start -0.120396 0.2794)
			(end 0.12065 0.2794)
			(stroke
				(width 0.1)
				(type default)
			)
			(layer "B.Fab")
		)
		(fp_line
			(start -0.120396 0.3048)
			(end -0.120396 0.2794)
			(stroke
				(width 0.1)
				(type default)
			)
			(layer "B.Fab")
		)
		(fp_line
			(start 0.12065 -0.305054)
			(end 0.12065 -0.2794)
			(stroke
				(width 0.1)
				(type default)
			)
			(layer "B.Fab")
		)
		(fp_line
			(start 0.12065 -0.2794)
			(end -0.12065 -0.2794)
			(stroke
				(width 0.1)
				(type default)
			)
			(layer "B.Fab")
		)
		(fp_line
			(start 0.12065 0.2794)
			(end 0.12065 0.3048)
			(stroke
				(width 0.1)
				(type default)
			)
			(layer "B.Fab")
		)
		(fp_line
			(start 0.12065 0.3048)
			(end 0.67945 0.3048)
			(stroke
				(width 0.1)
				(type default)
			)
			(layer "B.Fab")
		)
		(fp_line
			(start 0.67945 -0.305054)
			(end 0.12065 -0.305054)
			(stroke
				(width 0.1)
				(type default)
			)
			(layer "B.Fab")
		)
		(fp_line
			(start 0.67945 0.3048)
			(end 0.67945 -0.305054)
			(stroke
				(width 0.1)
				(type default)
			)
			(layer "B.Fab")
		)
		(pad "1" smd circle
			(at 0.40005 0 180)
			(size 0 0)
			(layers "B.Cu" "B.Mask" "B.Paste")
			(net "SVID_PVDDCR_CPU0_P0_SVTI")
		)
		(pad "2" smd circle
			(at -0.40005 0 180)
			(size 0 0)
			(layers "B.Cu" "B.Mask" "B.Paste")
			(net "GND")
		)
	)
	(footprint ""
		(layer "B.Cu")
		(at 164.062918 -119.336058)
		(property "Reference" "R6092"
			(at 0 0 0)
			(layer "B.SilkS")
			(hide yes)
			(effects
				(font
					(size 1.27 1.27)
				)
				(justify mirror)
			)
		)
		(property "Value" ""
			(at 0 0 0)
			(layer "B.Fab")
			(effects
				(font
					(size 1.27 1.27)
				)
				(justify mirror)
			)
		)
		(duplicate_pad_numbers_are_jumpers no)
		(fp_line
			(start -0.7874 -0.4064)
			(end -0.7874 0.4064)
			(stroke
				(width 0.1524)
				(type default)
			)
			(layer "B.SilkS")
		)
		(fp_line
			(start -0.7874 0.4064)
			(end 0.7874 0.4064)
			(stroke
				(width 0.1524)
				(type default)
			)
			(layer "B.SilkS")
		)
		(fp_line
			(start 0.7874 -0.4064)
			(end -0.7874 -0.4064)
			(stroke
				(width 0.1524)
				(type default)
			)
			(layer "B.SilkS")
		)
		(fp_line
			(start 0.7874 0.4064)
			(end 0.7874 -0.4064)
			(stroke
				(width 0.1524)
				(type default)
			)
			(layer "B.SilkS")
		)
		(fp_line
			(start -0.67945 -0.3048)
			(end -0.67945 0.3048)
			(stroke
				(width 0.1)
				(type default)
			)
			(layer "B.Fab")
		)
		(fp_line
			(start -0.67945 0.3048)
			(end -0.120396 0.3048)
			(stroke
				(width 0.1)
				(type default)
			)
			(layer "B.Fab")
		)
		(fp_line
			(start -0.12065 -0.3048)
			(end -0.67945 -0.3048)
			(stroke
				(width 0.1)
				(type default)
			)
			(layer "B.Fab")
		)
		(fp_line
			(start -0.12065 -0.2794)
			(end -0.12065 -0.3048)
			(stroke
				(width 0.1)
				(type default)
			)
			(layer "B.Fab")
		)
		(fp_line
			(start -0.120396 0.2794)
			(end 0.12065 0.2794)
			(stroke
				(width 0.1)
				(type default)
			)
			(layer "B.Fab")
		)
		(fp_line
			(start -0.120396 0.3048)
			(end -0.120396 0.2794)
			(stroke
				(width 0.1)
				(type default)
			)
			(layer "B.Fab")
		)
		(fp_line
			(start 0.12065 -0.305054)
			(end 0.12065 -0.2794)
			(stroke
				(width 0.1)
				(type default)
			)
			(layer "B.Fab")
		)
		(fp_line
			(start 0.12065 -0.2794)
			(end -0.12065 -0.2794)
			(stroke
				(width 0.1)
				(type default)
			)
			(layer "B.Fab")
		)
		(fp_line
			(start 0.12065 0.2794)
			(end 0.12065 0.3048)
			(stroke
				(width 0.1)
				(type default)
			)
			(layer "B.Fab")
		)
		(fp_line
			(start 0.12065 0.3048)
			(end 0.67945 0.3048)
			(stroke
				(width 0.1)
				(type default)
			)
			(layer "B.Fab")
		)
		(fp_line
			(start 0.67945 -0.305054)
			(end 0.12065 -0.305054)
			(stroke
				(width 0.1)
				(type default)
			)
			(layer "B.Fab")
		)
		(fp_line
			(start 0.67945 0.3048)
			(end 0.67945 -0.305054)
			(stroke
				(width 0.1)
				(type default)
			)
			(layer "B.Fab")
		)
		(pad "1" smd circle
			(at 0.40005 0 180)
			(size 0 0)
			(layers "B.Cu" "B.Mask" "B.Paste")
			(net "SCM_SYS_PWROK_R")
		)
		(pad "2" smd circle
			(at -0.40005 0 180)
			(size 0 0)
			(layers "B.Cu" "B.Mask" "B.Paste")
			(net "SCM_SYS_PWROK_R1")
		)
	)
	(footprint ""
		(layer "B.Cu")
		(at 454.188068 -192.660016)
		(property "Reference" "C170"
			(at 0 0 0)
			(layer "B.SilkS")
			(hide yes)
			(effects
				(font
					(size 1.27 1.27)
				)
				(justify mirror)
			)
		)
		(property "Value" ""
			(at 0 0 0)
			(layer "B.Fab")
			(effects
				(font
					(size 1.27 1.27)
				)
				(justify mirror)
			)
		)
		(duplicate_pad_numbers_are_jumpers no)
		(fp_line
			(start -1.524 -0.762)
			(end -1.524 0.762)
			(stroke
				(width 0.1524)
				(type default)
			)
			(layer "B.SilkS")
		)
		(fp_line
			(start -1.524 0.762)
			(end 1.524 0.762)
			(stroke
				(width 0.1524)
				(type default)
			)
			(layer "B.SilkS")
		)
		(fp_line
			(start 1.524 -0.762)
			(end -1.524 -0.762)
			(stroke
				(width 0.1524)
				(type default)
			)
			(layer "B.SilkS")
		)
		(fp_line
			(start 1.524 0.762)
			(end 1.524 -0.762)
			(stroke
				(width 0.1524)
				(type default)
			)
			(layer "B.SilkS")
		)
		(fp_line
			(start -1.1049 -0.724916)
			(end 1.1049 -0.724916)
			(stroke
				(width 0.1)
				(type default)
			)
			(layer "B.Fab")
		)
		(fp_line
			(start -1.1049 0.724916)
			(end -1.1049 -0.724916)
			(stroke
				(width 0.1)
				(type default)
			)
			(layer "B.Fab")
		)
		(fp_line
			(start 1.1049 -0.724916)
			(end 1.1049 0.724916)
			(stroke
				(width 0.1)
				(type default)
			)
			(layer "B.Fab")
		)
		(fp_line
			(start 1.1049 0.724916)
			(end -1.1049 0.724916)
			(stroke
				(width 0.1)
				(type default)
			)
			(layer "B.Fab")
		)
		(pad "1" smd rect
			(at 0.889 0)
			(size 1.016 1.27)
			(layers "B.Cu" "B.Mask" "B.Paste")
			(net "P12V_MEM_CPU0")
		)
		(pad "2" smd rect
			(at -0.889 0)
			(size 1.016 1.27)
			(layers "B.Cu" "B.Mask" "B.Paste")
			(net "GND")
		)
	)
	(footprint ""
		(layer "B.Cu")
		(at 278.671782 -346.784168 90)
		(property "Reference" "PC185_4"
			(at 0 0 90)
			(layer "B.SilkS")
			(hide yes)
			(effects
				(font
					(size 1.27 1.27)
				)
				(justify mirror)
			)
		)
		(property "Value" ""
			(at 0 0 90)
			(layer "B.Fab")
			(effects
				(font
					(size 1.27 1.27)
				)
				(justify mirror)
			)
		)
		(duplicate_pad_numbers_are_jumpers no)
		(fp_line
			(start 1.524 -0.762)
			(end -1.524 -0.762)
			(stroke
				(width 0.1524)
				(type default)
			)
			(layer "B.SilkS")
		)
		(fp_line
			(start -1.524 -0.762)
			(end -1.524 0.762)
			(stroke
				(width 0.1524)
				(type default)
			)
			(layer "B.SilkS")
		)
		(fp_line
			(start 1.524 0.762)
			(end 1.524 -0.762)
			(stroke
				(width 0.1524)
				(type default)
			)
			(layer "B.SilkS")
		)
		(fp_line
			(start -1.524 0.762)
			(end 1.524 0.762)
			(stroke
				(width 0.1524)
				(type default)
			)
			(layer "B.SilkS")
		)
		(fp_line
			(start 1.1049 -0.724916)
			(end 1.1049 0.724916)
			(stroke
				(width 0.1)
				(type default)
			)
			(layer "B.Fab")
		)
		(fp_line
			(start -1.1049 -0.724916)
			(end 1.1049 -0.724916)
			(stroke
				(width 0.1)
				(type default)
			)
			(layer "B.Fab")
		)
		(fp_line
			(start 1.1049 0.724916)
			(end -1.1049 0.724916)
			(stroke
				(width 0.1)
				(type default)
			)
			(layer "B.Fab")
		)
		(fp_line
			(start -1.1049 0.724916)
			(end -1.1049 -0.724916)
			(stroke
				(width 0.1)
				(type default)
			)
			(layer "B.Fab")
		)
		(pad "1" smd rect
			(at 0.889 0 90)
			(size 1.016 1.27)
			(layers "B.Cu" "B.Mask" "B.Paste")
			(net "SW_P12V_AUX_PVDDIO_P0_FLT")
		)
		(pad "2" smd rect
			(at -0.889 0 90)
			(size 1.016 1.27)
			(layers "B.Cu" "B.Mask" "B.Paste")
			(net "GND")
		)
	)
	(footprint ""
		(layer "B.Cu")
		(at 148.252434 -203.704952 -90)
		(property "Reference" "C235"
			(at 0 0 90)
			(layer "B.SilkS")
			(hide yes)
			(effects
				(font
					(size 1.27 1.27)
				)
				(justify mirror)
			)
		)
		(property "Value" ""
			(at 0 0 90)
			(layer "B.Fab")
			(effects
				(font
					(size 1.27 1.27)
				)
				(justify mirror)
			)
		)
		(duplicate_pad_numbers_are_jumpers no)
		(fp_line
			(start -0.7874 0.4064)
			(end 0.7874 0.4064)
			(stroke
				(width 0.1524)
				(type default)
			)
			(layer "B.SilkS")
		)
		(fp_line
			(start 0.7874 0.4064)
			(end 0.7874 -0.4064)
			(stroke
				(width 0.1524)
				(type default)
			)
			(layer "B.SilkS")
		)
		(fp_line
			(start -0.7874 -0.4064)
			(end -0.7874 0.4064)
			(stroke
				(width 0.1524)
				(type default)
			)
			(layer "B.SilkS")
		)
		(fp_line
			(start 0.7874 -0.4064)
			(end -0.7874 -0.4064)
			(stroke
				(width 0.1524)
				(type default)
			)
			(layer "B.SilkS")
		)
		(fp_line
			(start -0.67945 0.3048)
			(end -0.120396 0.3048)
			(stroke
				(width 0.1)
				(type default)
			)
			(layer "B.Fab")
		)
		(fp_line
			(start -0.120396 0.3048)
			(end -0.120396 0.2794)
			(stroke
				(width 0.1)
				(type default)
			)
			(layer "B.Fab")
		)
		(fp_line
			(start 0.12065 0.3048)
			(end 0.67945 0.3048)
			(stroke
				(width 0.1)
				(type default)
			)
			(layer "B.Fab")
		)
		(fp_line
			(start 0.67945 0.3048)
			(end 0.67945 -0.305054)
			(stroke
				(width 0.1)
				(type default)
			)
			(layer "B.Fab")
		)
		(fp_line
			(start -0.120396 0.2794)
			(end 0.12065 0.2794)
			(stroke
				(width 0.1)
				(type default)
			)
			(layer "B.Fab")
		)
		(fp_line
			(start 0.12065 0.2794)
			(end 0.12065 0.3048)
			(stroke
				(width 0.1)
				(type default)
			)
			(layer "B.Fab")
		)
		(fp_line
			(start -0.12065 -0.2794)
			(end -0.12065 -0.3048)
			(stroke
				(width 0.1)
				(type default)
			)
			(layer "B.Fab")
		)
		(fp_line
			(start 0.12065 -0.2794)
			(end -0.12065 -0.2794)
			(stroke
				(width 0.1)
				(type default)
			)
			(layer "B.Fab")
		)
		(fp_line
			(start -0.67945 -0.3048)
			(end -0.67945 0.3048)
			(stroke
				(width 0.1)
				(type default)
			)
			(layer "B.Fab")
		)
		(fp_line
			(start -0.12065 -0.3048)
			(end -0.67945 -0.3048)
			(stroke
				(width 0.1)
				(type default)
			)
			(layer "B.Fab")
		)
		(fp_line
			(start 0.12065 -0.305054)
			(end 0.12065 -0.2794)
			(stroke
				(width 0.1)
				(type default)
			)
			(layer "B.Fab")
		)
		(fp_line
			(start 0.67945 -0.305054)
			(end 0.12065 -0.305054)
			(stroke
				(width 0.1)
				(type default)
			)
			(layer "B.Fab")
		)
		(pad "1" smd circle
			(at 0.40005 0 90)
			(size 0 0)
			(layers "B.Cu" "B.Mask" "B.Paste")
			(net "JTAG_CPU1_DBREQ_N")
		)
		(pad "2" smd circle
			(at -0.40005 0 90)
			(size 0 0)
			(layers "B.Cu" "B.Mask" "B.Paste")
			(net "GND")
		)
	)
	(footprint ""
		(layer "B.Cu")
		(at 327.216008 -203.529946)
		(property "Reference" "R157"
			(at 0 0 0)
			(layer "B.SilkS")
			(hide yes)
			(effects
				(font
					(size 1.27 1.27)
				)
				(justify mirror)
			)
		)
		(property "Value" ""
			(at 0 0 0)
			(layer "B.Fab")
			(effects
				(font
					(size 1.27 1.27)
				)
				(justify mirror)
			)
		)
		(duplicate_pad_numbers_are_jumpers no)
		(fp_line
			(start -0.7874 -0.4064)
			(end -0.7874 0.4064)
			(stroke
				(width 0.1524)
				(type default)
			)
			(layer "B.SilkS")
		)
		(fp_line
			(start -0.7874 0.4064)
			(end 0.7874 0.4064)
			(stroke
				(width 0.1524)
				(type default)
			)
			(layer "B.SilkS")
		)
		(fp_line
			(start 0.7874 -0.4064)
			(end -0.7874 -0.4064)
			(stroke
				(width 0.1524)
				(type default)
			)
			(layer "B.SilkS")
		)
		(fp_line
			(start 0.7874 0.4064)
			(end 0.7874 -0.4064)
			(stroke
				(width 0.1524)
				(type default)
			)
			(layer "B.SilkS")
		)
		(fp_line
			(start -0.67945 -0.3048)
			(end -0.67945 0.3048)
			(stroke
				(width 0.1)
				(type default)
			)
			(layer "B.Fab")
		)
		(fp_line
			(start -0.67945 0.3048)
			(end -0.120396 0.3048)
			(stroke
				(width 0.1)
				(type default)
			)
			(layer "B.Fab")
		)
		(fp_line
			(start -0.12065 -0.3048)
			(end -0.67945 -0.3048)
			(stroke
				(width 0.1)
				(type default)
			)
			(layer "B.Fab")
		)
		(fp_line
			(start -0.12065 -0.2794)
			(end -0.12065 -0.3048)
			(stroke
				(width 0.1)
				(type default)
			)
			(layer "B.Fab")
		)
		(fp_line
			(start -0.120396 0.2794)
			(end 0.12065 0.2794)
			(stroke
				(width 0.1)
				(type default)
			)
			(layer "B.Fab")
		)
		(fp_line
			(start -0.120396 0.3048)
			(end -0.120396 0.2794)
			(stroke
				(width 0.1)
				(type default)
			)
			(layer "B.Fab")
		)
		(fp_line
			(start 0.12065 -0.305054)
			(end 0.12065 -0.2794)
			(stroke
				(width 0.1)
				(type default)
			)
			(layer "B.Fab")
		)
		(fp_line
			(start 0.12065 -0.2794)
			(end -0.12065 -0.2794)
			(stroke
				(width 0.1)
				(type default)
			)
			(layer "B.Fab")
		)
		(fp_line
			(start 0.12065 0.2794)
			(end 0.12065 0.3048)
			(stroke
				(width 0.1)
				(type default)
			)
			(layer "B.Fab")
		)
		(fp_line
			(start 0.12065 0.3048)
			(end 0.67945 0.3048)
			(stroke
				(width 0.1)
				(type default)
			)
			(layer "B.Fab")
		)
		(fp_line
			(start 0.67945 -0.305054)
			(end 0.12065 -0.305054)
			(stroke
				(width 0.1)
				(type default)
			)
			(layer "B.Fab")
		)
		(fp_line
			(start 0.67945 0.3048)
			(end 0.67945 -0.305054)
			(stroke
				(width 0.1)
				(type default)
			)
			(layer "B.Fab")
		)
		(pad "1" smd circle
			(at 0.40005 0 180)
			(size 0 0)
			(layers "B.Cu" "B.Mask" "B.Paste")
			(net "CPU0_XTRIG_R2_L5")
		)
		(pad "2" smd circle
			(at -0.40005 0 180)
			(size 0 0)
			(layers "B.Cu" "B.Mask" "B.Paste")
			(net "CPU0_XTRIG_L5")
		)
	)
	(footprint ""
		(layer "B.Cu")
		(at 398.443958 -326.671432 180)
		(property "Reference" "R753"
			(at 0 0 0)
			(layer "B.SilkS")
			(hide yes)
			(effects
				(font
					(size 1.27 1.27)
				)
				(justify mirror)
			)
		)
		(property "Value" ""
			(at 0 0 0)
			(layer "B.Fab")
			(effects
				(font
					(size 1.27 1.27)
				)
				(justify mirror)
			)
		)
		(duplicate_pad_numbers_are_jumpers no)
		(fp_line
			(start 0.7874 0.4064)
			(end 0.7874 -0.4064)
			(stroke
				(width 0.1524)
				(type default)
			)
			(layer "B.SilkS")
		)
		(fp_line
			(start 0.7874 -0.4064)
			(end -0.7874 -0.4064)
			(stroke
				(width 0.1524)
				(type default)
			)
			(layer "B.SilkS")
		)
		(fp_line
			(start -0.7874 0.4064)
			(end 0.7874 0.4064)
			(stroke
				(width 0.1524)
				(type default)
			)
			(layer "B.SilkS")
		)
		(fp_line
			(start -0.7874 -0.4064)
			(end -0.7874 0.4064)
			(stroke
				(width 0.1524)
				(type default)
			)
			(layer "B.SilkS")
		)
		(fp_line
			(start 0.67945 0.3048)
			(end 0.67945 -0.305054)
			(stroke
				(width 0.1)
				(type default)
			)
			(layer "B.Fab")
		)
		(fp_line
			(start 0.67945 -0.305054)
			(end 0.12065 -0.305054)
			(stroke
				(width 0.1)
				(type default)
			)
			(layer "B.Fab")
		)
		(fp_line
			(start 0.12065 0.3048)
			(end 0.67945 0.3048)
			(stroke
				(width 0.1)
				(type default)
			)
			(layer "B.Fab")
		)
		(fp_line
			(start 0.12065 0.2794)
			(end 0.12065 0.3048)
			(stroke
				(width 0.1)
				(type default)
			)
			(layer "B.Fab")
		)
		(fp_line
			(start 0.12065 -0.2794)
			(end -0.12065 -0.2794)
			(stroke
				(width 0.1)
				(type default)
			)
			(layer "B.Fab")
		)
		(fp_line
			(start 0.12065 -0.305054)
			(end 0.12065 -0.2794)
			(stroke
				(width 0.1)
				(type default)
			)
			(layer "B.Fab")
		)
		(fp_line
			(start -0.120396 0.3048)
			(end -0.120396 0.2794)
			(stroke
				(width 0.1)
				(type default)
			)
			(layer "B.Fab")
		)
		(fp_line
			(start -0.120396 0.2794)
			(end 0.12065 0.2794)
			(stroke
				(width 0.1)
				(type default)
			)
			(layer "B.Fab")
		)
		(fp_line
			(start -0.12065 -0.2794)
			(end -0.12065 -0.3048)
			(stroke
				(width 0.1)
				(type default)
			)
			(layer "B.Fab")
		)
		(fp_line
			(start -0.12065 -0.3048)
			(end -0.67945 -0.3048)
			(stroke
				(width 0.1)
				(type default)
			)
			(layer "B.Fab")
		)
		(fp_line
			(start -0.67945 0.3048)
			(end -0.120396 0.3048)
			(stroke
				(width 0.1)
				(type default)
			)
			(layer "B.Fab")
		)
		(fp_line
			(start -0.67945 -0.3048)
			(end -0.67945 0.3048)
			(stroke
				(width 0.1)
				(type default)
			)
			(layer "B.Fab")
		)
		(pad "1" smd circle
			(at 0.40005 0)
			(size 0 0)
			(layers "B.Cu" "B.Mask" "B.Paste")
			(net "GND")
		)
		(pad "2" smd circle
			(at -0.40005 0)
			(size 0 0)
			(layers "B.Cu" "B.Mask" "B.Paste")
			(net "PD_ESPI_CPU0_CLK2")
		)
	)
	(footprint ""
		(layer "B.Cu")
		(at 85.852 -147.955)
		(property "Reference" "C297"
			(at 0 0 0)
			(layer "B.SilkS")
			(hide yes)
			(effects
				(font
					(size 1.27 1.27)
				)
				(justify mirror)
			)
		)
		(property "Value" ""
			(at 0 0 0)
			(layer "B.Fab")
			(effects
				(font
					(size 1.27 1.27)
				)
				(justify mirror)
			)
		)
		(duplicate_pad_numbers_are_jumpers no)
		(fp_line
			(start -0.7874 -0.4064)
			(end -0.7874 0.4064)
			(stroke
				(width 0.1524)
				(type default)
			)
			(layer "B.SilkS")
		)
		(fp_line
			(start -0.7874 0.4064)
			(end 0.7874 0.4064)
			(stroke
				(width 0.1524)
				(type default)
			)
			(layer "B.SilkS")
		)
		(fp_line
			(start 0.7874 -0.4064)
			(end -0.7874 -0.4064)
			(stroke
				(width 0.1524)
				(type default)
			)
			(layer "B.SilkS")
		)
		(fp_line
			(start 0.7874 0.4064)
			(end 0.7874 -0.4064)
			(stroke
				(width 0.1524)
				(type default)
			)
			(layer "B.SilkS")
		)
		(fp_line
			(start -0.67945 -0.3048)
			(end -0.67945 0.3048)
			(stroke
				(width 0.1)
				(type default)
			)
			(layer "B.Fab")
		)
		(fp_line
			(start -0.67945 0.3048)
			(end -0.120396 0.3048)
			(stroke
				(width 0.1)
				(type default)
			)
			(layer "B.Fab")
		)
		(fp_line
			(start -0.12065 -0.3048)
			(end -0.67945 -0.3048)
			(stroke
				(width 0.1)
				(type default)
			)
			(layer "B.Fab")
		)
		(fp_line
			(start -0.12065 -0.2794)
			(end -0.12065 -0.3048)
			(stroke
				(width 0.1)
				(type default)
			)
			(layer "B.Fab")
		)
		(fp_line
			(start -0.120396 0.2794)
			(end 0.12065 0.2794)
			(stroke
				(width 0.1)
				(type default)
			)
			(layer "B.Fab")
		)
		(fp_line
			(start -0.120396 0.3048)
			(end -0.120396 0.2794)
			(stroke
				(width 0.1)
				(type default)
			)
			(layer "B.Fab")
		)
		(fp_line
			(start 0.12065 -0.305054)
			(end 0.12065 -0.2794)
			(stroke
				(width 0.1)
				(type default)
			)
			(layer "B.Fab")
		)
		(fp_line
			(start 0.12065 -0.2794)
			(end -0.12065 -0.2794)
			(stroke
				(width 0.1)
				(type default)
			)
			(layer "B.Fab")
		)
		(fp_line
			(start 0.12065 0.2794)
			(end 0.12065 0.3048)
			(stroke
				(width 0.1)
				(type default)
			)
			(layer "B.Fab")
		)
		(fp_line
			(start 0.12065 0.3048)
			(end 0.67945 0.3048)
			(stroke
				(width 0.1)
				(type default)
			)
			(layer "B.Fab")
		)
		(fp_line
			(start 0.67945 -0.305054)
			(end 0.12065 -0.305054)
			(stroke
				(width 0.1)
				(type default)
			)
			(layer "B.Fab")
		)
		(fp_line
			(start 0.67945 0.3048)
			(end 0.67945 -0.305054)
			(stroke
				(width 0.1)
				(type default)
			)
			(layer "B.Fab")
		)
		(pad "1" smd circle
			(at 0.40005 0 180)
			(size 0 0)
			(layers "B.Cu" "B.Mask" "B.Paste")
			(net "SVID_PVDDCR_CPU0_P1_SVC_R")
		)
		(pad "2" smd circle
			(at -0.40005 0 180)
			(size 0 0)
			(layers "B.Cu" "B.Mask" "B.Paste")
			(net "GND")
		)
	)
	(footprint ""
		(layer "B.Cu")
		(at 164.403532 -434.15458 90)
		(property "Reference" "R4122"
			(at 0 0 90)
			(layer "B.SilkS")
			(hide yes)
			(effects
				(font
					(size 1.27 1.27)
				)
				(justify mirror)
			)
		)
		(property "Value" ""
			(at 0 0 90)
			(layer "B.Fab")
			(effects
				(font
					(size 1.27 1.27)
				)
				(justify mirror)
			)
		)
		(duplicate_pad_numbers_are_jumpers no)
		(fp_line
			(start 0.7874 -0.4064)
			(end -0.7874 -0.4064)
			(stroke
				(width 0.1524)
				(type default)
			)
			(layer "B.SilkS")
		)
		(fp_line
			(start -0.7874 -0.4064)
			(end -0.7874 0.4064)
			(stroke
				(width 0.1524)
				(type default)
			)
			(layer "B.SilkS")
		)
		(fp_line
			(start 0.7874 0.4064)
			(end 0.7874 -0.4064)
			(stroke
				(width 0.1524)
				(type default)
			)
			(layer "B.SilkS")
		)
		(fp_line
			(start -0.7874 0.4064)
			(end 0.7874 0.4064)
			(stroke
				(width 0.1524)
				(type default)
			)
			(layer "B.SilkS")
		)
		(fp_line
			(start 0.67945 -0.305054)
			(end 0.12065 -0.305054)
			(stroke
				(width 0.1)
				(type default)
			)
			(layer "B.Fab")
		)
		(fp_line
			(start 0.12065 -0.305054)
			(end 0.12065 -0.2794)
			(stroke
				(width 0.1)
				(type default)
			)
			(layer "B.Fab")
		)
		(fp_line
			(start -0.12065 -0.3048)
			(end -0.67945 -0.3048)
			(stroke
				(width 0.1)
				(type default)
			)
			(layer "B.Fab")
		)
		(fp_line
			(start -0.67945 -0.3048)
			(end -0.67945 0.3048)
			(stroke
				(width 0.1)
				(type default)
			)
			(layer "B.Fab")
		)
		(fp_line
			(start 0.12065 -0.2794)
			(end -0.12065 -0.2794)
			(stroke
				(width 0.1)
				(type default)
			)
			(layer "B.Fab")
		)
		(fp_line
			(start -0.12065 -0.2794)
			(end -0.12065 -0.3048)
			(stroke
				(width 0.1)
				(type default)
			)
			(layer "B.Fab")
		)
		(fp_line
			(start 0.12065 0.2794)
			(end 0.12065 0.3048)
			(stroke
				(width 0.1)
				(type default)
			)
			(layer "B.Fab")
		)
		(fp_line
			(start -0.120396 0.2794)
			(end 0.12065 0.2794)
			(stroke
				(width 0.1)
				(type default)
			)
			(layer "B.Fab")
		)
		(fp_line
			(start 0.67945 0.3048)
			(end 0.67945 -0.305054)
			(stroke
				(width 0.1)
				(type default)
			)
			(layer "B.Fab")
		)
		(fp_line
			(start 0.12065 0.3048)
			(end 0.67945 0.3048)
			(stroke
				(width 0.1)
				(type default)
			)
			(layer "B.Fab")
		)
		(fp_line
			(start -0.120396 0.3048)
			(end -0.120396 0.2794)
			(stroke
				(width 0.1)
				(type default)
			)
			(layer "B.Fab")
		)
		(fp_line
			(start -0.67945 0.3048)
			(end -0.120396 0.3048)
			(stroke
				(width 0.1)
				(type default)
			)
			(layer "B.Fab")
		)
		(pad "1" smd circle
			(at 0.40005 0 270)
			(size 0 0)
			(layers "B.Cu" "B.Mask" "B.Paste")
			(net "PRSNT_CABLE_GPU_B3_N")
		)
		(pad "2" smd circle
			(at -0.40005 0 270)
			(size 0 0)
			(layers "B.Cu" "B.Mask" "B.Paste")
			(net "GND")
		)
	)
	(footprint ""
		(layer "B.Cu")
		(at 421.146224 -396.393162 -90)
		(property "Reference" "C790"
			(at 0 0 90)
			(layer "B.SilkS")
			(hide yes)
			(effects
				(font
					(size 1.27 1.27)
				)
				(justify mirror)
			)
		)
		(property "Value" ""
			(at 0 0 90)
			(layer "B.Fab")
			(effects
				(font
					(size 1.27 1.27)
				)
				(justify mirror)
			)
		)
		(duplicate_pad_numbers_are_jumpers no)
		(fp_line
			(start -0.299974 0.150114)
			(end 0.299974 0.150114)
			(stroke
				(width 0.1)
				(type default)
			)
			(layer "B.Fab")
		)
		(fp_line
			(start 0.299974 0.150114)
			(end 0.299974 -0.150114)
			(stroke
				(width 0.1)
				(type default)
			)
			(layer "B.Fab")
		)
		(fp_line
			(start -0.299974 -0.150114)
			(end -0.299974 0.150114)
			(stroke
				(width 0.1)
				(type default)
			)
			(layer "B.Fab")
		)
		(fp_line
			(start 0.299974 -0.150114)
			(end -0.299974 -0.150114)
			(stroke
				(width 0.1)
				(type default)
			)
			(layer "B.Fab")
		)
		(pad "1" smd rect
			(at 0.2667 0 90)
			(size 0.3048 0.381)
			(layers "B.Cu" "B.Mask" "B.Paste")
			(net "P0V9_CPU0_RT2_2A")
		)
		(pad "2" smd rect
			(at -0.2667 0 90)
			(size 0.3048 0.381)
			(layers "B.Cu" "B.Mask" "B.Paste")
			(net "GND")
		)
	)
	(footprint ""
		(layer "B.Cu")
		(at 104.648 -415.925 90)
		(property "Reference" "R4543"
			(at 0 0 90)
			(layer "B.SilkS")
			(hide yes)
			(effects
				(font
					(size 1.27 1.27)
				)
				(justify mirror)
			)
		)
		(property "Value" ""
			(at 0 0 90)
			(layer "B.Fab")
			(effects
				(font
					(size 1.27 1.27)
				)
				(justify mirror)
			)
		)
		(duplicate_pad_numbers_are_jumpers no)
		(fp_line
			(start 0.7874 -0.4064)
			(end -0.7874 -0.4064)
			(stroke
				(width 0.1524)
				(type default)
			)
			(layer "B.SilkS")
		)
		(fp_line
			(start -0.7874 -0.4064)
			(end -0.7874 0.4064)
			(stroke
				(width 0.1524)
				(type default)
			)
			(layer "B.SilkS")
		)
		(fp_line
			(start 0.7874 0.4064)
			(end 0.7874 -0.4064)
			(stroke
				(width 0.1524)
				(type default)
			)
			(layer "B.SilkS")
		)
		(fp_line
			(start -0.7874 0.4064)
			(end 0.7874 0.4064)
			(stroke
				(width 0.1524)
				(type default)
			)
			(layer "B.SilkS")
		)
		(fp_line
			(start 0.67945 -0.305054)
			(end 0.12065 -0.305054)
			(stroke
				(width 0.1)
				(type default)
			)
			(layer "B.Fab")
		)
		(fp_line
			(start 0.12065 -0.305054)
			(end 0.12065 -0.2794)
			(stroke
				(width 0.1)
				(type default)
			)
			(layer "B.Fab")
		)
		(fp_line
			(start -0.12065 -0.3048)
			(end -0.67945 -0.3048)
			(stroke
				(width 0.1)
				(type default)
			)
			(layer "B.Fab")
		)
		(fp_line
			(start -0.67945 -0.3048)
			(end -0.67945 0.3048)
			(stroke
				(width 0.1)
				(type default)
			)
			(layer "B.Fab")
		)
		(fp_line
			(start 0.12065 -0.2794)
			(end -0.12065 -0.2794)
			(stroke
				(width 0.1)
				(type default)
			)
			(layer "B.Fab")
		)
		(fp_line
			(start -0.12065 -0.2794)
			(end -0.12065 -0.3048)
			(stroke
				(width 0.1)
				(type default)
			)
			(layer "B.Fab")
		)
		(fp_line
			(start 0.12065 0.2794)
			(end 0.12065 0.3048)
			(stroke
				(width 0.1)
				(type default)
			)
			(layer "B.Fab")
		)
		(fp_line
			(start -0.120396 0.2794)
			(end 0.12065 0.2794)
			(stroke
				(width 0.1)
				(type default)
			)
			(layer "B.Fab")
		)
		(fp_line
			(start 0.67945 0.3048)
			(end 0.67945 -0.305054)
			(stroke
				(width 0.1)
				(type default)
			)
			(layer "B.Fab")
		)
		(fp_line
			(start 0.12065 0.3048)
			(end 0.67945 0.3048)
			(stroke
				(width 0.1)
				(type default)
			)
			(layer "B.Fab")
		)
		(fp_line
			(start -0.120396 0.3048)
			(end -0.120396 0.2794)
			(stroke
				(width 0.1)
				(type default)
			)
			(layer "B.Fab")
		)
		(fp_line
			(start -0.67945 0.3048)
			(end -0.120396 0.3048)
			(stroke
				(width 0.1)
				(type default)
			)
			(layer "B.Fab")
		)
		(pad "1" smd circle
			(at 0.40005 0 270)
			(size 0 0)
			(layers "B.Cu" "B.Mask" "B.Paste")
			(net "P3V3_AUX")
		)
		(pad "2" smd circle
			(at -0.40005 0 270)
			(size 0 0)
			(layers "B.Cu" "B.Mask" "B.Paste")
			(net "HGX_DETECT_N")
		)
	)
	(footprint ""
		(layer "B.Cu")
		(at 353.900232 -255.554988 180)
		(property "Reference" "C2526"
			(at 0 0 0)
			(layer "B.SilkS")
			(hide yes)
			(effects
				(font
					(size 1.27 1.27)
				)
				(justify mirror)
			)
		)
		(property "Value" ""
			(at 0 0 0)
			(layer "B.Fab")
			(effects
				(font
					(size 1.27 1.27)
				)
				(justify mirror)
			)
		)
		(duplicate_pad_numbers_are_jumpers no)
		(fp_line
			(start 0.7874 0.4064)
			(end 0.7874 -0.4064)
			(stroke
				(width 0.1524)
				(type default)
			)
			(layer "B.SilkS")
		)
		(fp_line
			(start 0.7874 -0.4064)
			(end -0.7874 -0.4064)
			(stroke
				(width 0.1524)
				(type default)
			)
			(layer "B.SilkS")
		)
		(fp_line
			(start -0.7874 0.4064)
			(end 0.7874 0.4064)
			(stroke
				(width 0.1524)
				(type default)
			)
			(layer "B.SilkS")
		)
		(fp_line
			(start -0.7874 -0.4064)
			(end -0.7874 0.4064)
			(stroke
				(width 0.1524)
				(type default)
			)
			(layer "B.SilkS")
		)
		(fp_line
			(start 0.67945 0.3048)
			(end 0.67945 -0.305054)
			(stroke
				(width 0.1)
				(type default)
			)
			(layer "B.Fab")
		)
		(fp_line
			(start 0.67945 -0.305054)
			(end 0.12065 -0.305054)
			(stroke
				(width 0.1)
				(type default)
			)
			(layer "B.Fab")
		)
		(fp_line
			(start 0.12065 0.3048)
			(end 0.67945 0.3048)
			(stroke
				(width 0.1)
				(type default)
			)
			(layer "B.Fab")
		)
		(fp_line
			(start 0.12065 0.2794)
			(end 0.12065 0.3048)
			(stroke
				(width 0.1)
				(type default)
			)
			(layer "B.Fab")
		)
		(fp_line
			(start 0.12065 -0.2794)
			(end -0.12065 -0.2794)
			(stroke
				(width 0.1)
				(type default)
			)
			(layer "B.Fab")
		)
		(fp_line
			(start 0.12065 -0.305054)
			(end 0.12065 -0.2794)
			(stroke
				(width 0.1)
				(type default)
			)
			(layer "B.Fab")
		)
		(fp_line
			(start -0.120396 0.3048)
			(end -0.120396 0.2794)
			(stroke
				(width 0.1)
				(type default)
			)
			(layer "B.Fab")
		)
		(fp_line
			(start -0.120396 0.2794)
			(end 0.12065 0.2794)
			(stroke
				(width 0.1)
				(type default)
			)
			(layer "B.Fab")
		)
		(fp_line
			(start -0.12065 -0.2794)
			(end -0.12065 -0.3048)
			(stroke
				(width 0.1)
				(type default)
			)
			(layer "B.Fab")
		)
		(fp_line
			(start -0.12065 -0.3048)
			(end -0.67945 -0.3048)
			(stroke
				(width 0.1)
				(type default)
			)
			(layer "B.Fab")
		)
		(fp_line
			(start -0.67945 0.3048)
			(end -0.120396 0.3048)
			(stroke
				(width 0.1)
				(type default)
			)
			(layer "B.Fab")
		)
		(fp_line
			(start -0.67945 -0.3048)
			(end -0.67945 0.3048)
			(stroke
				(width 0.1)
				(type default)
			)
			(layer "B.Fab")
		)
		(pad "1" smd circle
			(at 0.40005 0)
			(size 0 0)
			(layers "B.Cu" "B.Mask" "B.Paste")
			(net "PVDD18_S5_P0")
		)
		(pad "2" smd circle
			(at -0.40005 0)
			(size 0 0)
			(layers "B.Cu" "B.Mask" "B.Paste")
			(net "GND")
		)
	)
	(footprint ""
		(layer "B.Cu")
		(at 443.29985 -194.88531 180)
		(property "Reference" "R768"
			(at 0 0 0)
			(layer "B.SilkS")
			(hide yes)
			(effects
				(font
					(size 1.27 1.27)
				)
				(justify mirror)
			)
		)
		(property "Value" ""
			(at 0 0 0)
			(layer "B.Fab")
			(effects
				(font
					(size 1.27 1.27)
				)
				(justify mirror)
			)
		)
		(duplicate_pad_numbers_are_jumpers no)
		(fp_line
			(start 0.7874 0.4064)
			(end 0.7874 -0.4064)
			(stroke
				(width 0.1524)
				(type default)
			)
			(layer "B.SilkS")
		)
		(fp_line
			(start 0.7874 -0.4064)
			(end -0.7874 -0.4064)
			(stroke
				(width 0.1524)
				(type default)
			)
			(layer "B.SilkS")
		)
		(fp_line
			(start -0.7874 0.4064)
			(end 0.7874 0.4064)
			(stroke
				(width 0.1524)
				(type default)
			)
			(layer "B.SilkS")
		)
		(fp_line
			(start -0.7874 -0.4064)
			(end -0.7874 0.4064)
			(stroke
				(width 0.1524)
				(type default)
			)
			(layer "B.SilkS")
		)
		(fp_line
			(start 0.67945 0.3048)
			(end 0.67945 -0.305054)
			(stroke
				(width 0.1)
				(type default)
			)
			(layer "B.Fab")
		)
		(fp_line
			(start 0.67945 -0.305054)
			(end 0.12065 -0.305054)
			(stroke
				(width 0.1)
				(type default)
			)
			(layer "B.Fab")
		)
		(fp_line
			(start 0.12065 0.3048)
			(end 0.67945 0.3048)
			(stroke
				(width 0.1)
				(type default)
			)
			(layer "B.Fab")
		)
		(fp_line
			(start 0.12065 0.2794)
			(end 0.12065 0.3048)
			(stroke
				(width 0.1)
				(type default)
			)
			(layer "B.Fab")
		)
		(fp_line
			(start 0.12065 -0.2794)
			(end -0.12065 -0.2794)
			(stroke
				(width 0.1)
				(type default)
			)
			(layer "B.Fab")
		)
		(fp_line
			(start 0.12065 -0.305054)
			(end 0.12065 -0.2794)
			(stroke
				(width 0.1)
				(type default)
			)
			(layer "B.Fab")
		)
		(fp_line
			(start -0.120396 0.3048)
			(end -0.120396 0.2794)
			(stroke
				(width 0.1)
				(type default)
			)
			(layer "B.Fab")
		)
		(fp_line
			(start -0.120396 0.2794)
			(end 0.12065 0.2794)
			(stroke
				(width 0.1)
				(type default)
			)
			(layer "B.Fab")
		)
		(fp_line
			(start -0.12065 -0.2794)
			(end -0.12065 -0.3048)
			(stroke
				(width 0.1)
				(type default)
			)
			(layer "B.Fab")
		)
		(fp_line
			(start -0.12065 -0.3048)
			(end -0.67945 -0.3048)
			(stroke
				(width 0.1)
				(type default)
			)
			(layer "B.Fab")
		)
		(fp_line
			(start -0.67945 0.3048)
			(end -0.120396 0.3048)
			(stroke
				(width 0.1)
				(type default)
			)
			(layer "B.Fab")
		)
		(fp_line
			(start -0.67945 -0.3048)
			(end -0.67945 0.3048)
			(stroke
				(width 0.1)
				(type default)
			)
			(layer "B.Fab")
		)
		(pad "1" smd circle
			(at 0.40005 0)
			(size 0 0)
			(layers "B.Cu" "B.Mask" "B.Paste")
			(net "PD_CHK_CPU0_DIMM_SAA")
		)
		(pad "2" smd circle
			(at -0.40005 0)
			(size 0 0)
			(layers "B.Cu" "B.Mask" "B.Paste")
			(net "GND")
		)
	)
	(footprint ""
		(layer "B.Cu")
		(at 315.404246 -416.899344 90)
		(property "Reference" "C6539"
			(at 0 0 90)
			(layer "B.SilkS")
			(hide yes)
			(effects
				(font
					(size 1.27 1.27)
				)
				(justify mirror)
			)
		)
		(property "Value" ""
			(at 0 0 90)
			(layer "B.Fab")
			(effects
				(font
					(size 1.27 1.27)
				)
				(justify mirror)
			)
		)
		(duplicate_pad_numbers_are_jumpers no)
		(fp_line
			(start 0.299974 -0.150114)
			(end -0.299974 -0.150114)
			(stroke
				(width 0.1)
				(type default)
			)
			(layer "B.Fab")
		)
		(fp_line
			(start -0.299974 -0.150114)
			(end -0.299974 0.150114)
			(stroke
				(width 0.1)
				(type default)
			)
			(layer "B.Fab")
		)
		(fp_line
			(start 0.299974 0.150114)
			(end 0.299974 -0.150114)
			(stroke
				(width 0.1)
				(type default)
			)
			(layer "B.Fab")
		)
		(fp_line
			(start -0.299974 0.150114)
			(end 0.299974 0.150114)
			(stroke
				(width 0.1)
				(type default)
			)
			(layer "B.Fab")
		)
		(pad "1" smd rect
			(at 0.2667 0 270)
			(size 0.3048 0.381)
			(layers "B.Cu" "B.Mask" "B.Paste")
			(net "P5E_CPU0_P1_TX_BUF_C_DP<3>")
		)
		(pad "2" smd rect
			(at -0.2667 0 270)
			(size 0.3048 0.381)
			(layers "B.Cu" "B.Mask" "B.Paste")
			(net "P5E_CPU0_P1_TX_BUF_DP<3>")
		)
	)
	(footprint ""
		(layer "B.Cu")
		(at 190.404496 -193.996564)
		(property "Reference" "C172"
			(at 0 0 0)
			(layer "B.SilkS")
			(hide yes)
			(effects
				(font
					(size 1.27 1.27)
				)
				(justify mirror)
			)
		)
		(property "Value" ""
			(at 0 0 0)
			(layer "B.Fab")
			(effects
				(font
					(size 1.27 1.27)
				)
				(justify mirror)
			)
		)
		(duplicate_pad_numbers_are_jumpers no)
		(fp_line
			(start -0.7874 -0.4064)
			(end -0.7874 0.4064)
			(stroke
				(width 0.1524)
				(type default)
			)
			(layer "B.SilkS")
		)
		(fp_line
			(start -0.7874 0.4064)
			(end 0.7874 0.4064)
			(stroke
				(width 0.1524)
				(type default)
			)
			(layer "B.SilkS")
		)
		(fp_line
			(start 0.7874 -0.4064)
			(end -0.7874 -0.4064)
			(stroke
				(width 0.1524)
				(type default)
			)
			(layer "B.SilkS")
		)
		(fp_line
			(start 0.7874 0.4064)
			(end 0.7874 -0.4064)
			(stroke
				(width 0.1524)
				(type default)
			)
			(layer "B.SilkS")
		)
		(fp_line
			(start -0.67945 -0.3048)
			(end -0.67945 0.3048)
			(stroke
				(width 0.1)
				(type default)
			)
			(layer "B.Fab")
		)
		(fp_line
			(start -0.67945 0.3048)
			(end -0.120396 0.3048)
			(stroke
				(width 0.1)
				(type default)
			)
			(layer "B.Fab")
		)
		(fp_line
			(start -0.12065 -0.3048)
			(end -0.67945 -0.3048)
			(stroke
				(width 0.1)
				(type default)
			)
			(layer "B.Fab")
		)
		(fp_line
			(start -0.12065 -0.2794)
			(end -0.12065 -0.3048)
			(stroke
				(width 0.1)
				(type default)
			)
			(layer "B.Fab")
		)
		(fp_line
			(start -0.120396 0.2794)
			(end 0.12065 0.2794)
			(stroke
				(width 0.1)
				(type default)
			)
			(layer "B.Fab")
		)
		(fp_line
			(start -0.120396 0.3048)
			(end -0.120396 0.2794)
			(stroke
				(width 0.1)
				(type default)
			)
			(layer "B.Fab")
		)
		(fp_line
			(start 0.12065 -0.305054)
			(end 0.12065 -0.2794)
			(stroke
				(width 0.1)
				(type default)
			)
			(layer "B.Fab")
		)
		(fp_line
			(start 0.12065 -0.2794)
			(end -0.12065 -0.2794)
			(stroke
				(width 0.1)
				(type default)
			)
			(layer "B.Fab")
		)
		(fp_line
			(start 0.12065 0.2794)
			(end 0.12065 0.3048)
			(stroke
				(width 0.1)
				(type default)
			)
			(layer "B.Fab")
		)
		(fp_line
			(start 0.12065 0.3048)
			(end 0.67945 0.3048)
			(stroke
				(width 0.1)
				(type default)
			)
			(layer "B.Fab")
		)
		(fp_line
			(start 0.67945 -0.305054)
			(end 0.12065 -0.305054)
			(stroke
				(width 0.1)
				(type default)
			)
			(layer "B.Fab")
		)
		(fp_line
			(start 0.67945 0.3048)
			(end 0.67945 -0.305054)
			(stroke
				(width 0.1)
				(type default)
			)
			(layer "B.Fab")
		)
		(pad "1" smd circle
			(at 0.40005 0 180)
			(size 0 0)
			(layers "B.Cu" "B.Mask" "B.Paste")
			(net "P3V3_AUX")
		)
		(pad "2" smd circle
			(at -0.40005 0 180)
			(size 0 0)
			(layers "B.Cu" "B.Mask" "B.Paste")
			(net "GND")
		)
	)
	(footprint ""
		(layer "B.Cu")
		(at 185.166 -363.2581)
		(property "Reference" "PC7003"
			(at 0 0 0)
			(layer "B.SilkS")
			(hide yes)
			(effects
				(font
					(size 1.27 1.27)
				)
				(justify mirror)
			)
		)
		(property "Value" ""
			(at 0 0 0)
			(layer "B.Fab")
			(effects
				(font
					(size 1.27 1.27)
				)
				(justify mirror)
			)
		)
		(duplicate_pad_numbers_are_jumpers no)
		(fp_line
			(start -1.524 -0.762)
			(end -1.524 0.762)
			(stroke
				(width 0.1524)
				(type default)
			)
			(layer "B.SilkS")
		)
		(fp_line
			(start -1.524 0.762)
			(end 1.524 0.762)
			(stroke
				(width 0.1524)
				(type default)
			)
			(layer "B.SilkS")
		)
		(fp_line
			(start 1.524 -0.762)
			(end -1.524 -0.762)
			(stroke
				(width 0.1524)
				(type default)
			)
			(layer "B.SilkS")
		)
		(fp_line
			(start 1.524 0.762)
			(end 1.524 -0.762)
			(stroke
				(width 0.1524)
				(type default)
			)
			(layer "B.SilkS")
		)
		(fp_line
			(start -1.1049 -0.724916)
			(end 1.1049 -0.724916)
			(stroke
				(width 0.1)
				(type default)
			)
			(layer "B.Fab")
		)
		(fp_line
			(start -1.1049 0.724916)
			(end -1.1049 -0.724916)
			(stroke
				(width 0.1)
				(type default)
			)
			(layer "B.Fab")
		)
		(fp_line
			(start 1.1049 -0.724916)
			(end 1.1049 0.724916)
			(stroke
				(width 0.1)
				(type default)
			)
			(layer "B.Fab")
		)
		(fp_line
			(start 1.1049 0.724916)
			(end -1.1049 0.724916)
			(stroke
				(width 0.1)
				(type default)
			)
			(layer "B.Fab")
		)
		(pad "1" smd rect
			(at 0.889 0)
			(size 1.016 1.27)
			(layers "B.Cu" "B.Mask" "B.Paste")
			(net "SW_P12V_AUX_PVDD11_S3_P1_FLT")
		)
		(pad "2" smd rect
			(at -0.889 0)
			(size 1.016 1.27)
			(layers "B.Cu" "B.Mask" "B.Paste")
			(net "GND")
		)
	)
	(footprint ""
		(layer "B.Cu")
		(at 289.042856 -427.359572)
		(property "Reference" "C1708"
			(at 0 0 0)
			(layer "B.SilkS")
			(hide yes)
			(effects
				(font
					(size 1.27 1.27)
				)
				(justify mirror)
			)
		)
		(property "Value" ""
			(at 0 0 0)
			(layer "B.Fab")
			(effects
				(font
					(size 1.27 1.27)
				)
				(justify mirror)
			)
		)
		(duplicate_pad_numbers_are_jumpers no)
		(fp_line
			(start -0.7874 -0.4064)
			(end -0.7874 0.4064)
			(stroke
				(width 0.1524)
				(type default)
			)
			(layer "B.SilkS")
		)
		(fp_line
			(start -0.7874 0.4064)
			(end 0.7874 0.4064)
			(stroke
				(width 0.1524)
				(type default)
			)
			(layer "B.SilkS")
		)
		(fp_line
			(start 0.7874 -0.4064)
			(end -0.7874 -0.4064)
			(stroke
				(width 0.1524)
				(type default)
			)
			(layer "B.SilkS")
		)
		(fp_line
			(start 0.7874 0.4064)
			(end 0.7874 -0.4064)
			(stroke
				(width 0.1524)
				(type default)
			)
			(layer "B.SilkS")
		)
		(fp_line
			(start -0.67945 -0.3048)
			(end -0.67945 0.3048)
			(stroke
				(width 0.1)
				(type default)
			)
			(layer "B.Fab")
		)
		(fp_line
			(start -0.67945 0.3048)
			(end -0.120396 0.3048)
			(stroke
				(width 0.1)
				(type default)
			)
			(layer "B.Fab")
		)
		(fp_line
			(start -0.12065 -0.3048)
			(end -0.67945 -0.3048)
			(stroke
				(width 0.1)
				(type default)
			)
			(layer "B.Fab")
		)
		(fp_line
			(start -0.12065 -0.2794)
			(end -0.12065 -0.3048)
			(stroke
				(width 0.1)
				(type default)
			)
			(layer "B.Fab")
		)
		(fp_line
			(start -0.120396 0.2794)
			(end 0.12065 0.2794)
			(stroke
				(width 0.1)
				(type default)
			)
			(layer "B.Fab")
		)
		(fp_line
			(start -0.120396 0.3048)
			(end -0.120396 0.2794)
			(stroke
				(width 0.1)
				(type default)
			)
			(layer "B.Fab")
		)
		(fp_line
			(start 0.12065 -0.305054)
			(end 0.12065 -0.2794)
			(stroke
				(width 0.1)
				(type default)
			)
			(layer "B.Fab")
		)
		(fp_line
			(start 0.12065 -0.2794)
			(end -0.12065 -0.2794)
			(stroke
				(width 0.1)
				(type default)
			)
			(layer "B.Fab")
		)
		(fp_line
			(start 0.12065 0.2794)
			(end 0.12065 0.3048)
			(stroke
				(width 0.1)
				(type default)
			)
			(layer "B.Fab")
		)
		(fp_line
			(start 0.12065 0.3048)
			(end 0.67945 0.3048)
			(stroke
				(width 0.1)
				(type default)
			)
			(layer "B.Fab")
		)
		(fp_line
			(start 0.67945 -0.305054)
			(end 0.12065 -0.305054)
			(stroke
				(width 0.1)
				(type default)
			)
			(layer "B.Fab")
		)
		(fp_line
			(start 0.67945 0.3048)
			(end 0.67945 -0.305054)
			(stroke
				(width 0.1)
				(type default)
			)
			(layer "B.Fab")
		)
		(pad "1" smd circle
			(at 0.40005 0 180)
			(size 0 0)
			(layers "B.Cu" "B.Mask" "B.Paste")
			(net "P3V3_AUX")
		)
		(pad "2" smd circle
			(at -0.40005 0 180)
			(size 0 0)
			(layers "B.Cu" "B.Mask" "B.Paste")
			(net "GND")
		)
	)
	(footprint ""
		(layer "B.Cu")
		(at 98.51009 -248.479564 180)
		(property "Reference" "C2310"
			(at 0 0 0)
			(layer "B.SilkS")
			(hide yes)
			(effects
				(font
					(size 1.27 1.27)
				)
				(justify mirror)
			)
		)
		(property "Value" ""
			(at 0 0 0)
			(layer "B.Fab")
			(effects
				(font
					(size 1.27 1.27)
				)
				(justify mirror)
			)
		)
		(duplicate_pad_numbers_are_jumpers no)
		(fp_line
			(start 0.7874 0.4064)
			(end 0.7874 -0.4064)
			(stroke
				(width 0.1524)
				(type default)
			)
			(layer "B.SilkS")
		)
		(fp_line
			(start 0.7874 -0.4064)
			(end -0.7874 -0.4064)
			(stroke
				(width 0.1524)
				(type default)
			)
			(layer "B.SilkS")
		)
		(fp_line
			(start -0.7874 0.4064)
			(end 0.7874 0.4064)
			(stroke
				(width 0.1524)
				(type default)
			)
			(layer "B.SilkS")
		)
		(fp_line
			(start -0.7874 -0.4064)
			(end -0.7874 0.4064)
			(stroke
				(width 0.1524)
				(type default)
			)
			(layer "B.SilkS")
		)
		(fp_line
			(start 0.67945 0.3048)
			(end 0.67945 -0.305054)
			(stroke
				(width 0.1)
				(type default)
			)
			(layer "B.Fab")
		)
		(fp_line
			(start 0.67945 -0.305054)
			(end 0.12065 -0.305054)
			(stroke
				(width 0.1)
				(type default)
			)
			(layer "B.Fab")
		)
		(fp_line
			(start 0.12065 0.3048)
			(end 0.67945 0.3048)
			(stroke
				(width 0.1)
				(type default)
			)
			(layer "B.Fab")
		)
		(fp_line
			(start 0.12065 0.2794)
			(end 0.12065 0.3048)
			(stroke
				(width 0.1)
				(type default)
			)
			(layer "B.Fab")
		)
		(fp_line
			(start 0.12065 -0.2794)
			(end -0.12065 -0.2794)
			(stroke
				(width 0.1)
				(type default)
			)
			(layer "B.Fab")
		)
		(fp_line
			(start 0.12065 -0.305054)
			(end 0.12065 -0.2794)
			(stroke
				(width 0.1)
				(type default)
			)
			(layer "B.Fab")
		)
		(fp_line
			(start -0.120396 0.3048)
			(end -0.120396 0.2794)
			(stroke
				(width 0.1)
				(type default)
			)
			(layer "B.Fab")
		)
		(fp_line
			(start -0.120396 0.2794)
			(end 0.12065 0.2794)
			(stroke
				(width 0.1)
				(type default)
			)
			(layer "B.Fab")
		)
		(fp_line
			(start -0.12065 -0.2794)
			(end -0.12065 -0.3048)
			(stroke
				(width 0.1)
				(type default)
			)
			(layer "B.Fab")
		)
		(fp_line
			(start -0.12065 -0.3048)
			(end -0.67945 -0.3048)
			(stroke
				(width 0.1)
				(type default)
			)
			(layer "B.Fab")
		)
		(fp_line
			(start -0.67945 0.3048)
			(end -0.120396 0.3048)
			(stroke
				(width 0.1)
				(type default)
			)
			(layer "B.Fab")
		)
		(fp_line
			(start -0.67945 -0.3048)
			(end -0.67945 0.3048)
			(stroke
				(width 0.1)
				(type default)
			)
			(layer "B.Fab")
		)
		(pad "1" smd circle
			(at 0.40005 0)
			(size 0 0)
			(layers "B.Cu" "B.Mask" "B.Paste")
			(net "PVDDCR_CPU0_P1")
		)
		(pad "2" smd circle
			(at -0.40005 0)
			(size 0 0)
			(layers "B.Cu" "B.Mask" "B.Paste")
			(net "GND")
		)
	)
	(footprint ""
		(layer "B.Cu")
		(at 52.363624 -408.517344 90)
		(property "Reference" "C6664"
			(at 0 0 90)
			(layer "B.SilkS")
			(hide yes)
			(effects
				(font
					(size 1.27 1.27)
				)
				(justify mirror)
			)
		)
		(property "Value" ""
			(at 0 0 90)
			(layer "B.Fab")
			(effects
				(font
					(size 1.27 1.27)
				)
				(justify mirror)
			)
		)
		(duplicate_pad_numbers_are_jumpers no)
		(fp_line
			(start 0.299974 -0.150114)
			(end -0.299974 -0.150114)
			(stroke
				(width 0.1)
				(type default)
			)
			(layer "B.Fab")
		)
		(fp_line
			(start -0.299974 -0.150114)
			(end -0.299974 0.150114)
			(stroke
				(width 0.1)
				(type default)
			)
			(layer "B.Fab")
		)
		(fp_line
			(start 0.299974 0.150114)
			(end 0.299974 -0.150114)
			(stroke
				(width 0.1)
				(type default)
			)
			(layer "B.Fab")
		)
		(fp_line
			(start -0.299974 0.150114)
			(end 0.299974 0.150114)
			(stroke
				(width 0.1)
				(type default)
			)
			(layer "B.Fab")
		)
		(pad "1" smd rect
			(at 0.2667 0 270)
			(size 0.3048 0.381)
			(layers "B.Cu" "B.Mask" "B.Paste")
			(net "P5E_CPU1_P1_TX_BUF_C_DN<1>")
		)
		(pad "2" smd rect
			(at -0.2667 0 270)
			(size 0.3048 0.381)
			(layers "B.Cu" "B.Mask" "B.Paste")
			(net "P5E_CPU1_P1_TX_BUF_DN<1>")
		)
	)
	(footprint ""
		(layer "B.Cu")
		(at 191.897 -100.294948 -90)
		(property "Reference" "R268"
			(at 0 0 90)
			(layer "B.SilkS")
			(hide yes)
			(effects
				(font
					(size 1.27 1.27)
				)
				(justify mirror)
			)
		)
		(property "Value" ""
			(at 0 0 90)
			(layer "B.Fab")
			(effects
				(font
					(size 1.27 1.27)
				)
				(justify mirror)
			)
		)
		(duplicate_pad_numbers_are_jumpers no)
		(fp_line
			(start -0.7874 0.4064)
			(end 0.7874 0.4064)
			(stroke
				(width 0.1524)
				(type default)
			)
			(layer "B.SilkS")
		)
		(fp_line
			(start 0.7874 0.4064)
			(end 0.7874 -0.4064)
			(stroke
				(width 0.1524)
				(type default)
			)
			(layer "B.SilkS")
		)
		(fp_line
			(start -0.7874 -0.4064)
			(end -0.7874 0.4064)
			(stroke
				(width 0.1524)
				(type default)
			)
			(layer "B.SilkS")
		)
		(fp_line
			(start 0.7874 -0.4064)
			(end -0.7874 -0.4064)
			(stroke
				(width 0.1524)
				(type default)
			)
			(layer "B.SilkS")
		)
		(fp_line
			(start -0.67945 0.3048)
			(end -0.120396 0.3048)
			(stroke
				(width 0.1)
				(type default)
			)
			(layer "B.Fab")
		)
		(fp_line
			(start -0.120396 0.3048)
			(end -0.120396 0.2794)
			(stroke
				(width 0.1)
				(type default)
			)
			(layer "B.Fab")
		)
		(fp_line
			(start 0.12065 0.3048)
			(end 0.67945 0.3048)
			(stroke
				(width 0.1)
				(type default)
			)
			(layer "B.Fab")
		)
		(fp_line
			(start 0.67945 0.3048)
			(end 0.67945 -0.305054)
			(stroke
				(width 0.1)
				(type default)
			)
			(layer "B.Fab")
		)
		(fp_line
			(start -0.120396 0.2794)
			(end 0.12065 0.2794)
			(stroke
				(width 0.1)
				(type default)
			)
			(layer "B.Fab")
		)
		(fp_line
			(start 0.12065 0.2794)
			(end 0.12065 0.3048)
			(stroke
				(width 0.1)
				(type default)
			)
			(layer "B.Fab")
		)
		(fp_line
			(start -0.12065 -0.2794)
			(end -0.12065 -0.3048)
			(stroke
				(width 0.1)
				(type default)
			)
			(layer "B.Fab")
		)
		(fp_line
			(start 0.12065 -0.2794)
			(end -0.12065 -0.2794)
			(stroke
				(width 0.1)
				(type default)
			)
			(layer "B.Fab")
		)
		(fp_line
			(start -0.67945 -0.3048)
			(end -0.67945 0.3048)
			(stroke
				(width 0.1)
				(type default)
			)
			(layer "B.Fab")
		)
		(fp_line
			(start -0.12065 -0.3048)
			(end -0.67945 -0.3048)
			(stroke
				(width 0.1)
				(type default)
			)
			(layer "B.Fab")
		)
		(fp_line
			(start 0.12065 -0.305054)
			(end 0.12065 -0.2794)
			(stroke
				(width 0.1)
				(type default)
			)
			(layer "B.Fab")
		)
		(fp_line
			(start 0.67945 -0.305054)
			(end 0.12065 -0.305054)
			(stroke
				(width 0.1)
				(type default)
			)
			(layer "B.Fab")
		)
		(pad "1" smd circle
			(at 0.40005 0 90)
			(size 0 0)
			(layers "B.Cu" "B.Mask" "B.Paste")
			(net "CPU1_SP5R3")
		)
		(pad "2" smd circle
			(at -0.40005 0 90)
			(size 0 0)
			(layers "B.Cu" "B.Mask" "B.Paste")
			(net "FM_CPU1_SP5R3")
		)
	)
	(footprint ""
		(layer "B.Cu")
		(at 114.01806 -28.449778 -90)
		(property "Reference" "C6107"
			(at 0 0 90)
			(layer "B.SilkS")
			(hide yes)
			(effects
				(font
					(size 1.27 1.27)
				)
				(justify mirror)
			)
		)
		(property "Value" ""
			(at 0 0 90)
			(layer "B.Fab")
			(effects
				(font
					(size 1.27 1.27)
				)
				(justify mirror)
			)
		)
		(duplicate_pad_numbers_are_jumpers no)
		(fp_line
			(start -0.7874 0.4064)
			(end 0.7874 0.4064)
			(stroke
				(width 0.1524)
				(type default)
			)
			(layer "B.SilkS")
		)
		(fp_line
			(start 0.7874 0.4064)
			(end 0.7874 -0.4064)
			(stroke
				(width 0.1524)
				(type default)
			)
			(layer "B.SilkS")
		)
		(fp_line
			(start -0.7874 -0.4064)
			(end -0.7874 0.4064)
			(stroke
				(width 0.1524)
				(type default)
			)
			(layer "B.SilkS")
		)
		(fp_line
			(start 0.7874 -0.4064)
			(end -0.7874 -0.4064)
			(stroke
				(width 0.1524)
				(type default)
			)
			(layer "B.SilkS")
		)
		(fp_line
			(start -0.67945 0.3048)
			(end -0.120396 0.3048)
			(stroke
				(width 0.1)
				(type default)
			)
			(layer "B.Fab")
		)
		(fp_line
			(start -0.120396 0.3048)
			(end -0.120396 0.2794)
			(stroke
				(width 0.1)
				(type default)
			)
			(layer "B.Fab")
		)
		(fp_line
			(start 0.12065 0.3048)
			(end 0.67945 0.3048)
			(stroke
				(width 0.1)
				(type default)
			)
			(layer "B.Fab")
		)
		(fp_line
			(start 0.67945 0.3048)
			(end 0.67945 -0.305054)
			(stroke
				(width 0.1)
				(type default)
			)
			(layer "B.Fab")
		)
		(fp_line
			(start -0.120396 0.2794)
			(end 0.12065 0.2794)
			(stroke
				(width 0.1)
				(type default)
			)
			(layer "B.Fab")
		)
		(fp_line
			(start 0.12065 0.2794)
			(end 0.12065 0.3048)
			(stroke
				(width 0.1)
				(type default)
			)
			(layer "B.Fab")
		)
		(fp_line
			(start -0.12065 -0.2794)
			(end -0.12065 -0.3048)
			(stroke
				(width 0.1)
				(type default)
			)
			(layer "B.Fab")
		)
		(fp_line
			(start 0.12065 -0.2794)
			(end -0.12065 -0.2794)
			(stroke
				(width 0.1)
				(type default)
			)
			(layer "B.Fab")
		)
		(fp_line
			(start -0.67945 -0.3048)
			(end -0.67945 0.3048)
			(stroke
				(width 0.1)
				(type default)
			)
			(layer "B.Fab")
		)
		(fp_line
			(start -0.12065 -0.3048)
			(end -0.67945 -0.3048)
			(stroke
				(width 0.1)
				(type default)
			)
			(layer "B.Fab")
		)
		(fp_line
			(start 0.12065 -0.305054)
			(end 0.12065 -0.2794)
			(stroke
				(width 0.1)
				(type default)
			)
			(layer "B.Fab")
		)
		(fp_line
			(start 0.67945 -0.305054)
			(end 0.12065 -0.305054)
			(stroke
				(width 0.1)
				(type default)
			)
			(layer "B.Fab")
		)
		(pad "1" smd circle
			(at 0.40005 0 90)
			(size 0 0)
			(layers "B.Cu" "B.Mask" "B.Paste")
			(net "P1V2_CPU0_USB2_DVDD12")
		)
		(pad "2" smd circle
			(at -0.40005 0 90)
			(size 0 0)
			(layers "B.Cu" "B.Mask" "B.Paste")
			(net "GND")
		)
	)
	(footprint ""
		(layer "B.Cu")
		(at 95.964248 -182.555134 -90)
		(property "Reference" "PC298_3"
			(at 0 0 90)
			(layer "B.SilkS")
			(hide yes)
			(effects
				(font
					(size 1.27 1.27)
				)
				(justify mirror)
			)
		)
		(property "Value" ""
			(at 0 0 90)
			(layer "B.Fab")
			(effects
				(font
					(size 1.27 1.27)
				)
				(justify mirror)
			)
		)
		(duplicate_pad_numbers_are_jumpers no)
		(fp_line
			(start -1.524 0.762)
			(end 1.524 0.762)
			(stroke
				(width 0.1524)
				(type default)
			)
			(layer "B.SilkS")
		)
		(fp_line
			(start 1.524 0.762)
			(end 1.524 -0.762)
			(stroke
				(width 0.1524)
				(type default)
			)
			(layer "B.SilkS")
		)
		(fp_line
			(start -1.524 -0.762)
			(end -1.524 0.762)
			(stroke
				(width 0.1524)
				(type default)
			)
			(layer "B.SilkS")
		)
		(fp_line
			(start 1.524 -0.762)
			(end -1.524 -0.762)
			(stroke
				(width 0.1524)
				(type default)
			)
			(layer "B.SilkS")
		)
		(fp_line
			(start -1.1049 0.724916)
			(end -1.1049 -0.724916)
			(stroke
				(width 0.1)
				(type default)
			)
			(layer "B.Fab")
		)
		(fp_line
			(start 1.1049 0.724916)
			(end -1.1049 0.724916)
			(stroke
				(width 0.1)
				(type default)
			)
			(layer "B.Fab")
		)
		(fp_line
			(start -1.1049 -0.724916)
			(end 1.1049 -0.724916)
			(stroke
				(width 0.1)
				(type default)
			)
			(layer "B.Fab")
		)
		(fp_line
			(start 1.1049 -0.724916)
			(end 1.1049 0.724916)
			(stroke
				(width 0.1)
				(type default)
			)
			(layer "B.Fab")
		)
		(pad "1" smd rect
			(at 0.889 0 270)
			(size 1.016 1.27)
			(layers "B.Cu" "B.Mask" "B.Paste")
			(net "SW_P12V_AUX_PVDDCR_CPU0_P1_FLT")
		)
		(pad "2" smd rect
			(at -0.889 0 270)
			(size 1.016 1.27)
			(layers "B.Cu" "B.Mask" "B.Paste")
			(net "GND")
		)
	)
	(footprint ""
		(layer "B.Cu")
		(at 292.28034 -192.660016)
		(property "Reference" "C147"
			(at 0 0 0)
			(layer "B.SilkS")
			(hide yes)
			(effects
				(font
					(size 1.27 1.27)
				)
				(justify mirror)
			)
		)
		(property "Value" ""
			(at 0 0 0)
			(layer "B.Fab")
			(effects
				(font
					(size 1.27 1.27)
				)
				(justify mirror)
			)
		)
		(duplicate_pad_numbers_are_jumpers no)
		(fp_line
			(start -1.524 -0.762)
			(end -1.524 0.762)
			(stroke
				(width 0.1524)
				(type default)
			)
			(layer "B.SilkS")
		)
		(fp_line
			(start -1.524 0.762)
			(end 1.524 0.762)
			(stroke
				(width 0.1524)
				(type default)
			)
			(layer "B.SilkS")
		)
		(fp_line
			(start 1.524 -0.762)
			(end -1.524 -0.762)
			(stroke
				(width 0.1524)
				(type default)
			)
			(layer "B.SilkS")
		)
		(fp_line
			(start 1.524 0.762)
			(end 1.524 -0.762)
			(stroke
				(width 0.1524)
				(type default)
			)
			(layer "B.SilkS")
		)
		(fp_line
			(start -1.1049 -0.724916)
			(end 1.1049 -0.724916)
			(stroke
				(width 0.1)
				(type default)
			)
			(layer "B.Fab")
		)
		(fp_line
			(start -1.1049 0.724916)
			(end -1.1049 -0.724916)
			(stroke
				(width 0.1)
				(type default)
			)
			(layer "B.Fab")
		)
		(fp_line
			(start 1.1049 -0.724916)
			(end 1.1049 0.724916)
			(stroke
				(width 0.1)
				(type default)
			)
			(layer "B.Fab")
		)
		(fp_line
			(start 1.1049 0.724916)
			(end -1.1049 0.724916)
			(stroke
				(width 0.1)
				(type default)
			)
			(layer "B.Fab")
		)
		(pad "1" smd rect
			(at 0.889 0)
			(size 1.016 1.27)
			(layers "B.Cu" "B.Mask" "B.Paste")
			(net "P12V_MEM_CPU0")
		)
		(pad "2" smd rect
			(at -0.889 0)
			(size 1.016 1.27)
			(layers "B.Cu" "B.Mask" "B.Paste")
			(net "GND")
		)
	)
	(footprint ""
		(layer "B.Cu")
		(at 70.500494 -328.24547 -90)
		(property "Reference" "PC387"
			(at 10.257536 -0.312166 270)
			(unlocked yes)
			(layer "B.SilkS")
			(effects
				(font
					(size 0.7874 0.5842)
					(thickness 0.1524)
				)
				(justify left mirror)
			)
		)
		(property "Value" ""
			(at 0 0 90)
			(layer "B.Fab")
			(effects
				(font
					(size 1.27 1.27)
				)
				(justify mirror)
			)
		)
		(duplicate_pad_numbers_are_jumpers no)
		(fp_line
			(start -4.533392 2.249932)
			(end 4.533392 2.249932)
			(stroke
				(width 0.1524)
				(type default)
			)
			(layer "B.SilkS")
		)
		(fp_line
			(start 4.533392 2.249932)
			(end 4.533392 -2.249932)
			(stroke
				(width 0.1524)
				(type default)
			)
			(layer "B.SilkS")
		)
		(fp_line
			(start -4.533392 -2.249932)
			(end -4.533392 2.249932)
			(stroke
				(width 0.1524)
				(type default)
			)
			(layer "B.SilkS")
		)
		(fp_line
			(start 4.533392 -2.249932)
			(end -4.533392 -2.249932)
			(stroke
				(width 0.1524)
				(type default)
			)
			(layer "B.SilkS")
		)
		(fp_rect
			(start 5.39242 2.326132)
			(end 4.533392 -2.326132)
			(stroke
				(width 0)
				(type default)
			)
			(fill yes)
			(layer "B.SilkS")
		)
		(fp_line
			(start -3.750056 2.249932)
			(end 3.750056 2.249932)
			(stroke
				(width 0.1)
				(type default)
			)
			(layer "B.Fab")
		)
		(fp_line
			(start 3.750056 2.249932)
			(end 3.750056 -2.249932)
			(stroke
				(width 0.1)
				(type default)
			)
			(layer "B.Fab")
		)
		(fp_line
			(start -3.750056 -2.249932)
			(end -3.750056 2.249932)
			(stroke
				(width 0.1)
				(type default)
			)
			(layer "B.Fab")
		)
		(fp_line
			(start 3.750056 -2.249932)
			(end -3.750056 -2.249932)
			(stroke
				(width 0.1)
				(type default)
			)
			(layer "B.Fab")
		)
		(fp_text user "-"
			(at -4.489196 2.477516 270)
			(unlocked yes)
			(layer "B.SilkS")
			(effects
				(font
					(size 1.905 1.4224)
					(thickness 0.1524)
				)
				(justify left mirror)
			)
		)
		(fp_text user "+"
			(at 6.322314 0.786384 180)
			(unlocked yes)
			(layer "B.SilkS")
			(effects
				(font
					(size 1.905 1.4224)
					(thickness 0.1524)
				)
				(justify left mirror)
			)
		)
		(fp_text user "+"
			(at 6.322314 0.786384 180)
			(unlocked yes)
			(layer "B.Fab")
			(effects
				(font
					(size 1.905 1.4224)
					(thickness 0.1524)
				)
				(justify left mirror)
			)
		)
		(fp_text user "-"
			(at -4.8514 -0.14605 270)
			(unlocked yes)
			(layer "B.Fab")
			(effects
				(font
					(size 1.905 1.4224)
					(thickness 0.1524)
				)
				(justify left mirror)
			)
		)
		(pad "1" smd rect
			(at 3.199892 0 90)
			(size 2.413 2.8194)
			(layers "B.Cu" "B.Mask" "B.Paste")
			(net "PVDDCR_CPU1_P1")
		)
		(pad "2" smd rect
			(at -3.199892 0 90)
			(size 2.413 2.8194)
			(layers "B.Cu" "B.Mask" "B.Paste")
			(net "GND")
		)
	)
	(footprint ""
		(layer "B.Cu")
		(at 228.383592 -290.564062)
		(property "Reference" "PR6520"
			(at 0 0 0)
			(layer "B.SilkS")
			(hide yes)
			(effects
				(font
					(size 1.27 1.27)
				)
				(justify mirror)
			)
		)
		(property "Value" ""
			(at 0 0 0)
			(layer "B.Fab")
			(effects
				(font
					(size 1.27 1.27)
				)
				(justify mirror)
			)
		)
		(duplicate_pad_numbers_are_jumpers no)
		(fp_line
			(start -0.7874 -0.4064)
			(end -0.7874 0.4064)
			(stroke
				(width 0.1524)
				(type default)
			)
			(layer "B.SilkS")
		)
		(fp_line
			(start -0.7874 0.4064)
			(end 0.7874 0.4064)
			(stroke
				(width 0.1524)
				(type default)
			)
			(layer "B.SilkS")
		)
		(fp_line
			(start 0.7874 -0.4064)
			(end -0.7874 -0.4064)
			(stroke
				(width 0.1524)
				(type default)
			)
			(layer "B.SilkS")
		)
		(fp_line
			(start 0.7874 0.4064)
			(end 0.7874 -0.4064)
			(stroke
				(width 0.1524)
				(type default)
			)
			(layer "B.SilkS")
		)
		(fp_line
			(start -0.67945 -0.3048)
			(end -0.67945 0.3048)
			(stroke
				(width 0.1)
				(type default)
			)
			(layer "B.Fab")
		)
		(fp_line
			(start -0.67945 0.3048)
			(end -0.120396 0.3048)
			(stroke
				(width 0.1)
				(type default)
			)
			(layer "B.Fab")
		)
		(fp_line
			(start -0.12065 -0.3048)
			(end -0.67945 -0.3048)
			(stroke
				(width 0.1)
				(type default)
			)
			(layer "B.Fab")
		)
		(fp_line
			(start -0.12065 -0.2794)
			(end -0.12065 -0.3048)
			(stroke
				(width 0.1)
				(type default)
			)
			(layer "B.Fab")
		)
		(fp_line
			(start -0.120396 0.2794)
			(end 0.12065 0.2794)
			(stroke
				(width 0.1)
				(type default)
			)
			(layer "B.Fab")
		)
		(fp_line
			(start -0.120396 0.3048)
			(end -0.120396 0.2794)
			(stroke
				(width 0.1)
				(type default)
			)
			(layer "B.Fab")
		)
		(fp_line
			(start 0.12065 -0.305054)
			(end 0.12065 -0.2794)
			(stroke
				(width 0.1)
				(type default)
			)
			(layer "B.Fab")
		)
		(fp_line
			(start 0.12065 -0.2794)
			(end -0.12065 -0.2794)
			(stroke
				(width 0.1)
				(type default)
			)
			(layer "B.Fab")
		)
		(fp_line
			(start 0.12065 0.2794)
			(end 0.12065 0.3048)
			(stroke
				(width 0.1)
				(type default)
			)
			(layer "B.Fab")
		)
		(fp_line
			(start 0.12065 0.3048)
			(end 0.67945 0.3048)
			(stroke
				(width 0.1)
				(type default)
			)
			(layer "B.Fab")
		)
		(fp_line
			(start 0.67945 -0.305054)
			(end 0.12065 -0.305054)
			(stroke
				(width 0.1)
				(type default)
			)
			(layer "B.Fab")
		)
		(fp_line
			(start 0.67945 0.3048)
			(end 0.67945 -0.305054)
			(stroke
				(width 0.1)
				(type default)
			)
			(layer "B.Fab")
		)
		(pad "1" smd circle
			(at 0.40005 0 180)
			(size 0 0)
			(layers "B.Cu" "B.Mask" "B.Paste")
			(net "GND")
		)
		(pad "2" smd circle
			(at -0.40005 0 180)
			(size 0 0)
			(layers "B.Cu" "B.Mask" "B.Paste")
			(net "P1V8_RETIMER_CPU1_MODE")
		)
	)
	(footprint ""
		(layer "B.Cu")
		(at 51.232562 -347.780356 -90)
		(property "Reference" "PR277"
			(at 0 0 90)
			(layer "B.SilkS")
			(hide yes)
			(effects
				(font
					(size 1.27 1.27)
				)
				(justify mirror)
			)
		)
		(property "Value" ""
			(at 0 0 90)
			(layer "B.Fab")
			(effects
				(font
					(size 1.27 1.27)
				)
				(justify mirror)
			)
		)
		(duplicate_pad_numbers_are_jumpers no)
		(fp_line
			(start -0.7874 0.4064)
			(end 0.7874 0.4064)
			(stroke
				(width 0.1524)
				(type default)
			)
			(layer "B.SilkS")
		)
		(fp_line
			(start 0.7874 0.4064)
			(end 0.7874 -0.4064)
			(stroke
				(width 0.1524)
				(type default)
			)
			(layer "B.SilkS")
		)
		(fp_line
			(start -0.7874 -0.4064)
			(end -0.7874 0.4064)
			(stroke
				(width 0.1524)
				(type default)
			)
			(layer "B.SilkS")
		)
		(fp_line
			(start 0.7874 -0.4064)
			(end -0.7874 -0.4064)
			(stroke
				(width 0.1524)
				(type default)
			)
			(layer "B.SilkS")
		)
		(fp_line
			(start -0.67945 0.3048)
			(end -0.120396 0.3048)
			(stroke
				(width 0.1)
				(type default)
			)
			(layer "B.Fab")
		)
		(fp_line
			(start -0.120396 0.3048)
			(end -0.120396 0.2794)
			(stroke
				(width 0.1)
				(type default)
			)
			(layer "B.Fab")
		)
		(fp_line
			(start 0.12065 0.3048)
			(end 0.67945 0.3048)
			(stroke
				(width 0.1)
				(type default)
			)
			(layer "B.Fab")
		)
		(fp_line
			(start 0.67945 0.3048)
			(end 0.67945 -0.305054)
			(stroke
				(width 0.1)
				(type default)
			)
			(layer "B.Fab")
		)
		(fp_line
			(start -0.120396 0.2794)
			(end 0.12065 0.2794)
			(stroke
				(width 0.1)
				(type default)
			)
			(layer "B.Fab")
		)
		(fp_line
			(start 0.12065 0.2794)
			(end 0.12065 0.3048)
			(stroke
				(width 0.1)
				(type default)
			)
			(layer "B.Fab")
		)
		(fp_line
			(start -0.12065 -0.2794)
			(end -0.12065 -0.3048)
			(stroke
				(width 0.1)
				(type default)
			)
			(layer "B.Fab")
		)
		(fp_line
			(start 0.12065 -0.2794)
			(end -0.12065 -0.2794)
			(stroke
				(width 0.1)
				(type default)
			)
			(layer "B.Fab")
		)
		(fp_line
			(start -0.67945 -0.3048)
			(end -0.67945 0.3048)
			(stroke
				(width 0.1)
				(type default)
			)
			(layer "B.Fab")
		)
		(fp_line
			(start -0.12065 -0.3048)
			(end -0.67945 -0.3048)
			(stroke
				(width 0.1)
				(type default)
			)
			(layer "B.Fab")
		)
		(fp_line
			(start 0.12065 -0.305054)
			(end 0.12065 -0.2794)
			(stroke
				(width 0.1)
				(type default)
			)
			(layer "B.Fab")
		)
		(fp_line
			(start 0.67945 -0.305054)
			(end 0.12065 -0.305054)
			(stroke
				(width 0.1)
				(type default)
			)
			(layer "B.Fab")
		)
		(pad "1" smd circle
			(at 0.40005 0 90)
			(size 0 0)
			(layers "B.Cu" "B.Mask" "B.Paste")
			(net "PVDDCR_CPU1_P1_PVCC")
		)
		(pad "2" smd circle
			(at -0.40005 0 90)
			(size 0 0)
			(layers "B.Cu" "B.Mask" "B.Paste")
			(net "PVDDIO_P1_VCC1")
		)
	)
	(footprint ""
		(layer "B.Cu")
		(at 181.37886 -406.918922 90)
		(property "Reference" "R1714"
			(at 0 0 90)
			(layer "B.SilkS")
			(hide yes)
			(effects
				(font
					(size 1.27 1.27)
				)
				(justify mirror)
			)
		)
		(property "Value" ""
			(at 0 0 90)
			(layer "B.Fab")
			(effects
				(font
					(size 1.27 1.27)
				)
				(justify mirror)
			)
		)
		(duplicate_pad_numbers_are_jumpers no)
		(fp_line
			(start 0.7874 -0.4064)
			(end -0.7874 -0.4064)
			(stroke
				(width 0.1524)
				(type default)
			)
			(layer "B.SilkS")
		)
		(fp_line
			(start -0.7874 -0.4064)
			(end -0.7874 0.4064)
			(stroke
				(width 0.1524)
				(type default)
			)
			(layer "B.SilkS")
		)
		(fp_line
			(start 0.7874 0.4064)
			(end 0.7874 -0.4064)
			(stroke
				(width 0.1524)
				(type default)
			)
			(layer "B.SilkS")
		)
		(fp_line
			(start -0.7874 0.4064)
			(end 0.7874 0.4064)
			(stroke
				(width 0.1524)
				(type default)
			)
			(layer "B.SilkS")
		)
		(fp_line
			(start 0.67945 -0.305054)
			(end 0.12065 -0.305054)
			(stroke
				(width 0.1)
				(type default)
			)
			(layer "B.Fab")
		)
		(fp_line
			(start 0.12065 -0.305054)
			(end 0.12065 -0.2794)
			(stroke
				(width 0.1)
				(type default)
			)
			(layer "B.Fab")
		)
		(fp_line
			(start -0.12065 -0.3048)
			(end -0.67945 -0.3048)
			(stroke
				(width 0.1)
				(type default)
			)
			(layer "B.Fab")
		)
		(fp_line
			(start -0.67945 -0.3048)
			(end -0.67945 0.3048)
			(stroke
				(width 0.1)
				(type default)
			)
			(layer "B.Fab")
		)
		(fp_line
			(start 0.12065 -0.2794)
			(end -0.12065 -0.2794)
			(stroke
				(width 0.1)
				(type default)
			)
			(layer "B.Fab")
		)
		(fp_line
			(start -0.12065 -0.2794)
			(end -0.12065 -0.3048)
			(stroke
				(width 0.1)
				(type default)
			)
			(layer "B.Fab")
		)
		(fp_line
			(start 0.12065 0.2794)
			(end 0.12065 0.3048)
			(stroke
				(width 0.1)
				(type default)
			)
			(layer "B.Fab")
		)
		(fp_line
			(start -0.120396 0.2794)
			(end 0.12065 0.2794)
			(stroke
				(width 0.1)
				(type default)
			)
			(layer "B.Fab")
		)
		(fp_line
			(start 0.67945 0.3048)
			(end 0.67945 -0.305054)
			(stroke
				(width 0.1)
				(type default)
			)
			(layer "B.Fab")
		)
		(fp_line
			(start 0.12065 0.3048)
			(end 0.67945 0.3048)
			(stroke
				(width 0.1)
				(type default)
			)
			(layer "B.Fab")
		)
		(fp_line
			(start -0.120396 0.3048)
			(end -0.120396 0.2794)
			(stroke
				(width 0.1)
				(type default)
			)
			(layer "B.Fab")
		)
		(fp_line
			(start -0.67945 0.3048)
			(end -0.120396 0.3048)
			(stroke
				(width 0.1)
				(type default)
			)
			(layer "B.Fab")
		)
		(pad "1" smd circle
			(at 0.40005 0 270)
			(size 0 0)
			(layers "B.Cu" "B.Mask" "B.Paste")
			(net "SMB_SML1_PMBUS_HSC_SDA")
		)
		(pad "2" smd circle
			(at -0.40005 0 270)
			(size 0 0)
			(layers "B.Cu" "B.Mask" "B.Paste")
			(net "SMB_SML1_PMBUS_HSC_R_SDA")
		)
	)
	(footprint ""
		(layer "B.Cu")
		(at 182.225188 -418.423598 -90)
		(property "Reference" "R2800"
			(at 0 0 90)
			(layer "B.SilkS")
			(hide yes)
			(effects
				(font
					(size 1.27 1.27)
				)
				(justify mirror)
			)
		)
		(property "Value" ""
			(at 0 0 90)
			(layer "B.Fab")
			(effects
				(font
					(size 1.27 1.27)
				)
				(justify mirror)
			)
		)
		(duplicate_pad_numbers_are_jumpers no)
		(fp_line
			(start -0.7874 0.4064)
			(end 0.7874 0.4064)
			(stroke
				(width 0.1524)
				(type default)
			)
			(layer "B.SilkS")
		)
		(fp_line
			(start 0.7874 0.4064)
			(end 0.7874 -0.4064)
			(stroke
				(width 0.1524)
				(type default)
			)
			(layer "B.SilkS")
		)
		(fp_line
			(start -0.7874 -0.4064)
			(end -0.7874 0.4064)
			(stroke
				(width 0.1524)
				(type default)
			)
			(layer "B.SilkS")
		)
		(fp_line
			(start 0.7874 -0.4064)
			(end -0.7874 -0.4064)
			(stroke
				(width 0.1524)
				(type default)
			)
			(layer "B.SilkS")
		)
		(fp_line
			(start -0.67945 0.3048)
			(end -0.120396 0.3048)
			(stroke
				(width 0.1)
				(type default)
			)
			(layer "B.Fab")
		)
		(fp_line
			(start -0.120396 0.3048)
			(end -0.120396 0.2794)
			(stroke
				(width 0.1)
				(type default)
			)
			(layer "B.Fab")
		)
		(fp_line
			(start 0.12065 0.3048)
			(end 0.67945 0.3048)
			(stroke
				(width 0.1)
				(type default)
			)
			(layer "B.Fab")
		)
		(fp_line
			(start 0.67945 0.3048)
			(end 0.67945 -0.305054)
			(stroke
				(width 0.1)
				(type default)
			)
			(layer "B.Fab")
		)
		(fp_line
			(start -0.120396 0.2794)
			(end 0.12065 0.2794)
			(stroke
				(width 0.1)
				(type default)
			)
			(layer "B.Fab")
		)
		(fp_line
			(start 0.12065 0.2794)
			(end 0.12065 0.3048)
			(stroke
				(width 0.1)
				(type default)
			)
			(layer "B.Fab")
		)
		(fp_line
			(start -0.12065 -0.2794)
			(end -0.12065 -0.3048)
			(stroke
				(width 0.1)
				(type default)
			)
			(layer "B.Fab")
		)
		(fp_line
			(start 0.12065 -0.2794)
			(end -0.12065 -0.2794)
			(stroke
				(width 0.1)
				(type default)
			)
			(layer "B.Fab")
		)
		(fp_line
			(start -0.67945 -0.3048)
			(end -0.67945 0.3048)
			(stroke
				(width 0.1)
				(type default)
			)
			(layer "B.Fab")
		)
		(fp_line
			(start -0.12065 -0.3048)
			(end -0.67945 -0.3048)
			(stroke
				(width 0.1)
				(type default)
			)
			(layer "B.Fab")
		)
		(fp_line
			(start 0.12065 -0.305054)
			(end 0.12065 -0.2794)
			(stroke
				(width 0.1)
				(type default)
			)
			(layer "B.Fab")
		)
		(fp_line
			(start 0.67945 -0.305054)
			(end 0.12065 -0.305054)
			(stroke
				(width 0.1)
				(type default)
			)
			(layer "B.Fab")
		)
		(pad "1" smd circle
			(at 0.40005 0 90)
			(size 0 0)
			(layers "B.Cu" "B.Mask" "B.Paste")
			(net "SMB_FAN_3V3AUX_R_SCL")
		)
		(pad "2" smd circle
			(at -0.40005 0 90)
			(size 0 0)
			(layers "B.Cu" "B.Mask" "B.Paste")
			(net "SMB_FAN_3V3AUX_BUF_SCL")
		)
	)
	(footprint ""
		(layer "B.Cu")
		(at 83.646264 -388.011162 -90)
		(property "Reference" "C334"
			(at 0 0 90)
			(layer "B.SilkS")
			(hide yes)
			(effects
				(font
					(size 1.27 1.27)
				)
				(justify mirror)
			)
		)
		(property "Value" ""
			(at 0 0 90)
			(layer "B.Fab")
			(effects
				(font
					(size 1.27 1.27)
				)
				(justify mirror)
			)
		)
		(duplicate_pad_numbers_are_jumpers no)
		(fp_line
			(start -0.299974 0.150114)
			(end 0.299974 0.150114)
			(stroke
				(width 0.1)
				(type default)
			)
			(layer "B.Fab")
		)
		(fp_line
			(start 0.299974 0.150114)
			(end 0.299974 -0.150114)
			(stroke
				(width 0.1)
				(type default)
			)
			(layer "B.Fab")
		)
		(fp_line
			(start -0.299974 -0.150114)
			(end -0.299974 0.150114)
			(stroke
				(width 0.1)
				(type default)
			)
			(layer "B.Fab")
		)
		(fp_line
			(start 0.299974 -0.150114)
			(end -0.299974 -0.150114)
			(stroke
				(width 0.1)
				(type default)
			)
			(layer "B.Fab")
		)
		(pad "1" smd rect
			(at 0.2667 0 90)
			(size 0.3048 0.381)
			(layers "B.Cu" "B.Mask" "B.Paste")
			(net "P0V9_CPU1_RT1_2A")
		)
		(pad "2" smd rect
			(at -0.2667 0 90)
			(size 0.3048 0.381)
			(layers "B.Cu" "B.Mask" "B.Paste")
			(net "GND")
		)
	)
	(footprint ""
		(layer "B.Cu")
		(at 438.766966 -425.184824 -90)
		(property "Reference" "PR6615"
			(at 0 0 90)
			(layer "B.SilkS")
			(hide yes)
			(effects
				(font
					(size 1.27 1.27)
				)
				(justify mirror)
			)
		)
		(property "Value" ""
			(at 0 0 90)
			(layer "B.Fab")
			(effects
				(font
					(size 1.27 1.27)
				)
				(justify mirror)
			)
		)
		(duplicate_pad_numbers_are_jumpers no)
		(fp_line
			(start -0.7874 0.4064)
			(end 0.7874 0.4064)
			(stroke
				(width 0.1524)
				(type default)
			)
			(layer "B.SilkS")
		)
		(fp_line
			(start 0.7874 0.4064)
			(end 0.7874 -0.4064)
			(stroke
				(width 0.1524)
				(type default)
			)
			(layer "B.SilkS")
		)
		(fp_line
			(start -0.7874 -0.4064)
			(end -0.7874 0.4064)
			(stroke
				(width 0.1524)
				(type default)
			)
			(layer "B.SilkS")
		)
		(fp_line
			(start 0.7874 -0.4064)
			(end -0.7874 -0.4064)
			(stroke
				(width 0.1524)
				(type default)
			)
			(layer "B.SilkS")
		)
		(fp_line
			(start -0.67945 0.3048)
			(end -0.120396 0.3048)
			(stroke
				(width 0.1)
				(type default)
			)
			(layer "B.Fab")
		)
		(fp_line
			(start -0.120396 0.3048)
			(end -0.120396 0.2794)
			(stroke
				(width 0.1)
				(type default)
			)
			(layer "B.Fab")
		)
		(fp_line
			(start 0.12065 0.3048)
			(end 0.67945 0.3048)
			(stroke
				(width 0.1)
				(type default)
			)
			(layer "B.Fab")
		)
		(fp_line
			(start 0.67945 0.3048)
			(end 0.67945 -0.305054)
			(stroke
				(width 0.1)
				(type default)
			)
			(layer "B.Fab")
		)
		(fp_line
			(start -0.120396 0.2794)
			(end 0.12065 0.2794)
			(stroke
				(width 0.1)
				(type default)
			)
			(layer "B.Fab")
		)
		(fp_line
			(start 0.12065 0.2794)
			(end 0.12065 0.3048)
			(stroke
				(width 0.1)
				(type default)
			)
			(layer "B.Fab")
		)
		(fp_line
			(start -0.12065 -0.2794)
			(end -0.12065 -0.3048)
			(stroke
				(width 0.1)
				(type default)
			)
			(layer "B.Fab")
		)
		(fp_line
			(start 0.12065 -0.2794)
			(end -0.12065 -0.2794)
			(stroke
				(width 0.1)
				(type default)
			)
			(layer "B.Fab")
		)
		(fp_line
			(start -0.67945 -0.3048)
			(end -0.67945 0.3048)
			(stroke
				(width 0.1)
				(type default)
			)
			(layer "B.Fab")
		)
		(fp_line
			(start -0.12065 -0.3048)
			(end -0.67945 -0.3048)
			(stroke
				(width 0.1)
				(type default)
			)
			(layer "B.Fab")
		)
		(fp_line
			(start 0.12065 -0.305054)
			(end 0.12065 -0.2794)
			(stroke
				(width 0.1)
				(type default)
			)
			(layer "B.Fab")
		)
		(fp_line
			(start 0.67945 -0.305054)
			(end 0.12065 -0.305054)
			(stroke
				(width 0.1)
				(type default)
			)
			(layer "B.Fab")
		)
		(pad "1" smd circle
			(at 0.40005 0 90)
			(size 0 0)
			(layers "B.Cu" "B.Mask" "B.Paste")
			(net "P3V3_AUX")
		)
		(pad "2" smd circle
			(at -0.40005 0 90)
			(size 0 0)
			(layers "B.Cu" "B.Mask" "B.Paste")
			(net "TP_P0V9_RETIMER_CPU0_VRHOT")
		)
	)
	(footprint ""
		(layer "B.Cu")
		(at 130.702304 -33.019492 -90)
		(property "Reference" "C6065"
			(at 0 0 90)
			(layer "B.SilkS")
			(hide yes)
			(effects
				(font
					(size 1.27 1.27)
				)
				(justify mirror)
			)
		)
		(property "Value" ""
			(at 0 0 90)
			(layer "B.Fab")
			(effects
				(font
					(size 1.27 1.27)
				)
				(justify mirror)
			)
		)
		(duplicate_pad_numbers_are_jumpers no)
		(fp_line
			(start -0.7874 0.4064)
			(end 0.7874 0.4064)
			(stroke
				(width 0.1524)
				(type default)
			)
			(layer "B.SilkS")
		)
		(fp_line
			(start 0.7874 0.4064)
			(end 0.7874 -0.4064)
			(stroke
				(width 0.1524)
				(type default)
			)
			(layer "B.SilkS")
		)
		(fp_line
			(start -0.7874 -0.4064)
			(end -0.7874 0.4064)
			(stroke
				(width 0.1524)
				(type default)
			)
			(layer "B.SilkS")
		)
		(fp_line
			(start 0.7874 -0.4064)
			(end -0.7874 -0.4064)
			(stroke
				(width 0.1524)
				(type default)
			)
			(layer "B.SilkS")
		)
		(fp_line
			(start -0.67945 0.3048)
			(end -0.120396 0.3048)
			(stroke
				(width 0.1)
				(type default)
			)
			(layer "B.Fab")
		)
		(fp_line
			(start -0.120396 0.3048)
			(end -0.120396 0.2794)
			(stroke
				(width 0.1)
				(type default)
			)
			(layer "B.Fab")
		)
		(fp_line
			(start 0.12065 0.3048)
			(end 0.67945 0.3048)
			(stroke
				(width 0.1)
				(type default)
			)
			(layer "B.Fab")
		)
		(fp_line
			(start 0.67945 0.3048)
			(end 0.67945 -0.305054)
			(stroke
				(width 0.1)
				(type default)
			)
			(layer "B.Fab")
		)
		(fp_line
			(start -0.120396 0.2794)
			(end 0.12065 0.2794)
			(stroke
				(width 0.1)
				(type default)
			)
			(layer "B.Fab")
		)
		(fp_line
			(start 0.12065 0.2794)
			(end 0.12065 0.3048)
			(stroke
				(width 0.1)
				(type default)
			)
			(layer "B.Fab")
		)
		(fp_line
			(start -0.12065 -0.2794)
			(end -0.12065 -0.3048)
			(stroke
				(width 0.1)
				(type default)
			)
			(layer "B.Fab")
		)
		(fp_line
			(start 0.12065 -0.2794)
			(end -0.12065 -0.2794)
			(stroke
				(width 0.1)
				(type default)
			)
			(layer "B.Fab")
		)
		(fp_line
			(start -0.67945 -0.3048)
			(end -0.67945 0.3048)
			(stroke
				(width 0.1)
				(type default)
			)
			(layer "B.Fab")
		)
		(fp_line
			(start -0.12065 -0.3048)
			(end -0.67945 -0.3048)
			(stroke
				(width 0.1)
				(type default)
			)
			(layer "B.Fab")
		)
		(fp_line
			(start 0.12065 -0.305054)
			(end 0.12065 -0.2794)
			(stroke
				(width 0.1)
				(type default)
			)
			(layer "B.Fab")
		)
		(fp_line
			(start 0.67945 -0.305054)
			(end 0.12065 -0.305054)
			(stroke
				(width 0.1)
				(type default)
			)
			(layer "B.Fab")
		)
		(pad "1" smd circle
			(at 0.40005 0 90)
			(size 0 0)
			(layers "B.Cu" "B.Mask" "B.Paste")
			(net "P1V2_AUX")
		)
		(pad "2" smd circle
			(at -0.40005 0 90)
			(size 0 0)
			(layers "B.Cu" "B.Mask" "B.Paste")
			(net "GND")
		)
	)
	(footprint ""
		(layer "B.Cu")
		(at 235.660692 -422.849548 90)
		(property "Reference" "R2802"
			(at 0 0 90)
			(layer "B.SilkS")
			(hide yes)
			(effects
				(font
					(size 1.27 1.27)
				)
				(justify mirror)
			)
		)
		(property "Value" ""
			(at 0 0 90)
			(layer "B.Fab")
			(effects
				(font
					(size 1.27 1.27)
				)
				(justify mirror)
			)
		)
		(duplicate_pad_numbers_are_jumpers no)
		(fp_line
			(start 0.7874 -0.4064)
			(end -0.7874 -0.4064)
			(stroke
				(width 0.1524)
				(type default)
			)
			(layer "B.SilkS")
		)
		(fp_line
			(start -0.7874 -0.4064)
			(end -0.7874 0.4064)
			(stroke
				(width 0.1524)
				(type default)
			)
			(layer "B.SilkS")
		)
		(fp_line
			(start 0.7874 0.4064)
			(end 0.7874 -0.4064)
			(stroke
				(width 0.1524)
				(type default)
			)
			(layer "B.SilkS")
		)
		(fp_line
			(start -0.7874 0.4064)
			(end 0.7874 0.4064)
			(stroke
				(width 0.1524)
				(type default)
			)
			(layer "B.SilkS")
		)
		(fp_line
			(start 0.67945 -0.305054)
			(end 0.12065 -0.305054)
			(stroke
				(width 0.1)
				(type default)
			)
			(layer "B.Fab")
		)
		(fp_line
			(start 0.12065 -0.305054)
			(end 0.12065 -0.2794)
			(stroke
				(width 0.1)
				(type default)
			)
			(layer "B.Fab")
		)
		(fp_line
			(start -0.12065 -0.3048)
			(end -0.67945 -0.3048)
			(stroke
				(width 0.1)
				(type default)
			)
			(layer "B.Fab")
		)
		(fp_line
			(start -0.67945 -0.3048)
			(end -0.67945 0.3048)
			(stroke
				(width 0.1)
				(type default)
			)
			(layer "B.Fab")
		)
		(fp_line
			(start 0.12065 -0.2794)
			(end -0.12065 -0.2794)
			(stroke
				(width 0.1)
				(type default)
			)
			(layer "B.Fab")
		)
		(fp_line
			(start -0.12065 -0.2794)
			(end -0.12065 -0.3048)
			(stroke
				(width 0.1)
				(type default)
			)
			(layer "B.Fab")
		)
		(fp_line
			(start 0.12065 0.2794)
			(end 0.12065 0.3048)
			(stroke
				(width 0.1)
				(type default)
			)
			(layer "B.Fab")
		)
		(fp_line
			(start -0.120396 0.2794)
			(end 0.12065 0.2794)
			(stroke
				(width 0.1)
				(type default)
			)
			(layer "B.Fab")
		)
		(fp_line
			(start 0.67945 0.3048)
			(end 0.67945 -0.305054)
			(stroke
				(width 0.1)
				(type default)
			)
			(layer "B.Fab")
		)
		(fp_line
			(start 0.12065 0.3048)
			(end 0.67945 0.3048)
			(stroke
				(width 0.1)
				(type default)
			)
			(layer "B.Fab")
		)
		(fp_line
			(start -0.120396 0.3048)
			(end -0.120396 0.2794)
			(stroke
				(width 0.1)
				(type default)
			)
			(layer "B.Fab")
		)
		(fp_line
			(start -0.67945 0.3048)
			(end -0.120396 0.3048)
			(stroke
				(width 0.1)
				(type default)
			)
			(layer "B.Fab")
		)
		(pad "1" smd circle
			(at 0.40005 0 270)
			(size 0 0)
			(layers "B.Cu" "B.Mask" "B.Paste")
			(net "HPDB_HSC_PWRGD_R")
		)
		(pad "2" smd circle
			(at -0.40005 0 270)
			(size 0 0)
			(layers "B.Cu" "B.Mask" "B.Paste")
			(net "HPDB_HSC_PWRGD")
		)
	)
	(footprint ""
		(layer "B.Cu")
		(at 356.406958 -246.376952)
		(property "Reference" "C2199"
			(at 0 0 0)
			(layer "B.SilkS")
			(hide yes)
			(effects
				(font
					(size 1.27 1.27)
				)
				(justify mirror)
			)
		)
		(property "Value" ""
			(at 0 0 0)
			(layer "B.Fab")
			(effects
				(font
					(size 1.27 1.27)
				)
				(justify mirror)
			)
		)
		(duplicate_pad_numbers_are_jumpers no)
		(fp_line
			(start -0.7874 -0.4064)
			(end -0.7874 0.4064)
			(stroke
				(width 0.1524)
				(type default)
			)
			(layer "B.SilkS")
		)
		(fp_line
			(start -0.7874 0.4064)
			(end 0.7874 0.4064)
			(stroke
				(width 0.1524)
				(type default)
			)
			(layer "B.SilkS")
		)
		(fp_line
			(start 0.7874 -0.4064)
			(end -0.7874 -0.4064)
			(stroke
				(width 0.1524)
				(type default)
			)
			(layer "B.SilkS")
		)
		(fp_line
			(start 0.7874 0.4064)
			(end 0.7874 -0.4064)
			(stroke
				(width 0.1524)
				(type default)
			)
			(layer "B.SilkS")
		)
		(fp_line
			(start -0.67945 -0.3048)
			(end -0.67945 0.3048)
			(stroke
				(width 0.1)
				(type default)
			)
			(layer "B.Fab")
		)
		(fp_line
			(start -0.67945 0.3048)
			(end -0.120396 0.3048)
			(stroke
				(width 0.1)
				(type default)
			)
			(layer "B.Fab")
		)
		(fp_line
			(start -0.12065 -0.3048)
			(end -0.67945 -0.3048)
			(stroke
				(width 0.1)
				(type default)
			)
			(layer "B.Fab")
		)
		(fp_line
			(start -0.12065 -0.2794)
			(end -0.12065 -0.3048)
			(stroke
				(width 0.1)
				(type default)
			)
			(layer "B.Fab")
		)
		(fp_line
			(start -0.120396 0.2794)
			(end 0.12065 0.2794)
			(stroke
				(width 0.1)
				(type default)
			)
			(layer "B.Fab")
		)
		(fp_line
			(start -0.120396 0.3048)
			(end -0.120396 0.2794)
			(stroke
				(width 0.1)
				(type default)
			)
			(layer "B.Fab")
		)
		(fp_line
			(start 0.12065 -0.305054)
			(end 0.12065 -0.2794)
			(stroke
				(width 0.1)
				(type default)
			)
			(layer "B.Fab")
		)
		(fp_line
			(start 0.12065 -0.2794)
			(end -0.12065 -0.2794)
			(stroke
				(width 0.1)
				(type default)
			)
			(layer "B.Fab")
		)
		(fp_line
			(start 0.12065 0.2794)
			(end 0.12065 0.3048)
			(stroke
				(width 0.1)
				(type default)
			)
			(layer "B.Fab")
		)
		(fp_line
			(start 0.12065 0.3048)
			(end 0.67945 0.3048)
			(stroke
				(width 0.1)
				(type default)
			)
			(layer "B.Fab")
		)
		(fp_line
			(start 0.67945 -0.305054)
			(end 0.12065 -0.305054)
			(stroke
				(width 0.1)
				(type default)
			)
			(layer "B.Fab")
		)
		(fp_line
			(start 0.67945 0.3048)
			(end 0.67945 -0.305054)
			(stroke
				(width 0.1)
				(type default)
			)
			(layer "B.Fab")
		)
		(pad "1" smd circle
			(at 0.40005 0 180)
			(size 0 0)
			(layers "B.Cu" "B.Mask" "B.Paste")
			(net "PVDDCR_CPU0_P0")
		)
		(pad "2" smd circle
			(at -0.40005 0 180)
			(size 0 0)
			(layers "B.Cu" "B.Mask" "B.Paste")
			(net "GND")
		)
	)
	(footprint ""
		(layer "B.Cu")
		(at 386.21843 -396.393162 -90)
		(property "Reference" "C1051"
			(at 0 0 90)
			(layer "B.SilkS")
			(hide yes)
			(effects
				(font
					(size 1.27 1.27)
				)
				(justify mirror)
			)
		)
		(property "Value" ""
			(at 0 0 90)
			(layer "B.Fab")
			(effects
				(font
					(size 1.27 1.27)
				)
				(justify mirror)
			)
		)
		(duplicate_pad_numbers_are_jumpers no)
		(fp_line
			(start -0.299974 0.150114)
			(end 0.299974 0.150114)
			(stroke
				(width 0.1)
				(type default)
			)
			(layer "B.Fab")
		)
		(fp_line
			(start 0.299974 0.150114)
			(end 0.299974 -0.150114)
			(stroke
				(width 0.1)
				(type default)
			)
			(layer "B.Fab")
		)
		(fp_line
			(start -0.299974 -0.150114)
			(end -0.299974 0.150114)
			(stroke
				(width 0.1)
				(type default)
			)
			(layer "B.Fab")
		)
		(fp_line
			(start 0.299974 -0.150114)
			(end -0.299974 -0.150114)
			(stroke
				(width 0.1)
				(type default)
			)
			(layer "B.Fab")
		)
		(pad "1" smd rect
			(at 0.2667 0 90)
			(size 0.3048 0.381)
			(layers "B.Cu" "B.Mask" "B.Paste")
			(net "P0V9_CPU0_RT3_2A")
		)
		(pad "2" smd rect
			(at -0.2667 0 90)
			(size 0.3048 0.381)
			(layers "B.Cu" "B.Mask" "B.Paste")
			(net "GND")
		)
	)
	(footprint ""
		(layer "B.Cu")
		(at 233.172 -340.868 180)
		(property "Reference" "R976"
			(at 0 0 0)
			(layer "B.SilkS")
			(hide yes)
			(effects
				(font
					(size 1.27 1.27)
				)
				(justify mirror)
			)
		)
		(property "Value" ""
			(at 0 0 0)
			(layer "B.Fab")
			(effects
				(font
					(size 1.27 1.27)
				)
				(justify mirror)
			)
		)
		(duplicate_pad_numbers_are_jumpers no)
		(fp_line
			(start 0.32512 0.175006)
			(end 0.32512 -0.175006)
			(stroke
				(width 0.1)
				(type default)
			)
			(layer "B.Fab")
		)
		(fp_line
			(start 0.32512 -0.175006)
			(end -0.32512 -0.175006)
			(stroke
				(width 0.1)
				(type default)
			)
			(layer "B.Fab")
		)
		(fp_line
			(start -0.32512 0.175006)
			(end 0.32512 0.175006)
			(stroke
				(width 0.1)
				(type default)
			)
			(layer "B.Fab")
		)
		(fp_line
			(start -0.32512 -0.175006)
			(end -0.32512 0.175006)
			(stroke
				(width 0.1)
				(type default)
			)
			(layer "B.Fab")
		)
		(pad "1" smd rect
			(at 0.2667 0)
			(size 0.3048 0.381)
			(layers "B.Cu" "B.Mask" "B.Paste")
			(net "SMB_RT_CPU0_P0_R_SCL")
		)
		(pad "2" smd rect
			(at -0.2667 0 180)
			(size 0.3048 0.381)
			(layers "B.Cu" "B.Mask" "B.Paste")
			(net "SMB_RT_CPU0_P0_R2_SCL")
		)
	)
	(footprint ""
		(layer "B.Cu")
		(at 348.818454 -267.52931)
		(property "Reference" "C2231"
			(at 0 0 0)
			(layer "B.SilkS")
			(hide yes)
			(effects
				(font
					(size 1.27 1.27)
				)
				(justify mirror)
			)
		)
		(property "Value" ""
			(at 0 0 0)
			(layer "B.Fab")
			(effects
				(font
					(size 1.27 1.27)
				)
				(justify mirror)
			)
		)
		(duplicate_pad_numbers_are_jumpers no)
		(fp_line
			(start -0.7874 -0.4064)
			(end -0.7874 0.4064)
			(stroke
				(width 0.1524)
				(type default)
			)
			(layer "B.SilkS")
		)
		(fp_line
			(start -0.7874 0.4064)
			(end 0.7874 0.4064)
			(stroke
				(width 0.1524)
				(type default)
			)
			(layer "B.SilkS")
		)
		(fp_line
			(start 0.7874 -0.4064)
			(end -0.7874 -0.4064)
			(stroke
				(width 0.1524)
				(type default)
			)
			(layer "B.SilkS")
		)
		(fp_line
			(start 0.7874 0.4064)
			(end 0.7874 -0.4064)
			(stroke
				(width 0.1524)
				(type default)
			)
			(layer "B.SilkS")
		)
		(fp_line
			(start -0.67945 -0.3048)
			(end -0.67945 0.3048)
			(stroke
				(width 0.1)
				(type default)
			)
			(layer "B.Fab")
		)
		(fp_line
			(start -0.67945 0.3048)
			(end -0.120396 0.3048)
			(stroke
				(width 0.1)
				(type default)
			)
			(layer "B.Fab")
		)
		(fp_line
			(start -0.12065 -0.3048)
			(end -0.67945 -0.3048)
			(stroke
				(width 0.1)
				(type default)
			)
			(layer "B.Fab")
		)
		(fp_line
			(start -0.12065 -0.2794)
			(end -0.12065 -0.3048)
			(stroke
				(width 0.1)
				(type default)
			)
			(layer "B.Fab")
		)
		(fp_line
			(start -0.120396 0.2794)
			(end 0.12065 0.2794)
			(stroke
				(width 0.1)
				(type default)
			)
			(layer "B.Fab")
		)
		(fp_line
			(start -0.120396 0.3048)
			(end -0.120396 0.2794)
			(stroke
				(width 0.1)
				(type default)
			)
			(layer "B.Fab")
		)
		(fp_line
			(start 0.12065 -0.305054)
			(end 0.12065 -0.2794)
			(stroke
				(width 0.1)
				(type default)
			)
			(layer "B.Fab")
		)
		(fp_line
			(start 0.12065 -0.2794)
			(end -0.12065 -0.2794)
			(stroke
				(width 0.1)
				(type default)
			)
			(layer "B.Fab")
		)
		(fp_line
			(start 0.12065 0.2794)
			(end 0.12065 0.3048)
			(stroke
				(width 0.1)
				(type default)
			)
			(layer "B.Fab")
		)
		(fp_line
			(start 0.12065 0.3048)
			(end 0.67945 0.3048)
			(stroke
				(width 0.1)
				(type default)
			)
			(layer "B.Fab")
		)
		(fp_line
			(start 0.67945 -0.305054)
			(end 0.12065 -0.305054)
			(stroke
				(width 0.1)
				(type default)
			)
			(layer "B.Fab")
		)
		(fp_line
			(start 0.67945 0.3048)
			(end 0.67945 -0.305054)
			(stroke
				(width 0.1)
				(type default)
			)
			(layer "B.Fab")
		)
		(pad "1" smd circle
			(at 0.40005 0 180)
			(size 0 0)
			(layers "B.Cu" "B.Mask" "B.Paste")
			(net "PVDDCR_CPU1_P0")
		)
		(pad "2" smd circle
			(at -0.40005 0 180)
			(size 0 0)
			(layers "B.Cu" "B.Mask" "B.Paste")
			(net "GND")
		)
	)
	(footprint ""
		(layer "B.Cu")
		(at 180.166518 -415.616644 90)
		(property "Reference" "R2927"
			(at 0 0 90)
			(layer "B.SilkS")
			(hide yes)
			(effects
				(font
					(size 1.27 1.27)
				)
				(justify mirror)
			)
		)
		(property "Value" ""
			(at 0 0 90)
			(layer "B.Fab")
			(effects
				(font
					(size 1.27 1.27)
				)
				(justify mirror)
			)
		)
		(duplicate_pad_numbers_are_jumpers no)
		(fp_line
			(start 0.7874 -0.4064)
			(end -0.7874 -0.4064)
			(stroke
				(width 0.1524)
				(type default)
			)
			(layer "B.SilkS")
		)
		(fp_line
			(start -0.7874 -0.4064)
			(end -0.7874 0.4064)
			(stroke
				(width 0.1524)
				(type default)
			)
			(layer "B.SilkS")
		)
		(fp_line
			(start 0.7874 0.4064)
			(end 0.7874 -0.4064)
			(stroke
				(width 0.1524)
				(type default)
			)
			(layer "B.SilkS")
		)
		(fp_line
			(start -0.7874 0.4064)
			(end 0.7874 0.4064)
			(stroke
				(width 0.1524)
				(type default)
			)
			(layer "B.SilkS")
		)
		(fp_line
			(start 0.67945 -0.305054)
			(end 0.12065 -0.305054)
			(stroke
				(width 0.1)
				(type default)
			)
			(layer "B.Fab")
		)
		(fp_line
			(start 0.12065 -0.305054)
			(end 0.12065 -0.2794)
			(stroke
				(width 0.1)
				(type default)
			)
			(layer "B.Fab")
		)
		(fp_line
			(start -0.12065 -0.3048)
			(end -0.67945 -0.3048)
			(stroke
				(width 0.1)
				(type default)
			)
			(layer "B.Fab")
		)
		(fp_line
			(start -0.67945 -0.3048)
			(end -0.67945 0.3048)
			(stroke
				(width 0.1)
				(type default)
			)
			(layer "B.Fab")
		)
		(fp_line
			(start 0.12065 -0.2794)
			(end -0.12065 -0.2794)
			(stroke
				(width 0.1)
				(type default)
			)
			(layer "B.Fab")
		)
		(fp_line
			(start -0.12065 -0.2794)
			(end -0.12065 -0.3048)
			(stroke
				(width 0.1)
				(type default)
			)
			(layer "B.Fab")
		)
		(fp_line
			(start 0.12065 0.2794)
			(end 0.12065 0.3048)
			(stroke
				(width 0.1)
				(type default)
			)
			(layer "B.Fab")
		)
		(fp_line
			(start -0.120396 0.2794)
			(end 0.12065 0.2794)
			(stroke
				(width 0.1)
				(type default)
			)
			(layer "B.Fab")
		)
		(fp_line
			(start 0.67945 0.3048)
			(end 0.67945 -0.305054)
			(stroke
				(width 0.1)
				(type default)
			)
			(layer "B.Fab")
		)
		(fp_line
			(start 0.12065 0.3048)
			(end 0.67945 0.3048)
			(stroke
				(width 0.1)
				(type default)
			)
			(layer "B.Fab")
		)
		(fp_line
			(start -0.120396 0.3048)
			(end -0.120396 0.2794)
			(stroke
				(width 0.1)
				(type default)
			)
			(layer "B.Fab")
		)
		(fp_line
			(start -0.67945 0.3048)
			(end -0.120396 0.3048)
			(stroke
				(width 0.1)
				(type default)
			)
			(layer "B.Fab")
		)
		(pad "1" smd circle
			(at 0.40005 0 270)
			(size 0 0)
			(layers "B.Cu" "B.Mask" "B.Paste")
			(net "RST_SWB_BIC_BUF_R_N")
		)
		(pad "2" smd circle
			(at -0.40005 0 270)
			(size 0 0)
			(layers "B.Cu" "B.Mask" "B.Paste")
			(net "GND")
		)
	)
	(footprint ""
		(layer "B.Cu")
		(at 104.307386 -251.781564)
		(property "Reference" "C2411"
			(at 0 0 0)
			(layer "B.SilkS")
			(hide yes)
			(effects
				(font
					(size 1.27 1.27)
				)
				(justify mirror)
			)
		)
		(property "Value" ""
			(at 0 0 0)
			(layer "B.Fab")
			(effects
				(font
					(size 1.27 1.27)
				)
				(justify mirror)
			)
		)
		(duplicate_pad_numbers_are_jumpers no)
		(fp_line
			(start -0.7874 -0.4064)
			(end -0.7874 0.4064)
			(stroke
				(width 0.1524)
				(type default)
			)
			(layer "B.SilkS")
		)
		(fp_line
			(start -0.7874 0.4064)
			(end 0.7874 0.4064)
			(stroke
				(width 0.1524)
				(type default)
			)
			(layer "B.SilkS")
		)
		(fp_line
			(start 0.7874 -0.4064)
			(end -0.7874 -0.4064)
			(stroke
				(width 0.1524)
				(type default)
			)
			(layer "B.SilkS")
		)
		(fp_line
			(start 0.7874 0.4064)
			(end 0.7874 -0.4064)
			(stroke
				(width 0.1524)
				(type default)
			)
			(layer "B.SilkS")
		)
		(fp_line
			(start -0.67945 -0.3048)
			(end -0.67945 0.3048)
			(stroke
				(width 0.1)
				(type default)
			)
			(layer "B.Fab")
		)
		(fp_line
			(start -0.67945 0.3048)
			(end -0.120396 0.3048)
			(stroke
				(width 0.1)
				(type default)
			)
			(layer "B.Fab")
		)
		(fp_line
			(start -0.12065 -0.3048)
			(end -0.67945 -0.3048)
			(stroke
				(width 0.1)
				(type default)
			)
			(layer "B.Fab")
		)
		(fp_line
			(start -0.12065 -0.2794)
			(end -0.12065 -0.3048)
			(stroke
				(width 0.1)
				(type default)
			)
			(layer "B.Fab")
		)
		(fp_line
			(start -0.120396 0.2794)
			(end 0.12065 0.2794)
			(stroke
				(width 0.1)
				(type default)
			)
			(layer "B.Fab")
		)
		(fp_line
			(start -0.120396 0.3048)
			(end -0.120396 0.2794)
			(stroke
				(width 0.1)
				(type default)
			)
			(layer "B.Fab")
		)
		(fp_line
			(start 0.12065 -0.305054)
			(end 0.12065 -0.2794)
			(stroke
				(width 0.1)
				(type default)
			)
			(layer "B.Fab")
		)
		(fp_line
			(start 0.12065 -0.2794)
			(end -0.12065 -0.2794)
			(stroke
				(width 0.1)
				(type default)
			)
			(layer "B.Fab")
		)
		(fp_line
			(start 0.12065 0.2794)
			(end 0.12065 0.3048)
			(stroke
				(width 0.1)
				(type default)
			)
			(layer "B.Fab")
		)
		(fp_line
			(start 0.12065 0.3048)
			(end 0.67945 0.3048)
			(stroke
				(width 0.1)
				(type default)
			)
			(layer "B.Fab")
		)
		(fp_line
			(start 0.67945 -0.305054)
			(end 0.12065 -0.305054)
			(stroke
				(width 0.1)
				(type default)
			)
			(layer "B.Fab")
		)
		(fp_line
			(start 0.67945 0.3048)
			(end 0.67945 -0.305054)
			(stroke
				(width 0.1)
				(type default)
			)
			(layer "B.Fab")
		)
		(pad "1" smd circle
			(at 0.40005 0 180)
			(size 0 0)
			(layers "B.Cu" "B.Mask" "B.Paste")
			(net "PVDDCR_SOC_P1")
		)
		(pad "2" smd circle
			(at -0.40005 0 180)
			(size 0 0)
			(layers "B.Cu" "B.Mask" "B.Paste")
			(net "GND")
		)
	)
	(footprint ""
		(layer "B.Cu")
		(at 60.468002 -8.319262 -90)
		(property "Reference" "R3180"
			(at 0 0 90)
			(layer "B.SilkS")
			(hide yes)
			(effects
				(font
					(size 1.27 1.27)
				)
				(justify mirror)
			)
		)
		(property "Value" ""
			(at 0 0 90)
			(layer "B.Fab")
			(effects
				(font
					(size 1.27 1.27)
				)
				(justify mirror)
			)
		)
		(duplicate_pad_numbers_are_jumpers no)
		(fp_line
			(start -0.7874 0.4064)
			(end 0.7874 0.4064)
			(stroke
				(width 0.1524)
				(type default)
			)
			(layer "B.SilkS")
		)
		(fp_line
			(start 0.7874 0.4064)
			(end 0.7874 -0.4064)
			(stroke
				(width 0.1524)
				(type default)
			)
			(layer "B.SilkS")
		)
		(fp_line
			(start -0.7874 -0.4064)
			(end -0.7874 0.4064)
			(stroke
				(width 0.1524)
				(type default)
			)
			(layer "B.SilkS")
		)
		(fp_line
			(start 0.7874 -0.4064)
			(end -0.7874 -0.4064)
			(stroke
				(width 0.1524)
				(type default)
			)
			(layer "B.SilkS")
		)
		(fp_line
			(start -0.67945 0.3048)
			(end -0.120396 0.3048)
			(stroke
				(width 0.1)
				(type default)
			)
			(layer "B.Fab")
		)
		(fp_line
			(start -0.120396 0.3048)
			(end -0.120396 0.2794)
			(stroke
				(width 0.1)
				(type default)
			)
			(layer "B.Fab")
		)
		(fp_line
			(start 0.12065 0.3048)
			(end 0.67945 0.3048)
			(stroke
				(width 0.1)
				(type default)
			)
			(layer "B.Fab")
		)
		(fp_line
			(start 0.67945 0.3048)
			(end 0.67945 -0.305054)
			(stroke
				(width 0.1)
				(type default)
			)
			(layer "B.Fab")
		)
		(fp_line
			(start -0.120396 0.2794)
			(end 0.12065 0.2794)
			(stroke
				(width 0.1)
				(type default)
			)
			(layer "B.Fab")
		)
		(fp_line
			(start 0.12065 0.2794)
			(end 0.12065 0.3048)
			(stroke
				(width 0.1)
				(type default)
			)
			(layer "B.Fab")
		)
		(fp_line
			(start -0.12065 -0.2794)
			(end -0.12065 -0.3048)
			(stroke
				(width 0.1)
				(type default)
			)
			(layer "B.Fab")
		)
		(fp_line
			(start 0.12065 -0.2794)
			(end -0.12065 -0.2794)
			(stroke
				(width 0.1)
				(type default)
			)
			(layer "B.Fab")
		)
		(fp_line
			(start -0.67945 -0.3048)
			(end -0.67945 0.3048)
			(stroke
				(width 0.1)
				(type default)
			)
			(layer "B.Fab")
		)
		(fp_line
			(start -0.12065 -0.3048)
			(end -0.67945 -0.3048)
			(stroke
				(width 0.1)
				(type default)
			)
			(layer "B.Fab")
		)
		(fp_line
			(start 0.12065 -0.305054)
			(end 0.12065 -0.2794)
			(stroke
				(width 0.1)
				(type default)
			)
			(layer "B.Fab")
		)
		(fp_line
			(start 0.67945 -0.305054)
			(end 0.12065 -0.305054)
			(stroke
				(width 0.1)
				(type default)
			)
			(layer "B.Fab")
		)
		(pad "1" smd circle
			(at 0.40005 0 90)
			(size 0 0)
			(layers "B.Cu" "B.Mask" "B.Paste")
			(net "OCP_V3_2_PRSNTA_R_N")
		)
		(pad "2" smd circle
			(at -0.40005 0 90)
			(size 0 0)
			(layers "B.Cu" "B.Mask" "B.Paste")
			(net "GND")
		)
	)
	(footprint ""
		(layer "B.Cu")
		(at 203.87818 -79.444342)
		(property "Reference" "C1826"
			(at 0 0 0)
			(layer "B.SilkS")
			(hide yes)
			(effects
				(font
					(size 1.27 1.27)
				)
				(justify mirror)
			)
		)
		(property "Value" ""
			(at 0 0 0)
			(layer "B.Fab")
			(effects
				(font
					(size 1.27 1.27)
				)
				(justify mirror)
			)
		)
		(duplicate_pad_numbers_are_jumpers no)
		(fp_line
			(start -0.7874 -0.4064)
			(end -0.7874 0.4064)
			(stroke
				(width 0.1524)
				(type default)
			)
			(layer "B.SilkS")
		)
		(fp_line
			(start -0.7874 0.4064)
			(end 0.7874 0.4064)
			(stroke
				(width 0.1524)
				(type default)
			)
			(layer "B.SilkS")
		)
		(fp_line
			(start 0.7874 -0.4064)
			(end -0.7874 -0.4064)
			(stroke
				(width 0.1524)
				(type default)
			)
			(layer "B.SilkS")
		)
		(fp_line
			(start 0.7874 0.4064)
			(end 0.7874 -0.4064)
			(stroke
				(width 0.1524)
				(type default)
			)
			(layer "B.SilkS")
		)
		(fp_line
			(start -0.67945 -0.3048)
			(end -0.67945 0.3048)
			(stroke
				(width 0.1)
				(type default)
			)
			(layer "B.Fab")
		)
		(fp_line
			(start -0.67945 0.3048)
			(end -0.120396 0.3048)
			(stroke
				(width 0.1)
				(type default)
			)
			(layer "B.Fab")
		)
		(fp_line
			(start -0.12065 -0.3048)
			(end -0.67945 -0.3048)
			(stroke
				(width 0.1)
				(type default)
			)
			(layer "B.Fab")
		)
		(fp_line
			(start -0.12065 -0.2794)
			(end -0.12065 -0.3048)
			(stroke
				(width 0.1)
				(type default)
			)
			(layer "B.Fab")
		)
		(fp_line
			(start -0.120396 0.2794)
			(end 0.12065 0.2794)
			(stroke
				(width 0.1)
				(type default)
			)
			(layer "B.Fab")
		)
		(fp_line
			(start -0.120396 0.3048)
			(end -0.120396 0.2794)
			(stroke
				(width 0.1)
				(type default)
			)
			(layer "B.Fab")
		)
		(fp_line
			(start 0.12065 -0.305054)
			(end 0.12065 -0.2794)
			(stroke
				(width 0.1)
				(type default)
			)
			(layer "B.Fab")
		)
		(fp_line
			(start 0.12065 -0.2794)
			(end -0.12065 -0.2794)
			(stroke
				(width 0.1)
				(type default)
			)
			(layer "B.Fab")
		)
		(fp_line
			(start 0.12065 0.2794)
			(end 0.12065 0.3048)
			(stroke
				(width 0.1)
				(type default)
			)
			(layer "B.Fab")
		)
		(fp_line
			(start 0.12065 0.3048)
			(end 0.67945 0.3048)
			(stroke
				(width 0.1)
				(type default)
			)
			(layer "B.Fab")
		)
		(fp_line
			(start 0.67945 -0.305054)
			(end 0.12065 -0.305054)
			(stroke
				(width 0.1)
				(type default)
			)
			(layer "B.Fab")
		)
		(fp_line
			(start 0.67945 0.3048)
			(end 0.67945 -0.305054)
			(stroke
				(width 0.1)
				(type default)
			)
			(layer "B.Fab")
		)
		(pad "1" smd circle
			(at 0.40005 0 180)
			(size 0 0)
			(layers "B.Cu" "B.Mask" "B.Paste")
			(net "P3V3_AUX")
		)
		(pad "2" smd circle
			(at -0.40005 0 180)
			(size 0 0)
			(layers "B.Cu" "B.Mask" "B.Paste")
			(net "GND")
		)
	)
	(footprint ""
		(layer "B.Cu")
		(at 311.277 -358.14 -90)
		(property "Reference" "PR32"
			(at 0 0 90)
			(layer "B.SilkS")
			(hide yes)
			(effects
				(font
					(size 1.27 1.27)
				)
				(justify mirror)
			)
		)
		(property "Value" ""
			(at 0 0 90)
			(layer "B.Fab")
			(effects
				(font
					(size 1.27 1.27)
				)
				(justify mirror)
			)
		)
		(duplicate_pad_numbers_are_jumpers no)
		(fp_line
			(start -0.7874 0.4064)
			(end 0.7874 0.4064)
			(stroke
				(width 0.1524)
				(type default)
			)
			(layer "B.SilkS")
		)
		(fp_line
			(start 0.7874 0.4064)
			(end 0.7874 -0.4064)
			(stroke
				(width 0.1524)
				(type default)
			)
			(layer "B.SilkS")
		)
		(fp_line
			(start -0.7874 -0.4064)
			(end -0.7874 0.4064)
			(stroke
				(width 0.1524)
				(type default)
			)
			(layer "B.SilkS")
		)
		(fp_line
			(start 0.7874 -0.4064)
			(end -0.7874 -0.4064)
			(stroke
				(width 0.1524)
				(type default)
			)
			(layer "B.SilkS")
		)
		(fp_line
			(start -0.67945 0.3048)
			(end -0.120396 0.3048)
			(stroke
				(width 0.1)
				(type default)
			)
			(layer "B.Fab")
		)
		(fp_line
			(start -0.120396 0.3048)
			(end -0.120396 0.2794)
			(stroke
				(width 0.1)
				(type default)
			)
			(layer "B.Fab")
		)
		(fp_line
			(start 0.12065 0.3048)
			(end 0.67945 0.3048)
			(stroke
				(width 0.1)
				(type default)
			)
			(layer "B.Fab")
		)
		(fp_line
			(start 0.67945 0.3048)
			(end 0.67945 -0.305054)
			(stroke
				(width 0.1)
				(type default)
			)
			(layer "B.Fab")
		)
		(fp_line
			(start -0.120396 0.2794)
			(end 0.12065 0.2794)
			(stroke
				(width 0.1)
				(type default)
			)
			(layer "B.Fab")
		)
		(fp_line
			(start 0.12065 0.2794)
			(end 0.12065 0.3048)
			(stroke
				(width 0.1)
				(type default)
			)
			(layer "B.Fab")
		)
		(fp_line
			(start -0.12065 -0.2794)
			(end -0.12065 -0.3048)
			(stroke
				(width 0.1)
				(type default)
			)
			(layer "B.Fab")
		)
		(fp_line
			(start 0.12065 -0.2794)
			(end -0.12065 -0.2794)
			(stroke
				(width 0.1)
				(type default)
			)
			(layer "B.Fab")
		)
		(fp_line
			(start -0.67945 -0.3048)
			(end -0.67945 0.3048)
			(stroke
				(width 0.1)
				(type default)
			)
			(layer "B.Fab")
		)
		(fp_line
			(start -0.12065 -0.3048)
			(end -0.67945 -0.3048)
			(stroke
				(width 0.1)
				(type default)
			)
			(layer "B.Fab")
		)
		(fp_line
			(start 0.12065 -0.305054)
			(end 0.12065 -0.2794)
			(stroke
				(width 0.1)
				(type default)
			)
			(layer "B.Fab")
		)
		(fp_line
			(start 0.67945 -0.305054)
			(end 0.12065 -0.305054)
			(stroke
				(width 0.1)
				(type default)
			)
			(layer "B.Fab")
		)
		(pad "1" smd circle
			(at 0.40005 0 90)
			(size 0 0)
			(layers "B.Cu" "B.Mask" "B.Paste")
			(net "NC_PVDDCR_CPU1_P0_IMON8")
		)
		(pad "2" smd circle
			(at -0.40005 0 90)
			(size 0 0)
			(layers "B.Cu" "B.Mask" "B.Paste")
			(net "GND")
		)
	)
	(footprint ""
		(layer "B.Cu")
		(at 20.480782 -411.707584 180)
		(property "Reference" "PR6820"
			(at 0 0 0)
			(layer "B.SilkS")
			(hide yes)
			(effects
				(font
					(size 1.27 1.27)
				)
				(justify mirror)
			)
		)
		(property "Value" ""
			(at 0 0 0)
			(layer "B.Fab")
			(effects
				(font
					(size 1.27 1.27)
				)
				(justify mirror)
			)
		)
		(duplicate_pad_numbers_are_jumpers no)
		(fp_line
			(start 0.7874 0.4064)
			(end 0.7874 -0.4064)
			(stroke
				(width 0.1524)
				(type default)
			)
			(layer "B.SilkS")
		)
		(fp_line
			(start 0.7874 -0.4064)
			(end -0.7874 -0.4064)
			(stroke
				(width 0.1524)
				(type default)
			)
			(layer "B.SilkS")
		)
		(fp_line
			(start -0.7874 0.4064)
			(end 0.7874 0.4064)
			(stroke
				(width 0.1524)
				(type default)
			)
			(layer "B.SilkS")
		)
		(fp_line
			(start -0.7874 -0.4064)
			(end -0.7874 0.4064)
			(stroke
				(width 0.1524)
				(type default)
			)
			(layer "B.SilkS")
		)
		(fp_line
			(start 0.67945 0.3048)
			(end 0.67945 -0.305054)
			(stroke
				(width 0.1)
				(type default)
			)
			(layer "B.Fab")
		)
		(fp_line
			(start 0.67945 -0.305054)
			(end 0.12065 -0.305054)
			(stroke
				(width 0.1)
				(type default)
			)
			(layer "B.Fab")
		)
		(fp_line
			(start 0.12065 0.3048)
			(end 0.67945 0.3048)
			(stroke
				(width 0.1)
				(type default)
			)
			(layer "B.Fab")
		)
		(fp_line
			(start 0.12065 0.2794)
			(end 0.12065 0.3048)
			(stroke
				(width 0.1)
				(type default)
			)
			(layer "B.Fab")
		)
		(fp_line
			(start 0.12065 -0.2794)
			(end -0.12065 -0.2794)
			(stroke
				(width 0.1)
				(type default)
			)
			(layer "B.Fab")
		)
		(fp_line
			(start 0.12065 -0.305054)
			(end 0.12065 -0.2794)
			(stroke
				(width 0.1)
				(type default)
			)
			(layer "B.Fab")
		)
		(fp_line
			(start -0.120396 0.3048)
			(end -0.120396 0.2794)
			(stroke
				(width 0.1)
				(type default)
			)
			(layer "B.Fab")
		)
		(fp_line
			(start -0.120396 0.2794)
			(end 0.12065 0.2794)
			(stroke
				(width 0.1)
				(type default)
			)
			(layer "B.Fab")
		)
		(fp_line
			(start -0.12065 -0.2794)
			(end -0.12065 -0.3048)
			(stroke
				(width 0.1)
				(type default)
			)
			(layer "B.Fab")
		)
		(fp_line
			(start -0.12065 -0.3048)
			(end -0.67945 -0.3048)
			(stroke
				(width 0.1)
				(type default)
			)
			(layer "B.Fab")
		)
		(fp_line
			(start -0.67945 0.3048)
			(end -0.120396 0.3048)
			(stroke
				(width 0.1)
				(type default)
			)
			(layer "B.Fab")
		)
		(fp_line
			(start -0.67945 -0.3048)
			(end -0.67945 0.3048)
			(stroke
				(width 0.1)
				(type default)
			)
			(layer "B.Fab")
		)
		(pad "1" smd circle
			(at 0.40005 0)
			(size 0 0)
			(layers "B.Cu" "B.Mask" "B.Paste")
			(net "P0V9_RETIMER_CPU1_SVID_SDA")
		)
		(pad "2" smd circle
			(at -0.40005 0)
			(size 0 0)
			(layers "B.Cu" "B.Mask" "B.Paste")
			(net "GND")
		)
	)
	(footprint ""
		(layer "B.Cu")
		(at 99.273106 -390.560052 90)
		(property "Reference" "C351"
			(at 0 0 90)
			(layer "B.SilkS")
			(hide yes)
			(effects
				(font
					(size 1.27 1.27)
				)
				(justify mirror)
			)
		)
		(property "Value" ""
			(at 0 0 90)
			(layer "B.Fab")
			(effects
				(font
					(size 1.27 1.27)
				)
				(justify mirror)
			)
		)
		(duplicate_pad_numbers_are_jumpers no)
		(fp_line
			(start 0.7874 -0.4064)
			(end -0.7874 -0.4064)
			(stroke
				(width 0.1524)
				(type default)
			)
			(layer "B.SilkS")
		)
		(fp_line
			(start -0.7874 -0.4064)
			(end -0.7874 0.4064)
			(stroke
				(width 0.1524)
				(type default)
			)
			(layer "B.SilkS")
		)
		(fp_line
			(start 0.7874 0.4064)
			(end 0.7874 -0.4064)
			(stroke
				(width 0.1524)
				(type default)
			)
			(layer "B.SilkS")
		)
		(fp_line
			(start -0.7874 0.4064)
			(end 0.7874 0.4064)
			(stroke
				(width 0.1524)
				(type default)
			)
			(layer "B.SilkS")
		)
		(fp_line
			(start 0.67945 -0.305054)
			(end 0.12065 -0.305054)
			(stroke
				(width 0.1)
				(type default)
			)
			(layer "B.Fab")
		)
		(fp_line
			(start 0.12065 -0.305054)
			(end 0.12065 -0.2794)
			(stroke
				(width 0.1)
				(type default)
			)
			(layer "B.Fab")
		)
		(fp_line
			(start -0.12065 -0.3048)
			(end -0.67945 -0.3048)
			(stroke
				(width 0.1)
				(type default)
			)
			(layer "B.Fab")
		)
		(fp_line
			(start -0.67945 -0.3048)
			(end -0.67945 0.3048)
			(stroke
				(width 0.1)
				(type default)
			)
			(layer "B.Fab")
		)
		(fp_line
			(start 0.12065 -0.2794)
			(end -0.12065 -0.2794)
			(stroke
				(width 0.1)
				(type default)
			)
			(layer "B.Fab")
		)
		(fp_line
			(start -0.12065 -0.2794)
			(end -0.12065 -0.3048)
			(stroke
				(width 0.1)
				(type default)
			)
			(layer "B.Fab")
		)
		(fp_line
			(start 0.12065 0.2794)
			(end 0.12065 0.3048)
			(stroke
				(width 0.1)
				(type default)
			)
			(layer "B.Fab")
		)
		(fp_line
			(start -0.120396 0.2794)
			(end 0.12065 0.2794)
			(stroke
				(width 0.1)
				(type default)
			)
			(layer "B.Fab")
		)
		(fp_line
			(start 0.67945 0.3048)
			(end 0.67945 -0.305054)
			(stroke
				(width 0.1)
				(type default)
			)
			(layer "B.Fab")
		)
		(fp_line
			(start 0.12065 0.3048)
			(end 0.67945 0.3048)
			(stroke
				(width 0.1)
				(type default)
			)
			(layer "B.Fab")
		)
		(fp_line
			(start -0.120396 0.3048)
			(end -0.120396 0.2794)
			(stroke
				(width 0.1)
				(type default)
			)
			(layer "B.Fab")
		)
		(fp_line
			(start -0.67945 0.3048)
			(end -0.120396 0.3048)
			(stroke
				(width 0.1)
				(type default)
			)
			(layer "B.Fab")
		)
		(pad "1" smd circle
			(at 0.40005 0 270)
			(size 0 0)
			(layers "B.Cu" "B.Mask" "B.Paste")
			(net "P0V9_CPU1_RT1_2A")
		)
		(pad "2" smd circle
			(at -0.40005 0 270)
			(size 0 0)
			(layers "B.Cu" "B.Mask" "B.Paste")
			(net "GND")
		)
	)
	(footprint ""
		(layer "B.Cu")
		(at 112.425988 -256.012442 -90)
		(property "Reference" "C3901"
			(at 0 0 90)
			(layer "B.SilkS")
			(hide yes)
			(effects
				(font
					(size 1.27 1.27)
				)
				(justify mirror)
			)
		)
		(property "Value" ""
			(at 0 0 90)
			(layer "B.Fab")
			(effects
				(font
					(size 1.27 1.27)
				)
				(justify mirror)
			)
		)
		(duplicate_pad_numbers_are_jumpers no)
		(fp_line
			(start -0.7874 0.4064)
			(end 0.7874 0.4064)
			(stroke
				(width 0.1524)
				(type default)
			)
			(layer "B.SilkS")
		)
		(fp_line
			(start 0.7874 0.4064)
			(end 0.7874 -0.4064)
			(stroke
				(width 0.1524)
				(type default)
			)
			(layer "B.SilkS")
		)
		(fp_line
			(start -0.7874 -0.4064)
			(end -0.7874 0.4064)
			(stroke
				(width 0.1524)
				(type default)
			)
			(layer "B.SilkS")
		)
		(fp_line
			(start 0.7874 -0.4064)
			(end -0.7874 -0.4064)
			(stroke
				(width 0.1524)
				(type default)
			)
			(layer "B.SilkS")
		)
		(fp_line
			(start -0.67945 0.3048)
			(end -0.120396 0.3048)
			(stroke
				(width 0.1)
				(type default)
			)
			(layer "B.Fab")
		)
		(fp_line
			(start -0.120396 0.3048)
			(end -0.120396 0.2794)
			(stroke
				(width 0.1)
				(type default)
			)
			(layer "B.Fab")
		)
		(fp_line
			(start 0.12065 0.3048)
			(end 0.67945 0.3048)
			(stroke
				(width 0.1)
				(type default)
			)
			(layer "B.Fab")
		)
		(fp_line
			(start 0.67945 0.3048)
			(end 0.67945 -0.305054)
			(stroke
				(width 0.1)
				(type default)
			)
			(layer "B.Fab")
		)
		(fp_line
			(start -0.120396 0.2794)
			(end 0.12065 0.2794)
			(stroke
				(width 0.1)
				(type default)
			)
			(layer "B.Fab")
		)
		(fp_line
			(start 0.12065 0.2794)
			(end 0.12065 0.3048)
			(stroke
				(width 0.1)
				(type default)
			)
			(layer "B.Fab")
		)
		(fp_line
			(start -0.12065 -0.2794)
			(end -0.12065 -0.3048)
			(stroke
				(width 0.1)
				(type default)
			)
			(layer "B.Fab")
		)
		(fp_line
			(start 0.12065 -0.2794)
			(end -0.12065 -0.2794)
			(stroke
				(width 0.1)
				(type default)
			)
			(layer "B.Fab")
		)
		(fp_line
			(start -0.67945 -0.3048)
			(end -0.67945 0.3048)
			(stroke
				(width 0.1)
				(type default)
			)
			(layer "B.Fab")
		)
		(fp_line
			(start -0.12065 -0.3048)
			(end -0.67945 -0.3048)
			(stroke
				(width 0.1)
				(type default)
			)
			(layer "B.Fab")
		)
		(fp_line
			(start 0.12065 -0.305054)
			(end 0.12065 -0.2794)
			(stroke
				(width 0.1)
				(type default)
			)
			(layer "B.Fab")
		)
		(fp_line
			(start 0.67945 -0.305054)
			(end 0.12065 -0.305054)
			(stroke
				(width 0.1)
				(type default)
			)
			(layer "B.Fab")
		)
		(pad "1" smd circle
			(at 0.40005 0 90)
			(size 0 0)
			(layers "B.Cu" "B.Mask" "B.Paste")
			(net "PVDDCR_SOC_P1")
		)
		(pad "2" smd circle
			(at -0.40005 0 90)
			(size 0 0)
			(layers "B.Cu" "B.Mask" "B.Paste")
			(net "GND")
		)
	)
	(footprint ""
		(layer "B.Cu")
		(at 286.952182 -346.784168 90)
		(property "Reference" "PC184_3"
			(at 0 0 90)
			(layer "B.SilkS")
			(hide yes)
			(effects
				(font
					(size 1.27 1.27)
				)
				(justify mirror)
			)
		)
		(property "Value" ""
			(at 0 0 90)
			(layer "B.Fab")
			(effects
				(font
					(size 1.27 1.27)
				)
				(justify mirror)
			)
		)
		(duplicate_pad_numbers_are_jumpers no)
		(fp_line
			(start 1.524 -0.762)
			(end -1.524 -0.762)
			(stroke
				(width 0.1524)
				(type default)
			)
			(layer "B.SilkS")
		)
		(fp_line
			(start -1.524 -0.762)
			(end -1.524 0.762)
			(stroke
				(width 0.1524)
				(type default)
			)
			(layer "B.SilkS")
		)
		(fp_line
			(start 1.524 0.762)
			(end 1.524 -0.762)
			(stroke
				(width 0.1524)
				(type default)
			)
			(layer "B.SilkS")
		)
		(fp_line
			(start -1.524 0.762)
			(end 1.524 0.762)
			(stroke
				(width 0.1524)
				(type default)
			)
			(layer "B.SilkS")
		)
		(fp_line
			(start 1.1049 -0.724916)
			(end 1.1049 0.724916)
			(stroke
				(width 0.1)
				(type default)
			)
			(layer "B.Fab")
		)
		(fp_line
			(start -1.1049 -0.724916)
			(end 1.1049 -0.724916)
			(stroke
				(width 0.1)
				(type default)
			)
			(layer "B.Fab")
		)
		(fp_line
			(start 1.1049 0.724916)
			(end -1.1049 0.724916)
			(stroke
				(width 0.1)
				(type default)
			)
			(layer "B.Fab")
		)
		(fp_line
			(start -1.1049 0.724916)
			(end -1.1049 -0.724916)
			(stroke
				(width 0.1)
				(type default)
			)
			(layer "B.Fab")
		)
		(pad "1" smd rect
			(at 0.889 0 90)
			(size 1.016 1.27)
			(layers "B.Cu" "B.Mask" "B.Paste")
			(net "SW_P12V_AUX_PVDDIO_P0_FLT")
		)
		(pad "2" smd rect
			(at -0.889 0 90)
			(size 1.016 1.27)
			(layers "B.Cu" "B.Mask" "B.Paste")
			(net "GND")
		)
	)
	(footprint ""
		(layer "B.Cu")
		(at 420.667688 -194.88531 180)
		(property "Reference" "R765"
			(at 0 0 0)
			(layer "B.SilkS")
			(hide yes)
			(effects
				(font
					(size 1.27 1.27)
				)
				(justify mirror)
			)
		)
		(property "Value" ""
			(at 0 0 0)
			(layer "B.Fab")
			(effects
				(font
					(size 1.27 1.27)
				)
				(justify mirror)
			)
		)
		(duplicate_pad_numbers_are_jumpers no)
		(fp_line
			(start 0.7874 0.4064)
			(end 0.7874 -0.4064)
			(stroke
				(width 0.1524)
				(type default)
			)
			(layer "B.SilkS")
		)
		(fp_line
			(start 0.7874 -0.4064)
			(end -0.7874 -0.4064)
			(stroke
				(width 0.1524)
				(type default)
			)
			(layer "B.SilkS")
		)
		(fp_line
			(start -0.7874 0.4064)
			(end 0.7874 0.4064)
			(stroke
				(width 0.1524)
				(type default)
			)
			(layer "B.SilkS")
		)
		(fp_line
			(start -0.7874 -0.4064)
			(end -0.7874 0.4064)
			(stroke
				(width 0.1524)
				(type default)
			)
			(layer "B.SilkS")
		)
		(fp_line
			(start 0.67945 0.3048)
			(end 0.67945 -0.305054)
			(stroke
				(width 0.1)
				(type default)
			)
			(layer "B.Fab")
		)
		(fp_line
			(start 0.67945 -0.305054)
			(end 0.12065 -0.305054)
			(stroke
				(width 0.1)
				(type default)
			)
			(layer "B.Fab")
		)
		(fp_line
			(start 0.12065 0.3048)
			(end 0.67945 0.3048)
			(stroke
				(width 0.1)
				(type default)
			)
			(layer "B.Fab")
		)
		(fp_line
			(start 0.12065 0.2794)
			(end 0.12065 0.3048)
			(stroke
				(width 0.1)
				(type default)
			)
			(layer "B.Fab")
		)
		(fp_line
			(start 0.12065 -0.2794)
			(end -0.12065 -0.2794)
			(stroke
				(width 0.1)
				(type default)
			)
			(layer "B.Fab")
		)
		(fp_line
			(start 0.12065 -0.305054)
			(end 0.12065 -0.2794)
			(stroke
				(width 0.1)
				(type default)
			)
			(layer "B.Fab")
		)
		(fp_line
			(start -0.120396 0.3048)
			(end -0.120396 0.2794)
			(stroke
				(width 0.1)
				(type default)
			)
			(layer "B.Fab")
		)
		(fp_line
			(start -0.120396 0.2794)
			(end 0.12065 0.2794)
			(stroke
				(width 0.1)
				(type default)
			)
			(layer "B.Fab")
		)
		(fp_line
			(start -0.12065 -0.2794)
			(end -0.12065 -0.3048)
			(stroke
				(width 0.1)
				(type default)
			)
			(layer "B.Fab")
		)
		(fp_line
			(start -0.12065 -0.3048)
			(end -0.67945 -0.3048)
			(stroke
				(width 0.1)
				(type default)
			)
			(layer "B.Fab")
		)
		(fp_line
			(start -0.67945 0.3048)
			(end -0.120396 0.3048)
			(stroke
				(width 0.1)
				(type default)
			)
			(layer "B.Fab")
		)
		(fp_line
			(start -0.67945 -0.3048)
			(end -0.67945 0.3048)
			(stroke
				(width 0.1)
				(type default)
			)
			(layer "B.Fab")
		)
		(pad "1" smd circle
			(at 0.40005 0)
			(size 0 0)
			(layers "B.Cu" "B.Mask" "B.Paste")
			(net "PD_CHH_CPU0_DIMM_SAA")
		)
		(pad "2" smd circle
			(at -0.40005 0)
			(size 0 0)
			(layers "B.Cu" "B.Mask" "B.Paste")
			(net "GND")
		)
	)
	(footprint ""
		(layer "B.Cu")
		(at 196.977 -112.395)
		(property "Reference" "R6854"
			(at 0 0 0)
			(layer "B.SilkS")
			(hide yes)
			(effects
				(font
					(size 1.27 1.27)
				)
				(justify mirror)
			)
		)
		(property "Value" ""
			(at 0 0 0)
			(layer "B.Fab")
			(effects
				(font
					(size 1.27 1.27)
				)
				(justify mirror)
			)
		)
		(duplicate_pad_numbers_are_jumpers no)
		(fp_line
			(start -0.7874 -0.4064)
			(end -0.7874 0.4064)
			(stroke
				(width 0.1524)
				(type default)
			)
			(layer "B.SilkS")
		)
		(fp_line
			(start -0.7874 0.4064)
			(end 0.7874 0.4064)
			(stroke
				(width 0.1524)
				(type default)
			)
			(layer "B.SilkS")
		)
		(fp_line
			(start 0.7874 -0.4064)
			(end -0.7874 -0.4064)
			(stroke
				(width 0.1524)
				(type default)
			)
			(layer "B.SilkS")
		)
		(fp_line
			(start 0.7874 0.4064)
			(end 0.7874 -0.4064)
			(stroke
				(width 0.1524)
				(type default)
			)
			(layer "B.SilkS")
		)
		(fp_line
			(start -0.67945 -0.3048)
			(end -0.67945 0.3048)
			(stroke
				(width 0.1)
				(type default)
			)
			(layer "B.Fab")
		)
		(fp_line
			(start -0.67945 0.3048)
			(end -0.120396 0.3048)
			(stroke
				(width 0.1)
				(type default)
			)
			(layer "B.Fab")
		)
		(fp_line
			(start -0.12065 -0.3048)
			(end -0.67945 -0.3048)
			(stroke
				(width 0.1)
				(type default)
			)
			(layer "B.Fab")
		)
		(fp_line
			(start -0.12065 -0.2794)
			(end -0.12065 -0.3048)
			(stroke
				(width 0.1)
				(type default)
			)
			(layer "B.Fab")
		)
		(fp_line
			(start -0.120396 0.2794)
			(end 0.12065 0.2794)
			(stroke
				(width 0.1)
				(type default)
			)
			(layer "B.Fab")
		)
		(fp_line
			(start -0.120396 0.3048)
			(end -0.120396 0.2794)
			(stroke
				(width 0.1)
				(type default)
			)
			(layer "B.Fab")
		)
		(fp_line
			(start 0.12065 -0.305054)
			(end 0.12065 -0.2794)
			(stroke
				(width 0.1)
				(type default)
			)
			(layer "B.Fab")
		)
		(fp_line
			(start 0.12065 -0.2794)
			(end -0.12065 -0.2794)
			(stroke
				(width 0.1)
				(type default)
			)
			(layer "B.Fab")
		)
		(fp_line
			(start 0.12065 0.2794)
			(end 0.12065 0.3048)
			(stroke
				(width 0.1)
				(type default)
			)
			(layer "B.Fab")
		)
		(fp_line
			(start 0.12065 0.3048)
			(end 0.67945 0.3048)
			(stroke
				(width 0.1)
				(type default)
			)
			(layer "B.Fab")
		)
		(fp_line
			(start 0.67945 -0.305054)
			(end 0.12065 -0.305054)
			(stroke
				(width 0.1)
				(type default)
			)
			(layer "B.Fab")
		)
		(fp_line
			(start 0.67945 0.3048)
			(end 0.67945 -0.305054)
			(stroke
				(width 0.1)
				(type default)
			)
			(layer "B.Fab")
		)
		(pad "1" smd circle
			(at 0.40005 0 180)
			(size 0 0)
			(layers "B.Cu" "B.Mask" "B.Paste")
			(net "P0V9_RETIMER_CPU0_EN")
		)
		(pad "2" smd circle
			(at -0.40005 0 180)
			(size 0 0)
			(layers "B.Cu" "B.Mask" "B.Paste")
			(net "P0V9_RETIMER_CPU0_EN_R2")
		)
	)
	(footprint ""
		(layer "B.Cu")
		(at 307.368194 -192.660016)
		(property "Reference" "C89"
			(at 0 0 0)
			(layer "B.SilkS")
			(hide yes)
			(effects
				(font
					(size 1.27 1.27)
				)
				(justify mirror)
			)
		)
		(property "Value" ""
			(at 0 0 0)
			(layer "B.Fab")
			(effects
				(font
					(size 1.27 1.27)
				)
				(justify mirror)
			)
		)
		(duplicate_pad_numbers_are_jumpers no)
		(fp_line
			(start -1.524 -0.762)
			(end -1.524 0.762)
			(stroke
				(width 0.1524)
				(type default)
			)
			(layer "B.SilkS")
		)
		(fp_line
			(start -1.524 0.762)
			(end 1.524 0.762)
			(stroke
				(width 0.1524)
				(type default)
			)
			(layer "B.SilkS")
		)
		(fp_line
			(start 1.524 -0.762)
			(end -1.524 -0.762)
			(stroke
				(width 0.1524)
				(type default)
			)
			(layer "B.SilkS")
		)
		(fp_line
			(start 1.524 0.762)
			(end 1.524 -0.762)
			(stroke
				(width 0.1524)
				(type default)
			)
			(layer "B.SilkS")
		)
		(fp_line
			(start -1.1049 -0.724916)
			(end 1.1049 -0.724916)
			(stroke
				(width 0.1)
				(type default)
			)
			(layer "B.Fab")
		)
		(fp_line
			(start -1.1049 0.724916)
			(end -1.1049 -0.724916)
			(stroke
				(width 0.1)
				(type default)
			)
			(layer "B.Fab")
		)
		(fp_line
			(start 1.1049 -0.724916)
			(end 1.1049 0.724916)
			(stroke
				(width 0.1)
				(type default)
			)
			(layer "B.Fab")
		)
		(fp_line
			(start 1.1049 0.724916)
			(end -1.1049 0.724916)
			(stroke
				(width 0.1)
				(type default)
			)
			(layer "B.Fab")
		)
		(pad "1" smd rect
			(at 0.889 0)
			(size 1.016 1.27)
			(layers "B.Cu" "B.Mask" "B.Paste")
			(net "P12V_MEM_CPU0")
		)
		(pad "2" smd rect
			(at -0.889 0)
			(size 1.016 1.27)
			(layers "B.Cu" "B.Mask" "B.Paste")
			(net "GND")
		)
	)
	(footprint ""
		(layer "B.Cu")
		(at 411.546294 -396.393162 -90)
		(property "Reference" "C673"
			(at 0 0 90)
			(layer "B.SilkS")
			(hide yes)
			(effects
				(font
					(size 1.27 1.27)
				)
				(justify mirror)
			)
		)
		(property "Value" ""
			(at 0 0 90)
			(layer "B.Fab")
			(effects
				(font
					(size 1.27 1.27)
				)
				(justify mirror)
			)
		)
		(duplicate_pad_numbers_are_jumpers no)
		(fp_line
			(start -0.299974 0.150114)
			(end 0.299974 0.150114)
			(stroke
				(width 0.1)
				(type default)
			)
			(layer "B.Fab")
		)
		(fp_line
			(start 0.299974 0.150114)
			(end 0.299974 -0.150114)
			(stroke
				(width 0.1)
				(type default)
			)
			(layer "B.Fab")
		)
		(fp_line
			(start -0.299974 -0.150114)
			(end -0.299974 0.150114)
			(stroke
				(width 0.1)
				(type default)
			)
			(layer "B.Fab")
		)
		(fp_line
			(start 0.299974 -0.150114)
			(end -0.299974 -0.150114)
			(stroke
				(width 0.1)
				(type default)
			)
			(layer "B.Fab")
		)
		(pad "1" smd rect
			(at 0.2667 0 90)
			(size 0.3048 0.381)
			(layers "B.Cu" "B.Mask" "B.Paste")
			(net "P1V8_CPU0_RT2_1A")
		)
		(pad "2" smd rect
			(at -0.2667 0 90)
			(size 0.3048 0.381)
			(layers "B.Cu" "B.Mask" "B.Paste")
			(net "GND")
		)
	)
	(footprint ""
		(layer "B.Cu")
		(at 7.62 -383.032 -90)
		(property "Reference" "PR6625"
			(at 0 0 90)
			(layer "B.SilkS")
			(hide yes)
			(effects
				(font
					(size 1.27 1.27)
				)
				(justify mirror)
			)
		)
		(property "Value" ""
			(at 0 0 90)
			(layer "B.Fab")
			(effects
				(font
					(size 1.27 1.27)
				)
				(justify mirror)
			)
		)
		(duplicate_pad_numbers_are_jumpers no)
		(fp_line
			(start -1.2954 0.5842)
			(end 1.2954 0.5842)
			(stroke
				(width 0.1524)
				(type default)
			)
			(layer "B.SilkS")
		)
		(fp_line
			(start 1.2954 0.5842)
			(end 1.2954 -0.5842)
			(stroke
				(width 0.1524)
				(type default)
			)
			(layer "B.SilkS")
		)
		(fp_line
			(start -1.2954 -0.5842)
			(end -1.2954 0.5842)
			(stroke
				(width 0.1524)
				(type default)
			)
			(layer "B.SilkS")
		)
		(fp_line
			(start 1.2954 -0.5842)
			(end -1.2954 -0.5842)
			(stroke
				(width 0.1524)
				(type default)
			)
			(layer "B.SilkS")
		)
		(fp_line
			(start -0.8636 0.4572)
			(end 0.8636 0.4572)
			(stroke
				(width 0.1)
				(type default)
			)
			(layer "B.Fab")
		)
		(fp_line
			(start 0.8636 0.4572)
			(end 0.8636 0.4318)
			(stroke
				(width 0.1)
				(type default)
			)
			(layer "B.Fab")
		)
		(fp_line
			(start 0.8636 0.4318)
			(end 0.8636 0.4064)
			(stroke
				(width 0.1)
				(type default)
			)
			(layer "B.Fab")
		)
		(fp_line
			(start -1.1938 0.4064)
			(end -0.8636 0.4064)
			(stroke
				(width 0.1)
				(type default)
			)
			(layer "B.Fab")
		)
		(fp_line
			(start -0.8636 0.4064)
			(end -0.8636 0.4572)
			(stroke
				(width 0.1)
				(type default)
			)
			(layer "B.Fab")
		)
		(fp_line
			(start 0.8636 0.4064)
			(end 1.1938 0.4064)
			(stroke
				(width 0.1)
				(type default)
			)
			(layer "B.Fab")
		)
		(fp_line
			(start 1.1938 0.4064)
			(end 1.1938 -0.406654)
			(stroke
				(width 0.1)
				(type default)
			)
			(layer "B.Fab")
		)
		(fp_line
			(start -1.1938 -0.406654)
			(end -1.1938 0.4064)
			(stroke
				(width 0.1)
				(type default)
			)
			(layer "B.Fab")
		)
		(fp_line
			(start -0.8636 -0.406654)
			(end -1.1938 -0.406654)
			(stroke
				(width 0.1)
				(type default)
			)
			(layer "B.Fab")
		)
		(fp_line
			(start 0.8636 -0.406654)
			(end 0.8636 -0.4572)
			(stroke
				(width 0.1)
				(type default)
			)
			(layer "B.Fab")
		)
		(fp_line
			(start 1.1938 -0.406654)
			(end 0.8636 -0.406654)
			(stroke
				(width 0.1)
				(type default)
			)
			(layer "B.Fab")
		)
		(fp_line
			(start -0.8636 -0.4572)
			(end -0.8636 -0.406654)
			(stroke
				(width 0.1)
				(type default)
			)
			(layer "B.Fab")
		)
		(fp_line
			(start 0.8636 -0.4572)
			(end -0.8636 -0.4572)
			(stroke
				(width 0.1)
				(type default)
			)
			(layer "B.Fab")
		)
		(pad "1" smd rect
			(at 0.7366 0 180)
			(size 0.7112 0.8128)
			(layers "B.Cu" "B.Mask" "B.Paste")
			(net "P0V9_CPU1_RT_2D")
		)
		(pad "2" smd rect
			(at -0.7366 0 180)
			(size 0.7112 0.8128)
			(layers "B.Cu" "B.Mask" "B.Paste")
			(net "GND")
		)
	)
	(footprint ""
		(layer "B.Cu")
		(at 347.624908 -169.787062 90)
		(property "Reference" "PC500_1"
			(at 0 0 90)
			(layer "B.SilkS")
			(hide yes)
			(effects
				(font
					(size 1.27 1.27)
				)
				(justify mirror)
			)
		)
		(property "Value" ""
			(at 0 0 90)
			(layer "B.Fab")
			(effects
				(font
					(size 1.27 1.27)
				)
				(justify mirror)
			)
		)
		(duplicate_pad_numbers_are_jumpers no)
		(fp_line
			(start 1.524 -0.762)
			(end -1.524 -0.762)
			(stroke
				(width 0.1524)
				(type default)
			)
			(layer "B.SilkS")
		)
		(fp_line
			(start -1.524 -0.762)
			(end -1.524 0.762)
			(stroke
				(width 0.1524)
				(type default)
			)
			(layer "B.SilkS")
		)
		(fp_line
			(start 1.524 0.762)
			(end 1.524 -0.762)
			(stroke
				(width 0.1524)
				(type default)
			)
			(layer "B.SilkS")
		)
		(fp_line
			(start -1.524 0.762)
			(end 1.524 0.762)
			(stroke
				(width 0.1524)
				(type default)
			)
			(layer "B.SilkS")
		)
		(fp_line
			(start 1.1049 -0.724916)
			(end 1.1049 0.724916)
			(stroke
				(width 0.1)
				(type default)
			)
			(layer "B.Fab")
		)
		(fp_line
			(start -1.1049 -0.724916)
			(end 1.1049 -0.724916)
			(stroke
				(width 0.1)
				(type default)
			)
			(layer "B.Fab")
		)
		(fp_line
			(start 1.1049 0.724916)
			(end -1.1049 0.724916)
			(stroke
				(width 0.1)
				(type default)
			)
			(layer "B.Fab")
		)
		(fp_line
			(start -1.1049 0.724916)
			(end -1.1049 -0.724916)
			(stroke
				(width 0.1)
				(type default)
			)
			(layer "B.Fab")
		)
		(pad "1" smd rect
			(at 0.889 0 90)
			(size 1.016 1.27)
			(layers "B.Cu" "B.Mask" "B.Paste")
			(net "PVDDCR_CPU0_P0")
		)
		(pad "2" smd rect
			(at -0.889 0 90)
			(size 1.016 1.27)
			(layers "B.Cu" "B.Mask" "B.Paste")
			(net "GND")
		)
	)
	(footprint ""
		(layer "B.Cu")
		(at 326.052942 -391.2616 180)
		(property "Reference" "R6821"
			(at 0 0 0)
			(layer "B.SilkS")
			(hide yes)
			(effects
				(font
					(size 1.27 1.27)
				)
				(justify mirror)
			)
		)
		(property "Value" ""
			(at 0 0 0)
			(layer "B.Fab")
			(effects
				(font
					(size 1.27 1.27)
				)
				(justify mirror)
			)
		)
		(duplicate_pad_numbers_are_jumpers no)
		(fp_line
			(start 0.32512 0.175006)
			(end 0.32512 -0.175006)
			(stroke
				(width 0.1)
				(type default)
			)
			(layer "B.Fab")
		)
		(fp_line
			(start 0.32512 -0.175006)
			(end -0.32512 -0.175006)
			(stroke
				(width 0.1)
				(type default)
			)
			(layer "B.Fab")
		)
		(fp_line
			(start -0.32512 0.175006)
			(end 0.32512 0.175006)
			(stroke
				(width 0.1)
				(type default)
			)
			(layer "B.Fab")
		)
		(fp_line
			(start -0.32512 -0.175006)
			(end -0.32512 0.175006)
			(stroke
				(width 0.1)
				(type default)
			)
			(layer "B.Fab")
		)
		(pad "1" smd rect
			(at 0.2667 0)
			(size 0.3048 0.381)
			(layers "B.Cu" "B.Mask" "B.Paste")
			(net "NCF_CPU0_P0_GND")
		)
		(pad "2" smd rect
			(at -0.2667 0 180)
			(size 0.3048 0.381)
			(layers "B.Cu" "B.Mask" "B.Paste")
			(net "GND")
		)
	)
	(footprint ""
		(layer "B.Cu")
		(at 416.346132 -396.393162 -90)
		(property "Reference" "C794"
			(at 0 0 90)
			(layer "B.SilkS")
			(hide yes)
			(effects
				(font
					(size 1.27 1.27)
				)
				(justify mirror)
			)
		)
		(property "Value" ""
			(at 0 0 90)
			(layer "B.Fab")
			(effects
				(font
					(size 1.27 1.27)
				)
				(justify mirror)
			)
		)
		(duplicate_pad_numbers_are_jumpers no)
		(fp_line
			(start -0.299974 0.150114)
			(end 0.299974 0.150114)
			(stroke
				(width 0.1)
				(type default)
			)
			(layer "B.Fab")
		)
		(fp_line
			(start 0.299974 0.150114)
			(end 0.299974 -0.150114)
			(stroke
				(width 0.1)
				(type default)
			)
			(layer "B.Fab")
		)
		(fp_line
			(start -0.299974 -0.150114)
			(end -0.299974 0.150114)
			(stroke
				(width 0.1)
				(type default)
			)
			(layer "B.Fab")
		)
		(fp_line
			(start 0.299974 -0.150114)
			(end -0.299974 -0.150114)
			(stroke
				(width 0.1)
				(type default)
			)
			(layer "B.Fab")
		)
		(pad "1" smd rect
			(at 0.2667 0 90)
			(size 0.3048 0.381)
			(layers "B.Cu" "B.Mask" "B.Paste")
			(net "P0V9_CPU0_RT2_2A_2D")
		)
		(pad "2" smd rect
			(at -0.2667 0 90)
			(size 0.3048 0.381)
			(layers "B.Cu" "B.Mask" "B.Paste")
			(net "GND")
		)
	)
	(footprint ""
		(layer "B.Cu")
		(at 449.646802 -425.92371)
		(property "Reference" "PR6606"
			(at 0 0 0)
			(layer "B.SilkS")
			(hide yes)
			(effects
				(font
					(size 1.27 1.27)
				)
				(justify mirror)
			)
		)
		(property "Value" ""
			(at 0 0 0)
			(layer "B.Fab")
			(effects
				(font
					(size 1.27 1.27)
				)
				(justify mirror)
			)
		)
		(duplicate_pad_numbers_are_jumpers no)
		(fp_line
			(start -0.7874 -0.4064)
			(end -0.7874 0.4064)
			(stroke
				(width 0.1524)
				(type default)
			)
			(layer "B.SilkS")
		)
		(fp_line
			(start -0.7874 0.4064)
			(end 0.7874 0.4064)
			(stroke
				(width 0.1524)
				(type default)
			)
			(layer "B.SilkS")
		)
		(fp_line
			(start 0.7874 -0.4064)
			(end -0.7874 -0.4064)
			(stroke
				(width 0.1524)
				(type default)
			)
			(layer "B.SilkS")
		)
		(fp_line
			(start 0.7874 0.4064)
			(end 0.7874 -0.4064)
			(stroke
				(width 0.1524)
				(type default)
			)
			(layer "B.SilkS")
		)
		(fp_line
			(start -0.67945 -0.3048)
			(end -0.67945 0.3048)
			(stroke
				(width 0.1)
				(type default)
			)
			(layer "B.Fab")
		)
		(fp_line
			(start -0.67945 0.3048)
			(end -0.120396 0.3048)
			(stroke
				(width 0.1)
				(type default)
			)
			(layer "B.Fab")
		)
		(fp_line
			(start -0.12065 -0.3048)
			(end -0.67945 -0.3048)
			(stroke
				(width 0.1)
				(type default)
			)
			(layer "B.Fab")
		)
		(fp_line
			(start -0.12065 -0.2794)
			(end -0.12065 -0.3048)
			(stroke
				(width 0.1)
				(type default)
			)
			(layer "B.Fab")
		)
		(fp_line
			(start -0.120396 0.2794)
			(end 0.12065 0.2794)
			(stroke
				(width 0.1)
				(type default)
			)
			(layer "B.Fab")
		)
		(fp_line
			(start -0.120396 0.3048)
			(end -0.120396 0.2794)
			(stroke
				(width 0.1)
				(type default)
			)
			(layer "B.Fab")
		)
		(fp_line
			(start 0.12065 -0.305054)
			(end 0.12065 -0.2794)
			(stroke
				(width 0.1)
				(type default)
			)
			(layer "B.Fab")
		)
		(fp_line
			(start 0.12065 -0.2794)
			(end -0.12065 -0.2794)
			(stroke
				(width 0.1)
				(type default)
			)
			(layer "B.Fab")
		)
		(fp_line
			(start 0.12065 0.2794)
			(end 0.12065 0.3048)
			(stroke
				(width 0.1)
				(type default)
			)
			(layer "B.Fab")
		)
		(fp_line
			(start 0.12065 0.3048)
			(end 0.67945 0.3048)
			(stroke
				(width 0.1)
				(type default)
			)
			(layer "B.Fab")
		)
		(fp_line
			(start 0.67945 -0.305054)
			(end 0.12065 -0.305054)
			(stroke
				(width 0.1)
				(type default)
			)
			(layer "B.Fab")
		)
		(fp_line
			(start 0.67945 0.3048)
			(end 0.67945 -0.305054)
			(stroke
				(width 0.1)
				(type default)
			)
			(layer "B.Fab")
		)
		(pad "1" smd circle
			(at 0.40005 0 180)
			(size 0 0)
			(layers "B.Cu" "B.Mask" "B.Paste")
			(net "P12V_AUX")
		)
		(pad "2" smd circle
			(at -0.40005 0 180)
			(size 0 0)
			(layers "B.Cu" "B.Mask" "B.Paste")
			(net "P0V9_RETIMER_CPU0_VINSEN")
		)
	)
	(footprint ""
		(layer "B.Cu")
		(at 339.910166 -416.899344 90)
		(property "Reference" "C6555"
			(at 0 0 90)
			(layer "B.SilkS")
			(hide yes)
			(effects
				(font
					(size 1.27 1.27)
				)
				(justify mirror)
			)
		)
		(property "Value" ""
			(at 0 0 90)
			(layer "B.Fab")
			(effects
				(font
					(size 1.27 1.27)
				)
				(justify mirror)
			)
		)
		(duplicate_pad_numbers_are_jumpers no)
		(fp_line
			(start 0.299974 -0.150114)
			(end -0.299974 -0.150114)
			(stroke
				(width 0.1)
				(type default)
			)
			(layer "B.Fab")
		)
		(fp_line
			(start -0.299974 -0.150114)
			(end -0.299974 0.150114)
			(stroke
				(width 0.1)
				(type default)
			)
			(layer "B.Fab")
		)
		(fp_line
			(start 0.299974 0.150114)
			(end 0.299974 -0.150114)
			(stroke
				(width 0.1)
				(type default)
			)
			(layer "B.Fab")
		)
		(fp_line
			(start -0.299974 0.150114)
			(end 0.299974 0.150114)
			(stroke
				(width 0.1)
				(type default)
			)
			(layer "B.Fab")
		)
		(pad "1" smd rect
			(at 0.2667 0 270)
			(size 0.3048 0.381)
			(layers "B.Cu" "B.Mask" "B.Paste")
			(net "P5E_CPU0_P1_TX_BUF_C_DP<11>")
		)
		(pad "2" smd rect
			(at -0.2667 0 270)
			(size 0.3048 0.381)
			(layers "B.Cu" "B.Mask" "B.Paste")
			(net "P5E_CPU0_P1_TX_BUF_DP<11>")
		)
	)
	(footprint ""
		(layer "B.Cu")
		(at 226.366578 -290.844732 180)
		(property "Reference" "R644"
			(at 0 0 0)
			(layer "B.SilkS")
			(hide yes)
			(effects
				(font
					(size 1.27 1.27)
				)
				(justify mirror)
			)
		)
		(property "Value" ""
			(at 0 0 0)
			(layer "B.Fab")
			(effects
				(font
					(size 1.27 1.27)
				)
				(justify mirror)
			)
		)
		(duplicate_pad_numbers_are_jumpers no)
		(fp_line
			(start 0.7874 0.4064)
			(end 0.7874 -0.4064)
			(stroke
				(width 0.1524)
				(type default)
			)
			(layer "B.SilkS")
		)
		(fp_line
			(start 0.7874 -0.4064)
			(end -0.7874 -0.4064)
			(stroke
				(width 0.1524)
				(type default)
			)
			(layer "B.SilkS")
		)
		(fp_line
			(start -0.7874 0.4064)
			(end 0.7874 0.4064)
			(stroke
				(width 0.1524)
				(type default)
			)
			(layer "B.SilkS")
		)
		(fp_line
			(start -0.7874 -0.4064)
			(end -0.7874 0.4064)
			(stroke
				(width 0.1524)
				(type default)
			)
			(layer "B.SilkS")
		)
		(fp_line
			(start 0.67945 0.3048)
			(end 0.67945 -0.305054)
			(stroke
				(width 0.1)
				(type default)
			)
			(layer "B.Fab")
		)
		(fp_line
			(start 0.67945 -0.305054)
			(end 0.12065 -0.305054)
			(stroke
				(width 0.1)
				(type default)
			)
			(layer "B.Fab")
		)
		(fp_line
			(start 0.12065 0.3048)
			(end 0.67945 0.3048)
			(stroke
				(width 0.1)
				(type default)
			)
			(layer "B.Fab")
		)
		(fp_line
			(start 0.12065 0.2794)
			(end 0.12065 0.3048)
			(stroke
				(width 0.1)
				(type default)
			)
			(layer "B.Fab")
		)
		(fp_line
			(start 0.12065 -0.2794)
			(end -0.12065 -0.2794)
			(stroke
				(width 0.1)
				(type default)
			)
			(layer "B.Fab")
		)
		(fp_line
			(start 0.12065 -0.305054)
			(end 0.12065 -0.2794)
			(stroke
				(width 0.1)
				(type default)
			)
			(layer "B.Fab")
		)
		(fp_line
			(start -0.120396 0.3048)
			(end -0.120396 0.2794)
			(stroke
				(width 0.1)
				(type default)
			)
			(layer "B.Fab")
		)
		(fp_line
			(start -0.120396 0.2794)
			(end 0.12065 0.2794)
			(stroke
				(width 0.1)
				(type default)
			)
			(layer "B.Fab")
		)
		(fp_line
			(start -0.12065 -0.2794)
			(end -0.12065 -0.3048)
			(stroke
				(width 0.1)
				(type default)
			)
			(layer "B.Fab")
		)
		(fp_line
			(start -0.12065 -0.3048)
			(end -0.67945 -0.3048)
			(stroke
				(width 0.1)
				(type default)
			)
			(layer "B.Fab")
		)
		(fp_line
			(start -0.67945 0.3048)
			(end -0.120396 0.3048)
			(stroke
				(width 0.1)
				(type default)
			)
			(layer "B.Fab")
		)
		(fp_line
			(start -0.67945 -0.3048)
			(end -0.67945 0.3048)
			(stroke
				(width 0.1)
				(type default)
			)
			(layer "B.Fab")
		)
		(pad "1" smd circle
			(at 0.40005 0)
			(size 0 0)
			(layers "B.Cu" "B.Mask" "B.Paste")
			(net "P3V3_AUX")
		)
		(pad "2" smd circle
			(at -0.40005 0)
			(size 0 0)
			(layers "B.Cu" "B.Mask" "B.Paste")
			(net "PWRGD_P1V8_RETIMER_CPU1")
		)
	)
	(footprint ""
		(layer "B.Cu")
		(at 55.791354 -390.560052 90)
		(property "Reference" "C121"
			(at 0 0 90)
			(layer "B.SilkS")
			(hide yes)
			(effects
				(font
					(size 1.27 1.27)
				)
				(justify mirror)
			)
		)
		(property "Value" ""
			(at 0 0 90)
			(layer "B.Fab")
			(effects
				(font
					(size 1.27 1.27)
				)
				(justify mirror)
			)
		)
		(duplicate_pad_numbers_are_jumpers no)
		(fp_line
			(start 0.7874 -0.4064)
			(end -0.7874 -0.4064)
			(stroke
				(width 0.1524)
				(type default)
			)
			(layer "B.SilkS")
		)
		(fp_line
			(start -0.7874 -0.4064)
			(end -0.7874 0.4064)
			(stroke
				(width 0.1524)
				(type default)
			)
			(layer "B.SilkS")
		)
		(fp_line
			(start 0.7874 0.4064)
			(end 0.7874 -0.4064)
			(stroke
				(width 0.1524)
				(type default)
			)
			(layer "B.SilkS")
		)
		(fp_line
			(start -0.7874 0.4064)
			(end 0.7874 0.4064)
			(stroke
				(width 0.1524)
				(type default)
			)
			(layer "B.SilkS")
		)
		(fp_line
			(start 0.67945 -0.305054)
			(end 0.12065 -0.305054)
			(stroke
				(width 0.1)
				(type default)
			)
			(layer "B.Fab")
		)
		(fp_line
			(start 0.12065 -0.305054)
			(end 0.12065 -0.2794)
			(stroke
				(width 0.1)
				(type default)
			)
			(layer "B.Fab")
		)
		(fp_line
			(start -0.12065 -0.3048)
			(end -0.67945 -0.3048)
			(stroke
				(width 0.1)
				(type default)
			)
			(layer "B.Fab")
		)
		(fp_line
			(start -0.67945 -0.3048)
			(end -0.67945 0.3048)
			(stroke
				(width 0.1)
				(type default)
			)
			(layer "B.Fab")
		)
		(fp_line
			(start 0.12065 -0.2794)
			(end -0.12065 -0.2794)
			(stroke
				(width 0.1)
				(type default)
			)
			(layer "B.Fab")
		)
		(fp_line
			(start -0.12065 -0.2794)
			(end -0.12065 -0.3048)
			(stroke
				(width 0.1)
				(type default)
			)
			(layer "B.Fab")
		)
		(fp_line
			(start 0.12065 0.2794)
			(end 0.12065 0.3048)
			(stroke
				(width 0.1)
				(type default)
			)
			(layer "B.Fab")
		)
		(fp_line
			(start -0.120396 0.2794)
			(end 0.12065 0.2794)
			(stroke
				(width 0.1)
				(type default)
			)
			(layer "B.Fab")
		)
		(fp_line
			(start 0.67945 0.3048)
			(end 0.67945 -0.305054)
			(stroke
				(width 0.1)
				(type default)
			)
			(layer "B.Fab")
		)
		(fp_line
			(start 0.12065 0.3048)
			(end 0.67945 0.3048)
			(stroke
				(width 0.1)
				(type default)
			)
			(layer "B.Fab")
		)
		(fp_line
			(start -0.120396 0.3048)
			(end -0.120396 0.2794)
			(stroke
				(width 0.1)
				(type default)
			)
			(layer "B.Fab")
		)
		(fp_line
			(start -0.67945 0.3048)
			(end -0.120396 0.3048)
			(stroke
				(width 0.1)
				(type default)
			)
			(layer "B.Fab")
		)
		(pad "1" smd circle
			(at 0.40005 0 270)
			(size 0 0)
			(layers "B.Cu" "B.Mask" "B.Paste")
			(net "P1V8_CPU1_RT0_1A")
		)
		(pad "2" smd circle
			(at -0.40005 0 270)
			(size 0 0)
			(layers "B.Cu" "B.Mask" "B.Paste")
			(net "GND")
		)
	)
	(footprint ""
		(layer "B.Cu")
		(at 317.778384 -395.148562 90)
		(property "Reference" "C529"
			(at 0 0 90)
			(layer "B.SilkS")
			(hide yes)
			(effects
				(font
					(size 1.27 1.27)
				)
				(justify mirror)
			)
		)
		(property "Value" ""
			(at 0 0 90)
			(layer "B.Fab")
			(effects
				(font
					(size 1.27 1.27)
				)
				(justify mirror)
			)
		)
		(duplicate_pad_numbers_are_jumpers no)
		(fp_line
			(start 0.299974 -0.150114)
			(end -0.299974 -0.150114)
			(stroke
				(width 0.1)
				(type default)
			)
			(layer "B.Fab")
		)
		(fp_line
			(start -0.299974 -0.150114)
			(end -0.299974 0.150114)
			(stroke
				(width 0.1)
				(type default)
			)
			(layer "B.Fab")
		)
		(fp_line
			(start 0.299974 0.150114)
			(end 0.299974 -0.150114)
			(stroke
				(width 0.1)
				(type default)
			)
			(layer "B.Fab")
		)
		(fp_line
			(start -0.299974 0.150114)
			(end 0.299974 0.150114)
			(stroke
				(width 0.1)
				(type default)
			)
			(layer "B.Fab")
		)
		(pad "1" smd rect
			(at 0.2667 0 270)
			(size 0.3048 0.381)
			(layers "B.Cu" "B.Mask" "B.Paste")
			(net "P0V9_CPU0_RT0_2A")
		)
		(pad "2" smd rect
			(at -0.2667 0 270)
			(size 0.3048 0.381)
			(layers "B.Cu" "B.Mask" "B.Paste")
			(net "GND")
		)
	)
	(footprint ""
		(layer "B.Cu")
		(at 116.527834 -245.487952)
		(property "Reference" "C2306"
			(at 0 0 0)
			(layer "B.SilkS")
			(hide yes)
			(effects
				(font
					(size 1.27 1.27)
				)
				(justify mirror)
			)
		)
		(property "Value" ""
			(at 0 0 0)
			(layer "B.Fab")
			(effects
				(font
					(size 1.27 1.27)
				)
				(justify mirror)
			)
		)
		(duplicate_pad_numbers_are_jumpers no)
		(fp_line
			(start -0.7874 -0.4064)
			(end -0.7874 0.4064)
			(stroke
				(width 0.1524)
				(type default)
			)
			(layer "B.SilkS")
		)
		(fp_line
			(start -0.7874 0.4064)
			(end 0.7874 0.4064)
			(stroke
				(width 0.1524)
				(type default)
			)
			(layer "B.SilkS")
		)
		(fp_line
			(start 0.7874 -0.4064)
			(end -0.7874 -0.4064)
			(stroke
				(width 0.1524)
				(type default)
			)
			(layer "B.SilkS")
		)
		(fp_line
			(start 0.7874 0.4064)
			(end 0.7874 -0.4064)
			(stroke
				(width 0.1524)
				(type default)
			)
			(layer "B.SilkS")
		)
		(fp_line
			(start -0.67945 -0.3048)
			(end -0.67945 0.3048)
			(stroke
				(width 0.1)
				(type default)
			)
			(layer "B.Fab")
		)
		(fp_line
			(start -0.67945 0.3048)
			(end -0.120396 0.3048)
			(stroke
				(width 0.1)
				(type default)
			)
			(layer "B.Fab")
		)
		(fp_line
			(start -0.12065 -0.3048)
			(end -0.67945 -0.3048)
			(stroke
				(width 0.1)
				(type default)
			)
			(layer "B.Fab")
		)
		(fp_line
			(start -0.12065 -0.2794)
			(end -0.12065 -0.3048)
			(stroke
				(width 0.1)
				(type default)
			)
			(layer "B.Fab")
		)
		(fp_line
			(start -0.120396 0.2794)
			(end 0.12065 0.2794)
			(stroke
				(width 0.1)
				(type default)
			)
			(layer "B.Fab")
		)
		(fp_line
			(start -0.120396 0.3048)
			(end -0.120396 0.2794)
			(stroke
				(width 0.1)
				(type default)
			)
			(layer "B.Fab")
		)
		(fp_line
			(start 0.12065 -0.305054)
			(end 0.12065 -0.2794)
			(stroke
				(width 0.1)
				(type default)
			)
			(layer "B.Fab")
		)
		(fp_line
			(start 0.12065 -0.2794)
			(end -0.12065 -0.2794)
			(stroke
				(width 0.1)
				(type default)
			)
			(layer "B.Fab")
		)
		(fp_line
			(start 0.12065 0.2794)
			(end 0.12065 0.3048)
			(stroke
				(width 0.1)
				(type default)
			)
			(layer "B.Fab")
		)
		(fp_line
			(start 0.12065 0.3048)
			(end 0.67945 0.3048)
			(stroke
				(width 0.1)
				(type default)
			)
			(layer "B.Fab")
		)
		(fp_line
			(start 0.67945 -0.305054)
			(end 0.12065 -0.305054)
			(stroke
				(width 0.1)
				(type default)
			)
			(layer "B.Fab")
		)
		(fp_line
			(start 0.67945 0.3048)
			(end 0.67945 -0.305054)
			(stroke
				(width 0.1)
				(type default)
			)
			(layer "B.Fab")
		)
		(pad "1" smd circle
			(at 0.40005 0 180)
			(size 0 0)
			(layers "B.Cu" "B.Mask" "B.Paste")
			(net "PVDDCR_CPU0_P1")
		)
		(pad "2" smd circle
			(at -0.40005 0 180)
			(size 0 0)
			(layers "B.Cu" "B.Mask" "B.Paste")
			(net "GND")
		)
	)
	(footprint ""
		(layer "B.Cu")
		(at 353.900232 -261.255002 180)
		(property "Reference" "C2145"
			(at 0 0 0)
			(layer "B.SilkS")
			(hide yes)
			(effects
				(font
					(size 1.27 1.27)
				)
				(justify mirror)
			)
		)
		(property "Value" ""
			(at 0 0 0)
			(layer "B.Fab")
			(effects
				(font
					(size 1.27 1.27)
				)
				(justify mirror)
			)
		)
		(duplicate_pad_numbers_are_jumpers no)
		(fp_line
			(start 0.7874 0.4064)
			(end 0.7874 -0.4064)
			(stroke
				(width 0.1524)
				(type default)
			)
			(layer "B.SilkS")
		)
		(fp_line
			(start 0.7874 -0.4064)
			(end -0.7874 -0.4064)
			(stroke
				(width 0.1524)
				(type default)
			)
			(layer "B.SilkS")
		)
		(fp_line
			(start -0.7874 0.4064)
			(end 0.7874 0.4064)
			(stroke
				(width 0.1524)
				(type default)
			)
			(layer "B.SilkS")
		)
		(fp_line
			(start -0.7874 -0.4064)
			(end -0.7874 0.4064)
			(stroke
				(width 0.1524)
				(type default)
			)
			(layer "B.SilkS")
		)
		(fp_line
			(start 0.67945 0.3048)
			(end 0.67945 -0.305054)
			(stroke
				(width 0.1)
				(type default)
			)
			(layer "B.Fab")
		)
		(fp_line
			(start 0.67945 -0.305054)
			(end 0.12065 -0.305054)
			(stroke
				(width 0.1)
				(type default)
			)
			(layer "B.Fab")
		)
		(fp_line
			(start 0.12065 0.3048)
			(end 0.67945 0.3048)
			(stroke
				(width 0.1)
				(type default)
			)
			(layer "B.Fab")
		)
		(fp_line
			(start 0.12065 0.2794)
			(end 0.12065 0.3048)
			(stroke
				(width 0.1)
				(type default)
			)
			(layer "B.Fab")
		)
		(fp_line
			(start 0.12065 -0.2794)
			(end -0.12065 -0.2794)
			(stroke
				(width 0.1)
				(type default)
			)
			(layer "B.Fab")
		)
		(fp_line
			(start 0.12065 -0.305054)
			(end 0.12065 -0.2794)
			(stroke
				(width 0.1)
				(type default)
			)
			(layer "B.Fab")
		)
		(fp_line
			(start -0.120396 0.3048)
			(end -0.120396 0.2794)
			(stroke
				(width 0.1)
				(type default)
			)
			(layer "B.Fab")
		)
		(fp_line
			(start -0.120396 0.2794)
			(end 0.12065 0.2794)
			(stroke
				(width 0.1)
				(type default)
			)
			(layer "B.Fab")
		)
		(fp_line
			(start -0.12065 -0.2794)
			(end -0.12065 -0.3048)
			(stroke
				(width 0.1)
				(type default)
			)
			(layer "B.Fab")
		)
		(fp_line
			(start -0.12065 -0.3048)
			(end -0.67945 -0.3048)
			(stroke
				(width 0.1)
				(type default)
			)
			(layer "B.Fab")
		)
		(fp_line
			(start -0.67945 0.3048)
			(end -0.120396 0.3048)
			(stroke
				(width 0.1)
				(type default)
			)
			(layer "B.Fab")
		)
		(fp_line
			(start -0.67945 -0.3048)
			(end -0.67945 0.3048)
			(stroke
				(width 0.1)
				(type default)
			)
			(layer "B.Fab")
		)
		(pad "1" smd circle
			(at 0.40005 0)
			(size 0 0)
			(layers "B.Cu" "B.Mask" "B.Paste")
			(net "PVDDIO_P0")
		)
		(pad "2" smd circle
			(at -0.40005 0)
			(size 0 0)
			(layers "B.Cu" "B.Mask" "B.Paste")
			(net "GND")
		)
	)
	(footprint ""
		(layer "B.Cu")
		(at 396.142972 -200.754996 90)
		(property "Reference" "R6134"
			(at 0 0 90)
			(layer "B.SilkS")
			(hide yes)
			(effects
				(font
					(size 1.27 1.27)
				)
				(justify mirror)
			)
		)
		(property "Value" ""
			(at 0 0 90)
			(layer "B.Fab")
			(effects
				(font
					(size 1.27 1.27)
				)
				(justify mirror)
			)
		)
		(duplicate_pad_numbers_are_jumpers no)
		(fp_line
			(start 0.7874 -0.4064)
			(end -0.7874 -0.4064)
			(stroke
				(width 0.1524)
				(type default)
			)
			(layer "B.SilkS")
		)
		(fp_line
			(start -0.7874 -0.4064)
			(end -0.7874 0.4064)
			(stroke
				(width 0.1524)
				(type default)
			)
			(layer "B.SilkS")
		)
		(fp_line
			(start 0.7874 0.4064)
			(end 0.7874 -0.4064)
			(stroke
				(width 0.1524)
				(type default)
			)
			(layer "B.SilkS")
		)
		(fp_line
			(start -0.7874 0.4064)
			(end 0.7874 0.4064)
			(stroke
				(width 0.1524)
				(type default)
			)
			(layer "B.SilkS")
		)
		(fp_line
			(start 0.67945 -0.305054)
			(end 0.12065 -0.305054)
			(stroke
				(width 0.1)
				(type default)
			)
			(layer "B.Fab")
		)
		(fp_line
			(start 0.12065 -0.305054)
			(end 0.12065 -0.2794)
			(stroke
				(width 0.1)
				(type default)
			)
			(layer "B.Fab")
		)
		(fp_line
			(start -0.12065 -0.3048)
			(end -0.67945 -0.3048)
			(stroke
				(width 0.1)
				(type default)
			)
			(layer "B.Fab")
		)
		(fp_line
			(start -0.67945 -0.3048)
			(end -0.67945 0.3048)
			(stroke
				(width 0.1)
				(type default)
			)
			(layer "B.Fab")
		)
		(fp_line
			(start 0.12065 -0.2794)
			(end -0.12065 -0.2794)
			(stroke
				(width 0.1)
				(type default)
			)
			(layer "B.Fab")
		)
		(fp_line
			(start -0.12065 -0.2794)
			(end -0.12065 -0.3048)
			(stroke
				(width 0.1)
				(type default)
			)
			(layer "B.Fab")
		)
		(fp_line
			(start 0.12065 0.2794)
			(end 0.12065 0.3048)
			(stroke
				(width 0.1)
				(type default)
			)
			(layer "B.Fab")
		)
		(fp_line
			(start -0.120396 0.2794)
			(end 0.12065 0.2794)
			(stroke
				(width 0.1)
				(type default)
			)
			(layer "B.Fab")
		)
		(fp_line
			(start 0.67945 0.3048)
			(end 0.67945 -0.305054)
			(stroke
				(width 0.1)
				(type default)
			)
			(layer "B.Fab")
		)
		(fp_line
			(start 0.12065 0.3048)
			(end 0.67945 0.3048)
			(stroke
				(width 0.1)
				(type default)
			)
			(layer "B.Fab")
		)
		(fp_line
			(start -0.120396 0.3048)
			(end -0.120396 0.2794)
			(stroke
				(width 0.1)
				(type default)
			)
			(layer "B.Fab")
		)
		(fp_line
			(start -0.67945 0.3048)
			(end -0.120396 0.3048)
			(stroke
				(width 0.1)
				(type default)
			)
			(layer "B.Fab")
		)
		(pad "1" smd circle
			(at 0.40005 0 270)
			(size 0 0)
			(layers "B.Cu" "B.Mask" "B.Paste")
			(net "FAB_REV_ID1")
		)
		(pad "2" smd circle
			(at -0.40005 0 270)
			(size 0 0)
			(layers "B.Cu" "B.Mask" "B.Paste")
			(net "GND")
		)
	)
	(footprint ""
		(layer "B.Cu")
		(at 108.526834 -249.368564 180)
		(property "Reference" "C2298"
			(at 0 0 0)
			(layer "B.SilkS")
			(hide yes)
			(effects
				(font
					(size 1.27 1.27)
				)
				(justify mirror)
			)
		)
		(property "Value" ""
			(at 0 0 0)
			(layer "B.Fab")
			(effects
				(font
					(size 1.27 1.27)
				)
				(justify mirror)
			)
		)
		(duplicate_pad_numbers_are_jumpers no)
		(fp_line
			(start 0.7874 0.4064)
			(end 0.7874 -0.4064)
			(stroke
				(width 0.1524)
				(type default)
			)
			(layer "B.SilkS")
		)
		(fp_line
			(start 0.7874 -0.4064)
			(end -0.7874 -0.4064)
			(stroke
				(width 0.1524)
				(type default)
			)
			(layer "B.SilkS")
		)
		(fp_line
			(start -0.7874 0.4064)
			(end 0.7874 0.4064)
			(stroke
				(width 0.1524)
				(type default)
			)
			(layer "B.SilkS")
		)
		(fp_line
			(start -0.7874 -0.4064)
			(end -0.7874 0.4064)
			(stroke
				(width 0.1524)
				(type default)
			)
			(layer "B.SilkS")
		)
		(fp_line
			(start 0.67945 0.3048)
			(end 0.67945 -0.305054)
			(stroke
				(width 0.1)
				(type default)
			)
			(layer "B.Fab")
		)
		(fp_line
			(start 0.67945 -0.305054)
			(end 0.12065 -0.305054)
			(stroke
				(width 0.1)
				(type default)
			)
			(layer "B.Fab")
		)
		(fp_line
			(start 0.12065 0.3048)
			(end 0.67945 0.3048)
			(stroke
				(width 0.1)
				(type default)
			)
			(layer "B.Fab")
		)
		(fp_line
			(start 0.12065 0.2794)
			(end 0.12065 0.3048)
			(stroke
				(width 0.1)
				(type default)
			)
			(layer "B.Fab")
		)
		(fp_line
			(start 0.12065 -0.2794)
			(end -0.12065 -0.2794)
			(stroke
				(width 0.1)
				(type default)
			)
			(layer "B.Fab")
		)
		(fp_line
			(start 0.12065 -0.305054)
			(end 0.12065 -0.2794)
			(stroke
				(width 0.1)
				(type default)
			)
			(layer "B.Fab")
		)
		(fp_line
			(start -0.120396 0.3048)
			(end -0.120396 0.2794)
			(stroke
				(width 0.1)
				(type default)
			)
			(layer "B.Fab")
		)
		(fp_line
			(start -0.120396 0.2794)
			(end 0.12065 0.2794)
			(stroke
				(width 0.1)
				(type default)
			)
			(layer "B.Fab")
		)
		(fp_line
			(start -0.12065 -0.2794)
			(end -0.12065 -0.3048)
			(stroke
				(width 0.1)
				(type default)
			)
			(layer "B.Fab")
		)
		(fp_line
			(start -0.12065 -0.3048)
			(end -0.67945 -0.3048)
			(stroke
				(width 0.1)
				(type default)
			)
			(layer "B.Fab")
		)
		(fp_line
			(start -0.67945 0.3048)
			(end -0.120396 0.3048)
			(stroke
				(width 0.1)
				(type default)
			)
			(layer "B.Fab")
		)
		(fp_line
			(start -0.67945 -0.3048)
			(end -0.67945 0.3048)
			(stroke
				(width 0.1)
				(type default)
			)
			(layer "B.Fab")
		)
		(pad "1" smd circle
			(at 0.40005 0)
			(size 0 0)
			(layers "B.Cu" "B.Mask" "B.Paste")
			(net "PVDDCR_CPU0_P1")
		)
		(pad "2" smd circle
			(at -0.40005 0)
			(size 0 0)
			(layers "B.Cu" "B.Mask" "B.Paste")
			(net "GND")
		)
	)
	(footprint ""
		(layer "B.Cu")
		(at 38.002718 -346.788994 90)
		(property "Reference" "PC626_3"
			(at 0 0 90)
			(layer "B.SilkS")
			(hide yes)
			(effects
				(font
					(size 1.27 1.27)
				)
				(justify mirror)
			)
		)
		(property "Value" ""
			(at 0 0 90)
			(layer "B.Fab")
			(effects
				(font
					(size 1.27 1.27)
				)
				(justify mirror)
			)
		)
		(duplicate_pad_numbers_are_jumpers no)
		(fp_line
			(start 1.524 -0.762)
			(end -1.524 -0.762)
			(stroke
				(width 0.1524)
				(type default)
			)
			(layer "B.SilkS")
		)
		(fp_line
			(start -1.524 -0.762)
			(end -1.524 0.762)
			(stroke
				(width 0.1524)
				(type default)
			)
			(layer "B.SilkS")
		)
		(fp_line
			(start 1.524 0.762)
			(end 1.524 -0.762)
			(stroke
				(width 0.1524)
				(type default)
			)
			(layer "B.SilkS")
		)
		(fp_line
			(start -1.524 0.762)
			(end 1.524 0.762)
			(stroke
				(width 0.1524)
				(type default)
			)
			(layer "B.SilkS")
		)
		(fp_line
			(start 1.1049 -0.724916)
			(end 1.1049 0.724916)
			(stroke
				(width 0.1)
				(type default)
			)
			(layer "B.Fab")
		)
		(fp_line
			(start -1.1049 -0.724916)
			(end 1.1049 -0.724916)
			(stroke
				(width 0.1)
				(type default)
			)
			(layer "B.Fab")
		)
		(fp_line
			(start 1.1049 0.724916)
			(end -1.1049 0.724916)
			(stroke
				(width 0.1)
				(type default)
			)
			(layer "B.Fab")
		)
		(fp_line
			(start -1.1049 0.724916)
			(end -1.1049 -0.724916)
			(stroke
				(width 0.1)
				(type default)
			)
			(layer "B.Fab")
		)
		(pad "1" smd rect
			(at 0.889 0 90)
			(size 1.016 1.27)
			(layers "B.Cu" "B.Mask" "B.Paste")
			(net "SW_P12V_AUX_PVDDIO_P1_FLT")
		)
		(pad "2" smd rect
			(at -0.889 0 90)
			(size 1.016 1.27)
			(layers "B.Cu" "B.Mask" "B.Paste")
			(net "GND")
		)
	)
	(footprint ""
		(layer "B.Cu")
		(at 127.62738 -162.527234 90)
		(property "Reference" "PR212"
			(at 0 0 90)
			(layer "B.SilkS")
			(hide yes)
			(effects
				(font
					(size 1.27 1.27)
				)
				(justify mirror)
			)
		)
		(property "Value" ""
			(at 0 0 90)
			(layer "B.Fab")
			(effects
				(font
					(size 1.27 1.27)
				)
				(justify mirror)
			)
		)
		(duplicate_pad_numbers_are_jumpers no)
		(fp_line
			(start 0.7874 -0.4064)
			(end -0.7874 -0.4064)
			(stroke
				(width 0.1524)
				(type default)
			)
			(layer "B.SilkS")
		)
		(fp_line
			(start -0.7874 -0.4064)
			(end -0.7874 0.4064)
			(stroke
				(width 0.1524)
				(type default)
			)
			(layer "B.SilkS")
		)
		(fp_line
			(start 0.7874 0.4064)
			(end 0.7874 -0.4064)
			(stroke
				(width 0.1524)
				(type default)
			)
			(layer "B.SilkS")
		)
		(fp_line
			(start -0.7874 0.4064)
			(end 0.7874 0.4064)
			(stroke
				(width 0.1524)
				(type default)
			)
			(layer "B.SilkS")
		)
		(fp_line
			(start 0.67945 -0.305054)
			(end 0.12065 -0.305054)
			(stroke
				(width 0.1)
				(type default)
			)
			(layer "B.Fab")
		)
		(fp_line
			(start 0.12065 -0.305054)
			(end 0.12065 -0.2794)
			(stroke
				(width 0.1)
				(type default)
			)
			(layer "B.Fab")
		)
		(fp_line
			(start -0.12065 -0.3048)
			(end -0.67945 -0.3048)
			(stroke
				(width 0.1)
				(type default)
			)
			(layer "B.Fab")
		)
		(fp_line
			(start -0.67945 -0.3048)
			(end -0.67945 0.3048)
			(stroke
				(width 0.1)
				(type default)
			)
			(layer "B.Fab")
		)
		(fp_line
			(start 0.12065 -0.2794)
			(end -0.12065 -0.2794)
			(stroke
				(width 0.1)
				(type default)
			)
			(layer "B.Fab")
		)
		(fp_line
			(start -0.12065 -0.2794)
			(end -0.12065 -0.3048)
			(stroke
				(width 0.1)
				(type default)
			)
			(layer "B.Fab")
		)
		(fp_line
			(start 0.12065 0.2794)
			(end 0.12065 0.3048)
			(stroke
				(width 0.1)
				(type default)
			)
			(layer "B.Fab")
		)
		(fp_line
			(start -0.120396 0.2794)
			(end 0.12065 0.2794)
			(stroke
				(width 0.1)
				(type default)
			)
			(layer "B.Fab")
		)
		(fp_line
			(start 0.67945 0.3048)
			(end 0.67945 -0.305054)
			(stroke
				(width 0.1)
				(type default)
			)
			(layer "B.Fab")
		)
		(fp_line
			(start 0.12065 0.3048)
			(end 0.67945 0.3048)
			(stroke
				(width 0.1)
				(type default)
			)
			(layer "B.Fab")
		)
		(fp_line
			(start -0.120396 0.3048)
			(end -0.120396 0.2794)
			(stroke
				(width 0.1)
				(type default)
			)
			(layer "B.Fab")
		)
		(fp_line
			(start -0.67945 0.3048)
			(end -0.120396 0.3048)
			(stroke
				(width 0.1)
				(type default)
			)
			(layer "B.Fab")
		)
		(pad "1" smd circle
			(at 0.40005 0 270)
			(size 0 0)
			(layers "B.Cu" "B.Mask" "B.Paste")
			(net "PVDDCR_SOC_P1_VOS2")
		)
		(pad "2" smd circle
			(at -0.40005 0 270)
			(size 0 0)
			(layers "B.Cu" "B.Mask" "B.Paste")
			(net "PVDDCR_SOC_P1")
		)
	)
	(footprint ""
		(layer "B.Cu")
		(at 276.54377 -350.65589 -90)
		(property "Reference" "PC188_4"
			(at 0 0 90)
			(layer "B.SilkS")
			(hide yes)
			(effects
				(font
					(size 1.27 1.27)
				)
				(justify mirror)
			)
		)
		(property "Value" ""
			(at 0 0 90)
			(layer "B.Fab")
			(effects
				(font
					(size 1.27 1.27)
				)
				(justify mirror)
			)
		)
		(duplicate_pad_numbers_are_jumpers no)
		(fp_line
			(start -1.524 0.762)
			(end 1.524 0.762)
			(stroke
				(width 0.1524)
				(type default)
			)
			(layer "B.SilkS")
		)
		(fp_line
			(start 1.524 0.762)
			(end 1.524 -0.762)
			(stroke
				(width 0.1524)
				(type default)
			)
			(layer "B.SilkS")
		)
		(fp_line
			(start -1.524 -0.762)
			(end -1.524 0.762)
			(stroke
				(width 0.1524)
				(type default)
			)
			(layer "B.SilkS")
		)
		(fp_line
			(start 1.524 -0.762)
			(end -1.524 -0.762)
			(stroke
				(width 0.1524)
				(type default)
			)
			(layer "B.SilkS")
		)
		(fp_line
			(start -1.1049 0.724916)
			(end -1.1049 -0.724916)
			(stroke
				(width 0.1)
				(type default)
			)
			(layer "B.Fab")
		)
		(fp_line
			(start 1.1049 0.724916)
			(end -1.1049 0.724916)
			(stroke
				(width 0.1)
				(type default)
			)
			(layer "B.Fab")
		)
		(fp_line
			(start -1.1049 -0.724916)
			(end 1.1049 -0.724916)
			(stroke
				(width 0.1)
				(type default)
			)
			(layer "B.Fab")
		)
		(fp_line
			(start 1.1049 -0.724916)
			(end 1.1049 0.724916)
			(stroke
				(width 0.1)
				(type default)
			)
			(layer "B.Fab")
		)
		(pad "1" smd rect
			(at 0.889 0 270)
			(size 1.016 1.27)
			(layers "B.Cu" "B.Mask" "B.Paste")
			(net "SW_P12V_AUX_PVDDIO_P0_FLT")
		)
		(pad "2" smd rect
			(at -0.889 0 270)
			(size 1.016 1.27)
			(layers "B.Cu" "B.Mask" "B.Paste")
			(net "GND")
		)
	)
	(footprint ""
		(layer "B.Cu")
		(at 404.043642 -349.215964 -90)
		(property "Reference" "R6121"
			(at 0 0 90)
			(layer "B.SilkS")
			(hide yes)
			(effects
				(font
					(size 1.27 1.27)
				)
				(justify mirror)
			)
		)
		(property "Value" ""
			(at 0 0 90)
			(layer "B.Fab")
			(effects
				(font
					(size 1.27 1.27)
				)
				(justify mirror)
			)
		)
		(duplicate_pad_numbers_are_jumpers no)
		(fp_line
			(start -0.7874 0.4064)
			(end 0.7874 0.4064)
			(stroke
				(width 0.1524)
				(type default)
			)
			(layer "B.SilkS")
		)
		(fp_line
			(start 0.7874 0.4064)
			(end 0.7874 -0.4064)
			(stroke
				(width 0.1524)
				(type default)
			)
			(layer "B.SilkS")
		)
		(fp_line
			(start -0.7874 -0.4064)
			(end -0.7874 0.4064)
			(stroke
				(width 0.1524)
				(type default)
			)
			(layer "B.SilkS")
		)
		(fp_line
			(start 0.7874 -0.4064)
			(end -0.7874 -0.4064)
			(stroke
				(width 0.1524)
				(type default)
			)
			(layer "B.SilkS")
		)
		(fp_line
			(start -0.67945 0.3048)
			(end -0.120396 0.3048)
			(stroke
				(width 0.1)
				(type default)
			)
			(layer "B.Fab")
		)
		(fp_line
			(start -0.120396 0.3048)
			(end -0.120396 0.2794)
			(stroke
				(width 0.1)
				(type default)
			)
			(layer "B.Fab")
		)
		(fp_line
			(start 0.12065 0.3048)
			(end 0.67945 0.3048)
			(stroke
				(width 0.1)
				(type default)
			)
			(layer "B.Fab")
		)
		(fp_line
			(start 0.67945 0.3048)
			(end 0.67945 -0.305054)
			(stroke
				(width 0.1)
				(type default)
			)
			(layer "B.Fab")
		)
		(fp_line
			(start -0.120396 0.2794)
			(end 0.12065 0.2794)
			(stroke
				(width 0.1)
				(type default)
			)
			(layer "B.Fab")
		)
		(fp_line
			(start 0.12065 0.2794)
			(end 0.12065 0.3048)
			(stroke
				(width 0.1)
				(type default)
			)
			(layer "B.Fab")
		)
		(fp_line
			(start -0.12065 -0.2794)
			(end -0.12065 -0.3048)
			(stroke
				(width 0.1)
				(type default)
			)
			(layer "B.Fab")
		)
		(fp_line
			(start 0.12065 -0.2794)
			(end -0.12065 -0.2794)
			(stroke
				(width 0.1)
				(type default)
			)
			(layer "B.Fab")
		)
		(fp_line
			(start -0.67945 -0.3048)
			(end -0.67945 0.3048)
			(stroke
				(width 0.1)
				(type default)
			)
			(layer "B.Fab")
		)
		(fp_line
			(start -0.12065 -0.3048)
			(end -0.67945 -0.3048)
			(stroke
				(width 0.1)
				(type default)
			)
			(layer "B.Fab")
		)
		(fp_line
			(start 0.12065 -0.305054)
			(end 0.12065 -0.2794)
			(stroke
				(width 0.1)
				(type default)
			)
			(layer "B.Fab")
		)
		(fp_line
			(start 0.67945 -0.305054)
			(end 0.12065 -0.305054)
			(stroke
				(width 0.1)
				(type default)
			)
			(layer "B.Fab")
		)
		(pad "1" smd circle
			(at 0.40005 0 90)
			(size 0 0)
			(layers "B.Cu" "B.Mask" "B.Paste")
			(net "PVDD18_S5_P0")
		)
		(pad "2" smd circle
			(at -0.40005 0 90)
			(size 0 0)
			(layers "B.Cu" "B.Mask" "B.Paste")
			(net "FM_BOARD_SKU_ID3")
		)
	)
	(footprint ""
		(layer "B.Cu")
		(at 306.135278 -244.08511)
		(property "Reference" "R375"
			(at 0 0 0)
			(layer "B.SilkS")
			(hide yes)
			(effects
				(font
					(size 1.27 1.27)
				)
				(justify mirror)
			)
		)
		(property "Value" ""
			(at 0 0 0)
			(layer "B.Fab")
			(effects
				(font
					(size 1.27 1.27)
				)
				(justify mirror)
			)
		)
		(duplicate_pad_numbers_are_jumpers no)
		(fp_line
			(start -0.7874 -0.4064)
			(end -0.7874 0.4064)
			(stroke
				(width 0.1524)
				(type default)
			)
			(layer "B.SilkS")
		)
		(fp_line
			(start -0.7874 0.4064)
			(end 0.7874 0.4064)
			(stroke
				(width 0.1524)
				(type default)
			)
			(layer "B.SilkS")
		)
		(fp_line
			(start 0.7874 -0.4064)
			(end -0.7874 -0.4064)
			(stroke
				(width 0.1524)
				(type default)
			)
			(layer "B.SilkS")
		)
		(fp_line
			(start 0.7874 0.4064)
			(end 0.7874 -0.4064)
			(stroke
				(width 0.1524)
				(type default)
			)
			(layer "B.SilkS")
		)
		(fp_line
			(start -0.67945 -0.3048)
			(end -0.67945 0.3048)
			(stroke
				(width 0.1)
				(type default)
			)
			(layer "B.Fab")
		)
		(fp_line
			(start -0.67945 0.3048)
			(end -0.120396 0.3048)
			(stroke
				(width 0.1)
				(type default)
			)
			(layer "B.Fab")
		)
		(fp_line
			(start -0.12065 -0.3048)
			(end -0.67945 -0.3048)
			(stroke
				(width 0.1)
				(type default)
			)
			(layer "B.Fab")
		)
		(fp_line
			(start -0.12065 -0.2794)
			(end -0.12065 -0.3048)
			(stroke
				(width 0.1)
				(type default)
			)
			(layer "B.Fab")
		)
		(fp_line
			(start -0.120396 0.2794)
			(end 0.12065 0.2794)
			(stroke
				(width 0.1)
				(type default)
			)
			(layer "B.Fab")
		)
		(fp_line
			(start -0.120396 0.3048)
			(end -0.120396 0.2794)
			(stroke
				(width 0.1)
				(type default)
			)
			(layer "B.Fab")
		)
		(fp_line
			(start 0.12065 -0.305054)
			(end 0.12065 -0.2794)
			(stroke
				(width 0.1)
				(type default)
			)
			(layer "B.Fab")
		)
		(fp_line
			(start 0.12065 -0.2794)
			(end -0.12065 -0.2794)
			(stroke
				(width 0.1)
				(type default)
			)
			(layer "B.Fab")
		)
		(fp_line
			(start 0.12065 0.2794)
			(end 0.12065 0.3048)
			(stroke
				(width 0.1)
				(type default)
			)
			(layer "B.Fab")
		)
		(fp_line
			(start 0.12065 0.3048)
			(end 0.67945 0.3048)
			(stroke
				(width 0.1)
				(type default)
			)
			(layer "B.Fab")
		)
		(fp_line
			(start 0.67945 -0.305054)
			(end 0.12065 -0.305054)
			(stroke
				(width 0.1)
				(type default)
			)
			(layer "B.Fab")
		)
		(fp_line
			(start 0.67945 0.3048)
			(end 0.67945 -0.305054)
			(stroke
				(width 0.1)
				(type default)
			)
			(layer "B.Fab")
		)
		(pad "1" smd circle
			(at 0.40005 0 180)
			(size 0 0)
			(layers "B.Cu" "B.Mask" "B.Paste")
			(net "M_A_CPU0_ALERT_N")
		)
		(pad "2" smd circle
			(at -0.40005 0 180)
			(size 0 0)
			(layers "B.Cu" "B.Mask" "B.Paste")
			(net "M_A_CPU0_ALERT_R_N")
		)
	)
	(footprint ""
		(layer "B.Cu")
		(at 95.670878 -144.75841 -90)
		(property "Reference" "PU25"
			(at -3.958844 -4.823714 0)
			(unlocked yes)
			(layer "B.SilkS")
			(effects
				(font
					(size 0.7874 0.5842)
					(thickness 0.1524)
				)
				(justify mirror)
			)
		)
		(property "Value" ""
			(at 0 0 90)
			(layer "B.Fab")
			(effects
				(font
					(size 1.27 1.27)
				)
				(justify mirror)
			)
		)
		(duplicate_pad_numbers_are_jumpers no)
		(fp_line
			(start -3.024886 3.024886)
			(end -2.428494 3.024886)
			(stroke
				(width 0.1524)
				(type default)
			)
			(layer "B.SilkS")
		)
		(fp_line
			(start 2.428494 3.024886)
			(end 3.024886 3.024886)
			(stroke
				(width 0.1524)
				(type default)
			)
			(layer "B.SilkS")
		)
		(fp_line
			(start 3.024886 3.024886)
			(end 3.024886 2.428494)
			(stroke
				(width 0.1524)
				(type default)
			)
			(layer "B.SilkS")
		)
		(fp_line
			(start -3.024886 2.428494)
			(end -3.024886 3.024886)
			(stroke
				(width 0.1524)
				(type default)
			)
			(layer "B.SilkS")
		)
		(fp_line
			(start 3.024886 -2.428494)
			(end 3.024886 -3.024886)
			(stroke
				(width 0.1524)
				(type default)
			)
			(layer "B.SilkS")
		)
		(fp_line
			(start -3.024886 -3.024886)
			(end -3.024886 -2.428494)
			(stroke
				(width 0.1524)
				(type default)
			)
			(layer "B.SilkS")
		)
		(fp_line
			(start -2.428494 -3.024886)
			(end -3.024886 -3.024886)
			(stroke
				(width 0.1524)
				(type default)
			)
			(layer "B.SilkS")
		)
		(fp_line
			(start 3.024886 -3.024886)
			(end 2.428494 -3.024886)
			(stroke
				(width 0.1524)
				(type default)
			)
			(layer "B.SilkS")
		)
		(fp_poly
			(pts
				(xy 5.493004 -2.284222) (xy 5.202682 -1.310386) (xy 4.374134 -2.088134)
			)
			(stroke
				(width 0)
				(type default)
			)
			(fill yes)
			(layer "B.SilkS")
		)
		(fp_line
			(start -3.024886 3.024886)
			(end 3.024886 3.024886)
			(stroke
				(width 0.1)
				(type default)
			)
			(layer "B.Fab")
		)
		(fp_line
			(start 3.024886 3.024886)
			(end 3.024886 -3.024886)
			(stroke
				(width 0.1)
				(type default)
			)
			(layer "B.Fab")
		)
		(fp_line
			(start -3.024886 -3.024886)
			(end -3.024886 3.024886)
			(stroke
				(width 0.1)
				(type default)
			)
			(layer "B.Fab")
		)
		(fp_line
			(start 3.024886 -3.024886)
			(end -3.024886 -3.024886)
			(stroke
				(width 0.1)
				(type default)
			)
			(layer "B.Fab")
		)
		(fp_poly
			(pts
				(xy 3.332226 -2.199894) (xy 4.348226 -1.691894) (xy 4.348226 -2.707894)
			)
			(stroke
				(width 0)
				(type default)
			)
			(fill yes)
			(layer "B.Fab")
		)
		(pad "1" smd rect
			(at 2.875026 -2.199894 180)
			(size 0.1778 0.6604)
			(layers "B.Cu" "B.Mask" "B.Paste")
			(net "PVDDCR_SOC_P1_PWM1")
		)
		(pad "2" smd rect
			(at 2.875026 -1.800098 180)
			(size 0.1778 0.6604)
			(layers "B.Cu" "B.Mask" "B.Paste")
			(net "PVDDCR_SOC_P1_PWM2")
		)
		(pad "3" smd rect
			(at 2.875026 -1.400048 180)
			(size 0.1778 0.6604)
			(layers "B.Cu" "B.Mask" "B.Paste")
			(net "PVDDCR_SOC_P1_PWM3")
		)
		(pad "4" smd rect
			(at 2.875026 -0.999998 180)
			(size 0.1778 0.6604)
			(layers "B.Cu" "B.Mask" "B.Paste")
			(net "NC_PVDDCR_CPU0_P1_PWM9")
		)
		(pad "5" smd rect
			(at 2.875026 -0.599948 180)
			(size 0.1778 0.6604)
			(layers "B.Cu" "B.Mask" "B.Paste")
			(net "NC_PVDDCR_CPU0_P1_PWM8")
		)
		(pad "6" smd rect
			(at 2.875026 -0.199898 180)
			(size 0.1778 0.6604)
			(layers "B.Cu" "B.Mask" "B.Paste")
			(net "NC_PVDDCR_CPU0_P1_PWM7")
		)
		(pad "7" smd rect
			(at 2.875026 0.199898 180)
			(size 0.1778 0.6604)
			(layers "B.Cu" "B.Mask" "B.Paste")
			(net "PVDDCR_CPU0_P1_PWM6")
		)
		(pad "8" smd rect
			(at 2.875026 0.599948 180)
			(size 0.1778 0.6604)
			(layers "B.Cu" "B.Mask" "B.Paste")
			(net "PVDDCR_CPU0_P1_PWM5")
		)
		(pad "9" smd rect
			(at 2.875026 0.999998 180)
			(size 0.1778 0.6604)
			(layers "B.Cu" "B.Mask" "B.Paste")
			(net "PVDDCR_CPU0_P1_PWM4")
		)
		(pad "10" smd rect
			(at 2.875026 1.400048 180)
			(size 0.1778 0.6604)
			(layers "B.Cu" "B.Mask" "B.Paste")
			(net "PVDDCR_CPU0_P1_PWM3")
		)
		(pad "11" smd rect
			(at 2.875026 1.800098 180)
			(size 0.1778 0.6604)
			(layers "B.Cu" "B.Mask" "B.Paste")
			(net "PVDDCR_CPU0_P1_PWM2")
		)
		(pad "12" smd rect
			(at 2.875026 2.199894 180)
			(size 0.1778 0.6604)
			(layers "B.Cu" "B.Mask" "B.Paste")
			(net "PVDDCR_CPU0_P1_PWM1")
		)
		(pad "13" smd rect
			(at 2.199894 2.875026 90)
			(size 0.1778 0.6604)
			(layers "B.Cu" "B.Mask" "B.Paste")
			(net "PVDDCR_CPU0_P1_PMSDA_R")
		)
		(pad "14" smd rect
			(at 1.800098 2.875026 90)
			(size 0.1778 0.6604)
			(layers "B.Cu" "B.Mask" "B.Paste")
			(net "PVDDCR_CPU0_P1_PMSCL_R")
		)
		(pad "15" smd rect
			(at 1.400048 2.875026 90)
			(size 0.1778 0.6604)
			(layers "B.Cu" "B.Mask" "B.Paste")
			(net "PVDDCR_CPU0_P1_PMALERT_R")
		)
		(pad "16" smd rect
			(at 0.999998 2.875026 90)
			(size 0.1778 0.6604)
			(layers "B.Cu" "B.Mask" "B.Paste")
			(net "PWRGD_PVDDCR_CPU0_P1_R")
		)
		(pad "17" smd rect
			(at 0.599948 2.875026 90)
			(size 0.1778 0.6604)
			(layers "B.Cu" "B.Mask" "B.Paste")
			(net "PVDDCR_CPU0_P1_EN_R")
		)
		(pad "18" smd rect
			(at 0.199898 2.875026 90)
			(size 0.1778 0.6604)
			(layers "B.Cu" "B.Mask" "B.Paste")
			(net "PVDDCR_CPU0_P1_RESET_N_R")
		)
		(pad "19" smd rect
			(at -0.199898 2.875026 90)
			(size 0.1778 0.6604)
			(layers "B.Cu" "B.Mask" "B.Paste")
			(net "PVDD18_S5_P1")
		)
		(pad "20" smd rect
			(at -0.599948 2.875026 90)
			(size 0.1778 0.6604)
			(layers "B.Cu" "B.Mask" "B.Paste")
			(net "PWRGD_PVDDCR_SOC_P1_R")
		)
		(pad "21" smd rect
			(at -0.999998 2.875026 90)
			(size 0.1778 0.6604)
			(layers "B.Cu" "B.Mask" "B.Paste")
			(net "SVID_PVDDCR_CPU0_P1_SVD_R1")
		)
		(pad "22" smd rect
			(at -1.400048 2.875026 90)
			(size 0.1778 0.6604)
			(layers "B.Cu" "B.Mask" "B.Paste")
			(net "SVID_PVDDCR_CPU0_P1_SVC_R1")
		)
		(pad "23" smd rect
			(at -1.800098 2.875026 90)
			(size 0.1778 0.6604)
			(layers "B.Cu" "B.Mask" "B.Paste")
			(net "SVID_PVDDCR_CPU0_P1_SVTO_R")
		)
		(pad "24" smd rect
			(at -2.199894 2.875026 90)
			(size 0.1778 0.6604)
			(layers "B.Cu" "B.Mask" "B.Paste")
			(net "SVID_PVDDCR_CPU0_P1_SVTI_R")
		)
		(pad "25" smd rect
			(at -2.875026 2.199894 180)
			(size 0.1778 0.6604)
			(layers "B.Cu" "B.Mask" "B.Paste")
			(net "VSENSE_PVDDCR_CPU0_P1_VSEN0")
		)
		(pad "26" smd rect
			(at -2.875026 1.800098 180)
			(size 0.1778 0.6604)
			(layers "B.Cu" "B.Mask" "B.Paste")
			(net "VSENSE_VSS_SENSE_A_P1")
		)
		(pad "27" smd rect
			(at -2.875026 1.400048 180)
			(size 0.1778 0.6604)
			(layers "B.Cu" "B.Mask" "B.Paste")
			(net "PVDDCR_CPU0_P1_IMON1")
		)
		(pad "28" smd rect
			(at -2.875026 0.999998 180)
			(size 0.1778 0.6604)
			(layers "B.Cu" "B.Mask" "B.Paste")
			(net "PVDDCR_CPU0_P1_IMON2")
		)
		(pad "29" smd rect
			(at -2.875026 0.599948 180)
			(size 0.1778 0.6604)
			(layers "B.Cu" "B.Mask" "B.Paste")
			(net "PVDDCR_CPU0_P1_IMON3")
		)
		(pad "30" smd rect
			(at -2.875026 0.199898 180)
			(size 0.1778 0.6604)
			(layers "B.Cu" "B.Mask" "B.Paste")
			(net "PVDDCR_CPU0_P1_IMON4")
		)
		(pad "31" smd rect
			(at -2.875026 -0.199898 180)
			(size 0.1778 0.6604)
			(layers "B.Cu" "B.Mask" "B.Paste")
			(net "PVDDCR_CPU0_P1_IMON5")
		)
		(pad "32" smd rect
			(at -2.875026 -0.599948 180)
			(size 0.1778 0.6604)
			(layers "B.Cu" "B.Mask" "B.Paste")
			(net "PVDDCR_CPU0_P1_IMON6")
		)
		(pad "33" smd rect
			(at -2.875026 -0.999998 180)
			(size 0.1778 0.6604)
			(layers "B.Cu" "B.Mask" "B.Paste")
			(net "NC_PVDDCR_CPU0_P1_IMON7")
		)
		(pad "34" smd rect
			(at -2.875026 -1.400048 180)
			(size 0.1778 0.6604)
			(layers "B.Cu" "B.Mask" "B.Paste")
			(net "NC_PVDDCR_CPU0_P1_IMON8")
		)
		(pad "35" smd rect
			(at -2.875026 -1.800098 180)
			(size 0.1778 0.6604)
			(layers "B.Cu" "B.Mask" "B.Paste")
			(net "NC_PVDDCR_CPU0_P1_IMON9")
		)
		(pad "36" smd rect
			(at -2.875026 -2.199894 180)
			(size 0.1778 0.6604)
			(layers "B.Cu" "B.Mask" "B.Paste")
			(net "PVDDCR_SOC_P1_IMON3")
		)
		(pad "37" smd rect
			(at -2.199894 -2.875026 90)
			(size 0.1778 0.6604)
			(layers "B.Cu" "B.Mask" "B.Paste")
			(net "PVDDCR_SOC_P1_IMON2")
		)
		(pad "38" smd rect
			(at -1.800098 -2.875026 90)
			(size 0.1778 0.6604)
			(layers "B.Cu" "B.Mask" "B.Paste")
			(net "PVDDCR_SOC_P1_IMON1")
		)
		(pad "39" smd rect
			(at -1.400048 -2.875026 90)
			(size 0.1778 0.6604)
			(layers "B.Cu" "B.Mask" "B.Paste")
			(net "VSENSE_VSS_SENSE_A_P1")
		)
		(pad "40" smd rect
			(at -0.999998 -2.875026 90)
			(size 0.1778 0.6604)
			(layers "B.Cu" "B.Mask" "B.Paste")
			(net "VSENSE_PVDDCR_SOC_P1_VSEN1")
		)
		(pad "41" smd rect
			(at -0.599948 -2.875026 90)
			(size 0.1778 0.6604)
			(layers "B.Cu" "B.Mask" "B.Paste")
			(net "PVDDCR_CPU0_P1_OCP_N_R")
		)
		(pad "42" smd rect
			(at -0.199898 -2.875026 90)
			(size 0.1778 0.6604)
			(layers "B.Cu" "B.Mask" "B.Paste")
			(net "PVDDCR_SOC_P1_EN//ADDR_CFG")
		)
		(pad "43" smd rect
			(at 0.199898 -2.875026 90)
			(size 0.1778 0.6604)
			(layers "B.Cu" "B.Mask" "B.Paste")
			(net "PVDDCR_SOC_P1_TEMP1")
		)
		(pad "44" smd rect
			(at 0.599948 -2.875026 90)
			(size 0.1778 0.6604)
			(layers "B.Cu" "B.Mask" "B.Paste")
			(net "PVDDCR_CPU0_P1_TEMP0")
		)
		(pad "45" smd rect
			(at 0.999998 -2.875026 90)
			(size 0.1778 0.6604)
			(layers "B.Cu" "B.Mask" "B.Paste")
			(net "PVDDCR_CPU0_P1_VMON")
		)
		(pad "46" smd rect
			(at 1.400048 -2.875026 90)
			(size 0.1778 0.6604)
			(layers "B.Cu" "B.Mask" "B.Paste")
			(net "PVDDCR_CPU0_P1_VINSEN")
		)
		(pad "47" smd rect
			(at 1.800098 -2.875026 90)
			(size 0.1778 0.6604)
			(layers "B.Cu" "B.Mask" "B.Paste")
			(net "PVDDCR_CPU0_P1_VCC")
		)
		(pad "48" smd rect
			(at 2.199894 -2.875026 90)
			(size 0.1778 0.6604)
			(layers "B.Cu" "B.Mask" "B.Paste")
			(net "PVDDCR_CPU0_P1_VCCS")
		)
		(pad "TH" smd rect
			(at 0 0 90)
			(size 4.4196 4.4196)
			(layers "B.Cu" "B.Mask" "B.Paste")
			(net "GND")
		)
		(zone
			(layer "B.Cu")
			(hatch none 0.5)
			(connect_pads
				(clearance 0)
			)
			(min_thickness 0.25)
			(keepout
				(tracks not_allowed)
				(vias allowed)
				(pads allowed)
				(copperpour not_allowed)
				(footprints allowed)
			)
			(placement
				(enabled no)
				(sheetname "")
			)
			(fill
				(thermal_gap 0.5)
				(thermal_bridge_width 0.5)
				(island_removal_mode 0)
			)
			(polygon
				(pts
					(xy 95.696278 -142.264384) (xy 98.164904 -142.264384) (xy 98.164904 -147.252436) (xy 93.176852 -147.252436)
					(xy 93.176852 -142.264384) (xy 95.670878 -142.264384) (xy 95.670878 -142.49781) (xy 93.410278 -142.49781)
					(xy 93.410278 -147.01901) (xy 97.931478 -147.01901) (xy 97.931478 -142.49781) (xy 95.696278 -142.49781)
				)
			)
		)
	)
	(footprint ""
		(layer "B.Cu")
		(at 312.978292 -395.148562 90)
		(property "Reference" "C515"
			(at 0 0 90)
			(layer "B.SilkS")
			(hide yes)
			(effects
				(font
					(size 1.27 1.27)
				)
				(justify mirror)
			)
		)
		(property "Value" ""
			(at 0 0 90)
			(layer "B.Fab")
			(effects
				(font
					(size 1.27 1.27)
				)
				(justify mirror)
			)
		)
		(duplicate_pad_numbers_are_jumpers no)
		(fp_line
			(start 0.299974 -0.150114)
			(end -0.299974 -0.150114)
			(stroke
				(width 0.1)
				(type default)
			)
			(layer "B.Fab")
		)
		(fp_line
			(start -0.299974 -0.150114)
			(end -0.299974 0.150114)
			(stroke
				(width 0.1)
				(type default)
			)
			(layer "B.Fab")
		)
		(fp_line
			(start 0.299974 0.150114)
			(end 0.299974 -0.150114)
			(stroke
				(width 0.1)
				(type default)
			)
			(layer "B.Fab")
		)
		(fp_line
			(start -0.299974 0.150114)
			(end 0.299974 0.150114)
			(stroke
				(width 0.1)
				(type default)
			)
			(layer "B.Fab")
		)
		(pad "1" smd rect
			(at 0.2667 0 270)
			(size 0.3048 0.381)
			(layers "B.Cu" "B.Mask" "B.Paste")
			(net "P1V8_CPU0_RT0_1A")
		)
		(pad "2" smd rect
			(at -0.2667 0 270)
			(size 0.3048 0.381)
			(layers "B.Cu" "B.Mask" "B.Paste")
			(net "GND")
		)
	)
	(footprint ""
		(layer "B.Cu")
		(at 113.81486 -34.351468 90)
		(property "Reference" "C6105"
			(at 0 0 90)
			(layer "B.SilkS")
			(hide yes)
			(effects
				(font
					(size 1.27 1.27)
				)
				(justify mirror)
			)
		)
		(property "Value" ""
			(at 0 0 90)
			(layer "B.Fab")
			(effects
				(font
					(size 1.27 1.27)
				)
				(justify mirror)
			)
		)
		(duplicate_pad_numbers_are_jumpers no)
		(fp_line
			(start 1.524 -0.762)
			(end -1.524 -0.762)
			(stroke
				(width 0.1524)
				(type default)
			)
			(layer "B.SilkS")
		)
		(fp_line
			(start -1.524 -0.762)
			(end -1.524 0.762)
			(stroke
				(width 0.1524)
				(type default)
			)
			(layer "B.SilkS")
		)
		(fp_line
			(start 1.524 0.762)
			(end 1.524 -0.762)
			(stroke
				(width 0.1524)
				(type default)
			)
			(layer "B.SilkS")
		)
		(fp_line
			(start -1.524 0.762)
			(end 1.524 0.762)
			(stroke
				(width 0.1524)
				(type default)
			)
			(layer "B.SilkS")
		)
		(fp_line
			(start 1.1049 -0.724916)
			(end 1.1049 0.724916)
			(stroke
				(width 0.1)
				(type default)
			)
			(layer "B.Fab")
		)
		(fp_line
			(start -1.1049 -0.724916)
			(end 1.1049 -0.724916)
			(stroke
				(width 0.1)
				(type default)
			)
			(layer "B.Fab")
		)
		(fp_line
			(start 1.1049 0.724916)
			(end -1.1049 0.724916)
			(stroke
				(width 0.1)
				(type default)
			)
			(layer "B.Fab")
		)
		(fp_line
			(start -1.1049 0.724916)
			(end -1.1049 -0.724916)
			(stroke
				(width 0.1)
				(type default)
			)
			(layer "B.Fab")
		)
		(pad "1" smd rect
			(at 0.889 0 90)
			(size 1.016 1.27)
			(layers "B.Cu" "B.Mask" "B.Paste")
			(net "P1V2_CPU0_USB2_DVDD12")
		)
		(pad "2" smd rect
			(at -0.889 0 90)
			(size 1.016 1.27)
			(layers "B.Cu" "B.Mask" "B.Paste")
			(net "GND")
		)
	)
	(footprint ""
		(layer "B.Cu")
		(at 126.491238 -390.909302 90)
		(property "Reference" "C454"
			(at 0 0 90)
			(layer "B.SilkS")
			(hide yes)
			(effects
				(font
					(size 1.27 1.27)
				)
				(justify mirror)
			)
		)
		(property "Value" ""
			(at 0 0 90)
			(layer "B.Fab")
			(effects
				(font
					(size 1.27 1.27)
				)
				(justify mirror)
			)
		)
		(duplicate_pad_numbers_are_jumpers no)
		(fp_line
			(start 0.299974 -0.150114)
			(end -0.299974 -0.150114)
			(stroke
				(width 0.1)
				(type default)
			)
			(layer "B.Fab")
		)
		(fp_line
			(start -0.299974 -0.150114)
			(end -0.299974 0.150114)
			(stroke
				(width 0.1)
				(type default)
			)
			(layer "B.Fab")
		)
		(fp_line
			(start 0.299974 0.150114)
			(end 0.299974 -0.150114)
			(stroke
				(width 0.1)
				(type default)
			)
			(layer "B.Fab")
		)
		(fp_line
			(start -0.299974 0.150114)
			(end 0.299974 0.150114)
			(stroke
				(width 0.1)
				(type default)
			)
			(layer "B.Fab")
		)
		(pad "1" smd rect
			(at 0.2667 0 270)
			(size 0.3048 0.381)
			(layers "B.Cu" "B.Mask" "B.Paste")
			(net "P0V9_CPU1_RT_2D")
		)
		(pad "2" smd rect
			(at -0.2667 0 270)
			(size 0.3048 0.381)
			(layers "B.Cu" "B.Mask" "B.Paste")
			(net "GND")
		)
	)
	(footprint ""
		(layer "B.Cu")
		(at 454.068688 -13.102844 90)
		(property "Reference" "R3132"
			(at 0 0 90)
			(layer "B.SilkS")
			(hide yes)
			(effects
				(font
					(size 1.27 1.27)
				)
				(justify mirror)
			)
		)
		(property "Value" ""
			(at 0 0 90)
			(layer "B.Fab")
			(effects
				(font
					(size 1.27 1.27)
				)
				(justify mirror)
			)
		)
		(duplicate_pad_numbers_are_jumpers no)
		(fp_line
			(start 0.7874 -0.4064)
			(end -0.7874 -0.4064)
			(stroke
				(width 0.1524)
				(type default)
			)
			(layer "B.SilkS")
		)
		(fp_line
			(start -0.7874 -0.4064)
			(end -0.7874 0.4064)
			(stroke
				(width 0.1524)
				(type default)
			)
			(layer "B.SilkS")
		)
		(fp_line
			(start 0.7874 0.4064)
			(end 0.7874 -0.4064)
			(stroke
				(width 0.1524)
				(type default)
			)
			(layer "B.SilkS")
		)
		(fp_line
			(start -0.7874 0.4064)
			(end 0.7874 0.4064)
			(stroke
				(width 0.1524)
				(type default)
			)
			(layer "B.SilkS")
		)
		(fp_line
			(start 0.67945 -0.305054)
			(end 0.12065 -0.305054)
			(stroke
				(width 0.1)
				(type default)
			)
			(layer "B.Fab")
		)
		(fp_line
			(start 0.12065 -0.305054)
			(end 0.12065 -0.2794)
			(stroke
				(width 0.1)
				(type default)
			)
			(layer "B.Fab")
		)
		(fp_line
			(start -0.12065 -0.3048)
			(end -0.67945 -0.3048)
			(stroke
				(width 0.1)
				(type default)
			)
			(layer "B.Fab")
		)
		(fp_line
			(start -0.67945 -0.3048)
			(end -0.67945 0.3048)
			(stroke
				(width 0.1)
				(type default)
			)
			(layer "B.Fab")
		)
		(fp_line
			(start 0.12065 -0.2794)
			(end -0.12065 -0.2794)
			(stroke
				(width 0.1)
				(type default)
			)
			(layer "B.Fab")
		)
		(fp_line
			(start -0.12065 -0.2794)
			(end -0.12065 -0.3048)
			(stroke
				(width 0.1)
				(type default)
			)
			(layer "B.Fab")
		)
		(fp_line
			(start 0.12065 0.2794)
			(end 0.12065 0.3048)
			(stroke
				(width 0.1)
				(type default)
			)
			(layer "B.Fab")
		)
		(fp_line
			(start -0.120396 0.2794)
			(end 0.12065 0.2794)
			(stroke
				(width 0.1)
				(type default)
			)
			(layer "B.Fab")
		)
		(fp_line
			(start 0.67945 0.3048)
			(end 0.67945 -0.305054)
			(stroke
				(width 0.1)
				(type default)
			)
			(layer "B.Fab")
		)
		(fp_line
			(start 0.12065 0.3048)
			(end 0.67945 0.3048)
			(stroke
				(width 0.1)
				(type default)
			)
			(layer "B.Fab")
		)
		(fp_line
			(start -0.120396 0.3048)
			(end -0.120396 0.2794)
			(stroke
				(width 0.1)
				(type default)
			)
			(layer "B.Fab")
		)
		(fp_line
			(start -0.67945 0.3048)
			(end -0.120396 0.3048)
			(stroke
				(width 0.1)
				(type default)
			)
			(layer "B.Fab")
		)
		(pad "1" smd circle
			(at 0.40005 0 270)
			(size 0 0)
			(layers "B.Cu" "B.Mask" "B.Paste")
			(net "GND")
		)
		(pad "2" smd circle
			(at -0.40005 0 270)
			(size 0 0)
			(layers "B.Cu" "B.Mask" "B.Paste")
			(net "FM_OCP_SFF_PWR_GOOD")
		)
	)
	(footprint ""
		(layer "B.Cu")
		(at 416.206178 -395.148562 90)
		(property "Reference" "C793"
			(at 0 0 90)
			(layer "B.SilkS")
			(hide yes)
			(effects
				(font
					(size 1.27 1.27)
				)
				(justify mirror)
			)
		)
		(property "Value" ""
			(at 0 0 90)
			(layer "B.Fab")
			(effects
				(font
					(size 1.27 1.27)
				)
				(justify mirror)
			)
		)
		(duplicate_pad_numbers_are_jumpers no)
		(fp_line
			(start 0.299974 -0.150114)
			(end -0.299974 -0.150114)
			(stroke
				(width 0.1)
				(type default)
			)
			(layer "B.Fab")
		)
		(fp_line
			(start -0.299974 -0.150114)
			(end -0.299974 0.150114)
			(stroke
				(width 0.1)
				(type default)
			)
			(layer "B.Fab")
		)
		(fp_line
			(start 0.299974 0.150114)
			(end 0.299974 -0.150114)
			(stroke
				(width 0.1)
				(type default)
			)
			(layer "B.Fab")
		)
		(fp_line
			(start -0.299974 0.150114)
			(end 0.299974 0.150114)
			(stroke
				(width 0.1)
				(type default)
			)
			(layer "B.Fab")
		)
		(pad "1" smd rect
			(at 0.2667 0 270)
			(size 0.3048 0.381)
			(layers "B.Cu" "B.Mask" "B.Paste")
			(net "P0V9_CPU0_RT2_2A_2D")
		)
		(pad "2" smd rect
			(at -0.2667 0 270)
			(size 0.3048 0.381)
			(layers "B.Cu" "B.Mask" "B.Paste")
			(net "GND")
		)
	)
	(footprint ""
		(layer "B.Cu")
		(at 155.546298 -388.011162 -90)
		(property "Reference" "C376"
			(at 0 0 90)
			(layer "B.SilkS")
			(hide yes)
			(effects
				(font
					(size 1.27 1.27)
				)
				(justify mirror)
			)
		)
		(property "Value" ""
			(at 0 0 90)
			(layer "B.Fab")
			(effects
				(font
					(size 1.27 1.27)
				)
				(justify mirror)
			)
		)
		(duplicate_pad_numbers_are_jumpers no)
		(fp_line
			(start -0.299974 0.150114)
			(end 0.299974 0.150114)
			(stroke
				(width 0.1)
				(type default)
			)
			(layer "B.Fab")
		)
		(fp_line
			(start 0.299974 0.150114)
			(end 0.299974 -0.150114)
			(stroke
				(width 0.1)
				(type default)
			)
			(layer "B.Fab")
		)
		(fp_line
			(start -0.299974 -0.150114)
			(end -0.299974 0.150114)
			(stroke
				(width 0.1)
				(type default)
			)
			(layer "B.Fab")
		)
		(fp_line
			(start 0.299974 -0.150114)
			(end -0.299974 -0.150114)
			(stroke
				(width 0.1)
				(type default)
			)
			(layer "B.Fab")
		)
		(pad "1" smd rect
			(at 0.2667 0 90)
			(size 0.3048 0.381)
			(layers "B.Cu" "B.Mask" "B.Paste")
			(net "P1V8_CPU1_RT2_1A")
		)
		(pad "2" smd rect
			(at -0.2667 0 90)
			(size 0.3048 0.381)
			(layers "B.Cu" "B.Mask" "B.Paste")
			(net "GND")
		)
	)
	(footprint ""
		(layer "B.Cu")
		(at 357.708454 -268.41831)
		(property "Reference" "C2203"
			(at 0 0 0)
			(layer "B.SilkS")
			(hide yes)
			(effects
				(font
					(size 1.27 1.27)
				)
				(justify mirror)
			)
		)
		(property "Value" ""
			(at 0 0 0)
			(layer "B.Fab")
			(effects
				(font
					(size 1.27 1.27)
				)
				(justify mirror)
			)
		)
		(duplicate_pad_numbers_are_jumpers no)
		(fp_line
			(start -0.7874 -0.4064)
			(end -0.7874 0.4064)
			(stroke
				(width 0.1524)
				(type default)
			)
			(layer "B.SilkS")
		)
		(fp_line
			(start -0.7874 0.4064)
			(end 0.7874 0.4064)
			(stroke
				(width 0.1524)
				(type default)
			)
			(layer "B.SilkS")
		)
		(fp_line
			(start 0.7874 -0.4064)
			(end -0.7874 -0.4064)
			(stroke
				(width 0.1524)
				(type default)
			)
			(layer "B.SilkS")
		)
		(fp_line
			(start 0.7874 0.4064)
			(end 0.7874 -0.4064)
			(stroke
				(width 0.1524)
				(type default)
			)
			(layer "B.SilkS")
		)
		(fp_line
			(start -0.67945 -0.3048)
			(end -0.67945 0.3048)
			(stroke
				(width 0.1)
				(type default)
			)
			(layer "B.Fab")
		)
		(fp_line
			(start -0.67945 0.3048)
			(end -0.120396 0.3048)
			(stroke
				(width 0.1)
				(type default)
			)
			(layer "B.Fab")
		)
		(fp_line
			(start -0.12065 -0.3048)
			(end -0.67945 -0.3048)
			(stroke
				(width 0.1)
				(type default)
			)
			(layer "B.Fab")
		)
		(fp_line
			(start -0.12065 -0.2794)
			(end -0.12065 -0.3048)
			(stroke
				(width 0.1)
				(type default)
			)
			(layer "B.Fab")
		)
		(fp_line
			(start -0.120396 0.2794)
			(end 0.12065 0.2794)
			(stroke
				(width 0.1)
				(type default)
			)
			(layer "B.Fab")
		)
		(fp_line
			(start -0.120396 0.3048)
			(end -0.120396 0.2794)
			(stroke
				(width 0.1)
				(type default)
			)
			(layer "B.Fab")
		)
		(fp_line
			(start 0.12065 -0.305054)
			(end 0.12065 -0.2794)
			(stroke
				(width 0.1)
				(type default)
			)
			(layer "B.Fab")
		)
		(fp_line
			(start 0.12065 -0.2794)
			(end -0.12065 -0.2794)
			(stroke
				(width 0.1)
				(type default)
			)
			(layer "B.Fab")
		)
		(fp_line
			(start 0.12065 0.2794)
			(end 0.12065 0.3048)
			(stroke
				(width 0.1)
				(type default)
			)
			(layer "B.Fab")
		)
		(fp_line
			(start 0.12065 0.3048)
			(end 0.67945 0.3048)
			(stroke
				(width 0.1)
				(type default)
			)
			(layer "B.Fab")
		)
		(fp_line
			(start 0.67945 -0.305054)
			(end 0.12065 -0.305054)
			(stroke
				(width 0.1)
				(type default)
			)
			(layer "B.Fab")
		)
		(fp_line
			(start 0.67945 0.3048)
			(end 0.67945 -0.305054)
			(stroke
				(width 0.1)
				(type default)
			)
			(layer "B.Fab")
		)
		(pad "1" smd circle
			(at 0.40005 0 180)
			(size 0 0)
			(layers "B.Cu" "B.Mask" "B.Paste")
			(net "PVDDCR_CPU1_P0")
		)
		(pad "2" smd circle
			(at -0.40005 0 180)
			(size 0 0)
			(layers "B.Cu" "B.Mask" "B.Paste")
			(net "GND")
		)
	)
	(footprint ""
		(layer "B.Cu")
		(at 382.491234 -399.291302 90)
		(property "Reference" "C1016"
			(at 0 0 90)
			(layer "B.SilkS")
			(hide yes)
			(effects
				(font
					(size 1.27 1.27)
				)
				(justify mirror)
			)
		)
		(property "Value" ""
			(at 0 0 90)
			(layer "B.Fab")
			(effects
				(font
					(size 1.27 1.27)
				)
				(justify mirror)
			)
		)
		(duplicate_pad_numbers_are_jumpers no)
		(fp_line
			(start 0.299974 -0.150114)
			(end -0.299974 -0.150114)
			(stroke
				(width 0.1)
				(type default)
			)
			(layer "B.Fab")
		)
		(fp_line
			(start -0.299974 -0.150114)
			(end -0.299974 0.150114)
			(stroke
				(width 0.1)
				(type default)
			)
			(layer "B.Fab")
		)
		(fp_line
			(start 0.299974 0.150114)
			(end 0.299974 -0.150114)
			(stroke
				(width 0.1)
				(type default)
			)
			(layer "B.Fab")
		)
		(fp_line
			(start -0.299974 0.150114)
			(end 0.299974 0.150114)
			(stroke
				(width 0.1)
				(type default)
			)
			(layer "B.Fab")
		)
		(pad "1" smd rect
			(at 0.2667 0 270)
			(size 0.3048 0.381)
			(layers "B.Cu" "B.Mask" "B.Paste")
			(net "P0V9_CPU0_RT_2D")
		)
		(pad "2" smd rect
			(at -0.2667 0 270)
			(size 0.3048 0.381)
			(layers "B.Cu" "B.Mask" "B.Paste")
			(net "GND")
		)
	)
	(footprint ""
		(layer "B.Cu")
		(at 155.491434 -316.049152 90)
		(property "Reference" "C239"
			(at 0 0 90)
			(layer "B.SilkS")
			(hide yes)
			(effects
				(font
					(size 1.27 1.27)
				)
				(justify mirror)
			)
		)
		(property "Value" ""
			(at 0 0 90)
			(layer "B.Fab")
			(effects
				(font
					(size 1.27 1.27)
				)
				(justify mirror)
			)
		)
		(duplicate_pad_numbers_are_jumpers no)
		(fp_line
			(start 0.7874 -0.4064)
			(end -0.7874 -0.4064)
			(stroke
				(width 0.1524)
				(type default)
			)
			(layer "B.SilkS")
		)
		(fp_line
			(start -0.7874 -0.4064)
			(end -0.7874 0.4064)
			(stroke
				(width 0.1524)
				(type default)
			)
			(layer "B.SilkS")
		)
		(fp_line
			(start 0.7874 0.4064)
			(end 0.7874 -0.4064)
			(stroke
				(width 0.1524)
				(type default)
			)
			(layer "B.SilkS")
		)
		(fp_line
			(start -0.7874 0.4064)
			(end 0.7874 0.4064)
			(stroke
				(width 0.1524)
				(type default)
			)
			(layer "B.SilkS")
		)
		(fp_line
			(start 0.67945 -0.305054)
			(end 0.12065 -0.305054)
			(stroke
				(width 0.1)
				(type default)
			)
			(layer "B.Fab")
		)
		(fp_line
			(start 0.12065 -0.305054)
			(end 0.12065 -0.2794)
			(stroke
				(width 0.1)
				(type default)
			)
			(layer "B.Fab")
		)
		(fp_line
			(start -0.12065 -0.3048)
			(end -0.67945 -0.3048)
			(stroke
				(width 0.1)
				(type default)
			)
			(layer "B.Fab")
		)
		(fp_line
			(start -0.67945 -0.3048)
			(end -0.67945 0.3048)
			(stroke
				(width 0.1)
				(type default)
			)
			(layer "B.Fab")
		)
		(fp_line
			(start 0.12065 -0.2794)
			(end -0.12065 -0.2794)
			(stroke
				(width 0.1)
				(type default)
			)
			(layer "B.Fab")
		)
		(fp_line
			(start -0.12065 -0.2794)
			(end -0.12065 -0.3048)
			(stroke
				(width 0.1)
				(type default)
			)
			(layer "B.Fab")
		)
		(fp_line
			(start 0.12065 0.2794)
			(end 0.12065 0.3048)
			(stroke
				(width 0.1)
				(type default)
			)
			(layer "B.Fab")
		)
		(fp_line
			(start -0.120396 0.2794)
			(end 0.12065 0.2794)
			(stroke
				(width 0.1)
				(type default)
			)
			(layer "B.Fab")
		)
		(fp_line
			(start 0.67945 0.3048)
			(end 0.67945 -0.305054)
			(stroke
				(width 0.1)
				(type default)
			)
			(layer "B.Fab")
		)
		(fp_line
			(start 0.12065 0.3048)
			(end 0.67945 0.3048)
			(stroke
				(width 0.1)
				(type default)
			)
			(layer "B.Fab")
		)
		(fp_line
			(start -0.120396 0.3048)
			(end -0.120396 0.2794)
			(stroke
				(width 0.1)
				(type default)
			)
			(layer "B.Fab")
		)
		(fp_line
			(start -0.67945 0.3048)
			(end -0.120396 0.3048)
			(stroke
				(width 0.1)
				(type default)
			)
			(layer "B.Fab")
		)
		(pad "1" smd circle
			(at 0.40005 0 270)
			(size 0 0)
			(layers "B.Cu" "B.Mask" "B.Paste")
			(net "XTAL_CPU1_R_X32K_X2")
		)
		(pad "2" smd circle
			(at -0.40005 0 270)
			(size 0 0)
			(layers "B.Cu" "B.Mask" "B.Paste")
			(net "GND")
		)
	)
	(footprint ""
		(layer "B.Cu")
		(at 59.378596 -386.766562 90)
		(property "Reference" "C266"
			(at 0 0 90)
			(layer "B.SilkS")
			(hide yes)
			(effects
				(font
					(size 1.27 1.27)
				)
				(justify mirror)
			)
		)
		(property "Value" ""
			(at 0 0 90)
			(layer "B.Fab")
			(effects
				(font
					(size 1.27 1.27)
				)
				(justify mirror)
			)
		)
		(duplicate_pad_numbers_are_jumpers no)
		(fp_line
			(start 0.299974 -0.150114)
			(end -0.299974 -0.150114)
			(stroke
				(width 0.1)
				(type default)
			)
			(layer "B.Fab")
		)
		(fp_line
			(start -0.299974 -0.150114)
			(end -0.299974 0.150114)
			(stroke
				(width 0.1)
				(type default)
			)
			(layer "B.Fab")
		)
		(fp_line
			(start 0.299974 0.150114)
			(end 0.299974 -0.150114)
			(stroke
				(width 0.1)
				(type default)
			)
			(layer "B.Fab")
		)
		(fp_line
			(start -0.299974 0.150114)
			(end 0.299974 0.150114)
			(stroke
				(width 0.1)
				(type default)
			)
			(layer "B.Fab")
		)
		(pad "1" smd rect
			(at 0.2667 0 270)
			(size 0.3048 0.381)
			(layers "B.Cu" "B.Mask" "B.Paste")
			(net "P0V9_CPU1_RT_2D")
		)
		(pad "2" smd rect
			(at -0.2667 0 270)
			(size 0.3048 0.381)
			(layers "B.Cu" "B.Mask" "B.Paste")
			(net "GND")
		)
	)
	(footprint ""
		(layer "B.Cu")
		(at 51.128422 -194.9196 180)
		(property "Reference" "R1581"
			(at 0 0 0)
			(layer "B.SilkS")
			(hide yes)
			(effects
				(font
					(size 1.27 1.27)
				)
				(justify mirror)
			)
		)
		(property "Value" ""
			(at 0 0 0)
			(layer "B.Fab")
			(effects
				(font
					(size 1.27 1.27)
				)
				(justify mirror)
			)
		)
		(duplicate_pad_numbers_are_jumpers no)
		(fp_line
			(start 0.7874 0.4064)
			(end 0.7874 -0.4064)
			(stroke
				(width 0.1524)
				(type default)
			)
			(layer "B.SilkS")
		)
		(fp_line
			(start 0.7874 -0.4064)
			(end -0.7874 -0.4064)
			(stroke
				(width 0.1524)
				(type default)
			)
			(layer "B.SilkS")
		)
		(fp_line
			(start -0.7874 0.4064)
			(end 0.7874 0.4064)
			(stroke
				(width 0.1524)
				(type default)
			)
			(layer "B.SilkS")
		)
		(fp_line
			(start -0.7874 -0.4064)
			(end -0.7874 0.4064)
			(stroke
				(width 0.1524)
				(type default)
			)
			(layer "B.SilkS")
		)
		(fp_line
			(start 0.67945 0.3048)
			(end 0.67945 -0.305054)
			(stroke
				(width 0.1)
				(type default)
			)
			(layer "B.Fab")
		)
		(fp_line
			(start 0.67945 -0.305054)
			(end 0.12065 -0.305054)
			(stroke
				(width 0.1)
				(type default)
			)
			(layer "B.Fab")
		)
		(fp_line
			(start 0.12065 0.3048)
			(end 0.67945 0.3048)
			(stroke
				(width 0.1)
				(type default)
			)
			(layer "B.Fab")
		)
		(fp_line
			(start 0.12065 0.2794)
			(end 0.12065 0.3048)
			(stroke
				(width 0.1)
				(type default)
			)
			(layer "B.Fab")
		)
		(fp_line
			(start 0.12065 -0.2794)
			(end -0.12065 -0.2794)
			(stroke
				(width 0.1)
				(type default)
			)
			(layer "B.Fab")
		)
		(fp_line
			(start 0.12065 -0.305054)
			(end 0.12065 -0.2794)
			(stroke
				(width 0.1)
				(type default)
			)
			(layer "B.Fab")
		)
		(fp_line
			(start -0.120396 0.3048)
			(end -0.120396 0.2794)
			(stroke
				(width 0.1)
				(type default)
			)
			(layer "B.Fab")
		)
		(fp_line
			(start -0.120396 0.2794)
			(end 0.12065 0.2794)
			(stroke
				(width 0.1)
				(type default)
			)
			(layer "B.Fab")
		)
		(fp_line
			(start -0.12065 -0.2794)
			(end -0.12065 -0.3048)
			(stroke
				(width 0.1)
				(type default)
			)
			(layer "B.Fab")
		)
		(fp_line
			(start -0.12065 -0.3048)
			(end -0.67945 -0.3048)
			(stroke
				(width 0.1)
				(type default)
			)
			(layer "B.Fab")
		)
		(fp_line
			(start -0.67945 0.3048)
			(end -0.120396 0.3048)
			(stroke
				(width 0.1)
				(type default)
			)
			(layer "B.Fab")
		)
		(fp_line
			(start -0.67945 -0.3048)
			(end -0.67945 0.3048)
			(stroke
				(width 0.1)
				(type default)
			)
			(layer "B.Fab")
		)
		(pad "1" smd circle
			(at 0.40005 0)
			(size 0 0)
			(layers "B.Cu" "B.Mask" "B.Paste")
			(net "I3C_SPD_DDRAF_CPU1_SCL")
		)
		(pad "2" smd circle
			(at -0.40005 0)
			(size 0 0)
			(layers "B.Cu" "B.Mask" "B.Paste")
			(net "I3C_SPD_DDRB_CPU1_SCL")
		)
	)
	(footprint ""
		(layer "B.Cu")
		(at 33.02 -361.569 -90)
		(property "Reference" "PR533"
			(at 0 0 90)
			(layer "B.SilkS")
			(hide yes)
			(effects
				(font
					(size 1.27 1.27)
				)
				(justify mirror)
			)
		)
		(property "Value" ""
			(at 0 0 90)
			(layer "B.Fab")
			(effects
				(font
					(size 1.27 1.27)
				)
				(justify mirror)
			)
		)
		(duplicate_pad_numbers_are_jumpers no)
		(fp_line
			(start -0.7874 0.4064)
			(end 0.7874 0.4064)
			(stroke
				(width 0.1524)
				(type default)
			)
			(layer "B.SilkS")
		)
		(fp_line
			(start 0.7874 0.4064)
			(end 0.7874 -0.4064)
			(stroke
				(width 0.1524)
				(type default)
			)
			(layer "B.SilkS")
		)
		(fp_line
			(start -0.7874 -0.4064)
			(end -0.7874 0.4064)
			(stroke
				(width 0.1524)
				(type default)
			)
			(layer "B.SilkS")
		)
		(fp_line
			(start 0.7874 -0.4064)
			(end -0.7874 -0.4064)
			(stroke
				(width 0.1524)
				(type default)
			)
			(layer "B.SilkS")
		)
		(fp_line
			(start -0.67945 0.3048)
			(end -0.120396 0.3048)
			(stroke
				(width 0.1)
				(type default)
			)
			(layer "B.Fab")
		)
		(fp_line
			(start -0.120396 0.3048)
			(end -0.120396 0.2794)
			(stroke
				(width 0.1)
				(type default)
			)
			(layer "B.Fab")
		)
		(fp_line
			(start 0.12065 0.3048)
			(end 0.67945 0.3048)
			(stroke
				(width 0.1)
				(type default)
			)
			(layer "B.Fab")
		)
		(fp_line
			(start 0.67945 0.3048)
			(end 0.67945 -0.305054)
			(stroke
				(width 0.1)
				(type default)
			)
			(layer "B.Fab")
		)
		(fp_line
			(start -0.120396 0.2794)
			(end 0.12065 0.2794)
			(stroke
				(width 0.1)
				(type default)
			)
			(layer "B.Fab")
		)
		(fp_line
			(start 0.12065 0.2794)
			(end 0.12065 0.3048)
			(stroke
				(width 0.1)
				(type default)
			)
			(layer "B.Fab")
		)
		(fp_line
			(start -0.12065 -0.2794)
			(end -0.12065 -0.3048)
			(stroke
				(width 0.1)
				(type default)
			)
			(layer "B.Fab")
		)
		(fp_line
			(start 0.12065 -0.2794)
			(end -0.12065 -0.2794)
			(stroke
				(width 0.1)
				(type default)
			)
			(layer "B.Fab")
		)
		(fp_line
			(start -0.67945 -0.3048)
			(end -0.67945 0.3048)
			(stroke
				(width 0.1)
				(type default)
			)
			(layer "B.Fab")
		)
		(fp_line
			(start -0.12065 -0.3048)
			(end -0.67945 -0.3048)
			(stroke
				(width 0.1)
				(type default)
			)
			(layer "B.Fab")
		)
		(fp_line
			(start 0.12065 -0.305054)
			(end 0.12065 -0.2794)
			(stroke
				(width 0.1)
				(type default)
			)
			(layer "B.Fab")
		)
		(fp_line
			(start 0.67945 -0.305054)
			(end 0.12065 -0.305054)
			(stroke
				(width 0.1)
				(type default)
			)
			(layer "B.Fab")
		)
		(pad "1" smd circle
			(at 0.40005 0 90)
			(size 0 0)
			(layers "B.Cu" "B.Mask" "B.Paste")
			(net "NC_PVDDCR_CPU1_P1_IMON7")
		)
		(pad "2" smd circle
			(at -0.40005 0 90)
			(size 0 0)
			(layers "B.Cu" "B.Mask" "B.Paste")
			(net "GND")
		)
	)
	(footprint ""
		(layer "B.Cu")
		(at 135.858504 -31.874206 -90)
		(property "Reference" "C6052"
			(at 0 0 90)
			(layer "B.SilkS")
			(hide yes)
			(effects
				(font
					(size 1.27 1.27)
				)
				(justify mirror)
			)
		)
		(property "Value" ""
			(at 0 0 90)
			(layer "B.Fab")
			(effects
				(font
					(size 1.27 1.27)
				)
				(justify mirror)
			)
		)
		(duplicate_pad_numbers_are_jumpers no)
		(fp_line
			(start -0.7874 0.4064)
			(end 0.7874 0.4064)
			(stroke
				(width 0.1524)
				(type default)
			)
			(layer "B.SilkS")
		)
		(fp_line
			(start 0.7874 0.4064)
			(end 0.7874 -0.4064)
			(stroke
				(width 0.1524)
				(type default)
			)
			(layer "B.SilkS")
		)
		(fp_line
			(start -0.7874 -0.4064)
			(end -0.7874 0.4064)
			(stroke
				(width 0.1524)
				(type default)
			)
			(layer "B.SilkS")
		)
		(fp_line
			(start 0.7874 -0.4064)
			(end -0.7874 -0.4064)
			(stroke
				(width 0.1524)
				(type default)
			)
			(layer "B.SilkS")
		)
		(fp_line
			(start -0.67945 0.3048)
			(end -0.120396 0.3048)
			(stroke
				(width 0.1)
				(type default)
			)
			(layer "B.Fab")
		)
		(fp_line
			(start -0.120396 0.3048)
			(end -0.120396 0.2794)
			(stroke
				(width 0.1)
				(type default)
			)
			(layer "B.Fab")
		)
		(fp_line
			(start 0.12065 0.3048)
			(end 0.67945 0.3048)
			(stroke
				(width 0.1)
				(type default)
			)
			(layer "B.Fab")
		)
		(fp_line
			(start 0.67945 0.3048)
			(end 0.67945 -0.305054)
			(stroke
				(width 0.1)
				(type default)
			)
			(layer "B.Fab")
		)
		(fp_line
			(start -0.120396 0.2794)
			(end 0.12065 0.2794)
			(stroke
				(width 0.1)
				(type default)
			)
			(layer "B.Fab")
		)
		(fp_line
			(start 0.12065 0.2794)
			(end 0.12065 0.3048)
			(stroke
				(width 0.1)
				(type default)
			)
			(layer "B.Fab")
		)
		(fp_line
			(start -0.12065 -0.2794)
			(end -0.12065 -0.3048)
			(stroke
				(width 0.1)
				(type default)
			)
			(layer "B.Fab")
		)
		(fp_line
			(start 0.12065 -0.2794)
			(end -0.12065 -0.2794)
			(stroke
				(width 0.1)
				(type default)
			)
			(layer "B.Fab")
		)
		(fp_line
			(start -0.67945 -0.3048)
			(end -0.67945 0.3048)
			(stroke
				(width 0.1)
				(type default)
			)
			(layer "B.Fab")
		)
		(fp_line
			(start -0.12065 -0.3048)
			(end -0.67945 -0.3048)
			(stroke
				(width 0.1)
				(type default)
			)
			(layer "B.Fab")
		)
		(fp_line
			(start 0.12065 -0.305054)
			(end 0.12065 -0.2794)
			(stroke
				(width 0.1)
				(type default)
			)
			(layer "B.Fab")
		)
		(fp_line
			(start 0.67945 -0.305054)
			(end 0.12065 -0.305054)
			(stroke
				(width 0.1)
				(type default)
			)
			(layer "B.Fab")
		)
		(pad "1" smd circle
			(at 0.40005 0 90)
			(size 0 0)
			(layers "B.Cu" "B.Mask" "B.Paste")
			(net "P3V3_AUX")
		)
		(pad "2" smd circle
			(at -0.40005 0 90)
			(size 0 0)
			(layers "B.Cu" "B.Mask" "B.Paste")
			(net "GND")
		)
	)
	(footprint ""
		(layer "B.Cu")
		(at 89.506298 -386.766562 90)
		(property "Reference" "C217"
			(at 0 0 90)
			(layer "B.SilkS")
			(hide yes)
			(effects
				(font
					(size 1.27 1.27)
				)
				(justify mirror)
			)
		)
		(property "Value" ""
			(at 0 0 90)
			(layer "B.Fab")
			(effects
				(font
					(size 1.27 1.27)
				)
				(justify mirror)
			)
		)
		(duplicate_pad_numbers_are_jumpers no)
		(fp_line
			(start 0.299974 -0.150114)
			(end -0.299974 -0.150114)
			(stroke
				(width 0.1)
				(type default)
			)
			(layer "B.Fab")
		)
		(fp_line
			(start -0.299974 -0.150114)
			(end -0.299974 0.150114)
			(stroke
				(width 0.1)
				(type default)
			)
			(layer "B.Fab")
		)
		(fp_line
			(start 0.299974 0.150114)
			(end 0.299974 -0.150114)
			(stroke
				(width 0.1)
				(type default)
			)
			(layer "B.Fab")
		)
		(fp_line
			(start -0.299974 0.150114)
			(end 0.299974 0.150114)
			(stroke
				(width 0.1)
				(type default)
			)
			(layer "B.Fab")
		)
		(pad "1" smd rect
			(at 0.2667 0 270)
			(size 0.3048 0.381)
			(layers "B.Cu" "B.Mask" "B.Paste")
			(net "P1V8_CPU1_RT1_1A")
		)
		(pad "2" smd rect
			(at -0.2667 0 270)
			(size 0.3048 0.381)
			(layers "B.Cu" "B.Mask" "B.Paste")
			(net "GND")
		)
	)
	(footprint ""
		(layer "B.Cu")
		(at 381.278384 -395.148562 90)
		(property "Reference" "C999"
			(at 0 0 90)
			(layer "B.SilkS")
			(hide yes)
			(effects
				(font
					(size 1.27 1.27)
				)
				(justify mirror)
			)
		)
		(property "Value" ""
			(at 0 0 90)
			(layer "B.Fab")
			(effects
				(font
					(size 1.27 1.27)
				)
				(justify mirror)
			)
		)
		(duplicate_pad_numbers_are_jumpers no)
		(fp_line
			(start 0.299974 -0.150114)
			(end -0.299974 -0.150114)
			(stroke
				(width 0.1)
				(type default)
			)
			(layer "B.Fab")
		)
		(fp_line
			(start -0.299974 -0.150114)
			(end -0.299974 0.150114)
			(stroke
				(width 0.1)
				(type default)
			)
			(layer "B.Fab")
		)
		(fp_line
			(start 0.299974 0.150114)
			(end 0.299974 -0.150114)
			(stroke
				(width 0.1)
				(type default)
			)
			(layer "B.Fab")
		)
		(fp_line
			(start -0.299974 0.150114)
			(end 0.299974 0.150114)
			(stroke
				(width 0.1)
				(type default)
			)
			(layer "B.Fab")
		)
		(pad "1" smd rect
			(at 0.2667 0 270)
			(size 0.3048 0.381)
			(layers "B.Cu" "B.Mask" "B.Paste")
			(net "P1V8_CPU0_RT3_1A_1D")
		)
		(pad "2" smd rect
			(at -0.2667 0 270)
			(size 0.3048 0.381)
			(layers "B.Cu" "B.Mask" "B.Paste")
			(net "GND")
		)
	)
	(footprint ""
		(layer "B.Cu")
		(at 139.36472 -35.304222 -90)
		(property "Reference" "C6045"
			(at 0 0 90)
			(layer "B.SilkS")
			(hide yes)
			(effects
				(font
					(size 1.27 1.27)
				)
				(justify mirror)
			)
		)
		(property "Value" ""
			(at 0 0 90)
			(layer "B.Fab")
			(effects
				(font
					(size 1.27 1.27)
				)
				(justify mirror)
			)
		)
		(duplicate_pad_numbers_are_jumpers no)
		(fp_line
			(start -0.7874 0.4064)
			(end 0.7874 0.4064)
			(stroke
				(width 0.1524)
				(type default)
			)
			(layer "B.SilkS")
		)
		(fp_line
			(start 0.7874 0.4064)
			(end 0.7874 -0.4064)
			(stroke
				(width 0.1524)
				(type default)
			)
			(layer "B.SilkS")
		)
		(fp_line
			(start -0.7874 -0.4064)
			(end -0.7874 0.4064)
			(stroke
				(width 0.1524)
				(type default)
			)
			(layer "B.SilkS")
		)
		(fp_line
			(start 0.7874 -0.4064)
			(end -0.7874 -0.4064)
			(stroke
				(width 0.1524)
				(type default)
			)
			(layer "B.SilkS")
		)
		(fp_line
			(start -0.67945 0.3048)
			(end -0.120396 0.3048)
			(stroke
				(width 0.1)
				(type default)
			)
			(layer "B.Fab")
		)
		(fp_line
			(start -0.120396 0.3048)
			(end -0.120396 0.2794)
			(stroke
				(width 0.1)
				(type default)
			)
			(layer "B.Fab")
		)
		(fp_line
			(start 0.12065 0.3048)
			(end 0.67945 0.3048)
			(stroke
				(width 0.1)
				(type default)
			)
			(layer "B.Fab")
		)
		(fp_line
			(start 0.67945 0.3048)
			(end 0.67945 -0.305054)
			(stroke
				(width 0.1)
				(type default)
			)
			(layer "B.Fab")
		)
		(fp_line
			(start -0.120396 0.2794)
			(end 0.12065 0.2794)
			(stroke
				(width 0.1)
				(type default)
			)
			(layer "B.Fab")
		)
		(fp_line
			(start 0.12065 0.2794)
			(end 0.12065 0.3048)
			(stroke
				(width 0.1)
				(type default)
			)
			(layer "B.Fab")
		)
		(fp_line
			(start -0.12065 -0.2794)
			(end -0.12065 -0.3048)
			(stroke
				(width 0.1)
				(type default)
			)
			(layer "B.Fab")
		)
		(fp_line
			(start 0.12065 -0.2794)
			(end -0.12065 -0.2794)
			(stroke
				(width 0.1)
				(type default)
			)
			(layer "B.Fab")
		)
		(fp_line
			(start -0.67945 -0.3048)
			(end -0.67945 0.3048)
			(stroke
				(width 0.1)
				(type default)
			)
			(layer "B.Fab")
		)
		(fp_line
			(start -0.12065 -0.3048)
			(end -0.67945 -0.3048)
			(stroke
				(width 0.1)
				(type default)
			)
			(layer "B.Fab")
		)
		(fp_line
			(start 0.12065 -0.305054)
			(end 0.12065 -0.2794)
			(stroke
				(width 0.1)
				(type default)
			)
			(layer "B.Fab")
		)
		(fp_line
			(start 0.67945 -0.305054)
			(end 0.12065 -0.305054)
			(stroke
				(width 0.1)
				(type default)
			)
			(layer "B.Fab")
		)
		(pad "1" smd circle
			(at 0.40005 0 90)
			(size 0 0)
			(layers "B.Cu" "B.Mask" "B.Paste")
			(net "P3V3_AUX_CPU0_USB_AVDD33")
		)
		(pad "2" smd circle
			(at -0.40005 0 90)
			(size 0 0)
			(layers "B.Cu" "B.Mask" "B.Paste")
			(net "GND")
		)
	)
	(footprint ""
		(layer "B.Cu")
		(at 444.166752 -380.027434 90)
		(property "Reference" "PC6568"
			(at -6.293104 2.238248 0)
			(unlocked yes)
			(layer "B.SilkS")
			(effects
				(font
					(size 0.7874 0.5842)
					(thickness 0.1524)
				)
				(justify left mirror)
			)
		)
		(property "Value" ""
			(at 0 0 90)
			(layer "B.Fab")
			(effects
				(font
					(size 1.27 1.27)
				)
				(justify mirror)
			)
		)
		(duplicate_pad_numbers_are_jumpers no)
		(fp_line
			(start 4.84378 -2.150618)
			(end 4.53898 -2.150618)
			(stroke
				(width 0.1524)
				(type default)
			)
			(layer "B.SilkS")
		)
		(fp_line
			(start 4.84378 -2.150618)
			(end 4.842256 2.163064)
			(stroke
				(width 0.1524)
				(type default)
			)
			(layer "B.SilkS")
		)
		(fp_line
			(start 4.69138 -2.150618)
			(end 4.692396 2.161032)
			(stroke
				(width 0.1524)
				(type default)
			)
			(layer "B.SilkS")
		)
		(fp_line
			(start 4.53898 -2.150618)
			(end 4.539742 2.152142)
			(stroke
				(width 0.1524)
				(type default)
			)
			(layer "B.SilkS")
		)
		(fp_line
			(start 4.53898 -2.15011)
			(end -4.53898 -2.15011)
			(stroke
				(width 0.1524)
				(type default)
			)
			(layer "B.SilkS")
		)
		(fp_line
			(start -4.53898 -2.15011)
			(end -4.53898 2.15011)
			(stroke
				(width 0.1524)
				(type default)
			)
			(layer "B.SilkS")
		)
		(fp_line
			(start 4.53898 2.15011)
			(end 4.53898 -2.15011)
			(stroke
				(width 0.1524)
				(type default)
			)
			(layer "B.SilkS")
		)
		(fp_line
			(start -4.53898 2.15011)
			(end 4.53898 2.15011)
			(stroke
				(width 0.1524)
				(type default)
			)
			(layer "B.SilkS")
		)
		(fp_line
			(start 4.83108 2.150364)
			(end 4.447794 2.149348)
			(stroke
				(width 0.1524)
				(type default)
			)
			(layer "B.SilkS")
		)
		(fp_line
			(start 3.64998 -2.15011)
			(end -3.64998 -2.15011)
			(stroke
				(width 0.1)
				(type default)
			)
			(layer "B.Fab")
		)
		(fp_line
			(start -3.64998 -2.15011)
			(end -3.64998 2.15011)
			(stroke
				(width 0.1)
				(type default)
			)
			(layer "B.Fab")
		)
		(fp_line
			(start 3.64998 2.15011)
			(end 3.64998 -2.15011)
			(stroke
				(width 0.1)
				(type default)
			)
			(layer "B.Fab")
		)
		(fp_line
			(start -3.64998 2.15011)
			(end 3.64998 2.15011)
			(stroke
				(width 0.1)
				(type default)
			)
			(layer "B.Fab")
		)
		(fp_text user "+"
			(at 5.993638 -2.411222 90)
			(unlocked yes)
			(layer "B.SilkS")
			(effects
				(font
					(size 1.905 1.4224)
					(thickness 0.1524)
				)
				(justify left mirror)
			)
		)
		(fp_text user "-"
			(at -4.313174 -0.094488 90)
			(unlocked yes)
			(layer "B.SilkS")
			(effects
				(font
					(size 1.905 1.4224)
					(thickness 0.1524)
				)
				(justify left mirror)
			)
		)
		(fp_text user "+"
			(at 6.214872 -0.337058 90)
			(unlocked yes)
			(layer "B.Fab")
			(effects
				(font
					(size 1.905 1.4224)
					(thickness 0.1524)
				)
				(justify left mirror)
			)
		)
		(fp_text user "-"
			(at -4.313174 -0.094488 90)
			(unlocked yes)
			(layer "B.Fab")
			(effects
				(font
					(size 1.905 1.4224)
					(thickness 0.1524)
				)
				(justify left mirror)
			)
		)
		(pad "1" smd rect
			(at 3.199892 0 270)
			(size 2.413 2.8194)
			(layers "B.Cu" "B.Mask" "B.Paste")
			(net "P0V9_CPU0_RT_2D")
		)
		(pad "2" smd rect
			(at -3.199892 0 270)
			(size 2.413 2.8194)
			(layers "B.Cu" "B.Mask" "B.Paste")
			(net "GND")
		)
	)
	(footprint ""
		(layer "B.Cu")
		(at 350.596454 -264.35431)
		(property "Reference" "C2162"
			(at 0 0 0)
			(layer "B.SilkS")
			(hide yes)
			(effects
				(font
					(size 1.27 1.27)
				)
				(justify mirror)
			)
		)
		(property "Value" ""
			(at 0 0 0)
			(layer "B.Fab")
			(effects
				(font
					(size 1.27 1.27)
				)
				(justify mirror)
			)
		)
		(duplicate_pad_numbers_are_jumpers no)
		(fp_line
			(start -0.7874 -0.4064)
			(end -0.7874 0.4064)
			(stroke
				(width 0.1524)
				(type default)
			)
			(layer "B.SilkS")
		)
		(fp_line
			(start -0.7874 0.4064)
			(end 0.7874 0.4064)
			(stroke
				(width 0.1524)
				(type default)
			)
			(layer "B.SilkS")
		)
		(fp_line
			(start 0.7874 -0.4064)
			(end -0.7874 -0.4064)
			(stroke
				(width 0.1524)
				(type default)
			)
			(layer "B.SilkS")
		)
		(fp_line
			(start 0.7874 0.4064)
			(end 0.7874 -0.4064)
			(stroke
				(width 0.1524)
				(type default)
			)
			(layer "B.SilkS")
		)
		(fp_line
			(start -0.67945 -0.3048)
			(end -0.67945 0.3048)
			(stroke
				(width 0.1)
				(type default)
			)
			(layer "B.Fab")
		)
		(fp_line
			(start -0.67945 0.3048)
			(end -0.120396 0.3048)
			(stroke
				(width 0.1)
				(type default)
			)
			(layer "B.Fab")
		)
		(fp_line
			(start -0.12065 -0.3048)
			(end -0.67945 -0.3048)
			(stroke
				(width 0.1)
				(type default)
			)
			(layer "B.Fab")
		)
		(fp_line
			(start -0.12065 -0.2794)
			(end -0.12065 -0.3048)
			(stroke
				(width 0.1)
				(type default)
			)
			(layer "B.Fab")
		)
		(fp_line
			(start -0.120396 0.2794)
			(end 0.12065 0.2794)
			(stroke
				(width 0.1)
				(type default)
			)
			(layer "B.Fab")
		)
		(fp_line
			(start -0.120396 0.3048)
			(end -0.120396 0.2794)
			(stroke
				(width 0.1)
				(type default)
			)
			(layer "B.Fab")
		)
		(fp_line
			(start 0.12065 -0.305054)
			(end 0.12065 -0.2794)
			(stroke
				(width 0.1)
				(type default)
			)
			(layer "B.Fab")
		)
		(fp_line
			(start 0.12065 -0.2794)
			(end -0.12065 -0.2794)
			(stroke
				(width 0.1)
				(type default)
			)
			(layer "B.Fab")
		)
		(fp_line
			(start 0.12065 0.2794)
			(end 0.12065 0.3048)
			(stroke
				(width 0.1)
				(type default)
			)
			(layer "B.Fab")
		)
		(fp_line
			(start 0.12065 0.3048)
			(end 0.67945 0.3048)
			(stroke
				(width 0.1)
				(type default)
			)
			(layer "B.Fab")
		)
		(fp_line
			(start 0.67945 -0.305054)
			(end 0.12065 -0.305054)
			(stroke
				(width 0.1)
				(type default)
			)
			(layer "B.Fab")
		)
		(fp_line
			(start 0.67945 0.3048)
			(end 0.67945 -0.305054)
			(stroke
				(width 0.1)
				(type default)
			)
			(layer "B.Fab")
		)
		(pad "1" smd circle
			(at 0.40005 0 180)
			(size 0 0)
			(layers "B.Cu" "B.Mask" "B.Paste")
			(net "PVDD11_S3_P0")
		)
		(pad "2" smd circle
			(at -0.40005 0 180)
			(size 0 0)
			(layers "B.Cu" "B.Mask" "B.Paste")
			(net "GND")
		)
	)
	(footprint ""
		(layer "B.Cu")
		(at 255.744726 -323.022722 180)
		(property "Reference" "C1078"
			(at 0 0 0)
			(layer "B.SilkS")
			(hide yes)
			(effects
				(font
					(size 1.27 1.27)
				)
				(justify mirror)
			)
		)
		(property "Value" ""
			(at 0 0 0)
			(layer "B.Fab")
			(effects
				(font
					(size 1.27 1.27)
				)
				(justify mirror)
			)
		)
		(duplicate_pad_numbers_are_jumpers no)
		(fp_line
			(start 0.7874 0.4064)
			(end 0.7874 -0.4064)
			(stroke
				(width 0.1524)
				(type default)
			)
			(layer "B.SilkS")
		)
		(fp_line
			(start 0.7874 -0.4064)
			(end -0.7874 -0.4064)
			(stroke
				(width 0.1524)
				(type default)
			)
			(layer "B.SilkS")
		)
		(fp_line
			(start -0.7874 0.4064)
			(end 0.7874 0.4064)
			(stroke
				(width 0.1524)
				(type default)
			)
			(layer "B.SilkS")
		)
		(fp_line
			(start -0.7874 -0.4064)
			(end -0.7874 0.4064)
			(stroke
				(width 0.1524)
				(type default)
			)
			(layer "B.SilkS")
		)
		(fp_line
			(start 0.67945 0.3048)
			(end 0.67945 -0.305054)
			(stroke
				(width 0.1)
				(type default)
			)
			(layer "B.Fab")
		)
		(fp_line
			(start 0.67945 -0.305054)
			(end 0.12065 -0.305054)
			(stroke
				(width 0.1)
				(type default)
			)
			(layer "B.Fab")
		)
		(fp_line
			(start 0.12065 0.3048)
			(end 0.67945 0.3048)
			(stroke
				(width 0.1)
				(type default)
			)
			(layer "B.Fab")
		)
		(fp_line
			(start 0.12065 0.2794)
			(end 0.12065 0.3048)
			(stroke
				(width 0.1)
				(type default)
			)
			(layer "B.Fab")
		)
		(fp_line
			(start 0.12065 -0.2794)
			(end -0.12065 -0.2794)
			(stroke
				(width 0.1)
				(type default)
			)
			(layer "B.Fab")
		)
		(fp_line
			(start 0.12065 -0.305054)
			(end 0.12065 -0.2794)
			(stroke
				(width 0.1)
				(type default)
			)
			(layer "B.Fab")
		)
		(fp_line
			(start -0.120396 0.3048)
			(end -0.120396 0.2794)
			(stroke
				(width 0.1)
				(type default)
			)
			(layer "B.Fab")
		)
		(fp_line
			(start -0.120396 0.2794)
			(end 0.12065 0.2794)
			(stroke
				(width 0.1)
				(type default)
			)
			(layer "B.Fab")
		)
		(fp_line
			(start -0.12065 -0.2794)
			(end -0.12065 -0.3048)
			(stroke
				(width 0.1)
				(type default)
			)
			(layer "B.Fab")
		)
		(fp_line
			(start -0.12065 -0.3048)
			(end -0.67945 -0.3048)
			(stroke
				(width 0.1)
				(type default)
			)
			(layer "B.Fab")
		)
		(fp_line
			(start -0.67945 0.3048)
			(end -0.120396 0.3048)
			(stroke
				(width 0.1)
				(type default)
			)
			(layer "B.Fab")
		)
		(fp_line
			(start -0.67945 -0.3048)
			(end -0.67945 0.3048)
			(stroke
				(width 0.1)
				(type default)
			)
			(layer "B.Fab")
		)
		(pad "1" smd circle
			(at 0.40005 0)
			(size 0 0)
			(layers "B.Cu" "B.Mask" "B.Paste")
			(net "P1V2_AUX_ADC_MAM")
		)
		(pad "2" smd circle
			(at -0.40005 0)
			(size 0 0)
			(layers "B.Cu" "B.Mask" "B.Paste")
			(net "GND")
		)
	)
	(footprint ""
		(layer "B.Cu")
		(at 493.36833 7.564882 90)
		(property "Reference" "X8026"
			(at 0.93726 -1.53035 270)
			(unlocked yes)
			(layer "B.SilkS")
			(effects
				(font
					(size 0.7874 0.5842)
					(thickness 0.1524)
				)
				(justify left mirror)
			)
		)
		(property "Value" ""
			(at 0 0 90)
			(layer "B.Fab")
			(effects
				(font
					(size 1.27 1.27)
				)
				(justify mirror)
			)
		)
		(property "Device Type" "TP_TDR_4P_FTS_TH-TP_TDR_4P_DIP,EMPTY,TP15"
			(at -1.30175 1.27 0)
			(unlocked yes)
			(layer "B.Fab")
			(hide yes)
			(effects
				(font
					(size 0.635 0.4064)
					(thickness 0.1524)
				)
				(justify mirror)
			)
		)
		(property "User Part Number" "N_A"
			(at -1.30175 1.27 0)
			(unlocked yes)
			(layer "Cmts.User")
			(hide yes)
			(effects
				(font
					(size 0.635 0.4064)
					(thickness 0.1524)
				)
				(justify mirror)
			)
		)
		(duplicate_pad_numbers_are_jumpers no)
		(fp_line
			(start 0 -1.27)
			(end 0 -0.635)
			(stroke
				(width 0.1524)
				(type default)
			)
			(layer "B.SilkS")
		)
		(fp_line
			(start -2.54 -1.27)
			(end 0 -1.27)
			(stroke
				(width 0.1524)
				(type default)
			)
			(layer "B.SilkS")
		)
		(fp_line
			(start -2.54 -1.1303)
			(end -2.54 -1.27)
			(stroke
				(width 0.1524)
				(type default)
			)
			(layer "B.SilkS")
		)
		(fp_line
			(start 0 0.635)
			(end 0 1.905)
			(stroke
				(width 0.1524)
				(type default)
			)
			(layer "B.SilkS")
		)
		(fp_line
			(start -2.54 1.4097)
			(end -2.54 1.1303)
			(stroke
				(width 0.1524)
				(type default)
			)
			(layer "B.SilkS")
		)
		(fp_line
			(start 0 3.175)
			(end 0 3.81)
			(stroke
				(width 0.1524)
				(type default)
			)
			(layer "B.SilkS")
		)
		(fp_line
			(start 0 3.81)
			(end -2.54 3.81)
			(stroke
				(width 0.1524)
				(type default)
			)
			(layer "B.SilkS")
		)
		(fp_line
			(start -2.54 3.81)
			(end -2.54 3.6703)
			(stroke
				(width 0.1524)
				(type default)
			)
			(layer "B.SilkS")
		)
		(fp_poly
			(pts
				(xy 0.761746 0) (xy 2.285746 -0.762) (xy 2.285746 0.762)
			)
			(stroke
				(width 0)
				(type default)
			)
			(fill yes)
			(layer "B.SilkS")
		)
		(fp_line
			(start 0 -1.27)
			(end 0 3.81)
			(stroke
				(width 0.1)
				(type default)
			)
			(layer "B.Fab")
		)
		(fp_line
			(start -2.54 -1.27)
			(end 0 -1.27)
			(stroke
				(width 0.1)
				(type default)
			)
			(layer "B.Fab")
		)
		(fp_line
			(start 0 3.81)
			(end -2.54 3.81)
			(stroke
				(width 0.1)
				(type default)
			)
			(layer "B.Fab")
		)
		(fp_line
			(start -2.54 3.81)
			(end -2.54 -1.27)
			(stroke
				(width 0.1)
				(type default)
			)
			(layer "B.Fab")
		)
		(fp_poly
			(pts
				(xy 0.761746 0) (xy 2.285746 -0.762) (xy 2.285746 0.762)
			)
			(stroke
				(width 0)
				(type default)
			)
			(fill yes)
			(layer "B.Fab")
		)
		(pad "1" thru_hole circle
			(at 0 0 270)
			(size 1.0033 1.0033)
			(drill 0.249936)
			(layers "*.Cu" "*.Mask")
			(remove_unused_layers no)
			(net "TDR_DIFF_85_IN6_DP")
			(clearance 0.10795)
			(padstack
				(mode front_inner_back)
				(layer "Inner"
					(shape circle)
					(size 0.8001 0.8001)
					(clearance 0.1524)
				)
				(layer "B.Cu"
					(shape circle)
					(size 1.0033 1.0033)
					(thermal_gap 0.10795)
					(clearance 0.10795)
				)
			)
		)
		(pad "2" thru_hole circle
			(at -2.54 0 270)
			(size 1.9939 1.9939)
			(drill 0.249936)
			(layers "*.Cu" "*.Mask")
			(remove_unused_layers no)
			(net "T1_GND")
			(clearance 0.10795)
			(padstack
				(mode front_inner_back)
				(layer "Inner"
					(shape circle)
					(size 0.8001 0.8001)
					(clearance 0.1524)
				)
				(layer "B.Cu"
					(shape circle)
					(size 1.9939 1.9939)
					(thermal_gap 0.10795)
					(clearance 0.10795)
				)
			)
		)
		(pad "3" thru_hole circle
			(at -2.54 2.54 270)
			(size 1.9939 1.9939)
			(drill 0.249936)
			(layers "*.Cu" "*.Mask")
			(remove_unused_layers no)
			(net "T1_GND")
			(clearance 0.10795)
			(padstack
				(mode front_inner_back)
				(layer "Inner"
					(shape circle)
					(size 0.8001 0.8001)
					(clearance 0.1524)
				)
				(layer "B.Cu"
					(shape circle)
					(size 1.9939 1.9939)
					(thermal_gap 0.10795)
					(clearance 0.10795)
				)
			)
		)
		(pad "4" thru_hole circle
			(at 0 2.54 270)
			(size 1.0033 1.0033)
			(drill 0.249936)
			(layers "*.Cu" "*.Mask")
			(remove_unused_layers no)
			(net "TDR_DIFF_85_IN6_DN")
			(clearance 0.10795)
			(padstack
				(mode front_inner_back)
				(layer "Inner"
					(shape circle)
					(size 0.8001 0.8001)
					(clearance 0.1524)
				)
				(layer "B.Cu"
					(shape circle)
					(size 1.0033 1.0033)
					(thermal_gap 0.10795)
					(clearance 0.10795)
				)
			)
		)
	)
	(footprint ""
		(layer "B.Cu")
		(at 184.332372 -111.863124 -90)
		(property "Reference" "C1131"
			(at 0 0 90)
			(layer "B.SilkS")
			(hide yes)
			(effects
				(font
					(size 1.27 1.27)
				)
				(justify mirror)
			)
		)
		(property "Value" ""
			(at 0 0 90)
			(layer "B.Fab")
			(effects
				(font
					(size 1.27 1.27)
				)
				(justify mirror)
			)
		)
		(duplicate_pad_numbers_are_jumpers no)
		(fp_line
			(start -0.69215 0.2921)
			(end 0.69215 0.2921)
			(stroke
				(width 0.1524)
				(type default)
			)
			(layer "B.SilkS")
		)
		(fp_line
			(start 0.69215 0.2921)
			(end 0.69215 -0.2921)
			(stroke
				(width 0.1524)
				(type default)
			)
			(layer "B.SilkS")
		)
		(fp_line
			(start -0.69215 -0.2921)
			(end -0.69215 0.2921)
			(stroke
				(width 0.1524)
				(type default)
			)
			(layer "B.SilkS")
		)
		(fp_line
			(start 0.69215 -0.2921)
			(end -0.69215 -0.2921)
			(stroke
				(width 0.1524)
				(type default)
			)
			(layer "B.SilkS")
		)
		(fp_line
			(start -0.51435 0.2794)
			(end 0.51435 0.2794)
			(stroke
				(width 0.1)
				(type default)
			)
			(layer "B.Fab")
		)
		(fp_line
			(start 0.51435 0.2794)
			(end 0.51435 -0.2794)
			(stroke
				(width 0.1)
				(type default)
			)
			(layer "B.Fab")
		)
		(fp_line
			(start -0.51435 -0.2794)
			(end -0.51435 0.2794)
			(stroke
				(width 0.1)
				(type default)
			)
			(layer "B.Fab")
		)
		(fp_line
			(start 0.51435 -0.2794)
			(end -0.51435 -0.2794)
			(stroke
				(width 0.1)
				(type default)
			)
			(layer "B.Fab")
		)
		(pad "1" smd circle
			(at 0.40005 0 90)
			(size 0 0)
			(layers "B.Cu" "B.Mask" "B.Paste")
			(net "P1V8_AUX")
		)
		(pad "2" smd circle
			(at -0.40005 0 90)
			(size 0 0)
			(layers "B.Cu" "B.Mask" "B.Paste")
			(net "GND")
		)
		(zone
			(layer "B.Cu")
			(hatch none 0.5)
			(connect_pads
				(clearance 0)
			)
			(min_thickness 0.25)
			(keepout
				(tracks not_allowed)
				(vias allowed)
				(pads allowed)
				(copperpour not_allowed)
				(footprints allowed)
			)
			(placement
				(enabled no)
				(sheetname "")
			)
			(fill
				(thermal_gap 0.5)
				(thermal_bridge_width 0.5)
				(island_removal_mode 0)
			)
			(polygon
				(pts
					(xy 184.186576 -111.764064) (xy 184.186576 -111.963454) (xy 184.244742 -112.053624) (xy 184.420002 -112.053624)
					(xy 184.478422 -111.963454) (xy 184.478422 -111.764064) (xy 184.420256 -111.672624) (xy 184.244742 -111.672624)
				)
			)
		)
	)
	(footprint ""
		(layer "B.Cu")
		(at 259.565394 -51.213512 -90)
		(property "Reference" "PC2341"
			(at 0 0 90)
			(layer "B.SilkS")
			(hide yes)
			(effects
				(font
					(size 1.27 1.27)
				)
				(justify mirror)
			)
		)
		(property "Value" ""
			(at 0 0 90)
			(layer "B.Fab")
			(effects
				(font
					(size 1.27 1.27)
				)
				(justify mirror)
			)
		)
		(duplicate_pad_numbers_are_jumpers no)
		(fp_line
			(start -0.7874 0.4064)
			(end 0.7874 0.4064)
			(stroke
				(width 0.1524)
				(type default)
			)
			(layer "B.SilkS")
		)
		(fp_line
			(start 0.7874 0.4064)
			(end 0.7874 -0.4064)
			(stroke
				(width 0.1524)
				(type default)
			)
			(layer "B.SilkS")
		)
		(fp_line
			(start -0.7874 -0.4064)
			(end -0.7874 0.4064)
			(stroke
				(width 0.1524)
				(type default)
			)
			(layer "B.SilkS")
		)
		(fp_line
			(start 0.7874 -0.4064)
			(end -0.7874 -0.4064)
			(stroke
				(width 0.1524)
				(type default)
			)
			(layer "B.SilkS")
		)
		(fp_line
			(start -0.67945 0.3048)
			(end -0.120396 0.3048)
			(stroke
				(width 0.1)
				(type default)
			)
			(layer "B.Fab")
		)
		(fp_line
			(start -0.120396 0.3048)
			(end -0.120396 0.2794)
			(stroke
				(width 0.1)
				(type default)
			)
			(layer "B.Fab")
		)
		(fp_line
			(start 0.12065 0.3048)
			(end 0.67945 0.3048)
			(stroke
				(width 0.1)
				(type default)
			)
			(layer "B.Fab")
		)
		(fp_line
			(start 0.67945 0.3048)
			(end 0.67945 -0.305054)
			(stroke
				(width 0.1)
				(type default)
			)
			(layer "B.Fab")
		)
		(fp_line
			(start -0.120396 0.2794)
			(end 0.12065 0.2794)
			(stroke
				(width 0.1)
				(type default)
			)
			(layer "B.Fab")
		)
		(fp_line
			(start 0.12065 0.2794)
			(end 0.12065 0.3048)
			(stroke
				(width 0.1)
				(type default)
			)
			(layer "B.Fab")
		)
		(fp_line
			(start -0.12065 -0.2794)
			(end -0.12065 -0.3048)
			(stroke
				(width 0.1)
				(type default)
			)
			(layer "B.Fab")
		)
		(fp_line
			(start 0.12065 -0.2794)
			(end -0.12065 -0.2794)
			(stroke
				(width 0.1)
				(type default)
			)
			(layer "B.Fab")
		)
		(fp_line
			(start -0.67945 -0.3048)
			(end -0.67945 0.3048)
			(stroke
				(width 0.1)
				(type default)
			)
			(layer "B.Fab")
		)
		(fp_line
			(start -0.12065 -0.3048)
			(end -0.67945 -0.3048)
			(stroke
				(width 0.1)
				(type default)
			)
			(layer "B.Fab")
		)
		(fp_line
			(start 0.12065 -0.305054)
			(end 0.12065 -0.2794)
			(stroke
				(width 0.1)
				(type default)
			)
			(layer "B.Fab")
		)
		(fp_line
			(start 0.67945 -0.305054)
			(end 0.12065 -0.305054)
			(stroke
				(width 0.1)
				(type default)
			)
			(layer "B.Fab")
		)
		(pad "1" smd circle
			(at 0.40005 0 90)
			(size 0 0)
			(layers "B.Cu" "B.Mask" "B.Paste")
			(net "P12V_E1S_ISET_0_R")
		)
		(pad "2" smd circle
			(at -0.40005 0 90)
			(size 0 0)
			(layers "B.Cu" "B.Mask" "B.Paste")
			(net "GND")
		)
	)
	(footprint ""
		(layer "B.Cu")
		(at 102.378764 -259.73024 180)
		(property "Reference" "C2102"
			(at 0 0 0)
			(layer "B.SilkS")
			(hide yes)
			(effects
				(font
					(size 1.27 1.27)
				)
				(justify mirror)
			)
		)
		(property "Value" ""
			(at 0 0 0)
			(layer "B.Fab")
			(effects
				(font
					(size 1.27 1.27)
				)
				(justify mirror)
			)
		)
		(duplicate_pad_numbers_are_jumpers no)
		(fp_line
			(start 0.7874 0.4064)
			(end 0.7874 -0.4064)
			(stroke
				(width 0.1524)
				(type default)
			)
			(layer "B.SilkS")
		)
		(fp_line
			(start 0.7874 -0.4064)
			(end -0.7874 -0.4064)
			(stroke
				(width 0.1524)
				(type default)
			)
			(layer "B.SilkS")
		)
		(fp_line
			(start -0.7874 0.4064)
			(end 0.7874 0.4064)
			(stroke
				(width 0.1524)
				(type default)
			)
			(layer "B.SilkS")
		)
		(fp_line
			(start -0.7874 -0.4064)
			(end -0.7874 0.4064)
			(stroke
				(width 0.1524)
				(type default)
			)
			(layer "B.SilkS")
		)
		(fp_line
			(start 0.67945 0.3048)
			(end 0.67945 -0.305054)
			(stroke
				(width 0.1)
				(type default)
			)
			(layer "B.Fab")
		)
		(fp_line
			(start 0.67945 -0.305054)
			(end 0.12065 -0.305054)
			(stroke
				(width 0.1)
				(type default)
			)
			(layer "B.Fab")
		)
		(fp_line
			(start 0.12065 0.3048)
			(end 0.67945 0.3048)
			(stroke
				(width 0.1)
				(type default)
			)
			(layer "B.Fab")
		)
		(fp_line
			(start 0.12065 0.2794)
			(end 0.12065 0.3048)
			(stroke
				(width 0.1)
				(type default)
			)
			(layer "B.Fab")
		)
		(fp_line
			(start 0.12065 -0.2794)
			(end -0.12065 -0.2794)
			(stroke
				(width 0.1)
				(type default)
			)
			(layer "B.Fab")
		)
		(fp_line
			(start 0.12065 -0.305054)
			(end 0.12065 -0.2794)
			(stroke
				(width 0.1)
				(type default)
			)
			(layer "B.Fab")
		)
		(fp_line
			(start -0.120396 0.3048)
			(end -0.120396 0.2794)
			(stroke
				(width 0.1)
				(type default)
			)
			(layer "B.Fab")
		)
		(fp_line
			(start -0.120396 0.2794)
			(end 0.12065 0.2794)
			(stroke
				(width 0.1)
				(type default)
			)
			(layer "B.Fab")
		)
		(fp_line
			(start -0.12065 -0.2794)
			(end -0.12065 -0.3048)
			(stroke
				(width 0.1)
				(type default)
			)
			(layer "B.Fab")
		)
		(fp_line
			(start -0.12065 -0.3048)
			(end -0.67945 -0.3048)
			(stroke
				(width 0.1)
				(type default)
			)
			(layer "B.Fab")
		)
		(fp_line
			(start -0.67945 0.3048)
			(end -0.120396 0.3048)
			(stroke
				(width 0.1)
				(type default)
			)
			(layer "B.Fab")
		)
		(fp_line
			(start -0.67945 -0.3048)
			(end -0.67945 0.3048)
			(stroke
				(width 0.1)
				(type default)
			)
			(layer "B.Fab")
		)
		(pad "1" smd circle
			(at 0.40005 0)
			(size 0 0)
			(layers "B.Cu" "B.Mask" "B.Paste")
			(net "PVDDIO_P1")
		)
		(pad "2" smd circle
			(at -0.40005 0)
			(size 0 0)
			(layers "B.Cu" "B.Mask" "B.Paste")
			(net "GND")
		)
	)
	(footprint ""
		(layer "B.Cu")
		(at 206.429356 -383.612136 180)
		(property "Reference" "PR2527"
			(at 0 0 0)
			(layer "B.SilkS")
			(hide yes)
			(effects
				(font
					(size 1.27 1.27)
				)
				(justify mirror)
			)
		)
		(property "Value" ""
			(at 0 0 0)
			(layer "B.Fab")
			(effects
				(font
					(size 1.27 1.27)
				)
				(justify mirror)
			)
		)
		(duplicate_pad_numbers_are_jumpers no)
		(fp_line
			(start 0.7874 0.4064)
			(end 0.7874 -0.4064)
			(stroke
				(width 0.1524)
				(type default)
			)
			(layer "B.SilkS")
		)
		(fp_line
			(start 0.7874 -0.4064)
			(end -0.7874 -0.4064)
			(stroke
				(width 0.1524)
				(type default)
			)
			(layer "B.SilkS")
		)
		(fp_line
			(start -0.7874 0.4064)
			(end 0.7874 0.4064)
			(stroke
				(width 0.1524)
				(type default)
			)
			(layer "B.SilkS")
		)
		(fp_line
			(start -0.7874 -0.4064)
			(end -0.7874 0.4064)
			(stroke
				(width 0.1524)
				(type default)
			)
			(layer "B.SilkS")
		)
		(fp_line
			(start 0.67945 0.3048)
			(end 0.67945 -0.305054)
			(stroke
				(width 0.1)
				(type default)
			)
			(layer "B.Fab")
		)
		(fp_line
			(start 0.67945 -0.305054)
			(end 0.12065 -0.305054)
			(stroke
				(width 0.1)
				(type default)
			)
			(layer "B.Fab")
		)
		(fp_line
			(start 0.12065 0.3048)
			(end 0.67945 0.3048)
			(stroke
				(width 0.1)
				(type default)
			)
			(layer "B.Fab")
		)
		(fp_line
			(start 0.12065 0.2794)
			(end 0.12065 0.3048)
			(stroke
				(width 0.1)
				(type default)
			)
			(layer "B.Fab")
		)
		(fp_line
			(start 0.12065 -0.2794)
			(end -0.12065 -0.2794)
			(stroke
				(width 0.1)
				(type default)
			)
			(layer "B.Fab")
		)
		(fp_line
			(start 0.12065 -0.305054)
			(end 0.12065 -0.2794)
			(stroke
				(width 0.1)
				(type default)
			)
			(layer "B.Fab")
		)
		(fp_line
			(start -0.120396 0.3048)
			(end -0.120396 0.2794)
			(stroke
				(width 0.1)
				(type default)
			)
			(layer "B.Fab")
		)
		(fp_line
			(start -0.120396 0.2794)
			(end 0.12065 0.2794)
			(stroke
				(width 0.1)
				(type default)
			)
			(layer "B.Fab")
		)
		(fp_line
			(start -0.12065 -0.2794)
			(end -0.12065 -0.3048)
			(stroke
				(width 0.1)
				(type default)
			)
			(layer "B.Fab")
		)
		(fp_line
			(start -0.12065 -0.3048)
			(end -0.67945 -0.3048)
			(stroke
				(width 0.1)
				(type default)
			)
			(layer "B.Fab")
		)
		(fp_line
			(start -0.67945 0.3048)
			(end -0.120396 0.3048)
			(stroke
				(width 0.1)
				(type default)
			)
			(layer "B.Fab")
		)
		(fp_line
			(start -0.67945 -0.3048)
			(end -0.67945 0.3048)
			(stroke
				(width 0.1)
				(type default)
			)
			(layer "B.Fab")
		)
		(pad "1" smd circle
			(at 0.40005 0)
			(size 0 0)
			(layers "B.Cu" "B.Mask" "B.Paste")
			(net "P12V_HSC_SENSE2_N")
		)
		(pad "2" smd circle
			(at -0.40005 0)
			(size 0 0)
			(layers "B.Cu" "B.Mask" "B.Paste")
			(net "P12V_HSC_SENSE2_R4_N")
		)
	)
	(footprint ""
		(layer "B.Cu")
		(at 338.318856 -398.942052 90)
		(property "Reference" "C638"
			(at 0 0 90)
			(layer "B.SilkS")
			(hide yes)
			(effects
				(font
					(size 1.27 1.27)
				)
				(justify mirror)
			)
		)
		(property "Value" ""
			(at 0 0 90)
			(layer "B.Fab")
			(effects
				(font
					(size 1.27 1.27)
				)
				(justify mirror)
			)
		)
		(duplicate_pad_numbers_are_jumpers no)
		(fp_line
			(start 0.7874 -0.4064)
			(end -0.7874 -0.4064)
			(stroke
				(width 0.1524)
				(type default)
			)
			(layer "B.SilkS")
		)
		(fp_line
			(start -0.7874 -0.4064)
			(end -0.7874 0.4064)
			(stroke
				(width 0.1524)
				(type default)
			)
			(layer "B.SilkS")
		)
		(fp_line
			(start 0.7874 0.4064)
			(end 0.7874 -0.4064)
			(stroke
				(width 0.1524)
				(type default)
			)
			(layer "B.SilkS")
		)
		(fp_line
			(start -0.7874 0.4064)
			(end 0.7874 0.4064)
			(stroke
				(width 0.1524)
				(type default)
			)
			(layer "B.SilkS")
		)
		(fp_line
			(start 0.67945 -0.305054)
			(end 0.12065 -0.305054)
			(stroke
				(width 0.1)
				(type default)
			)
			(layer "B.Fab")
		)
		(fp_line
			(start 0.12065 -0.305054)
			(end 0.12065 -0.2794)
			(stroke
				(width 0.1)
				(type default)
			)
			(layer "B.Fab")
		)
		(fp_line
			(start -0.12065 -0.3048)
			(end -0.67945 -0.3048)
			(stroke
				(width 0.1)
				(type default)
			)
			(layer "B.Fab")
		)
		(fp_line
			(start -0.67945 -0.3048)
			(end -0.67945 0.3048)
			(stroke
				(width 0.1)
				(type default)
			)
			(layer "B.Fab")
		)
		(fp_line
			(start 0.12065 -0.2794)
			(end -0.12065 -0.2794)
			(stroke
				(width 0.1)
				(type default)
			)
			(layer "B.Fab")
		)
		(fp_line
			(start -0.12065 -0.2794)
			(end -0.12065 -0.3048)
			(stroke
				(width 0.1)
				(type default)
			)
			(layer "B.Fab")
		)
		(fp_line
			(start 0.12065 0.2794)
			(end 0.12065 0.3048)
			(stroke
				(width 0.1)
				(type default)
			)
			(layer "B.Fab")
		)
		(fp_line
			(start -0.120396 0.2794)
			(end 0.12065 0.2794)
			(stroke
				(width 0.1)
				(type default)
			)
			(layer "B.Fab")
		)
		(fp_line
			(start 0.67945 0.3048)
			(end 0.67945 -0.305054)
			(stroke
				(width 0.1)
				(type default)
			)
			(layer "B.Fab")
		)
		(fp_line
			(start 0.12065 0.3048)
			(end 0.67945 0.3048)
			(stroke
				(width 0.1)
				(type default)
			)
			(layer "B.Fab")
		)
		(fp_line
			(start -0.120396 0.3048)
			(end -0.120396 0.2794)
			(stroke
				(width 0.1)
				(type default)
			)
			(layer "B.Fab")
		)
		(fp_line
			(start -0.67945 0.3048)
			(end -0.120396 0.3048)
			(stroke
				(width 0.1)
				(type default)
			)
			(layer "B.Fab")
		)
		(pad "1" smd circle
			(at 0.40005 0 270)
			(size 0 0)
			(layers "B.Cu" "B.Mask" "B.Paste")
			(net "P0V9_CPU0_RT1_2A")
		)
		(pad "2" smd circle
			(at -0.40005 0 270)
			(size 0 0)
			(layers "B.Cu" "B.Mask" "B.Paste")
			(net "GND")
		)
	)
	(footprint ""
		(layer "B.Cu")
		(at 121.706386 -252.543564)
		(property "Reference" "C2468"
			(at 0 0 0)
			(layer "B.SilkS")
			(hide yes)
			(effects
				(font
					(size 1.27 1.27)
				)
				(justify mirror)
			)
		)
		(property "Value" ""
			(at 0 0 0)
			(layer "B.Fab")
			(effects
				(font
					(size 1.27 1.27)
				)
				(justify mirror)
			)
		)
		(duplicate_pad_numbers_are_jumpers no)
		(fp_line
			(start -0.7874 -0.4064)
			(end -0.7874 0.4064)
			(stroke
				(width 0.1524)
				(type default)
			)
			(layer "B.SilkS")
		)
		(fp_line
			(start -0.7874 0.4064)
			(end 0.7874 0.4064)
			(stroke
				(width 0.1524)
				(type default)
			)
			(layer "B.SilkS")
		)
		(fp_line
			(start 0.7874 -0.4064)
			(end -0.7874 -0.4064)
			(stroke
				(width 0.1524)
				(type default)
			)
			(layer "B.SilkS")
		)
		(fp_line
			(start 0.7874 0.4064)
			(end 0.7874 -0.4064)
			(stroke
				(width 0.1524)
				(type default)
			)
			(layer "B.SilkS")
		)
		(fp_line
			(start -0.67945 -0.3048)
			(end -0.67945 0.3048)
			(stroke
				(width 0.1)
				(type default)
			)
			(layer "B.Fab")
		)
		(fp_line
			(start -0.67945 0.3048)
			(end -0.120396 0.3048)
			(stroke
				(width 0.1)
				(type default)
			)
			(layer "B.Fab")
		)
		(fp_line
			(start -0.12065 -0.3048)
			(end -0.67945 -0.3048)
			(stroke
				(width 0.1)
				(type default)
			)
			(layer "B.Fab")
		)
		(fp_line
			(start -0.12065 -0.2794)
			(end -0.12065 -0.3048)
			(stroke
				(width 0.1)
				(type default)
			)
			(layer "B.Fab")
		)
		(fp_line
			(start -0.120396 0.2794)
			(end 0.12065 0.2794)
			(stroke
				(width 0.1)
				(type default)
			)
			(layer "B.Fab")
		)
		(fp_line
			(start -0.120396 0.3048)
			(end -0.120396 0.2794)
			(stroke
				(width 0.1)
				(type default)
			)
			(layer "B.Fab")
		)
		(fp_line
			(start 0.12065 -0.305054)
			(end 0.12065 -0.2794)
			(stroke
				(width 0.1)
				(type default)
			)
			(layer "B.Fab")
		)
		(fp_line
			(start 0.12065 -0.2794)
			(end -0.12065 -0.2794)
			(stroke
				(width 0.1)
				(type default)
			)
			(layer "B.Fab")
		)
		(fp_line
			(start 0.12065 0.2794)
			(end 0.12065 0.3048)
			(stroke
				(width 0.1)
				(type default)
			)
			(layer "B.Fab")
		)
		(fp_line
			(start 0.12065 0.3048)
			(end 0.67945 0.3048)
			(stroke
				(width 0.1)
				(type default)
			)
			(layer "B.Fab")
		)
		(fp_line
			(start 0.67945 -0.305054)
			(end 0.12065 -0.305054)
			(stroke
				(width 0.1)
				(type default)
			)
			(layer "B.Fab")
		)
		(fp_line
			(start 0.67945 0.3048)
			(end 0.67945 -0.305054)
			(stroke
				(width 0.1)
				(type default)
			)
			(layer "B.Fab")
		)
		(pad "1" smd circle
			(at 0.40005 0 180)
			(size 0 0)
			(layers "B.Cu" "B.Mask" "B.Paste")
			(net "PVDDCR_SOC_P1")
		)
		(pad "2" smd circle
			(at -0.40005 0 180)
			(size 0 0)
			(layers "B.Cu" "B.Mask" "B.Paste")
			(net "GND")
		)
	)
	(footprint ""
		(layer "B.Cu")
		(at 373.329454 -259.729986)
		(property "Reference" "C2584"
			(at 0 0 0)
			(layer "B.SilkS")
			(hide yes)
			(effects
				(font
					(size 1.27 1.27)
				)
				(justify mirror)
			)
		)
		(property "Value" ""
			(at 0 0 0)
			(layer "B.Fab")
			(effects
				(font
					(size 1.27 1.27)
				)
				(justify mirror)
			)
		)
		(duplicate_pad_numbers_are_jumpers no)
		(fp_line
			(start -0.7874 -0.4064)
			(end -0.7874 0.4064)
			(stroke
				(width 0.1524)
				(type default)
			)
			(layer "B.SilkS")
		)
		(fp_line
			(start -0.7874 0.4064)
			(end 0.7874 0.4064)
			(stroke
				(width 0.1524)
				(type default)
			)
			(layer "B.SilkS")
		)
		(fp_line
			(start 0.7874 -0.4064)
			(end -0.7874 -0.4064)
			(stroke
				(width 0.1524)
				(type default)
			)
			(layer "B.SilkS")
		)
		(fp_line
			(start 0.7874 0.4064)
			(end 0.7874 -0.4064)
			(stroke
				(width 0.1524)
				(type default)
			)
			(layer "B.SilkS")
		)
		(fp_line
			(start -0.67945 -0.3048)
			(end -0.67945 0.3048)
			(stroke
				(width 0.1)
				(type default)
			)
			(layer "B.Fab")
		)
		(fp_line
			(start -0.67945 0.3048)
			(end -0.120396 0.3048)
			(stroke
				(width 0.1)
				(type default)
			)
			(layer "B.Fab")
		)
		(fp_line
			(start -0.12065 -0.3048)
			(end -0.67945 -0.3048)
			(stroke
				(width 0.1)
				(type default)
			)
			(layer "B.Fab")
		)
		(fp_line
			(start -0.12065 -0.2794)
			(end -0.12065 -0.3048)
			(stroke
				(width 0.1)
				(type default)
			)
			(layer "B.Fab")
		)
		(fp_line
			(start -0.120396 0.2794)
			(end 0.12065 0.2794)
			(stroke
				(width 0.1)
				(type default)
			)
			(layer "B.Fab")
		)
		(fp_line
			(start -0.120396 0.3048)
			(end -0.120396 0.2794)
			(stroke
				(width 0.1)
				(type default)
			)
			(layer "B.Fab")
		)
		(fp_line
			(start 0.12065 -0.305054)
			(end 0.12065 -0.2794)
			(stroke
				(width 0.1)
				(type default)
			)
			(layer "B.Fab")
		)
		(fp_line
			(start 0.12065 -0.2794)
			(end -0.12065 -0.2794)
			(stroke
				(width 0.1)
				(type default)
			)
			(layer "B.Fab")
		)
		(fp_line
			(start 0.12065 0.2794)
			(end 0.12065 0.3048)
			(stroke
				(width 0.1)
				(type default)
			)
			(layer "B.Fab")
		)
		(fp_line
			(start 0.12065 0.3048)
			(end 0.67945 0.3048)
			(stroke
				(width 0.1)
				(type default)
			)
			(layer "B.Fab")
		)
		(fp_line
			(start 0.67945 -0.305054)
			(end 0.12065 -0.305054)
			(stroke
				(width 0.1)
				(type default)
			)
			(layer "B.Fab")
		)
		(fp_line
			(start 0.67945 0.3048)
			(end 0.67945 -0.305054)
			(stroke
				(width 0.1)
				(type default)
			)
			(layer "B.Fab")
		)
		(pad "1" smd circle
			(at 0.40005 0 180)
			(size 0 0)
			(layers "B.Cu" "B.Mask" "B.Paste")
			(net "PVDDCR_SOC_P0")
		)
		(pad "2" smd circle
			(at -0.40005 0 180)
			(size 0 0)
			(layers "B.Cu" "B.Mask" "B.Paste")
			(net "GND")
		)
	)
	(footprint ""
		(layer "B.Cu")
		(at 403.17928 -178.77282 90)
		(property "Reference" "PC603_2"
			(at 0 0 90)
			(layer "B.SilkS")
			(hide yes)
			(effects
				(font
					(size 1.27 1.27)
				)
				(justify mirror)
			)
		)
		(property "Value" ""
			(at 0 0 90)
			(layer "B.Fab")
			(effects
				(font
					(size 1.27 1.27)
				)
				(justify mirror)
			)
		)
		(duplicate_pad_numbers_are_jumpers no)
		(fp_line
			(start 1.524 -0.762)
			(end -1.524 -0.762)
			(stroke
				(width 0.1524)
				(type default)
			)
			(layer "B.SilkS")
		)
		(fp_line
			(start -1.524 -0.762)
			(end -1.524 0.762)
			(stroke
				(width 0.1524)
				(type default)
			)
			(layer "B.SilkS")
		)
		(fp_line
			(start 1.524 0.762)
			(end 1.524 -0.762)
			(stroke
				(width 0.1524)
				(type default)
			)
			(layer "B.SilkS")
		)
		(fp_line
			(start -1.524 0.762)
			(end 1.524 0.762)
			(stroke
				(width 0.1524)
				(type default)
			)
			(layer "B.SilkS")
		)
		(fp_line
			(start 1.1049 -0.724916)
			(end 1.1049 0.724916)
			(stroke
				(width 0.1)
				(type default)
			)
			(layer "B.Fab")
		)
		(fp_line
			(start -1.1049 -0.724916)
			(end 1.1049 -0.724916)
			(stroke
				(width 0.1)
				(type default)
			)
			(layer "B.Fab")
		)
		(fp_line
			(start 1.1049 0.724916)
			(end -1.1049 0.724916)
			(stroke
				(width 0.1)
				(type default)
			)
			(layer "B.Fab")
		)
		(fp_line
			(start -1.1049 0.724916)
			(end -1.1049 -0.724916)
			(stroke
				(width 0.1)
				(type default)
			)
			(layer "B.Fab")
		)
		(pad "1" smd rect
			(at 0.889 0 90)
			(size 1.016 1.27)
			(layers "B.Cu" "B.Mask" "B.Paste")
			(net "PVDDCR_SOC_P0")
		)
		(pad "2" smd rect
			(at -0.889 0 90)
			(size 1.016 1.27)
			(layers "B.Cu" "B.Mask" "B.Paste")
			(net "GND")
		)
	)
	(footprint ""
		(layer "B.Cu")
		(at 84.84616 -388.011162 -90)
		(property "Reference" "C313"
			(at 0 0 90)
			(layer "B.SilkS")
			(hide yes)
			(effects
				(font
					(size 1.27 1.27)
				)
				(justify mirror)
			)
		)
		(property "Value" ""
			(at 0 0 90)
			(layer "B.Fab")
			(effects
				(font
					(size 1.27 1.27)
				)
				(justify mirror)
			)
		)
		(duplicate_pad_numbers_are_jumpers no)
		(fp_line
			(start -0.299974 0.150114)
			(end 0.299974 0.150114)
			(stroke
				(width 0.1)
				(type default)
			)
			(layer "B.Fab")
		)
		(fp_line
			(start 0.299974 0.150114)
			(end 0.299974 -0.150114)
			(stroke
				(width 0.1)
				(type default)
			)
			(layer "B.Fab")
		)
		(fp_line
			(start -0.299974 -0.150114)
			(end -0.299974 0.150114)
			(stroke
				(width 0.1)
				(type default)
			)
			(layer "B.Fab")
		)
		(fp_line
			(start 0.299974 -0.150114)
			(end -0.299974 -0.150114)
			(stroke
				(width 0.1)
				(type default)
			)
			(layer "B.Fab")
		)
		(pad "1" smd rect
			(at 0.2667 0 90)
			(size 0.3048 0.381)
			(layers "B.Cu" "B.Mask" "B.Paste")
			(net "P0V9_CPU1_RT1_2A_2D")
		)
		(pad "2" smd rect
			(at -0.2667 0 90)
			(size 0.3048 0.381)
			(layers "B.Cu" "B.Mask" "B.Paste")
			(net "GND")
		)
	)
	(footprint ""
		(layer "B.Cu")
		(at 366.217454 -268.41831)
		(property "Reference" "C2222"
			(at 0 0 0)
			(layer "B.SilkS")
			(hide yes)
			(effects
				(font
					(size 1.27 1.27)
				)
				(justify mirror)
			)
		)
		(property "Value" ""
			(at 0 0 0)
			(layer "B.Fab")
			(effects
				(font
					(size 1.27 1.27)
				)
				(justify mirror)
			)
		)
		(duplicate_pad_numbers_are_jumpers no)
		(fp_line
			(start -0.7874 -0.4064)
			(end -0.7874 0.4064)
			(stroke
				(width 0.1524)
				(type default)
			)
			(layer "B.SilkS")
		)
		(fp_line
			(start -0.7874 0.4064)
			(end 0.7874 0.4064)
			(stroke
				(width 0.1524)
				(type default)
			)
			(layer "B.SilkS")
		)
		(fp_line
			(start 0.7874 -0.4064)
			(end -0.7874 -0.4064)
			(stroke
				(width 0.1524)
				(type default)
			)
			(layer "B.SilkS")
		)
		(fp_line
			(start 0.7874 0.4064)
			(end 0.7874 -0.4064)
			(stroke
				(width 0.1524)
				(type default)
			)
			(layer "B.SilkS")
		)
		(fp_line
			(start -0.67945 -0.3048)
			(end -0.67945 0.3048)
			(stroke
				(width 0.1)
				(type default)
			)
			(layer "B.Fab")
		)
		(fp_line
			(start -0.67945 0.3048)
			(end -0.120396 0.3048)
			(stroke
				(width 0.1)
				(type default)
			)
			(layer "B.Fab")
		)
		(fp_line
			(start -0.12065 -0.3048)
			(end -0.67945 -0.3048)
			(stroke
				(width 0.1)
				(type default)
			)
			(layer "B.Fab")
		)
		(fp_line
			(start -0.12065 -0.2794)
			(end -0.12065 -0.3048)
			(stroke
				(width 0.1)
				(type default)
			)
			(layer "B.Fab")
		)
		(fp_line
			(start -0.120396 0.2794)
			(end 0.12065 0.2794)
			(stroke
				(width 0.1)
				(type default)
			)
			(layer "B.Fab")
		)
		(fp_line
			(start -0.120396 0.3048)
			(end -0.120396 0.2794)
			(stroke
				(width 0.1)
				(type default)
			)
			(layer "B.Fab")
		)
		(fp_line
			(start 0.12065 -0.305054)
			(end 0.12065 -0.2794)
			(stroke
				(width 0.1)
				(type default)
			)
			(layer "B.Fab")
		)
		(fp_line
			(start 0.12065 -0.2794)
			(end -0.12065 -0.2794)
			(stroke
				(width 0.1)
				(type default)
			)
			(layer "B.Fab")
		)
		(fp_line
			(start 0.12065 0.2794)
			(end 0.12065 0.3048)
			(stroke
				(width 0.1)
				(type default)
			)
			(layer "B.Fab")
		)
		(fp_line
			(start 0.12065 0.3048)
			(end 0.67945 0.3048)
			(stroke
				(width 0.1)
				(type default)
			)
			(layer "B.Fab")
		)
		(fp_line
			(start 0.67945 -0.305054)
			(end 0.12065 -0.305054)
			(stroke
				(width 0.1)
				(type default)
			)
			(layer "B.Fab")
		)
		(fp_line
			(start 0.67945 0.3048)
			(end 0.67945 -0.305054)
			(stroke
				(width 0.1)
				(type default)
			)
			(layer "B.Fab")
		)
		(pad "1" smd circle
			(at 0.40005 0 180)
			(size 0 0)
			(layers "B.Cu" "B.Mask" "B.Paste")
			(net "PVDDCR_CPU1_P0")
		)
		(pad "2" smd circle
			(at -0.40005 0 180)
			(size 0 0)
			(layers "B.Cu" "B.Mask" "B.Paste")
			(net "GND")
		)
	)
	(footprint ""
		(layer "B.Cu")
		(at 120.49125 -390.560052 90)
		(property "Reference" "C484"
			(at 0 0 90)
			(layer "B.SilkS")
			(hide yes)
			(effects
				(font
					(size 1.27 1.27)
				)
				(justify mirror)
			)
		)
		(property "Value" ""
			(at 0 0 90)
			(layer "B.Fab")
			(effects
				(font
					(size 1.27 1.27)
				)
				(justify mirror)
			)
		)
		(duplicate_pad_numbers_are_jumpers no)
		(fp_line
			(start 0.7874 -0.4064)
			(end -0.7874 -0.4064)
			(stroke
				(width 0.1524)
				(type default)
			)
			(layer "B.SilkS")
		)
		(fp_line
			(start -0.7874 -0.4064)
			(end -0.7874 0.4064)
			(stroke
				(width 0.1524)
				(type default)
			)
			(layer "B.SilkS")
		)
		(fp_line
			(start 0.7874 0.4064)
			(end 0.7874 -0.4064)
			(stroke
				(width 0.1524)
				(type default)
			)
			(layer "B.SilkS")
		)
		(fp_line
			(start -0.7874 0.4064)
			(end 0.7874 0.4064)
			(stroke
				(width 0.1524)
				(type default)
			)
			(layer "B.SilkS")
		)
		(fp_line
			(start 0.67945 -0.305054)
			(end 0.12065 -0.305054)
			(stroke
				(width 0.1)
				(type default)
			)
			(layer "B.Fab")
		)
		(fp_line
			(start 0.12065 -0.305054)
			(end 0.12065 -0.2794)
			(stroke
				(width 0.1)
				(type default)
			)
			(layer "B.Fab")
		)
		(fp_line
			(start -0.12065 -0.3048)
			(end -0.67945 -0.3048)
			(stroke
				(width 0.1)
				(type default)
			)
			(layer "B.Fab")
		)
		(fp_line
			(start -0.67945 -0.3048)
			(end -0.67945 0.3048)
			(stroke
				(width 0.1)
				(type default)
			)
			(layer "B.Fab")
		)
		(fp_line
			(start 0.12065 -0.2794)
			(end -0.12065 -0.2794)
			(stroke
				(width 0.1)
				(type default)
			)
			(layer "B.Fab")
		)
		(fp_line
			(start -0.12065 -0.2794)
			(end -0.12065 -0.3048)
			(stroke
				(width 0.1)
				(type default)
			)
			(layer "B.Fab")
		)
		(fp_line
			(start 0.12065 0.2794)
			(end 0.12065 0.3048)
			(stroke
				(width 0.1)
				(type default)
			)
			(layer "B.Fab")
		)
		(fp_line
			(start -0.120396 0.2794)
			(end 0.12065 0.2794)
			(stroke
				(width 0.1)
				(type default)
			)
			(layer "B.Fab")
		)
		(fp_line
			(start 0.67945 0.3048)
			(end 0.67945 -0.305054)
			(stroke
				(width 0.1)
				(type default)
			)
			(layer "B.Fab")
		)
		(fp_line
			(start 0.12065 0.3048)
			(end 0.67945 0.3048)
			(stroke
				(width 0.1)
				(type default)
			)
			(layer "B.Fab")
		)
		(fp_line
			(start -0.120396 0.3048)
			(end -0.120396 0.2794)
			(stroke
				(width 0.1)
				(type default)
			)
			(layer "B.Fab")
		)
		(fp_line
			(start -0.67945 0.3048)
			(end -0.120396 0.3048)
			(stroke
				(width 0.1)
				(type default)
			)
			(layer "B.Fab")
		)
		(pad "1" smd circle
			(at 0.40005 0 270)
			(size 0 0)
			(layers "B.Cu" "B.Mask" "B.Paste")
			(net "P0V9_CPU1_RT_2D")
		)
		(pad "2" smd circle
			(at -0.40005 0 270)
			(size 0 0)
			(layers "B.Cu" "B.Mask" "B.Paste")
			(net "GND")
		)
	)
	(footprint ""
		(layer "B.Cu")
		(at 98.336354 -189.453012 90)
		(property "Reference" "PC275"
			(at 5.837936 0.970534 270)
			(unlocked yes)
			(layer "B.SilkS")
			(effects
				(font
					(size 0.7874 0.5842)
					(thickness 0.1524)
				)
				(justify left mirror)
			)
		)
		(property "Value" ""
			(at 0 0 90)
			(layer "B.Fab")
			(effects
				(font
					(size 1.27 1.27)
				)
				(justify mirror)
			)
		)
		(duplicate_pad_numbers_are_jumpers no)
		(fp_line
			(start 4.533392 -2.249932)
			(end -4.533392 -2.249932)
			(stroke
				(width 0.1524)
				(type default)
			)
			(layer "B.SilkS")
		)
		(fp_line
			(start -4.533392 -2.249932)
			(end -4.533392 2.249932)
			(stroke
				(width 0.1524)
				(type default)
			)
			(layer "B.SilkS")
		)
		(fp_line
			(start 4.533392 2.249932)
			(end 4.533392 -2.249932)
			(stroke
				(width 0.1524)
				(type default)
			)
			(layer "B.SilkS")
		)
		(fp_line
			(start -4.533392 2.249932)
			(end 4.533392 2.249932)
			(stroke
				(width 0.1524)
				(type default)
			)
			(layer "B.SilkS")
		)
		(fp_rect
			(start 4.533392 -2.326132)
			(end 5.39242 2.326132)
			(stroke
				(width 0)
				(type default)
			)
			(fill yes)
			(layer "B.SilkS")
		)
		(fp_line
			(start 3.750056 -2.249932)
			(end -3.750056 -2.249932)
			(stroke
				(width 0.1)
				(type default)
			)
			(layer "B.Fab")
		)
		(fp_line
			(start -3.750056 -2.249932)
			(end -3.750056 2.249932)
			(stroke
				(width 0.1)
				(type default)
			)
			(layer "B.Fab")
		)
		(fp_line
			(start 3.750056 2.249932)
			(end 3.750056 -2.249932)
			(stroke
				(width 0.1)
				(type default)
			)
			(layer "B.Fab")
		)
		(fp_line
			(start -3.750056 2.249932)
			(end 3.750056 2.249932)
			(stroke
				(width 0.1)
				(type default)
			)
			(layer "B.Fab")
		)
		(fp_text user "+"
			(at 6.322314 0.786384 0)
			(unlocked yes)
			(layer "B.SilkS")
			(effects
				(font
					(size 1.905 1.4224)
					(thickness 0.1524)
				)
				(justify left mirror)
			)
		)
		(fp_text user "-"
			(at -5.105908 0.958088 90)
			(unlocked yes)
			(layer "B.SilkS")
			(effects
				(font
					(size 1.905 1.4224)
					(thickness 0.1524)
				)
				(justify left mirror)
			)
		)
		(fp_text user "-"
			(at -4.8514 -0.14605 90)
			(unlocked yes)
			(layer "B.Fab")
			(effects
				(font
					(size 1.905 1.4224)
					(thickness 0.1524)
				)
				(justify left mirror)
			)
		)
		(fp_text user "+"
			(at 6.322314 0.786384 0)
			(unlocked yes)
			(layer "B.Fab")
			(effects
				(font
					(size 1.905 1.4224)
					(thickness 0.1524)
				)
				(justify left mirror)
			)
		)
		(pad "1" smd rect
			(at 3.199892 0 270)
			(size 2.413 2.8194)
			(layers "B.Cu" "B.Mask" "B.Paste")
			(net "PVDDCR_CPU0_P1")
		)
		(pad "2" smd rect
			(at -3.199892 0 270)
			(size 2.413 2.8194)
			(layers "B.Cu" "B.Mask" "B.Paste")
			(net "GND")
		)
	)
	(footprint ""
		(layer "B.Cu")
		(at 365.835692 -262.204962)
		(property "Reference" "C3892"
			(at 0 0 0)
			(layer "B.SilkS")
			(hide yes)
			(effects
				(font
					(size 1.27 1.27)
				)
				(justify mirror)
			)
		)
		(property "Value" ""
			(at 0 0 0)
			(layer "B.Fab")
			(effects
				(font
					(size 1.27 1.27)
				)
				(justify mirror)
			)
		)
		(duplicate_pad_numbers_are_jumpers no)
		(fp_line
			(start -0.7874 -0.4064)
			(end -0.7874 0.4064)
			(stroke
				(width 0.1524)
				(type default)
			)
			(layer "B.SilkS")
		)
		(fp_line
			(start -0.7874 0.4064)
			(end 0.7874 0.4064)
			(stroke
				(width 0.1524)
				(type default)
			)
			(layer "B.SilkS")
		)
		(fp_line
			(start 0.7874 -0.4064)
			(end -0.7874 -0.4064)
			(stroke
				(width 0.1524)
				(type default)
			)
			(layer "B.SilkS")
		)
		(fp_line
			(start 0.7874 0.4064)
			(end 0.7874 -0.4064)
			(stroke
				(width 0.1524)
				(type default)
			)
			(layer "B.SilkS")
		)
		(fp_line
			(start -0.67945 -0.3048)
			(end -0.67945 0.3048)
			(stroke
				(width 0.1)
				(type default)
			)
			(layer "B.Fab")
		)
		(fp_line
			(start -0.67945 0.3048)
			(end -0.120396 0.3048)
			(stroke
				(width 0.1)
				(type default)
			)
			(layer "B.Fab")
		)
		(fp_line
			(start -0.12065 -0.3048)
			(end -0.67945 -0.3048)
			(stroke
				(width 0.1)
				(type default)
			)
			(layer "B.Fab")
		)
		(fp_line
			(start -0.12065 -0.2794)
			(end -0.12065 -0.3048)
			(stroke
				(width 0.1)
				(type default)
			)
			(layer "B.Fab")
		)
		(fp_line
			(start -0.120396 0.2794)
			(end 0.12065 0.2794)
			(stroke
				(width 0.1)
				(type default)
			)
			(layer "B.Fab")
		)
		(fp_line
			(start -0.120396 0.3048)
			(end -0.120396 0.2794)
			(stroke
				(width 0.1)
				(type default)
			)
			(layer "B.Fab")
		)
		(fp_line
			(start 0.12065 -0.305054)
			(end 0.12065 -0.2794)
			(stroke
				(width 0.1)
				(type default)
			)
			(layer "B.Fab")
		)
		(fp_line
			(start 0.12065 -0.2794)
			(end -0.12065 -0.2794)
			(stroke
				(width 0.1)
				(type default)
			)
			(layer "B.Fab")
		)
		(fp_line
			(start 0.12065 0.2794)
			(end 0.12065 0.3048)
			(stroke
				(width 0.1)
				(type default)
			)
			(layer "B.Fab")
		)
		(fp_line
			(start 0.12065 0.3048)
			(end 0.67945 0.3048)
			(stroke
				(width 0.1)
				(type default)
			)
			(layer "B.Fab")
		)
		(fp_line
			(start 0.67945 -0.305054)
			(end 0.12065 -0.305054)
			(stroke
				(width 0.1)
				(type default)
			)
			(layer "B.Fab")
		)
		(fp_line
			(start 0.67945 0.3048)
			(end 0.67945 -0.305054)
			(stroke
				(width 0.1)
				(type default)
			)
			(layer "B.Fab")
		)
		(pad "1" smd circle
			(at 0.40005 0 180)
			(size 0 0)
			(layers "B.Cu" "B.Mask" "B.Paste")
			(net "PVDD11_S3_P0")
		)
		(pad "2" smd circle
			(at -0.40005 0 180)
			(size 0 0)
			(layers "B.Cu" "B.Mask" "B.Paste")
			(net "GND")
		)
	)
	(footprint ""
		(layer "B.Cu")
		(at 214.884 -330.708)
		(property "Reference" "R6775"
			(at 0 0 0)
			(layer "B.SilkS")
			(hide yes)
			(effects
				(font
					(size 1.27 1.27)
				)
				(justify mirror)
			)
		)
		(property "Value" ""
			(at 0 0 0)
			(layer "B.Fab")
			(effects
				(font
					(size 1.27 1.27)
				)
				(justify mirror)
			)
		)
		(duplicate_pad_numbers_are_jumpers no)
		(fp_line
			(start -0.32512 -0.175006)
			(end -0.32512 0.175006)
			(stroke
				(width 0.1)
				(type default)
			)
			(layer "B.Fab")
		)
		(fp_line
			(start -0.32512 0.175006)
			(end 0.32512 0.175006)
			(stroke
				(width 0.1)
				(type default)
			)
			(layer "B.Fab")
		)
		(fp_line
			(start 0.32512 -0.175006)
			(end -0.32512 -0.175006)
			(stroke
				(width 0.1)
				(type default)
			)
			(layer "B.Fab")
		)
		(fp_line
			(start 0.32512 0.175006)
			(end 0.32512 -0.175006)
			(stroke
				(width 0.1)
				(type default)
			)
			(layer "B.Fab")
		)
		(pad "1" smd rect
			(at 0.2667 0 180)
			(size 0.3048 0.381)
			(layers "B.Cu" "B.Mask" "B.Paste")
			(net "RT_SMB_MUX_ADDR0")
		)
		(pad "2" smd rect
			(at -0.2667 0)
			(size 0.3048 0.381)
			(layers "B.Cu" "B.Mask" "B.Paste")
			(net "GND")
		)
	)
	(footprint ""
		(layer "B.Cu")
		(at 326.64527 -395.466062 -90)
		(property "Reference" "C502"
			(at 0 0 90)
			(layer "B.SilkS")
			(hide yes)
			(effects
				(font
					(size 1.27 1.27)
				)
				(justify mirror)
			)
		)
		(property "Value" ""
			(at 0 0 90)
			(layer "B.Fab")
			(effects
				(font
					(size 1.27 1.27)
				)
				(justify mirror)
			)
		)
		(duplicate_pad_numbers_are_jumpers no)
		(fp_line
			(start -1.524 0.762)
			(end 1.524 0.762)
			(stroke
				(width 0.1524)
				(type default)
			)
			(layer "B.SilkS")
		)
		(fp_line
			(start 1.524 0.762)
			(end 1.524 -0.762)
			(stroke
				(width 0.1524)
				(type default)
			)
			(layer "B.SilkS")
		)
		(fp_line
			(start -1.524 -0.762)
			(end -1.524 0.762)
			(stroke
				(width 0.1524)
				(type default)
			)
			(layer "B.SilkS")
		)
		(fp_line
			(start 1.524 -0.762)
			(end -1.524 -0.762)
			(stroke
				(width 0.1524)
				(type default)
			)
			(layer "B.SilkS")
		)
		(fp_line
			(start -1.1049 0.724916)
			(end -1.1049 -0.724916)
			(stroke
				(width 0.1)
				(type default)
			)
			(layer "B.Fab")
		)
		(fp_line
			(start 1.1049 0.724916)
			(end -1.1049 0.724916)
			(stroke
				(width 0.1)
				(type default)
			)
			(layer "B.Fab")
		)
		(fp_line
			(start -1.1049 -0.724916)
			(end 1.1049 -0.724916)
			(stroke
				(width 0.1)
				(type default)
			)
			(layer "B.Fab")
		)
		(fp_line
			(start 1.1049 -0.724916)
			(end 1.1049 0.724916)
			(stroke
				(width 0.1)
				(type default)
			)
			(layer "B.Fab")
		)
		(pad "1" smd rect
			(at 0.889 0 270)
			(size 1.016 1.27)
			(layers "B.Cu" "B.Mask" "B.Paste")
			(net "P1V8_CPU0_RT_1D")
		)
		(pad "2" smd rect
			(at -0.889 0 270)
			(size 1.016 1.27)
			(layers "B.Cu" "B.Mask" "B.Paste")
			(net "GND")
		)
	)
	(footprint ""
		(layer "B.Cu")
		(at 355.616002 -256.012188 -90)
		(property "Reference" "C2568"
			(at 0 0 90)
			(layer "B.SilkS")
			(hide yes)
			(effects
				(font
					(size 1.27 1.27)
				)
				(justify mirror)
			)
		)
		(property "Value" ""
			(at 0 0 90)
			(layer "B.Fab")
			(effects
				(font
					(size 1.27 1.27)
				)
				(justify mirror)
			)
		)
		(duplicate_pad_numbers_are_jumpers no)
		(fp_line
			(start -0.7874 0.4064)
			(end 0.7874 0.4064)
			(stroke
				(width 0.1524)
				(type default)
			)
			(layer "B.SilkS")
		)
		(fp_line
			(start 0.7874 0.4064)
			(end 0.7874 -0.4064)
			(stroke
				(width 0.1524)
				(type default)
			)
			(layer "B.SilkS")
		)
		(fp_line
			(start -0.7874 -0.4064)
			(end -0.7874 0.4064)
			(stroke
				(width 0.1524)
				(type default)
			)
			(layer "B.SilkS")
		)
		(fp_line
			(start 0.7874 -0.4064)
			(end -0.7874 -0.4064)
			(stroke
				(width 0.1524)
				(type default)
			)
			(layer "B.SilkS")
		)
		(fp_line
			(start -0.67945 0.3048)
			(end -0.120396 0.3048)
			(stroke
				(width 0.1)
				(type default)
			)
			(layer "B.Fab")
		)
		(fp_line
			(start -0.120396 0.3048)
			(end -0.120396 0.2794)
			(stroke
				(width 0.1)
				(type default)
			)
			(layer "B.Fab")
		)
		(fp_line
			(start 0.12065 0.3048)
			(end 0.67945 0.3048)
			(stroke
				(width 0.1)
				(type default)
			)
			(layer "B.Fab")
		)
		(fp_line
			(start 0.67945 0.3048)
			(end 0.67945 -0.305054)
			(stroke
				(width 0.1)
				(type default)
			)
			(layer "B.Fab")
		)
		(fp_line
			(start -0.120396 0.2794)
			(end 0.12065 0.2794)
			(stroke
				(width 0.1)
				(type default)
			)
			(layer "B.Fab")
		)
		(fp_line
			(start 0.12065 0.2794)
			(end 0.12065 0.3048)
			(stroke
				(width 0.1)
				(type default)
			)
			(layer "B.Fab")
		)
		(fp_line
			(start -0.12065 -0.2794)
			(end -0.12065 -0.3048)
			(stroke
				(width 0.1)
				(type default)
			)
			(layer "B.Fab")
		)
		(fp_line
			(start 0.12065 -0.2794)
			(end -0.12065 -0.2794)
			(stroke
				(width 0.1)
				(type default)
			)
			(layer "B.Fab")
		)
		(fp_line
			(start -0.67945 -0.3048)
			(end -0.67945 0.3048)
			(stroke
				(width 0.1)
				(type default)
			)
			(layer "B.Fab")
		)
		(fp_line
			(start -0.12065 -0.3048)
			(end -0.67945 -0.3048)
			(stroke
				(width 0.1)
				(type default)
			)
			(layer "B.Fab")
		)
		(fp_line
			(start 0.12065 -0.305054)
			(end 0.12065 -0.2794)
			(stroke
				(width 0.1)
				(type default)
			)
			(layer "B.Fab")
		)
		(fp_line
			(start 0.67945 -0.305054)
			(end 0.12065 -0.305054)
			(stroke
				(width 0.1)
				(type default)
			)
			(layer "B.Fab")
		)
		(pad "1" smd circle
			(at 0.40005 0 90)
			(size 0 0)
			(layers "B.Cu" "B.Mask" "B.Paste")
			(net "PVDDCR_SOC_P0")
		)
		(pad "2" smd circle
			(at -0.40005 0 90)
			(size 0 0)
			(layers "B.Cu" "B.Mask" "B.Paste")
			(net "GND")
		)
	)
	(footprint ""
		(layer "B.Cu")
		(at 69.753734 -185.396632 90)
		(property "Reference" "PC281_1"
			(at 0 0 90)
			(layer "B.SilkS")
			(hide yes)
			(effects
				(font
					(size 1.27 1.27)
				)
				(justify mirror)
			)
		)
		(property "Value" ""
			(at 0 0 90)
			(layer "B.Fab")
			(effects
				(font
					(size 1.27 1.27)
				)
				(justify mirror)
			)
		)
		(duplicate_pad_numbers_are_jumpers no)
		(fp_line
			(start 1.524 -0.762)
			(end -1.524 -0.762)
			(stroke
				(width 0.1524)
				(type default)
			)
			(layer "B.SilkS")
		)
		(fp_line
			(start -1.524 -0.762)
			(end -1.524 0.762)
			(stroke
				(width 0.1524)
				(type default)
			)
			(layer "B.SilkS")
		)
		(fp_line
			(start 1.524 0.762)
			(end 1.524 -0.762)
			(stroke
				(width 0.1524)
				(type default)
			)
			(layer "B.SilkS")
		)
		(fp_line
			(start -1.524 0.762)
			(end 1.524 0.762)
			(stroke
				(width 0.1524)
				(type default)
			)
			(layer "B.SilkS")
		)
		(fp_line
			(start 1.1049 -0.724916)
			(end 1.1049 0.724916)
			(stroke
				(width 0.1)
				(type default)
			)
			(layer "B.Fab")
		)
		(fp_line
			(start -1.1049 -0.724916)
			(end 1.1049 -0.724916)
			(stroke
				(width 0.1)
				(type default)
			)
			(layer "B.Fab")
		)
		(fp_line
			(start 1.1049 0.724916)
			(end -1.1049 0.724916)
			(stroke
				(width 0.1)
				(type default)
			)
			(layer "B.Fab")
		)
		(fp_line
			(start -1.1049 0.724916)
			(end -1.1049 -0.724916)
			(stroke
				(width 0.1)
				(type default)
			)
			(layer "B.Fab")
		)
		(pad "1" smd rect
			(at 0.889 0 90)
			(size 1.016 1.27)
			(layers "B.Cu" "B.Mask" "B.Paste")
			(net "PVDDCR_CPU0_P1")
		)
		(pad "2" smd rect
			(at -0.889 0 90)
			(size 1.016 1.27)
			(layers "B.Cu" "B.Mask" "B.Paste")
			(net "GND")
		)
	)
	(footprint ""
		(layer "B.Cu")
		(at 91.966542 -151.376634 90)
		(property "Reference" "PR173"
			(at 0 0 90)
			(layer "B.SilkS")
			(hide yes)
			(effects
				(font
					(size 1.27 1.27)
				)
				(justify mirror)
			)
		)
		(property "Value" ""
			(at 0 0 90)
			(layer "B.Fab")
			(effects
				(font
					(size 1.27 1.27)
				)
				(justify mirror)
			)
		)
		(duplicate_pad_numbers_are_jumpers no)
		(fp_line
			(start 0.7874 -0.4064)
			(end -0.7874 -0.4064)
			(stroke
				(width 0.1524)
				(type default)
			)
			(layer "B.SilkS")
		)
		(fp_line
			(start -0.7874 -0.4064)
			(end -0.7874 0.4064)
			(stroke
				(width 0.1524)
				(type default)
			)
			(layer "B.SilkS")
		)
		(fp_line
			(start 0.7874 0.4064)
			(end 0.7874 -0.4064)
			(stroke
				(width 0.1524)
				(type default)
			)
			(layer "B.SilkS")
		)
		(fp_line
			(start -0.7874 0.4064)
			(end 0.7874 0.4064)
			(stroke
				(width 0.1524)
				(type default)
			)
			(layer "B.SilkS")
		)
		(fp_line
			(start 0.67945 -0.305054)
			(end 0.12065 -0.305054)
			(stroke
				(width 0.1)
				(type default)
			)
			(layer "B.Fab")
		)
		(fp_line
			(start 0.12065 -0.305054)
			(end 0.12065 -0.2794)
			(stroke
				(width 0.1)
				(type default)
			)
			(layer "B.Fab")
		)
		(fp_line
			(start -0.12065 -0.3048)
			(end -0.67945 -0.3048)
			(stroke
				(width 0.1)
				(type default)
			)
			(layer "B.Fab")
		)
		(fp_line
			(start -0.67945 -0.3048)
			(end -0.67945 0.3048)
			(stroke
				(width 0.1)
				(type default)
			)
			(layer "B.Fab")
		)
		(fp_line
			(start 0.12065 -0.2794)
			(end -0.12065 -0.2794)
			(stroke
				(width 0.1)
				(type default)
			)
			(layer "B.Fab")
		)
		(fp_line
			(start -0.12065 -0.2794)
			(end -0.12065 -0.3048)
			(stroke
				(width 0.1)
				(type default)
			)
			(layer "B.Fab")
		)
		(fp_line
			(start 0.12065 0.2794)
			(end 0.12065 0.3048)
			(stroke
				(width 0.1)
				(type default)
			)
			(layer "B.Fab")
		)
		(fp_line
			(start -0.120396 0.2794)
			(end 0.12065 0.2794)
			(stroke
				(width 0.1)
				(type default)
			)
			(layer "B.Fab")
		)
		(fp_line
			(start 0.67945 0.3048)
			(end 0.67945 -0.305054)
			(stroke
				(width 0.1)
				(type default)
			)
			(layer "B.Fab")
		)
		(fp_line
			(start 0.12065 0.3048)
			(end 0.67945 0.3048)
			(stroke
				(width 0.1)
				(type default)
			)
			(layer "B.Fab")
		)
		(fp_line
			(start -0.120396 0.3048)
			(end -0.120396 0.2794)
			(stroke
				(width 0.1)
				(type default)
			)
			(layer "B.Fab")
		)
		(fp_line
			(start -0.67945 0.3048)
			(end -0.120396 0.3048)
			(stroke
				(width 0.1)
				(type default)
			)
			(layer "B.Fab")
		)
		(pad "1" smd circle
			(at 0.40005 0 270)
			(size 0 0)
			(layers "B.Cu" "B.Mask" "B.Paste")
			(net "VSENSE_PVDDCR_CPU0_P1_DP")
		)
		(pad "2" smd circle
			(at -0.40005 0 270)
			(size 0 0)
			(layers "B.Cu" "B.Mask" "B.Paste")
			(net "VSENSE_PVDDCR_CPU0_P1_VSEN0")
		)
	)
	(footprint ""
		(layer "B.Cu")
		(at 308.49697 -389.49503 180)
		(property "Reference" "C7008"
			(at -1.7399 -2.910332 0)
			(unlocked yes)
			(layer "B.SilkS")
			(effects
				(font
					(size 0.7874 0.5842)
					(thickness 0.1524)
				)
				(justify left mirror)
			)
		)
		(property "Value" ""
			(at 0 0 0)
			(layer "B.Fab")
			(effects
				(font
					(size 1.27 1.27)
				)
				(justify mirror)
			)
		)
		(duplicate_pad_numbers_are_jumpers no)
		(fp_line
			(start 4.84378 -2.150618)
			(end 4.842256 2.163064)
			(stroke
				(width 0.1524)
				(type default)
			)
			(layer "B.SilkS")
		)
		(fp_line
			(start 4.84378 -2.150618)
			(end 4.53898 -2.150618)
			(stroke
				(width 0.1524)
				(type default)
			)
			(layer "B.SilkS")
		)
		(fp_line
			(start 4.83108 2.150364)
			(end 4.447794 2.149348)
			(stroke
				(width 0.1524)
				(type default)
			)
			(layer "B.SilkS")
		)
		(fp_line
			(start 4.69138 -2.150618)
			(end 4.692396 2.161032)
			(stroke
				(width 0.1524)
				(type default)
			)
			(layer "B.SilkS")
		)
		(fp_line
			(start 4.53898 2.15011)
			(end 4.53898 -2.15011)
			(stroke
				(width 0.1524)
				(type default)
			)
			(layer "B.SilkS")
		)
		(fp_line
			(start 4.53898 -2.15011)
			(end -4.53898 -2.15011)
			(stroke
				(width 0.1524)
				(type default)
			)
			(layer "B.SilkS")
		)
		(fp_line
			(start 4.53898 -2.150618)
			(end 4.539742 2.152142)
			(stroke
				(width 0.1524)
				(type default)
			)
			(layer "B.SilkS")
		)
		(fp_line
			(start -4.53898 2.15011)
			(end 4.53898 2.15011)
			(stroke
				(width 0.1524)
				(type default)
			)
			(layer "B.SilkS")
		)
		(fp_line
			(start -4.53898 -2.15011)
			(end -4.53898 2.15011)
			(stroke
				(width 0.1524)
				(type default)
			)
			(layer "B.SilkS")
		)
		(fp_line
			(start 3.64998 2.15011)
			(end 3.64998 -2.15011)
			(stroke
				(width 0.1)
				(type default)
			)
			(layer "B.Fab")
		)
		(fp_line
			(start 3.64998 -2.15011)
			(end -3.64998 -2.15011)
			(stroke
				(width 0.1)
				(type default)
			)
			(layer "B.Fab")
		)
		(fp_line
			(start -3.64998 2.15011)
			(end 3.64998 2.15011)
			(stroke
				(width 0.1)
				(type default)
			)
			(layer "B.Fab")
		)
		(fp_line
			(start -3.64998 -2.15011)
			(end -3.64998 2.15011)
			(stroke
				(width 0.1)
				(type default)
			)
			(layer "B.Fab")
		)
		(fp_text user "+"
			(at 4.327652 -3.143758 180)
			(unlocked yes)
			(layer "B.SilkS")
			(effects
				(font
					(size 1.905 1.4224)
					(thickness 0.1524)
				)
				(justify left mirror)
			)
		)
		(fp_text user "-"
			(at -2.969514 -2.667508 180)
			(unlocked yes)
			(layer "B.SilkS")
			(effects
				(font
					(size 1.905 1.4224)
					(thickness 0.1524)
				)
				(justify left mirror)
			)
		)
		(fp_text user "+"
			(at 6.214872 -0.337058 180)
			(unlocked yes)
			(layer "B.Fab")
			(effects
				(font
					(size 1.905 1.4224)
					(thickness 0.1524)
				)
				(justify left mirror)
			)
		)
		(fp_text user "-"
			(at -4.313174 -0.094488 180)
			(unlocked yes)
			(layer "B.Fab")
			(effects
				(font
					(size 1.905 1.4224)
					(thickness 0.1524)
				)
				(justify left mirror)
			)
		)
		(pad "1" smd rect
			(at 3.199892 0)
			(size 2.413 2.8194)
			(layers "B.Cu" "B.Mask" "B.Paste")
			(net "P0V9_CPU0_RT0_2A")
		)
		(pad "2" smd rect
			(at -3.199892 0)
			(size 2.413 2.8194)
			(layers "B.Cu" "B.Mask" "B.Paste")
			(net "GND")
		)
	)
	(footprint ""
		(layer "B.Cu")
		(at 183.896 -20.378166 90)
		(property "Reference" "R3238"
			(at 0 0 90)
			(layer "B.SilkS")
			(hide yes)
			(effects
				(font
					(size 1.27 1.27)
				)
				(justify mirror)
			)
		)
		(property "Value" ""
			(at 0 0 90)
			(layer "B.Fab")
			(effects
				(font
					(size 1.27 1.27)
				)
				(justify mirror)
			)
		)
		(duplicate_pad_numbers_are_jumpers no)
		(fp_line
			(start 0.7874 -0.4064)
			(end -0.7874 -0.4064)
			(stroke
				(width 0.1524)
				(type default)
			)
			(layer "B.SilkS")
		)
		(fp_line
			(start -0.7874 -0.4064)
			(end -0.7874 0.4064)
			(stroke
				(width 0.1524)
				(type default)
			)
			(layer "B.SilkS")
		)
		(fp_line
			(start 0.7874 0.4064)
			(end 0.7874 -0.4064)
			(stroke
				(width 0.1524)
				(type default)
			)
			(layer "B.SilkS")
		)
		(fp_line
			(start -0.7874 0.4064)
			(end 0.7874 0.4064)
			(stroke
				(width 0.1524)
				(type default)
			)
			(layer "B.SilkS")
		)
		(fp_line
			(start 0.67945 -0.305054)
			(end 0.12065 -0.305054)
			(stroke
				(width 0.1)
				(type default)
			)
			(layer "B.Fab")
		)
		(fp_line
			(start 0.12065 -0.305054)
			(end 0.12065 -0.2794)
			(stroke
				(width 0.1)
				(type default)
			)
			(layer "B.Fab")
		)
		(fp_line
			(start -0.12065 -0.3048)
			(end -0.67945 -0.3048)
			(stroke
				(width 0.1)
				(type default)
			)
			(layer "B.Fab")
		)
		(fp_line
			(start -0.67945 -0.3048)
			(end -0.67945 0.3048)
			(stroke
				(width 0.1)
				(type default)
			)
			(layer "B.Fab")
		)
		(fp_line
			(start 0.12065 -0.2794)
			(end -0.12065 -0.2794)
			(stroke
				(width 0.1)
				(type default)
			)
			(layer "B.Fab")
		)
		(fp_line
			(start -0.12065 -0.2794)
			(end -0.12065 -0.3048)
			(stroke
				(width 0.1)
				(type default)
			)
			(layer "B.Fab")
		)
		(fp_line
			(start 0.12065 0.2794)
			(end 0.12065 0.3048)
			(stroke
				(width 0.1)
				(type default)
			)
			(layer "B.Fab")
		)
		(fp_line
			(start -0.120396 0.2794)
			(end 0.12065 0.2794)
			(stroke
				(width 0.1)
				(type default)
			)
			(layer "B.Fab")
		)
		(fp_line
			(start 0.67945 0.3048)
			(end 0.67945 -0.305054)
			(stroke
				(width 0.1)
				(type default)
			)
			(layer "B.Fab")
		)
		(fp_line
			(start 0.12065 0.3048)
			(end 0.67945 0.3048)
			(stroke
				(width 0.1)
				(type default)
			)
			(layer "B.Fab")
		)
		(fp_line
			(start -0.120396 0.3048)
			(end -0.120396 0.2794)
			(stroke
				(width 0.1)
				(type default)
			)
			(layer "B.Fab")
		)
		(fp_line
			(start -0.67945 0.3048)
			(end -0.120396 0.3048)
			(stroke
				(width 0.1)
				(type default)
			)
			(layer "B.Fab")
		)
		(pad "1" smd circle
			(at 0.40005 0 270)
			(size 0 0)
			(layers "B.Cu" "B.Mask" "B.Paste")
			(net "SMB_OCP_SFF_3V3AUX_SCL")
		)
		(pad "2" smd circle
			(at -0.40005 0 270)
			(size 0 0)
			(layers "B.Cu" "B.Mask" "B.Paste")
			(net "SMB_OCP_SFF_3V3AUX_SCL_R0")
		)
	)
	(footprint ""
		(layer "B.Cu")
		(at 161.94024 -419.262306)
		(property "Reference" "R1214"
			(at 0 0 0)
			(layer "B.SilkS")
			(hide yes)
			(effects
				(font
					(size 1.27 1.27)
				)
				(justify mirror)
			)
		)
		(property "Value" ""
			(at 0 0 0)
			(layer "B.Fab")
			(effects
				(font
					(size 1.27 1.27)
				)
				(justify mirror)
			)
		)
		(duplicate_pad_numbers_are_jumpers no)
		(fp_line
			(start -0.32512 -0.175006)
			(end -0.32512 0.175006)
			(stroke
				(width 0.1)
				(type default)
			)
			(layer "B.Fab")
		)
		(fp_line
			(start -0.32512 0.175006)
			(end 0.32512 0.175006)
			(stroke
				(width 0.1)
				(type default)
			)
			(layer "B.Fab")
		)
		(fp_line
			(start 0.32512 -0.175006)
			(end -0.32512 -0.175006)
			(stroke
				(width 0.1)
				(type default)
			)
			(layer "B.Fab")
		)
		(fp_line
			(start 0.32512 0.175006)
			(end 0.32512 -0.175006)
			(stroke
				(width 0.1)
				(type default)
			)
			(layer "B.Fab")
		)
		(pad "1" smd rect
			(at 0.2667 0 180)
			(size 0.3048 0.381)
			(layers "B.Cu" "B.Mask" "B.Paste")
			(net "GND")
		)
		(pad "2" smd rect
			(at -0.2667 0)
			(size 0.3048 0.381)
			(layers "B.Cu" "B.Mask" "B.Paste")
			(net "RT_ROM_MUX4_OE_N")
		)
	)
	(footprint ""
		(layer "B.Cu")
		(at 5.260086 -35.495484 180)
		(property "Reference" ""
			(at 0 0 0)
			(layer "B.SilkS")
			(hide yes)
			(effects
				(font
					(size 1.27 1.27)
				)
				(justify mirror)
			)
		)
		(property "Value" ""
			(at 0 0 0)
			(layer "B.Fab")
			(effects
				(font
					(size 1.27 1.27)
				)
				(justify mirror)
			)
		)
		(duplicate_pad_numbers_are_jumpers no)
		(pad "1" smd circle
			(at 0 0)
			(size 0.9906 0.9906)
			(layers "B.Cu" "B.Mask" "B.Paste")
			(net "Net_2236")
		)
		(zone
			(layer "B.Cu")
			(hatch none 0.5)
			(connect_pads
				(clearance 0)
			)
			(min_thickness 0.25)
			(keepout
				(tracks not_allowed)
				(vias allowed)
				(pads allowed)
				(copperpour not_allowed)
				(footprints allowed)
			)
			(placement
				(enabled no)
				(sheetname "")
			)
			(fill
				(thermal_gap 0.5)
				(thermal_bridge_width 0.5)
				(island_removal_mode 0)
			)
			(polygon
				(pts
					(arc
						(start 6.885686 -35.495484)
						(mid 3.634486 -35.495484)
						(end 6.885686 -35.495484)
					)
				)
			)
		)
	)
	(footprint ""
		(layer "B.Cu")
		(at 143.969486 -408.517344 90)
		(property "Reference" "C6744"
			(at 0 0 90)
			(layer "B.SilkS")
			(hide yes)
			(effects
				(font
					(size 1.27 1.27)
				)
				(justify mirror)
			)
		)
		(property "Value" ""
			(at 0 0 90)
			(layer "B.Fab")
			(effects
				(font
					(size 1.27 1.27)
				)
				(justify mirror)
			)
		)
		(duplicate_pad_numbers_are_jumpers no)
		(fp_line
			(start 0.299974 -0.150114)
			(end -0.299974 -0.150114)
			(stroke
				(width 0.1)
				(type default)
			)
			(layer "B.Fab")
		)
		(fp_line
			(start -0.299974 -0.150114)
			(end -0.299974 0.150114)
			(stroke
				(width 0.1)
				(type default)
			)
			(layer "B.Fab")
		)
		(fp_line
			(start 0.299974 0.150114)
			(end 0.299974 -0.150114)
			(stroke
				(width 0.1)
				(type default)
			)
			(layer "B.Fab")
		)
		(fp_line
			(start -0.299974 0.150114)
			(end 0.299974 0.150114)
			(stroke
				(width 0.1)
				(type default)
			)
			(layer "B.Fab")
		)
		(pad "1" smd rect
			(at 0.2667 0 270)
			(size 0.3048 0.381)
			(layers "B.Cu" "B.Mask" "B.Paste")
			(net "P5E_CPU1_P3_TX_BUF_C_DN<9>")
		)
		(pad "2" smd rect
			(at -0.2667 0 270)
			(size 0.3048 0.381)
			(layers "B.Cu" "B.Mask" "B.Paste")
			(net "P5E_CPU1_P3_TX_BUF_DN<9>")
		)
	)
	(footprint ""
		(layer "B.Cu")
		(at 365.09579 -393.04468 180)
		(property "Reference" "R1116"
			(at 0 0 0)
			(layer "B.SilkS")
			(hide yes)
			(effects
				(font
					(size 1.27 1.27)
				)
				(justify mirror)
			)
		)
		(property "Value" ""
			(at 0 0 0)
			(layer "B.Fab")
			(effects
				(font
					(size 1.27 1.27)
				)
				(justify mirror)
			)
		)
		(duplicate_pad_numbers_are_jumpers no)
		(fp_line
			(start 0.32512 0.175006)
			(end 0.32512 -0.175006)
			(stroke
				(width 0.1)
				(type default)
			)
			(layer "B.Fab")
		)
		(fp_line
			(start 0.32512 -0.175006)
			(end -0.32512 -0.175006)
			(stroke
				(width 0.1)
				(type default)
			)
			(layer "B.Fab")
		)
		(fp_line
			(start -0.32512 0.175006)
			(end 0.32512 0.175006)
			(stroke
				(width 0.1)
				(type default)
			)
			(layer "B.Fab")
		)
		(fp_line
			(start -0.32512 -0.175006)
			(end -0.32512 0.175006)
			(stroke
				(width 0.1)
				(type default)
			)
			(layer "B.Fab")
		)
		(pad "1" smd rect
			(at 0.2667 0)
			(size 0.3048 0.381)
			(layers "B.Cu" "B.Mask" "B.Paste")
			(net "P1V8_CPU0_RT_1D")
		)
		(pad "2" smd rect
			(at -0.2667 0 180)
			(size 0.3048 0.381)
			(layers "B.Cu" "B.Mask" "B.Paste")
			(net "TEST1_RT_CPU0_P3")
		)
	)
	(footprint ""
		(layer "B.Cu")
		(at 396.546578 -327.766172 180)
		(property "Reference" "R1351"
			(at 0 0 0)
			(layer "B.SilkS")
			(hide yes)
			(effects
				(font
					(size 1.27 1.27)
				)
				(justify mirror)
			)
		)
		(property "Value" ""
			(at 0 0 0)
			(layer "B.Fab")
			(effects
				(font
					(size 1.27 1.27)
				)
				(justify mirror)
			)
		)
		(duplicate_pad_numbers_are_jumpers no)
		(fp_line
			(start 0.7874 0.4064)
			(end 0.7874 -0.4064)
			(stroke
				(width 0.1524)
				(type default)
			)
			(layer "B.SilkS")
		)
		(fp_line
			(start 0.7874 -0.4064)
			(end -0.7874 -0.4064)
			(stroke
				(width 0.1524)
				(type default)
			)
			(layer "B.SilkS")
		)
		(fp_line
			(start -0.7874 0.4064)
			(end 0.7874 0.4064)
			(stroke
				(width 0.1524)
				(type default)
			)
			(layer "B.SilkS")
		)
		(fp_line
			(start -0.7874 -0.4064)
			(end -0.7874 0.4064)
			(stroke
				(width 0.1524)
				(type default)
			)
			(layer "B.SilkS")
		)
		(fp_line
			(start 0.67945 0.3048)
			(end 0.67945 -0.305054)
			(stroke
				(width 0.1)
				(type default)
			)
			(layer "B.Fab")
		)
		(fp_line
			(start 0.67945 -0.305054)
			(end 0.12065 -0.305054)
			(stroke
				(width 0.1)
				(type default)
			)
			(layer "B.Fab")
		)
		(fp_line
			(start 0.12065 0.3048)
			(end 0.67945 0.3048)
			(stroke
				(width 0.1)
				(type default)
			)
			(layer "B.Fab")
		)
		(fp_line
			(start 0.12065 0.2794)
			(end 0.12065 0.3048)
			(stroke
				(width 0.1)
				(type default)
			)
			(layer "B.Fab")
		)
		(fp_line
			(start 0.12065 -0.2794)
			(end -0.12065 -0.2794)
			(stroke
				(width 0.1)
				(type default)
			)
			(layer "B.Fab")
		)
		(fp_line
			(start 0.12065 -0.305054)
			(end 0.12065 -0.2794)
			(stroke
				(width 0.1)
				(type default)
			)
			(layer "B.Fab")
		)
		(fp_line
			(start -0.120396 0.3048)
			(end -0.120396 0.2794)
			(stroke
				(width 0.1)
				(type default)
			)
			(layer "B.Fab")
		)
		(fp_line
			(start -0.120396 0.2794)
			(end 0.12065 0.2794)
			(stroke
				(width 0.1)
				(type default)
			)
			(layer "B.Fab")
		)
		(fp_line
			(start -0.12065 -0.2794)
			(end -0.12065 -0.3048)
			(stroke
				(width 0.1)
				(type default)
			)
			(layer "B.Fab")
		)
		(fp_line
			(start -0.12065 -0.3048)
			(end -0.67945 -0.3048)
			(stroke
				(width 0.1)
				(type default)
			)
			(layer "B.Fab")
		)
		(fp_line
			(start -0.67945 0.3048)
			(end -0.120396 0.3048)
			(stroke
				(width 0.1)
				(type default)
			)
			(layer "B.Fab")
		)
		(fp_line
			(start -0.67945 -0.3048)
			(end -0.67945 0.3048)
			(stroke
				(width 0.1)
				(type default)
			)
			(layer "B.Fab")
		)
		(pad "1" smd circle
			(at 0.40005 0)
			(size 0 0)
			(layers "B.Cu" "B.Mask" "B.Paste")
			(net "RST_CPU0_KBRST_R_N")
		)
		(pad "2" smd circle
			(at -0.40005 0)
			(size 0 0)
			(layers "B.Cu" "B.Mask" "B.Paste")
			(net "PVDD18_S5_P0")
		)
	)
	(footprint ""
		(layer "B.Cu")
		(at 366.288574 7.622794)
		(property "Reference" "J116"
			(at 4.461002 1.607058 270)
			(unlocked yes)
			(layer "B.SilkS")
			(effects
				(font
					(size 0.7874 0.5842)
					(thickness 0.1524)
				)
				(justify left mirror)
			)
		)
		(property "Value" ""
			(at 0 0 0)
			(layer "B.Fab")
			(effects
				(font
					(size 1.27 1.27)
				)
				(justify mirror)
			)
		)
		(duplicate_pad_numbers_are_jumpers no)
		(fp_line
			(start -1.2192 -2.06756)
			(end -1.2192 2.06756)
			(stroke
				(width 0.1524)
				(type default)
			)
			(layer "B.SilkS")
		)
		(fp_line
			(start -1.2192 2.06756)
			(end 1.2192 2.06756)
			(stroke
				(width 0.1524)
				(type default)
			)
			(layer "B.SilkS")
		)
		(fp_line
			(start 1.2192 -2.06756)
			(end -1.2192 -2.06756)
			(stroke
				(width 0.1524)
				(type default)
			)
			(layer "B.SilkS")
		)
		(fp_line
			(start 1.2192 2.06756)
			(end 1.2192 -2.06756)
			(stroke
				(width 0.1524)
				(type default)
			)
			(layer "B.SilkS")
		)
		(pad "" np_thru_hole circle
			(at -3.4671 -1.27 270)
			(size 1.0414 1.0414)
			(drill 1.0414)
			(layers "*.Cu" "*.Mask")
			(clearance 0.381)
			(thermal_gap 0.381)
		)
		(pad "" np_thru_hole circle
			(at -3.4671 1.27 270)
			(size 1.0414 1.0414)
			(drill 1.0414)
			(layers "*.Cu" "*.Mask")
			(clearance 0.381)
			(thermal_gap 0.381)
		)
		(pad "" np_thru_hole circle
			(at 2.8829 -1.27 270)
			(size 1.0414 1.0414)
			(drill 1.0414)
			(layers "*.Cu" "*.Mask")
			(clearance 0.381)
			(thermal_gap 0.381)
		)
		(pad "" np_thru_hole circle
			(at 2.8829 1.27 270)
			(size 1.0414 1.0414)
			(drill 1.0414)
			(layers "*.Cu" "*.Mask")
			(clearance 0.381)
			(thermal_gap 0.381)
		)
		(pad "1" smd rect
			(at -0.8255 -0.249936 270)
			(size 0.3048 0.508)
			(layers "B.Cu" "B.Mask" "B.Paste")
			(net "DELTA_L_85_5INCH_IN5_DN")
		)
		(pad "2" smd rect
			(at -0.8255 0.249936 270)
			(size 0.3048 0.508)
			(layers "B.Cu" "B.Mask" "B.Paste")
			(net "DELTA_L_85_5INCH_IN5_DP")
		)
		(pad "3" smd circle
			(at 0 0 180)
			(size 0 0)
			(layers "B.Cu" "B.Mask" "B.Paste")
			(net "DELTA_L_GND_1")
		)
		(zone
			(layers "F.Cu" "B.Cu" "In1.Cu" "In2.Cu" "In3.Cu" "In4.Cu" "In5.Cu" "In6.Cu"
				"In7.Cu" "In8.Cu" "In9.Cu" "In10.Cu" "In11.Cu" "In12.Cu" "In13.Cu" "In14.Cu"
				"In15.Cu" "In16.Cu"
			)
			(hatch none 0.5)
			(connect_pads
				(clearance 0)
			)
			(min_thickness 0.25)
			(keepout
				(tracks not_allowed)
				(vias allowed)
				(pads allowed)
				(copperpour not_allowed)
				(footprints allowed)
			)
			(placement
				(enabled no)
				(sheetname "")
			)
			(fill
				(thermal_gap 0.5)
				(thermal_bridge_width 0.5)
				(island_removal_mode 0)
			)
			(polygon
				(pts
					(arc
						(start 363.748574 6.352794)
						(mid 361.894374 6.352794)
						(end 363.748574 6.352794)
					)
				)
			)
		)
		(zone
			(layers "F.Cu" "B.Cu" "In1.Cu" "In2.Cu" "In3.Cu" "In4.Cu" "In5.Cu" "In6.Cu"
				"In7.Cu" "In8.Cu" "In9.Cu" "In10.Cu" "In11.Cu" "In12.Cu" "In13.Cu" "In14.Cu"
				"In15.Cu" "In16.Cu"
			)
			(hatch none 0.5)
			(connect_pads
				(clearance 0)
			)
			(min_thickness 0.25)
			(keepout
				(tracks not_allowed)
				(vias allowed)
				(pads allowed)
				(copperpour not_allowed)
				(footprints allowed)
			)
			(placement
				(enabled no)
				(sheetname "")
			)
			(fill
				(thermal_gap 0.5)
				(thermal_bridge_width 0.5)
				(island_removal_mode 0)
			)
			(polygon
				(pts
					(arc
						(start 363.748574 8.892794)
						(mid 361.894374 8.892794)
						(end 363.748574 8.892794)
					)
				)
			)
		)
		(zone
			(layers "F.Cu" "B.Cu" "In1.Cu" "In2.Cu" "In3.Cu" "In4.Cu" "In5.Cu" "In6.Cu"
				"In7.Cu" "In8.Cu" "In9.Cu" "In10.Cu" "In11.Cu" "In12.Cu" "In13.Cu" "In14.Cu"
				"In15.Cu" "In16.Cu"
			)
			(hatch none 0.5)
			(connect_pads
				(clearance 0)
			)
			(min_thickness 0.25)
			(keepout
				(tracks not_allowed)
				(vias allowed)
				(pads allowed)
				(copperpour not_allowed)
				(footprints allowed)
			)
			(placement
				(enabled no)
				(sheetname "")
			)
			(fill
				(thermal_gap 0.5)
				(thermal_bridge_width 0.5)
				(island_removal_mode 0)
			)
			(polygon
				(pts
					(arc
						(start 370.098574 6.352794)
						(mid 368.244374 6.352794)
						(end 370.098574 6.352794)
					)
				)
			)
		)
		(zone
			(layers "F.Cu" "B.Cu" "In1.Cu" "In2.Cu" "In3.Cu" "In4.Cu" "In5.Cu" "In6.Cu"
				"In7.Cu" "In8.Cu" "In9.Cu" "In10.Cu" "In11.Cu" "In12.Cu" "In13.Cu" "In14.Cu"
				"In15.Cu" "In16.Cu"
			)
			(hatch none 0.5)
			(connect_pads
				(clearance 0)
			)
			(min_thickness 0.25)
			(keepout
				(tracks not_allowed)
				(vias allowed)
				(pads allowed)
				(copperpour not_allowed)
				(footprints allowed)
			)
			(placement
				(enabled no)
				(sheetname "")
			)
			(fill
				(thermal_gap 0.5)
				(thermal_bridge_width 0.5)
				(island_removal_mode 0)
			)
			(polygon
				(pts
					(arc
						(start 370.098574 8.892794)
						(mid 368.244374 8.892794)
						(end 370.098574 8.892794)
					)
				)
			)
		)
		(zone
			(layer "B.Cu")
			(hatch none 0.5)
			(connect_pads
				(clearance 0)
			)
			(min_thickness 0.25)
			(keepout
				(tracks not_allowed)
				(vias allowed)
				(pads allowed)
				(copperpour not_allowed)
				(footprints allowed)
			)
			(placement
				(enabled no)
				(sheetname "")
			)
			(fill
				(thermal_gap 0.5)
				(thermal_bridge_width 0.5)
				(island_removal_mode 0)
			)
			(polygon
				(pts
					(xy 365.170974 7.074154) (xy 365.170974 7.169658) (xy 365.767874 7.169658) (xy 365.767874 7.576058)
					(xy 365.170974 7.576058) (xy 365.170974 7.66953) (xy 365.767874 7.66953) (xy 365.767874 8.07593)
					(xy 365.170974 8.07593) (xy 365.170974 8.171434) (xy 365.869474 8.171434) (xy 365.869474 7.074154)
				)
			)
		)
	)
	(footprint ""
		(layer "B.Cu")
		(at 399.969482 -416.899344 90)
		(property "Reference" "C6616"
			(at 0 0 90)
			(layer "B.SilkS")
			(hide yes)
			(effects
				(font
					(size 1.27 1.27)
				)
				(justify mirror)
			)
		)
		(property "Value" ""
			(at 0 0 90)
			(layer "B.Fab")
			(effects
				(font
					(size 1.27 1.27)
				)
				(justify mirror)
			)
		)
		(duplicate_pad_numbers_are_jumpers no)
		(fp_line
			(start 0.299974 -0.150114)
			(end -0.299974 -0.150114)
			(stroke
				(width 0.1)
				(type default)
			)
			(layer "B.Fab")
		)
		(fp_line
			(start -0.299974 -0.150114)
			(end -0.299974 0.150114)
			(stroke
				(width 0.1)
				(type default)
			)
			(layer "B.Fab")
		)
		(fp_line
			(start 0.299974 0.150114)
			(end 0.299974 -0.150114)
			(stroke
				(width 0.1)
				(type default)
			)
			(layer "B.Fab")
		)
		(fp_line
			(start -0.299974 0.150114)
			(end 0.299974 0.150114)
			(stroke
				(width 0.1)
				(type default)
			)
			(layer "B.Fab")
		)
		(pad "1" smd rect
			(at 0.2667 0 270)
			(size 0.3048 0.381)
			(layers "B.Cu" "B.Mask" "B.Paste")
			(net "P5E_CPU0_P3_TX_BUF_C_DN<9>")
		)
		(pad "2" smd rect
			(at -0.2667 0 270)
			(size 0.3048 0.381)
			(layers "B.Cu" "B.Mask" "B.Paste")
			(net "P5E_CPU0_P3_TX_BUF_DN<9>")
		)
	)
	(footprint ""
		(layer "B.Cu")
		(at 98.962464 -267.529564)
		(property "Reference" "C2662"
			(at 0 0 0)
			(layer "B.SilkS")
			(hide yes)
			(effects
				(font
					(size 1.27 1.27)
				)
				(justify mirror)
			)
		)
		(property "Value" ""
			(at 0 0 0)
			(layer "B.Fab")
			(effects
				(font
					(size 1.27 1.27)
				)
				(justify mirror)
			)
		)
		(duplicate_pad_numbers_are_jumpers no)
		(fp_line
			(start -0.7874 -0.4064)
			(end -0.7874 0.4064)
			(stroke
				(width 0.1524)
				(type default)
			)
			(layer "B.SilkS")
		)
		(fp_line
			(start -0.7874 0.4064)
			(end 0.7874 0.4064)
			(stroke
				(width 0.1524)
				(type default)
			)
			(layer "B.SilkS")
		)
		(fp_line
			(start 0.7874 -0.4064)
			(end -0.7874 -0.4064)
			(stroke
				(width 0.1524)
				(type default)
			)
			(layer "B.SilkS")
		)
		(fp_line
			(start 0.7874 0.4064)
			(end 0.7874 -0.4064)
			(stroke
				(width 0.1524)
				(type default)
			)
			(layer "B.SilkS")
		)
		(fp_line
			(start -0.67945 -0.3048)
			(end -0.67945 0.3048)
			(stroke
				(width 0.1)
				(type default)
			)
			(layer "B.Fab")
		)
		(fp_line
			(start -0.67945 0.3048)
			(end -0.120396 0.3048)
			(stroke
				(width 0.1)
				(type default)
			)
			(layer "B.Fab")
		)
		(fp_line
			(start -0.12065 -0.3048)
			(end -0.67945 -0.3048)
			(stroke
				(width 0.1)
				(type default)
			)
			(layer "B.Fab")
		)
		(fp_line
			(start -0.12065 -0.2794)
			(end -0.12065 -0.3048)
			(stroke
				(width 0.1)
				(type default)
			)
			(layer "B.Fab")
		)
		(fp_line
			(start -0.120396 0.2794)
			(end 0.12065 0.2794)
			(stroke
				(width 0.1)
				(type default)
			)
			(layer "B.Fab")
		)
		(fp_line
			(start -0.120396 0.3048)
			(end -0.120396 0.2794)
			(stroke
				(width 0.1)
				(type default)
			)
			(layer "B.Fab")
		)
		(fp_line
			(start 0.12065 -0.305054)
			(end 0.12065 -0.2794)
			(stroke
				(width 0.1)
				(type default)
			)
			(layer "B.Fab")
		)
		(fp_line
			(start 0.12065 -0.2794)
			(end -0.12065 -0.2794)
			(stroke
				(width 0.1)
				(type default)
			)
			(layer "B.Fab")
		)
		(fp_line
			(start 0.12065 0.2794)
			(end 0.12065 0.3048)
			(stroke
				(width 0.1)
				(type default)
			)
			(layer "B.Fab")
		)
		(fp_line
			(start 0.12065 0.3048)
			(end 0.67945 0.3048)
			(stroke
				(width 0.1)
				(type default)
			)
			(layer "B.Fab")
		)
		(fp_line
			(start 0.67945 -0.305054)
			(end 0.12065 -0.305054)
			(stroke
				(width 0.1)
				(type default)
			)
			(layer "B.Fab")
		)
		(fp_line
			(start 0.67945 0.3048)
			(end 0.67945 -0.305054)
			(stroke
				(width 0.1)
				(type default)
			)
			(layer "B.Fab")
		)
		(pad "1" smd circle
			(at 0.40005 0 180)
			(size 0 0)
			(layers "B.Cu" "B.Mask" "B.Paste")
			(net "PVDD_33_S5")
		)
		(pad "2" smd circle
			(at -0.40005 0 180)
			(size 0 0)
			(layers "B.Cu" "B.Mask" "B.Paste")
			(net "GND")
		)
	)
	(footprint ""
		(layer "B.Cu")
		(at 375.41835 -396.393162 -90)
		(property "Reference" "C1021"
			(at 0 0 90)
			(layer "B.SilkS")
			(hide yes)
			(effects
				(font
					(size 1.27 1.27)
				)
				(justify mirror)
			)
		)
		(property "Value" ""
			(at 0 0 90)
			(layer "B.Fab")
			(effects
				(font
					(size 1.27 1.27)
				)
				(justify mirror)
			)
		)
		(duplicate_pad_numbers_are_jumpers no)
		(fp_line
			(start -0.299974 0.150114)
			(end 0.299974 0.150114)
			(stroke
				(width 0.1)
				(type default)
			)
			(layer "B.Fab")
		)
		(fp_line
			(start 0.299974 0.150114)
			(end 0.299974 -0.150114)
			(stroke
				(width 0.1)
				(type default)
			)
			(layer "B.Fab")
		)
		(fp_line
			(start -0.299974 -0.150114)
			(end -0.299974 0.150114)
			(stroke
				(width 0.1)
				(type default)
			)
			(layer "B.Fab")
		)
		(fp_line
			(start 0.299974 -0.150114)
			(end -0.299974 -0.150114)
			(stroke
				(width 0.1)
				(type default)
			)
			(layer "B.Fab")
		)
		(pad "1" smd rect
			(at 0.2667 0 90)
			(size 0.3048 0.381)
			(layers "B.Cu" "B.Mask" "B.Paste")
			(net "P0V9_CPU0_RT3_2A_2D")
		)
		(pad "2" smd rect
			(at -0.2667 0 90)
			(size 0.3048 0.381)
			(layers "B.Cu" "B.Mask" "B.Paste")
			(net "GND")
		)
	)
	(footprint ""
		(layer "B.Cu")
		(at 205.28788 -35.956748 90)
		(property "Reference" "C2022"
			(at 0 0 90)
			(layer "B.SilkS")
			(hide yes)
			(effects
				(font
					(size 1.27 1.27)
				)
				(justify mirror)
			)
		)
		(property "Value" ""
			(at 0 0 90)
			(layer "B.Fab")
			(effects
				(font
					(size 1.27 1.27)
				)
				(justify mirror)
			)
		)
		(duplicate_pad_numbers_are_jumpers no)
		(fp_line
			(start 0.7874 -0.4064)
			(end -0.7874 -0.4064)
			(stroke
				(width 0.1524)
				(type default)
			)
			(layer "B.SilkS")
		)
		(fp_line
			(start -0.7874 -0.4064)
			(end -0.7874 0.4064)
			(stroke
				(width 0.1524)
				(type default)
			)
			(layer "B.SilkS")
		)
		(fp_line
			(start 0.7874 0.4064)
			(end 0.7874 -0.4064)
			(stroke
				(width 0.1524)
				(type default)
			)
			(layer "B.SilkS")
		)
		(fp_line
			(start -0.7874 0.4064)
			(end 0.7874 0.4064)
			(stroke
				(width 0.1524)
				(type default)
			)
			(layer "B.SilkS")
		)
		(fp_line
			(start 0.67945 -0.305054)
			(end 0.12065 -0.305054)
			(stroke
				(width 0.1)
				(type default)
			)
			(layer "B.Fab")
		)
		(fp_line
			(start 0.12065 -0.305054)
			(end 0.12065 -0.2794)
			(stroke
				(width 0.1)
				(type default)
			)
			(layer "B.Fab")
		)
		(fp_line
			(start -0.12065 -0.3048)
			(end -0.67945 -0.3048)
			(stroke
				(width 0.1)
				(type default)
			)
			(layer "B.Fab")
		)
		(fp_line
			(start -0.67945 -0.3048)
			(end -0.67945 0.3048)
			(stroke
				(width 0.1)
				(type default)
			)
			(layer "B.Fab")
		)
		(fp_line
			(start 0.12065 -0.2794)
			(end -0.12065 -0.2794)
			(stroke
				(width 0.1)
				(type default)
			)
			(layer "B.Fab")
		)
		(fp_line
			(start -0.12065 -0.2794)
			(end -0.12065 -0.3048)
			(stroke
				(width 0.1)
				(type default)
			)
			(layer "B.Fab")
		)
		(fp_line
			(start 0.12065 0.2794)
			(end 0.12065 0.3048)
			(stroke
				(width 0.1)
				(type default)
			)
			(layer "B.Fab")
		)
		(fp_line
			(start -0.120396 0.2794)
			(end 0.12065 0.2794)
			(stroke
				(width 0.1)
				(type default)
			)
			(layer "B.Fab")
		)
		(fp_line
			(start 0.67945 0.3048)
			(end 0.67945 -0.305054)
			(stroke
				(width 0.1)
				(type default)
			)
			(layer "B.Fab")
		)
		(fp_line
			(start 0.12065 0.3048)
			(end 0.67945 0.3048)
			(stroke
				(width 0.1)
				(type default)
			)
			(layer "B.Fab")
		)
		(fp_line
			(start -0.120396 0.3048)
			(end -0.120396 0.2794)
			(stroke
				(width 0.1)
				(type default)
			)
			(layer "B.Fab")
		)
		(fp_line
			(start -0.67945 0.3048)
			(end -0.120396 0.3048)
			(stroke
				(width 0.1)
				(type default)
			)
			(layer "B.Fab")
		)
		(pad "1" smd circle
			(at 0.40005 0 270)
			(size 0 0)
			(layers "B.Cu" "B.Mask" "B.Paste")
			(net "VSENSE_P12V_INA230_5_INP")
		)
		(pad "2" smd circle
			(at -0.40005 0 270)
			(size 0 0)
			(layers "B.Cu" "B.Mask" "B.Paste")
			(net "VSENSE_P12V_INA230_5_INN")
		)
	)
	(footprint ""
		(layer "B.Cu")
		(at 170.424856 -8.062468 -90)
		(property "Reference" "R3858"
			(at 0 0 90)
			(layer "B.SilkS")
			(hide yes)
			(effects
				(font
					(size 1.27 1.27)
				)
				(justify mirror)
			)
		)
		(property "Value" ""
			(at 0 0 90)
			(layer "B.Fab")
			(effects
				(font
					(size 1.27 1.27)
				)
				(justify mirror)
			)
		)
		(duplicate_pad_numbers_are_jumpers no)
		(fp_line
			(start -0.7874 0.4064)
			(end 0.7874 0.4064)
			(stroke
				(width 0.1524)
				(type default)
			)
			(layer "B.SilkS")
		)
		(fp_line
			(start 0.7874 0.4064)
			(end 0.7874 -0.4064)
			(stroke
				(width 0.1524)
				(type default)
			)
			(layer "B.SilkS")
		)
		(fp_line
			(start -0.7874 -0.4064)
			(end -0.7874 0.4064)
			(stroke
				(width 0.1524)
				(type default)
			)
			(layer "B.SilkS")
		)
		(fp_line
			(start 0.7874 -0.4064)
			(end -0.7874 -0.4064)
			(stroke
				(width 0.1524)
				(type default)
			)
			(layer "B.SilkS")
		)
		(fp_line
			(start -0.67945 0.3048)
			(end -0.120396 0.3048)
			(stroke
				(width 0.1)
				(type default)
			)
			(layer "B.Fab")
		)
		(fp_line
			(start -0.120396 0.3048)
			(end -0.120396 0.2794)
			(stroke
				(width 0.1)
				(type default)
			)
			(layer "B.Fab")
		)
		(fp_line
			(start 0.12065 0.3048)
			(end 0.67945 0.3048)
			(stroke
				(width 0.1)
				(type default)
			)
			(layer "B.Fab")
		)
		(fp_line
			(start 0.67945 0.3048)
			(end 0.67945 -0.305054)
			(stroke
				(width 0.1)
				(type default)
			)
			(layer "B.Fab")
		)
		(fp_line
			(start -0.120396 0.2794)
			(end 0.12065 0.2794)
			(stroke
				(width 0.1)
				(type default)
			)
			(layer "B.Fab")
		)
		(fp_line
			(start 0.12065 0.2794)
			(end 0.12065 0.3048)
			(stroke
				(width 0.1)
				(type default)
			)
			(layer "B.Fab")
		)
		(fp_line
			(start -0.12065 -0.2794)
			(end -0.12065 -0.3048)
			(stroke
				(width 0.1)
				(type default)
			)
			(layer "B.Fab")
		)
		(fp_line
			(start 0.12065 -0.2794)
			(end -0.12065 -0.2794)
			(stroke
				(width 0.1)
				(type default)
			)
			(layer "B.Fab")
		)
		(fp_line
			(start -0.67945 -0.3048)
			(end -0.67945 0.3048)
			(stroke
				(width 0.1)
				(type default)
			)
			(layer "B.Fab")
		)
		(fp_line
			(start -0.12065 -0.3048)
			(end -0.67945 -0.3048)
			(stroke
				(width 0.1)
				(type default)
			)
			(layer "B.Fab")
		)
		(fp_line
			(start 0.12065 -0.305054)
			(end 0.12065 -0.2794)
			(stroke
				(width 0.1)
				(type default)
			)
			(layer "B.Fab")
		)
		(fp_line
			(start 0.67945 -0.305054)
			(end 0.12065 -0.305054)
			(stroke
				(width 0.1)
				(type default)
			)
			(layer "B.Fab")
		)
		(pad "1" smd circle
			(at 0.40005 0 90)
			(size 0 0)
			(layers "B.Cu" "B.Mask" "B.Paste")
			(net "SMB_OCP_V3_2_3V3AUX_SDA")
		)
		(pad "2" smd circle
			(at -0.40005 0 90)
			(size 0 0)
			(layers "B.Cu" "B.Mask" "B.Paste")
			(net "SMB_OCP_V3_2_3V3AUX_SDA_R0")
		)
	)
	(footprint ""
		(layer "B.Cu")
		(at 152.9969 -13.762228 90)
		(property "Reference" "R2416"
			(at 0 0 90)
			(layer "B.SilkS")
			(hide yes)
			(effects
				(font
					(size 1.27 1.27)
				)
				(justify mirror)
			)
		)
		(property "Value" ""
			(at 0 0 90)
			(layer "B.Fab")
			(effects
				(font
					(size 1.27 1.27)
				)
				(justify mirror)
			)
		)
		(duplicate_pad_numbers_are_jumpers no)
		(fp_line
			(start 0.7874 -0.4064)
			(end -0.7874 -0.4064)
			(stroke
				(width 0.1524)
				(type default)
			)
			(layer "B.SilkS")
		)
		(fp_line
			(start -0.7874 -0.4064)
			(end -0.7874 0.4064)
			(stroke
				(width 0.1524)
				(type default)
			)
			(layer "B.SilkS")
		)
		(fp_line
			(start 0.7874 0.4064)
			(end 0.7874 -0.4064)
			(stroke
				(width 0.1524)
				(type default)
			)
			(layer "B.SilkS")
		)
		(fp_line
			(start -0.7874 0.4064)
			(end 0.7874 0.4064)
			(stroke
				(width 0.1524)
				(type default)
			)
			(layer "B.SilkS")
		)
		(fp_line
			(start 0.67945 -0.305054)
			(end 0.12065 -0.305054)
			(stroke
				(width 0.1)
				(type default)
			)
			(layer "B.Fab")
		)
		(fp_line
			(start 0.12065 -0.305054)
			(end 0.12065 -0.2794)
			(stroke
				(width 0.1)
				(type default)
			)
			(layer "B.Fab")
		)
		(fp_line
			(start -0.12065 -0.3048)
			(end -0.67945 -0.3048)
			(stroke
				(width 0.1)
				(type default)
			)
			(layer "B.Fab")
		)
		(fp_line
			(start -0.67945 -0.3048)
			(end -0.67945 0.3048)
			(stroke
				(width 0.1)
				(type default)
			)
			(layer "B.Fab")
		)
		(fp_line
			(start 0.12065 -0.2794)
			(end -0.12065 -0.2794)
			(stroke
				(width 0.1)
				(type default)
			)
			(layer "B.Fab")
		)
		(fp_line
			(start -0.12065 -0.2794)
			(end -0.12065 -0.3048)
			(stroke
				(width 0.1)
				(type default)
			)
			(layer "B.Fab")
		)
		(fp_line
			(start 0.12065 0.2794)
			(end 0.12065 0.3048)
			(stroke
				(width 0.1)
				(type default)
			)
			(layer "B.Fab")
		)
		(fp_line
			(start -0.120396 0.2794)
			(end 0.12065 0.2794)
			(stroke
				(width 0.1)
				(type default)
			)
			(layer "B.Fab")
		)
		(fp_line
			(start 0.67945 0.3048)
			(end 0.67945 -0.305054)
			(stroke
				(width 0.1)
				(type default)
			)
			(layer "B.Fab")
		)
		(fp_line
			(start 0.12065 0.3048)
			(end 0.67945 0.3048)
			(stroke
				(width 0.1)
				(type default)
			)
			(layer "B.Fab")
		)
		(fp_line
			(start -0.120396 0.3048)
			(end -0.120396 0.2794)
			(stroke
				(width 0.1)
				(type default)
			)
			(layer "B.Fab")
		)
		(fp_line
			(start -0.67945 0.3048)
			(end -0.120396 0.3048)
			(stroke
				(width 0.1)
				(type default)
			)
			(layer "B.Fab")
		)
		(pad "1" smd circle
			(at 0.40005 0 270)
			(size 0 0)
			(layers "B.Cu" "B.Mask" "B.Paste")
			(net "SMB_1_BMC_GPU_SDA")
		)
		(pad "2" smd circle
			(at -0.40005 0 270)
			(size 0 0)
			(layers "B.Cu" "B.Mask" "B.Paste")
			(net "SMB_PCIE3_3V3AUX_SDA_R")
		)
	)
	(footprint ""
		(layer "B.Cu")
		(at 437.66994 -362.77042 -90)
		(property "Reference" "PC7002"
			(at 0 0 90)
			(layer "B.SilkS")
			(hide yes)
			(effects
				(font
					(size 1.27 1.27)
				)
				(justify mirror)
			)
		)
		(property "Value" ""
			(at 0 0 90)
			(layer "B.Fab")
			(effects
				(font
					(size 1.27 1.27)
				)
				(justify mirror)
			)
		)
		(duplicate_pad_numbers_are_jumpers no)
		(fp_line
			(start -1.524 0.762)
			(end 1.524 0.762)
			(stroke
				(width 0.1524)
				(type default)
			)
			(layer "B.SilkS")
		)
		(fp_line
			(start 1.524 0.762)
			(end 1.524 -0.762)
			(stroke
				(width 0.1524)
				(type default)
			)
			(layer "B.SilkS")
		)
		(fp_line
			(start -1.524 -0.762)
			(end -1.524 0.762)
			(stroke
				(width 0.1524)
				(type default)
			)
			(layer "B.SilkS")
		)
		(fp_line
			(start 1.524 -0.762)
			(end -1.524 -0.762)
			(stroke
				(width 0.1524)
				(type default)
			)
			(layer "B.SilkS")
		)
		(fp_line
			(start -1.1049 0.724916)
			(end -1.1049 -0.724916)
			(stroke
				(width 0.1)
				(type default)
			)
			(layer "B.Fab")
		)
		(fp_line
			(start 1.1049 0.724916)
			(end -1.1049 0.724916)
			(stroke
				(width 0.1)
				(type default)
			)
			(layer "B.Fab")
		)
		(fp_line
			(start -1.1049 -0.724916)
			(end 1.1049 -0.724916)
			(stroke
				(width 0.1)
				(type default)
			)
			(layer "B.Fab")
		)
		(fp_line
			(start 1.1049 -0.724916)
			(end 1.1049 0.724916)
			(stroke
				(width 0.1)
				(type default)
			)
			(layer "B.Fab")
		)
		(pad "1" smd rect
			(at 0.889 0 270)
			(size 1.016 1.27)
			(layers "B.Cu" "B.Mask" "B.Paste")
			(net "SW_P12V_AUX_PVDD11_S3_P0_FLT")
		)
		(pad "2" smd rect
			(at -0.889 0 270)
			(size 1.016 1.27)
			(layers "B.Cu" "B.Mask" "B.Paste")
			(net "GND")
		)
	)
	(footprint ""
		(layer "B.Cu")
		(at 257.379724 -132.625084 -90)
		(property "Reference" "C1104"
			(at 0 0 90)
			(layer "B.SilkS")
			(hide yes)
			(effects
				(font
					(size 1.27 1.27)
				)
				(justify mirror)
			)
		)
		(property "Value" ""
			(at 0 0 90)
			(layer "B.Fab")
			(effects
				(font
					(size 1.27 1.27)
				)
				(justify mirror)
			)
		)
		(duplicate_pad_numbers_are_jumpers no)
		(fp_line
			(start -0.7874 0.4064)
			(end 0.7874 0.4064)
			(stroke
				(width 0.1524)
				(type default)
			)
			(layer "B.SilkS")
		)
		(fp_line
			(start 0.7874 0.4064)
			(end 0.7874 -0.4064)
			(stroke
				(width 0.1524)
				(type default)
			)
			(layer "B.SilkS")
		)
		(fp_line
			(start -0.7874 -0.4064)
			(end -0.7874 0.4064)
			(stroke
				(width 0.1524)
				(type default)
			)
			(layer "B.SilkS")
		)
		(fp_line
			(start 0.7874 -0.4064)
			(end -0.7874 -0.4064)
			(stroke
				(width 0.1524)
				(type default)
			)
			(layer "B.SilkS")
		)
		(fp_line
			(start -0.67945 0.3048)
			(end -0.120396 0.3048)
			(stroke
				(width 0.1)
				(type default)
			)
			(layer "B.Fab")
		)
		(fp_line
			(start -0.120396 0.3048)
			(end -0.120396 0.2794)
			(stroke
				(width 0.1)
				(type default)
			)
			(layer "B.Fab")
		)
		(fp_line
			(start 0.12065 0.3048)
			(end 0.67945 0.3048)
			(stroke
				(width 0.1)
				(type default)
			)
			(layer "B.Fab")
		)
		(fp_line
			(start 0.67945 0.3048)
			(end 0.67945 -0.305054)
			(stroke
				(width 0.1)
				(type default)
			)
			(layer "B.Fab")
		)
		(fp_line
			(start -0.120396 0.2794)
			(end 0.12065 0.2794)
			(stroke
				(width 0.1)
				(type default)
			)
			(layer "B.Fab")
		)
		(fp_line
			(start 0.12065 0.2794)
			(end 0.12065 0.3048)
			(stroke
				(width 0.1)
				(type default)
			)
			(layer "B.Fab")
		)
		(fp_line
			(start -0.12065 -0.2794)
			(end -0.12065 -0.3048)
			(stroke
				(width 0.1)
				(type default)
			)
			(layer "B.Fab")
		)
		(fp_line
			(start 0.12065 -0.2794)
			(end -0.12065 -0.2794)
			(stroke
				(width 0.1)
				(type default)
			)
			(layer "B.Fab")
		)
		(fp_line
			(start -0.67945 -0.3048)
			(end -0.67945 0.3048)
			(stroke
				(width 0.1)
				(type default)
			)
			(layer "B.Fab")
		)
		(fp_line
			(start -0.12065 -0.3048)
			(end -0.67945 -0.3048)
			(stroke
				(width 0.1)
				(type default)
			)
			(layer "B.Fab")
		)
		(fp_line
			(start 0.12065 -0.305054)
			(end 0.12065 -0.2794)
			(stroke
				(width 0.1)
				(type default)
			)
			(layer "B.Fab")
		)
		(fp_line
			(start 0.67945 -0.305054)
			(end 0.12065 -0.305054)
			(stroke
				(width 0.1)
				(type default)
			)
			(layer "B.Fab")
		)
		(pad "1" smd circle
			(at 0.40005 0 90)
			(size 0 0)
			(layers "B.Cu" "B.Mask" "B.Paste")
			(net "P3V3_AUX")
		)
		(pad "2" smd circle
			(at -0.40005 0 90)
			(size 0 0)
			(layers "B.Cu" "B.Mask" "B.Paste")
			(net "GND")
		)
	)
	(footprint ""
		(layer "B.Cu")
		(at 393.381484 -204.249782)
		(property "Reference" "R6130"
			(at 0 0 0)
			(layer "B.SilkS")
			(hide yes)
			(effects
				(font
					(size 1.27 1.27)
				)
				(justify mirror)
			)
		)
		(property "Value" ""
			(at 0 0 0)
			(layer "B.Fab")
			(effects
				(font
					(size 1.27 1.27)
				)
				(justify mirror)
			)
		)
		(duplicate_pad_numbers_are_jumpers no)
		(fp_line
			(start -0.7874 -0.4064)
			(end -0.7874 0.4064)
			(stroke
				(width 0.1524)
				(type default)
			)
			(layer "B.SilkS")
		)
		(fp_line
			(start -0.7874 0.4064)
			(end 0.7874 0.4064)
			(stroke
				(width 0.1524)
				(type default)
			)
			(layer "B.SilkS")
		)
		(fp_line
			(start 0.7874 -0.4064)
			(end -0.7874 -0.4064)
			(stroke
				(width 0.1524)
				(type default)
			)
			(layer "B.SilkS")
		)
		(fp_line
			(start 0.7874 0.4064)
			(end 0.7874 -0.4064)
			(stroke
				(width 0.1524)
				(type default)
			)
			(layer "B.SilkS")
		)
		(fp_line
			(start -0.67945 -0.3048)
			(end -0.67945 0.3048)
			(stroke
				(width 0.1)
				(type default)
			)
			(layer "B.Fab")
		)
		(fp_line
			(start -0.67945 0.3048)
			(end -0.120396 0.3048)
			(stroke
				(width 0.1)
				(type default)
			)
			(layer "B.Fab")
		)
		(fp_line
			(start -0.12065 -0.3048)
			(end -0.67945 -0.3048)
			(stroke
				(width 0.1)
				(type default)
			)
			(layer "B.Fab")
		)
		(fp_line
			(start -0.12065 -0.2794)
			(end -0.12065 -0.3048)
			(stroke
				(width 0.1)
				(type default)
			)
			(layer "B.Fab")
		)
		(fp_line
			(start -0.120396 0.2794)
			(end 0.12065 0.2794)
			(stroke
				(width 0.1)
				(type default)
			)
			(layer "B.Fab")
		)
		(fp_line
			(start -0.120396 0.3048)
			(end -0.120396 0.2794)
			(stroke
				(width 0.1)
				(type default)
			)
			(layer "B.Fab")
		)
		(fp_line
			(start 0.12065 -0.305054)
			(end 0.12065 -0.2794)
			(stroke
				(width 0.1)
				(type default)
			)
			(layer "B.Fab")
		)
		(fp_line
			(start 0.12065 -0.2794)
			(end -0.12065 -0.2794)
			(stroke
				(width 0.1)
				(type default)
			)
			(layer "B.Fab")
		)
		(fp_line
			(start 0.12065 0.2794)
			(end 0.12065 0.3048)
			(stroke
				(width 0.1)
				(type default)
			)
			(layer "B.Fab")
		)
		(fp_line
			(start 0.12065 0.3048)
			(end 0.67945 0.3048)
			(stroke
				(width 0.1)
				(type default)
			)
			(layer "B.Fab")
		)
		(fp_line
			(start 0.67945 -0.305054)
			(end 0.12065 -0.305054)
			(stroke
				(width 0.1)
				(type default)
			)
			(layer "B.Fab")
		)
		(fp_line
			(start 0.67945 0.3048)
			(end 0.67945 -0.305054)
			(stroke
				(width 0.1)
				(type default)
			)
			(layer "B.Fab")
		)
		(pad "1" smd circle
			(at 0.40005 0 180)
			(size 0 0)
			(layers "B.Cu" "B.Mask" "B.Paste")
			(net "PVDD18_S5_P0")
		)
		(pad "2" smd circle
			(at -0.40005 0 180)
			(size 0 0)
			(layers "B.Cu" "B.Mask" "B.Paste")
			(net "FAB_REV_ID2")
		)
	)
	(footprint ""
		(layer "B.Cu")
		(at 371.805454 -268.41831)
		(property "Reference" "C2245"
			(at 0 0 0)
			(layer "B.SilkS")
			(hide yes)
			(effects
				(font
					(size 1.27 1.27)
				)
				(justify mirror)
			)
		)
		(property "Value" ""
			(at 0 0 0)
			(layer "B.Fab")
			(effects
				(font
					(size 1.27 1.27)
				)
				(justify mirror)
			)
		)
		(duplicate_pad_numbers_are_jumpers no)
		(fp_line
			(start -0.7874 -0.4064)
			(end -0.7874 0.4064)
			(stroke
				(width 0.1524)
				(type default)
			)
			(layer "B.SilkS")
		)
		(fp_line
			(start -0.7874 0.4064)
			(end 0.7874 0.4064)
			(stroke
				(width 0.1524)
				(type default)
			)
			(layer "B.SilkS")
		)
		(fp_line
			(start 0.7874 -0.4064)
			(end -0.7874 -0.4064)
			(stroke
				(width 0.1524)
				(type default)
			)
			(layer "B.SilkS")
		)
		(fp_line
			(start 0.7874 0.4064)
			(end 0.7874 -0.4064)
			(stroke
				(width 0.1524)
				(type default)
			)
			(layer "B.SilkS")
		)
		(fp_line
			(start -0.67945 -0.3048)
			(end -0.67945 0.3048)
			(stroke
				(width 0.1)
				(type default)
			)
			(layer "B.Fab")
		)
		(fp_line
			(start -0.67945 0.3048)
			(end -0.120396 0.3048)
			(stroke
				(width 0.1)
				(type default)
			)
			(layer "B.Fab")
		)
		(fp_line
			(start -0.12065 -0.3048)
			(end -0.67945 -0.3048)
			(stroke
				(width 0.1)
				(type default)
			)
			(layer "B.Fab")
		)
		(fp_line
			(start -0.12065 -0.2794)
			(end -0.12065 -0.3048)
			(stroke
				(width 0.1)
				(type default)
			)
			(layer "B.Fab")
		)
		(fp_line
			(start -0.120396 0.2794)
			(end 0.12065 0.2794)
			(stroke
				(width 0.1)
				(type default)
			)
			(layer "B.Fab")
		)
		(fp_line
			(start -0.120396 0.3048)
			(end -0.120396 0.2794)
			(stroke
				(width 0.1)
				(type default)
			)
			(layer "B.Fab")
		)
		(fp_line
			(start 0.12065 -0.305054)
			(end 0.12065 -0.2794)
			(stroke
				(width 0.1)
				(type default)
			)
			(layer "B.Fab")
		)
		(fp_line
			(start 0.12065 -0.2794)
			(end -0.12065 -0.2794)
			(stroke
				(width 0.1)
				(type default)
			)
			(layer "B.Fab")
		)
		(fp_line
			(start 0.12065 0.2794)
			(end 0.12065 0.3048)
			(stroke
				(width 0.1)
				(type default)
			)
			(layer "B.Fab")
		)
		(fp_line
			(start 0.12065 0.3048)
			(end 0.67945 0.3048)
			(stroke
				(width 0.1)
				(type default)
			)
			(layer "B.Fab")
		)
		(fp_line
			(start 0.67945 -0.305054)
			(end 0.12065 -0.305054)
			(stroke
				(width 0.1)
				(type default)
			)
			(layer "B.Fab")
		)
		(fp_line
			(start 0.67945 0.3048)
			(end 0.67945 -0.305054)
			(stroke
				(width 0.1)
				(type default)
			)
			(layer "B.Fab")
		)
		(pad "1" smd circle
			(at 0.40005 0 180)
			(size 0 0)
			(layers "B.Cu" "B.Mask" "B.Paste")
			(net "PVDDCR_CPU1_P0")
		)
		(pad "2" smd circle
			(at -0.40005 0 180)
			(size 0 0)
			(layers "B.Cu" "B.Mask" "B.Paste")
			(net "GND")
		)
	)
	(footprint ""
		(layer "B.Cu")
		(at 379.613922 -148.30171 -90)
		(property "Reference" "PR531"
			(at 0 0 90)
			(layer "B.SilkS")
			(hide yes)
			(effects
				(font
					(size 1.27 1.27)
				)
				(justify mirror)
			)
		)
		(property "Value" ""
			(at 0 0 90)
			(layer "B.Fab")
			(effects
				(font
					(size 1.27 1.27)
				)
				(justify mirror)
			)
		)
		(duplicate_pad_numbers_are_jumpers no)
		(fp_line
			(start -0.7874 0.4064)
			(end 0.7874 0.4064)
			(stroke
				(width 0.1524)
				(type default)
			)
			(layer "B.SilkS")
		)
		(fp_line
			(start 0.7874 0.4064)
			(end 0.7874 -0.4064)
			(stroke
				(width 0.1524)
				(type default)
			)
			(layer "B.SilkS")
		)
		(fp_line
			(start -0.7874 -0.4064)
			(end -0.7874 0.4064)
			(stroke
				(width 0.1524)
				(type default)
			)
			(layer "B.SilkS")
		)
		(fp_line
			(start 0.7874 -0.4064)
			(end -0.7874 -0.4064)
			(stroke
				(width 0.1524)
				(type default)
			)
			(layer "B.SilkS")
		)
		(fp_line
			(start -0.67945 0.3048)
			(end -0.120396 0.3048)
			(stroke
				(width 0.1)
				(type default)
			)
			(layer "B.Fab")
		)
		(fp_line
			(start -0.120396 0.3048)
			(end -0.120396 0.2794)
			(stroke
				(width 0.1)
				(type default)
			)
			(layer "B.Fab")
		)
		(fp_line
			(start 0.12065 0.3048)
			(end 0.67945 0.3048)
			(stroke
				(width 0.1)
				(type default)
			)
			(layer "B.Fab")
		)
		(fp_line
			(start 0.67945 0.3048)
			(end 0.67945 -0.305054)
			(stroke
				(width 0.1)
				(type default)
			)
			(layer "B.Fab")
		)
		(fp_line
			(start -0.120396 0.2794)
			(end 0.12065 0.2794)
			(stroke
				(width 0.1)
				(type default)
			)
			(layer "B.Fab")
		)
		(fp_line
			(start 0.12065 0.2794)
			(end 0.12065 0.3048)
			(stroke
				(width 0.1)
				(type default)
			)
			(layer "B.Fab")
		)
		(fp_line
			(start -0.12065 -0.2794)
			(end -0.12065 -0.3048)
			(stroke
				(width 0.1)
				(type default)
			)
			(layer "B.Fab")
		)
		(fp_line
			(start 0.12065 -0.2794)
			(end -0.12065 -0.2794)
			(stroke
				(width 0.1)
				(type default)
			)
			(layer "B.Fab")
		)
		(fp_line
			(start -0.67945 -0.3048)
			(end -0.67945 0.3048)
			(stroke
				(width 0.1)
				(type default)
			)
			(layer "B.Fab")
		)
		(fp_line
			(start -0.12065 -0.3048)
			(end -0.67945 -0.3048)
			(stroke
				(width 0.1)
				(type default)
			)
			(layer "B.Fab")
		)
		(fp_line
			(start 0.12065 -0.305054)
			(end 0.12065 -0.2794)
			(stroke
				(width 0.1)
				(type default)
			)
			(layer "B.Fab")
		)
		(fp_line
			(start 0.67945 -0.305054)
			(end 0.12065 -0.305054)
			(stroke
				(width 0.1)
				(type default)
			)
			(layer "B.Fab")
		)
		(pad "1" smd circle
			(at 0.40005 0 90)
			(size 0 0)
			(layers "B.Cu" "B.Mask" "B.Paste")
			(net "NC_PVDDCR_CPU0_P0_IMON7")
		)
		(pad "2" smd circle
			(at -0.40005 0 90)
			(size 0 0)
			(layers "B.Cu" "B.Mask" "B.Paste")
			(net "GND")
		)
	)
	(footprint ""
		(layer "B.Cu")
		(at 58.656982 -153.821892 180)
		(property "Reference" "PC65"
			(at 0 0 0)
			(layer "B.SilkS")
			(hide yes)
			(effects
				(font
					(size 1.27 1.27)
				)
				(justify mirror)
			)
		)
		(property "Value" ""
			(at 0 0 0)
			(layer "B.Fab")
			(effects
				(font
					(size 1.27 1.27)
				)
				(justify mirror)
			)
		)
		(duplicate_pad_numbers_are_jumpers no)
		(fp_line
			(start 1.524 0.762)
			(end 1.524 -0.762)
			(stroke
				(width 0.1524)
				(type default)
			)
			(layer "B.SilkS")
		)
		(fp_line
			(start 1.524 -0.762)
			(end -1.524 -0.762)
			(stroke
				(width 0.1524)
				(type default)
			)
			(layer "B.SilkS")
		)
		(fp_line
			(start -1.524 0.762)
			(end 1.524 0.762)
			(stroke
				(width 0.1524)
				(type default)
			)
			(layer "B.SilkS")
		)
		(fp_line
			(start -1.524 -0.762)
			(end -1.524 0.762)
			(stroke
				(width 0.1524)
				(type default)
			)
			(layer "B.SilkS")
		)
		(fp_line
			(start 1.1049 0.724916)
			(end -1.1049 0.724916)
			(stroke
				(width 0.1)
				(type default)
			)
			(layer "B.Fab")
		)
		(fp_line
			(start 1.1049 -0.724916)
			(end 1.1049 0.724916)
			(stroke
				(width 0.1)
				(type default)
			)
			(layer "B.Fab")
		)
		(fp_line
			(start -1.1049 0.724916)
			(end -1.1049 -0.724916)
			(stroke
				(width 0.1)
				(type default)
			)
			(layer "B.Fab")
		)
		(fp_line
			(start -1.1049 -0.724916)
			(end 1.1049 -0.724916)
			(stroke
				(width 0.1)
				(type default)
			)
			(layer "B.Fab")
		)
		(pad "1" smd rect
			(at 0.889 0 180)
			(size 1.016 1.27)
			(layers "B.Cu" "B.Mask" "B.Paste")
			(net "PVDD18_S5_P1")
		)
		(pad "2" smd rect
			(at -0.889 0 180)
			(size 1.016 1.27)
			(layers "B.Cu" "B.Mask" "B.Paste")
			(net "GND")
		)
	)
	(footprint ""
		(layer "B.Cu")
		(at 98.578924 -257.930396 180)
		(property "Reference" "C2123"
			(at 0 0 0)
			(layer "B.SilkS")
			(hide yes)
			(effects
				(font
					(size 1.27 1.27)
				)
				(justify mirror)
			)
		)
		(property "Value" ""
			(at 0 0 0)
			(layer "B.Fab")
			(effects
				(font
					(size 1.27 1.27)
				)
				(justify mirror)
			)
		)
		(duplicate_pad_numbers_are_jumpers no)
		(fp_line
			(start 0.7874 0.4064)
			(end 0.7874 -0.4064)
			(stroke
				(width 0.1524)
				(type default)
			)
			(layer "B.SilkS")
		)
		(fp_line
			(start 0.7874 -0.4064)
			(end -0.7874 -0.4064)
			(stroke
				(width 0.1524)
				(type default)
			)
			(layer "B.SilkS")
		)
		(fp_line
			(start -0.7874 0.4064)
			(end 0.7874 0.4064)
			(stroke
				(width 0.1524)
				(type default)
			)
			(layer "B.SilkS")
		)
		(fp_line
			(start -0.7874 -0.4064)
			(end -0.7874 0.4064)
			(stroke
				(width 0.1524)
				(type default)
			)
			(layer "B.SilkS")
		)
		(fp_line
			(start 0.67945 0.3048)
			(end 0.67945 -0.305054)
			(stroke
				(width 0.1)
				(type default)
			)
			(layer "B.Fab")
		)
		(fp_line
			(start 0.67945 -0.305054)
			(end 0.12065 -0.305054)
			(stroke
				(width 0.1)
				(type default)
			)
			(layer "B.Fab")
		)
		(fp_line
			(start 0.12065 0.3048)
			(end 0.67945 0.3048)
			(stroke
				(width 0.1)
				(type default)
			)
			(layer "B.Fab")
		)
		(fp_line
			(start 0.12065 0.2794)
			(end 0.12065 0.3048)
			(stroke
				(width 0.1)
				(type default)
			)
			(layer "B.Fab")
		)
		(fp_line
			(start 0.12065 -0.2794)
			(end -0.12065 -0.2794)
			(stroke
				(width 0.1)
				(type default)
			)
			(layer "B.Fab")
		)
		(fp_line
			(start 0.12065 -0.305054)
			(end 0.12065 -0.2794)
			(stroke
				(width 0.1)
				(type default)
			)
			(layer "B.Fab")
		)
		(fp_line
			(start -0.120396 0.3048)
			(end -0.120396 0.2794)
			(stroke
				(width 0.1)
				(type default)
			)
			(layer "B.Fab")
		)
		(fp_line
			(start -0.120396 0.2794)
			(end 0.12065 0.2794)
			(stroke
				(width 0.1)
				(type default)
			)
			(layer "B.Fab")
		)
		(fp_line
			(start -0.12065 -0.2794)
			(end -0.12065 -0.3048)
			(stroke
				(width 0.1)
				(type default)
			)
			(layer "B.Fab")
		)
		(fp_line
			(start -0.12065 -0.3048)
			(end -0.67945 -0.3048)
			(stroke
				(width 0.1)
				(type default)
			)
			(layer "B.Fab")
		)
		(fp_line
			(start -0.67945 0.3048)
			(end -0.120396 0.3048)
			(stroke
				(width 0.1)
				(type default)
			)
			(layer "B.Fab")
		)
		(fp_line
			(start -0.67945 -0.3048)
			(end -0.67945 0.3048)
			(stroke
				(width 0.1)
				(type default)
			)
			(layer "B.Fab")
		)
		(pad "1" smd circle
			(at 0.40005 0)
			(size 0 0)
			(layers "B.Cu" "B.Mask" "B.Paste")
			(net "PVDDIO_P1")
		)
		(pad "2" smd circle
			(at -0.40005 0)
			(size 0 0)
			(layers "B.Cu" "B.Mask" "B.Paste")
			(net "GND")
		)
	)
	(footprint ""
		(layer "B.Cu")
		(at 153.357834 -199.234552 90)
		(property "Reference" "R523"
			(at 0 0 90)
			(layer "B.SilkS")
			(hide yes)
			(effects
				(font
					(size 1.27 1.27)
				)
				(justify mirror)
			)
		)
		(property "Value" ""
			(at 0 0 90)
			(layer "B.Fab")
			(effects
				(font
					(size 1.27 1.27)
				)
				(justify mirror)
			)
		)
		(duplicate_pad_numbers_are_jumpers no)
		(fp_line
			(start 0.7874 -0.4064)
			(end -0.7874 -0.4064)
			(stroke
				(width 0.1524)
				(type default)
			)
			(layer "B.SilkS")
		)
		(fp_line
			(start -0.7874 -0.4064)
			(end -0.7874 0.4064)
			(stroke
				(width 0.1524)
				(type default)
			)
			(layer "B.SilkS")
		)
		(fp_line
			(start 0.7874 0.4064)
			(end 0.7874 -0.4064)
			(stroke
				(width 0.1524)
				(type default)
			)
			(layer "B.SilkS")
		)
		(fp_line
			(start -0.7874 0.4064)
			(end 0.7874 0.4064)
			(stroke
				(width 0.1524)
				(type default)
			)
			(layer "B.SilkS")
		)
		(fp_line
			(start 0.67945 -0.305054)
			(end 0.12065 -0.305054)
			(stroke
				(width 0.1)
				(type default)
			)
			(layer "B.Fab")
		)
		(fp_line
			(start 0.12065 -0.305054)
			(end 0.12065 -0.2794)
			(stroke
				(width 0.1)
				(type default)
			)
			(layer "B.Fab")
		)
		(fp_line
			(start -0.12065 -0.3048)
			(end -0.67945 -0.3048)
			(stroke
				(width 0.1)
				(type default)
			)
			(layer "B.Fab")
		)
		(fp_line
			(start -0.67945 -0.3048)
			(end -0.67945 0.3048)
			(stroke
				(width 0.1)
				(type default)
			)
			(layer "B.Fab")
		)
		(fp_line
			(start 0.12065 -0.2794)
			(end -0.12065 -0.2794)
			(stroke
				(width 0.1)
				(type default)
			)
			(layer "B.Fab")
		)
		(fp_line
			(start -0.12065 -0.2794)
			(end -0.12065 -0.3048)
			(stroke
				(width 0.1)
				(type default)
			)
			(layer "B.Fab")
		)
		(fp_line
			(start 0.12065 0.2794)
			(end 0.12065 0.3048)
			(stroke
				(width 0.1)
				(type default)
			)
			(layer "B.Fab")
		)
		(fp_line
			(start -0.120396 0.2794)
			(end 0.12065 0.2794)
			(stroke
				(width 0.1)
				(type default)
			)
			(layer "B.Fab")
		)
		(fp_line
			(start 0.67945 0.3048)
			(end 0.67945 -0.305054)
			(stroke
				(width 0.1)
				(type default)
			)
			(layer "B.Fab")
		)
		(fp_line
			(start 0.12065 0.3048)
			(end 0.67945 0.3048)
			(stroke
				(width 0.1)
				(type default)
			)
			(layer "B.Fab")
		)
		(fp_line
			(start -0.120396 0.3048)
			(end -0.120396 0.2794)
			(stroke
				(width 0.1)
				(type default)
			)
			(layer "B.Fab")
		)
		(fp_line
			(start -0.67945 0.3048)
			(end -0.120396 0.3048)
			(stroke
				(width 0.1)
				(type default)
			)
			(layer "B.Fab")
		)
		(pad "1" smd circle
			(at 0.40005 0 270)
			(size 0 0)
			(layers "B.Cu" "B.Mask" "B.Paste")
			(net "PVDD18_S5_P1")
		)
		(pad "2" smd circle
			(at -0.40005 0 270)
			(size 0 0)
			(layers "B.Cu" "B.Mask" "B.Paste")
			(net "JTAG_CPU1_TDO")
		)
	)
	(footprint ""
		(layer "B.Cu")
		(at 217.678 -339.598 180)
		(property "Reference" "R6747"
			(at 0 0 0)
			(layer "B.SilkS")
			(hide yes)
			(effects
				(font
					(size 1.27 1.27)
				)
				(justify mirror)
			)
		)
		(property "Value" ""
			(at 0 0 0)
			(layer "B.Fab")
			(effects
				(font
					(size 1.27 1.27)
				)
				(justify mirror)
			)
		)
		(duplicate_pad_numbers_are_jumpers no)
		(fp_line
			(start 0.32512 0.175006)
			(end 0.32512 -0.175006)
			(stroke
				(width 0.1)
				(type default)
			)
			(layer "B.Fab")
		)
		(fp_line
			(start 0.32512 -0.175006)
			(end -0.32512 -0.175006)
			(stroke
				(width 0.1)
				(type default)
			)
			(layer "B.Fab")
		)
		(fp_line
			(start -0.32512 0.175006)
			(end 0.32512 0.175006)
			(stroke
				(width 0.1)
				(type default)
			)
			(layer "B.Fab")
		)
		(fp_line
			(start -0.32512 -0.175006)
			(end -0.32512 0.175006)
			(stroke
				(width 0.1)
				(type default)
			)
			(layer "B.Fab")
		)
		(pad "1" smd rect
			(at 0.2667 0)
			(size 0.3048 0.381)
			(layers "B.Cu" "B.Mask" "B.Paste")
			(net "SMB_RT_CPU1_P3_R_SCL")
		)
		(pad "2" smd rect
			(at -0.2667 0 180)
			(size 0.3048 0.381)
			(layers "B.Cu" "B.Mask" "B.Paste")
			(net "SMB_RT_CPU1_P3_SCL")
		)
	)
	(footprint ""
		(layer "B.Cu")
		(at 352.787712 -340.002368 90)
		(property "Reference" "PC119_6"
			(at 0 0 90)
			(layer "B.SilkS")
			(hide yes)
			(effects
				(font
					(size 1.27 1.27)
				)
				(justify mirror)
			)
		)
		(property "Value" ""
			(at 0 0 90)
			(layer "B.Fab")
			(effects
				(font
					(size 1.27 1.27)
				)
				(justify mirror)
			)
		)
		(duplicate_pad_numbers_are_jumpers no)
		(fp_line
			(start 1.524 -0.762)
			(end -1.524 -0.762)
			(stroke
				(width 0.1524)
				(type default)
			)
			(layer "B.SilkS")
		)
		(fp_line
			(start -1.524 -0.762)
			(end -1.524 0.762)
			(stroke
				(width 0.1524)
				(type default)
			)
			(layer "B.SilkS")
		)
		(fp_line
			(start 1.524 0.762)
			(end 1.524 -0.762)
			(stroke
				(width 0.1524)
				(type default)
			)
			(layer "B.SilkS")
		)
		(fp_line
			(start -1.524 0.762)
			(end 1.524 0.762)
			(stroke
				(width 0.1524)
				(type default)
			)
			(layer "B.SilkS")
		)
		(fp_line
			(start 1.1049 -0.724916)
			(end 1.1049 0.724916)
			(stroke
				(width 0.1)
				(type default)
			)
			(layer "B.Fab")
		)
		(fp_line
			(start -1.1049 -0.724916)
			(end 1.1049 -0.724916)
			(stroke
				(width 0.1)
				(type default)
			)
			(layer "B.Fab")
		)
		(fp_line
			(start 1.1049 0.724916)
			(end -1.1049 0.724916)
			(stroke
				(width 0.1)
				(type default)
			)
			(layer "B.Fab")
		)
		(fp_line
			(start -1.1049 0.724916)
			(end -1.1049 -0.724916)
			(stroke
				(width 0.1)
				(type default)
			)
			(layer "B.Fab")
		)
		(pad "1" smd rect
			(at 0.889 0 90)
			(size 1.016 1.27)
			(layers "B.Cu" "B.Mask" "B.Paste")
			(net "SW_P12V_AUX_PVDDCR_CPU1_P0_FLT")
		)
		(pad "2" smd rect
			(at -0.889 0 90)
			(size 1.016 1.27)
			(layers "B.Cu" "B.Mask" "B.Paste")
			(net "GND")
		)
	)
	(footprint ""
		(layer "B.Cu")
		(at 68.594224 -408.517344 90)
		(property "Reference" "C6673"
			(at 0 0 90)
			(layer "B.SilkS")
			(hide yes)
			(effects
				(font
					(size 1.27 1.27)
				)
				(justify mirror)
			)
		)
		(property "Value" ""
			(at 0 0 90)
			(layer "B.Fab")
			(effects
				(font
					(size 1.27 1.27)
				)
				(justify mirror)
			)
		)
		(duplicate_pad_numbers_are_jumpers no)
		(fp_line
			(start 0.299974 -0.150114)
			(end -0.299974 -0.150114)
			(stroke
				(width 0.1)
				(type default)
			)
			(layer "B.Fab")
		)
		(fp_line
			(start -0.299974 -0.150114)
			(end -0.299974 0.150114)
			(stroke
				(width 0.1)
				(type default)
			)
			(layer "B.Fab")
		)
		(fp_line
			(start 0.299974 0.150114)
			(end 0.299974 -0.150114)
			(stroke
				(width 0.1)
				(type default)
			)
			(layer "B.Fab")
		)
		(fp_line
			(start -0.299974 0.150114)
			(end 0.299974 0.150114)
			(stroke
				(width 0.1)
				(type default)
			)
			(layer "B.Fab")
		)
		(pad "1" smd rect
			(at 0.2667 0 270)
			(size 0.3048 0.381)
			(layers "B.Cu" "B.Mask" "B.Paste")
			(net "P5E_CPU1_P1_TX_BUF_C_DP<6>")
		)
		(pad "2" smd rect
			(at -0.2667 0 270)
			(size 0.3048 0.381)
			(layers "B.Cu" "B.Mask" "B.Paste")
			(net "P5E_CPU1_P1_TX_BUF_DP<6>")
		)
	)
	(footprint ""
		(layer "B.Cu")
		(at 346.639896 -335.092294 90)
		(property "Reference" "PC139_5"
			(at 0 0 90)
			(layer "B.SilkS")
			(hide yes)
			(effects
				(font
					(size 1.27 1.27)
				)
				(justify mirror)
			)
		)
		(property "Value" ""
			(at 0 0 90)
			(layer "B.Fab")
			(effects
				(font
					(size 1.27 1.27)
				)
				(justify mirror)
			)
		)
		(duplicate_pad_numbers_are_jumpers no)
		(fp_line
			(start 1.524 -0.762)
			(end -1.524 -0.762)
			(stroke
				(width 0.1524)
				(type default)
			)
			(layer "B.SilkS")
		)
		(fp_line
			(start -1.524 -0.762)
			(end -1.524 0.762)
			(stroke
				(width 0.1524)
				(type default)
			)
			(layer "B.SilkS")
		)
		(fp_line
			(start 1.524 0.762)
			(end 1.524 -0.762)
			(stroke
				(width 0.1524)
				(type default)
			)
			(layer "B.SilkS")
		)
		(fp_line
			(start -1.524 0.762)
			(end 1.524 0.762)
			(stroke
				(width 0.1524)
				(type default)
			)
			(layer "B.SilkS")
		)
		(fp_line
			(start 1.1049 -0.724916)
			(end 1.1049 0.724916)
			(stroke
				(width 0.1)
				(type default)
			)
			(layer "B.Fab")
		)
		(fp_line
			(start -1.1049 -0.724916)
			(end 1.1049 -0.724916)
			(stroke
				(width 0.1)
				(type default)
			)
			(layer "B.Fab")
		)
		(fp_line
			(start 1.1049 0.724916)
			(end -1.1049 0.724916)
			(stroke
				(width 0.1)
				(type default)
			)
			(layer "B.Fab")
		)
		(fp_line
			(start -1.1049 0.724916)
			(end -1.1049 -0.724916)
			(stroke
				(width 0.1)
				(type default)
			)
			(layer "B.Fab")
		)
		(pad "1" smd rect
			(at 0.889 0 90)
			(size 1.016 1.27)
			(layers "B.Cu" "B.Mask" "B.Paste")
			(net "SW_P12V_AUX_PVDDCR_CPU1_P0_FLT")
		)
		(pad "2" smd rect
			(at -0.889 0 90)
			(size 1.016 1.27)
			(layers "B.Cu" "B.Mask" "B.Paste")
			(net "GND")
		)
	)
	(footprint ""
		(layer "B.Cu")
		(at 408.597608 -327.866502 90)
		(property "Reference" "R5056"
			(at 0 0 90)
			(layer "B.SilkS")
			(hide yes)
			(effects
				(font
					(size 1.27 1.27)
				)
				(justify mirror)
			)
		)
		(property "Value" ""
			(at 0 0 90)
			(layer "B.Fab")
			(effects
				(font
					(size 1.27 1.27)
				)
				(justify mirror)
			)
		)
		(duplicate_pad_numbers_are_jumpers no)
		(fp_line
			(start 0.7874 -0.4064)
			(end -0.7874 -0.4064)
			(stroke
				(width 0.1524)
				(type default)
			)
			(layer "B.SilkS")
		)
		(fp_line
			(start -0.7874 -0.4064)
			(end -0.7874 0.4064)
			(stroke
				(width 0.1524)
				(type default)
			)
			(layer "B.SilkS")
		)
		(fp_line
			(start 0.7874 0.4064)
			(end 0.7874 -0.4064)
			(stroke
				(width 0.1524)
				(type default)
			)
			(layer "B.SilkS")
		)
		(fp_line
			(start -0.7874 0.4064)
			(end 0.7874 0.4064)
			(stroke
				(width 0.1524)
				(type default)
			)
			(layer "B.SilkS")
		)
		(fp_line
			(start 0.67945 -0.305054)
			(end 0.12065 -0.305054)
			(stroke
				(width 0.1)
				(type default)
			)
			(layer "B.Fab")
		)
		(fp_line
			(start 0.12065 -0.305054)
			(end 0.12065 -0.2794)
			(stroke
				(width 0.1)
				(type default)
			)
			(layer "B.Fab")
		)
		(fp_line
			(start -0.12065 -0.3048)
			(end -0.67945 -0.3048)
			(stroke
				(width 0.1)
				(type default)
			)
			(layer "B.Fab")
		)
		(fp_line
			(start -0.67945 -0.3048)
			(end -0.67945 0.3048)
			(stroke
				(width 0.1)
				(type default)
			)
			(layer "B.Fab")
		)
		(fp_line
			(start 0.12065 -0.2794)
			(end -0.12065 -0.2794)
			(stroke
				(width 0.1)
				(type default)
			)
			(layer "B.Fab")
		)
		(fp_line
			(start -0.12065 -0.2794)
			(end -0.12065 -0.3048)
			(stroke
				(width 0.1)
				(type default)
			)
			(layer "B.Fab")
		)
		(fp_line
			(start 0.12065 0.2794)
			(end 0.12065 0.3048)
			(stroke
				(width 0.1)
				(type default)
			)
			(layer "B.Fab")
		)
		(fp_line
			(start -0.120396 0.2794)
			(end 0.12065 0.2794)
			(stroke
				(width 0.1)
				(type default)
			)
			(layer "B.Fab")
		)
		(fp_line
			(start 0.67945 0.3048)
			(end 0.67945 -0.305054)
			(stroke
				(width 0.1)
				(type default)
			)
			(layer "B.Fab")
		)
		(fp_line
			(start 0.12065 0.3048)
			(end 0.67945 0.3048)
			(stroke
				(width 0.1)
				(type default)
			)
			(layer "B.Fab")
		)
		(fp_line
			(start -0.120396 0.3048)
			(end -0.120396 0.2794)
			(stroke
				(width 0.1)
				(type default)
			)
			(layer "B.Fab")
		)
		(fp_line
			(start -0.67945 0.3048)
			(end -0.120396 0.3048)
			(stroke
				(width 0.1)
				(type default)
			)
			(layer "B.Fab")
		)
		(pad "1" smd circle
			(at 0.40005 0 270)
			(size 0 0)
			(layers "B.Cu" "B.Mask" "B.Paste")
			(net "CPU0_RTC_LDO_SELECT")
		)
		(pad "2" smd circle
			(at -0.40005 0 270)
			(size 0 0)
			(layers "B.Cu" "B.Mask" "B.Paste")
			(net "GND")
		)
	)
	(footprint ""
		(layer "B.Cu")
		(at 415.471102 -244.08511)
		(property "Reference" "R381"
			(at 0 0 0)
			(layer "B.SilkS")
			(hide yes)
			(effects
				(font
					(size 1.27 1.27)
				)
				(justify mirror)
			)
		)
		(property "Value" ""
			(at 0 0 0)
			(layer "B.Fab")
			(effects
				(font
					(size 1.27 1.27)
				)
				(justify mirror)
			)
		)
		(duplicate_pad_numbers_are_jumpers no)
		(fp_line
			(start -0.7874 -0.4064)
			(end -0.7874 0.4064)
			(stroke
				(width 0.1524)
				(type default)
			)
			(layer "B.SilkS")
		)
		(fp_line
			(start -0.7874 0.4064)
			(end 0.7874 0.4064)
			(stroke
				(width 0.1524)
				(type default)
			)
			(layer "B.SilkS")
		)
		(fp_line
			(start 0.7874 -0.4064)
			(end -0.7874 -0.4064)
			(stroke
				(width 0.1524)
				(type default)
			)
			(layer "B.SilkS")
		)
		(fp_line
			(start 0.7874 0.4064)
			(end 0.7874 -0.4064)
			(stroke
				(width 0.1524)
				(type default)
			)
			(layer "B.SilkS")
		)
		(fp_line
			(start -0.67945 -0.3048)
			(end -0.67945 0.3048)
			(stroke
				(width 0.1)
				(type default)
			)
			(layer "B.Fab")
		)
		(fp_line
			(start -0.67945 0.3048)
			(end -0.120396 0.3048)
			(stroke
				(width 0.1)
				(type default)
			)
			(layer "B.Fab")
		)
		(fp_line
			(start -0.12065 -0.3048)
			(end -0.67945 -0.3048)
			(stroke
				(width 0.1)
				(type default)
			)
			(layer "B.Fab")
		)
		(fp_line
			(start -0.12065 -0.2794)
			(end -0.12065 -0.3048)
			(stroke
				(width 0.1)
				(type default)
			)
			(layer "B.Fab")
		)
		(fp_line
			(start -0.120396 0.2794)
			(end 0.12065 0.2794)
			(stroke
				(width 0.1)
				(type default)
			)
			(layer "B.Fab")
		)
		(fp_line
			(start -0.120396 0.3048)
			(end -0.120396 0.2794)
			(stroke
				(width 0.1)
				(type default)
			)
			(layer "B.Fab")
		)
		(fp_line
			(start 0.12065 -0.305054)
			(end 0.12065 -0.2794)
			(stroke
				(width 0.1)
				(type default)
			)
			(layer "B.Fab")
		)
		(fp_line
			(start 0.12065 -0.2794)
			(end -0.12065 -0.2794)
			(stroke
				(width 0.1)
				(type default)
			)
			(layer "B.Fab")
		)
		(fp_line
			(start 0.12065 0.2794)
			(end 0.12065 0.3048)
			(stroke
				(width 0.1)
				(type default)
			)
			(layer "B.Fab")
		)
		(fp_line
			(start 0.12065 0.3048)
			(end 0.67945 0.3048)
			(stroke
				(width 0.1)
				(type default)
			)
			(layer "B.Fab")
		)
		(fp_line
			(start 0.67945 -0.305054)
			(end 0.12065 -0.305054)
			(stroke
				(width 0.1)
				(type default)
			)
			(layer "B.Fab")
		)
		(fp_line
			(start 0.67945 0.3048)
			(end 0.67945 -0.305054)
			(stroke
				(width 0.1)
				(type default)
			)
			(layer "B.Fab")
		)
		(pad "1" smd circle
			(at 0.40005 0 180)
			(size 0 0)
			(layers "B.Cu" "B.Mask" "B.Paste")
			(net "M_G_CPU0_ALERT_N")
		)
		(pad "2" smd circle
			(at -0.40005 0 180)
			(size 0 0)
			(layers "B.Cu" "B.Mask" "B.Paste")
			(net "M_G_CPU0_ALERT_R_N")
		)
	)
	(footprint ""
		(layer "B.Cu")
		(at 164.107368 -420.184834 90)
		(property "Reference" "R826"
			(at 0 0 90)
			(layer "B.SilkS")
			(hide yes)
			(effects
				(font
					(size 1.27 1.27)
				)
				(justify mirror)
			)
		)
		(property "Value" ""
			(at 0 0 90)
			(layer "B.Fab")
			(effects
				(font
					(size 1.27 1.27)
				)
				(justify mirror)
			)
		)
		(duplicate_pad_numbers_are_jumpers no)
		(fp_line
			(start 0.32512 -0.175006)
			(end -0.32512 -0.175006)
			(stroke
				(width 0.1)
				(type default)
			)
			(layer "B.Fab")
		)
		(fp_line
			(start -0.32512 -0.175006)
			(end -0.32512 0.175006)
			(stroke
				(width 0.1)
				(type default)
			)
			(layer "B.Fab")
		)
		(fp_line
			(start 0.32512 0.175006)
			(end 0.32512 -0.175006)
			(stroke
				(width 0.1)
				(type default)
			)
			(layer "B.Fab")
		)
		(fp_line
			(start -0.32512 0.175006)
			(end 0.32512 0.175006)
			(stroke
				(width 0.1)
				(type default)
			)
			(layer "B.Fab")
		)
		(pad "1" smd rect
			(at 0.2667 0 270)
			(size 0.3048 0.381)
			(layers "B.Cu" "B.Mask" "B.Paste")
			(net "P1V8_CPU1_RT_1D")
		)
		(pad "2" smd rect
			(at -0.2667 0 90)
			(size 0.3048 0.381)
			(layers "B.Cu" "B.Mask" "B.Paste")
			(net "SMB_RT_CPU1_P2_ROM_R_SDA")
		)
	)
	(footprint ""
		(layer "B.Cu")
		(at 304.023776 -194.88531 180)
		(property "Reference" "R7"
			(at 0 0 0)
			(layer "B.SilkS")
			(hide yes)
			(effects
				(font
					(size 1.27 1.27)
				)
				(justify mirror)
			)
		)
		(property "Value" ""
			(at 0 0 0)
			(layer "B.Fab")
			(effects
				(font
					(size 1.27 1.27)
				)
				(justify mirror)
			)
		)
		(duplicate_pad_numbers_are_jumpers no)
		(fp_line
			(start 0.7874 0.4064)
			(end 0.7874 -0.4064)
			(stroke
				(width 0.1524)
				(type default)
			)
			(layer "B.SilkS")
		)
		(fp_line
			(start 0.7874 -0.4064)
			(end -0.7874 -0.4064)
			(stroke
				(width 0.1524)
				(type default)
			)
			(layer "B.SilkS")
		)
		(fp_line
			(start -0.7874 0.4064)
			(end 0.7874 0.4064)
			(stroke
				(width 0.1524)
				(type default)
			)
			(layer "B.SilkS")
		)
		(fp_line
			(start -0.7874 -0.4064)
			(end -0.7874 0.4064)
			(stroke
				(width 0.1524)
				(type default)
			)
			(layer "B.SilkS")
		)
		(fp_line
			(start 0.67945 0.3048)
			(end 0.67945 -0.305054)
			(stroke
				(width 0.1)
				(type default)
			)
			(layer "B.Fab")
		)
		(fp_line
			(start 0.67945 -0.305054)
			(end 0.12065 -0.305054)
			(stroke
				(width 0.1)
				(type default)
			)
			(layer "B.Fab")
		)
		(fp_line
			(start 0.12065 0.3048)
			(end 0.67945 0.3048)
			(stroke
				(width 0.1)
				(type default)
			)
			(layer "B.Fab")
		)
		(fp_line
			(start 0.12065 0.2794)
			(end 0.12065 0.3048)
			(stroke
				(width 0.1)
				(type default)
			)
			(layer "B.Fab")
		)
		(fp_line
			(start 0.12065 -0.2794)
			(end -0.12065 -0.2794)
			(stroke
				(width 0.1)
				(type default)
			)
			(layer "B.Fab")
		)
		(fp_line
			(start 0.12065 -0.305054)
			(end 0.12065 -0.2794)
			(stroke
				(width 0.1)
				(type default)
			)
			(layer "B.Fab")
		)
		(fp_line
			(start -0.120396 0.3048)
			(end -0.120396 0.2794)
			(stroke
				(width 0.1)
				(type default)
			)
			(layer "B.Fab")
		)
		(fp_line
			(start -0.120396 0.2794)
			(end 0.12065 0.2794)
			(stroke
				(width 0.1)
				(type default)
			)
			(layer "B.Fab")
		)
		(fp_line
			(start -0.12065 -0.2794)
			(end -0.12065 -0.3048)
			(stroke
				(width 0.1)
				(type default)
			)
			(layer "B.Fab")
		)
		(fp_line
			(start -0.12065 -0.3048)
			(end -0.67945 -0.3048)
			(stroke
				(width 0.1)
				(type default)
			)
			(layer "B.Fab")
		)
		(fp_line
			(start -0.67945 0.3048)
			(end -0.120396 0.3048)
			(stroke
				(width 0.1)
				(type default)
			)
			(layer "B.Fab")
		)
		(fp_line
			(start -0.67945 -0.3048)
			(end -0.67945 0.3048)
			(stroke
				(width 0.1)
				(type default)
			)
			(layer "B.Fab")
		)
		(pad "1" smd circle
			(at 0.40005 0)
			(size 0 0)
			(layers "B.Cu" "B.Mask" "B.Paste")
			(net "PD_CHA_CPU0_DIMM0_SAA")
		)
		(pad "2" smd circle
			(at -0.40005 0)
			(size 0 0)
			(layers "B.Cu" "B.Mask" "B.Paste")
			(net "GND")
		)
	)
	(footprint ""
		(layer "B.Cu")
		(at 405.120856 -168.717468 -90)
		(property "Reference" "PC590_2"
			(at 0 0 90)
			(layer "B.SilkS")
			(hide yes)
			(effects
				(font
					(size 1.27 1.27)
				)
				(justify mirror)
			)
		)
		(property "Value" ""
			(at 0 0 90)
			(layer "B.Fab")
			(effects
				(font
					(size 1.27 1.27)
				)
				(justify mirror)
			)
		)
		(duplicate_pad_numbers_are_jumpers no)
		(fp_line
			(start -1.524 0.762)
			(end 1.524 0.762)
			(stroke
				(width 0.1524)
				(type default)
			)
			(layer "B.SilkS")
		)
		(fp_line
			(start 1.524 0.762)
			(end 1.524 -0.762)
			(stroke
				(width 0.1524)
				(type default)
			)
			(layer "B.SilkS")
		)
		(fp_line
			(start -1.524 -0.762)
			(end -1.524 0.762)
			(stroke
				(width 0.1524)
				(type default)
			)
			(layer "B.SilkS")
		)
		(fp_line
			(start 1.524 -0.762)
			(end -1.524 -0.762)
			(stroke
				(width 0.1524)
				(type default)
			)
			(layer "B.SilkS")
		)
		(fp_line
			(start -1.1049 0.724916)
			(end -1.1049 -0.724916)
			(stroke
				(width 0.1)
				(type default)
			)
			(layer "B.Fab")
		)
		(fp_line
			(start 1.1049 0.724916)
			(end -1.1049 0.724916)
			(stroke
				(width 0.1)
				(type default)
			)
			(layer "B.Fab")
		)
		(fp_line
			(start -1.1049 -0.724916)
			(end 1.1049 -0.724916)
			(stroke
				(width 0.1)
				(type default)
			)
			(layer "B.Fab")
		)
		(fp_line
			(start 1.1049 -0.724916)
			(end 1.1049 0.724916)
			(stroke
				(width 0.1)
				(type default)
			)
			(layer "B.Fab")
		)
		(pad "1" smd rect
			(at 0.889 0 270)
			(size 1.016 1.27)
			(layers "B.Cu" "B.Mask" "B.Paste")
			(net "SW_P12V_AUX_PVDDCR_SOC_P0_FLT")
		)
		(pad "2" smd rect
			(at -0.889 0 270)
			(size 1.016 1.27)
			(layers "B.Cu" "B.Mask" "B.Paste")
			(net "GND")
		)
	)
	(footprint ""
		(layer "B.Cu")
		(at 154.073606 -408.517344 90)
		(property "Reference" "C6749"
			(at 0 0 90)
			(layer "B.SilkS")
			(hide yes)
			(effects
				(font
					(size 1.27 1.27)
				)
				(justify mirror)
			)
		)
		(property "Value" ""
			(at 0 0 90)
			(layer "B.Fab")
			(effects
				(font
					(size 1.27 1.27)
				)
				(justify mirror)
			)
		)
		(duplicate_pad_numbers_are_jumpers no)
		(fp_line
			(start 0.299974 -0.150114)
			(end -0.299974 -0.150114)
			(stroke
				(width 0.1)
				(type default)
			)
			(layer "B.Fab")
		)
		(fp_line
			(start -0.299974 -0.150114)
			(end -0.299974 0.150114)
			(stroke
				(width 0.1)
				(type default)
			)
			(layer "B.Fab")
		)
		(fp_line
			(start 0.299974 0.150114)
			(end 0.299974 -0.150114)
			(stroke
				(width 0.1)
				(type default)
			)
			(layer "B.Fab")
		)
		(fp_line
			(start -0.299974 0.150114)
			(end 0.299974 0.150114)
			(stroke
				(width 0.1)
				(type default)
			)
			(layer "B.Fab")
		)
		(pad "1" smd rect
			(at 0.2667 0 270)
			(size 0.3048 0.381)
			(layers "B.Cu" "B.Mask" "B.Paste")
			(net "P5E_CPU1_P3_TX_BUF_C_DP<12>")
		)
		(pad "2" smd rect
			(at -0.2667 0 270)
			(size 0.3048 0.381)
			(layers "B.Cu" "B.Mask" "B.Paste")
			(net "P5E_CPU1_P3_TX_BUF_DP<12>")
		)
	)
	(footprint ""
		(layer "B.Cu")
		(at 65.193164 -17.227804)
		(property "Reference" "C1830"
			(at 0 0 0)
			(layer "B.SilkS")
			(hide yes)
			(effects
				(font
					(size 1.27 1.27)
				)
				(justify mirror)
			)
		)
		(property "Value" ""
			(at 0 0 0)
			(layer "B.Fab")
			(effects
				(font
					(size 1.27 1.27)
				)
				(justify mirror)
			)
		)
		(duplicate_pad_numbers_are_jumpers no)
		(fp_line
			(start -1.524 -0.762)
			(end -1.524 0.762)
			(stroke
				(width 0.1524)
				(type default)
			)
			(layer "B.SilkS")
		)
		(fp_line
			(start -1.524 0.762)
			(end 1.524 0.762)
			(stroke
				(width 0.1524)
				(type default)
			)
			(layer "B.SilkS")
		)
		(fp_line
			(start 1.524 -0.762)
			(end -1.524 -0.762)
			(stroke
				(width 0.1524)
				(type default)
			)
			(layer "B.SilkS")
		)
		(fp_line
			(start 1.524 0.762)
			(end 1.524 -0.762)
			(stroke
				(width 0.1524)
				(type default)
			)
			(layer "B.SilkS")
		)
		(fp_line
			(start -1.1049 -0.724916)
			(end 1.1049 -0.724916)
			(stroke
				(width 0.1)
				(type default)
			)
			(layer "B.Fab")
		)
		(fp_line
			(start -1.1049 0.724916)
			(end -1.1049 -0.724916)
			(stroke
				(width 0.1)
				(type default)
			)
			(layer "B.Fab")
		)
		(fp_line
			(start 1.1049 -0.724916)
			(end 1.1049 0.724916)
			(stroke
				(width 0.1)
				(type default)
			)
			(layer "B.Fab")
		)
		(fp_line
			(start 1.1049 0.724916)
			(end -1.1049 0.724916)
			(stroke
				(width 0.1)
				(type default)
			)
			(layer "B.Fab")
		)
		(pad "1" smd rect
			(at 0.889 0)
			(size 1.016 1.27)
			(layers "B.Cu" "B.Mask" "B.Paste")
			(net "P12V_OCP_V3_2_R")
		)
		(pad "2" smd rect
			(at -0.889 0)
			(size 1.016 1.27)
			(layers "B.Cu" "B.Mask" "B.Paste")
			(net "GND")
		)
	)
	(footprint ""
		(layer "B.Cu")
		(at 237.917482 -324.626986)
		(property "Reference" "R1231"
			(at 0 0 0)
			(layer "B.SilkS")
			(hide yes)
			(effects
				(font
					(size 1.27 1.27)
				)
				(justify mirror)
			)
		)
		(property "Value" ""
			(at 0 0 0)
			(layer "B.Fab")
			(effects
				(font
					(size 1.27 1.27)
				)
				(justify mirror)
			)
		)
		(duplicate_pad_numbers_are_jumpers no)
		(fp_line
			(start -0.7874 -0.4064)
			(end -0.7874 0.4064)
			(stroke
				(width 0.1524)
				(type default)
			)
			(layer "B.SilkS")
		)
		(fp_line
			(start -0.7874 0.4064)
			(end 0.7874 0.4064)
			(stroke
				(width 0.1524)
				(type default)
			)
			(layer "B.SilkS")
		)
		(fp_line
			(start 0.7874 -0.4064)
			(end -0.7874 -0.4064)
			(stroke
				(width 0.1524)
				(type default)
			)
			(layer "B.SilkS")
		)
		(fp_line
			(start 0.7874 0.4064)
			(end 0.7874 -0.4064)
			(stroke
				(width 0.1524)
				(type default)
			)
			(layer "B.SilkS")
		)
		(fp_line
			(start -0.67945 -0.3048)
			(end -0.67945 0.3048)
			(stroke
				(width 0.1)
				(type default)
			)
			(layer "B.Fab")
		)
		(fp_line
			(start -0.67945 0.3048)
			(end -0.120396 0.3048)
			(stroke
				(width 0.1)
				(type default)
			)
			(layer "B.Fab")
		)
		(fp_line
			(start -0.12065 -0.3048)
			(end -0.67945 -0.3048)
			(stroke
				(width 0.1)
				(type default)
			)
			(layer "B.Fab")
		)
		(fp_line
			(start -0.12065 -0.2794)
			(end -0.12065 -0.3048)
			(stroke
				(width 0.1)
				(type default)
			)
			(layer "B.Fab")
		)
		(fp_line
			(start -0.120396 0.2794)
			(end 0.12065 0.2794)
			(stroke
				(width 0.1)
				(type default)
			)
			(layer "B.Fab")
		)
		(fp_line
			(start -0.120396 0.3048)
			(end -0.120396 0.2794)
			(stroke
				(width 0.1)
				(type default)
			)
			(layer "B.Fab")
		)
		(fp_line
			(start 0.12065 -0.305054)
			(end 0.12065 -0.2794)
			(stroke
				(width 0.1)
				(type default)
			)
			(layer "B.Fab")
		)
		(fp_line
			(start 0.12065 -0.2794)
			(end -0.12065 -0.2794)
			(stroke
				(width 0.1)
				(type default)
			)
			(layer "B.Fab")
		)
		(fp_line
			(start 0.12065 0.2794)
			(end 0.12065 0.3048)
			(stroke
				(width 0.1)
				(type default)
			)
			(layer "B.Fab")
		)
		(fp_line
			(start 0.12065 0.3048)
			(end 0.67945 0.3048)
			(stroke
				(width 0.1)
				(type default)
			)
			(layer "B.Fab")
		)
		(fp_line
			(start 0.67945 -0.305054)
			(end 0.12065 -0.305054)
			(stroke
				(width 0.1)
				(type default)
			)
			(layer "B.Fab")
		)
		(fp_line
			(start 0.67945 0.3048)
			(end 0.67945 -0.305054)
			(stroke
				(width 0.1)
				(type default)
			)
			(layer "B.Fab")
		)
		(pad "1" smd circle
			(at 0.40005 0 180)
			(size 0 0)
			(layers "B.Cu" "B.Mask" "B.Paste")
			(net "P1V8_CPU0_RT_1D")
		)
		(pad "2" smd circle
			(at -0.40005 0 180)
			(size 0 0)
			(layers "B.Cu" "B.Mask" "B.Paste")
			(net "P1V8_CPU0_RT_1D_ADC")
		)
	)
	(footprint ""
		(layer "B.Cu")
		(at 197.94855 -195.8594 180)
		(property "Reference" "R1710"
			(at 0 0 0)
			(layer "B.SilkS")
			(hide yes)
			(effects
				(font
					(size 1.27 1.27)
				)
				(justify mirror)
			)
		)
		(property "Value" ""
			(at 0 0 0)
			(layer "B.Fab")
			(effects
				(font
					(size 1.27 1.27)
				)
				(justify mirror)
			)
		)
		(duplicate_pad_numbers_are_jumpers no)
		(fp_line
			(start 0.7874 0.4064)
			(end 0.7874 -0.4064)
			(stroke
				(width 0.1524)
				(type default)
			)
			(layer "B.SilkS")
		)
		(fp_line
			(start 0.7874 -0.4064)
			(end -0.7874 -0.4064)
			(stroke
				(width 0.1524)
				(type default)
			)
			(layer "B.SilkS")
		)
		(fp_line
			(start -0.7874 0.4064)
			(end 0.7874 0.4064)
			(stroke
				(width 0.1524)
				(type default)
			)
			(layer "B.SilkS")
		)
		(fp_line
			(start -0.7874 -0.4064)
			(end -0.7874 0.4064)
			(stroke
				(width 0.1524)
				(type default)
			)
			(layer "B.SilkS")
		)
		(fp_line
			(start 0.67945 0.3048)
			(end 0.67945 -0.305054)
			(stroke
				(width 0.1)
				(type default)
			)
			(layer "B.Fab")
		)
		(fp_line
			(start 0.67945 -0.305054)
			(end 0.12065 -0.305054)
			(stroke
				(width 0.1)
				(type default)
			)
			(layer "B.Fab")
		)
		(fp_line
			(start 0.12065 0.3048)
			(end 0.67945 0.3048)
			(stroke
				(width 0.1)
				(type default)
			)
			(layer "B.Fab")
		)
		(fp_line
			(start 0.12065 0.2794)
			(end 0.12065 0.3048)
			(stroke
				(width 0.1)
				(type default)
			)
			(layer "B.Fab")
		)
		(fp_line
			(start 0.12065 -0.2794)
			(end -0.12065 -0.2794)
			(stroke
				(width 0.1)
				(type default)
			)
			(layer "B.Fab")
		)
		(fp_line
			(start 0.12065 -0.305054)
			(end 0.12065 -0.2794)
			(stroke
				(width 0.1)
				(type default)
			)
			(layer "B.Fab")
		)
		(fp_line
			(start -0.120396 0.3048)
			(end -0.120396 0.2794)
			(stroke
				(width 0.1)
				(type default)
			)
			(layer "B.Fab")
		)
		(fp_line
			(start -0.120396 0.2794)
			(end 0.12065 0.2794)
			(stroke
				(width 0.1)
				(type default)
			)
			(layer "B.Fab")
		)
		(fp_line
			(start -0.12065 -0.2794)
			(end -0.12065 -0.3048)
			(stroke
				(width 0.1)
				(type default)
			)
			(layer "B.Fab")
		)
		(fp_line
			(start -0.12065 -0.3048)
			(end -0.67945 -0.3048)
			(stroke
				(width 0.1)
				(type default)
			)
			(layer "B.Fab")
		)
		(fp_line
			(start -0.67945 0.3048)
			(end -0.120396 0.3048)
			(stroke
				(width 0.1)
				(type default)
			)
			(layer "B.Fab")
		)
		(fp_line
			(start -0.67945 -0.3048)
			(end -0.67945 0.3048)
			(stroke
				(width 0.1)
				(type default)
			)
			(layer "B.Fab")
		)
		(pad "1" smd circle
			(at 0.40005 0)
			(size 0 0)
			(layers "B.Cu" "B.Mask" "B.Paste")
			(net "I3C_SPD_DDRGL_CPU1_SDA")
		)
		(pad "2" smd circle
			(at -0.40005 0)
			(size 0 0)
			(layers "B.Cu" "B.Mask" "B.Paste")
			(net "I3C_SPD_DDRK_CPU1_SDA")
		)
	)
	(footprint ""
		(layer "B.Cu")
		(at 327.823068 -335.055972 90)
		(property "Reference" "PC96_2"
			(at 0 0 90)
			(layer "B.SilkS")
			(hide yes)
			(effects
				(font
					(size 1.27 1.27)
				)
				(justify mirror)
			)
		)
		(property "Value" ""
			(at 0 0 90)
			(layer "B.Fab")
			(effects
				(font
					(size 1.27 1.27)
				)
				(justify mirror)
			)
		)
		(duplicate_pad_numbers_are_jumpers no)
		(fp_line
			(start 1.524 -0.762)
			(end -1.524 -0.762)
			(stroke
				(width 0.1524)
				(type default)
			)
			(layer "B.SilkS")
		)
		(fp_line
			(start -1.524 -0.762)
			(end -1.524 0.762)
			(stroke
				(width 0.1524)
				(type default)
			)
			(layer "B.SilkS")
		)
		(fp_line
			(start 1.524 0.762)
			(end 1.524 -0.762)
			(stroke
				(width 0.1524)
				(type default)
			)
			(layer "B.SilkS")
		)
		(fp_line
			(start -1.524 0.762)
			(end 1.524 0.762)
			(stroke
				(width 0.1524)
				(type default)
			)
			(layer "B.SilkS")
		)
		(fp_line
			(start 1.1049 -0.724916)
			(end 1.1049 0.724916)
			(stroke
				(width 0.1)
				(type default)
			)
			(layer "B.Fab")
		)
		(fp_line
			(start -1.1049 -0.724916)
			(end 1.1049 -0.724916)
			(stroke
				(width 0.1)
				(type default)
			)
			(layer "B.Fab")
		)
		(fp_line
			(start 1.1049 0.724916)
			(end -1.1049 0.724916)
			(stroke
				(width 0.1)
				(type default)
			)
			(layer "B.Fab")
		)
		(fp_line
			(start -1.1049 0.724916)
			(end -1.1049 -0.724916)
			(stroke
				(width 0.1)
				(type default)
			)
			(layer "B.Fab")
		)
		(pad "1" smd rect
			(at 0.889 0 90)
			(size 1.016 1.27)
			(layers "B.Cu" "B.Mask" "B.Paste")
			(net "SW_P12V_AUX_PVDDCR_CPU1_P0_FLT")
		)
		(pad "2" smd rect
			(at -0.889 0 90)
			(size 1.016 1.27)
			(layers "B.Cu" "B.Mask" "B.Paste")
			(net "GND")
		)
	)
	(footprint ""
		(layer "B.Cu")
		(at 406.095962 -416.899344 90)
		(property "Reference" "C6620"
			(at 0 0 90)
			(layer "B.SilkS")
			(hide yes)
			(effects
				(font
					(size 1.27 1.27)
				)
				(justify mirror)
			)
		)
		(property "Value" ""
			(at 0 0 90)
			(layer "B.Fab")
			(effects
				(font
					(size 1.27 1.27)
				)
				(justify mirror)
			)
		)
		(duplicate_pad_numbers_are_jumpers no)
		(fp_line
			(start 0.299974 -0.150114)
			(end -0.299974 -0.150114)
			(stroke
				(width 0.1)
				(type default)
			)
			(layer "B.Fab")
		)
		(fp_line
			(start -0.299974 -0.150114)
			(end -0.299974 0.150114)
			(stroke
				(width 0.1)
				(type default)
			)
			(layer "B.Fab")
		)
		(fp_line
			(start 0.299974 0.150114)
			(end 0.299974 -0.150114)
			(stroke
				(width 0.1)
				(type default)
			)
			(layer "B.Fab")
		)
		(fp_line
			(start -0.299974 0.150114)
			(end 0.299974 0.150114)
			(stroke
				(width 0.1)
				(type default)
			)
			(layer "B.Fab")
		)
		(pad "1" smd rect
			(at 0.2667 0 270)
			(size 0.3048 0.381)
			(layers "B.Cu" "B.Mask" "B.Paste")
			(net "P5E_CPU0_P3_TX_BUF_C_DN<11>")
		)
		(pad "2" smd rect
			(at -0.2667 0 270)
			(size 0.3048 0.381)
			(layers "B.Cu" "B.Mask" "B.Paste")
			(net "P5E_CPU0_P3_TX_BUF_DN<11>")
		)
	)
	(footprint ""
		(layer "B.Cu")
		(at 372.937278 -145.536158 180)
		(property "Reference" "PR8005"
			(at 0 0 0)
			(layer "B.SilkS")
			(hide yes)
			(effects
				(font
					(size 1.27 1.27)
				)
				(justify mirror)
			)
		)
		(property "Value" ""
			(at 0 0 0)
			(layer "B.Fab")
			(effects
				(font
					(size 1.27 1.27)
				)
				(justify mirror)
			)
		)
		(duplicate_pad_numbers_are_jumpers no)
		(fp_line
			(start 0.7874 0.4064)
			(end 0.7874 -0.4064)
			(stroke
				(width 0.1524)
				(type default)
			)
			(layer "B.SilkS")
		)
		(fp_line
			(start 0.7874 -0.4064)
			(end -0.7874 -0.4064)
			(stroke
				(width 0.1524)
				(type default)
			)
			(layer "B.SilkS")
		)
		(fp_line
			(start -0.7874 0.4064)
			(end 0.7874 0.4064)
			(stroke
				(width 0.1524)
				(type default)
			)
			(layer "B.SilkS")
		)
		(fp_line
			(start -0.7874 -0.4064)
			(end -0.7874 0.4064)
			(stroke
				(width 0.1524)
				(type default)
			)
			(layer "B.SilkS")
		)
		(fp_line
			(start 0.67945 0.3048)
			(end 0.67945 -0.305054)
			(stroke
				(width 0.1)
				(type default)
			)
			(layer "B.Fab")
		)
		(fp_line
			(start 0.67945 -0.305054)
			(end 0.12065 -0.305054)
			(stroke
				(width 0.1)
				(type default)
			)
			(layer "B.Fab")
		)
		(fp_line
			(start 0.12065 0.3048)
			(end 0.67945 0.3048)
			(stroke
				(width 0.1)
				(type default)
			)
			(layer "B.Fab")
		)
		(fp_line
			(start 0.12065 0.2794)
			(end 0.12065 0.3048)
			(stroke
				(width 0.1)
				(type default)
			)
			(layer "B.Fab")
		)
		(fp_line
			(start 0.12065 -0.2794)
			(end -0.12065 -0.2794)
			(stroke
				(width 0.1)
				(type default)
			)
			(layer "B.Fab")
		)
		(fp_line
			(start 0.12065 -0.305054)
			(end 0.12065 -0.2794)
			(stroke
				(width 0.1)
				(type default)
			)
			(layer "B.Fab")
		)
		(fp_line
			(start -0.120396 0.3048)
			(end -0.120396 0.2794)
			(stroke
				(width 0.1)
				(type default)
			)
			(layer "B.Fab")
		)
		(fp_line
			(start -0.120396 0.2794)
			(end 0.12065 0.2794)
			(stroke
				(width 0.1)
				(type default)
			)
			(layer "B.Fab")
		)
		(fp_line
			(start -0.12065 -0.2794)
			(end -0.12065 -0.3048)
			(stroke
				(width 0.1)
				(type default)
			)
			(layer "B.Fab")
		)
		(fp_line
			(start -0.12065 -0.3048)
			(end -0.67945 -0.3048)
			(stroke
				(width 0.1)
				(type default)
			)
			(layer "B.Fab")
		)
		(fp_line
			(start -0.67945 0.3048)
			(end -0.120396 0.3048)
			(stroke
				(width 0.1)
				(type default)
			)
			(layer "B.Fab")
		)
		(fp_line
			(start -0.67945 -0.3048)
			(end -0.67945 0.3048)
			(stroke
				(width 0.1)
				(type default)
			)
			(layer "B.Fab")
		)
		(pad "1" smd circle
			(at 0.40005 0)
			(size 0 0)
			(layers "B.Cu" "B.Mask" "B.Paste")
			(net "SVID_PVDDCR_CPU0_P0_SVC_R")
		)
		(pad "2" smd circle
			(at -0.40005 0)
			(size 0 0)
			(layers "B.Cu" "B.Mask" "B.Paste")
			(net "SVID_PVDDCR_CPU0_P0_SVC_R1")
		)
	)
	(footprint ""
		(layer "B.Cu")
		(at 420.667688 -193.99631)
		(property "Reference" "R97"
			(at 0 0 0)
			(layer "B.SilkS")
			(hide yes)
			(effects
				(font
					(size 1.27 1.27)
				)
				(justify mirror)
			)
		)
		(property "Value" ""
			(at 0 0 0)
			(layer "B.Fab")
			(effects
				(font
					(size 1.27 1.27)
				)
				(justify mirror)
			)
		)
		(duplicate_pad_numbers_are_jumpers no)
		(fp_line
			(start -0.7874 -0.4064)
			(end -0.7874 0.4064)
			(stroke
				(width 0.1524)
				(type default)
			)
			(layer "B.SilkS")
		)
		(fp_line
			(start -0.7874 0.4064)
			(end 0.7874 0.4064)
			(stroke
				(width 0.1524)
				(type default)
			)
			(layer "B.SilkS")
		)
		(fp_line
			(start 0.7874 -0.4064)
			(end -0.7874 -0.4064)
			(stroke
				(width 0.1524)
				(type default)
			)
			(layer "B.SilkS")
		)
		(fp_line
			(start 0.7874 0.4064)
			(end 0.7874 -0.4064)
			(stroke
				(width 0.1524)
				(type default)
			)
			(layer "B.SilkS")
		)
		(fp_line
			(start -0.67945 -0.3048)
			(end -0.67945 0.3048)
			(stroke
				(width 0.1)
				(type default)
			)
			(layer "B.Fab")
		)
		(fp_line
			(start -0.67945 0.3048)
			(end -0.120396 0.3048)
			(stroke
				(width 0.1)
				(type default)
			)
			(layer "B.Fab")
		)
		(fp_line
			(start -0.12065 -0.3048)
			(end -0.67945 -0.3048)
			(stroke
				(width 0.1)
				(type default)
			)
			(layer "B.Fab")
		)
		(fp_line
			(start -0.12065 -0.2794)
			(end -0.12065 -0.3048)
			(stroke
				(width 0.1)
				(type default)
			)
			(layer "B.Fab")
		)
		(fp_line
			(start -0.120396 0.2794)
			(end 0.12065 0.2794)
			(stroke
				(width 0.1)
				(type default)
			)
			(layer "B.Fab")
		)
		(fp_line
			(start -0.120396 0.3048)
			(end -0.120396 0.2794)
			(stroke
				(width 0.1)
				(type default)
			)
			(layer "B.Fab")
		)
		(fp_line
			(start 0.12065 -0.305054)
			(end 0.12065 -0.2794)
			(stroke
				(width 0.1)
				(type default)
			)
			(layer "B.Fab")
		)
		(fp_line
			(start 0.12065 -0.2794)
			(end -0.12065 -0.2794)
			(stroke
				(width 0.1)
				(type default)
			)
			(layer "B.Fab")
		)
		(fp_line
			(start 0.12065 0.2794)
			(end 0.12065 0.3048)
			(stroke
				(width 0.1)
				(type default)
			)
			(layer "B.Fab")
		)
		(fp_line
			(start 0.12065 0.3048)
			(end 0.67945 0.3048)
			(stroke
				(width 0.1)
				(type default)
			)
			(layer "B.Fab")
		)
		(fp_line
			(start 0.67945 -0.305054)
			(end 0.12065 -0.305054)
			(stroke
				(width 0.1)
				(type default)
			)
			(layer "B.Fab")
		)
		(fp_line
			(start 0.67945 0.3048)
			(end 0.67945 -0.305054)
			(stroke
				(width 0.1)
				(type default)
			)
			(layer "B.Fab")
		)
		(pad "1" smd circle
			(at 0.40005 0 180)
			(size 0 0)
			(layers "B.Cu" "B.Mask" "B.Paste")
			(net "P3V3")
		)
		(pad "2" smd circle
			(at -0.40005 0 180)
			(size 0 0)
			(layers "B.Cu" "B.Mask" "B.Paste")
			(net "PWRGD_CHH_CPU0_DIMM")
		)
	)
	(footprint ""
		(layer "B.Cu")
		(at 389.845296 -398.942052 90)
		(property "Reference" "C1040"
			(at 0 0 90)
			(layer "B.SilkS")
			(hide yes)
			(effects
				(font
					(size 1.27 1.27)
				)
				(justify mirror)
			)
		)
		(property "Value" ""
			(at 0 0 90)
			(layer "B.Fab")
			(effects
				(font
					(size 1.27 1.27)
				)
				(justify mirror)
			)
		)
		(duplicate_pad_numbers_are_jumpers no)
		(fp_line
			(start 0.7874 -0.4064)
			(end -0.7874 -0.4064)
			(stroke
				(width 0.1524)
				(type default)
			)
			(layer "B.SilkS")
		)
		(fp_line
			(start -0.7874 -0.4064)
			(end -0.7874 0.4064)
			(stroke
				(width 0.1524)
				(type default)
			)
			(layer "B.SilkS")
		)
		(fp_line
			(start 0.7874 0.4064)
			(end 0.7874 -0.4064)
			(stroke
				(width 0.1524)
				(type default)
			)
			(layer "B.SilkS")
		)
		(fp_line
			(start -0.7874 0.4064)
			(end 0.7874 0.4064)
			(stroke
				(width 0.1524)
				(type default)
			)
			(layer "B.SilkS")
		)
		(fp_line
			(start 0.67945 -0.305054)
			(end 0.12065 -0.305054)
			(stroke
				(width 0.1)
				(type default)
			)
			(layer "B.Fab")
		)
		(fp_line
			(start 0.12065 -0.305054)
			(end 0.12065 -0.2794)
			(stroke
				(width 0.1)
				(type default)
			)
			(layer "B.Fab")
		)
		(fp_line
			(start -0.12065 -0.3048)
			(end -0.67945 -0.3048)
			(stroke
				(width 0.1)
				(type default)
			)
			(layer "B.Fab")
		)
		(fp_line
			(start -0.67945 -0.3048)
			(end -0.67945 0.3048)
			(stroke
				(width 0.1)
				(type default)
			)
			(layer "B.Fab")
		)
		(fp_line
			(start 0.12065 -0.2794)
			(end -0.12065 -0.2794)
			(stroke
				(width 0.1)
				(type default)
			)
			(layer "B.Fab")
		)
		(fp_line
			(start -0.12065 -0.2794)
			(end -0.12065 -0.3048)
			(stroke
				(width 0.1)
				(type default)
			)
			(layer "B.Fab")
		)
		(fp_line
			(start 0.12065 0.2794)
			(end 0.12065 0.3048)
			(stroke
				(width 0.1)
				(type default)
			)
			(layer "B.Fab")
		)
		(fp_line
			(start -0.120396 0.2794)
			(end 0.12065 0.2794)
			(stroke
				(width 0.1)
				(type default)
			)
			(layer "B.Fab")
		)
		(fp_line
			(start 0.67945 0.3048)
			(end 0.67945 -0.305054)
			(stroke
				(width 0.1)
				(type default)
			)
			(layer "B.Fab")
		)
		(fp_line
			(start 0.12065 0.3048)
			(end 0.67945 0.3048)
			(stroke
				(width 0.1)
				(type default)
			)
			(layer "B.Fab")
		)
		(fp_line
			(start -0.120396 0.3048)
			(end -0.120396 0.2794)
			(stroke
				(width 0.1)
				(type default)
			)
			(layer "B.Fab")
		)
		(fp_line
			(start -0.67945 0.3048)
			(end -0.120396 0.3048)
			(stroke
				(width 0.1)
				(type default)
			)
			(layer "B.Fab")
		)
		(pad "1" smd circle
			(at 0.40005 0 270)
			(size 0 0)
			(layers "B.Cu" "B.Mask" "B.Paste")
			(net "P0V9_CPU0_RT3_2A")
		)
		(pad "2" smd circle
			(at -0.40005 0 270)
			(size 0 0)
			(layers "B.Cu" "B.Mask" "B.Paste")
			(net "GND")
		)
	)
	(footprint ""
		(layer "B.Cu")
		(at 157.026864 -350.289622 180)
		(property "Reference" "R8386"
			(at 0 0 0)
			(layer "B.SilkS")
			(hide yes)
			(effects
				(font
					(size 1.27 1.27)
				)
				(justify mirror)
			)
		)
		(property "Value" ""
			(at 0 0 0)
			(layer "B.Fab")
			(effects
				(font
					(size 1.27 1.27)
				)
				(justify mirror)
			)
		)
		(duplicate_pad_numbers_are_jumpers no)
		(fp_line
			(start 0.7874 0.4064)
			(end 0.7874 -0.4064)
			(stroke
				(width 0.1524)
				(type default)
			)
			(layer "B.SilkS")
		)
		(fp_line
			(start 0.7874 -0.4064)
			(end -0.7874 -0.4064)
			(stroke
				(width 0.1524)
				(type default)
			)
			(layer "B.SilkS")
		)
		(fp_line
			(start -0.7874 0.4064)
			(end 0.7874 0.4064)
			(stroke
				(width 0.1524)
				(type default)
			)
			(layer "B.SilkS")
		)
		(fp_line
			(start -0.7874 -0.4064)
			(end -0.7874 0.4064)
			(stroke
				(width 0.1524)
				(type default)
			)
			(layer "B.SilkS")
		)
		(fp_line
			(start 0.67945 0.3048)
			(end 0.67945 -0.305054)
			(stroke
				(width 0.1)
				(type default)
			)
			(layer "B.Fab")
		)
		(fp_line
			(start 0.67945 -0.305054)
			(end 0.12065 -0.305054)
			(stroke
				(width 0.1)
				(type default)
			)
			(layer "B.Fab")
		)
		(fp_line
			(start 0.12065 0.3048)
			(end 0.67945 0.3048)
			(stroke
				(width 0.1)
				(type default)
			)
			(layer "B.Fab")
		)
		(fp_line
			(start 0.12065 0.2794)
			(end 0.12065 0.3048)
			(stroke
				(width 0.1)
				(type default)
			)
			(layer "B.Fab")
		)
		(fp_line
			(start 0.12065 -0.2794)
			(end -0.12065 -0.2794)
			(stroke
				(width 0.1)
				(type default)
			)
			(layer "B.Fab")
		)
		(fp_line
			(start 0.12065 -0.305054)
			(end 0.12065 -0.2794)
			(stroke
				(width 0.1)
				(type default)
			)
			(layer "B.Fab")
		)
		(fp_line
			(start -0.120396 0.3048)
			(end -0.120396 0.2794)
			(stroke
				(width 0.1)
				(type default)
			)
			(layer "B.Fab")
		)
		(fp_line
			(start -0.120396 0.2794)
			(end 0.12065 0.2794)
			(stroke
				(width 0.1)
				(type default)
			)
			(layer "B.Fab")
		)
		(fp_line
			(start -0.12065 -0.2794)
			(end -0.12065 -0.3048)
			(stroke
				(width 0.1)
				(type default)
			)
			(layer "B.Fab")
		)
		(fp_line
			(start -0.12065 -0.3048)
			(end -0.67945 -0.3048)
			(stroke
				(width 0.1)
				(type default)
			)
			(layer "B.Fab")
		)
		(fp_line
			(start -0.67945 0.3048)
			(end -0.120396 0.3048)
			(stroke
				(width 0.1)
				(type default)
			)
			(layer "B.Fab")
		)
		(fp_line
			(start -0.67945 -0.3048)
			(end -0.67945 0.3048)
			(stroke
				(width 0.1)
				(type default)
			)
			(layer "B.Fab")
		)
		(pad "1" smd circle
			(at 0.40005 0)
			(size 0 0)
			(layers "B.Cu" "B.Mask" "B.Paste")
			(net "PVDD11_S3_P1_EN")
		)
		(pad "2" smd circle
			(at -0.40005 0)
			(size 0 0)
			(layers "B.Cu" "B.Mask" "B.Paste")
			(net "PVDD11_S3_P1_EN_R")
		)
	)
	(footprint ""
		(layer "B.Cu")
		(at 117.896386 -250.892564)
		(property "Reference" "C2414"
			(at 0 0 0)
			(layer "B.SilkS")
			(hide yes)
			(effects
				(font
					(size 1.27 1.27)
				)
				(justify mirror)
			)
		)
		(property "Value" ""
			(at 0 0 0)
			(layer "B.Fab")
			(effects
				(font
					(size 1.27 1.27)
				)
				(justify mirror)
			)
		)
		(duplicate_pad_numbers_are_jumpers no)
		(fp_line
			(start -0.7874 -0.4064)
			(end -0.7874 0.4064)
			(stroke
				(width 0.1524)
				(type default)
			)
			(layer "B.SilkS")
		)
		(fp_line
			(start -0.7874 0.4064)
			(end 0.7874 0.4064)
			(stroke
				(width 0.1524)
				(type default)
			)
			(layer "B.SilkS")
		)
		(fp_line
			(start 0.7874 -0.4064)
			(end -0.7874 -0.4064)
			(stroke
				(width 0.1524)
				(type default)
			)
			(layer "B.SilkS")
		)
		(fp_line
			(start 0.7874 0.4064)
			(end 0.7874 -0.4064)
			(stroke
				(width 0.1524)
				(type default)
			)
			(layer "B.SilkS")
		)
		(fp_line
			(start -0.67945 -0.3048)
			(end -0.67945 0.3048)
			(stroke
				(width 0.1)
				(type default)
			)
			(layer "B.Fab")
		)
		(fp_line
			(start -0.67945 0.3048)
			(end -0.120396 0.3048)
			(stroke
				(width 0.1)
				(type default)
			)
			(layer "B.Fab")
		)
		(fp_line
			(start -0.12065 -0.3048)
			(end -0.67945 -0.3048)
			(stroke
				(width 0.1)
				(type default)
			)
			(layer "B.Fab")
		)
		(fp_line
			(start -0.12065 -0.2794)
			(end -0.12065 -0.3048)
			(stroke
				(width 0.1)
				(type default)
			)
			(layer "B.Fab")
		)
		(fp_line
			(start -0.120396 0.2794)
			(end 0.12065 0.2794)
			(stroke
				(width 0.1)
				(type default)
			)
			(layer "B.Fab")
		)
		(fp_line
			(start -0.120396 0.3048)
			(end -0.120396 0.2794)
			(stroke
				(width 0.1)
				(type default)
			)
			(layer "B.Fab")
		)
		(fp_line
			(start 0.12065 -0.305054)
			(end 0.12065 -0.2794)
			(stroke
				(width 0.1)
				(type default)
			)
			(layer "B.Fab")
		)
		(fp_line
			(start 0.12065 -0.2794)
			(end -0.12065 -0.2794)
			(stroke
				(width 0.1)
				(type default)
			)
			(layer "B.Fab")
		)
		(fp_line
			(start 0.12065 0.2794)
			(end 0.12065 0.3048)
			(stroke
				(width 0.1)
				(type default)
			)
			(layer "B.Fab")
		)
		(fp_line
			(start 0.12065 0.3048)
			(end 0.67945 0.3048)
			(stroke
				(width 0.1)
				(type default)
			)
			(layer "B.Fab")
		)
		(fp_line
			(start 0.67945 -0.305054)
			(end 0.12065 -0.305054)
			(stroke
				(width 0.1)
				(type default)
			)
			(layer "B.Fab")
		)
		(fp_line
			(start 0.67945 0.3048)
			(end 0.67945 -0.305054)
			(stroke
				(width 0.1)
				(type default)
			)
			(layer "B.Fab")
		)
		(pad "1" smd circle
			(at 0.40005 0 180)
			(size 0 0)
			(layers "B.Cu" "B.Mask" "B.Paste")
			(net "PVDDCR_SOC_P1")
		)
		(pad "2" smd circle
			(at -0.40005 0 180)
			(size 0 0)
			(layers "B.Cu" "B.Mask" "B.Paste")
			(net "GND")
		)
	)
	(footprint ""
		(layer "B.Cu")
		(at 239.141 -332.613)
		(property "Reference" "R849"
			(at 0 0 0)
			(layer "B.SilkS")
			(hide yes)
			(effects
				(font
					(size 1.27 1.27)
				)
				(justify mirror)
			)
		)
		(property "Value" ""
			(at 0 0 0)
			(layer "B.Fab")
			(effects
				(font
					(size 1.27 1.27)
				)
				(justify mirror)
			)
		)
		(duplicate_pad_numbers_are_jumpers no)
		(fp_line
			(start -0.32512 -0.175006)
			(end -0.32512 0.175006)
			(stroke
				(width 0.1)
				(type default)
			)
			(layer "B.Fab")
		)
		(fp_line
			(start -0.32512 0.175006)
			(end 0.32512 0.175006)
			(stroke
				(width 0.1)
				(type default)
			)
			(layer "B.Fab")
		)
		(fp_line
			(start 0.32512 -0.175006)
			(end -0.32512 -0.175006)
			(stroke
				(width 0.1)
				(type default)
			)
			(layer "B.Fab")
		)
		(fp_line
			(start 0.32512 0.175006)
			(end 0.32512 -0.175006)
			(stroke
				(width 0.1)
				(type default)
			)
			(layer "B.Fab")
		)
		(pad "1" smd rect
			(at 0.2667 0 180)
			(size 0.3048 0.381)
			(layers "B.Cu" "B.Mask" "B.Paste")
			(net "RST_SMB_RT_ROM_R1_N")
		)
		(pad "2" smd rect
			(at -0.2667 0)
			(size 0.3048 0.381)
			(layers "B.Cu" "B.Mask" "B.Paste")
			(net "GND")
		)
	)
	(footprint ""
		(layer "B.Cu")
		(at 372.937278 -143.504158)
		(property "Reference" "C465"
			(at 0 0 0)
			(layer "B.SilkS")
			(hide yes)
			(effects
				(font
					(size 1.27 1.27)
				)
				(justify mirror)
			)
		)
		(property "Value" ""
			(at 0 0 0)
			(layer "B.Fab")
			(effects
				(font
					(size 1.27 1.27)
				)
				(justify mirror)
			)
		)
		(duplicate_pad_numbers_are_jumpers no)
		(fp_line
			(start -0.7874 -0.4064)
			(end -0.7874 0.4064)
			(stroke
				(width 0.1524)
				(type default)
			)
			(layer "B.SilkS")
		)
		(fp_line
			(start -0.7874 0.4064)
			(end 0.7874 0.4064)
			(stroke
				(width 0.1524)
				(type default)
			)
			(layer "B.SilkS")
		)
		(fp_line
			(start 0.7874 -0.4064)
			(end -0.7874 -0.4064)
			(stroke
				(width 0.1524)
				(type default)
			)
			(layer "B.SilkS")
		)
		(fp_line
			(start 0.7874 0.4064)
			(end 0.7874 -0.4064)
			(stroke
				(width 0.1524)
				(type default)
			)
			(layer "B.SilkS")
		)
		(fp_line
			(start -0.67945 -0.3048)
			(end -0.67945 0.3048)
			(stroke
				(width 0.1)
				(type default)
			)
			(layer "B.Fab")
		)
		(fp_line
			(start -0.67945 0.3048)
			(end -0.120396 0.3048)
			(stroke
				(width 0.1)
				(type default)
			)
			(layer "B.Fab")
		)
		(fp_line
			(start -0.12065 -0.3048)
			(end -0.67945 -0.3048)
			(stroke
				(width 0.1)
				(type default)
			)
			(layer "B.Fab")
		)
		(fp_line
			(start -0.12065 -0.2794)
			(end -0.12065 -0.3048)
			(stroke
				(width 0.1)
				(type default)
			)
			(layer "B.Fab")
		)
		(fp_line
			(start -0.120396 0.2794)
			(end 0.12065 0.2794)
			(stroke
				(width 0.1)
				(type default)
			)
			(layer "B.Fab")
		)
		(fp_line
			(start -0.120396 0.3048)
			(end -0.120396 0.2794)
			(stroke
				(width 0.1)
				(type default)
			)
			(layer "B.Fab")
		)
		(fp_line
			(start 0.12065 -0.305054)
			(end 0.12065 -0.2794)
			(stroke
				(width 0.1)
				(type default)
			)
			(layer "B.Fab")
		)
		(fp_line
			(start 0.12065 -0.2794)
			(end -0.12065 -0.2794)
			(stroke
				(width 0.1)
				(type default)
			)
			(layer "B.Fab")
		)
		(fp_line
			(start 0.12065 0.2794)
			(end 0.12065 0.3048)
			(stroke
				(width 0.1)
				(type default)
			)
			(layer "B.Fab")
		)
		(fp_line
			(start 0.12065 0.3048)
			(end 0.67945 0.3048)
			(stroke
				(width 0.1)
				(type default)
			)
			(layer "B.Fab")
		)
		(fp_line
			(start 0.67945 -0.305054)
			(end 0.12065 -0.305054)
			(stroke
				(width 0.1)
				(type default)
			)
			(layer "B.Fab")
		)
		(fp_line
			(start 0.67945 0.3048)
			(end 0.67945 -0.305054)
			(stroke
				(width 0.1)
				(type default)
			)
			(layer "B.Fab")
		)
		(pad "1" smd circle
			(at 0.40005 0 180)
			(size 0 0)
			(layers "B.Cu" "B.Mask" "B.Paste")
			(net "PWRGD_PVDDCR_SOC_P0_R")
		)
		(pad "2" smd circle
			(at -0.40005 0 180)
			(size 0 0)
			(layers "B.Cu" "B.Mask" "B.Paste")
			(net "GND")
		)
	)
	(footprint ""
		(layer "B.Cu")
		(at 270.247872 -338.127086 -90)
		(property "Reference" "PR410"
			(at 0 0 90)
			(layer "B.SilkS")
			(hide yes)
			(effects
				(font
					(size 1.27 1.27)
				)
				(justify mirror)
			)
		)
		(property "Value" ""
			(at 0 0 90)
			(layer "B.Fab")
			(effects
				(font
					(size 1.27 1.27)
				)
				(justify mirror)
			)
		)
		(duplicate_pad_numbers_are_jumpers no)
		(fp_line
			(start -0.7874 0.4064)
			(end 0.7874 0.4064)
			(stroke
				(width 0.1524)
				(type default)
			)
			(layer "B.SilkS")
		)
		(fp_line
			(start 0.7874 0.4064)
			(end 0.7874 -0.4064)
			(stroke
				(width 0.1524)
				(type default)
			)
			(layer "B.SilkS")
		)
		(fp_line
			(start -0.7874 -0.4064)
			(end -0.7874 0.4064)
			(stroke
				(width 0.1524)
				(type default)
			)
			(layer "B.SilkS")
		)
		(fp_line
			(start 0.7874 -0.4064)
			(end -0.7874 -0.4064)
			(stroke
				(width 0.1524)
				(type default)
			)
			(layer "B.SilkS")
		)
		(fp_line
			(start -0.67945 0.3048)
			(end -0.120396 0.3048)
			(stroke
				(width 0.1)
				(type default)
			)
			(layer "B.Fab")
		)
		(fp_line
			(start -0.120396 0.3048)
			(end -0.120396 0.2794)
			(stroke
				(width 0.1)
				(type default)
			)
			(layer "B.Fab")
		)
		(fp_line
			(start 0.12065 0.3048)
			(end 0.67945 0.3048)
			(stroke
				(width 0.1)
				(type default)
			)
			(layer "B.Fab")
		)
		(fp_line
			(start 0.67945 0.3048)
			(end 0.67945 -0.305054)
			(stroke
				(width 0.1)
				(type default)
			)
			(layer "B.Fab")
		)
		(fp_line
			(start -0.120396 0.2794)
			(end 0.12065 0.2794)
			(stroke
				(width 0.1)
				(type default)
			)
			(layer "B.Fab")
		)
		(fp_line
			(start 0.12065 0.2794)
			(end 0.12065 0.3048)
			(stroke
				(width 0.1)
				(type default)
			)
			(layer "B.Fab")
		)
		(fp_line
			(start -0.12065 -0.2794)
			(end -0.12065 -0.3048)
			(stroke
				(width 0.1)
				(type default)
			)
			(layer "B.Fab")
		)
		(fp_line
			(start 0.12065 -0.2794)
			(end -0.12065 -0.2794)
			(stroke
				(width 0.1)
				(type default)
			)
			(layer "B.Fab")
		)
		(fp_line
			(start -0.67945 -0.3048)
			(end -0.67945 0.3048)
			(stroke
				(width 0.1)
				(type default)
			)
			(layer "B.Fab")
		)
		(fp_line
			(start -0.12065 -0.3048)
			(end -0.67945 -0.3048)
			(stroke
				(width 0.1)
				(type default)
			)
			(layer "B.Fab")
		)
		(fp_line
			(start 0.12065 -0.305054)
			(end 0.12065 -0.2794)
			(stroke
				(width 0.1)
				(type default)
			)
			(layer "B.Fab")
		)
		(fp_line
			(start 0.67945 -0.305054)
			(end 0.12065 -0.305054)
			(stroke
				(width 0.1)
				(type default)
			)
			(layer "B.Fab")
		)
		(pad "1" smd circle
			(at 0.40005 0 90)
			(size 0 0)
			(layers "B.Cu" "B.Mask" "B.Paste")
			(net "PVDDIO_P0")
		)
		(pad "2" smd circle
			(at -0.40005 0 90)
			(size 0 0)
			(layers "B.Cu" "B.Mask" "B.Paste")
			(net "GND")
		)
	)
	(footprint ""
		(layer "B.Cu")
		(at 105.960164 -258.405376 180)
		(property "Reference" "C2479"
			(at 0 0 0)
			(layer "B.SilkS")
			(hide yes)
			(effects
				(font
					(size 1.27 1.27)
				)
				(justify mirror)
			)
		)
		(property "Value" ""
			(at 0 0 0)
			(layer "B.Fab")
			(effects
				(font
					(size 1.27 1.27)
				)
				(justify mirror)
			)
		)
		(duplicate_pad_numbers_are_jumpers no)
		(fp_line
			(start 0.7874 0.4064)
			(end 0.7874 -0.4064)
			(stroke
				(width 0.1524)
				(type default)
			)
			(layer "B.SilkS")
		)
		(fp_line
			(start 0.7874 -0.4064)
			(end -0.7874 -0.4064)
			(stroke
				(width 0.1524)
				(type default)
			)
			(layer "B.SilkS")
		)
		(fp_line
			(start -0.7874 0.4064)
			(end 0.7874 0.4064)
			(stroke
				(width 0.1524)
				(type default)
			)
			(layer "B.SilkS")
		)
		(fp_line
			(start -0.7874 -0.4064)
			(end -0.7874 0.4064)
			(stroke
				(width 0.1524)
				(type default)
			)
			(layer "B.SilkS")
		)
		(fp_line
			(start 0.67945 0.3048)
			(end 0.67945 -0.305054)
			(stroke
				(width 0.1)
				(type default)
			)
			(layer "B.Fab")
		)
		(fp_line
			(start 0.67945 -0.305054)
			(end 0.12065 -0.305054)
			(stroke
				(width 0.1)
				(type default)
			)
			(layer "B.Fab")
		)
		(fp_line
			(start 0.12065 0.3048)
			(end 0.67945 0.3048)
			(stroke
				(width 0.1)
				(type default)
			)
			(layer "B.Fab")
		)
		(fp_line
			(start 0.12065 0.2794)
			(end 0.12065 0.3048)
			(stroke
				(width 0.1)
				(type default)
			)
			(layer "B.Fab")
		)
		(fp_line
			(start 0.12065 -0.2794)
			(end -0.12065 -0.2794)
			(stroke
				(width 0.1)
				(type default)
			)
			(layer "B.Fab")
		)
		(fp_line
			(start 0.12065 -0.305054)
			(end 0.12065 -0.2794)
			(stroke
				(width 0.1)
				(type default)
			)
			(layer "B.Fab")
		)
		(fp_line
			(start -0.120396 0.3048)
			(end -0.120396 0.2794)
			(stroke
				(width 0.1)
				(type default)
			)
			(layer "B.Fab")
		)
		(fp_line
			(start -0.120396 0.2794)
			(end 0.12065 0.2794)
			(stroke
				(width 0.1)
				(type default)
			)
			(layer "B.Fab")
		)
		(fp_line
			(start -0.12065 -0.2794)
			(end -0.12065 -0.3048)
			(stroke
				(width 0.1)
				(type default)
			)
			(layer "B.Fab")
		)
		(fp_line
			(start -0.12065 -0.3048)
			(end -0.67945 -0.3048)
			(stroke
				(width 0.1)
				(type default)
			)
			(layer "B.Fab")
		)
		(fp_line
			(start -0.67945 0.3048)
			(end -0.120396 0.3048)
			(stroke
				(width 0.1)
				(type default)
			)
			(layer "B.Fab")
		)
		(fp_line
			(start -0.67945 -0.3048)
			(end -0.67945 0.3048)
			(stroke
				(width 0.1)
				(type default)
			)
			(layer "B.Fab")
		)
		(pad "1" smd circle
			(at 0.40005 0)
			(size 0 0)
			(layers "B.Cu" "B.Mask" "B.Paste")
			(net "PVDDIO_P1")
		)
		(pad "2" smd circle
			(at -0.40005 0)
			(size 0 0)
			(layers "B.Cu" "B.Mask" "B.Paste")
			(net "GND")
		)
	)
	(footprint ""
		(layer "B.Cu")
		(at 144.932654 -315.49467 180)
		(property "Reference" "R547"
			(at 0 0 0)
			(layer "B.SilkS")
			(hide yes)
			(effects
				(font
					(size 1.27 1.27)
				)
				(justify mirror)
			)
		)
		(property "Value" ""
			(at 0 0 0)
			(layer "B.Fab")
			(effects
				(font
					(size 1.27 1.27)
				)
				(justify mirror)
			)
		)
		(duplicate_pad_numbers_are_jumpers no)
		(fp_line
			(start 0.7874 0.4064)
			(end 0.7874 -0.4064)
			(stroke
				(width 0.1524)
				(type default)
			)
			(layer "B.SilkS")
		)
		(fp_line
			(start 0.7874 -0.4064)
			(end -0.7874 -0.4064)
			(stroke
				(width 0.1524)
				(type default)
			)
			(layer "B.SilkS")
		)
		(fp_line
			(start -0.7874 0.4064)
			(end 0.7874 0.4064)
			(stroke
				(width 0.1524)
				(type default)
			)
			(layer "B.SilkS")
		)
		(fp_line
			(start -0.7874 -0.4064)
			(end -0.7874 0.4064)
			(stroke
				(width 0.1524)
				(type default)
			)
			(layer "B.SilkS")
		)
		(fp_line
			(start 0.67945 0.3048)
			(end 0.67945 -0.305054)
			(stroke
				(width 0.1)
				(type default)
			)
			(layer "B.Fab")
		)
		(fp_line
			(start 0.67945 -0.305054)
			(end 0.12065 -0.305054)
			(stroke
				(width 0.1)
				(type default)
			)
			(layer "B.Fab")
		)
		(fp_line
			(start 0.12065 0.3048)
			(end 0.67945 0.3048)
			(stroke
				(width 0.1)
				(type default)
			)
			(layer "B.Fab")
		)
		(fp_line
			(start 0.12065 0.2794)
			(end 0.12065 0.3048)
			(stroke
				(width 0.1)
				(type default)
			)
			(layer "B.Fab")
		)
		(fp_line
			(start 0.12065 -0.2794)
			(end -0.12065 -0.2794)
			(stroke
				(width 0.1)
				(type default)
			)
			(layer "B.Fab")
		)
		(fp_line
			(start 0.12065 -0.305054)
			(end 0.12065 -0.2794)
			(stroke
				(width 0.1)
				(type default)
			)
			(layer "B.Fab")
		)
		(fp_line
			(start -0.120396 0.3048)
			(end -0.120396 0.2794)
			(stroke
				(width 0.1)
				(type default)
			)
			(layer "B.Fab")
		)
		(fp_line
			(start -0.120396 0.2794)
			(end 0.12065 0.2794)
			(stroke
				(width 0.1)
				(type default)
			)
			(layer "B.Fab")
		)
		(fp_line
			(start -0.12065 -0.2794)
			(end -0.12065 -0.3048)
			(stroke
				(width 0.1)
				(type default)
			)
			(layer "B.Fab")
		)
		(fp_line
			(start -0.12065 -0.3048)
			(end -0.67945 -0.3048)
			(stroke
				(width 0.1)
				(type default)
			)
			(layer "B.Fab")
		)
		(fp_line
			(start -0.67945 0.3048)
			(end -0.120396 0.3048)
			(stroke
				(width 0.1)
				(type default)
			)
			(layer "B.Fab")
		)
		(fp_line
			(start -0.67945 -0.3048)
			(end -0.67945 0.3048)
			(stroke
				(width 0.1)
				(type default)
			)
			(layer "B.Fab")
		)
		(pad "1" smd circle
			(at 0.40005 0)
			(size 0 0)
			(layers "B.Cu" "B.Mask" "B.Paste")
			(net "FM_CPU1_BMC_RST_N")
		)
		(pad "2" smd circle
			(at -0.40005 0)
			(size 0 0)
			(layers "B.Cu" "B.Mask" "B.Paste")
			(net "PVDD18_S5_P1")
		)
	)
	(footprint ""
		(layer "B.Cu")
		(at 121.706386 -250.892564)
		(property "Reference" "C2449"
			(at 0 0 0)
			(layer "B.SilkS")
			(hide yes)
			(effects
				(font
					(size 1.27 1.27)
				)
				(justify mirror)
			)
		)
		(property "Value" ""
			(at 0 0 0)
			(layer "B.Fab")
			(effects
				(font
					(size 1.27 1.27)
				)
				(justify mirror)
			)
		)
		(duplicate_pad_numbers_are_jumpers no)
		(fp_line
			(start -0.7874 -0.4064)
			(end -0.7874 0.4064)
			(stroke
				(width 0.1524)
				(type default)
			)
			(layer "B.SilkS")
		)
		(fp_line
			(start -0.7874 0.4064)
			(end 0.7874 0.4064)
			(stroke
				(width 0.1524)
				(type default)
			)
			(layer "B.SilkS")
		)
		(fp_line
			(start 0.7874 -0.4064)
			(end -0.7874 -0.4064)
			(stroke
				(width 0.1524)
				(type default)
			)
			(layer "B.SilkS")
		)
		(fp_line
			(start 0.7874 0.4064)
			(end 0.7874 -0.4064)
			(stroke
				(width 0.1524)
				(type default)
			)
			(layer "B.SilkS")
		)
		(fp_line
			(start -0.67945 -0.3048)
			(end -0.67945 0.3048)
			(stroke
				(width 0.1)
				(type default)
			)
			(layer "B.Fab")
		)
		(fp_line
			(start -0.67945 0.3048)
			(end -0.120396 0.3048)
			(stroke
				(width 0.1)
				(type default)
			)
			(layer "B.Fab")
		)
		(fp_line
			(start -0.12065 -0.3048)
			(end -0.67945 -0.3048)
			(stroke
				(width 0.1)
				(type default)
			)
			(layer "B.Fab")
		)
		(fp_line
			(start -0.12065 -0.2794)
			(end -0.12065 -0.3048)
			(stroke
				(width 0.1)
				(type default)
			)
			(layer "B.Fab")
		)
		(fp_line
			(start -0.120396 0.2794)
			(end 0.12065 0.2794)
			(stroke
				(width 0.1)
				(type default)
			)
			(layer "B.Fab")
		)
		(fp_line
			(start -0.120396 0.3048)
			(end -0.120396 0.2794)
			(stroke
				(width 0.1)
				(type default)
			)
			(layer "B.Fab")
		)
		(fp_line
			(start 0.12065 -0.305054)
			(end 0.12065 -0.2794)
			(stroke
				(width 0.1)
				(type default)
			)
			(layer "B.Fab")
		)
		(fp_line
			(start 0.12065 -0.2794)
			(end -0.12065 -0.2794)
			(stroke
				(width 0.1)
				(type default)
			)
			(layer "B.Fab")
		)
		(fp_line
			(start 0.12065 0.2794)
			(end 0.12065 0.3048)
			(stroke
				(width 0.1)
				(type default)
			)
			(layer "B.Fab")
		)
		(fp_line
			(start 0.12065 0.3048)
			(end 0.67945 0.3048)
			(stroke
				(width 0.1)
				(type default)
			)
			(layer "B.Fab")
		)
		(fp_line
			(start 0.67945 -0.305054)
			(end 0.12065 -0.305054)
			(stroke
				(width 0.1)
				(type default)
			)
			(layer "B.Fab")
		)
		(fp_line
			(start 0.67945 0.3048)
			(end 0.67945 -0.305054)
			(stroke
				(width 0.1)
				(type default)
			)
			(layer "B.Fab")
		)
		(pad "1" smd circle
			(at 0.40005 0 180)
			(size 0 0)
			(layers "B.Cu" "B.Mask" "B.Paste")
			(net "PVDDCR_SOC_P1")
		)
		(pad "2" smd circle
			(at -0.40005 0 180)
			(size 0 0)
			(layers "B.Cu" "B.Mask" "B.Paste")
			(net "GND")
		)
	)
	(footprint ""
		(layer "B.Cu")
		(at 228.479604 -327.56602 180)
		(property "Reference" "C1089"
			(at 0 0 0)
			(layer "B.SilkS")
			(hide yes)
			(effects
				(font
					(size 1.27 1.27)
				)
				(justify mirror)
			)
		)
		(property "Value" ""
			(at 0 0 0)
			(layer "B.Fab")
			(effects
				(font
					(size 1.27 1.27)
				)
				(justify mirror)
			)
		)
		(duplicate_pad_numbers_are_jumpers no)
		(fp_line
			(start 0.7874 0.4064)
			(end 0.7874 -0.4064)
			(stroke
				(width 0.1524)
				(type default)
			)
			(layer "B.SilkS")
		)
		(fp_line
			(start 0.7874 -0.4064)
			(end -0.7874 -0.4064)
			(stroke
				(width 0.1524)
				(type default)
			)
			(layer "B.SilkS")
		)
		(fp_line
			(start -0.7874 0.4064)
			(end 0.7874 0.4064)
			(stroke
				(width 0.1524)
				(type default)
			)
			(layer "B.SilkS")
		)
		(fp_line
			(start -0.7874 -0.4064)
			(end -0.7874 0.4064)
			(stroke
				(width 0.1524)
				(type default)
			)
			(layer "B.SilkS")
		)
		(fp_line
			(start 0.67945 0.3048)
			(end 0.67945 -0.305054)
			(stroke
				(width 0.1)
				(type default)
			)
			(layer "B.Fab")
		)
		(fp_line
			(start 0.67945 -0.305054)
			(end 0.12065 -0.305054)
			(stroke
				(width 0.1)
				(type default)
			)
			(layer "B.Fab")
		)
		(fp_line
			(start 0.12065 0.3048)
			(end 0.67945 0.3048)
			(stroke
				(width 0.1)
				(type default)
			)
			(layer "B.Fab")
		)
		(fp_line
			(start 0.12065 0.2794)
			(end 0.12065 0.3048)
			(stroke
				(width 0.1)
				(type default)
			)
			(layer "B.Fab")
		)
		(fp_line
			(start 0.12065 -0.2794)
			(end -0.12065 -0.2794)
			(stroke
				(width 0.1)
				(type default)
			)
			(layer "B.Fab")
		)
		(fp_line
			(start 0.12065 -0.305054)
			(end 0.12065 -0.2794)
			(stroke
				(width 0.1)
				(type default)
			)
			(layer "B.Fab")
		)
		(fp_line
			(start -0.120396 0.3048)
			(end -0.120396 0.2794)
			(stroke
				(width 0.1)
				(type default)
			)
			(layer "B.Fab")
		)
		(fp_line
			(start -0.120396 0.2794)
			(end 0.12065 0.2794)
			(stroke
				(width 0.1)
				(type default)
			)
			(layer "B.Fab")
		)
		(fp_line
			(start -0.12065 -0.2794)
			(end -0.12065 -0.3048)
			(stroke
				(width 0.1)
				(type default)
			)
			(layer "B.Fab")
		)
		(fp_line
			(start -0.12065 -0.3048)
			(end -0.67945 -0.3048)
			(stroke
				(width 0.1)
				(type default)
			)
			(layer "B.Fab")
		)
		(fp_line
			(start -0.67945 0.3048)
			(end -0.120396 0.3048)
			(stroke
				(width 0.1)
				(type default)
			)
			(layer "B.Fab")
		)
		(fp_line
			(start -0.67945 -0.3048)
			(end -0.67945 0.3048)
			(stroke
				(width 0.1)
				(type default)
			)
			(layer "B.Fab")
		)
		(pad "1" smd circle
			(at 0.40005 0)
			(size 0 0)
			(layers "B.Cu" "B.Mask" "B.Paste")
			(net "PVDD_33_S5_ADC_TIC")
		)
		(pad "2" smd circle
			(at -0.40005 0)
			(size 0 0)
			(layers "B.Cu" "B.Mask" "B.Paste")
			(net "GND")
		)
	)
	(footprint ""
		(layer "B.Cu")
		(at 109.22 -415.036 -90)
		(property "Reference" "Q148"
			(at 4.3942 0.12827 270)
			(unlocked yes)
			(layer "B.SilkS")
			(effects
				(font
					(size 0.7874 0.5842)
					(thickness 0.1524)
				)
				(justify left mirror)
			)
		)
		(property "Value" ""
			(at 0 0 90)
			(layer "B.Fab")
			(effects
				(font
					(size 1.27 1.27)
				)
				(justify mirror)
			)
		)
		(duplicate_pad_numbers_are_jumpers no)
		(fp_line
			(start -1.332738 1.100074)
			(end 1.332738 1.100074)
			(stroke
				(width 0.1524)
				(type default)
			)
			(layer "B.SilkS")
		)
		(fp_line
			(start 1.332738 1.100074)
			(end 1.332738 -1.100074)
			(stroke
				(width 0.1524)
				(type default)
			)
			(layer "B.SilkS")
		)
		(fp_line
			(start 0 -0.541274)
			(end -0.4826 -1.100074)
			(stroke
				(width 0.1524)
				(type default)
			)
			(layer "B.SilkS")
		)
		(fp_line
			(start -1.332738 -1.100074)
			(end -1.332738 1.100074)
			(stroke
				(width 0.1524)
				(type default)
			)
			(layer "B.SilkS")
		)
		(fp_line
			(start -0.4826 -1.100074)
			(end -1.332738 -1.100074)
			(stroke
				(width 0.1524)
				(type default)
			)
			(layer "B.SilkS")
		)
		(fp_line
			(start 0.4826 -1.100074)
			(end 0 -0.541274)
			(stroke
				(width 0.1524)
				(type default)
			)
			(layer "B.SilkS")
		)
		(fp_line
			(start 1.332738 -1.100074)
			(end 0.4826 -1.100074)
			(stroke
				(width 0.1524)
				(type default)
			)
			(layer "B.SilkS")
		)
		(fp_poly
			(pts
				(xy 0.513334 -1.311148) (xy 0.295402 -2.065274) (xy -0.220726 -1.589278)
			)
			(stroke
				(width 0)
				(type default)
			)
			(fill yes)
			(layer "B.SilkS")
		)
		(fp_line
			(start -0.674878 1.100074)
			(end 0.674878 1.100074)
			(stroke
				(width 0.1)
				(type default)
			)
			(layer "B.Fab")
		)
		(fp_line
			(start 0.674878 1.100074)
			(end 0.674878 -1.100074)
			(stroke
				(width 0.1)
				(type default)
			)
			(layer "B.Fab")
		)
		(fp_line
			(start -0.674878 -1.100074)
			(end -0.674878 1.100074)
			(stroke
				(width 0.1)
				(type default)
			)
			(layer "B.Fab")
		)
		(fp_line
			(start 0.674878 -1.100074)
			(end -0.674878 -1.100074)
			(stroke
				(width 0.1)
				(type default)
			)
			(layer "B.Fab")
		)
		(fp_poly
			(pts
				(xy 2.2352 -0.298958) (xy 2.2352 -1.001014) (xy 1.533144 -0.649986)
			)
			(stroke
				(width 0)
				(type default)
			)
			(fill yes)
			(layer "B.Fab")
		)
		(pad "1" smd rect
			(at 0.94996 -0.649986)
			(size 0.4318 0.508)
			(layers "B.Cu" "B.Mask" "B.Paste")
			(net "GND")
		)
		(pad "2" smd rect
			(at 0.94996 0)
			(size 0.4318 0.508)
			(layers "B.Cu" "B.Mask" "B.Paste")
			(net "HGX_DETECT_N")
		)
		(pad "3" smd rect
			(at 0.94996 0.649986)
			(size 0.4318 0.508)
			(layers "B.Cu" "B.Mask" "B.Paste")
			(net "HGX_DETECT_N_ISO")
		)
		(pad "4" smd rect
			(at -0.94996 0.649986)
			(size 0.4318 0.508)
			(layers "B.Cu" "B.Mask" "B.Paste")
			(net "GND")
		)
		(pad "5" smd rect
			(at -0.94996 0)
			(size 0.4318 0.508)
			(layers "B.Cu" "B.Mask" "B.Paste")
			(net "HGX_DETECT")
		)
		(pad "6" smd rect
			(at -0.94996 -0.649986)
			(size 0.4318 0.508)
			(layers "B.Cu" "B.Mask" "B.Paste")
			(net "HGX_DETECT")
		)
	)
	(footprint ""
		(layer "B.Cu")
		(at 372.878604 -395.148562 90)
		(property "Reference" "C1013"
			(at 0 0 90)
			(layer "B.SilkS")
			(hide yes)
			(effects
				(font
					(size 1.27 1.27)
				)
				(justify mirror)
			)
		)
		(property "Value" ""
			(at 0 0 90)
			(layer "B.Fab")
			(effects
				(font
					(size 1.27 1.27)
				)
				(justify mirror)
			)
		)
		(duplicate_pad_numbers_are_jumpers no)
		(fp_line
			(start 0.299974 -0.150114)
			(end -0.299974 -0.150114)
			(stroke
				(width 0.1)
				(type default)
			)
			(layer "B.Fab")
		)
		(fp_line
			(start -0.299974 -0.150114)
			(end -0.299974 0.150114)
			(stroke
				(width 0.1)
				(type default)
			)
			(layer "B.Fab")
		)
		(fp_line
			(start 0.299974 0.150114)
			(end 0.299974 -0.150114)
			(stroke
				(width 0.1)
				(type default)
			)
			(layer "B.Fab")
		)
		(fp_line
			(start -0.299974 0.150114)
			(end 0.299974 0.150114)
			(stroke
				(width 0.1)
				(type default)
			)
			(layer "B.Fab")
		)
		(pad "1" smd rect
			(at 0.2667 0 270)
			(size 0.3048 0.381)
			(layers "B.Cu" "B.Mask" "B.Paste")
			(net "P0V9_CPU0_RT3_2A")
		)
		(pad "2" smd rect
			(at -0.2667 0 270)
			(size 0.3048 0.381)
			(layers "B.Cu" "B.Mask" "B.Paste")
			(net "GND")
		)
	)
	(footprint ""
		(layer "B.Cu")
		(at 63.619634 -196.186552 180)
		(property "Reference" "R514"
			(at 0 0 0)
			(layer "B.SilkS")
			(hide yes)
			(effects
				(font
					(size 1.27 1.27)
				)
				(justify mirror)
			)
		)
		(property "Value" ""
			(at 0 0 0)
			(layer "B.Fab")
			(effects
				(font
					(size 1.27 1.27)
				)
				(justify mirror)
			)
		)
		(duplicate_pad_numbers_are_jumpers no)
		(fp_line
			(start 0.7874 0.4064)
			(end 0.7874 -0.4064)
			(stroke
				(width 0.1524)
				(type default)
			)
			(layer "B.SilkS")
		)
		(fp_line
			(start 0.7874 -0.4064)
			(end -0.7874 -0.4064)
			(stroke
				(width 0.1524)
				(type default)
			)
			(layer "B.SilkS")
		)
		(fp_line
			(start -0.7874 0.4064)
			(end 0.7874 0.4064)
			(stroke
				(width 0.1524)
				(type default)
			)
			(layer "B.SilkS")
		)
		(fp_line
			(start -0.7874 -0.4064)
			(end -0.7874 0.4064)
			(stroke
				(width 0.1524)
				(type default)
			)
			(layer "B.SilkS")
		)
		(fp_line
			(start 0.67945 0.3048)
			(end 0.67945 -0.305054)
			(stroke
				(width 0.1)
				(type default)
			)
			(layer "B.Fab")
		)
		(fp_line
			(start 0.67945 -0.305054)
			(end 0.12065 -0.305054)
			(stroke
				(width 0.1)
				(type default)
			)
			(layer "B.Fab")
		)
		(fp_line
			(start 0.12065 0.3048)
			(end 0.67945 0.3048)
			(stroke
				(width 0.1)
				(type default)
			)
			(layer "B.Fab")
		)
		(fp_line
			(start 0.12065 0.2794)
			(end 0.12065 0.3048)
			(stroke
				(width 0.1)
				(type default)
			)
			(layer "B.Fab")
		)
		(fp_line
			(start 0.12065 -0.2794)
			(end -0.12065 -0.2794)
			(stroke
				(width 0.1)
				(type default)
			)
			(layer "B.Fab")
		)
		(fp_line
			(start 0.12065 -0.305054)
			(end 0.12065 -0.2794)
			(stroke
				(width 0.1)
				(type default)
			)
			(layer "B.Fab")
		)
		(fp_line
			(start -0.120396 0.3048)
			(end -0.120396 0.2794)
			(stroke
				(width 0.1)
				(type default)
			)
			(layer "B.Fab")
		)
		(fp_line
			(start -0.120396 0.2794)
			(end 0.12065 0.2794)
			(stroke
				(width 0.1)
				(type default)
			)
			(layer "B.Fab")
		)
		(fp_line
			(start -0.12065 -0.2794)
			(end -0.12065 -0.3048)
			(stroke
				(width 0.1)
				(type default)
			)
			(layer "B.Fab")
		)
		(fp_line
			(start -0.12065 -0.3048)
			(end -0.67945 -0.3048)
			(stroke
				(width 0.1)
				(type default)
			)
			(layer "B.Fab")
		)
		(fp_line
			(start -0.67945 0.3048)
			(end -0.120396 0.3048)
			(stroke
				(width 0.1)
				(type default)
			)
			(layer "B.Fab")
		)
		(fp_line
			(start -0.67945 -0.3048)
			(end -0.67945 0.3048)
			(stroke
				(width 0.1)
				(type default)
			)
			(layer "B.Fab")
		)
		(pad "1" smd circle
			(at 0.40005 0)
			(size 0 0)
			(layers "B.Cu" "B.Mask" "B.Paste")
			(net "P3V3_AUX")
		)
		(pad "2" smd circle
			(at -0.40005 0)
			(size 0 0)
			(layers "B.Cu" "B.Mask" "B.Paste")
			(net "CPU1_CORETYPE1")
		)
	)
	(footprint ""
		(layer "B.Cu")
		(at 303.390808 -398.942052 90)
		(property "Reference" "C561"
			(at 0 0 90)
			(layer "B.SilkS")
			(hide yes)
			(effects
				(font
					(size 1.27 1.27)
				)
				(justify mirror)
			)
		)
		(property "Value" ""
			(at 0 0 90)
			(layer "B.Fab")
			(effects
				(font
					(size 1.27 1.27)
				)
				(justify mirror)
			)
		)
		(duplicate_pad_numbers_are_jumpers no)
		(fp_line
			(start 0.7874 -0.4064)
			(end -0.7874 -0.4064)
			(stroke
				(width 0.1524)
				(type default)
			)
			(layer "B.SilkS")
		)
		(fp_line
			(start -0.7874 -0.4064)
			(end -0.7874 0.4064)
			(stroke
				(width 0.1524)
				(type default)
			)
			(layer "B.SilkS")
		)
		(fp_line
			(start 0.7874 0.4064)
			(end 0.7874 -0.4064)
			(stroke
				(width 0.1524)
				(type default)
			)
			(layer "B.SilkS")
		)
		(fp_line
			(start -0.7874 0.4064)
			(end 0.7874 0.4064)
			(stroke
				(width 0.1524)
				(type default)
			)
			(layer "B.SilkS")
		)
		(fp_line
			(start 0.67945 -0.305054)
			(end 0.12065 -0.305054)
			(stroke
				(width 0.1)
				(type default)
			)
			(layer "B.Fab")
		)
		(fp_line
			(start 0.12065 -0.305054)
			(end 0.12065 -0.2794)
			(stroke
				(width 0.1)
				(type default)
			)
			(layer "B.Fab")
		)
		(fp_line
			(start -0.12065 -0.3048)
			(end -0.67945 -0.3048)
			(stroke
				(width 0.1)
				(type default)
			)
			(layer "B.Fab")
		)
		(fp_line
			(start -0.67945 -0.3048)
			(end -0.67945 0.3048)
			(stroke
				(width 0.1)
				(type default)
			)
			(layer "B.Fab")
		)
		(fp_line
			(start 0.12065 -0.2794)
			(end -0.12065 -0.2794)
			(stroke
				(width 0.1)
				(type default)
			)
			(layer "B.Fab")
		)
		(fp_line
			(start -0.12065 -0.2794)
			(end -0.12065 -0.3048)
			(stroke
				(width 0.1)
				(type default)
			)
			(layer "B.Fab")
		)
		(fp_line
			(start 0.12065 0.2794)
			(end 0.12065 0.3048)
			(stroke
				(width 0.1)
				(type default)
			)
			(layer "B.Fab")
		)
		(fp_line
			(start -0.120396 0.2794)
			(end 0.12065 0.2794)
			(stroke
				(width 0.1)
				(type default)
			)
			(layer "B.Fab")
		)
		(fp_line
			(start 0.67945 0.3048)
			(end 0.67945 -0.305054)
			(stroke
				(width 0.1)
				(type default)
			)
			(layer "B.Fab")
		)
		(fp_line
			(start 0.12065 0.3048)
			(end 0.67945 0.3048)
			(stroke
				(width 0.1)
				(type default)
			)
			(layer "B.Fab")
		)
		(fp_line
			(start -0.120396 0.3048)
			(end -0.120396 0.2794)
			(stroke
				(width 0.1)
				(type default)
			)
			(layer "B.Fab")
		)
		(fp_line
			(start -0.67945 0.3048)
			(end -0.120396 0.3048)
			(stroke
				(width 0.1)
				(type default)
			)
			(layer "B.Fab")
		)
		(pad "1" smd circle
			(at 0.40005 0 270)
			(size 0 0)
			(layers "B.Cu" "B.Mask" "B.Paste")
			(net "P0V9_CPU0_RT0_2A")
		)
		(pad "2" smd circle
			(at -0.40005 0 270)
			(size 0 0)
			(layers "B.Cu" "B.Mask" "B.Paste")
			(net "GND")
		)
	)
	(footprint ""
		(layer "B.Cu")
		(at 187.871608 -100.290376 -90)
		(property "Reference" "R275"
			(at 0 0 90)
			(layer "B.SilkS")
			(hide yes)
			(effects
				(font
					(size 1.27 1.27)
				)
				(justify mirror)
			)
		)
		(property "Value" ""
			(at 0 0 90)
			(layer "B.Fab")
			(effects
				(font
					(size 1.27 1.27)
				)
				(justify mirror)
			)
		)
		(duplicate_pad_numbers_are_jumpers no)
		(fp_line
			(start -0.7874 0.4064)
			(end 0.7874 0.4064)
			(stroke
				(width 0.1524)
				(type default)
			)
			(layer "B.SilkS")
		)
		(fp_line
			(start 0.7874 0.4064)
			(end 0.7874 -0.4064)
			(stroke
				(width 0.1524)
				(type default)
			)
			(layer "B.SilkS")
		)
		(fp_line
			(start -0.7874 -0.4064)
			(end -0.7874 0.4064)
			(stroke
				(width 0.1524)
				(type default)
			)
			(layer "B.SilkS")
		)
		(fp_line
			(start 0.7874 -0.4064)
			(end -0.7874 -0.4064)
			(stroke
				(width 0.1524)
				(type default)
			)
			(layer "B.SilkS")
		)
		(fp_line
			(start -0.67945 0.3048)
			(end -0.120396 0.3048)
			(stroke
				(width 0.1)
				(type default)
			)
			(layer "B.Fab")
		)
		(fp_line
			(start -0.120396 0.3048)
			(end -0.120396 0.2794)
			(stroke
				(width 0.1)
				(type default)
			)
			(layer "B.Fab")
		)
		(fp_line
			(start 0.12065 0.3048)
			(end 0.67945 0.3048)
			(stroke
				(width 0.1)
				(type default)
			)
			(layer "B.Fab")
		)
		(fp_line
			(start 0.67945 0.3048)
			(end 0.67945 -0.305054)
			(stroke
				(width 0.1)
				(type default)
			)
			(layer "B.Fab")
		)
		(fp_line
			(start -0.120396 0.2794)
			(end 0.12065 0.2794)
			(stroke
				(width 0.1)
				(type default)
			)
			(layer "B.Fab")
		)
		(fp_line
			(start 0.12065 0.2794)
			(end 0.12065 0.3048)
			(stroke
				(width 0.1)
				(type default)
			)
			(layer "B.Fab")
		)
		(fp_line
			(start -0.12065 -0.2794)
			(end -0.12065 -0.3048)
			(stroke
				(width 0.1)
				(type default)
			)
			(layer "B.Fab")
		)
		(fp_line
			(start 0.12065 -0.2794)
			(end -0.12065 -0.2794)
			(stroke
				(width 0.1)
				(type default)
			)
			(layer "B.Fab")
		)
		(fp_line
			(start -0.67945 -0.3048)
			(end -0.67945 0.3048)
			(stroke
				(width 0.1)
				(type default)
			)
			(layer "B.Fab")
		)
		(fp_line
			(start -0.12065 -0.3048)
			(end -0.67945 -0.3048)
			(stroke
				(width 0.1)
				(type default)
			)
			(layer "B.Fab")
		)
		(fp_line
			(start 0.12065 -0.305054)
			(end 0.12065 -0.2794)
			(stroke
				(width 0.1)
				(type default)
			)
			(layer "B.Fab")
		)
		(fp_line
			(start 0.67945 -0.305054)
			(end 0.12065 -0.305054)
			(stroke
				(width 0.1)
				(type default)
			)
			(layer "B.Fab")
		)
		(pad "1" smd circle
			(at 0.40005 0 90)
			(size 0 0)
			(layers "B.Cu" "B.Mask" "B.Paste")
			(net "CLR_CMOS")
		)
		(pad "2" smd circle
			(at -0.40005 0 90)
			(size 0 0)
			(layers "B.Cu" "B.Mask" "B.Paste")
			(net "FM_CLR_CMOS")
		)
	)
	(footprint ""
		(layer "B.Cu")
		(at 367.741454 -249.36831)
		(property "Reference" "C2173"
			(at 0 0 0)
			(layer "B.SilkS")
			(hide yes)
			(effects
				(font
					(size 1.27 1.27)
				)
				(justify mirror)
			)
		)
		(property "Value" ""
			(at 0 0 0)
			(layer "B.Fab")
			(effects
				(font
					(size 1.27 1.27)
				)
				(justify mirror)
			)
		)
		(duplicate_pad_numbers_are_jumpers no)
		(fp_line
			(start -0.7874 -0.4064)
			(end -0.7874 0.4064)
			(stroke
				(width 0.1524)
				(type default)
			)
			(layer "B.SilkS")
		)
		(fp_line
			(start -0.7874 0.4064)
			(end 0.7874 0.4064)
			(stroke
				(width 0.1524)
				(type default)
			)
			(layer "B.SilkS")
		)
		(fp_line
			(start 0.7874 -0.4064)
			(end -0.7874 -0.4064)
			(stroke
				(width 0.1524)
				(type default)
			)
			(layer "B.SilkS")
		)
		(fp_line
			(start 0.7874 0.4064)
			(end 0.7874 -0.4064)
			(stroke
				(width 0.1524)
				(type default)
			)
			(layer "B.SilkS")
		)
		(fp_line
			(start -0.67945 -0.3048)
			(end -0.67945 0.3048)
			(stroke
				(width 0.1)
				(type default)
			)
			(layer "B.Fab")
		)
		(fp_line
			(start -0.67945 0.3048)
			(end -0.120396 0.3048)
			(stroke
				(width 0.1)
				(type default)
			)
			(layer "B.Fab")
		)
		(fp_line
			(start -0.12065 -0.3048)
			(end -0.67945 -0.3048)
			(stroke
				(width 0.1)
				(type default)
			)
			(layer "B.Fab")
		)
		(fp_line
			(start -0.12065 -0.2794)
			(end -0.12065 -0.3048)
			(stroke
				(width 0.1)
				(type default)
			)
			(layer "B.Fab")
		)
		(fp_line
			(start -0.120396 0.2794)
			(end 0.12065 0.2794)
			(stroke
				(width 0.1)
				(type default)
			)
			(layer "B.Fab")
		)
		(fp_line
			(start -0.120396 0.3048)
			(end -0.120396 0.2794)
			(stroke
				(width 0.1)
				(type default)
			)
			(layer "B.Fab")
		)
		(fp_line
			(start 0.12065 -0.305054)
			(end 0.12065 -0.2794)
			(stroke
				(width 0.1)
				(type default)
			)
			(layer "B.Fab")
		)
		(fp_line
			(start 0.12065 -0.2794)
			(end -0.12065 -0.2794)
			(stroke
				(width 0.1)
				(type default)
			)
			(layer "B.Fab")
		)
		(fp_line
			(start 0.12065 0.2794)
			(end 0.12065 0.3048)
			(stroke
				(width 0.1)
				(type default)
			)
			(layer "B.Fab")
		)
		(fp_line
			(start 0.12065 0.3048)
			(end 0.67945 0.3048)
			(stroke
				(width 0.1)
				(type default)
			)
			(layer "B.Fab")
		)
		(fp_line
			(start 0.67945 -0.305054)
			(end 0.12065 -0.305054)
			(stroke
				(width 0.1)
				(type default)
			)
			(layer "B.Fab")
		)
		(fp_line
			(start 0.67945 0.3048)
			(end 0.67945 -0.305054)
			(stroke
				(width 0.1)
				(type default)
			)
			(layer "B.Fab")
		)
		(pad "1" smd circle
			(at 0.40005 0 180)
			(size 0 0)
			(layers "B.Cu" "B.Mask" "B.Paste")
			(net "PVDDCR_CPU0_P0")
		)
		(pad "2" smd circle
			(at -0.40005 0 180)
			(size 0 0)
			(layers "B.Cu" "B.Mask" "B.Paste")
			(net "GND")
		)
	)
	(footprint ""
		(layer "B.Cu")
		(at 398.473168 -45.272706 180)
		(property "Reference" ""
			(at 0 0 0)
			(layer "B.SilkS")
			(hide yes)
			(effects
				(font
					(size 1.27 1.27)
				)
				(justify mirror)
			)
		)
		(property "Value" ""
			(at 0 0 0)
			(layer "B.Fab")
			(effects
				(font
					(size 1.27 1.27)
				)
				(justify mirror)
			)
		)
		(duplicate_pad_numbers_are_jumpers no)
		(pad "1" smd circle
			(at 0 0)
			(size 0.9906 0.9906)
			(layers "B.Cu" "B.Mask" "B.Paste")
			(net "Net_2234")
		)
		(zone
			(layer "B.Cu")
			(hatch none 0.5)
			(connect_pads
				(clearance 0)
			)
			(min_thickness 0.25)
			(keepout
				(tracks not_allowed)
				(vias allowed)
				(pads allowed)
				(copperpour not_allowed)
				(footprints allowed)
			)
			(placement
				(enabled no)
				(sheetname "")
			)
			(fill
				(thermal_gap 0.5)
				(thermal_bridge_width 0.5)
				(island_removal_mode 0)
			)
			(polygon
				(pts
					(arc
						(start 400.098768 -45.272706)
						(mid 396.847568 -45.272706)
						(end 400.098768 -45.272706)
					)
				)
			)
		)
	)
	(footprint ""
		(layer "B.Cu")
		(at 374.770142 -149.055582 90)
		(property "Reference" "PR306"
			(at 0 0 90)
			(layer "B.SilkS")
			(hide yes)
			(effects
				(font
					(size 1.27 1.27)
				)
				(justify mirror)
			)
		)
		(property "Value" ""
			(at 0 0 90)
			(layer "B.Fab")
			(effects
				(font
					(size 1.27 1.27)
				)
				(justify mirror)
			)
		)
		(duplicate_pad_numbers_are_jumpers no)
		(fp_line
			(start 0.7874 -0.4064)
			(end -0.7874 -0.4064)
			(stroke
				(width 0.1524)
				(type default)
			)
			(layer "B.SilkS")
		)
		(fp_line
			(start -0.7874 -0.4064)
			(end -0.7874 0.4064)
			(stroke
				(width 0.1524)
				(type default)
			)
			(layer "B.SilkS")
		)
		(fp_line
			(start 0.7874 0.4064)
			(end 0.7874 -0.4064)
			(stroke
				(width 0.1524)
				(type default)
			)
			(layer "B.SilkS")
		)
		(fp_line
			(start -0.7874 0.4064)
			(end 0.7874 0.4064)
			(stroke
				(width 0.1524)
				(type default)
			)
			(layer "B.SilkS")
		)
		(fp_line
			(start 0.67945 -0.305054)
			(end 0.12065 -0.305054)
			(stroke
				(width 0.1)
				(type default)
			)
			(layer "B.Fab")
		)
		(fp_line
			(start 0.12065 -0.305054)
			(end 0.12065 -0.2794)
			(stroke
				(width 0.1)
				(type default)
			)
			(layer "B.Fab")
		)
		(fp_line
			(start -0.12065 -0.3048)
			(end -0.67945 -0.3048)
			(stroke
				(width 0.1)
				(type default)
			)
			(layer "B.Fab")
		)
		(fp_line
			(start -0.67945 -0.3048)
			(end -0.67945 0.3048)
			(stroke
				(width 0.1)
				(type default)
			)
			(layer "B.Fab")
		)
		(fp_line
			(start 0.12065 -0.2794)
			(end -0.12065 -0.2794)
			(stroke
				(width 0.1)
				(type default)
			)
			(layer "B.Fab")
		)
		(fp_line
			(start -0.12065 -0.2794)
			(end -0.12065 -0.3048)
			(stroke
				(width 0.1)
				(type default)
			)
			(layer "B.Fab")
		)
		(fp_line
			(start 0.12065 0.2794)
			(end 0.12065 0.3048)
			(stroke
				(width 0.1)
				(type default)
			)
			(layer "B.Fab")
		)
		(fp_line
			(start -0.120396 0.2794)
			(end 0.12065 0.2794)
			(stroke
				(width 0.1)
				(type default)
			)
			(layer "B.Fab")
		)
		(fp_line
			(start 0.67945 0.3048)
			(end 0.67945 -0.305054)
			(stroke
				(width 0.1)
				(type default)
			)
			(layer "B.Fab")
		)
		(fp_line
			(start 0.12065 0.3048)
			(end 0.67945 0.3048)
			(stroke
				(width 0.1)
				(type default)
			)
			(layer "B.Fab")
		)
		(fp_line
			(start -0.120396 0.3048)
			(end -0.120396 0.2794)
			(stroke
				(width 0.1)
				(type default)
			)
			(layer "B.Fab")
		)
		(fp_line
			(start -0.67945 0.3048)
			(end -0.120396 0.3048)
			(stroke
				(width 0.1)
				(type default)
			)
			(layer "B.Fab")
		)
		(pad "1" smd circle
			(at 0.40005 0 270)
			(size 0 0)
			(layers "B.Cu" "B.Mask" "B.Paste")
			(net "VSENSE_PVDDCR_CPU0_P0_DP")
		)
		(pad "2" smd circle
			(at -0.40005 0 270)
			(size 0 0)
			(layers "B.Cu" "B.Mask" "B.Paste")
			(net "VSENSE_PVDDCR_CPU0_P0_VSEN0")
		)
	)
	(footprint ""
		(layer "B.Cu")
		(at 431.918618 -344.006932 -90)
		(property "Reference" "PC226"
			(at 7.654036 -3.431286 270)
			(unlocked yes)
			(layer "B.SilkS")
			(effects
				(font
					(size 0.7874 0.5842)
					(thickness 0.1524)
				)
				(justify left mirror)
			)
		)
		(property "Value" ""
			(at 0 0 90)
			(layer "B.Fab")
			(effects
				(font
					(size 1.27 1.27)
				)
				(justify mirror)
			)
		)
		(duplicate_pad_numbers_are_jumpers no)
		(fp_line
			(start -4.533392 2.249932)
			(end 4.533392 2.249932)
			(stroke
				(width 0.1524)
				(type default)
			)
			(layer "B.SilkS")
		)
		(fp_line
			(start 4.533392 2.249932)
			(end 4.533392 -2.249932)
			(stroke
				(width 0.1524)
				(type default)
			)
			(layer "B.SilkS")
		)
		(fp_line
			(start -4.533392 -2.249932)
			(end -4.533392 2.249932)
			(stroke
				(width 0.1524)
				(type default)
			)
			(layer "B.SilkS")
		)
		(fp_line
			(start 4.533392 -2.249932)
			(end -4.533392 -2.249932)
			(stroke
				(width 0.1524)
				(type default)
			)
			(layer "B.SilkS")
		)
		(fp_rect
			(start 5.39242 2.326132)
			(end 4.533392 -2.326132)
			(stroke
				(width 0)
				(type default)
			)
			(fill yes)
			(layer "B.SilkS")
		)
		(fp_line
			(start -3.750056 2.249932)
			(end 3.750056 2.249932)
			(stroke
				(width 0.1)
				(type default)
			)
			(layer "B.Fab")
		)
		(fp_line
			(start 3.750056 2.249932)
			(end 3.750056 -2.249932)
			(stroke
				(width 0.1)
				(type default)
			)
			(layer "B.Fab")
		)
		(fp_line
			(start -3.750056 -2.249932)
			(end -3.750056 2.249932)
			(stroke
				(width 0.1)
				(type default)
			)
			(layer "B.Fab")
		)
		(fp_line
			(start 3.750056 -2.249932)
			(end -3.750056 -2.249932)
			(stroke
				(width 0.1)
				(type default)
			)
			(layer "B.Fab")
		)
		(fp_text user "-"
			(at -4.416806 2.466848 270)
			(unlocked yes)
			(layer "B.SilkS")
			(effects
				(font
					(size 1.905 1.4224)
					(thickness 0.1524)
				)
				(justify left mirror)
			)
		)
		(fp_text user "+"
			(at 6.934454 0.61595 180)
			(unlocked yes)
			(layer "B.SilkS")
			(effects
				(font
					(size 1.905 1.4224)
					(thickness 0.1524)
				)
				(justify left mirror)
			)
		)
		(fp_text user "+"
			(at 6.322314 0.786384 180)
			(unlocked yes)
			(layer "B.Fab")
			(effects
				(font
					(size 1.905 1.4224)
					(thickness 0.1524)
				)
				(justify left mirror)
			)
		)
		(fp_text user "-"
			(at -4.8514 -0.14605 270)
			(unlocked yes)
			(layer "B.Fab")
			(effects
				(font
					(size 1.905 1.4224)
					(thickness 0.1524)
				)
				(justify left mirror)
			)
		)
		(pad "1" smd rect
			(at 3.199892 0 90)
			(size 2.413 2.8194)
			(layers "B.Cu" "B.Mask" "B.Paste")
			(net "PVDD11_S3_P0")
		)
		(pad "2" smd rect
			(at -3.199892 0 90)
			(size 2.413 2.8194)
			(layers "B.Cu" "B.Mask" "B.Paste")
			(net "GND")
		)
	)
	(footprint ""
		(layer "B.Cu")
		(at 16.985234 -407.10866 -90)
		(property "Reference" "R656"
			(at 0 0 90)
			(layer "B.SilkS")
			(hide yes)
			(effects
				(font
					(size 1.27 1.27)
				)
				(justify mirror)
			)
		)
		(property "Value" ""
			(at 0 0 90)
			(layer "B.Fab")
			(effects
				(font
					(size 1.27 1.27)
				)
				(justify mirror)
			)
		)
		(duplicate_pad_numbers_are_jumpers no)
		(fp_line
			(start -0.7874 0.4064)
			(end 0.7874 0.4064)
			(stroke
				(width 0.1524)
				(type default)
			)
			(layer "B.SilkS")
		)
		(fp_line
			(start 0.7874 0.4064)
			(end 0.7874 -0.4064)
			(stroke
				(width 0.1524)
				(type default)
			)
			(layer "B.SilkS")
		)
		(fp_line
			(start -0.7874 -0.4064)
			(end -0.7874 0.4064)
			(stroke
				(width 0.1524)
				(type default)
			)
			(layer "B.SilkS")
		)
		(fp_line
			(start 0.7874 -0.4064)
			(end -0.7874 -0.4064)
			(stroke
				(width 0.1524)
				(type default)
			)
			(layer "B.SilkS")
		)
		(fp_line
			(start -0.67945 0.3048)
			(end -0.120396 0.3048)
			(stroke
				(width 0.1)
				(type default)
			)
			(layer "B.Fab")
		)
		(fp_line
			(start -0.120396 0.3048)
			(end -0.120396 0.2794)
			(stroke
				(width 0.1)
				(type default)
			)
			(layer "B.Fab")
		)
		(fp_line
			(start 0.12065 0.3048)
			(end 0.67945 0.3048)
			(stroke
				(width 0.1)
				(type default)
			)
			(layer "B.Fab")
		)
		(fp_line
			(start 0.67945 0.3048)
			(end 0.67945 -0.305054)
			(stroke
				(width 0.1)
				(type default)
			)
			(layer "B.Fab")
		)
		(fp_line
			(start -0.120396 0.2794)
			(end 0.12065 0.2794)
			(stroke
				(width 0.1)
				(type default)
			)
			(layer "B.Fab")
		)
		(fp_line
			(start 0.12065 0.2794)
			(end 0.12065 0.3048)
			(stroke
				(width 0.1)
				(type default)
			)
			(layer "B.Fab")
		)
		(fp_line
			(start -0.12065 -0.2794)
			(end -0.12065 -0.3048)
			(stroke
				(width 0.1)
				(type default)
			)
			(layer "B.Fab")
		)
		(fp_line
			(start 0.12065 -0.2794)
			(end -0.12065 -0.2794)
			(stroke
				(width 0.1)
				(type default)
			)
			(layer "B.Fab")
		)
		(fp_line
			(start -0.67945 -0.3048)
			(end -0.67945 0.3048)
			(stroke
				(width 0.1)
				(type default)
			)
			(layer "B.Fab")
		)
		(fp_line
			(start -0.12065 -0.3048)
			(end -0.67945 -0.3048)
			(stroke
				(width 0.1)
				(type default)
			)
			(layer "B.Fab")
		)
		(fp_line
			(start 0.12065 -0.305054)
			(end 0.12065 -0.2794)
			(stroke
				(width 0.1)
				(type default)
			)
			(layer "B.Fab")
		)
		(fp_line
			(start 0.67945 -0.305054)
			(end 0.12065 -0.305054)
			(stroke
				(width 0.1)
				(type default)
			)
			(layer "B.Fab")
		)
		(pad "1" smd circle
			(at 0.40005 0 90)
			(size 0 0)
			(layers "B.Cu" "B.Mask" "B.Paste")
			(net "P3V3_AUX")
		)
		(pad "2" smd circle
			(at -0.40005 0 90)
			(size 0 0)
			(layers "B.Cu" "B.Mask" "B.Paste")
			(net "PWRGD_P0V9_RETIMER_CPU1_R")
		)
	)
	(footprint ""
		(layer "B.Cu")
		(at 240.740692 -422.849548 90)
		(property "Reference" "C66"
			(at 0 0 90)
			(layer "B.SilkS")
			(hide yes)
			(effects
				(font
					(size 1.27 1.27)
				)
				(justify mirror)
			)
		)
		(property "Value" ""
			(at 0 0 90)
			(layer "B.Fab")
			(effects
				(font
					(size 1.27 1.27)
				)
				(justify mirror)
			)
		)
		(duplicate_pad_numbers_are_jumpers no)
		(fp_line
			(start 0.7874 -0.4064)
			(end -0.7874 -0.4064)
			(stroke
				(width 0.1524)
				(type default)
			)
			(layer "B.SilkS")
		)
		(fp_line
			(start -0.7874 -0.4064)
			(end -0.7874 0.4064)
			(stroke
				(width 0.1524)
				(type default)
			)
			(layer "B.SilkS")
		)
		(fp_line
			(start 0.7874 0.4064)
			(end 0.7874 -0.4064)
			(stroke
				(width 0.1524)
				(type default)
			)
			(layer "B.SilkS")
		)
		(fp_line
			(start -0.7874 0.4064)
			(end 0.7874 0.4064)
			(stroke
				(width 0.1524)
				(type default)
			)
			(layer "B.SilkS")
		)
		(fp_line
			(start 0.67945 -0.305054)
			(end 0.12065 -0.305054)
			(stroke
				(width 0.1)
				(type default)
			)
			(layer "B.Fab")
		)
		(fp_line
			(start 0.12065 -0.305054)
			(end 0.12065 -0.2794)
			(stroke
				(width 0.1)
				(type default)
			)
			(layer "B.Fab")
		)
		(fp_line
			(start -0.12065 -0.3048)
			(end -0.67945 -0.3048)
			(stroke
				(width 0.1)
				(type default)
			)
			(layer "B.Fab")
		)
		(fp_line
			(start -0.67945 -0.3048)
			(end -0.67945 0.3048)
			(stroke
				(width 0.1)
				(type default)
			)
			(layer "B.Fab")
		)
		(fp_line
			(start 0.12065 -0.2794)
			(end -0.12065 -0.2794)
			(stroke
				(width 0.1)
				(type default)
			)
			(layer "B.Fab")
		)
		(fp_line
			(start -0.12065 -0.2794)
			(end -0.12065 -0.3048)
			(stroke
				(width 0.1)
				(type default)
			)
			(layer "B.Fab")
		)
		(fp_line
			(start 0.12065 0.2794)
			(end 0.12065 0.3048)
			(stroke
				(width 0.1)
				(type default)
			)
			(layer "B.Fab")
		)
		(fp_line
			(start -0.120396 0.2794)
			(end 0.12065 0.2794)
			(stroke
				(width 0.1)
				(type default)
			)
			(layer "B.Fab")
		)
		(fp_line
			(start 0.67945 0.3048)
			(end 0.67945 -0.305054)
			(stroke
				(width 0.1)
				(type default)
			)
			(layer "B.Fab")
		)
		(fp_line
			(start 0.12065 0.3048)
			(end 0.67945 0.3048)
			(stroke
				(width 0.1)
				(type default)
			)
			(layer "B.Fab")
		)
		(fp_line
			(start -0.120396 0.3048)
			(end -0.120396 0.2794)
			(stroke
				(width 0.1)
				(type default)
			)
			(layer "B.Fab")
		)
		(fp_line
			(start -0.67945 0.3048)
			(end -0.120396 0.3048)
			(stroke
				(width 0.1)
				(type default)
			)
			(layer "B.Fab")
		)
		(pad "1" smd circle
			(at 0.40005 0 270)
			(size 0 0)
			(layers "B.Cu" "B.Mask" "B.Paste")
			(net "FM_FAN_PWR_EN_R")
		)
		(pad "2" smd circle
			(at -0.40005 0 270)
			(size 0 0)
			(layers "B.Cu" "B.Mask" "B.Paste")
			(net "GND")
		)
	)
	(footprint ""
		(layer "B.Cu")
		(at 111.781336 -254.448564 180)
		(property "Reference" "C2419"
			(at 0 0 0)
			(layer "B.SilkS")
			(hide yes)
			(effects
				(font
					(size 1.27 1.27)
				)
				(justify mirror)
			)
		)
		(property "Value" ""
			(at 0 0 0)
			(layer "B.Fab")
			(effects
				(font
					(size 1.27 1.27)
				)
				(justify mirror)
			)
		)
		(duplicate_pad_numbers_are_jumpers no)
		(fp_line
			(start 0.7874 0.4064)
			(end 0.7874 -0.4064)
			(stroke
				(width 0.1524)
				(type default)
			)
			(layer "B.SilkS")
		)
		(fp_line
			(start 0.7874 -0.4064)
			(end -0.7874 -0.4064)
			(stroke
				(width 0.1524)
				(type default)
			)
			(layer "B.SilkS")
		)
		(fp_line
			(start -0.7874 0.4064)
			(end 0.7874 0.4064)
			(stroke
				(width 0.1524)
				(type default)
			)
			(layer "B.SilkS")
		)
		(fp_line
			(start -0.7874 -0.4064)
			(end -0.7874 0.4064)
			(stroke
				(width 0.1524)
				(type default)
			)
			(layer "B.SilkS")
		)
		(fp_line
			(start 0.67945 0.3048)
			(end 0.67945 -0.305054)
			(stroke
				(width 0.1)
				(type default)
			)
			(layer "B.Fab")
		)
		(fp_line
			(start 0.67945 -0.305054)
			(end 0.12065 -0.305054)
			(stroke
				(width 0.1)
				(type default)
			)
			(layer "B.Fab")
		)
		(fp_line
			(start 0.12065 0.3048)
			(end 0.67945 0.3048)
			(stroke
				(width 0.1)
				(type default)
			)
			(layer "B.Fab")
		)
		(fp_line
			(start 0.12065 0.2794)
			(end 0.12065 0.3048)
			(stroke
				(width 0.1)
				(type default)
			)
			(layer "B.Fab")
		)
		(fp_line
			(start 0.12065 -0.2794)
			(end -0.12065 -0.2794)
			(stroke
				(width 0.1)
				(type default)
			)
			(layer "B.Fab")
		)
		(fp_line
			(start 0.12065 -0.305054)
			(end 0.12065 -0.2794)
			(stroke
				(width 0.1)
				(type default)
			)
			(layer "B.Fab")
		)
		(fp_line
			(start -0.120396 0.3048)
			(end -0.120396 0.2794)
			(stroke
				(width 0.1)
				(type default)
			)
			(layer "B.Fab")
		)
		(fp_line
			(start -0.120396 0.2794)
			(end 0.12065 0.2794)
			(stroke
				(width 0.1)
				(type default)
			)
			(layer "B.Fab")
		)
		(fp_line
			(start -0.12065 -0.2794)
			(end -0.12065 -0.3048)
			(stroke
				(width 0.1)
				(type default)
			)
			(layer "B.Fab")
		)
		(fp_line
			(start -0.12065 -0.3048)
			(end -0.67945 -0.3048)
			(stroke
				(width 0.1)
				(type default)
			)
			(layer "B.Fab")
		)
		(fp_line
			(start -0.67945 0.3048)
			(end -0.120396 0.3048)
			(stroke
				(width 0.1)
				(type default)
			)
			(layer "B.Fab")
		)
		(fp_line
			(start -0.67945 -0.3048)
			(end -0.67945 0.3048)
			(stroke
				(width 0.1)
				(type default)
			)
			(layer "B.Fab")
		)
		(pad "1" smd circle
			(at 0.40005 0)
			(size 0 0)
			(layers "B.Cu" "B.Mask" "B.Paste")
			(net "PVDDCR_SOC_P1")
		)
		(pad "2" smd circle
			(at -0.40005 0)
			(size 0 0)
			(layers "B.Cu" "B.Mask" "B.Paste")
			(net "GND")
		)
	)
	(footprint ""
		(layer "B.Cu")
		(at 110.527084 -261.748016 90)
		(property "Reference" "C2124"
			(at 0 0 90)
			(layer "B.SilkS")
			(hide yes)
			(effects
				(font
					(size 1.27 1.27)
				)
				(justify mirror)
			)
		)
		(property "Value" ""
			(at 0 0 90)
			(layer "B.Fab")
			(effects
				(font
					(size 1.27 1.27)
				)
				(justify mirror)
			)
		)
		(duplicate_pad_numbers_are_jumpers no)
		(fp_line
			(start 0.7874 -0.4064)
			(end -0.7874 -0.4064)
			(stroke
				(width 0.1524)
				(type default)
			)
			(layer "B.SilkS")
		)
		(fp_line
			(start -0.7874 -0.4064)
			(end -0.7874 0.4064)
			(stroke
				(width 0.1524)
				(type default)
			)
			(layer "B.SilkS")
		)
		(fp_line
			(start 0.7874 0.4064)
			(end 0.7874 -0.4064)
			(stroke
				(width 0.1524)
				(type default)
			)
			(layer "B.SilkS")
		)
		(fp_line
			(start -0.7874 0.4064)
			(end 0.7874 0.4064)
			(stroke
				(width 0.1524)
				(type default)
			)
			(layer "B.SilkS")
		)
		(fp_line
			(start 0.67945 -0.305054)
			(end 0.12065 -0.305054)
			(stroke
				(width 0.1)
				(type default)
			)
			(layer "B.Fab")
		)
		(fp_line
			(start 0.12065 -0.305054)
			(end 0.12065 -0.2794)
			(stroke
				(width 0.1)
				(type default)
			)
			(layer "B.Fab")
		)
		(fp_line
			(start -0.12065 -0.3048)
			(end -0.67945 -0.3048)
			(stroke
				(width 0.1)
				(type default)
			)
			(layer "B.Fab")
		)
		(fp_line
			(start -0.67945 -0.3048)
			(end -0.67945 0.3048)
			(stroke
				(width 0.1)
				(type default)
			)
			(layer "B.Fab")
		)
		(fp_line
			(start 0.12065 -0.2794)
			(end -0.12065 -0.2794)
			(stroke
				(width 0.1)
				(type default)
			)
			(layer "B.Fab")
		)
		(fp_line
			(start -0.12065 -0.2794)
			(end -0.12065 -0.3048)
			(stroke
				(width 0.1)
				(type default)
			)
			(layer "B.Fab")
		)
		(fp_line
			(start 0.12065 0.2794)
			(end 0.12065 0.3048)
			(stroke
				(width 0.1)
				(type default)
			)
			(layer "B.Fab")
		)
		(fp_line
			(start -0.120396 0.2794)
			(end 0.12065 0.2794)
			(stroke
				(width 0.1)
				(type default)
			)
			(layer "B.Fab")
		)
		(fp_line
			(start 0.67945 0.3048)
			(end 0.67945 -0.305054)
			(stroke
				(width 0.1)
				(type default)
			)
			(layer "B.Fab")
		)
		(fp_line
			(start 0.12065 0.3048)
			(end 0.67945 0.3048)
			(stroke
				(width 0.1)
				(type default)
			)
			(layer "B.Fab")
		)
		(fp_line
			(start -0.120396 0.3048)
			(end -0.120396 0.2794)
			(stroke
				(width 0.1)
				(type default)
			)
			(layer "B.Fab")
		)
		(fp_line
			(start -0.67945 0.3048)
			(end -0.120396 0.3048)
			(stroke
				(width 0.1)
				(type default)
			)
			(layer "B.Fab")
		)
		(pad "1" smd circle
			(at 0.40005 0 270)
			(size 0 0)
			(layers "B.Cu" "B.Mask" "B.Paste")
			(net "PVDD11_S3_P1")
		)
		(pad "2" smd circle
			(at -0.40005 0 270)
			(size 0 0)
			(layers "B.Cu" "B.Mask" "B.Paste")
			(net "GND")
		)
	)
	(footprint ""
		(layer "B.Cu")
		(at 126.276862 -164.133276 90)
		(property "Reference" "PR206"
			(at 0 0 90)
			(layer "B.SilkS")
			(hide yes)
			(effects
				(font
					(size 1.27 1.27)
				)
				(justify mirror)
			)
		)
		(property "Value" ""
			(at 0 0 90)
			(layer "B.Fab")
			(effects
				(font
					(size 1.27 1.27)
				)
				(justify mirror)
			)
		)
		(duplicate_pad_numbers_are_jumpers no)
		(fp_line
			(start 0.7874 -0.4064)
			(end -0.7874 -0.4064)
			(stroke
				(width 0.1524)
				(type default)
			)
			(layer "B.SilkS")
		)
		(fp_line
			(start -0.7874 -0.4064)
			(end -0.7874 0.4064)
			(stroke
				(width 0.1524)
				(type default)
			)
			(layer "B.SilkS")
		)
		(fp_line
			(start 0.7874 0.4064)
			(end 0.7874 -0.4064)
			(stroke
				(width 0.1524)
				(type default)
			)
			(layer "B.SilkS")
		)
		(fp_line
			(start -0.7874 0.4064)
			(end 0.7874 0.4064)
			(stroke
				(width 0.1524)
				(type default)
			)
			(layer "B.SilkS")
		)
		(fp_line
			(start 0.67945 -0.305054)
			(end 0.12065 -0.305054)
			(stroke
				(width 0.1)
				(type default)
			)
			(layer "B.Fab")
		)
		(fp_line
			(start 0.12065 -0.305054)
			(end 0.12065 -0.2794)
			(stroke
				(width 0.1)
				(type default)
			)
			(layer "B.Fab")
		)
		(fp_line
			(start -0.12065 -0.3048)
			(end -0.67945 -0.3048)
			(stroke
				(width 0.1)
				(type default)
			)
			(layer "B.Fab")
		)
		(fp_line
			(start -0.67945 -0.3048)
			(end -0.67945 0.3048)
			(stroke
				(width 0.1)
				(type default)
			)
			(layer "B.Fab")
		)
		(fp_line
			(start 0.12065 -0.2794)
			(end -0.12065 -0.2794)
			(stroke
				(width 0.1)
				(type default)
			)
			(layer "B.Fab")
		)
		(fp_line
			(start -0.12065 -0.2794)
			(end -0.12065 -0.3048)
			(stroke
				(width 0.1)
				(type default)
			)
			(layer "B.Fab")
		)
		(fp_line
			(start 0.12065 0.2794)
			(end 0.12065 0.3048)
			(stroke
				(width 0.1)
				(type default)
			)
			(layer "B.Fab")
		)
		(fp_line
			(start -0.120396 0.2794)
			(end 0.12065 0.2794)
			(stroke
				(width 0.1)
				(type default)
			)
			(layer "B.Fab")
		)
		(fp_line
			(start 0.67945 0.3048)
			(end 0.67945 -0.305054)
			(stroke
				(width 0.1)
				(type default)
			)
			(layer "B.Fab")
		)
		(fp_line
			(start 0.12065 0.3048)
			(end 0.67945 0.3048)
			(stroke
				(width 0.1)
				(type default)
			)
			(layer "B.Fab")
		)
		(fp_line
			(start -0.120396 0.3048)
			(end -0.120396 0.2794)
			(stroke
				(width 0.1)
				(type default)
			)
			(layer "B.Fab")
		)
		(fp_line
			(start -0.67945 0.3048)
			(end -0.120396 0.3048)
			(stroke
				(width 0.1)
				(type default)
			)
			(layer "B.Fab")
		)
		(pad "1" smd circle
			(at 0.40005 0 270)
			(size 0 0)
			(layers "B.Cu" "B.Mask" "B.Paste")
			(net "PVDDCR_CPU0_P1_PVCC")
		)
		(pad "2" smd circle
			(at -0.40005 0 270)
			(size 0 0)
			(layers "B.Cu" "B.Mask" "B.Paste")
			(net "PVDDCR_SOC_P1_VCC2")
		)
	)
	(footprint ""
		(layer "B.Cu")
		(at 156.154374 -322.805552)
		(property "Reference" "R559"
			(at 0 0 0)
			(layer "B.SilkS")
			(hide yes)
			(effects
				(font
					(size 1.27 1.27)
				)
				(justify mirror)
			)
		)
		(property "Value" ""
			(at 0 0 0)
			(layer "B.Fab")
			(effects
				(font
					(size 1.27 1.27)
				)
				(justify mirror)
			)
		)
		(duplicate_pad_numbers_are_jumpers no)
		(fp_line
			(start -0.7874 -0.4064)
			(end -0.7874 0.4064)
			(stroke
				(width 0.1524)
				(type default)
			)
			(layer "B.SilkS")
		)
		(fp_line
			(start -0.7874 0.4064)
			(end 0.7874 0.4064)
			(stroke
				(width 0.1524)
				(type default)
			)
			(layer "B.SilkS")
		)
		(fp_line
			(start 0.7874 -0.4064)
			(end -0.7874 -0.4064)
			(stroke
				(width 0.1524)
				(type default)
			)
			(layer "B.SilkS")
		)
		(fp_line
			(start 0.7874 0.4064)
			(end 0.7874 -0.4064)
			(stroke
				(width 0.1524)
				(type default)
			)
			(layer "B.SilkS")
		)
		(fp_line
			(start -0.67945 -0.3048)
			(end -0.67945 0.3048)
			(stroke
				(width 0.1)
				(type default)
			)
			(layer "B.Fab")
		)
		(fp_line
			(start -0.67945 0.3048)
			(end -0.120396 0.3048)
			(stroke
				(width 0.1)
				(type default)
			)
			(layer "B.Fab")
		)
		(fp_line
			(start -0.12065 -0.3048)
			(end -0.67945 -0.3048)
			(stroke
				(width 0.1)
				(type default)
			)
			(layer "B.Fab")
		)
		(fp_line
			(start -0.12065 -0.2794)
			(end -0.12065 -0.3048)
			(stroke
				(width 0.1)
				(type default)
			)
			(layer "B.Fab")
		)
		(fp_line
			(start -0.120396 0.2794)
			(end 0.12065 0.2794)
			(stroke
				(width 0.1)
				(type default)
			)
			(layer "B.Fab")
		)
		(fp_line
			(start -0.120396 0.3048)
			(end -0.120396 0.2794)
			(stroke
				(width 0.1)
				(type default)
			)
			(layer "B.Fab")
		)
		(fp_line
			(start 0.12065 -0.305054)
			(end 0.12065 -0.2794)
			(stroke
				(width 0.1)
				(type default)
			)
			(layer "B.Fab")
		)
		(fp_line
			(start 0.12065 -0.2794)
			(end -0.12065 -0.2794)
			(stroke
				(width 0.1)
				(type default)
			)
			(layer "B.Fab")
		)
		(fp_line
			(start 0.12065 0.2794)
			(end 0.12065 0.3048)
			(stroke
				(width 0.1)
				(type default)
			)
			(layer "B.Fab")
		)
		(fp_line
			(start 0.12065 0.3048)
			(end 0.67945 0.3048)
			(stroke
				(width 0.1)
				(type default)
			)
			(layer "B.Fab")
		)
		(fp_line
			(start 0.67945 -0.305054)
			(end 0.12065 -0.305054)
			(stroke
				(width 0.1)
				(type default)
			)
			(layer "B.Fab")
		)
		(fp_line
			(start 0.67945 0.3048)
			(end 0.67945 -0.305054)
			(stroke
				(width 0.1)
				(type default)
			)
			(layer "B.Fab")
		)
		(pad "1" smd circle
			(at 0.40005 0 180)
			(size 0 0)
			(layers "B.Cu" "B.Mask" "B.Paste")
			(net "PVDD18_S5_P1")
		)
		(pad "2" smd circle
			(at -0.40005 0 180)
			(size 0 0)
			(layers "B.Cu" "B.Mask" "B.Paste")
			(net "RST_CPU1_SYS_N")
		)
	)
	(footprint ""
		(layer "B.Cu")
		(at 419.806374 -395.148562 90)
		(property "Reference" "C975"
			(at 0 0 90)
			(layer "B.SilkS")
			(hide yes)
			(effects
				(font
					(size 1.27 1.27)
				)
				(justify mirror)
			)
		)
		(property "Value" ""
			(at 0 0 90)
			(layer "B.Fab")
			(effects
				(font
					(size 1.27 1.27)
				)
				(justify mirror)
			)
		)
		(duplicate_pad_numbers_are_jumpers no)
		(fp_line
			(start 0.299974 -0.150114)
			(end -0.299974 -0.150114)
			(stroke
				(width 0.1)
				(type default)
			)
			(layer "B.Fab")
		)
		(fp_line
			(start -0.299974 -0.150114)
			(end -0.299974 0.150114)
			(stroke
				(width 0.1)
				(type default)
			)
			(layer "B.Fab")
		)
		(fp_line
			(start 0.299974 0.150114)
			(end 0.299974 -0.150114)
			(stroke
				(width 0.1)
				(type default)
			)
			(layer "B.Fab")
		)
		(fp_line
			(start -0.299974 0.150114)
			(end 0.299974 0.150114)
			(stroke
				(width 0.1)
				(type default)
			)
			(layer "B.Fab")
		)
		(pad "1" smd rect
			(at 0.2667 0 270)
			(size 0.3048 0.381)
			(layers "B.Cu" "B.Mask" "B.Paste")
			(net "P0V9_CPU0_RT2_2A")
		)
		(pad "2" smd rect
			(at -0.2667 0 270)
			(size 0.3048 0.381)
			(layers "B.Cu" "B.Mask" "B.Paste")
			(net "GND")
		)
	)
	(footprint ""
		(layer "B.Cu")
		(at 90.503502 -205.14945 90)
		(property "Reference" "R539"
			(at 0 0 90)
			(layer "B.SilkS")
			(hide yes)
			(effects
				(font
					(size 1.27 1.27)
				)
				(justify mirror)
			)
		)
		(property "Value" ""
			(at 0 0 90)
			(layer "B.Fab")
			(effects
				(font
					(size 1.27 1.27)
				)
				(justify mirror)
			)
		)
		(duplicate_pad_numbers_are_jumpers no)
		(fp_line
			(start 0.7874 -0.4064)
			(end -0.7874 -0.4064)
			(stroke
				(width 0.1524)
				(type default)
			)
			(layer "B.SilkS")
		)
		(fp_line
			(start -0.7874 -0.4064)
			(end -0.7874 0.4064)
			(stroke
				(width 0.1524)
				(type default)
			)
			(layer "B.SilkS")
		)
		(fp_line
			(start 0.7874 0.4064)
			(end 0.7874 -0.4064)
			(stroke
				(width 0.1524)
				(type default)
			)
			(layer "B.SilkS")
		)
		(fp_line
			(start -0.7874 0.4064)
			(end 0.7874 0.4064)
			(stroke
				(width 0.1524)
				(type default)
			)
			(layer "B.SilkS")
		)
		(fp_line
			(start 0.67945 -0.305054)
			(end 0.12065 -0.305054)
			(stroke
				(width 0.1)
				(type default)
			)
			(layer "B.Fab")
		)
		(fp_line
			(start 0.12065 -0.305054)
			(end 0.12065 -0.2794)
			(stroke
				(width 0.1)
				(type default)
			)
			(layer "B.Fab")
		)
		(fp_line
			(start -0.12065 -0.3048)
			(end -0.67945 -0.3048)
			(stroke
				(width 0.1)
				(type default)
			)
			(layer "B.Fab")
		)
		(fp_line
			(start -0.67945 -0.3048)
			(end -0.67945 0.3048)
			(stroke
				(width 0.1)
				(type default)
			)
			(layer "B.Fab")
		)
		(fp_line
			(start 0.12065 -0.2794)
			(end -0.12065 -0.2794)
			(stroke
				(width 0.1)
				(type default)
			)
			(layer "B.Fab")
		)
		(fp_line
			(start -0.12065 -0.2794)
			(end -0.12065 -0.3048)
			(stroke
				(width 0.1)
				(type default)
			)
			(layer "B.Fab")
		)
		(fp_line
			(start 0.12065 0.2794)
			(end 0.12065 0.3048)
			(stroke
				(width 0.1)
				(type default)
			)
			(layer "B.Fab")
		)
		(fp_line
			(start -0.120396 0.2794)
			(end 0.12065 0.2794)
			(stroke
				(width 0.1)
				(type default)
			)
			(layer "B.Fab")
		)
		(fp_line
			(start 0.67945 0.3048)
			(end 0.67945 -0.305054)
			(stroke
				(width 0.1)
				(type default)
			)
			(layer "B.Fab")
		)
		(fp_line
			(start 0.12065 0.3048)
			(end 0.67945 0.3048)
			(stroke
				(width 0.1)
				(type default)
			)
			(layer "B.Fab")
		)
		(fp_line
			(start -0.120396 0.3048)
			(end -0.120396 0.2794)
			(stroke
				(width 0.1)
				(type default)
			)
			(layer "B.Fab")
		)
		(fp_line
			(start -0.67945 0.3048)
			(end -0.120396 0.3048)
			(stroke
				(width 0.1)
				(type default)
			)
			(layer "B.Fab")
		)
		(pad "1" smd circle
			(at 0.40005 0 270)
			(size 0 0)
			(layers "B.Cu" "B.Mask" "B.Paste")
			(net "CPU1_XTRIG_L6")
		)
		(pad "2" smd circle
			(at -0.40005 0 270)
			(size 0 0)
			(layers "B.Cu" "B.Mask" "B.Paste")
			(net "PVDD18_S5_P1")
		)
	)
	(footprint ""
		(layer "B.Cu")
		(at 51.766978 -429.84293 -90)
		(property "Reference" "R3473"
			(at 0 0 90)
			(layer "B.SilkS")
			(hide yes)
			(effects
				(font
					(size 1.27 1.27)
				)
				(justify mirror)
			)
		)
		(property "Value" ""
			(at 0 0 90)
			(layer "B.Fab")
			(effects
				(font
					(size 1.27 1.27)
				)
				(justify mirror)
			)
		)
		(duplicate_pad_numbers_are_jumpers no)
		(fp_line
			(start -0.7874 0.4064)
			(end 0.7874 0.4064)
			(stroke
				(width 0.1524)
				(type default)
			)
			(layer "B.SilkS")
		)
		(fp_line
			(start 0.7874 0.4064)
			(end 0.7874 -0.4064)
			(stroke
				(width 0.1524)
				(type default)
			)
			(layer "B.SilkS")
		)
		(fp_line
			(start -0.7874 -0.4064)
			(end -0.7874 0.4064)
			(stroke
				(width 0.1524)
				(type default)
			)
			(layer "B.SilkS")
		)
		(fp_line
			(start 0.7874 -0.4064)
			(end -0.7874 -0.4064)
			(stroke
				(width 0.1524)
				(type default)
			)
			(layer "B.SilkS")
		)
		(fp_line
			(start -0.67945 0.3048)
			(end -0.120396 0.3048)
			(stroke
				(width 0.1)
				(type default)
			)
			(layer "B.Fab")
		)
		(fp_line
			(start -0.120396 0.3048)
			(end -0.120396 0.2794)
			(stroke
				(width 0.1)
				(type default)
			)
			(layer "B.Fab")
		)
		(fp_line
			(start 0.12065 0.3048)
			(end 0.67945 0.3048)
			(stroke
				(width 0.1)
				(type default)
			)
			(layer "B.Fab")
		)
		(fp_line
			(start 0.67945 0.3048)
			(end 0.67945 -0.305054)
			(stroke
				(width 0.1)
				(type default)
			)
			(layer "B.Fab")
		)
		(fp_line
			(start -0.120396 0.2794)
			(end 0.12065 0.2794)
			(stroke
				(width 0.1)
				(type default)
			)
			(layer "B.Fab")
		)
		(fp_line
			(start 0.12065 0.2794)
			(end 0.12065 0.3048)
			(stroke
				(width 0.1)
				(type default)
			)
			(layer "B.Fab")
		)
		(fp_line
			(start -0.12065 -0.2794)
			(end -0.12065 -0.3048)
			(stroke
				(width 0.1)
				(type default)
			)
			(layer "B.Fab")
		)
		(fp_line
			(start 0.12065 -0.2794)
			(end -0.12065 -0.2794)
			(stroke
				(width 0.1)
				(type default)
			)
			(layer "B.Fab")
		)
		(fp_line
			(start -0.67945 -0.3048)
			(end -0.67945 0.3048)
			(stroke
				(width 0.1)
				(type default)
			)
			(layer "B.Fab")
		)
		(fp_line
			(start -0.12065 -0.3048)
			(end -0.67945 -0.3048)
			(stroke
				(width 0.1)
				(type default)
			)
			(layer "B.Fab")
		)
		(fp_line
			(start 0.12065 -0.305054)
			(end 0.12065 -0.2794)
			(stroke
				(width 0.1)
				(type default)
			)
			(layer "B.Fab")
		)
		(fp_line
			(start 0.67945 -0.305054)
			(end 0.12065 -0.305054)
			(stroke
				(width 0.1)
				(type default)
			)
			(layer "B.Fab")
		)
		(pad "1" smd circle
			(at 0.40005 0 90)
			(size 0 0)
			(layers "B.Cu" "B.Mask" "B.Paste")
			(net "GPU_PRSNT_N")
		)
		(pad "2" smd circle
			(at -0.40005 0 90)
			(size 0 0)
			(layers "B.Cu" "B.Mask" "B.Paste")
			(net "GND")
		)
	)
	(footprint ""
		(layer "B.Cu")
		(at 130.09118 -390.560052 90)
		(property "Reference" "C501"
			(at 0 0 90)
			(layer "B.SilkS")
			(hide yes)
			(effects
				(font
					(size 1.27 1.27)
				)
				(justify mirror)
			)
		)
		(property "Value" ""
			(at 0 0 90)
			(layer "B.Fab")
			(effects
				(font
					(size 1.27 1.27)
				)
				(justify mirror)
			)
		)
		(duplicate_pad_numbers_are_jumpers no)
		(fp_line
			(start 0.7874 -0.4064)
			(end -0.7874 -0.4064)
			(stroke
				(width 0.1524)
				(type default)
			)
			(layer "B.SilkS")
		)
		(fp_line
			(start -0.7874 -0.4064)
			(end -0.7874 0.4064)
			(stroke
				(width 0.1524)
				(type default)
			)
			(layer "B.SilkS")
		)
		(fp_line
			(start 0.7874 0.4064)
			(end 0.7874 -0.4064)
			(stroke
				(width 0.1524)
				(type default)
			)
			(layer "B.SilkS")
		)
		(fp_line
			(start -0.7874 0.4064)
			(end 0.7874 0.4064)
			(stroke
				(width 0.1524)
				(type default)
			)
			(layer "B.SilkS")
		)
		(fp_line
			(start 0.67945 -0.305054)
			(end 0.12065 -0.305054)
			(stroke
				(width 0.1)
				(type default)
			)
			(layer "B.Fab")
		)
		(fp_line
			(start 0.12065 -0.305054)
			(end 0.12065 -0.2794)
			(stroke
				(width 0.1)
				(type default)
			)
			(layer "B.Fab")
		)
		(fp_line
			(start -0.12065 -0.3048)
			(end -0.67945 -0.3048)
			(stroke
				(width 0.1)
				(type default)
			)
			(layer "B.Fab")
		)
		(fp_line
			(start -0.67945 -0.3048)
			(end -0.67945 0.3048)
			(stroke
				(width 0.1)
				(type default)
			)
			(layer "B.Fab")
		)
		(fp_line
			(start 0.12065 -0.2794)
			(end -0.12065 -0.2794)
			(stroke
				(width 0.1)
				(type default)
			)
			(layer "B.Fab")
		)
		(fp_line
			(start -0.12065 -0.2794)
			(end -0.12065 -0.3048)
			(stroke
				(width 0.1)
				(type default)
			)
			(layer "B.Fab")
		)
		(fp_line
			(start 0.12065 0.2794)
			(end 0.12065 0.3048)
			(stroke
				(width 0.1)
				(type default)
			)
			(layer "B.Fab")
		)
		(fp_line
			(start -0.120396 0.2794)
			(end 0.12065 0.2794)
			(stroke
				(width 0.1)
				(type default)
			)
			(layer "B.Fab")
		)
		(fp_line
			(start 0.67945 0.3048)
			(end 0.67945 -0.305054)
			(stroke
				(width 0.1)
				(type default)
			)
			(layer "B.Fab")
		)
		(fp_line
			(start 0.12065 0.3048)
			(end 0.67945 0.3048)
			(stroke
				(width 0.1)
				(type default)
			)
			(layer "B.Fab")
		)
		(fp_line
			(start -0.120396 0.3048)
			(end -0.120396 0.2794)
			(stroke
				(width 0.1)
				(type default)
			)
			(layer "B.Fab")
		)
		(fp_line
			(start -0.67945 0.3048)
			(end -0.120396 0.3048)
			(stroke
				(width 0.1)
				(type default)
			)
			(layer "B.Fab")
		)
		(pad "1" smd circle
			(at 0.40005 0 270)
			(size 0 0)
			(layers "B.Cu" "B.Mask" "B.Paste")
			(net "P0V9_CPU1_RT3_2A")
		)
		(pad "2" smd circle
			(at -0.40005 0 270)
			(size 0 0)
			(layers "B.Cu" "B.Mask" "B.Paste")
			(net "GND")
		)
	)
	(footprint ""
		(layer "B.Cu")
		(at 383.076958 -205.101952 -90)
		(property "Reference" "R429"
			(at 0 0 90)
			(layer "B.SilkS")
			(hide yes)
			(effects
				(font
					(size 1.27 1.27)
				)
				(justify mirror)
			)
		)
		(property "Value" ""
			(at 0 0 90)
			(layer "B.Fab")
			(effects
				(font
					(size 1.27 1.27)
				)
				(justify mirror)
			)
		)
		(duplicate_pad_numbers_are_jumpers no)
		(fp_line
			(start -0.7874 0.4064)
			(end 0.7874 0.4064)
			(stroke
				(width 0.1524)
				(type default)
			)
			(layer "B.SilkS")
		)
		(fp_line
			(start 0.7874 0.4064)
			(end 0.7874 -0.4064)
			(stroke
				(width 0.1524)
				(type default)
			)
			(layer "B.SilkS")
		)
		(fp_line
			(start -0.7874 -0.4064)
			(end -0.7874 0.4064)
			(stroke
				(width 0.1524)
				(type default)
			)
			(layer "B.SilkS")
		)
		(fp_line
			(start 0.7874 -0.4064)
			(end -0.7874 -0.4064)
			(stroke
				(width 0.1524)
				(type default)
			)
			(layer "B.SilkS")
		)
		(fp_line
			(start -0.67945 0.3048)
			(end -0.120396 0.3048)
			(stroke
				(width 0.1)
				(type default)
			)
			(layer "B.Fab")
		)
		(fp_line
			(start -0.120396 0.3048)
			(end -0.120396 0.2794)
			(stroke
				(width 0.1)
				(type default)
			)
			(layer "B.Fab")
		)
		(fp_line
			(start 0.12065 0.3048)
			(end 0.67945 0.3048)
			(stroke
				(width 0.1)
				(type default)
			)
			(layer "B.Fab")
		)
		(fp_line
			(start 0.67945 0.3048)
			(end 0.67945 -0.305054)
			(stroke
				(width 0.1)
				(type default)
			)
			(layer "B.Fab")
		)
		(fp_line
			(start -0.120396 0.2794)
			(end 0.12065 0.2794)
			(stroke
				(width 0.1)
				(type default)
			)
			(layer "B.Fab")
		)
		(fp_line
			(start 0.12065 0.2794)
			(end 0.12065 0.3048)
			(stroke
				(width 0.1)
				(type default)
			)
			(layer "B.Fab")
		)
		(fp_line
			(start -0.12065 -0.2794)
			(end -0.12065 -0.3048)
			(stroke
				(width 0.1)
				(type default)
			)
			(layer "B.Fab")
		)
		(fp_line
			(start 0.12065 -0.2794)
			(end -0.12065 -0.2794)
			(stroke
				(width 0.1)
				(type default)
			)
			(layer "B.Fab")
		)
		(fp_line
			(start -0.67945 -0.3048)
			(end -0.67945 0.3048)
			(stroke
				(width 0.1)
				(type default)
			)
			(layer "B.Fab")
		)
		(fp_line
			(start -0.12065 -0.3048)
			(end -0.67945 -0.3048)
			(stroke
				(width 0.1)
				(type default)
			)
			(layer "B.Fab")
		)
		(fp_line
			(start 0.12065 -0.305054)
			(end 0.12065 -0.2794)
			(stroke
				(width 0.1)
				(type default)
			)
			(layer "B.Fab")
		)
		(fp_line
			(start 0.67945 -0.305054)
			(end 0.12065 -0.305054)
			(stroke
				(width 0.1)
				(type default)
			)
			(layer "B.Fab")
		)
		(pad "1" smd rect
			(at 0.40005 0 270)
			(size 0.4572 0.508)
			(layers "B.Cu" "B.Mask" "B.Paste")
			(net "I3C_1_SPD_DDRGL_CPU0_SDA")
		)
		(pad "2" smd rect
			(at -0.40005 0 270)
			(size 0.4572 0.508)
			(layers "B.Cu" "B.Mask" "B.Paste")
			(net "I3C_1_SPD_DDRGL_CPU0_R_SDA")
		)
	)
	(footprint ""
		(layer "B.Cu")
		(at 99.480878 -139.93241 90)
		(property "Reference" "PC251"
			(at 0 0 90)
			(layer "B.SilkS")
			(hide yes)
			(effects
				(font
					(size 1.27 1.27)
				)
				(justify mirror)
			)
		)
		(property "Value" ""
			(at 0 0 90)
			(layer "B.Fab")
			(effects
				(font
					(size 1.27 1.27)
				)
				(justify mirror)
			)
		)
		(duplicate_pad_numbers_are_jumpers no)
		(fp_line
			(start 0.7874 -0.4064)
			(end -0.7874 -0.4064)
			(stroke
				(width 0.1524)
				(type default)
			)
			(layer "B.SilkS")
		)
		(fp_line
			(start -0.7874 -0.4064)
			(end -0.7874 0.4064)
			(stroke
				(width 0.1524)
				(type default)
			)
			(layer "B.SilkS")
		)
		(fp_line
			(start 0.7874 0.4064)
			(end 0.7874 -0.4064)
			(stroke
				(width 0.1524)
				(type default)
			)
			(layer "B.SilkS")
		)
		(fp_line
			(start -0.7874 0.4064)
			(end 0.7874 0.4064)
			(stroke
				(width 0.1524)
				(type default)
			)
			(layer "B.SilkS")
		)
		(fp_line
			(start 0.67945 -0.305054)
			(end 0.12065 -0.305054)
			(stroke
				(width 0.1)
				(type default)
			)
			(layer "B.Fab")
		)
		(fp_line
			(start 0.12065 -0.305054)
			(end 0.12065 -0.2794)
			(stroke
				(width 0.1)
				(type default)
			)
			(layer "B.Fab")
		)
		(fp_line
			(start -0.12065 -0.3048)
			(end -0.67945 -0.3048)
			(stroke
				(width 0.1)
				(type default)
			)
			(layer "B.Fab")
		)
		(fp_line
			(start -0.67945 -0.3048)
			(end -0.67945 0.3048)
			(stroke
				(width 0.1)
				(type default)
			)
			(layer "B.Fab")
		)
		(fp_line
			(start 0.12065 -0.2794)
			(end -0.12065 -0.2794)
			(stroke
				(width 0.1)
				(type default)
			)
			(layer "B.Fab")
		)
		(fp_line
			(start -0.12065 -0.2794)
			(end -0.12065 -0.3048)
			(stroke
				(width 0.1)
				(type default)
			)
			(layer "B.Fab")
		)
		(fp_line
			(start 0.12065 0.2794)
			(end 0.12065 0.3048)
			(stroke
				(width 0.1)
				(type default)
			)
			(layer "B.Fab")
		)
		(fp_line
			(start -0.120396 0.2794)
			(end 0.12065 0.2794)
			(stroke
				(width 0.1)
				(type default)
			)
			(layer "B.Fab")
		)
		(fp_line
			(start 0.67945 0.3048)
			(end 0.67945 -0.305054)
			(stroke
				(width 0.1)
				(type default)
			)
			(layer "B.Fab")
		)
		(fp_line
			(start 0.12065 0.3048)
			(end 0.67945 0.3048)
			(stroke
				(width 0.1)
				(type default)
			)
			(layer "B.Fab")
		)
		(fp_line
			(start -0.120396 0.3048)
			(end -0.120396 0.2794)
			(stroke
				(width 0.1)
				(type default)
			)
			(layer "B.Fab")
		)
		(fp_line
			(start -0.67945 0.3048)
			(end -0.120396 0.3048)
			(stroke
				(width 0.1)
				(type default)
			)
			(layer "B.Fab")
		)
		(pad "1" smd circle
			(at 0.40005 0 270)
			(size 0 0)
			(layers "B.Cu" "B.Mask" "B.Paste")
			(net "PVDDCR_CPU0_P1_VCCS")
		)
		(pad "2" smd circle
			(at -0.40005 0 270)
			(size 0 0)
			(layers "B.Cu" "B.Mask" "B.Paste")
			(net "GND")
		)
	)
	(footprint ""
		(layer "B.Cu")
		(at 372.313454 -262.824976)
		(property "Reference" "C2538"
			(at 0 0 0)
			(layer "B.SilkS")
			(hide yes)
			(effects
				(font
					(size 1.27 1.27)
				)
				(justify mirror)
			)
		)
		(property "Value" ""
			(at 0 0 0)
			(layer "B.Fab")
			(effects
				(font
					(size 1.27 1.27)
				)
				(justify mirror)
			)
		)
		(duplicate_pad_numbers_are_jumpers no)
		(fp_line
			(start -0.7874 -0.4064)
			(end -0.7874 0.4064)
			(stroke
				(width 0.1524)
				(type default)
			)
			(layer "B.SilkS")
		)
		(fp_line
			(start -0.7874 0.4064)
			(end 0.7874 0.4064)
			(stroke
				(width 0.1524)
				(type default)
			)
			(layer "B.SilkS")
		)
		(fp_line
			(start 0.7874 -0.4064)
			(end -0.7874 -0.4064)
			(stroke
				(width 0.1524)
				(type default)
			)
			(layer "B.SilkS")
		)
		(fp_line
			(start 0.7874 0.4064)
			(end 0.7874 -0.4064)
			(stroke
				(width 0.1524)
				(type default)
			)
			(layer "B.SilkS")
		)
		(fp_line
			(start -0.67945 -0.3048)
			(end -0.67945 0.3048)
			(stroke
				(width 0.1)
				(type default)
			)
			(layer "B.Fab")
		)
		(fp_line
			(start -0.67945 0.3048)
			(end -0.120396 0.3048)
			(stroke
				(width 0.1)
				(type default)
			)
			(layer "B.Fab")
		)
		(fp_line
			(start -0.12065 -0.3048)
			(end -0.67945 -0.3048)
			(stroke
				(width 0.1)
				(type default)
			)
			(layer "B.Fab")
		)
		(fp_line
			(start -0.12065 -0.2794)
			(end -0.12065 -0.3048)
			(stroke
				(width 0.1)
				(type default)
			)
			(layer "B.Fab")
		)
		(fp_line
			(start -0.120396 0.2794)
			(end 0.12065 0.2794)
			(stroke
				(width 0.1)
				(type default)
			)
			(layer "B.Fab")
		)
		(fp_line
			(start -0.120396 0.3048)
			(end -0.120396 0.2794)
			(stroke
				(width 0.1)
				(type default)
			)
			(layer "B.Fab")
		)
		(fp_line
			(start 0.12065 -0.305054)
			(end 0.12065 -0.2794)
			(stroke
				(width 0.1)
				(type default)
			)
			(layer "B.Fab")
		)
		(fp_line
			(start 0.12065 -0.2794)
			(end -0.12065 -0.2794)
			(stroke
				(width 0.1)
				(type default)
			)
			(layer "B.Fab")
		)
		(fp_line
			(start 0.12065 0.2794)
			(end 0.12065 0.3048)
			(stroke
				(width 0.1)
				(type default)
			)
			(layer "B.Fab")
		)
		(fp_line
			(start 0.12065 0.3048)
			(end 0.67945 0.3048)
			(stroke
				(width 0.1)
				(type default)
			)
			(layer "B.Fab")
		)
		(fp_line
			(start 0.67945 -0.305054)
			(end 0.12065 -0.305054)
			(stroke
				(width 0.1)
				(type default)
			)
			(layer "B.Fab")
		)
		(fp_line
			(start 0.67945 0.3048)
			(end 0.67945 -0.305054)
			(stroke
				(width 0.1)
				(type default)
			)
			(layer "B.Fab")
		)
		(pad "1" smd circle
			(at 0.40005 0 180)
			(size 0 0)
			(layers "B.Cu" "B.Mask" "B.Paste")
			(net "PVDDCR_SOC_P0")
		)
		(pad "2" smd circle
			(at -0.40005 0 180)
			(size 0 0)
			(layers "B.Cu" "B.Mask" "B.Paste")
			(net "GND")
		)
	)
	(footprint ""
		(layer "B.Cu")
		(at 453.921622 -390.417558 -90)
		(property "Reference" "PC6812"
			(at -0.107442 -2.997708 270)
			(unlocked yes)
			(layer "B.SilkS")
			(effects
				(font
					(size 0.7874 0.5842)
					(thickness 0.1524)
				)
				(justify left mirror)
			)
		)
		(property "Value" ""
			(at 0 0 90)
			(layer "B.Fab")
			(effects
				(font
					(size 1.27 1.27)
				)
				(justify mirror)
			)
		)
		(duplicate_pad_numbers_are_jumpers no)
		(fp_line
			(start 4.83108 2.150364)
			(end 4.447794 2.149348)
			(stroke
				(width 0.1524)
				(type default)
			)
			(layer "B.SilkS")
		)
		(fp_line
			(start -4.53898 2.15011)
			(end 4.53898 2.15011)
			(stroke
				(width 0.1524)
				(type default)
			)
			(layer "B.SilkS")
		)
		(fp_line
			(start 4.53898 2.15011)
			(end 4.53898 -2.15011)
			(stroke
				(width 0.1524)
				(type default)
			)
			(layer "B.SilkS")
		)
		(fp_line
			(start -4.53898 -2.15011)
			(end -4.53898 2.15011)
			(stroke
				(width 0.1524)
				(type default)
			)
			(layer "B.SilkS")
		)
		(fp_line
			(start 4.53898 -2.15011)
			(end -4.53898 -2.15011)
			(stroke
				(width 0.1524)
				(type default)
			)
			(layer "B.SilkS")
		)
		(fp_line
			(start 4.53898 -2.150618)
			(end 4.539742 2.152142)
			(stroke
				(width 0.1524)
				(type default)
			)
			(layer "B.SilkS")
		)
		(fp_line
			(start 4.69138 -2.150618)
			(end 4.692396 2.161032)
			(stroke
				(width 0.1524)
				(type default)
			)
			(layer "B.SilkS")
		)
		(fp_line
			(start 4.84378 -2.150618)
			(end 4.842256 2.163064)
			(stroke
				(width 0.1524)
				(type default)
			)
			(layer "B.SilkS")
		)
		(fp_line
			(start 4.84378 -2.150618)
			(end 4.53898 -2.150618)
			(stroke
				(width 0.1524)
				(type default)
			)
			(layer "B.SilkS")
		)
		(fp_line
			(start -3.64998 2.15011)
			(end 3.64998 2.15011)
			(stroke
				(width 0.1)
				(type default)
			)
			(layer "B.Fab")
		)
		(fp_line
			(start 3.64998 2.15011)
			(end 3.64998 -2.15011)
			(stroke
				(width 0.1)
				(type default)
			)
			(layer "B.Fab")
		)
		(fp_line
			(start -3.64998 -2.15011)
			(end -3.64998 2.15011)
			(stroke
				(width 0.1)
				(type default)
			)
			(layer "B.Fab")
		)
		(fp_line
			(start 3.64998 -2.15011)
			(end -3.64998 -2.15011)
			(stroke
				(width 0.1)
				(type default)
			)
			(layer "B.Fab")
		)
		(fp_text user "-"
			(at -4.585716 2.04216 270)
			(unlocked yes)
			(layer "B.SilkS")
			(effects
				(font
					(size 1.905 1.4224)
					(thickness 0.1524)
				)
				(justify left mirror)
			)
		)
		(fp_text user "+"
			(at 5.572506 -4.343908 270)
			(unlocked yes)
			(layer "B.SilkS")
			(effects
				(font
					(size 1.905 1.4224)
					(thickness 0.1524)
				)
				(justify left mirror)
			)
		)
		(fp_text user "-"
			(at -4.313174 -0.094488 270)
			(unlocked yes)
			(layer "B.Fab")
			(effects
				(font
					(size 1.905 1.4224)
					(thickness 0.1524)
				)
				(justify left mirror)
			)
		)
		(fp_text user "+"
			(at 6.214872 -0.337058 270)
			(unlocked yes)
			(layer "B.Fab")
			(effects
				(font
					(size 1.905 1.4224)
					(thickness 0.1524)
				)
				(justify left mirror)
			)
		)
		(pad "1" smd rect
			(at 3.199892 0 90)
			(size 2.413 2.8194)
			(layers "B.Cu" "B.Mask" "B.Paste")
			(net "P0V9_CPU0_RT_2D")
		)
		(pad "2" smd rect
			(at -3.199892 0 90)
			(size 2.413 2.8194)
			(layers "B.Cu" "B.Mask" "B.Paste")
			(net "GND")
		)
	)
	(footprint ""
		(layer "B.Cu")
		(at 18.838926 -97.330768 -90)
		(property "Reference" "R3655"
			(at 0 0 90)
			(layer "B.SilkS")
			(hide yes)
			(effects
				(font
					(size 1.27 1.27)
				)
				(justify mirror)
			)
		)
		(property "Value" ""
			(at 0 0 90)
			(layer "B.Fab")
			(effects
				(font
					(size 1.27 1.27)
				)
				(justify mirror)
			)
		)
		(duplicate_pad_numbers_are_jumpers no)
		(fp_line
			(start -0.7874 0.4064)
			(end 0.7874 0.4064)
			(stroke
				(width 0.1524)
				(type default)
			)
			(layer "B.SilkS")
		)
		(fp_line
			(start 0.7874 0.4064)
			(end 0.7874 -0.4064)
			(stroke
				(width 0.1524)
				(type default)
			)
			(layer "B.SilkS")
		)
		(fp_line
			(start -0.7874 -0.4064)
			(end -0.7874 0.4064)
			(stroke
				(width 0.1524)
				(type default)
			)
			(layer "B.SilkS")
		)
		(fp_line
			(start 0.7874 -0.4064)
			(end -0.7874 -0.4064)
			(stroke
				(width 0.1524)
				(type default)
			)
			(layer "B.SilkS")
		)
		(fp_line
			(start -0.67945 0.3048)
			(end -0.120396 0.3048)
			(stroke
				(width 0.1)
				(type default)
			)
			(layer "B.Fab")
		)
		(fp_line
			(start -0.120396 0.3048)
			(end -0.120396 0.2794)
			(stroke
				(width 0.1)
				(type default)
			)
			(layer "B.Fab")
		)
		(fp_line
			(start 0.12065 0.3048)
			(end 0.67945 0.3048)
			(stroke
				(width 0.1)
				(type default)
			)
			(layer "B.Fab")
		)
		(fp_line
			(start 0.67945 0.3048)
			(end 0.67945 -0.305054)
			(stroke
				(width 0.1)
				(type default)
			)
			(layer "B.Fab")
		)
		(fp_line
			(start -0.120396 0.2794)
			(end 0.12065 0.2794)
			(stroke
				(width 0.1)
				(type default)
			)
			(layer "B.Fab")
		)
		(fp_line
			(start 0.12065 0.2794)
			(end 0.12065 0.3048)
			(stroke
				(width 0.1)
				(type default)
			)
			(layer "B.Fab")
		)
		(fp_line
			(start -0.12065 -0.2794)
			(end -0.12065 -0.3048)
			(stroke
				(width 0.1)
				(type default)
			)
			(layer "B.Fab")
		)
		(fp_line
			(start 0.12065 -0.2794)
			(end -0.12065 -0.2794)
			(stroke
				(width 0.1)
				(type default)
			)
			(layer "B.Fab")
		)
		(fp_line
			(start -0.67945 -0.3048)
			(end -0.67945 0.3048)
			(stroke
				(width 0.1)
				(type default)
			)
			(layer "B.Fab")
		)
		(fp_line
			(start -0.12065 -0.3048)
			(end -0.67945 -0.3048)
			(stroke
				(width 0.1)
				(type default)
			)
			(layer "B.Fab")
		)
		(fp_line
			(start 0.12065 -0.305054)
			(end 0.12065 -0.2794)
			(stroke
				(width 0.1)
				(type default)
			)
			(layer "B.Fab")
		)
		(fp_line
			(start 0.67945 -0.305054)
			(end 0.12065 -0.305054)
			(stroke
				(width 0.1)
				(type default)
			)
			(layer "B.Fab")
		)
		(pad "1" smd circle
			(at 0.40005 0 90)
			(size 0 0)
			(layers "B.Cu" "B.Mask" "B.Paste")
			(net "P3V3_AUX")
		)
		(pad "2" smd circle
			(at -0.40005 0 90)
			(size 0 0)
			(layers "B.Cu" "B.Mask" "B.Paste")
			(net "P3V3_AUX_USB_HUB")
		)
	)
	(footprint ""
		(layer "B.Cu")
		(at 384.87858 -395.148562 90)
		(property "Reference" "C1015"
			(at 0 0 90)
			(layer "B.SilkS")
			(hide yes)
			(effects
				(font
					(size 1.27 1.27)
				)
				(justify mirror)
			)
		)
		(property "Value" ""
			(at 0 0 90)
			(layer "B.Fab")
			(effects
				(font
					(size 1.27 1.27)
				)
				(justify mirror)
			)
		)
		(duplicate_pad_numbers_are_jumpers no)
		(fp_line
			(start 0.299974 -0.150114)
			(end -0.299974 -0.150114)
			(stroke
				(width 0.1)
				(type default)
			)
			(layer "B.Fab")
		)
		(fp_line
			(start -0.299974 -0.150114)
			(end -0.299974 0.150114)
			(stroke
				(width 0.1)
				(type default)
			)
			(layer "B.Fab")
		)
		(fp_line
			(start 0.299974 0.150114)
			(end 0.299974 -0.150114)
			(stroke
				(width 0.1)
				(type default)
			)
			(layer "B.Fab")
		)
		(fp_line
			(start -0.299974 0.150114)
			(end 0.299974 0.150114)
			(stroke
				(width 0.1)
				(type default)
			)
			(layer "B.Fab")
		)
		(pad "1" smd rect
			(at 0.2667 0 270)
			(size 0.3048 0.381)
			(layers "B.Cu" "B.Mask" "B.Paste")
			(net "P0V9_CPU0_RT3_2A")
		)
		(pad "2" smd rect
			(at -0.2667 0 270)
			(size 0.3048 0.381)
			(layers "B.Cu" "B.Mask" "B.Paste")
			(net "GND")
		)
	)
	(footprint ""
		(layer "B.Cu")
		(at 383.67843 -395.148562 90)
		(property "Reference" "C1018"
			(at 0 0 90)
			(layer "B.SilkS")
			(hide yes)
			(effects
				(font
					(size 1.27 1.27)
				)
				(justify mirror)
			)
		)
		(property "Value" ""
			(at 0 0 90)
			(layer "B.Fab")
			(effects
				(font
					(size 1.27 1.27)
				)
				(justify mirror)
			)
		)
		(duplicate_pad_numbers_are_jumpers no)
		(fp_line
			(start 0.299974 -0.150114)
			(end -0.299974 -0.150114)
			(stroke
				(width 0.1)
				(type default)
			)
			(layer "B.Fab")
		)
		(fp_line
			(start -0.299974 -0.150114)
			(end -0.299974 0.150114)
			(stroke
				(width 0.1)
				(type default)
			)
			(layer "B.Fab")
		)
		(fp_line
			(start 0.299974 0.150114)
			(end 0.299974 -0.150114)
			(stroke
				(width 0.1)
				(type default)
			)
			(layer "B.Fab")
		)
		(fp_line
			(start -0.299974 0.150114)
			(end 0.299974 0.150114)
			(stroke
				(width 0.1)
				(type default)
			)
			(layer "B.Fab")
		)
		(pad "1" smd rect
			(at 0.2667 0 270)
			(size 0.3048 0.381)
			(layers "B.Cu" "B.Mask" "B.Paste")
			(net "P0V9_CPU0_RT3_2A_2D")
		)
		(pad "2" smd rect
			(at -0.2667 0 270)
			(size 0.3048 0.381)
			(layers "B.Cu" "B.Mask" "B.Paste")
			(net "GND")
		)
	)
	(footprint ""
		(layer "B.Cu")
		(at 187.325 -426.212 -90)
		(property "Reference" "U8006"
			(at -0.208534 -6.062472 270)
			(unlocked yes)
			(layer "B.SilkS")
			(effects
				(font
					(size 0.7874 0.5842)
					(thickness 0.1524)
				)
				(justify mirror)
			)
		)
		(property "Value" ""
			(at 0 0 90)
			(layer "B.Fab")
			(effects
				(font
					(size 1.27 1.27)
				)
				(justify mirror)
			)
		)
		(duplicate_pad_numbers_are_jumpers no)
		(fp_line
			(start -2.032 1.549908)
			(end 2.032 1.549908)
			(stroke
				(width 0.1524)
				(type default)
			)
			(layer "B.SilkS")
		)
		(fp_line
			(start 2.032 1.549908)
			(end 2.032 -1.549908)
			(stroke
				(width 0.1524)
				(type default)
			)
			(layer "B.SilkS")
		)
		(fp_line
			(start 0 -0.762)
			(end -0.508 -1.549908)
			(stroke
				(width 0.1524)
				(type default)
			)
			(layer "B.SilkS")
		)
		(fp_line
			(start -2.032 -1.549908)
			(end -2.032 1.549908)
			(stroke
				(width 0.1524)
				(type default)
			)
			(layer "B.SilkS")
		)
		(fp_line
			(start -0.508 -1.549908)
			(end -2.032 -1.549908)
			(stroke
				(width 0.1524)
				(type default)
			)
			(layer "B.SilkS")
		)
		(fp_line
			(start 0.508 -1.549908)
			(end 0 -0.762)
			(stroke
				(width 0.1524)
				(type default)
			)
			(layer "B.SilkS")
		)
		(fp_line
			(start 2.032 -1.549908)
			(end 0.508 -1.549908)
			(stroke
				(width 0.1524)
				(type default)
			)
			(layer "B.SilkS")
		)
		(fp_poly
			(pts
				(xy 2.036572 -2.90957) (xy 2.864358 -2.320544) (xy 1.861566 -1.787144)
			)
			(stroke
				(width 0)
				(type default)
			)
			(fill yes)
			(layer "B.SilkS")
		)
		(fp_line
			(start -0.849884 1.549908)
			(end 0.849884 1.549908)
			(stroke
				(width 0.1)
				(type default)
			)
			(layer "B.Fab")
		)
		(fp_line
			(start 0.849884 1.549908)
			(end 0.849884 -1.549908)
			(stroke
				(width 0.1)
				(type default)
			)
			(layer "B.Fab")
		)
		(fp_line
			(start -0.849884 -1.549908)
			(end -0.849884 1.549908)
			(stroke
				(width 0.1)
				(type default)
			)
			(layer "B.Fab")
		)
		(fp_line
			(start 0.849884 -1.549908)
			(end -0.849884 -1.549908)
			(stroke
				(width 0.1)
				(type default)
			)
			(layer "B.Fab")
		)
		(fp_poly
			(pts
				(xy 3.2004 -1.45796) (xy 3.2004 -0.44196) (xy 2.1844 -0.94996)
			)
			(stroke
				(width 0)
				(type default)
			)
			(fill yes)
			(layer "B.Fab")
		)
		(pad "1" smd rect
			(at 1.35001 -0.94996 180)
			(size 0.6096 1.0668)
			(layers "B.Cu" "B.Mask" "B.Paste")
			(net "OC_P2V5_COMP")
		)
		(pad "2" smd rect
			(at 1.35001 0 180)
			(size 0.6096 1.0668)
			(layers "B.Cu" "B.Mask" "B.Paste")
			(net "GND")
		)
		(pad "3" smd rect
			(at 1.35001 0.94996 180)
			(size 0.6096 1.0668)
			(layers "B.Cu" "B.Mask" "B.Paste")
			(net "HSC_OC_VOL")
		)
		(pad "4" smd rect
			(at -1.35001 0.94996 180)
			(size 0.6096 1.0668)
			(layers "B.Cu" "B.Mask" "B.Paste")
			(net "HSC_D_OC_R2")
		)
		(pad "5" smd rect
			(at -1.35001 -0.94996 180)
			(size 0.6096 1.0668)
			(layers "B.Cu" "B.Mask" "B.Paste")
			(net "P12V_AUX")
		)
	)
	(footprint ""
		(layer "B.Cu")
		(at 31.623 -361.569 -90)
		(property "Reference" "PR12"
			(at 0 0 90)
			(layer "B.SilkS")
			(hide yes)
			(effects
				(font
					(size 1.27 1.27)
				)
				(justify mirror)
			)
		)
		(property "Value" ""
			(at 0 0 90)
			(layer "B.Fab")
			(effects
				(font
					(size 1.27 1.27)
				)
				(justify mirror)
			)
		)
		(duplicate_pad_numbers_are_jumpers no)
		(fp_line
			(start -0.7874 0.4064)
			(end 0.7874 0.4064)
			(stroke
				(width 0.1524)
				(type default)
			)
			(layer "B.SilkS")
		)
		(fp_line
			(start 0.7874 0.4064)
			(end 0.7874 -0.4064)
			(stroke
				(width 0.1524)
				(type default)
			)
			(layer "B.SilkS")
		)
		(fp_line
			(start -0.7874 -0.4064)
			(end -0.7874 0.4064)
			(stroke
				(width 0.1524)
				(type default)
			)
			(layer "B.SilkS")
		)
		(fp_line
			(start 0.7874 -0.4064)
			(end -0.7874 -0.4064)
			(stroke
				(width 0.1524)
				(type default)
			)
			(layer "B.SilkS")
		)
		(fp_line
			(start -0.67945 0.3048)
			(end -0.120396 0.3048)
			(stroke
				(width 0.1)
				(type default)
			)
			(layer "B.Fab")
		)
		(fp_line
			(start -0.120396 0.3048)
			(end -0.120396 0.2794)
			(stroke
				(width 0.1)
				(type default)
			)
			(layer "B.Fab")
		)
		(fp_line
			(start 0.12065 0.3048)
			(end 0.67945 0.3048)
			(stroke
				(width 0.1)
				(type default)
			)
			(layer "B.Fab")
		)
		(fp_line
			(start 0.67945 0.3048)
			(end 0.67945 -0.305054)
			(stroke
				(width 0.1)
				(type default)
			)
			(layer "B.Fab")
		)
		(fp_line
			(start -0.120396 0.2794)
			(end 0.12065 0.2794)
			(stroke
				(width 0.1)
				(type default)
			)
			(layer "B.Fab")
		)
		(fp_line
			(start 0.12065 0.2794)
			(end 0.12065 0.3048)
			(stroke
				(width 0.1)
				(type default)
			)
			(layer "B.Fab")
		)
		(fp_line
			(start -0.12065 -0.2794)
			(end -0.12065 -0.3048)
			(stroke
				(width 0.1)
				(type default)
			)
			(layer "B.Fab")
		)
		(fp_line
			(start 0.12065 -0.2794)
			(end -0.12065 -0.2794)
			(stroke
				(width 0.1)
				(type default)
			)
			(layer "B.Fab")
		)
		(fp_line
			(start -0.67945 -0.3048)
			(end -0.67945 0.3048)
			(stroke
				(width 0.1)
				(type default)
			)
			(layer "B.Fab")
		)
		(fp_line
			(start -0.12065 -0.3048)
			(end -0.67945 -0.3048)
			(stroke
				(width 0.1)
				(type default)
			)
			(layer "B.Fab")
		)
		(fp_line
			(start 0.12065 -0.305054)
			(end 0.12065 -0.2794)
			(stroke
				(width 0.1)
				(type default)
			)
			(layer "B.Fab")
		)
		(fp_line
			(start 0.67945 -0.305054)
			(end 0.12065 -0.305054)
			(stroke
				(width 0.1)
				(type default)
			)
			(layer "B.Fab")
		)
		(pad "1" smd circle
			(at 0.40005 0 90)
			(size 0 0)
			(layers "B.Cu" "B.Mask" "B.Paste")
			(net "NC_PVDDCR_CPU1_P1_IMON8")
		)
		(pad "2" smd circle
			(at -0.40005 0 90)
			(size 0 0)
			(layers "B.Cu" "B.Mask" "B.Paste")
			(net "GND")
		)
	)
	(footprint ""
		(layer "B.Cu")
		(at 350.318832 -398.942052 90)
		(property "Reference" "C648"
			(at 0 0 90)
			(layer "B.SilkS")
			(hide yes)
			(effects
				(font
					(size 1.27 1.27)
				)
				(justify mirror)
			)
		)
		(property "Value" ""
			(at 0 0 90)
			(layer "B.Fab")
			(effects
				(font
					(size 1.27 1.27)
				)
				(justify mirror)
			)
		)
		(duplicate_pad_numbers_are_jumpers no)
		(fp_line
			(start 0.7874 -0.4064)
			(end -0.7874 -0.4064)
			(stroke
				(width 0.1524)
				(type default)
			)
			(layer "B.SilkS")
		)
		(fp_line
			(start -0.7874 -0.4064)
			(end -0.7874 0.4064)
			(stroke
				(width 0.1524)
				(type default)
			)
			(layer "B.SilkS")
		)
		(fp_line
			(start 0.7874 0.4064)
			(end 0.7874 -0.4064)
			(stroke
				(width 0.1524)
				(type default)
			)
			(layer "B.SilkS")
		)
		(fp_line
			(start -0.7874 0.4064)
			(end 0.7874 0.4064)
			(stroke
				(width 0.1524)
				(type default)
			)
			(layer "B.SilkS")
		)
		(fp_line
			(start 0.67945 -0.305054)
			(end 0.12065 -0.305054)
			(stroke
				(width 0.1)
				(type default)
			)
			(layer "B.Fab")
		)
		(fp_line
			(start 0.12065 -0.305054)
			(end 0.12065 -0.2794)
			(stroke
				(width 0.1)
				(type default)
			)
			(layer "B.Fab")
		)
		(fp_line
			(start -0.12065 -0.3048)
			(end -0.67945 -0.3048)
			(stroke
				(width 0.1)
				(type default)
			)
			(layer "B.Fab")
		)
		(fp_line
			(start -0.67945 -0.3048)
			(end -0.67945 0.3048)
			(stroke
				(width 0.1)
				(type default)
			)
			(layer "B.Fab")
		)
		(fp_line
			(start 0.12065 -0.2794)
			(end -0.12065 -0.2794)
			(stroke
				(width 0.1)
				(type default)
			)
			(layer "B.Fab")
		)
		(fp_line
			(start -0.12065 -0.2794)
			(end -0.12065 -0.3048)
			(stroke
				(width 0.1)
				(type default)
			)
			(layer "B.Fab")
		)
		(fp_line
			(start 0.12065 0.2794)
			(end 0.12065 0.3048)
			(stroke
				(width 0.1)
				(type default)
			)
			(layer "B.Fab")
		)
		(fp_line
			(start -0.120396 0.2794)
			(end 0.12065 0.2794)
			(stroke
				(width 0.1)
				(type default)
			)
			(layer "B.Fab")
		)
		(fp_line
			(start 0.67945 0.3048)
			(end 0.67945 -0.305054)
			(stroke
				(width 0.1)
				(type default)
			)
			(layer "B.Fab")
		)
		(fp_line
			(start 0.12065 0.3048)
			(end 0.67945 0.3048)
			(stroke
				(width 0.1)
				(type default)
			)
			(layer "B.Fab")
		)
		(fp_line
			(start -0.120396 0.3048)
			(end -0.120396 0.2794)
			(stroke
				(width 0.1)
				(type default)
			)
			(layer "B.Fab")
		)
		(fp_line
			(start -0.67945 0.3048)
			(end -0.120396 0.3048)
			(stroke
				(width 0.1)
				(type default)
			)
			(layer "B.Fab")
		)
		(pad "1" smd circle
			(at 0.40005 0 270)
			(size 0 0)
			(layers "B.Cu" "B.Mask" "B.Paste")
			(net "P0V9_CPU0_RT1_2A")
		)
		(pad "2" smd circle
			(at -0.40005 0 270)
			(size 0 0)
			(layers "B.Cu" "B.Mask" "B.Paste")
			(net "GND")
		)
	)
	(footprint ""
		(layer "B.Cu")
		(at 171.972224 -192.66027 180)
		(property "Reference" "C532"
			(at 0 0 0)
			(layer "B.SilkS")
			(hide yes)
			(effects
				(font
					(size 1.27 1.27)
				)
				(justify mirror)
			)
		)
		(property "Value" ""
			(at 0 0 0)
			(layer "B.Fab")
			(effects
				(font
					(size 1.27 1.27)
				)
				(justify mirror)
			)
		)
		(duplicate_pad_numbers_are_jumpers no)
		(fp_line
			(start 1.524 0.762)
			(end 1.524 -0.762)
			(stroke
				(width 0.1524)
				(type default)
			)
			(layer "B.SilkS")
		)
		(fp_line
			(start 1.524 -0.762)
			(end -1.524 -0.762)
			(stroke
				(width 0.1524)
				(type default)
			)
			(layer "B.SilkS")
		)
		(fp_line
			(start -1.524 0.762)
			(end 1.524 0.762)
			(stroke
				(width 0.1524)
				(type default)
			)
			(layer "B.SilkS")
		)
		(fp_line
			(start -1.524 -0.762)
			(end -1.524 0.762)
			(stroke
				(width 0.1524)
				(type default)
			)
			(layer "B.SilkS")
		)
		(fp_line
			(start 1.1049 0.724916)
			(end -1.1049 0.724916)
			(stroke
				(width 0.1)
				(type default)
			)
			(layer "B.Fab")
		)
		(fp_line
			(start 1.1049 -0.724916)
			(end 1.1049 0.724916)
			(stroke
				(width 0.1)
				(type default)
			)
			(layer "B.Fab")
		)
		(fp_line
			(start -1.1049 0.724916)
			(end -1.1049 -0.724916)
			(stroke
				(width 0.1)
				(type default)
			)
			(layer "B.Fab")
		)
		(fp_line
			(start -1.1049 -0.724916)
			(end 1.1049 -0.724916)
			(stroke
				(width 0.1)
				(type default)
			)
			(layer "B.Fab")
		)
		(pad "1" smd rect
			(at 0.889 0 180)
			(size 1.016 1.27)
			(layers "B.Cu" "B.Mask" "B.Paste")
			(net "P12V_MEM_CPU1")
		)
		(pad "2" smd rect
			(at -0.889 0 180)
			(size 1.016 1.27)
			(layers "B.Cu" "B.Mask" "B.Paste")
			(net "GND")
		)
	)
	(footprint ""
		(layer "B.Cu")
		(at 404.475696 -344.300302)
		(property "Reference" "U101"
			(at 5.969 -0.980948 0)
			(unlocked yes)
			(layer "B.SilkS")
			(effects
				(font
					(size 0.7874 0.5842)
					(thickness 0.1524)
				)
				(justify left mirror)
			)
		)
		(property "Value" ""
			(at 0 0 0)
			(layer "B.Fab")
			(effects
				(font
					(size 1.27 1.27)
				)
				(justify mirror)
			)
		)
		(duplicate_pad_numbers_are_jumpers no)
		(fp_line
			(start -2.0574 -1.651)
			(end -2.0574 1.651)
			(stroke
				(width 0.1524)
				(type default)
			)
			(layer "B.SilkS")
		)
		(fp_line
			(start -2.0574 1.651)
			(end 2.0574 1.651)
			(stroke
				(width 0.1524)
				(type default)
			)
			(layer "B.SilkS")
		)
		(fp_line
			(start -0.381 -1.651)
			(end -2.0574 -1.651)
			(stroke
				(width 0.1524)
				(type default)
			)
			(layer "B.SilkS")
		)
		(fp_line
			(start 0 -1.016)
			(end -0.381 -1.651)
			(stroke
				(width 0.1524)
				(type default)
			)
			(layer "B.SilkS")
		)
		(fp_line
			(start 0.381 -1.651)
			(end 0 -1.016)
			(stroke
				(width 0.1524)
				(type default)
			)
			(layer "B.SilkS")
		)
		(fp_line
			(start 2.0574 -1.651)
			(end 0.381 -1.651)
			(stroke
				(width 0.1524)
				(type default)
			)
			(layer "B.SilkS")
		)
		(fp_line
			(start 2.0574 1.651)
			(end 2.0574 -1.651)
			(stroke
				(width 0.1524)
				(type default)
			)
			(layer "B.SilkS")
		)
		(fp_poly
			(pts
				(xy 2.159 -1.016) (xy 2.71272 -0.719328) (xy 2.71272 -1.344168)
			)
			(stroke
				(width 0)
				(type default)
			)
			(fill yes)
			(layer "B.SilkS")
		)
		(fp_line
			(start -1.599946 -1.199896)
			(end -1.599946 1.199896)
			(stroke
				(width 0.1)
				(type default)
			)
			(layer "B.Fab")
		)
		(fp_line
			(start -1.599946 1.199896)
			(end -0.899922 1.199896)
			(stroke
				(width 0.1)
				(type default)
			)
			(layer "B.Fab")
		)
		(fp_line
			(start -0.899922 -1.549908)
			(end -0.899922 -1.199896)
			(stroke
				(width 0.1)
				(type default)
			)
			(layer "B.Fab")
		)
		(fp_line
			(start -0.899922 -1.199896)
			(end -1.599946 -1.199896)
			(stroke
				(width 0.1)
				(type default)
			)
			(layer "B.Fab")
		)
		(fp_line
			(start -0.899922 1.199896)
			(end -0.899922 1.549908)
			(stroke
				(width 0.1)
				(type default)
			)
			(layer "B.Fab")
		)
		(fp_line
			(start -0.899922 1.549908)
			(end 0.899922 1.549908)
			(stroke
				(width 0.1)
				(type default)
			)
			(layer "B.Fab")
		)
		(fp_line
			(start 0.899922 -1.549908)
			(end -0.899922 -1.549908)
			(stroke
				(width 0.1)
				(type default)
			)
			(layer "B.Fab")
		)
		(fp_line
			(start 0.899922 -1.199896)
			(end 0.899922 -1.549908)
			(stroke
				(width 0.1)
				(type default)
			)
			(layer "B.Fab")
		)
		(fp_line
			(start 0.899922 1.199896)
			(end 1.599946 1.199896)
			(stroke
				(width 0.1)
				(type default)
			)
			(layer "B.Fab")
		)
		(fp_line
			(start 0.899922 1.549908)
			(end 0.899922 1.199896)
			(stroke
				(width 0.1)
				(type default)
			)
			(layer "B.Fab")
		)
		(fp_line
			(start 1.599946 -1.199896)
			(end 0.899922 -1.199896)
			(stroke
				(width 0.1)
				(type default)
			)
			(layer "B.Fab")
		)
		(fp_line
			(start 1.599946 1.199896)
			(end 1.599946 -1.199896)
			(stroke
				(width 0.1)
				(type default)
			)
			(layer "B.Fab")
		)
		(fp_poly
			(pts
				(xy 2.71272 -0.719328) (xy 2.71272 -1.344168) (xy 2.159 -1.016)
			)
			(stroke
				(width 0)
				(type default)
			)
			(fill yes)
			(layer "B.Fab")
		)
		(pad "1" smd rect
			(at 1.225042 -0.94996 270)
			(size 0.5588 1.3462)
			(layers "B.Cu" "B.Mask" "B.Paste")
			(net "Net_10729")
		)
		(pad "2" smd rect
			(at 1.225042 0 270)
			(size 0.5588 1.3462)
			(layers "B.Cu" "B.Mask" "B.Paste")
			(net "FM_BIOS_POST_CMPLT_N")
		)
		(pad "3" smd rect
			(at 1.225042 0.94996 270)
			(size 0.5588 1.3462)
			(layers "B.Cu" "B.Mask" "B.Paste")
			(net "GND")
		)
		(pad "4" smd rect
			(at -1.225042 0.94996 270)
			(size 0.5588 1.3462)
			(layers "B.Cu" "B.Mask" "B.Paste")
			(net "FM_BIOS_POST_CMPLT_BUF_R1_N")
		)
		(pad "5" smd rect
			(at -1.225042 -0.94996 270)
			(size 0.5588 1.3462)
			(layers "B.Cu" "B.Mask" "B.Paste")
			(net "PVDD18_S5_P0")
		)
	)
	(footprint ""
		(layer "B.Cu")
		(at 185.201814 -357.667052)
		(property "Reference" "PC521_1"
			(at 0 0 0)
			(layer "B.SilkS")
			(hide yes)
			(effects
				(font
					(size 1.27 1.27)
				)
				(justify mirror)
			)
		)
		(property "Value" ""
			(at 0 0 0)
			(layer "B.Fab")
			(effects
				(font
					(size 1.27 1.27)
				)
				(justify mirror)
			)
		)
		(duplicate_pad_numbers_are_jumpers no)
		(fp_line
			(start -1.524 -0.762)
			(end -1.524 0.762)
			(stroke
				(width 0.1524)
				(type default)
			)
			(layer "B.SilkS")
		)
		(fp_line
			(start -1.524 0.762)
			(end 1.524 0.762)
			(stroke
				(width 0.1524)
				(type default)
			)
			(layer "B.SilkS")
		)
		(fp_line
			(start 1.524 -0.762)
			(end -1.524 -0.762)
			(stroke
				(width 0.1524)
				(type default)
			)
			(layer "B.SilkS")
		)
		(fp_line
			(start 1.524 0.762)
			(end 1.524 -0.762)
			(stroke
				(width 0.1524)
				(type default)
			)
			(layer "B.SilkS")
		)
		(fp_line
			(start -1.1049 -0.724916)
			(end 1.1049 -0.724916)
			(stroke
				(width 0.1)
				(type default)
			)
			(layer "B.Fab")
		)
		(fp_line
			(start -1.1049 0.724916)
			(end -1.1049 -0.724916)
			(stroke
				(width 0.1)
				(type default)
			)
			(layer "B.Fab")
		)
		(fp_line
			(start 1.1049 -0.724916)
			(end 1.1049 0.724916)
			(stroke
				(width 0.1)
				(type default)
			)
			(layer "B.Fab")
		)
		(fp_line
			(start 1.1049 0.724916)
			(end -1.1049 0.724916)
			(stroke
				(width 0.1)
				(type default)
			)
			(layer "B.Fab")
		)
		(pad "1" smd rect
			(at 0.889 0)
			(size 1.016 1.27)
			(layers "B.Cu" "B.Mask" "B.Paste")
			(net "SW_P12V_AUX_PVDD11_S3_P1_FLT")
		)
		(pad "2" smd rect
			(at -0.889 0)
			(size 1.016 1.27)
			(layers "B.Cu" "B.Mask" "B.Paste")
			(net "GND")
		)
	)
	(footprint ""
		(layer "B.Cu")
		(at 43.576748 -194.987164 180)
		(property "Reference" "R1582"
			(at 0 0 0)
			(layer "B.SilkS")
			(hide yes)
			(effects
				(font
					(size 1.27 1.27)
				)
				(justify mirror)
			)
		)
		(property "Value" ""
			(at 0 0 0)
			(layer "B.Fab")
			(effects
				(font
					(size 1.27 1.27)
				)
				(justify mirror)
			)
		)
		(duplicate_pad_numbers_are_jumpers no)
		(fp_line
			(start 0.7874 0.4064)
			(end 0.7874 -0.4064)
			(stroke
				(width 0.1524)
				(type default)
			)
			(layer "B.SilkS")
		)
		(fp_line
			(start 0.7874 -0.4064)
			(end -0.7874 -0.4064)
			(stroke
				(width 0.1524)
				(type default)
			)
			(layer "B.SilkS")
		)
		(fp_line
			(start -0.7874 0.4064)
			(end 0.7874 0.4064)
			(stroke
				(width 0.1524)
				(type default)
			)
			(layer "B.SilkS")
		)
		(fp_line
			(start -0.7874 -0.4064)
			(end -0.7874 0.4064)
			(stroke
				(width 0.1524)
				(type default)
			)
			(layer "B.SilkS")
		)
		(fp_line
			(start 0.67945 0.3048)
			(end 0.67945 -0.305054)
			(stroke
				(width 0.1)
				(type default)
			)
			(layer "B.Fab")
		)
		(fp_line
			(start 0.67945 -0.305054)
			(end 0.12065 -0.305054)
			(stroke
				(width 0.1)
				(type default)
			)
			(layer "B.Fab")
		)
		(fp_line
			(start 0.12065 0.3048)
			(end 0.67945 0.3048)
			(stroke
				(width 0.1)
				(type default)
			)
			(layer "B.Fab")
		)
		(fp_line
			(start 0.12065 0.2794)
			(end 0.12065 0.3048)
			(stroke
				(width 0.1)
				(type default)
			)
			(layer "B.Fab")
		)
		(fp_line
			(start 0.12065 -0.2794)
			(end -0.12065 -0.2794)
			(stroke
				(width 0.1)
				(type default)
			)
			(layer "B.Fab")
		)
		(fp_line
			(start 0.12065 -0.305054)
			(end 0.12065 -0.2794)
			(stroke
				(width 0.1)
				(type default)
			)
			(layer "B.Fab")
		)
		(fp_line
			(start -0.120396 0.3048)
			(end -0.120396 0.2794)
			(stroke
				(width 0.1)
				(type default)
			)
			(layer "B.Fab")
		)
		(fp_line
			(start -0.120396 0.2794)
			(end 0.12065 0.2794)
			(stroke
				(width 0.1)
				(type default)
			)
			(layer "B.Fab")
		)
		(fp_line
			(start -0.12065 -0.2794)
			(end -0.12065 -0.3048)
			(stroke
				(width 0.1)
				(type default)
			)
			(layer "B.Fab")
		)
		(fp_line
			(start -0.12065 -0.3048)
			(end -0.67945 -0.3048)
			(stroke
				(width 0.1)
				(type default)
			)
			(layer "B.Fab")
		)
		(fp_line
			(start -0.67945 0.3048)
			(end -0.120396 0.3048)
			(stroke
				(width 0.1)
				(type default)
			)
			(layer "B.Fab")
		)
		(fp_line
			(start -0.67945 -0.3048)
			(end -0.67945 0.3048)
			(stroke
				(width 0.1)
				(type default)
			)
			(layer "B.Fab")
		)
		(pad "1" smd circle
			(at 0.40005 0)
			(size 0 0)
			(layers "B.Cu" "B.Mask" "B.Paste")
			(net "I3C_SPD_DDRAF_CPU1_SCL")
		)
		(pad "2" smd circle
			(at -0.40005 0)
			(size 0 0)
			(layers "B.Cu" "B.Mask" "B.Paste")
			(net "I3C_SPD_DDRC_CPU1_SCL")
		)
	)
	(footprint ""
		(layer "B.Cu")
		(at 406.698958 -324.862952)
		(property "Reference" "R455"
			(at 0 0 0)
			(layer "B.SilkS")
			(hide yes)
			(effects
				(font
					(size 1.27 1.27)
				)
				(justify mirror)
			)
		)
		(property "Value" ""
			(at 0 0 0)
			(layer "B.Fab")
			(effects
				(font
					(size 1.27 1.27)
				)
				(justify mirror)
			)
		)
		(duplicate_pad_numbers_are_jumpers no)
		(fp_line
			(start -0.7874 -0.4064)
			(end -0.7874 0.4064)
			(stroke
				(width 0.1524)
				(type default)
			)
			(layer "B.SilkS")
		)
		(fp_line
			(start -0.7874 0.4064)
			(end 0.7874 0.4064)
			(stroke
				(width 0.1524)
				(type default)
			)
			(layer "B.SilkS")
		)
		(fp_line
			(start 0.7874 -0.4064)
			(end -0.7874 -0.4064)
			(stroke
				(width 0.1524)
				(type default)
			)
			(layer "B.SilkS")
		)
		(fp_line
			(start 0.7874 0.4064)
			(end 0.7874 -0.4064)
			(stroke
				(width 0.1524)
				(type default)
			)
			(layer "B.SilkS")
		)
		(fp_line
			(start -0.67945 -0.3048)
			(end -0.67945 0.3048)
			(stroke
				(width 0.1)
				(type default)
			)
			(layer "B.Fab")
		)
		(fp_line
			(start -0.67945 0.3048)
			(end -0.120396 0.3048)
			(stroke
				(width 0.1)
				(type default)
			)
			(layer "B.Fab")
		)
		(fp_line
			(start -0.12065 -0.3048)
			(end -0.67945 -0.3048)
			(stroke
				(width 0.1)
				(type default)
			)
			(layer "B.Fab")
		)
		(fp_line
			(start -0.12065 -0.2794)
			(end -0.12065 -0.3048)
			(stroke
				(width 0.1)
				(type default)
			)
			(layer "B.Fab")
		)
		(fp_line
			(start -0.120396 0.2794)
			(end 0.12065 0.2794)
			(stroke
				(width 0.1)
				(type default)
			)
			(layer "B.Fab")
		)
		(fp_line
			(start -0.120396 0.3048)
			(end -0.120396 0.2794)
			(stroke
				(width 0.1)
				(type default)
			)
			(layer "B.Fab")
		)
		(fp_line
			(start 0.12065 -0.305054)
			(end 0.12065 -0.2794)
			(stroke
				(width 0.1)
				(type default)
			)
			(layer "B.Fab")
		)
		(fp_line
			(start 0.12065 -0.2794)
			(end -0.12065 -0.2794)
			(stroke
				(width 0.1)
				(type default)
			)
			(layer "B.Fab")
		)
		(fp_line
			(start 0.12065 0.2794)
			(end 0.12065 0.3048)
			(stroke
				(width 0.1)
				(type default)
			)
			(layer "B.Fab")
		)
		(fp_line
			(start 0.12065 0.3048)
			(end 0.67945 0.3048)
			(stroke
				(width 0.1)
				(type default)
			)
			(layer "B.Fab")
		)
		(fp_line
			(start 0.67945 -0.305054)
			(end 0.12065 -0.305054)
			(stroke
				(width 0.1)
				(type default)
			)
			(layer "B.Fab")
		)
		(fp_line
			(start 0.67945 0.3048)
			(end 0.67945 -0.305054)
			(stroke
				(width 0.1)
				(type default)
			)
			(layer "B.Fab")
		)
		(pad "1" smd circle
			(at 0.40005 0 180)
			(size 0 0)
			(layers "B.Cu" "B.Mask" "B.Paste")
			(net "PVDD18_S5_P0")
		)
		(pad "2" smd circle
			(at -0.40005 0 180)
			(size 0 0)
			(layers "B.Cu" "B.Mask" "B.Paste")
			(net "ESPI_CPU0_CS1_N")
		)
	)
	(footprint ""
		(layer "B.Cu")
		(at 154.348434 -199.234552 -90)
		(property "Reference" "C230"
			(at 0 0 90)
			(layer "B.SilkS")
			(hide yes)
			(effects
				(font
					(size 1.27 1.27)
				)
				(justify mirror)
			)
		)
		(property "Value" ""
			(at 0 0 90)
			(layer "B.Fab")
			(effects
				(font
					(size 1.27 1.27)
				)
				(justify mirror)
			)
		)
		(duplicate_pad_numbers_are_jumpers no)
		(fp_line
			(start -0.7874 0.4064)
			(end 0.7874 0.4064)
			(stroke
				(width 0.1524)
				(type default)
			)
			(layer "B.SilkS")
		)
		(fp_line
			(start 0.7874 0.4064)
			(end 0.7874 -0.4064)
			(stroke
				(width 0.1524)
				(type default)
			)
			(layer "B.SilkS")
		)
		(fp_line
			(start -0.7874 -0.4064)
			(end -0.7874 0.4064)
			(stroke
				(width 0.1524)
				(type default)
			)
			(layer "B.SilkS")
		)
		(fp_line
			(start 0.7874 -0.4064)
			(end -0.7874 -0.4064)
			(stroke
				(width 0.1524)
				(type default)
			)
			(layer "B.SilkS")
		)
		(fp_line
			(start -0.67945 0.3048)
			(end -0.120396 0.3048)
			(stroke
				(width 0.1)
				(type default)
			)
			(layer "B.Fab")
		)
		(fp_line
			(start -0.120396 0.3048)
			(end -0.120396 0.2794)
			(stroke
				(width 0.1)
				(type default)
			)
			(layer "B.Fab")
		)
		(fp_line
			(start 0.12065 0.3048)
			(end 0.67945 0.3048)
			(stroke
				(width 0.1)
				(type default)
			)
			(layer "B.Fab")
		)
		(fp_line
			(start 0.67945 0.3048)
			(end 0.67945 -0.305054)
			(stroke
				(width 0.1)
				(type default)
			)
			(layer "B.Fab")
		)
		(fp_line
			(start -0.120396 0.2794)
			(end 0.12065 0.2794)
			(stroke
				(width 0.1)
				(type default)
			)
			(layer "B.Fab")
		)
		(fp_line
			(start 0.12065 0.2794)
			(end 0.12065 0.3048)
			(stroke
				(width 0.1)
				(type default)
			)
			(layer "B.Fab")
		)
		(fp_line
			(start -0.12065 -0.2794)
			(end -0.12065 -0.3048)
			(stroke
				(width 0.1)
				(type default)
			)
			(layer "B.Fab")
		)
		(fp_line
			(start 0.12065 -0.2794)
			(end -0.12065 -0.2794)
			(stroke
				(width 0.1)
				(type default)
			)
			(layer "B.Fab")
		)
		(fp_line
			(start -0.67945 -0.3048)
			(end -0.67945 0.3048)
			(stroke
				(width 0.1)
				(type default)
			)
			(layer "B.Fab")
		)
		(fp_line
			(start -0.12065 -0.3048)
			(end -0.67945 -0.3048)
			(stroke
				(width 0.1)
				(type default)
			)
			(layer "B.Fab")
		)
		(fp_line
			(start 0.12065 -0.305054)
			(end 0.12065 -0.2794)
			(stroke
				(width 0.1)
				(type default)
			)
			(layer "B.Fab")
		)
		(fp_line
			(start 0.67945 -0.305054)
			(end 0.12065 -0.305054)
			(stroke
				(width 0.1)
				(type default)
			)
			(layer "B.Fab")
		)
		(pad "1" smd circle
			(at 0.40005 0 90)
			(size 0 0)
			(layers "B.Cu" "B.Mask" "B.Paste")
			(net "JTAG_CPU1_TDO")
		)
		(pad "2" smd circle
			(at -0.40005 0 90)
			(size 0 0)
			(layers "B.Cu" "B.Mask" "B.Paste")
			(net "GND")
		)
	)
	(footprint ""
		(layer "B.Cu")
		(at 434.797454 -191.20231 180)
		(property "Reference" "R300"
			(at 0 0 0)
			(layer "B.SilkS")
			(hide yes)
			(effects
				(font
					(size 1.27 1.27)
				)
				(justify mirror)
			)
		)
		(property "Value" ""
			(at 0 0 0)
			(layer "B.Fab")
			(effects
				(font
					(size 1.27 1.27)
				)
				(justify mirror)
			)
		)
		(duplicate_pad_numbers_are_jumpers no)
		(fp_line
			(start 0.7874 0.4064)
			(end 0.7874 -0.4064)
			(stroke
				(width 0.1524)
				(type default)
			)
			(layer "B.SilkS")
		)
		(fp_line
			(start 0.7874 -0.4064)
			(end -0.7874 -0.4064)
			(stroke
				(width 0.1524)
				(type default)
			)
			(layer "B.SilkS")
		)
		(fp_line
			(start -0.7874 0.4064)
			(end 0.7874 0.4064)
			(stroke
				(width 0.1524)
				(type default)
			)
			(layer "B.SilkS")
		)
		(fp_line
			(start -0.7874 -0.4064)
			(end -0.7874 0.4064)
			(stroke
				(width 0.1524)
				(type default)
			)
			(layer "B.SilkS")
		)
		(fp_line
			(start 0.67945 0.3048)
			(end 0.67945 -0.305054)
			(stroke
				(width 0.1)
				(type default)
			)
			(layer "B.Fab")
		)
		(fp_line
			(start 0.67945 -0.305054)
			(end 0.12065 -0.305054)
			(stroke
				(width 0.1)
				(type default)
			)
			(layer "B.Fab")
		)
		(fp_line
			(start 0.12065 0.3048)
			(end 0.67945 0.3048)
			(stroke
				(width 0.1)
				(type default)
			)
			(layer "B.Fab")
		)
		(fp_line
			(start 0.12065 0.2794)
			(end 0.12065 0.3048)
			(stroke
				(width 0.1)
				(type default)
			)
			(layer "B.Fab")
		)
		(fp_line
			(start 0.12065 -0.2794)
			(end -0.12065 -0.2794)
			(stroke
				(width 0.1)
				(type default)
			)
			(layer "B.Fab")
		)
		(fp_line
			(start 0.12065 -0.305054)
			(end 0.12065 -0.2794)
			(stroke
				(width 0.1)
				(type default)
			)
			(layer "B.Fab")
		)
		(fp_line
			(start -0.120396 0.3048)
			(end -0.120396 0.2794)
			(stroke
				(width 0.1)
				(type default)
			)
			(layer "B.Fab")
		)
		(fp_line
			(start -0.120396 0.2794)
			(end 0.12065 0.2794)
			(stroke
				(width 0.1)
				(type default)
			)
			(layer "B.Fab")
		)
		(fp_line
			(start -0.12065 -0.2794)
			(end -0.12065 -0.3048)
			(stroke
				(width 0.1)
				(type default)
			)
			(layer "B.Fab")
		)
		(fp_line
			(start -0.12065 -0.3048)
			(end -0.67945 -0.3048)
			(stroke
				(width 0.1)
				(type default)
			)
			(layer "B.Fab")
		)
		(fp_line
			(start -0.67945 0.3048)
			(end -0.120396 0.3048)
			(stroke
				(width 0.1)
				(type default)
			)
			(layer "B.Fab")
		)
		(fp_line
			(start -0.67945 -0.3048)
			(end -0.67945 0.3048)
			(stroke
				(width 0.1)
				(type default)
			)
			(layer "B.Fab")
		)
		(pad "1" smd circle
			(at 0.40005 0)
			(size 0 0)
			(layers "B.Cu" "B.Mask" "B.Paste")
			(net "PWRGD_CHJ_CPU0_DIMM")
		)
		(pad "2" smd circle
			(at -0.40005 0)
			(size 0 0)
			(layers "B.Cu" "B.Mask" "B.Paste")
			(net "PWRGD_CHGL_CPU0")
		)
	)
	(footprint ""
		(layer "B.Cu")
		(at 216.916 -336.169 -90)
		(property "Reference" "R6738"
			(at 0 0 90)
			(layer "B.SilkS")
			(hide yes)
			(effects
				(font
					(size 1.27 1.27)
				)
				(justify mirror)
			)
		)
		(property "Value" ""
			(at 0 0 90)
			(layer "B.Fab")
			(effects
				(font
					(size 1.27 1.27)
				)
				(justify mirror)
			)
		)
		(duplicate_pad_numbers_are_jumpers no)
		(fp_line
			(start -0.32512 0.175006)
			(end 0.32512 0.175006)
			(stroke
				(width 0.1)
				(type default)
			)
			(layer "B.Fab")
		)
		(fp_line
			(start 0.32512 0.175006)
			(end 0.32512 -0.175006)
			(stroke
				(width 0.1)
				(type default)
			)
			(layer "B.Fab")
		)
		(fp_line
			(start -0.32512 -0.175006)
			(end -0.32512 0.175006)
			(stroke
				(width 0.1)
				(type default)
			)
			(layer "B.Fab")
		)
		(fp_line
			(start 0.32512 -0.175006)
			(end -0.32512 -0.175006)
			(stroke
				(width 0.1)
				(type default)
			)
			(layer "B.Fab")
		)
		(pad "1" smd rect
			(at 0.2667 0 90)
			(size 0.3048 0.381)
			(layers "B.Cu" "B.Mask" "B.Paste")
			(net "P1V8_CPU1_RT_1D")
		)
		(pad "2" smd rect
			(at -0.2667 0 270)
			(size 0.3048 0.381)
			(layers "B.Cu" "B.Mask" "B.Paste")
			(net "SMB_RT_CPU1_P1_R_SDA")
		)
	)
	(footprint ""
		(layer "B.Cu")
		(at 329.889358 -401.624546 180)
		(property "Reference" "R1011"
			(at 0 0 0)
			(layer "B.SilkS")
			(hide yes)
			(effects
				(font
					(size 1.27 1.27)
				)
				(justify mirror)
			)
		)
		(property "Value" ""
			(at 0 0 0)
			(layer "B.Fab")
			(effects
				(font
					(size 1.27 1.27)
				)
				(justify mirror)
			)
		)
		(duplicate_pad_numbers_are_jumpers no)
		(fp_line
			(start 1.2954 0.5842)
			(end 1.2954 -0.5842)
			(stroke
				(width 0.1524)
				(type default)
			)
			(layer "B.SilkS")
		)
		(fp_line
			(start 1.2954 -0.5842)
			(end -1.2954 -0.5842)
			(stroke
				(width 0.1524)
				(type default)
			)
			(layer "B.SilkS")
		)
		(fp_line
			(start -1.2954 0.5842)
			(end 1.2954 0.5842)
			(stroke
				(width 0.1524)
				(type default)
			)
			(layer "B.SilkS")
		)
		(fp_line
			(start -1.2954 -0.5842)
			(end -1.2954 0.5842)
			(stroke
				(width 0.1524)
				(type default)
			)
			(layer "B.SilkS")
		)
		(fp_line
			(start 1.1938 0.4064)
			(end 1.1938 -0.406654)
			(stroke
				(width 0.1)
				(type default)
			)
			(layer "B.Fab")
		)
		(fp_line
			(start 1.1938 -0.406654)
			(end 0.8636 -0.406654)
			(stroke
				(width 0.1)
				(type default)
			)
			(layer "B.Fab")
		)
		(fp_line
			(start 0.8636 0.4572)
			(end 0.8636 0.4318)
			(stroke
				(width 0.1)
				(type default)
			)
			(layer "B.Fab")
		)
		(fp_line
			(start 0.8636 0.4318)
			(end 0.8636 0.4064)
			(stroke
				(width 0.1)
				(type default)
			)
			(layer "B.Fab")
		)
		(fp_line
			(start 0.8636 0.4064)
			(end 1.1938 0.4064)
			(stroke
				(width 0.1)
				(type default)
			)
			(layer "B.Fab")
		)
		(fp_line
			(start 0.8636 -0.406654)
			(end 0.8636 -0.4572)
			(stroke
				(width 0.1)
				(type default)
			)
			(layer "B.Fab")
		)
		(fp_line
			(start 0.8636 -0.4572)
			(end -0.8636 -0.4572)
			(stroke
				(width 0.1)
				(type default)
			)
			(layer "B.Fab")
		)
		(fp_line
			(start -0.8636 0.4572)
			(end 0.8636 0.4572)
			(stroke
				(width 0.1)
				(type default)
			)
			(layer "B.Fab")
		)
		(fp_line
			(start -0.8636 0.4064)
			(end -0.8636 0.4572)
			(stroke
				(width 0.1)
				(type default)
			)
			(layer "B.Fab")
		)
		(fp_line
			(start -0.8636 -0.406654)
			(end -1.1938 -0.406654)
			(stroke
				(width 0.1)
				(type default)
			)
			(layer "B.Fab")
		)
		(fp_line
			(start -0.8636 -0.4572)
			(end -0.8636 -0.406654)
			(stroke
				(width 0.1)
				(type default)
			)
			(layer "B.Fab")
		)
		(fp_line
			(start -1.1938 0.4064)
			(end -0.8636 0.4064)
			(stroke
				(width 0.1)
				(type default)
			)
			(layer "B.Fab")
		)
		(fp_line
			(start -1.1938 -0.406654)
			(end -1.1938 0.4064)
			(stroke
				(width 0.1)
				(type default)
			)
			(layer "B.Fab")
		)
		(pad "1" smd rect
			(at 0.7366 0 90)
			(size 0.7112 0.8128)
			(layers "B.Cu" "B.Mask" "B.Paste")
			(net "P0V9_CPU0_RT1_2A_2D")
		)
		(pad "2" smd rect
			(at -0.7366 0 90)
			(size 0.7112 0.8128)
			(layers "B.Cu" "B.Mask" "B.Paste")
			(net "P0V9_CPU0_RT1_2A")
		)
	)
	(footprint ""
		(layer "B.Cu")
		(at 362.407454 -268.41831)
		(property "Reference" "C2248"
			(at 0 0 0)
			(layer "B.SilkS")
			(hide yes)
			(effects
				(font
					(size 1.27 1.27)
				)
				(justify mirror)
			)
		)
		(property "Value" ""
			(at 0 0 0)
			(layer "B.Fab")
			(effects
				(font
					(size 1.27 1.27)
				)
				(justify mirror)
			)
		)
		(duplicate_pad_numbers_are_jumpers no)
		(fp_line
			(start -0.7874 -0.4064)
			(end -0.7874 0.4064)
			(stroke
				(width 0.1524)
				(type default)
			)
			(layer "B.SilkS")
		)
		(fp_line
			(start -0.7874 0.4064)
			(end 0.7874 0.4064)
			(stroke
				(width 0.1524)
				(type default)
			)
			(layer "B.SilkS")
		)
		(fp_line
			(start 0.7874 -0.4064)
			(end -0.7874 -0.4064)
			(stroke
				(width 0.1524)
				(type default)
			)
			(layer "B.SilkS")
		)
		(fp_line
			(start 0.7874 0.4064)
			(end 0.7874 -0.4064)
			(stroke
				(width 0.1524)
				(type default)
			)
			(layer "B.SilkS")
		)
		(fp_line
			(start -0.67945 -0.3048)
			(end -0.67945 0.3048)
			(stroke
				(width 0.1)
				(type default)
			)
			(layer "B.Fab")
		)
		(fp_line
			(start -0.67945 0.3048)
			(end -0.120396 0.3048)
			(stroke
				(width 0.1)
				(type default)
			)
			(layer "B.Fab")
		)
		(fp_line
			(start -0.12065 -0.3048)
			(end -0.67945 -0.3048)
			(stroke
				(width 0.1)
				(type default)
			)
			(layer "B.Fab")
		)
		(fp_line
			(start -0.12065 -0.2794)
			(end -0.12065 -0.3048)
			(stroke
				(width 0.1)
				(type default)
			)
			(layer "B.Fab")
		)
		(fp_line
			(start -0.120396 0.2794)
			(end 0.12065 0.2794)
			(stroke
				(width 0.1)
				(type default)
			)
			(layer "B.Fab")
		)
		(fp_line
			(start -0.120396 0.3048)
			(end -0.120396 0.2794)
			(stroke
				(width 0.1)
				(type default)
			)
			(layer "B.Fab")
		)
		(fp_line
			(start 0.12065 -0.305054)
			(end 0.12065 -0.2794)
			(stroke
				(width 0.1)
				(type default)
			)
			(layer "B.Fab")
		)
		(fp_line
			(start 0.12065 -0.2794)
			(end -0.12065 -0.2794)
			(stroke
				(width 0.1)
				(type default)
			)
			(layer "B.Fab")
		)
		(fp_line
			(start 0.12065 0.2794)
			(end 0.12065 0.3048)
			(stroke
				(width 0.1)
				(type default)
			)
			(layer "B.Fab")
		)
		(fp_line
			(start 0.12065 0.3048)
			(end 0.67945 0.3048)
			(stroke
				(width 0.1)
				(type default)
			)
			(layer "B.Fab")
		)
		(fp_line
			(start 0.67945 -0.305054)
			(end 0.12065 -0.305054)
			(stroke
				(width 0.1)
				(type default)
			)
			(layer "B.Fab")
		)
		(fp_line
			(start 0.67945 0.3048)
			(end 0.67945 -0.305054)
			(stroke
				(width 0.1)
				(type default)
			)
			(layer "B.Fab")
		)
		(pad "1" smd circle
			(at 0.40005 0 180)
			(size 0 0)
			(layers "B.Cu" "B.Mask" "B.Paste")
			(net "PVDDCR_CPU1_P0")
		)
		(pad "2" smd circle
			(at -0.40005 0 180)
			(size 0 0)
			(layers "B.Cu" "B.Mask" "B.Paste")
			(net "GND")
		)
	)
	(footprint ""
		(layer "B.Cu")
		(at 111.781336 -252.416564 180)
		(property "Reference" "C2268"
			(at 0 0 0)
			(layer "B.SilkS")
			(hide yes)
			(effects
				(font
					(size 1.27 1.27)
				)
				(justify mirror)
			)
		)
		(property "Value" ""
			(at 0 0 0)
			(layer "B.Fab")
			(effects
				(font
					(size 1.27 1.27)
				)
				(justify mirror)
			)
		)
		(duplicate_pad_numbers_are_jumpers no)
		(fp_line
			(start 0.7874 0.4064)
			(end 0.7874 -0.4064)
			(stroke
				(width 0.1524)
				(type default)
			)
			(layer "B.SilkS")
		)
		(fp_line
			(start 0.7874 -0.4064)
			(end -0.7874 -0.4064)
			(stroke
				(width 0.1524)
				(type default)
			)
			(layer "B.SilkS")
		)
		(fp_line
			(start -0.7874 0.4064)
			(end 0.7874 0.4064)
			(stroke
				(width 0.1524)
				(type default)
			)
			(layer "B.SilkS")
		)
		(fp_line
			(start -0.7874 -0.4064)
			(end -0.7874 0.4064)
			(stroke
				(width 0.1524)
				(type default)
			)
			(layer "B.SilkS")
		)
		(fp_line
			(start 0.67945 0.3048)
			(end 0.67945 -0.305054)
			(stroke
				(width 0.1)
				(type default)
			)
			(layer "B.Fab")
		)
		(fp_line
			(start 0.67945 -0.305054)
			(end 0.12065 -0.305054)
			(stroke
				(width 0.1)
				(type default)
			)
			(layer "B.Fab")
		)
		(fp_line
			(start 0.12065 0.3048)
			(end 0.67945 0.3048)
			(stroke
				(width 0.1)
				(type default)
			)
			(layer "B.Fab")
		)
		(fp_line
			(start 0.12065 0.2794)
			(end 0.12065 0.3048)
			(stroke
				(width 0.1)
				(type default)
			)
			(layer "B.Fab")
		)
		(fp_line
			(start 0.12065 -0.2794)
			(end -0.12065 -0.2794)
			(stroke
				(width 0.1)
				(type default)
			)
			(layer "B.Fab")
		)
		(fp_line
			(start 0.12065 -0.305054)
			(end 0.12065 -0.2794)
			(stroke
				(width 0.1)
				(type default)
			)
			(layer "B.Fab")
		)
		(fp_line
			(start -0.120396 0.3048)
			(end -0.120396 0.2794)
			(stroke
				(width 0.1)
				(type default)
			)
			(layer "B.Fab")
		)
		(fp_line
			(start -0.120396 0.2794)
			(end 0.12065 0.2794)
			(stroke
				(width 0.1)
				(type default)
			)
			(layer "B.Fab")
		)
		(fp_line
			(start -0.12065 -0.2794)
			(end -0.12065 -0.3048)
			(stroke
				(width 0.1)
				(type default)
			)
			(layer "B.Fab")
		)
		(fp_line
			(start -0.12065 -0.3048)
			(end -0.67945 -0.3048)
			(stroke
				(width 0.1)
				(type default)
			)
			(layer "B.Fab")
		)
		(fp_line
			(start -0.67945 0.3048)
			(end -0.120396 0.3048)
			(stroke
				(width 0.1)
				(type default)
			)
			(layer "B.Fab")
		)
		(fp_line
			(start -0.67945 -0.3048)
			(end -0.67945 0.3048)
			(stroke
				(width 0.1)
				(type default)
			)
			(layer "B.Fab")
		)
		(pad "1" smd circle
			(at 0.40005 0)
			(size 0 0)
			(layers "B.Cu" "B.Mask" "B.Paste")
			(net "PVDDCR_SOC_P1")
		)
		(pad "2" smd circle
			(at -0.40005 0)
			(size 0 0)
			(layers "B.Cu" "B.Mask" "B.Paste")
			(net "GND")
		)
	)
	(footprint ""
		(layer "B.Cu")
		(at 330.720446 -416.899344 90)
		(property "Reference" "C6549"
			(at 0 0 90)
			(layer "B.SilkS")
			(hide yes)
			(effects
				(font
					(size 1.27 1.27)
				)
				(justify mirror)
			)
		)
		(property "Value" ""
			(at 0 0 90)
			(layer "B.Fab")
			(effects
				(font
					(size 1.27 1.27)
				)
				(justify mirror)
			)
		)
		(duplicate_pad_numbers_are_jumpers no)
		(fp_line
			(start 0.299974 -0.150114)
			(end -0.299974 -0.150114)
			(stroke
				(width 0.1)
				(type default)
			)
			(layer "B.Fab")
		)
		(fp_line
			(start -0.299974 -0.150114)
			(end -0.299974 0.150114)
			(stroke
				(width 0.1)
				(type default)
			)
			(layer "B.Fab")
		)
		(fp_line
			(start 0.299974 0.150114)
			(end 0.299974 -0.150114)
			(stroke
				(width 0.1)
				(type default)
			)
			(layer "B.Fab")
		)
		(fp_line
			(start -0.299974 0.150114)
			(end 0.299974 0.150114)
			(stroke
				(width 0.1)
				(type default)
			)
			(layer "B.Fab")
		)
		(pad "1" smd rect
			(at 0.2667 0 270)
			(size 0.3048 0.381)
			(layers "B.Cu" "B.Mask" "B.Paste")
			(net "P5E_CPU0_P1_TX_BUF_C_DP<8>")
		)
		(pad "2" smd rect
			(at -0.2667 0 270)
			(size 0.3048 0.381)
			(layers "B.Cu" "B.Mask" "B.Paste")
			(net "P5E_CPU0_P1_TX_BUF_DP<8>")
		)
	)
	(footprint ""
		(layer "B.Cu")
		(at 485.20985 -142.805658 -90)
		(property "Reference" "X8012"
			(at 4.4577 -1.50495 270)
			(unlocked yes)
			(layer "B.SilkS")
			(effects
				(font
					(size 0.7874 0.5842)
					(thickness 0.1524)
				)
				(justify left mirror)
			)
		)
		(property "Value" ""
			(at 0 0 90)
			(layer "B.Fab")
			(effects
				(font
					(size 1.27 1.27)
				)
				(justify mirror)
			)
		)
		(property "Device Type" "TP_TDR_4P_FTS_TH-TP_TDR_4P_DIP,EMPTY,TP15"
			(at -1.30175 1.27 180)
			(unlocked yes)
			(layer "B.Fab")
			(hide yes)
			(effects
				(font
					(size 0.635 0.4064)
					(thickness 0.1524)
				)
				(justify mirror)
			)
		)
		(property "User Part Number" "N_A"
			(at -1.30175 1.27 180)
			(unlocked yes)
			(layer "Cmts.User")
			(hide yes)
			(effects
				(font
					(size 0.635 0.4064)
					(thickness 0.1524)
				)
				(justify mirror)
			)
		)
		(duplicate_pad_numbers_are_jumpers no)
		(fp_line
			(start -2.54 3.81)
			(end -2.54 3.6703)
			(stroke
				(width 0.1524)
				(type default)
			)
			(layer "B.SilkS")
		)
		(fp_line
			(start 0 3.81)
			(end -2.54 3.81)
			(stroke
				(width 0.1524)
				(type default)
			)
			(layer "B.SilkS")
		)
		(fp_line
			(start 0 3.175)
			(end 0 3.81)
			(stroke
				(width 0.1524)
				(type default)
			)
			(layer "B.SilkS")
		)
		(fp_line
			(start -2.54 1.4097)
			(end -2.54 1.1303)
			(stroke
				(width 0.1524)
				(type default)
			)
			(layer "B.SilkS")
		)
		(fp_line
			(start 0 0.635)
			(end 0 1.905)
			(stroke
				(width 0.1524)
				(type default)
			)
			(layer "B.SilkS")
		)
		(fp_line
			(start -2.54 -1.1303)
			(end -2.54 -1.27)
			(stroke
				(width 0.1524)
				(type default)
			)
			(layer "B.SilkS")
		)
		(fp_line
			(start -2.54 -1.27)
			(end 0 -1.27)
			(stroke
				(width 0.1524)
				(type default)
			)
			(layer "B.SilkS")
		)
		(fp_line
			(start 0 -1.27)
			(end 0 -0.635)
			(stroke
				(width 0.1524)
				(type default)
			)
			(layer "B.SilkS")
		)
		(fp_poly
			(pts
				(xy 0.761746 0) (xy 2.285746 -0.762) (xy 2.285746 0.762)
			)
			(stroke
				(width 0)
				(type default)
			)
			(fill yes)
			(layer "B.SilkS")
		)
		(fp_line
			(start -2.54 3.81)
			(end -2.54 -1.27)
			(stroke
				(width 0.1)
				(type default)
			)
			(layer "B.Fab")
		)
		(fp_line
			(start 0 3.81)
			(end -2.54 3.81)
			(stroke
				(width 0.1)
				(type default)
			)
			(layer "B.Fab")
		)
		(fp_line
			(start -2.54 -1.27)
			(end 0 -1.27)
			(stroke
				(width 0.1)
				(type default)
			)
			(layer "B.Fab")
		)
		(fp_line
			(start 0 -1.27)
			(end 0 3.81)
			(stroke
				(width 0.1)
				(type default)
			)
			(layer "B.Fab")
		)
		(fp_poly
			(pts
				(xy 0.761746 0) (xy 2.285746 -0.762) (xy 2.285746 0.762)
			)
			(stroke
				(width 0)
				(type default)
			)
			(fill yes)
			(layer "B.Fab")
		)
		(pad "1" thru_hole circle
			(at 0 0 90)
			(size 1.0033 1.0033)
			(drill 0.249936)
			(layers "*.Cu" "*.Mask")
			(remove_unused_layers no)
			(net "TDR_DIFF_85_BOT_DN")
			(clearance 0.10795)
			(padstack
				(mode front_inner_back)
				(layer "Inner"
					(shape circle)
					(size 0.8001 0.8001)
					(clearance 0.1524)
				)
				(layer "B.Cu"
					(shape circle)
					(size 1.0033 1.0033)
					(thermal_gap 0.10795)
					(clearance 0.10795)
				)
			)
		)
		(pad "2" thru_hole circle
			(at -2.54 0 90)
			(size 1.9939 1.9939)
			(drill 0.249936)
			(layers "*.Cu" "*.Mask")
			(remove_unused_layers no)
			(net "T1_GND")
			(clearance 0.10795)
			(padstack
				(mode front_inner_back)
				(layer "Inner"
					(shape circle)
					(size 0.8001 0.8001)
					(clearance 0.1524)
				)
				(layer "B.Cu"
					(shape circle)
					(size 1.9939 1.9939)
					(thermal_gap 0.10795)
					(clearance 0.10795)
				)
			)
		)
		(pad "3" thru_hole circle
			(at -2.54 2.54 90)
			(size 1.9939 1.9939)
			(drill 0.249936)
			(layers "*.Cu" "*.Mask")
			(remove_unused_layers no)
			(net "T1_GND")
			(clearance 0.10795)
			(padstack
				(mode front_inner_back)
				(layer "Inner"
					(shape circle)
					(size 0.8001 0.8001)
					(clearance 0.1524)
				)
				(layer "B.Cu"
					(shape circle)
					(size 1.9939 1.9939)
					(thermal_gap 0.10795)
					(clearance 0.10795)
				)
			)
		)
		(pad "4" thru_hole circle
			(at 0 2.54 90)
			(size 1.0033 1.0033)
			(drill 0.249936)
			(layers "*.Cu" "*.Mask")
			(remove_unused_layers no)
			(net "TDR_DIFF_85_BOT_DP")
			(clearance 0.10795)
			(padstack
				(mode front_inner_back)
				(layer "Inner"
					(shape circle)
					(size 0.8001 0.8001)
					(clearance 0.1524)
				)
				(layer "B.Cu"
					(shape circle)
					(size 1.0033 1.0033)
					(thermal_gap 0.10795)
					(clearance 0.10795)
				)
			)
		)
	)
	(footprint ""
		(layer "B.Cu")
		(at 94.49562 -381.11303)
		(property "Reference" "C7023"
			(at 2.6416 2.989072 0)
			(unlocked yes)
			(layer "B.SilkS")
			(effects
				(font
					(size 0.7874 0.5842)
					(thickness 0.1524)
				)
				(justify left mirror)
			)
		)
		(property "Value" ""
			(at 0 0 0)
			(layer "B.Fab")
			(effects
				(font
					(size 1.27 1.27)
				)
				(justify mirror)
			)
		)
		(duplicate_pad_numbers_are_jumpers no)
		(fp_line
			(start -4.53898 -2.15011)
			(end -4.53898 2.15011)
			(stroke
				(width 0.1524)
				(type default)
			)
			(layer "B.SilkS")
		)
		(fp_line
			(start -4.53898 2.15011)
			(end 4.53898 2.15011)
			(stroke
				(width 0.1524)
				(type default)
			)
			(layer "B.SilkS")
		)
		(fp_line
			(start 4.53898 -2.150618)
			(end 4.539742 2.152142)
			(stroke
				(width 0.1524)
				(type default)
			)
			(layer "B.SilkS")
		)
		(fp_line
			(start 4.53898 -2.15011)
			(end -4.53898 -2.15011)
			(stroke
				(width 0.1524)
				(type default)
			)
			(layer "B.SilkS")
		)
		(fp_line
			(start 4.53898 2.15011)
			(end 4.53898 -2.15011)
			(stroke
				(width 0.1524)
				(type default)
			)
			(layer "B.SilkS")
		)
		(fp_line
			(start 4.69138 -2.150618)
			(end 4.692396 2.161032)
			(stroke
				(width 0.1524)
				(type default)
			)
			(layer "B.SilkS")
		)
		(fp_line
			(start 4.83108 2.150364)
			(end 4.447794 2.149348)
			(stroke
				(width 0.1524)
				(type default)
			)
			(layer "B.SilkS")
		)
		(fp_line
			(start 4.84378 -2.150618)
			(end 4.53898 -2.150618)
			(stroke
				(width 0.1524)
				(type default)
			)
			(layer "B.SilkS")
		)
		(fp_line
			(start 4.84378 -2.150618)
			(end 4.842256 2.163064)
			(stroke
				(width 0.1524)
				(type default)
			)
			(layer "B.SilkS")
		)
		(fp_line
			(start -3.64998 -2.15011)
			(end -3.64998 2.15011)
			(stroke
				(width 0.1)
				(type default)
			)
			(layer "B.Fab")
		)
		(fp_line
			(start -3.64998 2.15011)
			(end 3.64998 2.15011)
			(stroke
				(width 0.1)
				(type default)
			)
			(layer "B.Fab")
		)
		(fp_line
			(start 3.64998 -2.15011)
			(end -3.64998 -2.15011)
			(stroke
				(width 0.1)
				(type default)
			)
			(layer "B.Fab")
		)
		(fp_line
			(start 3.64998 2.15011)
			(end 3.64998 -2.15011)
			(stroke
				(width 0.1)
				(type default)
			)
			(layer "B.Fab")
		)
		(fp_text user "-"
			(at -2.827274 2.572512 0)
			(unlocked yes)
			(layer "B.SilkS")
			(effects
				(font
					(size 1.905 1.4224)
					(thickness 0.1524)
				)
				(justify left mirror)
			)
		)
		(fp_text user "+"
			(at 6.214872 -0.337058 0)
			(unlocked yes)
			(layer "B.SilkS")
			(effects
				(font
					(size 1.905 1.4224)
					(thickness 0.1524)
				)
				(justify left mirror)
			)
		)
		(fp_text user "-"
			(at -4.313174 -0.094488 0)
			(unlocked yes)
			(layer "B.Fab")
			(effects
				(font
					(size 1.905 1.4224)
					(thickness 0.1524)
				)
				(justify left mirror)
			)
		)
		(fp_text user "+"
			(at 6.214872 -0.337058 0)
			(unlocked yes)
			(layer "B.Fab")
			(effects
				(font
					(size 1.905 1.4224)
					(thickness 0.1524)
				)
				(justify left mirror)
			)
		)
		(pad "1" smd rect
			(at 3.199892 0 180)
			(size 2.413 2.8194)
			(layers "B.Cu" "B.Mask" "B.Paste")
			(net "P0V9_CPU1_RT1_2A")
		)
		(pad "2" smd rect
			(at -3.199892 0 180)
			(size 2.413 2.8194)
			(layers "B.Cu" "B.Mask" "B.Paste")
			(net "GND")
		)
	)
	(footprint ""
		(layer "B.Cu")
		(at 128.878584 -386.766562 90)
		(property "Reference" "C453"
			(at 0 0 90)
			(layer "B.SilkS")
			(hide yes)
			(effects
				(font
					(size 1.27 1.27)
				)
				(justify mirror)
			)
		)
		(property "Value" ""
			(at 0 0 90)
			(layer "B.Fab")
			(effects
				(font
					(size 1.27 1.27)
				)
				(justify mirror)
			)
		)
		(duplicate_pad_numbers_are_jumpers no)
		(fp_line
			(start 0.299974 -0.150114)
			(end -0.299974 -0.150114)
			(stroke
				(width 0.1)
				(type default)
			)
			(layer "B.Fab")
		)
		(fp_line
			(start -0.299974 -0.150114)
			(end -0.299974 0.150114)
			(stroke
				(width 0.1)
				(type default)
			)
			(layer "B.Fab")
		)
		(fp_line
			(start 0.299974 0.150114)
			(end 0.299974 -0.150114)
			(stroke
				(width 0.1)
				(type default)
			)
			(layer "B.Fab")
		)
		(fp_line
			(start -0.299974 0.150114)
			(end 0.299974 0.150114)
			(stroke
				(width 0.1)
				(type default)
			)
			(layer "B.Fab")
		)
		(pad "1" smd rect
			(at 0.2667 0 270)
			(size 0.3048 0.381)
			(layers "B.Cu" "B.Mask" "B.Paste")
			(net "P0V9_CPU1_RT3_2A")
		)
		(pad "2" smd rect
			(at -0.2667 0 270)
			(size 0.3048 0.381)
			(layers "B.Cu" "B.Mask" "B.Paste")
			(net "GND")
		)
	)
	(footprint ""
		(layer "B.Cu")
		(at 18.039588 -397.456406)
		(property "Reference" "PC6617_1"
			(at 0 0 0)
			(layer "B.SilkS")
			(hide yes)
			(effects
				(font
					(size 1.27 1.27)
				)
				(justify mirror)
			)
		)
		(property "Value" ""
			(at 0 0 0)
			(layer "B.Fab")
			(effects
				(font
					(size 1.27 1.27)
				)
				(justify mirror)
			)
		)
		(duplicate_pad_numbers_are_jumpers no)
		(fp_line
			(start -1.524 -0.762)
			(end -1.524 0.762)
			(stroke
				(width 0.1524)
				(type default)
			)
			(layer "B.SilkS")
		)
		(fp_line
			(start -1.524 0.762)
			(end 1.524 0.762)
			(stroke
				(width 0.1524)
				(type default)
			)
			(layer "B.SilkS")
		)
		(fp_line
			(start 1.524 -0.762)
			(end -1.524 -0.762)
			(stroke
				(width 0.1524)
				(type default)
			)
			(layer "B.SilkS")
		)
		(fp_line
			(start 1.524 0.762)
			(end 1.524 -0.762)
			(stroke
				(width 0.1524)
				(type default)
			)
			(layer "B.SilkS")
		)
		(fp_line
			(start -1.1049 -0.724916)
			(end 1.1049 -0.724916)
			(stroke
				(width 0.1)
				(type default)
			)
			(layer "B.Fab")
		)
		(fp_line
			(start -1.1049 0.724916)
			(end -1.1049 -0.724916)
			(stroke
				(width 0.1)
				(type default)
			)
			(layer "B.Fab")
		)
		(fp_line
			(start 1.1049 -0.724916)
			(end 1.1049 0.724916)
			(stroke
				(width 0.1)
				(type default)
			)
			(layer "B.Fab")
		)
		(fp_line
			(start 1.1049 0.724916)
			(end -1.1049 0.724916)
			(stroke
				(width 0.1)
				(type default)
			)
			(layer "B.Fab")
		)
		(pad "1" smd rect
			(at 0.889 0)
			(size 1.016 1.27)
			(layers "B.Cu" "B.Mask" "B.Paste")
			(net "SW_P12V_AUX_P0V9_RETIMER_CPU1_FLT")
		)
		(pad "2" smd rect
			(at -0.889 0)
			(size 1.016 1.27)
			(layers "B.Cu" "B.Mask" "B.Paste")
			(net "GND")
		)
	)
	(footprint ""
		(layer "B.Cu")
		(at 424.670474 -351.032826 90)
		(property "Reference" "PC213_1"
			(at 0 0 90)
			(layer "B.SilkS")
			(hide yes)
			(effects
				(font
					(size 1.27 1.27)
				)
				(justify mirror)
			)
		)
		(property "Value" ""
			(at 0 0 90)
			(layer "B.Fab")
			(effects
				(font
					(size 1.27 1.27)
				)
				(justify mirror)
			)
		)
		(duplicate_pad_numbers_are_jumpers no)
		(fp_line
			(start 1.524 -0.762)
			(end -1.524 -0.762)
			(stroke
				(width 0.1524)
				(type default)
			)
			(layer "B.SilkS")
		)
		(fp_line
			(start -1.524 -0.762)
			(end -1.524 0.762)
			(stroke
				(width 0.1524)
				(type default)
			)
			(layer "B.SilkS")
		)
		(fp_line
			(start 1.524 0.762)
			(end 1.524 -0.762)
			(stroke
				(width 0.1524)
				(type default)
			)
			(layer "B.SilkS")
		)
		(fp_line
			(start -1.524 0.762)
			(end 1.524 0.762)
			(stroke
				(width 0.1524)
				(type default)
			)
			(layer "B.SilkS")
		)
		(fp_line
			(start 1.1049 -0.724916)
			(end 1.1049 0.724916)
			(stroke
				(width 0.1)
				(type default)
			)
			(layer "B.Fab")
		)
		(fp_line
			(start -1.1049 -0.724916)
			(end 1.1049 -0.724916)
			(stroke
				(width 0.1)
				(type default)
			)
			(layer "B.Fab")
		)
		(fp_line
			(start 1.1049 0.724916)
			(end -1.1049 0.724916)
			(stroke
				(width 0.1)
				(type default)
			)
			(layer "B.Fab")
		)
		(fp_line
			(start -1.1049 0.724916)
			(end -1.1049 -0.724916)
			(stroke
				(width 0.1)
				(type default)
			)
			(layer "B.Fab")
		)
		(pad "1" smd rect
			(at 0.889 0 90)
			(size 1.016 1.27)
			(layers "B.Cu" "B.Mask" "B.Paste")
			(net "SW_P12V_AUX_PVDD11_S3_P0_FLT")
		)
		(pad "2" smd rect
			(at -0.889 0 90)
			(size 1.016 1.27)
			(layers "B.Cu" "B.Mask" "B.Paste")
			(net "GND")
		)
	)
	(footprint ""
		(layer "B.Cu")
		(at 205.150466 -128.082294 180)
		(property "Reference" "R6823"
			(at 0 0 0)
			(layer "B.SilkS")
			(hide yes)
			(effects
				(font
					(size 1.27 1.27)
				)
				(justify mirror)
			)
		)
		(property "Value" ""
			(at 0 0 0)
			(layer "B.Fab")
			(effects
				(font
					(size 1.27 1.27)
				)
				(justify mirror)
			)
		)
		(duplicate_pad_numbers_are_jumpers no)
		(fp_line
			(start 0.7874 0.4064)
			(end 0.7874 -0.4064)
			(stroke
				(width 0.1524)
				(type default)
			)
			(layer "B.SilkS")
		)
		(fp_line
			(start 0.7874 -0.4064)
			(end -0.7874 -0.4064)
			(stroke
				(width 0.1524)
				(type default)
			)
			(layer "B.SilkS")
		)
		(fp_line
			(start -0.7874 0.4064)
			(end 0.7874 0.4064)
			(stroke
				(width 0.1524)
				(type default)
			)
			(layer "B.SilkS")
		)
		(fp_line
			(start -0.7874 -0.4064)
			(end -0.7874 0.4064)
			(stroke
				(width 0.1524)
				(type default)
			)
			(layer "B.SilkS")
		)
		(fp_line
			(start 0.67945 0.3048)
			(end 0.67945 -0.305054)
			(stroke
				(width 0.1)
				(type default)
			)
			(layer "B.Fab")
		)
		(fp_line
			(start 0.67945 -0.305054)
			(end 0.12065 -0.305054)
			(stroke
				(width 0.1)
				(type default)
			)
			(layer "B.Fab")
		)
		(fp_line
			(start 0.12065 0.3048)
			(end 0.67945 0.3048)
			(stroke
				(width 0.1)
				(type default)
			)
			(layer "B.Fab")
		)
		(fp_line
			(start 0.12065 0.2794)
			(end 0.12065 0.3048)
			(stroke
				(width 0.1)
				(type default)
			)
			(layer "B.Fab")
		)
		(fp_line
			(start 0.12065 -0.2794)
			(end -0.12065 -0.2794)
			(stroke
				(width 0.1)
				(type default)
			)
			(layer "B.Fab")
		)
		(fp_line
			(start 0.12065 -0.305054)
			(end 0.12065 -0.2794)
			(stroke
				(width 0.1)
				(type default)
			)
			(layer "B.Fab")
		)
		(fp_line
			(start -0.120396 0.3048)
			(end -0.120396 0.2794)
			(stroke
				(width 0.1)
				(type default)
			)
			(layer "B.Fab")
		)
		(fp_line
			(start -0.120396 0.2794)
			(end 0.12065 0.2794)
			(stroke
				(width 0.1)
				(type default)
			)
			(layer "B.Fab")
		)
		(fp_line
			(start -0.12065 -0.2794)
			(end -0.12065 -0.3048)
			(stroke
				(width 0.1)
				(type default)
			)
			(layer "B.Fab")
		)
		(fp_line
			(start -0.12065 -0.3048)
			(end -0.67945 -0.3048)
			(stroke
				(width 0.1)
				(type default)
			)
			(layer "B.Fab")
		)
		(fp_line
			(start -0.67945 0.3048)
			(end -0.120396 0.3048)
			(stroke
				(width 0.1)
				(type default)
			)
			(layer "B.Fab")
		)
		(fp_line
			(start -0.67945 -0.3048)
			(end -0.67945 0.3048)
			(stroke
				(width 0.1)
				(type default)
			)
			(layer "B.Fab")
		)
		(pad "1" smd circle
			(at 0.40005 0)
			(size 0 0)
			(layers "B.Cu" "B.Mask" "B.Paste")
			(net "RST_RT_CPU0_P2_PERST_R2_N")
		)
		(pad "2" smd circle
			(at -0.40005 0)
			(size 0 0)
			(layers "B.Cu" "B.Mask" "B.Paste")
			(net "RST_RT_CPU0_P2_PERST_R_N")
		)
	)
	(footprint ""
		(layer "B.Cu")
		(at 388.196836 -178.965098 90)
		(property "Reference" "PC555_4"
			(at 0 0 90)
			(layer "B.SilkS")
			(hide yes)
			(effects
				(font
					(size 1.27 1.27)
				)
				(justify mirror)
			)
		)
		(property "Value" ""
			(at 0 0 90)
			(layer "B.Fab")
			(effects
				(font
					(size 1.27 1.27)
				)
				(justify mirror)
			)
		)
		(duplicate_pad_numbers_are_jumpers no)
		(fp_line
			(start 1.524 -0.762)
			(end -1.524 -0.762)
			(stroke
				(width 0.1524)
				(type default)
			)
			(layer "B.SilkS")
		)
		(fp_line
			(start -1.524 -0.762)
			(end -1.524 0.762)
			(stroke
				(width 0.1524)
				(type default)
			)
			(layer "B.SilkS")
		)
		(fp_line
			(start 1.524 0.762)
			(end 1.524 -0.762)
			(stroke
				(width 0.1524)
				(type default)
			)
			(layer "B.SilkS")
		)
		(fp_line
			(start -1.524 0.762)
			(end 1.524 0.762)
			(stroke
				(width 0.1524)
				(type default)
			)
			(layer "B.SilkS")
		)
		(fp_line
			(start 1.1049 -0.724916)
			(end 1.1049 0.724916)
			(stroke
				(width 0.1)
				(type default)
			)
			(layer "B.Fab")
		)
		(fp_line
			(start -1.1049 -0.724916)
			(end 1.1049 -0.724916)
			(stroke
				(width 0.1)
				(type default)
			)
			(layer "B.Fab")
		)
		(fp_line
			(start 1.1049 0.724916)
			(end -1.1049 0.724916)
			(stroke
				(width 0.1)
				(type default)
			)
			(layer "B.Fab")
		)
		(fp_line
			(start -1.1049 0.724916)
			(end -1.1049 -0.724916)
			(stroke
				(width 0.1)
				(type default)
			)
			(layer "B.Fab")
		)
		(pad "1" smd rect
			(at 0.889 0 90)
			(size 1.016 1.27)
			(layers "B.Cu" "B.Mask" "B.Paste")
			(net "SW_P12V_AUX_PVDDCR_CPU0_P0_FLT")
		)
		(pad "2" smd rect
			(at -0.889 0 90)
			(size 1.016 1.27)
			(layers "B.Cu" "B.Mask" "B.Paste")
			(net "GND")
		)
	)
	(footprint ""
		(layer "B.Cu")
		(at 357.730806 -419.02888 180)
		(property "Reference" "R2837"
			(at 0 0 0)
			(layer "B.SilkS")
			(hide yes)
			(effects
				(font
					(size 1.27 1.27)
				)
				(justify mirror)
			)
		)
		(property "Value" ""
			(at 0 0 0)
			(layer "B.Fab")
			(effects
				(font
					(size 1.27 1.27)
				)
				(justify mirror)
			)
		)
		(duplicate_pad_numbers_are_jumpers no)
		(fp_line
			(start 0.7874 0.4064)
			(end 0.7874 -0.4064)
			(stroke
				(width 0.1524)
				(type default)
			)
			(layer "B.SilkS")
		)
		(fp_line
			(start 0.7874 -0.4064)
			(end -0.7874 -0.4064)
			(stroke
				(width 0.1524)
				(type default)
			)
			(layer "B.SilkS")
		)
		(fp_line
			(start -0.7874 0.4064)
			(end 0.7874 0.4064)
			(stroke
				(width 0.1524)
				(type default)
			)
			(layer "B.SilkS")
		)
		(fp_line
			(start -0.7874 -0.4064)
			(end -0.7874 0.4064)
			(stroke
				(width 0.1524)
				(type default)
			)
			(layer "B.SilkS")
		)
		(fp_line
			(start 0.67945 0.3048)
			(end 0.67945 -0.305054)
			(stroke
				(width 0.1)
				(type default)
			)
			(layer "B.Fab")
		)
		(fp_line
			(start 0.67945 -0.305054)
			(end 0.12065 -0.305054)
			(stroke
				(width 0.1)
				(type default)
			)
			(layer "B.Fab")
		)
		(fp_line
			(start 0.12065 0.3048)
			(end 0.67945 0.3048)
			(stroke
				(width 0.1)
				(type default)
			)
			(layer "B.Fab")
		)
		(fp_line
			(start 0.12065 0.2794)
			(end 0.12065 0.3048)
			(stroke
				(width 0.1)
				(type default)
			)
			(layer "B.Fab")
		)
		(fp_line
			(start 0.12065 -0.2794)
			(end -0.12065 -0.2794)
			(stroke
				(width 0.1)
				(type default)
			)
			(layer "B.Fab")
		)
		(fp_line
			(start 0.12065 -0.305054)
			(end 0.12065 -0.2794)
			(stroke
				(width 0.1)
				(type default)
			)
			(layer "B.Fab")
		)
		(fp_line
			(start -0.120396 0.3048)
			(end -0.120396 0.2794)
			(stroke
				(width 0.1)
				(type default)
			)
			(layer "B.Fab")
		)
		(fp_line
			(start -0.120396 0.2794)
			(end 0.12065 0.2794)
			(stroke
				(width 0.1)
				(type default)
			)
			(layer "B.Fab")
		)
		(fp_line
			(start -0.12065 -0.2794)
			(end -0.12065 -0.3048)
			(stroke
				(width 0.1)
				(type default)
			)
			(layer "B.Fab")
		)
		(fp_line
			(start -0.12065 -0.3048)
			(end -0.67945 -0.3048)
			(stroke
				(width 0.1)
				(type default)
			)
			(layer "B.Fab")
		)
		(fp_line
			(start -0.67945 0.3048)
			(end -0.120396 0.3048)
			(stroke
				(width 0.1)
				(type default)
			)
			(layer "B.Fab")
		)
		(fp_line
			(start -0.67945 -0.3048)
			(end -0.67945 0.3048)
			(stroke
				(width 0.1)
				(type default)
			)
			(layer "B.Fab")
		)
		(pad "1" smd circle
			(at 0.40005 0)
			(size 0 0)
			(layers "B.Cu" "B.Mask" "B.Paste")
			(net "P3V3_AUX")
		)
		(pad "2" smd circle
			(at -0.40005 0)
			(size 0 0)
			(layers "B.Cu" "B.Mask" "B.Paste")
			(net "FM_SWB_PWRGD")
		)
	)
	(footprint ""
		(layer "B.Cu")
		(at 136.936226 -391.81405 180)
		(property "Reference" "C471"
			(at 0 0 0)
			(layer "B.SilkS")
			(hide yes)
			(effects
				(font
					(size 1.27 1.27)
				)
				(justify mirror)
			)
		)
		(property "Value" ""
			(at 0 0 0)
			(layer "B.Fab")
			(effects
				(font
					(size 1.27 1.27)
				)
				(justify mirror)
			)
		)
		(duplicate_pad_numbers_are_jumpers no)
		(fp_line
			(start 1.524 0.762)
			(end 1.524 -0.762)
			(stroke
				(width 0.1524)
				(type default)
			)
			(layer "B.SilkS")
		)
		(fp_line
			(start 1.524 -0.762)
			(end -1.524 -0.762)
			(stroke
				(width 0.1524)
				(type default)
			)
			(layer "B.SilkS")
		)
		(fp_line
			(start -1.524 0.762)
			(end 1.524 0.762)
			(stroke
				(width 0.1524)
				(type default)
			)
			(layer "B.SilkS")
		)
		(fp_line
			(start -1.524 -0.762)
			(end -1.524 0.762)
			(stroke
				(width 0.1524)
				(type default)
			)
			(layer "B.SilkS")
		)
		(fp_line
			(start 1.1049 0.724916)
			(end -1.1049 0.724916)
			(stroke
				(width 0.1)
				(type default)
			)
			(layer "B.Fab")
		)
		(fp_line
			(start 1.1049 -0.724916)
			(end 1.1049 0.724916)
			(stroke
				(width 0.1)
				(type default)
			)
			(layer "B.Fab")
		)
		(fp_line
			(start -1.1049 0.724916)
			(end -1.1049 -0.724916)
			(stroke
				(width 0.1)
				(type default)
			)
			(layer "B.Fab")
		)
		(fp_line
			(start -1.1049 -0.724916)
			(end 1.1049 -0.724916)
			(stroke
				(width 0.1)
				(type default)
			)
			(layer "B.Fab")
		)
		(pad "1" smd rect
			(at 0.889 0 180)
			(size 1.016 1.27)
			(layers "B.Cu" "B.Mask" "B.Paste")
			(net "P0V9_CPU1_RT3_2A")
		)
		(pad "2" smd rect
			(at -0.889 0 180)
			(size 1.016 1.27)
			(layers "B.Cu" "B.Mask" "B.Paste")
			(net "GND")
		)
	)
	(footprint ""
		(layer "B.Cu")
		(at 179.258468 -353.960684 -90)
		(property "Reference" "PR332"
			(at 0 0 90)
			(layer "B.SilkS")
			(hide yes)
			(effects
				(font
					(size 1.27 1.27)
				)
				(justify mirror)
			)
		)
		(property "Value" ""
			(at 0 0 90)
			(layer "B.Fab")
			(effects
				(font
					(size 1.27 1.27)
				)
				(justify mirror)
			)
		)
		(duplicate_pad_numbers_are_jumpers no)
		(fp_line
			(start -0.7874 0.4064)
			(end 0.7874 0.4064)
			(stroke
				(width 0.1524)
				(type default)
			)
			(layer "B.SilkS")
		)
		(fp_line
			(start 0.7874 0.4064)
			(end 0.7874 -0.4064)
			(stroke
				(width 0.1524)
				(type default)
			)
			(layer "B.SilkS")
		)
		(fp_line
			(start -0.7874 -0.4064)
			(end -0.7874 0.4064)
			(stroke
				(width 0.1524)
				(type default)
			)
			(layer "B.SilkS")
		)
		(fp_line
			(start 0.7874 -0.4064)
			(end -0.7874 -0.4064)
			(stroke
				(width 0.1524)
				(type default)
			)
			(layer "B.SilkS")
		)
		(fp_line
			(start -0.67945 0.3048)
			(end -0.120396 0.3048)
			(stroke
				(width 0.1)
				(type default)
			)
			(layer "B.Fab")
		)
		(fp_line
			(start -0.120396 0.3048)
			(end -0.120396 0.2794)
			(stroke
				(width 0.1)
				(type default)
			)
			(layer "B.Fab")
		)
		(fp_line
			(start 0.12065 0.3048)
			(end 0.67945 0.3048)
			(stroke
				(width 0.1)
				(type default)
			)
			(layer "B.Fab")
		)
		(fp_line
			(start 0.67945 0.3048)
			(end 0.67945 -0.305054)
			(stroke
				(width 0.1)
				(type default)
			)
			(layer "B.Fab")
		)
		(fp_line
			(start -0.120396 0.2794)
			(end 0.12065 0.2794)
			(stroke
				(width 0.1)
				(type default)
			)
			(layer "B.Fab")
		)
		(fp_line
			(start 0.12065 0.2794)
			(end 0.12065 0.3048)
			(stroke
				(width 0.1)
				(type default)
			)
			(layer "B.Fab")
		)
		(fp_line
			(start -0.12065 -0.2794)
			(end -0.12065 -0.3048)
			(stroke
				(width 0.1)
				(type default)
			)
			(layer "B.Fab")
		)
		(fp_line
			(start 0.12065 -0.2794)
			(end -0.12065 -0.2794)
			(stroke
				(width 0.1)
				(type default)
			)
			(layer "B.Fab")
		)
		(fp_line
			(start -0.67945 -0.3048)
			(end -0.67945 0.3048)
			(stroke
				(width 0.1)
				(type default)
			)
			(layer "B.Fab")
		)
		(fp_line
			(start -0.12065 -0.3048)
			(end -0.67945 -0.3048)
			(stroke
				(width 0.1)
				(type default)
			)
			(layer "B.Fab")
		)
		(fp_line
			(start 0.12065 -0.305054)
			(end 0.12065 -0.2794)
			(stroke
				(width 0.1)
				(type default)
			)
			(layer "B.Fab")
		)
		(fp_line
			(start 0.67945 -0.305054)
			(end 0.12065 -0.305054)
			(stroke
				(width 0.1)
				(type default)
			)
			(layer "B.Fab")
		)
		(pad "1" smd circle
			(at 0.40005 0 90)
			(size 0 0)
			(layers "B.Cu" "B.Mask" "B.Paste")
			(net "PVDD11_S3_P1_VOS1")
		)
		(pad "2" smd circle
			(at -0.40005 0 90)
			(size 0 0)
			(layers "B.Cu" "B.Mask" "B.Paste")
			(net "PVDD11_S3_P1")
		)
	)
	(footprint ""
		(layer "B.Cu")
		(at 445.888364 -195.86067 180)
		(property "Reference" "R1685"
			(at 0 0 0)
			(layer "B.SilkS")
			(hide yes)
			(effects
				(font
					(size 1.27 1.27)
				)
				(justify mirror)
			)
		)
		(property "Value" ""
			(at 0 0 0)
			(layer "B.Fab")
			(effects
				(font
					(size 1.27 1.27)
				)
				(justify mirror)
			)
		)
		(duplicate_pad_numbers_are_jumpers no)
		(fp_line
			(start 0.7874 0.4064)
			(end 0.7874 -0.4064)
			(stroke
				(width 0.1524)
				(type default)
			)
			(layer "B.SilkS")
		)
		(fp_line
			(start 0.7874 -0.4064)
			(end -0.7874 -0.4064)
			(stroke
				(width 0.1524)
				(type default)
			)
			(layer "B.SilkS")
		)
		(fp_line
			(start -0.7874 0.4064)
			(end 0.7874 0.4064)
			(stroke
				(width 0.1524)
				(type default)
			)
			(layer "B.SilkS")
		)
		(fp_line
			(start -0.7874 -0.4064)
			(end -0.7874 0.4064)
			(stroke
				(width 0.1524)
				(type default)
			)
			(layer "B.SilkS")
		)
		(fp_line
			(start 0.67945 0.3048)
			(end 0.67945 -0.305054)
			(stroke
				(width 0.1)
				(type default)
			)
			(layer "B.Fab")
		)
		(fp_line
			(start 0.67945 -0.305054)
			(end 0.12065 -0.305054)
			(stroke
				(width 0.1)
				(type default)
			)
			(layer "B.Fab")
		)
		(fp_line
			(start 0.12065 0.3048)
			(end 0.67945 0.3048)
			(stroke
				(width 0.1)
				(type default)
			)
			(layer "B.Fab")
		)
		(fp_line
			(start 0.12065 0.2794)
			(end 0.12065 0.3048)
			(stroke
				(width 0.1)
				(type default)
			)
			(layer "B.Fab")
		)
		(fp_line
			(start 0.12065 -0.2794)
			(end -0.12065 -0.2794)
			(stroke
				(width 0.1)
				(type default)
			)
			(layer "B.Fab")
		)
		(fp_line
			(start 0.12065 -0.305054)
			(end 0.12065 -0.2794)
			(stroke
				(width 0.1)
				(type default)
			)
			(layer "B.Fab")
		)
		(fp_line
			(start -0.120396 0.3048)
			(end -0.120396 0.2794)
			(stroke
				(width 0.1)
				(type default)
			)
			(layer "B.Fab")
		)
		(fp_line
			(start -0.120396 0.2794)
			(end 0.12065 0.2794)
			(stroke
				(width 0.1)
				(type default)
			)
			(layer "B.Fab")
		)
		(fp_line
			(start -0.12065 -0.2794)
			(end -0.12065 -0.3048)
			(stroke
				(width 0.1)
				(type default)
			)
			(layer "B.Fab")
		)
		(fp_line
			(start -0.12065 -0.3048)
			(end -0.67945 -0.3048)
			(stroke
				(width 0.1)
				(type default)
			)
			(layer "B.Fab")
		)
		(fp_line
			(start -0.67945 0.3048)
			(end -0.120396 0.3048)
			(stroke
				(width 0.1)
				(type default)
			)
			(layer "B.Fab")
		)
		(fp_line
			(start -0.67945 -0.3048)
			(end -0.67945 0.3048)
			(stroke
				(width 0.1)
				(type default)
			)
			(layer "B.Fab")
		)
		(pad "1" smd circle
			(at 0.40005 0)
			(size 0 0)
			(layers "B.Cu" "B.Mask" "B.Paste")
			(net "I3C_SPD_DDRGL_CPU0_SDA")
		)
		(pad "2" smd circle
			(at -0.40005 0)
			(size 0 0)
			(layers "B.Cu" "B.Mask" "B.Paste")
			(net "I3C_SPD_DDRK_CPU0_SDA")
		)
	)
	(footprint ""
		(layer "B.Cu")
		(at 325.799958 -202.113896 90)
		(property "Reference" "R413"
			(at 0 0 90)
			(layer "B.SilkS")
			(hide yes)
			(effects
				(font
					(size 1.27 1.27)
				)
				(justify mirror)
			)
		)
		(property "Value" ""
			(at 0 0 90)
			(layer "B.Fab")
			(effects
				(font
					(size 1.27 1.27)
				)
				(justify mirror)
			)
		)
		(duplicate_pad_numbers_are_jumpers no)
		(fp_line
			(start 0.7874 -0.4064)
			(end -0.7874 -0.4064)
			(stroke
				(width 0.1524)
				(type default)
			)
			(layer "B.SilkS")
		)
		(fp_line
			(start -0.7874 -0.4064)
			(end -0.7874 0.4064)
			(stroke
				(width 0.1524)
				(type default)
			)
			(layer "B.SilkS")
		)
		(fp_line
			(start 0.7874 0.4064)
			(end 0.7874 -0.4064)
			(stroke
				(width 0.1524)
				(type default)
			)
			(layer "B.SilkS")
		)
		(fp_line
			(start -0.7874 0.4064)
			(end 0.7874 0.4064)
			(stroke
				(width 0.1524)
				(type default)
			)
			(layer "B.SilkS")
		)
		(fp_line
			(start 0.67945 -0.305054)
			(end 0.12065 -0.305054)
			(stroke
				(width 0.1)
				(type default)
			)
			(layer "B.Fab")
		)
		(fp_line
			(start 0.12065 -0.305054)
			(end 0.12065 -0.2794)
			(stroke
				(width 0.1)
				(type default)
			)
			(layer "B.Fab")
		)
		(fp_line
			(start -0.12065 -0.3048)
			(end -0.67945 -0.3048)
			(stroke
				(width 0.1)
				(type default)
			)
			(layer "B.Fab")
		)
		(fp_line
			(start -0.67945 -0.3048)
			(end -0.67945 0.3048)
			(stroke
				(width 0.1)
				(type default)
			)
			(layer "B.Fab")
		)
		(fp_line
			(start 0.12065 -0.2794)
			(end -0.12065 -0.2794)
			(stroke
				(width 0.1)
				(type default)
			)
			(layer "B.Fab")
		)
		(fp_line
			(start -0.12065 -0.2794)
			(end -0.12065 -0.3048)
			(stroke
				(width 0.1)
				(type default)
			)
			(layer "B.Fab")
		)
		(fp_line
			(start 0.12065 0.2794)
			(end 0.12065 0.3048)
			(stroke
				(width 0.1)
				(type default)
			)
			(layer "B.Fab")
		)
		(fp_line
			(start -0.120396 0.2794)
			(end 0.12065 0.2794)
			(stroke
				(width 0.1)
				(type default)
			)
			(layer "B.Fab")
		)
		(fp_line
			(start 0.67945 0.3048)
			(end 0.67945 -0.305054)
			(stroke
				(width 0.1)
				(type default)
			)
			(layer "B.Fab")
		)
		(fp_line
			(start 0.12065 0.3048)
			(end 0.67945 0.3048)
			(stroke
				(width 0.1)
				(type default)
			)
			(layer "B.Fab")
		)
		(fp_line
			(start -0.120396 0.3048)
			(end -0.120396 0.2794)
			(stroke
				(width 0.1)
				(type default)
			)
			(layer "B.Fab")
		)
		(fp_line
			(start -0.67945 0.3048)
			(end -0.120396 0.3048)
			(stroke
				(width 0.1)
				(type default)
			)
			(layer "B.Fab")
		)
		(pad "1" smd circle
			(at 0.40005 0 270)
			(size 0 0)
			(layers "B.Cu" "B.Mask" "B.Paste")
			(net "CPU0_XTRIG_L4")
		)
		(pad "2" smd circle
			(at -0.40005 0 270)
			(size 0 0)
			(layers "B.Cu" "B.Mask" "B.Paste")
			(net "PVDD18_S5_P0")
		)
	)
	(footprint ""
		(layer "B.Cu")
		(at 439.029602 -423.66311)
		(property "Reference" "PR6810"
			(at 0 0 0)
			(layer "B.SilkS")
			(hide yes)
			(effects
				(font
					(size 1.27 1.27)
				)
				(justify mirror)
			)
		)
		(property "Value" ""
			(at 0 0 0)
			(layer "B.Fab")
			(effects
				(font
					(size 1.27 1.27)
				)
				(justify mirror)
			)
		)
		(duplicate_pad_numbers_are_jumpers no)
		(fp_line
			(start -0.7874 -0.4064)
			(end -0.7874 0.4064)
			(stroke
				(width 0.1524)
				(type default)
			)
			(layer "B.SilkS")
		)
		(fp_line
			(start -0.7874 0.4064)
			(end 0.7874 0.4064)
			(stroke
				(width 0.1524)
				(type default)
			)
			(layer "B.SilkS")
		)
		(fp_line
			(start 0.7874 -0.4064)
			(end -0.7874 -0.4064)
			(stroke
				(width 0.1524)
				(type default)
			)
			(layer "B.SilkS")
		)
		(fp_line
			(start 0.7874 0.4064)
			(end 0.7874 -0.4064)
			(stroke
				(width 0.1524)
				(type default)
			)
			(layer "B.SilkS")
		)
		(fp_line
			(start -0.67945 -0.3048)
			(end -0.67945 0.3048)
			(stroke
				(width 0.1)
				(type default)
			)
			(layer "B.Fab")
		)
		(fp_line
			(start -0.67945 0.3048)
			(end -0.120396 0.3048)
			(stroke
				(width 0.1)
				(type default)
			)
			(layer "B.Fab")
		)
		(fp_line
			(start -0.12065 -0.3048)
			(end -0.67945 -0.3048)
			(stroke
				(width 0.1)
				(type default)
			)
			(layer "B.Fab")
		)
		(fp_line
			(start -0.12065 -0.2794)
			(end -0.12065 -0.3048)
			(stroke
				(width 0.1)
				(type default)
			)
			(layer "B.Fab")
		)
		(fp_line
			(start -0.120396 0.2794)
			(end 0.12065 0.2794)
			(stroke
				(width 0.1)
				(type default)
			)
			(layer "B.Fab")
		)
		(fp_line
			(start -0.120396 0.3048)
			(end -0.120396 0.2794)
			(stroke
				(width 0.1)
				(type default)
			)
			(layer "B.Fab")
		)
		(fp_line
			(start 0.12065 -0.305054)
			(end 0.12065 -0.2794)
			(stroke
				(width 0.1)
				(type default)
			)
			(layer "B.Fab")
		)
		(fp_line
			(start 0.12065 -0.2794)
			(end -0.12065 -0.2794)
			(stroke
				(width 0.1)
				(type default)
			)
			(layer "B.Fab")
		)
		(fp_line
			(start 0.12065 0.2794)
			(end 0.12065 0.3048)
			(stroke
				(width 0.1)
				(type default)
			)
			(layer "B.Fab")
		)
		(fp_line
			(start 0.12065 0.3048)
			(end 0.67945 0.3048)
			(stroke
				(width 0.1)
				(type default)
			)
			(layer "B.Fab")
		)
		(fp_line
			(start 0.67945 -0.305054)
			(end 0.12065 -0.305054)
			(stroke
				(width 0.1)
				(type default)
			)
			(layer "B.Fab")
		)
		(fp_line
			(start 0.67945 0.3048)
			(end 0.67945 -0.305054)
			(stroke
				(width 0.1)
				(type default)
			)
			(layer "B.Fab")
		)
		(pad "1" smd circle
			(at 0.40005 0 180)
			(size 0 0)
			(layers "B.Cu" "B.Mask" "B.Paste")
			(net "P0V9_RETIMER_CPU0_SVID_CLK")
		)
		(pad "2" smd circle
			(at -0.40005 0 180)
			(size 0 0)
			(layers "B.Cu" "B.Mask" "B.Paste")
			(net "GND")
		)
	)
	(footprint ""
		(layer "B.Cu")
		(at 122.18289 -245.488206)
		(property "Reference" "C2318"
			(at 0 0 0)
			(layer "B.SilkS")
			(hide yes)
			(effects
				(font
					(size 1.27 1.27)
				)
				(justify mirror)
			)
		)
		(property "Value" ""
			(at 0 0 0)
			(layer "B.Fab")
			(effects
				(font
					(size 1.27 1.27)
				)
				(justify mirror)
			)
		)
		(duplicate_pad_numbers_are_jumpers no)
		(fp_line
			(start -0.7874 -0.4064)
			(end -0.7874 0.4064)
			(stroke
				(width 0.1524)
				(type default)
			)
			(layer "B.SilkS")
		)
		(fp_line
			(start -0.7874 0.4064)
			(end 0.7874 0.4064)
			(stroke
				(width 0.1524)
				(type default)
			)
			(layer "B.SilkS")
		)
		(fp_line
			(start 0.7874 -0.4064)
			(end -0.7874 -0.4064)
			(stroke
				(width 0.1524)
				(type default)
			)
			(layer "B.SilkS")
		)
		(fp_line
			(start 0.7874 0.4064)
			(end 0.7874 -0.4064)
			(stroke
				(width 0.1524)
				(type default)
			)
			(layer "B.SilkS")
		)
		(fp_line
			(start -0.67945 -0.3048)
			(end -0.67945 0.3048)
			(stroke
				(width 0.1)
				(type default)
			)
			(layer "B.Fab")
		)
		(fp_line
			(start -0.67945 0.3048)
			(end -0.120396 0.3048)
			(stroke
				(width 0.1)
				(type default)
			)
			(layer "B.Fab")
		)
		(fp_line
			(start -0.12065 -0.3048)
			(end -0.67945 -0.3048)
			(stroke
				(width 0.1)
				(type default)
			)
			(layer "B.Fab")
		)
		(fp_line
			(start -0.12065 -0.2794)
			(end -0.12065 -0.3048)
			(stroke
				(width 0.1)
				(type default)
			)
			(layer "B.Fab")
		)
		(fp_line
			(start -0.120396 0.2794)
			(end 0.12065 0.2794)
			(stroke
				(width 0.1)
				(type default)
			)
			(layer "B.Fab")
		)
		(fp_line
			(start -0.120396 0.3048)
			(end -0.120396 0.2794)
			(stroke
				(width 0.1)
				(type default)
			)
			(layer "B.Fab")
		)
		(fp_line
			(start 0.12065 -0.305054)
			(end 0.12065 -0.2794)
			(stroke
				(width 0.1)
				(type default)
			)
			(layer "B.Fab")
		)
		(fp_line
			(start 0.12065 -0.2794)
			(end -0.12065 -0.2794)
			(stroke
				(width 0.1)
				(type default)
			)
			(layer "B.Fab")
		)
		(fp_line
			(start 0.12065 0.2794)
			(end 0.12065 0.3048)
			(stroke
				(width 0.1)
				(type default)
			)
			(layer "B.Fab")
		)
		(fp_line
			(start 0.12065 0.3048)
			(end 0.67945 0.3048)
			(stroke
				(width 0.1)
				(type default)
			)
			(layer "B.Fab")
		)
		(fp_line
			(start 0.67945 -0.305054)
			(end 0.12065 -0.305054)
			(stroke
				(width 0.1)
				(type default)
			)
			(layer "B.Fab")
		)
		(fp_line
			(start 0.67945 0.3048)
			(end 0.67945 -0.305054)
			(stroke
				(width 0.1)
				(type default)
			)
			(layer "B.Fab")
		)
		(pad "1" smd circle
			(at 0.40005 0 180)
			(size 0 0)
			(layers "B.Cu" "B.Mask" "B.Paste")
			(net "PVDDCR_CPU0_P1")
		)
		(pad "2" smd circle
			(at -0.40005 0 180)
			(size 0 0)
			(layers "B.Cu" "B.Mask" "B.Paste")
			(net "GND")
		)
	)
	(footprint ""
		(layer "B.Cu")
		(at 372.818406 -189.50432 90)
		(property "Reference" "PC498"
			(at 6.582664 -0.550926 270)
			(unlocked yes)
			(layer "B.SilkS")
			(effects
				(font
					(size 0.7874 0.5842)
					(thickness 0.1524)
				)
				(justify left mirror)
			)
		)
		(property "Value" ""
			(at 0 0 90)
			(layer "B.Fab")
			(effects
				(font
					(size 1.27 1.27)
				)
				(justify mirror)
			)
		)
		(duplicate_pad_numbers_are_jumpers no)
		(fp_line
			(start 4.533392 -2.249932)
			(end -4.533392 -2.249932)
			(stroke
				(width 0.1524)
				(type default)
			)
			(layer "B.SilkS")
		)
		(fp_line
			(start -4.533392 -2.249932)
			(end -4.533392 2.249932)
			(stroke
				(width 0.1524)
				(type default)
			)
			(layer "B.SilkS")
		)
		(fp_line
			(start 4.533392 2.249932)
			(end 4.533392 -2.249932)
			(stroke
				(width 0.1524)
				(type default)
			)
			(layer "B.SilkS")
		)
		(fp_line
			(start -4.533392 2.249932)
			(end 4.533392 2.249932)
			(stroke
				(width 0.1524)
				(type default)
			)
			(layer "B.SilkS")
		)
		(fp_rect
			(start 4.533392 -2.326132)
			(end 5.39242 2.326132)
			(stroke
				(width 0)
				(type default)
			)
			(fill yes)
			(layer "B.SilkS")
		)
		(fp_line
			(start 3.750056 -2.249932)
			(end -3.750056 -2.249932)
			(stroke
				(width 0.1)
				(type default)
			)
			(layer "B.Fab")
		)
		(fp_line
			(start -3.750056 -2.249932)
			(end -3.750056 2.249932)
			(stroke
				(width 0.1)
				(type default)
			)
			(layer "B.Fab")
		)
		(fp_line
			(start 3.750056 2.249932)
			(end 3.750056 -2.249932)
			(stroke
				(width 0.1)
				(type default)
			)
			(layer "B.Fab")
		)
		(fp_line
			(start -3.750056 2.249932)
			(end 3.750056 2.249932)
			(stroke
				(width 0.1)
				(type default)
			)
			(layer "B.Fab")
		)
		(fp_text user "-"
			(at -4.8514 -0.14605 90)
			(unlocked yes)
			(layer "B.SilkS")
			(effects
				(font
					(size 1.905 1.4224)
					(thickness 0.1524)
				)
				(justify left mirror)
			)
		)
		(fp_text user "+"
			(at 6.322314 0.786384 0)
			(unlocked yes)
			(layer "B.SilkS")
			(effects
				(font
					(size 1.905 1.4224)
					(thickness 0.1524)
				)
				(justify left mirror)
			)
		)
		(fp_text user "-"
			(at -4.8514 -0.14605 90)
			(unlocked yes)
			(layer "B.Fab")
			(effects
				(font
					(size 1.905 1.4224)
					(thickness 0.1524)
				)
				(justify left mirror)
			)
		)
		(fp_text user "+"
			(at 6.322314 0.786384 0)
			(unlocked yes)
			(layer "B.Fab")
			(effects
				(font
					(size 1.905 1.4224)
					(thickness 0.1524)
				)
				(justify left mirror)
			)
		)
		(pad "1" smd rect
			(at 3.199892 0 270)
			(size 2.413 2.8194)
			(layers "B.Cu" "B.Mask" "B.Paste")
			(net "PVDDCR_CPU0_P0")
		)
		(pad "2" smd rect
			(at -3.199892 0 270)
			(size 2.413 2.8194)
			(layers "B.Cu" "B.Mask" "B.Paste")
			(net "GND")
		)
	)
	(footprint ""
		(layer "B.Cu")
		(at 372.937278 -147.568158 180)
		(property "Reference" "PR305"
			(at 0 0 0)
			(layer "B.SilkS")
			(hide yes)
			(effects
				(font
					(size 1.27 1.27)
				)
				(justify mirror)
			)
		)
		(property "Value" ""
			(at 0 0 0)
			(layer "B.Fab")
			(effects
				(font
					(size 1.27 1.27)
				)
				(justify mirror)
			)
		)
		(duplicate_pad_numbers_are_jumpers no)
		(fp_line
			(start 0.7874 0.4064)
			(end 0.7874 -0.4064)
			(stroke
				(width 0.1524)
				(type default)
			)
			(layer "B.SilkS")
		)
		(fp_line
			(start 0.7874 -0.4064)
			(end -0.7874 -0.4064)
			(stroke
				(width 0.1524)
				(type default)
			)
			(layer "B.SilkS")
		)
		(fp_line
			(start -0.7874 0.4064)
			(end 0.7874 0.4064)
			(stroke
				(width 0.1524)
				(type default)
			)
			(layer "B.SilkS")
		)
		(fp_line
			(start -0.7874 -0.4064)
			(end -0.7874 0.4064)
			(stroke
				(width 0.1524)
				(type default)
			)
			(layer "B.SilkS")
		)
		(fp_line
			(start 0.67945 0.3048)
			(end 0.67945 -0.305054)
			(stroke
				(width 0.1)
				(type default)
			)
			(layer "B.Fab")
		)
		(fp_line
			(start 0.67945 -0.305054)
			(end 0.12065 -0.305054)
			(stroke
				(width 0.1)
				(type default)
			)
			(layer "B.Fab")
		)
		(fp_line
			(start 0.12065 0.3048)
			(end 0.67945 0.3048)
			(stroke
				(width 0.1)
				(type default)
			)
			(layer "B.Fab")
		)
		(fp_line
			(start 0.12065 0.2794)
			(end 0.12065 0.3048)
			(stroke
				(width 0.1)
				(type default)
			)
			(layer "B.Fab")
		)
		(fp_line
			(start 0.12065 -0.2794)
			(end -0.12065 -0.2794)
			(stroke
				(width 0.1)
				(type default)
			)
			(layer "B.Fab")
		)
		(fp_line
			(start 0.12065 -0.305054)
			(end 0.12065 -0.2794)
			(stroke
				(width 0.1)
				(type default)
			)
			(layer "B.Fab")
		)
		(fp_line
			(start -0.120396 0.3048)
			(end -0.120396 0.2794)
			(stroke
				(width 0.1)
				(type default)
			)
			(layer "B.Fab")
		)
		(fp_line
			(start -0.120396 0.2794)
			(end 0.12065 0.2794)
			(stroke
				(width 0.1)
				(type default)
			)
			(layer "B.Fab")
		)
		(fp_line
			(start -0.12065 -0.2794)
			(end -0.12065 -0.3048)
			(stroke
				(width 0.1)
				(type default)
			)
			(layer "B.Fab")
		)
		(fp_line
			(start -0.12065 -0.3048)
			(end -0.67945 -0.3048)
			(stroke
				(width 0.1)
				(type default)
			)
			(layer "B.Fab")
		)
		(fp_line
			(start -0.67945 0.3048)
			(end -0.120396 0.3048)
			(stroke
				(width 0.1)
				(type default)
			)
			(layer "B.Fab")
		)
		(fp_line
			(start -0.67945 -0.3048)
			(end -0.67945 0.3048)
			(stroke
				(width 0.1)
				(type default)
			)
			(layer "B.Fab")
		)
		(pad "1" smd circle
			(at 0.40005 0)
			(size 0 0)
			(layers "B.Cu" "B.Mask" "B.Paste")
			(net "SVID_PVDDCR_CPU0_P0_SVTI")
		)
		(pad "2" smd circle
			(at -0.40005 0)
			(size 0 0)
			(layers "B.Cu" "B.Mask" "B.Paste")
			(net "SVID_PVDDCR_CPU0_P0_SVTI_R")
		)
	)
	(footprint ""
		(layer "B.Cu")
		(at 369.62588 -259.729986)
		(property "Reference" "C2577"
			(at 0 0 0)
			(layer "B.SilkS")
			(hide yes)
			(effects
				(font
					(size 1.27 1.27)
				)
				(justify mirror)
			)
		)
		(property "Value" ""
			(at 0 0 0)
			(layer "B.Fab")
			(effects
				(font
					(size 1.27 1.27)
				)
				(justify mirror)
			)
		)
		(duplicate_pad_numbers_are_jumpers no)
		(fp_line
			(start -0.7874 -0.4064)
			(end -0.7874 0.4064)
			(stroke
				(width 0.1524)
				(type default)
			)
			(layer "B.SilkS")
		)
		(fp_line
			(start -0.7874 0.4064)
			(end 0.7874 0.4064)
			(stroke
				(width 0.1524)
				(type default)
			)
			(layer "B.SilkS")
		)
		(fp_line
			(start 0.7874 -0.4064)
			(end -0.7874 -0.4064)
			(stroke
				(width 0.1524)
				(type default)
			)
			(layer "B.SilkS")
		)
		(fp_line
			(start 0.7874 0.4064)
			(end 0.7874 -0.4064)
			(stroke
				(width 0.1524)
				(type default)
			)
			(layer "B.SilkS")
		)
		(fp_line
			(start -0.67945 -0.3048)
			(end -0.67945 0.3048)
			(stroke
				(width 0.1)
				(type default)
			)
			(layer "B.Fab")
		)
		(fp_line
			(start -0.67945 0.3048)
			(end -0.120396 0.3048)
			(stroke
				(width 0.1)
				(type default)
			)
			(layer "B.Fab")
		)
		(fp_line
			(start -0.12065 -0.3048)
			(end -0.67945 -0.3048)
			(stroke
				(width 0.1)
				(type default)
			)
			(layer "B.Fab")
		)
		(fp_line
			(start -0.12065 -0.2794)
			(end -0.12065 -0.3048)
			(stroke
				(width 0.1)
				(type default)
			)
			(layer "B.Fab")
		)
		(fp_line
			(start -0.120396 0.2794)
			(end 0.12065 0.2794)
			(stroke
				(width 0.1)
				(type default)
			)
			(layer "B.Fab")
		)
		(fp_line
			(start -0.120396 0.3048)
			(end -0.120396 0.2794)
			(stroke
				(width 0.1)
				(type default)
			)
			(layer "B.Fab")
		)
		(fp_line
			(start 0.12065 -0.305054)
			(end 0.12065 -0.2794)
			(stroke
				(width 0.1)
				(type default)
			)
			(layer "B.Fab")
		)
		(fp_line
			(start 0.12065 -0.2794)
			(end -0.12065 -0.2794)
			(stroke
				(width 0.1)
				(type default)
			)
			(layer "B.Fab")
		)
		(fp_line
			(start 0.12065 0.2794)
			(end 0.12065 0.3048)
			(stroke
				(width 0.1)
				(type default)
			)
			(layer "B.Fab")
		)
		(fp_line
			(start 0.12065 0.3048)
			(end 0.67945 0.3048)
			(stroke
				(width 0.1)
				(type default)
			)
			(layer "B.Fab")
		)
		(fp_line
			(start 0.67945 -0.305054)
			(end 0.12065 -0.305054)
			(stroke
				(width 0.1)
				(type default)
			)
			(layer "B.Fab")
		)
		(fp_line
			(start 0.67945 0.3048)
			(end 0.67945 -0.305054)
			(stroke
				(width 0.1)
				(type default)
			)
			(layer "B.Fab")
		)
		(pad "1" smd circle
			(at 0.40005 0 180)
			(size 0 0)
			(layers "B.Cu" "B.Mask" "B.Paste")
			(net "PVDDCR_SOC_P0")
		)
		(pad "2" smd circle
			(at -0.40005 0 180)
			(size 0 0)
			(layers "B.Cu" "B.Mask" "B.Paste")
			(net "GND")
		)
	)
	(footprint ""
		(layer "B.Cu")
		(at 208.461356 -380.206504)
		(property "Reference" "PR2512"
			(at 0 0 0)
			(layer "B.SilkS")
			(hide yes)
			(effects
				(font
					(size 1.27 1.27)
				)
				(justify mirror)
			)
		)
		(property "Value" ""
			(at 0 0 0)
			(layer "B.Fab")
			(effects
				(font
					(size 1.27 1.27)
				)
				(justify mirror)
			)
		)
		(duplicate_pad_numbers_are_jumpers no)
		(fp_line
			(start -0.7874 -0.4064)
			(end -0.7874 0.4064)
			(stroke
				(width 0.1524)
				(type default)
			)
			(layer "B.SilkS")
		)
		(fp_line
			(start -0.7874 0.4064)
			(end 0.7874 0.4064)
			(stroke
				(width 0.1524)
				(type default)
			)
			(layer "B.SilkS")
		)
		(fp_line
			(start 0.7874 -0.4064)
			(end -0.7874 -0.4064)
			(stroke
				(width 0.1524)
				(type default)
			)
			(layer "B.SilkS")
		)
		(fp_line
			(start 0.7874 0.4064)
			(end 0.7874 -0.4064)
			(stroke
				(width 0.1524)
				(type default)
			)
			(layer "B.SilkS")
		)
		(fp_line
			(start -0.67945 -0.3048)
			(end -0.67945 0.3048)
			(stroke
				(width 0.1)
				(type default)
			)
			(layer "B.Fab")
		)
		(fp_line
			(start -0.67945 0.3048)
			(end -0.120396 0.3048)
			(stroke
				(width 0.1)
				(type default)
			)
			(layer "B.Fab")
		)
		(fp_line
			(start -0.12065 -0.3048)
			(end -0.67945 -0.3048)
			(stroke
				(width 0.1)
				(type default)
			)
			(layer "B.Fab")
		)
		(fp_line
			(start -0.12065 -0.2794)
			(end -0.12065 -0.3048)
			(stroke
				(width 0.1)
				(type default)
			)
			(layer "B.Fab")
		)
		(fp_line
			(start -0.120396 0.2794)
			(end 0.12065 0.2794)
			(stroke
				(width 0.1)
				(type default)
			)
			(layer "B.Fab")
		)
		(fp_line
			(start -0.120396 0.3048)
			(end -0.120396 0.2794)
			(stroke
				(width 0.1)
				(type default)
			)
			(layer "B.Fab")
		)
		(fp_line
			(start 0.12065 -0.305054)
			(end 0.12065 -0.2794)
			(stroke
				(width 0.1)
				(type default)
			)
			(layer "B.Fab")
		)
		(fp_line
			(start 0.12065 -0.2794)
			(end -0.12065 -0.2794)
			(stroke
				(width 0.1)
				(type default)
			)
			(layer "B.Fab")
		)
		(fp_line
			(start 0.12065 0.2794)
			(end 0.12065 0.3048)
			(stroke
				(width 0.1)
				(type default)
			)
			(layer "B.Fab")
		)
		(fp_line
			(start 0.12065 0.3048)
			(end 0.67945 0.3048)
			(stroke
				(width 0.1)
				(type default)
			)
			(layer "B.Fab")
		)
		(fp_line
			(start 0.67945 -0.305054)
			(end 0.12065 -0.305054)
			(stroke
				(width 0.1)
				(type default)
			)
			(layer "B.Fab")
		)
		(fp_line
			(start 0.67945 0.3048)
			(end 0.67945 -0.305054)
			(stroke
				(width 0.1)
				(type default)
			)
			(layer "B.Fab")
		)
		(pad "1" smd circle
			(at 0.40005 0 180)
			(size 0 0)
			(layers "B.Cu" "B.Mask" "B.Paste")
			(net "P12V_HSC_ADC_P")
		)
		(pad "2" smd circle
			(at -0.40005 0 180)
			(size 0 0)
			(layers "B.Cu" "B.Mask" "B.Paste")
			(net "P12V_HSC_SENSE2_R3_P")
		)
	)
	(footprint ""
		(layer "B.Cu")
		(at 386.091176 -398.942052 90)
		(property "Reference" "C1026"
			(at 0 0 90)
			(layer "B.SilkS")
			(hide yes)
			(effects
				(font
					(size 1.27 1.27)
				)
				(justify mirror)
			)
		)
		(property "Value" ""
			(at 0 0 90)
			(layer "B.Fab")
			(effects
				(font
					(size 1.27 1.27)
				)
				(justify mirror)
			)
		)
		(duplicate_pad_numbers_are_jumpers no)
		(fp_line
			(start 0.7874 -0.4064)
			(end -0.7874 -0.4064)
			(stroke
				(width 0.1524)
				(type default)
			)
			(layer "B.SilkS")
		)
		(fp_line
			(start -0.7874 -0.4064)
			(end -0.7874 0.4064)
			(stroke
				(width 0.1524)
				(type default)
			)
			(layer "B.SilkS")
		)
		(fp_line
			(start 0.7874 0.4064)
			(end 0.7874 -0.4064)
			(stroke
				(width 0.1524)
				(type default)
			)
			(layer "B.SilkS")
		)
		(fp_line
			(start -0.7874 0.4064)
			(end 0.7874 0.4064)
			(stroke
				(width 0.1524)
				(type default)
			)
			(layer "B.SilkS")
		)
		(fp_line
			(start 0.67945 -0.305054)
			(end 0.12065 -0.305054)
			(stroke
				(width 0.1)
				(type default)
			)
			(layer "B.Fab")
		)
		(fp_line
			(start 0.12065 -0.305054)
			(end 0.12065 -0.2794)
			(stroke
				(width 0.1)
				(type default)
			)
			(layer "B.Fab")
		)
		(fp_line
			(start -0.12065 -0.3048)
			(end -0.67945 -0.3048)
			(stroke
				(width 0.1)
				(type default)
			)
			(layer "B.Fab")
		)
		(fp_line
			(start -0.67945 -0.3048)
			(end -0.67945 0.3048)
			(stroke
				(width 0.1)
				(type default)
			)
			(layer "B.Fab")
		)
		(fp_line
			(start 0.12065 -0.2794)
			(end -0.12065 -0.2794)
			(stroke
				(width 0.1)
				(type default)
			)
			(layer "B.Fab")
		)
		(fp_line
			(start -0.12065 -0.2794)
			(end -0.12065 -0.3048)
			(stroke
				(width 0.1)
				(type default)
			)
			(layer "B.Fab")
		)
		(fp_line
			(start 0.12065 0.2794)
			(end 0.12065 0.3048)
			(stroke
				(width 0.1)
				(type default)
			)
			(layer "B.Fab")
		)
		(fp_line
			(start -0.120396 0.2794)
			(end 0.12065 0.2794)
			(stroke
				(width 0.1)
				(type default)
			)
			(layer "B.Fab")
		)
		(fp_line
			(start 0.67945 0.3048)
			(end 0.67945 -0.305054)
			(stroke
				(width 0.1)
				(type default)
			)
			(layer "B.Fab")
		)
		(fp_line
			(start 0.12065 0.3048)
			(end 0.67945 0.3048)
			(stroke
				(width 0.1)
				(type default)
			)
			(layer "B.Fab")
		)
		(fp_line
			(start -0.120396 0.3048)
			(end -0.120396 0.2794)
			(stroke
				(width 0.1)
				(type default)
			)
			(layer "B.Fab")
		)
		(fp_line
			(start -0.67945 0.3048)
			(end -0.120396 0.3048)
			(stroke
				(width 0.1)
				(type default)
			)
			(layer "B.Fab")
		)
		(pad "1" smd circle
			(at 0.40005 0 270)
			(size 0 0)
			(layers "B.Cu" "B.Mask" "B.Paste")
			(net "P0V9_CPU0_RT3_2A")
		)
		(pad "2" smd circle
			(at -0.40005 0 270)
			(size 0 0)
			(layers "B.Cu" "B.Mask" "B.Paste")
			(net "GND")
		)
	)
	(footprint ""
		(layer "B.Cu")
		(at 365.836454 -250.89231)
		(property "Reference" "C2566"
			(at 0 0 0)
			(layer "B.SilkS")
			(hide yes)
			(effects
				(font
					(size 1.27 1.27)
				)
				(justify mirror)
			)
		)
		(property "Value" ""
			(at 0 0 0)
			(layer "B.Fab")
			(effects
				(font
					(size 1.27 1.27)
				)
				(justify mirror)
			)
		)
		(duplicate_pad_numbers_are_jumpers no)
		(fp_line
			(start -0.7874 -0.4064)
			(end -0.7874 0.4064)
			(stroke
				(width 0.1524)
				(type default)
			)
			(layer "B.SilkS")
		)
		(fp_line
			(start -0.7874 0.4064)
			(end 0.7874 0.4064)
			(stroke
				(width 0.1524)
				(type default)
			)
			(layer "B.SilkS")
		)
		(fp_line
			(start 0.7874 -0.4064)
			(end -0.7874 -0.4064)
			(stroke
				(width 0.1524)
				(type default)
			)
			(layer "B.SilkS")
		)
		(fp_line
			(start 0.7874 0.4064)
			(end 0.7874 -0.4064)
			(stroke
				(width 0.1524)
				(type default)
			)
			(layer "B.SilkS")
		)
		(fp_line
			(start -0.67945 -0.3048)
			(end -0.67945 0.3048)
			(stroke
				(width 0.1)
				(type default)
			)
			(layer "B.Fab")
		)
		(fp_line
			(start -0.67945 0.3048)
			(end -0.120396 0.3048)
			(stroke
				(width 0.1)
				(type default)
			)
			(layer "B.Fab")
		)
		(fp_line
			(start -0.12065 -0.3048)
			(end -0.67945 -0.3048)
			(stroke
				(width 0.1)
				(type default)
			)
			(layer "B.Fab")
		)
		(fp_line
			(start -0.12065 -0.2794)
			(end -0.12065 -0.3048)
			(stroke
				(width 0.1)
				(type default)
			)
			(layer "B.Fab")
		)
		(fp_line
			(start -0.120396 0.2794)
			(end 0.12065 0.2794)
			(stroke
				(width 0.1)
				(type default)
			)
			(layer "B.Fab")
		)
		(fp_line
			(start -0.120396 0.3048)
			(end -0.120396 0.2794)
			(stroke
				(width 0.1)
				(type default)
			)
			(layer "B.Fab")
		)
		(fp_line
			(start 0.12065 -0.305054)
			(end 0.12065 -0.2794)
			(stroke
				(width 0.1)
				(type default)
			)
			(layer "B.Fab")
		)
		(fp_line
			(start 0.12065 -0.2794)
			(end -0.12065 -0.2794)
			(stroke
				(width 0.1)
				(type default)
			)
			(layer "B.Fab")
		)
		(fp_line
			(start 0.12065 0.2794)
			(end 0.12065 0.3048)
			(stroke
				(width 0.1)
				(type default)
			)
			(layer "B.Fab")
		)
		(fp_line
			(start 0.12065 0.3048)
			(end 0.67945 0.3048)
			(stroke
				(width 0.1)
				(type default)
			)
			(layer "B.Fab")
		)
		(fp_line
			(start 0.67945 -0.305054)
			(end 0.12065 -0.305054)
			(stroke
				(width 0.1)
				(type default)
			)
			(layer "B.Fab")
		)
		(fp_line
			(start 0.67945 0.3048)
			(end 0.67945 -0.305054)
			(stroke
				(width 0.1)
				(type default)
			)
			(layer "B.Fab")
		)
		(pad "1" smd circle
			(at 0.40005 0 180)
			(size 0 0)
			(layers "B.Cu" "B.Mask" "B.Paste")
			(net "PVDDCR_SOC_P0")
		)
		(pad "2" smd circle
			(at -0.40005 0 180)
			(size 0 0)
			(layers "B.Cu" "B.Mask" "B.Paste")
			(net "GND")
		)
	)
	(footprint ""
		(layer "B.Cu")
		(at 296.479722 -194.88531 180)
		(property "Reference" "R761"
			(at 0 0 0)
			(layer "B.SilkS")
			(hide yes)
			(effects
				(font
					(size 1.27 1.27)
				)
				(justify mirror)
			)
		)
		(property "Value" ""
			(at 0 0 0)
			(layer "B.Fab")
			(effects
				(font
					(size 1.27 1.27)
				)
				(justify mirror)
			)
		)
		(duplicate_pad_numbers_are_jumpers no)
		(fp_line
			(start 0.7874 0.4064)
			(end 0.7874 -0.4064)
			(stroke
				(width 0.1524)
				(type default)
			)
			(layer "B.SilkS")
		)
		(fp_line
			(start 0.7874 -0.4064)
			(end -0.7874 -0.4064)
			(stroke
				(width 0.1524)
				(type default)
			)
			(layer "B.SilkS")
		)
		(fp_line
			(start -0.7874 0.4064)
			(end 0.7874 0.4064)
			(stroke
				(width 0.1524)
				(type default)
			)
			(layer "B.SilkS")
		)
		(fp_line
			(start -0.7874 -0.4064)
			(end -0.7874 0.4064)
			(stroke
				(width 0.1524)
				(type default)
			)
			(layer "B.SilkS")
		)
		(fp_line
			(start 0.67945 0.3048)
			(end 0.67945 -0.305054)
			(stroke
				(width 0.1)
				(type default)
			)
			(layer "B.Fab")
		)
		(fp_line
			(start 0.67945 -0.305054)
			(end 0.12065 -0.305054)
			(stroke
				(width 0.1)
				(type default)
			)
			(layer "B.Fab")
		)
		(fp_line
			(start 0.12065 0.3048)
			(end 0.67945 0.3048)
			(stroke
				(width 0.1)
				(type default)
			)
			(layer "B.Fab")
		)
		(fp_line
			(start 0.12065 0.2794)
			(end 0.12065 0.3048)
			(stroke
				(width 0.1)
				(type default)
			)
			(layer "B.Fab")
		)
		(fp_line
			(start 0.12065 -0.2794)
			(end -0.12065 -0.2794)
			(stroke
				(width 0.1)
				(type default)
			)
			(layer "B.Fab")
		)
		(fp_line
			(start 0.12065 -0.305054)
			(end 0.12065 -0.2794)
			(stroke
				(width 0.1)
				(type default)
			)
			(layer "B.Fab")
		)
		(fp_line
			(start -0.120396 0.3048)
			(end -0.120396 0.2794)
			(stroke
				(width 0.1)
				(type default)
			)
			(layer "B.Fab")
		)
		(fp_line
			(start -0.120396 0.2794)
			(end 0.12065 0.2794)
			(stroke
				(width 0.1)
				(type default)
			)
			(layer "B.Fab")
		)
		(fp_line
			(start -0.12065 -0.2794)
			(end -0.12065 -0.3048)
			(stroke
				(width 0.1)
				(type default)
			)
			(layer "B.Fab")
		)
		(fp_line
			(start -0.12065 -0.3048)
			(end -0.67945 -0.3048)
			(stroke
				(width 0.1)
				(type default)
			)
			(layer "B.Fab")
		)
		(fp_line
			(start -0.67945 0.3048)
			(end -0.120396 0.3048)
			(stroke
				(width 0.1)
				(type default)
			)
			(layer "B.Fab")
		)
		(fp_line
			(start -0.67945 -0.3048)
			(end -0.67945 0.3048)
			(stroke
				(width 0.1)
				(type default)
			)
			(layer "B.Fab")
		)
		(pad "1" smd circle
			(at 0.40005 0)
			(size 0 0)
			(layers "B.Cu" "B.Mask" "B.Paste")
			(net "PD_CHB_CPU0_DIMM_SAA")
		)
		(pad "2" smd circle
			(at -0.40005 0)
			(size 0 0)
			(layers "B.Cu" "B.Mask" "B.Paste")
			(net "GND")
		)
	)
	(footprint ""
		(layer "B.Cu")
		(at 287.933384 -337.984846 -90)
		(property "Reference" "PC190_3"
			(at 0 0 90)
			(layer "B.SilkS")
			(hide yes)
			(effects
				(font
					(size 1.27 1.27)
				)
				(justify mirror)
			)
		)
		(property "Value" ""
			(at 0 0 90)
			(layer "B.Fab")
			(effects
				(font
					(size 1.27 1.27)
				)
				(justify mirror)
			)
		)
		(duplicate_pad_numbers_are_jumpers no)
		(fp_line
			(start -1.524 0.762)
			(end 1.524 0.762)
			(stroke
				(width 0.1524)
				(type default)
			)
			(layer "B.SilkS")
		)
		(fp_line
			(start 1.524 0.762)
			(end 1.524 -0.762)
			(stroke
				(width 0.1524)
				(type default)
			)
			(layer "B.SilkS")
		)
		(fp_line
			(start -1.524 -0.762)
			(end -1.524 0.762)
			(stroke
				(width 0.1524)
				(type default)
			)
			(layer "B.SilkS")
		)
		(fp_line
			(start 1.524 -0.762)
			(end -1.524 -0.762)
			(stroke
				(width 0.1524)
				(type default)
			)
			(layer "B.SilkS")
		)
		(fp_line
			(start -1.1049 0.724916)
			(end -1.1049 -0.724916)
			(stroke
				(width 0.1)
				(type default)
			)
			(layer "B.Fab")
		)
		(fp_line
			(start 1.1049 0.724916)
			(end -1.1049 0.724916)
			(stroke
				(width 0.1)
				(type default)
			)
			(layer "B.Fab")
		)
		(fp_line
			(start -1.1049 -0.724916)
			(end 1.1049 -0.724916)
			(stroke
				(width 0.1)
				(type default)
			)
			(layer "B.Fab")
		)
		(fp_line
			(start 1.1049 -0.724916)
			(end 1.1049 0.724916)
			(stroke
				(width 0.1)
				(type default)
			)
			(layer "B.Fab")
		)
		(pad "1" smd rect
			(at 0.889 0 270)
			(size 1.016 1.27)
			(layers "B.Cu" "B.Mask" "B.Paste")
			(net "PVDDIO_P0")
		)
		(pad "2" smd rect
			(at -0.889 0 270)
			(size 1.016 1.27)
			(layers "B.Cu" "B.Mask" "B.Paste")
			(net "GND")
		)
	)
	(footprint ""
		(layer "B.Cu")
		(at 172.312838 -419.206426 180)
		(property "Reference" "R2807"
			(at 0 0 0)
			(layer "B.SilkS")
			(hide yes)
			(effects
				(font
					(size 1.27 1.27)
				)
				(justify mirror)
			)
		)
		(property "Value" ""
			(at 0 0 0)
			(layer "B.Fab")
			(effects
				(font
					(size 1.27 1.27)
				)
				(justify mirror)
			)
		)
		(duplicate_pad_numbers_are_jumpers no)
		(fp_line
			(start 0.7874 0.4064)
			(end 0.7874 -0.4064)
			(stroke
				(width 0.1524)
				(type default)
			)
			(layer "B.SilkS")
		)
		(fp_line
			(start 0.7874 -0.4064)
			(end -0.7874 -0.4064)
			(stroke
				(width 0.1524)
				(type default)
			)
			(layer "B.SilkS")
		)
		(fp_line
			(start -0.7874 0.4064)
			(end 0.7874 0.4064)
			(stroke
				(width 0.1524)
				(type default)
			)
			(layer "B.SilkS")
		)
		(fp_line
			(start -0.7874 -0.4064)
			(end -0.7874 0.4064)
			(stroke
				(width 0.1524)
				(type default)
			)
			(layer "B.SilkS")
		)
		(fp_line
			(start 0.67945 0.3048)
			(end 0.67945 -0.305054)
			(stroke
				(width 0.1)
				(type default)
			)
			(layer "B.Fab")
		)
		(fp_line
			(start 0.67945 -0.305054)
			(end 0.12065 -0.305054)
			(stroke
				(width 0.1)
				(type default)
			)
			(layer "B.Fab")
		)
		(fp_line
			(start 0.12065 0.3048)
			(end 0.67945 0.3048)
			(stroke
				(width 0.1)
				(type default)
			)
			(layer "B.Fab")
		)
		(fp_line
			(start 0.12065 0.2794)
			(end 0.12065 0.3048)
			(stroke
				(width 0.1)
				(type default)
			)
			(layer "B.Fab")
		)
		(fp_line
			(start 0.12065 -0.2794)
			(end -0.12065 -0.2794)
			(stroke
				(width 0.1)
				(type default)
			)
			(layer "B.Fab")
		)
		(fp_line
			(start 0.12065 -0.305054)
			(end 0.12065 -0.2794)
			(stroke
				(width 0.1)
				(type default)
			)
			(layer "B.Fab")
		)
		(fp_line
			(start -0.120396 0.3048)
			(end -0.120396 0.2794)
			(stroke
				(width 0.1)
				(type default)
			)
			(layer "B.Fab")
		)
		(fp_line
			(start -0.120396 0.2794)
			(end 0.12065 0.2794)
			(stroke
				(width 0.1)
				(type default)
			)
			(layer "B.Fab")
		)
		(fp_line
			(start -0.12065 -0.2794)
			(end -0.12065 -0.3048)
			(stroke
				(width 0.1)
				(type default)
			)
			(layer "B.Fab")
		)
		(fp_line
			(start -0.12065 -0.3048)
			(end -0.67945 -0.3048)
			(stroke
				(width 0.1)
				(type default)
			)
			(layer "B.Fab")
		)
		(fp_line
			(start -0.67945 0.3048)
			(end -0.120396 0.3048)
			(stroke
				(width 0.1)
				(type default)
			)
			(layer "B.Fab")
		)
		(fp_line
			(start -0.67945 -0.3048)
			(end -0.67945 0.3048)
			(stroke
				(width 0.1)
				(type default)
			)
			(layer "B.Fab")
		)
		(pad "1" smd circle
			(at 0.40005 0)
			(size 0 0)
			(layers "B.Cu" "B.Mask" "B.Paste")
			(net "P3V3_AUX")
		)
		(pad "2" smd circle
			(at -0.40005 0)
			(size 0 0)
			(layers "B.Cu" "B.Mask" "B.Paste")
			(net "SMB_FAN_3V3AUX_BUF_SDA")
		)
	)
	(footprint ""
		(layer "B.Cu")
		(at 9.271 -81.153 -90)
		(property "Reference" "C8002"
			(at 0 0 90)
			(layer "B.SilkS")
			(hide yes)
			(effects
				(font
					(size 1.27 1.27)
				)
				(justify mirror)
			)
		)
		(property "Value" ""
			(at 0 0 90)
			(layer "B.Fab")
			(effects
				(font
					(size 1.27 1.27)
				)
				(justify mirror)
			)
		)
		(duplicate_pad_numbers_are_jumpers no)
		(fp_line
			(start -0.7874 0.4064)
			(end 0.7874 0.4064)
			(stroke
				(width 0.1524)
				(type default)
			)
			(layer "B.SilkS")
		)
		(fp_line
			(start 0.7874 0.4064)
			(end 0.7874 -0.4064)
			(stroke
				(width 0.1524)
				(type default)
			)
			(layer "B.SilkS")
		)
		(fp_line
			(start -0.7874 -0.4064)
			(end -0.7874 0.4064)
			(stroke
				(width 0.1524)
				(type default)
			)
			(layer "B.SilkS")
		)
		(fp_line
			(start 0.7874 -0.4064)
			(end -0.7874 -0.4064)
			(stroke
				(width 0.1524)
				(type default)
			)
			(layer "B.SilkS")
		)
		(fp_line
			(start -0.67945 0.3048)
			(end -0.120396 0.3048)
			(stroke
				(width 0.1)
				(type default)
			)
			(layer "B.Fab")
		)
		(fp_line
			(start -0.120396 0.3048)
			(end -0.120396 0.2794)
			(stroke
				(width 0.1)
				(type default)
			)
			(layer "B.Fab")
		)
		(fp_line
			(start 0.12065 0.3048)
			(end 0.67945 0.3048)
			(stroke
				(width 0.1)
				(type default)
			)
			(layer "B.Fab")
		)
		(fp_line
			(start 0.67945 0.3048)
			(end 0.67945 -0.305054)
			(stroke
				(width 0.1)
				(type default)
			)
			(layer "B.Fab")
		)
		(fp_line
			(start -0.120396 0.2794)
			(end 0.12065 0.2794)
			(stroke
				(width 0.1)
				(type default)
			)
			(layer "B.Fab")
		)
		(fp_line
			(start 0.12065 0.2794)
			(end 0.12065 0.3048)
			(stroke
				(width 0.1)
				(type default)
			)
			(layer "B.Fab")
		)
		(fp_line
			(start -0.12065 -0.2794)
			(end -0.12065 -0.3048)
			(stroke
				(width 0.1)
				(type default)
			)
			(layer "B.Fab")
		)
		(fp_line
			(start 0.12065 -0.2794)
			(end -0.12065 -0.2794)
			(stroke
				(width 0.1)
				(type default)
			)
			(layer "B.Fab")
		)
		(fp_line
			(start -0.67945 -0.3048)
			(end -0.67945 0.3048)
			(stroke
				(width 0.1)
				(type default)
			)
			(layer "B.Fab")
		)
		(fp_line
			(start -0.12065 -0.3048)
			(end -0.67945 -0.3048)
			(stroke
				(width 0.1)
				(type default)
			)
			(layer "B.Fab")
		)
		(fp_line
			(start 0.12065 -0.305054)
			(end 0.12065 -0.2794)
			(stroke
				(width 0.1)
				(type default)
			)
			(layer "B.Fab")
		)
		(fp_line
			(start 0.67945 -0.305054)
			(end 0.12065 -0.305054)
			(stroke
				(width 0.1)
				(type default)
			)
			(layer "B.Fab")
		)
		(pad "1" smd circle
			(at 0.40005 0 90)
			(size 0 0)
			(layers "B.Cu" "B.Mask" "B.Paste")
			(net "OCP_SFF_PRSNT23_R1_N")
		)
		(pad "2" smd circle
			(at -0.40005 0 90)
			(size 0 0)
			(layers "B.Cu" "B.Mask" "B.Paste")
			(net "GND")
		)
	)
	(footprint ""
		(layer "B.Cu")
		(at 446.253616 -397.05407 90)
		(property "Reference" "PC6556_1"
			(at 0 0 90)
			(layer "B.SilkS")
			(hide yes)
			(effects
				(font
					(size 1.27 1.27)
				)
				(justify mirror)
			)
		)
		(property "Value" ""
			(at 0 0 90)
			(layer "B.Fab")
			(effects
				(font
					(size 1.27 1.27)
				)
				(justify mirror)
			)
		)
		(duplicate_pad_numbers_are_jumpers no)
		(fp_line
			(start 1.524 -0.762)
			(end -1.524 -0.762)
			(stroke
				(width 0.1524)
				(type default)
			)
			(layer "B.SilkS")
		)
		(fp_line
			(start -1.524 -0.762)
			(end -1.524 0.762)
			(stroke
				(width 0.1524)
				(type default)
			)
			(layer "B.SilkS")
		)
		(fp_line
			(start 1.524 0.762)
			(end 1.524 -0.762)
			(stroke
				(width 0.1524)
				(type default)
			)
			(layer "B.SilkS")
		)
		(fp_line
			(start -1.524 0.762)
			(end 1.524 0.762)
			(stroke
				(width 0.1524)
				(type default)
			)
			(layer "B.SilkS")
		)
		(fp_line
			(start 1.1049 -0.724916)
			(end 1.1049 0.724916)
			(stroke
				(width 0.1)
				(type default)
			)
			(layer "B.Fab")
		)
		(fp_line
			(start -1.1049 -0.724916)
			(end 1.1049 -0.724916)
			(stroke
				(width 0.1)
				(type default)
			)
			(layer "B.Fab")
		)
		(fp_line
			(start 1.1049 0.724916)
			(end -1.1049 0.724916)
			(stroke
				(width 0.1)
				(type default)
			)
			(layer "B.Fab")
		)
		(fp_line
			(start -1.1049 0.724916)
			(end -1.1049 -0.724916)
			(stroke
				(width 0.1)
				(type default)
			)
			(layer "B.Fab")
		)
		(pad "1" smd rect
			(at 0.889 0 90)
			(size 1.016 1.27)
			(layers "B.Cu" "B.Mask" "B.Paste")
			(net "SW_P12V_AUX_P0V9_RETIMER_CPU0_FLT")
		)
		(pad "2" smd rect
			(at -0.889 0 90)
			(size 1.016 1.27)
			(layers "B.Cu" "B.Mask" "B.Paste")
			(net "GND")
		)
	)
	(footprint ""
		(layer "B.Cu")
		(at 159.615632 -193.148966 -90)
		(property "Reference" "R566"
			(at 0 0 90)
			(layer "B.SilkS")
			(hide yes)
			(effects
				(font
					(size 1.27 1.27)
				)
				(justify mirror)
			)
		)
		(property "Value" ""
			(at 0 0 90)
			(layer "B.Fab")
			(effects
				(font
					(size 1.27 1.27)
				)
				(justify mirror)
			)
		)
		(duplicate_pad_numbers_are_jumpers no)
		(fp_line
			(start -0.7874 0.4064)
			(end 0.7874 0.4064)
			(stroke
				(width 0.1524)
				(type default)
			)
			(layer "B.SilkS")
		)
		(fp_line
			(start 0.7874 0.4064)
			(end 0.7874 -0.4064)
			(stroke
				(width 0.1524)
				(type default)
			)
			(layer "B.SilkS")
		)
		(fp_line
			(start -0.7874 -0.4064)
			(end -0.7874 0.4064)
			(stroke
				(width 0.1524)
				(type default)
			)
			(layer "B.SilkS")
		)
		(fp_line
			(start 0.7874 -0.4064)
			(end -0.7874 -0.4064)
			(stroke
				(width 0.1524)
				(type default)
			)
			(layer "B.SilkS")
		)
		(fp_line
			(start -0.67945 0.3048)
			(end -0.120396 0.3048)
			(stroke
				(width 0.1)
				(type default)
			)
			(layer "B.Fab")
		)
		(fp_line
			(start -0.120396 0.3048)
			(end -0.120396 0.2794)
			(stroke
				(width 0.1)
				(type default)
			)
			(layer "B.Fab")
		)
		(fp_line
			(start 0.12065 0.3048)
			(end 0.67945 0.3048)
			(stroke
				(width 0.1)
				(type default)
			)
			(layer "B.Fab")
		)
		(fp_line
			(start 0.67945 0.3048)
			(end 0.67945 -0.305054)
			(stroke
				(width 0.1)
				(type default)
			)
			(layer "B.Fab")
		)
		(fp_line
			(start -0.120396 0.2794)
			(end 0.12065 0.2794)
			(stroke
				(width 0.1)
				(type default)
			)
			(layer "B.Fab")
		)
		(fp_line
			(start 0.12065 0.2794)
			(end 0.12065 0.3048)
			(stroke
				(width 0.1)
				(type default)
			)
			(layer "B.Fab")
		)
		(fp_line
			(start -0.12065 -0.2794)
			(end -0.12065 -0.3048)
			(stroke
				(width 0.1)
				(type default)
			)
			(layer "B.Fab")
		)
		(fp_line
			(start 0.12065 -0.2794)
			(end -0.12065 -0.2794)
			(stroke
				(width 0.1)
				(type default)
			)
			(layer "B.Fab")
		)
		(fp_line
			(start -0.67945 -0.3048)
			(end -0.67945 0.3048)
			(stroke
				(width 0.1)
				(type default)
			)
			(layer "B.Fab")
		)
		(fp_line
			(start -0.12065 -0.3048)
			(end -0.67945 -0.3048)
			(stroke
				(width 0.1)
				(type default)
			)
			(layer "B.Fab")
		)
		(fp_line
			(start 0.12065 -0.305054)
			(end 0.12065 -0.2794)
			(stroke
				(width 0.1)
				(type default)
			)
			(layer "B.Fab")
		)
		(fp_line
			(start 0.67945 -0.305054)
			(end 0.12065 -0.305054)
			(stroke
				(width 0.1)
				(type default)
			)
			(layer "B.Fab")
		)
		(pad "1" smd rect
			(at 0.40005 0 270)
			(size 0.4572 0.508)
			(layers "B.Cu" "B.Mask" "B.Paste")
			(net "I3C_1_SPD_DDRGL_CPU1_SCL")
		)
		(pad "2" smd rect
			(at -0.40005 0 270)
			(size 0.4572 0.508)
			(layers "B.Cu" "B.Mask" "B.Paste")
			(net "I3C_1_SPD_DDRGL_CPU1_R_SCL")
		)
	)
	(footprint ""
		(layer "B.Cu")
		(at 29.252164 -192.66027)
		(property "Reference" "C183"
			(at 0 0 0)
			(layer "B.SilkS")
			(hide yes)
			(effects
				(font
					(size 1.27 1.27)
				)
				(justify mirror)
			)
		)
		(property "Value" ""
			(at 0 0 0)
			(layer "B.Fab")
			(effects
				(font
					(size 1.27 1.27)
				)
				(justify mirror)
			)
		)
		(duplicate_pad_numbers_are_jumpers no)
		(fp_line
			(start -1.524 -0.762)
			(end -1.524 0.762)
			(stroke
				(width 0.1524)
				(type default)
			)
			(layer "B.SilkS")
		)
		(fp_line
			(start -1.524 0.762)
			(end 1.524 0.762)
			(stroke
				(width 0.1524)
				(type default)
			)
			(layer "B.SilkS")
		)
		(fp_line
			(start 1.524 -0.762)
			(end -1.524 -0.762)
			(stroke
				(width 0.1524)
				(type default)
			)
			(layer "B.SilkS")
		)
		(fp_line
			(start 1.524 0.762)
			(end 1.524 -0.762)
			(stroke
				(width 0.1524)
				(type default)
			)
			(layer "B.SilkS")
		)
		(fp_line
			(start -1.1049 -0.724916)
			(end 1.1049 -0.724916)
			(stroke
				(width 0.1)
				(type default)
			)
			(layer "B.Fab")
		)
		(fp_line
			(start -1.1049 0.724916)
			(end -1.1049 -0.724916)
			(stroke
				(width 0.1)
				(type default)
			)
			(layer "B.Fab")
		)
		(fp_line
			(start 1.1049 -0.724916)
			(end 1.1049 0.724916)
			(stroke
				(width 0.1)
				(type default)
			)
			(layer "B.Fab")
		)
		(fp_line
			(start 1.1049 0.724916)
			(end -1.1049 0.724916)
			(stroke
				(width 0.1)
				(type default)
			)
			(layer "B.Fab")
		)
		(pad "1" smd rect
			(at 0.889 0)
			(size 1.016 1.27)
			(layers "B.Cu" "B.Mask" "B.Paste")
			(net "P12V_MEM_CPU1")
		)
		(pad "2" smd rect
			(at -0.889 0)
			(size 1.016 1.27)
			(layers "B.Cu" "B.Mask" "B.Paste")
			(net "GND")
		)
	)
	(footprint ""
		(layer "B.Cu")
		(at 305.239928 -338.082128 -90)
		(property "Reference" "PC127_4"
			(at 0 0 90)
			(layer "B.SilkS")
			(hide yes)
			(effects
				(font
					(size 1.27 1.27)
				)
				(justify mirror)
			)
		)
		(property "Value" ""
			(at 0 0 90)
			(layer "B.Fab")
			(effects
				(font
					(size 1.27 1.27)
				)
				(justify mirror)
			)
		)
		(duplicate_pad_numbers_are_jumpers no)
		(fp_line
			(start -1.524 0.762)
			(end 1.524 0.762)
			(stroke
				(width 0.1524)
				(type default)
			)
			(layer "B.SilkS")
		)
		(fp_line
			(start 1.524 0.762)
			(end 1.524 -0.762)
			(stroke
				(width 0.1524)
				(type default)
			)
			(layer "B.SilkS")
		)
		(fp_line
			(start -1.524 -0.762)
			(end -1.524 0.762)
			(stroke
				(width 0.1524)
				(type default)
			)
			(layer "B.SilkS")
		)
		(fp_line
			(start 1.524 -0.762)
			(end -1.524 -0.762)
			(stroke
				(width 0.1524)
				(type default)
			)
			(layer "B.SilkS")
		)
		(fp_line
			(start -1.1049 0.724916)
			(end -1.1049 -0.724916)
			(stroke
				(width 0.1)
				(type default)
			)
			(layer "B.Fab")
		)
		(fp_line
			(start 1.1049 0.724916)
			(end -1.1049 0.724916)
			(stroke
				(width 0.1)
				(type default)
			)
			(layer "B.Fab")
		)
		(fp_line
			(start -1.1049 -0.724916)
			(end 1.1049 -0.724916)
			(stroke
				(width 0.1)
				(type default)
			)
			(layer "B.Fab")
		)
		(fp_line
			(start 1.1049 -0.724916)
			(end 1.1049 0.724916)
			(stroke
				(width 0.1)
				(type default)
			)
			(layer "B.Fab")
		)
		(pad "1" smd rect
			(at 0.889 0 270)
			(size 1.016 1.27)
			(layers "B.Cu" "B.Mask" "B.Paste")
			(net "PVDDCR_CPU1_P0")
		)
		(pad "2" smd rect
			(at -0.889 0 270)
			(size 1.016 1.27)
			(layers "B.Cu" "B.Mask" "B.Paste")
			(net "GND")
		)
	)
	(footprint ""
		(layer "B.Cu")
		(at 236.62513 -48.104044)
		(property "Reference" "C1283"
			(at 0 0 0)
			(layer "B.SilkS")
			(hide yes)
			(effects
				(font
					(size 1.27 1.27)
				)
				(justify mirror)
			)
		)
		(property "Value" ""
			(at 0 0 0)
			(layer "B.Fab")
			(effects
				(font
					(size 1.27 1.27)
				)
				(justify mirror)
			)
		)
		(duplicate_pad_numbers_are_jumpers no)
		(fp_line
			(start -0.7874 -0.4064)
			(end -0.7874 0.4064)
			(stroke
				(width 0.1524)
				(type default)
			)
			(layer "B.SilkS")
		)
		(fp_line
			(start -0.7874 0.4064)
			(end 0.7874 0.4064)
			(stroke
				(width 0.1524)
				(type default)
			)
			(layer "B.SilkS")
		)
		(fp_line
			(start 0.7874 -0.4064)
			(end -0.7874 -0.4064)
			(stroke
				(width 0.1524)
				(type default)
			)
			(layer "B.SilkS")
		)
		(fp_line
			(start 0.7874 0.4064)
			(end 0.7874 -0.4064)
			(stroke
				(width 0.1524)
				(type default)
			)
			(layer "B.SilkS")
		)
		(fp_line
			(start -0.67945 -0.3048)
			(end -0.67945 0.3048)
			(stroke
				(width 0.1)
				(type default)
			)
			(layer "B.Fab")
		)
		(fp_line
			(start -0.67945 0.3048)
			(end -0.120396 0.3048)
			(stroke
				(width 0.1)
				(type default)
			)
			(layer "B.Fab")
		)
		(fp_line
			(start -0.12065 -0.3048)
			(end -0.67945 -0.3048)
			(stroke
				(width 0.1)
				(type default)
			)
			(layer "B.Fab")
		)
		(fp_line
			(start -0.12065 -0.2794)
			(end -0.12065 -0.3048)
			(stroke
				(width 0.1)
				(type default)
			)
			(layer "B.Fab")
		)
		(fp_line
			(start -0.120396 0.2794)
			(end 0.12065 0.2794)
			(stroke
				(width 0.1)
				(type default)
			)
			(layer "B.Fab")
		)
		(fp_line
			(start -0.120396 0.3048)
			(end -0.120396 0.2794)
			(stroke
				(width 0.1)
				(type default)
			)
			(layer "B.Fab")
		)
		(fp_line
			(start 0.12065 -0.305054)
			(end 0.12065 -0.2794)
			(stroke
				(width 0.1)
				(type default)
			)
			(layer "B.Fab")
		)
		(fp_line
			(start 0.12065 -0.2794)
			(end -0.12065 -0.2794)
			(stroke
				(width 0.1)
				(type default)
			)
			(layer "B.Fab")
		)
		(fp_line
			(start 0.12065 0.2794)
			(end 0.12065 0.3048)
			(stroke
				(width 0.1)
				(type default)
			)
			(layer "B.Fab")
		)
		(fp_line
			(start 0.12065 0.3048)
			(end 0.67945 0.3048)
			(stroke
				(width 0.1)
				(type default)
			)
			(layer "B.Fab")
		)
		(fp_line
			(start 0.67945 -0.305054)
			(end 0.12065 -0.305054)
			(stroke
				(width 0.1)
				(type default)
			)
			(layer "B.Fab")
		)
		(fp_line
			(start 0.67945 0.3048)
			(end 0.67945 -0.305054)
			(stroke
				(width 0.1)
				(type default)
			)
			(layer "B.Fab")
		)
		(pad "1" smd circle
			(at 0.40005 0 180)
			(size 0 0)
			(layers "B.Cu" "B.Mask" "B.Paste")
			(net "P3V3_E1S_0")
		)
		(pad "2" smd circle
			(at -0.40005 0 180)
			(size 0 0)
			(layers "B.Cu" "B.Mask" "B.Paste")
			(net "GND")
		)
	)
	(footprint ""
		(layer "B.Cu")
		(at 177.264822 -10.1473 -90)
		(property "Reference" "R2421"
			(at 0 0 90)
			(layer "B.SilkS")
			(hide yes)
			(effects
				(font
					(size 1.27 1.27)
				)
				(justify mirror)
			)
		)
		(property "Value" ""
			(at 0 0 90)
			(layer "B.Fab")
			(effects
				(font
					(size 1.27 1.27)
				)
				(justify mirror)
			)
		)
		(duplicate_pad_numbers_are_jumpers no)
		(fp_line
			(start -0.7874 0.4064)
			(end 0.7874 0.4064)
			(stroke
				(width 0.1524)
				(type default)
			)
			(layer "B.SilkS")
		)
		(fp_line
			(start 0.7874 0.4064)
			(end 0.7874 -0.4064)
			(stroke
				(width 0.1524)
				(type default)
			)
			(layer "B.SilkS")
		)
		(fp_line
			(start -0.7874 -0.4064)
			(end -0.7874 0.4064)
			(stroke
				(width 0.1524)
				(type default)
			)
			(layer "B.SilkS")
		)
		(fp_line
			(start 0.7874 -0.4064)
			(end -0.7874 -0.4064)
			(stroke
				(width 0.1524)
				(type default)
			)
			(layer "B.SilkS")
		)
		(fp_line
			(start -0.67945 0.3048)
			(end -0.120396 0.3048)
			(stroke
				(width 0.1)
				(type default)
			)
			(layer "B.Fab")
		)
		(fp_line
			(start -0.120396 0.3048)
			(end -0.120396 0.2794)
			(stroke
				(width 0.1)
				(type default)
			)
			(layer "B.Fab")
		)
		(fp_line
			(start 0.12065 0.3048)
			(end 0.67945 0.3048)
			(stroke
				(width 0.1)
				(type default)
			)
			(layer "B.Fab")
		)
		(fp_line
			(start 0.67945 0.3048)
			(end 0.67945 -0.305054)
			(stroke
				(width 0.1)
				(type default)
			)
			(layer "B.Fab")
		)
		(fp_line
			(start -0.120396 0.2794)
			(end 0.12065 0.2794)
			(stroke
				(width 0.1)
				(type default)
			)
			(layer "B.Fab")
		)
		(fp_line
			(start 0.12065 0.2794)
			(end 0.12065 0.3048)
			(stroke
				(width 0.1)
				(type default)
			)
			(layer "B.Fab")
		)
		(fp_line
			(start -0.12065 -0.2794)
			(end -0.12065 -0.3048)
			(stroke
				(width 0.1)
				(type default)
			)
			(layer "B.Fab")
		)
		(fp_line
			(start 0.12065 -0.2794)
			(end -0.12065 -0.2794)
			(stroke
				(width 0.1)
				(type default)
			)
			(layer "B.Fab")
		)
		(fp_line
			(start -0.67945 -0.3048)
			(end -0.67945 0.3048)
			(stroke
				(width 0.1)
				(type default)
			)
			(layer "B.Fab")
		)
		(fp_line
			(start -0.12065 -0.3048)
			(end -0.67945 -0.3048)
			(stroke
				(width 0.1)
				(type default)
			)
			(layer "B.Fab")
		)
		(fp_line
			(start 0.12065 -0.305054)
			(end 0.12065 -0.2794)
			(stroke
				(width 0.1)
				(type default)
			)
			(layer "B.Fab")
		)
		(fp_line
			(start 0.67945 -0.305054)
			(end 0.12065 -0.305054)
			(stroke
				(width 0.1)
				(type default)
			)
			(layer "B.Fab")
		)
		(pad "1" smd circle
			(at 0.40005 0 90)
			(size 0 0)
			(layers "B.Cu" "B.Mask" "B.Paste")
			(net "SMB_VR_SENSOR_3V3AUX_SCL")
		)
		(pad "2" smd circle
			(at -0.40005 0 90)
			(size 0 0)
			(layers "B.Cu" "B.Mask" "B.Paste")
			(net "SMB_VR_3V3AUX_SCL_R0")
		)
	)
	(footprint ""
		(layer "B.Cu")
		(at 240.411 -234.061 90)
		(property "Reference" "R1160"
			(at 0 0 90)
			(layer "B.SilkS")
			(hide yes)
			(effects
				(font
					(size 1.27 1.27)
				)
				(justify mirror)
			)
		)
		(property "Value" ""
			(at 0 0 90)
			(layer "B.Fab")
			(effects
				(font
					(size 1.27 1.27)
				)
				(justify mirror)
			)
		)
		(duplicate_pad_numbers_are_jumpers no)
		(fp_line
			(start 0.7874 -0.4064)
			(end -0.7874 -0.4064)
			(stroke
				(width 0.1524)
				(type default)
			)
			(layer "B.SilkS")
		)
		(fp_line
			(start -0.7874 -0.4064)
			(end -0.7874 0.4064)
			(stroke
				(width 0.1524)
				(type default)
			)
			(layer "B.SilkS")
		)
		(fp_line
			(start 0.7874 0.4064)
			(end 0.7874 -0.4064)
			(stroke
				(width 0.1524)
				(type default)
			)
			(layer "B.SilkS")
		)
		(fp_line
			(start -0.7874 0.4064)
			(end 0.7874 0.4064)
			(stroke
				(width 0.1524)
				(type default)
			)
			(layer "B.SilkS")
		)
		(fp_line
			(start 0.67945 -0.305054)
			(end 0.12065 -0.305054)
			(stroke
				(width 0.1)
				(type default)
			)
			(layer "B.Fab")
		)
		(fp_line
			(start 0.12065 -0.305054)
			(end 0.12065 -0.2794)
			(stroke
				(width 0.1)
				(type default)
			)
			(layer "B.Fab")
		)
		(fp_line
			(start -0.12065 -0.3048)
			(end -0.67945 -0.3048)
			(stroke
				(width 0.1)
				(type default)
			)
			(layer "B.Fab")
		)
		(fp_line
			(start -0.67945 -0.3048)
			(end -0.67945 0.3048)
			(stroke
				(width 0.1)
				(type default)
			)
			(layer "B.Fab")
		)
		(fp_line
			(start 0.12065 -0.2794)
			(end -0.12065 -0.2794)
			(stroke
				(width 0.1)
				(type default)
			)
			(layer "B.Fab")
		)
		(fp_line
			(start -0.12065 -0.2794)
			(end -0.12065 -0.3048)
			(stroke
				(width 0.1)
				(type default)
			)
			(layer "B.Fab")
		)
		(fp_line
			(start 0.12065 0.2794)
			(end 0.12065 0.3048)
			(stroke
				(width 0.1)
				(type default)
			)
			(layer "B.Fab")
		)
		(fp_line
			(start -0.120396 0.2794)
			(end 0.12065 0.2794)
			(stroke
				(width 0.1)
				(type default)
			)
			(layer "B.Fab")
		)
		(fp_line
			(start 0.67945 0.3048)
			(end 0.67945 -0.305054)
			(stroke
				(width 0.1)
				(type default)
			)
			(layer "B.Fab")
		)
		(fp_line
			(start 0.12065 0.3048)
			(end 0.67945 0.3048)
			(stroke
				(width 0.1)
				(type default)
			)
			(layer "B.Fab")
		)
		(fp_line
			(start -0.120396 0.3048)
			(end -0.120396 0.2794)
			(stroke
				(width 0.1)
				(type default)
			)
			(layer "B.Fab")
		)
		(fp_line
			(start -0.67945 0.3048)
			(end -0.120396 0.3048)
			(stroke
				(width 0.1)
				(type default)
			)
			(layer "B.Fab")
		)
		(pad "1" smd circle
			(at 0.40005 0 270)
			(size 0 0)
			(layers "B.Cu" "B.Mask" "B.Paste")
			(net "SMB_CPU0_SEC_R_SDA")
		)
		(pad "2" smd circle
			(at -0.40005 0 270)
			(size 0 0)
			(layers "B.Cu" "B.Mask" "B.Paste")
			(net "SMB_CPU0_SEC_SDA")
		)
	)
	(footprint ""
		(layer "B.Cu")
		(at 381.552958 -208.530952 -90)
		(property "Reference" "R399"
			(at 0 0 90)
			(layer "B.SilkS")
			(hide yes)
			(effects
				(font
					(size 1.27 1.27)
				)
				(justify mirror)
			)
		)
		(property "Value" ""
			(at 0 0 90)
			(layer "B.Fab")
			(effects
				(font
					(size 1.27 1.27)
				)
				(justify mirror)
			)
		)
		(duplicate_pad_numbers_are_jumpers no)
		(fp_line
			(start -0.7874 0.4064)
			(end 0.7874 0.4064)
			(stroke
				(width 0.1524)
				(type default)
			)
			(layer "B.SilkS")
		)
		(fp_line
			(start 0.7874 0.4064)
			(end 0.7874 -0.4064)
			(stroke
				(width 0.1524)
				(type default)
			)
			(layer "B.SilkS")
		)
		(fp_line
			(start -0.7874 -0.4064)
			(end -0.7874 0.4064)
			(stroke
				(width 0.1524)
				(type default)
			)
			(layer "B.SilkS")
		)
		(fp_line
			(start 0.7874 -0.4064)
			(end -0.7874 -0.4064)
			(stroke
				(width 0.1524)
				(type default)
			)
			(layer "B.SilkS")
		)
		(fp_line
			(start -0.67945 0.3048)
			(end -0.120396 0.3048)
			(stroke
				(width 0.1)
				(type default)
			)
			(layer "B.Fab")
		)
		(fp_line
			(start -0.120396 0.3048)
			(end -0.120396 0.2794)
			(stroke
				(width 0.1)
				(type default)
			)
			(layer "B.Fab")
		)
		(fp_line
			(start 0.12065 0.3048)
			(end 0.67945 0.3048)
			(stroke
				(width 0.1)
				(type default)
			)
			(layer "B.Fab")
		)
		(fp_line
			(start 0.67945 0.3048)
			(end 0.67945 -0.305054)
			(stroke
				(width 0.1)
				(type default)
			)
			(layer "B.Fab")
		)
		(fp_line
			(start -0.120396 0.2794)
			(end 0.12065 0.2794)
			(stroke
				(width 0.1)
				(type default)
			)
			(layer "B.Fab")
		)
		(fp_line
			(start 0.12065 0.2794)
			(end 0.12065 0.3048)
			(stroke
				(width 0.1)
				(type default)
			)
			(layer "B.Fab")
		)
		(fp_line
			(start -0.12065 -0.2794)
			(end -0.12065 -0.3048)
			(stroke
				(width 0.1)
				(type default)
			)
			(layer "B.Fab")
		)
		(fp_line
			(start 0.12065 -0.2794)
			(end -0.12065 -0.2794)
			(stroke
				(width 0.1)
				(type default)
			)
			(layer "B.Fab")
		)
		(fp_line
			(start -0.67945 -0.3048)
			(end -0.67945 0.3048)
			(stroke
				(width 0.1)
				(type default)
			)
			(layer "B.Fab")
		)
		(fp_line
			(start -0.12065 -0.3048)
			(end -0.67945 -0.3048)
			(stroke
				(width 0.1)
				(type default)
			)
			(layer "B.Fab")
		)
		(fp_line
			(start 0.12065 -0.305054)
			(end 0.12065 -0.2794)
			(stroke
				(width 0.1)
				(type default)
			)
			(layer "B.Fab")
		)
		(fp_line
			(start 0.67945 -0.305054)
			(end 0.12065 -0.305054)
			(stroke
				(width 0.1)
				(type default)
			)
			(layer "B.Fab")
		)
		(pad "1" smd circle
			(at 0.40005 0 90)
			(size 0 0)
			(layers "B.Cu" "B.Mask" "B.Paste")
			(net "PVDD18_S5_P0")
		)
		(pad "2" smd circle
			(at -0.40005 0 90)
			(size 0 0)
			(layers "B.Cu" "B.Mask" "B.Paste")
			(net "JTAG_CPU0_TDI")
		)
	)
	(footprint ""
		(layer "B.Cu")
		(at 46.308518 -350.660716 -90)
		(property "Reference" "PC446_2"
			(at 0 0 90)
			(layer "B.SilkS")
			(hide yes)
			(effects
				(font
					(size 1.27 1.27)
				)
				(justify mirror)
			)
		)
		(property "Value" ""
			(at 0 0 90)
			(layer "B.Fab")
			(effects
				(font
					(size 1.27 1.27)
				)
				(justify mirror)
			)
		)
		(duplicate_pad_numbers_are_jumpers no)
		(fp_line
			(start -1.524 0.762)
			(end 1.524 0.762)
			(stroke
				(width 0.1524)
				(type default)
			)
			(layer "B.SilkS")
		)
		(fp_line
			(start 1.524 0.762)
			(end 1.524 -0.762)
			(stroke
				(width 0.1524)
				(type default)
			)
			(layer "B.SilkS")
		)
		(fp_line
			(start -1.524 -0.762)
			(end -1.524 0.762)
			(stroke
				(width 0.1524)
				(type default)
			)
			(layer "B.SilkS")
		)
		(fp_line
			(start 1.524 -0.762)
			(end -1.524 -0.762)
			(stroke
				(width 0.1524)
				(type default)
			)
			(layer "B.SilkS")
		)
		(fp_line
			(start -1.1049 0.724916)
			(end -1.1049 -0.724916)
			(stroke
				(width 0.1)
				(type default)
			)
			(layer "B.Fab")
		)
		(fp_line
			(start 1.1049 0.724916)
			(end -1.1049 0.724916)
			(stroke
				(width 0.1)
				(type default)
			)
			(layer "B.Fab")
		)
		(fp_line
			(start -1.1049 -0.724916)
			(end 1.1049 -0.724916)
			(stroke
				(width 0.1)
				(type default)
			)
			(layer "B.Fab")
		)
		(fp_line
			(start 1.1049 -0.724916)
			(end 1.1049 0.724916)
			(stroke
				(width 0.1)
				(type default)
			)
			(layer "B.Fab")
		)
		(pad "1" smd rect
			(at 0.889 0 270)
			(size 1.016 1.27)
			(layers "B.Cu" "B.Mask" "B.Paste")
			(net "SW_P12V_AUX_PVDDIO_P1_FLT")
		)
		(pad "2" smd rect
			(at -0.889 0 270)
			(size 1.016 1.27)
			(layers "B.Cu" "B.Mask" "B.Paste")
			(net "GND")
		)
	)
	(footprint ""
		(layer "B.Cu")
		(at 315.518292 -396.393162 -90)
		(property "Reference" "C524"
			(at 0 0 90)
			(layer "B.SilkS")
			(hide yes)
			(effects
				(font
					(size 1.27 1.27)
				)
				(justify mirror)
			)
		)
		(property "Value" ""
			(at 0 0 90)
			(layer "B.Fab")
			(effects
				(font
					(size 1.27 1.27)
				)
				(justify mirror)
			)
		)
		(duplicate_pad_numbers_are_jumpers no)
		(fp_line
			(start -0.299974 0.150114)
			(end 0.299974 0.150114)
			(stroke
				(width 0.1)
				(type default)
			)
			(layer "B.Fab")
		)
		(fp_line
			(start 0.299974 0.150114)
			(end 0.299974 -0.150114)
			(stroke
				(width 0.1)
				(type default)
			)
			(layer "B.Fab")
		)
		(fp_line
			(start -0.299974 -0.150114)
			(end -0.299974 0.150114)
			(stroke
				(width 0.1)
				(type default)
			)
			(layer "B.Fab")
		)
		(fp_line
			(start 0.299974 -0.150114)
			(end -0.299974 -0.150114)
			(stroke
				(width 0.1)
				(type default)
			)
			(layer "B.Fab")
		)
		(pad "1" smd rect
			(at 0.2667 0 90)
			(size 0.3048 0.381)
			(layers "B.Cu" "B.Mask" "B.Paste")
			(net "P0V9_CPU0_RT_2D")
		)
		(pad "2" smd rect
			(at -0.2667 0 90)
			(size 0.3048 0.381)
			(layers "B.Cu" "B.Mask" "B.Paste")
			(net "GND")
		)
	)
	(footprint ""
		(layer "B.Cu")
		(at 97.919032 -390.560052 90)
		(property "Reference" "C354"
			(at 0 0 90)
			(layer "B.SilkS")
			(hide yes)
			(effects
				(font
					(size 1.27 1.27)
				)
				(justify mirror)
			)
		)
		(property "Value" ""
			(at 0 0 90)
			(layer "B.Fab")
			(effects
				(font
					(size 1.27 1.27)
				)
				(justify mirror)
			)
		)
		(duplicate_pad_numbers_are_jumpers no)
		(fp_line
			(start 0.7874 -0.4064)
			(end -0.7874 -0.4064)
			(stroke
				(width 0.1524)
				(type default)
			)
			(layer "B.SilkS")
		)
		(fp_line
			(start -0.7874 -0.4064)
			(end -0.7874 0.4064)
			(stroke
				(width 0.1524)
				(type default)
			)
			(layer "B.SilkS")
		)
		(fp_line
			(start 0.7874 0.4064)
			(end 0.7874 -0.4064)
			(stroke
				(width 0.1524)
				(type default)
			)
			(layer "B.SilkS")
		)
		(fp_line
			(start -0.7874 0.4064)
			(end 0.7874 0.4064)
			(stroke
				(width 0.1524)
				(type default)
			)
			(layer "B.SilkS")
		)
		(fp_line
			(start 0.67945 -0.305054)
			(end 0.12065 -0.305054)
			(stroke
				(width 0.1)
				(type default)
			)
			(layer "B.Fab")
		)
		(fp_line
			(start 0.12065 -0.305054)
			(end 0.12065 -0.2794)
			(stroke
				(width 0.1)
				(type default)
			)
			(layer "B.Fab")
		)
		(fp_line
			(start -0.12065 -0.3048)
			(end -0.67945 -0.3048)
			(stroke
				(width 0.1)
				(type default)
			)
			(layer "B.Fab")
		)
		(fp_line
			(start -0.67945 -0.3048)
			(end -0.67945 0.3048)
			(stroke
				(width 0.1)
				(type default)
			)
			(layer "B.Fab")
		)
		(fp_line
			(start 0.12065 -0.2794)
			(end -0.12065 -0.2794)
			(stroke
				(width 0.1)
				(type default)
			)
			(layer "B.Fab")
		)
		(fp_line
			(start -0.12065 -0.2794)
			(end -0.12065 -0.3048)
			(stroke
				(width 0.1)
				(type default)
			)
			(layer "B.Fab")
		)
		(fp_line
			(start 0.12065 0.2794)
			(end 0.12065 0.3048)
			(stroke
				(width 0.1)
				(type default)
			)
			(layer "B.Fab")
		)
		(fp_line
			(start -0.120396 0.2794)
			(end 0.12065 0.2794)
			(stroke
				(width 0.1)
				(type default)
			)
			(layer "B.Fab")
		)
		(fp_line
			(start 0.67945 0.3048)
			(end 0.67945 -0.305054)
			(stroke
				(width 0.1)
				(type default)
			)
			(layer "B.Fab")
		)
		(fp_line
			(start 0.12065 0.3048)
			(end 0.67945 0.3048)
			(stroke
				(width 0.1)
				(type default)
			)
			(layer "B.Fab")
		)
		(fp_line
			(start -0.120396 0.3048)
			(end -0.120396 0.2794)
			(stroke
				(width 0.1)
				(type default)
			)
			(layer "B.Fab")
		)
		(fp_line
			(start -0.67945 0.3048)
			(end -0.120396 0.3048)
			(stroke
				(width 0.1)
				(type default)
			)
			(layer "B.Fab")
		)
		(pad "1" smd circle
			(at 0.40005 0 270)
			(size 0 0)
			(layers "B.Cu" "B.Mask" "B.Paste")
			(net "P0V9_CPU1_RT1_2A")
		)
		(pad "2" smd circle
			(at -0.40005 0 270)
			(size 0 0)
			(layers "B.Cu" "B.Mask" "B.Paste")
			(net "GND")
		)
	)
	(footprint ""
		(layer "B.Cu")
		(at 322.878958 -196.678296)
		(property "Reference" "R410"
			(at 0 0 0)
			(layer "B.SilkS")
			(hide yes)
			(effects
				(font
					(size 1.27 1.27)
				)
				(justify mirror)
			)
		)
		(property "Value" ""
			(at 0 0 0)
			(layer "B.Fab")
			(effects
				(font
					(size 1.27 1.27)
				)
				(justify mirror)
			)
		)
		(duplicate_pad_numbers_are_jumpers no)
		(fp_line
			(start -0.7874 -0.4064)
			(end -0.7874 0.4064)
			(stroke
				(width 0.1524)
				(type default)
			)
			(layer "B.SilkS")
		)
		(fp_line
			(start -0.7874 0.4064)
			(end 0.7874 0.4064)
			(stroke
				(width 0.1524)
				(type default)
			)
			(layer "B.SilkS")
		)
		(fp_line
			(start 0.7874 -0.4064)
			(end -0.7874 -0.4064)
			(stroke
				(width 0.1524)
				(type default)
			)
			(layer "B.SilkS")
		)
		(fp_line
			(start 0.7874 0.4064)
			(end 0.7874 -0.4064)
			(stroke
				(width 0.1524)
				(type default)
			)
			(layer "B.SilkS")
		)
		(fp_line
			(start -0.67945 -0.3048)
			(end -0.67945 0.3048)
			(stroke
				(width 0.1)
				(type default)
			)
			(layer "B.Fab")
		)
		(fp_line
			(start -0.67945 0.3048)
			(end -0.120396 0.3048)
			(stroke
				(width 0.1)
				(type default)
			)
			(layer "B.Fab")
		)
		(fp_line
			(start -0.12065 -0.3048)
			(end -0.67945 -0.3048)
			(stroke
				(width 0.1)
				(type default)
			)
			(layer "B.Fab")
		)
		(fp_line
			(start -0.12065 -0.2794)
			(end -0.12065 -0.3048)
			(stroke
				(width 0.1)
				(type default)
			)
			(layer "B.Fab")
		)
		(fp_line
			(start -0.120396 0.2794)
			(end 0.12065 0.2794)
			(stroke
				(width 0.1)
				(type default)
			)
			(layer "B.Fab")
		)
		(fp_line
			(start -0.120396 0.3048)
			(end -0.120396 0.2794)
			(stroke
				(width 0.1)
				(type default)
			)
			(layer "B.Fab")
		)
		(fp_line
			(start 0.12065 -0.305054)
			(end 0.12065 -0.2794)
			(stroke
				(width 0.1)
				(type default)
			)
			(layer "B.Fab")
		)
		(fp_line
			(start 0.12065 -0.2794)
			(end -0.12065 -0.2794)
			(stroke
				(width 0.1)
				(type default)
			)
			(layer "B.Fab")
		)
		(fp_line
			(start 0.12065 0.2794)
			(end 0.12065 0.3048)
			(stroke
				(width 0.1)
				(type default)
			)
			(layer "B.Fab")
		)
		(fp_line
			(start 0.12065 0.3048)
			(end 0.67945 0.3048)
			(stroke
				(width 0.1)
				(type default)
			)
			(layer "B.Fab")
		)
		(fp_line
			(start 0.67945 -0.305054)
			(end 0.12065 -0.305054)
			(stroke
				(width 0.1)
				(type default)
			)
			(layer "B.Fab")
		)
		(fp_line
			(start 0.67945 0.3048)
			(end 0.67945 -0.305054)
			(stroke
				(width 0.1)
				(type default)
			)
			(layer "B.Fab")
		)
		(pad "1" smd circle
			(at 0.40005 0 180)
			(size 0 0)
			(layers "B.Cu" "B.Mask" "B.Paste")
			(net "CPU0_BP2")
		)
		(pad "2" smd circle
			(at -0.40005 0 180)
			(size 0 0)
			(layers "B.Cu" "B.Mask" "B.Paste")
			(net "PVDD18_S5_P0")
		)
	)
	(footprint ""
		(layer "B.Cu")
		(at 404.070058 -319.748916 -90)
		(property "Reference" "R430"
			(at 0 0 90)
			(layer "B.SilkS")
			(hide yes)
			(effects
				(font
					(size 1.27 1.27)
				)
				(justify mirror)
			)
		)
		(property "Value" ""
			(at 0 0 90)
			(layer "B.Fab")
			(effects
				(font
					(size 1.27 1.27)
				)
				(justify mirror)
			)
		)
		(duplicate_pad_numbers_are_jumpers no)
		(fp_line
			(start -0.7874 0.4064)
			(end 0.7874 0.4064)
			(stroke
				(width 0.1524)
				(type default)
			)
			(layer "B.SilkS")
		)
		(fp_line
			(start 0.7874 0.4064)
			(end 0.7874 -0.4064)
			(stroke
				(width 0.1524)
				(type default)
			)
			(layer "B.SilkS")
		)
		(fp_line
			(start -0.7874 -0.4064)
			(end -0.7874 0.4064)
			(stroke
				(width 0.1524)
				(type default)
			)
			(layer "B.SilkS")
		)
		(fp_line
			(start 0.7874 -0.4064)
			(end -0.7874 -0.4064)
			(stroke
				(width 0.1524)
				(type default)
			)
			(layer "B.SilkS")
		)
		(fp_line
			(start -0.67945 0.3048)
			(end -0.120396 0.3048)
			(stroke
				(width 0.1)
				(type default)
			)
			(layer "B.Fab")
		)
		(fp_line
			(start -0.120396 0.3048)
			(end -0.120396 0.2794)
			(stroke
				(width 0.1)
				(type default)
			)
			(layer "B.Fab")
		)
		(fp_line
			(start 0.12065 0.3048)
			(end 0.67945 0.3048)
			(stroke
				(width 0.1)
				(type default)
			)
			(layer "B.Fab")
		)
		(fp_line
			(start 0.67945 0.3048)
			(end 0.67945 -0.305054)
			(stroke
				(width 0.1)
				(type default)
			)
			(layer "B.Fab")
		)
		(fp_line
			(start -0.120396 0.2794)
			(end 0.12065 0.2794)
			(stroke
				(width 0.1)
				(type default)
			)
			(layer "B.Fab")
		)
		(fp_line
			(start 0.12065 0.2794)
			(end 0.12065 0.3048)
			(stroke
				(width 0.1)
				(type default)
			)
			(layer "B.Fab")
		)
		(fp_line
			(start -0.12065 -0.2794)
			(end -0.12065 -0.3048)
			(stroke
				(width 0.1)
				(type default)
			)
			(layer "B.Fab")
		)
		(fp_line
			(start 0.12065 -0.2794)
			(end -0.12065 -0.2794)
			(stroke
				(width 0.1)
				(type default)
			)
			(layer "B.Fab")
		)
		(fp_line
			(start -0.67945 -0.3048)
			(end -0.67945 0.3048)
			(stroke
				(width 0.1)
				(type default)
			)
			(layer "B.Fab")
		)
		(fp_line
			(start -0.12065 -0.3048)
			(end -0.67945 -0.3048)
			(stroke
				(width 0.1)
				(type default)
			)
			(layer "B.Fab")
		)
		(fp_line
			(start 0.12065 -0.305054)
			(end 0.12065 -0.2794)
			(stroke
				(width 0.1)
				(type default)
			)
			(layer "B.Fab")
		)
		(fp_line
			(start 0.67945 -0.305054)
			(end 0.12065 -0.305054)
			(stroke
				(width 0.1)
				(type default)
			)
			(layer "B.Fab")
		)
		(pad "1" smd circle
			(at 0.40005 0 90)
			(size 0 0)
			(layers "B.Cu" "B.Mask" "B.Paste")
			(net "SMB_CPU0_4_R_SCL")
		)
		(pad "2" smd circle
			(at -0.40005 0 90)
			(size 0 0)
			(layers "B.Cu" "B.Mask" "B.Paste")
			(net "SMB_CPU0_4_SCL")
		)
	)
	(footprint ""
		(layer "B.Cu")
		(at 397.788892 -202.324208)
		(property "Reference" "R454"
			(at 0 0 0)
			(layer "B.SilkS")
			(hide yes)
			(effects
				(font
					(size 1.27 1.27)
				)
				(justify mirror)
			)
		)
		(property "Value" ""
			(at 0 0 0)
			(layer "B.Fab")
			(effects
				(font
					(size 1.27 1.27)
				)
				(justify mirror)
			)
		)
		(duplicate_pad_numbers_are_jumpers no)
		(fp_line
			(start -0.7874 -0.4064)
			(end -0.7874 0.4064)
			(stroke
				(width 0.1524)
				(type default)
			)
			(layer "B.SilkS")
		)
		(fp_line
			(start -0.7874 0.4064)
			(end 0.7874 0.4064)
			(stroke
				(width 0.1524)
				(type default)
			)
			(layer "B.SilkS")
		)
		(fp_line
			(start 0.7874 -0.4064)
			(end -0.7874 -0.4064)
			(stroke
				(width 0.1524)
				(type default)
			)
			(layer "B.SilkS")
		)
		(fp_line
			(start 0.7874 0.4064)
			(end 0.7874 -0.4064)
			(stroke
				(width 0.1524)
				(type default)
			)
			(layer "B.SilkS")
		)
		(fp_line
			(start -0.67945 -0.3048)
			(end -0.67945 0.3048)
			(stroke
				(width 0.1)
				(type default)
			)
			(layer "B.Fab")
		)
		(fp_line
			(start -0.67945 0.3048)
			(end -0.120396 0.3048)
			(stroke
				(width 0.1)
				(type default)
			)
			(layer "B.Fab")
		)
		(fp_line
			(start -0.12065 -0.3048)
			(end -0.67945 -0.3048)
			(stroke
				(width 0.1)
				(type default)
			)
			(layer "B.Fab")
		)
		(fp_line
			(start -0.12065 -0.2794)
			(end -0.12065 -0.3048)
			(stroke
				(width 0.1)
				(type default)
			)
			(layer "B.Fab")
		)
		(fp_line
			(start -0.120396 0.2794)
			(end 0.12065 0.2794)
			(stroke
				(width 0.1)
				(type default)
			)
			(layer "B.Fab")
		)
		(fp_line
			(start -0.120396 0.3048)
			(end -0.120396 0.2794)
			(stroke
				(width 0.1)
				(type default)
			)
			(layer "B.Fab")
		)
		(fp_line
			(start 0.12065 -0.305054)
			(end 0.12065 -0.2794)
			(stroke
				(width 0.1)
				(type default)
			)
			(layer "B.Fab")
		)
		(fp_line
			(start 0.12065 -0.2794)
			(end -0.12065 -0.2794)
			(stroke
				(width 0.1)
				(type default)
			)
			(layer "B.Fab")
		)
		(fp_line
			(start 0.12065 0.2794)
			(end 0.12065 0.3048)
			(stroke
				(width 0.1)
				(type default)
			)
			(layer "B.Fab")
		)
		(fp_line
			(start 0.12065 0.3048)
			(end 0.67945 0.3048)
			(stroke
				(width 0.1)
				(type default)
			)
			(layer "B.Fab")
		)
		(fp_line
			(start 0.67945 -0.305054)
			(end 0.12065 -0.305054)
			(stroke
				(width 0.1)
				(type default)
			)
			(layer "B.Fab")
		)
		(fp_line
			(start 0.67945 0.3048)
			(end 0.67945 -0.305054)
			(stroke
				(width 0.1)
				(type default)
			)
			(layer "B.Fab")
		)
		(pad "1" smd circle
			(at 0.40005 0 180)
			(size 0 0)
			(layers "B.Cu" "B.Mask" "B.Paste")
			(net "PVDD18_S5_P0")
		)
		(pad "2" smd circle
			(at -0.40005 0 180)
			(size 0 0)
			(layers "B.Cu" "B.Mask" "B.Paste")
			(net "SCM_USB_OC_BUF_N")
		)
	)
	(footprint ""
		(layer "B.Cu")
		(at 46.359318 -430.165002 90)
		(property "Reference" "R3474"
			(at 0 0 90)
			(layer "B.SilkS")
			(hide yes)
			(effects
				(font
					(size 1.27 1.27)
				)
				(justify mirror)
			)
		)
		(property "Value" ""
			(at 0 0 90)
			(layer "B.Fab")
			(effects
				(font
					(size 1.27 1.27)
				)
				(justify mirror)
			)
		)
		(duplicate_pad_numbers_are_jumpers no)
		(fp_line
			(start 0.7874 -0.4064)
			(end -0.7874 -0.4064)
			(stroke
				(width 0.1524)
				(type default)
			)
			(layer "B.SilkS")
		)
		(fp_line
			(start -0.7874 -0.4064)
			(end -0.7874 0.4064)
			(stroke
				(width 0.1524)
				(type default)
			)
			(layer "B.SilkS")
		)
		(fp_line
			(start 0.7874 0.4064)
			(end 0.7874 -0.4064)
			(stroke
				(width 0.1524)
				(type default)
			)
			(layer "B.SilkS")
		)
		(fp_line
			(start -0.7874 0.4064)
			(end 0.7874 0.4064)
			(stroke
				(width 0.1524)
				(type default)
			)
			(layer "B.SilkS")
		)
		(fp_line
			(start 0.67945 -0.305054)
			(end 0.12065 -0.305054)
			(stroke
				(width 0.1)
				(type default)
			)
			(layer "B.Fab")
		)
		(fp_line
			(start 0.12065 -0.305054)
			(end 0.12065 -0.2794)
			(stroke
				(width 0.1)
				(type default)
			)
			(layer "B.Fab")
		)
		(fp_line
			(start -0.12065 -0.3048)
			(end -0.67945 -0.3048)
			(stroke
				(width 0.1)
				(type default)
			)
			(layer "B.Fab")
		)
		(fp_line
			(start -0.67945 -0.3048)
			(end -0.67945 0.3048)
			(stroke
				(width 0.1)
				(type default)
			)
			(layer "B.Fab")
		)
		(fp_line
			(start 0.12065 -0.2794)
			(end -0.12065 -0.2794)
			(stroke
				(width 0.1)
				(type default)
			)
			(layer "B.Fab")
		)
		(fp_line
			(start -0.12065 -0.2794)
			(end -0.12065 -0.3048)
			(stroke
				(width 0.1)
				(type default)
			)
			(layer "B.Fab")
		)
		(fp_line
			(start 0.12065 0.2794)
			(end 0.12065 0.3048)
			(stroke
				(width 0.1)
				(type default)
			)
			(layer "B.Fab")
		)
		(fp_line
			(start -0.120396 0.2794)
			(end 0.12065 0.2794)
			(stroke
				(width 0.1)
				(type default)
			)
			(layer "B.Fab")
		)
		(fp_line
			(start 0.67945 0.3048)
			(end 0.67945 -0.305054)
			(stroke
				(width 0.1)
				(type default)
			)
			(layer "B.Fab")
		)
		(fp_line
			(start 0.12065 0.3048)
			(end 0.67945 0.3048)
			(stroke
				(width 0.1)
				(type default)
			)
			(layer "B.Fab")
		)
		(fp_line
			(start -0.120396 0.3048)
			(end -0.120396 0.2794)
			(stroke
				(width 0.1)
				(type default)
			)
			(layer "B.Fab")
		)
		(fp_line
			(start -0.67945 0.3048)
			(end -0.120396 0.3048)
			(stroke
				(width 0.1)
				(type default)
			)
			(layer "B.Fab")
		)
		(pad "1" smd circle
			(at 0.40005 0 270)
			(size 0 0)
			(layers "B.Cu" "B.Mask" "B.Paste")
			(net "P3V3_AUX")
		)
		(pad "2" smd circle
			(at -0.40005 0 270)
			(size 0 0)
			(layers "B.Cu" "B.Mask" "B.Paste")
			(net "GPU_PRSNT")
		)
	)
	(footprint ""
		(layer "B.Cu")
		(at 151.884634 -316.353952 90)
		(property "Reference" "C238"
			(at 0 0 90)
			(layer "B.SilkS")
			(hide yes)
			(effects
				(font
					(size 1.27 1.27)
				)
				(justify mirror)
			)
		)
		(property "Value" ""
			(at 0 0 90)
			(layer "B.Fab")
			(effects
				(font
					(size 1.27 1.27)
				)
				(justify mirror)
			)
		)
		(duplicate_pad_numbers_are_jumpers no)
		(fp_line
			(start 0.7874 -0.4064)
			(end -0.7874 -0.4064)
			(stroke
				(width 0.1524)
				(type default)
			)
			(layer "B.SilkS")
		)
		(fp_line
			(start -0.7874 -0.4064)
			(end -0.7874 0.4064)
			(stroke
				(width 0.1524)
				(type default)
			)
			(layer "B.SilkS")
		)
		(fp_line
			(start 0.7874 0.4064)
			(end 0.7874 -0.4064)
			(stroke
				(width 0.1524)
				(type default)
			)
			(layer "B.SilkS")
		)
		(fp_line
			(start -0.7874 0.4064)
			(end 0.7874 0.4064)
			(stroke
				(width 0.1524)
				(type default)
			)
			(layer "B.SilkS")
		)
		(fp_line
			(start 0.67945 -0.305054)
			(end 0.12065 -0.305054)
			(stroke
				(width 0.1)
				(type default)
			)
			(layer "B.Fab")
		)
		(fp_line
			(start 0.12065 -0.305054)
			(end 0.12065 -0.2794)
			(stroke
				(width 0.1)
				(type default)
			)
			(layer "B.Fab")
		)
		(fp_line
			(start -0.12065 -0.3048)
			(end -0.67945 -0.3048)
			(stroke
				(width 0.1)
				(type default)
			)
			(layer "B.Fab")
		)
		(fp_line
			(start -0.67945 -0.3048)
			(end -0.67945 0.3048)
			(stroke
				(width 0.1)
				(type default)
			)
			(layer "B.Fab")
		)
		(fp_line
			(start 0.12065 -0.2794)
			(end -0.12065 -0.2794)
			(stroke
				(width 0.1)
				(type default)
			)
			(layer "B.Fab")
		)
		(fp_line
			(start -0.12065 -0.2794)
			(end -0.12065 -0.3048)
			(stroke
				(width 0.1)
				(type default)
			)
			(layer "B.Fab")
		)
		(fp_line
			(start 0.12065 0.2794)
			(end 0.12065 0.3048)
			(stroke
				(width 0.1)
				(type default)
			)
			(layer "B.Fab")
		)
		(fp_line
			(start -0.120396 0.2794)
			(end 0.12065 0.2794)
			(stroke
				(width 0.1)
				(type default)
			)
			(layer "B.Fab")
		)
		(fp_line
			(start 0.67945 0.3048)
			(end 0.67945 -0.305054)
			(stroke
				(width 0.1)
				(type default)
			)
			(layer "B.Fab")
		)
		(fp_line
			(start 0.12065 0.3048)
			(end 0.67945 0.3048)
			(stroke
				(width 0.1)
				(type default)
			)
			(layer "B.Fab")
		)
		(fp_line
			(start -0.120396 0.3048)
			(end -0.120396 0.2794)
			(stroke
				(width 0.1)
				(type default)
			)
			(layer "B.Fab")
		)
		(fp_line
			(start -0.67945 0.3048)
			(end -0.120396 0.3048)
			(stroke
				(width 0.1)
				(type default)
			)
			(layer "B.Fab")
		)
		(pad "1" smd circle
			(at 0.40005 0 270)
			(size 0 0)
			(layers "B.Cu" "B.Mask" "B.Paste")
			(net "XTAL_CPU1_R_X32K_X1")
		)
		(pad "2" smd circle
			(at -0.40005 0 270)
			(size 0 0)
			(layers "B.Cu" "B.Mask" "B.Paste")
			(net "GND")
		)
	)
	(footprint ""
		(layer "B.Cu")
		(at 47.417228 -337.989672 -90)
		(property "Reference" "PC459_1"
			(at 0 0 90)
			(layer "B.SilkS")
			(hide yes)
			(effects
				(font
					(size 1.27 1.27)
				)
				(justify mirror)
			)
		)
		(property "Value" ""
			(at 0 0 90)
			(layer "B.Fab")
			(effects
				(font
					(size 1.27 1.27)
				)
				(justify mirror)
			)
		)
		(duplicate_pad_numbers_are_jumpers no)
		(fp_line
			(start -1.524 0.762)
			(end 1.524 0.762)
			(stroke
				(width 0.1524)
				(type default)
			)
			(layer "B.SilkS")
		)
		(fp_line
			(start 1.524 0.762)
			(end 1.524 -0.762)
			(stroke
				(width 0.1524)
				(type default)
			)
			(layer "B.SilkS")
		)
		(fp_line
			(start -1.524 -0.762)
			(end -1.524 0.762)
			(stroke
				(width 0.1524)
				(type default)
			)
			(layer "B.SilkS")
		)
		(fp_line
			(start 1.524 -0.762)
			(end -1.524 -0.762)
			(stroke
				(width 0.1524)
				(type default)
			)
			(layer "B.SilkS")
		)
		(fp_line
			(start -1.1049 0.724916)
			(end -1.1049 -0.724916)
			(stroke
				(width 0.1)
				(type default)
			)
			(layer "B.Fab")
		)
		(fp_line
			(start 1.1049 0.724916)
			(end -1.1049 0.724916)
			(stroke
				(width 0.1)
				(type default)
			)
			(layer "B.Fab")
		)
		(fp_line
			(start -1.1049 -0.724916)
			(end 1.1049 -0.724916)
			(stroke
				(width 0.1)
				(type default)
			)
			(layer "B.Fab")
		)
		(fp_line
			(start 1.1049 -0.724916)
			(end 1.1049 0.724916)
			(stroke
				(width 0.1)
				(type default)
			)
			(layer "B.Fab")
		)
		(pad "1" smd rect
			(at 0.889 0 270)
			(size 1.016 1.27)
			(layers "B.Cu" "B.Mask" "B.Paste")
			(net "PVDDIO_P1")
		)
		(pad "2" smd rect
			(at -0.889 0 270)
			(size 1.016 1.27)
			(layers "B.Cu" "B.Mask" "B.Paste")
			(net "GND")
		)
	)
	(footprint ""
		(layer "B.Cu")
		(at 184.687972 -428.15764)
		(property "Reference" "R8110"
			(at 0 0 0)
			(layer "B.SilkS")
			(hide yes)
			(effects
				(font
					(size 1.27 1.27)
				)
				(justify mirror)
			)
		)
		(property "Value" ""
			(at 0 0 0)
			(layer "B.Fab")
			(effects
				(font
					(size 1.27 1.27)
				)
				(justify mirror)
			)
		)
		(duplicate_pad_numbers_are_jumpers no)
		(fp_line
			(start -0.7874 -0.4064)
			(end -0.7874 0.4064)
			(stroke
				(width 0.1524)
				(type default)
			)
			(layer "B.SilkS")
		)
		(fp_line
			(start -0.7874 0.4064)
			(end 0.7874 0.4064)
			(stroke
				(width 0.1524)
				(type default)
			)
			(layer "B.SilkS")
		)
		(fp_line
			(start 0.7874 -0.4064)
			(end -0.7874 -0.4064)
			(stroke
				(width 0.1524)
				(type default)
			)
			(layer "B.SilkS")
		)
		(fp_line
			(start 0.7874 0.4064)
			(end 0.7874 -0.4064)
			(stroke
				(width 0.1524)
				(type default)
			)
			(layer "B.SilkS")
		)
		(fp_line
			(start -0.67945 -0.3048)
			(end -0.67945 0.3048)
			(stroke
				(width 0.1)
				(type default)
			)
			(layer "B.Fab")
		)
		(fp_line
			(start -0.67945 0.3048)
			(end -0.120396 0.3048)
			(stroke
				(width 0.1)
				(type default)
			)
			(layer "B.Fab")
		)
		(fp_line
			(start -0.12065 -0.3048)
			(end -0.67945 -0.3048)
			(stroke
				(width 0.1)
				(type default)
			)
			(layer "B.Fab")
		)
		(fp_line
			(start -0.12065 -0.2794)
			(end -0.12065 -0.3048)
			(stroke
				(width 0.1)
				(type default)
			)
			(layer "B.Fab")
		)
		(fp_line
			(start -0.120396 0.2794)
			(end 0.12065 0.2794)
			(stroke
				(width 0.1)
				(type default)
			)
			(layer "B.Fab")
		)
		(fp_line
			(start -0.120396 0.3048)
			(end -0.120396 0.2794)
			(stroke
				(width 0.1)
				(type default)
			)
			(layer "B.Fab")
		)
		(fp_line
			(start 0.12065 -0.305054)
			(end 0.12065 -0.2794)
			(stroke
				(width 0.1)
				(type default)
			)
			(layer "B.Fab")
		)
		(fp_line
			(start 0.12065 -0.2794)
			(end -0.12065 -0.2794)
			(stroke
				(width 0.1)
				(type default)
			)
			(layer "B.Fab")
		)
		(fp_line
			(start 0.12065 0.2794)
			(end 0.12065 0.3048)
			(stroke
				(width 0.1)
				(type default)
			)
			(layer "B.Fab")
		)
		(fp_line
			(start 0.12065 0.3048)
			(end 0.67945 0.3048)
			(stroke
				(width 0.1)
				(type default)
			)
			(layer "B.Fab")
		)
		(fp_line
			(start 0.67945 -0.305054)
			(end 0.12065 -0.305054)
			(stroke
				(width 0.1)
				(type default)
			)
			(layer "B.Fab")
		)
		(fp_line
			(start 0.67945 0.3048)
			(end 0.67945 -0.305054)
			(stroke
				(width 0.1)
				(type default)
			)
			(layer "B.Fab")
		)
		(pad "1" smd circle
			(at 0.40005 0 180)
			(size 0 0)
			(layers "B.Cu" "B.Mask" "B.Paste")
			(net "HSC_D_OC_R2")
		)
		(pad "2" smd circle
			(at -0.40005 0 180)
			(size 0 0)
			(layers "B.Cu" "B.Mask" "B.Paste")
			(net "A_HSC_LOW_GATE")
		)
	)
	(footprint ""
		(layer "B.Cu")
		(at 344.318844 -398.942052 90)
		(property "Reference" "C594"
			(at 0 0 90)
			(layer "B.SilkS")
			(hide yes)
			(effects
				(font
					(size 1.27 1.27)
				)
				(justify mirror)
			)
		)
		(property "Value" ""
			(at 0 0 90)
			(layer "B.Fab")
			(effects
				(font
					(size 1.27 1.27)
				)
				(justify mirror)
			)
		)
		(duplicate_pad_numbers_are_jumpers no)
		(fp_line
			(start 0.7874 -0.4064)
			(end -0.7874 -0.4064)
			(stroke
				(width 0.1524)
				(type default)
			)
			(layer "B.SilkS")
		)
		(fp_line
			(start -0.7874 -0.4064)
			(end -0.7874 0.4064)
			(stroke
				(width 0.1524)
				(type default)
			)
			(layer "B.SilkS")
		)
		(fp_line
			(start 0.7874 0.4064)
			(end 0.7874 -0.4064)
			(stroke
				(width 0.1524)
				(type default)
			)
			(layer "B.SilkS")
		)
		(fp_line
			(start -0.7874 0.4064)
			(end 0.7874 0.4064)
			(stroke
				(width 0.1524)
				(type default)
			)
			(layer "B.SilkS")
		)
		(fp_line
			(start 0.67945 -0.305054)
			(end 0.12065 -0.305054)
			(stroke
				(width 0.1)
				(type default)
			)
			(layer "B.Fab")
		)
		(fp_line
			(start 0.12065 -0.305054)
			(end 0.12065 -0.2794)
			(stroke
				(width 0.1)
				(type default)
			)
			(layer "B.Fab")
		)
		(fp_line
			(start -0.12065 -0.3048)
			(end -0.67945 -0.3048)
			(stroke
				(width 0.1)
				(type default)
			)
			(layer "B.Fab")
		)
		(fp_line
			(start -0.67945 -0.3048)
			(end -0.67945 0.3048)
			(stroke
				(width 0.1)
				(type default)
			)
			(layer "B.Fab")
		)
		(fp_line
			(start 0.12065 -0.2794)
			(end -0.12065 -0.2794)
			(stroke
				(width 0.1)
				(type default)
			)
			(layer "B.Fab")
		)
		(fp_line
			(start -0.12065 -0.2794)
			(end -0.12065 -0.3048)
			(stroke
				(width 0.1)
				(type default)
			)
			(layer "B.Fab")
		)
		(fp_line
			(start 0.12065 0.2794)
			(end 0.12065 0.3048)
			(stroke
				(width 0.1)
				(type default)
			)
			(layer "B.Fab")
		)
		(fp_line
			(start -0.120396 0.2794)
			(end 0.12065 0.2794)
			(stroke
				(width 0.1)
				(type default)
			)
			(layer "B.Fab")
		)
		(fp_line
			(start 0.67945 0.3048)
			(end 0.67945 -0.305054)
			(stroke
				(width 0.1)
				(type default)
			)
			(layer "B.Fab")
		)
		(fp_line
			(start 0.12065 0.3048)
			(end 0.67945 0.3048)
			(stroke
				(width 0.1)
				(type default)
			)
			(layer "B.Fab")
		)
		(fp_line
			(start -0.120396 0.3048)
			(end -0.120396 0.2794)
			(stroke
				(width 0.1)
				(type default)
			)
			(layer "B.Fab")
		)
		(fp_line
			(start -0.67945 0.3048)
			(end -0.120396 0.3048)
			(stroke
				(width 0.1)
				(type default)
			)
			(layer "B.Fab")
		)
		(pad "1" smd circle
			(at 0.40005 0 270)
			(size 0 0)
			(layers "B.Cu" "B.Mask" "B.Paste")
			(net "P1V8_CPU0_RT1_1A")
		)
		(pad "2" smd circle
			(at -0.40005 0 270)
			(size 0 0)
			(layers "B.Cu" "B.Mask" "B.Paste")
			(net "GND")
		)
	)
	(footprint ""
		(layer "B.Cu")
		(at 231.114092 -321.775582)
		(property "Reference" "R1263"
			(at 0 0 0)
			(layer "B.SilkS")
			(hide yes)
			(effects
				(font
					(size 1.27 1.27)
				)
				(justify mirror)
			)
		)
		(property "Value" ""
			(at 0 0 0)
			(layer "B.Fab")
			(effects
				(font
					(size 1.27 1.27)
				)
				(justify mirror)
			)
		)
		(duplicate_pad_numbers_are_jumpers no)
		(fp_line
			(start -0.7874 -0.4064)
			(end -0.7874 0.4064)
			(stroke
				(width 0.1524)
				(type default)
			)
			(layer "B.SilkS")
		)
		(fp_line
			(start -0.7874 0.4064)
			(end 0.7874 0.4064)
			(stroke
				(width 0.1524)
				(type default)
			)
			(layer "B.SilkS")
		)
		(fp_line
			(start 0.7874 -0.4064)
			(end -0.7874 -0.4064)
			(stroke
				(width 0.1524)
				(type default)
			)
			(layer "B.SilkS")
		)
		(fp_line
			(start 0.7874 0.4064)
			(end 0.7874 -0.4064)
			(stroke
				(width 0.1524)
				(type default)
			)
			(layer "B.SilkS")
		)
		(fp_line
			(start -0.67945 -0.3048)
			(end -0.67945 0.3048)
			(stroke
				(width 0.1)
				(type default)
			)
			(layer "B.Fab")
		)
		(fp_line
			(start -0.67945 0.3048)
			(end -0.120396 0.3048)
			(stroke
				(width 0.1)
				(type default)
			)
			(layer "B.Fab")
		)
		(fp_line
			(start -0.12065 -0.3048)
			(end -0.67945 -0.3048)
			(stroke
				(width 0.1)
				(type default)
			)
			(layer "B.Fab")
		)
		(fp_line
			(start -0.12065 -0.2794)
			(end -0.12065 -0.3048)
			(stroke
				(width 0.1)
				(type default)
			)
			(layer "B.Fab")
		)
		(fp_line
			(start -0.120396 0.2794)
			(end 0.12065 0.2794)
			(stroke
				(width 0.1)
				(type default)
			)
			(layer "B.Fab")
		)
		(fp_line
			(start -0.120396 0.3048)
			(end -0.120396 0.2794)
			(stroke
				(width 0.1)
				(type default)
			)
			(layer "B.Fab")
		)
		(fp_line
			(start 0.12065 -0.305054)
			(end 0.12065 -0.2794)
			(stroke
				(width 0.1)
				(type default)
			)
			(layer "B.Fab")
		)
		(fp_line
			(start 0.12065 -0.2794)
			(end -0.12065 -0.2794)
			(stroke
				(width 0.1)
				(type default)
			)
			(layer "B.Fab")
		)
		(fp_line
			(start 0.12065 0.2794)
			(end 0.12065 0.3048)
			(stroke
				(width 0.1)
				(type default)
			)
			(layer "B.Fab")
		)
		(fp_line
			(start 0.12065 0.3048)
			(end 0.67945 0.3048)
			(stroke
				(width 0.1)
				(type default)
			)
			(layer "B.Fab")
		)
		(fp_line
			(start 0.67945 -0.305054)
			(end 0.12065 -0.305054)
			(stroke
				(width 0.1)
				(type default)
			)
			(layer "B.Fab")
		)
		(fp_line
			(start 0.67945 0.3048)
			(end 0.67945 -0.305054)
			(stroke
				(width 0.1)
				(type default)
			)
			(layer "B.Fab")
		)
		(pad "1" smd rect
			(at 0.40005 0)
			(size 0.4572 0.508)
			(layers "B.Cu" "B.Mask" "B.Paste")
			(net "P5V_AUX_ADC")
		)
		(pad "2" smd rect
			(at -0.40005 0)
			(size 0.4572 0.508)
			(layers "B.Cu" "B.Mask" "B.Paste")
			(net "P5V_AUX_ADC_TIC")
		)
	)
	(footprint ""
		(layer "B.Cu")
		(at 337.118706 -398.942052 90)
		(property "Reference" "C634"
			(at 0 0 90)
			(layer "B.SilkS")
			(hide yes)
			(effects
				(font
					(size 1.27 1.27)
				)
				(justify mirror)
			)
		)
		(property "Value" ""
			(at 0 0 90)
			(layer "B.Fab")
			(effects
				(font
					(size 1.27 1.27)
				)
				(justify mirror)
			)
		)
		(duplicate_pad_numbers_are_jumpers no)
		(fp_line
			(start 0.7874 -0.4064)
			(end -0.7874 -0.4064)
			(stroke
				(width 0.1524)
				(type default)
			)
			(layer "B.SilkS")
		)
		(fp_line
			(start -0.7874 -0.4064)
			(end -0.7874 0.4064)
			(stroke
				(width 0.1524)
				(type default)
			)
			(layer "B.SilkS")
		)
		(fp_line
			(start 0.7874 0.4064)
			(end 0.7874 -0.4064)
			(stroke
				(width 0.1524)
				(type default)
			)
			(layer "B.SilkS")
		)
		(fp_line
			(start -0.7874 0.4064)
			(end 0.7874 0.4064)
			(stroke
				(width 0.1524)
				(type default)
			)
			(layer "B.SilkS")
		)
		(fp_line
			(start 0.67945 -0.305054)
			(end 0.12065 -0.305054)
			(stroke
				(width 0.1)
				(type default)
			)
			(layer "B.Fab")
		)
		(fp_line
			(start 0.12065 -0.305054)
			(end 0.12065 -0.2794)
			(stroke
				(width 0.1)
				(type default)
			)
			(layer "B.Fab")
		)
		(fp_line
			(start -0.12065 -0.3048)
			(end -0.67945 -0.3048)
			(stroke
				(width 0.1)
				(type default)
			)
			(layer "B.Fab")
		)
		(fp_line
			(start -0.67945 -0.3048)
			(end -0.67945 0.3048)
			(stroke
				(width 0.1)
				(type default)
			)
			(layer "B.Fab")
		)
		(fp_line
			(start 0.12065 -0.2794)
			(end -0.12065 -0.2794)
			(stroke
				(width 0.1)
				(type default)
			)
			(layer "B.Fab")
		)
		(fp_line
			(start -0.12065 -0.2794)
			(end -0.12065 -0.3048)
			(stroke
				(width 0.1)
				(type default)
			)
			(layer "B.Fab")
		)
		(fp_line
			(start 0.12065 0.2794)
			(end 0.12065 0.3048)
			(stroke
				(width 0.1)
				(type default)
			)
			(layer "B.Fab")
		)
		(fp_line
			(start -0.120396 0.2794)
			(end 0.12065 0.2794)
			(stroke
				(width 0.1)
				(type default)
			)
			(layer "B.Fab")
		)
		(fp_line
			(start 0.67945 0.3048)
			(end 0.67945 -0.305054)
			(stroke
				(width 0.1)
				(type default)
			)
			(layer "B.Fab")
		)
		(fp_line
			(start 0.12065 0.3048)
			(end 0.67945 0.3048)
			(stroke
				(width 0.1)
				(type default)
			)
			(layer "B.Fab")
		)
		(fp_line
			(start -0.120396 0.3048)
			(end -0.120396 0.2794)
			(stroke
				(width 0.1)
				(type default)
			)
			(layer "B.Fab")
		)
		(fp_line
			(start -0.67945 0.3048)
			(end -0.120396 0.3048)
			(stroke
				(width 0.1)
				(type default)
			)
			(layer "B.Fab")
		)
		(pad "1" smd circle
			(at 0.40005 0 270)
			(size 0 0)
			(layers "B.Cu" "B.Mask" "B.Paste")
			(net "P0V9_CPU0_RT1_2A")
		)
		(pad "2" smd circle
			(at -0.40005 0 270)
			(size 0 0)
			(layers "B.Cu" "B.Mask" "B.Paste")
			(net "GND")
		)
	)
	(footprint ""
		(layer "B.Cu")
		(at 115.691158 -390.560052 90)
		(property "Reference" "C476"
			(at 0 0 90)
			(layer "B.SilkS")
			(hide yes)
			(effects
				(font
					(size 1.27 1.27)
				)
				(justify mirror)
			)
		)
		(property "Value" ""
			(at 0 0 90)
			(layer "B.Fab")
			(effects
				(font
					(size 1.27 1.27)
				)
				(justify mirror)
			)
		)
		(duplicate_pad_numbers_are_jumpers no)
		(fp_line
			(start 0.7874 -0.4064)
			(end -0.7874 -0.4064)
			(stroke
				(width 0.1524)
				(type default)
			)
			(layer "B.SilkS")
		)
		(fp_line
			(start -0.7874 -0.4064)
			(end -0.7874 0.4064)
			(stroke
				(width 0.1524)
				(type default)
			)
			(layer "B.SilkS")
		)
		(fp_line
			(start 0.7874 0.4064)
			(end 0.7874 -0.4064)
			(stroke
				(width 0.1524)
				(type default)
			)
			(layer "B.SilkS")
		)
		(fp_line
			(start -0.7874 0.4064)
			(end 0.7874 0.4064)
			(stroke
				(width 0.1524)
				(type default)
			)
			(layer "B.SilkS")
		)
		(fp_line
			(start 0.67945 -0.305054)
			(end 0.12065 -0.305054)
			(stroke
				(width 0.1)
				(type default)
			)
			(layer "B.Fab")
		)
		(fp_line
			(start 0.12065 -0.305054)
			(end 0.12065 -0.2794)
			(stroke
				(width 0.1)
				(type default)
			)
			(layer "B.Fab")
		)
		(fp_line
			(start -0.12065 -0.3048)
			(end -0.67945 -0.3048)
			(stroke
				(width 0.1)
				(type default)
			)
			(layer "B.Fab")
		)
		(fp_line
			(start -0.67945 -0.3048)
			(end -0.67945 0.3048)
			(stroke
				(width 0.1)
				(type default)
			)
			(layer "B.Fab")
		)
		(fp_line
			(start 0.12065 -0.2794)
			(end -0.12065 -0.2794)
			(stroke
				(width 0.1)
				(type default)
			)
			(layer "B.Fab")
		)
		(fp_line
			(start -0.12065 -0.2794)
			(end -0.12065 -0.3048)
			(stroke
				(width 0.1)
				(type default)
			)
			(layer "B.Fab")
		)
		(fp_line
			(start 0.12065 0.2794)
			(end 0.12065 0.3048)
			(stroke
				(width 0.1)
				(type default)
			)
			(layer "B.Fab")
		)
		(fp_line
			(start -0.120396 0.2794)
			(end 0.12065 0.2794)
			(stroke
				(width 0.1)
				(type default)
			)
			(layer "B.Fab")
		)
		(fp_line
			(start 0.67945 0.3048)
			(end 0.67945 -0.305054)
			(stroke
				(width 0.1)
				(type default)
			)
			(layer "B.Fab")
		)
		(fp_line
			(start 0.12065 0.3048)
			(end 0.67945 0.3048)
			(stroke
				(width 0.1)
				(type default)
			)
			(layer "B.Fab")
		)
		(fp_line
			(start -0.120396 0.3048)
			(end -0.120396 0.2794)
			(stroke
				(width 0.1)
				(type default)
			)
			(layer "B.Fab")
		)
		(fp_line
			(start -0.67945 0.3048)
			(end -0.120396 0.3048)
			(stroke
				(width 0.1)
				(type default)
			)
			(layer "B.Fab")
		)
		(pad "1" smd circle
			(at 0.40005 0 270)
			(size 0 0)
			(layers "B.Cu" "B.Mask" "B.Paste")
			(net "P0V9_CPU1_RT3_2A")
		)
		(pad "2" smd circle
			(at -0.40005 0 270)
			(size 0 0)
			(layers "B.Cu" "B.Mask" "B.Paste")
			(net "GND")
		)
	)
	(footprint ""
		(layer "B.Cu")
		(at 325.910448 -328.240644 -90)
		(property "Reference" "PC102"
			(at 10.105644 -1.341882 270)
			(unlocked yes)
			(layer "B.SilkS")
			(effects
				(font
					(size 0.7874 0.5842)
					(thickness 0.1524)
				)
				(justify left mirror)
			)
		)
		(property "Value" ""
			(at 0 0 90)
			(layer "B.Fab")
			(effects
				(font
					(size 1.27 1.27)
				)
				(justify mirror)
			)
		)
		(duplicate_pad_numbers_are_jumpers no)
		(fp_line
			(start -4.533392 2.249932)
			(end 4.533392 2.249932)
			(stroke
				(width 0.1524)
				(type default)
			)
			(layer "B.SilkS")
		)
		(fp_line
			(start 4.533392 2.249932)
			(end 4.533392 -2.249932)
			(stroke
				(width 0.1524)
				(type default)
			)
			(layer "B.SilkS")
		)
		(fp_line
			(start -4.533392 -2.249932)
			(end -4.533392 2.249932)
			(stroke
				(width 0.1524)
				(type default)
			)
			(layer "B.SilkS")
		)
		(fp_line
			(start 4.533392 -2.249932)
			(end -4.533392 -2.249932)
			(stroke
				(width 0.1524)
				(type default)
			)
			(layer "B.SilkS")
		)
		(fp_rect
			(start 5.39242 2.326132)
			(end 4.533392 -2.326132)
			(stroke
				(width 0)
				(type default)
			)
			(fill yes)
			(layer "B.SilkS")
		)
		(fp_line
			(start -3.750056 2.249932)
			(end 3.750056 2.249932)
			(stroke
				(width 0.1)
				(type default)
			)
			(layer "B.Fab")
		)
		(fp_line
			(start 3.750056 2.249932)
			(end 3.750056 -2.249932)
			(stroke
				(width 0.1)
				(type default)
			)
			(layer "B.Fab")
		)
		(fp_line
			(start -3.750056 -2.249932)
			(end -3.750056 2.249932)
			(stroke
				(width 0.1)
				(type default)
			)
			(layer "B.Fab")
		)
		(fp_line
			(start 3.750056 -2.249932)
			(end -3.750056 -2.249932)
			(stroke
				(width 0.1)
				(type default)
			)
			(layer "B.Fab")
		)
		(fp_text user "+"
			(at 6.294374 0.137922 180)
			(unlocked yes)
			(layer "B.SilkS")
			(effects
				(font
					(size 1.905 1.4224)
					(thickness 0.1524)
				)
				(justify left mirror)
			)
		)
		(fp_text user "-"
			(at -4.8514 -0.14605 270)
			(unlocked yes)
			(layer "B.SilkS")
			(effects
				(font
					(size 1.905 1.4224)
					(thickness 0.1524)
				)
				(justify left mirror)
			)
		)
		(fp_text user "+"
			(at 6.322314 0.786384 180)
			(unlocked yes)
			(layer "B.Fab")
			(effects
				(font
					(size 1.905 1.4224)
					(thickness 0.1524)
				)
				(justify left mirror)
			)
		)
		(fp_text user "-"
			(at -4.8514 -0.14605 270)
			(unlocked yes)
			(layer "B.Fab")
			(effects
				(font
					(size 1.905 1.4224)
					(thickness 0.1524)
				)
				(justify left mirror)
			)
		)
		(pad "1" smd rect
			(at 3.199892 0 90)
			(size 2.413 2.8194)
			(layers "B.Cu" "B.Mask" "B.Paste")
			(net "PVDDCR_CPU1_P0")
		)
		(pad "2" smd rect
			(at -3.199892 0 90)
			(size 2.413 2.8194)
			(layers "B.Cu" "B.Mask" "B.Paste")
			(net "GND")
		)
	)
	(footprint ""
		(layer "B.Cu")
		(at 358.089454 -246.44731 -120)
		(property "Reference" "C2190"
			(at 0 0 60)
			(layer "B.SilkS")
			(hide yes)
			(effects
				(font
					(size 1.27 1.27)
				)
				(justify mirror)
			)
		)
		(property "Value" ""
			(at 0 0 60)
			(layer "B.Fab")
			(effects
				(font
					(size 1.27 1.27)
				)
				(justify mirror)
			)
		)
		(duplicate_pad_numbers_are_jumpers no)
		(fp_line
			(start 0.787516 0.406438)
			(end 0.787425 -0.40652)
			(stroke
				(width 0.1524)
				(type default)
			)
			(layer "B.SilkS")
		)
		(fp_line
			(start 0.787425 -0.40652)
			(end -0.787516 -0.406438)
			(stroke
				(width 0.1524)
				(type default)
			)
			(layer "B.SilkS")
		)
		(fp_line
			(start -0.787425 0.40652)
			(end 0.787516 0.406438)
			(stroke
				(width 0.1524)
				(type default)
			)
			(layer "B.SilkS")
		)
		(fp_line
			(start -0.787516 -0.406438)
			(end -0.787425 0.40652)
			(stroke
				(width 0.1524)
				(type default)
			)
			(layer "B.SilkS")
		)
		(fp_line
			(start 0.679568 0.304811)
			(end 0.679373 -0.305128)
			(stroke
				(width 0.1)
				(type default)
			)
			(layer "B.Fab")
		)
		(fp_line
			(start 0.120605 0.304905)
			(end 0.679568 0.304811)
			(stroke
				(width 0.1)
				(type default)
			)
			(layer "B.Fab")
		)
		(fp_line
			(start 0.120554 0.279418)
			(end 0.120605 0.304905)
			(stroke
				(width 0.1)
				(type default)
			)
			(layer "B.Fab")
		)
		(fp_line
			(start -0.120316 0.304686)
			(end -0.12024 0.279419)
			(stroke
				(width 0.1)
				(type default)
			)
			(layer "B.Fab")
		)
		(fp_line
			(start -0.12024 0.279419)
			(end 0.120554 0.279418)
			(stroke
				(width 0.1)
				(type default)
			)
			(layer "B.Fab")
		)
		(fp_line
			(start 0.679373 -0.305128)
			(end 0.120629 -0.30516)
			(stroke
				(width 0.1)
				(type default)
			)
			(layer "B.Fab")
		)
		(fp_line
			(start -0.6795 0.304908)
			(end -0.120316 0.304686)
			(stroke
				(width 0.1)
				(type default)
			)
			(layer "B.Fab")
		)
		(fp_line
			(start 0.120587 -0.279326)
			(end -0.120554 -0.279418)
			(stroke
				(width 0.1)
				(type default)
			)
			(layer "B.Fab")
		)
		(fp_line
			(start 0.120629 -0.30516)
			(end 0.120587 -0.279326)
			(stroke
				(width 0.1)
				(type default)
			)
			(layer "B.Fab")
		)
		(fp_line
			(start -0.120554 -0.279418)
			(end -0.120605 -0.304905)
			(stroke
				(width 0.1)
				(type default)
			)
			(layer "B.Fab")
		)
		(fp_line
			(start -0.120605 -0.304905)
			(end -0.679568 -0.304811)
			(stroke
				(width 0.1)
				(type default)
			)
			(layer "B.Fab")
		)
		(fp_line
			(start -0.679568 -0.304811)
			(end -0.6795 0.304908)
			(stroke
				(width 0.1)
				(type default)
			)
			(layer "B.Fab")
		)
		(pad "1" smd circle
			(at 0.40005 0 60)
			(size 0 0)
			(layers "B.Cu" "B.Mask" "B.Paste")
			(net "PVDDCR_CPU0_P0")
		)
		(pad "2" smd circle
			(at -0.40005 0 60)
			(size 0 0)
			(layers "B.Cu" "B.Mask" "B.Paste")
			(net "GND")
		)
	)
	(footprint ""
		(layer "B.Cu")
		(at 183.294528 -425.674282 -90)
		(property "Reference" "R6232"
			(at 0 0 90)
			(layer "B.SilkS")
			(hide yes)
			(effects
				(font
					(size 1.27 1.27)
				)
				(justify mirror)
			)
		)
		(property "Value" ""
			(at 0 0 90)
			(layer "B.Fab")
			(effects
				(font
					(size 1.27 1.27)
				)
				(justify mirror)
			)
		)
		(duplicate_pad_numbers_are_jumpers no)
		(fp_line
			(start -0.7874 0.4064)
			(end 0.7874 0.4064)
			(stroke
				(width 0.1524)
				(type default)
			)
			(layer "B.SilkS")
		)
		(fp_line
			(start 0.7874 0.4064)
			(end 0.7874 -0.4064)
			(stroke
				(width 0.1524)
				(type default)
			)
			(layer "B.SilkS")
		)
		(fp_line
			(start -0.7874 -0.4064)
			(end -0.7874 0.4064)
			(stroke
				(width 0.1524)
				(type default)
			)
			(layer "B.SilkS")
		)
		(fp_line
			(start 0.7874 -0.4064)
			(end -0.7874 -0.4064)
			(stroke
				(width 0.1524)
				(type default)
			)
			(layer "B.SilkS")
		)
		(fp_line
			(start -0.67945 0.3048)
			(end -0.120396 0.3048)
			(stroke
				(width 0.1)
				(type default)
			)
			(layer "B.Fab")
		)
		(fp_line
			(start -0.120396 0.3048)
			(end -0.120396 0.2794)
			(stroke
				(width 0.1)
				(type default)
			)
			(layer "B.Fab")
		)
		(fp_line
			(start 0.12065 0.3048)
			(end 0.67945 0.3048)
			(stroke
				(width 0.1)
				(type default)
			)
			(layer "B.Fab")
		)
		(fp_line
			(start 0.67945 0.3048)
			(end 0.67945 -0.305054)
			(stroke
				(width 0.1)
				(type default)
			)
			(layer "B.Fab")
		)
		(fp_line
			(start -0.120396 0.2794)
			(end 0.12065 0.2794)
			(stroke
				(width 0.1)
				(type default)
			)
			(layer "B.Fab")
		)
		(fp_line
			(start 0.12065 0.2794)
			(end 0.12065 0.3048)
			(stroke
				(width 0.1)
				(type default)
			)
			(layer "B.Fab")
		)
		(fp_line
			(start -0.12065 -0.2794)
			(end -0.12065 -0.3048)
			(stroke
				(width 0.1)
				(type default)
			)
			(layer "B.Fab")
		)
		(fp_line
			(start 0.12065 -0.2794)
			(end -0.12065 -0.2794)
			(stroke
				(width 0.1)
				(type default)
			)
			(layer "B.Fab")
		)
		(fp_line
			(start -0.67945 -0.3048)
			(end -0.67945 0.3048)
			(stroke
				(width 0.1)
				(type default)
			)
			(layer "B.Fab")
		)
		(fp_line
			(start -0.12065 -0.3048)
			(end -0.67945 -0.3048)
			(stroke
				(width 0.1)
				(type default)
			)
			(layer "B.Fab")
		)
		(fp_line
			(start 0.12065 -0.305054)
			(end 0.12065 -0.2794)
			(stroke
				(width 0.1)
				(type default)
			)
			(layer "B.Fab")
		)
		(fp_line
			(start 0.67945 -0.305054)
			(end 0.12065 -0.305054)
			(stroke
				(width 0.1)
				(type default)
			)
			(layer "B.Fab")
		)
		(pad "1" smd circle
			(at 0.40005 0 90)
			(size 0 0)
			(layers "B.Cu" "B.Mask" "B.Paste")
			(net "HSC_CSOUT")
		)
		(pad "2" smd circle
			(at -0.40005 0 90)
			(size 0 0)
			(layers "B.Cu" "B.Mask" "B.Paste")
			(net "A_HSC_LOW")
		)
	)
	(footprint ""
		(layer "B.Cu")
		(at 379.888496 -178.977798 90)
		(property "Reference" "PC554_3"
			(at 0 0 90)
			(layer "B.SilkS")
			(hide yes)
			(effects
				(font
					(size 1.27 1.27)
				)
				(justify mirror)
			)
		)
		(property "Value" ""
			(at 0 0 90)
			(layer "B.Fab")
			(effects
				(font
					(size 1.27 1.27)
				)
				(justify mirror)
			)
		)
		(duplicate_pad_numbers_are_jumpers no)
		(fp_line
			(start 1.524 -0.762)
			(end -1.524 -0.762)
			(stroke
				(width 0.1524)
				(type default)
			)
			(layer "B.SilkS")
		)
		(fp_line
			(start -1.524 -0.762)
			(end -1.524 0.762)
			(stroke
				(width 0.1524)
				(type default)
			)
			(layer "B.SilkS")
		)
		(fp_line
			(start 1.524 0.762)
			(end 1.524 -0.762)
			(stroke
				(width 0.1524)
				(type default)
			)
			(layer "B.SilkS")
		)
		(fp_line
			(start -1.524 0.762)
			(end 1.524 0.762)
			(stroke
				(width 0.1524)
				(type default)
			)
			(layer "B.SilkS")
		)
		(fp_line
			(start 1.1049 -0.724916)
			(end 1.1049 0.724916)
			(stroke
				(width 0.1)
				(type default)
			)
			(layer "B.Fab")
		)
		(fp_line
			(start -1.1049 -0.724916)
			(end 1.1049 -0.724916)
			(stroke
				(width 0.1)
				(type default)
			)
			(layer "B.Fab")
		)
		(fp_line
			(start 1.1049 0.724916)
			(end -1.1049 0.724916)
			(stroke
				(width 0.1)
				(type default)
			)
			(layer "B.Fab")
		)
		(fp_line
			(start -1.1049 0.724916)
			(end -1.1049 -0.724916)
			(stroke
				(width 0.1)
				(type default)
			)
			(layer "B.Fab")
		)
		(pad "1" smd rect
			(at 0.889 0 90)
			(size 1.016 1.27)
			(layers "B.Cu" "B.Mask" "B.Paste")
			(net "SW_P12V_AUX_PVDDCR_CPU0_P0_FLT")
		)
		(pad "2" smd rect
			(at -0.889 0 90)
			(size 1.016 1.27)
			(layers "B.Cu" "B.Mask" "B.Paste")
			(net "GND")
		)
	)
	(footprint ""
		(layer "B.Cu")
		(at 142.04061 -388.846568)
		(property "Reference" "C409"
			(at 0 0 0)
			(layer "B.SilkS")
			(hide yes)
			(effects
				(font
					(size 1.27 1.27)
				)
				(justify mirror)
			)
		)
		(property "Value" ""
			(at 0 0 0)
			(layer "B.Fab")
			(effects
				(font
					(size 1.27 1.27)
				)
				(justify mirror)
			)
		)
		(duplicate_pad_numbers_are_jumpers no)
		(fp_line
			(start -1.524 -0.762)
			(end -1.524 0.762)
			(stroke
				(width 0.1524)
				(type default)
			)
			(layer "B.SilkS")
		)
		(fp_line
			(start -1.524 0.762)
			(end 1.524 0.762)
			(stroke
				(width 0.1524)
				(type default)
			)
			(layer "B.SilkS")
		)
		(fp_line
			(start 1.524 -0.762)
			(end -1.524 -0.762)
			(stroke
				(width 0.1524)
				(type default)
			)
			(layer "B.SilkS")
		)
		(fp_line
			(start 1.524 0.762)
			(end 1.524 -0.762)
			(stroke
				(width 0.1524)
				(type default)
			)
			(layer "B.SilkS")
		)
		(fp_line
			(start -1.1049 -0.724916)
			(end 1.1049 -0.724916)
			(stroke
				(width 0.1)
				(type default)
			)
			(layer "B.Fab")
		)
		(fp_line
			(start -1.1049 0.724916)
			(end -1.1049 -0.724916)
			(stroke
				(width 0.1)
				(type default)
			)
			(layer "B.Fab")
		)
		(fp_line
			(start 1.1049 -0.724916)
			(end 1.1049 0.724916)
			(stroke
				(width 0.1)
				(type default)
			)
			(layer "B.Fab")
		)
		(fp_line
			(start 1.1049 0.724916)
			(end -1.1049 0.724916)
			(stroke
				(width 0.1)
				(type default)
			)
			(layer "B.Fab")
		)
		(pad "1" smd rect
			(at 0.889 0)
			(size 1.016 1.27)
			(layers "B.Cu" "B.Mask" "B.Paste")
			(net "P0V9_CPU1_RT2_2A")
		)
		(pad "2" smd rect
			(at -0.889 0)
			(size 1.016 1.27)
			(layers "B.Cu" "B.Mask" "B.Paste")
			(net "GND")
		)
	)
	(footprint ""
		(layer "B.Cu")
		(at 106.68 -417.322 90)
		(property "Reference" "Q74"
			(at -3.683 -0.28067 270)
			(unlocked yes)
			(layer "B.SilkS")
			(effects
				(font
					(size 0.7874 0.5842)
					(thickness 0.1524)
				)
				(justify left mirror)
			)
		)
		(property "Value" ""
			(at 0 0 90)
			(layer "B.Fab")
			(effects
				(font
					(size 1.27 1.27)
				)
				(justify mirror)
			)
		)
		(duplicate_pad_numbers_are_jumpers no)
		(fp_line
			(start 1.332738 -1.100074)
			(end 0.4826 -1.100074)
			(stroke
				(width 0.1524)
				(type default)
			)
			(layer "B.SilkS")
		)
		(fp_line
			(start 0.4826 -1.100074)
			(end 0 -0.541274)
			(stroke
				(width 0.1524)
				(type default)
			)
			(layer "B.SilkS")
		)
		(fp_line
			(start -0.4826 -1.100074)
			(end -1.332738 -1.100074)
			(stroke
				(width 0.1524)
				(type default)
			)
			(layer "B.SilkS")
		)
		(fp_line
			(start -1.332738 -1.100074)
			(end -1.332738 1.100074)
			(stroke
				(width 0.1524)
				(type default)
			)
			(layer "B.SilkS")
		)
		(fp_line
			(start 0 -0.541274)
			(end -0.4826 -1.100074)
			(stroke
				(width 0.1524)
				(type default)
			)
			(layer "B.SilkS")
		)
		(fp_line
			(start 1.332738 1.100074)
			(end 1.332738 -1.100074)
			(stroke
				(width 0.1524)
				(type default)
			)
			(layer "B.SilkS")
		)
		(fp_line
			(start -1.332738 1.100074)
			(end 1.332738 1.100074)
			(stroke
				(width 0.1524)
				(type default)
			)
			(layer "B.SilkS")
		)
		(fp_poly
			(pts
				(xy 1.441196 -0.658876) (xy 2.143252 -0.307848) (xy 2.143252 -1.009904)
			)
			(stroke
				(width 0)
				(type default)
			)
			(fill yes)
			(layer "B.SilkS")
		)
		(fp_line
			(start 0.674878 -1.100074)
			(end -0.674878 -1.100074)
			(stroke
				(width 0.1)
				(type default)
			)
			(layer "B.Fab")
		)
		(fp_line
			(start -0.674878 -1.100074)
			(end -0.674878 1.100074)
			(stroke
				(width 0.1)
				(type default)
			)
			(layer "B.Fab")
		)
		(fp_line
			(start 0.674878 1.100074)
			(end 0.674878 -1.100074)
			(stroke
				(width 0.1)
				(type default)
			)
			(layer "B.Fab")
		)
		(fp_line
			(start -0.674878 1.100074)
			(end 0.674878 1.100074)
			(stroke
				(width 0.1)
				(type default)
			)
			(layer "B.Fab")
		)
		(fp_poly
			(pts
				(xy 2.2352 -0.298958) (xy 2.2352 -1.001014) (xy 1.533144 -0.649986)
			)
			(stroke
				(width 0)
				(type default)
			)
			(fill yes)
			(layer "B.Fab")
		)
		(pad "1" smd rect
			(at 0.94996 -0.649986 180)
			(size 0.4318 0.508)
			(layers "B.Cu" "B.Mask" "B.Paste")
			(net "GND")
		)
		(pad "2" smd rect
			(at 0.94996 0 180)
			(size 0.4318 0.508)
			(layers "B.Cu" "B.Mask" "B.Paste")
			(net "FM_SMB_2_ALERT_GPU_N")
		)
		(pad "3" smd rect
			(at 0.94996 0.649986 180)
			(size 0.4318 0.508)
			(layers "B.Cu" "B.Mask" "B.Paste")
			(net "FM_SMB_2_ALERT_GPU_ISO_N")
		)
		(pad "4" smd rect
			(at -0.94996 0.649986 180)
			(size 0.4318 0.508)
			(layers "B.Cu" "B.Mask" "B.Paste")
			(net "GND")
		)
		(pad "5" smd rect
			(at -0.94996 0 180)
			(size 0.4318 0.508)
			(layers "B.Cu" "B.Mask" "B.Paste")
			(net "FM_SMB_2_ALERT_GPU")
		)
		(pad "6" smd rect
			(at -0.94996 -0.649986 180)
			(size 0.4318 0.508)
			(layers "B.Cu" "B.Mask" "B.Paste")
			(net "FM_SMB_2_ALERT_GPU")
		)
	)
	(footprint ""
		(layer "B.Cu")
		(at 90.846148 -388.011162 -90)
		(property "Reference" "C206"
			(at 0 0 90)
			(layer "B.SilkS")
			(hide yes)
			(effects
				(font
					(size 1.27 1.27)
				)
				(justify mirror)
			)
		)
		(property "Value" ""
			(at 0 0 90)
			(layer "B.Fab")
			(effects
				(font
					(size 1.27 1.27)
				)
				(justify mirror)
			)
		)
		(duplicate_pad_numbers_are_jumpers no)
		(fp_line
			(start -0.299974 0.150114)
			(end 0.299974 0.150114)
			(stroke
				(width 0.1)
				(type default)
			)
			(layer "B.Fab")
		)
		(fp_line
			(start 0.299974 0.150114)
			(end 0.299974 -0.150114)
			(stroke
				(width 0.1)
				(type default)
			)
			(layer "B.Fab")
		)
		(fp_line
			(start -0.299974 -0.150114)
			(end -0.299974 0.150114)
			(stroke
				(width 0.1)
				(type default)
			)
			(layer "B.Fab")
		)
		(fp_line
			(start 0.299974 -0.150114)
			(end -0.299974 -0.150114)
			(stroke
				(width 0.1)
				(type default)
			)
			(layer "B.Fab")
		)
		(pad "1" smd rect
			(at 0.2667 0 90)
			(size 0.3048 0.381)
			(layers "B.Cu" "B.Mask" "B.Paste")
			(net "P1V8_CPU1_RT1_1A_1D")
		)
		(pad "2" smd rect
			(at -0.2667 0 90)
			(size 0.3048 0.381)
			(layers "B.Cu" "B.Mask" "B.Paste")
			(net "GND")
		)
	)
	(footprint ""
		(layer "B.Cu")
		(at 324.593966 -416.899344 90)
		(property "Reference" "C6545"
			(at 0 0 90)
			(layer "B.SilkS")
			(hide yes)
			(effects
				(font
					(size 1.27 1.27)
				)
				(justify mirror)
			)
		)
		(property "Value" ""
			(at 0 0 90)
			(layer "B.Fab")
			(effects
				(font
					(size 1.27 1.27)
				)
				(justify mirror)
			)
		)
		(duplicate_pad_numbers_are_jumpers no)
		(fp_line
			(start 0.299974 -0.150114)
			(end -0.299974 -0.150114)
			(stroke
				(width 0.1)
				(type default)
			)
			(layer "B.Fab")
		)
		(fp_line
			(start -0.299974 -0.150114)
			(end -0.299974 0.150114)
			(stroke
				(width 0.1)
				(type default)
			)
			(layer "B.Fab")
		)
		(fp_line
			(start 0.299974 0.150114)
			(end 0.299974 -0.150114)
			(stroke
				(width 0.1)
				(type default)
			)
			(layer "B.Fab")
		)
		(fp_line
			(start -0.299974 0.150114)
			(end 0.299974 0.150114)
			(stroke
				(width 0.1)
				(type default)
			)
			(layer "B.Fab")
		)
		(pad "1" smd rect
			(at 0.2667 0 270)
			(size 0.3048 0.381)
			(layers "B.Cu" "B.Mask" "B.Paste")
			(net "P5E_CPU0_P1_TX_BUF_C_DP<6>")
		)
		(pad "2" smd rect
			(at -0.2667 0 270)
			(size 0.3048 0.381)
			(layers "B.Cu" "B.Mask" "B.Paste")
			(net "P5E_CPU0_P1_TX_BUF_DP<6>")
		)
	)
	(footprint ""
		(layer "B.Cu")
		(at 232.537 -218.059 90)
		(property "Reference" "C3"
			(at 0 0 90)
			(layer "B.SilkS")
			(hide yes)
			(effects
				(font
					(size 1.27 1.27)
				)
				(justify mirror)
			)
		)
		(property "Value" ""
			(at 0 0 90)
			(layer "B.Fab")
			(effects
				(font
					(size 1.27 1.27)
				)
				(justify mirror)
			)
		)
		(duplicate_pad_numbers_are_jumpers no)
		(fp_line
			(start 0.7874 -0.4064)
			(end -0.7874 -0.4064)
			(stroke
				(width 0.1524)
				(type default)
			)
			(layer "B.SilkS")
		)
		(fp_line
			(start -0.7874 -0.4064)
			(end -0.7874 0.4064)
			(stroke
				(width 0.1524)
				(type default)
			)
			(layer "B.SilkS")
		)
		(fp_line
			(start 0.7874 0.4064)
			(end 0.7874 -0.4064)
			(stroke
				(width 0.1524)
				(type default)
			)
			(layer "B.SilkS")
		)
		(fp_line
			(start -0.7874 0.4064)
			(end 0.7874 0.4064)
			(stroke
				(width 0.1524)
				(type default)
			)
			(layer "B.SilkS")
		)
		(fp_line
			(start 0.67945 -0.305054)
			(end 0.12065 -0.305054)
			(stroke
				(width 0.1)
				(type default)
			)
			(layer "B.Fab")
		)
		(fp_line
			(start 0.12065 -0.305054)
			(end 0.12065 -0.2794)
			(stroke
				(width 0.1)
				(type default)
			)
			(layer "B.Fab")
		)
		(fp_line
			(start -0.12065 -0.3048)
			(end -0.67945 -0.3048)
			(stroke
				(width 0.1)
				(type default)
			)
			(layer "B.Fab")
		)
		(fp_line
			(start -0.67945 -0.3048)
			(end -0.67945 0.3048)
			(stroke
				(width 0.1)
				(type default)
			)
			(layer "B.Fab")
		)
		(fp_line
			(start 0.12065 -0.2794)
			(end -0.12065 -0.2794)
			(stroke
				(width 0.1)
				(type default)
			)
			(layer "B.Fab")
		)
		(fp_line
			(start -0.12065 -0.2794)
			(end -0.12065 -0.3048)
			(stroke
				(width 0.1)
				(type default)
			)
			(layer "B.Fab")
		)
		(fp_line
			(start 0.12065 0.2794)
			(end 0.12065 0.3048)
			(stroke
				(width 0.1)
				(type default)
			)
			(layer "B.Fab")
		)
		(fp_line
			(start -0.120396 0.2794)
			(end 0.12065 0.2794)
			(stroke
				(width 0.1)
				(type default)
			)
			(layer "B.Fab")
		)
		(fp_line
			(start 0.67945 0.3048)
			(end 0.67945 -0.305054)
			(stroke
				(width 0.1)
				(type default)
			)
			(layer "B.Fab")
		)
		(fp_line
			(start 0.12065 0.3048)
			(end 0.67945 0.3048)
			(stroke
				(width 0.1)
				(type default)
			)
			(layer "B.Fab")
		)
		(fp_line
			(start -0.120396 0.3048)
			(end -0.120396 0.2794)
			(stroke
				(width 0.1)
				(type default)
			)
			(layer "B.Fab")
		)
		(fp_line
			(start -0.67945 0.3048)
			(end -0.120396 0.3048)
			(stroke
				(width 0.1)
				(type default)
			)
			(layer "B.Fab")
		)
		(pad "1" smd circle
			(at 0.40005 0 270)
			(size 0 0)
			(layers "B.Cu" "B.Mask" "B.Paste")
			(net "PVDD11_S3_P0")
		)
		(pad "2" smd circle
			(at -0.40005 0 270)
			(size 0 0)
			(layers "B.Cu" "B.Mask" "B.Paste")
			(net "GND")
		)
	)
	(footprint ""
		(layer "B.Cu")
		(at 453.432418 -194.96151 180)
		(property "Reference" "R1579"
			(at 0 0 0)
			(layer "B.SilkS")
			(hide yes)
			(effects
				(font
					(size 1.27 1.27)
				)
				(justify mirror)
			)
		)
		(property "Value" ""
			(at 0 0 0)
			(layer "B.Fab")
			(effects
				(font
					(size 1.27 1.27)
				)
				(justify mirror)
			)
		)
		(duplicate_pad_numbers_are_jumpers no)
		(fp_line
			(start 0.7874 0.4064)
			(end 0.7874 -0.4064)
			(stroke
				(width 0.1524)
				(type default)
			)
			(layer "B.SilkS")
		)
		(fp_line
			(start 0.7874 -0.4064)
			(end -0.7874 -0.4064)
			(stroke
				(width 0.1524)
				(type default)
			)
			(layer "B.SilkS")
		)
		(fp_line
			(start -0.7874 0.4064)
			(end 0.7874 0.4064)
			(stroke
				(width 0.1524)
				(type default)
			)
			(layer "B.SilkS")
		)
		(fp_line
			(start -0.7874 -0.4064)
			(end -0.7874 0.4064)
			(stroke
				(width 0.1524)
				(type default)
			)
			(layer "B.SilkS")
		)
		(fp_line
			(start 0.67945 0.3048)
			(end 0.67945 -0.305054)
			(stroke
				(width 0.1)
				(type default)
			)
			(layer "B.Fab")
		)
		(fp_line
			(start 0.67945 -0.305054)
			(end 0.12065 -0.305054)
			(stroke
				(width 0.1)
				(type default)
			)
			(layer "B.Fab")
		)
		(fp_line
			(start 0.12065 0.3048)
			(end 0.67945 0.3048)
			(stroke
				(width 0.1)
				(type default)
			)
			(layer "B.Fab")
		)
		(fp_line
			(start 0.12065 0.2794)
			(end 0.12065 0.3048)
			(stroke
				(width 0.1)
				(type default)
			)
			(layer "B.Fab")
		)
		(fp_line
			(start 0.12065 -0.2794)
			(end -0.12065 -0.2794)
			(stroke
				(width 0.1)
				(type default)
			)
			(layer "B.Fab")
		)
		(fp_line
			(start 0.12065 -0.305054)
			(end 0.12065 -0.2794)
			(stroke
				(width 0.1)
				(type default)
			)
			(layer "B.Fab")
		)
		(fp_line
			(start -0.120396 0.3048)
			(end -0.120396 0.2794)
			(stroke
				(width 0.1)
				(type default)
			)
			(layer "B.Fab")
		)
		(fp_line
			(start -0.120396 0.2794)
			(end 0.12065 0.2794)
			(stroke
				(width 0.1)
				(type default)
			)
			(layer "B.Fab")
		)
		(fp_line
			(start -0.12065 -0.2794)
			(end -0.12065 -0.3048)
			(stroke
				(width 0.1)
				(type default)
			)
			(layer "B.Fab")
		)
		(fp_line
			(start -0.12065 -0.3048)
			(end -0.67945 -0.3048)
			(stroke
				(width 0.1)
				(type default)
			)
			(layer "B.Fab")
		)
		(fp_line
			(start -0.67945 0.3048)
			(end -0.120396 0.3048)
			(stroke
				(width 0.1)
				(type default)
			)
			(layer "B.Fab")
		)
		(fp_line
			(start -0.67945 -0.3048)
			(end -0.67945 0.3048)
			(stroke
				(width 0.1)
				(type default)
			)
			(layer "B.Fab")
		)
		(pad "1" smd circle
			(at 0.40005 0)
			(size 0 0)
			(layers "B.Cu" "B.Mask" "B.Paste")
			(net "I3C_SPD_DDRGL_CPU0_SCL")
		)
		(pad "2" smd circle
			(at -0.40005 0)
			(size 0 0)
			(layers "B.Cu" "B.Mask" "B.Paste")
			(net "I3C_SPD_DDRL_CPU0_SCL")
		)
	)
	(footprint ""
		(layer "B.Cu")
		(at 355.927406 -176.244504 90)
		(property "Reference" "PC495"
			(at 6.798056 -0.502666 270)
			(unlocked yes)
			(layer "B.SilkS")
			(effects
				(font
					(size 0.7874 0.5842)
					(thickness 0.1524)
				)
				(justify left mirror)
			)
		)
		(property "Value" ""
			(at 0 0 90)
			(layer "B.Fab")
			(effects
				(font
					(size 1.27 1.27)
				)
				(justify mirror)
			)
		)
		(duplicate_pad_numbers_are_jumpers no)
		(fp_line
			(start 4.533392 -2.249932)
			(end -4.533392 -2.249932)
			(stroke
				(width 0.1524)
				(type default)
			)
			(layer "B.SilkS")
		)
		(fp_line
			(start -4.533392 -2.249932)
			(end -4.533392 2.249932)
			(stroke
				(width 0.1524)
				(type default)
			)
			(layer "B.SilkS")
		)
		(fp_line
			(start 4.533392 2.249932)
			(end 4.533392 -2.249932)
			(stroke
				(width 0.1524)
				(type default)
			)
			(layer "B.SilkS")
		)
		(fp_line
			(start -4.533392 2.249932)
			(end 4.533392 2.249932)
			(stroke
				(width 0.1524)
				(type default)
			)
			(layer "B.SilkS")
		)
		(fp_rect
			(start 4.533392 -2.326132)
			(end 5.39242 2.326132)
			(stroke
				(width 0)
				(type default)
			)
			(fill yes)
			(layer "B.SilkS")
		)
		(fp_line
			(start 3.750056 -2.249932)
			(end -3.750056 -2.249932)
			(stroke
				(width 0.1)
				(type default)
			)
			(layer "B.Fab")
		)
		(fp_line
			(start -3.750056 -2.249932)
			(end -3.750056 2.249932)
			(stroke
				(width 0.1)
				(type default)
			)
			(layer "B.Fab")
		)
		(fp_line
			(start 3.750056 2.249932)
			(end 3.750056 -2.249932)
			(stroke
				(width 0.1)
				(type default)
			)
			(layer "B.Fab")
		)
		(fp_line
			(start -3.750056 2.249932)
			(end 3.750056 2.249932)
			(stroke
				(width 0.1)
				(type default)
			)
			(layer "B.Fab")
		)
		(fp_text user "-"
			(at -4.8514 -0.14605 90)
			(unlocked yes)
			(layer "B.SilkS")
			(effects
				(font
					(size 1.905 1.4224)
					(thickness 0.1524)
				)
				(justify left mirror)
			)
		)
		(fp_text user "+"
			(at 6.322314 0.786384 0)
			(unlocked yes)
			(layer "B.SilkS")
			(effects
				(font
					(size 1.905 1.4224)
					(thickness 0.1524)
				)
				(justify left mirror)
			)
		)
		(fp_text user "-"
			(at -4.8514 -0.14605 90)
			(unlocked yes)
			(layer "B.Fab")
			(effects
				(font
					(size 1.905 1.4224)
					(thickness 0.1524)
				)
				(justify left mirror)
			)
		)
		(fp_text user "+"
			(at 6.322314 0.786384 0)
			(unlocked yes)
			(layer "B.Fab")
			(effects
				(font
					(size 1.905 1.4224)
					(thickness 0.1524)
				)
				(justify left mirror)
			)
		)
		(pad "1" smd rect
			(at 3.199892 0 270)
			(size 2.413 2.8194)
			(layers "B.Cu" "B.Mask" "B.Paste")
			(net "PVDDCR_CPU0_P0")
		)
		(pad "2" smd rect
			(at -3.199892 0 270)
			(size 2.413 2.8194)
			(layers "B.Cu" "B.Mask" "B.Paste")
			(net "GND")
		)
	)
	(footprint ""
		(layer "B.Cu")
		(at 11.709908 -132.55625 -90)
		(property "Reference" "C1886"
			(at 0 0 90)
			(layer "B.SilkS")
			(hide yes)
			(effects
				(font
					(size 1.27 1.27)
				)
				(justify mirror)
			)
		)
		(property "Value" ""
			(at 0 0 90)
			(layer "B.Fab")
			(effects
				(font
					(size 1.27 1.27)
				)
				(justify mirror)
			)
		)
		(duplicate_pad_numbers_are_jumpers no)
		(fp_line
			(start -0.7874 0.4064)
			(end 0.7874 0.4064)
			(stroke
				(width 0.1524)
				(type default)
			)
			(layer "B.SilkS")
		)
		(fp_line
			(start 0.7874 0.4064)
			(end 0.7874 -0.4064)
			(stroke
				(width 0.1524)
				(type default)
			)
			(layer "B.SilkS")
		)
		(fp_line
			(start -0.7874 -0.4064)
			(end -0.7874 0.4064)
			(stroke
				(width 0.1524)
				(type default)
			)
			(layer "B.SilkS")
		)
		(fp_line
			(start 0.7874 -0.4064)
			(end -0.7874 -0.4064)
			(stroke
				(width 0.1524)
				(type default)
			)
			(layer "B.SilkS")
		)
		(fp_line
			(start -0.67945 0.3048)
			(end -0.120396 0.3048)
			(stroke
				(width 0.1)
				(type default)
			)
			(layer "B.Fab")
		)
		(fp_line
			(start -0.120396 0.3048)
			(end -0.120396 0.2794)
			(stroke
				(width 0.1)
				(type default)
			)
			(layer "B.Fab")
		)
		(fp_line
			(start 0.12065 0.3048)
			(end 0.67945 0.3048)
			(stroke
				(width 0.1)
				(type default)
			)
			(layer "B.Fab")
		)
		(fp_line
			(start 0.67945 0.3048)
			(end 0.67945 -0.305054)
			(stroke
				(width 0.1)
				(type default)
			)
			(layer "B.Fab")
		)
		(fp_line
			(start -0.120396 0.2794)
			(end 0.12065 0.2794)
			(stroke
				(width 0.1)
				(type default)
			)
			(layer "B.Fab")
		)
		(fp_line
			(start 0.12065 0.2794)
			(end 0.12065 0.3048)
			(stroke
				(width 0.1)
				(type default)
			)
			(layer "B.Fab")
		)
		(fp_line
			(start -0.12065 -0.2794)
			(end -0.12065 -0.3048)
			(stroke
				(width 0.1)
				(type default)
			)
			(layer "B.Fab")
		)
		(fp_line
			(start 0.12065 -0.2794)
			(end -0.12065 -0.2794)
			(stroke
				(width 0.1)
				(type default)
			)
			(layer "B.Fab")
		)
		(fp_line
			(start -0.67945 -0.3048)
			(end -0.67945 0.3048)
			(stroke
				(width 0.1)
				(type default)
			)
			(layer "B.Fab")
		)
		(fp_line
			(start -0.12065 -0.3048)
			(end -0.67945 -0.3048)
			(stroke
				(width 0.1)
				(type default)
			)
			(layer "B.Fab")
		)
		(fp_line
			(start 0.12065 -0.305054)
			(end 0.12065 -0.2794)
			(stroke
				(width 0.1)
				(type default)
			)
			(layer "B.Fab")
		)
		(fp_line
			(start 0.67945 -0.305054)
			(end 0.12065 -0.305054)
			(stroke
				(width 0.1)
				(type default)
			)
			(layer "B.Fab")
		)
		(pad "1" smd circle
			(at 0.40005 0 90)
			(size 0 0)
			(layers "B.Cu" "B.Mask" "B.Paste")
			(net "VFG3P3_CLK_GEN")
		)
		(pad "2" smd circle
			(at -0.40005 0 90)
			(size 0 0)
			(layers "B.Cu" "B.Mask" "B.Paste")
			(net "GND")
		)
	)
	(footprint ""
		(layer "B.Cu")
		(at 108.371386 -266.005564)
		(property "Reference" "C2289"
			(at 0 0 0)
			(layer "B.SilkS")
			(hide yes)
			(effects
				(font
					(size 1.27 1.27)
				)
				(justify mirror)
			)
		)
		(property "Value" ""
			(at 0 0 0)
			(layer "B.Fab")
			(effects
				(font
					(size 1.27 1.27)
				)
				(justify mirror)
			)
		)
		(duplicate_pad_numbers_are_jumpers no)
		(fp_line
			(start -0.7874 -0.4064)
			(end -0.7874 0.4064)
			(stroke
				(width 0.1524)
				(type default)
			)
			(layer "B.SilkS")
		)
		(fp_line
			(start -0.7874 0.4064)
			(end 0.7874 0.4064)
			(stroke
				(width 0.1524)
				(type default)
			)
			(layer "B.SilkS")
		)
		(fp_line
			(start 0.7874 -0.4064)
			(end -0.7874 -0.4064)
			(stroke
				(width 0.1524)
				(type default)
			)
			(layer "B.SilkS")
		)
		(fp_line
			(start 0.7874 0.4064)
			(end 0.7874 -0.4064)
			(stroke
				(width 0.1524)
				(type default)
			)
			(layer "B.SilkS")
		)
		(fp_line
			(start -0.67945 -0.3048)
			(end -0.67945 0.3048)
			(stroke
				(width 0.1)
				(type default)
			)
			(layer "B.Fab")
		)
		(fp_line
			(start -0.67945 0.3048)
			(end -0.120396 0.3048)
			(stroke
				(width 0.1)
				(type default)
			)
			(layer "B.Fab")
		)
		(fp_line
			(start -0.12065 -0.3048)
			(end -0.67945 -0.3048)
			(stroke
				(width 0.1)
				(type default)
			)
			(layer "B.Fab")
		)
		(fp_line
			(start -0.12065 -0.2794)
			(end -0.12065 -0.3048)
			(stroke
				(width 0.1)
				(type default)
			)
			(layer "B.Fab")
		)
		(fp_line
			(start -0.120396 0.2794)
			(end 0.12065 0.2794)
			(stroke
				(width 0.1)
				(type default)
			)
			(layer "B.Fab")
		)
		(fp_line
			(start -0.120396 0.3048)
			(end -0.120396 0.2794)
			(stroke
				(width 0.1)
				(type default)
			)
			(layer "B.Fab")
		)
		(fp_line
			(start 0.12065 -0.305054)
			(end 0.12065 -0.2794)
			(stroke
				(width 0.1)
				(type default)
			)
			(layer "B.Fab")
		)
		(fp_line
			(start 0.12065 -0.2794)
			(end -0.12065 -0.2794)
			(stroke
				(width 0.1)
				(type default)
			)
			(layer "B.Fab")
		)
		(fp_line
			(start 0.12065 0.2794)
			(end 0.12065 0.3048)
			(stroke
				(width 0.1)
				(type default)
			)
			(layer "B.Fab")
		)
		(fp_line
			(start 0.12065 0.3048)
			(end 0.67945 0.3048)
			(stroke
				(width 0.1)
				(type default)
			)
			(layer "B.Fab")
		)
		(fp_line
			(start 0.67945 -0.305054)
			(end 0.12065 -0.305054)
			(stroke
				(width 0.1)
				(type default)
			)
			(layer "B.Fab")
		)
		(fp_line
			(start 0.67945 0.3048)
			(end 0.67945 -0.305054)
			(stroke
				(width 0.1)
				(type default)
			)
			(layer "B.Fab")
		)
		(pad "1" smd circle
			(at 0.40005 0 180)
			(size 0 0)
			(layers "B.Cu" "B.Mask" "B.Paste")
			(net "PVDD11_S3_P1")
		)
		(pad "2" smd circle
			(at -0.40005 0 180)
			(size 0 0)
			(layers "B.Cu" "B.Mask" "B.Paste")
			(net "GND")
		)
	)
	(footprint ""
		(layer "B.Cu")
		(at 121.579386 -269.307564 180)
		(property "Reference" "C2353"
			(at 0 0 0)
			(layer "B.SilkS")
			(hide yes)
			(effects
				(font
					(size 1.27 1.27)
				)
				(justify mirror)
			)
		)
		(property "Value" ""
			(at 0 0 0)
			(layer "B.Fab")
			(effects
				(font
					(size 1.27 1.27)
				)
				(justify mirror)
			)
		)
		(duplicate_pad_numbers_are_jumpers no)
		(fp_line
			(start 0.7874 0.4064)
			(end 0.7874 -0.4064)
			(stroke
				(width 0.1524)
				(type default)
			)
			(layer "B.SilkS")
		)
		(fp_line
			(start 0.7874 -0.4064)
			(end -0.7874 -0.4064)
			(stroke
				(width 0.1524)
				(type default)
			)
			(layer "B.SilkS")
		)
		(fp_line
			(start -0.7874 0.4064)
			(end 0.7874 0.4064)
			(stroke
				(width 0.1524)
				(type default)
			)
			(layer "B.SilkS")
		)
		(fp_line
			(start -0.7874 -0.4064)
			(end -0.7874 0.4064)
			(stroke
				(width 0.1524)
				(type default)
			)
			(layer "B.SilkS")
		)
		(fp_line
			(start 0.67945 0.3048)
			(end 0.67945 -0.305054)
			(stroke
				(width 0.1)
				(type default)
			)
			(layer "B.Fab")
		)
		(fp_line
			(start 0.67945 -0.305054)
			(end 0.12065 -0.305054)
			(stroke
				(width 0.1)
				(type default)
			)
			(layer "B.Fab")
		)
		(fp_line
			(start 0.12065 0.3048)
			(end 0.67945 0.3048)
			(stroke
				(width 0.1)
				(type default)
			)
			(layer "B.Fab")
		)
		(fp_line
			(start 0.12065 0.2794)
			(end 0.12065 0.3048)
			(stroke
				(width 0.1)
				(type default)
			)
			(layer "B.Fab")
		)
		(fp_line
			(start 0.12065 -0.2794)
			(end -0.12065 -0.2794)
			(stroke
				(width 0.1)
				(type default)
			)
			(layer "B.Fab")
		)
		(fp_line
			(start 0.12065 -0.305054)
			(end 0.12065 -0.2794)
			(stroke
				(width 0.1)
				(type default)
			)
			(layer "B.Fab")
		)
		(fp_line
			(start -0.120396 0.3048)
			(end -0.120396 0.2794)
			(stroke
				(width 0.1)
				(type default)
			)
			(layer "B.Fab")
		)
		(fp_line
			(start -0.120396 0.2794)
			(end 0.12065 0.2794)
			(stroke
				(width 0.1)
				(type default)
			)
			(layer "B.Fab")
		)
		(fp_line
			(start -0.12065 -0.2794)
			(end -0.12065 -0.3048)
			(stroke
				(width 0.1)
				(type default)
			)
			(layer "B.Fab")
		)
		(fp_line
			(start -0.12065 -0.3048)
			(end -0.67945 -0.3048)
			(stroke
				(width 0.1)
				(type default)
			)
			(layer "B.Fab")
		)
		(fp_line
			(start -0.67945 0.3048)
			(end -0.120396 0.3048)
			(stroke
				(width 0.1)
				(type default)
			)
			(layer "B.Fab")
		)
		(fp_line
			(start -0.67945 -0.3048)
			(end -0.67945 0.3048)
			(stroke
				(width 0.1)
				(type default)
			)
			(layer "B.Fab")
		)
		(pad "1" smd circle
			(at 0.40005 0)
			(size 0 0)
			(layers "B.Cu" "B.Mask" "B.Paste")
			(net "PVDDCR_CPU1_P1")
		)
		(pad "2" smd circle
			(at -0.40005 0)
			(size 0 0)
			(layers "B.Cu" "B.Mask" "B.Paste")
			(net "GND")
		)
	)
	(footprint ""
		(layer "B.Cu")
		(at 48.43653 -346.788994 90)
		(property "Reference" "PC449_2"
			(at 0 0 90)
			(layer "B.SilkS")
			(hide yes)
			(effects
				(font
					(size 1.27 1.27)
				)
				(justify mirror)
			)
		)
		(property "Value" ""
			(at 0 0 90)
			(layer "B.Fab")
			(effects
				(font
					(size 1.27 1.27)
				)
				(justify mirror)
			)
		)
		(duplicate_pad_numbers_are_jumpers no)
		(fp_line
			(start 1.524 -0.762)
			(end -1.524 -0.762)
			(stroke
				(width 0.1524)
				(type default)
			)
			(layer "B.SilkS")
		)
		(fp_line
			(start -1.524 -0.762)
			(end -1.524 0.762)
			(stroke
				(width 0.1524)
				(type default)
			)
			(layer "B.SilkS")
		)
		(fp_line
			(start 1.524 0.762)
			(end 1.524 -0.762)
			(stroke
				(width 0.1524)
				(type default)
			)
			(layer "B.SilkS")
		)
		(fp_line
			(start -1.524 0.762)
			(end 1.524 0.762)
			(stroke
				(width 0.1524)
				(type default)
			)
			(layer "B.SilkS")
		)
		(fp_line
			(start 1.1049 -0.724916)
			(end 1.1049 0.724916)
			(stroke
				(width 0.1)
				(type default)
			)
			(layer "B.Fab")
		)
		(fp_line
			(start -1.1049 -0.724916)
			(end 1.1049 -0.724916)
			(stroke
				(width 0.1)
				(type default)
			)
			(layer "B.Fab")
		)
		(fp_line
			(start 1.1049 0.724916)
			(end -1.1049 0.724916)
			(stroke
				(width 0.1)
				(type default)
			)
			(layer "B.Fab")
		)
		(fp_line
			(start -1.1049 0.724916)
			(end -1.1049 -0.724916)
			(stroke
				(width 0.1)
				(type default)
			)
			(layer "B.Fab")
		)
		(pad "1" smd rect
			(at 0.889 0 90)
			(size 1.016 1.27)
			(layers "B.Cu" "B.Mask" "B.Paste")
			(net "SW_P12V_AUX_PVDDIO_P1_FLT")
		)
		(pad "2" smd rect
			(at -0.889 0 90)
			(size 1.016 1.27)
			(layers "B.Cu" "B.Mask" "B.Paste")
			(net "GND")
		)
	)
	(footprint ""
		(layer "B.Cu")
		(at 314.965588 7.622794 180)
		(property "Reference" "J114"
			(at 4.525264 -1.200404 270)
			(unlocked yes)
			(layer "B.SilkS")
			(effects
				(font
					(size 0.7874 0.5842)
					(thickness 0.1524)
				)
				(justify left mirror)
			)
		)
		(property "Value" ""
			(at 0 0 0)
			(layer "B.Fab")
			(effects
				(font
					(size 1.27 1.27)
				)
				(justify mirror)
			)
		)
		(duplicate_pad_numbers_are_jumpers no)
		(fp_line
			(start 1.2192 2.06756)
			(end 1.2192 -2.06756)
			(stroke
				(width 0.1524)
				(type default)
			)
			(layer "B.SilkS")
		)
		(fp_line
			(start 1.2192 -2.06756)
			(end -1.2192 -2.06756)
			(stroke
				(width 0.1524)
				(type default)
			)
			(layer "B.SilkS")
		)
		(fp_line
			(start -1.2192 2.06756)
			(end 1.2192 2.06756)
			(stroke
				(width 0.1524)
				(type default)
			)
			(layer "B.SilkS")
		)
		(fp_line
			(start -1.2192 -2.06756)
			(end -1.2192 2.06756)
			(stroke
				(width 0.1524)
				(type default)
			)
			(layer "B.SilkS")
		)
		(pad "" np_thru_hole circle
			(at -3.4671 -1.27 90)
			(size 1.0414 1.0414)
			(drill 1.0414)
			(layers "*.Cu" "*.Mask")
			(clearance 0.381)
			(thermal_gap 0.381)
		)
		(pad "" np_thru_hole circle
			(at -3.4671 1.27 90)
			(size 1.0414 1.0414)
			(drill 1.0414)
			(layers "*.Cu" "*.Mask")
			(clearance 0.381)
			(thermal_gap 0.381)
		)
		(pad "" np_thru_hole circle
			(at 2.8829 -1.27 90)
			(size 1.0414 1.0414)
			(drill 1.0414)
			(layers "*.Cu" "*.Mask")
			(clearance 0.381)
			(thermal_gap 0.381)
		)
		(pad "" np_thru_hole circle
			(at 2.8829 1.27 90)
			(size 1.0414 1.0414)
			(drill 1.0414)
			(layers "*.Cu" "*.Mask")
			(clearance 0.381)
			(thermal_gap 0.381)
		)
		(pad "1" smd rect
			(at -0.8255 -0.249936 90)
			(size 0.3048 0.508)
			(layers "B.Cu" "B.Mask" "B.Paste")
			(net "DELTA_L_85_5INCH_IN5_DP")
		)
		(pad "2" smd rect
			(at -0.8255 0.249936 90)
			(size 0.3048 0.508)
			(layers "B.Cu" "B.Mask" "B.Paste")
			(net "DELTA_L_85_5INCH_IN5_DN")
		)
		(pad "3" smd circle
			(at 0 0)
			(size 0 0)
			(layers "B.Cu" "B.Mask" "B.Paste")
			(net "DELTA_L_GND_1")
		)
		(zone
			(layers "F.Cu" "B.Cu" "In1.Cu" "In2.Cu" "In3.Cu" "In4.Cu" "In5.Cu" "In6.Cu"
				"In7.Cu" "In8.Cu" "In9.Cu" "In10.Cu" "In11.Cu" "In12.Cu" "In13.Cu" "In14.Cu"
				"In15.Cu" "In16.Cu"
			)
			(hatch none 0.5)
			(connect_pads
				(clearance 0)
			)
			(min_thickness 0.25)
			(keepout
				(tracks not_allowed)
				(vias allowed)
				(pads allowed)
				(copperpour not_allowed)
				(footprints allowed)
			)
			(placement
				(enabled no)
				(sheetname "")
			)
			(fill
				(thermal_gap 0.5)
				(thermal_bridge_width 0.5)
				(island_removal_mode 0)
			)
			(polygon
				(pts
					(arc
						(start 313.009788 6.352794)
						(mid 311.155588 6.352794)
						(end 313.009788 6.352794)
					)
				)
			)
		)
		(zone
			(layers "F.Cu" "B.Cu" "In1.Cu" "In2.Cu" "In3.Cu" "In4.Cu" "In5.Cu" "In6.Cu"
				"In7.Cu" "In8.Cu" "In9.Cu" "In10.Cu" "In11.Cu" "In12.Cu" "In13.Cu" "In14.Cu"
				"In15.Cu" "In16.Cu"
			)
			(hatch none 0.5)
			(connect_pads
				(clearance 0)
			)
			(min_thickness 0.25)
			(keepout
				(tracks not_allowed)
				(vias allowed)
				(pads allowed)
				(copperpour not_allowed)
				(footprints allowed)
			)
			(placement
				(enabled no)
				(sheetname "")
			)
			(fill
				(thermal_gap 0.5)
				(thermal_bridge_width 0.5)
				(island_removal_mode 0)
			)
			(polygon
				(pts
					(arc
						(start 313.009788 8.892794)
						(mid 311.155588 8.892794)
						(end 313.009788 8.892794)
					)
				)
			)
		)
		(zone
			(layers "F.Cu" "B.Cu" "In1.Cu" "In2.Cu" "In3.Cu" "In4.Cu" "In5.Cu" "In6.Cu"
				"In7.Cu" "In8.Cu" "In9.Cu" "In10.Cu" "In11.Cu" "In12.Cu" "In13.Cu" "In14.Cu"
				"In15.Cu" "In16.Cu"
			)
			(hatch none 0.5)
			(connect_pads
				(clearance 0)
			)
			(min_thickness 0.25)
			(keepout
				(tracks not_allowed)
				(vias allowed)
				(pads allowed)
				(copperpour not_allowed)
				(footprints allowed)
			)
			(placement
				(enabled no)
				(sheetname "")
			)
			(fill
				(thermal_gap 0.5)
				(thermal_bridge_width 0.5)
				(island_removal_mode 0)
			)
			(polygon
				(pts
					(arc
						(start 319.359788 6.352794)
						(mid 317.505588 6.352794)
						(end 319.359788 6.352794)
					)
				)
			)
		)
		(zone
			(layers "F.Cu" "B.Cu" "In1.Cu" "In2.Cu" "In3.Cu" "In4.Cu" "In5.Cu" "In6.Cu"
				"In7.Cu" "In8.Cu" "In9.Cu" "In10.Cu" "In11.Cu" "In12.Cu" "In13.Cu" "In14.Cu"
				"In15.Cu" "In16.Cu"
			)
			(hatch none 0.5)
			(connect_pads
				(clearance 0)
			)
			(min_thickness 0.25)
			(keepout
				(tracks not_allowed)
				(vias allowed)
				(pads allowed)
				(copperpour not_allowed)
				(footprints allowed)
			)
			(placement
				(enabled no)
				(sheetname "")
			)
			(fill
				(thermal_gap 0.5)
				(thermal_bridge_width 0.5)
				(island_removal_mode 0)
			)
			(polygon
				(pts
					(arc
						(start 319.359788 8.892794)
						(mid 317.505588 8.892794)
						(end 319.359788 8.892794)
					)
				)
			)
		)
		(zone
			(layer "B.Cu")
			(hatch none 0.5)
			(connect_pads
				(clearance 0)
			)
			(min_thickness 0.25)
			(keepout
				(tracks not_allowed)
				(vias allowed)
				(pads allowed)
				(copperpour not_allowed)
				(footprints allowed)
			)
			(placement
				(enabled no)
				(sheetname "")
			)
			(fill
				(thermal_gap 0.5)
				(thermal_bridge_width 0.5)
				(island_removal_mode 0)
			)
			(polygon
				(pts
					(xy 316.083188 8.171434) (xy 316.083188 8.07593) (xy 315.486288 8.07593) (xy 315.486288 7.66953)
					(xy 316.083188 7.66953) (xy 316.083188 7.576058) (xy 315.486288 7.576058) (xy 315.486288 7.169658)
					(xy 316.083188 7.169658) (xy 316.083188 7.074154) (xy 315.384688 7.074154) (xy 315.384688 8.171434)
				)
			)
		)
	)
	(footprint ""
		(layer "B.Cu")
		(at 47.518574 -388.011162 -90)
		(property "Reference" "C282"
			(at 0 0 90)
			(layer "B.SilkS")
			(hide yes)
			(effects
				(font
					(size 1.27 1.27)
				)
				(justify mirror)
			)
		)
		(property "Value" ""
			(at 0 0 90)
			(layer "B.Fab")
			(effects
				(font
					(size 1.27 1.27)
				)
				(justify mirror)
			)
		)
		(duplicate_pad_numbers_are_jumpers no)
		(fp_line
			(start -0.299974 0.150114)
			(end 0.299974 0.150114)
			(stroke
				(width 0.1)
				(type default)
			)
			(layer "B.Fab")
		)
		(fp_line
			(start 0.299974 0.150114)
			(end 0.299974 -0.150114)
			(stroke
				(width 0.1)
				(type default)
			)
			(layer "B.Fab")
		)
		(fp_line
			(start -0.299974 -0.150114)
			(end -0.299974 0.150114)
			(stroke
				(width 0.1)
				(type default)
			)
			(layer "B.Fab")
		)
		(fp_line
			(start 0.299974 -0.150114)
			(end -0.299974 -0.150114)
			(stroke
				(width 0.1)
				(type default)
			)
			(layer "B.Fab")
		)
		(pad "1" smd rect
			(at 0.2667 0 90)
			(size 0.3048 0.381)
			(layers "B.Cu" "B.Mask" "B.Paste")
			(net "P0V9_CPU1_RT0_2A")
		)
		(pad "2" smd rect
			(at -0.2667 0 90)
			(size 0.3048 0.381)
			(layers "B.Cu" "B.Mask" "B.Paste")
			(net "GND")
		)
	)
	(footprint ""
		(layer "B.Cu")
		(at 162.46983 -17.79016 180)
		(property "Reference" "R4149"
			(at 0 0 0)
			(layer "B.SilkS")
			(hide yes)
			(effects
				(font
					(size 1.27 1.27)
				)
				(justify mirror)
			)
		)
		(property "Value" ""
			(at 0 0 0)
			(layer "B.Fab")
			(effects
				(font
					(size 1.27 1.27)
				)
				(justify mirror)
			)
		)
		(duplicate_pad_numbers_are_jumpers no)
		(fp_line
			(start 0.7874 0.4064)
			(end 0.7874 -0.4064)
			(stroke
				(width 0.1524)
				(type default)
			)
			(layer "B.SilkS")
		)
		(fp_line
			(start 0.7874 -0.4064)
			(end -0.7874 -0.4064)
			(stroke
				(width 0.1524)
				(type default)
			)
			(layer "B.SilkS")
		)
		(fp_line
			(start -0.7874 0.4064)
			(end 0.7874 0.4064)
			(stroke
				(width 0.1524)
				(type default)
			)
			(layer "B.SilkS")
		)
		(fp_line
			(start -0.7874 -0.4064)
			(end -0.7874 0.4064)
			(stroke
				(width 0.1524)
				(type default)
			)
			(layer "B.SilkS")
		)
		(fp_line
			(start 0.67945 0.3048)
			(end 0.67945 -0.305054)
			(stroke
				(width 0.1)
				(type default)
			)
			(layer "B.Fab")
		)
		(fp_line
			(start 0.67945 -0.305054)
			(end 0.12065 -0.305054)
			(stroke
				(width 0.1)
				(type default)
			)
			(layer "B.Fab")
		)
		(fp_line
			(start 0.12065 0.3048)
			(end 0.67945 0.3048)
			(stroke
				(width 0.1)
				(type default)
			)
			(layer "B.Fab")
		)
		(fp_line
			(start 0.12065 0.2794)
			(end 0.12065 0.3048)
			(stroke
				(width 0.1)
				(type default)
			)
			(layer "B.Fab")
		)
		(fp_line
			(start 0.12065 -0.2794)
			(end -0.12065 -0.2794)
			(stroke
				(width 0.1)
				(type default)
			)
			(layer "B.Fab")
		)
		(fp_line
			(start 0.12065 -0.305054)
			(end 0.12065 -0.2794)
			(stroke
				(width 0.1)
				(type default)
			)
			(layer "B.Fab")
		)
		(fp_line
			(start -0.120396 0.3048)
			(end -0.120396 0.2794)
			(stroke
				(width 0.1)
				(type default)
			)
			(layer "B.Fab")
		)
		(fp_line
			(start -0.120396 0.2794)
			(end 0.12065 0.2794)
			(stroke
				(width 0.1)
				(type default)
			)
			(layer "B.Fab")
		)
		(fp_line
			(start -0.12065 -0.2794)
			(end -0.12065 -0.3048)
			(stroke
				(width 0.1)
				(type default)
			)
			(layer "B.Fab")
		)
		(fp_line
			(start -0.12065 -0.3048)
			(end -0.67945 -0.3048)
			(stroke
				(width 0.1)
				(type default)
			)
			(layer "B.Fab")
		)
		(fp_line
			(start -0.67945 0.3048)
			(end -0.120396 0.3048)
			(stroke
				(width 0.1)
				(type default)
			)
			(layer "B.Fab")
		)
		(fp_line
			(start -0.67945 -0.3048)
			(end -0.67945 0.3048)
			(stroke
				(width 0.1)
				(type default)
			)
			(layer "B.Fab")
		)
		(pad "1" smd circle
			(at 0.40005 0)
			(size 0 0)
			(layers "B.Cu" "B.Mask" "B.Paste")
			(net "SMB_1_PLD_3V3AUX_SCL")
		)
		(pad "2" smd circle
			(at -0.40005 0)
			(size 0 0)
			(layers "B.Cu" "B.Mask" "B.Paste")
			(net "SMB_1_PLD_3V3AUX_SCL_R1")
		)
	)
	(footprint ""
		(layer "B.Cu")
		(at 352.501454 -266.00531)
		(property "Reference" "C3933"
			(at 0 0 0)
			(layer "B.SilkS")
			(hide yes)
			(effects
				(font
					(size 1.27 1.27)
				)
				(justify mirror)
			)
		)
		(property "Value" ""
			(at 0 0 0)
			(layer "B.Fab")
			(effects
				(font
					(size 1.27 1.27)
				)
				(justify mirror)
			)
		)
		(duplicate_pad_numbers_are_jumpers no)
		(fp_line
			(start -0.7874 -0.4064)
			(end -0.7874 0.4064)
			(stroke
				(width 0.1524)
				(type default)
			)
			(layer "B.SilkS")
		)
		(fp_line
			(start -0.7874 0.4064)
			(end 0.7874 0.4064)
			(stroke
				(width 0.1524)
				(type default)
			)
			(layer "B.SilkS")
		)
		(fp_line
			(start 0.7874 -0.4064)
			(end -0.7874 -0.4064)
			(stroke
				(width 0.1524)
				(type default)
			)
			(layer "B.SilkS")
		)
		(fp_line
			(start 0.7874 0.4064)
			(end 0.7874 -0.4064)
			(stroke
				(width 0.1524)
				(type default)
			)
			(layer "B.SilkS")
		)
		(fp_line
			(start -0.67945 -0.3048)
			(end -0.67945 0.3048)
			(stroke
				(width 0.1)
				(type default)
			)
			(layer "B.Fab")
		)
		(fp_line
			(start -0.67945 0.3048)
			(end -0.120396 0.3048)
			(stroke
				(width 0.1)
				(type default)
			)
			(layer "B.Fab")
		)
		(fp_line
			(start -0.12065 -0.3048)
			(end -0.67945 -0.3048)
			(stroke
				(width 0.1)
				(type default)
			)
			(layer "B.Fab")
		)
		(fp_line
			(start -0.12065 -0.2794)
			(end -0.12065 -0.3048)
			(stroke
				(width 0.1)
				(type default)
			)
			(layer "B.Fab")
		)
		(fp_line
			(start -0.120396 0.2794)
			(end 0.12065 0.2794)
			(stroke
				(width 0.1)
				(type default)
			)
			(layer "B.Fab")
		)
		(fp_line
			(start -0.120396 0.3048)
			(end -0.120396 0.2794)
			(stroke
				(width 0.1)
				(type default)
			)
			(layer "B.Fab")
		)
		(fp_line
			(start 0.12065 -0.305054)
			(end 0.12065 -0.2794)
			(stroke
				(width 0.1)
				(type default)
			)
			(layer "B.Fab")
		)
		(fp_line
			(start 0.12065 -0.2794)
			(end -0.12065 -0.2794)
			(stroke
				(width 0.1)
				(type default)
			)
			(layer "B.Fab")
		)
		(fp_line
			(start 0.12065 0.2794)
			(end 0.12065 0.3048)
			(stroke
				(width 0.1)
				(type default)
			)
			(layer "B.Fab")
		)
		(fp_line
			(start 0.12065 0.3048)
			(end 0.67945 0.3048)
			(stroke
				(width 0.1)
				(type default)
			)
			(layer "B.Fab")
		)
		(fp_line
			(start 0.67945 -0.305054)
			(end 0.12065 -0.305054)
			(stroke
				(width 0.1)
				(type default)
			)
			(layer "B.Fab")
		)
		(fp_line
			(start 0.67945 0.3048)
			(end 0.67945 -0.305054)
			(stroke
				(width 0.1)
				(type default)
			)
			(layer "B.Fab")
		)
		(pad "1" smd circle
			(at 0.40005 0 180)
			(size 0 0)
			(layers "B.Cu" "B.Mask" "B.Paste")
			(net "PVDD11_S3_P0")
		)
		(pad "2" smd circle
			(at -0.40005 0 180)
			(size 0 0)
			(layers "B.Cu" "B.Mask" "B.Paste")
			(net "GND")
		)
	)
	(footprint ""
		(layer "B.Cu")
		(at 243.816378 -315.95568 -90)
		(property "Reference" "PC6508"
			(at 0 0 90)
			(layer "B.SilkS")
			(hide yes)
			(effects
				(font
					(size 1.27 1.27)
				)
				(justify mirror)
			)
		)
		(property "Value" ""
			(at 0 0 90)
			(layer "B.Fab")
			(effects
				(font
					(size 1.27 1.27)
				)
				(justify mirror)
			)
		)
		(duplicate_pad_numbers_are_jumpers no)
		(fp_line
			(start -1.524 0.762)
			(end 1.524 0.762)
			(stroke
				(width 0.1524)
				(type default)
			)
			(layer "B.SilkS")
		)
		(fp_line
			(start 1.524 0.762)
			(end 1.524 -0.762)
			(stroke
				(width 0.1524)
				(type default)
			)
			(layer "B.SilkS")
		)
		(fp_line
			(start -1.524 -0.762)
			(end -1.524 0.762)
			(stroke
				(width 0.1524)
				(type default)
			)
			(layer "B.SilkS")
		)
		(fp_line
			(start 1.524 -0.762)
			(end -1.524 -0.762)
			(stroke
				(width 0.1524)
				(type default)
			)
			(layer "B.SilkS")
		)
		(fp_line
			(start -1.1049 0.724916)
			(end -1.1049 -0.724916)
			(stroke
				(width 0.1)
				(type default)
			)
			(layer "B.Fab")
		)
		(fp_line
			(start 1.1049 0.724916)
			(end -1.1049 0.724916)
			(stroke
				(width 0.1)
				(type default)
			)
			(layer "B.Fab")
		)
		(fp_line
			(start -1.1049 -0.724916)
			(end 1.1049 -0.724916)
			(stroke
				(width 0.1)
				(type default)
			)
			(layer "B.Fab")
		)
		(fp_line
			(start 1.1049 -0.724916)
			(end 1.1049 0.724916)
			(stroke
				(width 0.1)
				(type default)
			)
			(layer "B.Fab")
		)
		(pad "1" smd rect
			(at 0.889 0 270)
			(size 1.016 1.27)
			(layers "B.Cu" "B.Mask" "B.Paste")
			(net "P1V8_CPU0_RT_1D")
		)
		(pad "2" smd rect
			(at -0.889 0 270)
			(size 1.016 1.27)
			(layers "B.Cu" "B.Mask" "B.Paste")
			(net "GND")
		)
	)
	(footprint ""
		(layer "B.Cu")
		(at 119.293386 -253.432564)
		(property "Reference" "C2280"
			(at 0 0 0)
			(layer "B.SilkS")
			(hide yes)
			(effects
				(font
					(size 1.27 1.27)
				)
				(justify mirror)
			)
		)
		(property "Value" ""
			(at 0 0 0)
			(layer "B.Fab")
			(effects
				(font
					(size 1.27 1.27)
				)
				(justify mirror)
			)
		)
		(duplicate_pad_numbers_are_jumpers no)
		(fp_line
			(start -0.7874 -0.4064)
			(end -0.7874 0.4064)
			(stroke
				(width 0.1524)
				(type default)
			)
			(layer "B.SilkS")
		)
		(fp_line
			(start -0.7874 0.4064)
			(end 0.7874 0.4064)
			(stroke
				(width 0.1524)
				(type default)
			)
			(layer "B.SilkS")
		)
		(fp_line
			(start 0.7874 -0.4064)
			(end -0.7874 -0.4064)
			(stroke
				(width 0.1524)
				(type default)
			)
			(layer "B.SilkS")
		)
		(fp_line
			(start 0.7874 0.4064)
			(end 0.7874 -0.4064)
			(stroke
				(width 0.1524)
				(type default)
			)
			(layer "B.SilkS")
		)
		(fp_line
			(start -0.67945 -0.3048)
			(end -0.67945 0.3048)
			(stroke
				(width 0.1)
				(type default)
			)
			(layer "B.Fab")
		)
		(fp_line
			(start -0.67945 0.3048)
			(end -0.120396 0.3048)
			(stroke
				(width 0.1)
				(type default)
			)
			(layer "B.Fab")
		)
		(fp_line
			(start -0.12065 -0.3048)
			(end -0.67945 -0.3048)
			(stroke
				(width 0.1)
				(type default)
			)
			(layer "B.Fab")
		)
		(fp_line
			(start -0.12065 -0.2794)
			(end -0.12065 -0.3048)
			(stroke
				(width 0.1)
				(type default)
			)
			(layer "B.Fab")
		)
		(fp_line
			(start -0.120396 0.2794)
			(end 0.12065 0.2794)
			(stroke
				(width 0.1)
				(type default)
			)
			(layer "B.Fab")
		)
		(fp_line
			(start -0.120396 0.3048)
			(end -0.120396 0.2794)
			(stroke
				(width 0.1)
				(type default)
			)
			(layer "B.Fab")
		)
		(fp_line
			(start 0.12065 -0.305054)
			(end 0.12065 -0.2794)
			(stroke
				(width 0.1)
				(type default)
			)
			(layer "B.Fab")
		)
		(fp_line
			(start 0.12065 -0.2794)
			(end -0.12065 -0.2794)
			(stroke
				(width 0.1)
				(type default)
			)
			(layer "B.Fab")
		)
		(fp_line
			(start 0.12065 0.2794)
			(end 0.12065 0.3048)
			(stroke
				(width 0.1)
				(type default)
			)
			(layer "B.Fab")
		)
		(fp_line
			(start 0.12065 0.3048)
			(end 0.67945 0.3048)
			(stroke
				(width 0.1)
				(type default)
			)
			(layer "B.Fab")
		)
		(fp_line
			(start 0.67945 -0.305054)
			(end 0.12065 -0.305054)
			(stroke
				(width 0.1)
				(type default)
			)
			(layer "B.Fab")
		)
		(fp_line
			(start 0.67945 0.3048)
			(end 0.67945 -0.305054)
			(stroke
				(width 0.1)
				(type default)
			)
			(layer "B.Fab")
		)
		(pad "1" smd circle
			(at 0.40005 0 180)
			(size 0 0)
			(layers "B.Cu" "B.Mask" "B.Paste")
			(net "PVDDCR_SOC_P1")
		)
		(pad "2" smd circle
			(at -0.40005 0 180)
			(size 0 0)
			(layers "B.Cu" "B.Mask" "B.Paste")
			(net "GND")
		)
	)
	(footprint ""
		(layer "B.Cu")
		(at 185.458608 -118.242842 90)
		(property "Reference" "C1134"
			(at 0 0 90)
			(layer "B.SilkS")
			(hide yes)
			(effects
				(font
					(size 1.27 1.27)
				)
				(justify mirror)
			)
		)
		(property "Value" ""
			(at 0 0 90)
			(layer "B.Fab")
			(effects
				(font
					(size 1.27 1.27)
				)
				(justify mirror)
			)
		)
		(duplicate_pad_numbers_are_jumpers no)
		(fp_line
			(start 0.69215 -0.2921)
			(end -0.69215 -0.2921)
			(stroke
				(width 0.1524)
				(type default)
			)
			(layer "B.SilkS")
		)
		(fp_line
			(start -0.69215 -0.2921)
			(end -0.69215 0.2921)
			(stroke
				(width 0.1524)
				(type default)
			)
			(layer "B.SilkS")
		)
		(fp_line
			(start 0.69215 0.2921)
			(end 0.69215 -0.2921)
			(stroke
				(width 0.1524)
				(type default)
			)
			(layer "B.SilkS")
		)
		(fp_line
			(start -0.69215 0.2921)
			(end 0.69215 0.2921)
			(stroke
				(width 0.1524)
				(type default)
			)
			(layer "B.SilkS")
		)
		(fp_line
			(start 0.51435 -0.2794)
			(end -0.51435 -0.2794)
			(stroke
				(width 0.1)
				(type default)
			)
			(layer "B.Fab")
		)
		(fp_line
			(start -0.51435 -0.2794)
			(end -0.51435 0.2794)
			(stroke
				(width 0.1)
				(type default)
			)
			(layer "B.Fab")
		)
		(fp_line
			(start 0.51435 0.2794)
			(end 0.51435 -0.2794)
			(stroke
				(width 0.1)
				(type default)
			)
			(layer "B.Fab")
		)
		(fp_line
			(start -0.51435 0.2794)
			(end 0.51435 0.2794)
			(stroke
				(width 0.1)
				(type default)
			)
			(layer "B.Fab")
		)
		(pad "1" smd circle
			(at 0.40005 0 270)
			(size 0 0)
			(layers "B.Cu" "B.Mask" "B.Paste")
			(net "P1V8_AUX")
		)
		(pad "2" smd circle
			(at -0.40005 0 270)
			(size 0 0)
			(layers "B.Cu" "B.Mask" "B.Paste")
			(net "GND")
		)
		(zone
			(layer "B.Cu")
			(hatch none 0.5)
			(connect_pads
				(clearance 0)
			)
			(min_thickness 0.25)
			(keepout
				(tracks not_allowed)
				(vias allowed)
				(pads allowed)
				(copperpour not_allowed)
				(footprints allowed)
			)
			(placement
				(enabled no)
				(sheetname "")
			)
			(fill
				(thermal_gap 0.5)
				(thermal_bridge_width 0.5)
				(island_removal_mode 0)
			)
			(polygon
				(pts
					(xy 185.312558 -118.142512) (xy 185.312558 -118.341902) (xy 185.370724 -118.433342) (xy 185.546238 -118.433342)
					(xy 185.604404 -118.341902) (xy 185.604404 -118.142512) (xy 185.546238 -118.052342) (xy 185.370978 -118.052342)
				)
			)
		)
	)
	(footprint ""
		(layer "B.Cu")
		(at 99.916234 -245.868952 -90)
		(property "Reference" "C2295"
			(at 0 0 90)
			(layer "B.SilkS")
			(hide yes)
			(effects
				(font
					(size 1.27 1.27)
				)
				(justify mirror)
			)
		)
		(property "Value" ""
			(at 0 0 90)
			(layer "B.Fab")
			(effects
				(font
					(size 1.27 1.27)
				)
				(justify mirror)
			)
		)
		(duplicate_pad_numbers_are_jumpers no)
		(fp_line
			(start -0.7874 0.4064)
			(end 0.7874 0.4064)
			(stroke
				(width 0.1524)
				(type default)
			)
			(layer "B.SilkS")
		)
		(fp_line
			(start 0.7874 0.4064)
			(end 0.7874 -0.4064)
			(stroke
				(width 0.1524)
				(type default)
			)
			(layer "B.SilkS")
		)
		(fp_line
			(start -0.7874 -0.4064)
			(end -0.7874 0.4064)
			(stroke
				(width 0.1524)
				(type default)
			)
			(layer "B.SilkS")
		)
		(fp_line
			(start 0.7874 -0.4064)
			(end -0.7874 -0.4064)
			(stroke
				(width 0.1524)
				(type default)
			)
			(layer "B.SilkS")
		)
		(fp_line
			(start -0.67945 0.3048)
			(end -0.120396 0.3048)
			(stroke
				(width 0.1)
				(type default)
			)
			(layer "B.Fab")
		)
		(fp_line
			(start -0.120396 0.3048)
			(end -0.120396 0.2794)
			(stroke
				(width 0.1)
				(type default)
			)
			(layer "B.Fab")
		)
		(fp_line
			(start 0.12065 0.3048)
			(end 0.67945 0.3048)
			(stroke
				(width 0.1)
				(type default)
			)
			(layer "B.Fab")
		)
		(fp_line
			(start 0.67945 0.3048)
			(end 0.67945 -0.305054)
			(stroke
				(width 0.1)
				(type default)
			)
			(layer "B.Fab")
		)
		(fp_line
			(start -0.120396 0.2794)
			(end 0.12065 0.2794)
			(stroke
				(width 0.1)
				(type default)
			)
			(layer "B.Fab")
		)
		(fp_line
			(start 0.12065 0.2794)
			(end 0.12065 0.3048)
			(stroke
				(width 0.1)
				(type default)
			)
			(layer "B.Fab")
		)
		(fp_line
			(start -0.12065 -0.2794)
			(end -0.12065 -0.3048)
			(stroke
				(width 0.1)
				(type default)
			)
			(layer "B.Fab")
		)
		(fp_line
			(start 0.12065 -0.2794)
			(end -0.12065 -0.2794)
			(stroke
				(width 0.1)
				(type default)
			)
			(layer "B.Fab")
		)
		(fp_line
			(start -0.67945 -0.3048)
			(end -0.67945 0.3048)
			(stroke
				(width 0.1)
				(type default)
			)
			(layer "B.Fab")
		)
		(fp_line
			(start -0.12065 -0.3048)
			(end -0.67945 -0.3048)
			(stroke
				(width 0.1)
				(type default)
			)
			(layer "B.Fab")
		)
		(fp_line
			(start 0.12065 -0.305054)
			(end 0.12065 -0.2794)
			(stroke
				(width 0.1)
				(type default)
			)
			(layer "B.Fab")
		)
		(fp_line
			(start 0.67945 -0.305054)
			(end 0.12065 -0.305054)
			(stroke
				(width 0.1)
				(type default)
			)
			(layer "B.Fab")
		)
		(pad "1" smd circle
			(at 0.40005 0 90)
			(size 0 0)
			(layers "B.Cu" "B.Mask" "B.Paste")
			(net "PVDDCR_CPU0_P1")
		)
		(pad "2" smd circle
			(at -0.40005 0 90)
			(size 0 0)
			(layers "B.Cu" "B.Mask" "B.Paste")
			(net "GND")
		)
	)
	(footprint ""
		(layer "B.Cu")
		(at 367.233454 -251.78131)
		(property "Reference" "C3896"
			(at 0 0 0)
			(layer "B.SilkS")
			(hide yes)
			(effects
				(font
					(size 1.27 1.27)
				)
				(justify mirror)
			)
		)
		(property "Value" ""
			(at 0 0 0)
			(layer "B.Fab")
			(effects
				(font
					(size 1.27 1.27)
				)
				(justify mirror)
			)
		)
		(duplicate_pad_numbers_are_jumpers no)
		(fp_line
			(start -0.7874 -0.4064)
			(end -0.7874 0.4064)
			(stroke
				(width 0.1524)
				(type default)
			)
			(layer "B.SilkS")
		)
		(fp_line
			(start -0.7874 0.4064)
			(end 0.7874 0.4064)
			(stroke
				(width 0.1524)
				(type default)
			)
			(layer "B.SilkS")
		)
		(fp_line
			(start 0.7874 -0.4064)
			(end -0.7874 -0.4064)
			(stroke
				(width 0.1524)
				(type default)
			)
			(layer "B.SilkS")
		)
		(fp_line
			(start 0.7874 0.4064)
			(end 0.7874 -0.4064)
			(stroke
				(width 0.1524)
				(type default)
			)
			(layer "B.SilkS")
		)
		(fp_line
			(start -0.67945 -0.3048)
			(end -0.67945 0.3048)
			(stroke
				(width 0.1)
				(type default)
			)
			(layer "B.Fab")
		)
		(fp_line
			(start -0.67945 0.3048)
			(end -0.120396 0.3048)
			(stroke
				(width 0.1)
				(type default)
			)
			(layer "B.Fab")
		)
		(fp_line
			(start -0.12065 -0.3048)
			(end -0.67945 -0.3048)
			(stroke
				(width 0.1)
				(type default)
			)
			(layer "B.Fab")
		)
		(fp_line
			(start -0.12065 -0.2794)
			(end -0.12065 -0.3048)
			(stroke
				(width 0.1)
				(type default)
			)
			(layer "B.Fab")
		)
		(fp_line
			(start -0.120396 0.2794)
			(end 0.12065 0.2794)
			(stroke
				(width 0.1)
				(type default)
			)
			(layer "B.Fab")
		)
		(fp_line
			(start -0.120396 0.3048)
			(end -0.120396 0.2794)
			(stroke
				(width 0.1)
				(type default)
			)
			(layer "B.Fab")
		)
		(fp_line
			(start 0.12065 -0.305054)
			(end 0.12065 -0.2794)
			(stroke
				(width 0.1)
				(type default)
			)
			(layer "B.Fab")
		)
		(fp_line
			(start 0.12065 -0.2794)
			(end -0.12065 -0.2794)
			(stroke
				(width 0.1)
				(type default)
			)
			(layer "B.Fab")
		)
		(fp_line
			(start 0.12065 0.2794)
			(end 0.12065 0.3048)
			(stroke
				(width 0.1)
				(type default)
			)
			(layer "B.Fab")
		)
		(fp_line
			(start 0.12065 0.3048)
			(end 0.67945 0.3048)
			(stroke
				(width 0.1)
				(type default)
			)
			(layer "B.Fab")
		)
		(fp_line
			(start 0.67945 -0.305054)
			(end 0.12065 -0.305054)
			(stroke
				(width 0.1)
				(type default)
			)
			(layer "B.Fab")
		)
		(fp_line
			(start 0.67945 0.3048)
			(end 0.67945 -0.305054)
			(stroke
				(width 0.1)
				(type default)
			)
			(layer "B.Fab")
		)
		(pad "1" smd circle
			(at 0.40005 0 180)
			(size 0 0)
			(layers "B.Cu" "B.Mask" "B.Paste")
			(net "PVDDCR_SOC_P0")
		)
		(pad "2" smd circle
			(at -0.40005 0 180)
			(size 0 0)
			(layers "B.Cu" "B.Mask" "B.Paste")
			(net "GND")
		)
	)
	(footprint ""
		(layer "B.Cu")
		(at 191.271144 -79.05623 -90)
		(property "Reference" "R1290"
			(at 0 0 90)
			(layer "B.SilkS")
			(hide yes)
			(effects
				(font
					(size 1.27 1.27)
				)
				(justify mirror)
			)
		)
		(property "Value" ""
			(at 0 0 90)
			(layer "B.Fab")
			(effects
				(font
					(size 1.27 1.27)
				)
				(justify mirror)
			)
		)
		(duplicate_pad_numbers_are_jumpers no)
		(fp_line
			(start -0.7874 0.4064)
			(end 0.7874 0.4064)
			(stroke
				(width 0.1524)
				(type default)
			)
			(layer "B.SilkS")
		)
		(fp_line
			(start 0.7874 0.4064)
			(end 0.7874 -0.4064)
			(stroke
				(width 0.1524)
				(type default)
			)
			(layer "B.SilkS")
		)
		(fp_line
			(start -0.7874 -0.4064)
			(end -0.7874 0.4064)
			(stroke
				(width 0.1524)
				(type default)
			)
			(layer "B.SilkS")
		)
		(fp_line
			(start 0.7874 -0.4064)
			(end -0.7874 -0.4064)
			(stroke
				(width 0.1524)
				(type default)
			)
			(layer "B.SilkS")
		)
		(fp_line
			(start -0.67945 0.3048)
			(end -0.120396 0.3048)
			(stroke
				(width 0.1)
				(type default)
			)
			(layer "B.Fab")
		)
		(fp_line
			(start -0.120396 0.3048)
			(end -0.120396 0.2794)
			(stroke
				(width 0.1)
				(type default)
			)
			(layer "B.Fab")
		)
		(fp_line
			(start 0.12065 0.3048)
			(end 0.67945 0.3048)
			(stroke
				(width 0.1)
				(type default)
			)
			(layer "B.Fab")
		)
		(fp_line
			(start 0.67945 0.3048)
			(end 0.67945 -0.305054)
			(stroke
				(width 0.1)
				(type default)
			)
			(layer "B.Fab")
		)
		(fp_line
			(start -0.120396 0.2794)
			(end 0.12065 0.2794)
			(stroke
				(width 0.1)
				(type default)
			)
			(layer "B.Fab")
		)
		(fp_line
			(start 0.12065 0.2794)
			(end 0.12065 0.3048)
			(stroke
				(width 0.1)
				(type default)
			)
			(layer "B.Fab")
		)
		(fp_line
			(start -0.12065 -0.2794)
			(end -0.12065 -0.3048)
			(stroke
				(width 0.1)
				(type default)
			)
			(layer "B.Fab")
		)
		(fp_line
			(start 0.12065 -0.2794)
			(end -0.12065 -0.2794)
			(stroke
				(width 0.1)
				(type default)
			)
			(layer "B.Fab")
		)
		(fp_line
			(start -0.67945 -0.3048)
			(end -0.67945 0.3048)
			(stroke
				(width 0.1)
				(type default)
			)
			(layer "B.Fab")
		)
		(fp_line
			(start -0.12065 -0.3048)
			(end -0.67945 -0.3048)
			(stroke
				(width 0.1)
				(type default)
			)
			(layer "B.Fab")
		)
		(fp_line
			(start 0.12065 -0.305054)
			(end 0.12065 -0.2794)
			(stroke
				(width 0.1)
				(type default)
			)
			(layer "B.Fab")
		)
		(fp_line
			(start 0.67945 -0.305054)
			(end 0.12065 -0.305054)
			(stroke
				(width 0.1)
				(type default)
			)
			(layer "B.Fab")
		)
		(pad "1" smd circle
			(at 0.40005 0 90)
			(size 0 0)
			(layers "B.Cu" "B.Mask" "B.Paste")
			(net "OCP_SFF_RBT_ARB_IN_R")
		)
		(pad "2" smd circle
			(at -0.40005 0 90)
			(size 0 0)
			(layers "B.Cu" "B.Mask" "B.Paste")
			(net "OCP_SFF_RBT_ARB_IN")
		)
	)
	(footprint ""
		(layer "B.Cu")
		(at 215.0618 -341.884)
		(property "Reference" "R872"
			(at 0 0 0)
			(layer "B.SilkS")
			(hide yes)
			(effects
				(font
					(size 1.27 1.27)
				)
				(justify mirror)
			)
		)
		(property "Value" ""
			(at 0 0 0)
			(layer "B.Fab")
			(effects
				(font
					(size 1.27 1.27)
				)
				(justify mirror)
			)
		)
		(duplicate_pad_numbers_are_jumpers no)
		(fp_line
			(start -0.32512 -0.175006)
			(end -0.32512 0.175006)
			(stroke
				(width 0.1)
				(type default)
			)
			(layer "B.Fab")
		)
		(fp_line
			(start -0.32512 0.175006)
			(end 0.32512 0.175006)
			(stroke
				(width 0.1)
				(type default)
			)
			(layer "B.Fab")
		)
		(fp_line
			(start 0.32512 -0.175006)
			(end -0.32512 -0.175006)
			(stroke
				(width 0.1)
				(type default)
			)
			(layer "B.Fab")
		)
		(fp_line
			(start 0.32512 0.175006)
			(end 0.32512 -0.175006)
			(stroke
				(width 0.1)
				(type default)
			)
			(layer "B.Fab")
		)
		(pad "1" smd rect
			(at 0.2667 0 180)
			(size 0.3048 0.381)
			(layers "B.Cu" "B.Mask" "B.Paste")
			(net "SMB_RT_CPU1_P2_R_SCL")
		)
		(pad "2" smd rect
			(at -0.2667 0)
			(size 0.3048 0.381)
			(layers "B.Cu" "B.Mask" "B.Paste")
			(net "SMB_RT_CPU1_P2_R2_SCL")
		)
	)
	(footprint ""
		(layer "B.Cu")
		(at 311.791096 -398.942052 90)
		(property "Reference" "C510"
			(at 0 0 90)
			(layer "B.SilkS")
			(hide yes)
			(effects
				(font
					(size 1.27 1.27)
				)
				(justify mirror)
			)
		)
		(property "Value" ""
			(at 0 0 90)
			(layer "B.Fab")
			(effects
				(font
					(size 1.27 1.27)
				)
				(justify mirror)
			)
		)
		(duplicate_pad_numbers_are_jumpers no)
		(fp_line
			(start 0.7874 -0.4064)
			(end -0.7874 -0.4064)
			(stroke
				(width 0.1524)
				(type default)
			)
			(layer "B.SilkS")
		)
		(fp_line
			(start -0.7874 -0.4064)
			(end -0.7874 0.4064)
			(stroke
				(width 0.1524)
				(type default)
			)
			(layer "B.SilkS")
		)
		(fp_line
			(start 0.7874 0.4064)
			(end 0.7874 -0.4064)
			(stroke
				(width 0.1524)
				(type default)
			)
			(layer "B.SilkS")
		)
		(fp_line
			(start -0.7874 0.4064)
			(end 0.7874 0.4064)
			(stroke
				(width 0.1524)
				(type default)
			)
			(layer "B.SilkS")
		)
		(fp_line
			(start 0.67945 -0.305054)
			(end 0.12065 -0.305054)
			(stroke
				(width 0.1)
				(type default)
			)
			(layer "B.Fab")
		)
		(fp_line
			(start 0.12065 -0.305054)
			(end 0.12065 -0.2794)
			(stroke
				(width 0.1)
				(type default)
			)
			(layer "B.Fab")
		)
		(fp_line
			(start -0.12065 -0.3048)
			(end -0.67945 -0.3048)
			(stroke
				(width 0.1)
				(type default)
			)
			(layer "B.Fab")
		)
		(fp_line
			(start -0.67945 -0.3048)
			(end -0.67945 0.3048)
			(stroke
				(width 0.1)
				(type default)
			)
			(layer "B.Fab")
		)
		(fp_line
			(start 0.12065 -0.2794)
			(end -0.12065 -0.2794)
			(stroke
				(width 0.1)
				(type default)
			)
			(layer "B.Fab")
		)
		(fp_line
			(start -0.12065 -0.2794)
			(end -0.12065 -0.3048)
			(stroke
				(width 0.1)
				(type default)
			)
			(layer "B.Fab")
		)
		(fp_line
			(start 0.12065 0.2794)
			(end 0.12065 0.3048)
			(stroke
				(width 0.1)
				(type default)
			)
			(layer "B.Fab")
		)
		(fp_line
			(start -0.120396 0.2794)
			(end 0.12065 0.2794)
			(stroke
				(width 0.1)
				(type default)
			)
			(layer "B.Fab")
		)
		(fp_line
			(start 0.67945 0.3048)
			(end 0.67945 -0.305054)
			(stroke
				(width 0.1)
				(type default)
			)
			(layer "B.Fab")
		)
		(fp_line
			(start 0.12065 0.3048)
			(end 0.67945 0.3048)
			(stroke
				(width 0.1)
				(type default)
			)
			(layer "B.Fab")
		)
		(fp_line
			(start -0.120396 0.3048)
			(end -0.120396 0.2794)
			(stroke
				(width 0.1)
				(type default)
			)
			(layer "B.Fab")
		)
		(fp_line
			(start -0.67945 0.3048)
			(end -0.120396 0.3048)
			(stroke
				(width 0.1)
				(type default)
			)
			(layer "B.Fab")
		)
		(pad "1" smd circle
			(at 0.40005 0 270)
			(size 0 0)
			(layers "B.Cu" "B.Mask" "B.Paste")
			(net "P1V8_CPU0_RT0_1A")
		)
		(pad "2" smd circle
			(at -0.40005 0 270)
			(size 0 0)
			(layers "B.Cu" "B.Mask" "B.Paste")
			(net "GND")
		)
	)
	(footprint ""
		(layer "B.Cu")
		(at 270.645128 -244.08511 180)
		(property "Reference" "R380"
			(at 0 0 0)
			(layer "B.SilkS")
			(hide yes)
			(effects
				(font
					(size 1.27 1.27)
				)
				(justify mirror)
			)
		)
		(property "Value" ""
			(at 0 0 0)
			(layer "B.Fab")
			(effects
				(font
					(size 1.27 1.27)
				)
				(justify mirror)
			)
		)
		(duplicate_pad_numbers_are_jumpers no)
		(fp_line
			(start 0.7874 0.4064)
			(end 0.7874 -0.4064)
			(stroke
				(width 0.1524)
				(type default)
			)
			(layer "B.SilkS")
		)
		(fp_line
			(start 0.7874 -0.4064)
			(end -0.7874 -0.4064)
			(stroke
				(width 0.1524)
				(type default)
			)
			(layer "B.SilkS")
		)
		(fp_line
			(start -0.7874 0.4064)
			(end 0.7874 0.4064)
			(stroke
				(width 0.1524)
				(type default)
			)
			(layer "B.SilkS")
		)
		(fp_line
			(start -0.7874 -0.4064)
			(end -0.7874 0.4064)
			(stroke
				(width 0.1524)
				(type default)
			)
			(layer "B.SilkS")
		)
		(fp_line
			(start 0.67945 0.3048)
			(end 0.67945 -0.305054)
			(stroke
				(width 0.1)
				(type default)
			)
			(layer "B.Fab")
		)
		(fp_line
			(start 0.67945 -0.305054)
			(end 0.12065 -0.305054)
			(stroke
				(width 0.1)
				(type default)
			)
			(layer "B.Fab")
		)
		(fp_line
			(start 0.12065 0.3048)
			(end 0.67945 0.3048)
			(stroke
				(width 0.1)
				(type default)
			)
			(layer "B.Fab")
		)
		(fp_line
			(start 0.12065 0.2794)
			(end 0.12065 0.3048)
			(stroke
				(width 0.1)
				(type default)
			)
			(layer "B.Fab")
		)
		(fp_line
			(start 0.12065 -0.2794)
			(end -0.12065 -0.2794)
			(stroke
				(width 0.1)
				(type default)
			)
			(layer "B.Fab")
		)
		(fp_line
			(start 0.12065 -0.305054)
			(end 0.12065 -0.2794)
			(stroke
				(width 0.1)
				(type default)
			)
			(layer "B.Fab")
		)
		(fp_line
			(start -0.120396 0.3048)
			(end -0.120396 0.2794)
			(stroke
				(width 0.1)
				(type default)
			)
			(layer "B.Fab")
		)
		(fp_line
			(start -0.120396 0.2794)
			(end 0.12065 0.2794)
			(stroke
				(width 0.1)
				(type default)
			)
			(layer "B.Fab")
		)
		(fp_line
			(start -0.12065 -0.2794)
			(end -0.12065 -0.3048)
			(stroke
				(width 0.1)
				(type default)
			)
			(layer "B.Fab")
		)
		(fp_line
			(start -0.12065 -0.3048)
			(end -0.67945 -0.3048)
			(stroke
				(width 0.1)
				(type default)
			)
			(layer "B.Fab")
		)
		(fp_line
			(start -0.67945 0.3048)
			(end -0.120396 0.3048)
			(stroke
				(width 0.1)
				(type default)
			)
			(layer "B.Fab")
		)
		(fp_line
			(start -0.67945 -0.3048)
			(end -0.67945 0.3048)
			(stroke
				(width 0.1)
				(type default)
			)
			(layer "B.Fab")
		)
		(pad "1" smd circle
			(at 0.40005 0)
			(size 0 0)
			(layers "B.Cu" "B.Mask" "B.Paste")
			(net "M_F_CPU0_ALERT_N")
		)
		(pad "2" smd circle
			(at -0.40005 0)
			(size 0 0)
			(layers "B.Cu" "B.Mask" "B.Paste")
			(net "M_F_CPU0_ALERT_R_N")
		)
	)
	(footprint ""
		(layer "B.Cu")
		(at 154.577288 -8.68045 -90)
		(property "Reference" "R6069"
			(at 0 0 90)
			(layer "B.SilkS")
			(hide yes)
			(effects
				(font
					(size 1.27 1.27)
				)
				(justify mirror)
			)
		)
		(property "Value" ""
			(at 0 0 90)
			(layer "B.Fab")
			(effects
				(font
					(size 1.27 1.27)
				)
				(justify mirror)
			)
		)
		(duplicate_pad_numbers_are_jumpers no)
		(fp_line
			(start -0.7874 0.4064)
			(end 0.7874 0.4064)
			(stroke
				(width 0.1524)
				(type default)
			)
			(layer "B.SilkS")
		)
		(fp_line
			(start 0.7874 0.4064)
			(end 0.7874 -0.4064)
			(stroke
				(width 0.1524)
				(type default)
			)
			(layer "B.SilkS")
		)
		(fp_line
			(start -0.7874 -0.4064)
			(end -0.7874 0.4064)
			(stroke
				(width 0.1524)
				(type default)
			)
			(layer "B.SilkS")
		)
		(fp_line
			(start 0.7874 -0.4064)
			(end -0.7874 -0.4064)
			(stroke
				(width 0.1524)
				(type default)
			)
			(layer "B.SilkS")
		)
		(fp_line
			(start -0.67945 0.3048)
			(end -0.120396 0.3048)
			(stroke
				(width 0.1)
				(type default)
			)
			(layer "B.Fab")
		)
		(fp_line
			(start -0.120396 0.3048)
			(end -0.120396 0.2794)
			(stroke
				(width 0.1)
				(type default)
			)
			(layer "B.Fab")
		)
		(fp_line
			(start 0.12065 0.3048)
			(end 0.67945 0.3048)
			(stroke
				(width 0.1)
				(type default)
			)
			(layer "B.Fab")
		)
		(fp_line
			(start 0.67945 0.3048)
			(end 0.67945 -0.305054)
			(stroke
				(width 0.1)
				(type default)
			)
			(layer "B.Fab")
		)
		(fp_line
			(start -0.120396 0.2794)
			(end 0.12065 0.2794)
			(stroke
				(width 0.1)
				(type default)
			)
			(layer "B.Fab")
		)
		(fp_line
			(start 0.12065 0.2794)
			(end 0.12065 0.3048)
			(stroke
				(width 0.1)
				(type default)
			)
			(layer "B.Fab")
		)
		(fp_line
			(start -0.12065 -0.2794)
			(end -0.12065 -0.3048)
			(stroke
				(width 0.1)
				(type default)
			)
			(layer "B.Fab")
		)
		(fp_line
			(start 0.12065 -0.2794)
			(end -0.12065 -0.2794)
			(stroke
				(width 0.1)
				(type default)
			)
			(layer "B.Fab")
		)
		(fp_line
			(start -0.67945 -0.3048)
			(end -0.67945 0.3048)
			(stroke
				(width 0.1)
				(type default)
			)
			(layer "B.Fab")
		)
		(fp_line
			(start -0.12065 -0.3048)
			(end -0.67945 -0.3048)
			(stroke
				(width 0.1)
				(type default)
			)
			(layer "B.Fab")
		)
		(fp_line
			(start 0.12065 -0.305054)
			(end 0.12065 -0.2794)
			(stroke
				(width 0.1)
				(type default)
			)
			(layer "B.Fab")
		)
		(fp_line
			(start 0.67945 -0.305054)
			(end 0.12065 -0.305054)
			(stroke
				(width 0.1)
				(type default)
			)
			(layer "B.Fab")
		)
		(pad "1" smd rect
			(at 0.40005 0 270)
			(size 0.4572 0.508)
			(layers "B.Cu" "B.Mask" "B.Paste")
			(net "JTAG_SCM_TDI_R")
		)
		(pad "2" smd rect
			(at -0.40005 0 270)
			(size 0.4572 0.508)
			(layers "B.Cu" "B.Mask" "B.Paste")
			(net "JTAG_SCM_TDO")
		)
	)
	(footprint ""
		(layer "B.Cu")
		(at 375.331482 -147.741132 180)
		(property "Reference" "PC463"
			(at 0 0 0)
			(layer "B.SilkS")
			(hide yes)
			(effects
				(font
					(size 1.27 1.27)
				)
				(justify mirror)
			)
		)
		(property "Value" ""
			(at 0 0 0)
			(layer "B.Fab")
			(effects
				(font
					(size 1.27 1.27)
				)
				(justify mirror)
			)
		)
		(duplicate_pad_numbers_are_jumpers no)
		(fp_line
			(start 0.7874 0.4064)
			(end 0.7874 -0.4064)
			(stroke
				(width 0.1524)
				(type default)
			)
			(layer "B.SilkS")
		)
		(fp_line
			(start 0.7874 -0.4064)
			(end -0.7874 -0.4064)
			(stroke
				(width 0.1524)
				(type default)
			)
			(layer "B.SilkS")
		)
		(fp_line
			(start -0.7874 0.4064)
			(end 0.7874 0.4064)
			(stroke
				(width 0.1524)
				(type default)
			)
			(layer "B.SilkS")
		)
		(fp_line
			(start -0.7874 -0.4064)
			(end -0.7874 0.4064)
			(stroke
				(width 0.1524)
				(type default)
			)
			(layer "B.SilkS")
		)
		(fp_line
			(start 0.67945 0.3048)
			(end 0.67945 -0.305054)
			(stroke
				(width 0.1)
				(type default)
			)
			(layer "B.Fab")
		)
		(fp_line
			(start 0.67945 -0.305054)
			(end 0.12065 -0.305054)
			(stroke
				(width 0.1)
				(type default)
			)
			(layer "B.Fab")
		)
		(fp_line
			(start 0.12065 0.3048)
			(end 0.67945 0.3048)
			(stroke
				(width 0.1)
				(type default)
			)
			(layer "B.Fab")
		)
		(fp_line
			(start 0.12065 0.2794)
			(end 0.12065 0.3048)
			(stroke
				(width 0.1)
				(type default)
			)
			(layer "B.Fab")
		)
		(fp_line
			(start 0.12065 -0.2794)
			(end -0.12065 -0.2794)
			(stroke
				(width 0.1)
				(type default)
			)
			(layer "B.Fab")
		)
		(fp_line
			(start 0.12065 -0.305054)
			(end 0.12065 -0.2794)
			(stroke
				(width 0.1)
				(type default)
			)
			(layer "B.Fab")
		)
		(fp_line
			(start -0.120396 0.3048)
			(end -0.120396 0.2794)
			(stroke
				(width 0.1)
				(type default)
			)
			(layer "B.Fab")
		)
		(fp_line
			(start -0.120396 0.2794)
			(end 0.12065 0.2794)
			(stroke
				(width 0.1)
				(type default)
			)
			(layer "B.Fab")
		)
		(fp_line
			(start -0.12065 -0.2794)
			(end -0.12065 -0.3048)
			(stroke
				(width 0.1)
				(type default)
			)
			(layer "B.Fab")
		)
		(fp_line
			(start -0.12065 -0.3048)
			(end -0.67945 -0.3048)
			(stroke
				(width 0.1)
				(type default)
			)
			(layer "B.Fab")
		)
		(fp_line
			(start -0.67945 0.3048)
			(end -0.120396 0.3048)
			(stroke
				(width 0.1)
				(type default)
			)
			(layer "B.Fab")
		)
		(fp_line
			(start -0.67945 -0.3048)
			(end -0.67945 0.3048)
			(stroke
				(width 0.1)
				(type default)
			)
			(layer "B.Fab")
		)
		(pad "1" smd circle
			(at 0.40005 0)
			(size 0 0)
			(layers "B.Cu" "B.Mask" "B.Paste")
			(net "VSENSE_PVDDCR_CPU0_P0_VSEN0")
		)
		(pad "2" smd circle
			(at -0.40005 0)
			(size 0 0)
			(layers "B.Cu" "B.Mask" "B.Paste")
			(net "VSENSE_VSS_SENSE_A_P0")
		)
	)
	(footprint ""
		(layer "B.Cu")
		(at 359.740454 -246.06631 90)
		(property "Reference" "C251"
			(at 0 0 90)
			(layer "B.SilkS")
			(hide yes)
			(effects
				(font
					(size 1.27 1.27)
				)
				(justify mirror)
			)
		)
		(property "Value" ""
			(at 0 0 90)
			(layer "B.Fab")
			(effects
				(font
					(size 1.27 1.27)
				)
				(justify mirror)
			)
		)
		(duplicate_pad_numbers_are_jumpers no)
		(fp_line
			(start 0.7874 -0.4064)
			(end -0.7874 -0.4064)
			(stroke
				(width 0.1524)
				(type default)
			)
			(layer "B.SilkS")
		)
		(fp_line
			(start -0.7874 -0.4064)
			(end -0.7874 0.4064)
			(stroke
				(width 0.1524)
				(type default)
			)
			(layer "B.SilkS")
		)
		(fp_line
			(start 0.7874 0.4064)
			(end 0.7874 -0.4064)
			(stroke
				(width 0.1524)
				(type default)
			)
			(layer "B.SilkS")
		)
		(fp_line
			(start -0.7874 0.4064)
			(end 0.7874 0.4064)
			(stroke
				(width 0.1524)
				(type default)
			)
			(layer "B.SilkS")
		)
		(fp_line
			(start 0.67945 -0.305054)
			(end 0.12065 -0.305054)
			(stroke
				(width 0.1)
				(type default)
			)
			(layer "B.Fab")
		)
		(fp_line
			(start 0.12065 -0.305054)
			(end 0.12065 -0.2794)
			(stroke
				(width 0.1)
				(type default)
			)
			(layer "B.Fab")
		)
		(fp_line
			(start -0.12065 -0.3048)
			(end -0.67945 -0.3048)
			(stroke
				(width 0.1)
				(type default)
			)
			(layer "B.Fab")
		)
		(fp_line
			(start -0.67945 -0.3048)
			(end -0.67945 0.3048)
			(stroke
				(width 0.1)
				(type default)
			)
			(layer "B.Fab")
		)
		(fp_line
			(start 0.12065 -0.2794)
			(end -0.12065 -0.2794)
			(stroke
				(width 0.1)
				(type default)
			)
			(layer "B.Fab")
		)
		(fp_line
			(start -0.12065 -0.2794)
			(end -0.12065 -0.3048)
			(stroke
				(width 0.1)
				(type default)
			)
			(layer "B.Fab")
		)
		(fp_line
			(start 0.12065 0.2794)
			(end 0.12065 0.3048)
			(stroke
				(width 0.1)
				(type default)
			)
			(layer "B.Fab")
		)
		(fp_line
			(start -0.120396 0.2794)
			(end 0.12065 0.2794)
			(stroke
				(width 0.1)
				(type default)
			)
			(layer "B.Fab")
		)
		(fp_line
			(start 0.67945 0.3048)
			(end 0.67945 -0.305054)
			(stroke
				(width 0.1)
				(type default)
			)
			(layer "B.Fab")
		)
		(fp_line
			(start 0.12065 0.3048)
			(end 0.67945 0.3048)
			(stroke
				(width 0.1)
				(type default)
			)
			(layer "B.Fab")
		)
		(fp_line
			(start -0.120396 0.3048)
			(end -0.120396 0.2794)
			(stroke
				(width 0.1)
				(type default)
			)
			(layer "B.Fab")
		)
		(fp_line
			(start -0.67945 0.3048)
			(end -0.120396 0.3048)
			(stroke
				(width 0.1)
				(type default)
			)
			(layer "B.Fab")
		)
		(pad "1" smd circle
			(at 0.40005 0 270)
			(size 0 0)
			(layers "B.Cu" "B.Mask" "B.Paste")
			(net "PVDDCR_CPU0_P0")
		)
		(pad "2" smd circle
			(at -0.40005 0 270)
			(size 0 0)
			(layers "B.Cu" "B.Mask" "B.Paste")
			(net "GND")
		)
	)
	(footprint ""
		(layer "B.Cu")
		(at 176.072292 -192.66027)
		(property "Reference" "C533"
			(at 0 0 0)
			(layer "B.SilkS")
			(hide yes)
			(effects
				(font
					(size 1.27 1.27)
				)
				(justify mirror)
			)
		)
		(property "Value" ""
			(at 0 0 0)
			(layer "B.Fab")
			(effects
				(font
					(size 1.27 1.27)
				)
				(justify mirror)
			)
		)
		(duplicate_pad_numbers_are_jumpers no)
		(fp_line
			(start -1.524 -0.762)
			(end -1.524 0.762)
			(stroke
				(width 0.1524)
				(type default)
			)
			(layer "B.SilkS")
		)
		(fp_line
			(start -1.524 0.762)
			(end 1.524 0.762)
			(stroke
				(width 0.1524)
				(type default)
			)
			(layer "B.SilkS")
		)
		(fp_line
			(start 1.524 -0.762)
			(end -1.524 -0.762)
			(stroke
				(width 0.1524)
				(type default)
			)
			(layer "B.SilkS")
		)
		(fp_line
			(start 1.524 0.762)
			(end 1.524 -0.762)
			(stroke
				(width 0.1524)
				(type default)
			)
			(layer "B.SilkS")
		)
		(fp_line
			(start -1.1049 -0.724916)
			(end 1.1049 -0.724916)
			(stroke
				(width 0.1)
				(type default)
			)
			(layer "B.Fab")
		)
		(fp_line
			(start -1.1049 0.724916)
			(end -1.1049 -0.724916)
			(stroke
				(width 0.1)
				(type default)
			)
			(layer "B.Fab")
		)
		(fp_line
			(start 1.1049 -0.724916)
			(end 1.1049 0.724916)
			(stroke
				(width 0.1)
				(type default)
			)
			(layer "B.Fab")
		)
		(fp_line
			(start 1.1049 0.724916)
			(end -1.1049 0.724916)
			(stroke
				(width 0.1)
				(type default)
			)
			(layer "B.Fab")
		)
		(pad "1" smd rect
			(at 0.889 0)
			(size 1.016 1.27)
			(layers "B.Cu" "B.Mask" "B.Paste")
			(net "P12V_MEM_CPU1")
		)
		(pad "2" smd rect
			(at -0.889 0)
			(size 1.016 1.27)
			(layers "B.Cu" "B.Mask" "B.Paste")
			(net "GND")
		)
	)
	(footprint ""
		(layer "B.Cu")
		(at 333.945992 -395.43228)
		(property "Reference" "C620"
			(at 0 0 0)
			(layer "B.SilkS")
			(hide yes)
			(effects
				(font
					(size 1.27 1.27)
				)
				(justify mirror)
			)
		)
		(property "Value" ""
			(at 0 0 0)
			(layer "B.Fab")
			(effects
				(font
					(size 1.27 1.27)
				)
				(justify mirror)
			)
		)
		(duplicate_pad_numbers_are_jumpers no)
		(fp_line
			(start -0.299974 -0.150114)
			(end -0.299974 0.150114)
			(stroke
				(width 0.1)
				(type default)
			)
			(layer "B.Fab")
		)
		(fp_line
			(start -0.299974 0.150114)
			(end 0.299974 0.150114)
			(stroke
				(width 0.1)
				(type default)
			)
			(layer "B.Fab")
		)
		(fp_line
			(start 0.299974 -0.150114)
			(end -0.299974 -0.150114)
			(stroke
				(width 0.1)
				(type default)
			)
			(layer "B.Fab")
		)
		(fp_line
			(start 0.299974 0.150114)
			(end 0.299974 -0.150114)
			(stroke
				(width 0.1)
				(type default)
			)
			(layer "B.Fab")
		)
		(pad "1" smd rect
			(at 0.2667 0 180)
			(size 0.3048 0.381)
			(layers "B.Cu" "B.Mask" "B.Paste")
			(net "P0V9_CPU0_RT1_2A")
		)
		(pad "2" smd rect
			(at -0.2667 0 180)
			(size 0.3048 0.381)
			(layers "B.Cu" "B.Mask" "B.Paste")
			(net "GND")
		)
	)
	(footprint ""
		(layer "B.Cu")
		(at 51.734974 -416.929316)
		(property "Reference" "C2076"
			(at 0 0 0)
			(layer "B.SilkS")
			(hide yes)
			(effects
				(font
					(size 1.27 1.27)
				)
				(justify mirror)
			)
		)
		(property "Value" ""
			(at 0 0 0)
			(layer "B.Fab")
			(effects
				(font
					(size 1.27 1.27)
				)
				(justify mirror)
			)
		)
		(duplicate_pad_numbers_are_jumpers no)
		(fp_line
			(start -0.299974 -0.150114)
			(end -0.299974 0.150114)
			(stroke
				(width 0.1)
				(type default)
			)
			(layer "B.Fab")
		)
		(fp_line
			(start -0.299974 0.150114)
			(end 0.299974 0.150114)
			(stroke
				(width 0.1)
				(type default)
			)
			(layer "B.Fab")
		)
		(fp_line
			(start 0.299974 -0.150114)
			(end -0.299974 -0.150114)
			(stroke
				(width 0.1)
				(type default)
			)
			(layer "B.Fab")
		)
		(fp_line
			(start 0.299974 0.150114)
			(end 0.299974 -0.150114)
			(stroke
				(width 0.1)
				(type default)
			)
			(layer "B.Fab")
		)
		(pad "1" smd rect
			(at 0.2667 0 180)
			(size 0.3048 0.381)
			(layers "B.Cu" "B.Mask" "B.Paste")
			(net "P3E_CPU1_P5_TX_C_DN<0>")
		)
		(pad "2" smd rect
			(at -0.2667 0 180)
			(size 0.3048 0.381)
			(layers "B.Cu" "B.Mask" "B.Paste")
			(net "P3E_CPU1_P5_TX_DN<0>")
		)
	)
	(footprint ""
		(layer "B.Cu")
		(at 138.65352 -38.733222 180)
		(property "Reference" "C6058"
			(at 0 0 0)
			(layer "B.SilkS")
			(hide yes)
			(effects
				(font
					(size 1.27 1.27)
				)
				(justify mirror)
			)
		)
		(property "Value" ""
			(at 0 0 0)
			(layer "B.Fab")
			(effects
				(font
					(size 1.27 1.27)
				)
				(justify mirror)
			)
		)
		(duplicate_pad_numbers_are_jumpers no)
		(fp_line
			(start 0.7874 0.4064)
			(end 0.7874 -0.4064)
			(stroke
				(width 0.1524)
				(type default)
			)
			(layer "B.SilkS")
		)
		(fp_line
			(start 0.7874 -0.4064)
			(end -0.7874 -0.4064)
			(stroke
				(width 0.1524)
				(type default)
			)
			(layer "B.SilkS")
		)
		(fp_line
			(start -0.7874 0.4064)
			(end 0.7874 0.4064)
			(stroke
				(width 0.1524)
				(type default)
			)
			(layer "B.SilkS")
		)
		(fp_line
			(start -0.7874 -0.4064)
			(end -0.7874 0.4064)
			(stroke
				(width 0.1524)
				(type default)
			)
			(layer "B.SilkS")
		)
		(fp_line
			(start 0.67945 0.3048)
			(end 0.67945 -0.305054)
			(stroke
				(width 0.1)
				(type default)
			)
			(layer "B.Fab")
		)
		(fp_line
			(start 0.67945 -0.305054)
			(end 0.12065 -0.305054)
			(stroke
				(width 0.1)
				(type default)
			)
			(layer "B.Fab")
		)
		(fp_line
			(start 0.12065 0.3048)
			(end 0.67945 0.3048)
			(stroke
				(width 0.1)
				(type default)
			)
			(layer "B.Fab")
		)
		(fp_line
			(start 0.12065 0.2794)
			(end 0.12065 0.3048)
			(stroke
				(width 0.1)
				(type default)
			)
			(layer "B.Fab")
		)
		(fp_line
			(start 0.12065 -0.2794)
			(end -0.12065 -0.2794)
			(stroke
				(width 0.1)
				(type default)
			)
			(layer "B.Fab")
		)
		(fp_line
			(start 0.12065 -0.305054)
			(end 0.12065 -0.2794)
			(stroke
				(width 0.1)
				(type default)
			)
			(layer "B.Fab")
		)
		(fp_line
			(start -0.120396 0.3048)
			(end -0.120396 0.2794)
			(stroke
				(width 0.1)
				(type default)
			)
			(layer "B.Fab")
		)
		(fp_line
			(start -0.120396 0.2794)
			(end 0.12065 0.2794)
			(stroke
				(width 0.1)
				(type default)
			)
			(layer "B.Fab")
		)
		(fp_line
			(start -0.12065 -0.2794)
			(end -0.12065 -0.3048)
			(stroke
				(width 0.1)
				(type default)
			)
			(layer "B.Fab")
		)
		(fp_line
			(start -0.12065 -0.3048)
			(end -0.67945 -0.3048)
			(stroke
				(width 0.1)
				(type default)
			)
			(layer "B.Fab")
		)
		(fp_line
			(start -0.67945 0.3048)
			(end -0.120396 0.3048)
			(stroke
				(width 0.1)
				(type default)
			)
			(layer "B.Fab")
		)
		(fp_line
			(start -0.67945 -0.3048)
			(end -0.67945 0.3048)
			(stroke
				(width 0.1)
				(type default)
			)
			(layer "B.Fab")
		)
		(pad "1" smd circle
			(at 0.40005 0)
			(size 0 0)
			(layers "B.Cu" "B.Mask" "B.Paste")
			(net "P1V2_AUX")
		)
		(pad "2" smd circle
			(at -0.40005 0)
			(size 0 0)
			(layers "B.Cu" "B.Mask" "B.Paste")
			(net "GND")
		)
	)
	(footprint ""
		(layer "B.Cu")
		(at 74.5236 -385.58216 180)
		(property "Reference" "R784"
			(at 0 0 0)
			(layer "B.SilkS")
			(hide yes)
			(effects
				(font
					(size 1.27 1.27)
				)
				(justify mirror)
			)
		)
		(property "Value" ""
			(at 0 0 0)
			(layer "B.Fab")
			(effects
				(font
					(size 1.27 1.27)
				)
				(justify mirror)
			)
		)
		(duplicate_pad_numbers_are_jumpers no)
		(fp_line
			(start 0.32512 0.175006)
			(end 0.32512 -0.175006)
			(stroke
				(width 0.1)
				(type default)
			)
			(layer "B.Fab")
		)
		(fp_line
			(start 0.32512 -0.175006)
			(end -0.32512 -0.175006)
			(stroke
				(width 0.1)
				(type default)
			)
			(layer "B.Fab")
		)
		(fp_line
			(start -0.32512 0.175006)
			(end 0.32512 0.175006)
			(stroke
				(width 0.1)
				(type default)
			)
			(layer "B.Fab")
		)
		(fp_line
			(start -0.32512 -0.175006)
			(end -0.32512 0.175006)
			(stroke
				(width 0.1)
				(type default)
			)
			(layer "B.Fab")
		)
		(pad "1" smd rect
			(at 0.2667 0)
			(size 0.3048 0.381)
			(layers "B.Cu" "B.Mask" "B.Paste")
			(net "P1V8_CPU1_RT_1D")
		)
		(pad "2" smd rect
			(at -0.2667 0 180)
			(size 0.3048 0.381)
			(layers "B.Cu" "B.Mask" "B.Paste")
			(net "TEST0_RT_CPU1_P1")
		)
	)
	(footprint ""
		(layer "B.Cu")
		(at 43.576748 -195.901564 180)
		(property "Reference" "R1697"
			(at 0 0 0)
			(layer "B.SilkS")
			(hide yes)
			(effects
				(font
					(size 1.27 1.27)
				)
				(justify mirror)
			)
		)
		(property "Value" ""
			(at 0 0 0)
			(layer "B.Fab")
			(effects
				(font
					(size 1.27 1.27)
				)
				(justify mirror)
			)
		)
		(duplicate_pad_numbers_are_jumpers no)
		(fp_line
			(start 0.7874 0.4064)
			(end 0.7874 -0.4064)
			(stroke
				(width 0.1524)
				(type default)
			)
			(layer "B.SilkS")
		)
		(fp_line
			(start 0.7874 -0.4064)
			(end -0.7874 -0.4064)
			(stroke
				(width 0.1524)
				(type default)
			)
			(layer "B.SilkS")
		)
		(fp_line
			(start -0.7874 0.4064)
			(end 0.7874 0.4064)
			(stroke
				(width 0.1524)
				(type default)
			)
			(layer "B.SilkS")
		)
		(fp_line
			(start -0.7874 -0.4064)
			(end -0.7874 0.4064)
			(stroke
				(width 0.1524)
				(type default)
			)
			(layer "B.SilkS")
		)
		(fp_line
			(start 0.67945 0.3048)
			(end 0.67945 -0.305054)
			(stroke
				(width 0.1)
				(type default)
			)
			(layer "B.Fab")
		)
		(fp_line
			(start 0.67945 -0.305054)
			(end 0.12065 -0.305054)
			(stroke
				(width 0.1)
				(type default)
			)
			(layer "B.Fab")
		)
		(fp_line
			(start 0.12065 0.3048)
			(end 0.67945 0.3048)
			(stroke
				(width 0.1)
				(type default)
			)
			(layer "B.Fab")
		)
		(fp_line
			(start 0.12065 0.2794)
			(end 0.12065 0.3048)
			(stroke
				(width 0.1)
				(type default)
			)
			(layer "B.Fab")
		)
		(fp_line
			(start 0.12065 -0.2794)
			(end -0.12065 -0.2794)
			(stroke
				(width 0.1)
				(type default)
			)
			(layer "B.Fab")
		)
		(fp_line
			(start 0.12065 -0.305054)
			(end 0.12065 -0.2794)
			(stroke
				(width 0.1)
				(type default)
			)
			(layer "B.Fab")
		)
		(fp_line
			(start -0.120396 0.3048)
			(end -0.120396 0.2794)
			(stroke
				(width 0.1)
				(type default)
			)
			(layer "B.Fab")
		)
		(fp_line
			(start -0.120396 0.2794)
			(end 0.12065 0.2794)
			(stroke
				(width 0.1)
				(type default)
			)
			(layer "B.Fab")
		)
		(fp_line
			(start -0.12065 -0.2794)
			(end -0.12065 -0.3048)
			(stroke
				(width 0.1)
				(type default)
			)
			(layer "B.Fab")
		)
		(fp_line
			(start -0.12065 -0.3048)
			(end -0.67945 -0.3048)
			(stroke
				(width 0.1)
				(type default)
			)
			(layer "B.Fab")
		)
		(fp_line
			(start -0.67945 0.3048)
			(end -0.120396 0.3048)
			(stroke
				(width 0.1)
				(type default)
			)
			(layer "B.Fab")
		)
		(fp_line
			(start -0.67945 -0.3048)
			(end -0.67945 0.3048)
			(stroke
				(width 0.1)
				(type default)
			)
			(layer "B.Fab")
		)
		(pad "1" smd circle
			(at 0.40005 0)
			(size 0 0)
			(layers "B.Cu" "B.Mask" "B.Paste")
			(net "I3C_SPD_DDRAF_CPU1_SDA")
		)
		(pad "2" smd circle
			(at -0.40005 0)
			(size 0 0)
			(layers "B.Cu" "B.Mask" "B.Paste")
			(net "I3C_SPD_DDRC_CPU1_SDA")
		)
	)
	(footprint ""
		(layer "B.Cu")
		(at 273.092164 -192.660016 180)
		(property "Reference" "C153"
			(at 0 0 0)
			(layer "B.SilkS")
			(hide yes)
			(effects
				(font
					(size 1.27 1.27)
				)
				(justify mirror)
			)
		)
		(property "Value" ""
			(at 0 0 0)
			(layer "B.Fab")
			(effects
				(font
					(size 1.27 1.27)
				)
				(justify mirror)
			)
		)
		(duplicate_pad_numbers_are_jumpers no)
		(fp_line
			(start 1.524 0.762)
			(end 1.524 -0.762)
			(stroke
				(width 0.1524)
				(type default)
			)
			(layer "B.SilkS")
		)
		(fp_line
			(start 1.524 -0.762)
			(end -1.524 -0.762)
			(stroke
				(width 0.1524)
				(type default)
			)
			(layer "B.SilkS")
		)
		(fp_line
			(start -1.524 0.762)
			(end 1.524 0.762)
			(stroke
				(width 0.1524)
				(type default)
			)
			(layer "B.SilkS")
		)
		(fp_line
			(start -1.524 -0.762)
			(end -1.524 0.762)
			(stroke
				(width 0.1524)
				(type default)
			)
			(layer "B.SilkS")
		)
		(fp_line
			(start 1.1049 0.724916)
			(end -1.1049 0.724916)
			(stroke
				(width 0.1)
				(type default)
			)
			(layer "B.Fab")
		)
		(fp_line
			(start 1.1049 -0.724916)
			(end 1.1049 0.724916)
			(stroke
				(width 0.1)
				(type default)
			)
			(layer "B.Fab")
		)
		(fp_line
			(start -1.1049 0.724916)
			(end -1.1049 -0.724916)
			(stroke
				(width 0.1)
				(type default)
			)
			(layer "B.Fab")
		)
		(fp_line
			(start -1.1049 -0.724916)
			(end 1.1049 -0.724916)
			(stroke
				(width 0.1)
				(type default)
			)
			(layer "B.Fab")
		)
		(pad "1" smd rect
			(at 0.889 0 180)
			(size 1.016 1.27)
			(layers "B.Cu" "B.Mask" "B.Paste")
			(net "P12V_MEM_CPU0")
		)
		(pad "2" smd rect
			(at -0.889 0 180)
			(size 1.016 1.27)
			(layers "B.Cu" "B.Mask" "B.Paste")
			(net "GND")
		)
	)
	(footprint ""
		(layer "B.Cu")
		(at 412.367984 -192.660016 180)
		(property "Reference" "C157"
			(at 0 0 0)
			(layer "B.SilkS")
			(hide yes)
			(effects
				(font
					(size 1.27 1.27)
				)
				(justify mirror)
			)
		)
		(property "Value" ""
			(at 0 0 0)
			(layer "B.Fab")
			(effects
				(font
					(size 1.27 1.27)
				)
				(justify mirror)
			)
		)
		(duplicate_pad_numbers_are_jumpers no)
		(fp_line
			(start 1.524 0.762)
			(end 1.524 -0.762)
			(stroke
				(width 0.1524)
				(type default)
			)
			(layer "B.SilkS")
		)
		(fp_line
			(start 1.524 -0.762)
			(end -1.524 -0.762)
			(stroke
				(width 0.1524)
				(type default)
			)
			(layer "B.SilkS")
		)
		(fp_line
			(start -1.524 0.762)
			(end 1.524 0.762)
			(stroke
				(width 0.1524)
				(type default)
			)
			(layer "B.SilkS")
		)
		(fp_line
			(start -1.524 -0.762)
			(end -1.524 0.762)
			(stroke
				(width 0.1524)
				(type default)
			)
			(layer "B.SilkS")
		)
		(fp_line
			(start 1.1049 0.724916)
			(end -1.1049 0.724916)
			(stroke
				(width 0.1)
				(type default)
			)
			(layer "B.Fab")
		)
		(fp_line
			(start 1.1049 -0.724916)
			(end 1.1049 0.724916)
			(stroke
				(width 0.1)
				(type default)
			)
			(layer "B.Fab")
		)
		(fp_line
			(start -1.1049 0.724916)
			(end -1.1049 -0.724916)
			(stroke
				(width 0.1)
				(type default)
			)
			(layer "B.Fab")
		)
		(fp_line
			(start -1.1049 -0.724916)
			(end 1.1049 -0.724916)
			(stroke
				(width 0.1)
				(type default)
			)
			(layer "B.Fab")
		)
		(pad "1" smd rect
			(at 0.889 0 180)
			(size 1.016 1.27)
			(layers "B.Cu" "B.Mask" "B.Paste")
			(net "P12V_MEM_CPU0")
		)
		(pad "2" smd rect
			(at -0.889 0 180)
			(size 1.016 1.27)
			(layers "B.Cu" "B.Mask" "B.Paste")
			(net "GND")
		)
	)
	(footprint ""
		(layer "B.Cu")
		(at 199.941942 -344.270584)
		(property "Reference" "PC8001"
			(at 0 0 0)
			(layer "B.SilkS")
			(hide yes)
			(effects
				(font
					(size 1.27 1.27)
				)
				(justify mirror)
			)
		)
		(property "Value" ""
			(at 0 0 0)
			(layer "B.Fab")
			(effects
				(font
					(size 1.27 1.27)
				)
				(justify mirror)
			)
		)
		(duplicate_pad_numbers_are_jumpers no)
		(fp_line
			(start -1.524 -0.762)
			(end -1.524 0.762)
			(stroke
				(width 0.1524)
				(type default)
			)
			(layer "B.SilkS")
		)
		(fp_line
			(start -1.524 0.762)
			(end 1.524 0.762)
			(stroke
				(width 0.1524)
				(type default)
			)
			(layer "B.SilkS")
		)
		(fp_line
			(start 1.524 -0.762)
			(end -1.524 -0.762)
			(stroke
				(width 0.1524)
				(type default)
			)
			(layer "B.SilkS")
		)
		(fp_line
			(start 1.524 0.762)
			(end 1.524 -0.762)
			(stroke
				(width 0.1524)
				(type default)
			)
			(layer "B.SilkS")
		)
		(fp_line
			(start -1.1049 -0.724916)
			(end 1.1049 -0.724916)
			(stroke
				(width 0.1)
				(type default)
			)
			(layer "B.Fab")
		)
		(fp_line
			(start -1.1049 0.724916)
			(end -1.1049 -0.724916)
			(stroke
				(width 0.1)
				(type default)
			)
			(layer "B.Fab")
		)
		(fp_line
			(start 1.1049 -0.724916)
			(end 1.1049 0.724916)
			(stroke
				(width 0.1)
				(type default)
			)
			(layer "B.Fab")
		)
		(fp_line
			(start 1.1049 0.724916)
			(end -1.1049 0.724916)
			(stroke
				(width 0.1)
				(type default)
			)
			(layer "B.Fab")
		)
		(pad "1" smd rect
			(at 0.889 0)
			(size 1.016 1.27)
			(layers "B.Cu" "B.Mask" "B.Paste")
			(net "SW_P12V_AUX_PVDD_33_S5_FLT")
		)
		(pad "2" smd rect
			(at -0.889 0)
			(size 1.016 1.27)
			(layers "B.Cu" "B.Mask" "B.Paste")
			(net "GND")
		)
	)
	(footprint ""
		(layer "B.Cu")
		(at 391.72007 -181.684676 90)
		(property "Reference" "PR345"
			(at 0 0 90)
			(layer "B.SilkS")
			(hide yes)
			(effects
				(font
					(size 1.27 1.27)
				)
				(justify mirror)
			)
		)
		(property "Value" ""
			(at 0 0 90)
			(layer "B.Fab")
			(effects
				(font
					(size 1.27 1.27)
				)
				(justify mirror)
			)
		)
		(duplicate_pad_numbers_are_jumpers no)
		(fp_line
			(start 0.7874 -0.4064)
			(end -0.7874 -0.4064)
			(stroke
				(width 0.1524)
				(type default)
			)
			(layer "B.SilkS")
		)
		(fp_line
			(start -0.7874 -0.4064)
			(end -0.7874 0.4064)
			(stroke
				(width 0.1524)
				(type default)
			)
			(layer "B.SilkS")
		)
		(fp_line
			(start 0.7874 0.4064)
			(end 0.7874 -0.4064)
			(stroke
				(width 0.1524)
				(type default)
			)
			(layer "B.SilkS")
		)
		(fp_line
			(start -0.7874 0.4064)
			(end 0.7874 0.4064)
			(stroke
				(width 0.1524)
				(type default)
			)
			(layer "B.SilkS")
		)
		(fp_line
			(start 0.67945 -0.305054)
			(end 0.12065 -0.305054)
			(stroke
				(width 0.1)
				(type default)
			)
			(layer "B.Fab")
		)
		(fp_line
			(start 0.12065 -0.305054)
			(end 0.12065 -0.2794)
			(stroke
				(width 0.1)
				(type default)
			)
			(layer "B.Fab")
		)
		(fp_line
			(start -0.12065 -0.3048)
			(end -0.67945 -0.3048)
			(stroke
				(width 0.1)
				(type default)
			)
			(layer "B.Fab")
		)
		(fp_line
			(start -0.67945 -0.3048)
			(end -0.67945 0.3048)
			(stroke
				(width 0.1)
				(type default)
			)
			(layer "B.Fab")
		)
		(fp_line
			(start 0.12065 -0.2794)
			(end -0.12065 -0.2794)
			(stroke
				(width 0.1)
				(type default)
			)
			(layer "B.Fab")
		)
		(fp_line
			(start -0.12065 -0.2794)
			(end -0.12065 -0.3048)
			(stroke
				(width 0.1)
				(type default)
			)
			(layer "B.Fab")
		)
		(fp_line
			(start 0.12065 0.2794)
			(end 0.12065 0.3048)
			(stroke
				(width 0.1)
				(type default)
			)
			(layer "B.Fab")
		)
		(fp_line
			(start -0.120396 0.2794)
			(end 0.12065 0.2794)
			(stroke
				(width 0.1)
				(type default)
			)
			(layer "B.Fab")
		)
		(fp_line
			(start 0.67945 0.3048)
			(end 0.67945 -0.305054)
			(stroke
				(width 0.1)
				(type default)
			)
			(layer "B.Fab")
		)
		(fp_line
			(start 0.12065 0.3048)
			(end 0.67945 0.3048)
			(stroke
				(width 0.1)
				(type default)
			)
			(layer "B.Fab")
		)
		(fp_line
			(start -0.120396 0.3048)
			(end -0.120396 0.2794)
			(stroke
				(width 0.1)
				(type default)
			)
			(layer "B.Fab")
		)
		(fp_line
			(start -0.67945 0.3048)
			(end -0.120396 0.3048)
			(stroke
				(width 0.1)
				(type default)
			)
			(layer "B.Fab")
		)
		(pad "1" smd circle
			(at 0.40005 0 270)
			(size 0 0)
			(layers "B.Cu" "B.Mask" "B.Paste")
			(net "PVDDCR_CPU0_P0_PVCC")
		)
		(pad "2" smd circle
			(at -0.40005 0 270)
			(size 0 0)
			(layers "B.Cu" "B.Mask" "B.Paste")
			(net "PVDDCR_CPU0_P0_VCC4")
		)
	)
	(footprint ""
		(layer "B.Cu")
		(at 271.711928 -337.980528 -90)
		(property "Reference" "PC191_4"
			(at 0 0 90)
			(layer "B.SilkS")
			(hide yes)
			(effects
				(font
					(size 1.27 1.27)
				)
				(justify mirror)
			)
		)
		(property "Value" ""
			(at 0 0 90)
			(layer "B.Fab")
			(effects
				(font
					(size 1.27 1.27)
				)
				(justify mirror)
			)
		)
		(duplicate_pad_numbers_are_jumpers no)
		(fp_line
			(start -1.524 0.762)
			(end 1.524 0.762)
			(stroke
				(width 0.1524)
				(type default)
			)
			(layer "B.SilkS")
		)
		(fp_line
			(start 1.524 0.762)
			(end 1.524 -0.762)
			(stroke
				(width 0.1524)
				(type default)
			)
			(layer "B.SilkS")
		)
		(fp_line
			(start -1.524 -0.762)
			(end -1.524 0.762)
			(stroke
				(width 0.1524)
				(type default)
			)
			(layer "B.SilkS")
		)
		(fp_line
			(start 1.524 -0.762)
			(end -1.524 -0.762)
			(stroke
				(width 0.1524)
				(type default)
			)
			(layer "B.SilkS")
		)
		(fp_line
			(start -1.1049 0.724916)
			(end -1.1049 -0.724916)
			(stroke
				(width 0.1)
				(type default)
			)
			(layer "B.Fab")
		)
		(fp_line
			(start 1.1049 0.724916)
			(end -1.1049 0.724916)
			(stroke
				(width 0.1)
				(type default)
			)
			(layer "B.Fab")
		)
		(fp_line
			(start -1.1049 -0.724916)
			(end 1.1049 -0.724916)
			(stroke
				(width 0.1)
				(type default)
			)
			(layer "B.Fab")
		)
		(fp_line
			(start 1.1049 -0.724916)
			(end 1.1049 0.724916)
			(stroke
				(width 0.1)
				(type default)
			)
			(layer "B.Fab")
		)
		(pad "1" smd rect
			(at 0.889 0 270)
			(size 1.016 1.27)
			(layers "B.Cu" "B.Mask" "B.Paste")
			(net "PVDDIO_P0")
		)
		(pad "2" smd rect
			(at -0.889 0 270)
			(size 1.016 1.27)
			(layers "B.Cu" "B.Mask" "B.Paste")
			(net "GND")
		)
	)
	(footprint ""
		(layer "B.Cu")
		(at 420.160958 -342.007952 -90)
		(property "Reference" "PC221_2"
			(at 0 0 90)
			(layer "B.SilkS")
			(hide yes)
			(effects
				(font
					(size 1.27 1.27)
				)
				(justify mirror)
			)
		)
		(property "Value" ""
			(at 0 0 90)
			(layer "B.Fab")
			(effects
				(font
					(size 1.27 1.27)
				)
				(justify mirror)
			)
		)
		(duplicate_pad_numbers_are_jumpers no)
		(fp_line
			(start -1.524 0.762)
			(end 1.524 0.762)
			(stroke
				(width 0.1524)
				(type default)
			)
			(layer "B.SilkS")
		)
		(fp_line
			(start 1.524 0.762)
			(end 1.524 -0.762)
			(stroke
				(width 0.1524)
				(type default)
			)
			(layer "B.SilkS")
		)
		(fp_line
			(start -1.524 -0.762)
			(end -1.524 0.762)
			(stroke
				(width 0.1524)
				(type default)
			)
			(layer "B.SilkS")
		)
		(fp_line
			(start 1.524 -0.762)
			(end -1.524 -0.762)
			(stroke
				(width 0.1524)
				(type default)
			)
			(layer "B.SilkS")
		)
		(fp_line
			(start -1.1049 0.724916)
			(end -1.1049 -0.724916)
			(stroke
				(width 0.1)
				(type default)
			)
			(layer "B.Fab")
		)
		(fp_line
			(start 1.1049 0.724916)
			(end -1.1049 0.724916)
			(stroke
				(width 0.1)
				(type default)
			)
			(layer "B.Fab")
		)
		(fp_line
			(start -1.1049 -0.724916)
			(end 1.1049 -0.724916)
			(stroke
				(width 0.1)
				(type default)
			)
			(layer "B.Fab")
		)
		(fp_line
			(start 1.1049 -0.724916)
			(end 1.1049 0.724916)
			(stroke
				(width 0.1)
				(type default)
			)
			(layer "B.Fab")
		)
		(pad "1" smd rect
			(at 0.889 0 270)
			(size 1.016 1.27)
			(layers "B.Cu" "B.Mask" "B.Paste")
			(net "PVDD11_S3_P0")
		)
		(pad "2" smd rect
			(at -0.889 0 270)
			(size 1.016 1.27)
			(layers "B.Cu" "B.Mask" "B.Paste")
			(net "GND")
		)
	)
	(footprint ""
		(layer "B.Cu")
		(at 353.900232 -260.305042 180)
		(property "Reference" "C2613"
			(at 0 0 0)
			(layer "B.SilkS")
			(hide yes)
			(effects
				(font
					(size 1.27 1.27)
				)
				(justify mirror)
			)
		)
		(property "Value" ""
			(at 0 0 0)
			(layer "B.Fab")
			(effects
				(font
					(size 1.27 1.27)
				)
				(justify mirror)
			)
		)
		(duplicate_pad_numbers_are_jumpers no)
		(fp_line
			(start 0.7874 0.4064)
			(end 0.7874 -0.4064)
			(stroke
				(width 0.1524)
				(type default)
			)
			(layer "B.SilkS")
		)
		(fp_line
			(start 0.7874 -0.4064)
			(end -0.7874 -0.4064)
			(stroke
				(width 0.1524)
				(type default)
			)
			(layer "B.SilkS")
		)
		(fp_line
			(start -0.7874 0.4064)
			(end 0.7874 0.4064)
			(stroke
				(width 0.1524)
				(type default)
			)
			(layer "B.SilkS")
		)
		(fp_line
			(start -0.7874 -0.4064)
			(end -0.7874 0.4064)
			(stroke
				(width 0.1524)
				(type default)
			)
			(layer "B.SilkS")
		)
		(fp_line
			(start 0.67945 0.3048)
			(end 0.67945 -0.305054)
			(stroke
				(width 0.1)
				(type default)
			)
			(layer "B.Fab")
		)
		(fp_line
			(start 0.67945 -0.305054)
			(end 0.12065 -0.305054)
			(stroke
				(width 0.1)
				(type default)
			)
			(layer "B.Fab")
		)
		(fp_line
			(start 0.12065 0.3048)
			(end 0.67945 0.3048)
			(stroke
				(width 0.1)
				(type default)
			)
			(layer "B.Fab")
		)
		(fp_line
			(start 0.12065 0.2794)
			(end 0.12065 0.3048)
			(stroke
				(width 0.1)
				(type default)
			)
			(layer "B.Fab")
		)
		(fp_line
			(start 0.12065 -0.2794)
			(end -0.12065 -0.2794)
			(stroke
				(width 0.1)
				(type default)
			)
			(layer "B.Fab")
		)
		(fp_line
			(start 0.12065 -0.305054)
			(end 0.12065 -0.2794)
			(stroke
				(width 0.1)
				(type default)
			)
			(layer "B.Fab")
		)
		(fp_line
			(start -0.120396 0.3048)
			(end -0.120396 0.2794)
			(stroke
				(width 0.1)
				(type default)
			)
			(layer "B.Fab")
		)
		(fp_line
			(start -0.120396 0.2794)
			(end 0.12065 0.2794)
			(stroke
				(width 0.1)
				(type default)
			)
			(layer "B.Fab")
		)
		(fp_line
			(start -0.12065 -0.2794)
			(end -0.12065 -0.3048)
			(stroke
				(width 0.1)
				(type default)
			)
			(layer "B.Fab")
		)
		(fp_line
			(start -0.12065 -0.3048)
			(end -0.67945 -0.3048)
			(stroke
				(width 0.1)
				(type default)
			)
			(layer "B.Fab")
		)
		(fp_line
			(start -0.67945 0.3048)
			(end -0.120396 0.3048)
			(stroke
				(width 0.1)
				(type default)
			)
			(layer "B.Fab")
		)
		(fp_line
			(start -0.67945 -0.3048)
			(end -0.67945 0.3048)
			(stroke
				(width 0.1)
				(type default)
			)
			(layer "B.Fab")
		)
		(pad "1" smd circle
			(at 0.40005 0)
			(size 0 0)
			(layers "B.Cu" "B.Mask" "B.Paste")
			(net "PVDDIO_P0")
		)
		(pad "2" smd circle
			(at -0.40005 0)
			(size 0 0)
			(layers "B.Cu" "B.Mask" "B.Paste")
			(net "GND")
		)
	)
	(footprint ""
		(layer "B.Cu")
		(at 104.307894 -333.125826 -90)
		(property "Reference" "PC106"
			(at 7.440676 -3.261106 270)
			(unlocked yes)
			(layer "B.SilkS")
			(effects
				(font
					(size 0.7874 0.5842)
					(thickness 0.1524)
				)
				(justify left mirror)
			)
		)
		(property "Value" ""
			(at 0 0 90)
			(layer "B.Fab")
			(effects
				(font
					(size 1.27 1.27)
				)
				(justify mirror)
			)
		)
		(duplicate_pad_numbers_are_jumpers no)
		(fp_line
			(start -4.533392 2.249932)
			(end 4.533392 2.249932)
			(stroke
				(width 0.1524)
				(type default)
			)
			(layer "B.SilkS")
		)
		(fp_line
			(start 4.533392 2.249932)
			(end 4.533392 -2.249932)
			(stroke
				(width 0.1524)
				(type default)
			)
			(layer "B.SilkS")
		)
		(fp_line
			(start -4.533392 -2.249932)
			(end -4.533392 2.249932)
			(stroke
				(width 0.1524)
				(type default)
			)
			(layer "B.SilkS")
		)
		(fp_line
			(start 4.533392 -2.249932)
			(end -4.533392 -2.249932)
			(stroke
				(width 0.1524)
				(type default)
			)
			(layer "B.SilkS")
		)
		(fp_rect
			(start 5.39242 2.326132)
			(end 4.533392 -2.326132)
			(stroke
				(width 0)
				(type default)
			)
			(fill yes)
			(layer "B.SilkS")
		)
		(fp_line
			(start -3.750056 2.249932)
			(end 3.750056 2.249932)
			(stroke
				(width 0.1)
				(type default)
			)
			(layer "B.Fab")
		)
		(fp_line
			(start 3.750056 2.249932)
			(end 3.750056 -2.249932)
			(stroke
				(width 0.1)
				(type default)
			)
			(layer "B.Fab")
		)
		(fp_line
			(start -3.750056 -2.249932)
			(end -3.750056 2.249932)
			(stroke
				(width 0.1)
				(type default)
			)
			(layer "B.Fab")
		)
		(fp_line
			(start 3.750056 -2.249932)
			(end -3.750056 -2.249932)
			(stroke
				(width 0.1)
				(type default)
			)
			(layer "B.Fab")
		)
		(fp_text user "-"
			(at -4.65201 2.95656 270)
			(unlocked yes)
			(layer "B.SilkS")
			(effects
				(font
					(size 1.905 1.4224)
					(thickness 0.1524)
				)
				(justify left mirror)
			)
		)
		(fp_text user "+"
			(at 6.322314 0.786384 180)
			(unlocked yes)
			(layer "B.SilkS")
			(effects
				(font
					(size 1.905 1.4224)
					(thickness 0.1524)
				)
				(justify left mirror)
			)
		)
		(fp_text user "+"
			(at 6.322314 0.786384 180)
			(unlocked yes)
			(layer "B.Fab")
			(effects
				(font
					(size 1.905 1.4224)
					(thickness 0.1524)
				)
				(justify left mirror)
			)
		)
		(fp_text user "-"
			(at -4.8514 -0.14605 270)
			(unlocked yes)
			(layer "B.Fab")
			(effects
				(font
					(size 1.905 1.4224)
					(thickness 0.1524)
				)
				(justify left mirror)
			)
		)
		(pad "1" smd rect
			(at 3.199892 0 90)
			(size 2.413 2.8194)
			(layers "B.Cu" "B.Mask" "B.Paste")
			(net "PVDDCR_CPU1_P1")
		)
		(pad "2" smd rect
			(at -3.199892 0 90)
			(size 2.413 2.8194)
			(layers "B.Cu" "B.Mask" "B.Paste")
			(net "GND")
		)
	)
	(footprint ""
		(layer "B.Cu")
		(at 130.104642 -74.43724)
		(property "Reference" "PC6018"
			(at 0 0 0)
			(layer "B.SilkS")
			(hide yes)
			(effects
				(font
					(size 1.27 1.27)
				)
				(justify mirror)
			)
		)
		(property "Value" ""
			(at 0 0 0)
			(layer "B.Fab")
			(effects
				(font
					(size 1.27 1.27)
				)
				(justify mirror)
			)
		)
		(duplicate_pad_numbers_are_jumpers no)
		(fp_line
			(start -1.524 -0.762)
			(end -1.524 0.762)
			(stroke
				(width 0.1524)
				(type default)
			)
			(layer "B.SilkS")
		)
		(fp_line
			(start -1.524 0.762)
			(end 1.524 0.762)
			(stroke
				(width 0.1524)
				(type default)
			)
			(layer "B.SilkS")
		)
		(fp_line
			(start 1.524 -0.762)
			(end -1.524 -0.762)
			(stroke
				(width 0.1524)
				(type default)
			)
			(layer "B.SilkS")
		)
		(fp_line
			(start 1.524 0.762)
			(end 1.524 -0.762)
			(stroke
				(width 0.1524)
				(type default)
			)
			(layer "B.SilkS")
		)
		(fp_line
			(start -1.1049 -0.724916)
			(end 1.1049 -0.724916)
			(stroke
				(width 0.1)
				(type default)
			)
			(layer "B.Fab")
		)
		(fp_line
			(start -1.1049 0.724916)
			(end -1.1049 -0.724916)
			(stroke
				(width 0.1)
				(type default)
			)
			(layer "B.Fab")
		)
		(fp_line
			(start 1.1049 -0.724916)
			(end 1.1049 0.724916)
			(stroke
				(width 0.1)
				(type default)
			)
			(layer "B.Fab")
		)
		(fp_line
			(start 1.1049 0.724916)
			(end -1.1049 0.724916)
			(stroke
				(width 0.1)
				(type default)
			)
			(layer "B.Fab")
		)
		(pad "1" smd rect
			(at 0.889 0)
			(size 1.016 1.27)
			(layers "B.Cu" "B.Mask" "B.Paste")
			(net "P1V2_AUX")
		)
		(pad "2" smd rect
			(at -0.889 0)
			(size 1.016 1.27)
			(layers "B.Cu" "B.Mask" "B.Paste")
			(net "GND")
		)
	)
	(footprint ""
		(layer "B.Cu")
		(at 92.281502 -205.14945 90)
		(property "Reference" "R537"
			(at 0 0 90)
			(layer "B.SilkS")
			(hide yes)
			(effects
				(font
					(size 1.27 1.27)
				)
				(justify mirror)
			)
		)
		(property "Value" ""
			(at 0 0 90)
			(layer "B.Fab")
			(effects
				(font
					(size 1.27 1.27)
				)
				(justify mirror)
			)
		)
		(duplicate_pad_numbers_are_jumpers no)
		(fp_line
			(start 0.7874 -0.4064)
			(end -0.7874 -0.4064)
			(stroke
				(width 0.1524)
				(type default)
			)
			(layer "B.SilkS")
		)
		(fp_line
			(start -0.7874 -0.4064)
			(end -0.7874 0.4064)
			(stroke
				(width 0.1524)
				(type default)
			)
			(layer "B.SilkS")
		)
		(fp_line
			(start 0.7874 0.4064)
			(end 0.7874 -0.4064)
			(stroke
				(width 0.1524)
				(type default)
			)
			(layer "B.SilkS")
		)
		(fp_line
			(start -0.7874 0.4064)
			(end 0.7874 0.4064)
			(stroke
				(width 0.1524)
				(type default)
			)
			(layer "B.SilkS")
		)
		(fp_line
			(start 0.67945 -0.305054)
			(end 0.12065 -0.305054)
			(stroke
				(width 0.1)
				(type default)
			)
			(layer "B.Fab")
		)
		(fp_line
			(start 0.12065 -0.305054)
			(end 0.12065 -0.2794)
			(stroke
				(width 0.1)
				(type default)
			)
			(layer "B.Fab")
		)
		(fp_line
			(start -0.12065 -0.3048)
			(end -0.67945 -0.3048)
			(stroke
				(width 0.1)
				(type default)
			)
			(layer "B.Fab")
		)
		(fp_line
			(start -0.67945 -0.3048)
			(end -0.67945 0.3048)
			(stroke
				(width 0.1)
				(type default)
			)
			(layer "B.Fab")
		)
		(fp_line
			(start 0.12065 -0.2794)
			(end -0.12065 -0.2794)
			(stroke
				(width 0.1)
				(type default)
			)
			(layer "B.Fab")
		)
		(fp_line
			(start -0.12065 -0.2794)
			(end -0.12065 -0.3048)
			(stroke
				(width 0.1)
				(type default)
			)
			(layer "B.Fab")
		)
		(fp_line
			(start 0.12065 0.2794)
			(end 0.12065 0.3048)
			(stroke
				(width 0.1)
				(type default)
			)
			(layer "B.Fab")
		)
		(fp_line
			(start -0.120396 0.2794)
			(end 0.12065 0.2794)
			(stroke
				(width 0.1)
				(type default)
			)
			(layer "B.Fab")
		)
		(fp_line
			(start 0.67945 0.3048)
			(end 0.67945 -0.305054)
			(stroke
				(width 0.1)
				(type default)
			)
			(layer "B.Fab")
		)
		(fp_line
			(start 0.12065 0.3048)
			(end 0.67945 0.3048)
			(stroke
				(width 0.1)
				(type default)
			)
			(layer "B.Fab")
		)
		(fp_line
			(start -0.120396 0.3048)
			(end -0.120396 0.2794)
			(stroke
				(width 0.1)
				(type default)
			)
			(layer "B.Fab")
		)
		(fp_line
			(start -0.67945 0.3048)
			(end -0.120396 0.3048)
			(stroke
				(width 0.1)
				(type default)
			)
			(layer "B.Fab")
		)
		(pad "1" smd circle
			(at 0.40005 0 270)
			(size 0 0)
			(layers "B.Cu" "B.Mask" "B.Paste")
			(net "CPU1_XTRIG_L4")
		)
		(pad "2" smd circle
			(at -0.40005 0 270)
			(size 0 0)
			(layers "B.Cu" "B.Mask" "B.Paste")
			(net "PVDD18_S5_P1")
		)
	)
	(footprint ""
		(layer "B.Cu")
		(at 58.213244 -349.386398 -90)
		(property "Reference" "PR268"
			(at 0 0 90)
			(layer "B.SilkS")
			(hide yes)
			(effects
				(font
					(size 1.27 1.27)
				)
				(justify mirror)
			)
		)
		(property "Value" ""
			(at 0 0 90)
			(layer "B.Fab")
			(effects
				(font
					(size 1.27 1.27)
				)
				(justify mirror)
			)
		)
		(duplicate_pad_numbers_are_jumpers no)
		(fp_line
			(start -0.7874 0.4064)
			(end 0.7874 0.4064)
			(stroke
				(width 0.1524)
				(type default)
			)
			(layer "B.SilkS")
		)
		(fp_line
			(start 0.7874 0.4064)
			(end 0.7874 -0.4064)
			(stroke
				(width 0.1524)
				(type default)
			)
			(layer "B.SilkS")
		)
		(fp_line
			(start -0.7874 -0.4064)
			(end -0.7874 0.4064)
			(stroke
				(width 0.1524)
				(type default)
			)
			(layer "B.SilkS")
		)
		(fp_line
			(start 0.7874 -0.4064)
			(end -0.7874 -0.4064)
			(stroke
				(width 0.1524)
				(type default)
			)
			(layer "B.SilkS")
		)
		(fp_line
			(start -0.67945 0.3048)
			(end -0.120396 0.3048)
			(stroke
				(width 0.1)
				(type default)
			)
			(layer "B.Fab")
		)
		(fp_line
			(start -0.120396 0.3048)
			(end -0.120396 0.2794)
			(stroke
				(width 0.1)
				(type default)
			)
			(layer "B.Fab")
		)
		(fp_line
			(start 0.12065 0.3048)
			(end 0.67945 0.3048)
			(stroke
				(width 0.1)
				(type default)
			)
			(layer "B.Fab")
		)
		(fp_line
			(start 0.67945 0.3048)
			(end 0.67945 -0.305054)
			(stroke
				(width 0.1)
				(type default)
			)
			(layer "B.Fab")
		)
		(fp_line
			(start -0.120396 0.2794)
			(end 0.12065 0.2794)
			(stroke
				(width 0.1)
				(type default)
			)
			(layer "B.Fab")
		)
		(fp_line
			(start 0.12065 0.2794)
			(end 0.12065 0.3048)
			(stroke
				(width 0.1)
				(type default)
			)
			(layer "B.Fab")
		)
		(fp_line
			(start -0.12065 -0.2794)
			(end -0.12065 -0.3048)
			(stroke
				(width 0.1)
				(type default)
			)
			(layer "B.Fab")
		)
		(fp_line
			(start 0.12065 -0.2794)
			(end -0.12065 -0.2794)
			(stroke
				(width 0.1)
				(type default)
			)
			(layer "B.Fab")
		)
		(fp_line
			(start -0.67945 -0.3048)
			(end -0.67945 0.3048)
			(stroke
				(width 0.1)
				(type default)
			)
			(layer "B.Fab")
		)
		(fp_line
			(start -0.12065 -0.3048)
			(end -0.67945 -0.3048)
			(stroke
				(width 0.1)
				(type default)
			)
			(layer "B.Fab")
		)
		(fp_line
			(start 0.12065 -0.305054)
			(end 0.12065 -0.2794)
			(stroke
				(width 0.1)
				(type default)
			)
			(layer "B.Fab")
		)
		(fp_line
			(start 0.67945 -0.305054)
			(end 0.12065 -0.305054)
			(stroke
				(width 0.1)
				(type default)
			)
			(layer "B.Fab")
		)
		(pad "1" smd circle
			(at 0.40005 0 90)
			(size 0 0)
			(layers "B.Cu" "B.Mask" "B.Paste")
			(net "PVDDCR_CPU1_P1_VOS4")
		)
		(pad "2" smd circle
			(at -0.40005 0 90)
			(size 0 0)
			(layers "B.Cu" "B.Mask" "B.Paste")
			(net "PVDDCR_CPU1_P1")
		)
	)
	(footprint ""
		(layer "B.Cu")
		(at 200.952608 -120.737376)
		(property "Reference" "R648"
			(at 0 0 0)
			(layer "B.SilkS")
			(hide yes)
			(effects
				(font
					(size 1.27 1.27)
				)
				(justify mirror)
			)
		)
		(property "Value" ""
			(at 0 0 0)
			(layer "B.Fab")
			(effects
				(font
					(size 1.27 1.27)
				)
				(justify mirror)
			)
		)
		(duplicate_pad_numbers_are_jumpers no)
		(fp_line
			(start -0.7874 -0.4064)
			(end -0.7874 0.4064)
			(stroke
				(width 0.1524)
				(type default)
			)
			(layer "B.SilkS")
		)
		(fp_line
			(start -0.7874 0.4064)
			(end 0.7874 0.4064)
			(stroke
				(width 0.1524)
				(type default)
			)
			(layer "B.SilkS")
		)
		(fp_line
			(start 0.7874 -0.4064)
			(end -0.7874 -0.4064)
			(stroke
				(width 0.1524)
				(type default)
			)
			(layer "B.SilkS")
		)
		(fp_line
			(start 0.7874 0.4064)
			(end 0.7874 -0.4064)
			(stroke
				(width 0.1524)
				(type default)
			)
			(layer "B.SilkS")
		)
		(fp_line
			(start -0.67945 -0.3048)
			(end -0.67945 0.3048)
			(stroke
				(width 0.1)
				(type default)
			)
			(layer "B.Fab")
		)
		(fp_line
			(start -0.67945 0.3048)
			(end -0.120396 0.3048)
			(stroke
				(width 0.1)
				(type default)
			)
			(layer "B.Fab")
		)
		(fp_line
			(start -0.12065 -0.3048)
			(end -0.67945 -0.3048)
			(stroke
				(width 0.1)
				(type default)
			)
			(layer "B.Fab")
		)
		(fp_line
			(start -0.12065 -0.2794)
			(end -0.12065 -0.3048)
			(stroke
				(width 0.1)
				(type default)
			)
			(layer "B.Fab")
		)
		(fp_line
			(start -0.120396 0.2794)
			(end 0.12065 0.2794)
			(stroke
				(width 0.1)
				(type default)
			)
			(layer "B.Fab")
		)
		(fp_line
			(start -0.120396 0.3048)
			(end -0.120396 0.2794)
			(stroke
				(width 0.1)
				(type default)
			)
			(layer "B.Fab")
		)
		(fp_line
			(start 0.12065 -0.305054)
			(end 0.12065 -0.2794)
			(stroke
				(width 0.1)
				(type default)
			)
			(layer "B.Fab")
		)
		(fp_line
			(start 0.12065 -0.2794)
			(end -0.12065 -0.2794)
			(stroke
				(width 0.1)
				(type default)
			)
			(layer "B.Fab")
		)
		(fp_line
			(start 0.12065 0.2794)
			(end 0.12065 0.3048)
			(stroke
				(width 0.1)
				(type default)
			)
			(layer "B.Fab")
		)
		(fp_line
			(start 0.12065 0.3048)
			(end 0.67945 0.3048)
			(stroke
				(width 0.1)
				(type default)
			)
			(layer "B.Fab")
		)
		(fp_line
			(start 0.67945 -0.305054)
			(end 0.12065 -0.305054)
			(stroke
				(width 0.1)
				(type default)
			)
			(layer "B.Fab")
		)
		(fp_line
			(start 0.67945 0.3048)
			(end 0.67945 -0.305054)
			(stroke
				(width 0.1)
				(type default)
			)
			(layer "B.Fab")
		)
		(pad "1" smd circle
			(at 0.40005 0 180)
			(size 0 0)
			(layers "B.Cu" "B.Mask" "B.Paste")
			(net "E1S_0_P3V3_EN")
		)
		(pad "2" smd circle
			(at -0.40005 0 180)
			(size 0 0)
			(layers "B.Cu" "B.Mask" "B.Paste")
			(net "P3V3_E1S_0_EN_R")
		)
	)
	(footprint ""
		(layer "B.Cu")
		(at 352.24466 -333.121 -90)
		(property "Reference" "PC100"
			(at 9.640316 0.988314 270)
			(unlocked yes)
			(layer "B.SilkS")
			(effects
				(font
					(size 0.7874 0.5842)
					(thickness 0.1524)
				)
				(justify left mirror)
			)
		)
		(property "Value" ""
			(at 0 0 90)
			(layer "B.Fab")
			(effects
				(font
					(size 1.27 1.27)
				)
				(justify mirror)
			)
		)
		(duplicate_pad_numbers_are_jumpers no)
		(fp_line
			(start -4.533392 2.249932)
			(end 4.533392 2.249932)
			(stroke
				(width 0.1524)
				(type default)
			)
			(layer "B.SilkS")
		)
		(fp_line
			(start 4.533392 2.249932)
			(end 4.533392 -2.249932)
			(stroke
				(width 0.1524)
				(type default)
			)
			(layer "B.SilkS")
		)
		(fp_line
			(start -4.533392 -2.249932)
			(end -4.533392 2.249932)
			(stroke
				(width 0.1524)
				(type default)
			)
			(layer "B.SilkS")
		)
		(fp_line
			(start 4.533392 -2.249932)
			(end -4.533392 -2.249932)
			(stroke
				(width 0.1524)
				(type default)
			)
			(layer "B.SilkS")
		)
		(fp_rect
			(start 5.39242 2.326132)
			(end 4.533392 -2.326132)
			(stroke
				(width 0)
				(type default)
			)
			(fill yes)
			(layer "B.SilkS")
		)
		(fp_line
			(start -3.750056 2.249932)
			(end 3.750056 2.249932)
			(stroke
				(width 0.1)
				(type default)
			)
			(layer "B.Fab")
		)
		(fp_line
			(start 3.750056 2.249932)
			(end 3.750056 -2.249932)
			(stroke
				(width 0.1)
				(type default)
			)
			(layer "B.Fab")
		)
		(fp_line
			(start -3.750056 -2.249932)
			(end -3.750056 2.249932)
			(stroke
				(width 0.1)
				(type default)
			)
			(layer "B.Fab")
		)
		(fp_line
			(start 3.750056 -2.249932)
			(end -3.750056 -2.249932)
			(stroke
				(width 0.1)
				(type default)
			)
			(layer "B.Fab")
		)
		(fp_text user "-"
			(at -4.36499 2.896108 270)
			(unlocked yes)
			(layer "B.SilkS")
			(effects
				(font
					(size 1.905 1.4224)
					(thickness 0.1524)
				)
				(justify left mirror)
			)
		)
		(fp_text user "+"
			(at 6.322314 0.786384 180)
			(unlocked yes)
			(layer "B.SilkS")
			(effects
				(font
					(size 1.905 1.4224)
					(thickness 0.1524)
				)
				(justify left mirror)
			)
		)
		(fp_text user "+"
			(at 6.322314 0.786384 180)
			(unlocked yes)
			(layer "B.Fab")
			(effects
				(font
					(size 1.905 1.4224)
					(thickness 0.1524)
				)
				(justify left mirror)
			)
		)
		(fp_text user "-"
			(at -4.8514 -0.14605 270)
			(unlocked yes)
			(layer "B.Fab")
			(effects
				(font
					(size 1.905 1.4224)
					(thickness 0.1524)
				)
				(justify left mirror)
			)
		)
		(pad "1" smd rect
			(at 3.199892 0 90)
			(size 2.413 2.8194)
			(layers "B.Cu" "B.Mask" "B.Paste")
			(net "PVDDCR_CPU1_P0")
		)
		(pad "2" smd rect
			(at -3.199892 0 90)
			(size 2.413 2.8194)
			(layers "B.Cu" "B.Mask" "B.Paste")
			(net "GND")
		)
	)
	(footprint ""
		(layer "B.Cu")
		(at 296.479722 -193.99631)
		(property "Reference" "R90"
			(at 0 0 0)
			(layer "B.SilkS")
			(hide yes)
			(effects
				(font
					(size 1.27 1.27)
				)
				(justify mirror)
			)
		)
		(property "Value" ""
			(at 0 0 0)
			(layer "B.Fab")
			(effects
				(font
					(size 1.27 1.27)
				)
				(justify mirror)
			)
		)
		(duplicate_pad_numbers_are_jumpers no)
		(fp_line
			(start -0.7874 -0.4064)
			(end -0.7874 0.4064)
			(stroke
				(width 0.1524)
				(type default)
			)
			(layer "B.SilkS")
		)
		(fp_line
			(start -0.7874 0.4064)
			(end 0.7874 0.4064)
			(stroke
				(width 0.1524)
				(type default)
			)
			(layer "B.SilkS")
		)
		(fp_line
			(start 0.7874 -0.4064)
			(end -0.7874 -0.4064)
			(stroke
				(width 0.1524)
				(type default)
			)
			(layer "B.SilkS")
		)
		(fp_line
			(start 0.7874 0.4064)
			(end 0.7874 -0.4064)
			(stroke
				(width 0.1524)
				(type default)
			)
			(layer "B.SilkS")
		)
		(fp_line
			(start -0.67945 -0.3048)
			(end -0.67945 0.3048)
			(stroke
				(width 0.1)
				(type default)
			)
			(layer "B.Fab")
		)
		(fp_line
			(start -0.67945 0.3048)
			(end -0.120396 0.3048)
			(stroke
				(width 0.1)
				(type default)
			)
			(layer "B.Fab")
		)
		(fp_line
			(start -0.12065 -0.3048)
			(end -0.67945 -0.3048)
			(stroke
				(width 0.1)
				(type default)
			)
			(layer "B.Fab")
		)
		(fp_line
			(start -0.12065 -0.2794)
			(end -0.12065 -0.3048)
			(stroke
				(width 0.1)
				(type default)
			)
			(layer "B.Fab")
		)
		(fp_line
			(start -0.120396 0.2794)
			(end 0.12065 0.2794)
			(stroke
				(width 0.1)
				(type default)
			)
			(layer "B.Fab")
		)
		(fp_line
			(start -0.120396 0.3048)
			(end -0.120396 0.2794)
			(stroke
				(width 0.1)
				(type default)
			)
			(layer "B.Fab")
		)
		(fp_line
			(start 0.12065 -0.305054)
			(end 0.12065 -0.2794)
			(stroke
				(width 0.1)
				(type default)
			)
			(layer "B.Fab")
		)
		(fp_line
			(start 0.12065 -0.2794)
			(end -0.12065 -0.2794)
			(stroke
				(width 0.1)
				(type default)
			)
			(layer "B.Fab")
		)
		(fp_line
			(start 0.12065 0.2794)
			(end 0.12065 0.3048)
			(stroke
				(width 0.1)
				(type default)
			)
			(layer "B.Fab")
		)
		(fp_line
			(start 0.12065 0.3048)
			(end 0.67945 0.3048)
			(stroke
				(width 0.1)
				(type default)
			)
			(layer "B.Fab")
		)
		(fp_line
			(start 0.67945 -0.305054)
			(end 0.12065 -0.305054)
			(stroke
				(width 0.1)
				(type default)
			)
			(layer "B.Fab")
		)
		(fp_line
			(start 0.67945 0.3048)
			(end 0.67945 -0.305054)
			(stroke
				(width 0.1)
				(type default)
			)
			(layer "B.Fab")
		)
		(pad "1" smd circle
			(at 0.40005 0 180)
			(size 0 0)
			(layers "B.Cu" "B.Mask" "B.Paste")
			(net "P3V3")
		)
		(pad "2" smd circle
			(at -0.40005 0 180)
			(size 0 0)
			(layers "B.Cu" "B.Mask" "B.Paste")
			(net "PWRGD_CHB_CPU0_DIMM")
		)
	)
	(footprint ""
		(layer "B.Cu")
		(at 133.683756 -386.766562 90)
		(property "Reference" "C485"
			(at 0 0 90)
			(layer "B.SilkS")
			(hide yes)
			(effects
				(font
					(size 1.27 1.27)
				)
				(justify mirror)
			)
		)
		(property "Value" ""
			(at 0 0 90)
			(layer "B.Fab")
			(effects
				(font
					(size 1.27 1.27)
				)
				(justify mirror)
			)
		)
		(duplicate_pad_numbers_are_jumpers no)
		(fp_line
			(start 0.299974 -0.150114)
			(end -0.299974 -0.150114)
			(stroke
				(width 0.1)
				(type default)
			)
			(layer "B.Fab")
		)
		(fp_line
			(start -0.299974 -0.150114)
			(end -0.299974 0.150114)
			(stroke
				(width 0.1)
				(type default)
			)
			(layer "B.Fab")
		)
		(fp_line
			(start 0.299974 0.150114)
			(end 0.299974 -0.150114)
			(stroke
				(width 0.1)
				(type default)
			)
			(layer "B.Fab")
		)
		(fp_line
			(start -0.299974 0.150114)
			(end 0.299974 0.150114)
			(stroke
				(width 0.1)
				(type default)
			)
			(layer "B.Fab")
		)
		(pad "1" smd rect
			(at 0.2667 0 270)
			(size 0.3048 0.381)
			(layers "B.Cu" "B.Mask" "B.Paste")
			(net "P0V9_CPU1_RT3_2A")
		)
		(pad "2" smd rect
			(at -0.2667 0 270)
			(size 0.3048 0.381)
			(layers "B.Cu" "B.Mask" "B.Paste")
			(net "GND")
		)
	)
	(footprint ""
		(layer "B.Cu")
		(at 91.987878 -140.18641 -90)
		(property "Reference" "R8176"
			(at 0 0 90)
			(layer "B.SilkS")
			(hide yes)
			(effects
				(font
					(size 1.27 1.27)
				)
				(justify mirror)
			)
		)
		(property "Value" ""
			(at 0 0 90)
			(layer "B.Fab")
			(effects
				(font
					(size 1.27 1.27)
				)
				(justify mirror)
			)
		)
		(duplicate_pad_numbers_are_jumpers no)
		(fp_line
			(start -0.7874 0.4064)
			(end 0.7874 0.4064)
			(stroke
				(width 0.1524)
				(type default)
			)
			(layer "B.SilkS")
		)
		(fp_line
			(start 0.7874 0.4064)
			(end 0.7874 -0.4064)
			(stroke
				(width 0.1524)
				(type default)
			)
			(layer "B.SilkS")
		)
		(fp_line
			(start -0.7874 -0.4064)
			(end -0.7874 0.4064)
			(stroke
				(width 0.1524)
				(type default)
			)
			(layer "B.SilkS")
		)
		(fp_line
			(start 0.7874 -0.4064)
			(end -0.7874 -0.4064)
			(stroke
				(width 0.1524)
				(type default)
			)
			(layer "B.SilkS")
		)
		(fp_line
			(start -0.67945 0.3048)
			(end -0.120396 0.3048)
			(stroke
				(width 0.1)
				(type default)
			)
			(layer "B.Fab")
		)
		(fp_line
			(start -0.120396 0.3048)
			(end -0.120396 0.2794)
			(stroke
				(width 0.1)
				(type default)
			)
			(layer "B.Fab")
		)
		(fp_line
			(start 0.12065 0.3048)
			(end 0.67945 0.3048)
			(stroke
				(width 0.1)
				(type default)
			)
			(layer "B.Fab")
		)
		(fp_line
			(start 0.67945 0.3048)
			(end 0.67945 -0.305054)
			(stroke
				(width 0.1)
				(type default)
			)
			(layer "B.Fab")
		)
		(fp_line
			(start -0.120396 0.2794)
			(end 0.12065 0.2794)
			(stroke
				(width 0.1)
				(type default)
			)
			(layer "B.Fab")
		)
		(fp_line
			(start 0.12065 0.2794)
			(end 0.12065 0.3048)
			(stroke
				(width 0.1)
				(type default)
			)
			(layer "B.Fab")
		)
		(fp_line
			(start -0.12065 -0.2794)
			(end -0.12065 -0.3048)
			(stroke
				(width 0.1)
				(type default)
			)
			(layer "B.Fab")
		)
		(fp_line
			(start 0.12065 -0.2794)
			(end -0.12065 -0.2794)
			(stroke
				(width 0.1)
				(type default)
			)
			(layer "B.Fab")
		)
		(fp_line
			(start -0.67945 -0.3048)
			(end -0.67945 0.3048)
			(stroke
				(width 0.1)
				(type default)
			)
			(layer "B.Fab")
		)
		(fp_line
			(start -0.12065 -0.3048)
			(end -0.67945 -0.3048)
			(stroke
				(width 0.1)
				(type default)
			)
			(layer "B.Fab")
		)
		(fp_line
			(start 0.12065 -0.305054)
			(end 0.12065 -0.2794)
			(stroke
				(width 0.1)
				(type default)
			)
			(layer "B.Fab")
		)
		(fp_line
			(start 0.67945 -0.305054)
			(end 0.12065 -0.305054)
			(stroke
				(width 0.1)
				(type default)
			)
			(layer "B.Fab")
		)
		(pad "1" smd circle
			(at 0.40005 0 90)
			(size 0 0)
			(layers "B.Cu" "B.Mask" "B.Paste")
			(net "SMB_VR_3V3STBY_SDA")
		)
		(pad "2" smd circle
			(at -0.40005 0 90)
			(size 0 0)
			(layers "B.Cu" "B.Mask" "B.Paste")
			(net "PVDDCR_CPU0_P1_PMSDA_R")
		)
	)
	(footprint ""
		(layer "B.Cu")
		(at 229.993698 -289.533838 -90)
		(property "Reference" "PR6521"
			(at 0 0 90)
			(layer "B.SilkS")
			(hide yes)
			(effects
				(font
					(size 1.27 1.27)
				)
				(justify mirror)
			)
		)
		(property "Value" ""
			(at 0 0 90)
			(layer "B.Fab")
			(effects
				(font
					(size 1.27 1.27)
				)
				(justify mirror)
			)
		)
		(duplicate_pad_numbers_are_jumpers no)
		(fp_line
			(start -0.7874 0.4064)
			(end 0.7874 0.4064)
			(stroke
				(width 0.1524)
				(type default)
			)
			(layer "B.SilkS")
		)
		(fp_line
			(start 0.7874 0.4064)
			(end 0.7874 -0.4064)
			(stroke
				(width 0.1524)
				(type default)
			)
			(layer "B.SilkS")
		)
		(fp_line
			(start -0.7874 -0.4064)
			(end -0.7874 0.4064)
			(stroke
				(width 0.1524)
				(type default)
			)
			(layer "B.SilkS")
		)
		(fp_line
			(start 0.7874 -0.4064)
			(end -0.7874 -0.4064)
			(stroke
				(width 0.1524)
				(type default)
			)
			(layer "B.SilkS")
		)
		(fp_line
			(start -0.67945 0.3048)
			(end -0.120396 0.3048)
			(stroke
				(width 0.1)
				(type default)
			)
			(layer "B.Fab")
		)
		(fp_line
			(start -0.120396 0.3048)
			(end -0.120396 0.2794)
			(stroke
				(width 0.1)
				(type default)
			)
			(layer "B.Fab")
		)
		(fp_line
			(start 0.12065 0.3048)
			(end 0.67945 0.3048)
			(stroke
				(width 0.1)
				(type default)
			)
			(layer "B.Fab")
		)
		(fp_line
			(start 0.67945 0.3048)
			(end 0.67945 -0.305054)
			(stroke
				(width 0.1)
				(type default)
			)
			(layer "B.Fab")
		)
		(fp_line
			(start -0.120396 0.2794)
			(end 0.12065 0.2794)
			(stroke
				(width 0.1)
				(type default)
			)
			(layer "B.Fab")
		)
		(fp_line
			(start 0.12065 0.2794)
			(end 0.12065 0.3048)
			(stroke
				(width 0.1)
				(type default)
			)
			(layer "B.Fab")
		)
		(fp_line
			(start -0.12065 -0.2794)
			(end -0.12065 -0.3048)
			(stroke
				(width 0.1)
				(type default)
			)
			(layer "B.Fab")
		)
		(fp_line
			(start 0.12065 -0.2794)
			(end -0.12065 -0.2794)
			(stroke
				(width 0.1)
				(type default)
			)
			(layer "B.Fab")
		)
		(fp_line
			(start -0.67945 -0.3048)
			(end -0.67945 0.3048)
			(stroke
				(width 0.1)
				(type default)
			)
			(layer "B.Fab")
		)
		(fp_line
			(start -0.12065 -0.3048)
			(end -0.67945 -0.3048)
			(stroke
				(width 0.1)
				(type default)
			)
			(layer "B.Fab")
		)
		(fp_line
			(start 0.12065 -0.305054)
			(end 0.12065 -0.2794)
			(stroke
				(width 0.1)
				(type default)
			)
			(layer "B.Fab")
		)
		(fp_line
			(start 0.67945 -0.305054)
			(end 0.12065 -0.305054)
			(stroke
				(width 0.1)
				(type default)
			)
			(layer "B.Fab")
		)
		(pad "1" smd circle
			(at 0.40005 0 90)
			(size 0 0)
			(layers "B.Cu" "B.Mask" "B.Paste")
			(net "P3V3_AUX")
		)
		(pad "2" smd circle
			(at -0.40005 0 90)
			(size 0 0)
			(layers "B.Cu" "B.Mask" "B.Paste")
			(net "P1V8_RETIMER_CPU1_VCC")
		)
	)
	(footprint ""
		(layer "B.Cu")
		(at 440.40171 -13.627354)
		(property "Reference" "C1235"
			(at 0 0 0)
			(layer "B.SilkS")
			(hide yes)
			(effects
				(font
					(size 1.27 1.27)
				)
				(justify mirror)
			)
		)
		(property "Value" ""
			(at 0 0 0)
			(layer "B.Fab")
			(effects
				(font
					(size 1.27 1.27)
				)
				(justify mirror)
			)
		)
		(duplicate_pad_numbers_are_jumpers no)
		(fp_line
			(start -0.7874 -0.4064)
			(end -0.7874 0.4064)
			(stroke
				(width 0.1524)
				(type default)
			)
			(layer "B.SilkS")
		)
		(fp_line
			(start -0.7874 0.4064)
			(end 0.7874 0.4064)
			(stroke
				(width 0.1524)
				(type default)
			)
			(layer "B.SilkS")
		)
		(fp_line
			(start 0.7874 -0.4064)
			(end -0.7874 -0.4064)
			(stroke
				(width 0.1524)
				(type default)
			)
			(layer "B.SilkS")
		)
		(fp_line
			(start 0.7874 0.4064)
			(end 0.7874 -0.4064)
			(stroke
				(width 0.1524)
				(type default)
			)
			(layer "B.SilkS")
		)
		(fp_line
			(start -0.67945 -0.3048)
			(end -0.67945 0.3048)
			(stroke
				(width 0.1)
				(type default)
			)
			(layer "B.Fab")
		)
		(fp_line
			(start -0.67945 0.3048)
			(end -0.120396 0.3048)
			(stroke
				(width 0.1)
				(type default)
			)
			(layer "B.Fab")
		)
		(fp_line
			(start -0.12065 -0.3048)
			(end -0.67945 -0.3048)
			(stroke
				(width 0.1)
				(type default)
			)
			(layer "B.Fab")
		)
		(fp_line
			(start -0.12065 -0.2794)
			(end -0.12065 -0.3048)
			(stroke
				(width 0.1)
				(type default)
			)
			(layer "B.Fab")
		)
		(fp_line
			(start -0.120396 0.2794)
			(end 0.12065 0.2794)
			(stroke
				(width 0.1)
				(type default)
			)
			(layer "B.Fab")
		)
		(fp_line
			(start -0.120396 0.3048)
			(end -0.120396 0.2794)
			(stroke
				(width 0.1)
				(type default)
			)
			(layer "B.Fab")
		)
		(fp_line
			(start 0.12065 -0.305054)
			(end 0.12065 -0.2794)
			(stroke
				(width 0.1)
				(type default)
			)
			(layer "B.Fab")
		)
		(fp_line
			(start 0.12065 -0.2794)
			(end -0.12065 -0.2794)
			(stroke
				(width 0.1)
				(type default)
			)
			(layer "B.Fab")
		)
		(fp_line
			(start 0.12065 0.2794)
			(end 0.12065 0.3048)
			(stroke
				(width 0.1)
				(type default)
			)
			(layer "B.Fab")
		)
		(fp_line
			(start 0.12065 0.3048)
			(end 0.67945 0.3048)
			(stroke
				(width 0.1)
				(type default)
			)
			(layer "B.Fab")
		)
		(fp_line
			(start 0.67945 -0.305054)
			(end 0.12065 -0.305054)
			(stroke
				(width 0.1)
				(type default)
			)
			(layer "B.Fab")
		)
		(fp_line
			(start 0.67945 0.3048)
			(end 0.67945 -0.305054)
			(stroke
				(width 0.1)
				(type default)
			)
			(layer "B.Fab")
		)
		(pad "1" smd circle
			(at 0.40005 0 180)
			(size 0 0)
			(layers "B.Cu" "B.Mask" "B.Paste")
			(net "P12V_OCP_SFF_R")
		)
		(pad "2" smd circle
			(at -0.40005 0 180)
			(size 0 0)
			(layers "B.Cu" "B.Mask" "B.Paste")
			(net "GND")
		)
	)
	(footprint ""
		(layer "B.Cu")
		(at 380.629922 -148.30171 -90)
		(property "Reference" "PR440"
			(at 0 0 90)
			(layer "B.SilkS")
			(hide yes)
			(effects
				(font
					(size 1.27 1.27)
				)
				(justify mirror)
			)
		)
		(property "Value" ""
			(at 0 0 90)
			(layer "B.Fab")
			(effects
				(font
					(size 1.27 1.27)
				)
				(justify mirror)
			)
		)
		(duplicate_pad_numbers_are_jumpers no)
		(fp_line
			(start -0.7874 0.4064)
			(end 0.7874 0.4064)
			(stroke
				(width 0.1524)
				(type default)
			)
			(layer "B.SilkS")
		)
		(fp_line
			(start 0.7874 0.4064)
			(end 0.7874 -0.4064)
			(stroke
				(width 0.1524)
				(type default)
			)
			(layer "B.SilkS")
		)
		(fp_line
			(start -0.7874 -0.4064)
			(end -0.7874 0.4064)
			(stroke
				(width 0.1524)
				(type default)
			)
			(layer "B.SilkS")
		)
		(fp_line
			(start 0.7874 -0.4064)
			(end -0.7874 -0.4064)
			(stroke
				(width 0.1524)
				(type default)
			)
			(layer "B.SilkS")
		)
		(fp_line
			(start -0.67945 0.3048)
			(end -0.120396 0.3048)
			(stroke
				(width 0.1)
				(type default)
			)
			(layer "B.Fab")
		)
		(fp_line
			(start -0.120396 0.3048)
			(end -0.120396 0.2794)
			(stroke
				(width 0.1)
				(type default)
			)
			(layer "B.Fab")
		)
		(fp_line
			(start 0.12065 0.3048)
			(end 0.67945 0.3048)
			(stroke
				(width 0.1)
				(type default)
			)
			(layer "B.Fab")
		)
		(fp_line
			(start 0.67945 0.3048)
			(end 0.67945 -0.305054)
			(stroke
				(width 0.1)
				(type default)
			)
			(layer "B.Fab")
		)
		(fp_line
			(start -0.120396 0.2794)
			(end 0.12065 0.2794)
			(stroke
				(width 0.1)
				(type default)
			)
			(layer "B.Fab")
		)
		(fp_line
			(start 0.12065 0.2794)
			(end 0.12065 0.3048)
			(stroke
				(width 0.1)
				(type default)
			)
			(layer "B.Fab")
		)
		(fp_line
			(start -0.12065 -0.2794)
			(end -0.12065 -0.3048)
			(stroke
				(width 0.1)
				(type default)
			)
			(layer "B.Fab")
		)
		(fp_line
			(start 0.12065 -0.2794)
			(end -0.12065 -0.2794)
			(stroke
				(width 0.1)
				(type default)
			)
			(layer "B.Fab")
		)
		(fp_line
			(start -0.67945 -0.3048)
			(end -0.67945 0.3048)
			(stroke
				(width 0.1)
				(type default)
			)
			(layer "B.Fab")
		)
		(fp_line
			(start -0.12065 -0.3048)
			(end -0.67945 -0.3048)
			(stroke
				(width 0.1)
				(type default)
			)
			(layer "B.Fab")
		)
		(fp_line
			(start 0.12065 -0.305054)
			(end 0.12065 -0.2794)
			(stroke
				(width 0.1)
				(type default)
			)
			(layer "B.Fab")
		)
		(fp_line
			(start 0.67945 -0.305054)
			(end 0.12065 -0.305054)
			(stroke
				(width 0.1)
				(type default)
			)
			(layer "B.Fab")
		)
		(pad "1" smd circle
			(at 0.40005 0 90)
			(size 0 0)
			(layers "B.Cu" "B.Mask" "B.Paste")
			(net "NC_PVDDCR_CPU0_P0_IMON8")
		)
		(pad "2" smd circle
			(at -0.40005 0 90)
			(size 0 0)
			(layers "B.Cu" "B.Mask" "B.Paste")
			(net "GND")
		)
	)
	(footprint ""
		(layer "B.Cu")
		(at 498.311424 -306.87518 90)
		(property "Reference" "X9025"
			(at 4.62026 -1.55829 90)
			(unlocked yes)
			(layer "B.SilkS")
			(effects
				(font
					(size 0.7874 0.5842)
					(thickness 0.1524)
				)
				(justify left mirror)
			)
		)
		(property "Value" ""
			(at 0 0 90)
			(layer "B.Fab")
			(effects
				(font
					(size 1.27 1.27)
				)
				(justify mirror)
			)
		)
		(property "User Part Number" "N_A"
			(at -1.30175 1.27 0)
			(unlocked yes)
			(layer "Cmts.User")
			(hide yes)
			(effects
				(font
					(size 0.635 0.4064)
					(thickness 0.1524)
				)
				(justify mirror)
			)
		)
		(property "Device Type" "TP_TDR_4P_FTS_TH-TP_TDR_4P_DIP,EMPTY,TP15"
			(at -1.30175 1.27 0)
			(unlocked yes)
			(layer "B.Fab")
			(hide yes)
			(effects
				(font
					(size 0.635 0.4064)
					(thickness 0.1524)
				)
				(justify mirror)
			)
		)
		(duplicate_pad_numbers_are_jumpers no)
		(fp_line
			(start 0 -1.27)
			(end 0 -0.635)
			(stroke
				(width 0.1524)
				(type default)
			)
			(layer "B.SilkS")
		)
		(fp_line
			(start -2.54 -1.27)
			(end 0 -1.27)
			(stroke
				(width 0.1524)
				(type default)
			)
			(layer "B.SilkS")
		)
		(fp_line
			(start -2.54 -1.1303)
			(end -2.54 -1.27)
			(stroke
				(width 0.1524)
				(type default)
			)
			(layer "B.SilkS")
		)
		(fp_line
			(start 0 0.635)
			(end 0 1.905)
			(stroke
				(width 0.1524)
				(type default)
			)
			(layer "B.SilkS")
		)
		(fp_line
			(start -2.54 1.4097)
			(end -2.54 1.1303)
			(stroke
				(width 0.1524)
				(type default)
			)
			(layer "B.SilkS")
		)
		(fp_line
			(start 0 3.175)
			(end 0 3.81)
			(stroke
				(width 0.1524)
				(type default)
			)
			(layer "B.SilkS")
		)
		(fp_line
			(start 0 3.81)
			(end -2.54 3.81)
			(stroke
				(width 0.1524)
				(type default)
			)
			(layer "B.SilkS")
		)
		(fp_line
			(start -2.54 3.81)
			(end -2.54 3.6703)
			(stroke
				(width 0.1524)
				(type default)
			)
			(layer "B.SilkS")
		)
		(fp_poly
			(pts
				(xy 0.761746 0) (xy 2.285746 -0.762) (xy 2.285746 0.762)
			)
			(stroke
				(width 0)
				(type default)
			)
			(fill yes)
			(layer "B.SilkS")
		)
		(fp_line
			(start 0 -1.27)
			(end 0 3.81)
			(stroke
				(width 0.1)
				(type default)
			)
			(layer "B.Fab")
		)
		(fp_line
			(start -2.54 -1.27)
			(end 0 -1.27)
			(stroke
				(width 0.1)
				(type default)
			)
			(layer "B.Fab")
		)
		(fp_line
			(start 0 3.81)
			(end -2.54 3.81)
			(stroke
				(width 0.1)
				(type default)
			)
			(layer "B.Fab")
		)
		(fp_line
			(start -2.54 3.81)
			(end -2.54 -1.27)
			(stroke
				(width 0.1)
				(type default)
			)
			(layer "B.Fab")
		)
		(fp_poly
			(pts
				(xy 0.761746 0) (xy 2.285746 -0.762) (xy 2.285746 0.762)
			)
			(stroke
				(width 0)
				(type default)
			)
			(fill yes)
			(layer "B.Fab")
		)
		(pad "1" thru_hole circle
			(at 0 0 270)
			(size 1.0033 1.0033)
			(drill 0.249936)
			(layers "*.Cu" "*.Mask")
			(remove_unused_layers no)
			(net "TDR_DIFF_85_NECK_IN5_DP")
			(clearance 0.10795)
			(padstack
				(mode front_inner_back)
				(layer "Inner"
					(shape circle)
					(size 0.8001 0.8001)
					(clearance 0.1524)
				)
				(layer "B.Cu"
					(shape circle)
					(size 1.0033 1.0033)
					(thermal_gap 0.10795)
					(clearance 0.10795)
				)
			)
		)
		(pad "2" thru_hole circle
			(at -2.54 0 270)
			(size 1.9939 1.9939)
			(drill 0.249936)
			(layers "*.Cu" "*.Mask")
			(remove_unused_layers no)
			(net "T1_GND")
			(clearance 0.10795)
			(padstack
				(mode front_inner_back)
				(layer "Inner"
					(shape circle)
					(size 0.8001 0.8001)
					(clearance 0.1524)
				)
				(layer "B.Cu"
					(shape circle)
					(size 1.9939 1.9939)
					(thermal_gap 0.10795)
					(clearance 0.10795)
				)
			)
		)
		(pad "3" thru_hole circle
			(at -2.54 2.54 270)
			(size 1.9939 1.9939)
			(drill 0.249936)
			(layers "*.Cu" "*.Mask")
			(remove_unused_layers no)
			(net "T1_GND")
			(clearance 0.10795)
			(padstack
				(mode front_inner_back)
				(layer "Inner"
					(shape circle)
					(size 0.8001 0.8001)
					(clearance 0.1524)
				)
				(layer "B.Cu"
					(shape circle)
					(size 1.9939 1.9939)
					(thermal_gap 0.10795)
					(clearance 0.10795)
				)
			)
		)
		(pad "4" thru_hole circle
			(at 0 2.54 270)
			(size 1.0033 1.0033)
			(drill 0.249936)
			(layers "*.Cu" "*.Mask")
			(remove_unused_layers no)
			(net "TDR_DIFF_85_NECK_IN5_DN")
			(clearance 0.10795)
			(padstack
				(mode front_inner_back)
				(layer "Inner"
					(shape circle)
					(size 0.8001 0.8001)
					(clearance 0.1524)
				)
				(layer "B.Cu"
					(shape circle)
					(size 1.0033 1.0033)
					(thermal_gap 0.10795)
					(clearance 0.10795)
				)
			)
		)
	)
	(footprint ""
		(layer "B.Cu")
		(at 101.92512 -191.278002 90)
		(property "Reference" "PC304_3"
			(at 0 0 90)
			(layer "B.SilkS")
			(hide yes)
			(effects
				(font
					(size 1.27 1.27)
				)
				(justify mirror)
			)
		)
		(property "Value" ""
			(at 0 0 90)
			(layer "B.Fab")
			(effects
				(font
					(size 1.27 1.27)
				)
				(justify mirror)
			)
		)
		(duplicate_pad_numbers_are_jumpers no)
		(fp_line
			(start 1.524 -0.762)
			(end -1.524 -0.762)
			(stroke
				(width 0.1524)
				(type default)
			)
			(layer "B.SilkS")
		)
		(fp_line
			(start -1.524 -0.762)
			(end -1.524 0.762)
			(stroke
				(width 0.1524)
				(type default)
			)
			(layer "B.SilkS")
		)
		(fp_line
			(start 1.524 0.762)
			(end 1.524 -0.762)
			(stroke
				(width 0.1524)
				(type default)
			)
			(layer "B.SilkS")
		)
		(fp_line
			(start -1.524 0.762)
			(end 1.524 0.762)
			(stroke
				(width 0.1524)
				(type default)
			)
			(layer "B.SilkS")
		)
		(fp_line
			(start 1.1049 -0.724916)
			(end 1.1049 0.724916)
			(stroke
				(width 0.1)
				(type default)
			)
			(layer "B.Fab")
		)
		(fp_line
			(start -1.1049 -0.724916)
			(end 1.1049 -0.724916)
			(stroke
				(width 0.1)
				(type default)
			)
			(layer "B.Fab")
		)
		(fp_line
			(start 1.1049 0.724916)
			(end -1.1049 0.724916)
			(stroke
				(width 0.1)
				(type default)
			)
			(layer "B.Fab")
		)
		(fp_line
			(start -1.1049 0.724916)
			(end -1.1049 -0.724916)
			(stroke
				(width 0.1)
				(type default)
			)
			(layer "B.Fab")
		)
		(pad "1" smd rect
			(at 0.889 0 90)
			(size 1.016 1.27)
			(layers "B.Cu" "B.Mask" "B.Paste")
			(net "PVDDCR_CPU0_P1")
		)
		(pad "2" smd rect
			(at -0.889 0 90)
			(size 1.016 1.27)
			(layers "B.Cu" "B.Mask" "B.Paste")
			(net "GND")
		)
	)
	(footprint ""
		(layer "B.Cu")
		(at 216.027 -333.883 -90)
		(property "Reference" "R6718"
			(at 0 0 90)
			(layer "B.SilkS")
			(hide yes)
			(effects
				(font
					(size 1.27 1.27)
				)
				(justify mirror)
			)
		)
		(property "Value" ""
			(at 0 0 90)
			(layer "B.Fab")
			(effects
				(font
					(size 1.27 1.27)
				)
				(justify mirror)
			)
		)
		(duplicate_pad_numbers_are_jumpers no)
		(fp_line
			(start -0.32512 0.175006)
			(end 0.32512 0.175006)
			(stroke
				(width 0.1)
				(type default)
			)
			(layer "B.Fab")
		)
		(fp_line
			(start 0.32512 0.175006)
			(end 0.32512 -0.175006)
			(stroke
				(width 0.1)
				(type default)
			)
			(layer "B.Fab")
		)
		(fp_line
			(start -0.32512 -0.175006)
			(end -0.32512 0.175006)
			(stroke
				(width 0.1)
				(type default)
			)
			(layer "B.Fab")
		)
		(fp_line
			(start 0.32512 -0.175006)
			(end -0.32512 -0.175006)
			(stroke
				(width 0.1)
				(type default)
			)
			(layer "B.Fab")
		)
		(pad "1" smd rect
			(at 0.2667 0 90)
			(size 0.3048 0.381)
			(layers "B.Cu" "B.Mask" "B.Paste")
			(net "P1V8_CPU1_RT_1D")
		)
		(pad "2" smd rect
			(at -0.2667 0 270)
			(size 0.3048 0.381)
			(layers "B.Cu" "B.Mask" "B.Paste")
			(net "SMB_RT_CPU1_P0_R_SDA")
		)
	)
	(footprint ""
		(layer "B.Cu")
		(at 129.305304 -32.638492)
		(property "Reference" "C6082"
			(at 0 0 0)
			(layer "B.SilkS")
			(hide yes)
			(effects
				(font
					(size 1.27 1.27)
				)
				(justify mirror)
			)
		)
		(property "Value" ""
			(at 0 0 0)
			(layer "B.Fab")
			(effects
				(font
					(size 1.27 1.27)
				)
				(justify mirror)
			)
		)
		(duplicate_pad_numbers_are_jumpers no)
		(fp_line
			(start -0.7874 -0.4064)
			(end -0.7874 0.4064)
			(stroke
				(width 0.1524)
				(type default)
			)
			(layer "B.SilkS")
		)
		(fp_line
			(start -0.7874 0.4064)
			(end 0.7874 0.4064)
			(stroke
				(width 0.1524)
				(type default)
			)
			(layer "B.SilkS")
		)
		(fp_line
			(start 0.7874 -0.4064)
			(end -0.7874 -0.4064)
			(stroke
				(width 0.1524)
				(type default)
			)
			(layer "B.SilkS")
		)
		(fp_line
			(start 0.7874 0.4064)
			(end 0.7874 -0.4064)
			(stroke
				(width 0.1524)
				(type default)
			)
			(layer "B.SilkS")
		)
		(fp_line
			(start -0.67945 -0.3048)
			(end -0.67945 0.3048)
			(stroke
				(width 0.1)
				(type default)
			)
			(layer "B.Fab")
		)
		(fp_line
			(start -0.67945 0.3048)
			(end -0.120396 0.3048)
			(stroke
				(width 0.1)
				(type default)
			)
			(layer "B.Fab")
		)
		(fp_line
			(start -0.12065 -0.3048)
			(end -0.67945 -0.3048)
			(stroke
				(width 0.1)
				(type default)
			)
			(layer "B.Fab")
		)
		(fp_line
			(start -0.12065 -0.2794)
			(end -0.12065 -0.3048)
			(stroke
				(width 0.1)
				(type default)
			)
			(layer "B.Fab")
		)
		(fp_line
			(start -0.120396 0.2794)
			(end 0.12065 0.2794)
			(stroke
				(width 0.1)
				(type default)
			)
			(layer "B.Fab")
		)
		(fp_line
			(start -0.120396 0.3048)
			(end -0.120396 0.2794)
			(stroke
				(width 0.1)
				(type default)
			)
			(layer "B.Fab")
		)
		(fp_line
			(start 0.12065 -0.305054)
			(end 0.12065 -0.2794)
			(stroke
				(width 0.1)
				(type default)
			)
			(layer "B.Fab")
		)
		(fp_line
			(start 0.12065 -0.2794)
			(end -0.12065 -0.2794)
			(stroke
				(width 0.1)
				(type default)
			)
			(layer "B.Fab")
		)
		(fp_line
			(start 0.12065 0.2794)
			(end 0.12065 0.3048)
			(stroke
				(width 0.1)
				(type default)
			)
			(layer "B.Fab")
		)
		(fp_line
			(start 0.12065 0.3048)
			(end 0.67945 0.3048)
			(stroke
				(width 0.1)
				(type default)
			)
			(layer "B.Fab")
		)
		(fp_line
			(start 0.67945 -0.305054)
			(end 0.12065 -0.305054)
			(stroke
				(width 0.1)
				(type default)
			)
			(layer "B.Fab")
		)
		(fp_line
			(start 0.67945 0.3048)
			(end 0.67945 -0.305054)
			(stroke
				(width 0.1)
				(type default)
			)
			(layer "B.Fab")
		)
		(pad "1" smd circle
			(at 0.40005 0 180)
			(size 0 0)
			(layers "B.Cu" "B.Mask" "B.Paste")
			(net "P1V2_AUX")
		)
		(pad "2" smd circle
			(at -0.40005 0 180)
			(size 0 0)
			(layers "B.Cu" "B.Mask" "B.Paste")
			(net "GND")
		)
	)
	(footprint ""
		(layer "B.Cu")
		(at 367.233454 -253.43231)
		(property "Reference" "C2143"
			(at 0 0 0)
			(layer "B.SilkS")
			(hide yes)
			(effects
				(font
					(size 1.27 1.27)
				)
				(justify mirror)
			)
		)
		(property "Value" ""
			(at 0 0 0)
			(layer "B.Fab")
			(effects
				(font
					(size 1.27 1.27)
				)
				(justify mirror)
			)
		)
		(duplicate_pad_numbers_are_jumpers no)
		(fp_line
			(start -0.7874 -0.4064)
			(end -0.7874 0.4064)
			(stroke
				(width 0.1524)
				(type default)
			)
			(layer "B.SilkS")
		)
		(fp_line
			(start -0.7874 0.4064)
			(end 0.7874 0.4064)
			(stroke
				(width 0.1524)
				(type default)
			)
			(layer "B.SilkS")
		)
		(fp_line
			(start 0.7874 -0.4064)
			(end -0.7874 -0.4064)
			(stroke
				(width 0.1524)
				(type default)
			)
			(layer "B.SilkS")
		)
		(fp_line
			(start 0.7874 0.4064)
			(end 0.7874 -0.4064)
			(stroke
				(width 0.1524)
				(type default)
			)
			(layer "B.SilkS")
		)
		(fp_line
			(start -0.67945 -0.3048)
			(end -0.67945 0.3048)
			(stroke
				(width 0.1)
				(type default)
			)
			(layer "B.Fab")
		)
		(fp_line
			(start -0.67945 0.3048)
			(end -0.120396 0.3048)
			(stroke
				(width 0.1)
				(type default)
			)
			(layer "B.Fab")
		)
		(fp_line
			(start -0.12065 -0.3048)
			(end -0.67945 -0.3048)
			(stroke
				(width 0.1)
				(type default)
			)
			(layer "B.Fab")
		)
		(fp_line
			(start -0.12065 -0.2794)
			(end -0.12065 -0.3048)
			(stroke
				(width 0.1)
				(type default)
			)
			(layer "B.Fab")
		)
		(fp_line
			(start -0.120396 0.2794)
			(end 0.12065 0.2794)
			(stroke
				(width 0.1)
				(type default)
			)
			(layer "B.Fab")
		)
		(fp_line
			(start -0.120396 0.3048)
			(end -0.120396 0.2794)
			(stroke
				(width 0.1)
				(type default)
			)
			(layer "B.Fab")
		)
		(fp_line
			(start 0.12065 -0.305054)
			(end 0.12065 -0.2794)
			(stroke
				(width 0.1)
				(type default)
			)
			(layer "B.Fab")
		)
		(fp_line
			(start 0.12065 -0.2794)
			(end -0.12065 -0.2794)
			(stroke
				(width 0.1)
				(type default)
			)
			(layer "B.Fab")
		)
		(fp_line
			(start 0.12065 0.2794)
			(end 0.12065 0.3048)
			(stroke
				(width 0.1)
				(type default)
			)
			(layer "B.Fab")
		)
		(fp_line
			(start 0.12065 0.3048)
			(end 0.67945 0.3048)
			(stroke
				(width 0.1)
				(type default)
			)
			(layer "B.Fab")
		)
		(fp_line
			(start 0.67945 -0.305054)
			(end 0.12065 -0.305054)
			(stroke
				(width 0.1)
				(type default)
			)
			(layer "B.Fab")
		)
		(fp_line
			(start 0.67945 0.3048)
			(end 0.67945 -0.305054)
			(stroke
				(width 0.1)
				(type default)
			)
			(layer "B.Fab")
		)
		(pad "1" smd circle
			(at 0.40005 0 180)
			(size 0 0)
			(layers "B.Cu" "B.Mask" "B.Paste")
			(net "PVDDCR_SOC_P0")
		)
		(pad "2" smd circle
			(at -0.40005 0 180)
			(size 0 0)
			(layers "B.Cu" "B.Mask" "B.Paste")
			(net "GND")
		)
	)
	(footprint ""
		(layer "B.Cu")
		(at 84.706206 -386.766562 90)
		(property "Reference" "C306"
			(at 0 0 90)
			(layer "B.SilkS")
			(hide yes)
			(effects
				(font
					(size 1.27 1.27)
				)
				(justify mirror)
			)
		)
		(property "Value" ""
			(at 0 0 90)
			(layer "B.Fab")
			(effects
				(font
					(size 1.27 1.27)
				)
				(justify mirror)
			)
		)
		(duplicate_pad_numbers_are_jumpers no)
		(fp_line
			(start 0.299974 -0.150114)
			(end -0.299974 -0.150114)
			(stroke
				(width 0.1)
				(type default)
			)
			(layer "B.Fab")
		)
		(fp_line
			(start -0.299974 -0.150114)
			(end -0.299974 0.150114)
			(stroke
				(width 0.1)
				(type default)
			)
			(layer "B.Fab")
		)
		(fp_line
			(start 0.299974 0.150114)
			(end 0.299974 -0.150114)
			(stroke
				(width 0.1)
				(type default)
			)
			(layer "B.Fab")
		)
		(fp_line
			(start -0.299974 0.150114)
			(end 0.299974 0.150114)
			(stroke
				(width 0.1)
				(type default)
			)
			(layer "B.Fab")
		)
		(pad "1" smd rect
			(at 0.2667 0 270)
			(size 0.3048 0.381)
			(layers "B.Cu" "B.Mask" "B.Paste")
			(net "P0V9_CPU1_RT1_2A_2D")
		)
		(pad "2" smd rect
			(at -0.2667 0 270)
			(size 0.3048 0.381)
			(layers "B.Cu" "B.Mask" "B.Paste")
			(net "GND")
		)
	)
	(footprint ""
		(layer "B.Cu")
		(at 31.85033 -346.788994 90)
		(property "Reference" "PC627_4"
			(at 0 0 90)
			(layer "B.SilkS")
			(hide yes)
			(effects
				(font
					(size 1.27 1.27)
				)
				(justify mirror)
			)
		)
		(property "Value" ""
			(at 0 0 90)
			(layer "B.Fab")
			(effects
				(font
					(size 1.27 1.27)
				)
				(justify mirror)
			)
		)
		(duplicate_pad_numbers_are_jumpers no)
		(fp_line
			(start 1.524 -0.762)
			(end -1.524 -0.762)
			(stroke
				(width 0.1524)
				(type default)
			)
			(layer "B.SilkS")
		)
		(fp_line
			(start -1.524 -0.762)
			(end -1.524 0.762)
			(stroke
				(width 0.1524)
				(type default)
			)
			(layer "B.SilkS")
		)
		(fp_line
			(start 1.524 0.762)
			(end 1.524 -0.762)
			(stroke
				(width 0.1524)
				(type default)
			)
			(layer "B.SilkS")
		)
		(fp_line
			(start -1.524 0.762)
			(end 1.524 0.762)
			(stroke
				(width 0.1524)
				(type default)
			)
			(layer "B.SilkS")
		)
		(fp_line
			(start 1.1049 -0.724916)
			(end 1.1049 0.724916)
			(stroke
				(width 0.1)
				(type default)
			)
			(layer "B.Fab")
		)
		(fp_line
			(start -1.1049 -0.724916)
			(end 1.1049 -0.724916)
			(stroke
				(width 0.1)
				(type default)
			)
			(layer "B.Fab")
		)
		(fp_line
			(start 1.1049 0.724916)
			(end -1.1049 0.724916)
			(stroke
				(width 0.1)
				(type default)
			)
			(layer "B.Fab")
		)
		(fp_line
			(start -1.1049 0.724916)
			(end -1.1049 -0.724916)
			(stroke
				(width 0.1)
				(type default)
			)
			(layer "B.Fab")
		)
		(pad "1" smd rect
			(at 0.889 0 90)
			(size 1.016 1.27)
			(layers "B.Cu" "B.Mask" "B.Paste")
			(net "SW_P12V_AUX_PVDDIO_P1_FLT")
		)
		(pad "2" smd rect
			(at -0.889 0 90)
			(size 1.016 1.27)
			(layers "B.Cu" "B.Mask" "B.Paste")
			(net "GND")
		)
	)
	(footprint ""
		(layer "B.Cu")
		(at 173.101 -30.099 -90)
		(property "Reference" "R8012"
			(at 0 0 90)
			(layer "B.SilkS")
			(hide yes)
			(effects
				(font
					(size 1.27 1.27)
				)
				(justify mirror)
			)
		)
		(property "Value" ""
			(at 0 0 90)
			(layer "B.Fab")
			(effects
				(font
					(size 1.27 1.27)
				)
				(justify mirror)
			)
		)
		(duplicate_pad_numbers_are_jumpers no)
		(fp_line
			(start -0.7874 0.4064)
			(end 0.7874 0.4064)
			(stroke
				(width 0.1524)
				(type default)
			)
			(layer "B.SilkS")
		)
		(fp_line
			(start 0.7874 0.4064)
			(end 0.7874 -0.4064)
			(stroke
				(width 0.1524)
				(type default)
			)
			(layer "B.SilkS")
		)
		(fp_line
			(start -0.7874 -0.4064)
			(end -0.7874 0.4064)
			(stroke
				(width 0.1524)
				(type default)
			)
			(layer "B.SilkS")
		)
		(fp_line
			(start 0.7874 -0.4064)
			(end -0.7874 -0.4064)
			(stroke
				(width 0.1524)
				(type default)
			)
			(layer "B.SilkS")
		)
		(fp_line
			(start -0.67945 0.3048)
			(end -0.120396 0.3048)
			(stroke
				(width 0.1)
				(type default)
			)
			(layer "B.Fab")
		)
		(fp_line
			(start -0.120396 0.3048)
			(end -0.120396 0.2794)
			(stroke
				(width 0.1)
				(type default)
			)
			(layer "B.Fab")
		)
		(fp_line
			(start 0.12065 0.3048)
			(end 0.67945 0.3048)
			(stroke
				(width 0.1)
				(type default)
			)
			(layer "B.Fab")
		)
		(fp_line
			(start 0.67945 0.3048)
			(end 0.67945 -0.305054)
			(stroke
				(width 0.1)
				(type default)
			)
			(layer "B.Fab")
		)
		(fp_line
			(start -0.120396 0.2794)
			(end 0.12065 0.2794)
			(stroke
				(width 0.1)
				(type default)
			)
			(layer "B.Fab")
		)
		(fp_line
			(start 0.12065 0.2794)
			(end 0.12065 0.3048)
			(stroke
				(width 0.1)
				(type default)
			)
			(layer "B.Fab")
		)
		(fp_line
			(start -0.12065 -0.2794)
			(end -0.12065 -0.3048)
			(stroke
				(width 0.1)
				(type default)
			)
			(layer "B.Fab")
		)
		(fp_line
			(start 0.12065 -0.2794)
			(end -0.12065 -0.2794)
			(stroke
				(width 0.1)
				(type default)
			)
			(layer "B.Fab")
		)
		(fp_line
			(start -0.67945 -0.3048)
			(end -0.67945 0.3048)
			(stroke
				(width 0.1)
				(type default)
			)
			(layer "B.Fab")
		)
		(fp_line
			(start -0.12065 -0.3048)
			(end -0.67945 -0.3048)
			(stroke
				(width 0.1)
				(type default)
			)
			(layer "B.Fab")
		)
		(fp_line
			(start 0.12065 -0.305054)
			(end 0.12065 -0.2794)
			(stroke
				(width 0.1)
				(type default)
			)
			(layer "B.Fab")
		)
		(fp_line
			(start 0.67945 -0.305054)
			(end 0.12065 -0.305054)
			(stroke
				(width 0.1)
				(type default)
			)
			(layer "B.Fab")
		)
		(pad "1" smd circle
			(at 0.40005 0 90)
			(size 0 0)
			(layers "B.Cu" "B.Mask" "B.Paste")
			(net "HP_LVC3_SCM_HSC_PWRGD_R")
		)
		(pad "2" smd circle
			(at -0.40005 0 90)
			(size 0 0)
			(layers "B.Cu" "B.Mask" "B.Paste")
			(net "HP_LVC3_SCM_HSC_PWRGD")
		)
	)
	(footprint ""
		(layer "B.Cu")
		(at 366.36579 -392.1252 180)
		(property "Reference" "R1106"
			(at 0 0 0)
			(layer "B.SilkS")
			(hide yes)
			(effects
				(font
					(size 1.27 1.27)
				)
				(justify mirror)
			)
		)
		(property "Value" ""
			(at 0 0 0)
			(layer "B.Fab")
			(effects
				(font
					(size 1.27 1.27)
				)
				(justify mirror)
			)
		)
		(duplicate_pad_numbers_are_jumpers no)
		(fp_line
			(start 0.32512 0.175006)
			(end 0.32512 -0.175006)
			(stroke
				(width 0.1)
				(type default)
			)
			(layer "B.Fab")
		)
		(fp_line
			(start 0.32512 -0.175006)
			(end -0.32512 -0.175006)
			(stroke
				(width 0.1)
				(type default)
			)
			(layer "B.Fab")
		)
		(fp_line
			(start -0.32512 0.175006)
			(end 0.32512 0.175006)
			(stroke
				(width 0.1)
				(type default)
			)
			(layer "B.Fab")
		)
		(fp_line
			(start -0.32512 -0.175006)
			(end -0.32512 0.175006)
			(stroke
				(width 0.1)
				(type default)
			)
			(layer "B.Fab")
		)
		(pad "1" smd rect
			(at 0.2667 0)
			(size 0.3048 0.381)
			(layers "B.Cu" "B.Mask" "B.Paste")
			(net "RT_CPU0_P3_SCAN_MODE")
		)
		(pad "2" smd rect
			(at -0.2667 0 180)
			(size 0.3048 0.381)
			(layers "B.Cu" "B.Mask" "B.Paste")
			(net "GND")
		)
	)
	(footprint ""
		(layer "B.Cu")
		(at 230.6828 -334.01 180)
		(property "Reference" "R6761"
			(at 0 0 0)
			(layer "B.SilkS")
			(hide yes)
			(effects
				(font
					(size 1.27 1.27)
				)
				(justify mirror)
			)
		)
		(property "Value" ""
			(at 0 0 0)
			(layer "B.Fab")
			(effects
				(font
					(size 1.27 1.27)
				)
				(justify mirror)
			)
		)
		(duplicate_pad_numbers_are_jumpers no)
		(fp_line
			(start 0.32512 0.175006)
			(end 0.32512 -0.175006)
			(stroke
				(width 0.1)
				(type default)
			)
			(layer "B.Fab")
		)
		(fp_line
			(start 0.32512 -0.175006)
			(end -0.32512 -0.175006)
			(stroke
				(width 0.1)
				(type default)
			)
			(layer "B.Fab")
		)
		(fp_line
			(start -0.32512 0.175006)
			(end 0.32512 0.175006)
			(stroke
				(width 0.1)
				(type default)
			)
			(layer "B.Fab")
		)
		(fp_line
			(start -0.32512 -0.175006)
			(end -0.32512 0.175006)
			(stroke
				(width 0.1)
				(type default)
			)
			(layer "B.Fab")
		)
		(pad "1" smd rect
			(at 0.2667 0)
			(size 0.3048 0.381)
			(layers "B.Cu" "B.Mask" "B.Paste")
			(net "SMB_RT_CPU0_P2_SCL")
		)
		(pad "2" smd rect
			(at -0.2667 0 180)
			(size 0.3048 0.381)
			(layers "B.Cu" "B.Mask" "B.Paste")
			(net "SMB_RT_CPU0_P2_R_SCL")
		)
	)
	(footprint ""
		(layer "B.Cu")
		(at 184.785 -100.294948 90)
		(property "Reference" "R1186"
			(at 0 0 90)
			(layer "B.SilkS")
			(hide yes)
			(effects
				(font
					(size 1.27 1.27)
				)
				(justify mirror)
			)
		)
		(property "Value" ""
			(at 0 0 90)
			(layer "B.Fab")
			(effects
				(font
					(size 1.27 1.27)
				)
				(justify mirror)
			)
		)
		(duplicate_pad_numbers_are_jumpers no)
		(fp_line
			(start 0.7874 -0.4064)
			(end -0.7874 -0.4064)
			(stroke
				(width 0.1524)
				(type default)
			)
			(layer "B.SilkS")
		)
		(fp_line
			(start -0.7874 -0.4064)
			(end -0.7874 0.4064)
			(stroke
				(width 0.1524)
				(type default)
			)
			(layer "B.SilkS")
		)
		(fp_line
			(start 0.7874 0.4064)
			(end 0.7874 -0.4064)
			(stroke
				(width 0.1524)
				(type default)
			)
			(layer "B.SilkS")
		)
		(fp_line
			(start -0.7874 0.4064)
			(end 0.7874 0.4064)
			(stroke
				(width 0.1524)
				(type default)
			)
			(layer "B.SilkS")
		)
		(fp_line
			(start 0.67945 -0.305054)
			(end 0.12065 -0.305054)
			(stroke
				(width 0.1)
				(type default)
			)
			(layer "B.Fab")
		)
		(fp_line
			(start 0.12065 -0.305054)
			(end 0.12065 -0.2794)
			(stroke
				(width 0.1)
				(type default)
			)
			(layer "B.Fab")
		)
		(fp_line
			(start -0.12065 -0.3048)
			(end -0.67945 -0.3048)
			(stroke
				(width 0.1)
				(type default)
			)
			(layer "B.Fab")
		)
		(fp_line
			(start -0.67945 -0.3048)
			(end -0.67945 0.3048)
			(stroke
				(width 0.1)
				(type default)
			)
			(layer "B.Fab")
		)
		(fp_line
			(start 0.12065 -0.2794)
			(end -0.12065 -0.2794)
			(stroke
				(width 0.1)
				(type default)
			)
			(layer "B.Fab")
		)
		(fp_line
			(start -0.12065 -0.2794)
			(end -0.12065 -0.3048)
			(stroke
				(width 0.1)
				(type default)
			)
			(layer "B.Fab")
		)
		(fp_line
			(start 0.12065 0.2794)
			(end 0.12065 0.3048)
			(stroke
				(width 0.1)
				(type default)
			)
			(layer "B.Fab")
		)
		(fp_line
			(start -0.120396 0.2794)
			(end 0.12065 0.2794)
			(stroke
				(width 0.1)
				(type default)
			)
			(layer "B.Fab")
		)
		(fp_line
			(start 0.67945 0.3048)
			(end 0.67945 -0.305054)
			(stroke
				(width 0.1)
				(type default)
			)
			(layer "B.Fab")
		)
		(fp_line
			(start 0.12065 0.3048)
			(end 0.67945 0.3048)
			(stroke
				(width 0.1)
				(type default)
			)
			(layer "B.Fab")
		)
		(fp_line
			(start -0.120396 0.3048)
			(end -0.120396 0.2794)
			(stroke
				(width 0.1)
				(type default)
			)
			(layer "B.Fab")
		)
		(fp_line
			(start -0.67945 0.3048)
			(end -0.120396 0.3048)
			(stroke
				(width 0.1)
				(type default)
			)
			(layer "B.Fab")
		)
		(pad "1" smd circle
			(at 0.40005 0 270)
			(size 0 0)
			(layers "B.Cu" "B.Mask" "B.Paste")
			(net "PVDDCR_CPU1_P0_SMB_ALERT")
		)
		(pad "2" smd circle
			(at -0.40005 0 270)
			(size 0 0)
			(layers "B.Cu" "B.Mask" "B.Paste")
			(net "P3V3_AUX")
		)
	)
	(footprint ""
		(layer "B.Cu")
		(at 381.590042 -416.899344 90)
		(property "Reference" "C6604"
			(at 0 0 90)
			(layer "B.SilkS")
			(hide yes)
			(effects
				(font
					(size 1.27 1.27)
				)
				(justify mirror)
			)
		)
		(property "Value" ""
			(at 0 0 90)
			(layer "B.Fab")
			(effects
				(font
					(size 1.27 1.27)
				)
				(justify mirror)
			)
		)
		(duplicate_pad_numbers_are_jumpers no)
		(fp_line
			(start 0.299974 -0.150114)
			(end -0.299974 -0.150114)
			(stroke
				(width 0.1)
				(type default)
			)
			(layer "B.Fab")
		)
		(fp_line
			(start -0.299974 -0.150114)
			(end -0.299974 0.150114)
			(stroke
				(width 0.1)
				(type default)
			)
			(layer "B.Fab")
		)
		(fp_line
			(start 0.299974 0.150114)
			(end 0.299974 -0.150114)
			(stroke
				(width 0.1)
				(type default)
			)
			(layer "B.Fab")
		)
		(fp_line
			(start -0.299974 0.150114)
			(end 0.299974 0.150114)
			(stroke
				(width 0.1)
				(type default)
			)
			(layer "B.Fab")
		)
		(pad "1" smd rect
			(at 0.2667 0 270)
			(size 0.3048 0.381)
			(layers "B.Cu" "B.Mask" "B.Paste")
			(net "P5E_CPU0_P3_TX_BUF_C_DN<3>")
		)
		(pad "2" smd rect
			(at -0.2667 0 270)
			(size 0.3048 0.381)
			(layers "B.Cu" "B.Mask" "B.Paste")
			(net "P5E_CPU0_P3_TX_BUF_DN<3>")
		)
	)
	(footprint ""
		(layer "B.Cu")
		(at 79.175864 -11.26871 -90)
		(property "Reference" "R8413"
			(at 0 0 90)
			(layer "B.SilkS")
			(hide yes)
			(effects
				(font
					(size 1.27 1.27)
				)
				(justify mirror)
			)
		)
		(property "Value" ""
			(at 0 0 90)
			(layer "B.Fab")
			(effects
				(font
					(size 1.27 1.27)
				)
				(justify mirror)
			)
		)
		(duplicate_pad_numbers_are_jumpers no)
		(fp_line
			(start -0.7874 0.4064)
			(end 0.7874 0.4064)
			(stroke
				(width 0.1524)
				(type default)
			)
			(layer "B.SilkS")
		)
		(fp_line
			(start 0.7874 0.4064)
			(end 0.7874 -0.4064)
			(stroke
				(width 0.1524)
				(type default)
			)
			(layer "B.SilkS")
		)
		(fp_line
			(start -0.7874 -0.4064)
			(end -0.7874 0.4064)
			(stroke
				(width 0.1524)
				(type default)
			)
			(layer "B.SilkS")
		)
		(fp_line
			(start 0.7874 -0.4064)
			(end -0.7874 -0.4064)
			(stroke
				(width 0.1524)
				(type default)
			)
			(layer "B.SilkS")
		)
		(fp_line
			(start -0.67945 0.3048)
			(end -0.120396 0.3048)
			(stroke
				(width 0.1)
				(type default)
			)
			(layer "B.Fab")
		)
		(fp_line
			(start -0.120396 0.3048)
			(end -0.120396 0.2794)
			(stroke
				(width 0.1)
				(type default)
			)
			(layer "B.Fab")
		)
		(fp_line
			(start 0.12065 0.3048)
			(end 0.67945 0.3048)
			(stroke
				(width 0.1)
				(type default)
			)
			(layer "B.Fab")
		)
		(fp_line
			(start 0.67945 0.3048)
			(end 0.67945 -0.305054)
			(stroke
				(width 0.1)
				(type default)
			)
			(layer "B.Fab")
		)
		(fp_line
			(start -0.120396 0.2794)
			(end 0.12065 0.2794)
			(stroke
				(width 0.1)
				(type default)
			)
			(layer "B.Fab")
		)
		(fp_line
			(start 0.12065 0.2794)
			(end 0.12065 0.3048)
			(stroke
				(width 0.1)
				(type default)
			)
			(layer "B.Fab")
		)
		(fp_line
			(start -0.12065 -0.2794)
			(end -0.12065 -0.3048)
			(stroke
				(width 0.1)
				(type default)
			)
			(layer "B.Fab")
		)
		(fp_line
			(start 0.12065 -0.2794)
			(end -0.12065 -0.2794)
			(stroke
				(width 0.1)
				(type default)
			)
			(layer "B.Fab")
		)
		(fp_line
			(start -0.67945 -0.3048)
			(end -0.67945 0.3048)
			(stroke
				(width 0.1)
				(type default)
			)
			(layer "B.Fab")
		)
		(fp_line
			(start -0.12065 -0.3048)
			(end -0.67945 -0.3048)
			(stroke
				(width 0.1)
				(type default)
			)
			(layer "B.Fab")
		)
		(fp_line
			(start 0.12065 -0.305054)
			(end 0.12065 -0.2794)
			(stroke
				(width 0.1)
				(type default)
			)
			(layer "B.Fab")
		)
		(fp_line
			(start 0.67945 -0.305054)
			(end 0.12065 -0.305054)
			(stroke
				(width 0.1)
				(type default)
			)
			(layer "B.Fab")
		)
		(pad "1" smd circle
			(at 0.40005 0 90)
			(size 0 0)
			(layers "B.Cu" "B.Mask" "B.Paste")
			(net "GND")
		)
		(pad "2" smd circle
			(at -0.40005 0 90)
			(size 0 0)
			(layers "B.Cu" "B.Mask" "B.Paste")
			(net "FM_OCP_V3_2_PWR_GOOD")
		)
	)
	(footprint ""
		(layer "B.Cu")
		(at 237.363 -234.061 -90)
		(property "Reference" "R358"
			(at 0 0 90)
			(layer "B.SilkS")
			(hide yes)
			(effects
				(font
					(size 1.27 1.27)
				)
				(justify mirror)
			)
		)
		(property "Value" ""
			(at 0 0 90)
			(layer "B.Fab")
			(effects
				(font
					(size 1.27 1.27)
				)
				(justify mirror)
			)
		)
		(duplicate_pad_numbers_are_jumpers no)
		(fp_line
			(start -0.7874 0.4064)
			(end 0.7874 0.4064)
			(stroke
				(width 0.1524)
				(type default)
			)
			(layer "B.SilkS")
		)
		(fp_line
			(start 0.7874 0.4064)
			(end 0.7874 -0.4064)
			(stroke
				(width 0.1524)
				(type default)
			)
			(layer "B.SilkS")
		)
		(fp_line
			(start -0.7874 -0.4064)
			(end -0.7874 0.4064)
			(stroke
				(width 0.1524)
				(type default)
			)
			(layer "B.SilkS")
		)
		(fp_line
			(start 0.7874 -0.4064)
			(end -0.7874 -0.4064)
			(stroke
				(width 0.1524)
				(type default)
			)
			(layer "B.SilkS")
		)
		(fp_line
			(start -0.67945 0.3048)
			(end -0.120396 0.3048)
			(stroke
				(width 0.1)
				(type default)
			)
			(layer "B.Fab")
		)
		(fp_line
			(start -0.120396 0.3048)
			(end -0.120396 0.2794)
			(stroke
				(width 0.1)
				(type default)
			)
			(layer "B.Fab")
		)
		(fp_line
			(start 0.12065 0.3048)
			(end 0.67945 0.3048)
			(stroke
				(width 0.1)
				(type default)
			)
			(layer "B.Fab")
		)
		(fp_line
			(start 0.67945 0.3048)
			(end 0.67945 -0.305054)
			(stroke
				(width 0.1)
				(type default)
			)
			(layer "B.Fab")
		)
		(fp_line
			(start -0.120396 0.2794)
			(end 0.12065 0.2794)
			(stroke
				(width 0.1)
				(type default)
			)
			(layer "B.Fab")
		)
		(fp_line
			(start 0.12065 0.2794)
			(end 0.12065 0.3048)
			(stroke
				(width 0.1)
				(type default)
			)
			(layer "B.Fab")
		)
		(fp_line
			(start -0.12065 -0.2794)
			(end -0.12065 -0.3048)
			(stroke
				(width 0.1)
				(type default)
			)
			(layer "B.Fab")
		)
		(fp_line
			(start 0.12065 -0.2794)
			(end -0.12065 -0.2794)
			(stroke
				(width 0.1)
				(type default)
			)
			(layer "B.Fab")
		)
		(fp_line
			(start -0.67945 -0.3048)
			(end -0.67945 0.3048)
			(stroke
				(width 0.1)
				(type default)
			)
			(layer "B.Fab")
		)
		(fp_line
			(start -0.12065 -0.3048)
			(end -0.67945 -0.3048)
			(stroke
				(width 0.1)
				(type default)
			)
			(layer "B.Fab")
		)
		(fp_line
			(start 0.12065 -0.305054)
			(end 0.12065 -0.2794)
			(stroke
				(width 0.1)
				(type default)
			)
			(layer "B.Fab")
		)
		(fp_line
			(start 0.67945 -0.305054)
			(end 0.12065 -0.305054)
			(stroke
				(width 0.1)
				(type default)
			)
			(layer "B.Fab")
		)
		(pad "1" smd circle
			(at 0.40005 0 90)
			(size 0 0)
			(layers "B.Cu" "B.Mask" "B.Paste")
			(net "SMB_CPU0_CPU1_SEC_SCL_R2")
		)
		(pad "2" smd circle
			(at -0.40005 0 90)
			(size 0 0)
			(layers "B.Cu" "B.Mask" "B.Paste")
			(net "SMB_CPU1_SEC_R_SCL")
		)
	)
	(footprint ""
		(layer "B.Cu")
		(at 102.402386 -256.734564 180)
		(property "Reference" "C2474"
			(at 0 0 0)
			(layer "B.SilkS")
			(hide yes)
			(effects
				(font
					(size 1.27 1.27)
				)
				(justify mirror)
			)
		)
		(property "Value" ""
			(at 0 0 0)
			(layer "B.Fab")
			(effects
				(font
					(size 1.27 1.27)
				)
				(justify mirror)
			)
		)
		(duplicate_pad_numbers_are_jumpers no)
		(fp_line
			(start 0.7874 0.4064)
			(end 0.7874 -0.4064)
			(stroke
				(width 0.1524)
				(type default)
			)
			(layer "B.SilkS")
		)
		(fp_line
			(start 0.7874 -0.4064)
			(end -0.7874 -0.4064)
			(stroke
				(width 0.1524)
				(type default)
			)
			(layer "B.SilkS")
		)
		(fp_line
			(start -0.7874 0.4064)
			(end 0.7874 0.4064)
			(stroke
				(width 0.1524)
				(type default)
			)
			(layer "B.SilkS")
		)
		(fp_line
			(start -0.7874 -0.4064)
			(end -0.7874 0.4064)
			(stroke
				(width 0.1524)
				(type default)
			)
			(layer "B.SilkS")
		)
		(fp_line
			(start 0.67945 0.3048)
			(end 0.67945 -0.305054)
			(stroke
				(width 0.1)
				(type default)
			)
			(layer "B.Fab")
		)
		(fp_line
			(start 0.67945 -0.305054)
			(end 0.12065 -0.305054)
			(stroke
				(width 0.1)
				(type default)
			)
			(layer "B.Fab")
		)
		(fp_line
			(start 0.12065 0.3048)
			(end 0.67945 0.3048)
			(stroke
				(width 0.1)
				(type default)
			)
			(layer "B.Fab")
		)
		(fp_line
			(start 0.12065 0.2794)
			(end 0.12065 0.3048)
			(stroke
				(width 0.1)
				(type default)
			)
			(layer "B.Fab")
		)
		(fp_line
			(start 0.12065 -0.2794)
			(end -0.12065 -0.2794)
			(stroke
				(width 0.1)
				(type default)
			)
			(layer "B.Fab")
		)
		(fp_line
			(start 0.12065 -0.305054)
			(end 0.12065 -0.2794)
			(stroke
				(width 0.1)
				(type default)
			)
			(layer "B.Fab")
		)
		(fp_line
			(start -0.120396 0.3048)
			(end -0.120396 0.2794)
			(stroke
				(width 0.1)
				(type default)
			)
			(layer "B.Fab")
		)
		(fp_line
			(start -0.120396 0.2794)
			(end 0.12065 0.2794)
			(stroke
				(width 0.1)
				(type default)
			)
			(layer "B.Fab")
		)
		(fp_line
			(start -0.12065 -0.2794)
			(end -0.12065 -0.3048)
			(stroke
				(width 0.1)
				(type default)
			)
			(layer "B.Fab")
		)
		(fp_line
			(start -0.12065 -0.3048)
			(end -0.67945 -0.3048)
			(stroke
				(width 0.1)
				(type default)
			)
			(layer "B.Fab")
		)
		(fp_line
			(start -0.67945 0.3048)
			(end -0.120396 0.3048)
			(stroke
				(width 0.1)
				(type default)
			)
			(layer "B.Fab")
		)
		(fp_line
			(start -0.67945 -0.3048)
			(end -0.67945 0.3048)
			(stroke
				(width 0.1)
				(type default)
			)
			(layer "B.Fab")
		)
		(pad "1" smd circle
			(at 0.40005 0)
			(size 0 0)
			(layers "B.Cu" "B.Mask" "B.Paste")
			(net "PVDDCR_SOC_P1")
		)
		(pad "2" smd circle
			(at -0.40005 0)
			(size 0 0)
			(layers "B.Cu" "B.Mask" "B.Paste")
			(net "GND")
		)
	)
	(footprint ""
		(layer "B.Cu")
		(at 401.359116 -185.63336 90)
		(property "Reference" "PC602_1"
			(at 0 0 90)
			(layer "B.SilkS")
			(hide yes)
			(effects
				(font
					(size 1.27 1.27)
				)
				(justify mirror)
			)
		)
		(property "Value" ""
			(at 0 0 90)
			(layer "B.Fab")
			(effects
				(font
					(size 1.27 1.27)
				)
				(justify mirror)
			)
		)
		(duplicate_pad_numbers_are_jumpers no)
		(fp_line
			(start 1.524 -0.762)
			(end -1.524 -0.762)
			(stroke
				(width 0.1524)
				(type default)
			)
			(layer "B.SilkS")
		)
		(fp_line
			(start -1.524 -0.762)
			(end -1.524 0.762)
			(stroke
				(width 0.1524)
				(type default)
			)
			(layer "B.SilkS")
		)
		(fp_line
			(start 1.524 0.762)
			(end 1.524 -0.762)
			(stroke
				(width 0.1524)
				(type default)
			)
			(layer "B.SilkS")
		)
		(fp_line
			(start -1.524 0.762)
			(end 1.524 0.762)
			(stroke
				(width 0.1524)
				(type default)
			)
			(layer "B.SilkS")
		)
		(fp_line
			(start 1.1049 -0.724916)
			(end 1.1049 0.724916)
			(stroke
				(width 0.1)
				(type default)
			)
			(layer "B.Fab")
		)
		(fp_line
			(start -1.1049 -0.724916)
			(end 1.1049 -0.724916)
			(stroke
				(width 0.1)
				(type default)
			)
			(layer "B.Fab")
		)
		(fp_line
			(start 1.1049 0.724916)
			(end -1.1049 0.724916)
			(stroke
				(width 0.1)
				(type default)
			)
			(layer "B.Fab")
		)
		(fp_line
			(start -1.1049 0.724916)
			(end -1.1049 -0.724916)
			(stroke
				(width 0.1)
				(type default)
			)
			(layer "B.Fab")
		)
		(pad "1" smd rect
			(at 0.889 0 90)
			(size 1.016 1.27)
			(layers "B.Cu" "B.Mask" "B.Paste")
			(net "PVDDCR_SOC_P0")
		)
		(pad "2" smd rect
			(at -0.889 0 90)
			(size 1.016 1.27)
			(layers "B.Cu" "B.Mask" "B.Paste")
			(net "GND")
		)
	)
	(footprint ""
		(layer "B.Cu")
		(at 119.801386 -249.368564)
		(property "Reference" "C2345"
			(at 0 0 0)
			(layer "B.SilkS")
			(hide yes)
			(effects
				(font
					(size 1.27 1.27)
				)
				(justify mirror)
			)
		)
		(property "Value" ""
			(at 0 0 0)
			(layer "B.Fab")
			(effects
				(font
					(size 1.27 1.27)
				)
				(justify mirror)
			)
		)
		(duplicate_pad_numbers_are_jumpers no)
		(fp_line
			(start -0.7874 -0.4064)
			(end -0.7874 0.4064)
			(stroke
				(width 0.1524)
				(type default)
			)
			(layer "B.SilkS")
		)
		(fp_line
			(start -0.7874 0.4064)
			(end 0.7874 0.4064)
			(stroke
				(width 0.1524)
				(type default)
			)
			(layer "B.SilkS")
		)
		(fp_line
			(start 0.7874 -0.4064)
			(end -0.7874 -0.4064)
			(stroke
				(width 0.1524)
				(type default)
			)
			(layer "B.SilkS")
		)
		(fp_line
			(start 0.7874 0.4064)
			(end 0.7874 -0.4064)
			(stroke
				(width 0.1524)
				(type default)
			)
			(layer "B.SilkS")
		)
		(fp_line
			(start -0.67945 -0.3048)
			(end -0.67945 0.3048)
			(stroke
				(width 0.1)
				(type default)
			)
			(layer "B.Fab")
		)
		(fp_line
			(start -0.67945 0.3048)
			(end -0.120396 0.3048)
			(stroke
				(width 0.1)
				(type default)
			)
			(layer "B.Fab")
		)
		(fp_line
			(start -0.12065 -0.3048)
			(end -0.67945 -0.3048)
			(stroke
				(width 0.1)
				(type default)
			)
			(layer "B.Fab")
		)
		(fp_line
			(start -0.12065 -0.2794)
			(end -0.12065 -0.3048)
			(stroke
				(width 0.1)
				(type default)
			)
			(layer "B.Fab")
		)
		(fp_line
			(start -0.120396 0.2794)
			(end 0.12065 0.2794)
			(stroke
				(width 0.1)
				(type default)
			)
			(layer "B.Fab")
		)
		(fp_line
			(start -0.120396 0.3048)
			(end -0.120396 0.2794)
			(stroke
				(width 0.1)
				(type default)
			)
			(layer "B.Fab")
		)
		(fp_line
			(start 0.12065 -0.305054)
			(end 0.12065 -0.2794)
			(stroke
				(width 0.1)
				(type default)
			)
			(layer "B.Fab")
		)
		(fp_line
			(start 0.12065 -0.2794)
			(end -0.12065 -0.2794)
			(stroke
				(width 0.1)
				(type default)
			)
			(layer "B.Fab")
		)
		(fp_line
			(start 0.12065 0.2794)
			(end 0.12065 0.3048)
			(stroke
				(width 0.1)
				(type default)
			)
			(layer "B.Fab")
		)
		(fp_line
			(start 0.12065 0.3048)
			(end 0.67945 0.3048)
			(stroke
				(width 0.1)
				(type default)
			)
			(layer "B.Fab")
		)
		(fp_line
			(start 0.67945 -0.305054)
			(end 0.12065 -0.305054)
			(stroke
				(width 0.1)
				(type default)
			)
			(layer "B.Fab")
		)
		(fp_line
			(start 0.67945 0.3048)
			(end 0.67945 -0.305054)
			(stroke
				(width 0.1)
				(type default)
			)
			(layer "B.Fab")
		)
		(pad "1" smd circle
			(at 0.40005 0 180)
			(size 0 0)
			(layers "B.Cu" "B.Mask" "B.Paste")
			(net "PVDDCR_CPU0_P1")
		)
		(pad "2" smd circle
			(at -0.40005 0 180)
			(size 0 0)
			(layers "B.Cu" "B.Mask" "B.Paste")
			(net "GND")
		)
	)
	(footprint ""
		(layer "B.Cu")
		(at 284.82417 -346.784168 90)
		(property "Reference" "PC181_3"
			(at 0 0 90)
			(layer "B.SilkS")
			(hide yes)
			(effects
				(font
					(size 1.27 1.27)
				)
				(justify mirror)
			)
		)
		(property "Value" ""
			(at 0 0 90)
			(layer "B.Fab")
			(effects
				(font
					(size 1.27 1.27)
				)
				(justify mirror)
			)
		)
		(duplicate_pad_numbers_are_jumpers no)
		(fp_line
			(start 1.524 -0.762)
			(end -1.524 -0.762)
			(stroke
				(width 0.1524)
				(type default)
			)
			(layer "B.SilkS")
		)
		(fp_line
			(start -1.524 -0.762)
			(end -1.524 0.762)
			(stroke
				(width 0.1524)
				(type default)
			)
			(layer "B.SilkS")
		)
		(fp_line
			(start 1.524 0.762)
			(end 1.524 -0.762)
			(stroke
				(width 0.1524)
				(type default)
			)
			(layer "B.SilkS")
		)
		(fp_line
			(start -1.524 0.762)
			(end 1.524 0.762)
			(stroke
				(width 0.1524)
				(type default)
			)
			(layer "B.SilkS")
		)
		(fp_line
			(start 1.1049 -0.724916)
			(end 1.1049 0.724916)
			(stroke
				(width 0.1)
				(type default)
			)
			(layer "B.Fab")
		)
		(fp_line
			(start -1.1049 -0.724916)
			(end 1.1049 -0.724916)
			(stroke
				(width 0.1)
				(type default)
			)
			(layer "B.Fab")
		)
		(fp_line
			(start 1.1049 0.724916)
			(end -1.1049 0.724916)
			(stroke
				(width 0.1)
				(type default)
			)
			(layer "B.Fab")
		)
		(fp_line
			(start -1.1049 0.724916)
			(end -1.1049 -0.724916)
			(stroke
				(width 0.1)
				(type default)
			)
			(layer "B.Fab")
		)
		(pad "1" smd rect
			(at 0.889 0 90)
			(size 1.016 1.27)
			(layers "B.Cu" "B.Mask" "B.Paste")
			(net "SW_P12V_AUX_PVDDIO_P0_FLT")
		)
		(pad "2" smd rect
			(at -0.889 0 90)
			(size 1.016 1.27)
			(layers "B.Cu" "B.Mask" "B.Paste")
			(net "GND")
		)
	)
	(footprint ""
		(layer "B.Cu")
		(at 336.180684 -338.913216 -90)
		(property "Reference" "PC95_1"
			(at 0 0 90)
			(layer "B.SilkS")
			(hide yes)
			(effects
				(font
					(size 1.27 1.27)
				)
				(justify mirror)
			)
		)
		(property "Value" ""
			(at 0 0 90)
			(layer "B.Fab")
			(effects
				(font
					(size 1.27 1.27)
				)
				(justify mirror)
			)
		)
		(duplicate_pad_numbers_are_jumpers no)
		(fp_line
			(start -1.524 0.762)
			(end 1.524 0.762)
			(stroke
				(width 0.1524)
				(type default)
			)
			(layer "B.SilkS")
		)
		(fp_line
			(start 1.524 0.762)
			(end 1.524 -0.762)
			(stroke
				(width 0.1524)
				(type default)
			)
			(layer "B.SilkS")
		)
		(fp_line
			(start -1.524 -0.762)
			(end -1.524 0.762)
			(stroke
				(width 0.1524)
				(type default)
			)
			(layer "B.SilkS")
		)
		(fp_line
			(start 1.524 -0.762)
			(end -1.524 -0.762)
			(stroke
				(width 0.1524)
				(type default)
			)
			(layer "B.SilkS")
		)
		(fp_line
			(start -1.1049 0.724916)
			(end -1.1049 -0.724916)
			(stroke
				(width 0.1)
				(type default)
			)
			(layer "B.Fab")
		)
		(fp_line
			(start 1.1049 0.724916)
			(end -1.1049 0.724916)
			(stroke
				(width 0.1)
				(type default)
			)
			(layer "B.Fab")
		)
		(fp_line
			(start -1.1049 -0.724916)
			(end 1.1049 -0.724916)
			(stroke
				(width 0.1)
				(type default)
			)
			(layer "B.Fab")
		)
		(fp_line
			(start 1.1049 -0.724916)
			(end 1.1049 0.724916)
			(stroke
				(width 0.1)
				(type default)
			)
			(layer "B.Fab")
		)
		(pad "1" smd rect
			(at 0.889 0 270)
			(size 1.016 1.27)
			(layers "B.Cu" "B.Mask" "B.Paste")
			(net "SW_P12V_AUX_PVDDCR_CPU1_P0_FLT")
		)
		(pad "2" smd rect
			(at -0.889 0 270)
			(size 1.016 1.27)
			(layers "B.Cu" "B.Mask" "B.Paste")
			(net "GND")
		)
	)
	(footprint ""
		(layer "B.Cu")
		(at 382.618488 -396.393162 -90)
		(property "Reference" "C1012"
			(at 0 0 90)
			(layer "B.SilkS")
			(hide yes)
			(effects
				(font
					(size 1.27 1.27)
				)
				(justify mirror)
			)
		)
		(property "Value" ""
			(at 0 0 90)
			(layer "B.Fab")
			(effects
				(font
					(size 1.27 1.27)
				)
				(justify mirror)
			)
		)
		(duplicate_pad_numbers_are_jumpers no)
		(fp_line
			(start -0.299974 0.150114)
			(end 0.299974 0.150114)
			(stroke
				(width 0.1)
				(type default)
			)
			(layer "B.Fab")
		)
		(fp_line
			(start 0.299974 0.150114)
			(end 0.299974 -0.150114)
			(stroke
				(width 0.1)
				(type default)
			)
			(layer "B.Fab")
		)
		(fp_line
			(start -0.299974 -0.150114)
			(end -0.299974 0.150114)
			(stroke
				(width 0.1)
				(type default)
			)
			(layer "B.Fab")
		)
		(fp_line
			(start 0.299974 -0.150114)
			(end -0.299974 -0.150114)
			(stroke
				(width 0.1)
				(type default)
			)
			(layer "B.Fab")
		)
		(pad "1" smd rect
			(at 0.2667 0 90)
			(size 0.3048 0.381)
			(layers "B.Cu" "B.Mask" "B.Paste")
			(net "P0V9_CPU0_RT_2D")
		)
		(pad "2" smd rect
			(at -0.2667 0 90)
			(size 0.3048 0.381)
			(layers "B.Cu" "B.Mask" "B.Paste")
			(net "GND")
		)
	)
	(footprint ""
		(layer "B.Cu")
		(at 205.375256 -70.31228 180)
		(property "Reference" "R3214"
			(at 0 0 0)
			(layer "B.SilkS")
			(hide yes)
			(effects
				(font
					(size 1.27 1.27)
				)
				(justify mirror)
			)
		)
		(property "Value" ""
			(at 0 0 0)
			(layer "B.Fab")
			(effects
				(font
					(size 1.27 1.27)
				)
				(justify mirror)
			)
		)
		(duplicate_pad_numbers_are_jumpers no)
		(fp_line
			(start 0.7874 0.4064)
			(end 0.7874 -0.4064)
			(stroke
				(width 0.1524)
				(type default)
			)
			(layer "B.SilkS")
		)
		(fp_line
			(start 0.7874 -0.4064)
			(end -0.7874 -0.4064)
			(stroke
				(width 0.1524)
				(type default)
			)
			(layer "B.SilkS")
		)
		(fp_line
			(start -0.7874 0.4064)
			(end 0.7874 0.4064)
			(stroke
				(width 0.1524)
				(type default)
			)
			(layer "B.SilkS")
		)
		(fp_line
			(start -0.7874 -0.4064)
			(end -0.7874 0.4064)
			(stroke
				(width 0.1524)
				(type default)
			)
			(layer "B.SilkS")
		)
		(fp_line
			(start 0.67945 0.3048)
			(end 0.67945 -0.305054)
			(stroke
				(width 0.1)
				(type default)
			)
			(layer "B.Fab")
		)
		(fp_line
			(start 0.67945 -0.305054)
			(end 0.12065 -0.305054)
			(stroke
				(width 0.1)
				(type default)
			)
			(layer "B.Fab")
		)
		(fp_line
			(start 0.12065 0.3048)
			(end 0.67945 0.3048)
			(stroke
				(width 0.1)
				(type default)
			)
			(layer "B.Fab")
		)
		(fp_line
			(start 0.12065 0.2794)
			(end 0.12065 0.3048)
			(stroke
				(width 0.1)
				(type default)
			)
			(layer "B.Fab")
		)
		(fp_line
			(start 0.12065 -0.2794)
			(end -0.12065 -0.2794)
			(stroke
				(width 0.1)
				(type default)
			)
			(layer "B.Fab")
		)
		(fp_line
			(start 0.12065 -0.305054)
			(end 0.12065 -0.2794)
			(stroke
				(width 0.1)
				(type default)
			)
			(layer "B.Fab")
		)
		(fp_line
			(start -0.120396 0.3048)
			(end -0.120396 0.2794)
			(stroke
				(width 0.1)
				(type default)
			)
			(layer "B.Fab")
		)
		(fp_line
			(start -0.120396 0.2794)
			(end 0.12065 0.2794)
			(stroke
				(width 0.1)
				(type default)
			)
			(layer "B.Fab")
		)
		(fp_line
			(start -0.12065 -0.2794)
			(end -0.12065 -0.3048)
			(stroke
				(width 0.1)
				(type default)
			)
			(layer "B.Fab")
		)
		(fp_line
			(start -0.12065 -0.3048)
			(end -0.67945 -0.3048)
			(stroke
				(width 0.1)
				(type default)
			)
			(layer "B.Fab")
		)
		(fp_line
			(start -0.67945 0.3048)
			(end -0.120396 0.3048)
			(stroke
				(width 0.1)
				(type default)
			)
			(layer "B.Fab")
		)
		(fp_line
			(start -0.67945 -0.3048)
			(end -0.67945 0.3048)
			(stroke
				(width 0.1)
				(type default)
			)
			(layer "B.Fab")
		)
		(pad "1" smd circle
			(at 0.40005 0)
			(size 0 0)
			(layers "B.Cu" "B.Mask" "B.Paste")
			(net "NCSI_BMC_TXD0_R1")
		)
		(pad "2" smd circle
			(at -0.40005 0)
			(size 0 0)
			(layers "B.Cu" "B.Mask" "B.Paste")
			(net "RMII_BMC_OCP_TXD_0")
		)
	)
	(footprint ""
		(layer "B.Cu")
		(at 370.478558 -395.148562 90)
		(property "Reference" "C1017"
			(at 0 0 90)
			(layer "B.SilkS")
			(hide yes)
			(effects
				(font
					(size 1.27 1.27)
				)
				(justify mirror)
			)
		)
		(property "Value" ""
			(at 0 0 90)
			(layer "B.Fab")
			(effects
				(font
					(size 1.27 1.27)
				)
				(justify mirror)
			)
		)
		(duplicate_pad_numbers_are_jumpers no)
		(fp_line
			(start 0.299974 -0.150114)
			(end -0.299974 -0.150114)
			(stroke
				(width 0.1)
				(type default)
			)
			(layer "B.Fab")
		)
		(fp_line
			(start -0.299974 -0.150114)
			(end -0.299974 0.150114)
			(stroke
				(width 0.1)
				(type default)
			)
			(layer "B.Fab")
		)
		(fp_line
			(start 0.299974 0.150114)
			(end 0.299974 -0.150114)
			(stroke
				(width 0.1)
				(type default)
			)
			(layer "B.Fab")
		)
		(fp_line
			(start -0.299974 0.150114)
			(end 0.299974 0.150114)
			(stroke
				(width 0.1)
				(type default)
			)
			(layer "B.Fab")
		)
		(pad "1" smd rect
			(at 0.2667 0 270)
			(size 0.3048 0.381)
			(layers "B.Cu" "B.Mask" "B.Paste")
			(net "P0V9_CPU0_RT3_2A")
		)
		(pad "2" smd rect
			(at -0.2667 0 270)
			(size 0.3048 0.381)
			(layers "B.Cu" "B.Mask" "B.Paste")
			(net "GND")
		)
	)
	(footprint ""
		(layer "B.Cu")
		(at 243.713 -321.818)
		(property "Reference" "C1083"
			(at 0 0 0)
			(layer "B.SilkS")
			(hide yes)
			(effects
				(font
					(size 1.27 1.27)
				)
				(justify mirror)
			)
		)
		(property "Value" ""
			(at 0 0 0)
			(layer "B.Fab")
			(effects
				(font
					(size 1.27 1.27)
				)
				(justify mirror)
			)
		)
		(duplicate_pad_numbers_are_jumpers no)
		(fp_line
			(start -0.7874 -0.4064)
			(end -0.7874 0.4064)
			(stroke
				(width 0.1524)
				(type default)
			)
			(layer "B.SilkS")
		)
		(fp_line
			(start -0.7874 0.4064)
			(end 0.7874 0.4064)
			(stroke
				(width 0.1524)
				(type default)
			)
			(layer "B.SilkS")
		)
		(fp_line
			(start 0.7874 -0.4064)
			(end -0.7874 -0.4064)
			(stroke
				(width 0.1524)
				(type default)
			)
			(layer "B.SilkS")
		)
		(fp_line
			(start 0.7874 0.4064)
			(end 0.7874 -0.4064)
			(stroke
				(width 0.1524)
				(type default)
			)
			(layer "B.SilkS")
		)
		(fp_line
			(start -0.67945 -0.3048)
			(end -0.67945 0.3048)
			(stroke
				(width 0.1)
				(type default)
			)
			(layer "B.Fab")
		)
		(fp_line
			(start -0.67945 0.3048)
			(end -0.120396 0.3048)
			(stroke
				(width 0.1)
				(type default)
			)
			(layer "B.Fab")
		)
		(fp_line
			(start -0.12065 -0.3048)
			(end -0.67945 -0.3048)
			(stroke
				(width 0.1)
				(type default)
			)
			(layer "B.Fab")
		)
		(fp_line
			(start -0.12065 -0.2794)
			(end -0.12065 -0.3048)
			(stroke
				(width 0.1)
				(type default)
			)
			(layer "B.Fab")
		)
		(fp_line
			(start -0.120396 0.2794)
			(end 0.12065 0.2794)
			(stroke
				(width 0.1)
				(type default)
			)
			(layer "B.Fab")
		)
		(fp_line
			(start -0.120396 0.3048)
			(end -0.120396 0.2794)
			(stroke
				(width 0.1)
				(type default)
			)
			(layer "B.Fab")
		)
		(fp_line
			(start 0.12065 -0.305054)
			(end 0.12065 -0.2794)
			(stroke
				(width 0.1)
				(type default)
			)
			(layer "B.Fab")
		)
		(fp_line
			(start 0.12065 -0.2794)
			(end -0.12065 -0.2794)
			(stroke
				(width 0.1)
				(type default)
			)
			(layer "B.Fab")
		)
		(fp_line
			(start 0.12065 0.2794)
			(end 0.12065 0.3048)
			(stroke
				(width 0.1)
				(type default)
			)
			(layer "B.Fab")
		)
		(fp_line
			(start 0.12065 0.3048)
			(end 0.67945 0.3048)
			(stroke
				(width 0.1)
				(type default)
			)
			(layer "B.Fab")
		)
		(fp_line
			(start 0.67945 -0.305054)
			(end 0.12065 -0.305054)
			(stroke
				(width 0.1)
				(type default)
			)
			(layer "B.Fab")
		)
		(fp_line
			(start 0.67945 0.3048)
			(end 0.67945 -0.305054)
			(stroke
				(width 0.1)
				(type default)
			)
			(layer "B.Fab")
		)
		(pad "1" smd circle
			(at 0.40005 0 180)
			(size 0 0)
			(layers "B.Cu" "B.Mask" "B.Paste")
			(net "P1V8_CPU1_RT_1D_ADC_MAM")
		)
		(pad "2" smd circle
			(at -0.40005 0 180)
			(size 0 0)
			(layers "B.Cu" "B.Mask" "B.Paste")
			(net "GND")
		)
	)
	(footprint ""
		(layer "B.Cu")
		(at 314.178188 -395.148562 90)
		(property "Reference" "C513"
			(at 0 0 90)
			(layer "B.SilkS")
			(hide yes)
			(effects
				(font
					(size 1.27 1.27)
				)
				(justify mirror)
			)
		)
		(property "Value" ""
			(at 0 0 90)
			(layer "B.Fab")
			(effects
				(font
					(size 1.27 1.27)
				)
				(justify mirror)
			)
		)
		(duplicate_pad_numbers_are_jumpers no)
		(fp_line
			(start 0.299974 -0.150114)
			(end -0.299974 -0.150114)
			(stroke
				(width 0.1)
				(type default)
			)
			(layer "B.Fab")
		)
		(fp_line
			(start -0.299974 -0.150114)
			(end -0.299974 0.150114)
			(stroke
				(width 0.1)
				(type default)
			)
			(layer "B.Fab")
		)
		(fp_line
			(start 0.299974 0.150114)
			(end 0.299974 -0.150114)
			(stroke
				(width 0.1)
				(type default)
			)
			(layer "B.Fab")
		)
		(fp_line
			(start -0.299974 0.150114)
			(end 0.299974 0.150114)
			(stroke
				(width 0.1)
				(type default)
			)
			(layer "B.Fab")
		)
		(pad "1" smd rect
			(at 0.2667 0 270)
			(size 0.3048 0.381)
			(layers "B.Cu" "B.Mask" "B.Paste")
			(net "P1V8_CPU0_RT0_1A_1D")
		)
		(pad "2" smd rect
			(at -0.2667 0 270)
			(size 0.3048 0.381)
			(layers "B.Cu" "B.Mask" "B.Paste")
			(net "GND")
		)
	)
	(footprint ""
		(layer "B.Cu")
		(at 22.479 -361.061 180)
		(property "Reference" "R8222"
			(at 0 0 0)
			(layer "B.SilkS")
			(hide yes)
			(effects
				(font
					(size 1.27 1.27)
				)
				(justify mirror)
			)
		)
		(property "Value" ""
			(at 0 0 0)
			(layer "B.Fab")
			(effects
				(font
					(size 1.27 1.27)
				)
				(justify mirror)
			)
		)
		(duplicate_pad_numbers_are_jumpers no)
		(fp_line
			(start 0.7874 0.4064)
			(end 0.7874 -0.4064)
			(stroke
				(width 0.1524)
				(type default)
			)
			(layer "B.SilkS")
		)
		(fp_line
			(start 0.7874 -0.4064)
			(end -0.7874 -0.4064)
			(stroke
				(width 0.1524)
				(type default)
			)
			(layer "B.SilkS")
		)
		(fp_line
			(start -0.7874 0.4064)
			(end 0.7874 0.4064)
			(stroke
				(width 0.1524)
				(type default)
			)
			(layer "B.SilkS")
		)
		(fp_line
			(start -0.7874 -0.4064)
			(end -0.7874 0.4064)
			(stroke
				(width 0.1524)
				(type default)
			)
			(layer "B.SilkS")
		)
		(fp_line
			(start 0.67945 0.3048)
			(end 0.67945 -0.305054)
			(stroke
				(width 0.1)
				(type default)
			)
			(layer "B.Fab")
		)
		(fp_line
			(start 0.67945 -0.305054)
			(end 0.12065 -0.305054)
			(stroke
				(width 0.1)
				(type default)
			)
			(layer "B.Fab")
		)
		(fp_line
			(start 0.12065 0.3048)
			(end 0.67945 0.3048)
			(stroke
				(width 0.1)
				(type default)
			)
			(layer "B.Fab")
		)
		(fp_line
			(start 0.12065 0.2794)
			(end 0.12065 0.3048)
			(stroke
				(width 0.1)
				(type default)
			)
			(layer "B.Fab")
		)
		(fp_line
			(start 0.12065 -0.2794)
			(end -0.12065 -0.2794)
			(stroke
				(width 0.1)
				(type default)
			)
			(layer "B.Fab")
		)
		(fp_line
			(start 0.12065 -0.305054)
			(end 0.12065 -0.2794)
			(stroke
				(width 0.1)
				(type default)
			)
			(layer "B.Fab")
		)
		(fp_line
			(start -0.120396 0.3048)
			(end -0.120396 0.2794)
			(stroke
				(width 0.1)
				(type default)
			)
			(layer "B.Fab")
		)
		(fp_line
			(start -0.120396 0.2794)
			(end 0.12065 0.2794)
			(stroke
				(width 0.1)
				(type default)
			)
			(layer "B.Fab")
		)
		(fp_line
			(start -0.12065 -0.2794)
			(end -0.12065 -0.3048)
			(stroke
				(width 0.1)
				(type default)
			)
			(layer "B.Fab")
		)
		(fp_line
			(start -0.12065 -0.3048)
			(end -0.67945 -0.3048)
			(stroke
				(width 0.1)
				(type default)
			)
			(layer "B.Fab")
		)
		(fp_line
			(start -0.67945 0.3048)
			(end -0.120396 0.3048)
			(stroke
				(width 0.1)
				(type default)
			)
			(layer "B.Fab")
		)
		(fp_line
			(start -0.67945 -0.3048)
			(end -0.67945 0.3048)
			(stroke
				(width 0.1)
				(type default)
			)
			(layer "B.Fab")
		)
		(pad "1" smd circle
			(at 0.40005 0)
			(size 0 0)
			(layers "B.Cu" "B.Mask" "B.Paste")
			(net "PVDD18_S5_P1")
		)
		(pad "2" smd circle
			(at -0.40005 0)
			(size 0 0)
			(layers "B.Cu" "B.Mask" "B.Paste")
			(net "SVID_PVDDCR_CPU1_P1_SVD_R")
		)
	)
	(footprint ""
		(layer "B.Cu")
		(at 345.510612 -169.787062 90)
		(property "Reference" "PC166_6"
			(at 0 0 90)
			(layer "B.SilkS")
			(hide yes)
			(effects
				(font
					(size 1.27 1.27)
				)
				(justify mirror)
			)
		)
		(property "Value" ""
			(at 0 0 90)
			(layer "B.Fab")
			(effects
				(font
					(size 1.27 1.27)
				)
				(justify mirror)
			)
		)
		(duplicate_pad_numbers_are_jumpers no)
		(fp_line
			(start 1.524 -0.762)
			(end -1.524 -0.762)
			(stroke
				(width 0.1524)
				(type default)
			)
			(layer "B.SilkS")
		)
		(fp_line
			(start -1.524 -0.762)
			(end -1.524 0.762)
			(stroke
				(width 0.1524)
				(type default)
			)
			(layer "B.SilkS")
		)
		(fp_line
			(start 1.524 0.762)
			(end 1.524 -0.762)
			(stroke
				(width 0.1524)
				(type default)
			)
			(layer "B.SilkS")
		)
		(fp_line
			(start -1.524 0.762)
			(end 1.524 0.762)
			(stroke
				(width 0.1524)
				(type default)
			)
			(layer "B.SilkS")
		)
		(fp_line
			(start 1.1049 -0.724916)
			(end 1.1049 0.724916)
			(stroke
				(width 0.1)
				(type default)
			)
			(layer "B.Fab")
		)
		(fp_line
			(start -1.1049 -0.724916)
			(end 1.1049 -0.724916)
			(stroke
				(width 0.1)
				(type default)
			)
			(layer "B.Fab")
		)
		(fp_line
			(start 1.1049 0.724916)
			(end -1.1049 0.724916)
			(stroke
				(width 0.1)
				(type default)
			)
			(layer "B.Fab")
		)
		(fp_line
			(start -1.1049 0.724916)
			(end -1.1049 -0.724916)
			(stroke
				(width 0.1)
				(type default)
			)
			(layer "B.Fab")
		)
		(pad "1" smd rect
			(at 0.889 0 90)
			(size 1.016 1.27)
			(layers "B.Cu" "B.Mask" "B.Paste")
			(net "PVDDCR_CPU0_P0")
		)
		(pad "2" smd rect
			(at -0.889 0 90)
			(size 1.016 1.27)
			(layers "B.Cu" "B.Mask" "B.Paste")
			(net "GND")
		)
	)
	(footprint ""
		(layer "B.Cu")
		(at 25.146 -367.157 90)
		(property "Reference" "R8233"
			(at 0 0 90)
			(layer "B.SilkS")
			(hide yes)
			(effects
				(font
					(size 1.27 1.27)
				)
				(justify mirror)
			)
		)
		(property "Value" ""
			(at 0 0 90)
			(layer "B.Fab")
			(effects
				(font
					(size 1.27 1.27)
				)
				(justify mirror)
			)
		)
		(duplicate_pad_numbers_are_jumpers no)
		(fp_line
			(start 0.7874 -0.4064)
			(end -0.7874 -0.4064)
			(stroke
				(width 0.1524)
				(type default)
			)
			(layer "B.SilkS")
		)
		(fp_line
			(start -0.7874 -0.4064)
			(end -0.7874 0.4064)
			(stroke
				(width 0.1524)
				(type default)
			)
			(layer "B.SilkS")
		)
		(fp_line
			(start 0.7874 0.4064)
			(end 0.7874 -0.4064)
			(stroke
				(width 0.1524)
				(type default)
			)
			(layer "B.SilkS")
		)
		(fp_line
			(start -0.7874 0.4064)
			(end 0.7874 0.4064)
			(stroke
				(width 0.1524)
				(type default)
			)
			(layer "B.SilkS")
		)
		(fp_line
			(start 0.67945 -0.305054)
			(end 0.12065 -0.305054)
			(stroke
				(width 0.1)
				(type default)
			)
			(layer "B.Fab")
		)
		(fp_line
			(start 0.12065 -0.305054)
			(end 0.12065 -0.2794)
			(stroke
				(width 0.1)
				(type default)
			)
			(layer "B.Fab")
		)
		(fp_line
			(start -0.12065 -0.3048)
			(end -0.67945 -0.3048)
			(stroke
				(width 0.1)
				(type default)
			)
			(layer "B.Fab")
		)
		(fp_line
			(start -0.67945 -0.3048)
			(end -0.67945 0.3048)
			(stroke
				(width 0.1)
				(type default)
			)
			(layer "B.Fab")
		)
		(fp_line
			(start 0.12065 -0.2794)
			(end -0.12065 -0.2794)
			(stroke
				(width 0.1)
				(type default)
			)
			(layer "B.Fab")
		)
		(fp_line
			(start -0.12065 -0.2794)
			(end -0.12065 -0.3048)
			(stroke
				(width 0.1)
				(type default)
			)
			(layer "B.Fab")
		)
		(fp_line
			(start 0.12065 0.2794)
			(end 0.12065 0.3048)
			(stroke
				(width 0.1)
				(type default)
			)
			(layer "B.Fab")
		)
		(fp_line
			(start -0.120396 0.2794)
			(end 0.12065 0.2794)
			(stroke
				(width 0.1)
				(type default)
			)
			(layer "B.Fab")
		)
		(fp_line
			(start 0.67945 0.3048)
			(end 0.67945 -0.305054)
			(stroke
				(width 0.1)
				(type default)
			)
			(layer "B.Fab")
		)
		(fp_line
			(start 0.12065 0.3048)
			(end 0.67945 0.3048)
			(stroke
				(width 0.1)
				(type default)
			)
			(layer "B.Fab")
		)
		(fp_line
			(start -0.120396 0.3048)
			(end -0.120396 0.2794)
			(stroke
				(width 0.1)
				(type default)
			)
			(layer "B.Fab")
		)
		(fp_line
			(start -0.67945 0.3048)
			(end -0.120396 0.3048)
			(stroke
				(width 0.1)
				(type default)
			)
			(layer "B.Fab")
		)
		(pad "1" smd circle
			(at 0.40005 0 270)
			(size 0 0)
			(layers "B.Cu" "B.Mask" "B.Paste")
			(net "P3V3_AUX")
		)
		(pad "2" smd circle
			(at -0.40005 0 270)
			(size 0 0)
			(layers "B.Cu" "B.Mask" "B.Paste")
			(net "PWRGD_PVDDCR_CPU1_P1_R")
		)
	)
	(footprint ""
		(layer "B.Cu")
		(at 174.64024 -100.294948 -90)
		(property "Reference" "R244"
			(at 0 0 90)
			(layer "B.SilkS")
			(hide yes)
			(effects
				(font
					(size 1.27 1.27)
				)
				(justify mirror)
			)
		)
		(property "Value" ""
			(at 0 0 90)
			(layer "B.Fab")
			(effects
				(font
					(size 1.27 1.27)
				)
				(justify mirror)
			)
		)
		(duplicate_pad_numbers_are_jumpers no)
		(fp_line
			(start -0.7874 0.4064)
			(end 0.7874 0.4064)
			(stroke
				(width 0.1524)
				(type default)
			)
			(layer "B.SilkS")
		)
		(fp_line
			(start 0.7874 0.4064)
			(end 0.7874 -0.4064)
			(stroke
				(width 0.1524)
				(type default)
			)
			(layer "B.SilkS")
		)
		(fp_line
			(start -0.7874 -0.4064)
			(end -0.7874 0.4064)
			(stroke
				(width 0.1524)
				(type default)
			)
			(layer "B.SilkS")
		)
		(fp_line
			(start 0.7874 -0.4064)
			(end -0.7874 -0.4064)
			(stroke
				(width 0.1524)
				(type default)
			)
			(layer "B.SilkS")
		)
		(fp_line
			(start -0.67945 0.3048)
			(end -0.120396 0.3048)
			(stroke
				(width 0.1)
				(type default)
			)
			(layer "B.Fab")
		)
		(fp_line
			(start -0.120396 0.3048)
			(end -0.120396 0.2794)
			(stroke
				(width 0.1)
				(type default)
			)
			(layer "B.Fab")
		)
		(fp_line
			(start 0.12065 0.3048)
			(end 0.67945 0.3048)
			(stroke
				(width 0.1)
				(type default)
			)
			(layer "B.Fab")
		)
		(fp_line
			(start 0.67945 0.3048)
			(end 0.67945 -0.305054)
			(stroke
				(width 0.1)
				(type default)
			)
			(layer "B.Fab")
		)
		(fp_line
			(start -0.120396 0.2794)
			(end 0.12065 0.2794)
			(stroke
				(width 0.1)
				(type default)
			)
			(layer "B.Fab")
		)
		(fp_line
			(start 0.12065 0.2794)
			(end 0.12065 0.3048)
			(stroke
				(width 0.1)
				(type default)
			)
			(layer "B.Fab")
		)
		(fp_line
			(start -0.12065 -0.2794)
			(end -0.12065 -0.3048)
			(stroke
				(width 0.1)
				(type default)
			)
			(layer "B.Fab")
		)
		(fp_line
			(start 0.12065 -0.2794)
			(end -0.12065 -0.2794)
			(stroke
				(width 0.1)
				(type default)
			)
			(layer "B.Fab")
		)
		(fp_line
			(start -0.67945 -0.3048)
			(end -0.67945 0.3048)
			(stroke
				(width 0.1)
				(type default)
			)
			(layer "B.Fab")
		)
		(fp_line
			(start -0.12065 -0.3048)
			(end -0.67945 -0.3048)
			(stroke
				(width 0.1)
				(type default)
			)
			(layer "B.Fab")
		)
		(fp_line
			(start 0.12065 -0.305054)
			(end 0.12065 -0.2794)
			(stroke
				(width 0.1)
				(type default)
			)
			(layer "B.Fab")
		)
		(fp_line
			(start 0.67945 -0.305054)
			(end 0.12065 -0.305054)
			(stroke
				(width 0.1)
				(type default)
			)
			(layer "B.Fab")
		)
		(pad "1" smd circle
			(at 0.40005 0 90)
			(size 0 0)
			(layers "B.Cu" "B.Mask" "B.Paste")
			(net "IRQ_BMC_SMI_N")
		)
		(pad "2" smd circle
			(at -0.40005 0 90)
			(size 0 0)
			(layers "B.Cu" "B.Mask" "B.Paste")
			(net "IRQ_BMC_SMI_R_N")
		)
	)
	(footprint ""
		(layer "B.Cu")
		(at 105.537 -421.005 180)
		(property "Reference" "R3514"
			(at 0 0 0)
			(layer "B.SilkS")
			(hide yes)
			(effects
				(font
					(size 1.27 1.27)
				)
				(justify mirror)
			)
		)
		(property "Value" ""
			(at 0 0 0)
			(layer "B.Fab")
			(effects
				(font
					(size 1.27 1.27)
				)
				(justify mirror)
			)
		)
		(duplicate_pad_numbers_are_jumpers no)
		(fp_line
			(start 0.7874 0.4064)
			(end 0.7874 -0.4064)
			(stroke
				(width 0.1524)
				(type default)
			)
			(layer "B.SilkS")
		)
		(fp_line
			(start 0.7874 -0.4064)
			(end -0.7874 -0.4064)
			(stroke
				(width 0.1524)
				(type default)
			)
			(layer "B.SilkS")
		)
		(fp_line
			(start -0.7874 0.4064)
			(end 0.7874 0.4064)
			(stroke
				(width 0.1524)
				(type default)
			)
			(layer "B.SilkS")
		)
		(fp_line
			(start -0.7874 -0.4064)
			(end -0.7874 0.4064)
			(stroke
				(width 0.1524)
				(type default)
			)
			(layer "B.SilkS")
		)
		(fp_line
			(start 0.67945 0.3048)
			(end 0.67945 -0.305054)
			(stroke
				(width 0.1)
				(type default)
			)
			(layer "B.Fab")
		)
		(fp_line
			(start 0.67945 -0.305054)
			(end 0.12065 -0.305054)
			(stroke
				(width 0.1)
				(type default)
			)
			(layer "B.Fab")
		)
		(fp_line
			(start 0.12065 0.3048)
			(end 0.67945 0.3048)
			(stroke
				(width 0.1)
				(type default)
			)
			(layer "B.Fab")
		)
		(fp_line
			(start 0.12065 0.2794)
			(end 0.12065 0.3048)
			(stroke
				(width 0.1)
				(type default)
			)
			(layer "B.Fab")
		)
		(fp_line
			(start 0.12065 -0.2794)
			(end -0.12065 -0.2794)
			(stroke
				(width 0.1)
				(type default)
			)
			(layer "B.Fab")
		)
		(fp_line
			(start 0.12065 -0.305054)
			(end 0.12065 -0.2794)
			(stroke
				(width 0.1)
				(type default)
			)
			(layer "B.Fab")
		)
		(fp_line
			(start -0.120396 0.3048)
			(end -0.120396 0.2794)
			(stroke
				(width 0.1)
				(type default)
			)
			(layer "B.Fab")
		)
		(fp_line
			(start -0.120396 0.2794)
			(end 0.12065 0.2794)
			(stroke
				(width 0.1)
				(type default)
			)
			(layer "B.Fab")
		)
		(fp_line
			(start -0.12065 -0.2794)
			(end -0.12065 -0.3048)
			(stroke
				(width 0.1)
				(type default)
			)
			(layer "B.Fab")
		)
		(fp_line
			(start -0.12065 -0.3048)
			(end -0.67945 -0.3048)
			(stroke
				(width 0.1)
				(type default)
			)
			(layer "B.Fab")
		)
		(fp_line
			(start -0.67945 0.3048)
			(end -0.120396 0.3048)
			(stroke
				(width 0.1)
				(type default)
			)
			(layer "B.Fab")
		)
		(fp_line
			(start -0.67945 -0.3048)
			(end -0.67945 0.3048)
			(stroke
				(width 0.1)
				(type default)
			)
			(layer "B.Fab")
		)
		(pad "1" smd circle
			(at 0.40005 0)
			(size 0 0)
			(layers "B.Cu" "B.Mask" "B.Paste")
			(net "P3V3_AUX")
		)
		(pad "2" smd circle
			(at -0.40005 0)
			(size 0 0)
			(layers "B.Cu" "B.Mask" "B.Paste")
			(net "FM_SMB_2_ALERT_GPU_N")
		)
	)
	(footprint ""
		(layer "B.Cu")
		(at 97.591118 -424.191684)
		(property "Reference" "R8001"
			(at 0 0 0)
			(layer "B.SilkS")
			(hide yes)
			(effects
				(font
					(size 1.27 1.27)
				)
				(justify mirror)
			)
		)
		(property "Value" ""
			(at 0 0 0)
			(layer "B.Fab")
			(effects
				(font
					(size 1.27 1.27)
				)
				(justify mirror)
			)
		)
		(duplicate_pad_numbers_are_jumpers no)
		(fp_line
			(start -0.7874 -0.4064)
			(end -0.7874 0.4064)
			(stroke
				(width 0.1524)
				(type default)
			)
			(layer "B.SilkS")
		)
		(fp_line
			(start -0.7874 0.4064)
			(end 0.7874 0.4064)
			(stroke
				(width 0.1524)
				(type default)
			)
			(layer "B.SilkS")
		)
		(fp_line
			(start 0.7874 -0.4064)
			(end -0.7874 -0.4064)
			(stroke
				(width 0.1524)
				(type default)
			)
			(layer "B.SilkS")
		)
		(fp_line
			(start 0.7874 0.4064)
			(end 0.7874 -0.4064)
			(stroke
				(width 0.1524)
				(type default)
			)
			(layer "B.SilkS")
		)
		(fp_line
			(start -0.67945 -0.3048)
			(end -0.67945 0.3048)
			(stroke
				(width 0.1)
				(type default)
			)
			(layer "B.Fab")
		)
		(fp_line
			(start -0.67945 0.3048)
			(end -0.120396 0.3048)
			(stroke
				(width 0.1)
				(type default)
			)
			(layer "B.Fab")
		)
		(fp_line
			(start -0.12065 -0.3048)
			(end -0.67945 -0.3048)
			(stroke
				(width 0.1)
				(type default)
			)
			(layer "B.Fab")
		)
		(fp_line
			(start -0.12065 -0.2794)
			(end -0.12065 -0.3048)
			(stroke
				(width 0.1)
				(type default)
			)
			(layer "B.Fab")
		)
		(fp_line
			(start -0.120396 0.2794)
			(end 0.12065 0.2794)
			(stroke
				(width 0.1)
				(type default)
			)
			(layer "B.Fab")
		)
		(fp_line
			(start -0.120396 0.3048)
			(end -0.120396 0.2794)
			(stroke
				(width 0.1)
				(type default)
			)
			(layer "B.Fab")
		)
		(fp_line
			(start 0.12065 -0.305054)
			(end 0.12065 -0.2794)
			(stroke
				(width 0.1)
				(type default)
			)
			(layer "B.Fab")
		)
		(fp_line
			(start 0.12065 -0.2794)
			(end -0.12065 -0.2794)
			(stroke
				(width 0.1)
				(type default)
			)
			(layer "B.Fab")
		)
		(fp_line
			(start 0.12065 0.2794)
			(end 0.12065 0.3048)
			(stroke
				(width 0.1)
				(type default)
			)
			(layer "B.Fab")
		)
		(fp_line
			(start 0.12065 0.3048)
			(end 0.67945 0.3048)
			(stroke
				(width 0.1)
				(type default)
			)
			(layer "B.Fab")
		)
		(fp_line
			(start 0.67945 -0.305054)
			(end 0.12065 -0.305054)
			(stroke
				(width 0.1)
				(type default)
			)
			(layer "B.Fab")
		)
		(fp_line
			(start 0.67945 0.3048)
			(end 0.67945 -0.305054)
			(stroke
				(width 0.1)
				(type default)
			)
			(layer "B.Fab")
		)
		(pad "1" smd circle
			(at 0.40005 0 180)
			(size 0 0)
			(layers "B.Cu" "B.Mask" "B.Paste")
			(net "PRSNT_SWB_N")
		)
		(pad "2" smd circle
			(at -0.40005 0 180)
			(size 0 0)
			(layers "B.Cu" "B.Mask" "B.Paste")
			(net "GND")
		)
	)
	(footprint ""
		(layer "B.Cu")
		(at 51.766978 -428.06493 90)
		(property "Reference" "C1978"
			(at 0 0 90)
			(layer "B.SilkS")
			(hide yes)
			(effects
				(font
					(size 1.27 1.27)
				)
				(justify mirror)
			)
		)
		(property "Value" ""
			(at 0 0 90)
			(layer "B.Fab")
			(effects
				(font
					(size 1.27 1.27)
				)
				(justify mirror)
			)
		)
		(duplicate_pad_numbers_are_jumpers no)
		(fp_line
			(start 0.7874 -0.4064)
			(end -0.7874 -0.4064)
			(stroke
				(width 0.1524)
				(type default)
			)
			(layer "B.SilkS")
		)
		(fp_line
			(start -0.7874 -0.4064)
			(end -0.7874 0.4064)
			(stroke
				(width 0.1524)
				(type default)
			)
			(layer "B.SilkS")
		)
		(fp_line
			(start 0.7874 0.4064)
			(end 0.7874 -0.4064)
			(stroke
				(width 0.1524)
				(type default)
			)
			(layer "B.SilkS")
		)
		(fp_line
			(start -0.7874 0.4064)
			(end 0.7874 0.4064)
			(stroke
				(width 0.1524)
				(type default)
			)
			(layer "B.SilkS")
		)
		(fp_line
			(start 0.67945 -0.305054)
			(end 0.12065 -0.305054)
			(stroke
				(width 0.1)
				(type default)
			)
			(layer "B.Fab")
		)
		(fp_line
			(start 0.12065 -0.305054)
			(end 0.12065 -0.2794)
			(stroke
				(width 0.1)
				(type default)
			)
			(layer "B.Fab")
		)
		(fp_line
			(start -0.12065 -0.3048)
			(end -0.67945 -0.3048)
			(stroke
				(width 0.1)
				(type default)
			)
			(layer "B.Fab")
		)
		(fp_line
			(start -0.67945 -0.3048)
			(end -0.67945 0.3048)
			(stroke
				(width 0.1)
				(type default)
			)
			(layer "B.Fab")
		)
		(fp_line
			(start 0.12065 -0.2794)
			(end -0.12065 -0.2794)
			(stroke
				(width 0.1)
				(type default)
			)
			(layer "B.Fab")
		)
		(fp_line
			(start -0.12065 -0.2794)
			(end -0.12065 -0.3048)
			(stroke
				(width 0.1)
				(type default)
			)
			(layer "B.Fab")
		)
		(fp_line
			(start 0.12065 0.2794)
			(end 0.12065 0.3048)
			(stroke
				(width 0.1)
				(type default)
			)
			(layer "B.Fab")
		)
		(fp_line
			(start -0.120396 0.2794)
			(end 0.12065 0.2794)
			(stroke
				(width 0.1)
				(type default)
			)
			(layer "B.Fab")
		)
		(fp_line
			(start 0.67945 0.3048)
			(end 0.67945 -0.305054)
			(stroke
				(width 0.1)
				(type default)
			)
			(layer "B.Fab")
		)
		(fp_line
			(start 0.12065 0.3048)
			(end 0.67945 0.3048)
			(stroke
				(width 0.1)
				(type default)
			)
			(layer "B.Fab")
		)
		(fp_line
			(start -0.120396 0.3048)
			(end -0.120396 0.2794)
			(stroke
				(width 0.1)
				(type default)
			)
			(layer "B.Fab")
		)
		(fp_line
			(start -0.67945 0.3048)
			(end -0.120396 0.3048)
			(stroke
				(width 0.1)
				(type default)
			)
			(layer "B.Fab")
		)
		(pad "1" smd circle
			(at 0.40005 0 270)
			(size 0 0)
			(layers "B.Cu" "B.Mask" "B.Paste")
			(net "GPU_PRSNT_N_ISO")
		)
		(pad "2" smd circle
			(at -0.40005 0 270)
			(size 0 0)
			(layers "B.Cu" "B.Mask" "B.Paste")
			(net "GND")
		)
	)
	(footprint ""
		(layer "B.Cu")
		(at 406.698958 -323.846952)
		(property "Reference" "R458"
			(at 0 0 0)
			(layer "B.SilkS")
			(hide yes)
			(effects
				(font
					(size 1.27 1.27)
				)
				(justify mirror)
			)
		)
		(property "Value" ""
			(at 0 0 0)
			(layer "B.Fab")
			(effects
				(font
					(size 1.27 1.27)
				)
				(justify mirror)
			)
		)
		(duplicate_pad_numbers_are_jumpers no)
		(fp_line
			(start -0.7874 -0.4064)
			(end -0.7874 0.4064)
			(stroke
				(width 0.1524)
				(type default)
			)
			(layer "B.SilkS")
		)
		(fp_line
			(start -0.7874 0.4064)
			(end 0.7874 0.4064)
			(stroke
				(width 0.1524)
				(type default)
			)
			(layer "B.SilkS")
		)
		(fp_line
			(start 0.7874 -0.4064)
			(end -0.7874 -0.4064)
			(stroke
				(width 0.1524)
				(type default)
			)
			(layer "B.SilkS")
		)
		(fp_line
			(start 0.7874 0.4064)
			(end 0.7874 -0.4064)
			(stroke
				(width 0.1524)
				(type default)
			)
			(layer "B.SilkS")
		)
		(fp_line
			(start -0.67945 -0.3048)
			(end -0.67945 0.3048)
			(stroke
				(width 0.1)
				(type default)
			)
			(layer "B.Fab")
		)
		(fp_line
			(start -0.67945 0.3048)
			(end -0.120396 0.3048)
			(stroke
				(width 0.1)
				(type default)
			)
			(layer "B.Fab")
		)
		(fp_line
			(start -0.12065 -0.3048)
			(end -0.67945 -0.3048)
			(stroke
				(width 0.1)
				(type default)
			)
			(layer "B.Fab")
		)
		(fp_line
			(start -0.12065 -0.2794)
			(end -0.12065 -0.3048)
			(stroke
				(width 0.1)
				(type default)
			)
			(layer "B.Fab")
		)
		(fp_line
			(start -0.120396 0.2794)
			(end 0.12065 0.2794)
			(stroke
				(width 0.1)
				(type default)
			)
			(layer "B.Fab")
		)
		(fp_line
			(start -0.120396 0.3048)
			(end -0.120396 0.2794)
			(stroke
				(width 0.1)
				(type default)
			)
			(layer "B.Fab")
		)
		(fp_line
			(start 0.12065 -0.305054)
			(end 0.12065 -0.2794)
			(stroke
				(width 0.1)
				(type default)
			)
			(layer "B.Fab")
		)
		(fp_line
			(start 0.12065 -0.2794)
			(end -0.12065 -0.2794)
			(stroke
				(width 0.1)
				(type default)
			)
			(layer "B.Fab")
		)
		(fp_line
			(start 0.12065 0.2794)
			(end 0.12065 0.3048)
			(stroke
				(width 0.1)
				(type default)
			)
			(layer "B.Fab")
		)
		(fp_line
			(start 0.12065 0.3048)
			(end 0.67945 0.3048)
			(stroke
				(width 0.1)
				(type default)
			)
			(layer "B.Fab")
		)
		(fp_line
			(start 0.67945 -0.305054)
			(end 0.12065 -0.305054)
			(stroke
				(width 0.1)
				(type default)
			)
			(layer "B.Fab")
		)
		(fp_line
			(start 0.67945 0.3048)
			(end 0.67945 -0.305054)
			(stroke
				(width 0.1)
				(type default)
			)
			(layer "B.Fab")
		)
		(pad "1" smd circle
			(at 0.40005 0 180)
			(size 0 0)
			(layers "B.Cu" "B.Mask" "B.Paste")
			(net "PVDD18_S5_P0")
		)
		(pad "2" smd circle
			(at -0.40005 0 180)
			(size 0 0)
			(layers "B.Cu" "B.Mask" "B.Paste")
			(net "ESPI_CPU0_ALERT_P0_N")
		)
	)
	(footprint ""
		(layer "B.Cu")
		(at 244.729 -218.186 -90)
		(property "Reference" "R200"
			(at 0 0 90)
			(layer "B.SilkS")
			(hide yes)
			(effects
				(font
					(size 1.27 1.27)
				)
				(justify mirror)
			)
		)
		(property "Value" ""
			(at 0 0 90)
			(layer "B.Fab")
			(effects
				(font
					(size 1.27 1.27)
				)
				(justify mirror)
			)
		)
		(duplicate_pad_numbers_are_jumpers no)
		(fp_line
			(start -0.7874 0.4064)
			(end 0.7874 0.4064)
			(stroke
				(width 0.1524)
				(type default)
			)
			(layer "B.SilkS")
		)
		(fp_line
			(start 0.7874 0.4064)
			(end 0.7874 -0.4064)
			(stroke
				(width 0.1524)
				(type default)
			)
			(layer "B.SilkS")
		)
		(fp_line
			(start -0.7874 -0.4064)
			(end -0.7874 0.4064)
			(stroke
				(width 0.1524)
				(type default)
			)
			(layer "B.SilkS")
		)
		(fp_line
			(start 0.7874 -0.4064)
			(end -0.7874 -0.4064)
			(stroke
				(width 0.1524)
				(type default)
			)
			(layer "B.SilkS")
		)
		(fp_line
			(start -0.67945 0.3048)
			(end -0.120396 0.3048)
			(stroke
				(width 0.1)
				(type default)
			)
			(layer "B.Fab")
		)
		(fp_line
			(start -0.120396 0.3048)
			(end -0.120396 0.2794)
			(stroke
				(width 0.1)
				(type default)
			)
			(layer "B.Fab")
		)
		(fp_line
			(start 0.12065 0.3048)
			(end 0.67945 0.3048)
			(stroke
				(width 0.1)
				(type default)
			)
			(layer "B.Fab")
		)
		(fp_line
			(start 0.67945 0.3048)
			(end 0.67945 -0.305054)
			(stroke
				(width 0.1)
				(type default)
			)
			(layer "B.Fab")
		)
		(fp_line
			(start -0.120396 0.2794)
			(end 0.12065 0.2794)
			(stroke
				(width 0.1)
				(type default)
			)
			(layer "B.Fab")
		)
		(fp_line
			(start 0.12065 0.2794)
			(end 0.12065 0.3048)
			(stroke
				(width 0.1)
				(type default)
			)
			(layer "B.Fab")
		)
		(fp_line
			(start -0.12065 -0.2794)
			(end -0.12065 -0.3048)
			(stroke
				(width 0.1)
				(type default)
			)
			(layer "B.Fab")
		)
		(fp_line
			(start 0.12065 -0.2794)
			(end -0.12065 -0.2794)
			(stroke
				(width 0.1)
				(type default)
			)
			(layer "B.Fab")
		)
		(fp_line
			(start -0.67945 -0.3048)
			(end -0.67945 0.3048)
			(stroke
				(width 0.1)
				(type default)
			)
			(layer "B.Fab")
		)
		(fp_line
			(start -0.12065 -0.3048)
			(end -0.67945 -0.3048)
			(stroke
				(width 0.1)
				(type default)
			)
			(layer "B.Fab")
		)
		(fp_line
			(start 0.12065 -0.305054)
			(end 0.12065 -0.2794)
			(stroke
				(width 0.1)
				(type default)
			)
			(layer "B.Fab")
		)
		(fp_line
			(start 0.67945 -0.305054)
			(end 0.12065 -0.305054)
			(stroke
				(width 0.1)
				(type default)
			)
			(layer "B.Fab")
		)
		(pad "1" smd circle
			(at 0.40005 0 90)
			(size 0 0)
			(layers "B.Cu" "B.Mask" "B.Paste")
			(net "P3V3_AUX")
		)
		(pad "2" smd circle
			(at -0.40005 0 90)
			(size 0 0)
			(layers "B.Cu" "B.Mask" "B.Paste")
			(net "PU_U96_EN")
		)
	)
	(footprint ""
		(layer "B.Cu")
		(at 357.443786 -395.466062 -90)
		(property "Reference" "C588"
			(at 0 0 90)
			(layer "B.SilkS")
			(hide yes)
			(effects
				(font
					(size 1.27 1.27)
				)
				(justify mirror)
			)
		)
		(property "Value" ""
			(at 0 0 90)
			(layer "B.Fab")
			(effects
				(font
					(size 1.27 1.27)
				)
				(justify mirror)
			)
		)
		(duplicate_pad_numbers_are_jumpers no)
		(fp_line
			(start -1.524 0.762)
			(end 1.524 0.762)
			(stroke
				(width 0.1524)
				(type default)
			)
			(layer "B.SilkS")
		)
		(fp_line
			(start 1.524 0.762)
			(end 1.524 -0.762)
			(stroke
				(width 0.1524)
				(type default)
			)
			(layer "B.SilkS")
		)
		(fp_line
			(start -1.524 -0.762)
			(end -1.524 0.762)
			(stroke
				(width 0.1524)
				(type default)
			)
			(layer "B.SilkS")
		)
		(fp_line
			(start 1.524 -0.762)
			(end -1.524 -0.762)
			(stroke
				(width 0.1524)
				(type default)
			)
			(layer "B.SilkS")
		)
		(fp_line
			(start -1.1049 0.724916)
			(end -1.1049 -0.724916)
			(stroke
				(width 0.1)
				(type default)
			)
			(layer "B.Fab")
		)
		(fp_line
			(start 1.1049 0.724916)
			(end -1.1049 0.724916)
			(stroke
				(width 0.1)
				(type default)
			)
			(layer "B.Fab")
		)
		(fp_line
			(start -1.1049 -0.724916)
			(end 1.1049 -0.724916)
			(stroke
				(width 0.1)
				(type default)
			)
			(layer "B.Fab")
		)
		(fp_line
			(start 1.1049 -0.724916)
			(end 1.1049 0.724916)
			(stroke
				(width 0.1)
				(type default)
			)
			(layer "B.Fab")
		)
		(pad "1" smd rect
			(at 0.889 0 270)
			(size 1.016 1.27)
			(layers "B.Cu" "B.Mask" "B.Paste")
			(net "P1V8_CPU0_RT1_1A")
		)
		(pad "2" smd rect
			(at -0.889 0 270)
			(size 1.016 1.27)
			(layers "B.Cu" "B.Mask" "B.Paste")
			(net "GND")
		)
	)
	(footprint ""
		(layer "B.Cu")
		(at 11.853418 -412.85287 180)
		(property "Reference" "PR885"
			(at 0 0 0)
			(layer "B.SilkS")
			(hide yes)
			(effects
				(font
					(size 1.27 1.27)
				)
				(justify mirror)
			)
		)
		(property "Value" ""
			(at 0 0 0)
			(layer "B.Fab")
			(effects
				(font
					(size 1.27 1.27)
				)
				(justify mirror)
			)
		)
		(duplicate_pad_numbers_are_jumpers no)
		(fp_line
			(start 0.7874 0.4064)
			(end 0.7874 -0.4064)
			(stroke
				(width 0.1524)
				(type default)
			)
			(layer "B.SilkS")
		)
		(fp_line
			(start 0.7874 -0.4064)
			(end -0.7874 -0.4064)
			(stroke
				(width 0.1524)
				(type default)
			)
			(layer "B.SilkS")
		)
		(fp_line
			(start -0.7874 0.4064)
			(end 0.7874 0.4064)
			(stroke
				(width 0.1524)
				(type default)
			)
			(layer "B.SilkS")
		)
		(fp_line
			(start -0.7874 -0.4064)
			(end -0.7874 0.4064)
			(stroke
				(width 0.1524)
				(type default)
			)
			(layer "B.SilkS")
		)
		(fp_line
			(start 0.67945 0.3048)
			(end 0.67945 -0.305054)
			(stroke
				(width 0.1)
				(type default)
			)
			(layer "B.Fab")
		)
		(fp_line
			(start 0.67945 -0.305054)
			(end 0.12065 -0.305054)
			(stroke
				(width 0.1)
				(type default)
			)
			(layer "B.Fab")
		)
		(fp_line
			(start 0.12065 0.3048)
			(end 0.67945 0.3048)
			(stroke
				(width 0.1)
				(type default)
			)
			(layer "B.Fab")
		)
		(fp_line
			(start 0.12065 0.2794)
			(end 0.12065 0.3048)
			(stroke
				(width 0.1)
				(type default)
			)
			(layer "B.Fab")
		)
		(fp_line
			(start 0.12065 -0.2794)
			(end -0.12065 -0.2794)
			(stroke
				(width 0.1)
				(type default)
			)
			(layer "B.Fab")
		)
		(fp_line
			(start 0.12065 -0.305054)
			(end 0.12065 -0.2794)
			(stroke
				(width 0.1)
				(type default)
			)
			(layer "B.Fab")
		)
		(fp_line
			(start -0.120396 0.3048)
			(end -0.120396 0.2794)
			(stroke
				(width 0.1)
				(type default)
			)
			(layer "B.Fab")
		)
		(fp_line
			(start -0.120396 0.2794)
			(end 0.12065 0.2794)
			(stroke
				(width 0.1)
				(type default)
			)
			(layer "B.Fab")
		)
		(fp_line
			(start -0.12065 -0.2794)
			(end -0.12065 -0.3048)
			(stroke
				(width 0.1)
				(type default)
			)
			(layer "B.Fab")
		)
		(fp_line
			(start -0.12065 -0.3048)
			(end -0.67945 -0.3048)
			(stroke
				(width 0.1)
				(type default)
			)
			(layer "B.Fab")
		)
		(fp_line
			(start -0.67945 0.3048)
			(end -0.120396 0.3048)
			(stroke
				(width 0.1)
				(type default)
			)
			(layer "B.Fab")
		)
		(fp_line
			(start -0.67945 -0.3048)
			(end -0.67945 0.3048)
			(stroke
				(width 0.1)
				(type default)
			)
			(layer "B.Fab")
		)
		(pad "1" smd circle
			(at 0.40005 0)
			(size 0 0)
			(layers "B.Cu" "B.Mask" "B.Paste")
			(net "P5V_AUX")
		)
		(pad "2" smd circle
			(at -0.40005 0)
			(size 0 0)
			(layers "B.Cu" "B.Mask" "B.Paste")
			(net "P0V9_RETIMER_CPU1_VMON")
		)
	)
	(footprint ""
		(layer "B.Cu")
		(at 106.978958 -340.007194 90)
		(property "Reference" "PC145_6"
			(at 0 0 90)
			(layer "B.SilkS")
			(hide yes)
			(effects
				(font
					(size 1.27 1.27)
				)
				(justify mirror)
			)
		)
		(property "Value" ""
			(at 0 0 90)
			(layer "B.Fab")
			(effects
				(font
					(size 1.27 1.27)
				)
				(justify mirror)
			)
		)
		(duplicate_pad_numbers_are_jumpers no)
		(fp_line
			(start 1.524 -0.762)
			(end -1.524 -0.762)
			(stroke
				(width 0.1524)
				(type default)
			)
			(layer "B.SilkS")
		)
		(fp_line
			(start -1.524 -0.762)
			(end -1.524 0.762)
			(stroke
				(width 0.1524)
				(type default)
			)
			(layer "B.SilkS")
		)
		(fp_line
			(start 1.524 0.762)
			(end 1.524 -0.762)
			(stroke
				(width 0.1524)
				(type default)
			)
			(layer "B.SilkS")
		)
		(fp_line
			(start -1.524 0.762)
			(end 1.524 0.762)
			(stroke
				(width 0.1524)
				(type default)
			)
			(layer "B.SilkS")
		)
		(fp_line
			(start 1.1049 -0.724916)
			(end 1.1049 0.724916)
			(stroke
				(width 0.1)
				(type default)
			)
			(layer "B.Fab")
		)
		(fp_line
			(start -1.1049 -0.724916)
			(end 1.1049 -0.724916)
			(stroke
				(width 0.1)
				(type default)
			)
			(layer "B.Fab")
		)
		(fp_line
			(start 1.1049 0.724916)
			(end -1.1049 0.724916)
			(stroke
				(width 0.1)
				(type default)
			)
			(layer "B.Fab")
		)
		(fp_line
			(start -1.1049 0.724916)
			(end -1.1049 -0.724916)
			(stroke
				(width 0.1)
				(type default)
			)
			(layer "B.Fab")
		)
		(pad "1" smd rect
			(at 0.889 0 90)
			(size 1.016 1.27)
			(layers "B.Cu" "B.Mask" "B.Paste")
			(net "SW_P12V_AUX_PVDDCR_CPU1_P1_FLT")
		)
		(pad "2" smd rect
			(at -0.889 0 90)
			(size 1.016 1.27)
			(layers "B.Cu" "B.Mask" "B.Paste")
			(net "GND")
		)
	)
	(footprint ""
		(layer "B.Cu")
		(at 427.456092 -192.660016 180)
		(property "Reference" "C162"
			(at 0 0 0)
			(layer "B.SilkS")
			(hide yes)
			(effects
				(font
					(size 1.27 1.27)
				)
				(justify mirror)
			)
		)
		(property "Value" ""
			(at 0 0 0)
			(layer "B.Fab")
			(effects
				(font
					(size 1.27 1.27)
				)
				(justify mirror)
			)
		)
		(duplicate_pad_numbers_are_jumpers no)
		(fp_line
			(start 1.524 0.762)
			(end 1.524 -0.762)
			(stroke
				(width 0.1524)
				(type default)
			)
			(layer "B.SilkS")
		)
		(fp_line
			(start 1.524 -0.762)
			(end -1.524 -0.762)
			(stroke
				(width 0.1524)
				(type default)
			)
			(layer "B.SilkS")
		)
		(fp_line
			(start -1.524 0.762)
			(end 1.524 0.762)
			(stroke
				(width 0.1524)
				(type default)
			)
			(layer "B.SilkS")
		)
		(fp_line
			(start -1.524 -0.762)
			(end -1.524 0.762)
			(stroke
				(width 0.1524)
				(type default)
			)
			(layer "B.SilkS")
		)
		(fp_line
			(start 1.1049 0.724916)
			(end -1.1049 0.724916)
			(stroke
				(width 0.1)
				(type default)
			)
			(layer "B.Fab")
		)
		(fp_line
			(start 1.1049 -0.724916)
			(end 1.1049 0.724916)
			(stroke
				(width 0.1)
				(type default)
			)
			(layer "B.Fab")
		)
		(fp_line
			(start -1.1049 0.724916)
			(end -1.1049 -0.724916)
			(stroke
				(width 0.1)
				(type default)
			)
			(layer "B.Fab")
		)
		(fp_line
			(start -1.1049 -0.724916)
			(end 1.1049 -0.724916)
			(stroke
				(width 0.1)
				(type default)
			)
			(layer "B.Fab")
		)
		(pad "1" smd rect
			(at 0.889 0 180)
			(size 1.016 1.27)
			(layers "B.Cu" "B.Mask" "B.Paste")
			(net "P12V_MEM_CPU0")
		)
		(pad "2" smd rect
			(at -0.889 0 180)
			(size 1.016 1.27)
			(layers "B.Cu" "B.Mask" "B.Paste")
			(net "GND")
		)
	)
	(footprint ""
		(layer "B.Cu")
		(at 243.586 -223.139 90)
		(property "Reference" "U96"
			(at -1.194562 3.014472 270)
			(unlocked yes)
			(layer "B.SilkS")
			(effects
				(font
					(size 0.7874 0.5842)
					(thickness 0.1524)
				)
				(justify left mirror)
			)
		)
		(property "Value" ""
			(at 0 0 90)
			(layer "B.Fab")
			(effects
				(font
					(size 1.27 1.27)
				)
				(justify mirror)
			)
		)
		(duplicate_pad_numbers_are_jumpers no)
		(fp_line
			(start 1.463548 -1.549908)
			(end 0.787908 -1.549908)
			(stroke
				(width 0.1524)
				(type default)
			)
			(layer "B.SilkS")
		)
		(fp_line
			(start 0.787908 -1.549908)
			(end 0 -0.762)
			(stroke
				(width 0.1524)
				(type default)
			)
			(layer "B.SilkS")
		)
		(fp_line
			(start -0.762 -1.549908)
			(end -1.463548 -1.549908)
			(stroke
				(width 0.1524)
				(type default)
			)
			(layer "B.SilkS")
		)
		(fp_line
			(start -1.463548 -1.549908)
			(end -1.463548 1.549908)
			(stroke
				(width 0.1524)
				(type default)
			)
			(layer "B.SilkS")
		)
		(fp_line
			(start 0 -0.762)
			(end -0.762 -1.549908)
			(stroke
				(width 0.1524)
				(type default)
			)
			(layer "B.SilkS")
		)
		(fp_line
			(start 1.463548 1.549908)
			(end 1.463548 -1.549908)
			(stroke
				(width 0.1524)
				(type default)
			)
			(layer "B.SilkS")
		)
		(fp_line
			(start -1.463548 1.549908)
			(end 1.463548 1.549908)
			(stroke
				(width 0.1524)
				(type default)
			)
			(layer "B.SilkS")
		)
		(fp_poly
			(pts
				(xy 3.4417 -0.959866) (xy 3.4417 -1.579626) (xy 2.82194 -1.269746)
			)
			(stroke
				(width 0)
				(type default)
			)
			(fill yes)
			(layer "B.SilkS")
		)
		(fp_line
			(start 1.549908 -1.549908)
			(end -1.549908 -1.549908)
			(stroke
				(width 0.1)
				(type default)
			)
			(layer "B.Fab")
		)
		(fp_line
			(start -1.549908 -1.549908)
			(end -1.549908 1.549908)
			(stroke
				(width 0.1)
				(type default)
			)
			(layer "B.Fab")
		)
		(fp_line
			(start 1.549908 1.549908)
			(end 1.549908 -1.549908)
			(stroke
				(width 0.1)
				(type default)
			)
			(layer "B.Fab")
		)
		(fp_line
			(start -1.549908 1.549908)
			(end 1.549908 1.549908)
			(stroke
				(width 0.1)
				(type default)
			)
			(layer "B.Fab")
		)
		(fp_poly
			(pts
				(xy 3.4798 -1.359916) (xy 2.86004 -1.050036) (xy 3.4798 -0.740156)
			)
			(stroke
				(width 0)
				(type default)
			)
			(fill yes)
			(layer "B.Fab")
		)
		(pad "1" smd rect
			(at 2.175002 -1.050036 180)
			(size 0.6096 1.1684)
			(layers "B.Cu" "B.Mask" "B.Paste")
			(net "PVDD18_S5_P0")
		)
		(pad "2" smd rect
			(at 2.175002 -0.32512 180)
			(size 0.4318 1.1684)
			(layers "B.Cu" "B.Mask" "B.Paste")
			(net "SMB_CPU0_CPU1_SEC_SCL_R1")
		)
		(pad "3" smd rect
			(at 2.175002 0.32512 180)
			(size 0.4318 1.1684)
			(layers "B.Cu" "B.Mask" "B.Paste")
			(net "SMB_CPU0_CPU1_SEC_SDA_R1")
		)
		(pad "4" smd rect
			(at 2.175002 1.050036 180)
			(size 0.6096 1.1684)
			(layers "B.Cu" "B.Mask" "B.Paste")
			(net "GND")
		)
		(pad "5" smd rect
			(at -2.175002 1.050036 180)
			(size 0.6096 1.1684)
			(layers "B.Cu" "B.Mask" "B.Paste")
			(net "PU_U96_EN")
		)
		(pad "6" smd rect
			(at -2.175002 0.32512 180)
			(size 0.4318 1.1684)
			(layers "B.Cu" "B.Mask" "B.Paste")
			(net "SMB_CPU0_CPU1_SEC_SDA")
		)
		(pad "7" smd rect
			(at -2.175002 -0.32512 180)
			(size 0.4318 1.1684)
			(layers "B.Cu" "B.Mask" "B.Paste")
			(net "SMB_CPU0_CPU1_SEC_SCL")
		)
		(pad "8" smd rect
			(at -2.175002 -1.050036 180)
			(size 0.6096 1.1684)
			(layers "B.Cu" "B.Mask" "B.Paste")
			(net "P3V3_AUX")
		)
	)
	(footprint ""
		(layer "B.Cu")
		(at 371.551454 -250.89231)
		(property "Reference" "C2166"
			(at 0 0 0)
			(layer "B.SilkS")
			(hide yes)
			(effects
				(font
					(size 1.27 1.27)
				)
				(justify mirror)
			)
		)
		(property "Value" ""
			(at 0 0 0)
			(layer "B.Fab")
			(effects
				(font
					(size 1.27 1.27)
				)
				(justify mirror)
			)
		)
		(duplicate_pad_numbers_are_jumpers no)
		(fp_line
			(start -0.7874 -0.4064)
			(end -0.7874 0.4064)
			(stroke
				(width 0.1524)
				(type default)
			)
			(layer "B.SilkS")
		)
		(fp_line
			(start -0.7874 0.4064)
			(end 0.7874 0.4064)
			(stroke
				(width 0.1524)
				(type default)
			)
			(layer "B.SilkS")
		)
		(fp_line
			(start 0.7874 -0.4064)
			(end -0.7874 -0.4064)
			(stroke
				(width 0.1524)
				(type default)
			)
			(layer "B.SilkS")
		)
		(fp_line
			(start 0.7874 0.4064)
			(end 0.7874 -0.4064)
			(stroke
				(width 0.1524)
				(type default)
			)
			(layer "B.SilkS")
		)
		(fp_line
			(start -0.67945 -0.3048)
			(end -0.67945 0.3048)
			(stroke
				(width 0.1)
				(type default)
			)
			(layer "B.Fab")
		)
		(fp_line
			(start -0.67945 0.3048)
			(end -0.120396 0.3048)
			(stroke
				(width 0.1)
				(type default)
			)
			(layer "B.Fab")
		)
		(fp_line
			(start -0.12065 -0.3048)
			(end -0.67945 -0.3048)
			(stroke
				(width 0.1)
				(type default)
			)
			(layer "B.Fab")
		)
		(fp_line
			(start -0.12065 -0.2794)
			(end -0.12065 -0.3048)
			(stroke
				(width 0.1)
				(type default)
			)
			(layer "B.Fab")
		)
		(fp_line
			(start -0.120396 0.2794)
			(end 0.12065 0.2794)
			(stroke
				(width 0.1)
				(type default)
			)
			(layer "B.Fab")
		)
		(fp_line
			(start -0.120396 0.3048)
			(end -0.120396 0.2794)
			(stroke
				(width 0.1)
				(type default)
			)
			(layer "B.Fab")
		)
		(fp_line
			(start 0.12065 -0.305054)
			(end 0.12065 -0.2794)
			(stroke
				(width 0.1)
				(type default)
			)
			(layer "B.Fab")
		)
		(fp_line
			(start 0.12065 -0.2794)
			(end -0.12065 -0.2794)
			(stroke
				(width 0.1)
				(type default)
			)
			(layer "B.Fab")
		)
		(fp_line
			(start 0.12065 0.2794)
			(end 0.12065 0.3048)
			(stroke
				(width 0.1)
				(type default)
			)
			(layer "B.Fab")
		)
		(fp_line
			(start 0.12065 0.3048)
			(end 0.67945 0.3048)
			(stroke
				(width 0.1)
				(type default)
			)
			(layer "B.Fab")
		)
		(fp_line
			(start 0.67945 -0.305054)
			(end 0.12065 -0.305054)
			(stroke
				(width 0.1)
				(type default)
			)
			(layer "B.Fab")
		)
		(fp_line
			(start 0.67945 0.3048)
			(end 0.67945 -0.305054)
			(stroke
				(width 0.1)
				(type default)
			)
			(layer "B.Fab")
		)
		(pad "1" smd circle
			(at 0.40005 0 180)
			(size 0 0)
			(layers "B.Cu" "B.Mask" "B.Paste")
			(net "PVDDCR_CPU0_P0")
		)
		(pad "2" smd circle
			(at -0.40005 0 180)
			(size 0 0)
			(layers "B.Cu" "B.Mask" "B.Paste")
			(net "GND")
		)
	)
	(footprint ""
		(layer "B.Cu")
		(at 426.53585 -34.737548 180)
		(property "Reference" "R734"
			(at 0 0 0)
			(layer "B.SilkS")
			(hide yes)
			(effects
				(font
					(size 1.27 1.27)
				)
				(justify mirror)
			)
		)
		(property "Value" ""
			(at 0 0 0)
			(layer "B.Fab")
			(effects
				(font
					(size 1.27 1.27)
				)
				(justify mirror)
			)
		)
		(duplicate_pad_numbers_are_jumpers no)
		(fp_line
			(start 0.7874 0.4064)
			(end 0.7874 -0.4064)
			(stroke
				(width 0.1524)
				(type default)
			)
			(layer "B.SilkS")
		)
		(fp_line
			(start 0.7874 -0.4064)
			(end -0.7874 -0.4064)
			(stroke
				(width 0.1524)
				(type default)
			)
			(layer "B.SilkS")
		)
		(fp_line
			(start -0.7874 0.4064)
			(end 0.7874 0.4064)
			(stroke
				(width 0.1524)
				(type default)
			)
			(layer "B.SilkS")
		)
		(fp_line
			(start -0.7874 -0.4064)
			(end -0.7874 0.4064)
			(stroke
				(width 0.1524)
				(type default)
			)
			(layer "B.SilkS")
		)
		(fp_line
			(start 0.67945 0.3048)
			(end 0.67945 -0.305054)
			(stroke
				(width 0.1)
				(type default)
			)
			(layer "B.Fab")
		)
		(fp_line
			(start 0.67945 -0.305054)
			(end 0.12065 -0.305054)
			(stroke
				(width 0.1)
				(type default)
			)
			(layer "B.Fab")
		)
		(fp_line
			(start 0.12065 0.3048)
			(end 0.67945 0.3048)
			(stroke
				(width 0.1)
				(type default)
			)
			(layer "B.Fab")
		)
		(fp_line
			(start 0.12065 0.2794)
			(end 0.12065 0.3048)
			(stroke
				(width 0.1)
				(type default)
			)
			(layer "B.Fab")
		)
		(fp_line
			(start 0.12065 -0.2794)
			(end -0.12065 -0.2794)
			(stroke
				(width 0.1)
				(type default)
			)
			(layer "B.Fab")
		)
		(fp_line
			(start 0.12065 -0.305054)
			(end 0.12065 -0.2794)
			(stroke
				(width 0.1)
				(type default)
			)
			(layer "B.Fab")
		)
		(fp_line
			(start -0.120396 0.3048)
			(end -0.120396 0.2794)
			(stroke
				(width 0.1)
				(type default)
			)
			(layer "B.Fab")
		)
		(fp_line
			(start -0.120396 0.2794)
			(end 0.12065 0.2794)
			(stroke
				(width 0.1)
				(type default)
			)
			(layer "B.Fab")
		)
		(fp_line
			(start -0.12065 -0.2794)
			(end -0.12065 -0.3048)
			(stroke
				(width 0.1)
				(type default)
			)
			(layer "B.Fab")
		)
		(fp_line
			(start -0.12065 -0.3048)
			(end -0.67945 -0.3048)
			(stroke
				(width 0.1)
				(type default)
			)
			(layer "B.Fab")
		)
		(fp_line
			(start -0.67945 0.3048)
			(end -0.120396 0.3048)
			(stroke
				(width 0.1)
				(type default)
			)
			(layer "B.Fab")
		)
		(fp_line
			(start -0.67945 -0.3048)
			(end -0.67945 0.3048)
			(stroke
				(width 0.1)
				(type default)
			)
			(layer "B.Fab")
		)
		(pad "1" smd circle
			(at 0.40005 0)
			(size 0 0)
			(layers "B.Cu" "B.Mask" "B.Paste")
			(net "PRSNT_CPU0_N")
		)
		(pad "2" smd circle
			(at -0.40005 0)
			(size 0 0)
			(layers "B.Cu" "B.Mask" "B.Paste")
			(net "FM_PRSNT_CPU0_N")
		)
	)
	(footprint ""
		(layer "B.Cu")
		(at 381.418338 -396.393162 -90)
		(property "Reference" "C1002"
			(at 0 0 90)
			(layer "B.SilkS")
			(hide yes)
			(effects
				(font
					(size 1.27 1.27)
				)
				(justify mirror)
			)
		)
		(property "Value" ""
			(at 0 0 90)
			(layer "B.Fab")
			(effects
				(font
					(size 1.27 1.27)
				)
				(justify mirror)
			)
		)
		(duplicate_pad_numbers_are_jumpers no)
		(fp_line
			(start -0.299974 0.150114)
			(end 0.299974 0.150114)
			(stroke
				(width 0.1)
				(type default)
			)
			(layer "B.Fab")
		)
		(fp_line
			(start 0.299974 0.150114)
			(end 0.299974 -0.150114)
			(stroke
				(width 0.1)
				(type default)
			)
			(layer "B.Fab")
		)
		(fp_line
			(start -0.299974 -0.150114)
			(end -0.299974 0.150114)
			(stroke
				(width 0.1)
				(type default)
			)
			(layer "B.Fab")
		)
		(fp_line
			(start 0.299974 -0.150114)
			(end -0.299974 -0.150114)
			(stroke
				(width 0.1)
				(type default)
			)
			(layer "B.Fab")
		)
		(pad "1" smd rect
			(at 0.2667 0 90)
			(size 0.3048 0.381)
			(layers "B.Cu" "B.Mask" "B.Paste")
			(net "P1V8_CPU0_RT3_1A_1D")
		)
		(pad "2" smd rect
			(at -0.2667 0 90)
			(size 0.3048 0.381)
			(layers "B.Cu" "B.Mask" "B.Paste")
			(net "GND")
		)
	)
	(footprint ""
		(layer "B.Cu")
		(at 423.256456 -195.85051 180)
		(property "Reference" "R1681"
			(at 0 0 0)
			(layer "B.SilkS")
			(hide yes)
			(effects
				(font
					(size 1.27 1.27)
				)
				(justify mirror)
			)
		)
		(property "Value" ""
			(at 0 0 0)
			(layer "B.Fab")
			(effects
				(font
					(size 1.27 1.27)
				)
				(justify mirror)
			)
		)
		(duplicate_pad_numbers_are_jumpers no)
		(fp_line
			(start 0.7874 0.4064)
			(end 0.7874 -0.4064)
			(stroke
				(width 0.1524)
				(type default)
			)
			(layer "B.SilkS")
		)
		(fp_line
			(start 0.7874 -0.4064)
			(end -0.7874 -0.4064)
			(stroke
				(width 0.1524)
				(type default)
			)
			(layer "B.SilkS")
		)
		(fp_line
			(start -0.7874 0.4064)
			(end 0.7874 0.4064)
			(stroke
				(width 0.1524)
				(type default)
			)
			(layer "B.SilkS")
		)
		(fp_line
			(start -0.7874 -0.4064)
			(end -0.7874 0.4064)
			(stroke
				(width 0.1524)
				(type default)
			)
			(layer "B.SilkS")
		)
		(fp_line
			(start 0.67945 0.3048)
			(end 0.67945 -0.305054)
			(stroke
				(width 0.1)
				(type default)
			)
			(layer "B.Fab")
		)
		(fp_line
			(start 0.67945 -0.305054)
			(end 0.12065 -0.305054)
			(stroke
				(width 0.1)
				(type default)
			)
			(layer "B.Fab")
		)
		(fp_line
			(start 0.12065 0.3048)
			(end 0.67945 0.3048)
			(stroke
				(width 0.1)
				(type default)
			)
			(layer "B.Fab")
		)
		(fp_line
			(start 0.12065 0.2794)
			(end 0.12065 0.3048)
			(stroke
				(width 0.1)
				(type default)
			)
			(layer "B.Fab")
		)
		(fp_line
			(start 0.12065 -0.2794)
			(end -0.12065 -0.2794)
			(stroke
				(width 0.1)
				(type default)
			)
			(layer "B.Fab")
		)
		(fp_line
			(start 0.12065 -0.305054)
			(end 0.12065 -0.2794)
			(stroke
				(width 0.1)
				(type default)
			)
			(layer "B.Fab")
		)
		(fp_line
			(start -0.120396 0.3048)
			(end -0.120396 0.2794)
			(stroke
				(width 0.1)
				(type default)
			)
			(layer "B.Fab")
		)
		(fp_line
			(start -0.120396 0.2794)
			(end 0.12065 0.2794)
			(stroke
				(width 0.1)
				(type default)
			)
			(layer "B.Fab")
		)
		(fp_line
			(start -0.12065 -0.2794)
			(end -0.12065 -0.3048)
			(stroke
				(width 0.1)
				(type default)
			)
			(layer "B.Fab")
		)
		(fp_line
			(start -0.12065 -0.3048)
			(end -0.67945 -0.3048)
			(stroke
				(width 0.1)
				(type default)
			)
			(layer "B.Fab")
		)
		(fp_line
			(start -0.67945 0.3048)
			(end -0.120396 0.3048)
			(stroke
				(width 0.1)
				(type default)
			)
			(layer "B.Fab")
		)
		(fp_line
			(start -0.67945 -0.3048)
			(end -0.67945 0.3048)
			(stroke
				(width 0.1)
				(type default)
			)
			(layer "B.Fab")
		)
		(pad "1" smd circle
			(at 0.40005 0)
			(size 0 0)
			(layers "B.Cu" "B.Mask" "B.Paste")
			(net "I3C_SPD_DDRGL_CPU0_SDA")
		)
		(pad "2" smd circle
			(at -0.40005 0)
			(size 0 0)
			(layers "B.Cu" "B.Mask" "B.Paste")
			(net "I3C_SPD_DDRH_CPU0_SDA")
		)
	)
	(footprint ""
		(layer "B.Cu")
		(at 348.151958 -261.870952)
		(property "Reference" "C2650"
			(at 0 0 0)
			(layer "B.SilkS")
			(hide yes)
			(effects
				(font
					(size 1.27 1.27)
				)
				(justify mirror)
			)
		)
		(property "Value" ""
			(at 0 0 0)
			(layer "B.Fab")
			(effects
				(font
					(size 1.27 1.27)
				)
				(justify mirror)
			)
		)
		(duplicate_pad_numbers_are_jumpers no)
		(fp_line
			(start -0.7874 -0.4064)
			(end -0.7874 0.4064)
			(stroke
				(width 0.1524)
				(type default)
			)
			(layer "B.SilkS")
		)
		(fp_line
			(start -0.7874 0.4064)
			(end 0.7874 0.4064)
			(stroke
				(width 0.1524)
				(type default)
			)
			(layer "B.SilkS")
		)
		(fp_line
			(start 0.7874 -0.4064)
			(end -0.7874 -0.4064)
			(stroke
				(width 0.1524)
				(type default)
			)
			(layer "B.SilkS")
		)
		(fp_line
			(start 0.7874 0.4064)
			(end 0.7874 -0.4064)
			(stroke
				(width 0.1524)
				(type default)
			)
			(layer "B.SilkS")
		)
		(fp_line
			(start -0.67945 -0.3048)
			(end -0.67945 0.3048)
			(stroke
				(width 0.1)
				(type default)
			)
			(layer "B.Fab")
		)
		(fp_line
			(start -0.67945 0.3048)
			(end -0.120396 0.3048)
			(stroke
				(width 0.1)
				(type default)
			)
			(layer "B.Fab")
		)
		(fp_line
			(start -0.12065 -0.3048)
			(end -0.67945 -0.3048)
			(stroke
				(width 0.1)
				(type default)
			)
			(layer "B.Fab")
		)
		(fp_line
			(start -0.12065 -0.2794)
			(end -0.12065 -0.3048)
			(stroke
				(width 0.1)
				(type default)
			)
			(layer "B.Fab")
		)
		(fp_line
			(start -0.120396 0.2794)
			(end 0.12065 0.2794)
			(stroke
				(width 0.1)
				(type default)
			)
			(layer "B.Fab")
		)
		(fp_line
			(start -0.120396 0.3048)
			(end -0.120396 0.2794)
			(stroke
				(width 0.1)
				(type default)
			)
			(layer "B.Fab")
		)
		(fp_line
			(start 0.12065 -0.305054)
			(end 0.12065 -0.2794)
			(stroke
				(width 0.1)
				(type default)
			)
			(layer "B.Fab")
		)
		(fp_line
			(start 0.12065 -0.2794)
			(end -0.12065 -0.2794)
			(stroke
				(width 0.1)
				(type default)
			)
			(layer "B.Fab")
		)
		(fp_line
			(start 0.12065 0.2794)
			(end 0.12065 0.3048)
			(stroke
				(width 0.1)
				(type default)
			)
			(layer "B.Fab")
		)
		(fp_line
			(start 0.12065 0.3048)
			(end 0.67945 0.3048)
			(stroke
				(width 0.1)
				(type default)
			)
			(layer "B.Fab")
		)
		(fp_line
			(start 0.67945 -0.305054)
			(end 0.12065 -0.305054)
			(stroke
				(width 0.1)
				(type default)
			)
			(layer "B.Fab")
		)
		(fp_line
			(start 0.67945 0.3048)
			(end 0.67945 -0.305054)
			(stroke
				(width 0.1)
				(type default)
			)
			(layer "B.Fab")
		)
		(pad "1" smd circle
			(at 0.40005 0 180)
			(size 0 0)
			(layers "B.Cu" "B.Mask" "B.Paste")
			(net "PVDDIO_P0")
		)
		(pad "2" smd circle
			(at -0.40005 0 180)
			(size 0 0)
			(layers "B.Cu" "B.Mask" "B.Paste")
			(net "GND")
		)
	)
	(footprint ""
		(layer "B.Cu")
		(at 90.036904 -408.517344 90)
		(property "Reference" "C6687"
			(at 0 0 90)
			(layer "B.SilkS")
			(hide yes)
			(effects
				(font
					(size 1.27 1.27)
				)
				(justify mirror)
			)
		)
		(property "Value" ""
			(at 0 0 90)
			(layer "B.Fab")
			(effects
				(font
					(size 1.27 1.27)
				)
				(justify mirror)
			)
		)
		(duplicate_pad_numbers_are_jumpers no)
		(fp_line
			(start 0.299974 -0.150114)
			(end -0.299974 -0.150114)
			(stroke
				(width 0.1)
				(type default)
			)
			(layer "B.Fab")
		)
		(fp_line
			(start -0.299974 -0.150114)
			(end -0.299974 0.150114)
			(stroke
				(width 0.1)
				(type default)
			)
			(layer "B.Fab")
		)
		(fp_line
			(start 0.299974 0.150114)
			(end 0.299974 -0.150114)
			(stroke
				(width 0.1)
				(type default)
			)
			(layer "B.Fab")
		)
		(fp_line
			(start -0.299974 0.150114)
			(end 0.299974 0.150114)
			(stroke
				(width 0.1)
				(type default)
			)
			(layer "B.Fab")
		)
		(pad "1" smd rect
			(at 0.2667 0 270)
			(size 0.3048 0.381)
			(layers "B.Cu" "B.Mask" "B.Paste")
			(net "P5E_CPU1_P1_TX_BUF_C_DP<13>")
		)
		(pad "2" smd rect
			(at -0.2667 0 270)
			(size 0.3048 0.381)
			(layers "B.Cu" "B.Mask" "B.Paste")
			(net "P5E_CPU1_P1_TX_BUF_DP<13>")
		)
	)
	(footprint ""
		(layer "B.Cu")
		(at 396.989554 -401.624546 180)
		(property "Reference" "R1053"
			(at 0 0 0)
			(layer "B.SilkS")
			(hide yes)
			(effects
				(font
					(size 1.27 1.27)
				)
				(justify mirror)
			)
		)
		(property "Value" ""
			(at 0 0 0)
			(layer "B.Fab")
			(effects
				(font
					(size 1.27 1.27)
				)
				(justify mirror)
			)
		)
		(duplicate_pad_numbers_are_jumpers no)
		(fp_line
			(start 1.2954 0.5842)
			(end 1.2954 -0.5842)
			(stroke
				(width 0.1524)
				(type default)
			)
			(layer "B.SilkS")
		)
		(fp_line
			(start 1.2954 -0.5842)
			(end -1.2954 -0.5842)
			(stroke
				(width 0.1524)
				(type default)
			)
			(layer "B.SilkS")
		)
		(fp_line
			(start -1.2954 0.5842)
			(end 1.2954 0.5842)
			(stroke
				(width 0.1524)
				(type default)
			)
			(layer "B.SilkS")
		)
		(fp_line
			(start -1.2954 -0.5842)
			(end -1.2954 0.5842)
			(stroke
				(width 0.1524)
				(type default)
			)
			(layer "B.SilkS")
		)
		(fp_line
			(start 1.1938 0.4064)
			(end 1.1938 -0.406654)
			(stroke
				(width 0.1)
				(type default)
			)
			(layer "B.Fab")
		)
		(fp_line
			(start 1.1938 -0.406654)
			(end 0.8636 -0.406654)
			(stroke
				(width 0.1)
				(type default)
			)
			(layer "B.Fab")
		)
		(fp_line
			(start 0.8636 0.4572)
			(end 0.8636 0.4318)
			(stroke
				(width 0.1)
				(type default)
			)
			(layer "B.Fab")
		)
		(fp_line
			(start 0.8636 0.4318)
			(end 0.8636 0.4064)
			(stroke
				(width 0.1)
				(type default)
			)
			(layer "B.Fab")
		)
		(fp_line
			(start 0.8636 0.4064)
			(end 1.1938 0.4064)
			(stroke
				(width 0.1)
				(type default)
			)
			(layer "B.Fab")
		)
		(fp_line
			(start 0.8636 -0.406654)
			(end 0.8636 -0.4572)
			(stroke
				(width 0.1)
				(type default)
			)
			(layer "B.Fab")
		)
		(fp_line
			(start 0.8636 -0.4572)
			(end -0.8636 -0.4572)
			(stroke
				(width 0.1)
				(type default)
			)
			(layer "B.Fab")
		)
		(fp_line
			(start -0.8636 0.4572)
			(end 0.8636 0.4572)
			(stroke
				(width 0.1)
				(type default)
			)
			(layer "B.Fab")
		)
		(fp_line
			(start -0.8636 0.4064)
			(end -0.8636 0.4572)
			(stroke
				(width 0.1)
				(type default)
			)
			(layer "B.Fab")
		)
		(fp_line
			(start -0.8636 -0.406654)
			(end -1.1938 -0.406654)
			(stroke
				(width 0.1)
				(type default)
			)
			(layer "B.Fab")
		)
		(fp_line
			(start -0.8636 -0.4572)
			(end -0.8636 -0.406654)
			(stroke
				(width 0.1)
				(type default)
			)
			(layer "B.Fab")
		)
		(fp_line
			(start -1.1938 0.4064)
			(end -0.8636 0.4064)
			(stroke
				(width 0.1)
				(type default)
			)
			(layer "B.Fab")
		)
		(fp_line
			(start -1.1938 -0.406654)
			(end -1.1938 0.4064)
			(stroke
				(width 0.1)
				(type default)
			)
			(layer "B.Fab")
		)
		(pad "1" smd rect
			(at 0.7366 0 90)
			(size 0.7112 0.8128)
			(layers "B.Cu" "B.Mask" "B.Paste")
			(net "P0V9_CPU0_RT2_2A_2D")
		)
		(pad "2" smd rect
			(at -0.7366 0 90)
			(size 0.7112 0.8128)
			(layers "B.Cu" "B.Mask" "B.Paste")
			(net "P0V9_CPU0_RT2_2A")
		)
	)
	(footprint ""
		(layer "B.Cu")
		(at 110.48746 -35.088068 90)
		(property "Reference" "C6115"
			(at 0 0 90)
			(layer "B.SilkS")
			(hide yes)
			(effects
				(font
					(size 1.27 1.27)
				)
				(justify mirror)
			)
		)
		(property "Value" ""
			(at 0 0 90)
			(layer "B.Fab")
			(effects
				(font
					(size 1.27 1.27)
				)
				(justify mirror)
			)
		)
		(duplicate_pad_numbers_are_jumpers no)
		(fp_line
			(start 0.7874 -0.4064)
			(end -0.7874 -0.4064)
			(stroke
				(width 0.1524)
				(type default)
			)
			(layer "B.SilkS")
		)
		(fp_line
			(start -0.7874 -0.4064)
			(end -0.7874 0.4064)
			(stroke
				(width 0.1524)
				(type default)
			)
			(layer "B.SilkS")
		)
		(fp_line
			(start 0.7874 0.4064)
			(end 0.7874 -0.4064)
			(stroke
				(width 0.1524)
				(type default)
			)
			(layer "B.SilkS")
		)
		(fp_line
			(start -0.7874 0.4064)
			(end 0.7874 0.4064)
			(stroke
				(width 0.1524)
				(type default)
			)
			(layer "B.SilkS")
		)
		(fp_line
			(start 0.67945 -0.305054)
			(end 0.12065 -0.305054)
			(stroke
				(width 0.1)
				(type default)
			)
			(layer "B.Fab")
		)
		(fp_line
			(start 0.12065 -0.305054)
			(end 0.12065 -0.2794)
			(stroke
				(width 0.1)
				(type default)
			)
			(layer "B.Fab")
		)
		(fp_line
			(start -0.12065 -0.3048)
			(end -0.67945 -0.3048)
			(stroke
				(width 0.1)
				(type default)
			)
			(layer "B.Fab")
		)
		(fp_line
			(start -0.67945 -0.3048)
			(end -0.67945 0.3048)
			(stroke
				(width 0.1)
				(type default)
			)
			(layer "B.Fab")
		)
		(fp_line
			(start 0.12065 -0.2794)
			(end -0.12065 -0.2794)
			(stroke
				(width 0.1)
				(type default)
			)
			(layer "B.Fab")
		)
		(fp_line
			(start -0.12065 -0.2794)
			(end -0.12065 -0.3048)
			(stroke
				(width 0.1)
				(type default)
			)
			(layer "B.Fab")
		)
		(fp_line
			(start 0.12065 0.2794)
			(end 0.12065 0.3048)
			(stroke
				(width 0.1)
				(type default)
			)
			(layer "B.Fab")
		)
		(fp_line
			(start -0.120396 0.2794)
			(end 0.12065 0.2794)
			(stroke
				(width 0.1)
				(type default)
			)
			(layer "B.Fab")
		)
		(fp_line
			(start 0.67945 0.3048)
			(end 0.67945 -0.305054)
			(stroke
				(width 0.1)
				(type default)
			)
			(layer "B.Fab")
		)
		(fp_line
			(start 0.12065 0.3048)
			(end 0.67945 0.3048)
			(stroke
				(width 0.1)
				(type default)
			)
			(layer "B.Fab")
		)
		(fp_line
			(start -0.120396 0.3048)
			(end -0.120396 0.2794)
			(stroke
				(width 0.1)
				(type default)
			)
			(layer "B.Fab")
		)
		(fp_line
			(start -0.67945 0.3048)
			(end -0.120396 0.3048)
			(stroke
				(width 0.1)
				(type default)
			)
			(layer "B.Fab")
		)
		(pad "1" smd circle
			(at 0.40005 0 270)
			(size 0 0)
			(layers "B.Cu" "B.Mask" "B.Paste")
			(net "P1V2_CPU0_USB2_DVDD12")
		)
		(pad "2" smd circle
			(at -0.40005 0 270)
			(size 0 0)
			(layers "B.Cu" "B.Mask" "B.Paste")
			(net "GND")
		)
	)
	(footprint ""
		(layer "B.Cu")
		(at 400.727672 -396.991078 90)
		(property "Reference" "C784"
			(at 0 0 90)
			(layer "B.SilkS")
			(hide yes)
			(effects
				(font
					(size 1.27 1.27)
				)
				(justify mirror)
			)
		)
		(property "Value" ""
			(at 0 0 90)
			(layer "B.Fab")
			(effects
				(font
					(size 1.27 1.27)
				)
				(justify mirror)
			)
		)
		(duplicate_pad_numbers_are_jumpers no)
		(fp_line
			(start 0.299974 -0.150114)
			(end -0.299974 -0.150114)
			(stroke
				(width 0.1)
				(type default)
			)
			(layer "B.Fab")
		)
		(fp_line
			(start -0.299974 -0.150114)
			(end -0.299974 0.150114)
			(stroke
				(width 0.1)
				(type default)
			)
			(layer "B.Fab")
		)
		(fp_line
			(start 0.299974 0.150114)
			(end 0.299974 -0.150114)
			(stroke
				(width 0.1)
				(type default)
			)
			(layer "B.Fab")
		)
		(fp_line
			(start -0.299974 0.150114)
			(end 0.299974 0.150114)
			(stroke
				(width 0.1)
				(type default)
			)
			(layer "B.Fab")
		)
		(pad "1" smd rect
			(at 0.2667 0 270)
			(size 0.3048 0.381)
			(layers "B.Cu" "B.Mask" "B.Paste")
			(net "P0V9_CPU0_RT2_2A")
		)
		(pad "2" smd rect
			(at -0.2667 0 270)
			(size 0.3048 0.381)
			(layers "B.Cu" "B.Mask" "B.Paste")
			(net "GND")
		)
	)
	(footprint ""
		(layer "B.Cu")
		(at 346.92082 -326.820276 -90)
		(property "Reference" "PC141_5"
			(at 0 0 90)
			(layer "B.SilkS")
			(hide yes)
			(effects
				(font
					(size 1.27 1.27)
				)
				(justify mirror)
			)
		)
		(property "Value" ""
			(at 0 0 90)
			(layer "B.Fab")
			(effects
				(font
					(size 1.27 1.27)
				)
				(justify mirror)
			)
		)
		(duplicate_pad_numbers_are_jumpers no)
		(fp_line
			(start -1.524 0.762)
			(end 1.524 0.762)
			(stroke
				(width 0.1524)
				(type default)
			)
			(layer "B.SilkS")
		)
		(fp_line
			(start 1.524 0.762)
			(end 1.524 -0.762)
			(stroke
				(width 0.1524)
				(type default)
			)
			(layer "B.SilkS")
		)
		(fp_line
			(start -1.524 -0.762)
			(end -1.524 0.762)
			(stroke
				(width 0.1524)
				(type default)
			)
			(layer "B.SilkS")
		)
		(fp_line
			(start 1.524 -0.762)
			(end -1.524 -0.762)
			(stroke
				(width 0.1524)
				(type default)
			)
			(layer "B.SilkS")
		)
		(fp_line
			(start -1.1049 0.724916)
			(end -1.1049 -0.724916)
			(stroke
				(width 0.1)
				(type default)
			)
			(layer "B.Fab")
		)
		(fp_line
			(start 1.1049 0.724916)
			(end -1.1049 0.724916)
			(stroke
				(width 0.1)
				(type default)
			)
			(layer "B.Fab")
		)
		(fp_line
			(start -1.1049 -0.724916)
			(end 1.1049 -0.724916)
			(stroke
				(width 0.1)
				(type default)
			)
			(layer "B.Fab")
		)
		(fp_line
			(start 1.1049 -0.724916)
			(end 1.1049 0.724916)
			(stroke
				(width 0.1)
				(type default)
			)
			(layer "B.Fab")
		)
		(pad "1" smd rect
			(at 0.889 0 270)
			(size 1.016 1.27)
			(layers "B.Cu" "B.Mask" "B.Paste")
			(net "PVDDCR_CPU1_P0")
		)
		(pad "2" smd rect
			(at -0.889 0 270)
			(size 1.016 1.27)
			(layers "B.Cu" "B.Mask" "B.Paste")
			(net "GND")
		)
	)
	(footprint ""
		(layer "B.Cu")
		(at 304.578258 -395.148562 90)
		(property "Reference" "C562"
			(at 0 0 90)
			(layer "B.SilkS")
			(hide yes)
			(effects
				(font
					(size 1.27 1.27)
				)
				(justify mirror)
			)
		)
		(property "Value" ""
			(at 0 0 90)
			(layer "B.Fab")
			(effects
				(font
					(size 1.27 1.27)
				)
				(justify mirror)
			)
		)
		(duplicate_pad_numbers_are_jumpers no)
		(fp_line
			(start 0.299974 -0.150114)
			(end -0.299974 -0.150114)
			(stroke
				(width 0.1)
				(type default)
			)
			(layer "B.Fab")
		)
		(fp_line
			(start -0.299974 -0.150114)
			(end -0.299974 0.150114)
			(stroke
				(width 0.1)
				(type default)
			)
			(layer "B.Fab")
		)
		(fp_line
			(start 0.299974 0.150114)
			(end 0.299974 -0.150114)
			(stroke
				(width 0.1)
				(type default)
			)
			(layer "B.Fab")
		)
		(fp_line
			(start -0.299974 0.150114)
			(end 0.299974 0.150114)
			(stroke
				(width 0.1)
				(type default)
			)
			(layer "B.Fab")
		)
		(pad "1" smd rect
			(at 0.2667 0 270)
			(size 0.3048 0.381)
			(layers "B.Cu" "B.Mask" "B.Paste")
			(net "P0V9_CPU0_RT0_2A")
		)
		(pad "2" smd rect
			(at -0.2667 0 270)
			(size 0.3048 0.381)
			(layers "B.Cu" "B.Mask" "B.Paste")
			(net "GND")
		)
	)
	(footprint ""
		(layer "B.Cu")
		(at 113.105946 -258.795266 180)
		(property "Reference" "C2276"
			(at 0 0 0)
			(layer "B.SilkS")
			(hide yes)
			(effects
				(font
					(size 1.27 1.27)
				)
				(justify mirror)
			)
		)
		(property "Value" ""
			(at 0 0 0)
			(layer "B.Fab")
			(effects
				(font
					(size 1.27 1.27)
				)
				(justify mirror)
			)
		)
		(duplicate_pad_numbers_are_jumpers no)
		(fp_line
			(start 0.7874 0.4064)
			(end 0.7874 -0.4064)
			(stroke
				(width 0.1524)
				(type default)
			)
			(layer "B.SilkS")
		)
		(fp_line
			(start 0.7874 -0.4064)
			(end -0.7874 -0.4064)
			(stroke
				(width 0.1524)
				(type default)
			)
			(layer "B.SilkS")
		)
		(fp_line
			(start -0.7874 0.4064)
			(end 0.7874 0.4064)
			(stroke
				(width 0.1524)
				(type default)
			)
			(layer "B.SilkS")
		)
		(fp_line
			(start -0.7874 -0.4064)
			(end -0.7874 0.4064)
			(stroke
				(width 0.1524)
				(type default)
			)
			(layer "B.SilkS")
		)
		(fp_line
			(start 0.67945 0.3048)
			(end 0.67945 -0.305054)
			(stroke
				(width 0.1)
				(type default)
			)
			(layer "B.Fab")
		)
		(fp_line
			(start 0.67945 -0.305054)
			(end 0.12065 -0.305054)
			(stroke
				(width 0.1)
				(type default)
			)
			(layer "B.Fab")
		)
		(fp_line
			(start 0.12065 0.3048)
			(end 0.67945 0.3048)
			(stroke
				(width 0.1)
				(type default)
			)
			(layer "B.Fab")
		)
		(fp_line
			(start 0.12065 0.2794)
			(end 0.12065 0.3048)
			(stroke
				(width 0.1)
				(type default)
			)
			(layer "B.Fab")
		)
		(fp_line
			(start 0.12065 -0.2794)
			(end -0.12065 -0.2794)
			(stroke
				(width 0.1)
				(type default)
			)
			(layer "B.Fab")
		)
		(fp_line
			(start 0.12065 -0.305054)
			(end 0.12065 -0.2794)
			(stroke
				(width 0.1)
				(type default)
			)
			(layer "B.Fab")
		)
		(fp_line
			(start -0.120396 0.3048)
			(end -0.120396 0.2794)
			(stroke
				(width 0.1)
				(type default)
			)
			(layer "B.Fab")
		)
		(fp_line
			(start -0.120396 0.2794)
			(end 0.12065 0.2794)
			(stroke
				(width 0.1)
				(type default)
			)
			(layer "B.Fab")
		)
		(fp_line
			(start -0.12065 -0.2794)
			(end -0.12065 -0.3048)
			(stroke
				(width 0.1)
				(type default)
			)
			(layer "B.Fab")
		)
		(fp_line
			(start -0.12065 -0.3048)
			(end -0.67945 -0.3048)
			(stroke
				(width 0.1)
				(type default)
			)
			(layer "B.Fab")
		)
		(fp_line
			(start -0.67945 0.3048)
			(end -0.120396 0.3048)
			(stroke
				(width 0.1)
				(type default)
			)
			(layer "B.Fab")
		)
		(fp_line
			(start -0.67945 -0.3048)
			(end -0.67945 0.3048)
			(stroke
				(width 0.1)
				(type default)
			)
			(layer "B.Fab")
		)
		(pad "1" smd circle
			(at 0.40005 0)
			(size 0 0)
			(layers "B.Cu" "B.Mask" "B.Paste")
			(net "PVDDCR_SOC_P1")
		)
		(pad "2" smd circle
			(at -0.40005 0)
			(size 0 0)
			(layers "B.Cu" "B.Mask" "B.Paste")
			(net "GND")
		)
	)
	(footprint ""
		(layer "B.Cu")
		(at 354.152454 -251.78131)
		(property "Reference" "C2576"
			(at 0 0 0)
			(layer "B.SilkS")
			(hide yes)
			(effects
				(font
					(size 1.27 1.27)
				)
				(justify mirror)
			)
		)
		(property "Value" ""
			(at 0 0 0)
			(layer "B.Fab")
			(effects
				(font
					(size 1.27 1.27)
				)
				(justify mirror)
			)
		)
		(duplicate_pad_numbers_are_jumpers no)
		(fp_line
			(start -0.7874 -0.4064)
			(end -0.7874 0.4064)
			(stroke
				(width 0.1524)
				(type default)
			)
			(layer "B.SilkS")
		)
		(fp_line
			(start -0.7874 0.4064)
			(end 0.7874 0.4064)
			(stroke
				(width 0.1524)
				(type default)
			)
			(layer "B.SilkS")
		)
		(fp_line
			(start 0.7874 -0.4064)
			(end -0.7874 -0.4064)
			(stroke
				(width 0.1524)
				(type default)
			)
			(layer "B.SilkS")
		)
		(fp_line
			(start 0.7874 0.4064)
			(end 0.7874 -0.4064)
			(stroke
				(width 0.1524)
				(type default)
			)
			(layer "B.SilkS")
		)
		(fp_line
			(start -0.67945 -0.3048)
			(end -0.67945 0.3048)
			(stroke
				(width 0.1)
				(type default)
			)
			(layer "B.Fab")
		)
		(fp_line
			(start -0.67945 0.3048)
			(end -0.120396 0.3048)
			(stroke
				(width 0.1)
				(type default)
			)
			(layer "B.Fab")
		)
		(fp_line
			(start -0.12065 -0.3048)
			(end -0.67945 -0.3048)
			(stroke
				(width 0.1)
				(type default)
			)
			(layer "B.Fab")
		)
		(fp_line
			(start -0.12065 -0.2794)
			(end -0.12065 -0.3048)
			(stroke
				(width 0.1)
				(type default)
			)
			(layer "B.Fab")
		)
		(fp_line
			(start -0.120396 0.2794)
			(end 0.12065 0.2794)
			(stroke
				(width 0.1)
				(type default)
			)
			(layer "B.Fab")
		)
		(fp_line
			(start -0.120396 0.3048)
			(end -0.120396 0.2794)
			(stroke
				(width 0.1)
				(type default)
			)
			(layer "B.Fab")
		)
		(fp_line
			(start 0.12065 -0.305054)
			(end 0.12065 -0.2794)
			(stroke
				(width 0.1)
				(type default)
			)
			(layer "B.Fab")
		)
		(fp_line
			(start 0.12065 -0.2794)
			(end -0.12065 -0.2794)
			(stroke
				(width 0.1)
				(type default)
			)
			(layer "B.Fab")
		)
		(fp_line
			(start 0.12065 0.2794)
			(end 0.12065 0.3048)
			(stroke
				(width 0.1)
				(type default)
			)
			(layer "B.Fab")
		)
		(fp_line
			(start 0.12065 0.3048)
			(end 0.67945 0.3048)
			(stroke
				(width 0.1)
				(type default)
			)
			(layer "B.Fab")
		)
		(fp_line
			(start 0.67945 -0.305054)
			(end 0.12065 -0.305054)
			(stroke
				(width 0.1)
				(type default)
			)
			(layer "B.Fab")
		)
		(fp_line
			(start 0.67945 0.3048)
			(end 0.67945 -0.305054)
			(stroke
				(width 0.1)
				(type default)
			)
			(layer "B.Fab")
		)
		(pad "1" smd circle
			(at 0.40005 0 180)
			(size 0 0)
			(layers "B.Cu" "B.Mask" "B.Paste")
			(net "PVDDCR_SOC_P0")
		)
		(pad "2" smd circle
			(at -0.40005 0 180)
			(size 0 0)
			(layers "B.Cu" "B.Mask" "B.Paste")
			(net "GND")
		)
	)
	(footprint ""
		(layer "B.Cu")
		(at 337.661504 -151.064722 90)
		(property "Reference" "PC288"
			(at 0 0 90)
			(layer "B.SilkS")
			(hide yes)
			(effects
				(font
					(size 1.27 1.27)
				)
				(justify mirror)
			)
		)
		(property "Value" ""
			(at 0 0 90)
			(layer "B.Fab")
			(effects
				(font
					(size 1.27 1.27)
				)
				(justify mirror)
			)
		)
		(duplicate_pad_numbers_are_jumpers no)
		(fp_line
			(start 1.524 -0.762)
			(end -1.524 -0.762)
			(stroke
				(width 0.1524)
				(type default)
			)
			(layer "B.SilkS")
		)
		(fp_line
			(start -1.524 -0.762)
			(end -1.524 0.762)
			(stroke
				(width 0.1524)
				(type default)
			)
			(layer "B.SilkS")
		)
		(fp_line
			(start 1.524 0.762)
			(end 1.524 -0.762)
			(stroke
				(width 0.1524)
				(type default)
			)
			(layer "B.SilkS")
		)
		(fp_line
			(start -1.524 0.762)
			(end 1.524 0.762)
			(stroke
				(width 0.1524)
				(type default)
			)
			(layer "B.SilkS")
		)
		(fp_line
			(start 1.1049 -0.724916)
			(end 1.1049 0.724916)
			(stroke
				(width 0.1)
				(type default)
			)
			(layer "B.Fab")
		)
		(fp_line
			(start -1.1049 -0.724916)
			(end 1.1049 -0.724916)
			(stroke
				(width 0.1)
				(type default)
			)
			(layer "B.Fab")
		)
		(fp_line
			(start 1.1049 0.724916)
			(end -1.1049 0.724916)
			(stroke
				(width 0.1)
				(type default)
			)
			(layer "B.Fab")
		)
		(fp_line
			(start -1.1049 0.724916)
			(end -1.1049 -0.724916)
			(stroke
				(width 0.1)
				(type default)
			)
			(layer "B.Fab")
		)
		(pad "1" smd rect
			(at 0.889 0 90)
			(size 1.016 1.27)
			(layers "B.Cu" "B.Mask" "B.Paste")
			(net "PVDD18_S5_P0")
		)
		(pad "2" smd rect
			(at -0.889 0 90)
			(size 1.016 1.27)
			(layers "B.Cu" "B.Mask" "B.Paste")
			(net "GND")
		)
	)
	(footprint ""
		(layer "B.Cu")
		(at 316.590934 -398.942052 90)
		(property "Reference" "C572"
			(at 0 0 90)
			(layer "B.SilkS")
			(hide yes)
			(effects
				(font
					(size 1.27 1.27)
				)
				(justify mirror)
			)
		)
		(property "Value" ""
			(at 0 0 90)
			(layer "B.Fab")
			(effects
				(font
					(size 1.27 1.27)
				)
				(justify mirror)
			)
		)
		(duplicate_pad_numbers_are_jumpers no)
		(fp_line
			(start 0.7874 -0.4064)
			(end -0.7874 -0.4064)
			(stroke
				(width 0.1524)
				(type default)
			)
			(layer "B.SilkS")
		)
		(fp_line
			(start -0.7874 -0.4064)
			(end -0.7874 0.4064)
			(stroke
				(width 0.1524)
				(type default)
			)
			(layer "B.SilkS")
		)
		(fp_line
			(start 0.7874 0.4064)
			(end 0.7874 -0.4064)
			(stroke
				(width 0.1524)
				(type default)
			)
			(layer "B.SilkS")
		)
		(fp_line
			(start -0.7874 0.4064)
			(end 0.7874 0.4064)
			(stroke
				(width 0.1524)
				(type default)
			)
			(layer "B.SilkS")
		)
		(fp_line
			(start 0.67945 -0.305054)
			(end 0.12065 -0.305054)
			(stroke
				(width 0.1)
				(type default)
			)
			(layer "B.Fab")
		)
		(fp_line
			(start 0.12065 -0.305054)
			(end 0.12065 -0.2794)
			(stroke
				(width 0.1)
				(type default)
			)
			(layer "B.Fab")
		)
		(fp_line
			(start -0.12065 -0.3048)
			(end -0.67945 -0.3048)
			(stroke
				(width 0.1)
				(type default)
			)
			(layer "B.Fab")
		)
		(fp_line
			(start -0.67945 -0.3048)
			(end -0.67945 0.3048)
			(stroke
				(width 0.1)
				(type default)
			)
			(layer "B.Fab")
		)
		(fp_line
			(start 0.12065 -0.2794)
			(end -0.12065 -0.2794)
			(stroke
				(width 0.1)
				(type default)
			)
			(layer "B.Fab")
		)
		(fp_line
			(start -0.12065 -0.2794)
			(end -0.12065 -0.3048)
			(stroke
				(width 0.1)
				(type default)
			)
			(layer "B.Fab")
		)
		(fp_line
			(start 0.12065 0.2794)
			(end 0.12065 0.3048)
			(stroke
				(width 0.1)
				(type default)
			)
			(layer "B.Fab")
		)
		(fp_line
			(start -0.120396 0.2794)
			(end 0.12065 0.2794)
			(stroke
				(width 0.1)
				(type default)
			)
			(layer "B.Fab")
		)
		(fp_line
			(start 0.67945 0.3048)
			(end 0.67945 -0.305054)
			(stroke
				(width 0.1)
				(type default)
			)
			(layer "B.Fab")
		)
		(fp_line
			(start 0.12065 0.3048)
			(end 0.67945 0.3048)
			(stroke
				(width 0.1)
				(type default)
			)
			(layer "B.Fab")
		)
		(fp_line
			(start -0.120396 0.3048)
			(end -0.120396 0.2794)
			(stroke
				(width 0.1)
				(type default)
			)
			(layer "B.Fab")
		)
		(fp_line
			(start -0.67945 0.3048)
			(end -0.120396 0.3048)
			(stroke
				(width 0.1)
				(type default)
			)
			(layer "B.Fab")
		)
		(pad "1" smd circle
			(at 0.40005 0 270)
			(size 0 0)
			(layers "B.Cu" "B.Mask" "B.Paste")
			(net "P0V9_CPU0_RT0_2A")
		)
		(pad "2" smd circle
			(at -0.40005 0 270)
			(size 0 0)
			(layers "B.Cu" "B.Mask" "B.Paste")
			(net "GND")
		)
	)
	(footprint ""
		(layer "B.Cu")
		(at 233.172 -341.884 180)
		(property "Reference" "R977"
			(at 0 0 0)
			(layer "B.SilkS")
			(hide yes)
			(effects
				(font
					(size 1.27 1.27)
				)
				(justify mirror)
			)
		)
		(property "Value" ""
			(at 0 0 0)
			(layer "B.Fab")
			(effects
				(font
					(size 1.27 1.27)
				)
				(justify mirror)
			)
		)
		(duplicate_pad_numbers_are_jumpers no)
		(fp_line
			(start 0.32512 0.175006)
			(end 0.32512 -0.175006)
			(stroke
				(width 0.1)
				(type default)
			)
			(layer "B.Fab")
		)
		(fp_line
			(start 0.32512 -0.175006)
			(end -0.32512 -0.175006)
			(stroke
				(width 0.1)
				(type default)
			)
			(layer "B.Fab")
		)
		(fp_line
			(start -0.32512 0.175006)
			(end 0.32512 0.175006)
			(stroke
				(width 0.1)
				(type default)
			)
			(layer "B.Fab")
		)
		(fp_line
			(start -0.32512 -0.175006)
			(end -0.32512 0.175006)
			(stroke
				(width 0.1)
				(type default)
			)
			(layer "B.Fab")
		)
		(pad "1" smd rect
			(at 0.2667 0)
			(size 0.3048 0.381)
			(layers "B.Cu" "B.Mask" "B.Paste")
			(net "SMB_RT_CPU0_P0_R_SDA")
		)
		(pad "2" smd rect
			(at -0.2667 0 180)
			(size 0.3048 0.381)
			(layers "B.Cu" "B.Mask" "B.Paste")
			(net "SMB_RT_CPU0_P0_R2_SDA")
		)
	)
	(footprint ""
		(layer "B.Cu")
		(at 155.419044 -390.560052 90)
		(property "Reference" "C371"
			(at 0 0 90)
			(layer "B.SilkS")
			(hide yes)
			(effects
				(font
					(size 1.27 1.27)
				)
				(justify mirror)
			)
		)
		(property "Value" ""
			(at 0 0 90)
			(layer "B.Fab")
			(effects
				(font
					(size 1.27 1.27)
				)
				(justify mirror)
			)
		)
		(duplicate_pad_numbers_are_jumpers no)
		(fp_line
			(start 0.7874 -0.4064)
			(end -0.7874 -0.4064)
			(stroke
				(width 0.1524)
				(type default)
			)
			(layer "B.SilkS")
		)
		(fp_line
			(start -0.7874 -0.4064)
			(end -0.7874 0.4064)
			(stroke
				(width 0.1524)
				(type default)
			)
			(layer "B.SilkS")
		)
		(fp_line
			(start 0.7874 0.4064)
			(end 0.7874 -0.4064)
			(stroke
				(width 0.1524)
				(type default)
			)
			(layer "B.SilkS")
		)
		(fp_line
			(start -0.7874 0.4064)
			(end 0.7874 0.4064)
			(stroke
				(width 0.1524)
				(type default)
			)
			(layer "B.SilkS")
		)
		(fp_line
			(start 0.67945 -0.305054)
			(end 0.12065 -0.305054)
			(stroke
				(width 0.1)
				(type default)
			)
			(layer "B.Fab")
		)
		(fp_line
			(start 0.12065 -0.305054)
			(end 0.12065 -0.2794)
			(stroke
				(width 0.1)
				(type default)
			)
			(layer "B.Fab")
		)
		(fp_line
			(start -0.12065 -0.3048)
			(end -0.67945 -0.3048)
			(stroke
				(width 0.1)
				(type default)
			)
			(layer "B.Fab")
		)
		(fp_line
			(start -0.67945 -0.3048)
			(end -0.67945 0.3048)
			(stroke
				(width 0.1)
				(type default)
			)
			(layer "B.Fab")
		)
		(fp_line
			(start 0.12065 -0.2794)
			(end -0.12065 -0.2794)
			(stroke
				(width 0.1)
				(type default)
			)
			(layer "B.Fab")
		)
		(fp_line
			(start -0.12065 -0.2794)
			(end -0.12065 -0.3048)
			(stroke
				(width 0.1)
				(type default)
			)
			(layer "B.Fab")
		)
		(fp_line
			(start 0.12065 0.2794)
			(end 0.12065 0.3048)
			(stroke
				(width 0.1)
				(type default)
			)
			(layer "B.Fab")
		)
		(fp_line
			(start -0.120396 0.2794)
			(end 0.12065 0.2794)
			(stroke
				(width 0.1)
				(type default)
			)
			(layer "B.Fab")
		)
		(fp_line
			(start 0.67945 0.3048)
			(end 0.67945 -0.305054)
			(stroke
				(width 0.1)
				(type default)
			)
			(layer "B.Fab")
		)
		(fp_line
			(start 0.12065 0.3048)
			(end 0.67945 0.3048)
			(stroke
				(width 0.1)
				(type default)
			)
			(layer "B.Fab")
		)
		(fp_line
			(start -0.120396 0.3048)
			(end -0.120396 0.2794)
			(stroke
				(width 0.1)
				(type default)
			)
			(layer "B.Fab")
		)
		(fp_line
			(start -0.67945 0.3048)
			(end -0.120396 0.3048)
			(stroke
				(width 0.1)
				(type default)
			)
			(layer "B.Fab")
		)
		(pad "1" smd circle
			(at 0.40005 0 270)
			(size 0 0)
			(layers "B.Cu" "B.Mask" "B.Paste")
			(net "P1V8_CPU1_RT2_1A")
		)
		(pad "2" smd circle
			(at -0.40005 0 270)
			(size 0 0)
			(layers "B.Cu" "B.Mask" "B.Paste")
			(net "GND")
		)
	)
	(footprint ""
		(layer "B.Cu")
		(at 101.385878 -142.59941 180)
		(property "Reference" "PC243"
			(at 0 0 0)
			(layer "B.SilkS")
			(hide yes)
			(effects
				(font
					(size 1.27 1.27)
				)
				(justify mirror)
			)
		)
		(property "Value" ""
			(at 0 0 0)
			(layer "B.Fab")
			(effects
				(font
					(size 1.27 1.27)
				)
				(justify mirror)
			)
		)
		(duplicate_pad_numbers_are_jumpers no)
		(fp_line
			(start 0.7874 0.4064)
			(end 0.7874 -0.4064)
			(stroke
				(width 0.1524)
				(type default)
			)
			(layer "B.SilkS")
		)
		(fp_line
			(start 0.7874 -0.4064)
			(end -0.7874 -0.4064)
			(stroke
				(width 0.1524)
				(type default)
			)
			(layer "B.SilkS")
		)
		(fp_line
			(start -0.7874 0.4064)
			(end 0.7874 0.4064)
			(stroke
				(width 0.1524)
				(type default)
			)
			(layer "B.SilkS")
		)
		(fp_line
			(start -0.7874 -0.4064)
			(end -0.7874 0.4064)
			(stroke
				(width 0.1524)
				(type default)
			)
			(layer "B.SilkS")
		)
		(fp_line
			(start 0.67945 0.3048)
			(end 0.67945 -0.305054)
			(stroke
				(width 0.1)
				(type default)
			)
			(layer "B.Fab")
		)
		(fp_line
			(start 0.67945 -0.305054)
			(end 0.12065 -0.305054)
			(stroke
				(width 0.1)
				(type default)
			)
			(layer "B.Fab")
		)
		(fp_line
			(start 0.12065 0.3048)
			(end 0.67945 0.3048)
			(stroke
				(width 0.1)
				(type default)
			)
			(layer "B.Fab")
		)
		(fp_line
			(start 0.12065 0.2794)
			(end 0.12065 0.3048)
			(stroke
				(width 0.1)
				(type default)
			)
			(layer "B.Fab")
		)
		(fp_line
			(start 0.12065 -0.2794)
			(end -0.12065 -0.2794)
			(stroke
				(width 0.1)
				(type default)
			)
			(layer "B.Fab")
		)
		(fp_line
			(start 0.12065 -0.305054)
			(end 0.12065 -0.2794)
			(stroke
				(width 0.1)
				(type default)
			)
			(layer "B.Fab")
		)
		(fp_line
			(start -0.120396 0.3048)
			(end -0.120396 0.2794)
			(stroke
				(width 0.1)
				(type default)
			)
			(layer "B.Fab")
		)
		(fp_line
			(start -0.120396 0.2794)
			(end 0.12065 0.2794)
			(stroke
				(width 0.1)
				(type default)
			)
			(layer "B.Fab")
		)
		(fp_line
			(start -0.12065 -0.2794)
			(end -0.12065 -0.3048)
			(stroke
				(width 0.1)
				(type default)
			)
			(layer "B.Fab")
		)
		(fp_line
			(start -0.12065 -0.3048)
			(end -0.67945 -0.3048)
			(stroke
				(width 0.1)
				(type default)
			)
			(layer "B.Fab")
		)
		(fp_line
			(start -0.67945 0.3048)
			(end -0.120396 0.3048)
			(stroke
				(width 0.1)
				(type default)
			)
			(layer "B.Fab")
		)
		(fp_line
			(start -0.67945 -0.3048)
			(end -0.67945 0.3048)
			(stroke
				(width 0.1)
				(type default)
			)
			(layer "B.Fab")
		)
		(pad "1" smd circle
			(at 0.40005 0)
			(size 0 0)
			(layers "B.Cu" "B.Mask" "B.Paste")
			(net "PVDDCR_CPU0_P1_VMON")
		)
		(pad "2" smd circle
			(at -0.40005 0)
			(size 0 0)
			(layers "B.Cu" "B.Mask" "B.Paste")
			(net "GND")
		)
	)
	(footprint ""
		(layer "B.Cu")
		(at 265.54811 -192.660016 180)
		(property "Reference" "C155"
			(at 0 0 0)
			(layer "B.SilkS")
			(hide yes)
			(effects
				(font
					(size 1.27 1.27)
				)
				(justify mirror)
			)
		)
		(property "Value" ""
			(at 0 0 0)
			(layer "B.Fab")
			(effects
				(font
					(size 1.27 1.27)
				)
				(justify mirror)
			)
		)
		(duplicate_pad_numbers_are_jumpers no)
		(fp_line
			(start 1.524 0.762)
			(end 1.524 -0.762)
			(stroke
				(width 0.1524)
				(type default)
			)
			(layer "B.SilkS")
		)
		(fp_line
			(start 1.524 -0.762)
			(end -1.524 -0.762)
			(stroke
				(width 0.1524)
				(type default)
			)
			(layer "B.SilkS")
		)
		(fp_line
			(start -1.524 0.762)
			(end 1.524 0.762)
			(stroke
				(width 0.1524)
				(type default)
			)
			(layer "B.SilkS")
		)
		(fp_line
			(start -1.524 -0.762)
			(end -1.524 0.762)
			(stroke
				(width 0.1524)
				(type default)
			)
			(layer "B.SilkS")
		)
		(fp_line
			(start 1.1049 0.724916)
			(end -1.1049 0.724916)
			(stroke
				(width 0.1)
				(type default)
			)
			(layer "B.Fab")
		)
		(fp_line
			(start 1.1049 -0.724916)
			(end 1.1049 0.724916)
			(stroke
				(width 0.1)
				(type default)
			)
			(layer "B.Fab")
		)
		(fp_line
			(start -1.1049 0.724916)
			(end -1.1049 -0.724916)
			(stroke
				(width 0.1)
				(type default)
			)
			(layer "B.Fab")
		)
		(fp_line
			(start -1.1049 -0.724916)
			(end 1.1049 -0.724916)
			(stroke
				(width 0.1)
				(type default)
			)
			(layer "B.Fab")
		)
		(pad "1" smd rect
			(at 0.889 0 180)
			(size 1.016 1.27)
			(layers "B.Cu" "B.Mask" "B.Paste")
			(net "P12V_MEM_CPU0")
		)
		(pad "2" smd rect
			(at -0.889 0 180)
			(size 1.016 1.27)
			(layers "B.Cu" "B.Mask" "B.Paste")
			(net "GND")
		)
	)
	(footprint ""
		(layer "B.Cu")
		(at 148.218906 -390.560052 90)
		(property "Reference" "C417"
			(at 0 0 90)
			(layer "B.SilkS")
			(hide yes)
			(effects
				(font
					(size 1.27 1.27)
				)
				(justify mirror)
			)
		)
		(property "Value" ""
			(at 0 0 90)
			(layer "B.Fab")
			(effects
				(font
					(size 1.27 1.27)
				)
				(justify mirror)
			)
		)
		(duplicate_pad_numbers_are_jumpers no)
		(fp_line
			(start 0.7874 -0.4064)
			(end -0.7874 -0.4064)
			(stroke
				(width 0.1524)
				(type default)
			)
			(layer "B.SilkS")
		)
		(fp_line
			(start -0.7874 -0.4064)
			(end -0.7874 0.4064)
			(stroke
				(width 0.1524)
				(type default)
			)
			(layer "B.SilkS")
		)
		(fp_line
			(start 0.7874 0.4064)
			(end 0.7874 -0.4064)
			(stroke
				(width 0.1524)
				(type default)
			)
			(layer "B.SilkS")
		)
		(fp_line
			(start -0.7874 0.4064)
			(end 0.7874 0.4064)
			(stroke
				(width 0.1524)
				(type default)
			)
			(layer "B.SilkS")
		)
		(fp_line
			(start 0.67945 -0.305054)
			(end 0.12065 -0.305054)
			(stroke
				(width 0.1)
				(type default)
			)
			(layer "B.Fab")
		)
		(fp_line
			(start 0.12065 -0.305054)
			(end 0.12065 -0.2794)
			(stroke
				(width 0.1)
				(type default)
			)
			(layer "B.Fab")
		)
		(fp_line
			(start -0.12065 -0.3048)
			(end -0.67945 -0.3048)
			(stroke
				(width 0.1)
				(type default)
			)
			(layer "B.Fab")
		)
		(fp_line
			(start -0.67945 -0.3048)
			(end -0.67945 0.3048)
			(stroke
				(width 0.1)
				(type default)
			)
			(layer "B.Fab")
		)
		(fp_line
			(start 0.12065 -0.2794)
			(end -0.12065 -0.2794)
			(stroke
				(width 0.1)
				(type default)
			)
			(layer "B.Fab")
		)
		(fp_line
			(start -0.12065 -0.2794)
			(end -0.12065 -0.3048)
			(stroke
				(width 0.1)
				(type default)
			)
			(layer "B.Fab")
		)
		(fp_line
			(start 0.12065 0.2794)
			(end 0.12065 0.3048)
			(stroke
				(width 0.1)
				(type default)
			)
			(layer "B.Fab")
		)
		(fp_line
			(start -0.120396 0.2794)
			(end 0.12065 0.2794)
			(stroke
				(width 0.1)
				(type default)
			)
			(layer "B.Fab")
		)
		(fp_line
			(start 0.67945 0.3048)
			(end 0.67945 -0.305054)
			(stroke
				(width 0.1)
				(type default)
			)
			(layer "B.Fab")
		)
		(fp_line
			(start 0.12065 0.3048)
			(end 0.67945 0.3048)
			(stroke
				(width 0.1)
				(type default)
			)
			(layer "B.Fab")
		)
		(fp_line
			(start -0.120396 0.3048)
			(end -0.120396 0.2794)
			(stroke
				(width 0.1)
				(type default)
			)
			(layer "B.Fab")
		)
		(fp_line
			(start -0.67945 0.3048)
			(end -0.120396 0.3048)
			(stroke
				(width 0.1)
				(type default)
			)
			(layer "B.Fab")
		)
		(pad "1" smd circle
			(at 0.40005 0 270)
			(size 0 0)
			(layers "B.Cu" "B.Mask" "B.Paste")
			(net "P0V9_CPU1_RT2_2A")
		)
		(pad "2" smd circle
			(at -0.40005 0 270)
			(size 0 0)
			(layers "B.Cu" "B.Mask" "B.Paste")
			(net "GND")
		)
	)
	(footprint ""
		(layer "B.Cu")
		(at 112.35436 -408.651456 90)
		(property "Reference" "R696"
			(at 0 0 90)
			(layer "B.SilkS")
			(hide yes)
			(effects
				(font
					(size 1.27 1.27)
				)
				(justify mirror)
			)
		)
		(property "Value" ""
			(at 0 0 90)
			(layer "B.Fab")
			(effects
				(font
					(size 1.27 1.27)
				)
				(justify mirror)
			)
		)
		(duplicate_pad_numbers_are_jumpers no)
		(fp_line
			(start 0.32512 -0.175006)
			(end -0.32512 -0.175006)
			(stroke
				(width 0.1)
				(type default)
			)
			(layer "B.Fab")
		)
		(fp_line
			(start -0.32512 -0.175006)
			(end -0.32512 0.175006)
			(stroke
				(width 0.1)
				(type default)
			)
			(layer "B.Fab")
		)
		(fp_line
			(start 0.32512 0.175006)
			(end 0.32512 -0.175006)
			(stroke
				(width 0.1)
				(type default)
			)
			(layer "B.Fab")
		)
		(fp_line
			(start -0.32512 0.175006)
			(end 0.32512 0.175006)
			(stroke
				(width 0.1)
				(type default)
			)
			(layer "B.Fab")
		)
		(pad "1" smd rect
			(at 0.2667 0 270)
			(size 0.3048 0.381)
			(layers "B.Cu" "B.Mask" "B.Paste")
			(net "SMB_RT_CPU1_P3_ROM_MUX_1D_SDA")
		)
		(pad "2" smd rect
			(at -0.2667 0 90)
			(size 0.3048 0.381)
			(layers "B.Cu" "B.Mask" "B.Paste")
			(net "SMB_RT_CPU1_P3_ROM_MUX_1D_R_SDA")
		)
	)
	(footprint ""
		(layer "B.Cu")
		(at 231.138476 -236.074204 90)
		(property "Reference" "U213"
			(at -2.063242 -3.25882 270)
			(unlocked yes)
			(layer "B.SilkS")
			(effects
				(font
					(size 0.7874 0.5842)
					(thickness 0.1524)
				)
				(justify left mirror)
			)
		)
		(property "Value" ""
			(at 0 0 90)
			(layer "B.Fab")
			(effects
				(font
					(size 1.27 1.27)
				)
				(justify mirror)
			)
		)
		(duplicate_pad_numbers_are_jumpers no)
		(fp_line
			(start 1.781302 -1.012698)
			(end -1.781302 -1.012698)
			(stroke
				(width 0.1524)
				(type default)
			)
			(layer "B.SilkS")
		)
		(fp_line
			(start -1.781302 -1.012698)
			(end -1.781302 1.012698)
			(stroke
				(width 0.1524)
				(type default)
			)
			(layer "B.SilkS")
		)
		(fp_line
			(start 1.781302 1.012698)
			(end 1.781302 -1.012698)
			(stroke
				(width 0.1524)
				(type default)
			)
			(layer "B.SilkS")
		)
		(fp_line
			(start 0 1.012698)
			(end 1.781302 1.012698)
			(stroke
				(width 0.1524)
				(type default)
			)
			(layer "B.SilkS")
		)
		(fp_line
			(start -1.781302 1.012698)
			(end 0 1.012698)
			(stroke
				(width 0.1524)
				(type default)
			)
			(layer "B.SilkS")
		)
		(fp_poly
			(pts
				(xy 1.214374 -1.333754) (xy 1.187704 -2.469134) (xy 0.290068 -1.993646)
			)
			(stroke
				(width 0)
				(type default)
			)
			(fill yes)
			(layer "B.SilkS")
		)
		(fp_line
			(start 1.500124 -0.999998)
			(end -1.500124 -0.999998)
			(stroke
				(width 0.1)
				(type default)
			)
			(layer "B.Fab")
		)
		(fp_line
			(start -1.500124 -0.999998)
			(end -1.500124 0.999998)
			(stroke
				(width 0.1)
				(type default)
			)
			(layer "B.Fab")
		)
		(fp_line
			(start 1.500124 0.999998)
			(end 1.500124 -0.999998)
			(stroke
				(width 0.1)
				(type default)
			)
			(layer "B.Fab")
		)
		(fp_line
			(start 0 0.999998)
			(end 1.500124 0.999998)
			(stroke
				(width 0.1)
				(type default)
			)
			(layer "B.Fab")
		)
		(fp_line
			(start -1.500124 0.999998)
			(end 0 0.999998)
			(stroke
				(width 0.1)
				(type default)
			)
			(layer "B.Fab")
		)
		(fp_poly
			(pts
				(xy 2.9972 -1.258062) (xy 2.9972 -0.242062) (xy 1.9812 -0.750062)
			)
			(stroke
				(width 0)
				(type default)
			)
			(fill yes)
			(layer "B.Fab")
		)
		(pad "1" smd rect
			(at 1.374902 -0.750062)
			(size 0.254 0.5588)
			(layers "B.Cu" "B.Mask" "B.Paste")
			(net "SMB_APML_CPU0_R_SDA")
		)
		(pad "2" smd rect
			(at 1.374902 -0.249936)
			(size 0.254 0.5588)
			(layers "B.Cu" "B.Mask" "B.Paste")
			(net "SMB_CPU0_CPU1_APML_MUX1_SDA")
		)
		(pad "3" smd rect
			(at 1.374902 0.249936)
			(size 0.254 0.5588)
			(layers "B.Cu" "B.Mask" "B.Paste")
			(net "SMB_CPU0_CPU1_APML_MUX1_SCL")
		)
		(pad "4" smd rect
			(at 1.374902 0.750062)
			(size 0.254 0.5588)
			(layers "B.Cu" "B.Mask" "B.Paste")
			(net "SMB_APML_CPU0_R_SCL")
		)
		(pad "5" smd rect
			(at -1.374902 0.750062)
			(size 0.254 0.5588)
			(layers "B.Cu" "B.Mask" "B.Paste")
			(net "PVDD18_S5_P0")
		)
		(pad "6" smd rect
			(at -1.374902 0.249936)
			(size 0.254 0.5588)
			(layers "B.Cu" "B.Mask" "B.Paste")
			(net "SMB_APML_CPU1_R_SCL")
		)
		(pad "7" smd rect
			(at -1.374902 -0.249936)
			(size 0.254 0.5588)
			(layers "B.Cu" "B.Mask" "B.Paste")
			(net "I3C_MUX_CPU0_VIO")
		)
		(pad "8" smd rect
			(at -1.374902 -0.750062)
			(size 0.254 0.5588)
			(layers "B.Cu" "B.Mask" "B.Paste")
			(net "SMB_APML_CPU1_R_SDA")
		)
		(pad "9" smd circle
			(at 0 0 270)
			(size 0 0)
			(layers "B.Cu" "B.Mask" "B.Paste")
			(net "GND")
		)
		(zone
			(layer "B.Cu")
			(hatch none 0.5)
			(connect_pads
				(clearance 0)
			)
			(min_thickness 0.25)
			(keepout
				(tracks not_allowed)
				(vias allowed)
				(pads allowed)
				(copperpour not_allowed)
				(footprints allowed)
			)
			(placement
				(enabled no)
				(sheetname "")
			)
			(fill
				(thermal_gap 0.5)
				(thermal_bridge_width 0.5)
				(island_removal_mode 0)
			)
			(polygon
				(pts
					(xy 232.129076 -237.115604) (xy 230.147876 -237.115604) (xy 230.147876 -236.556804) (xy 230.325676 -236.556804)
					(xy 230.325676 -236.887004) (xy 231.951276 -236.887004) (xy 231.951276 -235.261404) (xy 230.325676 -235.261404)
					(xy 230.325676 -236.531404) (xy 230.147876 -236.531404) (xy 230.147876 -235.032804) (xy 232.129076 -235.032804)
				)
			)
		)
	)
	(footprint ""
		(layer "B.Cu")
		(at 155.02001 -16.851122 -90)
		(property "Reference" "R3004"
			(at 0 0 90)
			(layer "B.SilkS")
			(hide yes)
			(effects
				(font
					(size 1.27 1.27)
				)
				(justify mirror)
			)
		)
		(property "Value" ""
			(at 0 0 90)
			(layer "B.Fab")
			(effects
				(font
					(size 1.27 1.27)
				)
				(justify mirror)
			)
		)
		(duplicate_pad_numbers_are_jumpers no)
		(fp_line
			(start -0.7874 0.4064)
			(end 0.7874 0.4064)
			(stroke
				(width 0.1524)
				(type default)
			)
			(layer "B.SilkS")
		)
		(fp_line
			(start 0.7874 0.4064)
			(end 0.7874 -0.4064)
			(stroke
				(width 0.1524)
				(type default)
			)
			(layer "B.SilkS")
		)
		(fp_line
			(start -0.7874 -0.4064)
			(end -0.7874 0.4064)
			(stroke
				(width 0.1524)
				(type default)
			)
			(layer "B.SilkS")
		)
		(fp_line
			(start 0.7874 -0.4064)
			(end -0.7874 -0.4064)
			(stroke
				(width 0.1524)
				(type default)
			)
			(layer "B.SilkS")
		)
		(fp_line
			(start -0.67945 0.3048)
			(end -0.120396 0.3048)
			(stroke
				(width 0.1)
				(type default)
			)
			(layer "B.Fab")
		)
		(fp_line
			(start -0.120396 0.3048)
			(end -0.120396 0.2794)
			(stroke
				(width 0.1)
				(type default)
			)
			(layer "B.Fab")
		)
		(fp_line
			(start 0.12065 0.3048)
			(end 0.67945 0.3048)
			(stroke
				(width 0.1)
				(type default)
			)
			(layer "B.Fab")
		)
		(fp_line
			(start 0.67945 0.3048)
			(end 0.67945 -0.305054)
			(stroke
				(width 0.1)
				(type default)
			)
			(layer "B.Fab")
		)
		(fp_line
			(start -0.120396 0.2794)
			(end 0.12065 0.2794)
			(stroke
				(width 0.1)
				(type default)
			)
			(layer "B.Fab")
		)
		(fp_line
			(start 0.12065 0.2794)
			(end 0.12065 0.3048)
			(stroke
				(width 0.1)
				(type default)
			)
			(layer "B.Fab")
		)
		(fp_line
			(start -0.12065 -0.2794)
			(end -0.12065 -0.3048)
			(stroke
				(width 0.1)
				(type default)
			)
			(layer "B.Fab")
		)
		(fp_line
			(start 0.12065 -0.2794)
			(end -0.12065 -0.2794)
			(stroke
				(width 0.1)
				(type default)
			)
			(layer "B.Fab")
		)
		(fp_line
			(start -0.67945 -0.3048)
			(end -0.67945 0.3048)
			(stroke
				(width 0.1)
				(type default)
			)
			(layer "B.Fab")
		)
		(fp_line
			(start -0.12065 -0.3048)
			(end -0.67945 -0.3048)
			(stroke
				(width 0.1)
				(type default)
			)
			(layer "B.Fab")
		)
		(fp_line
			(start 0.12065 -0.305054)
			(end 0.12065 -0.2794)
			(stroke
				(width 0.1)
				(type default)
			)
			(layer "B.Fab")
		)
		(fp_line
			(start 0.67945 -0.305054)
			(end 0.12065 -0.305054)
			(stroke
				(width 0.1)
				(type default)
			)
			(layer "B.Fab")
		)
		(pad "1" smd circle
			(at 0.40005 0 90)
			(size 0 0)
			(layers "B.Cu" "B.Mask" "B.Paste")
			(net "SMB_2_BMC_GPU_SDA")
		)
		(pad "2" smd circle
			(at -0.40005 0 90)
			(size 0 0)
			(layers "B.Cu" "B.Mask" "B.Paste")
			(net "P3V3_AUX")
		)
	)
	(footprint ""
		(layer "B.Cu")
		(at 450.84365 -193.99631)
		(property "Reference" "R101"
			(at 0 0 0)
			(layer "B.SilkS")
			(hide yes)
			(effects
				(font
					(size 1.27 1.27)
				)
				(justify mirror)
			)
		)
		(property "Value" ""
			(at 0 0 0)
			(layer "B.Fab")
			(effects
				(font
					(size 1.27 1.27)
				)
				(justify mirror)
			)
		)
		(duplicate_pad_numbers_are_jumpers no)
		(fp_line
			(start -0.7874 -0.4064)
			(end -0.7874 0.4064)
			(stroke
				(width 0.1524)
				(type default)
			)
			(layer "B.SilkS")
		)
		(fp_line
			(start -0.7874 0.4064)
			(end 0.7874 0.4064)
			(stroke
				(width 0.1524)
				(type default)
			)
			(layer "B.SilkS")
		)
		(fp_line
			(start 0.7874 -0.4064)
			(end -0.7874 -0.4064)
			(stroke
				(width 0.1524)
				(type default)
			)
			(layer "B.SilkS")
		)
		(fp_line
			(start 0.7874 0.4064)
			(end 0.7874 -0.4064)
			(stroke
				(width 0.1524)
				(type default)
			)
			(layer "B.SilkS")
		)
		(fp_line
			(start -0.67945 -0.3048)
			(end -0.67945 0.3048)
			(stroke
				(width 0.1)
				(type default)
			)
			(layer "B.Fab")
		)
		(fp_line
			(start -0.67945 0.3048)
			(end -0.120396 0.3048)
			(stroke
				(width 0.1)
				(type default)
			)
			(layer "B.Fab")
		)
		(fp_line
			(start -0.12065 -0.3048)
			(end -0.67945 -0.3048)
			(stroke
				(width 0.1)
				(type default)
			)
			(layer "B.Fab")
		)
		(fp_line
			(start -0.12065 -0.2794)
			(end -0.12065 -0.3048)
			(stroke
				(width 0.1)
				(type default)
			)
			(layer "B.Fab")
		)
		(fp_line
			(start -0.120396 0.2794)
			(end 0.12065 0.2794)
			(stroke
				(width 0.1)
				(type default)
			)
			(layer "B.Fab")
		)
		(fp_line
			(start -0.120396 0.3048)
			(end -0.120396 0.2794)
			(stroke
				(width 0.1)
				(type default)
			)
			(layer "B.Fab")
		)
		(fp_line
			(start 0.12065 -0.305054)
			(end 0.12065 -0.2794)
			(stroke
				(width 0.1)
				(type default)
			)
			(layer "B.Fab")
		)
		(fp_line
			(start 0.12065 -0.2794)
			(end -0.12065 -0.2794)
			(stroke
				(width 0.1)
				(type default)
			)
			(layer "B.Fab")
		)
		(fp_line
			(start 0.12065 0.2794)
			(end 0.12065 0.3048)
			(stroke
				(width 0.1)
				(type default)
			)
			(layer "B.Fab")
		)
		(fp_line
			(start 0.12065 0.3048)
			(end 0.67945 0.3048)
			(stroke
				(width 0.1)
				(type default)
			)
			(layer "B.Fab")
		)
		(fp_line
			(start 0.67945 -0.305054)
			(end 0.12065 -0.305054)
			(stroke
				(width 0.1)
				(type default)
			)
			(layer "B.Fab")
		)
		(fp_line
			(start 0.67945 0.3048)
			(end 0.67945 -0.305054)
			(stroke
				(width 0.1)
				(type default)
			)
			(layer "B.Fab")
		)
		(pad "1" smd circle
			(at 0.40005 0 180)
			(size 0 0)
			(layers "B.Cu" "B.Mask" "B.Paste")
			(net "P3V3")
		)
		(pad "2" smd circle
			(at -0.40005 0 180)
			(size 0 0)
			(layers "B.Cu" "B.Mask" "B.Paste")
			(net "PWRGD_CHL_CPU0_DIMM")
		)
	)
	(footprint ""
		(layer "B.Cu")
		(at 48.0568 -112.800384)
		(property "Reference" "ME16"
			(at 0 0 0)
			(layer "B.SilkS")
			(hide yes)
			(effects
				(font
					(size 1.27 1.27)
				)
				(justify mirror)
			)
		)
		(property "Value" ""
			(at 0 0 0)
			(layer "B.Fab")
			(effects
				(font
					(size 1.27 1.27)
				)
				(justify mirror)
			)
		)
		(duplicate_pad_numbers_are_jumpers no)
		(zone
			(layer "B.Cu")
			(hatch none 0.5)
			(connect_pads
				(clearance 0)
			)
			(min_thickness 0.25)
			(keepout
				(tracks allowed)
				(vias allowed)
				(pads allowed)
				(copperpour allowed)
				(footprints not_allowed)
			)
			(placement
				(enabled no)
				(sheetname "")
			)
			(fill
				(thermal_gap 0.5)
				(thermal_bridge_width 0.5)
				(island_removal_mode 0)
			)
			(polygon
				(pts
					(arc
						(start 58.05678 -112.800384)
						(mid 38.05682 -112.800384)
						(end 58.05678 -112.800384)
					)
				)
			)
		)
	)
	(footprint ""
		(layer "B.Cu")
		(at 373.329454 -254.19431)
		(property "Reference" "C2534"
			(at 0 0 0)
			(layer "B.SilkS")
			(hide yes)
			(effects
				(font
					(size 1.27 1.27)
				)
				(justify mirror)
			)
		)
		(property "Value" ""
			(at 0 0 0)
			(layer "B.Fab")
			(effects
				(font
					(size 1.27 1.27)
				)
				(justify mirror)
			)
		)
		(duplicate_pad_numbers_are_jumpers no)
		(fp_line
			(start -0.7874 -0.4064)
			(end -0.7874 0.4064)
			(stroke
				(width 0.1524)
				(type default)
			)
			(layer "B.SilkS")
		)
		(fp_line
			(start -0.7874 0.4064)
			(end 0.7874 0.4064)
			(stroke
				(width 0.1524)
				(type default)
			)
			(layer "B.SilkS")
		)
		(fp_line
			(start 0.7874 -0.4064)
			(end -0.7874 -0.4064)
			(stroke
				(width 0.1524)
				(type default)
			)
			(layer "B.SilkS")
		)
		(fp_line
			(start 0.7874 0.4064)
			(end 0.7874 -0.4064)
			(stroke
				(width 0.1524)
				(type default)
			)
			(layer "B.SilkS")
		)
		(fp_line
			(start -0.67945 -0.3048)
			(end -0.67945 0.3048)
			(stroke
				(width 0.1)
				(type default)
			)
			(layer "B.Fab")
		)
		(fp_line
			(start -0.67945 0.3048)
			(end -0.120396 0.3048)
			(stroke
				(width 0.1)
				(type default)
			)
			(layer "B.Fab")
		)
		(fp_line
			(start -0.12065 -0.3048)
			(end -0.67945 -0.3048)
			(stroke
				(width 0.1)
				(type default)
			)
			(layer "B.Fab")
		)
		(fp_line
			(start -0.12065 -0.2794)
			(end -0.12065 -0.3048)
			(stroke
				(width 0.1)
				(type default)
			)
			(layer "B.Fab")
		)
		(fp_line
			(start -0.120396 0.2794)
			(end 0.12065 0.2794)
			(stroke
				(width 0.1)
				(type default)
			)
			(layer "B.Fab")
		)
		(fp_line
			(start -0.120396 0.3048)
			(end -0.120396 0.2794)
			(stroke
				(width 0.1)
				(type default)
			)
			(layer "B.Fab")
		)
		(fp_line
			(start 0.12065 -0.305054)
			(end 0.12065 -0.2794)
			(stroke
				(width 0.1)
				(type default)
			)
			(layer "B.Fab")
		)
		(fp_line
			(start 0.12065 -0.2794)
			(end -0.12065 -0.2794)
			(stroke
				(width 0.1)
				(type default)
			)
			(layer "B.Fab")
		)
		(fp_line
			(start 0.12065 0.2794)
			(end 0.12065 0.3048)
			(stroke
				(width 0.1)
				(type default)
			)
			(layer "B.Fab")
		)
		(fp_line
			(start 0.12065 0.3048)
			(end 0.67945 0.3048)
			(stroke
				(width 0.1)
				(type default)
			)
			(layer "B.Fab")
		)
		(fp_line
			(start 0.67945 -0.305054)
			(end 0.12065 -0.305054)
			(stroke
				(width 0.1)
				(type default)
			)
			(layer "B.Fab")
		)
		(fp_line
			(start 0.67945 0.3048)
			(end 0.67945 -0.305054)
			(stroke
				(width 0.1)
				(type default)
			)
			(layer "B.Fab")
		)
		(pad "1" smd circle
			(at 0.40005 0 180)
			(size 0 0)
			(layers "B.Cu" "B.Mask" "B.Paste")
			(net "PVDDCR_SOC_P0")
		)
		(pad "2" smd circle
			(at -0.40005 0 180)
			(size 0 0)
			(layers "B.Cu" "B.Mask" "B.Paste")
			(net "GND")
		)
	)
	(footprint ""
		(layer "B.Cu")
		(at 91.906344 -386.766562 90)
		(property "Reference" "C300"
			(at 0 0 90)
			(layer "B.SilkS")
			(hide yes)
			(effects
				(font
					(size 1.27 1.27)
				)
				(justify mirror)
			)
		)
		(property "Value" ""
			(at 0 0 90)
			(layer "B.Fab")
			(effects
				(font
					(size 1.27 1.27)
				)
				(justify mirror)
			)
		)
		(duplicate_pad_numbers_are_jumpers no)
		(fp_line
			(start 0.299974 -0.150114)
			(end -0.299974 -0.150114)
			(stroke
				(width 0.1)
				(type default)
			)
			(layer "B.Fab")
		)
		(fp_line
			(start -0.299974 -0.150114)
			(end -0.299974 0.150114)
			(stroke
				(width 0.1)
				(type default)
			)
			(layer "B.Fab")
		)
		(fp_line
			(start 0.299974 0.150114)
			(end 0.299974 -0.150114)
			(stroke
				(width 0.1)
				(type default)
			)
			(layer "B.Fab")
		)
		(fp_line
			(start -0.299974 0.150114)
			(end 0.299974 0.150114)
			(stroke
				(width 0.1)
				(type default)
			)
			(layer "B.Fab")
		)
		(pad "1" smd rect
			(at 0.2667 0 270)
			(size 0.3048 0.381)
			(layers "B.Cu" "B.Mask" "B.Paste")
			(net "P0V9_CPU1_RT_2D")
		)
		(pad "2" smd rect
			(at -0.2667 0 270)
			(size 0.3048 0.381)
			(layers "B.Cu" "B.Mask" "B.Paste")
			(net "GND")
		)
	)
	(footprint ""
		(layer "B.Cu")
		(at 316.718188 -396.393162 -90)
		(property "Reference" "C544"
			(at 0 0 90)
			(layer "B.SilkS")
			(hide yes)
			(effects
				(font
					(size 1.27 1.27)
				)
				(justify mirror)
			)
		)
		(property "Value" ""
			(at 0 0 90)
			(layer "B.Fab")
			(effects
				(font
					(size 1.27 1.27)
				)
				(justify mirror)
			)
		)
		(duplicate_pad_numbers_are_jumpers no)
		(fp_line
			(start -0.299974 0.150114)
			(end 0.299974 0.150114)
			(stroke
				(width 0.1)
				(type default)
			)
			(layer "B.Fab")
		)
		(fp_line
			(start 0.299974 0.150114)
			(end 0.299974 -0.150114)
			(stroke
				(width 0.1)
				(type default)
			)
			(layer "B.Fab")
		)
		(fp_line
			(start -0.299974 -0.150114)
			(end -0.299974 0.150114)
			(stroke
				(width 0.1)
				(type default)
			)
			(layer "B.Fab")
		)
		(fp_line
			(start 0.299974 -0.150114)
			(end -0.299974 -0.150114)
			(stroke
				(width 0.1)
				(type default)
			)
			(layer "B.Fab")
		)
		(pad "1" smd rect
			(at 0.2667 0 90)
			(size 0.3048 0.381)
			(layers "B.Cu" "B.Mask" "B.Paste")
			(net "P0V9_CPU0_RT0_2A_2D")
		)
		(pad "2" smd rect
			(at -0.2667 0 90)
			(size 0.3048 0.381)
			(layers "B.Cu" "B.Mask" "B.Paste")
			(net "GND")
		)
	)
	(footprint ""
		(layer "B.Cu")
		(at 384.739388 -180.078634 90)
		(property "Reference" "PR350"
			(at 0 0 90)
			(layer "B.SilkS")
			(hide yes)
			(effects
				(font
					(size 1.27 1.27)
				)
				(justify mirror)
			)
		)
		(property "Value" ""
			(at 0 0 90)
			(layer "B.Fab")
			(effects
				(font
					(size 1.27 1.27)
				)
				(justify mirror)
			)
		)
		(duplicate_pad_numbers_are_jumpers no)
		(fp_line
			(start 0.7874 -0.4064)
			(end -0.7874 -0.4064)
			(stroke
				(width 0.1524)
				(type default)
			)
			(layer "B.SilkS")
		)
		(fp_line
			(start -0.7874 -0.4064)
			(end -0.7874 0.4064)
			(stroke
				(width 0.1524)
				(type default)
			)
			(layer "B.SilkS")
		)
		(fp_line
			(start 0.7874 0.4064)
			(end 0.7874 -0.4064)
			(stroke
				(width 0.1524)
				(type default)
			)
			(layer "B.SilkS")
		)
		(fp_line
			(start -0.7874 0.4064)
			(end 0.7874 0.4064)
			(stroke
				(width 0.1524)
				(type default)
			)
			(layer "B.SilkS")
		)
		(fp_line
			(start 0.67945 -0.305054)
			(end 0.12065 -0.305054)
			(stroke
				(width 0.1)
				(type default)
			)
			(layer "B.Fab")
		)
		(fp_line
			(start 0.12065 -0.305054)
			(end 0.12065 -0.2794)
			(stroke
				(width 0.1)
				(type default)
			)
			(layer "B.Fab")
		)
		(fp_line
			(start -0.12065 -0.3048)
			(end -0.67945 -0.3048)
			(stroke
				(width 0.1)
				(type default)
			)
			(layer "B.Fab")
		)
		(fp_line
			(start -0.67945 -0.3048)
			(end -0.67945 0.3048)
			(stroke
				(width 0.1)
				(type default)
			)
			(layer "B.Fab")
		)
		(fp_line
			(start 0.12065 -0.2794)
			(end -0.12065 -0.2794)
			(stroke
				(width 0.1)
				(type default)
			)
			(layer "B.Fab")
		)
		(fp_line
			(start -0.12065 -0.2794)
			(end -0.12065 -0.3048)
			(stroke
				(width 0.1)
				(type default)
			)
			(layer "B.Fab")
		)
		(fp_line
			(start 0.12065 0.2794)
			(end 0.12065 0.3048)
			(stroke
				(width 0.1)
				(type default)
			)
			(layer "B.Fab")
		)
		(fp_line
			(start -0.120396 0.2794)
			(end 0.12065 0.2794)
			(stroke
				(width 0.1)
				(type default)
			)
			(layer "B.Fab")
		)
		(fp_line
			(start 0.67945 0.3048)
			(end 0.67945 -0.305054)
			(stroke
				(width 0.1)
				(type default)
			)
			(layer "B.Fab")
		)
		(fp_line
			(start 0.12065 0.3048)
			(end 0.67945 0.3048)
			(stroke
				(width 0.1)
				(type default)
			)
			(layer "B.Fab")
		)
		(fp_line
			(start -0.120396 0.3048)
			(end -0.120396 0.2794)
			(stroke
				(width 0.1)
				(type default)
			)
			(layer "B.Fab")
		)
		(fp_line
			(start -0.67945 0.3048)
			(end -0.120396 0.3048)
			(stroke
				(width 0.1)
				(type default)
			)
			(layer "B.Fab")
		)
		(pad "1" smd circle
			(at 0.40005 0 270)
			(size 0 0)
			(layers "B.Cu" "B.Mask" "B.Paste")
			(net "PVDDCR_CPU0_P0_VOS3")
		)
		(pad "2" smd circle
			(at -0.40005 0 270)
			(size 0 0)
			(layers "B.Cu" "B.Mask" "B.Paste")
			(net "PVDDCR_CPU0_P0")
		)
	)
	(footprint ""
		(layer "B.Cu")
		(at 350.495362 -389.49503)
		(property "Reference" "C7012"
			(at 2.35966 3.083052 0)
			(unlocked yes)
			(layer "B.SilkS")
			(effects
				(font
					(size 0.7874 0.5842)
					(thickness 0.1524)
				)
				(justify left mirror)
			)
		)
		(property "Value" ""
			(at 0 0 0)
			(layer "B.Fab")
			(effects
				(font
					(size 1.27 1.27)
				)
				(justify mirror)
			)
		)
		(duplicate_pad_numbers_are_jumpers no)
		(fp_line
			(start -4.53898 -2.15011)
			(end -4.53898 2.15011)
			(stroke
				(width 0.1524)
				(type default)
			)
			(layer "B.SilkS")
		)
		(fp_line
			(start -4.53898 2.15011)
			(end 4.53898 2.15011)
			(stroke
				(width 0.1524)
				(type default)
			)
			(layer "B.SilkS")
		)
		(fp_line
			(start 4.53898 -2.150618)
			(end 4.539742 2.152142)
			(stroke
				(width 0.1524)
				(type default)
			)
			(layer "B.SilkS")
		)
		(fp_line
			(start 4.53898 -2.15011)
			(end -4.53898 -2.15011)
			(stroke
				(width 0.1524)
				(type default)
			)
			(layer "B.SilkS")
		)
		(fp_line
			(start 4.53898 2.15011)
			(end 4.53898 -2.15011)
			(stroke
				(width 0.1524)
				(type default)
			)
			(layer "B.SilkS")
		)
		(fp_line
			(start 4.69138 -2.150618)
			(end 4.692396 2.161032)
			(stroke
				(width 0.1524)
				(type default)
			)
			(layer "B.SilkS")
		)
		(fp_line
			(start 4.83108 2.150364)
			(end 4.447794 2.149348)
			(stroke
				(width 0.1524)
				(type default)
			)
			(layer "B.SilkS")
		)
		(fp_line
			(start 4.84378 -2.150618)
			(end 4.53898 -2.150618)
			(stroke
				(width 0.1524)
				(type default)
			)
			(layer "B.SilkS")
		)
		(fp_line
			(start 4.84378 -2.150618)
			(end 4.842256 2.163064)
			(stroke
				(width 0.1524)
				(type default)
			)
			(layer "B.SilkS")
		)
		(fp_line
			(start -3.64998 -2.15011)
			(end -3.64998 2.15011)
			(stroke
				(width 0.1)
				(type default)
			)
			(layer "B.Fab")
		)
		(fp_line
			(start -3.64998 2.15011)
			(end 3.64998 2.15011)
			(stroke
				(width 0.1)
				(type default)
			)
			(layer "B.Fab")
		)
		(fp_line
			(start 3.64998 -2.15011)
			(end -3.64998 -2.15011)
			(stroke
				(width 0.1)
				(type default)
			)
			(layer "B.Fab")
		)
		(fp_line
			(start 3.64998 2.15011)
			(end 3.64998 -2.15011)
			(stroke
				(width 0.1)
				(type default)
			)
			(layer "B.Fab")
		)
		(fp_text user "-"
			(at -2.872994 2.336292 0)
			(unlocked yes)
			(layer "B.SilkS")
			(effects
				(font
					(size 1.905 1.4224)
					(thickness 0.1524)
				)
				(justify left mirror)
			)
		)
		(fp_text user "+"
			(at 6.214872 -0.337058 0)
			(unlocked yes)
			(layer "B.SilkS")
			(effects
				(font
					(size 1.905 1.4224)
					(thickness 0.1524)
				)
				(justify left mirror)
			)
		)
		(fp_text user "-"
			(at -4.313174 -0.094488 0)
			(unlocked yes)
			(layer "B.Fab")
			(effects
				(font
					(size 1.905 1.4224)
					(thickness 0.1524)
				)
				(justify left mirror)
			)
		)
		(fp_text user "+"
			(at 6.214872 -0.337058 0)
			(unlocked yes)
			(layer "B.Fab")
			(effects
				(font
					(size 1.905 1.4224)
					(thickness 0.1524)
				)
				(justify left mirror)
			)
		)
		(pad "1" smd rect
			(at 3.199892 0 180)
			(size 2.413 2.8194)
			(layers "B.Cu" "B.Mask" "B.Paste")
			(net "P0V9_CPU0_RT1_2A")
		)
		(pad "2" smd rect
			(at -3.199892 0 180)
			(size 2.413 2.8194)
			(layers "B.Cu" "B.Mask" "B.Paste")
			(net "GND")
		)
	)
	(footprint ""
		(layer "B.Cu")
		(at 401.554696 -344.850212 90)
		(property "Reference" "C226"
			(at 0 0 90)
			(layer "B.SilkS")
			(hide yes)
			(effects
				(font
					(size 1.27 1.27)
				)
				(justify mirror)
			)
		)
		(property "Value" ""
			(at 0 0 90)
			(layer "B.Fab")
			(effects
				(font
					(size 1.27 1.27)
				)
				(justify mirror)
			)
		)
		(duplicate_pad_numbers_are_jumpers no)
		(fp_line
			(start 0.7874 -0.4064)
			(end -0.7874 -0.4064)
			(stroke
				(width 0.1524)
				(type default)
			)
			(layer "B.SilkS")
		)
		(fp_line
			(start -0.7874 -0.4064)
			(end -0.7874 0.4064)
			(stroke
				(width 0.1524)
				(type default)
			)
			(layer "B.SilkS")
		)
		(fp_line
			(start 0.7874 0.4064)
			(end 0.7874 -0.4064)
			(stroke
				(width 0.1524)
				(type default)
			)
			(layer "B.SilkS")
		)
		(fp_line
			(start -0.7874 0.4064)
			(end 0.7874 0.4064)
			(stroke
				(width 0.1524)
				(type default)
			)
			(layer "B.SilkS")
		)
		(fp_line
			(start 0.67945 -0.305054)
			(end 0.12065 -0.305054)
			(stroke
				(width 0.1)
				(type default)
			)
			(layer "B.Fab")
		)
		(fp_line
			(start 0.12065 -0.305054)
			(end 0.12065 -0.2794)
			(stroke
				(width 0.1)
				(type default)
			)
			(layer "B.Fab")
		)
		(fp_line
			(start -0.12065 -0.3048)
			(end -0.67945 -0.3048)
			(stroke
				(width 0.1)
				(type default)
			)
			(layer "B.Fab")
		)
		(fp_line
			(start -0.67945 -0.3048)
			(end -0.67945 0.3048)
			(stroke
				(width 0.1)
				(type default)
			)
			(layer "B.Fab")
		)
		(fp_line
			(start 0.12065 -0.2794)
			(end -0.12065 -0.2794)
			(stroke
				(width 0.1)
				(type default)
			)
			(layer "B.Fab")
		)
		(fp_line
			(start -0.12065 -0.2794)
			(end -0.12065 -0.3048)
			(stroke
				(width 0.1)
				(type default)
			)
			(layer "B.Fab")
		)
		(fp_line
			(start 0.12065 0.2794)
			(end 0.12065 0.3048)
			(stroke
				(width 0.1)
				(type default)
			)
			(layer "B.Fab")
		)
		(fp_line
			(start -0.120396 0.2794)
			(end 0.12065 0.2794)
			(stroke
				(width 0.1)
				(type default)
			)
			(layer "B.Fab")
		)
		(fp_line
			(start 0.67945 0.3048)
			(end 0.67945 -0.305054)
			(stroke
				(width 0.1)
				(type default)
			)
			(layer "B.Fab")
		)
		(fp_line
			(start 0.12065 0.3048)
			(end 0.67945 0.3048)
			(stroke
				(width 0.1)
				(type default)
			)
			(layer "B.Fab")
		)
		(fp_line
			(start -0.120396 0.3048)
			(end -0.120396 0.2794)
			(stroke
				(width 0.1)
				(type default)
			)
			(layer "B.Fab")
		)
		(fp_line
			(start -0.67945 0.3048)
			(end -0.120396 0.3048)
			(stroke
				(width 0.1)
				(type default)
			)
			(layer "B.Fab")
		)
		(pad "1" smd circle
			(at 0.40005 0 270)
			(size 0 0)
			(layers "B.Cu" "B.Mask" "B.Paste")
			(net "PVDD18_S5_P0")
		)
		(pad "2" smd circle
			(at -0.40005 0 270)
			(size 0 0)
			(layers "B.Cu" "B.Mask" "B.Paste")
			(net "GND")
		)
	)
	(footprint ""
		(layer "B.Cu")
		(at 90.209878 -142.85341)
		(property "Reference" "C249"
			(at 0 0 0)
			(layer "B.SilkS")
			(hide yes)
			(effects
				(font
					(size 1.27 1.27)
				)
				(justify mirror)
			)
		)
		(property "Value" ""
			(at 0 0 0)
			(layer "B.Fab")
			(effects
				(font
					(size 1.27 1.27)
				)
				(justify mirror)
			)
		)
		(duplicate_pad_numbers_are_jumpers no)
		(fp_line
			(start -0.7874 -0.4064)
			(end -0.7874 0.4064)
			(stroke
				(width 0.1524)
				(type default)
			)
			(layer "B.SilkS")
		)
		(fp_line
			(start -0.7874 0.4064)
			(end 0.7874 0.4064)
			(stroke
				(width 0.1524)
				(type default)
			)
			(layer "B.SilkS")
		)
		(fp_line
			(start 0.7874 -0.4064)
			(end -0.7874 -0.4064)
			(stroke
				(width 0.1524)
				(type default)
			)
			(layer "B.SilkS")
		)
		(fp_line
			(start 0.7874 0.4064)
			(end 0.7874 -0.4064)
			(stroke
				(width 0.1524)
				(type default)
			)
			(layer "B.SilkS")
		)
		(fp_line
			(start -0.67945 -0.3048)
			(end -0.67945 0.3048)
			(stroke
				(width 0.1)
				(type default)
			)
			(layer "B.Fab")
		)
		(fp_line
			(start -0.67945 0.3048)
			(end -0.120396 0.3048)
			(stroke
				(width 0.1)
				(type default)
			)
			(layer "B.Fab")
		)
		(fp_line
			(start -0.12065 -0.3048)
			(end -0.67945 -0.3048)
			(stroke
				(width 0.1)
				(type default)
			)
			(layer "B.Fab")
		)
		(fp_line
			(start -0.12065 -0.2794)
			(end -0.12065 -0.3048)
			(stroke
				(width 0.1)
				(type default)
			)
			(layer "B.Fab")
		)
		(fp_line
			(start -0.120396 0.2794)
			(end 0.12065 0.2794)
			(stroke
				(width 0.1)
				(type default)
			)
			(layer "B.Fab")
		)
		(fp_line
			(start -0.120396 0.3048)
			(end -0.120396 0.2794)
			(stroke
				(width 0.1)
				(type default)
			)
			(layer "B.Fab")
		)
		(fp_line
			(start 0.12065 -0.305054)
			(end 0.12065 -0.2794)
			(stroke
				(width 0.1)
				(type default)
			)
			(layer "B.Fab")
		)
		(fp_line
			(start 0.12065 -0.2794)
			(end -0.12065 -0.2794)
			(stroke
				(width 0.1)
				(type default)
			)
			(layer "B.Fab")
		)
		(fp_line
			(start 0.12065 0.2794)
			(end 0.12065 0.3048)
			(stroke
				(width 0.1)
				(type default)
			)
			(layer "B.Fab")
		)
		(fp_line
			(start 0.12065 0.3048)
			(end 0.67945 0.3048)
			(stroke
				(width 0.1)
				(type default)
			)
			(layer "B.Fab")
		)
		(fp_line
			(start 0.67945 -0.305054)
			(end 0.12065 -0.305054)
			(stroke
				(width 0.1)
				(type default)
			)
			(layer "B.Fab")
		)
		(fp_line
			(start 0.67945 0.3048)
			(end 0.67945 -0.305054)
			(stroke
				(width 0.1)
				(type default)
			)
			(layer "B.Fab")
		)
		(pad "1" smd circle
			(at 0.40005 0 180)
			(size 0 0)
			(layers "B.Cu" "B.Mask" "B.Paste")
			(net "PVDDCR_CPU0_P1_EN_R")
		)
		(pad "2" smd circle
			(at -0.40005 0 180)
			(size 0 0)
			(layers "B.Cu" "B.Mask" "B.Paste")
			(net "GND")
		)
	)
	(footprint ""
		(layer "B.Cu")
		(at 16.207994 -99.842066)
		(property "Reference" "C2038"
			(at 0 0 0)
			(layer "B.SilkS")
			(hide yes)
			(effects
				(font
					(size 1.27 1.27)
				)
				(justify mirror)
			)
		)
		(property "Value" ""
			(at 0 0 0)
			(layer "B.Fab")
			(effects
				(font
					(size 1.27 1.27)
				)
				(justify mirror)
			)
		)
		(duplicate_pad_numbers_are_jumpers no)
		(fp_line
			(start -0.7874 -0.4064)
			(end -0.7874 0.4064)
			(stroke
				(width 0.1524)
				(type default)
			)
			(layer "B.SilkS")
		)
		(fp_line
			(start -0.7874 0.4064)
			(end 0.7874 0.4064)
			(stroke
				(width 0.1524)
				(type default)
			)
			(layer "B.SilkS")
		)
		(fp_line
			(start 0.7874 -0.4064)
			(end -0.7874 -0.4064)
			(stroke
				(width 0.1524)
				(type default)
			)
			(layer "B.SilkS")
		)
		(fp_line
			(start 0.7874 0.4064)
			(end 0.7874 -0.4064)
			(stroke
				(width 0.1524)
				(type default)
			)
			(layer "B.SilkS")
		)
		(fp_line
			(start -0.67945 -0.3048)
			(end -0.67945 0.3048)
			(stroke
				(width 0.1)
				(type default)
			)
			(layer "B.Fab")
		)
		(fp_line
			(start -0.67945 0.3048)
			(end -0.120396 0.3048)
			(stroke
				(width 0.1)
				(type default)
			)
			(layer "B.Fab")
		)
		(fp_line
			(start -0.12065 -0.3048)
			(end -0.67945 -0.3048)
			(stroke
				(width 0.1)
				(type default)
			)
			(layer "B.Fab")
		)
		(fp_line
			(start -0.12065 -0.2794)
			(end -0.12065 -0.3048)
			(stroke
				(width 0.1)
				(type default)
			)
			(layer "B.Fab")
		)
		(fp_line
			(start -0.120396 0.2794)
			(end 0.12065 0.2794)
			(stroke
				(width 0.1)
				(type default)
			)
			(layer "B.Fab")
		)
		(fp_line
			(start -0.120396 0.3048)
			(end -0.120396 0.2794)
			(stroke
				(width 0.1)
				(type default)
			)
			(layer "B.Fab")
		)
		(fp_line
			(start 0.12065 -0.305054)
			(end 0.12065 -0.2794)
			(stroke
				(width 0.1)
				(type default)
			)
			(layer "B.Fab")
		)
		(fp_line
			(start 0.12065 -0.2794)
			(end -0.12065 -0.2794)
			(stroke
				(width 0.1)
				(type default)
			)
			(layer "B.Fab")
		)
		(fp_line
			(start 0.12065 0.2794)
			(end 0.12065 0.3048)
			(stroke
				(width 0.1)
				(type default)
			)
			(layer "B.Fab")
		)
		(fp_line
			(start 0.12065 0.3048)
			(end 0.67945 0.3048)
			(stroke
				(width 0.1)
				(type default)
			)
			(layer "B.Fab")
		)
		(fp_line
			(start 0.67945 -0.305054)
			(end 0.12065 -0.305054)
			(stroke
				(width 0.1)
				(type default)
			)
			(layer "B.Fab")
		)
		(fp_line
			(start 0.67945 0.3048)
			(end 0.67945 -0.305054)
			(stroke
				(width 0.1)
				(type default)
			)
			(layer "B.Fab")
		)
		(pad "1" smd circle
			(at 0.40005 0 180)
			(size 0 0)
			(layers "B.Cu" "B.Mask" "B.Paste")
			(net "P3V3_AUX_USB_HUB")
		)
		(pad "2" smd circle
			(at -0.40005 0 180)
			(size 0 0)
			(layers "B.Cu" "B.Mask" "B.Paste")
			(net "GND")
		)
	)
	(footprint ""
		(layer "B.Cu")
		(at 411.41904 -398.942052 90)
		(property "Reference" "C670"
			(at 0 0 90)
			(layer "B.SilkS")
			(hide yes)
			(effects
				(font
					(size 1.27 1.27)
				)
				(justify mirror)
			)
		)
		(property "Value" ""
			(at 0 0 90)
			(layer "B.Fab")
			(effects
				(font
					(size 1.27 1.27)
				)
				(justify mirror)
			)
		)
		(duplicate_pad_numbers_are_jumpers no)
		(fp_line
			(start 0.7874 -0.4064)
			(end -0.7874 -0.4064)
			(stroke
				(width 0.1524)
				(type default)
			)
			(layer "B.SilkS")
		)
		(fp_line
			(start -0.7874 -0.4064)
			(end -0.7874 0.4064)
			(stroke
				(width 0.1524)
				(type default)
			)
			(layer "B.SilkS")
		)
		(fp_line
			(start 0.7874 0.4064)
			(end 0.7874 -0.4064)
			(stroke
				(width 0.1524)
				(type default)
			)
			(layer "B.SilkS")
		)
		(fp_line
			(start -0.7874 0.4064)
			(end 0.7874 0.4064)
			(stroke
				(width 0.1524)
				(type default)
			)
			(layer "B.SilkS")
		)
		(fp_line
			(start 0.67945 -0.305054)
			(end 0.12065 -0.305054)
			(stroke
				(width 0.1)
				(type default)
			)
			(layer "B.Fab")
		)
		(fp_line
			(start 0.12065 -0.305054)
			(end 0.12065 -0.2794)
			(stroke
				(width 0.1)
				(type default)
			)
			(layer "B.Fab")
		)
		(fp_line
			(start -0.12065 -0.3048)
			(end -0.67945 -0.3048)
			(stroke
				(width 0.1)
				(type default)
			)
			(layer "B.Fab")
		)
		(fp_line
			(start -0.67945 -0.3048)
			(end -0.67945 0.3048)
			(stroke
				(width 0.1)
				(type default)
			)
			(layer "B.Fab")
		)
		(fp_line
			(start 0.12065 -0.2794)
			(end -0.12065 -0.2794)
			(stroke
				(width 0.1)
				(type default)
			)
			(layer "B.Fab")
		)
		(fp_line
			(start -0.12065 -0.2794)
			(end -0.12065 -0.3048)
			(stroke
				(width 0.1)
				(type default)
			)
			(layer "B.Fab")
		)
		(fp_line
			(start 0.12065 0.2794)
			(end 0.12065 0.3048)
			(stroke
				(width 0.1)
				(type default)
			)
			(layer "B.Fab")
		)
		(fp_line
			(start -0.120396 0.2794)
			(end 0.12065 0.2794)
			(stroke
				(width 0.1)
				(type default)
			)
			(layer "B.Fab")
		)
		(fp_line
			(start 0.67945 0.3048)
			(end 0.67945 -0.305054)
			(stroke
				(width 0.1)
				(type default)
			)
			(layer "B.Fab")
		)
		(fp_line
			(start 0.12065 0.3048)
			(end 0.67945 0.3048)
			(stroke
				(width 0.1)
				(type default)
			)
			(layer "B.Fab")
		)
		(fp_line
			(start -0.120396 0.3048)
			(end -0.120396 0.2794)
			(stroke
				(width 0.1)
				(type default)
			)
			(layer "B.Fab")
		)
		(fp_line
			(start -0.67945 0.3048)
			(end -0.120396 0.3048)
			(stroke
				(width 0.1)
				(type default)
			)
			(layer "B.Fab")
		)
		(pad "1" smd circle
			(at 0.40005 0 270)
			(size 0 0)
			(layers "B.Cu" "B.Mask" "B.Paste")
			(net "P1V8_CPU0_RT2_1A")
		)
		(pad "2" smd circle
			(at -0.40005 0 270)
			(size 0 0)
			(layers "B.Cu" "B.Mask" "B.Paste")
			(net "GND")
		)
	)
	(footprint ""
		(layer "B.Cu")
		(at 153.006298 -386.766562 90)
		(property "Reference" "C385"
			(at 0 0 90)
			(layer "B.SilkS")
			(hide yes)
			(effects
				(font
					(size 1.27 1.27)
				)
				(justify mirror)
			)
		)
		(property "Value" ""
			(at 0 0 90)
			(layer "B.Fab")
			(effects
				(font
					(size 1.27 1.27)
				)
				(justify mirror)
			)
		)
		(duplicate_pad_numbers_are_jumpers no)
		(fp_line
			(start 0.299974 -0.150114)
			(end -0.299974 -0.150114)
			(stroke
				(width 0.1)
				(type default)
			)
			(layer "B.Fab")
		)
		(fp_line
			(start -0.299974 -0.150114)
			(end -0.299974 0.150114)
			(stroke
				(width 0.1)
				(type default)
			)
			(layer "B.Fab")
		)
		(fp_line
			(start 0.299974 0.150114)
			(end 0.299974 -0.150114)
			(stroke
				(width 0.1)
				(type default)
			)
			(layer "B.Fab")
		)
		(fp_line
			(start -0.299974 0.150114)
			(end 0.299974 0.150114)
			(stroke
				(width 0.1)
				(type default)
			)
			(layer "B.Fab")
		)
		(pad "1" smd rect
			(at 0.2667 0 270)
			(size 0.3048 0.381)
			(layers "B.Cu" "B.Mask" "B.Paste")
			(net "P0V9_CPU1_RT_2D")
		)
		(pad "2" smd rect
			(at -0.2667 0 270)
			(size 0.3048 0.381)
			(layers "B.Cu" "B.Mask" "B.Paste")
			(net "GND")
		)
	)
	(footprint ""
		(layer "B.Cu")
		(at 337.106006 -395.148562 90)
		(property "Reference" "C647"
			(at 0 0 90)
			(layer "B.SilkS")
			(hide yes)
			(effects
				(font
					(size 1.27 1.27)
				)
				(justify mirror)
			)
		)
		(property "Value" ""
			(at 0 0 90)
			(layer "B.Fab")
			(effects
				(font
					(size 1.27 1.27)
				)
				(justify mirror)
			)
		)
		(duplicate_pad_numbers_are_jumpers no)
		(fp_line
			(start 0.299974 -0.150114)
			(end -0.299974 -0.150114)
			(stroke
				(width 0.1)
				(type default)
			)
			(layer "B.Fab")
		)
		(fp_line
			(start -0.299974 -0.150114)
			(end -0.299974 0.150114)
			(stroke
				(width 0.1)
				(type default)
			)
			(layer "B.Fab")
		)
		(fp_line
			(start 0.299974 0.150114)
			(end 0.299974 -0.150114)
			(stroke
				(width 0.1)
				(type default)
			)
			(layer "B.Fab")
		)
		(fp_line
			(start -0.299974 0.150114)
			(end 0.299974 0.150114)
			(stroke
				(width 0.1)
				(type default)
			)
			(layer "B.Fab")
		)
		(pad "1" smd rect
			(at 0.2667 0 270)
			(size 0.3048 0.381)
			(layers "B.Cu" "B.Mask" "B.Paste")
			(net "P0V9_CPU0_RT1_2A")
		)
		(pad "2" smd rect
			(at -0.2667 0 270)
			(size 0.3048 0.381)
			(layers "B.Cu" "B.Mask" "B.Paste")
			(net "GND")
		)
	)
	(footprint ""
		(layer "B.Cu")
		(at 355.727508 -331.304646 -90)
		(property "Reference" "PC123_6"
			(at 0 0 90)
			(layer "B.SilkS")
			(hide yes)
			(effects
				(font
					(size 1.27 1.27)
				)
				(justify mirror)
			)
		)
		(property "Value" ""
			(at 0 0 90)
			(layer "B.Fab")
			(effects
				(font
					(size 1.27 1.27)
				)
				(justify mirror)
			)
		)
		(duplicate_pad_numbers_are_jumpers no)
		(fp_line
			(start -1.524 0.762)
			(end 1.524 0.762)
			(stroke
				(width 0.1524)
				(type default)
			)
			(layer "B.SilkS")
		)
		(fp_line
			(start 1.524 0.762)
			(end 1.524 -0.762)
			(stroke
				(width 0.1524)
				(type default)
			)
			(layer "B.SilkS")
		)
		(fp_line
			(start -1.524 -0.762)
			(end -1.524 0.762)
			(stroke
				(width 0.1524)
				(type default)
			)
			(layer "B.SilkS")
		)
		(fp_line
			(start 1.524 -0.762)
			(end -1.524 -0.762)
			(stroke
				(width 0.1524)
				(type default)
			)
			(layer "B.SilkS")
		)
		(fp_line
			(start -1.1049 0.724916)
			(end -1.1049 -0.724916)
			(stroke
				(width 0.1)
				(type default)
			)
			(layer "B.Fab")
		)
		(fp_line
			(start 1.1049 0.724916)
			(end -1.1049 0.724916)
			(stroke
				(width 0.1)
				(type default)
			)
			(layer "B.Fab")
		)
		(fp_line
			(start -1.1049 -0.724916)
			(end 1.1049 -0.724916)
			(stroke
				(width 0.1)
				(type default)
			)
			(layer "B.Fab")
		)
		(fp_line
			(start 1.1049 -0.724916)
			(end 1.1049 0.724916)
			(stroke
				(width 0.1)
				(type default)
			)
			(layer "B.Fab")
		)
		(pad "1" smd rect
			(at 0.889 0 270)
			(size 1.016 1.27)
			(layers "B.Cu" "B.Mask" "B.Paste")
			(net "PVDDCR_CPU1_P0")
		)
		(pad "2" smd rect
			(at -0.889 0 270)
			(size 1.016 1.27)
			(layers "B.Cu" "B.Mask" "B.Paste")
			(net "GND")
		)
	)
	(footprint ""
		(layer "B.Cu")
		(at 153.146252 -388.011162 -90)
		(property "Reference" "C383"
			(at 0 0 90)
			(layer "B.SilkS")
			(hide yes)
			(effects
				(font
					(size 1.27 1.27)
				)
				(justify mirror)
			)
		)
		(property "Value" ""
			(at 0 0 90)
			(layer "B.Fab")
			(effects
				(font
					(size 1.27 1.27)
				)
				(justify mirror)
			)
		)
		(duplicate_pad_numbers_are_jumpers no)
		(fp_line
			(start -0.299974 0.150114)
			(end 0.299974 0.150114)
			(stroke
				(width 0.1)
				(type default)
			)
			(layer "B.Fab")
		)
		(fp_line
			(start 0.299974 0.150114)
			(end 0.299974 -0.150114)
			(stroke
				(width 0.1)
				(type default)
			)
			(layer "B.Fab")
		)
		(fp_line
			(start -0.299974 -0.150114)
			(end -0.299974 0.150114)
			(stroke
				(width 0.1)
				(type default)
			)
			(layer "B.Fab")
		)
		(fp_line
			(start 0.299974 -0.150114)
			(end -0.299974 -0.150114)
			(stroke
				(width 0.1)
				(type default)
			)
			(layer "B.Fab")
		)
		(pad "1" smd rect
			(at 0.2667 0 90)
			(size 0.3048 0.381)
			(layers "B.Cu" "B.Mask" "B.Paste")
			(net "P0V9_CPU1_RT_2D")
		)
		(pad "2" smd rect
			(at -0.2667 0 90)
			(size 0.3048 0.381)
			(layers "B.Cu" "B.Mask" "B.Paste")
			(net "GND")
		)
	)
	(footprint ""
		(layer "B.Cu")
		(at 238.633 -335.026 180)
		(property "Reference" "R802"
			(at 0 0 0)
			(layer "B.SilkS")
			(hide yes)
			(effects
				(font
					(size 1.27 1.27)
				)
				(justify mirror)
			)
		)
		(property "Value" ""
			(at 0 0 0)
			(layer "B.Fab")
			(effects
				(font
					(size 1.27 1.27)
				)
				(justify mirror)
			)
		)
		(duplicate_pad_numbers_are_jumpers no)
		(fp_line
			(start 0.32512 0.175006)
			(end 0.32512 -0.175006)
			(stroke
				(width 0.1)
				(type default)
			)
			(layer "B.Fab")
		)
		(fp_line
			(start 0.32512 -0.175006)
			(end -0.32512 -0.175006)
			(stroke
				(width 0.1)
				(type default)
			)
			(layer "B.Fab")
		)
		(fp_line
			(start -0.32512 0.175006)
			(end 0.32512 0.175006)
			(stroke
				(width 0.1)
				(type default)
			)
			(layer "B.Fab")
		)
		(fp_line
			(start -0.32512 -0.175006)
			(end -0.32512 0.175006)
			(stroke
				(width 0.1)
				(type default)
			)
			(layer "B.Fab")
		)
		(pad "1" smd rect
			(at 0.2667 0)
			(size 0.3048 0.381)
			(layers "B.Cu" "B.Mask" "B.Paste")
			(net "SMB_RT_CPU1_P0_ROM_MUX_2D_SCL")
		)
		(pad "2" smd rect
			(at -0.2667 0 180)
			(size 0.3048 0.381)
			(layers "B.Cu" "B.Mask" "B.Paste")
			(net "SMB_RT_CPU1_P0_ROM_MUX_2D_R_SCL")
		)
	)
	(footprint ""
		(layer "B.Cu")
		(at 243.713 -324.866)
		(property "Reference" "C1081"
			(at 0 0 0)
			(layer "B.SilkS")
			(hide yes)
			(effects
				(font
					(size 1.27 1.27)
				)
				(justify mirror)
			)
		)
		(property "Value" ""
			(at 0 0 0)
			(layer "B.Fab")
			(effects
				(font
					(size 1.27 1.27)
				)
				(justify mirror)
			)
		)
		(duplicate_pad_numbers_are_jumpers no)
		(fp_line
			(start -0.7874 -0.4064)
			(end -0.7874 0.4064)
			(stroke
				(width 0.1524)
				(type default)
			)
			(layer "B.SilkS")
		)
		(fp_line
			(start -0.7874 0.4064)
			(end 0.7874 0.4064)
			(stroke
				(width 0.1524)
				(type default)
			)
			(layer "B.SilkS")
		)
		(fp_line
			(start 0.7874 -0.4064)
			(end -0.7874 -0.4064)
			(stroke
				(width 0.1524)
				(type default)
			)
			(layer "B.SilkS")
		)
		(fp_line
			(start 0.7874 0.4064)
			(end 0.7874 -0.4064)
			(stroke
				(width 0.1524)
				(type default)
			)
			(layer "B.SilkS")
		)
		(fp_line
			(start -0.67945 -0.3048)
			(end -0.67945 0.3048)
			(stroke
				(width 0.1)
				(type default)
			)
			(layer "B.Fab")
		)
		(fp_line
			(start -0.67945 0.3048)
			(end -0.120396 0.3048)
			(stroke
				(width 0.1)
				(type default)
			)
			(layer "B.Fab")
		)
		(fp_line
			(start -0.12065 -0.3048)
			(end -0.67945 -0.3048)
			(stroke
				(width 0.1)
				(type default)
			)
			(layer "B.Fab")
		)
		(fp_line
			(start -0.12065 -0.2794)
			(end -0.12065 -0.3048)
			(stroke
				(width 0.1)
				(type default)
			)
			(layer "B.Fab")
		)
		(fp_line
			(start -0.120396 0.2794)
			(end 0.12065 0.2794)
			(stroke
				(width 0.1)
				(type default)
			)
			(layer "B.Fab")
		)
		(fp_line
			(start -0.120396 0.3048)
			(end -0.120396 0.2794)
			(stroke
				(width 0.1)
				(type default)
			)
			(layer "B.Fab")
		)
		(fp_line
			(start 0.12065 -0.305054)
			(end 0.12065 -0.2794)
			(stroke
				(width 0.1)
				(type default)
			)
			(layer "B.Fab")
		)
		(fp_line
			(start 0.12065 -0.2794)
			(end -0.12065 -0.2794)
			(stroke
				(width 0.1)
				(type default)
			)
			(layer "B.Fab")
		)
		(fp_line
			(start 0.12065 0.2794)
			(end 0.12065 0.3048)
			(stroke
				(width 0.1)
				(type default)
			)
			(layer "B.Fab")
		)
		(fp_line
			(start 0.12065 0.3048)
			(end 0.67945 0.3048)
			(stroke
				(width 0.1)
				(type default)
			)
			(layer "B.Fab")
		)
		(fp_line
			(start 0.67945 -0.305054)
			(end 0.12065 -0.305054)
			(stroke
				(width 0.1)
				(type default)
			)
			(layer "B.Fab")
		)
		(fp_line
			(start 0.67945 0.3048)
			(end 0.67945 -0.305054)
			(stroke
				(width 0.1)
				(type default)
			)
			(layer "B.Fab")
		)
		(pad "1" smd circle
			(at 0.40005 0 180)
			(size 0 0)
			(layers "B.Cu" "B.Mask" "B.Paste")
			(net "PVDD18_S5_P1_ADC_MAM")
		)
		(pad "2" smd circle
			(at -0.40005 0 180)
			(size 0 0)
			(layers "B.Cu" "B.Mask" "B.Paste")
			(net "GND")
		)
	)
	(footprint ""
		(layer "B.Cu")
		(at 320.211958 -203.917296 90)
		(property "Reference" "R443"
			(at 0 0 90)
			(layer "B.SilkS")
			(hide yes)
			(effects
				(font
					(size 1.27 1.27)
				)
				(justify mirror)
			)
		)
		(property "Value" ""
			(at 0 0 90)
			(layer "B.Fab")
			(effects
				(font
					(size 1.27 1.27)
				)
				(justify mirror)
			)
		)
		(duplicate_pad_numbers_are_jumpers no)
		(fp_line
			(start 0.7874 -0.4064)
			(end -0.7874 -0.4064)
			(stroke
				(width 0.1524)
				(type default)
			)
			(layer "B.SilkS")
		)
		(fp_line
			(start -0.7874 -0.4064)
			(end -0.7874 0.4064)
			(stroke
				(width 0.1524)
				(type default)
			)
			(layer "B.SilkS")
		)
		(fp_line
			(start 0.7874 0.4064)
			(end 0.7874 -0.4064)
			(stroke
				(width 0.1524)
				(type default)
			)
			(layer "B.SilkS")
		)
		(fp_line
			(start -0.7874 0.4064)
			(end 0.7874 0.4064)
			(stroke
				(width 0.1524)
				(type default)
			)
			(layer "B.SilkS")
		)
		(fp_line
			(start 0.67945 -0.305054)
			(end 0.12065 -0.305054)
			(stroke
				(width 0.1)
				(type default)
			)
			(layer "B.Fab")
		)
		(fp_line
			(start 0.12065 -0.305054)
			(end 0.12065 -0.2794)
			(stroke
				(width 0.1)
				(type default)
			)
			(layer "B.Fab")
		)
		(fp_line
			(start -0.12065 -0.3048)
			(end -0.67945 -0.3048)
			(stroke
				(width 0.1)
				(type default)
			)
			(layer "B.Fab")
		)
		(fp_line
			(start -0.67945 -0.3048)
			(end -0.67945 0.3048)
			(stroke
				(width 0.1)
				(type default)
			)
			(layer "B.Fab")
		)
		(fp_line
			(start 0.12065 -0.2794)
			(end -0.12065 -0.2794)
			(stroke
				(width 0.1)
				(type default)
			)
			(layer "B.Fab")
		)
		(fp_line
			(start -0.12065 -0.2794)
			(end -0.12065 -0.3048)
			(stroke
				(width 0.1)
				(type default)
			)
			(layer "B.Fab")
		)
		(fp_line
			(start 0.12065 0.2794)
			(end 0.12065 0.3048)
			(stroke
				(width 0.1)
				(type default)
			)
			(layer "B.Fab")
		)
		(fp_line
			(start -0.120396 0.2794)
			(end 0.12065 0.2794)
			(stroke
				(width 0.1)
				(type default)
			)
			(layer "B.Fab")
		)
		(fp_line
			(start 0.67945 0.3048)
			(end 0.67945 -0.305054)
			(stroke
				(width 0.1)
				(type default)
			)
			(layer "B.Fab")
		)
		(fp_line
			(start 0.12065 0.3048)
			(end 0.67945 0.3048)
			(stroke
				(width 0.1)
				(type default)
			)
			(layer "B.Fab")
		)
		(fp_line
			(start -0.120396 0.3048)
			(end -0.120396 0.2794)
			(stroke
				(width 0.1)
				(type default)
			)
			(layer "B.Fab")
		)
		(fp_line
			(start -0.67945 0.3048)
			(end -0.120396 0.3048)
			(stroke
				(width 0.1)
				(type default)
			)
			(layer "B.Fab")
		)
		(pad "1" smd circle
			(at 0.40005 0 270)
			(size 0 0)
			(layers "B.Cu" "B.Mask" "B.Paste")
			(net "PWRGD_CPU0_PWROK")
		)
		(pad "2" smd circle
			(at -0.40005 0 270)
			(size 0 0)
			(layers "B.Cu" "B.Mask" "B.Paste")
			(net "PVDD18_S5_P0")
		)
	)
	(footprint ""
		(layer "B.Cu")
		(at 234.569 -240.411 -90)
		(property "Reference" "R1158"
			(at 0 0 90)
			(layer "B.SilkS")
			(hide yes)
			(effects
				(font
					(size 1.27 1.27)
				)
				(justify mirror)
			)
		)
		(property "Value" ""
			(at 0 0 90)
			(layer "B.Fab")
			(effects
				(font
					(size 1.27 1.27)
				)
				(justify mirror)
			)
		)
		(duplicate_pad_numbers_are_jumpers no)
		(fp_line
			(start -0.7874 0.4064)
			(end 0.7874 0.4064)
			(stroke
				(width 0.1524)
				(type default)
			)
			(layer "B.SilkS")
		)
		(fp_line
			(start 0.7874 0.4064)
			(end 0.7874 -0.4064)
			(stroke
				(width 0.1524)
				(type default)
			)
			(layer "B.SilkS")
		)
		(fp_line
			(start -0.7874 -0.4064)
			(end -0.7874 0.4064)
			(stroke
				(width 0.1524)
				(type default)
			)
			(layer "B.SilkS")
		)
		(fp_line
			(start 0.7874 -0.4064)
			(end -0.7874 -0.4064)
			(stroke
				(width 0.1524)
				(type default)
			)
			(layer "B.SilkS")
		)
		(fp_line
			(start -0.67945 0.3048)
			(end -0.120396 0.3048)
			(stroke
				(width 0.1)
				(type default)
			)
			(layer "B.Fab")
		)
		(fp_line
			(start -0.120396 0.3048)
			(end -0.120396 0.2794)
			(stroke
				(width 0.1)
				(type default)
			)
			(layer "B.Fab")
		)
		(fp_line
			(start 0.12065 0.3048)
			(end 0.67945 0.3048)
			(stroke
				(width 0.1)
				(type default)
			)
			(layer "B.Fab")
		)
		(fp_line
			(start 0.67945 0.3048)
			(end 0.67945 -0.305054)
			(stroke
				(width 0.1)
				(type default)
			)
			(layer "B.Fab")
		)
		(fp_line
			(start -0.120396 0.2794)
			(end 0.12065 0.2794)
			(stroke
				(width 0.1)
				(type default)
			)
			(layer "B.Fab")
		)
		(fp_line
			(start 0.12065 0.2794)
			(end 0.12065 0.3048)
			(stroke
				(width 0.1)
				(type default)
			)
			(layer "B.Fab")
		)
		(fp_line
			(start -0.12065 -0.2794)
			(end -0.12065 -0.3048)
			(stroke
				(width 0.1)
				(type default)
			)
			(layer "B.Fab")
		)
		(fp_line
			(start 0.12065 -0.2794)
			(end -0.12065 -0.2794)
			(stroke
				(width 0.1)
				(type default)
			)
			(layer "B.Fab")
		)
		(fp_line
			(start -0.67945 -0.3048)
			(end -0.67945 0.3048)
			(stroke
				(width 0.1)
				(type default)
			)
			(layer "B.Fab")
		)
		(fp_line
			(start -0.12065 -0.3048)
			(end -0.67945 -0.3048)
			(stroke
				(width 0.1)
				(type default)
			)
			(layer "B.Fab")
		)
		(fp_line
			(start 0.12065 -0.305054)
			(end 0.12065 -0.2794)
			(stroke
				(width 0.1)
				(type default)
			)
			(layer "B.Fab")
		)
		(fp_line
			(start 0.67945 -0.305054)
			(end 0.12065 -0.305054)
			(stroke
				(width 0.1)
				(type default)
			)
			(layer "B.Fab")
		)
		(pad "1" smd rect
			(at 0.40005 0 270)
			(size 0.4572 0.508)
			(layers "B.Cu" "B.Mask" "B.Paste")
			(net "SMB_APML_CPU1_R_SDA")
		)
		(pad "2" smd rect
			(at -0.40005 0 270)
			(size 0.4572 0.508)
			(layers "B.Cu" "B.Mask" "B.Paste")
			(net "SMB_APML_CPU1_SDA")
		)
	)
	(footprint ""
		(layer "B.Cu")
		(at 15.113762 -192.362328 90)
		(property "Reference" "R1183"
			(at 0 0 90)
			(layer "B.SilkS")
			(hide yes)
			(effects
				(font
					(size 1.27 1.27)
				)
				(justify mirror)
			)
		)
		(property "Value" ""
			(at 0 0 90)
			(layer "B.Fab")
			(effects
				(font
					(size 1.27 1.27)
				)
				(justify mirror)
			)
		)
		(duplicate_pad_numbers_are_jumpers no)
		(fp_line
			(start 0.7874 -0.4064)
			(end -0.7874 -0.4064)
			(stroke
				(width 0.1524)
				(type default)
			)
			(layer "B.SilkS")
		)
		(fp_line
			(start -0.7874 -0.4064)
			(end -0.7874 0.4064)
			(stroke
				(width 0.1524)
				(type default)
			)
			(layer "B.SilkS")
		)
		(fp_line
			(start 0.7874 0.4064)
			(end 0.7874 -0.4064)
			(stroke
				(width 0.1524)
				(type default)
			)
			(layer "B.SilkS")
		)
		(fp_line
			(start -0.7874 0.4064)
			(end 0.7874 0.4064)
			(stroke
				(width 0.1524)
				(type default)
			)
			(layer "B.SilkS")
		)
		(fp_line
			(start 0.67945 -0.305054)
			(end 0.12065 -0.305054)
			(stroke
				(width 0.1)
				(type default)
			)
			(layer "B.Fab")
		)
		(fp_line
			(start 0.12065 -0.305054)
			(end 0.12065 -0.2794)
			(stroke
				(width 0.1)
				(type default)
			)
			(layer "B.Fab")
		)
		(fp_line
			(start -0.12065 -0.3048)
			(end -0.67945 -0.3048)
			(stroke
				(width 0.1)
				(type default)
			)
			(layer "B.Fab")
		)
		(fp_line
			(start -0.67945 -0.3048)
			(end -0.67945 0.3048)
			(stroke
				(width 0.1)
				(type default)
			)
			(layer "B.Fab")
		)
		(fp_line
			(start 0.12065 -0.2794)
			(end -0.12065 -0.2794)
			(stroke
				(width 0.1)
				(type default)
			)
			(layer "B.Fab")
		)
		(fp_line
			(start -0.12065 -0.2794)
			(end -0.12065 -0.3048)
			(stroke
				(width 0.1)
				(type default)
			)
			(layer "B.Fab")
		)
		(fp_line
			(start 0.12065 0.2794)
			(end 0.12065 0.3048)
			(stroke
				(width 0.1)
				(type default)
			)
			(layer "B.Fab")
		)
		(fp_line
			(start -0.120396 0.2794)
			(end 0.12065 0.2794)
			(stroke
				(width 0.1)
				(type default)
			)
			(layer "B.Fab")
		)
		(fp_line
			(start 0.67945 0.3048)
			(end 0.67945 -0.305054)
			(stroke
				(width 0.1)
				(type default)
			)
			(layer "B.Fab")
		)
		(fp_line
			(start 0.12065 0.3048)
			(end 0.67945 0.3048)
			(stroke
				(width 0.1)
				(type default)
			)
			(layer "B.Fab")
		)
		(fp_line
			(start -0.120396 0.3048)
			(end -0.120396 0.2794)
			(stroke
				(width 0.1)
				(type default)
			)
			(layer "B.Fab")
		)
		(fp_line
			(start -0.67945 0.3048)
			(end -0.120396 0.3048)
			(stroke
				(width 0.1)
				(type default)
			)
			(layer "B.Fab")
		)
		(pad "1" smd circle
			(at 0.40005 0 270)
			(size 0 0)
			(layers "B.Cu" "B.Mask" "B.Paste")
			(net "PWRGD_CHF_CPU1_DIMM")
		)
		(pad "2" smd circle
			(at -0.40005 0 270)
			(size 0 0)
			(layers "B.Cu" "B.Mask" "B.Paste")
			(net "PWRGD_CHAF_CPU1")
		)
	)
	(footprint ""
		(layer "B.Cu")
		(at 355.617272 -261.747762 90)
		(property "Reference" "C2615"
			(at 0 0 90)
			(layer "B.SilkS")
			(hide yes)
			(effects
				(font
					(size 1.27 1.27)
				)
				(justify mirror)
			)
		)
		(property "Value" ""
			(at 0 0 90)
			(layer "B.Fab")
			(effects
				(font
					(size 1.27 1.27)
				)
				(justify mirror)
			)
		)
		(duplicate_pad_numbers_are_jumpers no)
		(fp_line
			(start 0.7874 -0.4064)
			(end -0.7874 -0.4064)
			(stroke
				(width 0.1524)
				(type default)
			)
			(layer "B.SilkS")
		)
		(fp_line
			(start -0.7874 -0.4064)
			(end -0.7874 0.4064)
			(stroke
				(width 0.1524)
				(type default)
			)
			(layer "B.SilkS")
		)
		(fp_line
			(start 0.7874 0.4064)
			(end 0.7874 -0.4064)
			(stroke
				(width 0.1524)
				(type default)
			)
			(layer "B.SilkS")
		)
		(fp_line
			(start -0.7874 0.4064)
			(end 0.7874 0.4064)
			(stroke
				(width 0.1524)
				(type default)
			)
			(layer "B.SilkS")
		)
		(fp_line
			(start 0.67945 -0.305054)
			(end 0.12065 -0.305054)
			(stroke
				(width 0.1)
				(type default)
			)
			(layer "B.Fab")
		)
		(fp_line
			(start 0.12065 -0.305054)
			(end 0.12065 -0.2794)
			(stroke
				(width 0.1)
				(type default)
			)
			(layer "B.Fab")
		)
		(fp_line
			(start -0.12065 -0.3048)
			(end -0.67945 -0.3048)
			(stroke
				(width 0.1)
				(type default)
			)
			(layer "B.Fab")
		)
		(fp_line
			(start -0.67945 -0.3048)
			(end -0.67945 0.3048)
			(stroke
				(width 0.1)
				(type default)
			)
			(layer "B.Fab")
		)
		(fp_line
			(start 0.12065 -0.2794)
			(end -0.12065 -0.2794)
			(stroke
				(width 0.1)
				(type default)
			)
			(layer "B.Fab")
		)
		(fp_line
			(start -0.12065 -0.2794)
			(end -0.12065 -0.3048)
			(stroke
				(width 0.1)
				(type default)
			)
			(layer "B.Fab")
		)
		(fp_line
			(start 0.12065 0.2794)
			(end 0.12065 0.3048)
			(stroke
				(width 0.1)
				(type default)
			)
			(layer "B.Fab")
		)
		(fp_line
			(start -0.120396 0.2794)
			(end 0.12065 0.2794)
			(stroke
				(width 0.1)
				(type default)
			)
			(layer "B.Fab")
		)
		(fp_line
			(start 0.67945 0.3048)
			(end 0.67945 -0.305054)
			(stroke
				(width 0.1)
				(type default)
			)
			(layer "B.Fab")
		)
		(fp_line
			(start 0.12065 0.3048)
			(end 0.67945 0.3048)
			(stroke
				(width 0.1)
				(type default)
			)
			(layer "B.Fab")
		)
		(fp_line
			(start -0.120396 0.3048)
			(end -0.120396 0.2794)
			(stroke
				(width 0.1)
				(type default)
			)
			(layer "B.Fab")
		)
		(fp_line
			(start -0.67945 0.3048)
			(end -0.120396 0.3048)
			(stroke
				(width 0.1)
				(type default)
			)
			(layer "B.Fab")
		)
		(pad "1" smd circle
			(at 0.40005 0 270)
			(size 0 0)
			(layers "B.Cu" "B.Mask" "B.Paste")
			(net "PVDD11_S3_P0")
		)
		(pad "2" smd circle
			(at -0.40005 0 270)
			(size 0 0)
			(layers "B.Cu" "B.Mask" "B.Paste")
			(net "GND")
		)
	)
	(footprint ""
		(layer "B.Cu")
		(at 108.117386 -251.781564)
		(property "Reference" "C2438"
			(at 0 0 0)
			(layer "B.SilkS")
			(hide yes)
			(effects
				(font
					(size 1.27 1.27)
				)
				(justify mirror)
			)
		)
		(property "Value" ""
			(at 0 0 0)
			(layer "B.Fab")
			(effects
				(font
					(size 1.27 1.27)
				)
				(justify mirror)
			)
		)
		(duplicate_pad_numbers_are_jumpers no)
		(fp_line
			(start -0.7874 -0.4064)
			(end -0.7874 0.4064)
			(stroke
				(width 0.1524)
				(type default)
			)
			(layer "B.SilkS")
		)
		(fp_line
			(start -0.7874 0.4064)
			(end 0.7874 0.4064)
			(stroke
				(width 0.1524)
				(type default)
			)
			(layer "B.SilkS")
		)
		(fp_line
			(start 0.7874 -0.4064)
			(end -0.7874 -0.4064)
			(stroke
				(width 0.1524)
				(type default)
			)
			(layer "B.SilkS")
		)
		(fp_line
			(start 0.7874 0.4064)
			(end 0.7874 -0.4064)
			(stroke
				(width 0.1524)
				(type default)
			)
			(layer "B.SilkS")
		)
		(fp_line
			(start -0.67945 -0.3048)
			(end -0.67945 0.3048)
			(stroke
				(width 0.1)
				(type default)
			)
			(layer "B.Fab")
		)
		(fp_line
			(start -0.67945 0.3048)
			(end -0.120396 0.3048)
			(stroke
				(width 0.1)
				(type default)
			)
			(layer "B.Fab")
		)
		(fp_line
			(start -0.12065 -0.3048)
			(end -0.67945 -0.3048)
			(stroke
				(width 0.1)
				(type default)
			)
			(layer "B.Fab")
		)
		(fp_line
			(start -0.12065 -0.2794)
			(end -0.12065 -0.3048)
			(stroke
				(width 0.1)
				(type default)
			)
			(layer "B.Fab")
		)
		(fp_line
			(start -0.120396 0.2794)
			(end 0.12065 0.2794)
			(stroke
				(width 0.1)
				(type default)
			)
			(layer "B.Fab")
		)
		(fp_line
			(start -0.120396 0.3048)
			(end -0.120396 0.2794)
			(stroke
				(width 0.1)
				(type default)
			)
			(layer "B.Fab")
		)
		(fp_line
			(start 0.12065 -0.305054)
			(end 0.12065 -0.2794)
			(stroke
				(width 0.1)
				(type default)
			)
			(layer "B.Fab")
		)
		(fp_line
			(start 0.12065 -0.2794)
			(end -0.12065 -0.2794)
			(stroke
				(width 0.1)
				(type default)
			)
			(layer "B.Fab")
		)
		(fp_line
			(start 0.12065 0.2794)
			(end 0.12065 0.3048)
			(stroke
				(width 0.1)
				(type default)
			)
			(layer "B.Fab")
		)
		(fp_line
			(start 0.12065 0.3048)
			(end 0.67945 0.3048)
			(stroke
				(width 0.1)
				(type default)
			)
			(layer "B.Fab")
		)
		(fp_line
			(start 0.67945 -0.305054)
			(end 0.12065 -0.305054)
			(stroke
				(width 0.1)
				(type default)
			)
			(layer "B.Fab")
		)
		(fp_line
			(start 0.67945 0.3048)
			(end 0.67945 -0.305054)
			(stroke
				(width 0.1)
				(type default)
			)
			(layer "B.Fab")
		)
		(pad "1" smd circle
			(at 0.40005 0 180)
			(size 0 0)
			(layers "B.Cu" "B.Mask" "B.Paste")
			(net "PVDDCR_SOC_P1")
		)
		(pad "2" smd circle
			(at -0.40005 0 180)
			(size 0 0)
			(layers "B.Cu" "B.Mask" "B.Paste")
			(net "GND")
		)
	)
	(footprint ""
		(layer "B.Cu")
		(at 452.62546 -10.60577 90)
		(property "Reference" "R8420"
			(at 0 0 90)
			(layer "B.SilkS")
			(hide yes)
			(effects
				(font
					(size 1.27 1.27)
				)
				(justify mirror)
			)
		)
		(property "Value" ""
			(at 0 0 90)
			(layer "B.Fab")
			(effects
				(font
					(size 1.27 1.27)
				)
				(justify mirror)
			)
		)
		(duplicate_pad_numbers_are_jumpers no)
		(fp_line
			(start 0.7874 -0.4064)
			(end -0.7874 -0.4064)
			(stroke
				(width 0.1524)
				(type default)
			)
			(layer "B.SilkS")
		)
		(fp_line
			(start -0.7874 -0.4064)
			(end -0.7874 0.4064)
			(stroke
				(width 0.1524)
				(type default)
			)
			(layer "B.SilkS")
		)
		(fp_line
			(start 0.7874 0.4064)
			(end 0.7874 -0.4064)
			(stroke
				(width 0.1524)
				(type default)
			)
			(layer "B.SilkS")
		)
		(fp_line
			(start -0.7874 0.4064)
			(end 0.7874 0.4064)
			(stroke
				(width 0.1524)
				(type default)
			)
			(layer "B.SilkS")
		)
		(fp_line
			(start 0.67945 -0.305054)
			(end 0.12065 -0.305054)
			(stroke
				(width 0.1)
				(type default)
			)
			(layer "B.Fab")
		)
		(fp_line
			(start 0.12065 -0.305054)
			(end 0.12065 -0.2794)
			(stroke
				(width 0.1)
				(type default)
			)
			(layer "B.Fab")
		)
		(fp_line
			(start -0.12065 -0.3048)
			(end -0.67945 -0.3048)
			(stroke
				(width 0.1)
				(type default)
			)
			(layer "B.Fab")
		)
		(fp_line
			(start -0.67945 -0.3048)
			(end -0.67945 0.3048)
			(stroke
				(width 0.1)
				(type default)
			)
			(layer "B.Fab")
		)
		(fp_line
			(start 0.12065 -0.2794)
			(end -0.12065 -0.2794)
			(stroke
				(width 0.1)
				(type default)
			)
			(layer "B.Fab")
		)
		(fp_line
			(start -0.12065 -0.2794)
			(end -0.12065 -0.3048)
			(stroke
				(width 0.1)
				(type default)
			)
			(layer "B.Fab")
		)
		(fp_line
			(start 0.12065 0.2794)
			(end 0.12065 0.3048)
			(stroke
				(width 0.1)
				(type default)
			)
			(layer "B.Fab")
		)
		(fp_line
			(start -0.120396 0.2794)
			(end 0.12065 0.2794)
			(stroke
				(width 0.1)
				(type default)
			)
			(layer "B.Fab")
		)
		(fp_line
			(start 0.67945 0.3048)
			(end 0.67945 -0.305054)
			(stroke
				(width 0.1)
				(type default)
			)
			(layer "B.Fab")
		)
		(fp_line
			(start 0.12065 0.3048)
			(end 0.67945 0.3048)
			(stroke
				(width 0.1)
				(type default)
			)
			(layer "B.Fab")
		)
		(fp_line
			(start -0.120396 0.3048)
			(end -0.120396 0.2794)
			(stroke
				(width 0.1)
				(type default)
			)
			(layer "B.Fab")
		)
		(fp_line
			(start -0.67945 0.3048)
			(end -0.120396 0.3048)
			(stroke
				(width 0.1)
				(type default)
			)
			(layer "B.Fab")
		)
		(pad "1" smd circle
			(at 0.40005 0 270)
			(size 0 0)
			(layers "B.Cu" "B.Mask" "B.Paste")
			(net "SGPIO_OCP_SFF_LD_N")
		)
		(pad "2" smd circle
			(at -0.40005 0 270)
			(size 0 0)
			(layers "B.Cu" "B.Mask" "B.Paste")
			(net "P3V3_OCP_SFF")
		)
	)
	(footprint ""
		(layer "B.Cu")
		(at 183.045608 -126.833376 90)
		(property "Reference" "R1278"
			(at 0 0 90)
			(layer "B.SilkS")
			(hide yes)
			(effects
				(font
					(size 1.27 1.27)
				)
				(justify mirror)
			)
		)
		(property "Value" ""
			(at 0 0 90)
			(layer "B.Fab")
			(effects
				(font
					(size 1.27 1.27)
				)
				(justify mirror)
			)
		)
		(duplicate_pad_numbers_are_jumpers no)
		(fp_line
			(start 0.7874 -0.4064)
			(end -0.7874 -0.4064)
			(stroke
				(width 0.1524)
				(type default)
			)
			(layer "B.SilkS")
		)
		(fp_line
			(start -0.7874 -0.4064)
			(end -0.7874 0.4064)
			(stroke
				(width 0.1524)
				(type default)
			)
			(layer "B.SilkS")
		)
		(fp_line
			(start 0.7874 0.4064)
			(end 0.7874 -0.4064)
			(stroke
				(width 0.1524)
				(type default)
			)
			(layer "B.SilkS")
		)
		(fp_line
			(start -0.7874 0.4064)
			(end 0.7874 0.4064)
			(stroke
				(width 0.1524)
				(type default)
			)
			(layer "B.SilkS")
		)
		(fp_line
			(start 0.67945 -0.305054)
			(end 0.12065 -0.305054)
			(stroke
				(width 0.1)
				(type default)
			)
			(layer "B.Fab")
		)
		(fp_line
			(start 0.12065 -0.305054)
			(end 0.12065 -0.2794)
			(stroke
				(width 0.1)
				(type default)
			)
			(layer "B.Fab")
		)
		(fp_line
			(start -0.12065 -0.3048)
			(end -0.67945 -0.3048)
			(stroke
				(width 0.1)
				(type default)
			)
			(layer "B.Fab")
		)
		(fp_line
			(start -0.67945 -0.3048)
			(end -0.67945 0.3048)
			(stroke
				(width 0.1)
				(type default)
			)
			(layer "B.Fab")
		)
		(fp_line
			(start 0.12065 -0.2794)
			(end -0.12065 -0.2794)
			(stroke
				(width 0.1)
				(type default)
			)
			(layer "B.Fab")
		)
		(fp_line
			(start -0.12065 -0.2794)
			(end -0.12065 -0.3048)
			(stroke
				(width 0.1)
				(type default)
			)
			(layer "B.Fab")
		)
		(fp_line
			(start 0.12065 0.2794)
			(end 0.12065 0.3048)
			(stroke
				(width 0.1)
				(type default)
			)
			(layer "B.Fab")
		)
		(fp_line
			(start -0.120396 0.2794)
			(end 0.12065 0.2794)
			(stroke
				(width 0.1)
				(type default)
			)
			(layer "B.Fab")
		)
		(fp_line
			(start 0.67945 0.3048)
			(end 0.67945 -0.305054)
			(stroke
				(width 0.1)
				(type default)
			)
			(layer "B.Fab")
		)
		(fp_line
			(start 0.12065 0.3048)
			(end 0.67945 0.3048)
			(stroke
				(width 0.1)
				(type default)
			)
			(layer "B.Fab")
		)
		(fp_line
			(start -0.120396 0.3048)
			(end -0.120396 0.2794)
			(stroke
				(width 0.1)
				(type default)
			)
			(layer "B.Fab")
		)
		(fp_line
			(start -0.67945 0.3048)
			(end -0.120396 0.3048)
			(stroke
				(width 0.1)
				(type default)
			)
			(layer "B.Fab")
		)
		(pad "1" smd circle
			(at 0.40005 0 270)
			(size 0 0)
			(layers "B.Cu" "B.Mask" "B.Paste")
			(net "FM_P1_PCC0_N")
		)
		(pad "2" smd circle
			(at -0.40005 0 270)
			(size 0 0)
			(layers "B.Cu" "B.Mask" "B.Paste")
			(net "FM_P1_PCC0_R_N")
		)
	)
	(footprint ""
		(layer "B.Cu")
		(at 407.946098 -396.393162 -90)
		(property "Reference" "C791"
			(at 0 0 90)
			(layer "B.SilkS")
			(hide yes)
			(effects
				(font
					(size 1.27 1.27)
				)
				(justify mirror)
			)
		)
		(property "Value" ""
			(at 0 0 90)
			(layer "B.Fab")
			(effects
				(font
					(size 1.27 1.27)
				)
				(justify mirror)
			)
		)
		(duplicate_pad_numbers_are_jumpers no)
		(fp_line
			(start -0.299974 0.150114)
			(end 0.299974 0.150114)
			(stroke
				(width 0.1)
				(type default)
			)
			(layer "B.Fab")
		)
		(fp_line
			(start 0.299974 0.150114)
			(end 0.299974 -0.150114)
			(stroke
				(width 0.1)
				(type default)
			)
			(layer "B.Fab")
		)
		(fp_line
			(start -0.299974 -0.150114)
			(end -0.299974 0.150114)
			(stroke
				(width 0.1)
				(type default)
			)
			(layer "B.Fab")
		)
		(fp_line
			(start 0.299974 -0.150114)
			(end -0.299974 -0.150114)
			(stroke
				(width 0.1)
				(type default)
			)
			(layer "B.Fab")
		)
		(pad "1" smd rect
			(at 0.2667 0 90)
			(size 0.3048 0.381)
			(layers "B.Cu" "B.Mask" "B.Paste")
			(net "P0V9_CPU0_RT2_2A_2D")
		)
		(pad "2" smd rect
			(at -0.2667 0 90)
			(size 0.3048 0.381)
			(layers "B.Cu" "B.Mask" "B.Paste")
			(net "GND")
		)
	)
	(footprint ""
		(layer "B.Cu")
		(at 114.033046 -267.529564)
		(property "Reference" "C2388"
			(at 0 0 0)
			(layer "B.SilkS")
			(hide yes)
			(effects
				(font
					(size 1.27 1.27)
				)
				(justify mirror)
			)
		)
		(property "Value" ""
			(at 0 0 0)
			(layer "B.Fab")
			(effects
				(font
					(size 1.27 1.27)
				)
				(justify mirror)
			)
		)
		(duplicate_pad_numbers_are_jumpers no)
		(fp_line
			(start -0.7874 -0.4064)
			(end -0.7874 0.4064)
			(stroke
				(width 0.1524)
				(type default)
			)
			(layer "B.SilkS")
		)
		(fp_line
			(start -0.7874 0.4064)
			(end 0.7874 0.4064)
			(stroke
				(width 0.1524)
				(type default)
			)
			(layer "B.SilkS")
		)
		(fp_line
			(start 0.7874 -0.4064)
			(end -0.7874 -0.4064)
			(stroke
				(width 0.1524)
				(type default)
			)
			(layer "B.SilkS")
		)
		(fp_line
			(start 0.7874 0.4064)
			(end 0.7874 -0.4064)
			(stroke
				(width 0.1524)
				(type default)
			)
			(layer "B.SilkS")
		)
		(fp_line
			(start -0.67945 -0.3048)
			(end -0.67945 0.3048)
			(stroke
				(width 0.1)
				(type default)
			)
			(layer "B.Fab")
		)
		(fp_line
			(start -0.67945 0.3048)
			(end -0.120396 0.3048)
			(stroke
				(width 0.1)
				(type default)
			)
			(layer "B.Fab")
		)
		(fp_line
			(start -0.12065 -0.3048)
			(end -0.67945 -0.3048)
			(stroke
				(width 0.1)
				(type default)
			)
			(layer "B.Fab")
		)
		(fp_line
			(start -0.12065 -0.2794)
			(end -0.12065 -0.3048)
			(stroke
				(width 0.1)
				(type default)
			)
			(layer "B.Fab")
		)
		(fp_line
			(start -0.120396 0.2794)
			(end 0.12065 0.2794)
			(stroke
				(width 0.1)
				(type default)
			)
			(layer "B.Fab")
		)
		(fp_line
			(start -0.120396 0.3048)
			(end -0.120396 0.2794)
			(stroke
				(width 0.1)
				(type default)
			)
			(layer "B.Fab")
		)
		(fp_line
			(start 0.12065 -0.305054)
			(end 0.12065 -0.2794)
			(stroke
				(width 0.1)
				(type default)
			)
			(layer "B.Fab")
		)
		(fp_line
			(start 0.12065 -0.2794)
			(end -0.12065 -0.2794)
			(stroke
				(width 0.1)
				(type default)
			)
			(layer "B.Fab")
		)
		(fp_line
			(start 0.12065 0.2794)
			(end 0.12065 0.3048)
			(stroke
				(width 0.1)
				(type default)
			)
			(layer "B.Fab")
		)
		(fp_line
			(start 0.12065 0.3048)
			(end 0.67945 0.3048)
			(stroke
				(width 0.1)
				(type default)
			)
			(layer "B.Fab")
		)
		(fp_line
			(start 0.67945 -0.305054)
			(end 0.12065 -0.305054)
			(stroke
				(width 0.1)
				(type default)
			)
			(layer "B.Fab")
		)
		(fp_line
			(start 0.67945 0.3048)
			(end 0.67945 -0.305054)
			(stroke
				(width 0.1)
				(type default)
			)
			(layer "B.Fab")
		)
		(pad "1" smd circle
			(at 0.40005 0 180)
			(size 0 0)
			(layers "B.Cu" "B.Mask" "B.Paste")
			(net "PVDDCR_CPU1_P1")
		)
		(pad "2" smd circle
			(at -0.40005 0 180)
			(size 0 0)
			(layers "B.Cu" "B.Mask" "B.Paste")
			(net "GND")
		)
	)
	(footprint ""
		(layer "B.Cu")
		(at 115.595146 -30.481778)
		(property "Reference" "C6118"
			(at 0 0 0)
			(layer "B.SilkS")
			(hide yes)
			(effects
				(font
					(size 1.27 1.27)
				)
				(justify mirror)
			)
		)
		(property "Value" ""
			(at 0 0 0)
			(layer "B.Fab")
			(effects
				(font
					(size 1.27 1.27)
				)
				(justify mirror)
			)
		)
		(duplicate_pad_numbers_are_jumpers no)
		(fp_line
			(start -1.524 -0.762)
			(end -1.524 0.762)
			(stroke
				(width 0.1524)
				(type default)
			)
			(layer "B.SilkS")
		)
		(fp_line
			(start -1.524 0.762)
			(end 1.524 0.762)
			(stroke
				(width 0.1524)
				(type default)
			)
			(layer "B.SilkS")
		)
		(fp_line
			(start 1.524 -0.762)
			(end -1.524 -0.762)
			(stroke
				(width 0.1524)
				(type default)
			)
			(layer "B.SilkS")
		)
		(fp_line
			(start 1.524 0.762)
			(end 1.524 -0.762)
			(stroke
				(width 0.1524)
				(type default)
			)
			(layer "B.SilkS")
		)
		(fp_line
			(start -1.1049 -0.724916)
			(end 1.1049 -0.724916)
			(stroke
				(width 0.1)
				(type default)
			)
			(layer "B.Fab")
		)
		(fp_line
			(start -1.1049 0.724916)
			(end -1.1049 -0.724916)
			(stroke
				(width 0.1)
				(type default)
			)
			(layer "B.Fab")
		)
		(fp_line
			(start 1.1049 -0.724916)
			(end 1.1049 0.724916)
			(stroke
				(width 0.1)
				(type default)
			)
			(layer "B.Fab")
		)
		(fp_line
			(start 1.1049 0.724916)
			(end -1.1049 0.724916)
			(stroke
				(width 0.1)
				(type default)
			)
			(layer "B.Fab")
		)
		(pad "1" smd rect
			(at 0.889 0)
			(size 1.016 1.27)
			(layers "B.Cu" "B.Mask" "B.Paste")
			(net "P1V2_CPU0_USB2_DVDD12")
		)
		(pad "2" smd rect
			(at -0.889 0)
			(size 1.016 1.27)
			(layers "B.Cu" "B.Mask" "B.Paste")
			(net "GND")
		)
	)
	(footprint ""
		(layer "B.Cu")
		(at 138.341354 -164.957252 90)
		(property "Reference" "PR339"
			(at 0 0 90)
			(layer "B.SilkS")
			(hide yes)
			(effects
				(font
					(size 1.27 1.27)
				)
				(justify mirror)
			)
		)
		(property "Value" ""
			(at 0 0 90)
			(layer "B.Fab")
			(effects
				(font
					(size 1.27 1.27)
				)
				(justify mirror)
			)
		)
		(duplicate_pad_numbers_are_jumpers no)
		(fp_line
			(start 0.7874 -0.4064)
			(end -0.7874 -0.4064)
			(stroke
				(width 0.1524)
				(type default)
			)
			(layer "B.SilkS")
		)
		(fp_line
			(start -0.7874 -0.4064)
			(end -0.7874 0.4064)
			(stroke
				(width 0.1524)
				(type default)
			)
			(layer "B.SilkS")
		)
		(fp_line
			(start 0.7874 0.4064)
			(end 0.7874 -0.4064)
			(stroke
				(width 0.1524)
				(type default)
			)
			(layer "B.SilkS")
		)
		(fp_line
			(start -0.7874 0.4064)
			(end 0.7874 0.4064)
			(stroke
				(width 0.1524)
				(type default)
			)
			(layer "B.SilkS")
		)
		(fp_line
			(start 0.67945 -0.305054)
			(end 0.12065 -0.305054)
			(stroke
				(width 0.1)
				(type default)
			)
			(layer "B.Fab")
		)
		(fp_line
			(start 0.12065 -0.305054)
			(end 0.12065 -0.2794)
			(stroke
				(width 0.1)
				(type default)
			)
			(layer "B.Fab")
		)
		(fp_line
			(start -0.12065 -0.3048)
			(end -0.67945 -0.3048)
			(stroke
				(width 0.1)
				(type default)
			)
			(layer "B.Fab")
		)
		(fp_line
			(start -0.67945 -0.3048)
			(end -0.67945 0.3048)
			(stroke
				(width 0.1)
				(type default)
			)
			(layer "B.Fab")
		)
		(fp_line
			(start 0.12065 -0.2794)
			(end -0.12065 -0.2794)
			(stroke
				(width 0.1)
				(type default)
			)
			(layer "B.Fab")
		)
		(fp_line
			(start -0.12065 -0.2794)
			(end -0.12065 -0.3048)
			(stroke
				(width 0.1)
				(type default)
			)
			(layer "B.Fab")
		)
		(fp_line
			(start 0.12065 0.2794)
			(end 0.12065 0.3048)
			(stroke
				(width 0.1)
				(type default)
			)
			(layer "B.Fab")
		)
		(fp_line
			(start -0.120396 0.2794)
			(end 0.12065 0.2794)
			(stroke
				(width 0.1)
				(type default)
			)
			(layer "B.Fab")
		)
		(fp_line
			(start 0.67945 0.3048)
			(end 0.67945 -0.305054)
			(stroke
				(width 0.1)
				(type default)
			)
			(layer "B.Fab")
		)
		(fp_line
			(start 0.12065 0.3048)
			(end 0.67945 0.3048)
			(stroke
				(width 0.1)
				(type default)
			)
			(layer "B.Fab")
		)
		(fp_line
			(start -0.120396 0.3048)
			(end -0.120396 0.2794)
			(stroke
				(width 0.1)
				(type default)
			)
			(layer "B.Fab")
		)
		(fp_line
			(start -0.67945 0.3048)
			(end -0.120396 0.3048)
			(stroke
				(width 0.1)
				(type default)
			)
			(layer "B.Fab")
		)
		(pad "1" smd circle
			(at 0.40005 0 270)
			(size 0 0)
			(layers "B.Cu" "B.Mask" "B.Paste")
			(net "PVDDCR_SOC_P1")
		)
		(pad "2" smd circle
			(at -0.40005 0 270)
			(size 0 0)
			(layers "B.Cu" "B.Mask" "B.Paste")
			(net "GND")
		)
	)
	(footprint ""
		(layer "B.Cu")
		(at 434.39842 -438.1119 90)
		(property "Reference" "R4166"
			(at 0 0 90)
			(layer "B.SilkS")
			(hide yes)
			(effects
				(font
					(size 1.27 1.27)
				)
				(justify mirror)
			)
		)
		(property "Value" ""
			(at 0 0 90)
			(layer "B.Fab")
			(effects
				(font
					(size 1.27 1.27)
				)
				(justify mirror)
			)
		)
		(duplicate_pad_numbers_are_jumpers no)
		(fp_line
			(start 0.7874 -0.4064)
			(end -0.7874 -0.4064)
			(stroke
				(width 0.1524)
				(type default)
			)
			(layer "B.SilkS")
		)
		(fp_line
			(start -0.7874 -0.4064)
			(end -0.7874 0.4064)
			(stroke
				(width 0.1524)
				(type default)
			)
			(layer "B.SilkS")
		)
		(fp_line
			(start 0.7874 0.4064)
			(end 0.7874 -0.4064)
			(stroke
				(width 0.1524)
				(type default)
			)
			(layer "B.SilkS")
		)
		(fp_line
			(start -0.7874 0.4064)
			(end 0.7874 0.4064)
			(stroke
				(width 0.1524)
				(type default)
			)
			(layer "B.SilkS")
		)
		(fp_line
			(start 0.67945 -0.305054)
			(end 0.12065 -0.305054)
			(stroke
				(width 0.1)
				(type default)
			)
			(layer "B.Fab")
		)
		(fp_line
			(start 0.12065 -0.305054)
			(end 0.12065 -0.2794)
			(stroke
				(width 0.1)
				(type default)
			)
			(layer "B.Fab")
		)
		(fp_line
			(start -0.12065 -0.3048)
			(end -0.67945 -0.3048)
			(stroke
				(width 0.1)
				(type default)
			)
			(layer "B.Fab")
		)
		(fp_line
			(start -0.67945 -0.3048)
			(end -0.67945 0.3048)
			(stroke
				(width 0.1)
				(type default)
			)
			(layer "B.Fab")
		)
		(fp_line
			(start 0.12065 -0.2794)
			(end -0.12065 -0.2794)
			(stroke
				(width 0.1)
				(type default)
			)
			(layer "B.Fab")
		)
		(fp_line
			(start -0.12065 -0.2794)
			(end -0.12065 -0.3048)
			(stroke
				(width 0.1)
				(type default)
			)
			(layer "B.Fab")
		)
		(fp_line
			(start 0.12065 0.2794)
			(end 0.12065 0.3048)
			(stroke
				(width 0.1)
				(type default)
			)
			(layer "B.Fab")
		)
		(fp_line
			(start -0.120396 0.2794)
			(end 0.12065 0.2794)
			(stroke
				(width 0.1)
				(type default)
			)
			(layer "B.Fab")
		)
		(fp_line
			(start 0.67945 0.3048)
			(end 0.67945 -0.305054)
			(stroke
				(width 0.1)
				(type default)
			)
			(layer "B.Fab")
		)
		(fp_line
			(start 0.12065 0.3048)
			(end 0.67945 0.3048)
			(stroke
				(width 0.1)
				(type default)
			)
			(layer "B.Fab")
		)
		(fp_line
			(start -0.120396 0.3048)
			(end -0.120396 0.2794)
			(stroke
				(width 0.1)
				(type default)
			)
			(layer "B.Fab")
		)
		(fp_line
			(start -0.67945 0.3048)
			(end -0.120396 0.3048)
			(stroke
				(width 0.1)
				(type default)
			)
			(layer "B.Fab")
		)
		(pad "1" smd circle
			(at 0.40005 0 270)
			(size 0 0)
			(layers "B.Cu" "B.Mask" "B.Paste")
			(net "P3V3_AUX")
		)
		(pad "2" smd circle
			(at -0.40005 0 270)
			(size 0 0)
			(layers "B.Cu" "B.Mask" "B.Paste")
			(net "GPU_3V3IO_RSVD3_N")
		)
	)
	(footprint ""
		(layer "B.Cu")
		(at 131.59105 -213.203028 90)
		(property "Reference" "R529"
			(at 0 0 90)
			(layer "B.SilkS")
			(hide yes)
			(effects
				(font
					(size 1.27 1.27)
				)
				(justify mirror)
			)
		)
		(property "Value" ""
			(at 0 0 90)
			(layer "B.Fab")
			(effects
				(font
					(size 1.27 1.27)
				)
				(justify mirror)
			)
		)
		(duplicate_pad_numbers_are_jumpers no)
		(fp_line
			(start 0.7874 -0.4064)
			(end -0.7874 -0.4064)
			(stroke
				(width 0.1524)
				(type default)
			)
			(layer "B.SilkS")
		)
		(fp_line
			(start -0.7874 -0.4064)
			(end -0.7874 0.4064)
			(stroke
				(width 0.1524)
				(type default)
			)
			(layer "B.SilkS")
		)
		(fp_line
			(start 0.7874 0.4064)
			(end 0.7874 -0.4064)
			(stroke
				(width 0.1524)
				(type default)
			)
			(layer "B.SilkS")
		)
		(fp_line
			(start -0.7874 0.4064)
			(end 0.7874 0.4064)
			(stroke
				(width 0.1524)
				(type default)
			)
			(layer "B.SilkS")
		)
		(fp_line
			(start 0.67945 -0.305054)
			(end 0.12065 -0.305054)
			(stroke
				(width 0.1)
				(type default)
			)
			(layer "B.Fab")
		)
		(fp_line
			(start 0.12065 -0.305054)
			(end 0.12065 -0.2794)
			(stroke
				(width 0.1)
				(type default)
			)
			(layer "B.Fab")
		)
		(fp_line
			(start -0.12065 -0.3048)
			(end -0.67945 -0.3048)
			(stroke
				(width 0.1)
				(type default)
			)
			(layer "B.Fab")
		)
		(fp_line
			(start -0.67945 -0.3048)
			(end -0.67945 0.3048)
			(stroke
				(width 0.1)
				(type default)
			)
			(layer "B.Fab")
		)
		(fp_line
			(start 0.12065 -0.2794)
			(end -0.12065 -0.2794)
			(stroke
				(width 0.1)
				(type default)
			)
			(layer "B.Fab")
		)
		(fp_line
			(start -0.12065 -0.2794)
			(end -0.12065 -0.3048)
			(stroke
				(width 0.1)
				(type default)
			)
			(layer "B.Fab")
		)
		(fp_line
			(start 0.12065 0.2794)
			(end 0.12065 0.3048)
			(stroke
				(width 0.1)
				(type default)
			)
			(layer "B.Fab")
		)
		(fp_line
			(start -0.120396 0.2794)
			(end 0.12065 0.2794)
			(stroke
				(width 0.1)
				(type default)
			)
			(layer "B.Fab")
		)
		(fp_line
			(start 0.67945 0.3048)
			(end 0.67945 -0.305054)
			(stroke
				(width 0.1)
				(type default)
			)
			(layer "B.Fab")
		)
		(fp_line
			(start 0.12065 0.3048)
			(end 0.67945 0.3048)
			(stroke
				(width 0.1)
				(type default)
			)
			(layer "B.Fab")
		)
		(fp_line
			(start -0.120396 0.3048)
			(end -0.120396 0.2794)
			(stroke
				(width 0.1)
				(type default)
			)
			(layer "B.Fab")
		)
		(fp_line
			(start -0.67945 0.3048)
			(end -0.120396 0.3048)
			(stroke
				(width 0.1)
				(type default)
			)
			(layer "B.Fab")
		)
		(pad "1" smd circle
			(at 0.40005 0 270)
			(size 0 0)
			(layers "B.Cu" "B.Mask" "B.Paste")
			(net "JTAG_CPU1_R_TDO")
		)
		(pad "2" smd circle
			(at -0.40005 0 270)
			(size 0 0)
			(layers "B.Cu" "B.Mask" "B.Paste")
			(net "JTAG_CPU1_TDO")
		)
	)
	(footprint ""
		(layer "B.Cu")
		(at 43.265852 -382.68656 180)
		(property "Reference" "R6722"
			(at 0 0 0)
			(layer "B.SilkS")
			(hide yes)
			(effects
				(font
					(size 1.27 1.27)
				)
				(justify mirror)
			)
		)
		(property "Value" ""
			(at 0 0 0)
			(layer "B.Fab")
			(effects
				(font
					(size 1.27 1.27)
				)
				(justify mirror)
			)
		)
		(duplicate_pad_numbers_are_jumpers no)
		(fp_line
			(start 0.32512 0.175006)
			(end 0.32512 -0.175006)
			(stroke
				(width 0.1)
				(type default)
			)
			(layer "B.Fab")
		)
		(fp_line
			(start 0.32512 -0.175006)
			(end -0.32512 -0.175006)
			(stroke
				(width 0.1)
				(type default)
			)
			(layer "B.Fab")
		)
		(fp_line
			(start -0.32512 0.175006)
			(end 0.32512 0.175006)
			(stroke
				(width 0.1)
				(type default)
			)
			(layer "B.Fab")
		)
		(fp_line
			(start -0.32512 -0.175006)
			(end -0.32512 0.175006)
			(stroke
				(width 0.1)
				(type default)
			)
			(layer "B.Fab")
		)
		(pad "1" smd rect
			(at 0.2667 0)
			(size 0.3048 0.381)
			(layers "B.Cu" "B.Mask" "B.Paste")
			(net "P1V8_CPU1_RT_1D")
		)
		(pad "2" smd rect
			(at -0.2667 0 180)
			(size 0.3048 0.381)
			(layers "B.Cu" "B.Mask" "B.Paste")
			(net "RT_CPU1_P0_SCAN_MODE")
		)
	)
	(footprint ""
		(layer "B.Cu")
		(at 157.989778 -17.969992 -90)
		(property "Reference" "R3114"
			(at 0 0 90)
			(layer "B.SilkS")
			(hide yes)
			(effects
				(font
					(size 1.27 1.27)
				)
				(justify mirror)
			)
		)
		(property "Value" ""
			(at 0 0 90)
			(layer "B.Fab")
			(effects
				(font
					(size 1.27 1.27)
				)
				(justify mirror)
			)
		)
		(duplicate_pad_numbers_are_jumpers no)
		(fp_line
			(start -0.7874 0.4064)
			(end 0.7874 0.4064)
			(stroke
				(width 0.1524)
				(type default)
			)
			(layer "B.SilkS")
		)
		(fp_line
			(start 0.7874 0.4064)
			(end 0.7874 -0.4064)
			(stroke
				(width 0.1524)
				(type default)
			)
			(layer "B.SilkS")
		)
		(fp_line
			(start -0.7874 -0.4064)
			(end -0.7874 0.4064)
			(stroke
				(width 0.1524)
				(type default)
			)
			(layer "B.SilkS")
		)
		(fp_line
			(start 0.7874 -0.4064)
			(end -0.7874 -0.4064)
			(stroke
				(width 0.1524)
				(type default)
			)
			(layer "B.SilkS")
		)
		(fp_line
			(start -0.67945 0.3048)
			(end -0.120396 0.3048)
			(stroke
				(width 0.1)
				(type default)
			)
			(layer "B.Fab")
		)
		(fp_line
			(start -0.120396 0.3048)
			(end -0.120396 0.2794)
			(stroke
				(width 0.1)
				(type default)
			)
			(layer "B.Fab")
		)
		(fp_line
			(start 0.12065 0.3048)
			(end 0.67945 0.3048)
			(stroke
				(width 0.1)
				(type default)
			)
			(layer "B.Fab")
		)
		(fp_line
			(start 0.67945 0.3048)
			(end 0.67945 -0.305054)
			(stroke
				(width 0.1)
				(type default)
			)
			(layer "B.Fab")
		)
		(fp_line
			(start -0.120396 0.2794)
			(end 0.12065 0.2794)
			(stroke
				(width 0.1)
				(type default)
			)
			(layer "B.Fab")
		)
		(fp_line
			(start 0.12065 0.2794)
			(end 0.12065 0.3048)
			(stroke
				(width 0.1)
				(type default)
			)
			(layer "B.Fab")
		)
		(fp_line
			(start -0.12065 -0.2794)
			(end -0.12065 -0.3048)
			(stroke
				(width 0.1)
				(type default)
			)
			(layer "B.Fab")
		)
		(fp_line
			(start 0.12065 -0.2794)
			(end -0.12065 -0.2794)
			(stroke
				(width 0.1)
				(type default)
			)
			(layer "B.Fab")
		)
		(fp_line
			(start -0.67945 -0.3048)
			(end -0.67945 0.3048)
			(stroke
				(width 0.1)
				(type default)
			)
			(layer "B.Fab")
		)
		(fp_line
			(start -0.12065 -0.3048)
			(end -0.67945 -0.3048)
			(stroke
				(width 0.1)
				(type default)
			)
			(layer "B.Fab")
		)
		(fp_line
			(start 0.12065 -0.305054)
			(end 0.12065 -0.2794)
			(stroke
				(width 0.1)
				(type default)
			)
			(layer "B.Fab")
		)
		(fp_line
			(start 0.67945 -0.305054)
			(end 0.12065 -0.305054)
			(stroke
				(width 0.1)
				(type default)
			)
			(layer "B.Fab")
		)
		(pad "1" smd circle
			(at 0.40005 0 90)
			(size 0 0)
			(layers "B.Cu" "B.Mask" "B.Paste")
			(net "SMB_FAN_3V3AUX_SDA")
		)
		(pad "2" smd circle
			(at -0.40005 0 90)
			(size 0 0)
			(layers "B.Cu" "B.Mask" "B.Paste")
			(net "SMB_FAN_3V3AUX_R_SDA")
		)
	)
	(footprint ""
		(layer "B.Cu")
		(at 127.691134 -390.560052 90)
		(property "Reference" "C483"
			(at 0 0 90)
			(layer "B.SilkS")
			(hide yes)
			(effects
				(font
					(size 1.27 1.27)
				)
				(justify mirror)
			)
		)
		(property "Value" ""
			(at 0 0 90)
			(layer "B.Fab")
			(effects
				(font
					(size 1.27 1.27)
				)
				(justify mirror)
			)
		)
		(duplicate_pad_numbers_are_jumpers no)
		(fp_line
			(start 0.7874 -0.4064)
			(end -0.7874 -0.4064)
			(stroke
				(width 0.1524)
				(type default)
			)
			(layer "B.SilkS")
		)
		(fp_line
			(start -0.7874 -0.4064)
			(end -0.7874 0.4064)
			(stroke
				(width 0.1524)
				(type default)
			)
			(layer "B.SilkS")
		)
		(fp_line
			(start 0.7874 0.4064)
			(end 0.7874 -0.4064)
			(stroke
				(width 0.1524)
				(type default)
			)
			(layer "B.SilkS")
		)
		(fp_line
			(start -0.7874 0.4064)
			(end 0.7874 0.4064)
			(stroke
				(width 0.1524)
				(type default)
			)
			(layer "B.SilkS")
		)
		(fp_line
			(start 0.67945 -0.305054)
			(end 0.12065 -0.305054)
			(stroke
				(width 0.1)
				(type default)
			)
			(layer "B.Fab")
		)
		(fp_line
			(start 0.12065 -0.305054)
			(end 0.12065 -0.2794)
			(stroke
				(width 0.1)
				(type default)
			)
			(layer "B.Fab")
		)
		(fp_line
			(start -0.12065 -0.3048)
			(end -0.67945 -0.3048)
			(stroke
				(width 0.1)
				(type default)
			)
			(layer "B.Fab")
		)
		(fp_line
			(start -0.67945 -0.3048)
			(end -0.67945 0.3048)
			(stroke
				(width 0.1)
				(type default)
			)
			(layer "B.Fab")
		)
		(fp_line
			(start 0.12065 -0.2794)
			(end -0.12065 -0.2794)
			(stroke
				(width 0.1)
				(type default)
			)
			(layer "B.Fab")
		)
		(fp_line
			(start -0.12065 -0.2794)
			(end -0.12065 -0.3048)
			(stroke
				(width 0.1)
				(type default)
			)
			(layer "B.Fab")
		)
		(fp_line
			(start 0.12065 0.2794)
			(end 0.12065 0.3048)
			(stroke
				(width 0.1)
				(type default)
			)
			(layer "B.Fab")
		)
		(fp_line
			(start -0.120396 0.2794)
			(end 0.12065 0.2794)
			(stroke
				(width 0.1)
				(type default)
			)
			(layer "B.Fab")
		)
		(fp_line
			(start 0.67945 0.3048)
			(end 0.67945 -0.305054)
			(stroke
				(width 0.1)
				(type default)
			)
			(layer "B.Fab")
		)
		(fp_line
			(start 0.12065 0.3048)
			(end 0.67945 0.3048)
			(stroke
				(width 0.1)
				(type default)
			)
			(layer "B.Fab")
		)
		(fp_line
			(start -0.120396 0.3048)
			(end -0.120396 0.2794)
			(stroke
				(width 0.1)
				(type default)
			)
			(layer "B.Fab")
		)
		(fp_line
			(start -0.67945 0.3048)
			(end -0.120396 0.3048)
			(stroke
				(width 0.1)
				(type default)
			)
			(layer "B.Fab")
		)
		(pad "1" smd circle
			(at 0.40005 0 270)
			(size 0 0)
			(layers "B.Cu" "B.Mask" "B.Paste")
			(net "P0V9_CPU1_RT3_2A")
		)
		(pad "2" smd circle
			(at -0.40005 0 270)
			(size 0 0)
			(layers "B.Cu" "B.Mask" "B.Paste")
			(net "GND")
		)
	)
	(footprint ""
		(layer "B.Cu")
		(at 156.151834 -320.798952)
		(property "Reference" "R513"
			(at 0 0 0)
			(layer "B.SilkS")
			(hide yes)
			(effects
				(font
					(size 1.27 1.27)
				)
				(justify mirror)
			)
		)
		(property "Value" ""
			(at 0 0 0)
			(layer "B.Fab")
			(effects
				(font
					(size 1.27 1.27)
				)
				(justify mirror)
			)
		)
		(duplicate_pad_numbers_are_jumpers no)
		(fp_line
			(start -0.7874 -0.4064)
			(end -0.7874 0.4064)
			(stroke
				(width 0.1524)
				(type default)
			)
			(layer "B.SilkS")
		)
		(fp_line
			(start -0.7874 0.4064)
			(end 0.7874 0.4064)
			(stroke
				(width 0.1524)
				(type default)
			)
			(layer "B.SilkS")
		)
		(fp_line
			(start 0.7874 -0.4064)
			(end -0.7874 -0.4064)
			(stroke
				(width 0.1524)
				(type default)
			)
			(layer "B.SilkS")
		)
		(fp_line
			(start 0.7874 0.4064)
			(end 0.7874 -0.4064)
			(stroke
				(width 0.1524)
				(type default)
			)
			(layer "B.SilkS")
		)
		(fp_line
			(start -0.67945 -0.3048)
			(end -0.67945 0.3048)
			(stroke
				(width 0.1)
				(type default)
			)
			(layer "B.Fab")
		)
		(fp_line
			(start -0.67945 0.3048)
			(end -0.120396 0.3048)
			(stroke
				(width 0.1)
				(type default)
			)
			(layer "B.Fab")
		)
		(fp_line
			(start -0.12065 -0.3048)
			(end -0.67945 -0.3048)
			(stroke
				(width 0.1)
				(type default)
			)
			(layer "B.Fab")
		)
		(fp_line
			(start -0.12065 -0.2794)
			(end -0.12065 -0.3048)
			(stroke
				(width 0.1)
				(type default)
			)
			(layer "B.Fab")
		)
		(fp_line
			(start -0.120396 0.2794)
			(end 0.12065 0.2794)
			(stroke
				(width 0.1)
				(type default)
			)
			(layer "B.Fab")
		)
		(fp_line
			(start -0.120396 0.3048)
			(end -0.120396 0.2794)
			(stroke
				(width 0.1)
				(type default)
			)
			(layer "B.Fab")
		)
		(fp_line
			(start 0.12065 -0.305054)
			(end 0.12065 -0.2794)
			(stroke
				(width 0.1)
				(type default)
			)
			(layer "B.Fab")
		)
		(fp_line
			(start 0.12065 -0.2794)
			(end -0.12065 -0.2794)
			(stroke
				(width 0.1)
				(type default)
			)
			(layer "B.Fab")
		)
		(fp_line
			(start 0.12065 0.2794)
			(end 0.12065 0.3048)
			(stroke
				(width 0.1)
				(type default)
			)
			(layer "B.Fab")
		)
		(fp_line
			(start 0.12065 0.3048)
			(end 0.67945 0.3048)
			(stroke
				(width 0.1)
				(type default)
			)
			(layer "B.Fab")
		)
		(fp_line
			(start 0.67945 -0.305054)
			(end 0.12065 -0.305054)
			(stroke
				(width 0.1)
				(type default)
			)
			(layer "B.Fab")
		)
		(fp_line
			(start 0.67945 0.3048)
			(end 0.67945 -0.305054)
			(stroke
				(width 0.1)
				(type default)
			)
			(layer "B.Fab")
		)
		(pad "1" smd circle
			(at 0.40005 0 180)
			(size 0 0)
			(layers "B.Cu" "B.Mask" "B.Paste")
			(net "P3V3_AUX")
		)
		(pad "2" smd circle
			(at -0.40005 0 180)
			(size 0 0)
			(layers "B.Cu" "B.Mask" "B.Paste")
			(net "CPU1_SP5R4")
		)
	)
	(footprint ""
		(layer "B.Cu")
		(at 428.087282 -436.414672 90)
		(property "Reference" "R4163"
			(at 0 0 90)
			(layer "B.SilkS")
			(hide yes)
			(effects
				(font
					(size 1.27 1.27)
				)
				(justify mirror)
			)
		)
		(property "Value" ""
			(at 0 0 90)
			(layer "B.Fab")
			(effects
				(font
					(size 1.27 1.27)
				)
				(justify mirror)
			)
		)
		(duplicate_pad_numbers_are_jumpers no)
		(fp_line
			(start 0.7874 -0.4064)
			(end -0.7874 -0.4064)
			(stroke
				(width 0.1524)
				(type default)
			)
			(layer "B.SilkS")
		)
		(fp_line
			(start -0.7874 -0.4064)
			(end -0.7874 0.4064)
			(stroke
				(width 0.1524)
				(type default)
			)
			(layer "B.SilkS")
		)
		(fp_line
			(start 0.7874 0.4064)
			(end 0.7874 -0.4064)
			(stroke
				(width 0.1524)
				(type default)
			)
			(layer "B.SilkS")
		)
		(fp_line
			(start -0.7874 0.4064)
			(end 0.7874 0.4064)
			(stroke
				(width 0.1524)
				(type default)
			)
			(layer "B.SilkS")
		)
		(fp_line
			(start 0.67945 -0.305054)
			(end 0.12065 -0.305054)
			(stroke
				(width 0.1)
				(type default)
			)
			(layer "B.Fab")
		)
		(fp_line
			(start 0.12065 -0.305054)
			(end 0.12065 -0.2794)
			(stroke
				(width 0.1)
				(type default)
			)
			(layer "B.Fab")
		)
		(fp_line
			(start -0.12065 -0.3048)
			(end -0.67945 -0.3048)
			(stroke
				(width 0.1)
				(type default)
			)
			(layer "B.Fab")
		)
		(fp_line
			(start -0.67945 -0.3048)
			(end -0.67945 0.3048)
			(stroke
				(width 0.1)
				(type default)
			)
			(layer "B.Fab")
		)
		(fp_line
			(start 0.12065 -0.2794)
			(end -0.12065 -0.2794)
			(stroke
				(width 0.1)
				(type default)
			)
			(layer "B.Fab")
		)
		(fp_line
			(start -0.12065 -0.2794)
			(end -0.12065 -0.3048)
			(stroke
				(width 0.1)
				(type default)
			)
			(layer "B.Fab")
		)
		(fp_line
			(start 0.12065 0.2794)
			(end 0.12065 0.3048)
			(stroke
				(width 0.1)
				(type default)
			)
			(layer "B.Fab")
		)
		(fp_line
			(start -0.120396 0.2794)
			(end 0.12065 0.2794)
			(stroke
				(width 0.1)
				(type default)
			)
			(layer "B.Fab")
		)
		(fp_line
			(start 0.67945 0.3048)
			(end 0.67945 -0.305054)
			(stroke
				(width 0.1)
				(type default)
			)
			(layer "B.Fab")
		)
		(fp_line
			(start 0.12065 0.3048)
			(end 0.67945 0.3048)
			(stroke
				(width 0.1)
				(type default)
			)
			(layer "B.Fab")
		)
		(fp_line
			(start -0.120396 0.3048)
			(end -0.120396 0.2794)
			(stroke
				(width 0.1)
				(type default)
			)
			(layer "B.Fab")
		)
		(fp_line
			(start -0.67945 0.3048)
			(end -0.120396 0.3048)
			(stroke
				(width 0.1)
				(type default)
			)
			(layer "B.Fab")
		)
		(pad "1" smd circle
			(at 0.40005 0 270)
			(size 0 0)
			(layers "B.Cu" "B.Mask" "B.Paste")
			(net "GPU_3V3IO_RSVD3")
		)
		(pad "2" smd circle
			(at -0.40005 0 270)
			(size 0 0)
			(layers "B.Cu" "B.Mask" "B.Paste")
			(net "GND")
		)
	)
	(footprint ""
		(layer "B.Cu")
		(at 201.12355 -116.971572 180)
		(property "Reference" "R3"
			(at 0 0 0)
			(layer "B.SilkS")
			(hide yes)
			(effects
				(font
					(size 1.27 1.27)
				)
				(justify mirror)
			)
		)
		(property "Value" ""
			(at 0 0 0)
			(layer "B.Fab")
			(effects
				(font
					(size 1.27 1.27)
				)
				(justify mirror)
			)
		)
		(duplicate_pad_numbers_are_jumpers no)
		(fp_line
			(start 0.7874 0.4064)
			(end 0.7874 -0.4064)
			(stroke
				(width 0.1524)
				(type default)
			)
			(layer "B.SilkS")
		)
		(fp_line
			(start 0.7874 -0.4064)
			(end -0.7874 -0.4064)
			(stroke
				(width 0.1524)
				(type default)
			)
			(layer "B.SilkS")
		)
		(fp_line
			(start -0.7874 0.4064)
			(end 0.7874 0.4064)
			(stroke
				(width 0.1524)
				(type default)
			)
			(layer "B.SilkS")
		)
		(fp_line
			(start -0.7874 -0.4064)
			(end -0.7874 0.4064)
			(stroke
				(width 0.1524)
				(type default)
			)
			(layer "B.SilkS")
		)
		(fp_line
			(start 0.67945 0.3048)
			(end 0.67945 -0.305054)
			(stroke
				(width 0.1)
				(type default)
			)
			(layer "B.Fab")
		)
		(fp_line
			(start 0.67945 -0.305054)
			(end 0.12065 -0.305054)
			(stroke
				(width 0.1)
				(type default)
			)
			(layer "B.Fab")
		)
		(fp_line
			(start 0.12065 0.3048)
			(end 0.67945 0.3048)
			(stroke
				(width 0.1)
				(type default)
			)
			(layer "B.Fab")
		)
		(fp_line
			(start 0.12065 0.2794)
			(end 0.12065 0.3048)
			(stroke
				(width 0.1)
				(type default)
			)
			(layer "B.Fab")
		)
		(fp_line
			(start 0.12065 -0.2794)
			(end -0.12065 -0.2794)
			(stroke
				(width 0.1)
				(type default)
			)
			(layer "B.Fab")
		)
		(fp_line
			(start 0.12065 -0.305054)
			(end 0.12065 -0.2794)
			(stroke
				(width 0.1)
				(type default)
			)
			(layer "B.Fab")
		)
		(fp_line
			(start -0.120396 0.3048)
			(end -0.120396 0.2794)
			(stroke
				(width 0.1)
				(type default)
			)
			(layer "B.Fab")
		)
		(fp_line
			(start -0.120396 0.2794)
			(end 0.12065 0.2794)
			(stroke
				(width 0.1)
				(type default)
			)
			(layer "B.Fab")
		)
		(fp_line
			(start -0.12065 -0.2794)
			(end -0.12065 -0.3048)
			(stroke
				(width 0.1)
				(type default)
			)
			(layer "B.Fab")
		)
		(fp_line
			(start -0.12065 -0.3048)
			(end -0.67945 -0.3048)
			(stroke
				(width 0.1)
				(type default)
			)
			(layer "B.Fab")
		)
		(fp_line
			(start -0.67945 0.3048)
			(end -0.120396 0.3048)
			(stroke
				(width 0.1)
				(type default)
			)
			(layer "B.Fab")
		)
		(fp_line
			(start -0.67945 -0.3048)
			(end -0.67945 0.3048)
			(stroke
				(width 0.1)
				(type default)
			)
			(layer "B.Fab")
		)
		(pad "1" smd circle
			(at 0.40005 0)
			(size 0 0)
			(layers "B.Cu" "B.Mask" "B.Paste")
			(net "RST_PERST_CPU1_SWB_1_N")
		)
		(pad "2" smd circle
			(at -0.40005 0)
			(size 0 0)
			(layers "B.Cu" "B.Mask" "B.Paste")
			(net "GND")
		)
	)
	(footprint ""
		(layer "B.Cu")
		(at 16.208502 -98.669348)
		(property "Reference" "C2032"
			(at 0 0 0)
			(layer "B.SilkS")
			(hide yes)
			(effects
				(font
					(size 1.27 1.27)
				)
				(justify mirror)
			)
		)
		(property "Value" ""
			(at 0 0 0)
			(layer "B.Fab")
			(effects
				(font
					(size 1.27 1.27)
				)
				(justify mirror)
			)
		)
		(duplicate_pad_numbers_are_jumpers no)
		(fp_line
			(start -0.7874 -0.4064)
			(end -0.7874 0.4064)
			(stroke
				(width 0.1524)
				(type default)
			)
			(layer "B.SilkS")
		)
		(fp_line
			(start -0.7874 0.4064)
			(end 0.7874 0.4064)
			(stroke
				(width 0.1524)
				(type default)
			)
			(layer "B.SilkS")
		)
		(fp_line
			(start 0.7874 -0.4064)
			(end -0.7874 -0.4064)
			(stroke
				(width 0.1524)
				(type default)
			)
			(layer "B.SilkS")
		)
		(fp_line
			(start 0.7874 0.4064)
			(end 0.7874 -0.4064)
			(stroke
				(width 0.1524)
				(type default)
			)
			(layer "B.SilkS")
		)
		(fp_line
			(start -0.67945 -0.3048)
			(end -0.67945 0.3048)
			(stroke
				(width 0.1)
				(type default)
			)
			(layer "B.Fab")
		)
		(fp_line
			(start -0.67945 0.3048)
			(end -0.120396 0.3048)
			(stroke
				(width 0.1)
				(type default)
			)
			(layer "B.Fab")
		)
		(fp_line
			(start -0.12065 -0.3048)
			(end -0.67945 -0.3048)
			(stroke
				(width 0.1)
				(type default)
			)
			(layer "B.Fab")
		)
		(fp_line
			(start -0.12065 -0.2794)
			(end -0.12065 -0.3048)
			(stroke
				(width 0.1)
				(type default)
			)
			(layer "B.Fab")
		)
		(fp_line
			(start -0.120396 0.2794)
			(end 0.12065 0.2794)
			(stroke
				(width 0.1)
				(type default)
			)
			(layer "B.Fab")
		)
		(fp_line
			(start -0.120396 0.3048)
			(end -0.120396 0.2794)
			(stroke
				(width 0.1)
				(type default)
			)
			(layer "B.Fab")
		)
		(fp_line
			(start 0.12065 -0.305054)
			(end 0.12065 -0.2794)
			(stroke
				(width 0.1)
				(type default)
			)
			(layer "B.Fab")
		)
		(fp_line
			(start 0.12065 -0.2794)
			(end -0.12065 -0.2794)
			(stroke
				(width 0.1)
				(type default)
			)
			(layer "B.Fab")
		)
		(fp_line
			(start 0.12065 0.2794)
			(end 0.12065 0.3048)
			(stroke
				(width 0.1)
				(type default)
			)
			(layer "B.Fab")
		)
		(fp_line
			(start 0.12065 0.3048)
			(end 0.67945 0.3048)
			(stroke
				(width 0.1)
				(type default)
			)
			(layer "B.Fab")
		)
		(fp_line
			(start 0.67945 -0.305054)
			(end 0.12065 -0.305054)
			(stroke
				(width 0.1)
				(type default)
			)
			(layer "B.Fab")
		)
		(fp_line
			(start 0.67945 0.3048)
			(end 0.67945 -0.305054)
			(stroke
				(width 0.1)
				(type default)
			)
			(layer "B.Fab")
		)
		(pad "1" smd circle
			(at 0.40005 0 180)
			(size 0 0)
			(layers "B.Cu" "B.Mask" "B.Paste")
			(net "P3V3_AUX_USB_HUB")
		)
		(pad "2" smd circle
			(at -0.40005 0 180)
			(size 0 0)
			(layers "B.Cu" "B.Mask" "B.Paste")
			(net "GND")
		)
	)
	(footprint ""
		(layer "B.Cu")
		(at 101.444044 -387.084062 -90)
		(property "Reference" "C103"
			(at 0 0 90)
			(layer "B.SilkS")
			(hide yes)
			(effects
				(font
					(size 1.27 1.27)
				)
				(justify mirror)
			)
		)
		(property "Value" ""
			(at 0 0 90)
			(layer "B.Fab")
			(effects
				(font
					(size 1.27 1.27)
				)
				(justify mirror)
			)
		)
		(duplicate_pad_numbers_are_jumpers no)
		(fp_line
			(start -1.524 0.762)
			(end 1.524 0.762)
			(stroke
				(width 0.1524)
				(type default)
			)
			(layer "B.SilkS")
		)
		(fp_line
			(start 1.524 0.762)
			(end 1.524 -0.762)
			(stroke
				(width 0.1524)
				(type default)
			)
			(layer "B.SilkS")
		)
		(fp_line
			(start -1.524 -0.762)
			(end -1.524 0.762)
			(stroke
				(width 0.1524)
				(type default)
			)
			(layer "B.SilkS")
		)
		(fp_line
			(start 1.524 -0.762)
			(end -1.524 -0.762)
			(stroke
				(width 0.1524)
				(type default)
			)
			(layer "B.SilkS")
		)
		(fp_line
			(start -1.1049 0.724916)
			(end -1.1049 -0.724916)
			(stroke
				(width 0.1)
				(type default)
			)
			(layer "B.Fab")
		)
		(fp_line
			(start 1.1049 0.724916)
			(end -1.1049 0.724916)
			(stroke
				(width 0.1)
				(type default)
			)
			(layer "B.Fab")
		)
		(fp_line
			(start -1.1049 -0.724916)
			(end 1.1049 -0.724916)
			(stroke
				(width 0.1)
				(type default)
			)
			(layer "B.Fab")
		)
		(fp_line
			(start 1.1049 -0.724916)
			(end 1.1049 0.724916)
			(stroke
				(width 0.1)
				(type default)
			)
			(layer "B.Fab")
		)
		(pad "1" smd rect
			(at 0.889 0 270)
			(size 1.016 1.27)
			(layers "B.Cu" "B.Mask" "B.Paste")
			(net "P1V8_CPU1_RT1_1A")
		)
		(pad "2" smd rect
			(at -0.889 0 270)
			(size 1.016 1.27)
			(layers "B.Cu" "B.Mask" "B.Paste")
			(net "GND")
		)
	)
	(footprint ""
		(layer "B.Cu")
		(at 208.461356 -377.666504)
		(property "Reference" "PR2510"
			(at 0 0 0)
			(layer "B.SilkS")
			(hide yes)
			(effects
				(font
					(size 1.27 1.27)
				)
				(justify mirror)
			)
		)
		(property "Value" ""
			(at 0 0 0)
			(layer "B.Fab")
			(effects
				(font
					(size 1.27 1.27)
				)
				(justify mirror)
			)
		)
		(duplicate_pad_numbers_are_jumpers no)
		(fp_line
			(start -0.7874 -0.4064)
			(end -0.7874 0.4064)
			(stroke
				(width 0.1524)
				(type default)
			)
			(layer "B.SilkS")
		)
		(fp_line
			(start -0.7874 0.4064)
			(end 0.7874 0.4064)
			(stroke
				(width 0.1524)
				(type default)
			)
			(layer "B.SilkS")
		)
		(fp_line
			(start 0.7874 -0.4064)
			(end -0.7874 -0.4064)
			(stroke
				(width 0.1524)
				(type default)
			)
			(layer "B.SilkS")
		)
		(fp_line
			(start 0.7874 0.4064)
			(end 0.7874 -0.4064)
			(stroke
				(width 0.1524)
				(type default)
			)
			(layer "B.SilkS")
		)
		(fp_line
			(start -0.67945 -0.3048)
			(end -0.67945 0.3048)
			(stroke
				(width 0.1)
				(type default)
			)
			(layer "B.Fab")
		)
		(fp_line
			(start -0.67945 0.3048)
			(end -0.120396 0.3048)
			(stroke
				(width 0.1)
				(type default)
			)
			(layer "B.Fab")
		)
		(fp_line
			(start -0.12065 -0.3048)
			(end -0.67945 -0.3048)
			(stroke
				(width 0.1)
				(type default)
			)
			(layer "B.Fab")
		)
		(fp_line
			(start -0.12065 -0.2794)
			(end -0.12065 -0.3048)
			(stroke
				(width 0.1)
				(type default)
			)
			(layer "B.Fab")
		)
		(fp_line
			(start -0.120396 0.2794)
			(end 0.12065 0.2794)
			(stroke
				(width 0.1)
				(type default)
			)
			(layer "B.Fab")
		)
		(fp_line
			(start -0.120396 0.3048)
			(end -0.120396 0.2794)
			(stroke
				(width 0.1)
				(type default)
			)
			(layer "B.Fab")
		)
		(fp_line
			(start 0.12065 -0.305054)
			(end 0.12065 -0.2794)
			(stroke
				(width 0.1)
				(type default)
			)
			(layer "B.Fab")
		)
		(fp_line
			(start 0.12065 -0.2794)
			(end -0.12065 -0.2794)
			(stroke
				(width 0.1)
				(type default)
			)
			(layer "B.Fab")
		)
		(fp_line
			(start 0.12065 0.2794)
			(end 0.12065 0.3048)
			(stroke
				(width 0.1)
				(type default)
			)
			(layer "B.Fab")
		)
		(fp_line
			(start 0.12065 0.3048)
			(end 0.67945 0.3048)
			(stroke
				(width 0.1)
				(type default)
			)
			(layer "B.Fab")
		)
		(fp_line
			(start 0.67945 -0.305054)
			(end 0.12065 -0.305054)
			(stroke
				(width 0.1)
				(type default)
			)
			(layer "B.Fab")
		)
		(fp_line
			(start 0.67945 0.3048)
			(end 0.67945 -0.305054)
			(stroke
				(width 0.1)
				(type default)
			)
			(layer "B.Fab")
		)
		(pad "1" smd circle
			(at 0.40005 0 180)
			(size 0 0)
			(layers "B.Cu" "B.Mask" "B.Paste")
			(net "P12V_HSC_ADC_P")
		)
		(pad "2" smd circle
			(at -0.40005 0 180)
			(size 0 0)
			(layers "B.Cu" "B.Mask" "B.Paste")
			(net "P12V_HSC_SENSE2_R1_P")
		)
	)
	(footprint ""
		(layer "B.Cu")
		(at 236.855 -240.411 -90)
		(property "Reference" "R362"
			(at 0 0 90)
			(layer "B.SilkS")
			(hide yes)
			(effects
				(font
					(size 1.27 1.27)
				)
				(justify mirror)
			)
		)
		(property "Value" ""
			(at 0 0 90)
			(layer "B.Fab")
			(effects
				(font
					(size 1.27 1.27)
				)
				(justify mirror)
			)
		)
		(duplicate_pad_numbers_are_jumpers no)
		(fp_line
			(start -0.7874 0.4064)
			(end 0.7874 0.4064)
			(stroke
				(width 0.1524)
				(type default)
			)
			(layer "B.SilkS")
		)
		(fp_line
			(start 0.7874 0.4064)
			(end 0.7874 -0.4064)
			(stroke
				(width 0.1524)
				(type default)
			)
			(layer "B.SilkS")
		)
		(fp_line
			(start -0.7874 -0.4064)
			(end -0.7874 0.4064)
			(stroke
				(width 0.1524)
				(type default)
			)
			(layer "B.SilkS")
		)
		(fp_line
			(start 0.7874 -0.4064)
			(end -0.7874 -0.4064)
			(stroke
				(width 0.1524)
				(type default)
			)
			(layer "B.SilkS")
		)
		(fp_line
			(start -0.67945 0.3048)
			(end -0.120396 0.3048)
			(stroke
				(width 0.1)
				(type default)
			)
			(layer "B.Fab")
		)
		(fp_line
			(start -0.120396 0.3048)
			(end -0.120396 0.2794)
			(stroke
				(width 0.1)
				(type default)
			)
			(layer "B.Fab")
		)
		(fp_line
			(start 0.12065 0.3048)
			(end 0.67945 0.3048)
			(stroke
				(width 0.1)
				(type default)
			)
			(layer "B.Fab")
		)
		(fp_line
			(start 0.67945 0.3048)
			(end 0.67945 -0.305054)
			(stroke
				(width 0.1)
				(type default)
			)
			(layer "B.Fab")
		)
		(fp_line
			(start -0.120396 0.2794)
			(end 0.12065 0.2794)
			(stroke
				(width 0.1)
				(type default)
			)
			(layer "B.Fab")
		)
		(fp_line
			(start 0.12065 0.2794)
			(end 0.12065 0.3048)
			(stroke
				(width 0.1)
				(type default)
			)
			(layer "B.Fab")
		)
		(fp_line
			(start -0.12065 -0.2794)
			(end -0.12065 -0.3048)
			(stroke
				(width 0.1)
				(type default)
			)
			(layer "B.Fab")
		)
		(fp_line
			(start 0.12065 -0.2794)
			(end -0.12065 -0.2794)
			(stroke
				(width 0.1)
				(type default)
			)
			(layer "B.Fab")
		)
		(fp_line
			(start -0.67945 -0.3048)
			(end -0.67945 0.3048)
			(stroke
				(width 0.1)
				(type default)
			)
			(layer "B.Fab")
		)
		(fp_line
			(start -0.12065 -0.3048)
			(end -0.67945 -0.3048)
			(stroke
				(width 0.1)
				(type default)
			)
			(layer "B.Fab")
		)
		(fp_line
			(start 0.12065 -0.305054)
			(end 0.12065 -0.2794)
			(stroke
				(width 0.1)
				(type default)
			)
			(layer "B.Fab")
		)
		(fp_line
			(start 0.67945 -0.305054)
			(end 0.12065 -0.305054)
			(stroke
				(width 0.1)
				(type default)
			)
			(layer "B.Fab")
		)
		(pad "1" smd circle
			(at 0.40005 0 90)
			(size 0 0)
			(layers "B.Cu" "B.Mask" "B.Paste")
			(net "PVDD11_S3_P1")
		)
		(pad "2" smd circle
			(at -0.40005 0 90)
			(size 0 0)
			(layers "B.Cu" "B.Mask" "B.Paste")
			(net "SMB_APML_CPU1_SCL")
		)
	)
	(footprint ""
		(layer "B.Cu")
		(at 97.906332 -386.766562 90)
		(property "Reference" "C289"
			(at 0 0 90)
			(layer "B.SilkS")
			(hide yes)
			(effects
				(font
					(size 1.27 1.27)
				)
				(justify mirror)
			)
		)
		(property "Value" ""
			(at 0 0 90)
			(layer "B.Fab")
			(effects
				(font
					(size 1.27 1.27)
				)
				(justify mirror)
			)
		)
		(duplicate_pad_numbers_are_jumpers no)
		(fp_line
			(start 0.299974 -0.150114)
			(end -0.299974 -0.150114)
			(stroke
				(width 0.1)
				(type default)
			)
			(layer "B.Fab")
		)
		(fp_line
			(start -0.299974 -0.150114)
			(end -0.299974 0.150114)
			(stroke
				(width 0.1)
				(type default)
			)
			(layer "B.Fab")
		)
		(fp_line
			(start 0.299974 0.150114)
			(end 0.299974 -0.150114)
			(stroke
				(width 0.1)
				(type default)
			)
			(layer "B.Fab")
		)
		(fp_line
			(start -0.299974 0.150114)
			(end 0.299974 0.150114)
			(stroke
				(width 0.1)
				(type default)
			)
			(layer "B.Fab")
		)
		(pad "1" smd rect
			(at 0.2667 0 270)
			(size 0.3048 0.381)
			(layers "B.Cu" "B.Mask" "B.Paste")
			(net "P0V9_CPU1_RT1_2A")
		)
		(pad "2" smd rect
			(at -0.2667 0 270)
			(size 0.3048 0.381)
			(layers "B.Cu" "B.Mask" "B.Paste")
			(net "GND")
		)
	)
	(footprint ""
		(layer "B.Cu")
		(at 123.611386 -258.830318)
		(property "Reference" "C2461"
			(at 0 0 0)
			(layer "B.SilkS")
			(hide yes)
			(effects
				(font
					(size 1.27 1.27)
				)
				(justify mirror)
			)
		)
		(property "Value" ""
			(at 0 0 0)
			(layer "B.Fab")
			(effects
				(font
					(size 1.27 1.27)
				)
				(justify mirror)
			)
		)
		(duplicate_pad_numbers_are_jumpers no)
		(fp_line
			(start -0.7874 -0.4064)
			(end -0.7874 0.4064)
			(stroke
				(width 0.1524)
				(type default)
			)
			(layer "B.SilkS")
		)
		(fp_line
			(start -0.7874 0.4064)
			(end 0.7874 0.4064)
			(stroke
				(width 0.1524)
				(type default)
			)
			(layer "B.SilkS")
		)
		(fp_line
			(start 0.7874 -0.4064)
			(end -0.7874 -0.4064)
			(stroke
				(width 0.1524)
				(type default)
			)
			(layer "B.SilkS")
		)
		(fp_line
			(start 0.7874 0.4064)
			(end 0.7874 -0.4064)
			(stroke
				(width 0.1524)
				(type default)
			)
			(layer "B.SilkS")
		)
		(fp_line
			(start -0.67945 -0.3048)
			(end -0.67945 0.3048)
			(stroke
				(width 0.1)
				(type default)
			)
			(layer "B.Fab")
		)
		(fp_line
			(start -0.67945 0.3048)
			(end -0.120396 0.3048)
			(stroke
				(width 0.1)
				(type default)
			)
			(layer "B.Fab")
		)
		(fp_line
			(start -0.12065 -0.3048)
			(end -0.67945 -0.3048)
			(stroke
				(width 0.1)
				(type default)
			)
			(layer "B.Fab")
		)
		(fp_line
			(start -0.12065 -0.2794)
			(end -0.12065 -0.3048)
			(stroke
				(width 0.1)
				(type default)
			)
			(layer "B.Fab")
		)
		(fp_line
			(start -0.120396 0.2794)
			(end 0.12065 0.2794)
			(stroke
				(width 0.1)
				(type default)
			)
			(layer "B.Fab")
		)
		(fp_line
			(start -0.120396 0.3048)
			(end -0.120396 0.2794)
			(stroke
				(width 0.1)
				(type default)
			)
			(layer "B.Fab")
		)
		(fp_line
			(start 0.12065 -0.305054)
			(end 0.12065 -0.2794)
			(stroke
				(width 0.1)
				(type default)
			)
			(layer "B.Fab")
		)
		(fp_line
			(start 0.12065 -0.2794)
			(end -0.12065 -0.2794)
			(stroke
				(width 0.1)
				(type default)
			)
			(layer "B.Fab")
		)
		(fp_line
			(start 0.12065 0.2794)
			(end 0.12065 0.3048)
			(stroke
				(width 0.1)
				(type default)
			)
			(layer "B.Fab")
		)
		(fp_line
			(start 0.12065 0.3048)
			(end 0.67945 0.3048)
			(stroke
				(width 0.1)
				(type default)
			)
			(layer "B.Fab")
		)
		(fp_line
			(start 0.67945 -0.305054)
			(end 0.12065 -0.305054)
			(stroke
				(width 0.1)
				(type default)
			)
			(layer "B.Fab")
		)
		(fp_line
			(start 0.67945 0.3048)
			(end 0.67945 -0.305054)
			(stroke
				(width 0.1)
				(type default)
			)
			(layer "B.Fab")
		)
		(pad "1" smd circle
			(at 0.40005 0 180)
			(size 0 0)
			(layers "B.Cu" "B.Mask" "B.Paste")
			(net "PVDDCR_SOC_P1")
		)
		(pad "2" smd circle
			(at -0.40005 0 180)
			(size 0 0)
			(layers "B.Cu" "B.Mask" "B.Paste")
			(net "GND")
		)
	)
	(footprint ""
		(layer "B.Cu")
		(at 19.91487 -388.789926 90)
		(property "Reference" "PC6614_1"
			(at 0 0 90)
			(layer "B.SilkS")
			(hide yes)
			(effects
				(font
					(size 1.27 1.27)
				)
				(justify mirror)
			)
		)
		(property "Value" ""
			(at 0 0 90)
			(layer "B.Fab")
			(effects
				(font
					(size 1.27 1.27)
				)
				(justify mirror)
			)
		)
		(duplicate_pad_numbers_are_jumpers no)
		(fp_line
			(start 1.524 -0.762)
			(end -1.524 -0.762)
			(stroke
				(width 0.1524)
				(type default)
			)
			(layer "B.SilkS")
		)
		(fp_line
			(start -1.524 -0.762)
			(end -1.524 0.762)
			(stroke
				(width 0.1524)
				(type default)
			)
			(layer "B.SilkS")
		)
		(fp_line
			(start 1.524 0.762)
			(end 1.524 -0.762)
			(stroke
				(width 0.1524)
				(type default)
			)
			(layer "B.SilkS")
		)
		(fp_line
			(start -1.524 0.762)
			(end 1.524 0.762)
			(stroke
				(width 0.1524)
				(type default)
			)
			(layer "B.SilkS")
		)
		(fp_line
			(start 1.1049 -0.724916)
			(end 1.1049 0.724916)
			(stroke
				(width 0.1)
				(type default)
			)
			(layer "B.Fab")
		)
		(fp_line
			(start -1.1049 -0.724916)
			(end 1.1049 -0.724916)
			(stroke
				(width 0.1)
				(type default)
			)
			(layer "B.Fab")
		)
		(fp_line
			(start 1.1049 0.724916)
			(end -1.1049 0.724916)
			(stroke
				(width 0.1)
				(type default)
			)
			(layer "B.Fab")
		)
		(fp_line
			(start -1.1049 0.724916)
			(end -1.1049 -0.724916)
			(stroke
				(width 0.1)
				(type default)
			)
			(layer "B.Fab")
		)
		(pad "1" smd rect
			(at 0.889 0 90)
			(size 1.016 1.27)
			(layers "B.Cu" "B.Mask" "B.Paste")
			(net "SW_P12V_AUX_P0V9_RETIMER_CPU1_FLT")
		)
		(pad "2" smd rect
			(at -0.889 0 90)
			(size 1.016 1.27)
			(layers "B.Cu" "B.Mask" "B.Paste")
			(net "GND")
		)
	)
	(footprint ""
		(layer "B.Cu")
		(at 400.964146 -354.439728 -90)
		(property "Reference" "R6129"
			(at 0 0 90)
			(layer "B.SilkS")
			(hide yes)
			(effects
				(font
					(size 1.27 1.27)
				)
				(justify mirror)
			)
		)
		(property "Value" ""
			(at 0 0 90)
			(layer "B.Fab")
			(effects
				(font
					(size 1.27 1.27)
				)
				(justify mirror)
			)
		)
		(duplicate_pad_numbers_are_jumpers no)
		(fp_line
			(start -0.7874 0.4064)
			(end 0.7874 0.4064)
			(stroke
				(width 0.1524)
				(type default)
			)
			(layer "B.SilkS")
		)
		(fp_line
			(start 0.7874 0.4064)
			(end 0.7874 -0.4064)
			(stroke
				(width 0.1524)
				(type default)
			)
			(layer "B.SilkS")
		)
		(fp_line
			(start -0.7874 -0.4064)
			(end -0.7874 0.4064)
			(stroke
				(width 0.1524)
				(type default)
			)
			(layer "B.SilkS")
		)
		(fp_line
			(start 0.7874 -0.4064)
			(end -0.7874 -0.4064)
			(stroke
				(width 0.1524)
				(type default)
			)
			(layer "B.SilkS")
		)
		(fp_line
			(start -0.67945 0.3048)
			(end -0.120396 0.3048)
			(stroke
				(width 0.1)
				(type default)
			)
			(layer "B.Fab")
		)
		(fp_line
			(start -0.120396 0.3048)
			(end -0.120396 0.2794)
			(stroke
				(width 0.1)
				(type default)
			)
			(layer "B.Fab")
		)
		(fp_line
			(start 0.12065 0.3048)
			(end 0.67945 0.3048)
			(stroke
				(width 0.1)
				(type default)
			)
			(layer "B.Fab")
		)
		(fp_line
			(start 0.67945 0.3048)
			(end 0.67945 -0.305054)
			(stroke
				(width 0.1)
				(type default)
			)
			(layer "B.Fab")
		)
		(fp_line
			(start -0.120396 0.2794)
			(end 0.12065 0.2794)
			(stroke
				(width 0.1)
				(type default)
			)
			(layer "B.Fab")
		)
		(fp_line
			(start 0.12065 0.2794)
			(end 0.12065 0.3048)
			(stroke
				(width 0.1)
				(type default)
			)
			(layer "B.Fab")
		)
		(fp_line
			(start -0.12065 -0.2794)
			(end -0.12065 -0.3048)
			(stroke
				(width 0.1)
				(type default)
			)
			(layer "B.Fab")
		)
		(fp_line
			(start 0.12065 -0.2794)
			(end -0.12065 -0.2794)
			(stroke
				(width 0.1)
				(type default)
			)
			(layer "B.Fab")
		)
		(fp_line
			(start -0.67945 -0.3048)
			(end -0.67945 0.3048)
			(stroke
				(width 0.1)
				(type default)
			)
			(layer "B.Fab")
		)
		(fp_line
			(start -0.12065 -0.3048)
			(end -0.67945 -0.3048)
			(stroke
				(width 0.1)
				(type default)
			)
			(layer "B.Fab")
		)
		(fp_line
			(start 0.12065 -0.305054)
			(end 0.12065 -0.2794)
			(stroke
				(width 0.1)
				(type default)
			)
			(layer "B.Fab")
		)
		(fp_line
			(start 0.67945 -0.305054)
			(end 0.12065 -0.305054)
			(stroke
				(width 0.1)
				(type default)
			)
			(layer "B.Fab")
		)
		(pad "1" smd circle
			(at 0.40005 0 90)
			(size 0 0)
			(layers "B.Cu" "B.Mask" "B.Paste")
			(net "FM_BOARD_SKU_ID0")
		)
		(pad "2" smd circle
			(at -0.40005 0 90)
			(size 0 0)
			(layers "B.Cu" "B.Mask" "B.Paste")
			(net "GND")
		)
	)
	(footprint ""
		(layer "B.Cu")
		(at 365.835692 -261.255002)
		(property "Reference" "C2594"
			(at 0 0 0)
			(layer "B.SilkS")
			(hide yes)
			(effects
				(font
					(size 1.27 1.27)
				)
				(justify mirror)
			)
		)
		(property "Value" ""
			(at 0 0 0)
			(layer "B.Fab")
			(effects
				(font
					(size 1.27 1.27)
				)
				(justify mirror)
			)
		)
		(duplicate_pad_numbers_are_jumpers no)
		(fp_line
			(start -0.7874 -0.4064)
			(end -0.7874 0.4064)
			(stroke
				(width 0.1524)
				(type default)
			)
			(layer "B.SilkS")
		)
		(fp_line
			(start -0.7874 0.4064)
			(end 0.7874 0.4064)
			(stroke
				(width 0.1524)
				(type default)
			)
			(layer "B.SilkS")
		)
		(fp_line
			(start 0.7874 -0.4064)
			(end -0.7874 -0.4064)
			(stroke
				(width 0.1524)
				(type default)
			)
			(layer "B.SilkS")
		)
		(fp_line
			(start 0.7874 0.4064)
			(end 0.7874 -0.4064)
			(stroke
				(width 0.1524)
				(type default)
			)
			(layer "B.SilkS")
		)
		(fp_line
			(start -0.67945 -0.3048)
			(end -0.67945 0.3048)
			(stroke
				(width 0.1)
				(type default)
			)
			(layer "B.Fab")
		)
		(fp_line
			(start -0.67945 0.3048)
			(end -0.120396 0.3048)
			(stroke
				(width 0.1)
				(type default)
			)
			(layer "B.Fab")
		)
		(fp_line
			(start -0.12065 -0.3048)
			(end -0.67945 -0.3048)
			(stroke
				(width 0.1)
				(type default)
			)
			(layer "B.Fab")
		)
		(fp_line
			(start -0.12065 -0.2794)
			(end -0.12065 -0.3048)
			(stroke
				(width 0.1)
				(type default)
			)
			(layer "B.Fab")
		)
		(fp_line
			(start -0.120396 0.2794)
			(end 0.12065 0.2794)
			(stroke
				(width 0.1)
				(type default)
			)
			(layer "B.Fab")
		)
		(fp_line
			(start -0.120396 0.3048)
			(end -0.120396 0.2794)
			(stroke
				(width 0.1)
				(type default)
			)
			(layer "B.Fab")
		)
		(fp_line
			(start 0.12065 -0.305054)
			(end 0.12065 -0.2794)
			(stroke
				(width 0.1)
				(type default)
			)
			(layer "B.Fab")
		)
		(fp_line
			(start 0.12065 -0.2794)
			(end -0.12065 -0.2794)
			(stroke
				(width 0.1)
				(type default)
			)
			(layer "B.Fab")
		)
		(fp_line
			(start 0.12065 0.2794)
			(end 0.12065 0.3048)
			(stroke
				(width 0.1)
				(type default)
			)
			(layer "B.Fab")
		)
		(fp_line
			(start 0.12065 0.3048)
			(end 0.67945 0.3048)
			(stroke
				(width 0.1)
				(type default)
			)
			(layer "B.Fab")
		)
		(fp_line
			(start 0.67945 -0.305054)
			(end 0.12065 -0.305054)
			(stroke
				(width 0.1)
				(type default)
			)
			(layer "B.Fab")
		)
		(fp_line
			(start 0.67945 0.3048)
			(end 0.67945 -0.305054)
			(stroke
				(width 0.1)
				(type default)
			)
			(layer "B.Fab")
		)
		(pad "1" smd circle
			(at 0.40005 0 180)
			(size 0 0)
			(layers "B.Cu" "B.Mask" "B.Paste")
			(net "PVDDCR_SOC_P0")
		)
		(pad "2" smd circle
			(at -0.40005 0 180)
			(size 0 0)
			(layers "B.Cu" "B.Mask" "B.Paste")
			(net "GND")
		)
	)
	(footprint ""
		(layer "B.Cu")
		(at 303.614582 -346.784168 90)
		(property "Reference" "PC158_1"
			(at 0 0 90)
			(layer "B.SilkS")
			(hide yes)
			(effects
				(font
					(size 1.27 1.27)
				)
				(justify mirror)
			)
		)
		(property "Value" ""
			(at 0 0 90)
			(layer "B.Fab")
			(effects
				(font
					(size 1.27 1.27)
				)
				(justify mirror)
			)
		)
		(duplicate_pad_numbers_are_jumpers no)
		(fp_line
			(start 1.524 -0.762)
			(end -1.524 -0.762)
			(stroke
				(width 0.1524)
				(type default)
			)
			(layer "B.SilkS")
		)
		(fp_line
			(start -1.524 -0.762)
			(end -1.524 0.762)
			(stroke
				(width 0.1524)
				(type default)
			)
			(layer "B.SilkS")
		)
		(fp_line
			(start 1.524 0.762)
			(end 1.524 -0.762)
			(stroke
				(width 0.1524)
				(type default)
			)
			(layer "B.SilkS")
		)
		(fp_line
			(start -1.524 0.762)
			(end 1.524 0.762)
			(stroke
				(width 0.1524)
				(type default)
			)
			(layer "B.SilkS")
		)
		(fp_line
			(start 1.1049 -0.724916)
			(end 1.1049 0.724916)
			(stroke
				(width 0.1)
				(type default)
			)
			(layer "B.Fab")
		)
		(fp_line
			(start -1.1049 -0.724916)
			(end 1.1049 -0.724916)
			(stroke
				(width 0.1)
				(type default)
			)
			(layer "B.Fab")
		)
		(fp_line
			(start 1.1049 0.724916)
			(end -1.1049 0.724916)
			(stroke
				(width 0.1)
				(type default)
			)
			(layer "B.Fab")
		)
		(fp_line
			(start -1.1049 0.724916)
			(end -1.1049 -0.724916)
			(stroke
				(width 0.1)
				(type default)
			)
			(layer "B.Fab")
		)
		(pad "1" smd rect
			(at 0.889 0 90)
			(size 1.016 1.27)
			(layers "B.Cu" "B.Mask" "B.Paste")
			(net "SW_P12V_AUX_PVDDIO_P0_FLT")
		)
		(pad "2" smd rect
			(at -0.889 0 90)
			(size 1.016 1.27)
			(layers "B.Cu" "B.Mask" "B.Paste")
			(net "GND")
		)
	)
	(footprint ""
		(layer "B.Cu")
		(at 164.403532 -435.93258 -90)
		(property "Reference" "C13"
			(at 0 0 90)
			(layer "B.SilkS")
			(hide yes)
			(effects
				(font
					(size 1.27 1.27)
				)
				(justify mirror)
			)
		)
		(property "Value" ""
			(at 0 0 90)
			(layer "B.Fab")
			(effects
				(font
					(size 1.27 1.27)
				)
				(justify mirror)
			)
		)
		(duplicate_pad_numbers_are_jumpers no)
		(fp_line
			(start -0.7874 0.4064)
			(end 0.7874 0.4064)
			(stroke
				(width 0.1524)
				(type default)
			)
			(layer "B.SilkS")
		)
		(fp_line
			(start 0.7874 0.4064)
			(end 0.7874 -0.4064)
			(stroke
				(width 0.1524)
				(type default)
			)
			(layer "B.SilkS")
		)
		(fp_line
			(start -0.7874 -0.4064)
			(end -0.7874 0.4064)
			(stroke
				(width 0.1524)
				(type default)
			)
			(layer "B.SilkS")
		)
		(fp_line
			(start 0.7874 -0.4064)
			(end -0.7874 -0.4064)
			(stroke
				(width 0.1524)
				(type default)
			)
			(layer "B.SilkS")
		)
		(fp_line
			(start -0.67945 0.3048)
			(end -0.120396 0.3048)
			(stroke
				(width 0.1)
				(type default)
			)
			(layer "B.Fab")
		)
		(fp_line
			(start -0.120396 0.3048)
			(end -0.120396 0.2794)
			(stroke
				(width 0.1)
				(type default)
			)
			(layer "B.Fab")
		)
		(fp_line
			(start 0.12065 0.3048)
			(end 0.67945 0.3048)
			(stroke
				(width 0.1)
				(type default)
			)
			(layer "B.Fab")
		)
		(fp_line
			(start 0.67945 0.3048)
			(end 0.67945 -0.305054)
			(stroke
				(width 0.1)
				(type default)
			)
			(layer "B.Fab")
		)
		(fp_line
			(start -0.120396 0.2794)
			(end 0.12065 0.2794)
			(stroke
				(width 0.1)
				(type default)
			)
			(layer "B.Fab")
		)
		(fp_line
			(start 0.12065 0.2794)
			(end 0.12065 0.3048)
			(stroke
				(width 0.1)
				(type default)
			)
			(layer "B.Fab")
		)
		(fp_line
			(start -0.12065 -0.2794)
			(end -0.12065 -0.3048)
			(stroke
				(width 0.1)
				(type default)
			)
			(layer "B.Fab")
		)
		(fp_line
			(start 0.12065 -0.2794)
			(end -0.12065 -0.2794)
			(stroke
				(width 0.1)
				(type default)
			)
			(layer "B.Fab")
		)
		(fp_line
			(start -0.67945 -0.3048)
			(end -0.67945 0.3048)
			(stroke
				(width 0.1)
				(type default)
			)
			(layer "B.Fab")
		)
		(fp_line
			(start -0.12065 -0.3048)
			(end -0.67945 -0.3048)
			(stroke
				(width 0.1)
				(type default)
			)
			(layer "B.Fab")
		)
		(fp_line
			(start 0.12065 -0.305054)
			(end 0.12065 -0.2794)
			(stroke
				(width 0.1)
				(type default)
			)
			(layer "B.Fab")
		)
		(fp_line
			(start 0.67945 -0.305054)
			(end 0.12065 -0.305054)
			(stroke
				(width 0.1)
				(type default)
			)
			(layer "B.Fab")
		)
		(pad "1" smd circle
			(at 0.40005 0 90)
			(size 0 0)
			(layers "B.Cu" "B.Mask" "B.Paste")
			(net "PRSNT_CABLE_GPU_B3_ISO_N")
		)
		(pad "2" smd circle
			(at -0.40005 0 90)
			(size 0 0)
			(layers "B.Cu" "B.Mask" "B.Paste")
			(net "GND")
		)
	)
	(footprint ""
		(layer "B.Cu")
		(at 359.721404 -252.41631 180)
		(property "Reference" "C3931"
			(at 0 0 0)
			(layer "B.SilkS")
			(hide yes)
			(effects
				(font
					(size 1.27 1.27)
				)
				(justify mirror)
			)
		)
		(property "Value" ""
			(at 0 0 0)
			(layer "B.Fab")
			(effects
				(font
					(size 1.27 1.27)
				)
				(justify mirror)
			)
		)
		(duplicate_pad_numbers_are_jumpers no)
		(fp_line
			(start 0.7874 0.4064)
			(end 0.7874 -0.4064)
			(stroke
				(width 0.1524)
				(type default)
			)
			(layer "B.SilkS")
		)
		(fp_line
			(start 0.7874 -0.4064)
			(end -0.7874 -0.4064)
			(stroke
				(width 0.1524)
				(type default)
			)
			(layer "B.SilkS")
		)
		(fp_line
			(start -0.7874 0.4064)
			(end 0.7874 0.4064)
			(stroke
				(width 0.1524)
				(type default)
			)
			(layer "B.SilkS")
		)
		(fp_line
			(start -0.7874 -0.4064)
			(end -0.7874 0.4064)
			(stroke
				(width 0.1524)
				(type default)
			)
			(layer "B.SilkS")
		)
		(fp_line
			(start 0.67945 0.3048)
			(end 0.67945 -0.305054)
			(stroke
				(width 0.1)
				(type default)
			)
			(layer "B.Fab")
		)
		(fp_line
			(start 0.67945 -0.305054)
			(end 0.12065 -0.305054)
			(stroke
				(width 0.1)
				(type default)
			)
			(layer "B.Fab")
		)
		(fp_line
			(start 0.12065 0.3048)
			(end 0.67945 0.3048)
			(stroke
				(width 0.1)
				(type default)
			)
			(layer "B.Fab")
		)
		(fp_line
			(start 0.12065 0.2794)
			(end 0.12065 0.3048)
			(stroke
				(width 0.1)
				(type default)
			)
			(layer "B.Fab")
		)
		(fp_line
			(start 0.12065 -0.2794)
			(end -0.12065 -0.2794)
			(stroke
				(width 0.1)
				(type default)
			)
			(layer "B.Fab")
		)
		(fp_line
			(start 0.12065 -0.305054)
			(end 0.12065 -0.2794)
			(stroke
				(width 0.1)
				(type default)
			)
			(layer "B.Fab")
		)
		(fp_line
			(start -0.120396 0.3048)
			(end -0.120396 0.2794)
			(stroke
				(width 0.1)
				(type default)
			)
			(layer "B.Fab")
		)
		(fp_line
			(start -0.120396 0.2794)
			(end 0.12065 0.2794)
			(stroke
				(width 0.1)
				(type default)
			)
			(layer "B.Fab")
		)
		(fp_line
			(start -0.12065 -0.2794)
			(end -0.12065 -0.3048)
			(stroke
				(width 0.1)
				(type default)
			)
			(layer "B.Fab")
		)
		(fp_line
			(start -0.12065 -0.3048)
			(end -0.67945 -0.3048)
			(stroke
				(width 0.1)
				(type default)
			)
			(layer "B.Fab")
		)
		(fp_line
			(start -0.67945 0.3048)
			(end -0.120396 0.3048)
			(stroke
				(width 0.1)
				(type default)
			)
			(layer "B.Fab")
		)
		(fp_line
			(start -0.67945 -0.3048)
			(end -0.67945 0.3048)
			(stroke
				(width 0.1)
				(type default)
			)
			(layer "B.Fab")
		)
		(pad "1" smd circle
			(at 0.40005 0)
			(size 0 0)
			(layers "B.Cu" "B.Mask" "B.Paste")
			(net "PVDDCR_SOC_P0")
		)
		(pad "2" smd circle
			(at -0.40005 0)
			(size 0 0)
			(layers "B.Cu" "B.Mask" "B.Paste")
			(net "GND")
		)
	)
	(footprint ""
		(layer "B.Cu")
		(at 239.903 -338.455)
		(property "Reference" "R1399"
			(at 0 0 0)
			(layer "B.SilkS")
			(hide yes)
			(effects
				(font
					(size 1.27 1.27)
				)
				(justify mirror)
			)
		)
		(property "Value" ""
			(at 0 0 0)
			(layer "B.Fab")
			(effects
				(font
					(size 1.27 1.27)
				)
				(justify mirror)
			)
		)
		(duplicate_pad_numbers_are_jumpers no)
		(fp_line
			(start -0.32512 -0.175006)
			(end -0.32512 0.175006)
			(stroke
				(width 0.1)
				(type default)
			)
			(layer "B.Fab")
		)
		(fp_line
			(start -0.32512 0.175006)
			(end 0.32512 0.175006)
			(stroke
				(width 0.1)
				(type default)
			)
			(layer "B.Fab")
		)
		(fp_line
			(start 0.32512 -0.175006)
			(end -0.32512 -0.175006)
			(stroke
				(width 0.1)
				(type default)
			)
			(layer "B.Fab")
		)
		(fp_line
			(start 0.32512 0.175006)
			(end 0.32512 -0.175006)
			(stroke
				(width 0.1)
				(type default)
			)
			(layer "B.Fab")
		)
		(pad "1" smd rect
			(at 0.2667 0 180)
			(size 0.3048 0.381)
			(layers "B.Cu" "B.Mask" "B.Paste")
			(net "P1V8_CPU1_RT_1D")
		)
		(pad "2" smd rect
			(at -0.2667 0)
			(size 0.3048 0.381)
			(layers "B.Cu" "B.Mask" "B.Paste")
			(net "SMB_RT_CPU1_P3_ROM_MUX_2D_R_SDA")
		)
	)
	(footprint ""
		(layer "B.Cu")
		(at 241.140488 -332.613 180)
		(property "Reference" "R848"
			(at 0 0 0)
			(layer "B.SilkS")
			(hide yes)
			(effects
				(font
					(size 1.27 1.27)
				)
				(justify mirror)
			)
		)
		(property "Value" ""
			(at 0 0 0)
			(layer "B.Fab")
			(effects
				(font
					(size 1.27 1.27)
				)
				(justify mirror)
			)
		)
		(duplicate_pad_numbers_are_jumpers no)
		(fp_line
			(start 0.32512 0.175006)
			(end 0.32512 -0.175006)
			(stroke
				(width 0.1)
				(type default)
			)
			(layer "B.Fab")
		)
		(fp_line
			(start 0.32512 -0.175006)
			(end -0.32512 -0.175006)
			(stroke
				(width 0.1)
				(type default)
			)
			(layer "B.Fab")
		)
		(fp_line
			(start -0.32512 0.175006)
			(end 0.32512 0.175006)
			(stroke
				(width 0.1)
				(type default)
			)
			(layer "B.Fab")
		)
		(fp_line
			(start -0.32512 -0.175006)
			(end -0.32512 0.175006)
			(stroke
				(width 0.1)
				(type default)
			)
			(layer "B.Fab")
		)
		(pad "1" smd rect
			(at 0.2667 0)
			(size 0.3048 0.381)
			(layers "B.Cu" "B.Mask" "B.Paste")
			(net "RST_SMB_RT_ROM_R1_N")
		)
		(pad "2" smd rect
			(at -0.2667 0 180)
			(size 0.3048 0.381)
			(layers "B.Cu" "B.Mask" "B.Paste")
			(net "RST_SMB_RT_ROM_N")
		)
	)
	(footprint ""
		(layer "B.Cu")
		(at 208.461356 -387.676136)
		(property "Reference" "PR2514"
			(at 0 0 0)
			(layer "B.SilkS")
			(hide yes)
			(effects
				(font
					(size 1.27 1.27)
				)
				(justify mirror)
			)
		)
		(property "Value" ""
			(at 0 0 0)
			(layer "B.Fab")
			(effects
				(font
					(size 1.27 1.27)
				)
				(justify mirror)
			)
		)
		(duplicate_pad_numbers_are_jumpers no)
		(fp_line
			(start -0.7874 -0.4064)
			(end -0.7874 0.4064)
			(stroke
				(width 0.1524)
				(type default)
			)
			(layer "B.SilkS")
		)
		(fp_line
			(start -0.7874 0.4064)
			(end 0.7874 0.4064)
			(stroke
				(width 0.1524)
				(type default)
			)
			(layer "B.SilkS")
		)
		(fp_line
			(start 0.7874 -0.4064)
			(end -0.7874 -0.4064)
			(stroke
				(width 0.1524)
				(type default)
			)
			(layer "B.SilkS")
		)
		(fp_line
			(start 0.7874 0.4064)
			(end 0.7874 -0.4064)
			(stroke
				(width 0.1524)
				(type default)
			)
			(layer "B.SilkS")
		)
		(fp_line
			(start -0.67945 -0.3048)
			(end -0.67945 0.3048)
			(stroke
				(width 0.1)
				(type default)
			)
			(layer "B.Fab")
		)
		(fp_line
			(start -0.67945 0.3048)
			(end -0.120396 0.3048)
			(stroke
				(width 0.1)
				(type default)
			)
			(layer "B.Fab")
		)
		(fp_line
			(start -0.12065 -0.3048)
			(end -0.67945 -0.3048)
			(stroke
				(width 0.1)
				(type default)
			)
			(layer "B.Fab")
		)
		(fp_line
			(start -0.12065 -0.2794)
			(end -0.12065 -0.3048)
			(stroke
				(width 0.1)
				(type default)
			)
			(layer "B.Fab")
		)
		(fp_line
			(start -0.120396 0.2794)
			(end 0.12065 0.2794)
			(stroke
				(width 0.1)
				(type default)
			)
			(layer "B.Fab")
		)
		(fp_line
			(start -0.120396 0.3048)
			(end -0.120396 0.2794)
			(stroke
				(width 0.1)
				(type default)
			)
			(layer "B.Fab")
		)
		(fp_line
			(start 0.12065 -0.305054)
			(end 0.12065 -0.2794)
			(stroke
				(width 0.1)
				(type default)
			)
			(layer "B.Fab")
		)
		(fp_line
			(start 0.12065 -0.2794)
			(end -0.12065 -0.2794)
			(stroke
				(width 0.1)
				(type default)
			)
			(layer "B.Fab")
		)
		(fp_line
			(start 0.12065 0.2794)
			(end 0.12065 0.3048)
			(stroke
				(width 0.1)
				(type default)
			)
			(layer "B.Fab")
		)
		(fp_line
			(start 0.12065 0.3048)
			(end 0.67945 0.3048)
			(stroke
				(width 0.1)
				(type default)
			)
			(layer "B.Fab")
		)
		(fp_line
			(start 0.67945 -0.305054)
			(end 0.12065 -0.305054)
			(stroke
				(width 0.1)
				(type default)
			)
			(layer "B.Fab")
		)
		(fp_line
			(start 0.67945 0.3048)
			(end 0.67945 -0.305054)
			(stroke
				(width 0.1)
				(type default)
			)
			(layer "B.Fab")
		)
		(pad "1" smd circle
			(at 0.40005 0 180)
			(size 0 0)
			(layers "B.Cu" "B.Mask" "B.Paste")
			(net "P12V_HSC_ADC_P")
		)
		(pad "2" smd circle
			(at -0.40005 0 180)
			(size 0 0)
			(layers "B.Cu" "B.Mask" "B.Paste")
			(net "P12V_HSC_SENSE1_P")
		)
	)
	(footprint ""
		(layer "B.Cu")
		(at 164.266626 -109.076998 90)
		(property "Reference" "R25"
			(at 0 0 90)
			(layer "B.SilkS")
			(hide yes)
			(effects
				(font
					(size 1.27 1.27)
				)
				(justify mirror)
			)
		)
		(property "Value" ""
			(at 0 0 90)
			(layer "B.Fab")
			(effects
				(font
					(size 1.27 1.27)
				)
				(justify mirror)
			)
		)
		(duplicate_pad_numbers_are_jumpers no)
		(fp_line
			(start 0.7874 -0.4064)
			(end -0.7874 -0.4064)
			(stroke
				(width 0.1524)
				(type default)
			)
			(layer "B.SilkS")
		)
		(fp_line
			(start -0.7874 -0.4064)
			(end -0.7874 0.4064)
			(stroke
				(width 0.1524)
				(type default)
			)
			(layer "B.SilkS")
		)
		(fp_line
			(start 0.7874 0.4064)
			(end 0.7874 -0.4064)
			(stroke
				(width 0.1524)
				(type default)
			)
			(layer "B.SilkS")
		)
		(fp_line
			(start -0.7874 0.4064)
			(end 0.7874 0.4064)
			(stroke
				(width 0.1524)
				(type default)
			)
			(layer "B.SilkS")
		)
		(fp_line
			(start 0.67945 -0.305054)
			(end 0.12065 -0.305054)
			(stroke
				(width 0.1)
				(type default)
			)
			(layer "B.Fab")
		)
		(fp_line
			(start 0.12065 -0.305054)
			(end 0.12065 -0.2794)
			(stroke
				(width 0.1)
				(type default)
			)
			(layer "B.Fab")
		)
		(fp_line
			(start -0.12065 -0.3048)
			(end -0.67945 -0.3048)
			(stroke
				(width 0.1)
				(type default)
			)
			(layer "B.Fab")
		)
		(fp_line
			(start -0.67945 -0.3048)
			(end -0.67945 0.3048)
			(stroke
				(width 0.1)
				(type default)
			)
			(layer "B.Fab")
		)
		(fp_line
			(start 0.12065 -0.2794)
			(end -0.12065 -0.2794)
			(stroke
				(width 0.1)
				(type default)
			)
			(layer "B.Fab")
		)
		(fp_line
			(start -0.12065 -0.2794)
			(end -0.12065 -0.3048)
			(stroke
				(width 0.1)
				(type default)
			)
			(layer "B.Fab")
		)
		(fp_line
			(start 0.12065 0.2794)
			(end 0.12065 0.3048)
			(stroke
				(width 0.1)
				(type default)
			)
			(layer "B.Fab")
		)
		(fp_line
			(start -0.120396 0.2794)
			(end 0.12065 0.2794)
			(stroke
				(width 0.1)
				(type default)
			)
			(layer "B.Fab")
		)
		(fp_line
			(start 0.67945 0.3048)
			(end 0.67945 -0.305054)
			(stroke
				(width 0.1)
				(type default)
			)
			(layer "B.Fab")
		)
		(fp_line
			(start 0.12065 0.3048)
			(end 0.67945 0.3048)
			(stroke
				(width 0.1)
				(type default)
			)
			(layer "B.Fab")
		)
		(fp_line
			(start -0.120396 0.3048)
			(end -0.120396 0.2794)
			(stroke
				(width 0.1)
				(type default)
			)
			(layer "B.Fab")
		)
		(fp_line
			(start -0.67945 0.3048)
			(end -0.120396 0.3048)
			(stroke
				(width 0.1)
				(type default)
			)
			(layer "B.Fab")
		)
		(pad "1" smd circle
			(at 0.40005 0 270)
			(size 0 0)
			(layers "B.Cu" "B.Mask" "B.Paste")
			(net "FM_I3C_CPU1_MUX1_OE_N")
		)
		(pad "2" smd circle
			(at -0.40005 0 270)
			(size 0 0)
			(layers "B.Cu" "B.Mask" "B.Paste")
			(net "GND")
		)
	)
	(footprint ""
		(layer "B.Cu")
		(at 43.265852 -385.09956 180)
		(property "Reference" "R720"
			(at 0 0 0)
			(layer "B.SilkS")
			(hide yes)
			(effects
				(font
					(size 1.27 1.27)
				)
				(justify mirror)
			)
		)
		(property "Value" ""
			(at 0 0 0)
			(layer "B.Fab")
			(effects
				(font
					(size 1.27 1.27)
				)
				(justify mirror)
			)
		)
		(duplicate_pad_numbers_are_jumpers no)
		(fp_line
			(start 0.32512 0.175006)
			(end 0.32512 -0.175006)
			(stroke
				(width 0.1)
				(type default)
			)
			(layer "B.Fab")
		)
		(fp_line
			(start 0.32512 -0.175006)
			(end -0.32512 -0.175006)
			(stroke
				(width 0.1)
				(type default)
			)
			(layer "B.Fab")
		)
		(fp_line
			(start -0.32512 0.175006)
			(end 0.32512 0.175006)
			(stroke
				(width 0.1)
				(type default)
			)
			(layer "B.Fab")
		)
		(fp_line
			(start -0.32512 -0.175006)
			(end -0.32512 0.175006)
			(stroke
				(width 0.1)
				(type default)
			)
			(layer "B.Fab")
		)
		(pad "1" smd rect
			(at 0.2667 0)
			(size 0.3048 0.381)
			(layers "B.Cu" "B.Mask" "B.Paste")
			(net "P1V8_CPU1_RT_1D")
		)
		(pad "2" smd rect
			(at -0.2667 0 180)
			(size 0.3048 0.381)
			(layers "B.Cu" "B.Mask" "B.Paste")
			(net "TEST1_RT_CPU1_P0")
		)
	)
	(footprint ""
		(layer "B.Cu")
		(at 114.325908 -256.012442 -90)
		(property "Reference" "C3907"
			(at 0 0 90)
			(layer "B.SilkS")
			(hide yes)
			(effects
				(font
					(size 1.27 1.27)
				)
				(justify mirror)
			)
		)
		(property "Value" ""
			(at 0 0 90)
			(layer "B.Fab")
			(effects
				(font
					(size 1.27 1.27)
				)
				(justify mirror)
			)
		)
		(duplicate_pad_numbers_are_jumpers no)
		(fp_line
			(start -0.7874 0.4064)
			(end 0.7874 0.4064)
			(stroke
				(width 0.1524)
				(type default)
			)
			(layer "B.SilkS")
		)
		(fp_line
			(start 0.7874 0.4064)
			(end 0.7874 -0.4064)
			(stroke
				(width 0.1524)
				(type default)
			)
			(layer "B.SilkS")
		)
		(fp_line
			(start -0.7874 -0.4064)
			(end -0.7874 0.4064)
			(stroke
				(width 0.1524)
				(type default)
			)
			(layer "B.SilkS")
		)
		(fp_line
			(start 0.7874 -0.4064)
			(end -0.7874 -0.4064)
			(stroke
				(width 0.1524)
				(type default)
			)
			(layer "B.SilkS")
		)
		(fp_line
			(start -0.67945 0.3048)
			(end -0.120396 0.3048)
			(stroke
				(width 0.1)
				(type default)
			)
			(layer "B.Fab")
		)
		(fp_line
			(start -0.120396 0.3048)
			(end -0.120396 0.2794)
			(stroke
				(width 0.1)
				(type default)
			)
			(layer "B.Fab")
		)
		(fp_line
			(start 0.12065 0.3048)
			(end 0.67945 0.3048)
			(stroke
				(width 0.1)
				(type default)
			)
			(layer "B.Fab")
		)
		(fp_line
			(start 0.67945 0.3048)
			(end 0.67945 -0.305054)
			(stroke
				(width 0.1)
				(type default)
			)
			(layer "B.Fab")
		)
		(fp_line
			(start -0.120396 0.2794)
			(end 0.12065 0.2794)
			(stroke
				(width 0.1)
				(type default)
			)
			(layer "B.Fab")
		)
		(fp_line
			(start 0.12065 0.2794)
			(end 0.12065 0.3048)
			(stroke
				(width 0.1)
				(type default)
			)
			(layer "B.Fab")
		)
		(fp_line
			(start -0.12065 -0.2794)
			(end -0.12065 -0.3048)
			(stroke
				(width 0.1)
				(type default)
			)
			(layer "B.Fab")
		)
		(fp_line
			(start 0.12065 -0.2794)
			(end -0.12065 -0.2794)
			(stroke
				(width 0.1)
				(type default)
			)
			(layer "B.Fab")
		)
		(fp_line
			(start -0.67945 -0.3048)
			(end -0.67945 0.3048)
			(stroke
				(width 0.1)
				(type default)
			)
			(layer "B.Fab")
		)
		(fp_line
			(start -0.12065 -0.3048)
			(end -0.67945 -0.3048)
			(stroke
				(width 0.1)
				(type default)
			)
			(layer "B.Fab")
		)
		(fp_line
			(start 0.12065 -0.305054)
			(end 0.12065 -0.2794)
			(stroke
				(width 0.1)
				(type default)
			)
			(layer "B.Fab")
		)
		(fp_line
			(start 0.67945 -0.305054)
			(end 0.12065 -0.305054)
			(stroke
				(width 0.1)
				(type default)
			)
			(layer "B.Fab")
		)
		(pad "1" smd circle
			(at 0.40005 0 90)
			(size 0 0)
			(layers "B.Cu" "B.Mask" "B.Paste")
			(net "PVDDCR_SOC_P1")
		)
		(pad "2" smd circle
			(at -0.40005 0 90)
			(size 0 0)
			(layers "B.Cu" "B.Mask" "B.Paste")
			(net "GND")
		)
	)
	(footprint ""
		(layer "B.Cu")
		(at 352.501454 -264.35431)
		(property "Reference" "C2608"
			(at 0 0 0)
			(layer "B.SilkS")
			(hide yes)
			(effects
				(font
					(size 1.27 1.27)
				)
				(justify mirror)
			)
		)
		(property "Value" ""
			(at 0 0 0)
			(layer "B.Fab")
			(effects
				(font
					(size 1.27 1.27)
				)
				(justify mirror)
			)
		)
		(duplicate_pad_numbers_are_jumpers no)
		(fp_line
			(start -0.7874 -0.4064)
			(end -0.7874 0.4064)
			(stroke
				(width 0.1524)
				(type default)
			)
			(layer "B.SilkS")
		)
		(fp_line
			(start -0.7874 0.4064)
			(end 0.7874 0.4064)
			(stroke
				(width 0.1524)
				(type default)
			)
			(layer "B.SilkS")
		)
		(fp_line
			(start 0.7874 -0.4064)
			(end -0.7874 -0.4064)
			(stroke
				(width 0.1524)
				(type default)
			)
			(layer "B.SilkS")
		)
		(fp_line
			(start 0.7874 0.4064)
			(end 0.7874 -0.4064)
			(stroke
				(width 0.1524)
				(type default)
			)
			(layer "B.SilkS")
		)
		(fp_line
			(start -0.67945 -0.3048)
			(end -0.67945 0.3048)
			(stroke
				(width 0.1)
				(type default)
			)
			(layer "B.Fab")
		)
		(fp_line
			(start -0.67945 0.3048)
			(end -0.120396 0.3048)
			(stroke
				(width 0.1)
				(type default)
			)
			(layer "B.Fab")
		)
		(fp_line
			(start -0.12065 -0.3048)
			(end -0.67945 -0.3048)
			(stroke
				(width 0.1)
				(type default)
			)
			(layer "B.Fab")
		)
		(fp_line
			(start -0.12065 -0.2794)
			(end -0.12065 -0.3048)
			(stroke
				(width 0.1)
				(type default)
			)
			(layer "B.Fab")
		)
		(fp_line
			(start -0.120396 0.2794)
			(end 0.12065 0.2794)
			(stroke
				(width 0.1)
				(type default)
			)
			(layer "B.Fab")
		)
		(fp_line
			(start -0.120396 0.3048)
			(end -0.120396 0.2794)
			(stroke
				(width 0.1)
				(type default)
			)
			(layer "B.Fab")
		)
		(fp_line
			(start 0.12065 -0.305054)
			(end 0.12065 -0.2794)
			(stroke
				(width 0.1)
				(type default)
			)
			(layer "B.Fab")
		)
		(fp_line
			(start 0.12065 -0.2794)
			(end -0.12065 -0.2794)
			(stroke
				(width 0.1)
				(type default)
			)
			(layer "B.Fab")
		)
		(fp_line
			(start 0.12065 0.2794)
			(end 0.12065 0.3048)
			(stroke
				(width 0.1)
				(type default)
			)
			(layer "B.Fab")
		)
		(fp_line
			(start 0.12065 0.3048)
			(end 0.67945 0.3048)
			(stroke
				(width 0.1)
				(type default)
			)
			(layer "B.Fab")
		)
		(fp_line
			(start 0.67945 -0.305054)
			(end 0.12065 -0.305054)
			(stroke
				(width 0.1)
				(type default)
			)
			(layer "B.Fab")
		)
		(fp_line
			(start 0.67945 0.3048)
			(end 0.67945 -0.305054)
			(stroke
				(width 0.1)
				(type default)
			)
			(layer "B.Fab")
		)
		(pad "1" smd circle
			(at 0.40005 0 180)
			(size 0 0)
			(layers "B.Cu" "B.Mask" "B.Paste")
			(net "PVDD11_S3_P0")
		)
		(pad "2" smd circle
			(at -0.40005 0 180)
			(size 0 0)
			(layers "B.Cu" "B.Mask" "B.Paste")
			(net "GND")
		)
	)
	(footprint ""
		(layer "B.Cu")
		(at 124.091192 -390.560052 90)
		(property "Reference" "C437"
			(at 0 0 90)
			(layer "B.SilkS")
			(hide yes)
			(effects
				(font
					(size 1.27 1.27)
				)
				(justify mirror)
			)
		)
		(property "Value" ""
			(at 0 0 90)
			(layer "B.Fab")
			(effects
				(font
					(size 1.27 1.27)
				)
				(justify mirror)
			)
		)
		(duplicate_pad_numbers_are_jumpers no)
		(fp_line
			(start 0.7874 -0.4064)
			(end -0.7874 -0.4064)
			(stroke
				(width 0.1524)
				(type default)
			)
			(layer "B.SilkS")
		)
		(fp_line
			(start -0.7874 -0.4064)
			(end -0.7874 0.4064)
			(stroke
				(width 0.1524)
				(type default)
			)
			(layer "B.SilkS")
		)
		(fp_line
			(start 0.7874 0.4064)
			(end 0.7874 -0.4064)
			(stroke
				(width 0.1524)
				(type default)
			)
			(layer "B.SilkS")
		)
		(fp_line
			(start -0.7874 0.4064)
			(end 0.7874 0.4064)
			(stroke
				(width 0.1524)
				(type default)
			)
			(layer "B.SilkS")
		)
		(fp_line
			(start 0.67945 -0.305054)
			(end 0.12065 -0.305054)
			(stroke
				(width 0.1)
				(type default)
			)
			(layer "B.Fab")
		)
		(fp_line
			(start 0.12065 -0.305054)
			(end 0.12065 -0.2794)
			(stroke
				(width 0.1)
				(type default)
			)
			(layer "B.Fab")
		)
		(fp_line
			(start -0.12065 -0.3048)
			(end -0.67945 -0.3048)
			(stroke
				(width 0.1)
				(type default)
			)
			(layer "B.Fab")
		)
		(fp_line
			(start -0.67945 -0.3048)
			(end -0.67945 0.3048)
			(stroke
				(width 0.1)
				(type default)
			)
			(layer "B.Fab")
		)
		(fp_line
			(start 0.12065 -0.2794)
			(end -0.12065 -0.2794)
			(stroke
				(width 0.1)
				(type default)
			)
			(layer "B.Fab")
		)
		(fp_line
			(start -0.12065 -0.2794)
			(end -0.12065 -0.3048)
			(stroke
				(width 0.1)
				(type default)
			)
			(layer "B.Fab")
		)
		(fp_line
			(start 0.12065 0.2794)
			(end 0.12065 0.3048)
			(stroke
				(width 0.1)
				(type default)
			)
			(layer "B.Fab")
		)
		(fp_line
			(start -0.120396 0.2794)
			(end 0.12065 0.2794)
			(stroke
				(width 0.1)
				(type default)
			)
			(layer "B.Fab")
		)
		(fp_line
			(start 0.67945 0.3048)
			(end 0.67945 -0.305054)
			(stroke
				(width 0.1)
				(type default)
			)
			(layer "B.Fab")
		)
		(fp_line
			(start 0.12065 0.3048)
			(end 0.67945 0.3048)
			(stroke
				(width 0.1)
				(type default)
			)
			(layer "B.Fab")
		)
		(fp_line
			(start -0.120396 0.3048)
			(end -0.120396 0.2794)
			(stroke
				(width 0.1)
				(type default)
			)
			(layer "B.Fab")
		)
		(fp_line
			(start -0.67945 0.3048)
			(end -0.120396 0.3048)
			(stroke
				(width 0.1)
				(type default)
			)
			(layer "B.Fab")
		)
		(pad "1" smd circle
			(at 0.40005 0 270)
			(size 0 0)
			(layers "B.Cu" "B.Mask" "B.Paste")
			(net "P1V8_CPU1_RT3_1A")
		)
		(pad "2" smd circle
			(at -0.40005 0 270)
			(size 0 0)
			(layers "B.Cu" "B.Mask" "B.Paste")
			(net "GND")
		)
	)
	(footprint ""
		(layer "B.Cu")
		(at 191.992758 -69.443346)
		(property "Reference" "R3213"
			(at 0 0 0)
			(layer "B.SilkS")
			(hide yes)
			(effects
				(font
					(size 1.27 1.27)
				)
				(justify mirror)
			)
		)
		(property "Value" ""
			(at 0 0 0)
			(layer "B.Fab")
			(effects
				(font
					(size 1.27 1.27)
				)
				(justify mirror)
			)
		)
		(duplicate_pad_numbers_are_jumpers no)
		(fp_line
			(start -0.7874 -0.4064)
			(end -0.7874 0.4064)
			(stroke
				(width 0.1524)
				(type default)
			)
			(layer "B.SilkS")
		)
		(fp_line
			(start -0.7874 0.4064)
			(end 0.7874 0.4064)
			(stroke
				(width 0.1524)
				(type default)
			)
			(layer "B.SilkS")
		)
		(fp_line
			(start 0.7874 -0.4064)
			(end -0.7874 -0.4064)
			(stroke
				(width 0.1524)
				(type default)
			)
			(layer "B.SilkS")
		)
		(fp_line
			(start 0.7874 0.4064)
			(end 0.7874 -0.4064)
			(stroke
				(width 0.1524)
				(type default)
			)
			(layer "B.SilkS")
		)
		(fp_line
			(start -0.67945 -0.3048)
			(end -0.67945 0.3048)
			(stroke
				(width 0.1)
				(type default)
			)
			(layer "B.Fab")
		)
		(fp_line
			(start -0.67945 0.3048)
			(end -0.120396 0.3048)
			(stroke
				(width 0.1)
				(type default)
			)
			(layer "B.Fab")
		)
		(fp_line
			(start -0.12065 -0.3048)
			(end -0.67945 -0.3048)
			(stroke
				(width 0.1)
				(type default)
			)
			(layer "B.Fab")
		)
		(fp_line
			(start -0.12065 -0.2794)
			(end -0.12065 -0.3048)
			(stroke
				(width 0.1)
				(type default)
			)
			(layer "B.Fab")
		)
		(fp_line
			(start -0.120396 0.2794)
			(end 0.12065 0.2794)
			(stroke
				(width 0.1)
				(type default)
			)
			(layer "B.Fab")
		)
		(fp_line
			(start -0.120396 0.3048)
			(end -0.120396 0.2794)
			(stroke
				(width 0.1)
				(type default)
			)
			(layer "B.Fab")
		)
		(fp_line
			(start 0.12065 -0.305054)
			(end 0.12065 -0.2794)
			(stroke
				(width 0.1)
				(type default)
			)
			(layer "B.Fab")
		)
		(fp_line
			(start 0.12065 -0.2794)
			(end -0.12065 -0.2794)
			(stroke
				(width 0.1)
				(type default)
			)
			(layer "B.Fab")
		)
		(fp_line
			(start 0.12065 0.2794)
			(end 0.12065 0.3048)
			(stroke
				(width 0.1)
				(type default)
			)
			(layer "B.Fab")
		)
		(fp_line
			(start 0.12065 0.3048)
			(end 0.67945 0.3048)
			(stroke
				(width 0.1)
				(type default)
			)
			(layer "B.Fab")
		)
		(fp_line
			(start 0.67945 -0.305054)
			(end 0.12065 -0.305054)
			(stroke
				(width 0.1)
				(type default)
			)
			(layer "B.Fab")
		)
		(fp_line
			(start 0.67945 0.3048)
			(end 0.67945 -0.305054)
			(stroke
				(width 0.1)
				(type default)
			)
			(layer "B.Fab")
		)
		(pad "1" smd circle
			(at 0.40005 0 180)
			(size 0 0)
			(layers "B.Cu" "B.Mask" "B.Paste")
			(net "NCSI_BMC_TX_EN_R1")
		)
		(pad "2" smd circle
			(at -0.40005 0 180)
			(size 0 0)
			(layers "B.Cu" "B.Mask" "B.Paste")
			(net "RMII_BMC_OCP_TX_EN")
		)
	)
	(footprint ""
		(layer "B.Cu")
		(at 51.884072 -192.66027)
		(property "Reference" "C177"
			(at 0 0 0)
			(layer "B.SilkS")
			(hide yes)
			(effects
				(font
					(size 1.27 1.27)
				)
				(justify mirror)
			)
		)
		(property "Value" ""
			(at 0 0 0)
			(layer "B.Fab")
			(effects
				(font
					(size 1.27 1.27)
				)
				(justify mirror)
			)
		)
		(duplicate_pad_numbers_are_jumpers no)
		(fp_line
			(start -1.524 -0.762)
			(end -1.524 0.762)
			(stroke
				(width 0.1524)
				(type default)
			)
			(layer "B.SilkS")
		)
		(fp_line
			(start -1.524 0.762)
			(end 1.524 0.762)
			(stroke
				(width 0.1524)
				(type default)
			)
			(layer "B.SilkS")
		)
		(fp_line
			(start 1.524 -0.762)
			(end -1.524 -0.762)
			(stroke
				(width 0.1524)
				(type default)
			)
			(layer "B.SilkS")
		)
		(fp_line
			(start 1.524 0.762)
			(end 1.524 -0.762)
			(stroke
				(width 0.1524)
				(type default)
			)
			(layer "B.SilkS")
		)
		(fp_line
			(start -1.1049 -0.724916)
			(end 1.1049 -0.724916)
			(stroke
				(width 0.1)
				(type default)
			)
			(layer "B.Fab")
		)
		(fp_line
			(start -1.1049 0.724916)
			(end -1.1049 -0.724916)
			(stroke
				(width 0.1)
				(type default)
			)
			(layer "B.Fab")
		)
		(fp_line
			(start 1.1049 -0.724916)
			(end 1.1049 0.724916)
			(stroke
				(width 0.1)
				(type default)
			)
			(layer "B.Fab")
		)
		(fp_line
			(start 1.1049 0.724916)
			(end -1.1049 0.724916)
			(stroke
				(width 0.1)
				(type default)
			)
			(layer "B.Fab")
		)
		(pad "1" smd rect
			(at 0.889 0)
			(size 1.016 1.27)
			(layers "B.Cu" "B.Mask" "B.Paste")
			(net "P12V_MEM_CPU1")
		)
		(pad "2" smd rect
			(at -0.889 0)
			(size 1.016 1.27)
			(layers "B.Cu" "B.Mask" "B.Paste")
			(net "GND")
		)
	)
	(footprint ""
		(layer "B.Cu")
		(at 96.575118 -338.968842 -90)
		(property "Reference" "PC429_5"
			(at 0 0 90)
			(layer "B.SilkS")
			(hide yes)
			(effects
				(font
					(size 1.27 1.27)
				)
				(justify mirror)
			)
		)
		(property "Value" ""
			(at 0 0 90)
			(layer "B.Fab")
			(effects
				(font
					(size 1.27 1.27)
				)
				(justify mirror)
			)
		)
		(duplicate_pad_numbers_are_jumpers no)
		(fp_line
			(start -1.524 0.762)
			(end 1.524 0.762)
			(stroke
				(width 0.1524)
				(type default)
			)
			(layer "B.SilkS")
		)
		(fp_line
			(start 1.524 0.762)
			(end 1.524 -0.762)
			(stroke
				(width 0.1524)
				(type default)
			)
			(layer "B.SilkS")
		)
		(fp_line
			(start -1.524 -0.762)
			(end -1.524 0.762)
			(stroke
				(width 0.1524)
				(type default)
			)
			(layer "B.SilkS")
		)
		(fp_line
			(start 1.524 -0.762)
			(end -1.524 -0.762)
			(stroke
				(width 0.1524)
				(type default)
			)
			(layer "B.SilkS")
		)
		(fp_line
			(start -1.1049 0.724916)
			(end -1.1049 -0.724916)
			(stroke
				(width 0.1)
				(type default)
			)
			(layer "B.Fab")
		)
		(fp_line
			(start 1.1049 0.724916)
			(end -1.1049 0.724916)
			(stroke
				(width 0.1)
				(type default)
			)
			(layer "B.Fab")
		)
		(fp_line
			(start -1.1049 -0.724916)
			(end 1.1049 -0.724916)
			(stroke
				(width 0.1)
				(type default)
			)
			(layer "B.Fab")
		)
		(fp_line
			(start 1.1049 -0.724916)
			(end 1.1049 0.724916)
			(stroke
				(width 0.1)
				(type default)
			)
			(layer "B.Fab")
		)
		(pad "1" smd rect
			(at 0.889 0 270)
			(size 1.016 1.27)
			(layers "B.Cu" "B.Mask" "B.Paste")
			(net "SW_P12V_AUX_PVDDCR_CPU1_P1_FLT")
		)
		(pad "2" smd rect
			(at -0.889 0 270)
			(size 1.016 1.27)
			(layers "B.Cu" "B.Mask" "B.Paste")
			(net "GND")
		)
	)
	(footprint ""
		(layer "B.Cu")
		(at 358.389174 -398.455134 180)
		(property "Reference" "C628"
			(at 0 0 0)
			(layer "B.SilkS")
			(hide yes)
			(effects
				(font
					(size 1.27 1.27)
				)
				(justify mirror)
			)
		)
		(property "Value" ""
			(at 0 0 0)
			(layer "B.Fab")
			(effects
				(font
					(size 1.27 1.27)
				)
				(justify mirror)
			)
		)
		(duplicate_pad_numbers_are_jumpers no)
		(fp_line
			(start 1.524 0.762)
			(end 1.524 -0.762)
			(stroke
				(width 0.1524)
				(type default)
			)
			(layer "B.SilkS")
		)
		(fp_line
			(start 1.524 -0.762)
			(end -1.524 -0.762)
			(stroke
				(width 0.1524)
				(type default)
			)
			(layer "B.SilkS")
		)
		(fp_line
			(start -1.524 0.762)
			(end 1.524 0.762)
			(stroke
				(width 0.1524)
				(type default)
			)
			(layer "B.SilkS")
		)
		(fp_line
			(start -1.524 -0.762)
			(end -1.524 0.762)
			(stroke
				(width 0.1524)
				(type default)
			)
			(layer "B.SilkS")
		)
		(fp_line
			(start 1.1049 0.724916)
			(end -1.1049 0.724916)
			(stroke
				(width 0.1)
				(type default)
			)
			(layer "B.Fab")
		)
		(fp_line
			(start 1.1049 -0.724916)
			(end 1.1049 0.724916)
			(stroke
				(width 0.1)
				(type default)
			)
			(layer "B.Fab")
		)
		(fp_line
			(start -1.1049 0.724916)
			(end -1.1049 -0.724916)
			(stroke
				(width 0.1)
				(type default)
			)
			(layer "B.Fab")
		)
		(fp_line
			(start -1.1049 -0.724916)
			(end 1.1049 -0.724916)
			(stroke
				(width 0.1)
				(type default)
			)
			(layer "B.Fab")
		)
		(pad "1" smd rect
			(at 0.889 0 180)
			(size 1.016 1.27)
			(layers "B.Cu" "B.Mask" "B.Paste")
			(net "P0V9_CPU0_RT1_2A")
		)
		(pad "2" smd rect
			(at -0.889 0 180)
			(size 1.016 1.27)
			(layers "B.Cu" "B.Mask" "B.Paste")
			(net "GND")
		)
	)
	(footprint ""
		(layer "B.Cu")
		(at 366.312958 -245.487952 180)
		(property "Reference" "C277"
			(at 0 0 0)
			(layer "B.SilkS")
			(hide yes)
			(effects
				(font
					(size 1.27 1.27)
				)
				(justify mirror)
			)
		)
		(property "Value" ""
			(at 0 0 0)
			(layer "B.Fab")
			(effects
				(font
					(size 1.27 1.27)
				)
				(justify mirror)
			)
		)
		(duplicate_pad_numbers_are_jumpers no)
		(fp_line
			(start 0.7874 0.4064)
			(end 0.7874 -0.4064)
			(stroke
				(width 0.1524)
				(type default)
			)
			(layer "B.SilkS")
		)
		(fp_line
			(start 0.7874 -0.4064)
			(end -0.7874 -0.4064)
			(stroke
				(width 0.1524)
				(type default)
			)
			(layer "B.SilkS")
		)
		(fp_line
			(start -0.7874 0.4064)
			(end 0.7874 0.4064)
			(stroke
				(width 0.1524)
				(type default)
			)
			(layer "B.SilkS")
		)
		(fp_line
			(start -0.7874 -0.4064)
			(end -0.7874 0.4064)
			(stroke
				(width 0.1524)
				(type default)
			)
			(layer "B.SilkS")
		)
		(fp_line
			(start 0.67945 0.3048)
			(end 0.67945 -0.305054)
			(stroke
				(width 0.1)
				(type default)
			)
			(layer "B.Fab")
		)
		(fp_line
			(start 0.67945 -0.305054)
			(end 0.12065 -0.305054)
			(stroke
				(width 0.1)
				(type default)
			)
			(layer "B.Fab")
		)
		(fp_line
			(start 0.12065 0.3048)
			(end 0.67945 0.3048)
			(stroke
				(width 0.1)
				(type default)
			)
			(layer "B.Fab")
		)
		(fp_line
			(start 0.12065 0.2794)
			(end 0.12065 0.3048)
			(stroke
				(width 0.1)
				(type default)
			)
			(layer "B.Fab")
		)
		(fp_line
			(start 0.12065 -0.2794)
			(end -0.12065 -0.2794)
			(stroke
				(width 0.1)
				(type default)
			)
			(layer "B.Fab")
		)
		(fp_line
			(start 0.12065 -0.305054)
			(end 0.12065 -0.2794)
			(stroke
				(width 0.1)
				(type default)
			)
			(layer "B.Fab")
		)
		(fp_line
			(start -0.120396 0.3048)
			(end -0.120396 0.2794)
			(stroke
				(width 0.1)
				(type default)
			)
			(layer "B.Fab")
		)
		(fp_line
			(start -0.120396 0.2794)
			(end 0.12065 0.2794)
			(stroke
				(width 0.1)
				(type default)
			)
			(layer "B.Fab")
		)
		(fp_line
			(start -0.12065 -0.2794)
			(end -0.12065 -0.3048)
			(stroke
				(width 0.1)
				(type default)
			)
			(layer "B.Fab")
		)
		(fp_line
			(start -0.12065 -0.3048)
			(end -0.67945 -0.3048)
			(stroke
				(width 0.1)
				(type default)
			)
			(layer "B.Fab")
		)
		(fp_line
			(start -0.67945 0.3048)
			(end -0.120396 0.3048)
			(stroke
				(width 0.1)
				(type default)
			)
			(layer "B.Fab")
		)
		(fp_line
			(start -0.67945 -0.3048)
			(end -0.67945 0.3048)
			(stroke
				(width 0.1)
				(type default)
			)
			(layer "B.Fab")
		)
		(pad "1" smd circle
			(at 0.40005 0)
			(size 0 0)
			(layers "B.Cu" "B.Mask" "B.Paste")
			(net "PVDDCR_CPU0_P0")
		)
		(pad "2" smd circle
			(at -0.40005 0)
			(size 0 0)
			(layers "B.Cu" "B.Mask" "B.Paste")
			(net "GND")
		)
	)
	(footprint ""
		(layer "B.Cu")
		(at 132.61848 -388.011162 -90)
		(property "Reference" "C495"
			(at 0 0 90)
			(layer "B.SilkS")
			(hide yes)
			(effects
				(font
					(size 1.27 1.27)
				)
				(justify mirror)
			)
		)
		(property "Value" ""
			(at 0 0 90)
			(layer "B.Fab")
			(effects
				(font
					(size 1.27 1.27)
				)
				(justify mirror)
			)
		)
		(duplicate_pad_numbers_are_jumpers no)
		(fp_line
			(start -0.299974 0.150114)
			(end 0.299974 0.150114)
			(stroke
				(width 0.1)
				(type default)
			)
			(layer "B.Fab")
		)
		(fp_line
			(start 0.299974 0.150114)
			(end 0.299974 -0.150114)
			(stroke
				(width 0.1)
				(type default)
			)
			(layer "B.Fab")
		)
		(fp_line
			(start -0.299974 -0.150114)
			(end -0.299974 0.150114)
			(stroke
				(width 0.1)
				(type default)
			)
			(layer "B.Fab")
		)
		(fp_line
			(start 0.299974 -0.150114)
			(end -0.299974 -0.150114)
			(stroke
				(width 0.1)
				(type default)
			)
			(layer "B.Fab")
		)
		(pad "1" smd rect
			(at 0.2667 0 90)
			(size 0.3048 0.381)
			(layers "B.Cu" "B.Mask" "B.Paste")
			(net "P0V9_CPU1_RT3_2A")
		)
		(pad "2" smd rect
			(at -0.2667 0 90)
			(size 0.3048 0.381)
			(layers "B.Cu" "B.Mask" "B.Paste")
			(net "GND")
		)
	)
	(footprint ""
		(layer "B.Cu")
		(at 435.549802 -11.088116 180)
		(property "Reference" "C1239"
			(at 0 0 0)
			(layer "B.SilkS")
			(hide yes)
			(effects
				(font
					(size 1.27 1.27)
				)
				(justify mirror)
			)
		)
		(property "Value" ""
			(at 0 0 0)
			(layer "B.Fab")
			(effects
				(font
					(size 1.27 1.27)
				)
				(justify mirror)
			)
		)
		(duplicate_pad_numbers_are_jumpers no)
		(fp_line
			(start 0.7874 0.4064)
			(end 0.7874 -0.4064)
			(stroke
				(width 0.1524)
				(type default)
			)
			(layer "B.SilkS")
		)
		(fp_line
			(start 0.7874 -0.4064)
			(end -0.7874 -0.4064)
			(stroke
				(width 0.1524)
				(type default)
			)
			(layer "B.SilkS")
		)
		(fp_line
			(start -0.7874 0.4064)
			(end 0.7874 0.4064)
			(stroke
				(width 0.1524)
				(type default)
			)
			(layer "B.SilkS")
		)
		(fp_line
			(start -0.7874 -0.4064)
			(end -0.7874 0.4064)
			(stroke
				(width 0.1524)
				(type default)
			)
			(layer "B.SilkS")
		)
		(fp_line
			(start 0.67945 0.3048)
			(end 0.67945 -0.305054)
			(stroke
				(width 0.1)
				(type default)
			)
			(layer "B.Fab")
		)
		(fp_line
			(start 0.67945 -0.305054)
			(end 0.12065 -0.305054)
			(stroke
				(width 0.1)
				(type default)
			)
			(layer "B.Fab")
		)
		(fp_line
			(start 0.12065 0.3048)
			(end 0.67945 0.3048)
			(stroke
				(width 0.1)
				(type default)
			)
			(layer "B.Fab")
		)
		(fp_line
			(start 0.12065 0.2794)
			(end 0.12065 0.3048)
			(stroke
				(width 0.1)
				(type default)
			)
			(layer "B.Fab")
		)
		(fp_line
			(start 0.12065 -0.2794)
			(end -0.12065 -0.2794)
			(stroke
				(width 0.1)
				(type default)
			)
			(layer "B.Fab")
		)
		(fp_line
			(start 0.12065 -0.305054)
			(end 0.12065 -0.2794)
			(stroke
				(width 0.1)
				(type default)
			)
			(layer "B.Fab")
		)
		(fp_line
			(start -0.120396 0.3048)
			(end -0.120396 0.2794)
			(stroke
				(width 0.1)
				(type default)
			)
			(layer "B.Fab")
		)
		(fp_line
			(start -0.120396 0.2794)
			(end 0.12065 0.2794)
			(stroke
				(width 0.1)
				(type default)
			)
			(layer "B.Fab")
		)
		(fp_line
			(start -0.12065 -0.2794)
			(end -0.12065 -0.3048)
			(stroke
				(width 0.1)
				(type default)
			)
			(layer "B.Fab")
		)
		(fp_line
			(start -0.12065 -0.3048)
			(end -0.67945 -0.3048)
			(stroke
				(width 0.1)
				(type default)
			)
			(layer "B.Fab")
		)
		(fp_line
			(start -0.67945 0.3048)
			(end -0.120396 0.3048)
			(stroke
				(width 0.1)
				(type default)
			)
			(layer "B.Fab")
		)
		(fp_line
			(start -0.67945 -0.3048)
			(end -0.67945 0.3048)
			(stroke
				(width 0.1)
				(type default)
			)
			(layer "B.Fab")
		)
		(pad "1" smd circle
			(at 0.40005 0)
			(size 0 0)
			(layers "B.Cu" "B.Mask" "B.Paste")
			(net "P3V3_OCP_SFF")
		)
		(pad "2" smd circle
			(at -0.40005 0)
			(size 0 0)
			(layers "B.Cu" "B.Mask" "B.Paste")
			(net "GND")
		)
	)
	(footprint ""
		(layer "B.Cu")
		(at 189.865 -97.119948 -90)
		(property "Reference" "R185"
			(at 0 0 90)
			(layer "B.SilkS")
			(hide yes)
			(effects
				(font
					(size 1.27 1.27)
				)
				(justify mirror)
			)
		)
		(property "Value" ""
			(at 0 0 90)
			(layer "B.Fab")
			(effects
				(font
					(size 1.27 1.27)
				)
				(justify mirror)
			)
		)
		(duplicate_pad_numbers_are_jumpers no)
		(fp_line
			(start -0.7874 0.4064)
			(end 0.7874 0.4064)
			(stroke
				(width 0.1524)
				(type default)
			)
			(layer "B.SilkS")
		)
		(fp_line
			(start 0.7874 0.4064)
			(end 0.7874 -0.4064)
			(stroke
				(width 0.1524)
				(type default)
			)
			(layer "B.SilkS")
		)
		(fp_line
			(start -0.7874 -0.4064)
			(end -0.7874 0.4064)
			(stroke
				(width 0.1524)
				(type default)
			)
			(layer "B.SilkS")
		)
		(fp_line
			(start 0.7874 -0.4064)
			(end -0.7874 -0.4064)
			(stroke
				(width 0.1524)
				(type default)
			)
			(layer "B.SilkS")
		)
		(fp_line
			(start -0.67945 0.3048)
			(end -0.120396 0.3048)
			(stroke
				(width 0.1)
				(type default)
			)
			(layer "B.Fab")
		)
		(fp_line
			(start -0.120396 0.3048)
			(end -0.120396 0.2794)
			(stroke
				(width 0.1)
				(type default)
			)
			(layer "B.Fab")
		)
		(fp_line
			(start 0.12065 0.3048)
			(end 0.67945 0.3048)
			(stroke
				(width 0.1)
				(type default)
			)
			(layer "B.Fab")
		)
		(fp_line
			(start 0.67945 0.3048)
			(end 0.67945 -0.305054)
			(stroke
				(width 0.1)
				(type default)
			)
			(layer "B.Fab")
		)
		(fp_line
			(start -0.120396 0.2794)
			(end 0.12065 0.2794)
			(stroke
				(width 0.1)
				(type default)
			)
			(layer "B.Fab")
		)
		(fp_line
			(start 0.12065 0.2794)
			(end 0.12065 0.3048)
			(stroke
				(width 0.1)
				(type default)
			)
			(layer "B.Fab")
		)
		(fp_line
			(start -0.12065 -0.2794)
			(end -0.12065 -0.3048)
			(stroke
				(width 0.1)
				(type default)
			)
			(layer "B.Fab")
		)
		(fp_line
			(start 0.12065 -0.2794)
			(end -0.12065 -0.2794)
			(stroke
				(width 0.1)
				(type default)
			)
			(layer "B.Fab")
		)
		(fp_line
			(start -0.67945 -0.3048)
			(end -0.67945 0.3048)
			(stroke
				(width 0.1)
				(type default)
			)
			(layer "B.Fab")
		)
		(fp_line
			(start -0.12065 -0.3048)
			(end -0.67945 -0.3048)
			(stroke
				(width 0.1)
				(type default)
			)
			(layer "B.Fab")
		)
		(fp_line
			(start 0.12065 -0.305054)
			(end 0.12065 -0.2794)
			(stroke
				(width 0.1)
				(type default)
			)
			(layer "B.Fab")
		)
		(fp_line
			(start 0.67945 -0.305054)
			(end 0.12065 -0.305054)
			(stroke
				(width 0.1)
				(type default)
			)
			(layer "B.Fab")
		)
		(pad "1" smd circle
			(at 0.40005 0 90)
			(size 0 0)
			(layers "B.Cu" "B.Mask" "B.Paste")
			(net "CPU0_CORETYPE2")
		)
		(pad "2" smd circle
			(at -0.40005 0 90)
			(size 0 0)
			(layers "B.Cu" "B.Mask" "B.Paste")
			(net "FM_CPU0_CORETYPE2")
		)
	)
	(footprint ""
		(layer "B.Cu")
		(at 61.413898 -15.58036 90)
		(property "Reference" "R3216"
			(at 0 0 90)
			(layer "B.SilkS")
			(hide yes)
			(effects
				(font
					(size 1.27 1.27)
				)
				(justify mirror)
			)
		)
		(property "Value" ""
			(at 0 0 90)
			(layer "B.Fab")
			(effects
				(font
					(size 1.27 1.27)
				)
				(justify mirror)
			)
		)
		(duplicate_pad_numbers_are_jumpers no)
		(fp_line
			(start 0.7874 -0.4064)
			(end -0.7874 -0.4064)
			(stroke
				(width 0.1524)
				(type default)
			)
			(layer "B.SilkS")
		)
		(fp_line
			(start -0.7874 -0.4064)
			(end -0.7874 0.4064)
			(stroke
				(width 0.1524)
				(type default)
			)
			(layer "B.SilkS")
		)
		(fp_line
			(start 0.7874 0.4064)
			(end 0.7874 -0.4064)
			(stroke
				(width 0.1524)
				(type default)
			)
			(layer "B.SilkS")
		)
		(fp_line
			(start -0.7874 0.4064)
			(end 0.7874 0.4064)
			(stroke
				(width 0.1524)
				(type default)
			)
			(layer "B.SilkS")
		)
		(fp_line
			(start 0.67945 -0.305054)
			(end 0.12065 -0.305054)
			(stroke
				(width 0.1)
				(type default)
			)
			(layer "B.Fab")
		)
		(fp_line
			(start 0.12065 -0.305054)
			(end 0.12065 -0.2794)
			(stroke
				(width 0.1)
				(type default)
			)
			(layer "B.Fab")
		)
		(fp_line
			(start -0.12065 -0.3048)
			(end -0.67945 -0.3048)
			(stroke
				(width 0.1)
				(type default)
			)
			(layer "B.Fab")
		)
		(fp_line
			(start -0.67945 -0.3048)
			(end -0.67945 0.3048)
			(stroke
				(width 0.1)
				(type default)
			)
			(layer "B.Fab")
		)
		(fp_line
			(start 0.12065 -0.2794)
			(end -0.12065 -0.2794)
			(stroke
				(width 0.1)
				(type default)
			)
			(layer "B.Fab")
		)
		(fp_line
			(start -0.12065 -0.2794)
			(end -0.12065 -0.3048)
			(stroke
				(width 0.1)
				(type default)
			)
			(layer "B.Fab")
		)
		(fp_line
			(start 0.12065 0.2794)
			(end 0.12065 0.3048)
			(stroke
				(width 0.1)
				(type default)
			)
			(layer "B.Fab")
		)
		(fp_line
			(start -0.120396 0.2794)
			(end 0.12065 0.2794)
			(stroke
				(width 0.1)
				(type default)
			)
			(layer "B.Fab")
		)
		(fp_line
			(start 0.67945 0.3048)
			(end 0.67945 -0.305054)
			(stroke
				(width 0.1)
				(type default)
			)
			(layer "B.Fab")
		)
		(fp_line
			(start 0.12065 0.3048)
			(end 0.67945 0.3048)
			(stroke
				(width 0.1)
				(type default)
			)
			(layer "B.Fab")
		)
		(fp_line
			(start -0.120396 0.3048)
			(end -0.120396 0.2794)
			(stroke
				(width 0.1)
				(type default)
			)
			(layer "B.Fab")
		)
		(fp_line
			(start -0.67945 0.3048)
			(end -0.120396 0.3048)
			(stroke
				(width 0.1)
				(type default)
			)
			(layer "B.Fab")
		)
		(pad "1" smd circle
			(at 0.40005 0 270)
			(size 0 0)
			(layers "B.Cu" "B.Mask" "B.Paste")
			(net "OCP_V3_2_ISO_BIF1_EN")
		)
		(pad "2" smd circle
			(at -0.40005 0 270)
			(size 0 0)
			(layers "B.Cu" "B.Mask" "B.Paste")
			(net "GND")
		)
	)
	(footprint ""
		(layer "B.Cu")
		(at 22.70506 -244.085364 180)
		(property "Reference" "R505"
			(at 0 0 0)
			(layer "B.SilkS")
			(hide yes)
			(effects
				(font
					(size 1.27 1.27)
				)
				(justify mirror)
			)
		)
		(property "Value" ""
			(at 0 0 0)
			(layer "B.Fab")
			(effects
				(font
					(size 1.27 1.27)
				)
				(justify mirror)
			)
		)
		(duplicate_pad_numbers_are_jumpers no)
		(fp_line
			(start 0.7874 0.4064)
			(end 0.7874 -0.4064)
			(stroke
				(width 0.1524)
				(type default)
			)
			(layer "B.SilkS")
		)
		(fp_line
			(start 0.7874 -0.4064)
			(end -0.7874 -0.4064)
			(stroke
				(width 0.1524)
				(type default)
			)
			(layer "B.SilkS")
		)
		(fp_line
			(start -0.7874 0.4064)
			(end 0.7874 0.4064)
			(stroke
				(width 0.1524)
				(type default)
			)
			(layer "B.SilkS")
		)
		(fp_line
			(start -0.7874 -0.4064)
			(end -0.7874 0.4064)
			(stroke
				(width 0.1524)
				(type default)
			)
			(layer "B.SilkS")
		)
		(fp_line
			(start 0.67945 0.3048)
			(end 0.67945 -0.305054)
			(stroke
				(width 0.1)
				(type default)
			)
			(layer "B.Fab")
		)
		(fp_line
			(start 0.67945 -0.305054)
			(end 0.12065 -0.305054)
			(stroke
				(width 0.1)
				(type default)
			)
			(layer "B.Fab")
		)
		(fp_line
			(start 0.12065 0.3048)
			(end 0.67945 0.3048)
			(stroke
				(width 0.1)
				(type default)
			)
			(layer "B.Fab")
		)
		(fp_line
			(start 0.12065 0.2794)
			(end 0.12065 0.3048)
			(stroke
				(width 0.1)
				(type default)
			)
			(layer "B.Fab")
		)
		(fp_line
			(start 0.12065 -0.2794)
			(end -0.12065 -0.2794)
			(stroke
				(width 0.1)
				(type default)
			)
			(layer "B.Fab")
		)
		(fp_line
			(start 0.12065 -0.305054)
			(end 0.12065 -0.2794)
			(stroke
				(width 0.1)
				(type default)
			)
			(layer "B.Fab")
		)
		(fp_line
			(start -0.120396 0.3048)
			(end -0.120396 0.2794)
			(stroke
				(width 0.1)
				(type default)
			)
			(layer "B.Fab")
		)
		(fp_line
			(start -0.120396 0.2794)
			(end 0.12065 0.2794)
			(stroke
				(width 0.1)
				(type default)
			)
			(layer "B.Fab")
		)
		(fp_line
			(start -0.12065 -0.2794)
			(end -0.12065 -0.3048)
			(stroke
				(width 0.1)
				(type default)
			)
			(layer "B.Fab")
		)
		(fp_line
			(start -0.12065 -0.3048)
			(end -0.67945 -0.3048)
			(stroke
				(width 0.1)
				(type default)
			)
			(layer "B.Fab")
		)
		(fp_line
			(start -0.67945 0.3048)
			(end -0.120396 0.3048)
			(stroke
				(width 0.1)
				(type default)
			)
			(layer "B.Fab")
		)
		(fp_line
			(start -0.67945 -0.3048)
			(end -0.67945 0.3048)
			(stroke
				(width 0.1)
				(type default)
			)
			(layer "B.Fab")
		)
		(pad "1" smd circle
			(at 0.40005 0)
			(size 0 0)
			(layers "B.Cu" "B.Mask" "B.Paste")
			(net "M_F_CPU1_ALERT_N")
		)
		(pad "2" smd circle
			(at -0.40005 0)
			(size 0 0)
			(layers "B.Cu" "B.Mask" "B.Paste")
			(net "M_F_CPU1_ALERT_R_N")
		)
	)
	(footprint ""
		(layer "B.Cu")
		(at 26.206958 -382.874012 -90)
		(property "Reference" "PC6807"
			(at 0 0 90)
			(layer "B.SilkS")
			(hide yes)
			(effects
				(font
					(size 1.27 1.27)
				)
				(justify mirror)
			)
		)
		(property "Value" ""
			(at 0 0 90)
			(layer "B.Fab")
			(effects
				(font
					(size 1.27 1.27)
				)
				(justify mirror)
			)
		)
		(duplicate_pad_numbers_are_jumpers no)
		(fp_line
			(start -0.7874 0.4064)
			(end 0.7874 0.4064)
			(stroke
				(width 0.1524)
				(type default)
			)
			(layer "B.SilkS")
		)
		(fp_line
			(start 0.7874 0.4064)
			(end 0.7874 -0.4064)
			(stroke
				(width 0.1524)
				(type default)
			)
			(layer "B.SilkS")
		)
		(fp_line
			(start -0.7874 -0.4064)
			(end -0.7874 0.4064)
			(stroke
				(width 0.1524)
				(type default)
			)
			(layer "B.SilkS")
		)
		(fp_line
			(start 0.7874 -0.4064)
			(end -0.7874 -0.4064)
			(stroke
				(width 0.1524)
				(type default)
			)
			(layer "B.SilkS")
		)
		(fp_line
			(start -0.67945 0.3048)
			(end -0.120396 0.3048)
			(stroke
				(width 0.1)
				(type default)
			)
			(layer "B.Fab")
		)
		(fp_line
			(start -0.120396 0.3048)
			(end -0.120396 0.2794)
			(stroke
				(width 0.1)
				(type default)
			)
			(layer "B.Fab")
		)
		(fp_line
			(start 0.12065 0.3048)
			(end 0.67945 0.3048)
			(stroke
				(width 0.1)
				(type default)
			)
			(layer "B.Fab")
		)
		(fp_line
			(start 0.67945 0.3048)
			(end 0.67945 -0.305054)
			(stroke
				(width 0.1)
				(type default)
			)
			(layer "B.Fab")
		)
		(fp_line
			(start -0.120396 0.2794)
			(end 0.12065 0.2794)
			(stroke
				(width 0.1)
				(type default)
			)
			(layer "B.Fab")
		)
		(fp_line
			(start 0.12065 0.2794)
			(end 0.12065 0.3048)
			(stroke
				(width 0.1)
				(type default)
			)
			(layer "B.Fab")
		)
		(fp_line
			(start -0.12065 -0.2794)
			(end -0.12065 -0.3048)
			(stroke
				(width 0.1)
				(type default)
			)
			(layer "B.Fab")
		)
		(fp_line
			(start 0.12065 -0.2794)
			(end -0.12065 -0.2794)
			(stroke
				(width 0.1)
				(type default)
			)
			(layer "B.Fab")
		)
		(fp_line
			(start -0.67945 -0.3048)
			(end -0.67945 0.3048)
			(stroke
				(width 0.1)
				(type default)
			)
			(layer "B.Fab")
		)
		(fp_line
			(start -0.12065 -0.3048)
			(end -0.67945 -0.3048)
			(stroke
				(width 0.1)
				(type default)
			)
			(layer "B.Fab")
		)
		(fp_line
			(start 0.12065 -0.305054)
			(end 0.12065 -0.2794)
			(stroke
				(width 0.1)
				(type default)
			)
			(layer "B.Fab")
		)
		(fp_line
			(start 0.67945 -0.305054)
			(end 0.12065 -0.305054)
			(stroke
				(width 0.1)
				(type default)
			)
			(layer "B.Fab")
		)
		(pad "1" smd circle
			(at 0.40005 0 90)
			(size 0 0)
			(layers "B.Cu" "B.Mask" "B.Paste")
			(net "P0V9_CPU1_RT_2D")
		)
		(pad "2" smd circle
			(at -0.40005 0 90)
			(size 0 0)
			(layers "B.Cu" "B.Mask" "B.Paste")
			(net "GND")
		)
	)
	(footprint ""
		(layer "B.Cu")
		(at 350.318832 -259.729986 180)
		(property "Reference" "C2611"
			(at 0 0 0)
			(layer "B.SilkS")
			(hide yes)
			(effects
				(font
					(size 1.27 1.27)
				)
				(justify mirror)
			)
		)
		(property "Value" ""
			(at 0 0 0)
			(layer "B.Fab")
			(effects
				(font
					(size 1.27 1.27)
				)
				(justify mirror)
			)
		)
		(duplicate_pad_numbers_are_jumpers no)
		(fp_line
			(start 0.7874 0.4064)
			(end 0.7874 -0.4064)
			(stroke
				(width 0.1524)
				(type default)
			)
			(layer "B.SilkS")
		)
		(fp_line
			(start 0.7874 -0.4064)
			(end -0.7874 -0.4064)
			(stroke
				(width 0.1524)
				(type default)
			)
			(layer "B.SilkS")
		)
		(fp_line
			(start -0.7874 0.4064)
			(end 0.7874 0.4064)
			(stroke
				(width 0.1524)
				(type default)
			)
			(layer "B.SilkS")
		)
		(fp_line
			(start -0.7874 -0.4064)
			(end -0.7874 0.4064)
			(stroke
				(width 0.1524)
				(type default)
			)
			(layer "B.SilkS")
		)
		(fp_line
			(start 0.67945 0.3048)
			(end 0.67945 -0.305054)
			(stroke
				(width 0.1)
				(type default)
			)
			(layer "B.Fab")
		)
		(fp_line
			(start 0.67945 -0.305054)
			(end 0.12065 -0.305054)
			(stroke
				(width 0.1)
				(type default)
			)
			(layer "B.Fab")
		)
		(fp_line
			(start 0.12065 0.3048)
			(end 0.67945 0.3048)
			(stroke
				(width 0.1)
				(type default)
			)
			(layer "B.Fab")
		)
		(fp_line
			(start 0.12065 0.2794)
			(end 0.12065 0.3048)
			(stroke
				(width 0.1)
				(type default)
			)
			(layer "B.Fab")
		)
		(fp_line
			(start 0.12065 -0.2794)
			(end -0.12065 -0.2794)
			(stroke
				(width 0.1)
				(type default)
			)
			(layer "B.Fab")
		)
		(fp_line
			(start 0.12065 -0.305054)
			(end 0.12065 -0.2794)
			(stroke
				(width 0.1)
				(type default)
			)
			(layer "B.Fab")
		)
		(fp_line
			(start -0.120396 0.3048)
			(end -0.120396 0.2794)
			(stroke
				(width 0.1)
				(type default)
			)
			(layer "B.Fab")
		)
		(fp_line
			(start -0.120396 0.2794)
			(end 0.12065 0.2794)
			(stroke
				(width 0.1)
				(type default)
			)
			(layer "B.Fab")
		)
		(fp_line
			(start -0.12065 -0.2794)
			(end -0.12065 -0.3048)
			(stroke
				(width 0.1)
				(type default)
			)
			(layer "B.Fab")
		)
		(fp_line
			(start -0.12065 -0.3048)
			(end -0.67945 -0.3048)
			(stroke
				(width 0.1)
				(type default)
			)
			(layer "B.Fab")
		)
		(fp_line
			(start -0.67945 0.3048)
			(end -0.120396 0.3048)
			(stroke
				(width 0.1)
				(type default)
			)
			(layer "B.Fab")
		)
		(fp_line
			(start -0.67945 -0.3048)
			(end -0.67945 0.3048)
			(stroke
				(width 0.1)
				(type default)
			)
			(layer "B.Fab")
		)
		(pad "1" smd circle
			(at 0.40005 0)
			(size 0 0)
			(layers "B.Cu" "B.Mask" "B.Paste")
			(net "PVDDIO_P0")
		)
		(pad "2" smd circle
			(at -0.40005 0)
			(size 0 0)
			(layers "B.Cu" "B.Mask" "B.Paste")
			(net "GND")
		)
	)
	(footprint ""
		(layer "B.Cu")
		(at 156.746194 -388.011162 -90)
		(property "Reference" "C379"
			(at 0 0 90)
			(layer "B.SilkS")
			(hide yes)
			(effects
				(font
					(size 1.27 1.27)
				)
				(justify mirror)
			)
		)
		(property "Value" ""
			(at 0 0 90)
			(layer "B.Fab")
			(effects
				(font
					(size 1.27 1.27)
				)
				(justify mirror)
			)
		)
		(duplicate_pad_numbers_are_jumpers no)
		(fp_line
			(start -0.299974 0.150114)
			(end 0.299974 0.150114)
			(stroke
				(width 0.1)
				(type default)
			)
			(layer "B.Fab")
		)
		(fp_line
			(start 0.299974 0.150114)
			(end 0.299974 -0.150114)
			(stroke
				(width 0.1)
				(type default)
			)
			(layer "B.Fab")
		)
		(fp_line
			(start -0.299974 -0.150114)
			(end -0.299974 0.150114)
			(stroke
				(width 0.1)
				(type default)
			)
			(layer "B.Fab")
		)
		(fp_line
			(start 0.299974 -0.150114)
			(end -0.299974 -0.150114)
			(stroke
				(width 0.1)
				(type default)
			)
			(layer "B.Fab")
		)
		(pad "1" smd rect
			(at 0.2667 0 90)
			(size 0.3048 0.381)
			(layers "B.Cu" "B.Mask" "B.Paste")
			(net "P1V8_CPU1_RT2_1A")
		)
		(pad "2" smd rect
			(at -0.2667 0 90)
			(size 0.3048 0.381)
			(layers "B.Cu" "B.Mask" "B.Paste")
			(net "GND")
		)
	)
	(footprint ""
		(layer "B.Cu")
		(at 90.209878 -144.88541)
		(property "Reference" "PC247"
			(at 0 0 0)
			(layer "B.SilkS")
			(hide yes)
			(effects
				(font
					(size 1.27 1.27)
				)
				(justify mirror)
			)
		)
		(property "Value" ""
			(at 0 0 0)
			(layer "B.Fab")
			(effects
				(font
					(size 1.27 1.27)
				)
				(justify mirror)
			)
		)
		(duplicate_pad_numbers_are_jumpers no)
		(fp_line
			(start -0.7874 -0.4064)
			(end -0.7874 0.4064)
			(stroke
				(width 0.1524)
				(type default)
			)
			(layer "B.SilkS")
		)
		(fp_line
			(start -0.7874 0.4064)
			(end 0.7874 0.4064)
			(stroke
				(width 0.1524)
				(type default)
			)
			(layer "B.SilkS")
		)
		(fp_line
			(start 0.7874 -0.4064)
			(end -0.7874 -0.4064)
			(stroke
				(width 0.1524)
				(type default)
			)
			(layer "B.SilkS")
		)
		(fp_line
			(start 0.7874 0.4064)
			(end 0.7874 -0.4064)
			(stroke
				(width 0.1524)
				(type default)
			)
			(layer "B.SilkS")
		)
		(fp_line
			(start -0.67945 -0.3048)
			(end -0.67945 0.3048)
			(stroke
				(width 0.1)
				(type default)
			)
			(layer "B.Fab")
		)
		(fp_line
			(start -0.67945 0.3048)
			(end -0.120396 0.3048)
			(stroke
				(width 0.1)
				(type default)
			)
			(layer "B.Fab")
		)
		(fp_line
			(start -0.12065 -0.3048)
			(end -0.67945 -0.3048)
			(stroke
				(width 0.1)
				(type default)
			)
			(layer "B.Fab")
		)
		(fp_line
			(start -0.12065 -0.2794)
			(end -0.12065 -0.3048)
			(stroke
				(width 0.1)
				(type default)
			)
			(layer "B.Fab")
		)
		(fp_line
			(start -0.120396 0.2794)
			(end 0.12065 0.2794)
			(stroke
				(width 0.1)
				(type default)
			)
			(layer "B.Fab")
		)
		(fp_line
			(start -0.120396 0.3048)
			(end -0.120396 0.2794)
			(stroke
				(width 0.1)
				(type default)
			)
			(layer "B.Fab")
		)
		(fp_line
			(start 0.12065 -0.305054)
			(end 0.12065 -0.2794)
			(stroke
				(width 0.1)
				(type default)
			)
			(layer "B.Fab")
		)
		(fp_line
			(start 0.12065 -0.2794)
			(end -0.12065 -0.2794)
			(stroke
				(width 0.1)
				(type default)
			)
			(layer "B.Fab")
		)
		(fp_line
			(start 0.12065 0.2794)
			(end 0.12065 0.3048)
			(stroke
				(width 0.1)
				(type default)
			)
			(layer "B.Fab")
		)
		(fp_line
			(start 0.12065 0.3048)
			(end 0.67945 0.3048)
			(stroke
				(width 0.1)
				(type default)
			)
			(layer "B.Fab")
		)
		(fp_line
			(start 0.67945 -0.305054)
			(end 0.12065 -0.305054)
			(stroke
				(width 0.1)
				(type default)
			)
			(layer "B.Fab")
		)
		(fp_line
			(start 0.67945 0.3048)
			(end 0.67945 -0.305054)
			(stroke
				(width 0.1)
				(type default)
			)
			(layer "B.Fab")
		)
		(pad "1" smd circle
			(at 0.40005 0 180)
			(size 0 0)
			(layers "B.Cu" "B.Mask" "B.Paste")
			(net "PVDD18_S5_P1")
		)
		(pad "2" smd circle
			(at -0.40005 0 180)
			(size 0 0)
			(layers "B.Cu" "B.Mask" "B.Paste")
			(net "GND")
		)
	)
	(footprint ""
		(layer "B.Cu")
		(at 408.721814 -151.614124 90)
		(property "Reference" "PC1852"
			(at 0 0 90)
			(layer "B.SilkS")
			(hide yes)
			(effects
				(font
					(size 1.27 1.27)
				)
				(justify mirror)
			)
		)
		(property "Value" ""
			(at 0 0 90)
			(layer "B.Fab")
			(effects
				(font
					(size 1.27 1.27)
				)
				(justify mirror)
			)
		)
		(duplicate_pad_numbers_are_jumpers no)
		(fp_line
			(start 0.7874 -0.4064)
			(end -0.7874 -0.4064)
			(stroke
				(width 0.1524)
				(type default)
			)
			(layer "B.SilkS")
		)
		(fp_line
			(start -0.7874 -0.4064)
			(end -0.7874 0.4064)
			(stroke
				(width 0.1524)
				(type default)
			)
			(layer "B.SilkS")
		)
		(fp_line
			(start 0.7874 0.4064)
			(end 0.7874 -0.4064)
			(stroke
				(width 0.1524)
				(type default)
			)
			(layer "B.SilkS")
		)
		(fp_line
			(start -0.7874 0.4064)
			(end 0.7874 0.4064)
			(stroke
				(width 0.1524)
				(type default)
			)
			(layer "B.SilkS")
		)
		(fp_line
			(start 0.67945 -0.305054)
			(end 0.12065 -0.305054)
			(stroke
				(width 0.1)
				(type default)
			)
			(layer "B.Fab")
		)
		(fp_line
			(start 0.12065 -0.305054)
			(end 0.12065 -0.2794)
			(stroke
				(width 0.1)
				(type default)
			)
			(layer "B.Fab")
		)
		(fp_line
			(start -0.12065 -0.3048)
			(end -0.67945 -0.3048)
			(stroke
				(width 0.1)
				(type default)
			)
			(layer "B.Fab")
		)
		(fp_line
			(start -0.67945 -0.3048)
			(end -0.67945 0.3048)
			(stroke
				(width 0.1)
				(type default)
			)
			(layer "B.Fab")
		)
		(fp_line
			(start 0.12065 -0.2794)
			(end -0.12065 -0.2794)
			(stroke
				(width 0.1)
				(type default)
			)
			(layer "B.Fab")
		)
		(fp_line
			(start -0.12065 -0.2794)
			(end -0.12065 -0.3048)
			(stroke
				(width 0.1)
				(type default)
			)
			(layer "B.Fab")
		)
		(fp_line
			(start 0.12065 0.2794)
			(end 0.12065 0.3048)
			(stroke
				(width 0.1)
				(type default)
			)
			(layer "B.Fab")
		)
		(fp_line
			(start -0.120396 0.2794)
			(end 0.12065 0.2794)
			(stroke
				(width 0.1)
				(type default)
			)
			(layer "B.Fab")
		)
		(fp_line
			(start 0.67945 0.3048)
			(end 0.67945 -0.305054)
			(stroke
				(width 0.1)
				(type default)
			)
			(layer "B.Fab")
		)
		(fp_line
			(start 0.12065 0.3048)
			(end 0.67945 0.3048)
			(stroke
				(width 0.1)
				(type default)
			)
			(layer "B.Fab")
		)
		(fp_line
			(start -0.120396 0.3048)
			(end -0.120396 0.2794)
			(stroke
				(width 0.1)
				(type default)
			)
			(layer "B.Fab")
		)
		(fp_line
			(start -0.67945 0.3048)
			(end -0.120396 0.3048)
			(stroke
				(width 0.1)
				(type default)
			)
			(layer "B.Fab")
		)
		(pad "1" smd circle
			(at 0.40005 0 270)
			(size 0 0)
			(layers "B.Cu" "B.Mask" "B.Paste")
			(net "P5V_AUX")
		)
		(pad "2" smd circle
			(at -0.40005 0 270)
			(size 0 0)
			(layers "B.Cu" "B.Mask" "B.Paste")
			(net "GND")
		)
	)
	(footprint ""
		(layer "B.Cu")
		(at 352.787712 -343.87409 -90)
		(property "Reference" "PC116_6"
			(at 0 0 90)
			(layer "B.SilkS")
			(hide yes)
			(effects
				(font
					(size 1.27 1.27)
				)
				(justify mirror)
			)
		)
		(property "Value" ""
			(at 0 0 90)
			(layer "B.Fab")
			(effects
				(font
					(size 1.27 1.27)
				)
				(justify mirror)
			)
		)
		(duplicate_pad_numbers_are_jumpers no)
		(fp_line
			(start -1.524 0.762)
			(end 1.524 0.762)
			(stroke
				(width 0.1524)
				(type default)
			)
			(layer "B.SilkS")
		)
		(fp_line
			(start 1.524 0.762)
			(end 1.524 -0.762)
			(stroke
				(width 0.1524)
				(type default)
			)
			(layer "B.SilkS")
		)
		(fp_line
			(start -1.524 -0.762)
			(end -1.524 0.762)
			(stroke
				(width 0.1524)
				(type default)
			)
			(layer "B.SilkS")
		)
		(fp_line
			(start 1.524 -0.762)
			(end -1.524 -0.762)
			(stroke
				(width 0.1524)
				(type default)
			)
			(layer "B.SilkS")
		)
		(fp_line
			(start -1.1049 0.724916)
			(end -1.1049 -0.724916)
			(stroke
				(width 0.1)
				(type default)
			)
			(layer "B.Fab")
		)
		(fp_line
			(start 1.1049 0.724916)
			(end -1.1049 0.724916)
			(stroke
				(width 0.1)
				(type default)
			)
			(layer "B.Fab")
		)
		(fp_line
			(start -1.1049 -0.724916)
			(end 1.1049 -0.724916)
			(stroke
				(width 0.1)
				(type default)
			)
			(layer "B.Fab")
		)
		(fp_line
			(start 1.1049 -0.724916)
			(end 1.1049 0.724916)
			(stroke
				(width 0.1)
				(type default)
			)
			(layer "B.Fab")
		)
		(pad "1" smd rect
			(at 0.889 0 270)
			(size 1.016 1.27)
			(layers "B.Cu" "B.Mask" "B.Paste")
			(net "SW_P12V_AUX_PVDDCR_CPU1_P0_FLT")
		)
		(pad "2" smd rect
			(at -0.889 0 270)
			(size 1.016 1.27)
			(layers "B.Cu" "B.Mask" "B.Paste")
			(net "GND")
		)
	)
	(footprint ""
		(layer "B.Cu")
		(at 116.781834 -272.284952)
		(property "Reference" "C2369"
			(at 0 0 0)
			(layer "B.SilkS")
			(hide yes)
			(effects
				(font
					(size 1.27 1.27)
				)
				(justify mirror)
			)
		)
		(property "Value" ""
			(at 0 0 0)
			(layer "B.Fab")
			(effects
				(font
					(size 1.27 1.27)
				)
				(justify mirror)
			)
		)
		(duplicate_pad_numbers_are_jumpers no)
		(fp_line
			(start -0.7874 -0.4064)
			(end -0.7874 0.4064)
			(stroke
				(width 0.1524)
				(type default)
			)
			(layer "B.SilkS")
		)
		(fp_line
			(start -0.7874 0.4064)
			(end 0.7874 0.4064)
			(stroke
				(width 0.1524)
				(type default)
			)
			(layer "B.SilkS")
		)
		(fp_line
			(start 0.7874 -0.4064)
			(end -0.7874 -0.4064)
			(stroke
				(width 0.1524)
				(type default)
			)
			(layer "B.SilkS")
		)
		(fp_line
			(start 0.7874 0.4064)
			(end 0.7874 -0.4064)
			(stroke
				(width 0.1524)
				(type default)
			)
			(layer "B.SilkS")
		)
		(fp_line
			(start -0.67945 -0.3048)
			(end -0.67945 0.3048)
			(stroke
				(width 0.1)
				(type default)
			)
			(layer "B.Fab")
		)
		(fp_line
			(start -0.67945 0.3048)
			(end -0.120396 0.3048)
			(stroke
				(width 0.1)
				(type default)
			)
			(layer "B.Fab")
		)
		(fp_line
			(start -0.12065 -0.3048)
			(end -0.67945 -0.3048)
			(stroke
				(width 0.1)
				(type default)
			)
			(layer "B.Fab")
		)
		(fp_line
			(start -0.12065 -0.2794)
			(end -0.12065 -0.3048)
			(stroke
				(width 0.1)
				(type default)
			)
			(layer "B.Fab")
		)
		(fp_line
			(start -0.120396 0.2794)
			(end 0.12065 0.2794)
			(stroke
				(width 0.1)
				(type default)
			)
			(layer "B.Fab")
		)
		(fp_line
			(start -0.120396 0.3048)
			(end -0.120396 0.2794)
			(stroke
				(width 0.1)
				(type default)
			)
			(layer "B.Fab")
		)
		(fp_line
			(start 0.12065 -0.305054)
			(end 0.12065 -0.2794)
			(stroke
				(width 0.1)
				(type default)
			)
			(layer "B.Fab")
		)
		(fp_line
			(start 0.12065 -0.2794)
			(end -0.12065 -0.2794)
			(stroke
				(width 0.1)
				(type default)
			)
			(layer "B.Fab")
		)
		(fp_line
			(start 0.12065 0.2794)
			(end 0.12065 0.3048)
			(stroke
				(width 0.1)
				(type default)
			)
			(layer "B.Fab")
		)
		(fp_line
			(start 0.12065 0.3048)
			(end 0.67945 0.3048)
			(stroke
				(width 0.1)
				(type default)
			)
			(layer "B.Fab")
		)
		(fp_line
			(start 0.67945 -0.305054)
			(end 0.12065 -0.305054)
			(stroke
				(width 0.1)
				(type default)
			)
			(layer "B.Fab")
		)
		(fp_line
			(start 0.67945 0.3048)
			(end 0.67945 -0.305054)
			(stroke
				(width 0.1)
				(type default)
			)
			(layer "B.Fab")
		)
		(pad "1" smd circle
			(at 0.40005 0 180)
			(size 0 0)
			(layers "B.Cu" "B.Mask" "B.Paste")
			(net "PVDDCR_CPU1_P1")
		)
		(pad "2" smd circle
			(at -0.40005 0 180)
			(size 0 0)
			(layers "B.Cu" "B.Mask" "B.Paste")
			(net "GND")
		)
	)
	(footprint ""
		(layer "B.Cu")
		(at 427.526958 -342.007952 -90)
		(property "Reference" "PC224_1"
			(at 0 0 90)
			(layer "B.SilkS")
			(hide yes)
			(effects
				(font
					(size 1.27 1.27)
				)
				(justify mirror)
			)
		)
		(property "Value" ""
			(at 0 0 90)
			(layer "B.Fab")
			(effects
				(font
					(size 1.27 1.27)
				)
				(justify mirror)
			)
		)
		(duplicate_pad_numbers_are_jumpers no)
		(fp_line
			(start -1.524 0.762)
			(end 1.524 0.762)
			(stroke
				(width 0.1524)
				(type default)
			)
			(layer "B.SilkS")
		)
		(fp_line
			(start 1.524 0.762)
			(end 1.524 -0.762)
			(stroke
				(width 0.1524)
				(type default)
			)
			(layer "B.SilkS")
		)
		(fp_line
			(start -1.524 -0.762)
			(end -1.524 0.762)
			(stroke
				(width 0.1524)
				(type default)
			)
			(layer "B.SilkS")
		)
		(fp_line
			(start 1.524 -0.762)
			(end -1.524 -0.762)
			(stroke
				(width 0.1524)
				(type default)
			)
			(layer "B.SilkS")
		)
		(fp_line
			(start -1.1049 0.724916)
			(end -1.1049 -0.724916)
			(stroke
				(width 0.1)
				(type default)
			)
			(layer "B.Fab")
		)
		(fp_line
			(start 1.1049 0.724916)
			(end -1.1049 0.724916)
			(stroke
				(width 0.1)
				(type default)
			)
			(layer "B.Fab")
		)
		(fp_line
			(start -1.1049 -0.724916)
			(end 1.1049 -0.724916)
			(stroke
				(width 0.1)
				(type default)
			)
			(layer "B.Fab")
		)
		(fp_line
			(start 1.1049 -0.724916)
			(end 1.1049 0.724916)
			(stroke
				(width 0.1)
				(type default)
			)
			(layer "B.Fab")
		)
		(pad "1" smd rect
			(at 0.889 0 270)
			(size 1.016 1.27)
			(layers "B.Cu" "B.Mask" "B.Paste")
			(net "PVDD11_S3_P0")
		)
		(pad "2" smd rect
			(at -0.889 0 270)
			(size 1.016 1.27)
			(layers "B.Cu" "B.Mask" "B.Paste")
			(net "GND")
		)
	)
	(footprint ""
		(layer "B.Cu")
		(at 182.737252 -97.112836 90)
		(property "Reference" "R1533"
			(at 0 0 90)
			(layer "B.SilkS")
			(hide yes)
			(effects
				(font
					(size 1.27 1.27)
				)
				(justify mirror)
			)
		)
		(property "Value" ""
			(at 0 0 90)
			(layer "B.Fab")
			(effects
				(font
					(size 1.27 1.27)
				)
				(justify mirror)
			)
		)
		(duplicate_pad_numbers_are_jumpers no)
		(fp_line
			(start 0.7874 -0.4064)
			(end -0.7874 -0.4064)
			(stroke
				(width 0.1524)
				(type default)
			)
			(layer "B.SilkS")
		)
		(fp_line
			(start -0.7874 -0.4064)
			(end -0.7874 0.4064)
			(stroke
				(width 0.1524)
				(type default)
			)
			(layer "B.SilkS")
		)
		(fp_line
			(start 0.7874 0.4064)
			(end 0.7874 -0.4064)
			(stroke
				(width 0.1524)
				(type default)
			)
			(layer "B.SilkS")
		)
		(fp_line
			(start -0.7874 0.4064)
			(end 0.7874 0.4064)
			(stroke
				(width 0.1524)
				(type default)
			)
			(layer "B.SilkS")
		)
		(fp_line
			(start 0.67945 -0.305054)
			(end 0.12065 -0.305054)
			(stroke
				(width 0.1)
				(type default)
			)
			(layer "B.Fab")
		)
		(fp_line
			(start 0.12065 -0.305054)
			(end 0.12065 -0.2794)
			(stroke
				(width 0.1)
				(type default)
			)
			(layer "B.Fab")
		)
		(fp_line
			(start -0.12065 -0.3048)
			(end -0.67945 -0.3048)
			(stroke
				(width 0.1)
				(type default)
			)
			(layer "B.Fab")
		)
		(fp_line
			(start -0.67945 -0.3048)
			(end -0.67945 0.3048)
			(stroke
				(width 0.1)
				(type default)
			)
			(layer "B.Fab")
		)
		(fp_line
			(start 0.12065 -0.2794)
			(end -0.12065 -0.2794)
			(stroke
				(width 0.1)
				(type default)
			)
			(layer "B.Fab")
		)
		(fp_line
			(start -0.12065 -0.2794)
			(end -0.12065 -0.3048)
			(stroke
				(width 0.1)
				(type default)
			)
			(layer "B.Fab")
		)
		(fp_line
			(start 0.12065 0.2794)
			(end 0.12065 0.3048)
			(stroke
				(width 0.1)
				(type default)
			)
			(layer "B.Fab")
		)
		(fp_line
			(start -0.120396 0.2794)
			(end 0.12065 0.2794)
			(stroke
				(width 0.1)
				(type default)
			)
			(layer "B.Fab")
		)
		(fp_line
			(start 0.67945 0.3048)
			(end 0.67945 -0.305054)
			(stroke
				(width 0.1)
				(type default)
			)
			(layer "B.Fab")
		)
		(fp_line
			(start 0.12065 0.3048)
			(end 0.67945 0.3048)
			(stroke
				(width 0.1)
				(type default)
			)
			(layer "B.Fab")
		)
		(fp_line
			(start -0.120396 0.3048)
			(end -0.120396 0.2794)
			(stroke
				(width 0.1)
				(type default)
			)
			(layer "B.Fab")
		)
		(fp_line
			(start -0.67945 0.3048)
			(end -0.120396 0.3048)
			(stroke
				(width 0.1)
				(type default)
			)
			(layer "B.Fab")
		)
		(pad "1" smd circle
			(at 0.40005 0 270)
			(size 0 0)
			(layers "B.Cu" "B.Mask" "B.Paste")
			(net "CPU0_THERMTRIP_R_N")
		)
		(pad "2" smd circle
			(at -0.40005 0 270)
			(size 0 0)
			(layers "B.Cu" "B.Mask" "B.Paste")
			(net "CPU1_THERMTRIP_R_N")
		)
	)
	(footprint ""
		(layer "B.Cu")
		(at 389.462264 8.689848 180)
		(property "Reference" "J74"
			(at 4.491482 -1.033526 270)
			(unlocked yes)
			(layer "B.SilkS")
			(effects
				(font
					(size 0.7874 0.5842)
					(thickness 0.1524)
				)
				(justify left mirror)
			)
		)
		(property "Value" ""
			(at 0 0 0)
			(layer "B.Fab")
			(effects
				(font
					(size 1.27 1.27)
				)
				(justify mirror)
			)
		)
		(duplicate_pad_numbers_are_jumpers no)
		(fp_line
			(start 1.2192 2.06756)
			(end 1.2192 -2.06756)
			(stroke
				(width 0.1524)
				(type default)
			)
			(layer "B.SilkS")
		)
		(fp_line
			(start 1.2192 -2.06756)
			(end -1.2192 -2.06756)
			(stroke
				(width 0.1524)
				(type default)
			)
			(layer "B.SilkS")
		)
		(fp_line
			(start -1.2192 2.06756)
			(end 1.2192 2.06756)
			(stroke
				(width 0.1524)
				(type default)
			)
			(layer "B.SilkS")
		)
		(fp_line
			(start -1.2192 -2.06756)
			(end -1.2192 2.06756)
			(stroke
				(width 0.1524)
				(type default)
			)
			(layer "B.SilkS")
		)
		(pad "" np_thru_hole circle
			(at -3.4671 -1.27 90)
			(size 1.0414 1.0414)
			(drill 1.0414)
			(layers "*.Cu" "*.Mask")
			(clearance 0.381)
			(thermal_gap 0.381)
		)
		(pad "" np_thru_hole circle
			(at -3.4671 1.27 90)
			(size 1.0414 1.0414)
			(drill 1.0414)
			(layers "*.Cu" "*.Mask")
			(clearance 0.381)
			(thermal_gap 0.381)
		)
		(pad "" np_thru_hole circle
			(at 2.8829 -1.27 90)
			(size 1.0414 1.0414)
			(drill 1.0414)
			(layers "*.Cu" "*.Mask")
			(clearance 0.381)
			(thermal_gap 0.381)
		)
		(pad "" np_thru_hole circle
			(at 2.8829 1.27 90)
			(size 1.0414 1.0414)
			(drill 1.0414)
			(layers "*.Cu" "*.Mask")
			(clearance 0.381)
			(thermal_gap 0.381)
		)
		(pad "1" smd rect
			(at -0.8255 -0.249936 90)
			(size 0.3048 0.508)
			(layers "B.Cu" "B.Mask" "B.Paste")
			(net "DELTA_L_85_5INCH_IN4_DN")
		)
		(pad "2" smd rect
			(at -0.8255 0.249936 90)
			(size 0.3048 0.508)
			(layers "B.Cu" "B.Mask" "B.Paste")
			(net "DELTA_L_85_5INCH_IN4_DP")
		)
		(pad "3" smd circle
			(at 0 0)
			(size 0 0)
			(layers "B.Cu" "B.Mask" "B.Paste")
			(net "DELTA_L_GND_1")
		)
		(zone
			(layers "F.Cu" "B.Cu" "In1.Cu" "In2.Cu" "In3.Cu" "In4.Cu" "In5.Cu" "In6.Cu"
				"In7.Cu" "In8.Cu" "In9.Cu" "In10.Cu" "In11.Cu" "In12.Cu" "In13.Cu" "In14.Cu"
				"In15.Cu" "In16.Cu"
			)
			(hatch none 0.5)
			(connect_pads
				(clearance 0)
			)
			(min_thickness 0.25)
			(keepout
				(tracks not_allowed)
				(vias allowed)
				(pads allowed)
				(copperpour not_allowed)
				(footprints allowed)
			)
			(placement
				(enabled no)
				(sheetname "")
			)
			(fill
				(thermal_gap 0.5)
				(thermal_bridge_width 0.5)
				(island_removal_mode 0)
			)
			(polygon
				(pts
					(arc
						(start 387.506464 7.419848)
						(mid 385.652264 7.419848)
						(end 387.506464 7.419848)
					)
				)
			)
		)
		(zone
			(layers "F.Cu" "B.Cu" "In1.Cu" "In2.Cu" "In3.Cu" "In4.Cu" "In5.Cu" "In6.Cu"
				"In7.Cu" "In8.Cu" "In9.Cu" "In10.Cu" "In11.Cu" "In12.Cu" "In13.Cu" "In14.Cu"
				"In15.Cu" "In16.Cu"
			)
			(hatch none 0.5)
			(connect_pads
				(clearance 0)
			)
			(min_thickness 0.25)
			(keepout
				(tracks not_allowed)
				(vias allowed)
				(pads allowed)
				(copperpour not_allowed)
				(footprints allowed)
			)
			(placement
				(enabled no)
				(sheetname "")
			)
			(fill
				(thermal_gap 0.5)
				(thermal_bridge_width 0.5)
				(island_removal_mode 0)
			)
			(polygon
				(pts
					(arc
						(start 387.506464 9.959848)
						(mid 385.652264 9.959848)
						(end 387.506464 9.959848)
					)
				)
			)
		)
		(zone
			(layers "F.Cu" "B.Cu" "In1.Cu" "In2.Cu" "In3.Cu" "In4.Cu" "In5.Cu" "In6.Cu"
				"In7.Cu" "In8.Cu" "In9.Cu" "In10.Cu" "In11.Cu" "In12.Cu" "In13.Cu" "In14.Cu"
				"In15.Cu" "In16.Cu"
			)
			(hatch none 0.5)
			(connect_pads
				(clearance 0)
			)
			(min_thickness 0.25)
			(keepout
				(tracks not_allowed)
				(vias allowed)
				(pads allowed)
				(copperpour not_allowed)
				(footprints allowed)
			)
			(placement
				(enabled no)
				(sheetname "")
			)
			(fill
				(thermal_gap 0.5)
				(thermal_bridge_width 0.5)
				(island_removal_mode 0)
			)
			(polygon
				(pts
					(arc
						(start 393.856464 7.419848)
						(mid 392.002264 7.419848)
						(end 393.856464 7.419848)
					)
				)
			)
		)
		(zone
			(layers "F.Cu" "B.Cu" "In1.Cu" "In2.Cu" "In3.Cu" "In4.Cu" "In5.Cu" "In6.Cu"
				"In7.Cu" "In8.Cu" "In9.Cu" "In10.Cu" "In11.Cu" "In12.Cu" "In13.Cu" "In14.Cu"
				"In15.Cu" "In16.Cu"
			)
			(hatch none 0.5)
			(connect_pads
				(clearance 0)
			)
			(min_thickness 0.25)
			(keepout
				(tracks not_allowed)
				(vias allowed)
				(pads allowed)
				(copperpour not_allowed)
				(footprints allowed)
			)
			(placement
				(enabled no)
				(sheetname "")
			)
			(fill
				(thermal_gap 0.5)
				(thermal_bridge_width 0.5)
				(island_removal_mode 0)
			)
			(polygon
				(pts
					(arc
						(start 393.856464 9.959848)
						(mid 392.002264 9.959848)
						(end 393.856464 9.959848)
					)
				)
			)
		)
		(zone
			(layer "B.Cu")
			(hatch none 0.5)
			(connect_pads
				(clearance 0)
			)
			(min_thickness 0.25)
			(keepout
				(tracks not_allowed)
				(vias allowed)
				(pads allowed)
				(copperpour not_allowed)
				(footprints allowed)
			)
			(placement
				(enabled no)
				(sheetname "")
			)
			(fill
				(thermal_gap 0.5)
				(thermal_bridge_width 0.5)
				(island_removal_mode 0)
			)
			(polygon
				(pts
					(xy 390.579864 9.238488) (xy 390.579864 9.142984) (xy 389.982964 9.142984) (xy 389.982964 8.736584)
					(xy 390.579864 8.736584) (xy 390.579864 8.643112) (xy 389.982964 8.643112) (xy 389.982964 8.236712)
					(xy 390.579864 8.236712) (xy 390.579864 8.141208) (xy 389.881364 8.141208) (xy 389.881364 9.238488)
				)
			)
		)
	)
	(footprint ""
		(layer "B.Cu")
		(at 91.762834 -308.606952 90)
		(property "Reference" "PR236"
			(at 0 0 90)
			(layer "B.SilkS")
			(hide yes)
			(effects
				(font
					(size 1.27 1.27)
				)
				(justify mirror)
			)
		)
		(property "Value" ""
			(at 0 0 90)
			(layer "B.Fab")
			(effects
				(font
					(size 1.27 1.27)
				)
				(justify mirror)
			)
		)
		(duplicate_pad_numbers_are_jumpers no)
		(fp_line
			(start 0.7874 -0.4064)
			(end -0.7874 -0.4064)
			(stroke
				(width 0.1524)
				(type default)
			)
			(layer "B.SilkS")
		)
		(fp_line
			(start -0.7874 -0.4064)
			(end -0.7874 0.4064)
			(stroke
				(width 0.1524)
				(type default)
			)
			(layer "B.SilkS")
		)
		(fp_line
			(start 0.7874 0.4064)
			(end 0.7874 -0.4064)
			(stroke
				(width 0.1524)
				(type default)
			)
			(layer "B.SilkS")
		)
		(fp_line
			(start -0.7874 0.4064)
			(end 0.7874 0.4064)
			(stroke
				(width 0.1524)
				(type default)
			)
			(layer "B.SilkS")
		)
		(fp_line
			(start 0.67945 -0.305054)
			(end 0.12065 -0.305054)
			(stroke
				(width 0.1)
				(type default)
			)
			(layer "B.Fab")
		)
		(fp_line
			(start 0.12065 -0.305054)
			(end 0.12065 -0.2794)
			(stroke
				(width 0.1)
				(type default)
			)
			(layer "B.Fab")
		)
		(fp_line
			(start -0.12065 -0.3048)
			(end -0.67945 -0.3048)
			(stroke
				(width 0.1)
				(type default)
			)
			(layer "B.Fab")
		)
		(fp_line
			(start -0.67945 -0.3048)
			(end -0.67945 0.3048)
			(stroke
				(width 0.1)
				(type default)
			)
			(layer "B.Fab")
		)
		(fp_line
			(start 0.12065 -0.2794)
			(end -0.12065 -0.2794)
			(stroke
				(width 0.1)
				(type default)
			)
			(layer "B.Fab")
		)
		(fp_line
			(start -0.12065 -0.2794)
			(end -0.12065 -0.3048)
			(stroke
				(width 0.1)
				(type default)
			)
			(layer "B.Fab")
		)
		(fp_line
			(start 0.12065 0.2794)
			(end 0.12065 0.3048)
			(stroke
				(width 0.1)
				(type default)
			)
			(layer "B.Fab")
		)
		(fp_line
			(start -0.120396 0.2794)
			(end 0.12065 0.2794)
			(stroke
				(width 0.1)
				(type default)
			)
			(layer "B.Fab")
		)
		(fp_line
			(start 0.67945 0.3048)
			(end 0.67945 -0.305054)
			(stroke
				(width 0.1)
				(type default)
			)
			(layer "B.Fab")
		)
		(fp_line
			(start 0.12065 0.3048)
			(end 0.67945 0.3048)
			(stroke
				(width 0.1)
				(type default)
			)
			(layer "B.Fab")
		)
		(fp_line
			(start -0.120396 0.3048)
			(end -0.120396 0.2794)
			(stroke
				(width 0.1)
				(type default)
			)
			(layer "B.Fab")
		)
		(fp_line
			(start -0.67945 0.3048)
			(end -0.120396 0.3048)
			(stroke
				(width 0.1)
				(type default)
			)
			(layer "B.Fab")
		)
		(pad "1" smd circle
			(at 0.40005 0 270)
			(size 0 0)
			(layers "B.Cu" "B.Mask" "B.Paste")
			(net "SVID_PVDDCR_CPU1_P1_SVC_R")
		)
		(pad "2" smd circle
			(at -0.40005 0 270)
			(size 0 0)
			(layers "B.Cu" "B.Mask" "B.Paste")
			(net "SVID_PVDDCR_CPU1_P1_SVC")
		)
	)
	(footprint ""
		(layer "B.Cu")
		(at 111.800386 -247.971564 90)
		(property "Reference" "C2341"
			(at 0 0 90)
			(layer "B.SilkS")
			(hide yes)
			(effects
				(font
					(size 1.27 1.27)
				)
				(justify mirror)
			)
		)
		(property "Value" ""
			(at 0 0 90)
			(layer "B.Fab")
			(effects
				(font
					(size 1.27 1.27)
				)
				(justify mirror)
			)
		)
		(duplicate_pad_numbers_are_jumpers no)
		(fp_line
			(start 0.7874 -0.4064)
			(end -0.7874 -0.4064)
			(stroke
				(width 0.1524)
				(type default)
			)
			(layer "B.SilkS")
		)
		(fp_line
			(start -0.7874 -0.4064)
			(end -0.7874 0.4064)
			(stroke
				(width 0.1524)
				(type default)
			)
			(layer "B.SilkS")
		)
		(fp_line
			(start 0.7874 0.4064)
			(end 0.7874 -0.4064)
			(stroke
				(width 0.1524)
				(type default)
			)
			(layer "B.SilkS")
		)
		(fp_line
			(start -0.7874 0.4064)
			(end 0.7874 0.4064)
			(stroke
				(width 0.1524)
				(type default)
			)
			(layer "B.SilkS")
		)
		(fp_line
			(start 0.67945 -0.305054)
			(end 0.12065 -0.305054)
			(stroke
				(width 0.1)
				(type default)
			)
			(layer "B.Fab")
		)
		(fp_line
			(start 0.12065 -0.305054)
			(end 0.12065 -0.2794)
			(stroke
				(width 0.1)
				(type default)
			)
			(layer "B.Fab")
		)
		(fp_line
			(start -0.12065 -0.3048)
			(end -0.67945 -0.3048)
			(stroke
				(width 0.1)
				(type default)
			)
			(layer "B.Fab")
		)
		(fp_line
			(start -0.67945 -0.3048)
			(end -0.67945 0.3048)
			(stroke
				(width 0.1)
				(type default)
			)
			(layer "B.Fab")
		)
		(fp_line
			(start 0.12065 -0.2794)
			(end -0.12065 -0.2794)
			(stroke
				(width 0.1)
				(type default)
			)
			(layer "B.Fab")
		)
		(fp_line
			(start -0.12065 -0.2794)
			(end -0.12065 -0.3048)
			(stroke
				(width 0.1)
				(type default)
			)
			(layer "B.Fab")
		)
		(fp_line
			(start 0.12065 0.2794)
			(end 0.12065 0.3048)
			(stroke
				(width 0.1)
				(type default)
			)
			(layer "B.Fab")
		)
		(fp_line
			(start -0.120396 0.2794)
			(end 0.12065 0.2794)
			(stroke
				(width 0.1)
				(type default)
			)
			(layer "B.Fab")
		)
		(fp_line
			(start 0.67945 0.3048)
			(end 0.67945 -0.305054)
			(stroke
				(width 0.1)
				(type default)
			)
			(layer "B.Fab")
		)
		(fp_line
			(start 0.12065 0.3048)
			(end 0.67945 0.3048)
			(stroke
				(width 0.1)
				(type default)
			)
			(layer "B.Fab")
		)
		(fp_line
			(start -0.120396 0.3048)
			(end -0.120396 0.2794)
			(stroke
				(width 0.1)
				(type default)
			)
			(layer "B.Fab")
		)
		(fp_line
			(start -0.67945 0.3048)
			(end -0.120396 0.3048)
			(stroke
				(width 0.1)
				(type default)
			)
			(layer "B.Fab")
		)
		(pad "1" smd circle
			(at 0.40005 0 270)
			(size 0 0)
			(layers "B.Cu" "B.Mask" "B.Paste")
			(net "PVDDCR_CPU0_P1")
		)
		(pad "2" smd circle
			(at -0.40005 0 270)
			(size 0 0)
			(layers "B.Cu" "B.Mask" "B.Paste")
			(net "GND")
		)
	)
	(footprint ""
		(layer "B.Cu")
		(at 239.903 -341.884)
		(property "Reference" "R1407"
			(at 0 0 0)
			(layer "B.SilkS")
			(hide yes)
			(effects
				(font
					(size 1.27 1.27)
				)
				(justify mirror)
			)
		)
		(property "Value" ""
			(at 0 0 0)
			(layer "B.Fab")
			(effects
				(font
					(size 1.27 1.27)
				)
				(justify mirror)
			)
		)
		(duplicate_pad_numbers_are_jumpers no)
		(fp_line
			(start -0.32512 -0.175006)
			(end -0.32512 0.175006)
			(stroke
				(width 0.1)
				(type default)
			)
			(layer "B.Fab")
		)
		(fp_line
			(start -0.32512 0.175006)
			(end 0.32512 0.175006)
			(stroke
				(width 0.1)
				(type default)
			)
			(layer "B.Fab")
		)
		(fp_line
			(start 0.32512 -0.175006)
			(end -0.32512 -0.175006)
			(stroke
				(width 0.1)
				(type default)
			)
			(layer "B.Fab")
		)
		(fp_line
			(start 0.32512 0.175006)
			(end 0.32512 -0.175006)
			(stroke
				(width 0.1)
				(type default)
			)
			(layer "B.Fab")
		)
		(pad "1" smd rect
			(at 0.2667 0 180)
			(size 0.3048 0.381)
			(layers "B.Cu" "B.Mask" "B.Paste")
			(net "P1V8_CPU1_RT_1D")
		)
		(pad "2" smd rect
			(at -0.2667 0)
			(size 0.3048 0.381)
			(layers "B.Cu" "B.Mask" "B.Paste")
			(net "SMB_RT_CPU1_P2_ROM_MUX_2D_R_SCL")
		)
	)
	(footprint ""
		(layer "B.Cu")
		(at 139.152376 -386.745988 -90)
		(property "Reference" "C439"
			(at 0 0 90)
			(layer "B.SilkS")
			(hide yes)
			(effects
				(font
					(size 1.27 1.27)
				)
				(justify mirror)
			)
		)
		(property "Value" ""
			(at 0 0 90)
			(layer "B.Fab")
			(effects
				(font
					(size 1.27 1.27)
				)
				(justify mirror)
			)
		)
		(duplicate_pad_numbers_are_jumpers no)
		(fp_line
			(start -0.7874 0.4064)
			(end 0.7874 0.4064)
			(stroke
				(width 0.1524)
				(type default)
			)
			(layer "B.SilkS")
		)
		(fp_line
			(start 0.7874 0.4064)
			(end 0.7874 -0.4064)
			(stroke
				(width 0.1524)
				(type default)
			)
			(layer "B.SilkS")
		)
		(fp_line
			(start -0.7874 -0.4064)
			(end -0.7874 0.4064)
			(stroke
				(width 0.1524)
				(type default)
			)
			(layer "B.SilkS")
		)
		(fp_line
			(start 0.7874 -0.4064)
			(end -0.7874 -0.4064)
			(stroke
				(width 0.1524)
				(type default)
			)
			(layer "B.SilkS")
		)
		(fp_line
			(start -0.67945 0.3048)
			(end -0.120396 0.3048)
			(stroke
				(width 0.1)
				(type default)
			)
			(layer "B.Fab")
		)
		(fp_line
			(start -0.120396 0.3048)
			(end -0.120396 0.2794)
			(stroke
				(width 0.1)
				(type default)
			)
			(layer "B.Fab")
		)
		(fp_line
			(start 0.12065 0.3048)
			(end 0.67945 0.3048)
			(stroke
				(width 0.1)
				(type default)
			)
			(layer "B.Fab")
		)
		(fp_line
			(start 0.67945 0.3048)
			(end 0.67945 -0.305054)
			(stroke
				(width 0.1)
				(type default)
			)
			(layer "B.Fab")
		)
		(fp_line
			(start -0.120396 0.2794)
			(end 0.12065 0.2794)
			(stroke
				(width 0.1)
				(type default)
			)
			(layer "B.Fab")
		)
		(fp_line
			(start 0.12065 0.2794)
			(end 0.12065 0.3048)
			(stroke
				(width 0.1)
				(type default)
			)
			(layer "B.Fab")
		)
		(fp_line
			(start -0.12065 -0.2794)
			(end -0.12065 -0.3048)
			(stroke
				(width 0.1)
				(type default)
			)
			(layer "B.Fab")
		)
		(fp_line
			(start 0.12065 -0.2794)
			(end -0.12065 -0.2794)
			(stroke
				(width 0.1)
				(type default)
			)
			(layer "B.Fab")
		)
		(fp_line
			(start -0.67945 -0.3048)
			(end -0.67945 0.3048)
			(stroke
				(width 0.1)
				(type default)
			)
			(layer "B.Fab")
		)
		(fp_line
			(start -0.12065 -0.3048)
			(end -0.67945 -0.3048)
			(stroke
				(width 0.1)
				(type default)
			)
			(layer "B.Fab")
		)
		(fp_line
			(start 0.12065 -0.305054)
			(end 0.12065 -0.2794)
			(stroke
				(width 0.1)
				(type default)
			)
			(layer "B.Fab")
		)
		(fp_line
			(start 0.67945 -0.305054)
			(end 0.12065 -0.305054)
			(stroke
				(width 0.1)
				(type default)
			)
			(layer "B.Fab")
		)
		(pad "1" smd circle
			(at 0.40005 0 90)
			(size 0 0)
			(layers "B.Cu" "B.Mask" "B.Paste")
			(net "P1V8_CPU1_RT_1D")
		)
		(pad "2" smd circle
			(at -0.40005 0 90)
			(size 0 0)
			(layers "B.Cu" "B.Mask" "B.Paste")
			(net "GND")
		)
	)
	(footprint ""
		(layer "B.Cu")
		(at 182.880254 -424.39082)
		(property "Reference" "R6234"
			(at 0 0 0)
			(layer "B.SilkS")
			(hide yes)
			(effects
				(font
					(size 1.27 1.27)
				)
				(justify mirror)
			)
		)
		(property "Value" ""
			(at 0 0 0)
			(layer "B.Fab")
			(effects
				(font
					(size 1.27 1.27)
				)
				(justify mirror)
			)
		)
		(duplicate_pad_numbers_are_jumpers no)
		(fp_line
			(start -0.7874 -0.4064)
			(end -0.7874 0.4064)
			(stroke
				(width 0.1524)
				(type default)
			)
			(layer "B.SilkS")
		)
		(fp_line
			(start -0.7874 0.4064)
			(end 0.7874 0.4064)
			(stroke
				(width 0.1524)
				(type default)
			)
			(layer "B.SilkS")
		)
		(fp_line
			(start 0.7874 -0.4064)
			(end -0.7874 -0.4064)
			(stroke
				(width 0.1524)
				(type default)
			)
			(layer "B.SilkS")
		)
		(fp_line
			(start 0.7874 0.4064)
			(end 0.7874 -0.4064)
			(stroke
				(width 0.1524)
				(type default)
			)
			(layer "B.SilkS")
		)
		(fp_line
			(start -0.67945 -0.3048)
			(end -0.67945 0.3048)
			(stroke
				(width 0.1)
				(type default)
			)
			(layer "B.Fab")
		)
		(fp_line
			(start -0.67945 0.3048)
			(end -0.120396 0.3048)
			(stroke
				(width 0.1)
				(type default)
			)
			(layer "B.Fab")
		)
		(fp_line
			(start -0.12065 -0.3048)
			(end -0.67945 -0.3048)
			(stroke
				(width 0.1)
				(type default)
			)
			(layer "B.Fab")
		)
		(fp_line
			(start -0.12065 -0.2794)
			(end -0.12065 -0.3048)
			(stroke
				(width 0.1)
				(type default)
			)
			(layer "B.Fab")
		)
		(fp_line
			(start -0.120396 0.2794)
			(end 0.12065 0.2794)
			(stroke
				(width 0.1)
				(type default)
			)
			(layer "B.Fab")
		)
		(fp_line
			(start -0.120396 0.3048)
			(end -0.120396 0.2794)
			(stroke
				(width 0.1)
				(type default)
			)
			(layer "B.Fab")
		)
		(fp_line
			(start 0.12065 -0.305054)
			(end 0.12065 -0.2794)
			(stroke
				(width 0.1)
				(type default)
			)
			(layer "B.Fab")
		)
		(fp_line
			(start 0.12065 -0.2794)
			(end -0.12065 -0.2794)
			(stroke
				(width 0.1)
				(type default)
			)
			(layer "B.Fab")
		)
		(fp_line
			(start 0.12065 0.2794)
			(end 0.12065 0.3048)
			(stroke
				(width 0.1)
				(type default)
			)
			(layer "B.Fab")
		)
		(fp_line
			(start 0.12065 0.3048)
			(end 0.67945 0.3048)
			(stroke
				(width 0.1)
				(type default)
			)
			(layer "B.Fab")
		)
		(fp_line
			(start 0.67945 -0.305054)
			(end 0.12065 -0.305054)
			(stroke
				(width 0.1)
				(type default)
			)
			(layer "B.Fab")
		)
		(fp_line
			(start 0.67945 0.3048)
			(end 0.67945 -0.305054)
			(stroke
				(width 0.1)
				(type default)
			)
			(layer "B.Fab")
		)
		(pad "1" smd circle
			(at 0.40005 0 180)
			(size 0 0)
			(layers "B.Cu" "B.Mask" "B.Paste")
			(net "HSC_CSOUT")
		)
		(pad "2" smd circle
			(at -0.40005 0 180)
			(size 0 0)
			(layers "B.Cu" "B.Mask" "B.Paste")
			(net "A_HSC_HIGH")
		)
	)
	(footprint ""
		(layer "B.Cu")
		(at 52.782978 -433.682902 -90)
		(property "Reference" "R3428"
			(at 0 0 90)
			(layer "B.SilkS")
			(hide yes)
			(effects
				(font
					(size 1.27 1.27)
				)
				(justify mirror)
			)
		)
		(property "Value" ""
			(at 0 0 90)
			(layer "B.Fab")
			(effects
				(font
					(size 1.27 1.27)
				)
				(justify mirror)
			)
		)
		(duplicate_pad_numbers_are_jumpers no)
		(fp_line
			(start -0.7874 0.4064)
			(end 0.7874 0.4064)
			(stroke
				(width 0.1524)
				(type default)
			)
			(layer "B.SilkS")
		)
		(fp_line
			(start 0.7874 0.4064)
			(end 0.7874 -0.4064)
			(stroke
				(width 0.1524)
				(type default)
			)
			(layer "B.SilkS")
		)
		(fp_line
			(start -0.7874 -0.4064)
			(end -0.7874 0.4064)
			(stroke
				(width 0.1524)
				(type default)
			)
			(layer "B.SilkS")
		)
		(fp_line
			(start 0.7874 -0.4064)
			(end -0.7874 -0.4064)
			(stroke
				(width 0.1524)
				(type default)
			)
			(layer "B.SilkS")
		)
		(fp_line
			(start -0.67945 0.3048)
			(end -0.120396 0.3048)
			(stroke
				(width 0.1)
				(type default)
			)
			(layer "B.Fab")
		)
		(fp_line
			(start -0.120396 0.3048)
			(end -0.120396 0.2794)
			(stroke
				(width 0.1)
				(type default)
			)
			(layer "B.Fab")
		)
		(fp_line
			(start 0.12065 0.3048)
			(end 0.67945 0.3048)
			(stroke
				(width 0.1)
				(type default)
			)
			(layer "B.Fab")
		)
		(fp_line
			(start 0.67945 0.3048)
			(end 0.67945 -0.305054)
			(stroke
				(width 0.1)
				(type default)
			)
			(layer "B.Fab")
		)
		(fp_line
			(start -0.120396 0.2794)
			(end 0.12065 0.2794)
			(stroke
				(width 0.1)
				(type default)
			)
			(layer "B.Fab")
		)
		(fp_line
			(start 0.12065 0.2794)
			(end 0.12065 0.3048)
			(stroke
				(width 0.1)
				(type default)
			)
			(layer "B.Fab")
		)
		(fp_line
			(start -0.12065 -0.2794)
			(end -0.12065 -0.3048)
			(stroke
				(width 0.1)
				(type default)
			)
			(layer "B.Fab")
		)
		(fp_line
			(start 0.12065 -0.2794)
			(end -0.12065 -0.2794)
			(stroke
				(width 0.1)
				(type default)
			)
			(layer "B.Fab")
		)
		(fp_line
			(start -0.67945 -0.3048)
			(end -0.67945 0.3048)
			(stroke
				(width 0.1)
				(type default)
			)
			(layer "B.Fab")
		)
		(fp_line
			(start -0.12065 -0.3048)
			(end -0.67945 -0.3048)
			(stroke
				(width 0.1)
				(type default)
			)
			(layer "B.Fab")
		)
		(fp_line
			(start 0.12065 -0.305054)
			(end 0.12065 -0.2794)
			(stroke
				(width 0.1)
				(type default)
			)
			(layer "B.Fab")
		)
		(fp_line
			(start 0.67945 -0.305054)
			(end 0.12065 -0.305054)
			(stroke
				(width 0.1)
				(type default)
			)
			(layer "B.Fab")
		)
		(pad "1" smd circle
			(at 0.40005 0 90)
			(size 0 0)
			(layers "B.Cu" "B.Mask" "B.Paste")
			(net "GPU_FPGA_THERM_OVERT_N")
		)
		(pad "2" smd circle
			(at -0.40005 0 90)
			(size 0 0)
			(layers "B.Cu" "B.Mask" "B.Paste")
			(net "GND")
		)
	)
	(footprint ""
		(layer "B.Cu")
		(at 208.461356 -385.136136)
		(property "Reference" "PR2511"
			(at 0 0 0)
			(layer "B.SilkS")
			(hide yes)
			(effects
				(font
					(size 1.27 1.27)
				)
				(justify mirror)
			)
		)
		(property "Value" ""
			(at 0 0 0)
			(layer "B.Fab")
			(effects
				(font
					(size 1.27 1.27)
				)
				(justify mirror)
			)
		)
		(duplicate_pad_numbers_are_jumpers no)
		(fp_line
			(start -0.7874 -0.4064)
			(end -0.7874 0.4064)
			(stroke
				(width 0.1524)
				(type default)
			)
			(layer "B.SilkS")
		)
		(fp_line
			(start -0.7874 0.4064)
			(end 0.7874 0.4064)
			(stroke
				(width 0.1524)
				(type default)
			)
			(layer "B.SilkS")
		)
		(fp_line
			(start 0.7874 -0.4064)
			(end -0.7874 -0.4064)
			(stroke
				(width 0.1524)
				(type default)
			)
			(layer "B.SilkS")
		)
		(fp_line
			(start 0.7874 0.4064)
			(end 0.7874 -0.4064)
			(stroke
				(width 0.1524)
				(type default)
			)
			(layer "B.SilkS")
		)
		(fp_line
			(start -0.67945 -0.3048)
			(end -0.67945 0.3048)
			(stroke
				(width 0.1)
				(type default)
			)
			(layer "B.Fab")
		)
		(fp_line
			(start -0.67945 0.3048)
			(end -0.120396 0.3048)
			(stroke
				(width 0.1)
				(type default)
			)
			(layer "B.Fab")
		)
		(fp_line
			(start -0.12065 -0.3048)
			(end -0.67945 -0.3048)
			(stroke
				(width 0.1)
				(type default)
			)
			(layer "B.Fab")
		)
		(fp_line
			(start -0.12065 -0.2794)
			(end -0.12065 -0.3048)
			(stroke
				(width 0.1)
				(type default)
			)
			(layer "B.Fab")
		)
		(fp_line
			(start -0.120396 0.2794)
			(end 0.12065 0.2794)
			(stroke
				(width 0.1)
				(type default)
			)
			(layer "B.Fab")
		)
		(fp_line
			(start -0.120396 0.3048)
			(end -0.120396 0.2794)
			(stroke
				(width 0.1)
				(type default)
			)
			(layer "B.Fab")
		)
		(fp_line
			(start 0.12065 -0.305054)
			(end 0.12065 -0.2794)
			(stroke
				(width 0.1)
				(type default)
			)
			(layer "B.Fab")
		)
		(fp_line
			(start 0.12065 -0.2794)
			(end -0.12065 -0.2794)
			(stroke
				(width 0.1)
				(type default)
			)
			(layer "B.Fab")
		)
		(fp_line
			(start 0.12065 0.2794)
			(end 0.12065 0.3048)
			(stroke
				(width 0.1)
				(type default)
			)
			(layer "B.Fab")
		)
		(fp_line
			(start 0.12065 0.3048)
			(end 0.67945 0.3048)
			(stroke
				(width 0.1)
				(type default)
			)
			(layer "B.Fab")
		)
		(fp_line
			(start 0.67945 -0.305054)
			(end 0.12065 -0.305054)
			(stroke
				(width 0.1)
				(type default)
			)
			(layer "B.Fab")
		)
		(fp_line
			(start 0.67945 0.3048)
			(end 0.67945 -0.305054)
			(stroke
				(width 0.1)
				(type default)
			)
			(layer "B.Fab")
		)
		(pad "1" smd circle
			(at 0.40005 0 180)
			(size 0 0)
			(layers "B.Cu" "B.Mask" "B.Paste")
			(net "P12V_HSC_ADC_P")
		)
		(pad "2" smd circle
			(at -0.40005 0 180)
			(size 0 0)
			(layers "B.Cu" "B.Mask" "B.Paste")
			(net "P12V_HSC_SENSE2_R2_P")
		)
	)
	(footprint ""
		(layer "B.Cu")
		(at 154.206194 -386.766562 90)
		(property "Reference" "C381"
			(at 0 0 90)
			(layer "B.SilkS")
			(hide yes)
			(effects
				(font
					(size 1.27 1.27)
				)
				(justify mirror)
			)
		)
		(property "Value" ""
			(at 0 0 90)
			(layer "B.Fab")
			(effects
				(font
					(size 1.27 1.27)
				)
				(justify mirror)
			)
		)
		(duplicate_pad_numbers_are_jumpers no)
		(fp_line
			(start 0.299974 -0.150114)
			(end -0.299974 -0.150114)
			(stroke
				(width 0.1)
				(type default)
			)
			(layer "B.Fab")
		)
		(fp_line
			(start -0.299974 -0.150114)
			(end -0.299974 0.150114)
			(stroke
				(width 0.1)
				(type default)
			)
			(layer "B.Fab")
		)
		(fp_line
			(start 0.299974 0.150114)
			(end 0.299974 -0.150114)
			(stroke
				(width 0.1)
				(type default)
			)
			(layer "B.Fab")
		)
		(fp_line
			(start -0.299974 0.150114)
			(end 0.299974 0.150114)
			(stroke
				(width 0.1)
				(type default)
			)
			(layer "B.Fab")
		)
		(pad "1" smd rect
			(at 0.2667 0 270)
			(size 0.3048 0.381)
			(layers "B.Cu" "B.Mask" "B.Paste")
			(net "P1V8_CPU1_RT2_1A")
		)
		(pad "2" smd rect
			(at -0.2667 0 270)
			(size 0.3048 0.381)
			(layers "B.Cu" "B.Mask" "B.Paste")
			(net "GND")
		)
	)
	(footprint ""
		(layer "B.Cu")
		(at 342.923876 -66.708782 90)
		(property "Reference" "R3095"
			(at 0 0 90)
			(layer "B.SilkS")
			(hide yes)
			(effects
				(font
					(size 1.27 1.27)
				)
				(justify mirror)
			)
		)
		(property "Value" ""
			(at 0 0 90)
			(layer "B.Fab")
			(effects
				(font
					(size 1.27 1.27)
				)
				(justify mirror)
			)
		)
		(duplicate_pad_numbers_are_jumpers no)
		(fp_line
			(start 0.7874 -0.4064)
			(end -0.7874 -0.4064)
			(stroke
				(width 0.1524)
				(type default)
			)
			(layer "B.SilkS")
		)
		(fp_line
			(start -0.7874 -0.4064)
			(end -0.7874 0.4064)
			(stroke
				(width 0.1524)
				(type default)
			)
			(layer "B.SilkS")
		)
		(fp_line
			(start 0.7874 0.4064)
			(end 0.7874 -0.4064)
			(stroke
				(width 0.1524)
				(type default)
			)
			(layer "B.SilkS")
		)
		(fp_line
			(start -0.7874 0.4064)
			(end 0.7874 0.4064)
			(stroke
				(width 0.1524)
				(type default)
			)
			(layer "B.SilkS")
		)
		(fp_line
			(start 0.67945 -0.305054)
			(end 0.12065 -0.305054)
			(stroke
				(width 0.1)
				(type default)
			)
			(layer "B.Fab")
		)
		(fp_line
			(start 0.12065 -0.305054)
			(end 0.12065 -0.2794)
			(stroke
				(width 0.1)
				(type default)
			)
			(layer "B.Fab")
		)
		(fp_line
			(start -0.12065 -0.3048)
			(end -0.67945 -0.3048)
			(stroke
				(width 0.1)
				(type default)
			)
			(layer "B.Fab")
		)
		(fp_line
			(start -0.67945 -0.3048)
			(end -0.67945 0.3048)
			(stroke
				(width 0.1)
				(type default)
			)
			(layer "B.Fab")
		)
		(fp_line
			(start 0.12065 -0.2794)
			(end -0.12065 -0.2794)
			(stroke
				(width 0.1)
				(type default)
			)
			(layer "B.Fab")
		)
		(fp_line
			(start -0.12065 -0.2794)
			(end -0.12065 -0.3048)
			(stroke
				(width 0.1)
				(type default)
			)
			(layer "B.Fab")
		)
		(fp_line
			(start 0.12065 0.2794)
			(end 0.12065 0.3048)
			(stroke
				(width 0.1)
				(type default)
			)
			(layer "B.Fab")
		)
		(fp_line
			(start -0.120396 0.2794)
			(end 0.12065 0.2794)
			(stroke
				(width 0.1)
				(type default)
			)
			(layer "B.Fab")
		)
		(fp_line
			(start 0.67945 0.3048)
			(end 0.67945 -0.305054)
			(stroke
				(width 0.1)
				(type default)
			)
			(layer "B.Fab")
		)
		(fp_line
			(start 0.12065 0.3048)
			(end 0.67945 0.3048)
			(stroke
				(width 0.1)
				(type default)
			)
			(layer "B.Fab")
		)
		(fp_line
			(start -0.120396 0.3048)
			(end -0.120396 0.2794)
			(stroke
				(width 0.1)
				(type default)
			)
			(layer "B.Fab")
		)
		(fp_line
			(start -0.67945 0.3048)
			(end -0.120396 0.3048)
			(stroke
				(width 0.1)
				(type default)
			)
			(layer "B.Fab")
		)
		(pad "1" smd circle
			(at 0.40005 0 270)
			(size 0 0)
			(layers "B.Cu" "B.Mask" "B.Paste")
			(net "LED_PWRGD_PVDDIO_P1_R")
		)
		(pad "2" smd circle
			(at -0.40005 0 270)
			(size 0 0)
			(layers "B.Cu" "B.Mask" "B.Paste")
			(net "P3V3_AUX")
		)
	)
	(footprint ""
		(layer "B.Cu")
		(at 287.986978 -419.04285)
		(property "Reference" "C79"
			(at 0 0 0)
			(layer "B.SilkS")
			(hide yes)
			(effects
				(font
					(size 1.27 1.27)
				)
				(justify mirror)
			)
		)
		(property "Value" ""
			(at 0 0 0)
			(layer "B.Fab")
			(effects
				(font
					(size 1.27 1.27)
				)
				(justify mirror)
			)
		)
		(duplicate_pad_numbers_are_jumpers no)
		(fp_line
			(start -0.7874 -0.4064)
			(end -0.7874 0.4064)
			(stroke
				(width 0.1524)
				(type default)
			)
			(layer "B.SilkS")
		)
		(fp_line
			(start -0.7874 0.4064)
			(end 0.7874 0.4064)
			(stroke
				(width 0.1524)
				(type default)
			)
			(layer "B.SilkS")
		)
		(fp_line
			(start 0.7874 -0.4064)
			(end -0.7874 -0.4064)
			(stroke
				(width 0.1524)
				(type default)
			)
			(layer "B.SilkS")
		)
		(fp_line
			(start 0.7874 0.4064)
			(end 0.7874 -0.4064)
			(stroke
				(width 0.1524)
				(type default)
			)
			(layer "B.SilkS")
		)
		(fp_line
			(start -0.67945 -0.3048)
			(end -0.67945 0.3048)
			(stroke
				(width 0.1)
				(type default)
			)
			(layer "B.Fab")
		)
		(fp_line
			(start -0.67945 0.3048)
			(end -0.120396 0.3048)
			(stroke
				(width 0.1)
				(type default)
			)
			(layer "B.Fab")
		)
		(fp_line
			(start -0.12065 -0.3048)
			(end -0.67945 -0.3048)
			(stroke
				(width 0.1)
				(type default)
			)
			(layer "B.Fab")
		)
		(fp_line
			(start -0.12065 -0.2794)
			(end -0.12065 -0.3048)
			(stroke
				(width 0.1)
				(type default)
			)
			(layer "B.Fab")
		)
		(fp_line
			(start -0.120396 0.2794)
			(end 0.12065 0.2794)
			(stroke
				(width 0.1)
				(type default)
			)
			(layer "B.Fab")
		)
		(fp_line
			(start -0.120396 0.3048)
			(end -0.120396 0.2794)
			(stroke
				(width 0.1)
				(type default)
			)
			(layer "B.Fab")
		)
		(fp_line
			(start 0.12065 -0.305054)
			(end 0.12065 -0.2794)
			(stroke
				(width 0.1)
				(type default)
			)
			(layer "B.Fab")
		)
		(fp_line
			(start 0.12065 -0.2794)
			(end -0.12065 -0.2794)
			(stroke
				(width 0.1)
				(type default)
			)
			(layer "B.Fab")
		)
		(fp_line
			(start 0.12065 0.2794)
			(end 0.12065 0.3048)
			(stroke
				(width 0.1)
				(type default)
			)
			(layer "B.Fab")
		)
		(fp_line
			(start 0.12065 0.3048)
			(end 0.67945 0.3048)
			(stroke
				(width 0.1)
				(type default)
			)
			(layer "B.Fab")
		)
		(fp_line
			(start 0.67945 -0.305054)
			(end 0.12065 -0.305054)
			(stroke
				(width 0.1)
				(type default)
			)
			(layer "B.Fab")
		)
		(fp_line
			(start 0.67945 0.3048)
			(end 0.67945 -0.305054)
			(stroke
				(width 0.1)
				(type default)
			)
			(layer "B.Fab")
		)
		(pad "1" smd circle
			(at 0.40005 0 180)
			(size 0 0)
			(layers "B.Cu" "B.Mask" "B.Paste")
			(net "P3V3_9ZXL045_P0_VDD")
		)
		(pad "2" smd circle
			(at -0.40005 0 180)
			(size 0 0)
			(layers "B.Cu" "B.Mask" "B.Paste")
			(net "GND")
		)
	)
	(footprint ""
		(layer "B.Cu")
		(at 134.840218 -42.401998)
		(property "Reference" "C6031"
			(at 0 0 0)
			(layer "B.SilkS")
			(hide yes)
			(effects
				(font
					(size 1.27 1.27)
				)
				(justify mirror)
			)
		)
		(property "Value" ""
			(at 0 0 0)
			(layer "B.Fab")
			(effects
				(font
					(size 1.27 1.27)
				)
				(justify mirror)
			)
		)
		(duplicate_pad_numbers_are_jumpers no)
		(fp_line
			(start -0.7874 -0.4064)
			(end -0.7874 0.4064)
			(stroke
				(width 0.1524)
				(type default)
			)
			(layer "B.SilkS")
		)
		(fp_line
			(start -0.7874 0.4064)
			(end 0.7874 0.4064)
			(stroke
				(width 0.1524)
				(type default)
			)
			(layer "B.SilkS")
		)
		(fp_line
			(start 0.7874 -0.4064)
			(end -0.7874 -0.4064)
			(stroke
				(width 0.1524)
				(type default)
			)
			(layer "B.SilkS")
		)
		(fp_line
			(start 0.7874 0.4064)
			(end 0.7874 -0.4064)
			(stroke
				(width 0.1524)
				(type default)
			)
			(layer "B.SilkS")
		)
		(fp_line
			(start -0.67945 -0.3048)
			(end -0.67945 0.3048)
			(stroke
				(width 0.1)
				(type default)
			)
			(layer "B.Fab")
		)
		(fp_line
			(start -0.67945 0.3048)
			(end -0.120396 0.3048)
			(stroke
				(width 0.1)
				(type default)
			)
			(layer "B.Fab")
		)
		(fp_line
			(start -0.12065 -0.3048)
			(end -0.67945 -0.3048)
			(stroke
				(width 0.1)
				(type default)
			)
			(layer "B.Fab")
		)
		(fp_line
			(start -0.12065 -0.2794)
			(end -0.12065 -0.3048)
			(stroke
				(width 0.1)
				(type default)
			)
			(layer "B.Fab")
		)
		(fp_line
			(start -0.120396 0.2794)
			(end 0.12065 0.2794)
			(stroke
				(width 0.1)
				(type default)
			)
			(layer "B.Fab")
		)
		(fp_line
			(start -0.120396 0.3048)
			(end -0.120396 0.2794)
			(stroke
				(width 0.1)
				(type default)
			)
			(layer "B.Fab")
		)
		(fp_line
			(start 0.12065 -0.305054)
			(end 0.12065 -0.2794)
			(stroke
				(width 0.1)
				(type default)
			)
			(layer "B.Fab")
		)
		(fp_line
			(start 0.12065 -0.2794)
			(end -0.12065 -0.2794)
			(stroke
				(width 0.1)
				(type default)
			)
			(layer "B.Fab")
		)
		(fp_line
			(start 0.12065 0.2794)
			(end 0.12065 0.3048)
			(stroke
				(width 0.1)
				(type default)
			)
			(layer "B.Fab")
		)
		(fp_line
			(start 0.12065 0.3048)
			(end 0.67945 0.3048)
			(stroke
				(width 0.1)
				(type default)
			)
			(layer "B.Fab")
		)
		(fp_line
			(start 0.67945 -0.305054)
			(end 0.12065 -0.305054)
			(stroke
				(width 0.1)
				(type default)
			)
			(layer "B.Fab")
		)
		(fp_line
			(start 0.67945 0.3048)
			(end 0.67945 -0.305054)
			(stroke
				(width 0.1)
				(type default)
			)
			(layer "B.Fab")
		)
		(pad "1" smd circle
			(at 0.40005 0 180)
			(size 0 0)
			(layers "B.Cu" "B.Mask" "B.Paste")
			(net "P1V2_CPU0_USB_DVDD12")
		)
		(pad "2" smd circle
			(at -0.40005 0 180)
			(size 0 0)
			(layers "B.Cu" "B.Mask" "B.Paste")
			(net "GND")
		)
	)
	(footprint ""
		(layer "B.Cu")
		(at 170.307 -98.135948 -90)
		(property "Reference" "R6027"
			(at 0 0 90)
			(layer "B.SilkS")
			(hide yes)
			(effects
				(font
					(size 1.27 1.27)
				)
				(justify mirror)
			)
		)
		(property "Value" ""
			(at 0 0 90)
			(layer "B.Fab")
			(effects
				(font
					(size 1.27 1.27)
				)
				(justify mirror)
			)
		)
		(duplicate_pad_numbers_are_jumpers no)
		(fp_line
			(start -0.7874 0.4064)
			(end 0.7874 0.4064)
			(stroke
				(width 0.1524)
				(type default)
			)
			(layer "B.SilkS")
		)
		(fp_line
			(start 0.7874 0.4064)
			(end 0.7874 -0.4064)
			(stroke
				(width 0.1524)
				(type default)
			)
			(layer "B.SilkS")
		)
		(fp_line
			(start -0.7874 -0.4064)
			(end -0.7874 0.4064)
			(stroke
				(width 0.1524)
				(type default)
			)
			(layer "B.SilkS")
		)
		(fp_line
			(start 0.7874 -0.4064)
			(end -0.7874 -0.4064)
			(stroke
				(width 0.1524)
				(type default)
			)
			(layer "B.SilkS")
		)
		(fp_line
			(start -0.67945 0.3048)
			(end -0.120396 0.3048)
			(stroke
				(width 0.1)
				(type default)
			)
			(layer "B.Fab")
		)
		(fp_line
			(start -0.120396 0.3048)
			(end -0.120396 0.2794)
			(stroke
				(width 0.1)
				(type default)
			)
			(layer "B.Fab")
		)
		(fp_line
			(start 0.12065 0.3048)
			(end 0.67945 0.3048)
			(stroke
				(width 0.1)
				(type default)
			)
			(layer "B.Fab")
		)
		(fp_line
			(start 0.67945 0.3048)
			(end 0.67945 -0.305054)
			(stroke
				(width 0.1)
				(type default)
			)
			(layer "B.Fab")
		)
		(fp_line
			(start -0.120396 0.2794)
			(end 0.12065 0.2794)
			(stroke
				(width 0.1)
				(type default)
			)
			(layer "B.Fab")
		)
		(fp_line
			(start 0.12065 0.2794)
			(end 0.12065 0.3048)
			(stroke
				(width 0.1)
				(type default)
			)
			(layer "B.Fab")
		)
		(fp_line
			(start -0.12065 -0.2794)
			(end -0.12065 -0.3048)
			(stroke
				(width 0.1)
				(type default)
			)
			(layer "B.Fab")
		)
		(fp_line
			(start 0.12065 -0.2794)
			(end -0.12065 -0.2794)
			(stroke
				(width 0.1)
				(type default)
			)
			(layer "B.Fab")
		)
		(fp_line
			(start -0.67945 -0.3048)
			(end -0.67945 0.3048)
			(stroke
				(width 0.1)
				(type default)
			)
			(layer "B.Fab")
		)
		(fp_line
			(start -0.12065 -0.3048)
			(end -0.67945 -0.3048)
			(stroke
				(width 0.1)
				(type default)
			)
			(layer "B.Fab")
		)
		(fp_line
			(start 0.12065 -0.305054)
			(end 0.12065 -0.2794)
			(stroke
				(width 0.1)
				(type default)
			)
			(layer "B.Fab")
		)
		(fp_line
			(start 0.67945 -0.305054)
			(end 0.12065 -0.305054)
			(stroke
				(width 0.1)
				(type default)
			)
			(layer "B.Fab")
		)
		(pad "1" smd circle
			(at 0.40005 0 90)
			(size 0 0)
			(layers "B.Cu" "B.Mask" "B.Paste")
			(net "SGPIO_SCM_RESET_N")
		)
		(pad "2" smd circle
			(at -0.40005 0 90)
			(size 0 0)
			(layers "B.Cu" "B.Mask" "B.Paste")
			(net "GND")
		)
	)
	(footprint ""
		(layer "B.Cu")
		(at 52.364386 -190.821564)
		(property "Reference" "R303"
			(at 0 0 0)
			(layer "B.SilkS")
			(hide yes)
			(effects
				(font
					(size 1.27 1.27)
				)
				(justify mirror)
			)
		)
		(property "Value" ""
			(at 0 0 0)
			(layer "B.Fab")
			(effects
				(font
					(size 1.27 1.27)
				)
				(justify mirror)
			)
		)
		(duplicate_pad_numbers_are_jumpers no)
		(fp_line
			(start -0.7874 -0.4064)
			(end -0.7874 0.4064)
			(stroke
				(width 0.1524)
				(type default)
			)
			(layer "B.SilkS")
		)
		(fp_line
			(start -0.7874 0.4064)
			(end 0.7874 0.4064)
			(stroke
				(width 0.1524)
				(type default)
			)
			(layer "B.SilkS")
		)
		(fp_line
			(start 0.7874 -0.4064)
			(end -0.7874 -0.4064)
			(stroke
				(width 0.1524)
				(type default)
			)
			(layer "B.SilkS")
		)
		(fp_line
			(start 0.7874 0.4064)
			(end 0.7874 -0.4064)
			(stroke
				(width 0.1524)
				(type default)
			)
			(layer "B.SilkS")
		)
		(fp_line
			(start -0.67945 -0.3048)
			(end -0.67945 0.3048)
			(stroke
				(width 0.1)
				(type default)
			)
			(layer "B.Fab")
		)
		(fp_line
			(start -0.67945 0.3048)
			(end -0.120396 0.3048)
			(stroke
				(width 0.1)
				(type default)
			)
			(layer "B.Fab")
		)
		(fp_line
			(start -0.12065 -0.3048)
			(end -0.67945 -0.3048)
			(stroke
				(width 0.1)
				(type default)
			)
			(layer "B.Fab")
		)
		(fp_line
			(start -0.12065 -0.2794)
			(end -0.12065 -0.3048)
			(stroke
				(width 0.1)
				(type default)
			)
			(layer "B.Fab")
		)
		(fp_line
			(start -0.120396 0.2794)
			(end 0.12065 0.2794)
			(stroke
				(width 0.1)
				(type default)
			)
			(layer "B.Fab")
		)
		(fp_line
			(start -0.120396 0.3048)
			(end -0.120396 0.2794)
			(stroke
				(width 0.1)
				(type default)
			)
			(layer "B.Fab")
		)
		(fp_line
			(start 0.12065 -0.305054)
			(end 0.12065 -0.2794)
			(stroke
				(width 0.1)
				(type default)
			)
			(layer "B.Fab")
		)
		(fp_line
			(start 0.12065 -0.2794)
			(end -0.12065 -0.2794)
			(stroke
				(width 0.1)
				(type default)
			)
			(layer "B.Fab")
		)
		(fp_line
			(start 0.12065 0.2794)
			(end 0.12065 0.3048)
			(stroke
				(width 0.1)
				(type default)
			)
			(layer "B.Fab")
		)
		(fp_line
			(start 0.12065 0.3048)
			(end 0.67945 0.3048)
			(stroke
				(width 0.1)
				(type default)
			)
			(layer "B.Fab")
		)
		(fp_line
			(start 0.67945 -0.305054)
			(end 0.12065 -0.305054)
			(stroke
				(width 0.1)
				(type default)
			)
			(layer "B.Fab")
		)
		(fp_line
			(start 0.67945 0.3048)
			(end 0.67945 -0.305054)
			(stroke
				(width 0.1)
				(type default)
			)
			(layer "B.Fab")
		)
		(pad "1" smd circle
			(at 0.40005 0 180)
			(size 0 0)
			(layers "B.Cu" "B.Mask" "B.Paste")
			(net "PWRGD_CHA_CPU1_DIMM0")
		)
		(pad "2" smd circle
			(at -0.40005 0 180)
			(size 0 0)
			(layers "B.Cu" "B.Mask" "B.Paste")
			(net "PWRGD_CHAF_CPU1")
		)
	)
	(footprint ""
		(layer "B.Cu")
		(at 363.088936 -174.01794 90)
		(property "Reference" "PC483_1"
			(at 0 0 90)
			(layer "B.SilkS")
			(hide yes)
			(effects
				(font
					(size 1.27 1.27)
				)
				(justify mirror)
			)
		)
		(property "Value" ""
			(at 0 0 90)
			(layer "B.Fab")
			(effects
				(font
					(size 1.27 1.27)
				)
				(justify mirror)
			)
		)
		(duplicate_pad_numbers_are_jumpers no)
		(fp_line
			(start 1.524 -0.762)
			(end -1.524 -0.762)
			(stroke
				(width 0.1524)
				(type default)
			)
			(layer "B.SilkS")
		)
		(fp_line
			(start -1.524 -0.762)
			(end -1.524 0.762)
			(stroke
				(width 0.1524)
				(type default)
			)
			(layer "B.SilkS")
		)
		(fp_line
			(start 1.524 0.762)
			(end 1.524 -0.762)
			(stroke
				(width 0.1524)
				(type default)
			)
			(layer "B.SilkS")
		)
		(fp_line
			(start -1.524 0.762)
			(end 1.524 0.762)
			(stroke
				(width 0.1524)
				(type default)
			)
			(layer "B.SilkS")
		)
		(fp_line
			(start 1.1049 -0.724916)
			(end 1.1049 0.724916)
			(stroke
				(width 0.1)
				(type default)
			)
			(layer "B.Fab")
		)
		(fp_line
			(start -1.1049 -0.724916)
			(end 1.1049 -0.724916)
			(stroke
				(width 0.1)
				(type default)
			)
			(layer "B.Fab")
		)
		(fp_line
			(start 1.1049 0.724916)
			(end -1.1049 0.724916)
			(stroke
				(width 0.1)
				(type default)
			)
			(layer "B.Fab")
		)
		(fp_line
			(start -1.1049 0.724916)
			(end -1.1049 -0.724916)
			(stroke
				(width 0.1)
				(type default)
			)
			(layer "B.Fab")
		)
		(pad "1" smd rect
			(at 0.889 0 90)
			(size 1.016 1.27)
			(layers "B.Cu" "B.Mask" "B.Paste")
			(net "SW_P12V_AUX_PVDDCR_CPU0_P0_FLT")
		)
		(pad "2" smd rect
			(at -0.889 0 90)
			(size 1.016 1.27)
			(layers "B.Cu" "B.Mask" "B.Paste")
			(net "GND")
		)
	)
	(footprint ""
		(layer "B.Cu")
		(at 134.517384 -387.768592 180)
		(property "Reference" "C481"
			(at 0 0 0)
			(layer "B.SilkS")
			(hide yes)
			(effects
				(font
					(size 1.27 1.27)
				)
				(justify mirror)
			)
		)
		(property "Value" ""
			(at 0 0 0)
			(layer "B.Fab")
			(effects
				(font
					(size 1.27 1.27)
				)
				(justify mirror)
			)
		)
		(duplicate_pad_numbers_are_jumpers no)
		(fp_line
			(start 0.299974 0.150114)
			(end 0.299974 -0.150114)
			(stroke
				(width 0.1)
				(type default)
			)
			(layer "B.Fab")
		)
		(fp_line
			(start 0.299974 -0.150114)
			(end -0.299974 -0.150114)
			(stroke
				(width 0.1)
				(type default)
			)
			(layer "B.Fab")
		)
		(fp_line
			(start -0.299974 0.150114)
			(end 0.299974 0.150114)
			(stroke
				(width 0.1)
				(type default)
			)
			(layer "B.Fab")
		)
		(fp_line
			(start -0.299974 -0.150114)
			(end -0.299974 0.150114)
			(stroke
				(width 0.1)
				(type default)
			)
			(layer "B.Fab")
		)
		(pad "1" smd rect
			(at 0.2667 0)
			(size 0.3048 0.381)
			(layers "B.Cu" "B.Mask" "B.Paste")
			(net "P0V9_CPU1_RT3_2A")
		)
		(pad "2" smd rect
			(at -0.2667 0)
			(size 0.3048 0.381)
			(layers "B.Cu" "B.Mask" "B.Paste")
			(net "GND")
		)
	)
	(footprint ""
		(layer "B.Cu")
		(at 46.308518 -346.788994 90)
		(property "Reference" "PC443_2"
			(at 0 0 90)
			(layer "B.SilkS")
			(hide yes)
			(effects
				(font
					(size 1.27 1.27)
				)
				(justify mirror)
			)
		)
		(property "Value" ""
			(at 0 0 90)
			(layer "B.Fab")
			(effects
				(font
					(size 1.27 1.27)
				)
				(justify mirror)
			)
		)
		(duplicate_pad_numbers_are_jumpers no)
		(fp_line
			(start 1.524 -0.762)
			(end -1.524 -0.762)
			(stroke
				(width 0.1524)
				(type default)
			)
			(layer "B.SilkS")
		)
		(fp_line
			(start -1.524 -0.762)
			(end -1.524 0.762)
			(stroke
				(width 0.1524)
				(type default)
			)
			(layer "B.SilkS")
		)
		(fp_line
			(start 1.524 0.762)
			(end 1.524 -0.762)
			(stroke
				(width 0.1524)
				(type default)
			)
			(layer "B.SilkS")
		)
		(fp_line
			(start -1.524 0.762)
			(end 1.524 0.762)
			(stroke
				(width 0.1524)
				(type default)
			)
			(layer "B.SilkS")
		)
		(fp_line
			(start 1.1049 -0.724916)
			(end 1.1049 0.724916)
			(stroke
				(width 0.1)
				(type default)
			)
			(layer "B.Fab")
		)
		(fp_line
			(start -1.1049 -0.724916)
			(end 1.1049 -0.724916)
			(stroke
				(width 0.1)
				(type default)
			)
			(layer "B.Fab")
		)
		(fp_line
			(start 1.1049 0.724916)
			(end -1.1049 0.724916)
			(stroke
				(width 0.1)
				(type default)
			)
			(layer "B.Fab")
		)
		(fp_line
			(start -1.1049 0.724916)
			(end -1.1049 -0.724916)
			(stroke
				(width 0.1)
				(type default)
			)
			(layer "B.Fab")
		)
		(pad "1" smd rect
			(at 0.889 0 90)
			(size 1.016 1.27)
			(layers "B.Cu" "B.Mask" "B.Paste")
			(net "SW_P12V_AUX_PVDDIO_P1_FLT")
		)
		(pad "2" smd rect
			(at -0.889 0 90)
			(size 1.016 1.27)
			(layers "B.Cu" "B.Mask" "B.Paste")
			(net "GND")
		)
	)
	(footprint ""
		(layer "B.Cu")
		(at 320.17843 -395.148562 90)
		(property "Reference" "C573"
			(at 0 0 90)
			(layer "B.SilkS")
			(hide yes)
			(effects
				(font
					(size 1.27 1.27)
				)
				(justify mirror)
			)
		)
		(property "Value" ""
			(at 0 0 90)
			(layer "B.Fab")
			(effects
				(font
					(size 1.27 1.27)
				)
				(justify mirror)
			)
		)
		(duplicate_pad_numbers_are_jumpers no)
		(fp_line
			(start 0.299974 -0.150114)
			(end -0.299974 -0.150114)
			(stroke
				(width 0.1)
				(type default)
			)
			(layer "B.Fab")
		)
		(fp_line
			(start -0.299974 -0.150114)
			(end -0.299974 0.150114)
			(stroke
				(width 0.1)
				(type default)
			)
			(layer "B.Fab")
		)
		(fp_line
			(start 0.299974 0.150114)
			(end 0.299974 -0.150114)
			(stroke
				(width 0.1)
				(type default)
			)
			(layer "B.Fab")
		)
		(fp_line
			(start -0.299974 0.150114)
			(end 0.299974 0.150114)
			(stroke
				(width 0.1)
				(type default)
			)
			(layer "B.Fab")
		)
		(pad "1" smd rect
			(at 0.2667 0 270)
			(size 0.3048 0.381)
			(layers "B.Cu" "B.Mask" "B.Paste")
			(net "P0V9_CPU0_RT0_2A")
		)
		(pad "2" smd rect
			(at -0.2667 0 270)
			(size 0.3048 0.381)
			(layers "B.Cu" "B.Mask" "B.Paste")
			(net "GND")
		)
	)
	(footprint ""
		(layer "B.Cu")
		(at 100.496878 -139.93241 90)
		(property "Reference" "PC10"
			(at 0 0 90)
			(layer "B.SilkS")
			(hide yes)
			(effects
				(font
					(size 1.27 1.27)
				)
				(justify mirror)
			)
		)
		(property "Value" ""
			(at 0 0 90)
			(layer "B.Fab")
			(effects
				(font
					(size 1.27 1.27)
				)
				(justify mirror)
			)
		)
		(duplicate_pad_numbers_are_jumpers no)
		(fp_line
			(start 0.7874 -0.4064)
			(end -0.7874 -0.4064)
			(stroke
				(width 0.1524)
				(type default)
			)
			(layer "B.SilkS")
		)
		(fp_line
			(start -0.7874 -0.4064)
			(end -0.7874 0.4064)
			(stroke
				(width 0.1524)
				(type default)
			)
			(layer "B.SilkS")
		)
		(fp_line
			(start 0.7874 0.4064)
			(end 0.7874 -0.4064)
			(stroke
				(width 0.1524)
				(type default)
			)
			(layer "B.SilkS")
		)
		(fp_line
			(start -0.7874 0.4064)
			(end 0.7874 0.4064)
			(stroke
				(width 0.1524)
				(type default)
			)
			(layer "B.SilkS")
		)
		(fp_line
			(start 0.67945 -0.305054)
			(end 0.12065 -0.305054)
			(stroke
				(width 0.1)
				(type default)
			)
			(layer "B.Fab")
		)
		(fp_line
			(start 0.12065 -0.305054)
			(end 0.12065 -0.2794)
			(stroke
				(width 0.1)
				(type default)
			)
			(layer "B.Fab")
		)
		(fp_line
			(start -0.12065 -0.3048)
			(end -0.67945 -0.3048)
			(stroke
				(width 0.1)
				(type default)
			)
			(layer "B.Fab")
		)
		(fp_line
			(start -0.67945 -0.3048)
			(end -0.67945 0.3048)
			(stroke
				(width 0.1)
				(type default)
			)
			(layer "B.Fab")
		)
		(fp_line
			(start 0.12065 -0.2794)
			(end -0.12065 -0.2794)
			(stroke
				(width 0.1)
				(type default)
			)
			(layer "B.Fab")
		)
		(fp_line
			(start -0.12065 -0.2794)
			(end -0.12065 -0.3048)
			(stroke
				(width 0.1)
				(type default)
			)
			(layer "B.Fab")
		)
		(fp_line
			(start 0.12065 0.2794)
			(end 0.12065 0.3048)
			(stroke
				(width 0.1)
				(type default)
			)
			(layer "B.Fab")
		)
		(fp_line
			(start -0.120396 0.2794)
			(end 0.12065 0.2794)
			(stroke
				(width 0.1)
				(type default)
			)
			(layer "B.Fab")
		)
		(fp_line
			(start 0.67945 0.3048)
			(end 0.67945 -0.305054)
			(stroke
				(width 0.1)
				(type default)
			)
			(layer "B.Fab")
		)
		(fp_line
			(start 0.12065 0.3048)
			(end 0.67945 0.3048)
			(stroke
				(width 0.1)
				(type default)
			)
			(layer "B.Fab")
		)
		(fp_line
			(start -0.120396 0.3048)
			(end -0.120396 0.2794)
			(stroke
				(width 0.1)
				(type default)
			)
			(layer "B.Fab")
		)
		(fp_line
			(start -0.67945 0.3048)
			(end -0.120396 0.3048)
			(stroke
				(width 0.1)
				(type default)
			)
			(layer "B.Fab")
		)
		(pad "1" smd circle
			(at 0.40005 0 270)
			(size 0 0)
			(layers "B.Cu" "B.Mask" "B.Paste")
			(net "PVDDCR_CPU0_P1_VCC")
		)
		(pad "2" smd circle
			(at -0.40005 0 270)
			(size 0 0)
			(layers "B.Cu" "B.Mask" "B.Paste")
			(net "GND")
		)
	)
	(footprint ""
		(layer "B.Cu")
		(at 374.0912 -398.942052 90)
		(property "Reference" "C1049"
			(at 0 0 90)
			(layer "B.SilkS")
			(hide yes)
			(effects
				(font
					(size 1.27 1.27)
				)
				(justify mirror)
			)
		)
		(property "Value" ""
			(at 0 0 90)
			(layer "B.Fab")
			(effects
				(font
					(size 1.27 1.27)
				)
				(justify mirror)
			)
		)
		(duplicate_pad_numbers_are_jumpers no)
		(fp_line
			(start 0.7874 -0.4064)
			(end -0.7874 -0.4064)
			(stroke
				(width 0.1524)
				(type default)
			)
			(layer "B.SilkS")
		)
		(fp_line
			(start -0.7874 -0.4064)
			(end -0.7874 0.4064)
			(stroke
				(width 0.1524)
				(type default)
			)
			(layer "B.SilkS")
		)
		(fp_line
			(start 0.7874 0.4064)
			(end 0.7874 -0.4064)
			(stroke
				(width 0.1524)
				(type default)
			)
			(layer "B.SilkS")
		)
		(fp_line
			(start -0.7874 0.4064)
			(end 0.7874 0.4064)
			(stroke
				(width 0.1524)
				(type default)
			)
			(layer "B.SilkS")
		)
		(fp_line
			(start 0.67945 -0.305054)
			(end 0.12065 -0.305054)
			(stroke
				(width 0.1)
				(type default)
			)
			(layer "B.Fab")
		)
		(fp_line
			(start 0.12065 -0.305054)
			(end 0.12065 -0.2794)
			(stroke
				(width 0.1)
				(type default)
			)
			(layer "B.Fab")
		)
		(fp_line
			(start -0.12065 -0.3048)
			(end -0.67945 -0.3048)
			(stroke
				(width 0.1)
				(type default)
			)
			(layer "B.Fab")
		)
		(fp_line
			(start -0.67945 -0.3048)
			(end -0.67945 0.3048)
			(stroke
				(width 0.1)
				(type default)
			)
			(layer "B.Fab")
		)
		(fp_line
			(start 0.12065 -0.2794)
			(end -0.12065 -0.2794)
			(stroke
				(width 0.1)
				(type default)
			)
			(layer "B.Fab")
		)
		(fp_line
			(start -0.12065 -0.2794)
			(end -0.12065 -0.3048)
			(stroke
				(width 0.1)
				(type default)
			)
			(layer "B.Fab")
		)
		(fp_line
			(start 0.12065 0.2794)
			(end 0.12065 0.3048)
			(stroke
				(width 0.1)
				(type default)
			)
			(layer "B.Fab")
		)
		(fp_line
			(start -0.120396 0.2794)
			(end 0.12065 0.2794)
			(stroke
				(width 0.1)
				(type default)
			)
			(layer "B.Fab")
		)
		(fp_line
			(start 0.67945 0.3048)
			(end 0.67945 -0.305054)
			(stroke
				(width 0.1)
				(type default)
			)
			(layer "B.Fab")
		)
		(fp_line
			(start 0.12065 0.3048)
			(end 0.67945 0.3048)
			(stroke
				(width 0.1)
				(type default)
			)
			(layer "B.Fab")
		)
		(fp_line
			(start -0.120396 0.3048)
			(end -0.120396 0.2794)
			(stroke
				(width 0.1)
				(type default)
			)
			(layer "B.Fab")
		)
		(fp_line
			(start -0.67945 0.3048)
			(end -0.120396 0.3048)
			(stroke
				(width 0.1)
				(type default)
			)
			(layer "B.Fab")
		)
		(pad "1" smd circle
			(at 0.40005 0 270)
			(size 0 0)
			(layers "B.Cu" "B.Mask" "B.Paste")
			(net "P0V9_CPU0_RT3_2A")
		)
		(pad "2" smd circle
			(at -0.40005 0 270)
			(size 0 0)
			(layers "B.Cu" "B.Mask" "B.Paste")
			(net "GND")
		)
	)
	(footprint ""
		(layer "B.Cu")
		(at 51.766978 -431.904902 90)
		(property "Reference" "C1974"
			(at 0 0 90)
			(layer "B.SilkS")
			(hide yes)
			(effects
				(font
					(size 1.27 1.27)
				)
				(justify mirror)
			)
		)
		(property "Value" ""
			(at 0 0 90)
			(layer "B.Fab")
			(effects
				(font
					(size 1.27 1.27)
				)
				(justify mirror)
			)
		)
		(duplicate_pad_numbers_are_jumpers no)
		(fp_line
			(start 0.7874 -0.4064)
			(end -0.7874 -0.4064)
			(stroke
				(width 0.1524)
				(type default)
			)
			(layer "B.SilkS")
		)
		(fp_line
			(start -0.7874 -0.4064)
			(end -0.7874 0.4064)
			(stroke
				(width 0.1524)
				(type default)
			)
			(layer "B.SilkS")
		)
		(fp_line
			(start 0.7874 0.4064)
			(end 0.7874 -0.4064)
			(stroke
				(width 0.1524)
				(type default)
			)
			(layer "B.SilkS")
		)
		(fp_line
			(start -0.7874 0.4064)
			(end 0.7874 0.4064)
			(stroke
				(width 0.1524)
				(type default)
			)
			(layer "B.SilkS")
		)
		(fp_line
			(start 0.67945 -0.305054)
			(end 0.12065 -0.305054)
			(stroke
				(width 0.1)
				(type default)
			)
			(layer "B.Fab")
		)
		(fp_line
			(start 0.12065 -0.305054)
			(end 0.12065 -0.2794)
			(stroke
				(width 0.1)
				(type default)
			)
			(layer "B.Fab")
		)
		(fp_line
			(start -0.12065 -0.3048)
			(end -0.67945 -0.3048)
			(stroke
				(width 0.1)
				(type default)
			)
			(layer "B.Fab")
		)
		(fp_line
			(start -0.67945 -0.3048)
			(end -0.67945 0.3048)
			(stroke
				(width 0.1)
				(type default)
			)
			(layer "B.Fab")
		)
		(fp_line
			(start 0.12065 -0.2794)
			(end -0.12065 -0.2794)
			(stroke
				(width 0.1)
				(type default)
			)
			(layer "B.Fab")
		)
		(fp_line
			(start -0.12065 -0.2794)
			(end -0.12065 -0.3048)
			(stroke
				(width 0.1)
				(type default)
			)
			(layer "B.Fab")
		)
		(fp_line
			(start 0.12065 0.2794)
			(end 0.12065 0.3048)
			(stroke
				(width 0.1)
				(type default)
			)
			(layer "B.Fab")
		)
		(fp_line
			(start -0.120396 0.2794)
			(end 0.12065 0.2794)
			(stroke
				(width 0.1)
				(type default)
			)
			(layer "B.Fab")
		)
		(fp_line
			(start 0.67945 0.3048)
			(end 0.67945 -0.305054)
			(stroke
				(width 0.1)
				(type default)
			)
			(layer "B.Fab")
		)
		(fp_line
			(start 0.12065 0.3048)
			(end 0.67945 0.3048)
			(stroke
				(width 0.1)
				(type default)
			)
			(layer "B.Fab")
		)
		(fp_line
			(start -0.120396 0.3048)
			(end -0.120396 0.2794)
			(stroke
				(width 0.1)
				(type default)
			)
			(layer "B.Fab")
		)
		(fp_line
			(start -0.67945 0.3048)
			(end -0.120396 0.3048)
			(stroke
				(width 0.1)
				(type default)
			)
			(layer "B.Fab")
		)
		(pad "1" smd circle
			(at 0.40005 0 270)
			(size 0 0)
			(layers "B.Cu" "B.Mask" "B.Paste")
			(net "GPU_FPGA_THERM_OVERT_ISO_N")
		)
		(pad "2" smd circle
			(at -0.40005 0 270)
			(size 0 0)
			(layers "B.Cu" "B.Mask" "B.Paste")
			(net "GND")
		)
	)
	(footprint ""
		(layer "B.Cu")
		(at 235.839 -241.2111 90)
		(property "Reference" "R337"
			(at 0 0 90)
			(layer "B.SilkS")
			(hide yes)
			(effects
				(font
					(size 1.27 1.27)
				)
				(justify mirror)
			)
		)
		(property "Value" ""
			(at 0 0 90)
			(layer "B.Fab")
			(effects
				(font
					(size 1.27 1.27)
				)
				(justify mirror)
			)
		)
		(duplicate_pad_numbers_are_jumpers no)
		(fp_line
			(start 0.7874 -0.4064)
			(end -0.7874 -0.4064)
			(stroke
				(width 0.1524)
				(type default)
			)
			(layer "B.SilkS")
		)
		(fp_line
			(start -0.7874 -0.4064)
			(end -0.7874 0.4064)
			(stroke
				(width 0.1524)
				(type default)
			)
			(layer "B.SilkS")
		)
		(fp_line
			(start 0.7874 0.4064)
			(end 0.7874 -0.4064)
			(stroke
				(width 0.1524)
				(type default)
			)
			(layer "B.SilkS")
		)
		(fp_line
			(start -0.7874 0.4064)
			(end 0.7874 0.4064)
			(stroke
				(width 0.1524)
				(type default)
			)
			(layer "B.SilkS")
		)
		(fp_line
			(start 0.67945 -0.305054)
			(end 0.12065 -0.305054)
			(stroke
				(width 0.1)
				(type default)
			)
			(layer "B.Fab")
		)
		(fp_line
			(start 0.12065 -0.305054)
			(end 0.12065 -0.2794)
			(stroke
				(width 0.1)
				(type default)
			)
			(layer "B.Fab")
		)
		(fp_line
			(start -0.12065 -0.3048)
			(end -0.67945 -0.3048)
			(stroke
				(width 0.1)
				(type default)
			)
			(layer "B.Fab")
		)
		(fp_line
			(start -0.67945 -0.3048)
			(end -0.67945 0.3048)
			(stroke
				(width 0.1)
				(type default)
			)
			(layer "B.Fab")
		)
		(fp_line
			(start 0.12065 -0.2794)
			(end -0.12065 -0.2794)
			(stroke
				(width 0.1)
				(type default)
			)
			(layer "B.Fab")
		)
		(fp_line
			(start -0.12065 -0.2794)
			(end -0.12065 -0.3048)
			(stroke
				(width 0.1)
				(type default)
			)
			(layer "B.Fab")
		)
		(fp_line
			(start 0.12065 0.2794)
			(end 0.12065 0.3048)
			(stroke
				(width 0.1)
				(type default)
			)
			(layer "B.Fab")
		)
		(fp_line
			(start -0.120396 0.2794)
			(end 0.12065 0.2794)
			(stroke
				(width 0.1)
				(type default)
			)
			(layer "B.Fab")
		)
		(fp_line
			(start 0.67945 0.3048)
			(end 0.67945 -0.305054)
			(stroke
				(width 0.1)
				(type default)
			)
			(layer "B.Fab")
		)
		(fp_line
			(start 0.12065 0.3048)
			(end 0.67945 0.3048)
			(stroke
				(width 0.1)
				(type default)
			)
			(layer "B.Fab")
		)
		(fp_line
			(start -0.120396 0.3048)
			(end -0.120396 0.2794)
			(stroke
				(width 0.1)
				(type default)
			)
			(layer "B.Fab")
		)
		(fp_line
			(start -0.67945 0.3048)
			(end -0.120396 0.3048)
			(stroke
				(width 0.1)
				(type default)
			)
			(layer "B.Fab")
		)
		(pad "1" smd rect
			(at 0.40005 0 90)
			(size 0.4572 0.508)
			(layers "B.Cu" "B.Mask" "B.Paste")
			(net "SMB_APML_CPU1_MUX2_SCL")
		)
		(pad "2" smd rect
			(at -0.40005 0 90)
			(size 0.4572 0.508)
			(layers "B.Cu" "B.Mask" "B.Paste")
			(net "SMB_APML_CPU1_SCL")
		)
	)
	(footprint ""
		(layer "B.Cu")
		(at 61.791342 -390.560052 90)
		(property "Reference" "C286"
			(at 0 0 90)
			(layer "B.SilkS")
			(hide yes)
			(effects
				(font
					(size 1.27 1.27)
				)
				(justify mirror)
			)
		)
		(property "Value" ""
			(at 0 0 90)
			(layer "B.Fab")
			(effects
				(font
					(size 1.27 1.27)
				)
				(justify mirror)
			)
		)
		(duplicate_pad_numbers_are_jumpers no)
		(fp_line
			(start 0.7874 -0.4064)
			(end -0.7874 -0.4064)
			(stroke
				(width 0.1524)
				(type default)
			)
			(layer "B.SilkS")
		)
		(fp_line
			(start -0.7874 -0.4064)
			(end -0.7874 0.4064)
			(stroke
				(width 0.1524)
				(type default)
			)
			(layer "B.SilkS")
		)
		(fp_line
			(start 0.7874 0.4064)
			(end 0.7874 -0.4064)
			(stroke
				(width 0.1524)
				(type default)
			)
			(layer "B.SilkS")
		)
		(fp_line
			(start -0.7874 0.4064)
			(end 0.7874 0.4064)
			(stroke
				(width 0.1524)
				(type default)
			)
			(layer "B.SilkS")
		)
		(fp_line
			(start 0.67945 -0.305054)
			(end 0.12065 -0.305054)
			(stroke
				(width 0.1)
				(type default)
			)
			(layer "B.Fab")
		)
		(fp_line
			(start 0.12065 -0.305054)
			(end 0.12065 -0.2794)
			(stroke
				(width 0.1)
				(type default)
			)
			(layer "B.Fab")
		)
		(fp_line
			(start -0.12065 -0.3048)
			(end -0.67945 -0.3048)
			(stroke
				(width 0.1)
				(type default)
			)
			(layer "B.Fab")
		)
		(fp_line
			(start -0.67945 -0.3048)
			(end -0.67945 0.3048)
			(stroke
				(width 0.1)
				(type default)
			)
			(layer "B.Fab")
		)
		(fp_line
			(start 0.12065 -0.2794)
			(end -0.12065 -0.2794)
			(stroke
				(width 0.1)
				(type default)
			)
			(layer "B.Fab")
		)
		(fp_line
			(start -0.12065 -0.2794)
			(end -0.12065 -0.3048)
			(stroke
				(width 0.1)
				(type default)
			)
			(layer "B.Fab")
		)
		(fp_line
			(start 0.12065 0.2794)
			(end 0.12065 0.3048)
			(stroke
				(width 0.1)
				(type default)
			)
			(layer "B.Fab")
		)
		(fp_line
			(start -0.120396 0.2794)
			(end 0.12065 0.2794)
			(stroke
				(width 0.1)
				(type default)
			)
			(layer "B.Fab")
		)
		(fp_line
			(start 0.67945 0.3048)
			(end 0.67945 -0.305054)
			(stroke
				(width 0.1)
				(type default)
			)
			(layer "B.Fab")
		)
		(fp_line
			(start 0.12065 0.3048)
			(end 0.67945 0.3048)
			(stroke
				(width 0.1)
				(type default)
			)
			(layer "B.Fab")
		)
		(fp_line
			(start -0.120396 0.3048)
			(end -0.120396 0.2794)
			(stroke
				(width 0.1)
				(type default)
			)
			(layer "B.Fab")
		)
		(fp_line
			(start -0.67945 0.3048)
			(end -0.120396 0.3048)
			(stroke
				(width 0.1)
				(type default)
			)
			(layer "B.Fab")
		)
		(pad "1" smd circle
			(at 0.40005 0 270)
			(size 0 0)
			(layers "B.Cu" "B.Mask" "B.Paste")
			(net "P0V9_CPU1_RT0_2A")
		)
		(pad "2" smd circle
			(at -0.40005 0 270)
			(size 0 0)
			(layers "B.Cu" "B.Mask" "B.Paste")
			(net "GND")
		)
	)
	(footprint ""
		(layer "B.Cu")
		(at 281.391614 -194.88531 180)
		(property "Reference" "R763"
			(at 0 0 0)
			(layer "B.SilkS")
			(hide yes)
			(effects
				(font
					(size 1.27 1.27)
				)
				(justify mirror)
			)
		)
		(property "Value" ""
			(at 0 0 0)
			(layer "B.Fab")
			(effects
				(font
					(size 1.27 1.27)
				)
				(justify mirror)
			)
		)
		(duplicate_pad_numbers_are_jumpers no)
		(fp_line
			(start 0.7874 0.4064)
			(end 0.7874 -0.4064)
			(stroke
				(width 0.1524)
				(type default)
			)
			(layer "B.SilkS")
		)
		(fp_line
			(start 0.7874 -0.4064)
			(end -0.7874 -0.4064)
			(stroke
				(width 0.1524)
				(type default)
			)
			(layer "B.SilkS")
		)
		(fp_line
			(start -0.7874 0.4064)
			(end 0.7874 0.4064)
			(stroke
				(width 0.1524)
				(type default)
			)
			(layer "B.SilkS")
		)
		(fp_line
			(start -0.7874 -0.4064)
			(end -0.7874 0.4064)
			(stroke
				(width 0.1524)
				(type default)
			)
			(layer "B.SilkS")
		)
		(fp_line
			(start 0.67945 0.3048)
			(end 0.67945 -0.305054)
			(stroke
				(width 0.1)
				(type default)
			)
			(layer "B.Fab")
		)
		(fp_line
			(start 0.67945 -0.305054)
			(end 0.12065 -0.305054)
			(stroke
				(width 0.1)
				(type default)
			)
			(layer "B.Fab")
		)
		(fp_line
			(start 0.12065 0.3048)
			(end 0.67945 0.3048)
			(stroke
				(width 0.1)
				(type default)
			)
			(layer "B.Fab")
		)
		(fp_line
			(start 0.12065 0.2794)
			(end 0.12065 0.3048)
			(stroke
				(width 0.1)
				(type default)
			)
			(layer "B.Fab")
		)
		(fp_line
			(start 0.12065 -0.2794)
			(end -0.12065 -0.2794)
			(stroke
				(width 0.1)
				(type default)
			)
			(layer "B.Fab")
		)
		(fp_line
			(start 0.12065 -0.305054)
			(end 0.12065 -0.2794)
			(stroke
				(width 0.1)
				(type default)
			)
			(layer "B.Fab")
		)
		(fp_line
			(start -0.120396 0.3048)
			(end -0.120396 0.2794)
			(stroke
				(width 0.1)
				(type default)
			)
			(layer "B.Fab")
		)
		(fp_line
			(start -0.120396 0.2794)
			(end 0.12065 0.2794)
			(stroke
				(width 0.1)
				(type default)
			)
			(layer "B.Fab")
		)
		(fp_line
			(start -0.12065 -0.2794)
			(end -0.12065 -0.3048)
			(stroke
				(width 0.1)
				(type default)
			)
			(layer "B.Fab")
		)
		(fp_line
			(start -0.12065 -0.3048)
			(end -0.67945 -0.3048)
			(stroke
				(width 0.1)
				(type default)
			)
			(layer "B.Fab")
		)
		(fp_line
			(start -0.67945 0.3048)
			(end -0.120396 0.3048)
			(stroke
				(width 0.1)
				(type default)
			)
			(layer "B.Fab")
		)
		(fp_line
			(start -0.67945 -0.3048)
			(end -0.67945 0.3048)
			(stroke
				(width 0.1)
				(type default)
			)
			(layer "B.Fab")
		)
		(pad "1" smd circle
			(at 0.40005 0)
			(size 0 0)
			(layers "B.Cu" "B.Mask" "B.Paste")
			(net "PD_CHD_CPU0_DIMM_SAA")
		)
		(pad "2" smd circle
			(at -0.40005 0)
			(size 0 0)
			(layers "B.Cu" "B.Mask" "B.Paste")
			(net "GND")
		)
	)
	(footprint ""
		(layer "B.Cu")
		(at 67.417442 -387.768592 180)
		(property "Reference" "C264"
			(at 0 0 0)
			(layer "B.SilkS")
			(hide yes)
			(effects
				(font
					(size 1.27 1.27)
				)
				(justify mirror)
			)
		)
		(property "Value" ""
			(at 0 0 0)
			(layer "B.Fab")
			(effects
				(font
					(size 1.27 1.27)
				)
				(justify mirror)
			)
		)
		(duplicate_pad_numbers_are_jumpers no)
		(fp_line
			(start 0.299974 0.150114)
			(end 0.299974 -0.150114)
			(stroke
				(width 0.1)
				(type default)
			)
			(layer "B.Fab")
		)
		(fp_line
			(start 0.299974 -0.150114)
			(end -0.299974 -0.150114)
			(stroke
				(width 0.1)
				(type default)
			)
			(layer "B.Fab")
		)
		(fp_line
			(start -0.299974 0.150114)
			(end 0.299974 0.150114)
			(stroke
				(width 0.1)
				(type default)
			)
			(layer "B.Fab")
		)
		(fp_line
			(start -0.299974 -0.150114)
			(end -0.299974 0.150114)
			(stroke
				(width 0.1)
				(type default)
			)
			(layer "B.Fab")
		)
		(pad "1" smd rect
			(at 0.2667 0)
			(size 0.3048 0.381)
			(layers "B.Cu" "B.Mask" "B.Paste")
			(net "P0V9_CPU1_RT0_2A")
		)
		(pad "2" smd rect
			(at -0.2667 0)
			(size 0.3048 0.381)
			(layers "B.Cu" "B.Mask" "B.Paste")
			(net "GND")
		)
	)
	(footprint ""
		(layer "B.Cu")
		(at 325.635112 -34.651442 90)
		(property "Reference" "R3939"
			(at 0 0 90)
			(layer "B.SilkS")
			(hide yes)
			(effects
				(font
					(size 1.27 1.27)
				)
				(justify mirror)
			)
		)
		(property "Value" ""
			(at 0 0 90)
			(layer "B.Fab")
			(effects
				(font
					(size 1.27 1.27)
				)
				(justify mirror)
			)
		)
		(duplicate_pad_numbers_are_jumpers no)
		(fp_line
			(start 0.7874 -0.4064)
			(end -0.7874 -0.4064)
			(stroke
				(width 0.1524)
				(type default)
			)
			(layer "B.SilkS")
		)
		(fp_line
			(start -0.7874 -0.4064)
			(end -0.7874 0.4064)
			(stroke
				(width 0.1524)
				(type default)
			)
			(layer "B.SilkS")
		)
		(fp_line
			(start 0.7874 0.4064)
			(end 0.7874 -0.4064)
			(stroke
				(width 0.1524)
				(type default)
			)
			(layer "B.SilkS")
		)
		(fp_line
			(start -0.7874 0.4064)
			(end 0.7874 0.4064)
			(stroke
				(width 0.1524)
				(type default)
			)
			(layer "B.SilkS")
		)
		(fp_line
			(start 0.67945 -0.305054)
			(end 0.12065 -0.305054)
			(stroke
				(width 0.1)
				(type default)
			)
			(layer "B.Fab")
		)
		(fp_line
			(start 0.12065 -0.305054)
			(end 0.12065 -0.2794)
			(stroke
				(width 0.1)
				(type default)
			)
			(layer "B.Fab")
		)
		(fp_line
			(start -0.12065 -0.3048)
			(end -0.67945 -0.3048)
			(stroke
				(width 0.1)
				(type default)
			)
			(layer "B.Fab")
		)
		(fp_line
			(start -0.67945 -0.3048)
			(end -0.67945 0.3048)
			(stroke
				(width 0.1)
				(type default)
			)
			(layer "B.Fab")
		)
		(fp_line
			(start 0.12065 -0.2794)
			(end -0.12065 -0.2794)
			(stroke
				(width 0.1)
				(type default)
			)
			(layer "B.Fab")
		)
		(fp_line
			(start -0.12065 -0.2794)
			(end -0.12065 -0.3048)
			(stroke
				(width 0.1)
				(type default)
			)
			(layer "B.Fab")
		)
		(fp_line
			(start 0.12065 0.2794)
			(end 0.12065 0.3048)
			(stroke
				(width 0.1)
				(type default)
			)
			(layer "B.Fab")
		)
		(fp_line
			(start -0.120396 0.2794)
			(end 0.12065 0.2794)
			(stroke
				(width 0.1)
				(type default)
			)
			(layer "B.Fab")
		)
		(fp_line
			(start 0.67945 0.3048)
			(end 0.67945 -0.305054)
			(stroke
				(width 0.1)
				(type default)
			)
			(layer "B.Fab")
		)
		(fp_line
			(start 0.12065 0.3048)
			(end 0.67945 0.3048)
			(stroke
				(width 0.1)
				(type default)
			)
			(layer "B.Fab")
		)
		(fp_line
			(start -0.120396 0.3048)
			(end -0.120396 0.2794)
			(stroke
				(width 0.1)
				(type default)
			)
			(layer "B.Fab")
		)
		(fp_line
			(start -0.67945 0.3048)
			(end -0.120396 0.3048)
			(stroke
				(width 0.1)
				(type default)
			)
			(layer "B.Fab")
		)
		(pad "1" smd rect
			(at 0.40005 0 90)
			(size 0.4572 0.508)
			(layers "B.Cu" "B.Mask" "B.Paste")
			(net "P12V_E1S_0_ISENSE_MAM_MAM")
		)
		(pad "2" smd rect
			(at -0.40005 0 90)
			(size 0.4572 0.508)
			(layers "B.Cu" "B.Mask" "B.Paste")
			(net "P12V_E1S_0_ISENSE_MAM")
		)
	)
	(footprint ""
		(layer "B.Cu")
		(at 449.518278 -8.3566 -90)
		(property "Reference" "R34"
			(at 0 0 90)
			(layer "B.SilkS")
			(hide yes)
			(effects
				(font
					(size 1.27 1.27)
				)
				(justify mirror)
			)
		)
		(property "Value" ""
			(at 0 0 90)
			(layer "B.Fab")
			(effects
				(font
					(size 1.27 1.27)
				)
				(justify mirror)
			)
		)
		(duplicate_pad_numbers_are_jumpers no)
		(fp_line
			(start -0.7874 0.4064)
			(end 0.7874 0.4064)
			(stroke
				(width 0.1524)
				(type default)
			)
			(layer "B.SilkS")
		)
		(fp_line
			(start 0.7874 0.4064)
			(end 0.7874 -0.4064)
			(stroke
				(width 0.1524)
				(type default)
			)
			(layer "B.SilkS")
		)
		(fp_line
			(start -0.7874 -0.4064)
			(end -0.7874 0.4064)
			(stroke
				(width 0.1524)
				(type default)
			)
			(layer "B.SilkS")
		)
		(fp_line
			(start 0.7874 -0.4064)
			(end -0.7874 -0.4064)
			(stroke
				(width 0.1524)
				(type default)
			)
			(layer "B.SilkS")
		)
		(fp_line
			(start -0.67945 0.3048)
			(end -0.120396 0.3048)
			(stroke
				(width 0.1)
				(type default)
			)
			(layer "B.Fab")
		)
		(fp_line
			(start -0.120396 0.3048)
			(end -0.120396 0.2794)
			(stroke
				(width 0.1)
				(type default)
			)
			(layer "B.Fab")
		)
		(fp_line
			(start 0.12065 0.3048)
			(end 0.67945 0.3048)
			(stroke
				(width 0.1)
				(type default)
			)
			(layer "B.Fab")
		)
		(fp_line
			(start 0.67945 0.3048)
			(end 0.67945 -0.305054)
			(stroke
				(width 0.1)
				(type default)
			)
			(layer "B.Fab")
		)
		(fp_line
			(start -0.120396 0.2794)
			(end 0.12065 0.2794)
			(stroke
				(width 0.1)
				(type default)
			)
			(layer "B.Fab")
		)
		(fp_line
			(start 0.12065 0.2794)
			(end 0.12065 0.3048)
			(stroke
				(width 0.1)
				(type default)
			)
			(layer "B.Fab")
		)
		(fp_line
			(start -0.12065 -0.2794)
			(end -0.12065 -0.3048)
			(stroke
				(width 0.1)
				(type default)
			)
			(layer "B.Fab")
		)
		(fp_line
			(start 0.12065 -0.2794)
			(end -0.12065 -0.2794)
			(stroke
				(width 0.1)
				(type default)
			)
			(layer "B.Fab")
		)
		(fp_line
			(start -0.67945 -0.3048)
			(end -0.67945 0.3048)
			(stroke
				(width 0.1)
				(type default)
			)
			(layer "B.Fab")
		)
		(fp_line
			(start -0.12065 -0.3048)
			(end -0.67945 -0.3048)
			(stroke
				(width 0.1)
				(type default)
			)
			(layer "B.Fab")
		)
		(fp_line
			(start 0.12065 -0.305054)
			(end 0.12065 -0.2794)
			(stroke
				(width 0.1)
				(type default)
			)
			(layer "B.Fab")
		)
		(fp_line
			(start 0.67945 -0.305054)
			(end 0.12065 -0.305054)
			(stroke
				(width 0.1)
				(type default)
			)
			(layer "B.Fab")
		)
		(pad "1" smd circle
			(at 0.40005 0 90)
			(size 0 0)
			(layers "B.Cu" "B.Mask" "B.Paste")
			(net "OCP_SFF_ID1")
		)
		(pad "2" smd circle
			(at -0.40005 0 90)
			(size 0 0)
			(layers "B.Cu" "B.Mask" "B.Paste")
			(net "GND")
		)
	)
	(footprint ""
		(layer "B.Cu")
		(at 90.209878 -143.86941 180)
		(property "Reference" "R8182"
			(at 0 0 0)
			(layer "B.SilkS")
			(hide yes)
			(effects
				(font
					(size 1.27 1.27)
				)
				(justify mirror)
			)
		)
		(property "Value" ""
			(at 0 0 0)
			(layer "B.Fab")
			(effects
				(font
					(size 1.27 1.27)
				)
				(justify mirror)
			)
		)
		(duplicate_pad_numbers_are_jumpers no)
		(fp_line
			(start 0.7874 0.4064)
			(end 0.7874 -0.4064)
			(stroke
				(width 0.1524)
				(type default)
			)
			(layer "B.SilkS")
		)
		(fp_line
			(start 0.7874 -0.4064)
			(end -0.7874 -0.4064)
			(stroke
				(width 0.1524)
				(type default)
			)
			(layer "B.SilkS")
		)
		(fp_line
			(start -0.7874 0.4064)
			(end 0.7874 0.4064)
			(stroke
				(width 0.1524)
				(type default)
			)
			(layer "B.SilkS")
		)
		(fp_line
			(start -0.7874 -0.4064)
			(end -0.7874 0.4064)
			(stroke
				(width 0.1524)
				(type default)
			)
			(layer "B.SilkS")
		)
		(fp_line
			(start 0.67945 0.3048)
			(end 0.67945 -0.305054)
			(stroke
				(width 0.1)
				(type default)
			)
			(layer "B.Fab")
		)
		(fp_line
			(start 0.67945 -0.305054)
			(end 0.12065 -0.305054)
			(stroke
				(width 0.1)
				(type default)
			)
			(layer "B.Fab")
		)
		(fp_line
			(start 0.12065 0.3048)
			(end 0.67945 0.3048)
			(stroke
				(width 0.1)
				(type default)
			)
			(layer "B.Fab")
		)
		(fp_line
			(start 0.12065 0.2794)
			(end 0.12065 0.3048)
			(stroke
				(width 0.1)
				(type default)
			)
			(layer "B.Fab")
		)
		(fp_line
			(start 0.12065 -0.2794)
			(end -0.12065 -0.2794)
			(stroke
				(width 0.1)
				(type default)
			)
			(layer "B.Fab")
		)
		(fp_line
			(start 0.12065 -0.305054)
			(end 0.12065 -0.2794)
			(stroke
				(width 0.1)
				(type default)
			)
			(layer "B.Fab")
		)
		(fp_line
			(start -0.120396 0.3048)
			(end -0.120396 0.2794)
			(stroke
				(width 0.1)
				(type default)
			)
			(layer "B.Fab")
		)
		(fp_line
			(start -0.120396 0.2794)
			(end 0.12065 0.2794)
			(stroke
				(width 0.1)
				(type default)
			)
			(layer "B.Fab")
		)
		(fp_line
			(start -0.12065 -0.2794)
			(end -0.12065 -0.3048)
			(stroke
				(width 0.1)
				(type default)
			)
			(layer "B.Fab")
		)
		(fp_line
			(start -0.12065 -0.3048)
			(end -0.67945 -0.3048)
			(stroke
				(width 0.1)
				(type default)
			)
			(layer "B.Fab")
		)
		(fp_line
			(start -0.67945 0.3048)
			(end -0.120396 0.3048)
			(stroke
				(width 0.1)
				(type default)
			)
			(layer "B.Fab")
		)
		(fp_line
			(start -0.67945 -0.3048)
			(end -0.67945 0.3048)
			(stroke
				(width 0.1)
				(type default)
			)
			(layer "B.Fab")
		)
		(pad "1" smd circle
			(at 0.40005 0)
			(size 0 0)
			(layers "B.Cu" "B.Mask" "B.Paste")
			(net "PVDDCR_CPU0_P1_RESET_N")
		)
		(pad "2" smd circle
			(at -0.40005 0)
			(size 0 0)
			(layers "B.Cu" "B.Mask" "B.Paste")
			(net "PVDDCR_CPU0_P1_RESET_N_R")
		)
	)
	(footprint ""
		(layer "B.Cu")
		(at 90.249756 -326.346058 -90)
		(property "Reference" "PC394_2"
			(at 0 0 90)
			(layer "B.SilkS")
			(hide yes)
			(effects
				(font
					(size 1.27 1.27)
				)
				(justify mirror)
			)
		)
		(property "Value" ""
			(at 0 0 90)
			(layer "B.Fab")
			(effects
				(font
					(size 1.27 1.27)
				)
				(justify mirror)
			)
		)
		(duplicate_pad_numbers_are_jumpers no)
		(fp_line
			(start -1.524 0.762)
			(end 1.524 0.762)
			(stroke
				(width 0.1524)
				(type default)
			)
			(layer "B.SilkS")
		)
		(fp_line
			(start 1.524 0.762)
			(end 1.524 -0.762)
			(stroke
				(width 0.1524)
				(type default)
			)
			(layer "B.SilkS")
		)
		(fp_line
			(start -1.524 -0.762)
			(end -1.524 0.762)
			(stroke
				(width 0.1524)
				(type default)
			)
			(layer "B.SilkS")
		)
		(fp_line
			(start 1.524 -0.762)
			(end -1.524 -0.762)
			(stroke
				(width 0.1524)
				(type default)
			)
			(layer "B.SilkS")
		)
		(fp_line
			(start -1.1049 0.724916)
			(end -1.1049 -0.724916)
			(stroke
				(width 0.1)
				(type default)
			)
			(layer "B.Fab")
		)
		(fp_line
			(start 1.1049 0.724916)
			(end -1.1049 0.724916)
			(stroke
				(width 0.1)
				(type default)
			)
			(layer "B.Fab")
		)
		(fp_line
			(start -1.1049 -0.724916)
			(end 1.1049 -0.724916)
			(stroke
				(width 0.1)
				(type default)
			)
			(layer "B.Fab")
		)
		(fp_line
			(start 1.1049 -0.724916)
			(end 1.1049 0.724916)
			(stroke
				(width 0.1)
				(type default)
			)
			(layer "B.Fab")
		)
		(pad "1" smd rect
			(at 0.889 0 270)
			(size 1.016 1.27)
			(layers "B.Cu" "B.Mask" "B.Paste")
			(net "PVDDCR_CPU1_P1")
		)
		(pad "2" smd rect
			(at -0.889 0 270)
			(size 1.016 1.27)
			(layers "B.Cu" "B.Mask" "B.Paste")
			(net "GND")
		)
	)
	(footprint ""
		(layer "B.Cu")
		(at 20.919186 -195.012564 180)
		(property "Reference" "R1585"
			(at 0 0 0)
			(layer "B.SilkS")
			(hide yes)
			(effects
				(font
					(size 1.27 1.27)
				)
				(justify mirror)
			)
		)
		(property "Value" ""
			(at 0 0 0)
			(layer "B.Fab")
			(effects
				(font
					(size 1.27 1.27)
				)
				(justify mirror)
			)
		)
		(duplicate_pad_numbers_are_jumpers no)
		(fp_line
			(start 0.7874 0.4064)
			(end 0.7874 -0.4064)
			(stroke
				(width 0.1524)
				(type default)
			)
			(layer "B.SilkS")
		)
		(fp_line
			(start 0.7874 -0.4064)
			(end -0.7874 -0.4064)
			(stroke
				(width 0.1524)
				(type default)
			)
			(layer "B.SilkS")
		)
		(fp_line
			(start -0.7874 0.4064)
			(end 0.7874 0.4064)
			(stroke
				(width 0.1524)
				(type default)
			)
			(layer "B.SilkS")
		)
		(fp_line
			(start -0.7874 -0.4064)
			(end -0.7874 0.4064)
			(stroke
				(width 0.1524)
				(type default)
			)
			(layer "B.SilkS")
		)
		(fp_line
			(start 0.67945 0.3048)
			(end 0.67945 -0.305054)
			(stroke
				(width 0.1)
				(type default)
			)
			(layer "B.Fab")
		)
		(fp_line
			(start 0.67945 -0.305054)
			(end 0.12065 -0.305054)
			(stroke
				(width 0.1)
				(type default)
			)
			(layer "B.Fab")
		)
		(fp_line
			(start 0.12065 0.3048)
			(end 0.67945 0.3048)
			(stroke
				(width 0.1)
				(type default)
			)
			(layer "B.Fab")
		)
		(fp_line
			(start 0.12065 0.2794)
			(end 0.12065 0.3048)
			(stroke
				(width 0.1)
				(type default)
			)
			(layer "B.Fab")
		)
		(fp_line
			(start 0.12065 -0.2794)
			(end -0.12065 -0.2794)
			(stroke
				(width 0.1)
				(type default)
			)
			(layer "B.Fab")
		)
		(fp_line
			(start 0.12065 -0.305054)
			(end 0.12065 -0.2794)
			(stroke
				(width 0.1)
				(type default)
			)
			(layer "B.Fab")
		)
		(fp_line
			(start -0.120396 0.3048)
			(end -0.120396 0.2794)
			(stroke
				(width 0.1)
				(type default)
			)
			(layer "B.Fab")
		)
		(fp_line
			(start -0.120396 0.2794)
			(end 0.12065 0.2794)
			(stroke
				(width 0.1)
				(type default)
			)
			(layer "B.Fab")
		)
		(fp_line
			(start -0.12065 -0.2794)
			(end -0.12065 -0.3048)
			(stroke
				(width 0.1)
				(type default)
			)
			(layer "B.Fab")
		)
		(fp_line
			(start -0.12065 -0.3048)
			(end -0.67945 -0.3048)
			(stroke
				(width 0.1)
				(type default)
			)
			(layer "B.Fab")
		)
		(fp_line
			(start -0.67945 0.3048)
			(end -0.120396 0.3048)
			(stroke
				(width 0.1)
				(type default)
			)
			(layer "B.Fab")
		)
		(fp_line
			(start -0.67945 -0.3048)
			(end -0.67945 0.3048)
			(stroke
				(width 0.1)
				(type default)
			)
			(layer "B.Fab")
		)
		(pad "1" smd circle
			(at 0.40005 0)
			(size 0 0)
			(layers "B.Cu" "B.Mask" "B.Paste")
			(net "I3C_SPD_DDRAF_CPU1_SCL")
		)
		(pad "2" smd circle
			(at -0.40005 0)
			(size 0 0)
			(layers "B.Cu" "B.Mask" "B.Paste")
			(net "I3C_SPD_DDRF_CPU1_SCL")
		)
	)
	(footprint ""
		(layer "B.Cu")
		(at 305.918362 -396.393162 -90)
		(property "Reference" "C543"
			(at 0 0 90)
			(layer "B.SilkS")
			(hide yes)
			(effects
				(font
					(size 1.27 1.27)
				)
				(justify mirror)
			)
		)
		(property "Value" ""
			(at 0 0 90)
			(layer "B.Fab")
			(effects
				(font
					(size 1.27 1.27)
				)
				(justify mirror)
			)
		)
		(duplicate_pad_numbers_are_jumpers no)
		(fp_line
			(start -0.299974 0.150114)
			(end 0.299974 0.150114)
			(stroke
				(width 0.1)
				(type default)
			)
			(layer "B.Fab")
		)
		(fp_line
			(start 0.299974 0.150114)
			(end 0.299974 -0.150114)
			(stroke
				(width 0.1)
				(type default)
			)
			(layer "B.Fab")
		)
		(fp_line
			(start -0.299974 -0.150114)
			(end -0.299974 0.150114)
			(stroke
				(width 0.1)
				(type default)
			)
			(layer "B.Fab")
		)
		(fp_line
			(start 0.299974 -0.150114)
			(end -0.299974 -0.150114)
			(stroke
				(width 0.1)
				(type default)
			)
			(layer "B.Fab")
		)
		(pad "1" smd rect
			(at 0.2667 0 90)
			(size 0.3048 0.381)
			(layers "B.Cu" "B.Mask" "B.Paste")
			(net "P0V9_CPU0_RT0_2A")
		)
		(pad "2" smd rect
			(at -0.2667 0 90)
			(size 0.3048 0.381)
			(layers "B.Cu" "B.Mask" "B.Paste")
			(net "GND")
		)
	)
	(footprint ""
		(layer "B.Cu")
		(at 295.478454 -190.94831 180)
		(property "Reference" "R292"
			(at 0 0 0)
			(layer "B.SilkS")
			(hide yes)
			(effects
				(font
					(size 1.27 1.27)
				)
				(justify mirror)
			)
		)
		(property "Value" ""
			(at 0 0 0)
			(layer "B.Fab")
			(effects
				(font
					(size 1.27 1.27)
				)
				(justify mirror)
			)
		)
		(duplicate_pad_numbers_are_jumpers no)
		(fp_line
			(start 0.7874 0.4064)
			(end 0.7874 -0.4064)
			(stroke
				(width 0.1524)
				(type default)
			)
			(layer "B.SilkS")
		)
		(fp_line
			(start 0.7874 -0.4064)
			(end -0.7874 -0.4064)
			(stroke
				(width 0.1524)
				(type default)
			)
			(layer "B.SilkS")
		)
		(fp_line
			(start -0.7874 0.4064)
			(end 0.7874 0.4064)
			(stroke
				(width 0.1524)
				(type default)
			)
			(layer "B.SilkS")
		)
		(fp_line
			(start -0.7874 -0.4064)
			(end -0.7874 0.4064)
			(stroke
				(width 0.1524)
				(type default)
			)
			(layer "B.SilkS")
		)
		(fp_line
			(start 0.67945 0.3048)
			(end 0.67945 -0.305054)
			(stroke
				(width 0.1)
				(type default)
			)
			(layer "B.Fab")
		)
		(fp_line
			(start 0.67945 -0.305054)
			(end 0.12065 -0.305054)
			(stroke
				(width 0.1)
				(type default)
			)
			(layer "B.Fab")
		)
		(fp_line
			(start 0.12065 0.3048)
			(end 0.67945 0.3048)
			(stroke
				(width 0.1)
				(type default)
			)
			(layer "B.Fab")
		)
		(fp_line
			(start 0.12065 0.2794)
			(end 0.12065 0.3048)
			(stroke
				(width 0.1)
				(type default)
			)
			(layer "B.Fab")
		)
		(fp_line
			(start 0.12065 -0.2794)
			(end -0.12065 -0.2794)
			(stroke
				(width 0.1)
				(type default)
			)
			(layer "B.Fab")
		)
		(fp_line
			(start 0.12065 -0.305054)
			(end 0.12065 -0.2794)
			(stroke
				(width 0.1)
				(type default)
			)
			(layer "B.Fab")
		)
		(fp_line
			(start -0.120396 0.3048)
			(end -0.120396 0.2794)
			(stroke
				(width 0.1)
				(type default)
			)
			(layer "B.Fab")
		)
		(fp_line
			(start -0.120396 0.2794)
			(end 0.12065 0.2794)
			(stroke
				(width 0.1)
				(type default)
			)
			(layer "B.Fab")
		)
		(fp_line
			(start -0.12065 -0.2794)
			(end -0.12065 -0.3048)
			(stroke
				(width 0.1)
				(type default)
			)
			(layer "B.Fab")
		)
		(fp_line
			(start -0.12065 -0.3048)
			(end -0.67945 -0.3048)
			(stroke
				(width 0.1)
				(type default)
			)
			(layer "B.Fab")
		)
		(fp_line
			(start -0.67945 0.3048)
			(end -0.120396 0.3048)
			(stroke
				(width 0.1)
				(type default)
			)
			(layer "B.Fab")
		)
		(fp_line
			(start -0.67945 -0.3048)
			(end -0.67945 0.3048)
			(stroke
				(width 0.1)
				(type default)
			)
			(layer "B.Fab")
		)
		(pad "1" smd circle
			(at 0.40005 0)
			(size 0 0)
			(layers "B.Cu" "B.Mask" "B.Paste")
			(net "PWRGD_CHB_CPU0_DIMM")
		)
		(pad "2" smd circle
			(at -0.40005 0)
			(size 0 0)
			(layers "B.Cu" "B.Mask" "B.Paste")
			(net "PWRGD_CHAF_CPU0")
		)
	)
	(footprint ""
		(layer "B.Cu")
		(at 233.013758 -224.397316 -90)
		(property "Reference" "C2"
			(at 0 0 90)
			(layer "B.SilkS")
			(hide yes)
			(effects
				(font
					(size 1.27 1.27)
				)
				(justify mirror)
			)
		)
		(property "Value" ""
			(at 0 0 90)
			(layer "B.Fab")
			(effects
				(font
					(size 1.27 1.27)
				)
				(justify mirror)
			)
		)
		(duplicate_pad_numbers_are_jumpers no)
		(fp_line
			(start -0.7874 0.4064)
			(end 0.7874 0.4064)
			(stroke
				(width 0.1524)
				(type default)
			)
			(layer "B.SilkS")
		)
		(fp_line
			(start 0.7874 0.4064)
			(end 0.7874 -0.4064)
			(stroke
				(width 0.1524)
				(type default)
			)
			(layer "B.SilkS")
		)
		(fp_line
			(start -0.7874 -0.4064)
			(end -0.7874 0.4064)
			(stroke
				(width 0.1524)
				(type default)
			)
			(layer "B.SilkS")
		)
		(fp_line
			(start 0.7874 -0.4064)
			(end -0.7874 -0.4064)
			(stroke
				(width 0.1524)
				(type default)
			)
			(layer "B.SilkS")
		)
		(fp_line
			(start -0.67945 0.3048)
			(end -0.120396 0.3048)
			(stroke
				(width 0.1)
				(type default)
			)
			(layer "B.Fab")
		)
		(fp_line
			(start -0.120396 0.3048)
			(end -0.120396 0.2794)
			(stroke
				(width 0.1)
				(type default)
			)
			(layer "B.Fab")
		)
		(fp_line
			(start 0.12065 0.3048)
			(end 0.67945 0.3048)
			(stroke
				(width 0.1)
				(type default)
			)
			(layer "B.Fab")
		)
		(fp_line
			(start 0.67945 0.3048)
			(end 0.67945 -0.305054)
			(stroke
				(width 0.1)
				(type default)
			)
			(layer "B.Fab")
		)
		(fp_line
			(start -0.120396 0.2794)
			(end 0.12065 0.2794)
			(stroke
				(width 0.1)
				(type default)
			)
			(layer "B.Fab")
		)
		(fp_line
			(start 0.12065 0.2794)
			(end 0.12065 0.3048)
			(stroke
				(width 0.1)
				(type default)
			)
			(layer "B.Fab")
		)
		(fp_line
			(start -0.12065 -0.2794)
			(end -0.12065 -0.3048)
			(stroke
				(width 0.1)
				(type default)
			)
			(layer "B.Fab")
		)
		(fp_line
			(start 0.12065 -0.2794)
			(end -0.12065 -0.2794)
			(stroke
				(width 0.1)
				(type default)
			)
			(layer "B.Fab")
		)
		(fp_line
			(start -0.67945 -0.3048)
			(end -0.67945 0.3048)
			(stroke
				(width 0.1)
				(type default)
			)
			(layer "B.Fab")
		)
		(fp_line
			(start -0.12065 -0.3048)
			(end -0.67945 -0.3048)
			(stroke
				(width 0.1)
				(type default)
			)
			(layer "B.Fab")
		)
		(fp_line
			(start 0.12065 -0.305054)
			(end 0.12065 -0.2794)
			(stroke
				(width 0.1)
				(type default)
			)
			(layer "B.Fab")
		)
		(fp_line
			(start 0.67945 -0.305054)
			(end 0.12065 -0.305054)
			(stroke
				(width 0.1)
				(type default)
			)
			(layer "B.Fab")
		)
		(pad "1" smd circle
			(at 0.40005 0 90)
			(size 0 0)
			(layers "B.Cu" "B.Mask" "B.Paste")
			(net "P3V3_AUX")
		)
		(pad "2" smd circle
			(at -0.40005 0 90)
			(size 0 0)
			(layers "B.Cu" "B.Mask" "B.Paste")
			(net "GND")
		)
	)
	(footprint ""
		(layer "B.Cu")
		(at 162.489388 -13.651738 180)
		(property "Reference" "R4508"
			(at 0 0 0)
			(layer "B.SilkS")
			(hide yes)
			(effects
				(font
					(size 1.27 1.27)
				)
				(justify mirror)
			)
		)
		(property "Value" ""
			(at 0 0 0)
			(layer "B.Fab")
			(effects
				(font
					(size 1.27 1.27)
				)
				(justify mirror)
			)
		)
		(duplicate_pad_numbers_are_jumpers no)
		(fp_line
			(start 0.7874 0.4064)
			(end 0.7874 -0.4064)
			(stroke
				(width 0.1524)
				(type default)
			)
			(layer "B.SilkS")
		)
		(fp_line
			(start 0.7874 -0.4064)
			(end -0.7874 -0.4064)
			(stroke
				(width 0.1524)
				(type default)
			)
			(layer "B.SilkS")
		)
		(fp_line
			(start -0.7874 0.4064)
			(end 0.7874 0.4064)
			(stroke
				(width 0.1524)
				(type default)
			)
			(layer "B.SilkS")
		)
		(fp_line
			(start -0.7874 -0.4064)
			(end -0.7874 0.4064)
			(stroke
				(width 0.1524)
				(type default)
			)
			(layer "B.SilkS")
		)
		(fp_line
			(start 0.67945 0.3048)
			(end 0.67945 -0.305054)
			(stroke
				(width 0.1)
				(type default)
			)
			(layer "B.Fab")
		)
		(fp_line
			(start 0.67945 -0.305054)
			(end 0.12065 -0.305054)
			(stroke
				(width 0.1)
				(type default)
			)
			(layer "B.Fab")
		)
		(fp_line
			(start 0.12065 0.3048)
			(end 0.67945 0.3048)
			(stroke
				(width 0.1)
				(type default)
			)
			(layer "B.Fab")
		)
		(fp_line
			(start 0.12065 0.2794)
			(end 0.12065 0.3048)
			(stroke
				(width 0.1)
				(type default)
			)
			(layer "B.Fab")
		)
		(fp_line
			(start 0.12065 -0.2794)
			(end -0.12065 -0.2794)
			(stroke
				(width 0.1)
				(type default)
			)
			(layer "B.Fab")
		)
		(fp_line
			(start 0.12065 -0.305054)
			(end 0.12065 -0.2794)
			(stroke
				(width 0.1)
				(type default)
			)
			(layer "B.Fab")
		)
		(fp_line
			(start -0.120396 0.3048)
			(end -0.120396 0.2794)
			(stroke
				(width 0.1)
				(type default)
			)
			(layer "B.Fab")
		)
		(fp_line
			(start -0.120396 0.2794)
			(end 0.12065 0.2794)
			(stroke
				(width 0.1)
				(type default)
			)
			(layer "B.Fab")
		)
		(fp_line
			(start -0.12065 -0.2794)
			(end -0.12065 -0.3048)
			(stroke
				(width 0.1)
				(type default)
			)
			(layer "B.Fab")
		)
		(fp_line
			(start -0.12065 -0.3048)
			(end -0.67945 -0.3048)
			(stroke
				(width 0.1)
				(type default)
			)
			(layer "B.Fab")
		)
		(fp_line
			(start -0.67945 0.3048)
			(end -0.120396 0.3048)
			(stroke
				(width 0.1)
				(type default)
			)
			(layer "B.Fab")
		)
		(fp_line
			(start -0.67945 -0.3048)
			(end -0.67945 0.3048)
			(stroke
				(width 0.1)
				(type default)
			)
			(layer "B.Fab")
		)
		(pad "1" smd circle
			(at 0.40005 0)
			(size 0 0)
			(layers "B.Cu" "B.Mask" "B.Paste")
			(net "SMB_1_PLD_3V3AUX_SCL")
		)
		(pad "2" smd circle
			(at -0.40005 0)
			(size 0 0)
			(layers "B.Cu" "B.Mask" "B.Paste")
			(net "SMB_1_PLD_3V3AUX_SCL_R3")
		)
	)
	(footprint ""
		(layer "B.Cu")
		(at 178.881532 -414.283144 180)
		(property "Reference" "C1769"
			(at 0 0 0)
			(layer "B.SilkS")
			(hide yes)
			(effects
				(font
					(size 1.27 1.27)
				)
				(justify mirror)
			)
		)
		(property "Value" ""
			(at 0 0 0)
			(layer "B.Fab")
			(effects
				(font
					(size 1.27 1.27)
				)
				(justify mirror)
			)
		)
		(duplicate_pad_numbers_are_jumpers no)
		(fp_line
			(start 0.7874 0.4064)
			(end 0.7874 -0.4064)
			(stroke
				(width 0.1524)
				(type default)
			)
			(layer "B.SilkS")
		)
		(fp_line
			(start 0.7874 -0.4064)
			(end -0.7874 -0.4064)
			(stroke
				(width 0.1524)
				(type default)
			)
			(layer "B.SilkS")
		)
		(fp_line
			(start -0.7874 0.4064)
			(end 0.7874 0.4064)
			(stroke
				(width 0.1524)
				(type default)
			)
			(layer "B.SilkS")
		)
		(fp_line
			(start -0.7874 -0.4064)
			(end -0.7874 0.4064)
			(stroke
				(width 0.1524)
				(type default)
			)
			(layer "B.SilkS")
		)
		(fp_line
			(start 0.67945 0.3048)
			(end 0.67945 -0.305054)
			(stroke
				(width 0.1)
				(type default)
			)
			(layer "B.Fab")
		)
		(fp_line
			(start 0.67945 -0.305054)
			(end 0.12065 -0.305054)
			(stroke
				(width 0.1)
				(type default)
			)
			(layer "B.Fab")
		)
		(fp_line
			(start 0.12065 0.3048)
			(end 0.67945 0.3048)
			(stroke
				(width 0.1)
				(type default)
			)
			(layer "B.Fab")
		)
		(fp_line
			(start 0.12065 0.2794)
			(end 0.12065 0.3048)
			(stroke
				(width 0.1)
				(type default)
			)
			(layer "B.Fab")
		)
		(fp_line
			(start 0.12065 -0.2794)
			(end -0.12065 -0.2794)
			(stroke
				(width 0.1)
				(type default)
			)
			(layer "B.Fab")
		)
		(fp_line
			(start 0.12065 -0.305054)
			(end 0.12065 -0.2794)
			(stroke
				(width 0.1)
				(type default)
			)
			(layer "B.Fab")
		)
		(fp_line
			(start -0.120396 0.3048)
			(end -0.120396 0.2794)
			(stroke
				(width 0.1)
				(type default)
			)
			(layer "B.Fab")
		)
		(fp_line
			(start -0.120396 0.2794)
			(end 0.12065 0.2794)
			(stroke
				(width 0.1)
				(type default)
			)
			(layer "B.Fab")
		)
		(fp_line
			(start -0.12065 -0.2794)
			(end -0.12065 -0.3048)
			(stroke
				(width 0.1)
				(type default)
			)
			(layer "B.Fab")
		)
		(fp_line
			(start -0.12065 -0.3048)
			(end -0.67945 -0.3048)
			(stroke
				(width 0.1)
				(type default)
			)
			(layer "B.Fab")
		)
		(fp_line
			(start -0.67945 0.3048)
			(end -0.120396 0.3048)
			(stroke
				(width 0.1)
				(type default)
			)
			(layer "B.Fab")
		)
		(fp_line
			(start -0.67945 -0.3048)
			(end -0.67945 0.3048)
			(stroke
				(width 0.1)
				(type default)
			)
			(layer "B.Fab")
		)
		(pad "1" smd circle
			(at 0.40005 0)
			(size 0 0)
			(layers "B.Cu" "B.Mask" "B.Paste")
			(net "P3V3_AUX")
		)
		(pad "2" smd circle
			(at -0.40005 0)
			(size 0 0)
			(layers "B.Cu" "B.Mask" "B.Paste")
			(net "GND")
		)
	)
	(footprint ""
		(layer "B.Cu")
		(at 233.807 -338.582 180)
		(property "Reference" "R1025"
			(at 0 0 0)
			(layer "B.SilkS")
			(hide yes)
			(effects
				(font
					(size 1.27 1.27)
				)
				(justify mirror)
			)
		)
		(property "Value" ""
			(at 0 0 0)
			(layer "B.Fab")
			(effects
				(font
					(size 1.27 1.27)
				)
				(justify mirror)
			)
		)
		(duplicate_pad_numbers_are_jumpers no)
		(fp_line
			(start 0.32512 0.175006)
			(end 0.32512 -0.175006)
			(stroke
				(width 0.1)
				(type default)
			)
			(layer "B.Fab")
		)
		(fp_line
			(start 0.32512 -0.175006)
			(end -0.32512 -0.175006)
			(stroke
				(width 0.1)
				(type default)
			)
			(layer "B.Fab")
		)
		(fp_line
			(start -0.32512 0.175006)
			(end 0.32512 0.175006)
			(stroke
				(width 0.1)
				(type default)
			)
			(layer "B.Fab")
		)
		(fp_line
			(start -0.32512 -0.175006)
			(end -0.32512 0.175006)
			(stroke
				(width 0.1)
				(type default)
			)
			(layer "B.Fab")
		)
		(pad "1" smd rect
			(at 0.2667 0)
			(size 0.3048 0.381)
			(layers "B.Cu" "B.Mask" "B.Paste")
			(net "SMB_RT_CPU0_P1_R_SCL")
		)
		(pad "2" smd rect
			(at -0.2667 0 180)
			(size 0.3048 0.381)
			(layers "B.Cu" "B.Mask" "B.Paste")
			(net "SMB_RT_CPU0_P1_R2_SCL")
		)
	)
	(footprint ""
		(layer "B.Cu")
		(at 104.561386 -266.005564)
		(property "Reference" "C2261"
			(at 0 0 0)
			(layer "B.SilkS")
			(hide yes)
			(effects
				(font
					(size 1.27 1.27)
				)
				(justify mirror)
			)
		)
		(property "Value" ""
			(at 0 0 0)
			(layer "B.Fab")
			(effects
				(font
					(size 1.27 1.27)
				)
				(justify mirror)
			)
		)
		(duplicate_pad_numbers_are_jumpers no)
		(fp_line
			(start -0.7874 -0.4064)
			(end -0.7874 0.4064)
			(stroke
				(width 0.1524)
				(type default)
			)
			(layer "B.SilkS")
		)
		(fp_line
			(start -0.7874 0.4064)
			(end 0.7874 0.4064)
			(stroke
				(width 0.1524)
				(type default)
			)
			(layer "B.SilkS")
		)
		(fp_line
			(start 0.7874 -0.4064)
			(end -0.7874 -0.4064)
			(stroke
				(width 0.1524)
				(type default)
			)
			(layer "B.SilkS")
		)
		(fp_line
			(start 0.7874 0.4064)
			(end 0.7874 -0.4064)
			(stroke
				(width 0.1524)
				(type default)
			)
			(layer "B.SilkS")
		)
		(fp_line
			(start -0.67945 -0.3048)
			(end -0.67945 0.3048)
			(stroke
				(width 0.1)
				(type default)
			)
			(layer "B.Fab")
		)
		(fp_line
			(start -0.67945 0.3048)
			(end -0.120396 0.3048)
			(stroke
				(width 0.1)
				(type default)
			)
			(layer "B.Fab")
		)
		(fp_line
			(start -0.12065 -0.3048)
			(end -0.67945 -0.3048)
			(stroke
				(width 0.1)
				(type default)
			)
			(layer "B.Fab")
		)
		(fp_line
			(start -0.12065 -0.2794)
			(end -0.12065 -0.3048)
			(stroke
				(width 0.1)
				(type default)
			)
			(layer "B.Fab")
		)
		(fp_line
			(start -0.120396 0.2794)
			(end 0.12065 0.2794)
			(stroke
				(width 0.1)
				(type default)
			)
			(layer "B.Fab")
		)
		(fp_line
			(start -0.120396 0.3048)
			(end -0.120396 0.2794)
			(stroke
				(width 0.1)
				(type default)
			)
			(layer "B.Fab")
		)
		(fp_line
			(start 0.12065 -0.305054)
			(end 0.12065 -0.2794)
			(stroke
				(width 0.1)
				(type default)
			)
			(layer "B.Fab")
		)
		(fp_line
			(start 0.12065 -0.2794)
			(end -0.12065 -0.2794)
			(stroke
				(width 0.1)
				(type default)
			)
			(layer "B.Fab")
		)
		(fp_line
			(start 0.12065 0.2794)
			(end 0.12065 0.3048)
			(stroke
				(width 0.1)
				(type default)
			)
			(layer "B.Fab")
		)
		(fp_line
			(start 0.12065 0.3048)
			(end 0.67945 0.3048)
			(stroke
				(width 0.1)
				(type default)
			)
			(layer "B.Fab")
		)
		(fp_line
			(start 0.67945 -0.305054)
			(end 0.12065 -0.305054)
			(stroke
				(width 0.1)
				(type default)
			)
			(layer "B.Fab")
		)
		(fp_line
			(start 0.67945 0.3048)
			(end 0.67945 -0.305054)
			(stroke
				(width 0.1)
				(type default)
			)
			(layer "B.Fab")
		)
		(pad "1" smd circle
			(at 0.40005 0 180)
			(size 0 0)
			(layers "B.Cu" "B.Mask" "B.Paste")
			(net "PVDD11_S3_P1")
		)
		(pad "2" smd circle
			(at -0.40005 0 180)
			(size 0 0)
			(layers "B.Cu" "B.Mask" "B.Paste")
			(net "GND")
		)
	)
	(footprint ""
		(layer "B.Cu")
		(at 354.406454 -267.52931)
		(property "Reference" "C2253"
			(at 0 0 0)
			(layer "B.SilkS")
			(hide yes)
			(effects
				(font
					(size 1.27 1.27)
				)
				(justify mirror)
			)
		)
		(property "Value" ""
			(at 0 0 0)
			(layer "B.Fab")
			(effects
				(font
					(size 1.27 1.27)
				)
				(justify mirror)
			)
		)
		(duplicate_pad_numbers_are_jumpers no)
		(fp_line
			(start -0.7874 -0.4064)
			(end -0.7874 0.4064)
			(stroke
				(width 0.1524)
				(type default)
			)
			(layer "B.SilkS")
		)
		(fp_line
			(start -0.7874 0.4064)
			(end 0.7874 0.4064)
			(stroke
				(width 0.1524)
				(type default)
			)
			(layer "B.SilkS")
		)
		(fp_line
			(start 0.7874 -0.4064)
			(end -0.7874 -0.4064)
			(stroke
				(width 0.1524)
				(type default)
			)
			(layer "B.SilkS")
		)
		(fp_line
			(start 0.7874 0.4064)
			(end 0.7874 -0.4064)
			(stroke
				(width 0.1524)
				(type default)
			)
			(layer "B.SilkS")
		)
		(fp_line
			(start -0.67945 -0.3048)
			(end -0.67945 0.3048)
			(stroke
				(width 0.1)
				(type default)
			)
			(layer "B.Fab")
		)
		(fp_line
			(start -0.67945 0.3048)
			(end -0.120396 0.3048)
			(stroke
				(width 0.1)
				(type default)
			)
			(layer "B.Fab")
		)
		(fp_line
			(start -0.12065 -0.3048)
			(end -0.67945 -0.3048)
			(stroke
				(width 0.1)
				(type default)
			)
			(layer "B.Fab")
		)
		(fp_line
			(start -0.12065 -0.2794)
			(end -0.12065 -0.3048)
			(stroke
				(width 0.1)
				(type default)
			)
			(layer "B.Fab")
		)
		(fp_line
			(start -0.120396 0.2794)
			(end 0.12065 0.2794)
			(stroke
				(width 0.1)
				(type default)
			)
			(layer "B.Fab")
		)
		(fp_line
			(start -0.120396 0.3048)
			(end -0.120396 0.2794)
			(stroke
				(width 0.1)
				(type default)
			)
			(layer "B.Fab")
		)
		(fp_line
			(start 0.12065 -0.305054)
			(end 0.12065 -0.2794)
			(stroke
				(width 0.1)
				(type default)
			)
			(layer "B.Fab")
		)
		(fp_line
			(start 0.12065 -0.2794)
			(end -0.12065 -0.2794)
			(stroke
				(width 0.1)
				(type default)
			)
			(layer "B.Fab")
		)
		(fp_line
			(start 0.12065 0.2794)
			(end 0.12065 0.3048)
			(stroke
				(width 0.1)
				(type default)
			)
			(layer "B.Fab")
		)
		(fp_line
			(start 0.12065 0.3048)
			(end 0.67945 0.3048)
			(stroke
				(width 0.1)
				(type default)
			)
			(layer "B.Fab")
		)
		(fp_line
			(start 0.67945 -0.305054)
			(end 0.12065 -0.305054)
			(stroke
				(width 0.1)
				(type default)
			)
			(layer "B.Fab")
		)
		(fp_line
			(start 0.67945 0.3048)
			(end 0.67945 -0.305054)
			(stroke
				(width 0.1)
				(type default)
			)
			(layer "B.Fab")
		)
		(pad "1" smd circle
			(at 0.40005 0 180)
			(size 0 0)
			(layers "B.Cu" "B.Mask" "B.Paste")
			(net "PVDDCR_CPU1_P0")
		)
		(pad "2" smd circle
			(at -0.40005 0 180)
			(size 0 0)
			(layers "B.Cu" "B.Mask" "B.Paste")
			(net "GND")
		)
	)
	(footprint ""
		(layer "B.Cu")
		(at 309.81777 -346.784168 90)
		(property "Reference" "PC125_4"
			(at 0 0 90)
			(layer "B.SilkS")
			(hide yes)
			(effects
				(font
					(size 1.27 1.27)
				)
				(justify mirror)
			)
		)
		(property "Value" ""
			(at 0 0 90)
			(layer "B.Fab")
			(effects
				(font
					(size 1.27 1.27)
				)
				(justify mirror)
			)
		)
		(duplicate_pad_numbers_are_jumpers no)
		(fp_line
			(start 1.524 -0.762)
			(end -1.524 -0.762)
			(stroke
				(width 0.1524)
				(type default)
			)
			(layer "B.SilkS")
		)
		(fp_line
			(start -1.524 -0.762)
			(end -1.524 0.762)
			(stroke
				(width 0.1524)
				(type default)
			)
			(layer "B.SilkS")
		)
		(fp_line
			(start 1.524 0.762)
			(end 1.524 -0.762)
			(stroke
				(width 0.1524)
				(type default)
			)
			(layer "B.SilkS")
		)
		(fp_line
			(start -1.524 0.762)
			(end 1.524 0.762)
			(stroke
				(width 0.1524)
				(type default)
			)
			(layer "B.SilkS")
		)
		(fp_line
			(start 1.1049 -0.724916)
			(end 1.1049 0.724916)
			(stroke
				(width 0.1)
				(type default)
			)
			(layer "B.Fab")
		)
		(fp_line
			(start -1.1049 -0.724916)
			(end 1.1049 -0.724916)
			(stroke
				(width 0.1)
				(type default)
			)
			(layer "B.Fab")
		)
		(fp_line
			(start 1.1049 0.724916)
			(end -1.1049 0.724916)
			(stroke
				(width 0.1)
				(type default)
			)
			(layer "B.Fab")
		)
		(fp_line
			(start -1.1049 0.724916)
			(end -1.1049 -0.724916)
			(stroke
				(width 0.1)
				(type default)
			)
			(layer "B.Fab")
		)
		(pad "1" smd rect
			(at 0.889 0 90)
			(size 1.016 1.27)
			(layers "B.Cu" "B.Mask" "B.Paste")
			(net "SW_P12V_AUX_PVDDCR_CPU1_P0_FLT")
		)
		(pad "2" smd rect
			(at -0.889 0 90)
			(size 1.016 1.27)
			(layers "B.Cu" "B.Mask" "B.Paste")
			(net "GND")
		)
	)
	(footprint ""
		(layer "B.Cu")
		(at 141.623542 -384.66268 180)
		(property "Reference" "R880"
			(at 0 0 0)
			(layer "B.SilkS")
			(hide yes)
			(effects
				(font
					(size 1.27 1.27)
				)
				(justify mirror)
			)
		)
		(property "Value" ""
			(at 0 0 0)
			(layer "B.Fab")
			(effects
				(font
					(size 1.27 1.27)
				)
				(justify mirror)
			)
		)
		(duplicate_pad_numbers_are_jumpers no)
		(fp_line
			(start 0.32512 0.175006)
			(end 0.32512 -0.175006)
			(stroke
				(width 0.1)
				(type default)
			)
			(layer "B.Fab")
		)
		(fp_line
			(start 0.32512 -0.175006)
			(end -0.32512 -0.175006)
			(stroke
				(width 0.1)
				(type default)
			)
			(layer "B.Fab")
		)
		(fp_line
			(start -0.32512 0.175006)
			(end 0.32512 0.175006)
			(stroke
				(width 0.1)
				(type default)
			)
			(layer "B.Fab")
		)
		(fp_line
			(start -0.32512 -0.175006)
			(end -0.32512 0.175006)
			(stroke
				(width 0.1)
				(type default)
			)
			(layer "B.Fab")
		)
		(pad "1" smd rect
			(at 0.2667 0)
			(size 0.3048 0.381)
			(layers "B.Cu" "B.Mask" "B.Paste")
			(net "P1V8_CPU1_RT_1D")
		)
		(pad "2" smd rect
			(at -0.2667 0 180)
			(size 0.3048 0.381)
			(layers "B.Cu" "B.Mask" "B.Paste")
			(net "TEST1_RT_CPU1_P2")
		)
	)
	(footprint ""
		(layer "B.Cu")
		(at 398.680178 -324.812152 180)
		(property "Reference" "R1592"
			(at 0 0 0)
			(layer "B.SilkS")
			(hide yes)
			(effects
				(font
					(size 1.27 1.27)
				)
				(justify mirror)
			)
		)
		(property "Value" ""
			(at 0 0 0)
			(layer "B.Fab")
			(effects
				(font
					(size 1.27 1.27)
				)
				(justify mirror)
			)
		)
		(duplicate_pad_numbers_are_jumpers no)
		(fp_line
			(start 0.7874 0.4064)
			(end 0.7874 -0.4064)
			(stroke
				(width 0.1524)
				(type default)
			)
			(layer "B.SilkS")
		)
		(fp_line
			(start 0.7874 -0.4064)
			(end -0.7874 -0.4064)
			(stroke
				(width 0.1524)
				(type default)
			)
			(layer "B.SilkS")
		)
		(fp_line
			(start -0.7874 0.4064)
			(end 0.7874 0.4064)
			(stroke
				(width 0.1524)
				(type default)
			)
			(layer "B.SilkS")
		)
		(fp_line
			(start -0.7874 -0.4064)
			(end -0.7874 0.4064)
			(stroke
				(width 0.1524)
				(type default)
			)
			(layer "B.SilkS")
		)
		(fp_line
			(start 0.67945 0.3048)
			(end 0.67945 -0.305054)
			(stroke
				(width 0.1)
				(type default)
			)
			(layer "B.Fab")
		)
		(fp_line
			(start 0.67945 -0.305054)
			(end 0.12065 -0.305054)
			(stroke
				(width 0.1)
				(type default)
			)
			(layer "B.Fab")
		)
		(fp_line
			(start 0.12065 0.3048)
			(end 0.67945 0.3048)
			(stroke
				(width 0.1)
				(type default)
			)
			(layer "B.Fab")
		)
		(fp_line
			(start 0.12065 0.2794)
			(end 0.12065 0.3048)
			(stroke
				(width 0.1)
				(type default)
			)
			(layer "B.Fab")
		)
		(fp_line
			(start 0.12065 -0.2794)
			(end -0.12065 -0.2794)
			(stroke
				(width 0.1)
				(type default)
			)
			(layer "B.Fab")
		)
		(fp_line
			(start 0.12065 -0.305054)
			(end 0.12065 -0.2794)
			(stroke
				(width 0.1)
				(type default)
			)
			(layer "B.Fab")
		)
		(fp_line
			(start -0.120396 0.3048)
			(end -0.120396 0.2794)
			(stroke
				(width 0.1)
				(type default)
			)
			(layer "B.Fab")
		)
		(fp_line
			(start -0.120396 0.2794)
			(end 0.12065 0.2794)
			(stroke
				(width 0.1)
				(type default)
			)
			(layer "B.Fab")
		)
		(fp_line
			(start -0.12065 -0.2794)
			(end -0.12065 -0.3048)
			(stroke
				(width 0.1)
				(type default)
			)
			(layer "B.Fab")
		)
		(fp_line
			(start -0.12065 -0.3048)
			(end -0.67945 -0.3048)
			(stroke
				(width 0.1)
				(type default)
			)
			(layer "B.Fab")
		)
		(fp_line
			(start -0.67945 0.3048)
			(end -0.120396 0.3048)
			(stroke
				(width 0.1)
				(type default)
			)
			(layer "B.Fab")
		)
		(fp_line
			(start -0.67945 -0.3048)
			(end -0.67945 0.3048)
			(stroke
				(width 0.1)
				(type default)
			)
			(layer "B.Fab")
		)
		(pad "1" smd rect
			(at 0.40005 0 180)
			(size 0.4572 0.508)
			(layers "B.Cu" "B.Mask" "B.Paste")
			(net "ESPI_CPU0_CS1_N")
		)
		(pad "2" smd rect
			(at -0.40005 0 180)
			(size 0.4572 0.508)
			(layers "B.Cu" "B.Mask" "B.Paste")
			(net "CPU0_ESPI_CS0_N")
		)
	)
	(footprint ""
		(layer "B.Cu")
		(at 93.4212 -138.176)
		(property "Reference" "R308"
			(at 0 0 0)
			(layer "B.SilkS")
			(hide yes)
			(effects
				(font
					(size 1.27 1.27)
				)
				(justify mirror)
			)
		)
		(property "Value" ""
			(at 0 0 0)
			(layer "B.Fab")
			(effects
				(font
					(size 1.27 1.27)
				)
				(justify mirror)
			)
		)
		(duplicate_pad_numbers_are_jumpers no)
		(fp_line
			(start -0.7874 -0.4064)
			(end -0.7874 0.4064)
			(stroke
				(width 0.1524)
				(type default)
			)
			(layer "B.SilkS")
		)
		(fp_line
			(start -0.7874 0.4064)
			(end 0.7874 0.4064)
			(stroke
				(width 0.1524)
				(type default)
			)
			(layer "B.SilkS")
		)
		(fp_line
			(start 0.7874 -0.4064)
			(end -0.7874 -0.4064)
			(stroke
				(width 0.1524)
				(type default)
			)
			(layer "B.SilkS")
		)
		(fp_line
			(start 0.7874 0.4064)
			(end 0.7874 -0.4064)
			(stroke
				(width 0.1524)
				(type default)
			)
			(layer "B.SilkS")
		)
		(fp_line
			(start -0.67945 -0.3048)
			(end -0.67945 0.3048)
			(stroke
				(width 0.1)
				(type default)
			)
			(layer "B.Fab")
		)
		(fp_line
			(start -0.67945 0.3048)
			(end -0.120396 0.3048)
			(stroke
				(width 0.1)
				(type default)
			)
			(layer "B.Fab")
		)
		(fp_line
			(start -0.12065 -0.3048)
			(end -0.67945 -0.3048)
			(stroke
				(width 0.1)
				(type default)
			)
			(layer "B.Fab")
		)
		(fp_line
			(start -0.12065 -0.2794)
			(end -0.12065 -0.3048)
			(stroke
				(width 0.1)
				(type default)
			)
			(layer "B.Fab")
		)
		(fp_line
			(start -0.120396 0.2794)
			(end 0.12065 0.2794)
			(stroke
				(width 0.1)
				(type default)
			)
			(layer "B.Fab")
		)
		(fp_line
			(start -0.120396 0.3048)
			(end -0.120396 0.2794)
			(stroke
				(width 0.1)
				(type default)
			)
			(layer "B.Fab")
		)
		(fp_line
			(start 0.12065 -0.305054)
			(end 0.12065 -0.2794)
			(stroke
				(width 0.1)
				(type default)
			)
			(layer "B.Fab")
		)
		(fp_line
			(start 0.12065 -0.2794)
			(end -0.12065 -0.2794)
			(stroke
				(width 0.1)
				(type default)
			)
			(layer "B.Fab")
		)
		(fp_line
			(start 0.12065 0.2794)
			(end 0.12065 0.3048)
			(stroke
				(width 0.1)
				(type default)
			)
			(layer "B.Fab")
		)
		(fp_line
			(start 0.12065 0.3048)
			(end 0.67945 0.3048)
			(stroke
				(width 0.1)
				(type default)
			)
			(layer "B.Fab")
		)
		(fp_line
			(start 0.67945 -0.305054)
			(end 0.12065 -0.305054)
			(stroke
				(width 0.1)
				(type default)
			)
			(layer "B.Fab")
		)
		(fp_line
			(start 0.67945 0.3048)
			(end 0.67945 -0.305054)
			(stroke
				(width 0.1)
				(type default)
			)
			(layer "B.Fab")
		)
		(pad "1" smd circle
			(at 0.40005 0 180)
			(size 0 0)
			(layers "B.Cu" "B.Mask" "B.Paste")
			(net "SMB_VR_3V3AUX_SCL")
		)
		(pad "2" smd circle
			(at -0.40005 0 180)
			(size 0 0)
			(layers "B.Cu" "B.Mask" "B.Paste")
			(net "SMB_VR_3V3STBY_SCL")
		)
	)
	(footprint ""
		(layer "B.Cu")
		(at 101.385878 -144.63141 180)
		(property "Reference" "PC253"
			(at 0 0 0)
			(layer "B.SilkS")
			(hide yes)
			(effects
				(font
					(size 1.27 1.27)
				)
				(justify mirror)
			)
		)
		(property "Value" ""
			(at 0 0 0)
			(layer "B.Fab")
			(effects
				(font
					(size 1.27 1.27)
				)
				(justify mirror)
			)
		)
		(duplicate_pad_numbers_are_jumpers no)
		(fp_line
			(start 0.7874 0.4064)
			(end 0.7874 -0.4064)
			(stroke
				(width 0.1524)
				(type default)
			)
			(layer "B.SilkS")
		)
		(fp_line
			(start 0.7874 -0.4064)
			(end -0.7874 -0.4064)
			(stroke
				(width 0.1524)
				(type default)
			)
			(layer "B.SilkS")
		)
		(fp_line
			(start -0.7874 0.4064)
			(end 0.7874 0.4064)
			(stroke
				(width 0.1524)
				(type default)
			)
			(layer "B.SilkS")
		)
		(fp_line
			(start -0.7874 -0.4064)
			(end -0.7874 0.4064)
			(stroke
				(width 0.1524)
				(type default)
			)
			(layer "B.SilkS")
		)
		(fp_line
			(start 0.67945 0.3048)
			(end 0.67945 -0.305054)
			(stroke
				(width 0.1)
				(type default)
			)
			(layer "B.Fab")
		)
		(fp_line
			(start 0.67945 -0.305054)
			(end 0.12065 -0.305054)
			(stroke
				(width 0.1)
				(type default)
			)
			(layer "B.Fab")
		)
		(fp_line
			(start 0.12065 0.3048)
			(end 0.67945 0.3048)
			(stroke
				(width 0.1)
				(type default)
			)
			(layer "B.Fab")
		)
		(fp_line
			(start 0.12065 0.2794)
			(end 0.12065 0.3048)
			(stroke
				(width 0.1)
				(type default)
			)
			(layer "B.Fab")
		)
		(fp_line
			(start 0.12065 -0.2794)
			(end -0.12065 -0.2794)
			(stroke
				(width 0.1)
				(type default)
			)
			(layer "B.Fab")
		)
		(fp_line
			(start 0.12065 -0.305054)
			(end 0.12065 -0.2794)
			(stroke
				(width 0.1)
				(type default)
			)
			(layer "B.Fab")
		)
		(fp_line
			(start -0.120396 0.3048)
			(end -0.120396 0.2794)
			(stroke
				(width 0.1)
				(type default)
			)
			(layer "B.Fab")
		)
		(fp_line
			(start -0.120396 0.2794)
			(end 0.12065 0.2794)
			(stroke
				(width 0.1)
				(type default)
			)
			(layer "B.Fab")
		)
		(fp_line
			(start -0.12065 -0.2794)
			(end -0.12065 -0.3048)
			(stroke
				(width 0.1)
				(type default)
			)
			(layer "B.Fab")
		)
		(fp_line
			(start -0.12065 -0.3048)
			(end -0.67945 -0.3048)
			(stroke
				(width 0.1)
				(type default)
			)
			(layer "B.Fab")
		)
		(fp_line
			(start -0.67945 0.3048)
			(end -0.120396 0.3048)
			(stroke
				(width 0.1)
				(type default)
			)
			(layer "B.Fab")
		)
		(fp_line
			(start -0.67945 -0.3048)
			(end -0.67945 0.3048)
			(stroke
				(width 0.1)
				(type default)
			)
			(layer "B.Fab")
		)
		(pad "1" smd circle
			(at 0.40005 0)
			(size 0 0)
			(layers "B.Cu" "B.Mask" "B.Paste")
			(net "PVDDCR_SOC_P1_TEMP1")
		)
		(pad "2" smd circle
			(at -0.40005 0)
			(size 0 0)
			(layers "B.Cu" "B.Mask" "B.Paste")
			(net "GND")
		)
	)
	(footprint ""
		(layer "B.Cu")
		(at 300.538388 2.542794)
		(property "Reference" "J119"
			(at 4.387088 1.491742 270)
			(unlocked yes)
			(layer "B.SilkS")
			(effects
				(font
					(size 0.7874 0.5842)
					(thickness 0.1524)
				)
				(justify left mirror)
			)
		)
		(property "Value" ""
			(at 0 0 0)
			(layer "B.Fab")
			(effects
				(font
					(size 1.27 1.27)
				)
				(justify mirror)
			)
		)
		(duplicate_pad_numbers_are_jumpers no)
		(fp_line
			(start -1.2192 -2.06756)
			(end -1.2192 2.06756)
			(stroke
				(width 0.1524)
				(type default)
			)
			(layer "B.SilkS")
		)
		(fp_line
			(start -1.2192 2.06756)
			(end 1.2192 2.06756)
			(stroke
				(width 0.1524)
				(type default)
			)
			(layer "B.SilkS")
		)
		(fp_line
			(start 1.2192 -2.06756)
			(end -1.2192 -2.06756)
			(stroke
				(width 0.1524)
				(type default)
			)
			(layer "B.SilkS")
		)
		(fp_line
			(start 1.2192 2.06756)
			(end 1.2192 -2.06756)
			(stroke
				(width 0.1524)
				(type default)
			)
			(layer "B.SilkS")
		)
		(pad "" np_thru_hole circle
			(at -3.4671 -1.27 270)
			(size 1.0414 1.0414)
			(drill 1.0414)
			(layers "*.Cu" "*.Mask")
			(clearance 0.381)
			(thermal_gap 0.381)
		)
		(pad "" np_thru_hole circle
			(at -3.4671 1.27 270)
			(size 1.0414 1.0414)
			(drill 1.0414)
			(layers "*.Cu" "*.Mask")
			(clearance 0.381)
			(thermal_gap 0.381)
		)
		(pad "" np_thru_hole circle
			(at 2.8829 -1.27 270)
			(size 1.0414 1.0414)
			(drill 1.0414)
			(layers "*.Cu" "*.Mask")
			(clearance 0.381)
			(thermal_gap 0.381)
		)
		(pad "" np_thru_hole circle
			(at 2.8829 1.27 270)
			(size 1.0414 1.0414)
			(drill 1.0414)
			(layers "*.Cu" "*.Mask")
			(clearance 0.381)
			(thermal_gap 0.381)
		)
		(pad "1" smd rect
			(at -0.8255 -0.249936 270)
			(size 0.3048 0.508)
			(layers "B.Cu" "B.Mask" "B.Paste")
			(net "DELTA_L_85_10INCH_IN6_DP")
		)
		(pad "2" smd rect
			(at -0.8255 0.249936 270)
			(size 0.3048 0.508)
			(layers "B.Cu" "B.Mask" "B.Paste")
			(net "DELTA_L_85_10INCH_IN6_DN")
		)
		(pad "3" smd circle
			(at 0 0 180)
			(size 0 0)
			(layers "B.Cu" "B.Mask" "B.Paste")
			(net "DELTA_L_GND_1")
		)
		(zone
			(layers "F.Cu" "B.Cu" "In1.Cu" "In2.Cu" "In3.Cu" "In4.Cu" "In5.Cu" "In6.Cu"
				"In7.Cu" "In8.Cu" "In9.Cu" "In10.Cu" "In11.Cu" "In12.Cu" "In13.Cu" "In14.Cu"
				"In15.Cu" "In16.Cu"
			)
			(hatch none 0.5)
			(connect_pads
				(clearance 0)
			)
			(min_thickness 0.25)
			(keepout
				(tracks not_allowed)
				(vias allowed)
				(pads allowed)
				(copperpour not_allowed)
				(footprints allowed)
			)
			(placement
				(enabled no)
				(sheetname "")
			)
			(fill
				(thermal_gap 0.5)
				(thermal_bridge_width 0.5)
				(island_removal_mode 0)
			)
			(polygon
				(pts
					(arc
						(start 297.998388 1.272794)
						(mid 296.144188 1.272794)
						(end 297.998388 1.272794)
					)
				)
			)
		)
		(zone
			(layers "F.Cu" "B.Cu" "In1.Cu" "In2.Cu" "In3.Cu" "In4.Cu" "In5.Cu" "In6.Cu"
				"In7.Cu" "In8.Cu" "In9.Cu" "In10.Cu" "In11.Cu" "In12.Cu" "In13.Cu" "In14.Cu"
				"In15.Cu" "In16.Cu"
			)
			(hatch none 0.5)
			(connect_pads
				(clearance 0)
			)
			(min_thickness 0.25)
			(keepout
				(tracks not_allowed)
				(vias allowed)
				(pads allowed)
				(copperpour not_allowed)
				(footprints allowed)
			)
			(placement
				(enabled no)
				(sheetname "")
			)
			(fill
				(thermal_gap 0.5)
				(thermal_bridge_width 0.5)
				(island_removal_mode 0)
			)
			(polygon
				(pts
					(arc
						(start 297.998388 3.812794)
						(mid 296.144188 3.812794)
						(end 297.998388 3.812794)
					)
				)
			)
		)
		(zone
			(layers "F.Cu" "B.Cu" "In1.Cu" "In2.Cu" "In3.Cu" "In4.Cu" "In5.Cu" "In6.Cu"
				"In7.Cu" "In8.Cu" "In9.Cu" "In10.Cu" "In11.Cu" "In12.Cu" "In13.Cu" "In14.Cu"
				"In15.Cu" "In16.Cu"
			)
			(hatch none 0.5)
			(connect_pads
				(clearance 0)
			)
			(min_thickness 0.25)
			(keepout
				(tracks not_allowed)
				(vias allowed)
				(pads allowed)
				(copperpour not_allowed)
				(footprints allowed)
			)
			(placement
				(enabled no)
				(sheetname "")
			)
			(fill
				(thermal_gap 0.5)
				(thermal_bridge_width 0.5)
				(island_removal_mode 0)
			)
			(polygon
				(pts
					(arc
						(start 304.348388 1.272794)
						(mid 302.494188 1.272794)
						(end 304.348388 1.272794)
					)
				)
			)
		)
		(zone
			(layers "F.Cu" "B.Cu" "In1.Cu" "In2.Cu" "In3.Cu" "In4.Cu" "In5.Cu" "In6.Cu"
				"In7.Cu" "In8.Cu" "In9.Cu" "In10.Cu" "In11.Cu" "In12.Cu" "In13.Cu" "In14.Cu"
				"In15.Cu" "In16.Cu"
			)
			(hatch none 0.5)
			(connect_pads
				(clearance 0)
			)
			(min_thickness 0.25)
			(keepout
				(tracks not_allowed)
				(vias allowed)
				(pads allowed)
				(copperpour not_allowed)
				(footprints allowed)
			)
			(placement
				(enabled no)
				(sheetname "")
			)
			(fill
				(thermal_gap 0.5)
				(thermal_bridge_width 0.5)
				(island_removal_mode 0)
			)
			(polygon
				(pts
					(arc
						(start 304.348388 3.812794)
						(mid 302.494188 3.812794)
						(end 304.348388 3.812794)
					)
				)
			)
		)
		(zone
			(layer "B.Cu")
			(hatch none 0.5)
			(connect_pads
				(clearance 0)
			)
			(min_thickness 0.25)
			(keepout
				(tracks not_allowed)
				(vias allowed)
				(pads allowed)
				(copperpour not_allowed)
				(footprints allowed)
			)
			(placement
				(enabled no)
				(sheetname "")
			)
			(fill
				(thermal_gap 0.5)
				(thermal_bridge_width 0.5)
				(island_removal_mode 0)
			)
			(polygon
				(pts
					(xy 299.420788 1.994154) (xy 299.420788 2.089658) (xy 300.017688 2.089658) (xy 300.017688 2.496058)
					(xy 299.420788 2.496058) (xy 299.420788 2.58953) (xy 300.017688 2.58953) (xy 300.017688 2.99593)
					(xy 299.420788 2.99593) (xy 299.420788 3.091434) (xy 300.119288 3.091434) (xy 300.119288 1.994154)
				)
			)
		)
	)
	(footprint ""
		(layer "B.Cu")
		(at 110.365794 -383.7432 180)
		(property "Reference" "R910"
			(at 0 0 0)
			(layer "B.SilkS")
			(hide yes)
			(effects
				(font
					(size 1.27 1.27)
				)
				(justify mirror)
			)
		)
		(property "Value" ""
			(at 0 0 0)
			(layer "B.Fab")
			(effects
				(font
					(size 1.27 1.27)
				)
				(justify mirror)
			)
		)
		(duplicate_pad_numbers_are_jumpers no)
		(fp_line
			(start 0.32512 0.175006)
			(end 0.32512 -0.175006)
			(stroke
				(width 0.1)
				(type default)
			)
			(layer "B.Fab")
		)
		(fp_line
			(start 0.32512 -0.175006)
			(end -0.32512 -0.175006)
			(stroke
				(width 0.1)
				(type default)
			)
			(layer "B.Fab")
		)
		(fp_line
			(start -0.32512 0.175006)
			(end 0.32512 0.175006)
			(stroke
				(width 0.1)
				(type default)
			)
			(layer "B.Fab")
		)
		(fp_line
			(start -0.32512 -0.175006)
			(end -0.32512 0.175006)
			(stroke
				(width 0.1)
				(type default)
			)
			(layer "B.Fab")
		)
		(pad "1" smd rect
			(at 0.2667 0)
			(size 0.3048 0.381)
			(layers "B.Cu" "B.Mask" "B.Paste")
			(net "RT_CPU1_P3_SCAN_MODE")
		)
		(pad "2" smd rect
			(at -0.2667 0 180)
			(size 0.3048 0.381)
			(layers "B.Cu" "B.Mask" "B.Paste")
			(net "GND")
		)
	)
	(footprint ""
		(layer "B.Cu")
		(at 191.196214 -344.177112 -90)
		(property "Reference" "PC528"
			(at 7.567676 -4.797806 270)
			(unlocked yes)
			(layer "B.SilkS")
			(effects
				(font
					(size 0.7874 0.5842)
					(thickness 0.1524)
				)
				(justify left mirror)
			)
		)
		(property "Value" ""
			(at 0 0 90)
			(layer "B.Fab")
			(effects
				(font
					(size 1.27 1.27)
				)
				(justify mirror)
			)
		)
		(duplicate_pad_numbers_are_jumpers no)
		(fp_line
			(start -4.533392 2.249932)
			(end 4.533392 2.249932)
			(stroke
				(width 0.1524)
				(type default)
			)
			(layer "B.SilkS")
		)
		(fp_line
			(start 4.533392 2.249932)
			(end 4.533392 -2.249932)
			(stroke
				(width 0.1524)
				(type default)
			)
			(layer "B.SilkS")
		)
		(fp_line
			(start -4.533392 -2.249932)
			(end -4.533392 2.249932)
			(stroke
				(width 0.1524)
				(type default)
			)
			(layer "B.SilkS")
		)
		(fp_line
			(start 4.533392 -2.249932)
			(end -4.533392 -2.249932)
			(stroke
				(width 0.1524)
				(type default)
			)
			(layer "B.SilkS")
		)
		(fp_rect
			(start 5.39242 2.326132)
			(end 4.533392 -2.326132)
			(stroke
				(width 0)
				(type default)
			)
			(fill yes)
			(layer "B.SilkS")
		)
		(fp_line
			(start -3.750056 2.249932)
			(end 3.750056 2.249932)
			(stroke
				(width 0.1)
				(type default)
			)
			(layer "B.Fab")
		)
		(fp_line
			(start 3.750056 2.249932)
			(end 3.750056 -2.249932)
			(stroke
				(width 0.1)
				(type default)
			)
			(layer "B.Fab")
		)
		(fp_line
			(start -3.750056 -2.249932)
			(end -3.750056 2.249932)
			(stroke
				(width 0.1)
				(type default)
			)
			(layer "B.Fab")
		)
		(fp_line
			(start 3.750056 -2.249932)
			(end -3.750056 -2.249932)
			(stroke
				(width 0.1)
				(type default)
			)
			(layer "B.Fab")
		)
		(fp_text user "-"
			(at -4.956048 2.39776 270)
			(unlocked yes)
			(layer "B.SilkS")
			(effects
				(font
					(size 1.905 1.4224)
					(thickness 0.1524)
				)
				(justify left mirror)
			)
		)
		(fp_text user "+"
			(at 6.322314 0.786384 180)
			(unlocked yes)
			(layer "B.SilkS")
			(effects
				(font
					(size 1.905 1.4224)
					(thickness 0.1524)
				)
				(justify left mirror)
			)
		)
		(fp_text user "+"
			(at 6.322314 0.786384 180)
			(unlocked yes)
			(layer "B.Fab")
			(effects
				(font
					(size 1.905 1.4224)
					(thickness 0.1524)
				)
				(justify left mirror)
			)
		)
		(fp_text user "-"
			(at -4.8514 -0.14605 270)
			(unlocked yes)
			(layer "B.Fab")
			(effects
				(font
					(size 1.905 1.4224)
					(thickness 0.1524)
				)
				(justify left mirror)
			)
		)
		(pad "1" smd rect
			(at 3.199892 0 90)
			(size 2.413 2.8194)
			(layers "B.Cu" "B.Mask" "B.Paste")
			(net "PVDD11_S3_P1")
		)
		(pad "2" smd rect
			(at -3.199892 0 90)
			(size 2.413 2.8194)
			(layers "B.Cu" "B.Mask" "B.Paste")
			(net "GND")
		)
	)
	(footprint ""
		(layer "B.Cu")
		(at 373.314722 -416.899344 90)
		(property "Reference" "C6597"
			(at 0 0 90)
			(layer "B.SilkS")
			(hide yes)
			(effects
				(font
					(size 1.27 1.27)
				)
				(justify mirror)
			)
		)
		(property "Value" ""
			(at 0 0 90)
			(layer "B.Fab")
			(effects
				(font
					(size 1.27 1.27)
				)
				(justify mirror)
			)
		)
		(duplicate_pad_numbers_are_jumpers no)
		(fp_line
			(start 0.299974 -0.150114)
			(end -0.299974 -0.150114)
			(stroke
				(width 0.1)
				(type default)
			)
			(layer "B.Fab")
		)
		(fp_line
			(start -0.299974 -0.150114)
			(end -0.299974 0.150114)
			(stroke
				(width 0.1)
				(type default)
			)
			(layer "B.Fab")
		)
		(fp_line
			(start 0.299974 0.150114)
			(end 0.299974 -0.150114)
			(stroke
				(width 0.1)
				(type default)
			)
			(layer "B.Fab")
		)
		(fp_line
			(start -0.299974 0.150114)
			(end 0.299974 0.150114)
			(stroke
				(width 0.1)
				(type default)
			)
			(layer "B.Fab")
		)
		(pad "1" smd rect
			(at 0.2667 0 270)
			(size 0.3048 0.381)
			(layers "B.Cu" "B.Mask" "B.Paste")
			(net "P5E_CPU0_P3_TX_BUF_C_DP<0>")
		)
		(pad "2" smd rect
			(at -0.2667 0 270)
			(size 0.3048 0.381)
			(layers "B.Cu" "B.Mask" "B.Paste")
			(net "P5E_CPU0_P3_TX_BUF_DP<0>")
		)
	)
	(footprint ""
		(layer "B.Cu")
		(at 122.526806 -408.517344 90)
		(property "Reference" "C6730"
			(at 0 0 90)
			(layer "B.SilkS")
			(hide yes)
			(effects
				(font
					(size 1.27 1.27)
				)
				(justify mirror)
			)
		)
		(property "Value" ""
			(at 0 0 90)
			(layer "B.Fab")
			(effects
				(font
					(size 1.27 1.27)
				)
				(justify mirror)
			)
		)
		(duplicate_pad_numbers_are_jumpers no)
		(fp_line
			(start 0.299974 -0.150114)
			(end -0.299974 -0.150114)
			(stroke
				(width 0.1)
				(type default)
			)
			(layer "B.Fab")
		)
		(fp_line
			(start -0.299974 -0.150114)
			(end -0.299974 0.150114)
			(stroke
				(width 0.1)
				(type default)
			)
			(layer "B.Fab")
		)
		(fp_line
			(start 0.299974 0.150114)
			(end 0.299974 -0.150114)
			(stroke
				(width 0.1)
				(type default)
			)
			(layer "B.Fab")
		)
		(fp_line
			(start -0.299974 0.150114)
			(end 0.299974 0.150114)
			(stroke
				(width 0.1)
				(type default)
			)
			(layer "B.Fab")
		)
		(pad "1" smd rect
			(at 0.2667 0 270)
			(size 0.3048 0.381)
			(layers "B.Cu" "B.Mask" "B.Paste")
			(net "P5E_CPU1_P3_TX_BUF_C_DN<2>")
		)
		(pad "2" smd rect
			(at -0.2667 0 270)
			(size 0.3048 0.381)
			(layers "B.Cu" "B.Mask" "B.Paste")
			(net "P5E_CPU1_P3_TX_BUF_DN<2>")
		)
	)
	(footprint ""
		(layer "B.Cu")
		(at 130.104642 -78.52918)
		(property "Reference" "PC6025"
			(at 0 0 0)
			(layer "B.SilkS")
			(hide yes)
			(effects
				(font
					(size 1.27 1.27)
				)
				(justify mirror)
			)
		)
		(property "Value" ""
			(at 0 0 0)
			(layer "B.Fab")
			(effects
				(font
					(size 1.27 1.27)
				)
				(justify mirror)
			)
		)
		(duplicate_pad_numbers_are_jumpers no)
		(fp_line
			(start -1.524 -0.762)
			(end -1.524 0.762)
			(stroke
				(width 0.1524)
				(type default)
			)
			(layer "B.SilkS")
		)
		(fp_line
			(start -1.524 0.762)
			(end 1.524 0.762)
			(stroke
				(width 0.1524)
				(type default)
			)
			(layer "B.SilkS")
		)
		(fp_line
			(start 1.524 -0.762)
			(end -1.524 -0.762)
			(stroke
				(width 0.1524)
				(type default)
			)
			(layer "B.SilkS")
		)
		(fp_line
			(start 1.524 0.762)
			(end 1.524 -0.762)
			(stroke
				(width 0.1524)
				(type default)
			)
			(layer "B.SilkS")
		)
		(fp_line
			(start -1.1049 -0.724916)
			(end 1.1049 -0.724916)
			(stroke
				(width 0.1)
				(type default)
			)
			(layer "B.Fab")
		)
		(fp_line
			(start -1.1049 0.724916)
			(end -1.1049 -0.724916)
			(stroke
				(width 0.1)
				(type default)
			)
			(layer "B.Fab")
		)
		(fp_line
			(start 1.1049 -0.724916)
			(end 1.1049 0.724916)
			(stroke
				(width 0.1)
				(type default)
			)
			(layer "B.Fab")
		)
		(fp_line
			(start 1.1049 0.724916)
			(end -1.1049 0.724916)
			(stroke
				(width 0.1)
				(type default)
			)
			(layer "B.Fab")
		)
		(pad "1" smd rect
			(at 0.889 0)
			(size 1.016 1.27)
			(layers "B.Cu" "B.Mask" "B.Paste")
			(net "P1V2_AUX")
		)
		(pad "2" smd rect
			(at -0.889 0)
			(size 1.016 1.27)
			(layers "B.Cu" "B.Mask" "B.Paste")
			(net "GND")
		)
	)
	(footprint ""
		(layer "B.Cu")
		(at 338.186522 -326.341232 -90)
		(property "Reference" "PC102_1"
			(at 0 0 90)
			(layer "B.SilkS")
			(hide yes)
			(effects
				(font
					(size 1.27 1.27)
				)
				(justify mirror)
			)
		)
		(property "Value" ""
			(at 0 0 90)
			(layer "B.Fab")
			(effects
				(font
					(size 1.27 1.27)
				)
				(justify mirror)
			)
		)
		(duplicate_pad_numbers_are_jumpers no)
		(fp_line
			(start -1.524 0.762)
			(end 1.524 0.762)
			(stroke
				(width 0.1524)
				(type default)
			)
			(layer "B.SilkS")
		)
		(fp_line
			(start 1.524 0.762)
			(end 1.524 -0.762)
			(stroke
				(width 0.1524)
				(type default)
			)
			(layer "B.SilkS")
		)
		(fp_line
			(start -1.524 -0.762)
			(end -1.524 0.762)
			(stroke
				(width 0.1524)
				(type default)
			)
			(layer "B.SilkS")
		)
		(fp_line
			(start 1.524 -0.762)
			(end -1.524 -0.762)
			(stroke
				(width 0.1524)
				(type default)
			)
			(layer "B.SilkS")
		)
		(fp_line
			(start -1.1049 0.724916)
			(end -1.1049 -0.724916)
			(stroke
				(width 0.1)
				(type default)
			)
			(layer "B.Fab")
		)
		(fp_line
			(start 1.1049 0.724916)
			(end -1.1049 0.724916)
			(stroke
				(width 0.1)
				(type default)
			)
			(layer "B.Fab")
		)
		(fp_line
			(start -1.1049 -0.724916)
			(end 1.1049 -0.724916)
			(stroke
				(width 0.1)
				(type default)
			)
			(layer "B.Fab")
		)
		(fp_line
			(start 1.1049 -0.724916)
			(end 1.1049 0.724916)
			(stroke
				(width 0.1)
				(type default)
			)
			(layer "B.Fab")
		)
		(pad "1" smd rect
			(at 0.889 0 270)
			(size 1.016 1.27)
			(layers "B.Cu" "B.Mask" "B.Paste")
			(net "PVDDCR_CPU1_P0")
		)
		(pad "2" smd rect
			(at -0.889 0 270)
			(size 1.016 1.27)
			(layers "B.Cu" "B.Mask" "B.Paste")
			(net "GND")
		)
	)
	(footprint ""
		(layer "B.Cu")
		(at 230.505 -243.2431 -90)
		(property "Reference" "R326"
			(at 0 0 90)
			(layer "B.SilkS")
			(hide yes)
			(effects
				(font
					(size 1.27 1.27)
				)
				(justify mirror)
			)
		)
		(property "Value" ""
			(at 0 0 90)
			(layer "B.Fab")
			(effects
				(font
					(size 1.27 1.27)
				)
				(justify mirror)
			)
		)
		(duplicate_pad_numbers_are_jumpers no)
		(fp_line
			(start -0.7874 0.4064)
			(end 0.7874 0.4064)
			(stroke
				(width 0.1524)
				(type default)
			)
			(layer "B.SilkS")
		)
		(fp_line
			(start 0.7874 0.4064)
			(end 0.7874 -0.4064)
			(stroke
				(width 0.1524)
				(type default)
			)
			(layer "B.SilkS")
		)
		(fp_line
			(start -0.7874 -0.4064)
			(end -0.7874 0.4064)
			(stroke
				(width 0.1524)
				(type default)
			)
			(layer "B.SilkS")
		)
		(fp_line
			(start 0.7874 -0.4064)
			(end -0.7874 -0.4064)
			(stroke
				(width 0.1524)
				(type default)
			)
			(layer "B.SilkS")
		)
		(fp_line
			(start -0.67945 0.3048)
			(end -0.120396 0.3048)
			(stroke
				(width 0.1)
				(type default)
			)
			(layer "B.Fab")
		)
		(fp_line
			(start -0.120396 0.3048)
			(end -0.120396 0.2794)
			(stroke
				(width 0.1)
				(type default)
			)
			(layer "B.Fab")
		)
		(fp_line
			(start 0.12065 0.3048)
			(end 0.67945 0.3048)
			(stroke
				(width 0.1)
				(type default)
			)
			(layer "B.Fab")
		)
		(fp_line
			(start 0.67945 0.3048)
			(end 0.67945 -0.305054)
			(stroke
				(width 0.1)
				(type default)
			)
			(layer "B.Fab")
		)
		(fp_line
			(start -0.120396 0.2794)
			(end 0.12065 0.2794)
			(stroke
				(width 0.1)
				(type default)
			)
			(layer "B.Fab")
		)
		(fp_line
			(start 0.12065 0.2794)
			(end 0.12065 0.3048)
			(stroke
				(width 0.1)
				(type default)
			)
			(layer "B.Fab")
		)
		(fp_line
			(start -0.12065 -0.2794)
			(end -0.12065 -0.3048)
			(stroke
				(width 0.1)
				(type default)
			)
			(layer "B.Fab")
		)
		(fp_line
			(start 0.12065 -0.2794)
			(end -0.12065 -0.2794)
			(stroke
				(width 0.1)
				(type default)
			)
			(layer "B.Fab")
		)
		(fp_line
			(start -0.67945 -0.3048)
			(end -0.67945 0.3048)
			(stroke
				(width 0.1)
				(type default)
			)
			(layer "B.Fab")
		)
		(fp_line
			(start -0.12065 -0.3048)
			(end -0.67945 -0.3048)
			(stroke
				(width 0.1)
				(type default)
			)
			(layer "B.Fab")
		)
		(fp_line
			(start 0.12065 -0.305054)
			(end 0.12065 -0.2794)
			(stroke
				(width 0.1)
				(type default)
			)
			(layer "B.Fab")
		)
		(fp_line
			(start 0.67945 -0.305054)
			(end 0.12065 -0.305054)
			(stroke
				(width 0.1)
				(type default)
			)
			(layer "B.Fab")
		)
		(pad "1" smd rect
			(at 0.40005 0 270)
			(size 0.4572 0.508)
			(layers "B.Cu" "B.Mask" "B.Paste")
			(net "SMB_CPU0_CPU1_APML_SDA_R2")
		)
		(pad "2" smd rect
			(at -0.40005 0 270)
			(size 0.4572 0.508)
			(layers "B.Cu" "B.Mask" "B.Paste")
			(net "SMB_CPU0_CPU1_APML_MUX2_SDA")
		)
	)
	(footprint ""
		(layer "B.Cu")
		(at 115.705636 -36.138866 90)
		(property "Reference" "L6004"
			(at 0 0 90)
			(layer "B.SilkS")
			(hide yes)
			(effects
				(font
					(size 1.27 1.27)
				)
				(justify mirror)
			)
		)
		(property "Value" ""
			(at 0 0 90)
			(layer "B.Fab")
			(effects
				(font
					(size 1.27 1.27)
				)
				(justify mirror)
			)
		)
		(duplicate_pad_numbers_are_jumpers no)
		(fp_line
			(start 1.63576 -0.8128)
			(end -1.63576 -0.8128)
			(stroke
				(width 0.1524)
				(type default)
			)
			(layer "B.SilkS")
		)
		(fp_line
			(start 1.63576 -0.8128)
			(end 1.63576 0.8128)
			(stroke
				(width 0.1524)
				(type default)
			)
			(layer "B.SilkS")
		)
		(fp_line
			(start -1.63576 -0.8128)
			(end -1.63576 0.8128)
			(stroke
				(width 0.1524)
				(type default)
			)
			(layer "B.SilkS")
		)
		(fp_line
			(start -1.63576 0.8128)
			(end 1.63576 0.8128)
			(stroke
				(width 0.1524)
				(type default)
			)
			(layer "B.SilkS")
		)
		(fp_line
			(start 1.56083 -0.738632)
			(end 1.56083 0.7366)
			(stroke
				(width 0.1)
				(type default)
			)
			(layer "B.Fab")
		)
		(fp_line
			(start -1.560576 -0.738632)
			(end 1.56083 -0.738632)
			(stroke
				(width 0.1)
				(type default)
			)
			(layer "B.Fab")
		)
		(fp_line
			(start 1.56083 0.7366)
			(end 1.524 0.7366)
			(stroke
				(width 0.1)
				(type default)
			)
			(layer "B.Fab")
		)
		(fp_line
			(start 1.524 0.7366)
			(end -1.524 0.7366)
			(stroke
				(width 0.1)
				(type default)
			)
			(layer "B.Fab")
		)
		(fp_line
			(start -1.524 0.7366)
			(end -1.560576 0.7366)
			(stroke
				(width 0.1)
				(type default)
			)
			(layer "B.Fab")
		)
		(fp_line
			(start -1.560576 0.7366)
			(end -1.560576 -0.738632)
			(stroke
				(width 0.1)
				(type default)
			)
			(layer "B.Fab")
		)
		(pad "1" smd rect
			(at 0.94996 0 90)
			(size 1.1176 1.3716)
			(layers "B.Cu" "B.Mask" "B.Paste")
			(net "P1V2_AUX")
		)
		(pad "2" smd rect
			(at -0.94996 0 90)
			(size 1.1176 1.3716)
			(layers "B.Cu" "B.Mask" "B.Paste")
			(net "P1V2_CPU0_USB2_DVDD12")
		)
	)
	(footprint ""
		(layer "B.Cu")
		(at 64.318642 -388.011162 -90)
		(property "Reference" "C192"
			(at 0 0 90)
			(layer "B.SilkS")
			(hide yes)
			(effects
				(font
					(size 1.27 1.27)
				)
				(justify mirror)
			)
		)
		(property "Value" ""
			(at 0 0 90)
			(layer "B.Fab")
			(effects
				(font
					(size 1.27 1.27)
				)
				(justify mirror)
			)
		)
		(duplicate_pad_numbers_are_jumpers no)
		(fp_line
			(start -0.299974 0.150114)
			(end 0.299974 0.150114)
			(stroke
				(width 0.1)
				(type default)
			)
			(layer "B.Fab")
		)
		(fp_line
			(start 0.299974 0.150114)
			(end 0.299974 -0.150114)
			(stroke
				(width 0.1)
				(type default)
			)
			(layer "B.Fab")
		)
		(fp_line
			(start -0.299974 -0.150114)
			(end -0.299974 0.150114)
			(stroke
				(width 0.1)
				(type default)
			)
			(layer "B.Fab")
		)
		(fp_line
			(start 0.299974 -0.150114)
			(end -0.299974 -0.150114)
			(stroke
				(width 0.1)
				(type default)
			)
			(layer "B.Fab")
		)
		(pad "1" smd rect
			(at 0.2667 0 90)
			(size 0.3048 0.381)
			(layers "B.Cu" "B.Mask" "B.Paste")
			(net "P0V9_CPU1_RT0_2A")
		)
		(pad "2" smd rect
			(at -0.2667 0 90)
			(size 0.3048 0.381)
			(layers "B.Cu" "B.Mask" "B.Paste")
			(net "GND")
		)
	)
	(footprint ""
		(layer "B.Cu")
		(at 108.712 -417.83 90)
		(property "Reference" "C1804"
			(at 0 0 90)
			(layer "B.SilkS")
			(hide yes)
			(effects
				(font
					(size 1.27 1.27)
				)
				(justify mirror)
			)
		)
		(property "Value" ""
			(at 0 0 90)
			(layer "B.Fab")
			(effects
				(font
					(size 1.27 1.27)
				)
				(justify mirror)
			)
		)
		(duplicate_pad_numbers_are_jumpers no)
		(fp_line
			(start 0.7874 -0.4064)
			(end -0.7874 -0.4064)
			(stroke
				(width 0.1524)
				(type default)
			)
			(layer "B.SilkS")
		)
		(fp_line
			(start -0.7874 -0.4064)
			(end -0.7874 0.4064)
			(stroke
				(width 0.1524)
				(type default)
			)
			(layer "B.SilkS")
		)
		(fp_line
			(start 0.7874 0.4064)
			(end 0.7874 -0.4064)
			(stroke
				(width 0.1524)
				(type default)
			)
			(layer "B.SilkS")
		)
		(fp_line
			(start -0.7874 0.4064)
			(end 0.7874 0.4064)
			(stroke
				(width 0.1524)
				(type default)
			)
			(layer "B.SilkS")
		)
		(fp_line
			(start 0.67945 -0.305054)
			(end 0.12065 -0.305054)
			(stroke
				(width 0.1)
				(type default)
			)
			(layer "B.Fab")
		)
		(fp_line
			(start 0.12065 -0.305054)
			(end 0.12065 -0.2794)
			(stroke
				(width 0.1)
				(type default)
			)
			(layer "B.Fab")
		)
		(fp_line
			(start -0.12065 -0.3048)
			(end -0.67945 -0.3048)
			(stroke
				(width 0.1)
				(type default)
			)
			(layer "B.Fab")
		)
		(fp_line
			(start -0.67945 -0.3048)
			(end -0.67945 0.3048)
			(stroke
				(width 0.1)
				(type default)
			)
			(layer "B.Fab")
		)
		(fp_line
			(start 0.12065 -0.2794)
			(end -0.12065 -0.2794)
			(stroke
				(width 0.1)
				(type default)
			)
			(layer "B.Fab")
		)
		(fp_line
			(start -0.12065 -0.2794)
			(end -0.12065 -0.3048)
			(stroke
				(width 0.1)
				(type default)
			)
			(layer "B.Fab")
		)
		(fp_line
			(start 0.12065 0.2794)
			(end 0.12065 0.3048)
			(stroke
				(width 0.1)
				(type default)
			)
			(layer "B.Fab")
		)
		(fp_line
			(start -0.120396 0.2794)
			(end 0.12065 0.2794)
			(stroke
				(width 0.1)
				(type default)
			)
			(layer "B.Fab")
		)
		(fp_line
			(start 0.67945 0.3048)
			(end 0.67945 -0.305054)
			(stroke
				(width 0.1)
				(type default)
			)
			(layer "B.Fab")
		)
		(fp_line
			(start 0.12065 0.3048)
			(end 0.67945 0.3048)
			(stroke
				(width 0.1)
				(type default)
			)
			(layer "B.Fab")
		)
		(fp_line
			(start -0.120396 0.3048)
			(end -0.120396 0.2794)
			(stroke
				(width 0.1)
				(type default)
			)
			(layer "B.Fab")
		)
		(fp_line
			(start -0.67945 0.3048)
			(end -0.120396 0.3048)
			(stroke
				(width 0.1)
				(type default)
			)
			(layer "B.Fab")
		)
		(pad "1" smd circle
			(at 0.40005 0 270)
			(size 0 0)
			(layers "B.Cu" "B.Mask" "B.Paste")
			(net "FM_SMB_2_ALERT_GPU_ISO_N")
		)
		(pad "2" smd circle
			(at -0.40005 0 270)
			(size 0 0)
			(layers "B.Cu" "B.Mask" "B.Paste")
			(net "GND")
		)
	)
	(footprint ""
		(layer "B.Cu")
		(at 439.029602 -422.52011)
		(property "Reference" "PR6819"
			(at 0 0 0)
			(layer "B.SilkS")
			(hide yes)
			(effects
				(font
					(size 1.27 1.27)
				)
				(justify mirror)
			)
		)
		(property "Value" ""
			(at 0 0 0)
			(layer "B.Fab")
			(effects
				(font
					(size 1.27 1.27)
				)
				(justify mirror)
			)
		)
		(duplicate_pad_numbers_are_jumpers no)
		(fp_line
			(start -0.7874 -0.4064)
			(end -0.7874 0.4064)
			(stroke
				(width 0.1524)
				(type default)
			)
			(layer "B.SilkS")
		)
		(fp_line
			(start -0.7874 0.4064)
			(end 0.7874 0.4064)
			(stroke
				(width 0.1524)
				(type default)
			)
			(layer "B.SilkS")
		)
		(fp_line
			(start 0.7874 -0.4064)
			(end -0.7874 -0.4064)
			(stroke
				(width 0.1524)
				(type default)
			)
			(layer "B.SilkS")
		)
		(fp_line
			(start 0.7874 0.4064)
			(end 0.7874 -0.4064)
			(stroke
				(width 0.1524)
				(type default)
			)
			(layer "B.SilkS")
		)
		(fp_line
			(start -0.67945 -0.3048)
			(end -0.67945 0.3048)
			(stroke
				(width 0.1)
				(type default)
			)
			(layer "B.Fab")
		)
		(fp_line
			(start -0.67945 0.3048)
			(end -0.120396 0.3048)
			(stroke
				(width 0.1)
				(type default)
			)
			(layer "B.Fab")
		)
		(fp_line
			(start -0.12065 -0.3048)
			(end -0.67945 -0.3048)
			(stroke
				(width 0.1)
				(type default)
			)
			(layer "B.Fab")
		)
		(fp_line
			(start -0.12065 -0.2794)
			(end -0.12065 -0.3048)
			(stroke
				(width 0.1)
				(type default)
			)
			(layer "B.Fab")
		)
		(fp_line
			(start -0.120396 0.2794)
			(end 0.12065 0.2794)
			(stroke
				(width 0.1)
				(type default)
			)
			(layer "B.Fab")
		)
		(fp_line
			(start -0.120396 0.3048)
			(end -0.120396 0.2794)
			(stroke
				(width 0.1)
				(type default)
			)
			(layer "B.Fab")
		)
		(fp_line
			(start 0.12065 -0.305054)
			(end 0.12065 -0.2794)
			(stroke
				(width 0.1)
				(type default)
			)
			(layer "B.Fab")
		)
		(fp_line
			(start 0.12065 -0.2794)
			(end -0.12065 -0.2794)
			(stroke
				(width 0.1)
				(type default)
			)
			(layer "B.Fab")
		)
		(fp_line
			(start 0.12065 0.2794)
			(end 0.12065 0.3048)
			(stroke
				(width 0.1)
				(type default)
			)
			(layer "B.Fab")
		)
		(fp_line
			(start 0.12065 0.3048)
			(end 0.67945 0.3048)
			(stroke
				(width 0.1)
				(type default)
			)
			(layer "B.Fab")
		)
		(fp_line
			(start 0.67945 -0.305054)
			(end 0.12065 -0.305054)
			(stroke
				(width 0.1)
				(type default)
			)
			(layer "B.Fab")
		)
		(fp_line
			(start 0.67945 0.3048)
			(end 0.67945 -0.305054)
			(stroke
				(width 0.1)
				(type default)
			)
			(layer "B.Fab")
		)
		(pad "1" smd circle
			(at 0.40005 0 180)
			(size 0 0)
			(layers "B.Cu" "B.Mask" "B.Paste")
			(net "P0V9_RETIMER_CPU0_SVID_SDA")
		)
		(pad "2" smd circle
			(at -0.40005 0 180)
			(size 0 0)
			(layers "B.Cu" "B.Mask" "B.Paste")
			(net "GND")
		)
	)
	(footprint ""
		(layer "B.Cu")
		(at 172.877734 -8.062468 -90)
		(property "Reference" "R3242"
			(at 0 0 90)
			(layer "B.SilkS")
			(hide yes)
			(effects
				(font
					(size 1.27 1.27)
				)
				(justify mirror)
			)
		)
		(property "Value" ""
			(at 0 0 90)
			(layer "B.Fab")
			(effects
				(font
					(size 1.27 1.27)
				)
				(justify mirror)
			)
		)
		(duplicate_pad_numbers_are_jumpers no)
		(fp_line
			(start -0.7874 0.4064)
			(end 0.7874 0.4064)
			(stroke
				(width 0.1524)
				(type default)
			)
			(layer "B.SilkS")
		)
		(fp_line
			(start 0.7874 0.4064)
			(end 0.7874 -0.4064)
			(stroke
				(width 0.1524)
				(type default)
			)
			(layer "B.SilkS")
		)
		(fp_line
			(start -0.7874 -0.4064)
			(end -0.7874 0.4064)
			(stroke
				(width 0.1524)
				(type default)
			)
			(layer "B.SilkS")
		)
		(fp_line
			(start 0.7874 -0.4064)
			(end -0.7874 -0.4064)
			(stroke
				(width 0.1524)
				(type default)
			)
			(layer "B.SilkS")
		)
		(fp_line
			(start -0.67945 0.3048)
			(end -0.120396 0.3048)
			(stroke
				(width 0.1)
				(type default)
			)
			(layer "B.Fab")
		)
		(fp_line
			(start -0.120396 0.3048)
			(end -0.120396 0.2794)
			(stroke
				(width 0.1)
				(type default)
			)
			(layer "B.Fab")
		)
		(fp_line
			(start 0.12065 0.3048)
			(end 0.67945 0.3048)
			(stroke
				(width 0.1)
				(type default)
			)
			(layer "B.Fab")
		)
		(fp_line
			(start 0.67945 0.3048)
			(end 0.67945 -0.305054)
			(stroke
				(width 0.1)
				(type default)
			)
			(layer "B.Fab")
		)
		(fp_line
			(start -0.120396 0.2794)
			(end 0.12065 0.2794)
			(stroke
				(width 0.1)
				(type default)
			)
			(layer "B.Fab")
		)
		(fp_line
			(start 0.12065 0.2794)
			(end 0.12065 0.3048)
			(stroke
				(width 0.1)
				(type default)
			)
			(layer "B.Fab")
		)
		(fp_line
			(start -0.12065 -0.2794)
			(end -0.12065 -0.3048)
			(stroke
				(width 0.1)
				(type default)
			)
			(layer "B.Fab")
		)
		(fp_line
			(start 0.12065 -0.2794)
			(end -0.12065 -0.2794)
			(stroke
				(width 0.1)
				(type default)
			)
			(layer "B.Fab")
		)
		(fp_line
			(start -0.67945 -0.3048)
			(end -0.67945 0.3048)
			(stroke
				(width 0.1)
				(type default)
			)
			(layer "B.Fab")
		)
		(fp_line
			(start -0.12065 -0.3048)
			(end -0.67945 -0.3048)
			(stroke
				(width 0.1)
				(type default)
			)
			(layer "B.Fab")
		)
		(fp_line
			(start 0.12065 -0.305054)
			(end 0.12065 -0.2794)
			(stroke
				(width 0.1)
				(type default)
			)
			(layer "B.Fab")
		)
		(fp_line
			(start 0.67945 -0.305054)
			(end 0.12065 -0.305054)
			(stroke
				(width 0.1)
				(type default)
			)
			(layer "B.Fab")
		)
		(pad "1" smd circle
			(at 0.40005 0 90)
			(size 0 0)
			(layers "B.Cu" "B.Mask" "B.Paste")
			(net "SMB_OCP_V3_2_3V3AUX_SCL")
		)
		(pad "2" smd circle
			(at -0.40005 0 90)
			(size 0 0)
			(layers "B.Cu" "B.Mask" "B.Paste")
			(net "P3V3_AUX")
		)
	)
	(footprint ""
		(layer "B.Cu")
		(at 359.173018 -395.466062 -90)
		(property "Reference" "C587"
			(at 0 0 90)
			(layer "B.SilkS")
			(hide yes)
			(effects
				(font
					(size 1.27 1.27)
				)
				(justify mirror)
			)
		)
		(property "Value" ""
			(at 0 0 90)
			(layer "B.Fab")
			(effects
				(font
					(size 1.27 1.27)
				)
				(justify mirror)
			)
		)
		(duplicate_pad_numbers_are_jumpers no)
		(fp_line
			(start -1.524 0.762)
			(end 1.524 0.762)
			(stroke
				(width 0.1524)
				(type default)
			)
			(layer "B.SilkS")
		)
		(fp_line
			(start 1.524 0.762)
			(end 1.524 -0.762)
			(stroke
				(width 0.1524)
				(type default)
			)
			(layer "B.SilkS")
		)
		(fp_line
			(start -1.524 -0.762)
			(end -1.524 0.762)
			(stroke
				(width 0.1524)
				(type default)
			)
			(layer "B.SilkS")
		)
		(fp_line
			(start 1.524 -0.762)
			(end -1.524 -0.762)
			(stroke
				(width 0.1524)
				(type default)
			)
			(layer "B.SilkS")
		)
		(fp_line
			(start -1.1049 0.724916)
			(end -1.1049 -0.724916)
			(stroke
				(width 0.1)
				(type default)
			)
			(layer "B.Fab")
		)
		(fp_line
			(start 1.1049 0.724916)
			(end -1.1049 0.724916)
			(stroke
				(width 0.1)
				(type default)
			)
			(layer "B.Fab")
		)
		(fp_line
			(start -1.1049 -0.724916)
			(end 1.1049 -0.724916)
			(stroke
				(width 0.1)
				(type default)
			)
			(layer "B.Fab")
		)
		(fp_line
			(start 1.1049 -0.724916)
			(end 1.1049 0.724916)
			(stroke
				(width 0.1)
				(type default)
			)
			(layer "B.Fab")
		)
		(pad "1" smd rect
			(at 0.889 0 270)
			(size 1.016 1.27)
			(layers "B.Cu" "B.Mask" "B.Paste")
			(net "P1V8_CPU0_RT_1D")
		)
		(pad "2" smd rect
			(at -0.889 0 270)
			(size 1.016 1.27)
			(layers "B.Cu" "B.Mask" "B.Paste")
			(net "GND")
		)
	)
	(footprint ""
		(layer "B.Cu")
		(at 141.623542 -385.58216 180)
		(property "Reference" "R878"
			(at 0 0 0)
			(layer "B.SilkS")
			(hide yes)
			(effects
				(font
					(size 1.27 1.27)
				)
				(justify mirror)
			)
		)
		(property "Value" ""
			(at 0 0 0)
			(layer "B.Fab")
			(effects
				(font
					(size 1.27 1.27)
				)
				(justify mirror)
			)
		)
		(duplicate_pad_numbers_are_jumpers no)
		(fp_line
			(start 0.32512 0.175006)
			(end 0.32512 -0.175006)
			(stroke
				(width 0.1)
				(type default)
			)
			(layer "B.Fab")
		)
		(fp_line
			(start 0.32512 -0.175006)
			(end -0.32512 -0.175006)
			(stroke
				(width 0.1)
				(type default)
			)
			(layer "B.Fab")
		)
		(fp_line
			(start -0.32512 0.175006)
			(end 0.32512 0.175006)
			(stroke
				(width 0.1)
				(type default)
			)
			(layer "B.Fab")
		)
		(fp_line
			(start -0.32512 -0.175006)
			(end -0.32512 0.175006)
			(stroke
				(width 0.1)
				(type default)
			)
			(layer "B.Fab")
		)
		(pad "1" smd rect
			(at 0.2667 0)
			(size 0.3048 0.381)
			(layers "B.Cu" "B.Mask" "B.Paste")
			(net "P1V8_CPU1_RT_1D")
		)
		(pad "2" smd rect
			(at -0.2667 0 180)
			(size 0.3048 0.381)
			(layers "B.Cu" "B.Mask" "B.Paste")
			(net "TEST0_RT_CPU1_P2")
		)
	)
	(footprint ""
		(layer "B.Cu")
		(at 71.657464 -408.517344 90)
		(property "Reference" "C6675"
			(at 0 0 90)
			(layer "B.SilkS")
			(hide yes)
			(effects
				(font
					(size 1.27 1.27)
				)
				(justify mirror)
			)
		)
		(property "Value" ""
			(at 0 0 90)
			(layer "B.Fab")
			(effects
				(font
					(size 1.27 1.27)
				)
				(justify mirror)
			)
		)
		(duplicate_pad_numbers_are_jumpers no)
		(fp_line
			(start 0.299974 -0.150114)
			(end -0.299974 -0.150114)
			(stroke
				(width 0.1)
				(type default)
			)
			(layer "B.Fab")
		)
		(fp_line
			(start -0.299974 -0.150114)
			(end -0.299974 0.150114)
			(stroke
				(width 0.1)
				(type default)
			)
			(layer "B.Fab")
		)
		(fp_line
			(start 0.299974 0.150114)
			(end 0.299974 -0.150114)
			(stroke
				(width 0.1)
				(type default)
			)
			(layer "B.Fab")
		)
		(fp_line
			(start -0.299974 0.150114)
			(end 0.299974 0.150114)
			(stroke
				(width 0.1)
				(type default)
			)
			(layer "B.Fab")
		)
		(pad "1" smd rect
			(at 0.2667 0 270)
			(size 0.3048 0.381)
			(layers "B.Cu" "B.Mask" "B.Paste")
			(net "P5E_CPU1_P1_TX_BUF_C_DP<7>")
		)
		(pad "2" smd rect
			(at -0.2667 0 270)
			(size 0.3048 0.381)
			(layers "B.Cu" "B.Mask" "B.Paste")
			(net "P5E_CPU1_P1_TX_BUF_DP<7>")
		)
	)
	(footprint ""
		(layer "B.Cu")
		(at 372.916958 -248.47931)
		(property "Reference" "C2181"
			(at 0 0 0)
			(layer "B.SilkS")
			(hide yes)
			(effects
				(font
					(size 1.27 1.27)
				)
				(justify mirror)
			)
		)
		(property "Value" ""
			(at 0 0 0)
			(layer "B.Fab")
			(effects
				(font
					(size 1.27 1.27)
				)
				(justify mirror)
			)
		)
		(duplicate_pad_numbers_are_jumpers no)
		(fp_line
			(start -0.7874 -0.4064)
			(end -0.7874 0.4064)
			(stroke
				(width 0.1524)
				(type default)
			)
			(layer "B.SilkS")
		)
		(fp_line
			(start -0.7874 0.4064)
			(end 0.7874 0.4064)
			(stroke
				(width 0.1524)
				(type default)
			)
			(layer "B.SilkS")
		)
		(fp_line
			(start 0.7874 -0.4064)
			(end -0.7874 -0.4064)
			(stroke
				(width 0.1524)
				(type default)
			)
			(layer "B.SilkS")
		)
		(fp_line
			(start 0.7874 0.4064)
			(end 0.7874 -0.4064)
			(stroke
				(width 0.1524)
				(type default)
			)
			(layer "B.SilkS")
		)
		(fp_line
			(start -0.67945 -0.3048)
			(end -0.67945 0.3048)
			(stroke
				(width 0.1)
				(type default)
			)
			(layer "B.Fab")
		)
		(fp_line
			(start -0.67945 0.3048)
			(end -0.120396 0.3048)
			(stroke
				(width 0.1)
				(type default)
			)
			(layer "B.Fab")
		)
		(fp_line
			(start -0.12065 -0.3048)
			(end -0.67945 -0.3048)
			(stroke
				(width 0.1)
				(type default)
			)
			(layer "B.Fab")
		)
		(fp_line
			(start -0.12065 -0.2794)
			(end -0.12065 -0.3048)
			(stroke
				(width 0.1)
				(type default)
			)
			(layer "B.Fab")
		)
		(fp_line
			(start -0.120396 0.2794)
			(end 0.12065 0.2794)
			(stroke
				(width 0.1)
				(type default)
			)
			(layer "B.Fab")
		)
		(fp_line
			(start -0.120396 0.3048)
			(end -0.120396 0.2794)
			(stroke
				(width 0.1)
				(type default)
			)
			(layer "B.Fab")
		)
		(fp_line
			(start 0.12065 -0.305054)
			(end 0.12065 -0.2794)
			(stroke
				(width 0.1)
				(type default)
			)
			(layer "B.Fab")
		)
		(fp_line
			(start 0.12065 -0.2794)
			(end -0.12065 -0.2794)
			(stroke
				(width 0.1)
				(type default)
			)
			(layer "B.Fab")
		)
		(fp_line
			(start 0.12065 0.2794)
			(end 0.12065 0.3048)
			(stroke
				(width 0.1)
				(type default)
			)
			(layer "B.Fab")
		)
		(fp_line
			(start 0.12065 0.3048)
			(end 0.67945 0.3048)
			(stroke
				(width 0.1)
				(type default)
			)
			(layer "B.Fab")
		)
		(fp_line
			(start 0.67945 -0.305054)
			(end 0.12065 -0.305054)
			(stroke
				(width 0.1)
				(type default)
			)
			(layer "B.Fab")
		)
		(fp_line
			(start 0.67945 0.3048)
			(end 0.67945 -0.305054)
			(stroke
				(width 0.1)
				(type default)
			)
			(layer "B.Fab")
		)
		(pad "1" smd circle
			(at 0.40005 0 180)
			(size 0 0)
			(layers "B.Cu" "B.Mask" "B.Paste")
			(net "PVDDCR_CPU0_P0")
		)
		(pad "2" smd circle
			(at -0.40005 0 180)
			(size 0 0)
			(layers "B.Cu" "B.Mask" "B.Paste")
			(net "GND")
		)
	)
	(footprint ""
		(layer "B.Cu")
		(at 163.815268 -415.75101)
		(property "Reference" "R4125"
			(at 0 0 0)
			(layer "B.SilkS")
			(hide yes)
			(effects
				(font
					(size 1.27 1.27)
				)
				(justify mirror)
			)
		)
		(property "Value" ""
			(at 0 0 0)
			(layer "B.Fab")
			(effects
				(font
					(size 1.27 1.27)
				)
				(justify mirror)
			)
		)
		(duplicate_pad_numbers_are_jumpers no)
		(fp_line
			(start -0.7874 -0.4064)
			(end -0.7874 0.4064)
			(stroke
				(width 0.1524)
				(type default)
			)
			(layer "B.SilkS")
		)
		(fp_line
			(start -0.7874 0.4064)
			(end 0.7874 0.4064)
			(stroke
				(width 0.1524)
				(type default)
			)
			(layer "B.SilkS")
		)
		(fp_line
			(start 0.7874 -0.4064)
			(end -0.7874 -0.4064)
			(stroke
				(width 0.1524)
				(type default)
			)
			(layer "B.SilkS")
		)
		(fp_line
			(start 0.7874 0.4064)
			(end 0.7874 -0.4064)
			(stroke
				(width 0.1524)
				(type default)
			)
			(layer "B.SilkS")
		)
		(fp_line
			(start -0.67945 -0.3048)
			(end -0.67945 0.3048)
			(stroke
				(width 0.1)
				(type default)
			)
			(layer "B.Fab")
		)
		(fp_line
			(start -0.67945 0.3048)
			(end -0.120396 0.3048)
			(stroke
				(width 0.1)
				(type default)
			)
			(layer "B.Fab")
		)
		(fp_line
			(start -0.12065 -0.3048)
			(end -0.67945 -0.3048)
			(stroke
				(width 0.1)
				(type default)
			)
			(layer "B.Fab")
		)
		(fp_line
			(start -0.12065 -0.2794)
			(end -0.12065 -0.3048)
			(stroke
				(width 0.1)
				(type default)
			)
			(layer "B.Fab")
		)
		(fp_line
			(start -0.120396 0.2794)
			(end 0.12065 0.2794)
			(stroke
				(width 0.1)
				(type default)
			)
			(layer "B.Fab")
		)
		(fp_line
			(start -0.120396 0.3048)
			(end -0.120396 0.2794)
			(stroke
				(width 0.1)
				(type default)
			)
			(layer "B.Fab")
		)
		(fp_line
			(start 0.12065 -0.305054)
			(end 0.12065 -0.2794)
			(stroke
				(width 0.1)
				(type default)
			)
			(layer "B.Fab")
		)
		(fp_line
			(start 0.12065 -0.2794)
			(end -0.12065 -0.2794)
			(stroke
				(width 0.1)
				(type default)
			)
			(layer "B.Fab")
		)
		(fp_line
			(start 0.12065 0.2794)
			(end 0.12065 0.3048)
			(stroke
				(width 0.1)
				(type default)
			)
			(layer "B.Fab")
		)
		(fp_line
			(start 0.12065 0.3048)
			(end 0.67945 0.3048)
			(stroke
				(width 0.1)
				(type default)
			)
			(layer "B.Fab")
		)
		(fp_line
			(start 0.67945 -0.305054)
			(end 0.12065 -0.305054)
			(stroke
				(width 0.1)
				(type default)
			)
			(layer "B.Fab")
		)
		(fp_line
			(start 0.67945 0.3048)
			(end 0.67945 -0.305054)
			(stroke
				(width 0.1)
				(type default)
			)
			(layer "B.Fab")
		)
		(pad "1" smd circle
			(at 0.40005 0 180)
			(size 0 0)
			(layers "B.Cu" "B.Mask" "B.Paste")
			(net "P3V3_AUX")
		)
		(pad "2" smd circle
			(at -0.40005 0 180)
			(size 0 0)
			(layers "B.Cu" "B.Mask" "B.Paste")
			(net "GPU_3V3IO_RSVD0_FFU_N")
		)
	)
	(footprint ""
		(layer "B.Cu")
		(at 90.209878 -141.83741)
		(property "Reference" "C248"
			(at 0 0 0)
			(layer "B.SilkS")
			(hide yes)
			(effects
				(font
					(size 1.27 1.27)
				)
				(justify mirror)
			)
		)
		(property "Value" ""
			(at 0 0 0)
			(layer "B.Fab")
			(effects
				(font
					(size 1.27 1.27)
				)
				(justify mirror)
			)
		)
		(duplicate_pad_numbers_are_jumpers no)
		(fp_line
			(start -0.7874 -0.4064)
			(end -0.7874 0.4064)
			(stroke
				(width 0.1524)
				(type default)
			)
			(layer "B.SilkS")
		)
		(fp_line
			(start -0.7874 0.4064)
			(end 0.7874 0.4064)
			(stroke
				(width 0.1524)
				(type default)
			)
			(layer "B.SilkS")
		)
		(fp_line
			(start 0.7874 -0.4064)
			(end -0.7874 -0.4064)
			(stroke
				(width 0.1524)
				(type default)
			)
			(layer "B.SilkS")
		)
		(fp_line
			(start 0.7874 0.4064)
			(end 0.7874 -0.4064)
			(stroke
				(width 0.1524)
				(type default)
			)
			(layer "B.SilkS")
		)
		(fp_line
			(start -0.67945 -0.3048)
			(end -0.67945 0.3048)
			(stroke
				(width 0.1)
				(type default)
			)
			(layer "B.Fab")
		)
		(fp_line
			(start -0.67945 0.3048)
			(end -0.120396 0.3048)
			(stroke
				(width 0.1)
				(type default)
			)
			(layer "B.Fab")
		)
		(fp_line
			(start -0.12065 -0.3048)
			(end -0.67945 -0.3048)
			(stroke
				(width 0.1)
				(type default)
			)
			(layer "B.Fab")
		)
		(fp_line
			(start -0.12065 -0.2794)
			(end -0.12065 -0.3048)
			(stroke
				(width 0.1)
				(type default)
			)
			(layer "B.Fab")
		)
		(fp_line
			(start -0.120396 0.2794)
			(end 0.12065 0.2794)
			(stroke
				(width 0.1)
				(type default)
			)
			(layer "B.Fab")
		)
		(fp_line
			(start -0.120396 0.3048)
			(end -0.120396 0.2794)
			(stroke
				(width 0.1)
				(type default)
			)
			(layer "B.Fab")
		)
		(fp_line
			(start 0.12065 -0.305054)
			(end 0.12065 -0.2794)
			(stroke
				(width 0.1)
				(type default)
			)
			(layer "B.Fab")
		)
		(fp_line
			(start 0.12065 -0.2794)
			(end -0.12065 -0.2794)
			(stroke
				(width 0.1)
				(type default)
			)
			(layer "B.Fab")
		)
		(fp_line
			(start 0.12065 0.2794)
			(end 0.12065 0.3048)
			(stroke
				(width 0.1)
				(type default)
			)
			(layer "B.Fab")
		)
		(fp_line
			(start 0.12065 0.3048)
			(end 0.67945 0.3048)
			(stroke
				(width 0.1)
				(type default)
			)
			(layer "B.Fab")
		)
		(fp_line
			(start 0.67945 -0.305054)
			(end 0.12065 -0.305054)
			(stroke
				(width 0.1)
				(type default)
			)
			(layer "B.Fab")
		)
		(fp_line
			(start 0.67945 0.3048)
			(end 0.67945 -0.305054)
			(stroke
				(width 0.1)
				(type default)
			)
			(layer "B.Fab")
		)
		(pad "1" smd circle
			(at 0.40005 0 180)
			(size 0 0)
			(layers "B.Cu" "B.Mask" "B.Paste")
			(net "PWRGD_PVDDCR_CPU0_P1_R")
		)
		(pad "2" smd circle
			(at -0.40005 0 180)
			(size 0 0)
			(layers "B.Cu" "B.Mask" "B.Paste")
			(net "GND")
		)
	)
	(footprint ""
		(layer "B.Cu")
		(at 5.985002 -403.945852 180)
		(property "Reference" ""
			(at 0 0 0)
			(layer "B.SilkS")
			(hide yes)
			(effects
				(font
					(size 1.27 1.27)
				)
				(justify mirror)
			)
		)
		(property "Value" ""
			(at 0 0 0)
			(layer "B.Fab")
			(effects
				(font
					(size 1.27 1.27)
				)
				(justify mirror)
			)
		)
		(duplicate_pad_numbers_are_jumpers no)
		(pad "1" smd circle
			(at 0 0)
			(size 0.9906 0.9906)
			(layers "B.Cu" "B.Mask" "B.Paste")
			(net "Net_2231")
		)
		(zone
			(layer "B.Cu")
			(hatch none 0.5)
			(connect_pads
				(clearance 0)
			)
			(min_thickness 0.25)
			(keepout
				(tracks not_allowed)
				(vias allowed)
				(pads allowed)
				(copperpour not_allowed)
				(footprints allowed)
			)
			(placement
				(enabled no)
				(sheetname "")
			)
			(fill
				(thermal_gap 0.5)
				(thermal_bridge_width 0.5)
				(island_removal_mode 0)
			)
			(polygon
				(pts
					(arc
						(start 7.610602 -403.945852)
						(mid 4.359402 -403.945852)
						(end 7.610602 -403.945852)
					)
				)
			)
		)
	)
	(footprint ""
		(layer "B.Cu")
		(at 354.812854 -420.626032 90)
		(property "Reference" "R2841"
			(at 0 0 90)
			(layer "B.SilkS")
			(hide yes)
			(effects
				(font
					(size 1.27 1.27)
				)
				(justify mirror)
			)
		)
		(property "Value" ""
			(at 0 0 90)
			(layer "B.Fab")
			(effects
				(font
					(size 1.27 1.27)
				)
				(justify mirror)
			)
		)
		(duplicate_pad_numbers_are_jumpers no)
		(fp_line
			(start 0.7874 -0.4064)
			(end -0.7874 -0.4064)
			(stroke
				(width 0.1524)
				(type default)
			)
			(layer "B.SilkS")
		)
		(fp_line
			(start -0.7874 -0.4064)
			(end -0.7874 0.4064)
			(stroke
				(width 0.1524)
				(type default)
			)
			(layer "B.SilkS")
		)
		(fp_line
			(start 0.7874 0.4064)
			(end 0.7874 -0.4064)
			(stroke
				(width 0.1524)
				(type default)
			)
			(layer "B.SilkS")
		)
		(fp_line
			(start -0.7874 0.4064)
			(end 0.7874 0.4064)
			(stroke
				(width 0.1524)
				(type default)
			)
			(layer "B.SilkS")
		)
		(fp_line
			(start 0.67945 -0.305054)
			(end 0.12065 -0.305054)
			(stroke
				(width 0.1)
				(type default)
			)
			(layer "B.Fab")
		)
		(fp_line
			(start 0.12065 -0.305054)
			(end 0.12065 -0.2794)
			(stroke
				(width 0.1)
				(type default)
			)
			(layer "B.Fab")
		)
		(fp_line
			(start -0.12065 -0.3048)
			(end -0.67945 -0.3048)
			(stroke
				(width 0.1)
				(type default)
			)
			(layer "B.Fab")
		)
		(fp_line
			(start -0.67945 -0.3048)
			(end -0.67945 0.3048)
			(stroke
				(width 0.1)
				(type default)
			)
			(layer "B.Fab")
		)
		(fp_line
			(start 0.12065 -0.2794)
			(end -0.12065 -0.2794)
			(stroke
				(width 0.1)
				(type default)
			)
			(layer "B.Fab")
		)
		(fp_line
			(start -0.12065 -0.2794)
			(end -0.12065 -0.3048)
			(stroke
				(width 0.1)
				(type default)
			)
			(layer "B.Fab")
		)
		(fp_line
			(start 0.12065 0.2794)
			(end 0.12065 0.3048)
			(stroke
				(width 0.1)
				(type default)
			)
			(layer "B.Fab")
		)
		(fp_line
			(start -0.120396 0.2794)
			(end 0.12065 0.2794)
			(stroke
				(width 0.1)
				(type default)
			)
			(layer "B.Fab")
		)
		(fp_line
			(start 0.67945 0.3048)
			(end 0.67945 -0.305054)
			(stroke
				(width 0.1)
				(type default)
			)
			(layer "B.Fab")
		)
		(fp_line
			(start 0.12065 0.3048)
			(end 0.67945 0.3048)
			(stroke
				(width 0.1)
				(type default)
			)
			(layer "B.Fab")
		)
		(fp_line
			(start -0.120396 0.3048)
			(end -0.120396 0.2794)
			(stroke
				(width 0.1)
				(type default)
			)
			(layer "B.Fab")
		)
		(fp_line
			(start -0.67945 0.3048)
			(end -0.120396 0.3048)
			(stroke
				(width 0.1)
				(type default)
			)
			(layer "B.Fab")
		)
		(pad "1" smd circle
			(at 0.40005 0 270)
			(size 0 0)
			(layers "B.Cu" "B.Mask" "B.Paste")
			(net "P3V3_AUX")
		)
		(pad "2" smd circle
			(at -0.40005 0 270)
			(size 0 0)
			(layers "B.Cu" "B.Mask" "B.Paste")
			(net "FM_SWB_PWRGD_N")
		)
	)
	(footprint ""
		(layer "B.Cu")
		(at 185.862722 3.523234)
		(property "Reference" "J120"
			(at 4.65455 1.527302 270)
			(unlocked yes)
			(layer "B.SilkS")
			(effects
				(font
					(size 0.7874 0.5842)
					(thickness 0.1524)
				)
				(justify left mirror)
			)
		)
		(property "Value" ""
			(at 0 0 0)
			(layer "B.Fab")
			(effects
				(font
					(size 1.27 1.27)
				)
				(justify mirror)
			)
		)
		(duplicate_pad_numbers_are_jumpers no)
		(fp_line
			(start -1.2192 -2.06756)
			(end -1.2192 2.06756)
			(stroke
				(width 0.1524)
				(type default)
			)
			(layer "B.SilkS")
		)
		(fp_line
			(start -1.2192 2.06756)
			(end 1.2192 2.06756)
			(stroke
				(width 0.1524)
				(type default)
			)
			(layer "B.SilkS")
		)
		(fp_line
			(start 1.2192 -2.06756)
			(end -1.2192 -2.06756)
			(stroke
				(width 0.1524)
				(type default)
			)
			(layer "B.SilkS")
		)
		(fp_line
			(start 1.2192 2.06756)
			(end 1.2192 -2.06756)
			(stroke
				(width 0.1524)
				(type default)
			)
			(layer "B.SilkS")
		)
		(pad "" np_thru_hole circle
			(at -3.4671 -1.27 270)
			(size 1.0414 1.0414)
			(drill 1.0414)
			(layers "*.Cu" "*.Mask")
			(clearance 0.381)
			(thermal_gap 0.381)
		)
		(pad "" np_thru_hole circle
			(at -3.4671 1.27 270)
			(size 1.0414 1.0414)
			(drill 1.0414)
			(layers "*.Cu" "*.Mask")
			(clearance 0.381)
			(thermal_gap 0.381)
		)
		(pad "" np_thru_hole circle
			(at 2.8829 -1.27 270)
			(size 1.0414 1.0414)
			(drill 1.0414)
			(layers "*.Cu" "*.Mask")
			(clearance 0.381)
			(thermal_gap 0.381)
		)
		(pad "" np_thru_hole circle
			(at 2.8829 1.27 270)
			(size 1.0414 1.0414)
			(drill 1.0414)
			(layers "*.Cu" "*.Mask")
			(clearance 0.381)
			(thermal_gap 0.381)
		)
		(pad "1" smd rect
			(at -0.8255 -0.249936 270)
			(size 0.3048 0.508)
			(layers "B.Cu" "B.Mask" "B.Paste")
			(net "DELTA_L_85_10INCH_IN5_DN")
		)
		(pad "2" smd rect
			(at -0.8255 0.249936 270)
			(size 0.3048 0.508)
			(layers "B.Cu" "B.Mask" "B.Paste")
			(net "DELTA_L_85_10INCH_IN5_DP")
		)
		(pad "3" smd circle
			(at 0 0 180)
			(size 0 0)
			(layers "B.Cu" "B.Mask" "B.Paste")
			(net "DELTA_L_GND_1")
		)
		(zone
			(layers "F.Cu" "B.Cu" "In1.Cu" "In2.Cu" "In3.Cu" "In4.Cu" "In5.Cu" "In6.Cu"
				"In7.Cu" "In8.Cu" "In9.Cu" "In10.Cu" "In11.Cu" "In12.Cu" "In13.Cu" "In14.Cu"
				"In15.Cu" "In16.Cu"
			)
			(hatch none 0.5)
			(connect_pads
				(clearance 0)
			)
			(min_thickness 0.25)
			(keepout
				(tracks not_allowed)
				(vias allowed)
				(pads allowed)
				(copperpour not_allowed)
				(footprints allowed)
			)
			(placement
				(enabled no)
				(sheetname "")
			)
			(fill
				(thermal_gap 0.5)
				(thermal_bridge_width 0.5)
				(island_removal_mode 0)
			)
			(polygon
				(pts
					(arc
						(start 183.322722 2.253234)
						(mid 181.468522 2.253234)
						(end 183.322722 2.253234)
					)
				)
			)
		)
		(zone
			(layers "F.Cu" "B.Cu" "In1.Cu" "In2.Cu" "In3.Cu" "In4.Cu" "In5.Cu" "In6.Cu"
				"In7.Cu" "In8.Cu" "In9.Cu" "In10.Cu" "In11.Cu" "In12.Cu" "In13.Cu" "In14.Cu"
				"In15.Cu" "In16.Cu"
			)
			(hatch none 0.5)
			(connect_pads
				(clearance 0)
			)
			(min_thickness 0.25)
			(keepout
				(tracks not_allowed)
				(vias allowed)
				(pads allowed)
				(copperpour not_allowed)
				(footprints allowed)
			)
			(placement
				(enabled no)
				(sheetname "")
			)
			(fill
				(thermal_gap 0.5)
				(thermal_bridge_width 0.5)
				(island_removal_mode 0)
			)
			(polygon
				(pts
					(arc
						(start 183.322722 4.793234)
						(mid 181.468522 4.793234)
						(end 183.322722 4.793234)
					)
				)
			)
		)
		(zone
			(layers "F.Cu" "B.Cu" "In1.Cu" "In2.Cu" "In3.Cu" "In4.Cu" "In5.Cu" "In6.Cu"
				"In7.Cu" "In8.Cu" "In9.Cu" "In10.Cu" "In11.Cu" "In12.Cu" "In13.Cu" "In14.Cu"
				"In15.Cu" "In16.Cu"
			)
			(hatch none 0.5)
			(connect_pads
				(clearance 0)
			)
			(min_thickness 0.25)
			(keepout
				(tracks not_allowed)
				(vias allowed)
				(pads allowed)
				(copperpour not_allowed)
				(footprints allowed)
			)
			(placement
				(enabled no)
				(sheetname "")
			)
			(fill
				(thermal_gap 0.5)
				(thermal_bridge_width 0.5)
				(island_removal_mode 0)
			)
			(polygon
				(pts
					(arc
						(start 189.672722 2.253234)
						(mid 187.818522 2.253234)
						(end 189.672722 2.253234)
					)
				)
			)
		)
		(zone
			(layers "F.Cu" "B.Cu" "In1.Cu" "In2.Cu" "In3.Cu" "In4.Cu" "In5.Cu" "In6.Cu"
				"In7.Cu" "In8.Cu" "In9.Cu" "In10.Cu" "In11.Cu" "In12.Cu" "In13.Cu" "In14.Cu"
				"In15.Cu" "In16.Cu"
			)
			(hatch none 0.5)
			(connect_pads
				(clearance 0)
			)
			(min_thickness 0.25)
			(keepout
				(tracks not_allowed)
				(vias allowed)
				(pads allowed)
				(copperpour not_allowed)
				(footprints allowed)
			)
			(placement
				(enabled no)
				(sheetname "")
			)
			(fill
				(thermal_gap 0.5)
				(thermal_bridge_width 0.5)
				(island_removal_mode 0)
			)
			(polygon
				(pts
					(arc
						(start 189.672722 4.793234)
						(mid 187.818522 4.793234)
						(end 189.672722 4.793234)
					)
				)
			)
		)
		(zone
			(layer "B.Cu")
			(hatch none 0.5)
			(connect_pads
				(clearance 0)
			)
			(min_thickness 0.25)
			(keepout
				(tracks not_allowed)
				(vias allowed)
				(pads allowed)
				(copperpour not_allowed)
				(footprints allowed)
			)
			(placement
				(enabled no)
				(sheetname "")
			)
			(fill
				(thermal_gap 0.5)
				(thermal_bridge_width 0.5)
				(island_removal_mode 0)
			)
			(polygon
				(pts
					(xy 184.745122 2.974594) (xy 184.745122 3.070098) (xy 185.342022 3.070098) (xy 185.342022 3.476498)
					(xy 184.745122 3.476498) (xy 184.745122 3.56997) (xy 185.342022 3.56997) (xy 185.342022 3.97637)
					(xy 184.745122 3.97637) (xy 184.745122 4.071874) (xy 185.443622 4.071874) (xy 185.443622 2.974594)
				)
			)
		)
	)
	(footprint ""
		(layer "B.Cu")
		(at 105.196386 -248.479564)
		(property "Reference" "C2319"
			(at 0 0 0)
			(layer "B.SilkS")
			(hide yes)
			(effects
				(font
					(size 1.27 1.27)
				)
				(justify mirror)
			)
		)
		(property "Value" ""
			(at 0 0 0)
			(layer "B.Fab")
			(effects
				(font
					(size 1.27 1.27)
				)
				(justify mirror)
			)
		)
		(duplicate_pad_numbers_are_jumpers no)
		(fp_line
			(start -0.7874 -0.4064)
			(end -0.7874 0.4064)
			(stroke
				(width 0.1524)
				(type default)
			)
			(layer "B.SilkS")
		)
		(fp_line
			(start -0.7874 0.4064)
			(end 0.7874 0.4064)
			(stroke
				(width 0.1524)
				(type default)
			)
			(layer "B.SilkS")
		)
		(fp_line
			(start 0.7874 -0.4064)
			(end -0.7874 -0.4064)
			(stroke
				(width 0.1524)
				(type default)
			)
			(layer "B.SilkS")
		)
		(fp_line
			(start 0.7874 0.4064)
			(end 0.7874 -0.4064)
			(stroke
				(width 0.1524)
				(type default)
			)
			(layer "B.SilkS")
		)
		(fp_line
			(start -0.67945 -0.3048)
			(end -0.67945 0.3048)
			(stroke
				(width 0.1)
				(type default)
			)
			(layer "B.Fab")
		)
		(fp_line
			(start -0.67945 0.3048)
			(end -0.120396 0.3048)
			(stroke
				(width 0.1)
				(type default)
			)
			(layer "B.Fab")
		)
		(fp_line
			(start -0.12065 -0.3048)
			(end -0.67945 -0.3048)
			(stroke
				(width 0.1)
				(type default)
			)
			(layer "B.Fab")
		)
		(fp_line
			(start -0.12065 -0.2794)
			(end -0.12065 -0.3048)
			(stroke
				(width 0.1)
				(type default)
			)
			(layer "B.Fab")
		)
		(fp_line
			(start -0.120396 0.2794)
			(end 0.12065 0.2794)
			(stroke
				(width 0.1)
				(type default)
			)
			(layer "B.Fab")
		)
		(fp_line
			(start -0.120396 0.3048)
			(end -0.120396 0.2794)
			(stroke
				(width 0.1)
				(type default)
			)
			(layer "B.Fab")
		)
		(fp_line
			(start 0.12065 -0.305054)
			(end 0.12065 -0.2794)
			(stroke
				(width 0.1)
				(type default)
			)
			(layer "B.Fab")
		)
		(fp_line
			(start 0.12065 -0.2794)
			(end -0.12065 -0.2794)
			(stroke
				(width 0.1)
				(type default)
			)
			(layer "B.Fab")
		)
		(fp_line
			(start 0.12065 0.2794)
			(end 0.12065 0.3048)
			(stroke
				(width 0.1)
				(type default)
			)
			(layer "B.Fab")
		)
		(fp_line
			(start 0.12065 0.3048)
			(end 0.67945 0.3048)
			(stroke
				(width 0.1)
				(type default)
			)
			(layer "B.Fab")
		)
		(fp_line
			(start 0.67945 -0.305054)
			(end 0.12065 -0.305054)
			(stroke
				(width 0.1)
				(type default)
			)
			(layer "B.Fab")
		)
		(fp_line
			(start 0.67945 0.3048)
			(end 0.67945 -0.305054)
			(stroke
				(width 0.1)
				(type default)
			)
			(layer "B.Fab")
		)
		(pad "1" smd circle
			(at 0.40005 0 180)
			(size 0 0)
			(layers "B.Cu" "B.Mask" "B.Paste")
			(net "PVDDCR_CPU0_P1")
		)
		(pad "2" smd circle
			(at -0.40005 0 180)
			(size 0 0)
			(layers "B.Cu" "B.Mask" "B.Paste")
			(net "GND")
		)
	)
	(footprint ""
		(layer "B.Cu")
		(at 379.018546 -396.393162 -90)
		(property "Reference" "C998"
			(at 0 0 90)
			(layer "B.SilkS")
			(hide yes)
			(effects
				(font
					(size 1.27 1.27)
				)
				(justify mirror)
			)
		)
		(property "Value" ""
			(at 0 0 90)
			(layer "B.Fab")
			(effects
				(font
					(size 1.27 1.27)
				)
				(justify mirror)
			)
		)
		(duplicate_pad_numbers_are_jumpers no)
		(fp_line
			(start -0.299974 0.150114)
			(end 0.299974 0.150114)
			(stroke
				(width 0.1)
				(type default)
			)
			(layer "B.Fab")
		)
		(fp_line
			(start 0.299974 0.150114)
			(end 0.299974 -0.150114)
			(stroke
				(width 0.1)
				(type default)
			)
			(layer "B.Fab")
		)
		(fp_line
			(start -0.299974 -0.150114)
			(end -0.299974 0.150114)
			(stroke
				(width 0.1)
				(type default)
			)
			(layer "B.Fab")
		)
		(fp_line
			(start 0.299974 -0.150114)
			(end -0.299974 -0.150114)
			(stroke
				(width 0.1)
				(type default)
			)
			(layer "B.Fab")
		)
		(pad "1" smd rect
			(at 0.2667 0 90)
			(size 0.3048 0.381)
			(layers "B.Cu" "B.Mask" "B.Paste")
			(net "P1V8_CPU0_RT3_1A")
		)
		(pad "2" smd rect
			(at -0.2667 0 90)
			(size 0.3048 0.381)
			(layers "B.Cu" "B.Mask" "B.Paste")
			(net "GND")
		)
	)
	(footprint ""
		(layer "B.Cu")
		(at 334.099408 -389.97763)
		(property "Reference" "C7013"
			(at 0 0 0)
			(layer "B.SilkS")
			(hide yes)
			(effects
				(font
					(size 1.27 1.27)
				)
				(justify mirror)
			)
		)
		(property "Value" ""
			(at 0 0 0)
			(layer "B.Fab")
			(effects
				(font
					(size 1.27 1.27)
				)
				(justify mirror)
			)
		)
		(duplicate_pad_numbers_are_jumpers no)
		(fp_line
			(start -1.524 -0.762)
			(end -1.524 0.762)
			(stroke
				(width 0.1524)
				(type default)
			)
			(layer "B.SilkS")
		)
		(fp_line
			(start -1.524 0.762)
			(end 1.524 0.762)
			(stroke
				(width 0.1524)
				(type default)
			)
			(layer "B.SilkS")
		)
		(fp_line
			(start 1.524 -0.762)
			(end -1.524 -0.762)
			(stroke
				(width 0.1524)
				(type default)
			)
			(layer "B.SilkS")
		)
		(fp_line
			(start 1.524 0.762)
			(end 1.524 -0.762)
			(stroke
				(width 0.1524)
				(type default)
			)
			(layer "B.SilkS")
		)
		(fp_line
			(start -1.1049 -0.724916)
			(end 1.1049 -0.724916)
			(stroke
				(width 0.1)
				(type default)
			)
			(layer "B.Fab")
		)
		(fp_line
			(start -1.1049 0.724916)
			(end -1.1049 -0.724916)
			(stroke
				(width 0.1)
				(type default)
			)
			(layer "B.Fab")
		)
		(fp_line
			(start 1.1049 -0.724916)
			(end 1.1049 0.724916)
			(stroke
				(width 0.1)
				(type default)
			)
			(layer "B.Fab")
		)
		(fp_line
			(start 1.1049 0.724916)
			(end -1.1049 0.724916)
			(stroke
				(width 0.1)
				(type default)
			)
			(layer "B.Fab")
		)
		(pad "1" smd rect
			(at 0.889 0)
			(size 1.016 1.27)
			(layers "B.Cu" "B.Mask" "B.Paste")
			(net "P0V9_CPU0_RT1_2A")
		)
		(pad "2" smd rect
			(at -0.889 0)
			(size 1.016 1.27)
			(layers "B.Cu" "B.Mask" "B.Paste")
			(net "GND")
		)
	)
	(footprint ""
		(layer "B.Cu")
		(at 305.423316 -428.0916 180)
		(property "Reference" "R1446"
			(at 0 0 0)
			(layer "B.SilkS")
			(hide yes)
			(effects
				(font
					(size 1.27 1.27)
				)
				(justify mirror)
			)
		)
		(property "Value" ""
			(at 0 0 0)
			(layer "B.Fab")
			(effects
				(font
					(size 1.27 1.27)
				)
				(justify mirror)
			)
		)
		(duplicate_pad_numbers_are_jumpers no)
		(fp_line
			(start 0.32512 0.175006)
			(end 0.32512 -0.175006)
			(stroke
				(width 0.1)
				(type default)
			)
			(layer "B.Fab")
		)
		(fp_line
			(start 0.32512 -0.175006)
			(end -0.32512 -0.175006)
			(stroke
				(width 0.1)
				(type default)
			)
			(layer "B.Fab")
		)
		(fp_line
			(start -0.32512 0.175006)
			(end 0.32512 0.175006)
			(stroke
				(width 0.1)
				(type default)
			)
			(layer "B.Fab")
		)
		(fp_line
			(start -0.32512 -0.175006)
			(end -0.32512 0.175006)
			(stroke
				(width 0.1)
				(type default)
			)
			(layer "B.Fab")
		)
		(pad "1" smd rect
			(at 0.2667 0)
			(size 0.3048 0.381)
			(layers "B.Cu" "B.Mask" "B.Paste")
			(net "P1V8_CPU0_RT_1D")
		)
		(pad "2" smd rect
			(at -0.2667 0 180)
			(size 0.3048 0.381)
			(layers "B.Cu" "B.Mask" "B.Paste")
			(net "JTAG_TCK_RT_CPU0_P0")
		)
	)
	(footprint ""
		(layer "B.Cu")
		(at 104.307386 -253.432564)
		(property "Reference" "C2455"
			(at 0 0 0)
			(layer "B.SilkS")
			(hide yes)
			(effects
				(font
					(size 1.27 1.27)
				)
				(justify mirror)
			)
		)
		(property "Value" ""
			(at 0 0 0)
			(layer "B.Fab")
			(effects
				(font
					(size 1.27 1.27)
				)
				(justify mirror)
			)
		)
		(duplicate_pad_numbers_are_jumpers no)
		(fp_line
			(start -0.7874 -0.4064)
			(end -0.7874 0.4064)
			(stroke
				(width 0.1524)
				(type default)
			)
			(layer "B.SilkS")
		)
		(fp_line
			(start -0.7874 0.4064)
			(end 0.7874 0.4064)
			(stroke
				(width 0.1524)
				(type default)
			)
			(layer "B.SilkS")
		)
		(fp_line
			(start 0.7874 -0.4064)
			(end -0.7874 -0.4064)
			(stroke
				(width 0.1524)
				(type default)
			)
			(layer "B.SilkS")
		)
		(fp_line
			(start 0.7874 0.4064)
			(end 0.7874 -0.4064)
			(stroke
				(width 0.1524)
				(type default)
			)
			(layer "B.SilkS")
		)
		(fp_line
			(start -0.67945 -0.3048)
			(end -0.67945 0.3048)
			(stroke
				(width 0.1)
				(type default)
			)
			(layer "B.Fab")
		)
		(fp_line
			(start -0.67945 0.3048)
			(end -0.120396 0.3048)
			(stroke
				(width 0.1)
				(type default)
			)
			(layer "B.Fab")
		)
		(fp_line
			(start -0.12065 -0.3048)
			(end -0.67945 -0.3048)
			(stroke
				(width 0.1)
				(type default)
			)
			(layer "B.Fab")
		)
		(fp_line
			(start -0.12065 -0.2794)
			(end -0.12065 -0.3048)
			(stroke
				(width 0.1)
				(type default)
			)
			(layer "B.Fab")
		)
		(fp_line
			(start -0.120396 0.2794)
			(end 0.12065 0.2794)
			(stroke
				(width 0.1)
				(type default)
			)
			(layer "B.Fab")
		)
		(fp_line
			(start -0.120396 0.3048)
			(end -0.120396 0.2794)
			(stroke
				(width 0.1)
				(type default)
			)
			(layer "B.Fab")
		)
		(fp_line
			(start 0.12065 -0.305054)
			(end 0.12065 -0.2794)
			(stroke
				(width 0.1)
				(type default)
			)
			(layer "B.Fab")
		)
		(fp_line
			(start 0.12065 -0.2794)
			(end -0.12065 -0.2794)
			(stroke
				(width 0.1)
				(type default)
			)
			(layer "B.Fab")
		)
		(fp_line
			(start 0.12065 0.2794)
			(end 0.12065 0.3048)
			(stroke
				(width 0.1)
				(type default)
			)
			(layer "B.Fab")
		)
		(fp_line
			(start 0.12065 0.3048)
			(end 0.67945 0.3048)
			(stroke
				(width 0.1)
				(type default)
			)
			(layer "B.Fab")
		)
		(fp_line
			(start 0.67945 -0.305054)
			(end 0.12065 -0.305054)
			(stroke
				(width 0.1)
				(type default)
			)
			(layer "B.Fab")
		)
		(fp_line
			(start 0.67945 0.3048)
			(end 0.67945 -0.305054)
			(stroke
				(width 0.1)
				(type default)
			)
			(layer "B.Fab")
		)
		(pad "1" smd circle
			(at 0.40005 0 180)
			(size 0 0)
			(layers "B.Cu" "B.Mask" "B.Paste")
			(net "PVDDCR_SOC_P1")
		)
		(pad "2" smd circle
			(at -0.40005 0 180)
			(size 0 0)
			(layers "B.Cu" "B.Mask" "B.Paste")
			(net "GND")
		)
	)
	(footprint ""
		(layer "B.Cu")
		(at 214.122 -339.598)
		(property "Reference" "R913"
			(at 0 0 0)
			(layer "B.SilkS")
			(hide yes)
			(effects
				(font
					(size 1.27 1.27)
				)
				(justify mirror)
			)
		)
		(property "Value" ""
			(at 0 0 0)
			(layer "B.Fab")
			(effects
				(font
					(size 1.27 1.27)
				)
				(justify mirror)
			)
		)
		(duplicate_pad_numbers_are_jumpers no)
		(fp_line
			(start -0.32512 -0.175006)
			(end -0.32512 0.175006)
			(stroke
				(width 0.1)
				(type default)
			)
			(layer "B.Fab")
		)
		(fp_line
			(start -0.32512 0.175006)
			(end 0.32512 0.175006)
			(stroke
				(width 0.1)
				(type default)
			)
			(layer "B.Fab")
		)
		(fp_line
			(start 0.32512 -0.175006)
			(end -0.32512 -0.175006)
			(stroke
				(width 0.1)
				(type default)
			)
			(layer "B.Fab")
		)
		(fp_line
			(start 0.32512 0.175006)
			(end 0.32512 -0.175006)
			(stroke
				(width 0.1)
				(type default)
			)
			(layer "B.Fab")
		)
		(pad "1" smd rect
			(at 0.2667 0 180)
			(size 0.3048 0.381)
			(layers "B.Cu" "B.Mask" "B.Paste")
			(net "SMB_RT_CPU1_P3_R_SCL")
		)
		(pad "2" smd rect
			(at -0.2667 0)
			(size 0.3048 0.381)
			(layers "B.Cu" "B.Mask" "B.Paste")
			(net "SMB_RT_CPU1_P3_R2_SCL")
		)
	)
	(footprint ""
		(layer "B.Cu")
		(at 315.391038 -399.291302 90)
		(property "Reference" "C528"
			(at 0 0 90)
			(layer "B.SilkS")
			(hide yes)
			(effects
				(font
					(size 1.27 1.27)
				)
				(justify mirror)
			)
		)
		(property "Value" ""
			(at 0 0 90)
			(layer "B.Fab")
			(effects
				(font
					(size 1.27 1.27)
				)
				(justify mirror)
			)
		)
		(duplicate_pad_numbers_are_jumpers no)
		(fp_line
			(start 0.299974 -0.150114)
			(end -0.299974 -0.150114)
			(stroke
				(width 0.1)
				(type default)
			)
			(layer "B.Fab")
		)
		(fp_line
			(start -0.299974 -0.150114)
			(end -0.299974 0.150114)
			(stroke
				(width 0.1)
				(type default)
			)
			(layer "B.Fab")
		)
		(fp_line
			(start 0.299974 0.150114)
			(end 0.299974 -0.150114)
			(stroke
				(width 0.1)
				(type default)
			)
			(layer "B.Fab")
		)
		(fp_line
			(start -0.299974 0.150114)
			(end 0.299974 0.150114)
			(stroke
				(width 0.1)
				(type default)
			)
			(layer "B.Fab")
		)
		(pad "1" smd rect
			(at 0.2667 0 270)
			(size 0.3048 0.381)
			(layers "B.Cu" "B.Mask" "B.Paste")
			(net "P0V9_CPU0_RT_2D")
		)
		(pad "2" smd rect
			(at -0.2667 0 270)
			(size 0.3048 0.381)
			(layers "B.Cu" "B.Mask" "B.Paste")
			(net "GND")
		)
	)
	(footprint ""
		(layer "B.Cu")
		(at 397.332962 -316.652148 90)
		(property "Reference" "Y2"
			(at 2.936748 0.993648 0)
			(unlocked yes)
			(layer "B.SilkS")
			(effects
				(font
					(size 0.7874 0.5842)
					(thickness 0.1524)
				)
				(justify left mirror)
			)
		)
		(property "Value" ""
			(at 0 0 90)
			(layer "B.Fab")
			(effects
				(font
					(size 1.27 1.27)
				)
				(justify mirror)
			)
		)
		(duplicate_pad_numbers_are_jumpers no)
		(fp_line
			(start 1.538732 -1.937004)
			(end -1.538732 -1.937004)
			(stroke
				(width 0.1524)
				(type default)
			)
			(layer "B.SilkS")
		)
		(fp_line
			(start -1.538732 -1.937004)
			(end -1.538732 1.937004)
			(stroke
				(width 0.1524)
				(type default)
			)
			(layer "B.SilkS")
		)
		(fp_line
			(start 1.538732 1.937004)
			(end 1.538732 -1.937004)
			(stroke
				(width 0.1524)
				(type default)
			)
			(layer "B.SilkS")
		)
		(fp_line
			(start -1.538732 1.937004)
			(end 1.538732 1.937004)
			(stroke
				(width 0.1524)
				(type default)
			)
			(layer "B.SilkS")
		)
		(fp_poly
			(pts
				(xy 1.724406 -1.059942) (xy 2.5908 -1.493266) (xy 2.5908 -0.626872)
			)
			(stroke
				(width 0)
				(type default)
			)
			(fill yes)
			(layer "B.SilkS")
		)
		(fp_line
			(start 1.299972 -1.649984)
			(end -1.299972 -1.649984)
			(stroke
				(width 0.1)
				(type default)
			)
			(layer "B.Fab")
		)
		(fp_line
			(start -1.299972 -1.649984)
			(end -1.299972 1.649984)
			(stroke
				(width 0.1)
				(type default)
			)
			(layer "B.Fab")
		)
		(fp_line
			(start 1.299972 1.649984)
			(end 1.299972 -1.649984)
			(stroke
				(width 0.1)
				(type default)
			)
			(layer "B.Fab")
		)
		(fp_line
			(start -1.299972 1.649984)
			(end 1.299972 1.649984)
			(stroke
				(width 0.1)
				(type default)
			)
			(layer "B.Fab")
		)
		(fp_poly
			(pts
				(xy 2.5908 -0.626872) (xy 2.5908 -1.493266) (xy 1.724406 -1.059942)
			)
			(stroke
				(width 0)
				(type default)
			)
			(fill yes)
			(layer "B.Fab")
		)
		(pad "1" smd rect
			(at 0.8001 -1.059942 270)
			(size 1.2192 1.4986)
			(layers "B.Cu" "B.Mask" "B.Paste")
			(net "XTAL_CPU0_X48M_X1")
		)
		(pad "2" smd rect
			(at 0.8001 1.059942 270)
			(size 1.2192 1.4986)
			(layers "B.Cu" "B.Mask" "B.Paste")
			(net "GND")
		)
		(pad "3" smd rect
			(at -0.8001 1.059942 270)
			(size 1.2192 1.4986)
			(layers "B.Cu" "B.Mask" "B.Paste")
			(net "XTAL_CPU0_X48M_X2_R")
		)
		(pad "4" smd rect
			(at -0.8001 -1.059942 270)
			(size 1.2192 1.4986)
			(layers "B.Cu" "B.Mask" "B.Paste")
			(net "GND")
		)
	)
	(footprint ""
		(layer "B.Cu")
		(at 111.379 -416.941 180)
		(property "Reference" "R4545"
			(at 0 0 0)
			(layer "B.SilkS")
			(hide yes)
			(effects
				(font
					(size 1.27 1.27)
				)
				(justify mirror)
			)
		)
		(property "Value" ""
			(at 0 0 0)
			(layer "B.Fab")
			(effects
				(font
					(size 1.27 1.27)
				)
				(justify mirror)
			)
		)
		(duplicate_pad_numbers_are_jumpers no)
		(fp_line
			(start 0.7874 0.4064)
			(end 0.7874 -0.4064)
			(stroke
				(width 0.1524)
				(type default)
			)
			(layer "B.SilkS")
		)
		(fp_line
			(start 0.7874 -0.4064)
			(end -0.7874 -0.4064)
			(stroke
				(width 0.1524)
				(type default)
			)
			(layer "B.SilkS")
		)
		(fp_line
			(start -0.7874 0.4064)
			(end 0.7874 0.4064)
			(stroke
				(width 0.1524)
				(type default)
			)
			(layer "B.SilkS")
		)
		(fp_line
			(start -0.7874 -0.4064)
			(end -0.7874 0.4064)
			(stroke
				(width 0.1524)
				(type default)
			)
			(layer "B.SilkS")
		)
		(fp_line
			(start 0.67945 0.3048)
			(end 0.67945 -0.305054)
			(stroke
				(width 0.1)
				(type default)
			)
			(layer "B.Fab")
		)
		(fp_line
			(start 0.67945 -0.305054)
			(end 0.12065 -0.305054)
			(stroke
				(width 0.1)
				(type default)
			)
			(layer "B.Fab")
		)
		(fp_line
			(start 0.12065 0.3048)
			(end 0.67945 0.3048)
			(stroke
				(width 0.1)
				(type default)
			)
			(layer "B.Fab")
		)
		(fp_line
			(start 0.12065 0.2794)
			(end 0.12065 0.3048)
			(stroke
				(width 0.1)
				(type default)
			)
			(layer "B.Fab")
		)
		(fp_line
			(start 0.12065 -0.2794)
			(end -0.12065 -0.2794)
			(stroke
				(width 0.1)
				(type default)
			)
			(layer "B.Fab")
		)
		(fp_line
			(start 0.12065 -0.305054)
			(end 0.12065 -0.2794)
			(stroke
				(width 0.1)
				(type default)
			)
			(layer "B.Fab")
		)
		(fp_line
			(start -0.120396 0.3048)
			(end -0.120396 0.2794)
			(stroke
				(width 0.1)
				(type default)
			)
			(layer "B.Fab")
		)
		(fp_line
			(start -0.120396 0.2794)
			(end 0.12065 0.2794)
			(stroke
				(width 0.1)
				(type default)
			)
			(layer "B.Fab")
		)
		(fp_line
			(start -0.12065 -0.2794)
			(end -0.12065 -0.3048)
			(stroke
				(width 0.1)
				(type default)
			)
			(layer "B.Fab")
		)
		(fp_line
			(start -0.12065 -0.3048)
			(end -0.67945 -0.3048)
			(stroke
				(width 0.1)
				(type default)
			)
			(layer "B.Fab")
		)
		(fp_line
			(start -0.67945 0.3048)
			(end -0.120396 0.3048)
			(stroke
				(width 0.1)
				(type default)
			)
			(layer "B.Fab")
		)
		(fp_line
			(start -0.67945 -0.3048)
			(end -0.67945 0.3048)
			(stroke
				(width 0.1)
				(type default)
			)
			(layer "B.Fab")
		)
		(pad "1" smd circle
			(at 0.40005 0)
			(size 0 0)
			(layers "B.Cu" "B.Mask" "B.Paste")
			(net "P3V3_AUX")
		)
		(pad "2" smd circle
			(at -0.40005 0)
			(size 0 0)
			(layers "B.Cu" "B.Mask" "B.Paste")
			(net "HGX_DETECT")
		)
	)
	(footprint ""
		(layer "B.Cu")
		(at 141.820646 -408.517344 90)
		(property "Reference" "C6741"
			(at 0 0 90)
			(layer "B.SilkS")
			(hide yes)
			(effects
				(font
					(size 1.27 1.27)
				)
				(justify mirror)
			)
		)
		(property "Value" ""
			(at 0 0 90)
			(layer "B.Fab")
			(effects
				(font
					(size 1.27 1.27)
				)
				(justify mirror)
			)
		)
		(duplicate_pad_numbers_are_jumpers no)
		(fp_line
			(start 0.299974 -0.150114)
			(end -0.299974 -0.150114)
			(stroke
				(width 0.1)
				(type default)
			)
			(layer "B.Fab")
		)
		(fp_line
			(start -0.299974 -0.150114)
			(end -0.299974 0.150114)
			(stroke
				(width 0.1)
				(type default)
			)
			(layer "B.Fab")
		)
		(fp_line
			(start 0.299974 0.150114)
			(end 0.299974 -0.150114)
			(stroke
				(width 0.1)
				(type default)
			)
			(layer "B.Fab")
		)
		(fp_line
			(start -0.299974 0.150114)
			(end 0.299974 0.150114)
			(stroke
				(width 0.1)
				(type default)
			)
			(layer "B.Fab")
		)
		(pad "1" smd rect
			(at 0.2667 0 270)
			(size 0.3048 0.381)
			(layers "B.Cu" "B.Mask" "B.Paste")
			(net "P5E_CPU1_P3_TX_BUF_C_DP<8>")
		)
		(pad "2" smd rect
			(at -0.2667 0 270)
			(size 0.3048 0.381)
			(layers "B.Cu" "B.Mask" "B.Paste")
			(net "P5E_CPU1_P3_TX_BUF_DP<8>")
		)
	)
	(footprint ""
		(layer "B.Cu")
		(at 231.775 -242.443 90)
		(property "Reference" "R324"
			(at 0 0 90)
			(layer "B.SilkS")
			(hide yes)
			(effects
				(font
					(size 1.27 1.27)
				)
				(justify mirror)
			)
		)
		(property "Value" ""
			(at 0 0 90)
			(layer "B.Fab")
			(effects
				(font
					(size 1.27 1.27)
				)
				(justify mirror)
			)
		)
		(duplicate_pad_numbers_are_jumpers no)
		(fp_line
			(start 0.7874 -0.4064)
			(end -0.7874 -0.4064)
			(stroke
				(width 0.1524)
				(type default)
			)
			(layer "B.SilkS")
		)
		(fp_line
			(start -0.7874 -0.4064)
			(end -0.7874 0.4064)
			(stroke
				(width 0.1524)
				(type default)
			)
			(layer "B.SilkS")
		)
		(fp_line
			(start 0.7874 0.4064)
			(end 0.7874 -0.4064)
			(stroke
				(width 0.1524)
				(type default)
			)
			(layer "B.SilkS")
		)
		(fp_line
			(start -0.7874 0.4064)
			(end 0.7874 0.4064)
			(stroke
				(width 0.1524)
				(type default)
			)
			(layer "B.SilkS")
		)
		(fp_line
			(start 0.67945 -0.305054)
			(end 0.12065 -0.305054)
			(stroke
				(width 0.1)
				(type default)
			)
			(layer "B.Fab")
		)
		(fp_line
			(start 0.12065 -0.305054)
			(end 0.12065 -0.2794)
			(stroke
				(width 0.1)
				(type default)
			)
			(layer "B.Fab")
		)
		(fp_line
			(start -0.12065 -0.3048)
			(end -0.67945 -0.3048)
			(stroke
				(width 0.1)
				(type default)
			)
			(layer "B.Fab")
		)
		(fp_line
			(start -0.67945 -0.3048)
			(end -0.67945 0.3048)
			(stroke
				(width 0.1)
				(type default)
			)
			(layer "B.Fab")
		)
		(fp_line
			(start 0.12065 -0.2794)
			(end -0.12065 -0.2794)
			(stroke
				(width 0.1)
				(type default)
			)
			(layer "B.Fab")
		)
		(fp_line
			(start -0.12065 -0.2794)
			(end -0.12065 -0.3048)
			(stroke
				(width 0.1)
				(type default)
			)
			(layer "B.Fab")
		)
		(fp_line
			(start 0.12065 0.2794)
			(end 0.12065 0.3048)
			(stroke
				(width 0.1)
				(type default)
			)
			(layer "B.Fab")
		)
		(fp_line
			(start -0.120396 0.2794)
			(end 0.12065 0.2794)
			(stroke
				(width 0.1)
				(type default)
			)
			(layer "B.Fab")
		)
		(fp_line
			(start 0.67945 0.3048)
			(end 0.67945 -0.305054)
			(stroke
				(width 0.1)
				(type default)
			)
			(layer "B.Fab")
		)
		(fp_line
			(start 0.12065 0.3048)
			(end 0.67945 0.3048)
			(stroke
				(width 0.1)
				(type default)
			)
			(layer "B.Fab")
		)
		(fp_line
			(start -0.120396 0.3048)
			(end -0.120396 0.2794)
			(stroke
				(width 0.1)
				(type default)
			)
			(layer "B.Fab")
		)
		(fp_line
			(start -0.67945 0.3048)
			(end -0.120396 0.3048)
			(stroke
				(width 0.1)
				(type default)
			)
			(layer "B.Fab")
		)
		(pad "1" smd rect
			(at 0.40005 0 90)
			(size 0.4572 0.508)
			(layers "B.Cu" "B.Mask" "B.Paste")
			(net "SMB_CPU0_CPU1_APML_SCL_R2")
		)
		(pad "2" smd rect
			(at -0.40005 0 90)
			(size 0.4572 0.508)
			(layers "B.Cu" "B.Mask" "B.Paste")
			(net "SMB_CPU0_CPU1_APML_MUX1_SCL")
		)
	)
	(footprint ""
		(layer "B.Cu")
		(at 380.218442 -396.393162 -90)
		(property "Reference" "C1005"
			(at 0 0 90)
			(layer "B.SilkS")
			(hide yes)
			(effects
				(font
					(size 1.27 1.27)
				)
				(justify mirror)
			)
		)
		(property "Value" ""
			(at 0 0 90)
			(layer "B.Fab")
			(effects
				(font
					(size 1.27 1.27)
				)
				(justify mirror)
			)
		)
		(duplicate_pad_numbers_are_jumpers no)
		(fp_line
			(start -0.299974 0.150114)
			(end 0.299974 0.150114)
			(stroke
				(width 0.1)
				(type default)
			)
			(layer "B.Fab")
		)
		(fp_line
			(start 0.299974 0.150114)
			(end 0.299974 -0.150114)
			(stroke
				(width 0.1)
				(type default)
			)
			(layer "B.Fab")
		)
		(fp_line
			(start -0.299974 -0.150114)
			(end -0.299974 0.150114)
			(stroke
				(width 0.1)
				(type default)
			)
			(layer "B.Fab")
		)
		(fp_line
			(start 0.299974 -0.150114)
			(end -0.299974 -0.150114)
			(stroke
				(width 0.1)
				(type default)
			)
			(layer "B.Fab")
		)
		(pad "1" smd rect
			(at 0.2667 0 90)
			(size 0.3048 0.381)
			(layers "B.Cu" "B.Mask" "B.Paste")
			(net "P1V8_CPU0_RT3_1A")
		)
		(pad "2" smd rect
			(at -0.2667 0 90)
			(size 0.3048 0.381)
			(layers "B.Cu" "B.Mask" "B.Paste")
			(net "GND")
		)
	)
	(footprint ""
		(layer "B.Cu")
		(at 319.322958 -203.917296 -90)
		(property "Reference" "R388"
			(at 0 0 90)
			(layer "B.SilkS")
			(hide yes)
			(effects
				(font
					(size 1.27 1.27)
				)
				(justify mirror)
			)
		)
		(property "Value" ""
			(at 0 0 90)
			(layer "B.Fab")
			(effects
				(font
					(size 1.27 1.27)
				)
				(justify mirror)
			)
		)
		(duplicate_pad_numbers_are_jumpers no)
		(fp_line
			(start -0.7874 0.4064)
			(end 0.7874 0.4064)
			(stroke
				(width 0.1524)
				(type default)
			)
			(layer "B.SilkS")
		)
		(fp_line
			(start 0.7874 0.4064)
			(end 0.7874 -0.4064)
			(stroke
				(width 0.1524)
				(type default)
			)
			(layer "B.SilkS")
		)
		(fp_line
			(start -0.7874 -0.4064)
			(end -0.7874 0.4064)
			(stroke
				(width 0.1524)
				(type default)
			)
			(layer "B.SilkS")
		)
		(fp_line
			(start 0.7874 -0.4064)
			(end -0.7874 -0.4064)
			(stroke
				(width 0.1524)
				(type default)
			)
			(layer "B.SilkS")
		)
		(fp_line
			(start -0.67945 0.3048)
			(end -0.120396 0.3048)
			(stroke
				(width 0.1)
				(type default)
			)
			(layer "B.Fab")
		)
		(fp_line
			(start -0.120396 0.3048)
			(end -0.120396 0.2794)
			(stroke
				(width 0.1)
				(type default)
			)
			(layer "B.Fab")
		)
		(fp_line
			(start 0.12065 0.3048)
			(end 0.67945 0.3048)
			(stroke
				(width 0.1)
				(type default)
			)
			(layer "B.Fab")
		)
		(fp_line
			(start 0.67945 0.3048)
			(end 0.67945 -0.305054)
			(stroke
				(width 0.1)
				(type default)
			)
			(layer "B.Fab")
		)
		(fp_line
			(start -0.120396 0.2794)
			(end 0.12065 0.2794)
			(stroke
				(width 0.1)
				(type default)
			)
			(layer "B.Fab")
		)
		(fp_line
			(start 0.12065 0.2794)
			(end 0.12065 0.3048)
			(stroke
				(width 0.1)
				(type default)
			)
			(layer "B.Fab")
		)
		(fp_line
			(start -0.12065 -0.2794)
			(end -0.12065 -0.3048)
			(stroke
				(width 0.1)
				(type default)
			)
			(layer "B.Fab")
		)
		(fp_line
			(start 0.12065 -0.2794)
			(end -0.12065 -0.2794)
			(stroke
				(width 0.1)
				(type default)
			)
			(layer "B.Fab")
		)
		(fp_line
			(start -0.67945 -0.3048)
			(end -0.67945 0.3048)
			(stroke
				(width 0.1)
				(type default)
			)
			(layer "B.Fab")
		)
		(fp_line
			(start -0.12065 -0.3048)
			(end -0.67945 -0.3048)
			(stroke
				(width 0.1)
				(type default)
			)
			(layer "B.Fab")
		)
		(fp_line
			(start 0.12065 -0.305054)
			(end 0.12065 -0.2794)
			(stroke
				(width 0.1)
				(type default)
			)
			(layer "B.Fab")
		)
		(fp_line
			(start 0.67945 -0.305054)
			(end 0.12065 -0.305054)
			(stroke
				(width 0.1)
				(type default)
			)
			(layer "B.Fab")
		)
		(pad "1" smd circle
			(at 0.40005 0 90)
			(size 0 0)
			(layers "B.Cu" "B.Mask" "B.Paste")
			(net "P3V3_AUX")
		)
		(pad "2" smd circle
			(at -0.40005 0 90)
			(size 0 0)
			(layers "B.Cu" "B.Mask" "B.Paste")
			(net "CPU0_CORETYPE1")
		)
	)
	(footprint ""
		(layer "B.Cu")
		(at 372.135654 -269.30731 180)
		(property "Reference" "C2251"
			(at 0 0 0)
			(layer "B.SilkS")
			(hide yes)
			(effects
				(font
					(size 1.27 1.27)
				)
				(justify mirror)
			)
		)
		(property "Value" ""
			(at 0 0 0)
			(layer "B.Fab")
			(effects
				(font
					(size 1.27 1.27)
				)
				(justify mirror)
			)
		)
		(duplicate_pad_numbers_are_jumpers no)
		(fp_line
			(start 0.7874 0.4064)
			(end 0.7874 -0.4064)
			(stroke
				(width 0.1524)
				(type default)
			)
			(layer "B.SilkS")
		)
		(fp_line
			(start 0.7874 -0.4064)
			(end -0.7874 -0.4064)
			(stroke
				(width 0.1524)
				(type default)
			)
			(layer "B.SilkS")
		)
		(fp_line
			(start -0.7874 0.4064)
			(end 0.7874 0.4064)
			(stroke
				(width 0.1524)
				(type default)
			)
			(layer "B.SilkS")
		)
		(fp_line
			(start -0.7874 -0.4064)
			(end -0.7874 0.4064)
			(stroke
				(width 0.1524)
				(type default)
			)
			(layer "B.SilkS")
		)
		(fp_line
			(start 0.67945 0.3048)
			(end 0.67945 -0.305054)
			(stroke
				(width 0.1)
				(type default)
			)
			(layer "B.Fab")
		)
		(fp_line
			(start 0.67945 -0.305054)
			(end 0.12065 -0.305054)
			(stroke
				(width 0.1)
				(type default)
			)
			(layer "B.Fab")
		)
		(fp_line
			(start 0.12065 0.3048)
			(end 0.67945 0.3048)
			(stroke
				(width 0.1)
				(type default)
			)
			(layer "B.Fab")
		)
		(fp_line
			(start 0.12065 0.2794)
			(end 0.12065 0.3048)
			(stroke
				(width 0.1)
				(type default)
			)
			(layer "B.Fab")
		)
		(fp_line
			(start 0.12065 -0.2794)
			(end -0.12065 -0.2794)
			(stroke
				(width 0.1)
				(type default)
			)
			(layer "B.Fab")
		)
		(fp_line
			(start 0.12065 -0.305054)
			(end 0.12065 -0.2794)
			(stroke
				(width 0.1)
				(type default)
			)
			(layer "B.Fab")
		)
		(fp_line
			(start -0.120396 0.3048)
			(end -0.120396 0.2794)
			(stroke
				(width 0.1)
				(type default)
			)
			(layer "B.Fab")
		)
		(fp_line
			(start -0.120396 0.2794)
			(end 0.12065 0.2794)
			(stroke
				(width 0.1)
				(type default)
			)
			(layer "B.Fab")
		)
		(fp_line
			(start -0.12065 -0.2794)
			(end -0.12065 -0.3048)
			(stroke
				(width 0.1)
				(type default)
			)
			(layer "B.Fab")
		)
		(fp_line
			(start -0.12065 -0.3048)
			(end -0.67945 -0.3048)
			(stroke
				(width 0.1)
				(type default)
			)
			(layer "B.Fab")
		)
		(fp_line
			(start -0.67945 0.3048)
			(end -0.120396 0.3048)
			(stroke
				(width 0.1)
				(type default)
			)
			(layer "B.Fab")
		)
		(fp_line
			(start -0.67945 -0.3048)
			(end -0.67945 0.3048)
			(stroke
				(width 0.1)
				(type default)
			)
			(layer "B.Fab")
		)
		(pad "1" smd circle
			(at 0.40005 0)
			(size 0 0)
			(layers "B.Cu" "B.Mask" "B.Paste")
			(net "PVDDCR_CPU1_P0")
		)
		(pad "2" smd circle
			(at -0.40005 0)
			(size 0 0)
			(layers "B.Cu" "B.Mask" "B.Paste")
			(net "GND")
		)
	)
	(footprint ""
		(layer "B.Cu")
		(at 28.657804 -388.654036 90)
		(property "Reference" "PC6635_2"
			(at 0 0 90)
			(layer "B.SilkS")
			(hide yes)
			(effects
				(font
					(size 1.27 1.27)
				)
				(justify mirror)
			)
		)
		(property "Value" ""
			(at 0 0 90)
			(layer "B.Fab")
			(effects
				(font
					(size 1.27 1.27)
				)
				(justify mirror)
			)
		)
		(duplicate_pad_numbers_are_jumpers no)
		(fp_line
			(start 1.524 -0.762)
			(end -1.524 -0.762)
			(stroke
				(width 0.1524)
				(type default)
			)
			(layer "B.SilkS")
		)
		(fp_line
			(start -1.524 -0.762)
			(end -1.524 0.762)
			(stroke
				(width 0.1524)
				(type default)
			)
			(layer "B.SilkS")
		)
		(fp_line
			(start 1.524 0.762)
			(end 1.524 -0.762)
			(stroke
				(width 0.1524)
				(type default)
			)
			(layer "B.SilkS")
		)
		(fp_line
			(start -1.524 0.762)
			(end 1.524 0.762)
			(stroke
				(width 0.1524)
				(type default)
			)
			(layer "B.SilkS")
		)
		(fp_line
			(start 1.1049 -0.724916)
			(end 1.1049 0.724916)
			(stroke
				(width 0.1)
				(type default)
			)
			(layer "B.Fab")
		)
		(fp_line
			(start -1.1049 -0.724916)
			(end 1.1049 -0.724916)
			(stroke
				(width 0.1)
				(type default)
			)
			(layer "B.Fab")
		)
		(fp_line
			(start 1.1049 0.724916)
			(end -1.1049 0.724916)
			(stroke
				(width 0.1)
				(type default)
			)
			(layer "B.Fab")
		)
		(fp_line
			(start -1.1049 0.724916)
			(end -1.1049 -0.724916)
			(stroke
				(width 0.1)
				(type default)
			)
			(layer "B.Fab")
		)
		(pad "1" smd rect
			(at 0.889 0 90)
			(size 1.016 1.27)
			(layers "B.Cu" "B.Mask" "B.Paste")
			(net "SW_P12V_AUX_P0V9_RETIMER_CPU1_FLT")
		)
		(pad "2" smd rect
			(at -0.889 0 90)
			(size 1.016 1.27)
			(layers "B.Cu" "B.Mask" "B.Paste")
			(net "GND")
		)
	)
	(footprint ""
		(layer "B.Cu")
		(at 241.938048 -289.533838 -90)
		(property "Reference" "PR6501"
			(at 0 0 90)
			(layer "B.SilkS")
			(hide yes)
			(effects
				(font
					(size 1.27 1.27)
				)
				(justify mirror)
			)
		)
		(property "Value" ""
			(at 0 0 90)
			(layer "B.Fab")
			(effects
				(font
					(size 1.27 1.27)
				)
				(justify mirror)
			)
		)
		(duplicate_pad_numbers_are_jumpers no)
		(fp_line
			(start -0.7874 0.4064)
			(end 0.7874 0.4064)
			(stroke
				(width 0.1524)
				(type default)
			)
			(layer "B.SilkS")
		)
		(fp_line
			(start 0.7874 0.4064)
			(end 0.7874 -0.4064)
			(stroke
				(width 0.1524)
				(type default)
			)
			(layer "B.SilkS")
		)
		(fp_line
			(start -0.7874 -0.4064)
			(end -0.7874 0.4064)
			(stroke
				(width 0.1524)
				(type default)
			)
			(layer "B.SilkS")
		)
		(fp_line
			(start 0.7874 -0.4064)
			(end -0.7874 -0.4064)
			(stroke
				(width 0.1524)
				(type default)
			)
			(layer "B.SilkS")
		)
		(fp_line
			(start -0.67945 0.3048)
			(end -0.120396 0.3048)
			(stroke
				(width 0.1)
				(type default)
			)
			(layer "B.Fab")
		)
		(fp_line
			(start -0.120396 0.3048)
			(end -0.120396 0.2794)
			(stroke
				(width 0.1)
				(type default)
			)
			(layer "B.Fab")
		)
		(fp_line
			(start 0.12065 0.3048)
			(end 0.67945 0.3048)
			(stroke
				(width 0.1)
				(type default)
			)
			(layer "B.Fab")
		)
		(fp_line
			(start 0.67945 0.3048)
			(end 0.67945 -0.305054)
			(stroke
				(width 0.1)
				(type default)
			)
			(layer "B.Fab")
		)
		(fp_line
			(start -0.120396 0.2794)
			(end 0.12065 0.2794)
			(stroke
				(width 0.1)
				(type default)
			)
			(layer "B.Fab")
		)
		(fp_line
			(start 0.12065 0.2794)
			(end 0.12065 0.3048)
			(stroke
				(width 0.1)
				(type default)
			)
			(layer "B.Fab")
		)
		(fp_line
			(start -0.12065 -0.2794)
			(end -0.12065 -0.3048)
			(stroke
				(width 0.1)
				(type default)
			)
			(layer "B.Fab")
		)
		(fp_line
			(start 0.12065 -0.2794)
			(end -0.12065 -0.2794)
			(stroke
				(width 0.1)
				(type default)
			)
			(layer "B.Fab")
		)
		(fp_line
			(start -0.67945 -0.3048)
			(end -0.67945 0.3048)
			(stroke
				(width 0.1)
				(type default)
			)
			(layer "B.Fab")
		)
		(fp_line
			(start -0.12065 -0.3048)
			(end -0.67945 -0.3048)
			(stroke
				(width 0.1)
				(type default)
			)
			(layer "B.Fab")
		)
		(fp_line
			(start 0.12065 -0.305054)
			(end 0.12065 -0.2794)
			(stroke
				(width 0.1)
				(type default)
			)
			(layer "B.Fab")
		)
		(fp_line
			(start 0.67945 -0.305054)
			(end 0.12065 -0.305054)
			(stroke
				(width 0.1)
				(type default)
			)
			(layer "B.Fab")
		)
		(pad "1" smd circle
			(at 0.40005 0 90)
			(size 0 0)
			(layers "B.Cu" "B.Mask" "B.Paste")
			(net "P3V3_AUX")
		)
		(pad "2" smd circle
			(at -0.40005 0 90)
			(size 0 0)
			(layers "B.Cu" "B.Mask" "B.Paste")
			(net "P1V8_RETIMER_CPU0_VCC")
		)
	)
	(footprint ""
		(layer "B.Cu")
		(at 74.478134 -326.232012 -90)
		(property "Reference" "PC395_1"
			(at 0 0 90)
			(layer "B.SilkS")
			(hide yes)
			(effects
				(font
					(size 1.27 1.27)
				)
				(justify mirror)
			)
		)
		(property "Value" ""
			(at 0 0 90)
			(layer "B.Fab")
			(effects
				(font
					(size 1.27 1.27)
				)
				(justify mirror)
			)
		)
		(duplicate_pad_numbers_are_jumpers no)
		(fp_line
			(start -1.524 0.762)
			(end 1.524 0.762)
			(stroke
				(width 0.1524)
				(type default)
			)
			(layer "B.SilkS")
		)
		(fp_line
			(start 1.524 0.762)
			(end 1.524 -0.762)
			(stroke
				(width 0.1524)
				(type default)
			)
			(layer "B.SilkS")
		)
		(fp_line
			(start -1.524 -0.762)
			(end -1.524 0.762)
			(stroke
				(width 0.1524)
				(type default)
			)
			(layer "B.SilkS")
		)
		(fp_line
			(start 1.524 -0.762)
			(end -1.524 -0.762)
			(stroke
				(width 0.1524)
				(type default)
			)
			(layer "B.SilkS")
		)
		(fp_line
			(start -1.1049 0.724916)
			(end -1.1049 -0.724916)
			(stroke
				(width 0.1)
				(type default)
			)
			(layer "B.Fab")
		)
		(fp_line
			(start 1.1049 0.724916)
			(end -1.1049 0.724916)
			(stroke
				(width 0.1)
				(type default)
			)
			(layer "B.Fab")
		)
		(fp_line
			(start -1.1049 -0.724916)
			(end 1.1049 -0.724916)
			(stroke
				(width 0.1)
				(type default)
			)
			(layer "B.Fab")
		)
		(fp_line
			(start 1.1049 -0.724916)
			(end 1.1049 0.724916)
			(stroke
				(width 0.1)
				(type default)
			)
			(layer "B.Fab")
		)
		(pad "1" smd rect
			(at 0.889 0 270)
			(size 1.016 1.27)
			(layers "B.Cu" "B.Mask" "B.Paste")
			(net "PVDDCR_CPU1_P1")
		)
		(pad "2" smd rect
			(at -0.889 0 270)
			(size 1.016 1.27)
			(layers "B.Cu" "B.Mask" "B.Paste")
			(net "GND")
		)
	)
	(footprint ""
		(layer "B.Cu")
		(at 392.961622 -400.19605 180)
		(property "Reference" "C1025"
			(at 0 0 0)
			(layer "B.SilkS")
			(hide yes)
			(effects
				(font
					(size 1.27 1.27)
				)
				(justify mirror)
			)
		)
		(property "Value" ""
			(at 0 0 0)
			(layer "B.Fab")
			(effects
				(font
					(size 1.27 1.27)
				)
				(justify mirror)
			)
		)
		(duplicate_pad_numbers_are_jumpers no)
		(fp_line
			(start 1.524 0.762)
			(end 1.524 -0.762)
			(stroke
				(width 0.1524)
				(type default)
			)
			(layer "B.SilkS")
		)
		(fp_line
			(start 1.524 -0.762)
			(end -1.524 -0.762)
			(stroke
				(width 0.1524)
				(type default)
			)
			(layer "B.SilkS")
		)
		(fp_line
			(start -1.524 0.762)
			(end 1.524 0.762)
			(stroke
				(width 0.1524)
				(type default)
			)
			(layer "B.SilkS")
		)
		(fp_line
			(start -1.524 -0.762)
			(end -1.524 0.762)
			(stroke
				(width 0.1524)
				(type default)
			)
			(layer "B.SilkS")
		)
		(fp_line
			(start 1.1049 0.724916)
			(end -1.1049 0.724916)
			(stroke
				(width 0.1)
				(type default)
			)
			(layer "B.Fab")
		)
		(fp_line
			(start 1.1049 -0.724916)
			(end 1.1049 0.724916)
			(stroke
				(width 0.1)
				(type default)
			)
			(layer "B.Fab")
		)
		(fp_line
			(start -1.1049 0.724916)
			(end -1.1049 -0.724916)
			(stroke
				(width 0.1)
				(type default)
			)
			(layer "B.Fab")
		)
		(fp_line
			(start -1.1049 -0.724916)
			(end 1.1049 -0.724916)
			(stroke
				(width 0.1)
				(type default)
			)
			(layer "B.Fab")
		)
		(pad "1" smd rect
			(at 0.889 0 180)
			(size 1.016 1.27)
			(layers "B.Cu" "B.Mask" "B.Paste")
			(net "P0V9_CPU0_RT3_2A")
		)
		(pad "2" smd rect
			(at -0.889 0 180)
			(size 1.016 1.27)
			(layers "B.Cu" "B.Mask" "B.Paste")
			(net "GND")
		)
	)
	(footprint ""
		(layer "B.Cu")
		(at 206.429356 -382.596136 180)
		(property "Reference" "PR2523"
			(at 0 0 0)
			(layer "B.SilkS")
			(hide yes)
			(effects
				(font
					(size 1.27 1.27)
				)
				(justify mirror)
			)
		)
		(property "Value" ""
			(at 0 0 0)
			(layer "B.Fab")
			(effects
				(font
					(size 1.27 1.27)
				)
				(justify mirror)
			)
		)
		(duplicate_pad_numbers_are_jumpers no)
		(fp_line
			(start 0.7874 0.4064)
			(end 0.7874 -0.4064)
			(stroke
				(width 0.1524)
				(type default)
			)
			(layer "B.SilkS")
		)
		(fp_line
			(start 0.7874 -0.4064)
			(end -0.7874 -0.4064)
			(stroke
				(width 0.1524)
				(type default)
			)
			(layer "B.SilkS")
		)
		(fp_line
			(start -0.7874 0.4064)
			(end 0.7874 0.4064)
			(stroke
				(width 0.1524)
				(type default)
			)
			(layer "B.SilkS")
		)
		(fp_line
			(start -0.7874 -0.4064)
			(end -0.7874 0.4064)
			(stroke
				(width 0.1524)
				(type default)
			)
			(layer "B.SilkS")
		)
		(fp_line
			(start 0.67945 0.3048)
			(end 0.67945 -0.305054)
			(stroke
				(width 0.1)
				(type default)
			)
			(layer "B.Fab")
		)
		(fp_line
			(start 0.67945 -0.305054)
			(end 0.12065 -0.305054)
			(stroke
				(width 0.1)
				(type default)
			)
			(layer "B.Fab")
		)
		(fp_line
			(start 0.12065 0.3048)
			(end 0.67945 0.3048)
			(stroke
				(width 0.1)
				(type default)
			)
			(layer "B.Fab")
		)
		(fp_line
			(start 0.12065 0.2794)
			(end 0.12065 0.3048)
			(stroke
				(width 0.1)
				(type default)
			)
			(layer "B.Fab")
		)
		(fp_line
			(start 0.12065 -0.2794)
			(end -0.12065 -0.2794)
			(stroke
				(width 0.1)
				(type default)
			)
			(layer "B.Fab")
		)
		(fp_line
			(start 0.12065 -0.305054)
			(end 0.12065 -0.2794)
			(stroke
				(width 0.1)
				(type default)
			)
			(layer "B.Fab")
		)
		(fp_line
			(start -0.120396 0.3048)
			(end -0.120396 0.2794)
			(stroke
				(width 0.1)
				(type default)
			)
			(layer "B.Fab")
		)
		(fp_line
			(start -0.120396 0.2794)
			(end 0.12065 0.2794)
			(stroke
				(width 0.1)
				(type default)
			)
			(layer "B.Fab")
		)
		(fp_line
			(start -0.12065 -0.2794)
			(end -0.12065 -0.3048)
			(stroke
				(width 0.1)
				(type default)
			)
			(layer "B.Fab")
		)
		(fp_line
			(start -0.12065 -0.3048)
			(end -0.67945 -0.3048)
			(stroke
				(width 0.1)
				(type default)
			)
			(layer "B.Fab")
		)
		(fp_line
			(start -0.67945 0.3048)
			(end -0.120396 0.3048)
			(stroke
				(width 0.1)
				(type default)
			)
			(layer "B.Fab")
		)
		(fp_line
			(start -0.67945 -0.3048)
			(end -0.67945 0.3048)
			(stroke
				(width 0.1)
				(type default)
			)
			(layer "B.Fab")
		)
		(pad "1" smd circle
			(at 0.40005 0)
			(size 0 0)
			(layers "B.Cu" "B.Mask" "B.Paste")
			(net "P12V_HSC_SENSE2_P")
		)
		(pad "2" smd circle
			(at -0.40005 0)
			(size 0 0)
			(layers "B.Cu" "B.Mask" "B.Paste")
			(net "P12V_HSC_SENSE2_R4_P")
		)
	)
	(footprint ""
		(layer "B.Cu")
		(at 373.075454 -264.35431)
		(property "Reference" "C2628"
			(at 0 0 0)
			(layer "B.SilkS")
			(hide yes)
			(effects
				(font
					(size 1.27 1.27)
				)
				(justify mirror)
			)
		)
		(property "Value" ""
			(at 0 0 0)
			(layer "B.Fab")
			(effects
				(font
					(size 1.27 1.27)
				)
				(justify mirror)
			)
		)
		(duplicate_pad_numbers_are_jumpers no)
		(fp_line
			(start -0.7874 -0.4064)
			(end -0.7874 0.4064)
			(stroke
				(width 0.1524)
				(type default)
			)
			(layer "B.SilkS")
		)
		(fp_line
			(start -0.7874 0.4064)
			(end 0.7874 0.4064)
			(stroke
				(width 0.1524)
				(type default)
			)
			(layer "B.SilkS")
		)
		(fp_line
			(start 0.7874 -0.4064)
			(end -0.7874 -0.4064)
			(stroke
				(width 0.1524)
				(type default)
			)
			(layer "B.SilkS")
		)
		(fp_line
			(start 0.7874 0.4064)
			(end 0.7874 -0.4064)
			(stroke
				(width 0.1524)
				(type default)
			)
			(layer "B.SilkS")
		)
		(fp_line
			(start -0.67945 -0.3048)
			(end -0.67945 0.3048)
			(stroke
				(width 0.1)
				(type default)
			)
			(layer "B.Fab")
		)
		(fp_line
			(start -0.67945 0.3048)
			(end -0.120396 0.3048)
			(stroke
				(width 0.1)
				(type default)
			)
			(layer "B.Fab")
		)
		(fp_line
			(start -0.12065 -0.3048)
			(end -0.67945 -0.3048)
			(stroke
				(width 0.1)
				(type default)
			)
			(layer "B.Fab")
		)
		(fp_line
			(start -0.12065 -0.2794)
			(end -0.12065 -0.3048)
			(stroke
				(width 0.1)
				(type default)
			)
			(layer "B.Fab")
		)
		(fp_line
			(start -0.120396 0.2794)
			(end 0.12065 0.2794)
			(stroke
				(width 0.1)
				(type default)
			)
			(layer "B.Fab")
		)
		(fp_line
			(start -0.120396 0.3048)
			(end -0.120396 0.2794)
			(stroke
				(width 0.1)
				(type default)
			)
			(layer "B.Fab")
		)
		(fp_line
			(start 0.12065 -0.305054)
			(end 0.12065 -0.2794)
			(stroke
				(width 0.1)
				(type default)
			)
			(layer "B.Fab")
		)
		(fp_line
			(start 0.12065 -0.2794)
			(end -0.12065 -0.2794)
			(stroke
				(width 0.1)
				(type default)
			)
			(layer "B.Fab")
		)
		(fp_line
			(start 0.12065 0.2794)
			(end 0.12065 0.3048)
			(stroke
				(width 0.1)
				(type default)
			)
			(layer "B.Fab")
		)
		(fp_line
			(start 0.12065 0.3048)
			(end 0.67945 0.3048)
			(stroke
				(width 0.1)
				(type default)
			)
			(layer "B.Fab")
		)
		(fp_line
			(start 0.67945 -0.305054)
			(end 0.12065 -0.305054)
			(stroke
				(width 0.1)
				(type default)
			)
			(layer "B.Fab")
		)
		(fp_line
			(start 0.67945 0.3048)
			(end 0.67945 -0.305054)
			(stroke
				(width 0.1)
				(type default)
			)
			(layer "B.Fab")
		)
		(pad "1" smd circle
			(at 0.40005 0 180)
			(size 0 0)
			(layers "B.Cu" "B.Mask" "B.Paste")
			(net "PVDD11_S3_P0")
		)
		(pad "2" smd circle
			(at -0.40005 0 180)
			(size 0 0)
			(layers "B.Cu" "B.Mask" "B.Paste")
			(net "GND")
		)
	)
	(footprint ""
		(layer "B.Cu")
		(at 159.615632 -193.949066 -90)
		(property "Reference" "R990"
			(at 0 0 90)
			(layer "B.SilkS")
			(hide yes)
			(effects
				(font
					(size 1.27 1.27)
				)
				(justify mirror)
			)
		)
		(property "Value" ""
			(at 0 0 90)
			(layer "B.Fab")
			(effects
				(font
					(size 1.27 1.27)
				)
				(justify mirror)
			)
		)
		(duplicate_pad_numbers_are_jumpers no)
		(fp_line
			(start -0.7874 0.4064)
			(end 0.7874 0.4064)
			(stroke
				(width 0.1524)
				(type default)
			)
			(layer "B.SilkS")
		)
		(fp_line
			(start 0.7874 0.4064)
			(end 0.7874 -0.4064)
			(stroke
				(width 0.1524)
				(type default)
			)
			(layer "B.SilkS")
		)
		(fp_line
			(start -0.7874 -0.4064)
			(end -0.7874 0.4064)
			(stroke
				(width 0.1524)
				(type default)
			)
			(layer "B.SilkS")
		)
		(fp_line
			(start 0.7874 -0.4064)
			(end -0.7874 -0.4064)
			(stroke
				(width 0.1524)
				(type default)
			)
			(layer "B.SilkS")
		)
		(fp_line
			(start -0.67945 0.3048)
			(end -0.120396 0.3048)
			(stroke
				(width 0.1)
				(type default)
			)
			(layer "B.Fab")
		)
		(fp_line
			(start -0.120396 0.3048)
			(end -0.120396 0.2794)
			(stroke
				(width 0.1)
				(type default)
			)
			(layer "B.Fab")
		)
		(fp_line
			(start 0.12065 0.3048)
			(end 0.67945 0.3048)
			(stroke
				(width 0.1)
				(type default)
			)
			(layer "B.Fab")
		)
		(fp_line
			(start 0.67945 0.3048)
			(end 0.67945 -0.305054)
			(stroke
				(width 0.1)
				(type default)
			)
			(layer "B.Fab")
		)
		(fp_line
			(start -0.120396 0.2794)
			(end 0.12065 0.2794)
			(stroke
				(width 0.1)
				(type default)
			)
			(layer "B.Fab")
		)
		(fp_line
			(start 0.12065 0.2794)
			(end 0.12065 0.3048)
			(stroke
				(width 0.1)
				(type default)
			)
			(layer "B.Fab")
		)
		(fp_line
			(start -0.12065 -0.2794)
			(end -0.12065 -0.3048)
			(stroke
				(width 0.1)
				(type default)
			)
			(layer "B.Fab")
		)
		(fp_line
			(start 0.12065 -0.2794)
			(end -0.12065 -0.2794)
			(stroke
				(width 0.1)
				(type default)
			)
			(layer "B.Fab")
		)
		(fp_line
			(start -0.67945 -0.3048)
			(end -0.67945 0.3048)
			(stroke
				(width 0.1)
				(type default)
			)
			(layer "B.Fab")
		)
		(fp_line
			(start -0.12065 -0.3048)
			(end -0.67945 -0.3048)
			(stroke
				(width 0.1)
				(type default)
			)
			(layer "B.Fab")
		)
		(fp_line
			(start 0.12065 -0.305054)
			(end 0.12065 -0.2794)
			(stroke
				(width 0.1)
				(type default)
			)
			(layer "B.Fab")
		)
		(fp_line
			(start 0.67945 -0.305054)
			(end 0.12065 -0.305054)
			(stroke
				(width 0.1)
				(type default)
			)
			(layer "B.Fab")
		)
		(pad "1" smd rect
			(at 0.40005 0 270)
			(size 0.4572 0.508)
			(layers "B.Cu" "B.Mask" "B.Paste")
			(net "I3C_1_SPD_DDRGL_CPU1_R_SCL")
		)
		(pad "2" smd rect
			(at -0.40005 0 270)
			(size 0.4572 0.508)
			(layers "B.Cu" "B.Mask" "B.Paste")
			(net "I3C_SPD_DDRGL_CPU1_BYPASS_SCL")
		)
	)
	(footprint ""
		(layer "B.Cu")
		(at 110.149386 -246.447564 -120)
		(property "Reference" "C2340"
			(at 0 0 60)
			(layer "B.SilkS")
			(hide yes)
			(effects
				(font
					(size 1.27 1.27)
				)
				(justify mirror)
			)
		)
		(property "Value" ""
			(at 0 0 60)
			(layer "B.Fab")
			(effects
				(font
					(size 1.27 1.27)
				)
				(justify mirror)
			)
		)
		(duplicate_pad_numbers_are_jumpers no)
		(fp_line
			(start 0.787516 0.406438)
			(end 0.787425 -0.40652)
			(stroke
				(width 0.1524)
				(type default)
			)
			(layer "B.SilkS")
		)
		(fp_line
			(start 0.787425 -0.40652)
			(end -0.787516 -0.406438)
			(stroke
				(width 0.1524)
				(type default)
			)
			(layer "B.SilkS")
		)
		(fp_line
			(start -0.787425 0.40652)
			(end 0.787516 0.406438)
			(stroke
				(width 0.1524)
				(type default)
			)
			(layer "B.SilkS")
		)
		(fp_line
			(start -0.787516 -0.406438)
			(end -0.787425 0.40652)
			(stroke
				(width 0.1524)
				(type default)
			)
			(layer "B.SilkS")
		)
		(fp_line
			(start 0.679568 0.304811)
			(end 0.679373 -0.305128)
			(stroke
				(width 0.1)
				(type default)
			)
			(layer "B.Fab")
		)
		(fp_line
			(start 0.120605 0.304905)
			(end 0.679568 0.304811)
			(stroke
				(width 0.1)
				(type default)
			)
			(layer "B.Fab")
		)
		(fp_line
			(start 0.120554 0.279418)
			(end 0.120605 0.304905)
			(stroke
				(width 0.1)
				(type default)
			)
			(layer "B.Fab")
		)
		(fp_line
			(start -0.120316 0.304686)
			(end -0.12024 0.279419)
			(stroke
				(width 0.1)
				(type default)
			)
			(layer "B.Fab")
		)
		(fp_line
			(start -0.12024 0.279419)
			(end 0.120554 0.279418)
			(stroke
				(width 0.1)
				(type default)
			)
			(layer "B.Fab")
		)
		(fp_line
			(start 0.679373 -0.305128)
			(end 0.120629 -0.30516)
			(stroke
				(width 0.1)
				(type default)
			)
			(layer "B.Fab")
		)
		(fp_line
			(start -0.6795 0.304908)
			(end -0.120316 0.304686)
			(stroke
				(width 0.1)
				(type default)
			)
			(layer "B.Fab")
		)
		(fp_line
			(start 0.120587 -0.279326)
			(end -0.120554 -0.279418)
			(stroke
				(width 0.1)
				(type default)
			)
			(layer "B.Fab")
		)
		(fp_line
			(start 0.120629 -0.30516)
			(end 0.120587 -0.279326)
			(stroke
				(width 0.1)
				(type default)
			)
			(layer "B.Fab")
		)
		(fp_line
			(start -0.120554 -0.279418)
			(end -0.120605 -0.304905)
			(stroke
				(width 0.1)
				(type default)
			)
			(layer "B.Fab")
		)
		(fp_line
			(start -0.120605 -0.304905)
			(end -0.679568 -0.304811)
			(stroke
				(width 0.1)
				(type default)
			)
			(layer "B.Fab")
		)
		(fp_line
			(start -0.679568 -0.304811)
			(end -0.6795 0.304908)
			(stroke
				(width 0.1)
				(type default)
			)
			(layer "B.Fab")
		)
		(pad "1" smd circle
			(at 0.40005 0 60)
			(size 0 0)
			(layers "B.Cu" "B.Mask" "B.Paste")
			(net "PVDDCR_CPU0_P1")
		)
		(pad "2" smd circle
			(at -0.40005 0 60)
			(size 0 0)
			(layers "B.Cu" "B.Mask" "B.Paste")
			(net "GND")
		)
	)
	(footprint ""
		(layer "B.Cu")
		(at 238.740442 -223.10217 90)
		(property "Reference" "U5"
			(at -1.79324 -2.775458 270)
			(unlocked yes)
			(layer "B.SilkS")
			(effects
				(font
					(size 0.7874 0.5842)
					(thickness 0.1524)
				)
				(justify left mirror)
			)
		)
		(property "Value" ""
			(at 0 0 90)
			(layer "B.Fab")
			(effects
				(font
					(size 1.27 1.27)
				)
				(justify mirror)
			)
		)
		(duplicate_pad_numbers_are_jumpers no)
		(fp_line
			(start 1.463548 -1.549908)
			(end 0.787908 -1.549908)
			(stroke
				(width 0.1524)
				(type default)
			)
			(layer "B.SilkS")
		)
		(fp_line
			(start 0.787908 -1.549908)
			(end 0 -0.762)
			(stroke
				(width 0.1524)
				(type default)
			)
			(layer "B.SilkS")
		)
		(fp_line
			(start -0.762 -1.549908)
			(end -1.463548 -1.549908)
			(stroke
				(width 0.1524)
				(type default)
			)
			(layer "B.SilkS")
		)
		(fp_line
			(start -1.463548 -1.549908)
			(end -1.463548 1.549908)
			(stroke
				(width 0.1524)
				(type default)
			)
			(layer "B.SilkS")
		)
		(fp_line
			(start 0 -0.762)
			(end -0.762 -1.549908)
			(stroke
				(width 0.1524)
				(type default)
			)
			(layer "B.SilkS")
		)
		(fp_line
			(start 1.463548 1.549908)
			(end 1.463548 -1.549908)
			(stroke
				(width 0.1524)
				(type default)
			)
			(layer "B.SilkS")
		)
		(fp_line
			(start -1.463548 1.549908)
			(end 1.463548 1.549908)
			(stroke
				(width 0.1524)
				(type default)
			)
			(layer "B.SilkS")
		)
		(fp_poly
			(pts
				(xy 3.314446 -0.304292) (xy 3.581908 -0.863346) (xy 2.888996 -0.851154)
			)
			(stroke
				(width 0)
				(type default)
			)
			(fill yes)
			(layer "B.SilkS")
		)
		(fp_line
			(start 1.549908 -1.549908)
			(end -1.549908 -1.549908)
			(stroke
				(width 0.1)
				(type default)
			)
			(layer "B.Fab")
		)
		(fp_line
			(start -1.549908 -1.549908)
			(end -1.549908 1.549908)
			(stroke
				(width 0.1)
				(type default)
			)
			(layer "B.Fab")
		)
		(fp_line
			(start 1.549908 1.549908)
			(end 1.549908 -1.549908)
			(stroke
				(width 0.1)
				(type default)
			)
			(layer "B.Fab")
		)
		(fp_line
			(start -1.549908 1.549908)
			(end 1.549908 1.549908)
			(stroke
				(width 0.1)
				(type default)
			)
			(layer "B.Fab")
		)
		(fp_poly
			(pts
				(xy 3.4798 -1.359916) (xy 2.86004 -1.050036) (xy 3.4798 -0.740156)
			)
			(stroke
				(width 0)
				(type default)
			)
			(fill yes)
			(layer "B.Fab")
		)
		(pad "1" smd rect
			(at 2.175002 -1.050036 180)
			(size 0.6096 1.1684)
			(layers "B.Cu" "B.Mask" "B.Paste")
			(net "P3V3_AUX")
		)
		(pad "2" smd rect
			(at 2.175002 -0.32512 180)
			(size 0.4318 1.1684)
			(layers "B.Cu" "B.Mask" "B.Paste")
			(net "SMB_CPU0_CPU1_APML_BUF1_SCL")
		)
		(pad "3" smd rect
			(at 2.175002 0.32512 180)
			(size 0.4318 1.1684)
			(layers "B.Cu" "B.Mask" "B.Paste")
			(net "SMB_CPU0_CPU1_APML_BUF1_SDA")
		)
		(pad "4" smd rect
			(at 2.175002 1.050036 180)
			(size 0.6096 1.1684)
			(layers "B.Cu" "B.Mask" "B.Paste")
			(net "GND")
		)
		(pad "5" smd rect
			(at -2.175002 1.050036 180)
			(size 0.6096 1.1684)
			(layers "B.Cu" "B.Mask" "B.Paste")
			(net "PU_U5_EN")
		)
		(pad "6" smd rect
			(at -2.175002 0.32512 180)
			(size 0.4318 1.1684)
			(layers "B.Cu" "B.Mask" "B.Paste")
			(net "SMB_CPU0_CPU1_APML_BUF1_SDA_R1")
		)
		(pad "7" smd rect
			(at -2.175002 -0.32512 180)
			(size 0.4318 1.1684)
			(layers "B.Cu" "B.Mask" "B.Paste")
			(net "SMB_CPU0_CPU1_APML_BUF1_SCL_R1")
		)
		(pad "8" smd rect
			(at -2.175002 -1.050036 180)
			(size 0.6096 1.1684)
			(layers "B.Cu" "B.Mask" "B.Paste")
			(net "P3V3")
		)
	)
	(footprint ""
		(layer "B.Cu")
		(at 324.336664 -73.534778)
		(property "Reference" "Q79"
			(at 1.4224 -1.768348 0)
			(unlocked yes)
			(layer "B.SilkS")
			(effects
				(font
					(size 0.7874 0.5842)
					(thickness 0.1524)
				)
				(justify left mirror)
			)
		)
		(property "Value" ""
			(at 0 0 0)
			(layer "B.Fab")
			(effects
				(font
					(size 1.27 1.27)
				)
				(justify mirror)
			)
		)
		(duplicate_pad_numbers_are_jumpers no)
		(fp_line
			(start -1.332738 -1.100074)
			(end -1.332738 1.100074)
			(stroke
				(width 0.1524)
				(type default)
			)
			(layer "B.SilkS")
		)
		(fp_line
			(start -1.332738 1.100074)
			(end 1.332738 1.100074)
			(stroke
				(width 0.1524)
				(type default)
			)
			(layer "B.SilkS")
		)
		(fp_line
			(start -0.4826 -1.100074)
			(end -1.332738 -1.100074)
			(stroke
				(width 0.1524)
				(type default)
			)
			(layer "B.SilkS")
		)
		(fp_line
			(start 0 -0.541274)
			(end -0.4826 -1.100074)
			(stroke
				(width 0.1524)
				(type default)
			)
			(layer "B.SilkS")
		)
		(fp_line
			(start 0.4826 -1.100074)
			(end 0 -0.541274)
			(stroke
				(width 0.1524)
				(type default)
			)
			(layer "B.SilkS")
		)
		(fp_line
			(start 1.332738 -1.100074)
			(end 0.4826 -1.100074)
			(stroke
				(width 0.1524)
				(type default)
			)
			(layer "B.SilkS")
		)
		(fp_line
			(start 1.332738 1.100074)
			(end 1.332738 -1.100074)
			(stroke
				(width 0.1524)
				(type default)
			)
			(layer "B.SilkS")
		)
		(fp_poly
			(pts
				(xy 1.334516 -0.649986) (xy 2.036572 -1.001014) (xy 2.036572 -0.298958)
			)
			(stroke
				(width 0)
				(type default)
			)
			(fill yes)
			(layer "B.SilkS")
		)
		(fp_line
			(start -0.674878 -1.100074)
			(end -0.674878 1.100074)
			(stroke
				(width 0.1)
				(type default)
			)
			(layer "B.Fab")
		)
		(fp_line
			(start -0.674878 1.100074)
			(end 0.674878 1.100074)
			(stroke
				(width 0.1)
				(type default)
			)
			(layer "B.Fab")
		)
		(fp_line
			(start 0.674878 -1.100074)
			(end -0.674878 -1.100074)
			(stroke
				(width 0.1)
				(type default)
			)
			(layer "B.Fab")
		)
		(fp_line
			(start 0.674878 1.100074)
			(end 0.674878 -1.100074)
			(stroke
				(width 0.1)
				(type default)
			)
			(layer "B.Fab")
		)
		(fp_poly
			(pts
				(xy 2.2352 -0.298958) (xy 2.2352 -1.001014) (xy 1.533144 -0.649986)
			)
			(stroke
				(width 0)
				(type default)
			)
			(fill yes)
			(layer "B.Fab")
		)
		(pad "1" smd rect
			(at 0.94996 -0.649986 90)
			(size 0.4318 0.508)
			(layers "B.Cu" "B.Mask" "B.Paste")
			(net "GND")
		)
		(pad "2" smd rect
			(at 0.94996 0 90)
			(size 0.4318 0.508)
			(layers "B.Cu" "B.Mask" "B.Paste")
			(net "FM_LED_PWRGD_PVDD33_S5")
		)
		(pad "3" smd rect
			(at 0.94996 0.649986 90)
			(size 0.4318 0.508)
			(layers "B.Cu" "B.Mask" "B.Paste")
			(net "LED_PWRGD_PVDDCR_CPU0_P0_D")
		)
		(pad "4" smd rect
			(at -0.94996 0.649986 90)
			(size 0.4318 0.508)
			(layers "B.Cu" "B.Mask" "B.Paste")
			(net "GND")
		)
		(pad "5" smd rect
			(at -0.94996 0 90)
			(size 0.4318 0.508)
			(layers "B.Cu" "B.Mask" "B.Paste")
			(net "FM_LED_PWRGD_PVDDCR_CPU0_P0")
		)
		(pad "6" smd rect
			(at -0.94996 -0.649986 90)
			(size 0.4318 0.508)
			(layers "B.Cu" "B.Mask" "B.Paste")
			(net "LED_PWRGD_PVDD33_S5_D")
		)
	)
	(footprint ""
		(layer "B.Cu")
		(at 50.978562 -386.766562 90)
		(property "Reference" "C265"
			(at 0 0 90)
			(layer "B.SilkS")
			(hide yes)
			(effects
				(font
					(size 1.27 1.27)
				)
				(justify mirror)
			)
		)
		(property "Value" ""
			(at 0 0 90)
			(layer "B.Fab")
			(effects
				(font
					(size 1.27 1.27)
				)
				(justify mirror)
			)
		)
		(duplicate_pad_numbers_are_jumpers no)
		(fp_line
			(start 0.299974 -0.150114)
			(end -0.299974 -0.150114)
			(stroke
				(width 0.1)
				(type default)
			)
			(layer "B.Fab")
		)
		(fp_line
			(start -0.299974 -0.150114)
			(end -0.299974 0.150114)
			(stroke
				(width 0.1)
				(type default)
			)
			(layer "B.Fab")
		)
		(fp_line
			(start 0.299974 0.150114)
			(end 0.299974 -0.150114)
			(stroke
				(width 0.1)
				(type default)
			)
			(layer "B.Fab")
		)
		(fp_line
			(start -0.299974 0.150114)
			(end 0.299974 0.150114)
			(stroke
				(width 0.1)
				(type default)
			)
			(layer "B.Fab")
		)
		(pad "1" smd rect
			(at 0.2667 0 270)
			(size 0.3048 0.381)
			(layers "B.Cu" "B.Mask" "B.Paste")
			(net "P0V9_CPU1_RT0_2A")
		)
		(pad "2" smd rect
			(at -0.2667 0 270)
			(size 0.3048 0.381)
			(layers "B.Cu" "B.Mask" "B.Paste")
			(net "GND")
		)
	)
	(footprint ""
		(layer "B.Cu")
		(at 409.006294 -395.148562 90)
		(property "Reference" "C780"
			(at 0 0 90)
			(layer "B.SilkS")
			(hide yes)
			(effects
				(font
					(size 1.27 1.27)
				)
				(justify mirror)
			)
		)
		(property "Value" ""
			(at 0 0 90)
			(layer "B.Fab")
			(effects
				(font
					(size 1.27 1.27)
				)
				(justify mirror)
			)
		)
		(duplicate_pad_numbers_are_jumpers no)
		(fp_line
			(start 0.299974 -0.150114)
			(end -0.299974 -0.150114)
			(stroke
				(width 0.1)
				(type default)
			)
			(layer "B.Fab")
		)
		(fp_line
			(start -0.299974 -0.150114)
			(end -0.299974 0.150114)
			(stroke
				(width 0.1)
				(type default)
			)
			(layer "B.Fab")
		)
		(fp_line
			(start 0.299974 0.150114)
			(end 0.299974 -0.150114)
			(stroke
				(width 0.1)
				(type default)
			)
			(layer "B.Fab")
		)
		(fp_line
			(start -0.299974 0.150114)
			(end 0.299974 0.150114)
			(stroke
				(width 0.1)
				(type default)
			)
			(layer "B.Fab")
		)
		(pad "1" smd rect
			(at 0.2667 0 270)
			(size 0.3048 0.381)
			(layers "B.Cu" "B.Mask" "B.Paste")
			(net "P0V9_CPU0_RT_2D")
		)
		(pad "2" smd rect
			(at -0.2667 0 270)
			(size 0.3048 0.381)
			(layers "B.Cu" "B.Mask" "B.Paste")
			(net "GND")
		)
	)
	(footprint ""
		(layer "B.Cu")
		(at 409.159202 -416.899344 90)
		(property "Reference" "C6622"
			(at 0 0 90)
			(layer "B.SilkS")
			(hide yes)
			(effects
				(font
					(size 1.27 1.27)
				)
				(justify mirror)
			)
		)
		(property "Value" ""
			(at 0 0 90)
			(layer "B.Fab")
			(effects
				(font
					(size 1.27 1.27)
				)
				(justify mirror)
			)
		)
		(duplicate_pad_numbers_are_jumpers no)
		(fp_line
			(start 0.299974 -0.150114)
			(end -0.299974 -0.150114)
			(stroke
				(width 0.1)
				(type default)
			)
			(layer "B.Fab")
		)
		(fp_line
			(start -0.299974 -0.150114)
			(end -0.299974 0.150114)
			(stroke
				(width 0.1)
				(type default)
			)
			(layer "B.Fab")
		)
		(fp_line
			(start 0.299974 0.150114)
			(end 0.299974 -0.150114)
			(stroke
				(width 0.1)
				(type default)
			)
			(layer "B.Fab")
		)
		(fp_line
			(start -0.299974 0.150114)
			(end 0.299974 0.150114)
			(stroke
				(width 0.1)
				(type default)
			)
			(layer "B.Fab")
		)
		(pad "1" smd rect
			(at 0.2667 0 270)
			(size 0.3048 0.381)
			(layers "B.Cu" "B.Mask" "B.Paste")
			(net "P5E_CPU0_P3_TX_BUF_C_DN<12>")
		)
		(pad "2" smd rect
			(at -0.2667 0 270)
			(size 0.3048 0.381)
			(layers "B.Cu" "B.Mask" "B.Paste")
			(net "P5E_CPU0_P3_TX_BUF_DN<12>")
		)
	)
	(footprint ""
		(layer "B.Cu")
		(at 361.973114 -267.52931)
		(property "Reference" "C2202"
			(at 0 0 0)
			(layer "B.SilkS")
			(hide yes)
			(effects
				(font
					(size 1.27 1.27)
				)
				(justify mirror)
			)
		)
		(property "Value" ""
			(at 0 0 0)
			(layer "B.Fab")
			(effects
				(font
					(size 1.27 1.27)
				)
				(justify mirror)
			)
		)
		(duplicate_pad_numbers_are_jumpers no)
		(fp_line
			(start -0.7874 -0.4064)
			(end -0.7874 0.4064)
			(stroke
				(width 0.1524)
				(type default)
			)
			(layer "B.SilkS")
		)
		(fp_line
			(start -0.7874 0.4064)
			(end 0.7874 0.4064)
			(stroke
				(width 0.1524)
				(type default)
			)
			(layer "B.SilkS")
		)
		(fp_line
			(start 0.7874 -0.4064)
			(end -0.7874 -0.4064)
			(stroke
				(width 0.1524)
				(type default)
			)
			(layer "B.SilkS")
		)
		(fp_line
			(start 0.7874 0.4064)
			(end 0.7874 -0.4064)
			(stroke
				(width 0.1524)
				(type default)
			)
			(layer "B.SilkS")
		)
		(fp_line
			(start -0.67945 -0.3048)
			(end -0.67945 0.3048)
			(stroke
				(width 0.1)
				(type default)
			)
			(layer "B.Fab")
		)
		(fp_line
			(start -0.67945 0.3048)
			(end -0.120396 0.3048)
			(stroke
				(width 0.1)
				(type default)
			)
			(layer "B.Fab")
		)
		(fp_line
			(start -0.12065 -0.3048)
			(end -0.67945 -0.3048)
			(stroke
				(width 0.1)
				(type default)
			)
			(layer "B.Fab")
		)
		(fp_line
			(start -0.12065 -0.2794)
			(end -0.12065 -0.3048)
			(stroke
				(width 0.1)
				(type default)
			)
			(layer "B.Fab")
		)
		(fp_line
			(start -0.120396 0.2794)
			(end 0.12065 0.2794)
			(stroke
				(width 0.1)
				(type default)
			)
			(layer "B.Fab")
		)
		(fp_line
			(start -0.120396 0.3048)
			(end -0.120396 0.2794)
			(stroke
				(width 0.1)
				(type default)
			)
			(layer "B.Fab")
		)
		(fp_line
			(start 0.12065 -0.305054)
			(end 0.12065 -0.2794)
			(stroke
				(width 0.1)
				(type default)
			)
			(layer "B.Fab")
		)
		(fp_line
			(start 0.12065 -0.2794)
			(end -0.12065 -0.2794)
			(stroke
				(width 0.1)
				(type default)
			)
			(layer "B.Fab")
		)
		(fp_line
			(start 0.12065 0.2794)
			(end 0.12065 0.3048)
			(stroke
				(width 0.1)
				(type default)
			)
			(layer "B.Fab")
		)
		(fp_line
			(start 0.12065 0.3048)
			(end 0.67945 0.3048)
			(stroke
				(width 0.1)
				(type default)
			)
			(layer "B.Fab")
		)
		(fp_line
			(start 0.67945 -0.305054)
			(end 0.12065 -0.305054)
			(stroke
				(width 0.1)
				(type default)
			)
			(layer "B.Fab")
		)
		(fp_line
			(start 0.67945 0.3048)
			(end 0.67945 -0.305054)
			(stroke
				(width 0.1)
				(type default)
			)
			(layer "B.Fab")
		)
		(pad "1" smd circle
			(at 0.40005 0 180)
			(size 0 0)
			(layers "B.Cu" "B.Mask" "B.Paste")
			(net "PVDDCR_CPU1_P0")
		)
		(pad "2" smd circle
			(at -0.40005 0 180)
			(size 0 0)
			(layers "B.Cu" "B.Mask" "B.Paste")
			(net "GND")
		)
	)
	(footprint ""
		(layer "B.Cu")
		(at 234.830874 -326.947022 180)
		(property "Reference" "R1224"
			(at 0 0 0)
			(layer "B.SilkS")
			(hide yes)
			(effects
				(font
					(size 1.27 1.27)
				)
				(justify mirror)
			)
		)
		(property "Value" ""
			(at 0 0 0)
			(layer "B.Fab")
			(effects
				(font
					(size 1.27 1.27)
				)
				(justify mirror)
			)
		)
		(duplicate_pad_numbers_are_jumpers no)
		(fp_line
			(start 0.7874 0.4064)
			(end 0.7874 -0.4064)
			(stroke
				(width 0.1524)
				(type default)
			)
			(layer "B.SilkS")
		)
		(fp_line
			(start 0.7874 -0.4064)
			(end -0.7874 -0.4064)
			(stroke
				(width 0.1524)
				(type default)
			)
			(layer "B.SilkS")
		)
		(fp_line
			(start -0.7874 0.4064)
			(end 0.7874 0.4064)
			(stroke
				(width 0.1524)
				(type default)
			)
			(layer "B.SilkS")
		)
		(fp_line
			(start -0.7874 -0.4064)
			(end -0.7874 0.4064)
			(stroke
				(width 0.1524)
				(type default)
			)
			(layer "B.SilkS")
		)
		(fp_line
			(start 0.67945 0.3048)
			(end 0.67945 -0.305054)
			(stroke
				(width 0.1)
				(type default)
			)
			(layer "B.Fab")
		)
		(fp_line
			(start 0.67945 -0.305054)
			(end 0.12065 -0.305054)
			(stroke
				(width 0.1)
				(type default)
			)
			(layer "B.Fab")
		)
		(fp_line
			(start 0.12065 0.3048)
			(end 0.67945 0.3048)
			(stroke
				(width 0.1)
				(type default)
			)
			(layer "B.Fab")
		)
		(fp_line
			(start 0.12065 0.2794)
			(end 0.12065 0.3048)
			(stroke
				(width 0.1)
				(type default)
			)
			(layer "B.Fab")
		)
		(fp_line
			(start 0.12065 -0.2794)
			(end -0.12065 -0.2794)
			(stroke
				(width 0.1)
				(type default)
			)
			(layer "B.Fab")
		)
		(fp_line
			(start 0.12065 -0.305054)
			(end 0.12065 -0.2794)
			(stroke
				(width 0.1)
				(type default)
			)
			(layer "B.Fab")
		)
		(fp_line
			(start -0.120396 0.3048)
			(end -0.120396 0.2794)
			(stroke
				(width 0.1)
				(type default)
			)
			(layer "B.Fab")
		)
		(fp_line
			(start -0.120396 0.2794)
			(end 0.12065 0.2794)
			(stroke
				(width 0.1)
				(type default)
			)
			(layer "B.Fab")
		)
		(fp_line
			(start -0.12065 -0.2794)
			(end -0.12065 -0.3048)
			(stroke
				(width 0.1)
				(type default)
			)
			(layer "B.Fab")
		)
		(fp_line
			(start -0.12065 -0.3048)
			(end -0.67945 -0.3048)
			(stroke
				(width 0.1)
				(type default)
			)
			(layer "B.Fab")
		)
		(fp_line
			(start -0.67945 0.3048)
			(end -0.120396 0.3048)
			(stroke
				(width 0.1)
				(type default)
			)
			(layer "B.Fab")
		)
		(fp_line
			(start -0.67945 -0.3048)
			(end -0.67945 0.3048)
			(stroke
				(width 0.1)
				(type default)
			)
			(layer "B.Fab")
		)
		(pad "1" smd circle
			(at 0.40005 0)
			(size 0 0)
			(layers "B.Cu" "B.Mask" "B.Paste")
			(net "PVDD_33_S5_ADC")
		)
		(pad "2" smd circle
			(at -0.40005 0)
			(size 0 0)
			(layers "B.Cu" "B.Mask" "B.Paste")
			(net "GND")
		)
	)
	(footprint ""
		(layer "B.Cu")
		(at 94.30639 -386.766562 90)
		(property "Reference" "C314"
			(at 0 0 90)
			(layer "B.SilkS")
			(hide yes)
			(effects
				(font
					(size 1.27 1.27)
				)
				(justify mirror)
			)
		)
		(property "Value" ""
			(at 0 0 90)
			(layer "B.Fab")
			(effects
				(font
					(size 1.27 1.27)
				)
				(justify mirror)
			)
		)
		(duplicate_pad_numbers_are_jumpers no)
		(fp_line
			(start 0.299974 -0.150114)
			(end -0.299974 -0.150114)
			(stroke
				(width 0.1)
				(type default)
			)
			(layer "B.Fab")
		)
		(fp_line
			(start -0.299974 -0.150114)
			(end -0.299974 0.150114)
			(stroke
				(width 0.1)
				(type default)
			)
			(layer "B.Fab")
		)
		(fp_line
			(start 0.299974 0.150114)
			(end 0.299974 -0.150114)
			(stroke
				(width 0.1)
				(type default)
			)
			(layer "B.Fab")
		)
		(fp_line
			(start -0.299974 0.150114)
			(end 0.299974 0.150114)
			(stroke
				(width 0.1)
				(type default)
			)
			(layer "B.Fab")
		)
		(pad "1" smd rect
			(at 0.2667 0 270)
			(size 0.3048 0.381)
			(layers "B.Cu" "B.Mask" "B.Paste")
			(net "P0V9_CPU1_RT1_2A")
		)
		(pad "2" smd rect
			(at -0.2667 0 270)
			(size 0.3048 0.381)
			(layers "B.Cu" "B.Mask" "B.Paste")
			(net "GND")
		)
	)
	(footprint ""
		(layer "B.Cu")
		(at 358.465882 -256.012188 -90)
		(property "Reference" "C2553"
			(at 0 0 90)
			(layer "B.SilkS")
			(hide yes)
			(effects
				(font
					(size 1.27 1.27)
				)
				(justify mirror)
			)
		)
		(property "Value" ""
			(at 0 0 90)
			(layer "B.Fab")
			(effects
				(font
					(size 1.27 1.27)
				)
				(justify mirror)
			)
		)
		(duplicate_pad_numbers_are_jumpers no)
		(fp_line
			(start -0.7874 0.4064)
			(end 0.7874 0.4064)
			(stroke
				(width 0.1524)
				(type default)
			)
			(layer "B.SilkS")
		)
		(fp_line
			(start 0.7874 0.4064)
			(end 0.7874 -0.4064)
			(stroke
				(width 0.1524)
				(type default)
			)
			(layer "B.SilkS")
		)
		(fp_line
			(start -0.7874 -0.4064)
			(end -0.7874 0.4064)
			(stroke
				(width 0.1524)
				(type default)
			)
			(layer "B.SilkS")
		)
		(fp_line
			(start 0.7874 -0.4064)
			(end -0.7874 -0.4064)
			(stroke
				(width 0.1524)
				(type default)
			)
			(layer "B.SilkS")
		)
		(fp_line
			(start -0.67945 0.3048)
			(end -0.120396 0.3048)
			(stroke
				(width 0.1)
				(type default)
			)
			(layer "B.Fab")
		)
		(fp_line
			(start -0.120396 0.3048)
			(end -0.120396 0.2794)
			(stroke
				(width 0.1)
				(type default)
			)
			(layer "B.Fab")
		)
		(fp_line
			(start 0.12065 0.3048)
			(end 0.67945 0.3048)
			(stroke
				(width 0.1)
				(type default)
			)
			(layer "B.Fab")
		)
		(fp_line
			(start 0.67945 0.3048)
			(end 0.67945 -0.305054)
			(stroke
				(width 0.1)
				(type default)
			)
			(layer "B.Fab")
		)
		(fp_line
			(start -0.120396 0.2794)
			(end 0.12065 0.2794)
			(stroke
				(width 0.1)
				(type default)
			)
			(layer "B.Fab")
		)
		(fp_line
			(start 0.12065 0.2794)
			(end 0.12065 0.3048)
			(stroke
				(width 0.1)
				(type default)
			)
			(layer "B.Fab")
		)
		(fp_line
			(start -0.12065 -0.2794)
			(end -0.12065 -0.3048)
			(stroke
				(width 0.1)
				(type default)
			)
			(layer "B.Fab")
		)
		(fp_line
			(start 0.12065 -0.2794)
			(end -0.12065 -0.2794)
			(stroke
				(width 0.1)
				(type default)
			)
			(layer "B.Fab")
		)
		(fp_line
			(start -0.67945 -0.3048)
			(end -0.67945 0.3048)
			(stroke
				(width 0.1)
				(type default)
			)
			(layer "B.Fab")
		)
		(fp_line
			(start -0.12065 -0.3048)
			(end -0.67945 -0.3048)
			(stroke
				(width 0.1)
				(type default)
			)
			(layer "B.Fab")
		)
		(fp_line
			(start 0.12065 -0.305054)
			(end 0.12065 -0.2794)
			(stroke
				(width 0.1)
				(type default)
			)
			(layer "B.Fab")
		)
		(fp_line
			(start 0.67945 -0.305054)
			(end 0.12065 -0.305054)
			(stroke
				(width 0.1)
				(type default)
			)
			(layer "B.Fab")
		)
		(pad "1" smd circle
			(at 0.40005 0 90)
			(size 0 0)
			(layers "B.Cu" "B.Mask" "B.Paste")
			(net "PVDDCR_SOC_P0")
		)
		(pad "2" smd circle
			(at -0.40005 0 90)
			(size 0 0)
			(layers "B.Cu" "B.Mask" "B.Paste")
			(net "GND")
		)
	)
	(footprint ""
		(layer "B.Cu")
		(at 107.917996 -26.952448 90)
		(property "Reference" "C6100"
			(at 0 0 90)
			(layer "B.SilkS")
			(hide yes)
			(effects
				(font
					(size 1.27 1.27)
				)
				(justify mirror)
			)
		)
		(property "Value" ""
			(at 0 0 90)
			(layer "B.Fab")
			(effects
				(font
					(size 1.27 1.27)
				)
				(justify mirror)
			)
		)
		(duplicate_pad_numbers_are_jumpers no)
		(fp_line
			(start 0.7874 -0.4064)
			(end -0.7874 -0.4064)
			(stroke
				(width 0.1524)
				(type default)
			)
			(layer "B.SilkS")
		)
		(fp_line
			(start -0.7874 -0.4064)
			(end -0.7874 0.4064)
			(stroke
				(width 0.1524)
				(type default)
			)
			(layer "B.SilkS")
		)
		(fp_line
			(start 0.7874 0.4064)
			(end 0.7874 -0.4064)
			(stroke
				(width 0.1524)
				(type default)
			)
			(layer "B.SilkS")
		)
		(fp_line
			(start -0.7874 0.4064)
			(end 0.7874 0.4064)
			(stroke
				(width 0.1524)
				(type default)
			)
			(layer "B.SilkS")
		)
		(fp_line
			(start 0.67945 -0.305054)
			(end 0.12065 -0.305054)
			(stroke
				(width 0.1)
				(type default)
			)
			(layer "B.Fab")
		)
		(fp_line
			(start 0.12065 -0.305054)
			(end 0.12065 -0.2794)
			(stroke
				(width 0.1)
				(type default)
			)
			(layer "B.Fab")
		)
		(fp_line
			(start -0.12065 -0.3048)
			(end -0.67945 -0.3048)
			(stroke
				(width 0.1)
				(type default)
			)
			(layer "B.Fab")
		)
		(fp_line
			(start -0.67945 -0.3048)
			(end -0.67945 0.3048)
			(stroke
				(width 0.1)
				(type default)
			)
			(layer "B.Fab")
		)
		(fp_line
			(start 0.12065 -0.2794)
			(end -0.12065 -0.2794)
			(stroke
				(width 0.1)
				(type default)
			)
			(layer "B.Fab")
		)
		(fp_line
			(start -0.12065 -0.2794)
			(end -0.12065 -0.3048)
			(stroke
				(width 0.1)
				(type default)
			)
			(layer "B.Fab")
		)
		(fp_line
			(start 0.12065 0.2794)
			(end 0.12065 0.3048)
			(stroke
				(width 0.1)
				(type default)
			)
			(layer "B.Fab")
		)
		(fp_line
			(start -0.120396 0.2794)
			(end 0.12065 0.2794)
			(stroke
				(width 0.1)
				(type default)
			)
			(layer "B.Fab")
		)
		(fp_line
			(start 0.67945 0.3048)
			(end 0.67945 -0.305054)
			(stroke
				(width 0.1)
				(type default)
			)
			(layer "B.Fab")
		)
		(fp_line
			(start 0.12065 0.3048)
			(end 0.67945 0.3048)
			(stroke
				(width 0.1)
				(type default)
			)
			(layer "B.Fab")
		)
		(fp_line
			(start -0.120396 0.3048)
			(end -0.120396 0.2794)
			(stroke
				(width 0.1)
				(type default)
			)
			(layer "B.Fab")
		)
		(fp_line
			(start -0.67945 0.3048)
			(end -0.120396 0.3048)
			(stroke
				(width 0.1)
				(type default)
			)
			(layer "B.Fab")
		)
		(pad "1" smd circle
			(at 0.40005 0 270)
			(size 0 0)
			(layers "B.Cu" "B.Mask" "B.Paste")
			(net "P3V3_AUX_CPU0_USB2_AVDD33")
		)
		(pad "2" smd circle
			(at -0.40005 0 270)
			(size 0 0)
			(layers "B.Cu" "B.Mask" "B.Paste")
			(net "GND")
		)
	)
	(footprint ""
		(layer "B.Cu")
		(at 114.467386 -268.418564)
		(property "Reference" "C2387"
			(at 0 0 0)
			(layer "B.SilkS")
			(hide yes)
			(effects
				(font
					(size 1.27 1.27)
				)
				(justify mirror)
			)
		)
		(property "Value" ""
			(at 0 0 0)
			(layer "B.Fab")
			(effects
				(font
					(size 1.27 1.27)
				)
				(justify mirror)
			)
		)
		(duplicate_pad_numbers_are_jumpers no)
		(fp_line
			(start -0.7874 -0.4064)
			(end -0.7874 0.4064)
			(stroke
				(width 0.1524)
				(type default)
			)
			(layer "B.SilkS")
		)
		(fp_line
			(start -0.7874 0.4064)
			(end 0.7874 0.4064)
			(stroke
				(width 0.1524)
				(type default)
			)
			(layer "B.SilkS")
		)
		(fp_line
			(start 0.7874 -0.4064)
			(end -0.7874 -0.4064)
			(stroke
				(width 0.1524)
				(type default)
			)
			(layer "B.SilkS")
		)
		(fp_line
			(start 0.7874 0.4064)
			(end 0.7874 -0.4064)
			(stroke
				(width 0.1524)
				(type default)
			)
			(layer "B.SilkS")
		)
		(fp_line
			(start -0.67945 -0.3048)
			(end -0.67945 0.3048)
			(stroke
				(width 0.1)
				(type default)
			)
			(layer "B.Fab")
		)
		(fp_line
			(start -0.67945 0.3048)
			(end -0.120396 0.3048)
			(stroke
				(width 0.1)
				(type default)
			)
			(layer "B.Fab")
		)
		(fp_line
			(start -0.12065 -0.3048)
			(end -0.67945 -0.3048)
			(stroke
				(width 0.1)
				(type default)
			)
			(layer "B.Fab")
		)
		(fp_line
			(start -0.12065 -0.2794)
			(end -0.12065 -0.3048)
			(stroke
				(width 0.1)
				(type default)
			)
			(layer "B.Fab")
		)
		(fp_line
			(start -0.120396 0.2794)
			(end 0.12065 0.2794)
			(stroke
				(width 0.1)
				(type default)
			)
			(layer "B.Fab")
		)
		(fp_line
			(start -0.120396 0.3048)
			(end -0.120396 0.2794)
			(stroke
				(width 0.1)
				(type default)
			)
			(layer "B.Fab")
		)
		(fp_line
			(start 0.12065 -0.305054)
			(end 0.12065 -0.2794)
			(stroke
				(width 0.1)
				(type default)
			)
			(layer "B.Fab")
		)
		(fp_line
			(start 0.12065 -0.2794)
			(end -0.12065 -0.2794)
			(stroke
				(width 0.1)
				(type default)
			)
			(layer "B.Fab")
		)
		(fp_line
			(start 0.12065 0.2794)
			(end 0.12065 0.3048)
			(stroke
				(width 0.1)
				(type default)
			)
			(layer "B.Fab")
		)
		(fp_line
			(start 0.12065 0.3048)
			(end 0.67945 0.3048)
			(stroke
				(width 0.1)
				(type default)
			)
			(layer "B.Fab")
		)
		(fp_line
			(start 0.67945 -0.305054)
			(end 0.12065 -0.305054)
			(stroke
				(width 0.1)
				(type default)
			)
			(layer "B.Fab")
		)
		(fp_line
			(start 0.67945 0.3048)
			(end 0.67945 -0.305054)
			(stroke
				(width 0.1)
				(type default)
			)
			(layer "B.Fab")
		)
		(pad "1" smd circle
			(at 0.40005 0 180)
			(size 0 0)
			(layers "B.Cu" "B.Mask" "B.Paste")
			(net "PVDDCR_CPU1_P1")
		)
		(pad "2" smd circle
			(at -0.40005 0 180)
			(size 0 0)
			(layers "B.Cu" "B.Mask" "B.Paste")
			(net "GND")
		)
	)
	(footprint ""
		(layer "B.Cu")
		(at 348.913958 -250.89231 180)
		(property "Reference" "C2514"
			(at 0 0 0)
			(layer "B.SilkS")
			(hide yes)
			(effects
				(font
					(size 1.27 1.27)
				)
				(justify mirror)
			)
		)
		(property "Value" ""
			(at 0 0 0)
			(layer "B.Fab")
			(effects
				(font
					(size 1.27 1.27)
				)
				(justify mirror)
			)
		)
		(duplicate_pad_numbers_are_jumpers no)
		(fp_line
			(start 0.7874 0.4064)
			(end 0.7874 -0.4064)
			(stroke
				(width 0.1524)
				(type default)
			)
			(layer "B.SilkS")
		)
		(fp_line
			(start 0.7874 -0.4064)
			(end -0.7874 -0.4064)
			(stroke
				(width 0.1524)
				(type default)
			)
			(layer "B.SilkS")
		)
		(fp_line
			(start -0.7874 0.4064)
			(end 0.7874 0.4064)
			(stroke
				(width 0.1524)
				(type default)
			)
			(layer "B.SilkS")
		)
		(fp_line
			(start -0.7874 -0.4064)
			(end -0.7874 0.4064)
			(stroke
				(width 0.1524)
				(type default)
			)
			(layer "B.SilkS")
		)
		(fp_line
			(start 0.67945 0.3048)
			(end 0.67945 -0.305054)
			(stroke
				(width 0.1)
				(type default)
			)
			(layer "B.Fab")
		)
		(fp_line
			(start 0.67945 -0.305054)
			(end 0.12065 -0.305054)
			(stroke
				(width 0.1)
				(type default)
			)
			(layer "B.Fab")
		)
		(fp_line
			(start 0.12065 0.3048)
			(end 0.67945 0.3048)
			(stroke
				(width 0.1)
				(type default)
			)
			(layer "B.Fab")
		)
		(fp_line
			(start 0.12065 0.2794)
			(end 0.12065 0.3048)
			(stroke
				(width 0.1)
				(type default)
			)
			(layer "B.Fab")
		)
		(fp_line
			(start 0.12065 -0.2794)
			(end -0.12065 -0.2794)
			(stroke
				(width 0.1)
				(type default)
			)
			(layer "B.Fab")
		)
		(fp_line
			(start 0.12065 -0.305054)
			(end 0.12065 -0.2794)
			(stroke
				(width 0.1)
				(type default)
			)
			(layer "B.Fab")
		)
		(fp_line
			(start -0.120396 0.3048)
			(end -0.120396 0.2794)
			(stroke
				(width 0.1)
				(type default)
			)
			(layer "B.Fab")
		)
		(fp_line
			(start -0.120396 0.2794)
			(end 0.12065 0.2794)
			(stroke
				(width 0.1)
				(type default)
			)
			(layer "B.Fab")
		)
		(fp_line
			(start -0.12065 -0.2794)
			(end -0.12065 -0.3048)
			(stroke
				(width 0.1)
				(type default)
			)
			(layer "B.Fab")
		)
		(fp_line
			(start -0.12065 -0.3048)
			(end -0.67945 -0.3048)
			(stroke
				(width 0.1)
				(type default)
			)
			(layer "B.Fab")
		)
		(fp_line
			(start -0.67945 0.3048)
			(end -0.120396 0.3048)
			(stroke
				(width 0.1)
				(type default)
			)
			(layer "B.Fab")
		)
		(fp_line
			(start -0.67945 -0.3048)
			(end -0.67945 0.3048)
			(stroke
				(width 0.1)
				(type default)
			)
			(layer "B.Fab")
		)
		(pad "1" smd circle
			(at 0.40005 0)
			(size 0 0)
			(layers "B.Cu" "B.Mask" "B.Paste")
			(net "PVDD18_S5_P0")
		)
		(pad "2" smd circle
			(at -0.40005 0)
			(size 0 0)
			(layers "B.Cu" "B.Mask" "B.Paste")
			(net "GND")
		)
	)
	(footprint ""
		(layer "B.Cu")
		(at 126.894844 -41.762172 -90)
		(property "Reference" "C6079"
			(at 0 0 90)
			(layer "B.SilkS")
			(hide yes)
			(effects
				(font
					(size 1.27 1.27)
				)
				(justify mirror)
			)
		)
		(property "Value" ""
			(at 0 0 90)
			(layer "B.Fab")
			(effects
				(font
					(size 1.27 1.27)
				)
				(justify mirror)
			)
		)
		(duplicate_pad_numbers_are_jumpers no)
		(fp_line
			(start -1.2954 0.5842)
			(end 1.2954 0.5842)
			(stroke
				(width 0.1524)
				(type default)
			)
			(layer "B.SilkS")
		)
		(fp_line
			(start 1.2954 0.5842)
			(end 1.2954 -0.5842)
			(stroke
				(width 0.1524)
				(type default)
			)
			(layer "B.SilkS")
		)
		(fp_line
			(start -1.2954 -0.5842)
			(end -1.2954 0.5842)
			(stroke
				(width 0.1524)
				(type default)
			)
			(layer "B.SilkS")
		)
		(fp_line
			(start 1.2954 -0.5842)
			(end -1.2954 -0.5842)
			(stroke
				(width 0.1524)
				(type default)
			)
			(layer "B.SilkS")
		)
		(fp_line
			(start -0.8636 0.4572)
			(end 0.8636 0.4572)
			(stroke
				(width 0.1)
				(type default)
			)
			(layer "B.Fab")
		)
		(fp_line
			(start 0.8636 0.4572)
			(end 0.8636 0.4064)
			(stroke
				(width 0.1)
				(type default)
			)
			(layer "B.Fab")
		)
		(fp_line
			(start -1.1938 0.4064)
			(end -0.8636 0.4064)
			(stroke
				(width 0.1)
				(type default)
			)
			(layer "B.Fab")
		)
		(fp_line
			(start -0.8636 0.4064)
			(end -0.8636 0.4572)
			(stroke
				(width 0.1)
				(type default)
			)
			(layer "B.Fab")
		)
		(fp_line
			(start 0.8636 0.4064)
			(end 1.1938 0.4064)
			(stroke
				(width 0.1)
				(type default)
			)
			(layer "B.Fab")
		)
		(fp_line
			(start 1.1938 0.4064)
			(end 1.1938 -0.4064)
			(stroke
				(width 0.1)
				(type default)
			)
			(layer "B.Fab")
		)
		(fp_line
			(start -1.1938 -0.4064)
			(end -1.1938 0.4064)
			(stroke
				(width 0.1)
				(type default)
			)
			(layer "B.Fab")
		)
		(fp_line
			(start -0.8636 -0.4064)
			(end -1.1938 -0.4064)
			(stroke
				(width 0.1)
				(type default)
			)
			(layer "B.Fab")
		)
		(fp_line
			(start 0.8636 -0.4064)
			(end 0.8636 -0.4572)
			(stroke
				(width 0.1)
				(type default)
			)
			(layer "B.Fab")
		)
		(fp_line
			(start 1.1938 -0.4064)
			(end 0.8636 -0.4064)
			(stroke
				(width 0.1)
				(type default)
			)
			(layer "B.Fab")
		)
		(fp_line
			(start -0.8636 -0.4572)
			(end -0.8636 -0.4064)
			(stroke
				(width 0.1)
				(type default)
			)
			(layer "B.Fab")
		)
		(fp_line
			(start 0.8636 -0.4572)
			(end -0.8636 -0.4572)
			(stroke
				(width 0.1)
				(type default)
			)
			(layer "B.Fab")
		)
		(pad "1" smd rect
			(at 0.7366 0 180)
			(size 0.7112 0.8128)
			(layers "B.Cu" "B.Mask" "B.Paste")
			(net "P1V2_AUX")
		)
		(pad "2" smd rect
			(at -0.7366 0 180)
			(size 0.7112 0.8128)
			(layers "B.Cu" "B.Mask" "B.Paste")
			(net "GND")
		)
	)
	(footprint ""
		(layer "B.Cu")
		(at 130.458972 -41.007792 90)
		(property "Reference" "C6041"
			(at 0 0 90)
			(layer "B.SilkS")
			(hide yes)
			(effects
				(font
					(size 1.27 1.27)
				)
				(justify mirror)
			)
		)
		(property "Value" ""
			(at 0 0 90)
			(layer "B.Fab")
			(effects
				(font
					(size 1.27 1.27)
				)
				(justify mirror)
			)
		)
		(duplicate_pad_numbers_are_jumpers no)
		(fp_line
			(start 0.7874 -0.4064)
			(end -0.7874 -0.4064)
			(stroke
				(width 0.1524)
				(type default)
			)
			(layer "B.SilkS")
		)
		(fp_line
			(start -0.7874 -0.4064)
			(end -0.7874 0.4064)
			(stroke
				(width 0.1524)
				(type default)
			)
			(layer "B.SilkS")
		)
		(fp_line
			(start 0.7874 0.4064)
			(end 0.7874 -0.4064)
			(stroke
				(width 0.1524)
				(type default)
			)
			(layer "B.SilkS")
		)
		(fp_line
			(start -0.7874 0.4064)
			(end 0.7874 0.4064)
			(stroke
				(width 0.1524)
				(type default)
			)
			(layer "B.SilkS")
		)
		(fp_line
			(start 0.67945 -0.305054)
			(end 0.12065 -0.305054)
			(stroke
				(width 0.1)
				(type default)
			)
			(layer "B.Fab")
		)
		(fp_line
			(start 0.12065 -0.305054)
			(end 0.12065 -0.2794)
			(stroke
				(width 0.1)
				(type default)
			)
			(layer "B.Fab")
		)
		(fp_line
			(start -0.12065 -0.3048)
			(end -0.67945 -0.3048)
			(stroke
				(width 0.1)
				(type default)
			)
			(layer "B.Fab")
		)
		(fp_line
			(start -0.67945 -0.3048)
			(end -0.67945 0.3048)
			(stroke
				(width 0.1)
				(type default)
			)
			(layer "B.Fab")
		)
		(fp_line
			(start 0.12065 -0.2794)
			(end -0.12065 -0.2794)
			(stroke
				(width 0.1)
				(type default)
			)
			(layer "B.Fab")
		)
		(fp_line
			(start -0.12065 -0.2794)
			(end -0.12065 -0.3048)
			(stroke
				(width 0.1)
				(type default)
			)
			(layer "B.Fab")
		)
		(fp_line
			(start 0.12065 0.2794)
			(end 0.12065 0.3048)
			(stroke
				(width 0.1)
				(type default)
			)
			(layer "B.Fab")
		)
		(fp_line
			(start -0.120396 0.2794)
			(end 0.12065 0.2794)
			(stroke
				(width 0.1)
				(type default)
			)
			(layer "B.Fab")
		)
		(fp_line
			(start 0.67945 0.3048)
			(end 0.67945 -0.305054)
			(stroke
				(width 0.1)
				(type default)
			)
			(layer "B.Fab")
		)
		(fp_line
			(start 0.12065 0.3048)
			(end 0.67945 0.3048)
			(stroke
				(width 0.1)
				(type default)
			)
			(layer "B.Fab")
		)
		(fp_line
			(start -0.120396 0.3048)
			(end -0.120396 0.2794)
			(stroke
				(width 0.1)
				(type default)
			)
			(layer "B.Fab")
		)
		(fp_line
			(start -0.67945 0.3048)
			(end -0.120396 0.3048)
			(stroke
				(width 0.1)
				(type default)
			)
			(layer "B.Fab")
		)
		(pad "1" smd circle
			(at 0.40005 0 270)
			(size 0 0)
			(layers "B.Cu" "B.Mask" "B.Paste")
			(net "P3V3_AUX")
		)
		(pad "2" smd circle
			(at -0.40005 0 270)
			(size 0 0)
			(layers "B.Cu" "B.Mask" "B.Paste")
			(net "GND")
		)
	)
	(footprint ""
		(layer "B.Cu")
		(at 102.378764 -258.830318 180)
		(property "Reference" "C2484"
			(at 0 0 0)
			(layer "B.SilkS")
			(hide yes)
			(effects
				(font
					(size 1.27 1.27)
				)
				(justify mirror)
			)
		)
		(property "Value" ""
			(at 0 0 0)
			(layer "B.Fab")
			(effects
				(font
					(size 1.27 1.27)
				)
				(justify mirror)
			)
		)
		(duplicate_pad_numbers_are_jumpers no)
		(fp_line
			(start 0.7874 0.4064)
			(end 0.7874 -0.4064)
			(stroke
				(width 0.1524)
				(type default)
			)
			(layer "B.SilkS")
		)
		(fp_line
			(start 0.7874 -0.4064)
			(end -0.7874 -0.4064)
			(stroke
				(width 0.1524)
				(type default)
			)
			(layer "B.SilkS")
		)
		(fp_line
			(start -0.7874 0.4064)
			(end 0.7874 0.4064)
			(stroke
				(width 0.1524)
				(type default)
			)
			(layer "B.SilkS")
		)
		(fp_line
			(start -0.7874 -0.4064)
			(end -0.7874 0.4064)
			(stroke
				(width 0.1524)
				(type default)
			)
			(layer "B.SilkS")
		)
		(fp_line
			(start 0.67945 0.3048)
			(end 0.67945 -0.305054)
			(stroke
				(width 0.1)
				(type default)
			)
			(layer "B.Fab")
		)
		(fp_line
			(start 0.67945 -0.305054)
			(end 0.12065 -0.305054)
			(stroke
				(width 0.1)
				(type default)
			)
			(layer "B.Fab")
		)
		(fp_line
			(start 0.12065 0.3048)
			(end 0.67945 0.3048)
			(stroke
				(width 0.1)
				(type default)
			)
			(layer "B.Fab")
		)
		(fp_line
			(start 0.12065 0.2794)
			(end 0.12065 0.3048)
			(stroke
				(width 0.1)
				(type default)
			)
			(layer "B.Fab")
		)
		(fp_line
			(start 0.12065 -0.2794)
			(end -0.12065 -0.2794)
			(stroke
				(width 0.1)
				(type default)
			)
			(layer "B.Fab")
		)
		(fp_line
			(start 0.12065 -0.305054)
			(end 0.12065 -0.2794)
			(stroke
				(width 0.1)
				(type default)
			)
			(layer "B.Fab")
		)
		(fp_line
			(start -0.120396 0.3048)
			(end -0.120396 0.2794)
			(stroke
				(width 0.1)
				(type default)
			)
			(layer "B.Fab")
		)
		(fp_line
			(start -0.120396 0.2794)
			(end 0.12065 0.2794)
			(stroke
				(width 0.1)
				(type default)
			)
			(layer "B.Fab")
		)
		(fp_line
			(start -0.12065 -0.2794)
			(end -0.12065 -0.3048)
			(stroke
				(width 0.1)
				(type default)
			)
			(layer "B.Fab")
		)
		(fp_line
			(start -0.12065 -0.3048)
			(end -0.67945 -0.3048)
			(stroke
				(width 0.1)
				(type default)
			)
			(layer "B.Fab")
		)
		(fp_line
			(start -0.67945 0.3048)
			(end -0.120396 0.3048)
			(stroke
				(width 0.1)
				(type default)
			)
			(layer "B.Fab")
		)
		(fp_line
			(start -0.67945 -0.3048)
			(end -0.67945 0.3048)
			(stroke
				(width 0.1)
				(type default)
			)
			(layer "B.Fab")
		)
		(pad "1" smd circle
			(at 0.40005 0)
			(size 0 0)
			(layers "B.Cu" "B.Mask" "B.Paste")
			(net "PVDDIO_P1")
		)
		(pad "2" smd circle
			(at -0.40005 0)
			(size 0 0)
			(layers "B.Cu" "B.Mask" "B.Paste")
			(net "GND")
		)
	)
	(footprint ""
		(layer "B.Cu")
		(at 209.295746 -77.263752)
		(property "Reference" "U222"
			(at 2.032 -3.27533 0)
			(unlocked yes)
			(layer "B.SilkS")
			(effects
				(font
					(size 0.7874 0.5842)
					(thickness 0.1524)
				)
				(justify left mirror)
			)
		)
		(property "Value" ""
			(at 0 0 0)
			(layer "B.Fab")
			(effects
				(font
					(size 1.27 1.27)
				)
				(justify mirror)
			)
		)
		(duplicate_pad_numbers_are_jumpers no)
		(fp_line
			(start -2.0066 -2.5527)
			(end -2.0066 2.5527)
			(stroke
				(width 0.1524)
				(type default)
			)
			(layer "B.SilkS")
		)
		(fp_line
			(start -2.0066 2.5527)
			(end 2.0066 2.5527)
			(stroke
				(width 0.1524)
				(type default)
			)
			(layer "B.SilkS")
		)
		(fp_line
			(start -0.5715 -2.5527)
			(end -2.0066 -2.5527)
			(stroke
				(width 0.1524)
				(type default)
			)
			(layer "B.SilkS")
		)
		(fp_line
			(start 0 -1.9812)
			(end -0.5715 -2.5527)
			(stroke
				(width 0.1524)
				(type default)
			)
			(layer "B.SilkS")
		)
		(fp_line
			(start 0.5715 -2.5527)
			(end 0 -1.9812)
			(stroke
				(width 0.1524)
				(type default)
			)
			(layer "B.SilkS")
		)
		(fp_line
			(start 2.0066 -2.5527)
			(end 0.5715 -2.5527)
			(stroke
				(width 0.1524)
				(type default)
			)
			(layer "B.SilkS")
		)
		(fp_line
			(start 2.0066 2.5527)
			(end 2.0066 -2.5527)
			(stroke
				(width 0.1524)
				(type default)
			)
			(layer "B.SilkS")
		)
		(fp_poly
			(pts
				(xy 3.81 -1.905) (xy 4.36372 -2.233168) (xy 4.36372 -1.608328)
			)
			(stroke
				(width 0)
				(type default)
			)
			(fill yes)
			(layer "B.SilkS")
		)
		(fp_line
			(start -2.249932 -2.549906)
			(end -2.249932 2.549906)
			(stroke
				(width 0.1)
				(type default)
			)
			(layer "B.Fab")
		)
		(fp_line
			(start -2.249932 2.549906)
			(end 2.249932 2.549906)
			(stroke
				(width 0.1)
				(type default)
			)
			(layer "B.Fab")
		)
		(fp_line
			(start 2.249932 -2.549906)
			(end -2.249932 -2.549906)
			(stroke
				(width 0.1)
				(type default)
			)
			(layer "B.Fab")
		)
		(fp_line
			(start 2.249932 2.549906)
			(end 2.249932 -2.549906)
			(stroke
				(width 0.1)
				(type default)
			)
			(layer "B.Fab")
		)
		(fp_poly
			(pts
				(xy 4.36372 -1.608328) (xy 4.36372 -2.233168) (xy 3.81 -1.905)
			)
			(stroke
				(width 0)
				(type default)
			)
			(fill yes)
			(layer "B.Fab")
		)
		(pad "1" smd rect
			(at 2.921 -1.949958 270)
			(size 0.3556 1.4986)
			(layers "B.Cu" "B.Mask" "B.Paste")
			(net "FB_BMC_ISOLATE1")
		)
		(pad "2" smd rect
			(at 2.921 -1.299972 270)
			(size 0.3556 1.4986)
			(layers "B.Cu" "B.Mask" "B.Paste")
			(net "NCSI_BMC_RXD1_R1")
		)
		(pad "3" smd rect
			(at 2.921 -0.649986 270)
			(size 0.3556 1.4986)
			(layers "B.Cu" "B.Mask" "B.Paste")
			(net "NCSI_OCP_V3_2_RXD1")
		)
		(pad "4" smd rect
			(at 2.921 0 270)
			(size 0.3556 1.4986)
			(layers "B.Cu" "B.Mask" "B.Paste")
			(net "FB_BMC_ISOLATE1")
		)
		(pad "5" smd rect
			(at 2.921 0.649986 270)
			(size 0.3556 1.4986)
			(layers "B.Cu" "B.Mask" "B.Paste")
			(net "NCSI_BMC_RXD0_R1")
		)
		(pad "6" smd rect
			(at 2.921 1.299972 270)
			(size 0.3556 1.4986)
			(layers "B.Cu" "B.Mask" "B.Paste")
			(net "NCSI_OCP_V3_2_RXD0")
		)
		(pad "7" smd rect
			(at 2.921 1.949958 270)
			(size 0.3556 1.4986)
			(layers "B.Cu" "B.Mask" "B.Paste")
			(net "GND")
		)
		(pad "8" smd rect
			(at -2.921 1.949958 270)
			(size 0.3556 1.4986)
			(layers "B.Cu" "B.Mask" "B.Paste")
			(net "NCSI_OCP_V3_2_CRS_DV")
		)
		(pad "9" smd rect
			(at -2.921 1.299972 270)
			(size 0.3556 1.4986)
			(layers "B.Cu" "B.Mask" "B.Paste")
			(net "NCSI_BMC_CRS_DV_R1")
		)
		(pad "10" smd rect
			(at -2.921 0.649986 270)
			(size 0.3556 1.4986)
			(layers "B.Cu" "B.Mask" "B.Paste")
			(net "FB_BMC_ISOLATE1")
		)
		(pad "11" smd rect
			(at -2.921 0 270)
			(size 0.3556 1.4986)
			(layers "B.Cu" "B.Mask" "B.Paste")
			(net "OCP_V3_2_ISO1_RBT_ARB_IN")
		)
		(pad "12" smd rect
			(at -2.921 -0.649986 270)
			(size 0.3556 1.4986)
			(layers "B.Cu" "B.Mask" "B.Paste")
			(net "OCP_V3_2_RBT_ARB_IN_R")
		)
		(pad "13" smd rect
			(at -2.921 -1.299972 270)
			(size 0.3556 1.4986)
			(layers "B.Cu" "B.Mask" "B.Paste")
			(net "FB_BMC_ISOLATE1")
		)
		(pad "14" smd rect
			(at -2.921 -1.949958 270)
			(size 0.3556 1.4986)
			(layers "B.Cu" "B.Mask" "B.Paste")
			(net "P3V3_AUX")
		)
	)
	(footprint ""
		(layer "B.Cu")
		(at 400.358102 -152.29078 -90)
		(property "Reference" "R4640"
			(at 0 0 90)
			(layer "B.SilkS")
			(hide yes)
			(effects
				(font
					(size 1.27 1.27)
				)
				(justify mirror)
			)
		)
		(property "Value" ""
			(at 0 0 90)
			(layer "B.Fab")
			(effects
				(font
					(size 1.27 1.27)
				)
				(justify mirror)
			)
		)
		(duplicate_pad_numbers_are_jumpers no)
		(fp_line
			(start -2.234946 0.9271)
			(end 2.234946 0.9271)
			(stroke
				(width 0.1524)
				(type default)
			)
			(layer "B.SilkS")
		)
		(fp_line
			(start 2.234946 0.9271)
			(end 2.234946 -0.9271)
			(stroke
				(width 0.1524)
				(type default)
			)
			(layer "B.SilkS")
		)
		(fp_line
			(start -2.234946 -0.9271)
			(end -2.234946 0.9271)
			(stroke
				(width 0.1524)
				(type default)
			)
			(layer "B.SilkS")
		)
		(fp_line
			(start 2.234946 -0.9271)
			(end -2.234946 -0.9271)
			(stroke
				(width 0.1524)
				(type default)
			)
			(layer "B.SilkS")
		)
		(fp_line
			(start -1.575054 0.824992)
			(end -1.575054 -0.824992)
			(stroke
				(width 0.1)
				(type default)
			)
			(layer "B.Fab")
		)
		(fp_line
			(start 1.575054 0.824992)
			(end -1.575054 0.824992)
			(stroke
				(width 0.1)
				(type default)
			)
			(layer "B.Fab")
		)
		(fp_line
			(start -1.575054 -0.824992)
			(end 1.575054 -0.824992)
			(stroke
				(width 0.1)
				(type default)
			)
			(layer "B.Fab")
		)
		(fp_line
			(start 1.575054 -0.824992)
			(end 1.575054 0.824992)
			(stroke
				(width 0.1)
				(type default)
			)
			(layer "B.Fab")
		)
		(pad "1" smd rect
			(at 1.599946 0 90)
			(size 1.016 1.6002)
			(layers "B.Cu" "B.Mask" "B.Paste")
			(net "P5V")
		)
		(pad "2" smd rect
			(at -1.599946 0 90)
			(size 1.016 1.6002)
			(layers "B.Cu" "B.Mask" "B.Paste")
			(net "VR_P5V_EN_D")
		)
	)
	(footprint ""
		(layer "B.Cu")
		(at 378.250958 -205.101952 90)
		(property "Reference" "C212"
			(at 0 0 90)
			(layer "B.SilkS")
			(hide yes)
			(effects
				(font
					(size 1.27 1.27)
				)
				(justify mirror)
			)
		)
		(property "Value" ""
			(at 0 0 90)
			(layer "B.Fab")
			(effects
				(font
					(size 1.27 1.27)
				)
				(justify mirror)
			)
		)
		(duplicate_pad_numbers_are_jumpers no)
		(fp_line
			(start 0.7874 -0.4064)
			(end -0.7874 -0.4064)
			(stroke
				(width 0.1524)
				(type default)
			)
			(layer "B.SilkS")
		)
		(fp_line
			(start -0.7874 -0.4064)
			(end -0.7874 0.4064)
			(stroke
				(width 0.1524)
				(type default)
			)
			(layer "B.SilkS")
		)
		(fp_line
			(start 0.7874 0.4064)
			(end 0.7874 -0.4064)
			(stroke
				(width 0.1524)
				(type default)
			)
			(layer "B.SilkS")
		)
		(fp_line
			(start -0.7874 0.4064)
			(end 0.7874 0.4064)
			(stroke
				(width 0.1524)
				(type default)
			)
			(layer "B.SilkS")
		)
		(fp_line
			(start 0.67945 -0.305054)
			(end 0.12065 -0.305054)
			(stroke
				(width 0.1)
				(type default)
			)
			(layer "B.Fab")
		)
		(fp_line
			(start 0.12065 -0.305054)
			(end 0.12065 -0.2794)
			(stroke
				(width 0.1)
				(type default)
			)
			(layer "B.Fab")
		)
		(fp_line
			(start -0.12065 -0.3048)
			(end -0.67945 -0.3048)
			(stroke
				(width 0.1)
				(type default)
			)
			(layer "B.Fab")
		)
		(fp_line
			(start -0.67945 -0.3048)
			(end -0.67945 0.3048)
			(stroke
				(width 0.1)
				(type default)
			)
			(layer "B.Fab")
		)
		(fp_line
			(start 0.12065 -0.2794)
			(end -0.12065 -0.2794)
			(stroke
				(width 0.1)
				(type default)
			)
			(layer "B.Fab")
		)
		(fp_line
			(start -0.12065 -0.2794)
			(end -0.12065 -0.3048)
			(stroke
				(width 0.1)
				(type default)
			)
			(layer "B.Fab")
		)
		(fp_line
			(start 0.12065 0.2794)
			(end 0.12065 0.3048)
			(stroke
				(width 0.1)
				(type default)
			)
			(layer "B.Fab")
		)
		(fp_line
			(start -0.120396 0.2794)
			(end 0.12065 0.2794)
			(stroke
				(width 0.1)
				(type default)
			)
			(layer "B.Fab")
		)
		(fp_line
			(start 0.67945 0.3048)
			(end 0.67945 -0.305054)
			(stroke
				(width 0.1)
				(type default)
			)
			(layer "B.Fab")
		)
		(fp_line
			(start 0.12065 0.3048)
			(end 0.67945 0.3048)
			(stroke
				(width 0.1)
				(type default)
			)
			(layer "B.Fab")
		)
		(fp_line
			(start -0.120396 0.3048)
			(end -0.120396 0.2794)
			(stroke
				(width 0.1)
				(type default)
			)
			(layer "B.Fab")
		)
		(fp_line
			(start -0.67945 0.3048)
			(end -0.120396 0.3048)
			(stroke
				(width 0.1)
				(type default)
			)
			(layer "B.Fab")
		)
		(pad "1" smd circle
			(at 0.40005 0 270)
			(size 0 0)
			(layers "B.Cu" "B.Mask" "B.Paste")
			(net "JTAG_CPU0_DBREQ_N")
		)
		(pad "2" smd circle
			(at -0.40005 0 270)
			(size 0 0)
			(layers "B.Cu" "B.Mask" "B.Paste")
			(net "GND")
		)
	)
	(footprint ""
		(layer "B.Cu")
		(at 131.153154 -152.724612 90)
		(property "Reference" "PC352_3"
			(at 0 0 90)
			(layer "B.SilkS")
			(hide yes)
			(effects
				(font
					(size 1.27 1.27)
				)
				(justify mirror)
			)
		)
		(property "Value" ""
			(at 0 0 90)
			(layer "B.Fab")
			(effects
				(font
					(size 1.27 1.27)
				)
				(justify mirror)
			)
		)
		(duplicate_pad_numbers_are_jumpers no)
		(fp_line
			(start 1.524 -0.762)
			(end -1.524 -0.762)
			(stroke
				(width 0.1524)
				(type default)
			)
			(layer "B.SilkS")
		)
		(fp_line
			(start -1.524 -0.762)
			(end -1.524 0.762)
			(stroke
				(width 0.1524)
				(type default)
			)
			(layer "B.SilkS")
		)
		(fp_line
			(start 1.524 0.762)
			(end 1.524 -0.762)
			(stroke
				(width 0.1524)
				(type default)
			)
			(layer "B.SilkS")
		)
		(fp_line
			(start -1.524 0.762)
			(end 1.524 0.762)
			(stroke
				(width 0.1524)
				(type default)
			)
			(layer "B.SilkS")
		)
		(fp_line
			(start 1.1049 -0.724916)
			(end 1.1049 0.724916)
			(stroke
				(width 0.1)
				(type default)
			)
			(layer "B.Fab")
		)
		(fp_line
			(start -1.1049 -0.724916)
			(end 1.1049 -0.724916)
			(stroke
				(width 0.1)
				(type default)
			)
			(layer "B.Fab")
		)
		(fp_line
			(start 1.1049 0.724916)
			(end -1.1049 0.724916)
			(stroke
				(width 0.1)
				(type default)
			)
			(layer "B.Fab")
		)
		(fp_line
			(start -1.1049 0.724916)
			(end -1.1049 -0.724916)
			(stroke
				(width 0.1)
				(type default)
			)
			(layer "B.Fab")
		)
		(pad "1" smd rect
			(at 0.889 0 90)
			(size 1.016 1.27)
			(layers "B.Cu" "B.Mask" "B.Paste")
			(net "SW_P12V_AUX_PVDDCR_SOC_P1_FLT")
		)
		(pad "2" smd rect
			(at -0.889 0 90)
			(size 1.016 1.27)
			(layers "B.Cu" "B.Mask" "B.Paste")
			(net "GND")
		)
	)
	(footprint ""
		(layer "B.Cu")
		(at 188.310012 -13.60043 -90)
		(property "Reference" "R6002"
			(at 0 0 90)
			(layer "B.SilkS")
			(hide yes)
			(effects
				(font
					(size 1.27 1.27)
				)
				(justify mirror)
			)
		)
		(property "Value" ""
			(at 0 0 90)
			(layer "B.Fab")
			(effects
				(font
					(size 1.27 1.27)
				)
				(justify mirror)
			)
		)
		(duplicate_pad_numbers_are_jumpers no)
		(fp_line
			(start -0.7874 0.4064)
			(end 0.7874 0.4064)
			(stroke
				(width 0.1524)
				(type default)
			)
			(layer "B.SilkS")
		)
		(fp_line
			(start 0.7874 0.4064)
			(end 0.7874 -0.4064)
			(stroke
				(width 0.1524)
				(type default)
			)
			(layer "B.SilkS")
		)
		(fp_line
			(start -0.7874 -0.4064)
			(end -0.7874 0.4064)
			(stroke
				(width 0.1524)
				(type default)
			)
			(layer "B.SilkS")
		)
		(fp_line
			(start 0.7874 -0.4064)
			(end -0.7874 -0.4064)
			(stroke
				(width 0.1524)
				(type default)
			)
			(layer "B.SilkS")
		)
		(fp_line
			(start -0.67945 0.3048)
			(end -0.120396 0.3048)
			(stroke
				(width 0.1)
				(type default)
			)
			(layer "B.Fab")
		)
		(fp_line
			(start -0.120396 0.3048)
			(end -0.120396 0.2794)
			(stroke
				(width 0.1)
				(type default)
			)
			(layer "B.Fab")
		)
		(fp_line
			(start 0.12065 0.3048)
			(end 0.67945 0.3048)
			(stroke
				(width 0.1)
				(type default)
			)
			(layer "B.Fab")
		)
		(fp_line
			(start 0.67945 0.3048)
			(end 0.67945 -0.305054)
			(stroke
				(width 0.1)
				(type default)
			)
			(layer "B.Fab")
		)
		(fp_line
			(start -0.120396 0.2794)
			(end 0.12065 0.2794)
			(stroke
				(width 0.1)
				(type default)
			)
			(layer "B.Fab")
		)
		(fp_line
			(start 0.12065 0.2794)
			(end 0.12065 0.3048)
			(stroke
				(width 0.1)
				(type default)
			)
			(layer "B.Fab")
		)
		(fp_line
			(start -0.12065 -0.2794)
			(end -0.12065 -0.3048)
			(stroke
				(width 0.1)
				(type default)
			)
			(layer "B.Fab")
		)
		(fp_line
			(start 0.12065 -0.2794)
			(end -0.12065 -0.2794)
			(stroke
				(width 0.1)
				(type default)
			)
			(layer "B.Fab")
		)
		(fp_line
			(start -0.67945 -0.3048)
			(end -0.67945 0.3048)
			(stroke
				(width 0.1)
				(type default)
			)
			(layer "B.Fab")
		)
		(fp_line
			(start -0.12065 -0.3048)
			(end -0.67945 -0.3048)
			(stroke
				(width 0.1)
				(type default)
			)
			(layer "B.Fab")
		)
		(fp_line
			(start 0.12065 -0.305054)
			(end 0.12065 -0.2794)
			(stroke
				(width 0.1)
				(type default)
			)
			(layer "B.Fab")
		)
		(fp_line
			(start 0.67945 -0.305054)
			(end 0.12065 -0.305054)
			(stroke
				(width 0.1)
				(type default)
			)
			(layer "B.Fab")
		)
		(pad "1" smd circle
			(at 0.40005 0 90)
			(size 0 0)
			(layers "B.Cu" "B.Mask" "B.Paste")
			(net "I3C_SCM_1_SCL")
		)
		(pad "2" smd circle
			(at -0.40005 0 90)
			(size 0 0)
			(layers "B.Cu" "B.Mask" "B.Paste")
			(net "I3C_SCM_1_R_SCL")
		)
	)
	(footprint ""
		(layer "B.Cu")
		(at 240.469928 -289.066732 90)
		(property "Reference" "R6506"
			(at 0 0 90)
			(layer "B.SilkS")
			(hide yes)
			(effects
				(font
					(size 1.27 1.27)
				)
				(justify mirror)
			)
		)
		(property "Value" ""
			(at 0 0 90)
			(layer "B.Fab")
			(effects
				(font
					(size 1.27 1.27)
				)
				(justify mirror)
			)
		)
		(duplicate_pad_numbers_are_jumpers no)
		(fp_line
			(start 0.7874 -0.4064)
			(end -0.7874 -0.4064)
			(stroke
				(width 0.1524)
				(type default)
			)
			(layer "B.SilkS")
		)
		(fp_line
			(start -0.7874 -0.4064)
			(end -0.7874 0.4064)
			(stroke
				(width 0.1524)
				(type default)
			)
			(layer "B.SilkS")
		)
		(fp_line
			(start 0.7874 0.4064)
			(end 0.7874 -0.4064)
			(stroke
				(width 0.1524)
				(type default)
			)
			(layer "B.SilkS")
		)
		(fp_line
			(start -0.7874 0.4064)
			(end 0.7874 0.4064)
			(stroke
				(width 0.1524)
				(type default)
			)
			(layer "B.SilkS")
		)
		(fp_line
			(start 0.67945 -0.305054)
			(end 0.12065 -0.305054)
			(stroke
				(width 0.1)
				(type default)
			)
			(layer "B.Fab")
		)
		(fp_line
			(start 0.12065 -0.305054)
			(end 0.12065 -0.2794)
			(stroke
				(width 0.1)
				(type default)
			)
			(layer "B.Fab")
		)
		(fp_line
			(start -0.12065 -0.3048)
			(end -0.67945 -0.3048)
			(stroke
				(width 0.1)
				(type default)
			)
			(layer "B.Fab")
		)
		(fp_line
			(start -0.67945 -0.3048)
			(end -0.67945 0.3048)
			(stroke
				(width 0.1)
				(type default)
			)
			(layer "B.Fab")
		)
		(fp_line
			(start 0.12065 -0.2794)
			(end -0.12065 -0.2794)
			(stroke
				(width 0.1)
				(type default)
			)
			(layer "B.Fab")
		)
		(fp_line
			(start -0.12065 -0.2794)
			(end -0.12065 -0.3048)
			(stroke
				(width 0.1)
				(type default)
			)
			(layer "B.Fab")
		)
		(fp_line
			(start 0.12065 0.2794)
			(end 0.12065 0.3048)
			(stroke
				(width 0.1)
				(type default)
			)
			(layer "B.Fab")
		)
		(fp_line
			(start -0.120396 0.2794)
			(end 0.12065 0.2794)
			(stroke
				(width 0.1)
				(type default)
			)
			(layer "B.Fab")
		)
		(fp_line
			(start 0.67945 0.3048)
			(end 0.67945 -0.305054)
			(stroke
				(width 0.1)
				(type default)
			)
			(layer "B.Fab")
		)
		(fp_line
			(start 0.12065 0.3048)
			(end 0.67945 0.3048)
			(stroke
				(width 0.1)
				(type default)
			)
			(layer "B.Fab")
		)
		(fp_line
			(start -0.120396 0.3048)
			(end -0.120396 0.2794)
			(stroke
				(width 0.1)
				(type default)
			)
			(layer "B.Fab")
		)
		(fp_line
			(start -0.67945 0.3048)
			(end -0.120396 0.3048)
			(stroke
				(width 0.1)
				(type default)
			)
			(layer "B.Fab")
		)
		(pad "1" smd circle
			(at 0.40005 0 270)
			(size 0 0)
			(layers "B.Cu" "B.Mask" "B.Paste")
			(net "PWRGD_P1V8_RETIMER_CPU0")
		)
		(pad "2" smd circle
			(at -0.40005 0 270)
			(size 0 0)
			(layers "B.Cu" "B.Mask" "B.Paste")
			(net "FM_PWRGD_P1V8_RETIMER_CPU0")
		)
	)
	(footprint ""
		(layer "B.Cu")
		(at 327.657206 -416.899344 90)
		(property "Reference" "C6547"
			(at 0 0 90)
			(layer "B.SilkS")
			(hide yes)
			(effects
				(font
					(size 1.27 1.27)
				)
				(justify mirror)
			)
		)
		(property "Value" ""
			(at 0 0 90)
			(layer "B.Fab")
			(effects
				(font
					(size 1.27 1.27)
				)
				(justify mirror)
			)
		)
		(duplicate_pad_numbers_are_jumpers no)
		(fp_line
			(start 0.299974 -0.150114)
			(end -0.299974 -0.150114)
			(stroke
				(width 0.1)
				(type default)
			)
			(layer "B.Fab")
		)
		(fp_line
			(start -0.299974 -0.150114)
			(end -0.299974 0.150114)
			(stroke
				(width 0.1)
				(type default)
			)
			(layer "B.Fab")
		)
		(fp_line
			(start 0.299974 0.150114)
			(end 0.299974 -0.150114)
			(stroke
				(width 0.1)
				(type default)
			)
			(layer "B.Fab")
		)
		(fp_line
			(start -0.299974 0.150114)
			(end 0.299974 0.150114)
			(stroke
				(width 0.1)
				(type default)
			)
			(layer "B.Fab")
		)
		(pad "1" smd rect
			(at 0.2667 0 270)
			(size 0.3048 0.381)
			(layers "B.Cu" "B.Mask" "B.Paste")
			(net "P5E_CPU0_P1_TX_BUF_C_DP<7>")
		)
		(pad "2" smd rect
			(at -0.2667 0 270)
			(size 0.3048 0.381)
			(layers "B.Cu" "B.Mask" "B.Paste")
			(net "P5E_CPU0_P1_TX_BUF_DP<7>")
		)
	)
	(footprint ""
		(layer "B.Cu")
		(at 237.617 -249.555)
		(property "Reference" "R1156"
			(at 0 0 0)
			(layer "B.SilkS")
			(hide yes)
			(effects
				(font
					(size 1.27 1.27)
				)
				(justify mirror)
			)
		)
		(property "Value" ""
			(at 0 0 0)
			(layer "B.Fab")
			(effects
				(font
					(size 1.27 1.27)
				)
				(justify mirror)
			)
		)
		(duplicate_pad_numbers_are_jumpers no)
		(fp_line
			(start -0.7874 -0.4064)
			(end -0.7874 0.4064)
			(stroke
				(width 0.1524)
				(type default)
			)
			(layer "B.SilkS")
		)
		(fp_line
			(start -0.7874 0.4064)
			(end 0.7874 0.4064)
			(stroke
				(width 0.1524)
				(type default)
			)
			(layer "B.SilkS")
		)
		(fp_line
			(start 0.7874 -0.4064)
			(end -0.7874 -0.4064)
			(stroke
				(width 0.1524)
				(type default)
			)
			(layer "B.SilkS")
		)
		(fp_line
			(start 0.7874 0.4064)
			(end 0.7874 -0.4064)
			(stroke
				(width 0.1524)
				(type default)
			)
			(layer "B.SilkS")
		)
		(fp_line
			(start -0.67945 -0.3048)
			(end -0.67945 0.3048)
			(stroke
				(width 0.1)
				(type default)
			)
			(layer "B.Fab")
		)
		(fp_line
			(start -0.67945 0.3048)
			(end -0.120396 0.3048)
			(stroke
				(width 0.1)
				(type default)
			)
			(layer "B.Fab")
		)
		(fp_line
			(start -0.12065 -0.3048)
			(end -0.67945 -0.3048)
			(stroke
				(width 0.1)
				(type default)
			)
			(layer "B.Fab")
		)
		(fp_line
			(start -0.12065 -0.2794)
			(end -0.12065 -0.3048)
			(stroke
				(width 0.1)
				(type default)
			)
			(layer "B.Fab")
		)
		(fp_line
			(start -0.120396 0.2794)
			(end 0.12065 0.2794)
			(stroke
				(width 0.1)
				(type default)
			)
			(layer "B.Fab")
		)
		(fp_line
			(start -0.120396 0.3048)
			(end -0.120396 0.2794)
			(stroke
				(width 0.1)
				(type default)
			)
			(layer "B.Fab")
		)
		(fp_line
			(start 0.12065 -0.305054)
			(end 0.12065 -0.2794)
			(stroke
				(width 0.1)
				(type default)
			)
			(layer "B.Fab")
		)
		(fp_line
			(start 0.12065 -0.2794)
			(end -0.12065 -0.2794)
			(stroke
				(width 0.1)
				(type default)
			)
			(layer "B.Fab")
		)
		(fp_line
			(start 0.12065 0.2794)
			(end 0.12065 0.3048)
			(stroke
				(width 0.1)
				(type default)
			)
			(layer "B.Fab")
		)
		(fp_line
			(start 0.12065 0.3048)
			(end 0.67945 0.3048)
			(stroke
				(width 0.1)
				(type default)
			)
			(layer "B.Fab")
		)
		(fp_line
			(start 0.67945 -0.305054)
			(end 0.12065 -0.305054)
			(stroke
				(width 0.1)
				(type default)
			)
			(layer "B.Fab")
		)
		(fp_line
			(start 0.67945 0.3048)
			(end 0.67945 -0.305054)
			(stroke
				(width 0.1)
				(type default)
			)
			(layer "B.Fab")
		)
		(pad "1" smd rect
			(at 0.40005 0)
			(size 0.4572 0.508)
			(layers "B.Cu" "B.Mask" "B.Paste")
			(net "SMB_APML_CPU0_R_SCL")
		)
		(pad "2" smd rect
			(at -0.40005 0)
			(size 0.4572 0.508)
			(layers "B.Cu" "B.Mask" "B.Paste")
			(net "SMB_APML_CPU0_SCL")
		)
	)
	(footprint ""
		(layer "B.Cu")
		(at 98.592386 -256.734564 180)
		(property "Reference" "C2104"
			(at 0 0 0)
			(layer "B.SilkS")
			(hide yes)
			(effects
				(font
					(size 1.27 1.27)
				)
				(justify mirror)
			)
		)
		(property "Value" ""
			(at 0 0 0)
			(layer "B.Fab")
			(effects
				(font
					(size 1.27 1.27)
				)
				(justify mirror)
			)
		)
		(duplicate_pad_numbers_are_jumpers no)
		(fp_line
			(start 0.7874 0.4064)
			(end 0.7874 -0.4064)
			(stroke
				(width 0.1524)
				(type default)
			)
			(layer "B.SilkS")
		)
		(fp_line
			(start 0.7874 -0.4064)
			(end -0.7874 -0.4064)
			(stroke
				(width 0.1524)
				(type default)
			)
			(layer "B.SilkS")
		)
		(fp_line
			(start -0.7874 0.4064)
			(end 0.7874 0.4064)
			(stroke
				(width 0.1524)
				(type default)
			)
			(layer "B.SilkS")
		)
		(fp_line
			(start -0.7874 -0.4064)
			(end -0.7874 0.4064)
			(stroke
				(width 0.1524)
				(type default)
			)
			(layer "B.SilkS")
		)
		(fp_line
			(start 0.67945 0.3048)
			(end 0.67945 -0.305054)
			(stroke
				(width 0.1)
				(type default)
			)
			(layer "B.Fab")
		)
		(fp_line
			(start 0.67945 -0.305054)
			(end 0.12065 -0.305054)
			(stroke
				(width 0.1)
				(type default)
			)
			(layer "B.Fab")
		)
		(fp_line
			(start 0.12065 0.3048)
			(end 0.67945 0.3048)
			(stroke
				(width 0.1)
				(type default)
			)
			(layer "B.Fab")
		)
		(fp_line
			(start 0.12065 0.2794)
			(end 0.12065 0.3048)
			(stroke
				(width 0.1)
				(type default)
			)
			(layer "B.Fab")
		)
		(fp_line
			(start 0.12065 -0.2794)
			(end -0.12065 -0.2794)
			(stroke
				(width 0.1)
				(type default)
			)
			(layer "B.Fab")
		)
		(fp_line
			(start 0.12065 -0.305054)
			(end 0.12065 -0.2794)
			(stroke
				(width 0.1)
				(type default)
			)
			(layer "B.Fab")
		)
		(fp_line
			(start -0.120396 0.3048)
			(end -0.120396 0.2794)
			(stroke
				(width 0.1)
				(type default)
			)
			(layer "B.Fab")
		)
		(fp_line
			(start -0.120396 0.2794)
			(end 0.12065 0.2794)
			(stroke
				(width 0.1)
				(type default)
			)
			(layer "B.Fab")
		)
		(fp_line
			(start -0.12065 -0.2794)
			(end -0.12065 -0.3048)
			(stroke
				(width 0.1)
				(type default)
			)
			(layer "B.Fab")
		)
		(fp_line
			(start -0.12065 -0.3048)
			(end -0.67945 -0.3048)
			(stroke
				(width 0.1)
				(type default)
			)
			(layer "B.Fab")
		)
		(fp_line
			(start -0.67945 0.3048)
			(end -0.120396 0.3048)
			(stroke
				(width 0.1)
				(type default)
			)
			(layer "B.Fab")
		)
		(fp_line
			(start -0.67945 -0.3048)
			(end -0.67945 0.3048)
			(stroke
				(width 0.1)
				(type default)
			)
			(layer "B.Fab")
		)
		(pad "1" smd circle
			(at 0.40005 0)
			(size 0 0)
			(layers "B.Cu" "B.Mask" "B.Paste")
			(net "PVDDIO_P1")
		)
		(pad "2" smd circle
			(at -0.40005 0)
			(size 0 0)
			(layers "B.Cu" "B.Mask" "B.Paste")
			(net "GND")
		)
	)
	(footprint ""
		(layer "B.Cu")
		(at 218.059 -336.296 180)
		(property "Reference" "R6736"
			(at 0 0 0)
			(layer "B.SilkS")
			(hide yes)
			(effects
				(font
					(size 1.27 1.27)
				)
				(justify mirror)
			)
		)
		(property "Value" ""
			(at 0 0 0)
			(layer "B.Fab")
			(effects
				(font
					(size 1.27 1.27)
				)
				(justify mirror)
			)
		)
		(duplicate_pad_numbers_are_jumpers no)
		(fp_line
			(start 0.32512 0.175006)
			(end 0.32512 -0.175006)
			(stroke
				(width 0.1)
				(type default)
			)
			(layer "B.Fab")
		)
		(fp_line
			(start 0.32512 -0.175006)
			(end -0.32512 -0.175006)
			(stroke
				(width 0.1)
				(type default)
			)
			(layer "B.Fab")
		)
		(fp_line
			(start -0.32512 0.175006)
			(end 0.32512 0.175006)
			(stroke
				(width 0.1)
				(type default)
			)
			(layer "B.Fab")
		)
		(fp_line
			(start -0.32512 -0.175006)
			(end -0.32512 0.175006)
			(stroke
				(width 0.1)
				(type default)
			)
			(layer "B.Fab")
		)
		(pad "1" smd rect
			(at 0.2667 0)
			(size 0.3048 0.381)
			(layers "B.Cu" "B.Mask" "B.Paste")
			(net "SMB_RT_CPU1_P1_R_SDA")
		)
		(pad "2" smd rect
			(at -0.2667 0 180)
			(size 0.3048 0.381)
			(layers "B.Cu" "B.Mask" "B.Paste")
			(net "SMB_RT_CPU1_P1_SDA")
		)
	)
	(footprint ""
		(layer "B.Cu")
		(at 374.0785 -395.148562 90)
		(property "Reference" "C1024"
			(at 0 0 90)
			(layer "B.SilkS")
			(hide yes)
			(effects
				(font
					(size 1.27 1.27)
				)
				(justify mirror)
			)
		)
		(property "Value" ""
			(at 0 0 90)
			(layer "B.Fab")
			(effects
				(font
					(size 1.27 1.27)
				)
				(justify mirror)
			)
		)
		(duplicate_pad_numbers_are_jumpers no)
		(fp_line
			(start 0.299974 -0.150114)
			(end -0.299974 -0.150114)
			(stroke
				(width 0.1)
				(type default)
			)
			(layer "B.Fab")
		)
		(fp_line
			(start -0.299974 -0.150114)
			(end -0.299974 0.150114)
			(stroke
				(width 0.1)
				(type default)
			)
			(layer "B.Fab")
		)
		(fp_line
			(start 0.299974 0.150114)
			(end 0.299974 -0.150114)
			(stroke
				(width 0.1)
				(type default)
			)
			(layer "B.Fab")
		)
		(fp_line
			(start -0.299974 0.150114)
			(end 0.299974 0.150114)
			(stroke
				(width 0.1)
				(type default)
			)
			(layer "B.Fab")
		)
		(pad "1" smd rect
			(at 0.2667 0 270)
			(size 0.3048 0.381)
			(layers "B.Cu" "B.Mask" "B.Paste")
			(net "P0V9_CPU0_RT3_2A")
		)
		(pad "2" smd rect
			(at -0.2667 0 270)
			(size 0.3048 0.381)
			(layers "B.Cu" "B.Mask" "B.Paste")
			(net "GND")
		)
	)
	(footprint ""
		(layer "B.Cu")
		(at 308.1782 -395.148562 90)
		(property "Reference" "C542"
			(at 0 0 90)
			(layer "B.SilkS")
			(hide yes)
			(effects
				(font
					(size 1.27 1.27)
				)
				(justify mirror)
			)
		)
		(property "Value" ""
			(at 0 0 90)
			(layer "B.Fab")
			(effects
				(font
					(size 1.27 1.27)
				)
				(justify mirror)
			)
		)
		(duplicate_pad_numbers_are_jumpers no)
		(fp_line
			(start 0.299974 -0.150114)
			(end -0.299974 -0.150114)
			(stroke
				(width 0.1)
				(type default)
			)
			(layer "B.Fab")
		)
		(fp_line
			(start -0.299974 -0.150114)
			(end -0.299974 0.150114)
			(stroke
				(width 0.1)
				(type default)
			)
			(layer "B.Fab")
		)
		(fp_line
			(start 0.299974 0.150114)
			(end 0.299974 -0.150114)
			(stroke
				(width 0.1)
				(type default)
			)
			(layer "B.Fab")
		)
		(fp_line
			(start -0.299974 0.150114)
			(end 0.299974 0.150114)
			(stroke
				(width 0.1)
				(type default)
			)
			(layer "B.Fab")
		)
		(pad "1" smd rect
			(at 0.2667 0 270)
			(size 0.3048 0.381)
			(layers "B.Cu" "B.Mask" "B.Paste")
			(net "P0V9_CPU0_RT0_2A_2D")
		)
		(pad "2" smd rect
			(at -0.2667 0 270)
			(size 0.3048 0.381)
			(layers "B.Cu" "B.Mask" "B.Paste")
			(net "GND")
		)
	)
	(footprint ""
		(layer "B.Cu")
		(at 358.796082 -259.845048 180)
		(property "Reference" "C2621"
			(at 0 0 0)
			(layer "B.SilkS")
			(hide yes)
			(effects
				(font
					(size 1.27 1.27)
				)
				(justify mirror)
			)
		)
		(property "Value" ""
			(at 0 0 0)
			(layer "B.Fab")
			(effects
				(font
					(size 1.27 1.27)
				)
				(justify mirror)
			)
		)
		(duplicate_pad_numbers_are_jumpers no)
		(fp_line
			(start 0.7874 0.4064)
			(end 0.7874 -0.4064)
			(stroke
				(width 0.1524)
				(type default)
			)
			(layer "B.SilkS")
		)
		(fp_line
			(start 0.7874 -0.4064)
			(end -0.7874 -0.4064)
			(stroke
				(width 0.1524)
				(type default)
			)
			(layer "B.SilkS")
		)
		(fp_line
			(start -0.7874 0.4064)
			(end 0.7874 0.4064)
			(stroke
				(width 0.1524)
				(type default)
			)
			(layer "B.SilkS")
		)
		(fp_line
			(start -0.7874 -0.4064)
			(end -0.7874 0.4064)
			(stroke
				(width 0.1524)
				(type default)
			)
			(layer "B.SilkS")
		)
		(fp_line
			(start 0.67945 0.3048)
			(end 0.67945 -0.305054)
			(stroke
				(width 0.1)
				(type default)
			)
			(layer "B.Fab")
		)
		(fp_line
			(start 0.67945 -0.305054)
			(end 0.12065 -0.305054)
			(stroke
				(width 0.1)
				(type default)
			)
			(layer "B.Fab")
		)
		(fp_line
			(start 0.12065 0.3048)
			(end 0.67945 0.3048)
			(stroke
				(width 0.1)
				(type default)
			)
			(layer "B.Fab")
		)
		(fp_line
			(start 0.12065 0.2794)
			(end 0.12065 0.3048)
			(stroke
				(width 0.1)
				(type default)
			)
			(layer "B.Fab")
		)
		(fp_line
			(start 0.12065 -0.2794)
			(end -0.12065 -0.2794)
			(stroke
				(width 0.1)
				(type default)
			)
			(layer "B.Fab")
		)
		(fp_line
			(start 0.12065 -0.305054)
			(end 0.12065 -0.2794)
			(stroke
				(width 0.1)
				(type default)
			)
			(layer "B.Fab")
		)
		(fp_line
			(start -0.120396 0.3048)
			(end -0.120396 0.2794)
			(stroke
				(width 0.1)
				(type default)
			)
			(layer "B.Fab")
		)
		(fp_line
			(start -0.120396 0.2794)
			(end 0.12065 0.2794)
			(stroke
				(width 0.1)
				(type default)
			)
			(layer "B.Fab")
		)
		(fp_line
			(start -0.12065 -0.2794)
			(end -0.12065 -0.3048)
			(stroke
				(width 0.1)
				(type default)
			)
			(layer "B.Fab")
		)
		(fp_line
			(start -0.12065 -0.3048)
			(end -0.67945 -0.3048)
			(stroke
				(width 0.1)
				(type default)
			)
			(layer "B.Fab")
		)
		(fp_line
			(start -0.67945 0.3048)
			(end -0.120396 0.3048)
			(stroke
				(width 0.1)
				(type default)
			)
			(layer "B.Fab")
		)
		(fp_line
			(start -0.67945 -0.3048)
			(end -0.67945 0.3048)
			(stroke
				(width 0.1)
				(type default)
			)
			(layer "B.Fab")
		)
		(pad "1" smd circle
			(at 0.40005 0)
			(size 0 0)
			(layers "B.Cu" "B.Mask" "B.Paste")
			(net "PVDD11_S3_P0")
		)
		(pad "2" smd circle
			(at -0.40005 0)
			(size 0 0)
			(layers "B.Cu" "B.Mask" "B.Paste")
			(net "GND")
		)
	)
	(footprint ""
		(layer "B.Cu")
		(at 48.65624 -432.954938)
		(property "Reference" "Q101"
			(at -1.126998 -1.815846 0)
			(unlocked yes)
			(layer "B.SilkS")
			(effects
				(font
					(size 0.7874 0.5842)
					(thickness 0.1524)
				)
				(justify left mirror)
			)
		)
		(property "Value" ""
			(at 0 0 0)
			(layer "B.Fab")
			(effects
				(font
					(size 1.27 1.27)
				)
				(justify mirror)
			)
		)
		(duplicate_pad_numbers_are_jumpers no)
		(fp_line
			(start -1.332738 -1.100074)
			(end -1.332738 1.100074)
			(stroke
				(width 0.1524)
				(type default)
			)
			(layer "B.SilkS")
		)
		(fp_line
			(start -1.332738 1.100074)
			(end 1.332738 1.100074)
			(stroke
				(width 0.1524)
				(type default)
			)
			(layer "B.SilkS")
		)
		(fp_line
			(start -0.4826 -1.100074)
			(end -1.332738 -1.100074)
			(stroke
				(width 0.1524)
				(type default)
			)
			(layer "B.SilkS")
		)
		(fp_line
			(start 0 -0.541274)
			(end -0.4826 -1.100074)
			(stroke
				(width 0.1524)
				(type default)
			)
			(layer "B.SilkS")
		)
		(fp_line
			(start 0.4826 -1.100074)
			(end 0 -0.541274)
			(stroke
				(width 0.1524)
				(type default)
			)
			(layer "B.SilkS")
		)
		(fp_line
			(start 1.332738 -1.100074)
			(end 0.4826 -1.100074)
			(stroke
				(width 0.1524)
				(type default)
			)
			(layer "B.SilkS")
		)
		(fp_line
			(start 1.332738 1.100074)
			(end 1.332738 -1.100074)
			(stroke
				(width 0.1524)
				(type default)
			)
			(layer "B.SilkS")
		)
		(fp_poly
			(pts
				(xy 1.533144 -0.649986) (xy 2.2352 -0.298958) (xy 2.2352 -1.001014)
			)
			(stroke
				(width 0)
				(type default)
			)
			(fill yes)
			(layer "B.SilkS")
		)
		(fp_line
			(start -0.674878 -1.100074)
			(end -0.674878 1.100074)
			(stroke
				(width 0.1)
				(type default)
			)
			(layer "B.Fab")
		)
		(fp_line
			(start -0.674878 1.100074)
			(end 0.674878 1.100074)
			(stroke
				(width 0.1)
				(type default)
			)
			(layer "B.Fab")
		)
		(fp_line
			(start 0.674878 -1.100074)
			(end -0.674878 -1.100074)
			(stroke
				(width 0.1)
				(type default)
			)
			(layer "B.Fab")
		)
		(fp_line
			(start 0.674878 1.100074)
			(end 0.674878 -1.100074)
			(stroke
				(width 0.1)
				(type default)
			)
			(layer "B.Fab")
		)
		(fp_poly
			(pts
				(xy 2.2352 -0.298958) (xy 2.2352 -1.001014) (xy 1.533144 -0.649986)
			)
			(stroke
				(width 0)
				(type default)
			)
			(fill yes)
			(layer "B.Fab")
		)
		(pad "1" smd rect
			(at 0.94996 -0.649986 90)
			(size 0.4318 0.508)
			(layers "B.Cu" "B.Mask" "B.Paste")
			(net "GND")
		)
		(pad "2" smd rect
			(at 0.94996 0 90)
			(size 0.4318 0.508)
			(layers "B.Cu" "B.Mask" "B.Paste")
			(net "GPU_FPGA_THERM_OVERT_N")
		)
		(pad "3" smd rect
			(at 0.94996 0.649986 90)
			(size 0.4318 0.508)
			(layers "B.Cu" "B.Mask" "B.Paste")
			(net "GPU_FPGA_THERM_OVERT_ISO_N")
		)
		(pad "4" smd rect
			(at -0.94996 0.649986 90)
			(size 0.4318 0.508)
			(layers "B.Cu" "B.Mask" "B.Paste")
			(net "GND")
		)
		(pad "5" smd rect
			(at -0.94996 0 90)
			(size 0.4318 0.508)
			(layers "B.Cu" "B.Mask" "B.Paste")
			(net "GPU_FPGA_THERM_OVERT")
		)
		(pad "6" smd rect
			(at -0.94996 -0.649986 90)
			(size 0.4318 0.508)
			(layers "B.Cu" "B.Mask" "B.Paste")
			(net "GPU_FPGA_THERM_OVERT")
		)
	)
	(footprint ""
		(layer "B.Cu")
		(at 417.595558 -389.49503)
		(property "Reference" "C7014"
			(at 2.26314 2.989072 0)
			(unlocked yes)
			(layer "B.SilkS")
			(effects
				(font
					(size 0.7874 0.5842)
					(thickness 0.1524)
				)
				(justify left mirror)
			)
		)
		(property "Value" ""
			(at 0 0 0)
			(layer "B.Fab")
			(effects
				(font
					(size 1.27 1.27)
				)
				(justify mirror)
			)
		)
		(duplicate_pad_numbers_are_jumpers no)
		(fp_line
			(start -4.53898 -2.15011)
			(end -4.53898 2.15011)
			(stroke
				(width 0.1524)
				(type default)
			)
			(layer "B.SilkS")
		)
		(fp_line
			(start -4.53898 2.15011)
			(end 4.53898 2.15011)
			(stroke
				(width 0.1524)
				(type default)
			)
			(layer "B.SilkS")
		)
		(fp_line
			(start 4.53898 -2.150618)
			(end 4.539742 2.152142)
			(stroke
				(width 0.1524)
				(type default)
			)
			(layer "B.SilkS")
		)
		(fp_line
			(start 4.53898 -2.15011)
			(end -4.53898 -2.15011)
			(stroke
				(width 0.1524)
				(type default)
			)
			(layer "B.SilkS")
		)
		(fp_line
			(start 4.53898 2.15011)
			(end 4.53898 -2.15011)
			(stroke
				(width 0.1524)
				(type default)
			)
			(layer "B.SilkS")
		)
		(fp_line
			(start 4.69138 -2.150618)
			(end 4.692396 2.161032)
			(stroke
				(width 0.1524)
				(type default)
			)
			(layer "B.SilkS")
		)
		(fp_line
			(start 4.83108 2.150364)
			(end 4.447794 2.149348)
			(stroke
				(width 0.1524)
				(type default)
			)
			(layer "B.SilkS")
		)
		(fp_line
			(start 4.84378 -2.150618)
			(end 4.53898 -2.150618)
			(stroke
				(width 0.1524)
				(type default)
			)
			(layer "B.SilkS")
		)
		(fp_line
			(start 4.84378 -2.150618)
			(end 4.842256 2.163064)
			(stroke
				(width 0.1524)
				(type default)
			)
			(layer "B.SilkS")
		)
		(fp_line
			(start -3.64998 -2.15011)
			(end -3.64998 2.15011)
			(stroke
				(width 0.1)
				(type default)
			)
			(layer "B.Fab")
		)
		(fp_line
			(start -3.64998 2.15011)
			(end 3.64998 2.15011)
			(stroke
				(width 0.1)
				(type default)
			)
			(layer "B.Fab")
		)
		(fp_line
			(start 3.64998 -2.15011)
			(end -3.64998 -2.15011)
			(stroke
				(width 0.1)
				(type default)
			)
			(layer "B.Fab")
		)
		(fp_line
			(start 3.64998 2.15011)
			(end 3.64998 -2.15011)
			(stroke
				(width 0.1)
				(type default)
			)
			(layer "B.Fab")
		)
		(fp_text user "-"
			(at -2.944114 2.239772 0)
			(unlocked yes)
			(layer "B.SilkS")
			(effects
				(font
					(size 1.905 1.4224)
					(thickness 0.1524)
				)
				(justify left mirror)
			)
		)
		(fp_text user "+"
			(at 6.214872 -0.337058 0)
			(unlocked yes)
			(layer "B.SilkS")
			(effects
				(font
					(size 1.905 1.4224)
					(thickness 0.1524)
				)
				(justify left mirror)
			)
		)
		(fp_text user "-"
			(at -4.313174 -0.094488 0)
			(unlocked yes)
			(layer "B.Fab")
			(effects
				(font
					(size 1.905 1.4224)
					(thickness 0.1524)
				)
				(justify left mirror)
			)
		)
		(fp_text user "+"
			(at 6.214872 -0.337058 0)
			(unlocked yes)
			(layer "B.Fab")
			(effects
				(font
					(size 1.905 1.4224)
					(thickness 0.1524)
				)
				(justify left mirror)
			)
		)
		(pad "1" smd rect
			(at 3.199892 0 180)
			(size 2.413 2.8194)
			(layers "B.Cu" "B.Mask" "B.Paste")
			(net "P0V9_CPU0_RT2_2A")
		)
		(pad "2" smd rect
			(at -3.199892 0 180)
			(size 2.413 2.8194)
			(layers "B.Cu" "B.Mask" "B.Paste")
			(net "GND")
		)
	)
	(footprint ""
		(layer "B.Cu")
		(at 123.126754 -171.910248 90)
		(property "Reference" "PC337"
			(at 5.774436 1.227074 270)
			(unlocked yes)
			(layer "B.SilkS")
			(effects
				(font
					(size 0.7874 0.5842)
					(thickness 0.1524)
				)
				(justify left mirror)
			)
		)
		(property "Value" ""
			(at 0 0 90)
			(layer "B.Fab")
			(effects
				(font
					(size 1.27 1.27)
				)
				(justify mirror)
			)
		)
		(duplicate_pad_numbers_are_jumpers no)
		(fp_line
			(start 4.533392 -2.249932)
			(end -4.533392 -2.249932)
			(stroke
				(width 0.1524)
				(type default)
			)
			(layer "B.SilkS")
		)
		(fp_line
			(start -4.533392 -2.249932)
			(end -4.533392 2.249932)
			(stroke
				(width 0.1524)
				(type default)
			)
			(layer "B.SilkS")
		)
		(fp_line
			(start 4.533392 2.249932)
			(end 4.533392 -2.249932)
			(stroke
				(width 0.1524)
				(type default)
			)
			(layer "B.SilkS")
		)
		(fp_line
			(start -4.533392 2.249932)
			(end 4.533392 2.249932)
			(stroke
				(width 0.1524)
				(type default)
			)
			(layer "B.SilkS")
		)
		(fp_rect
			(start 4.533392 -2.326132)
			(end 5.39242 2.326132)
			(stroke
				(width 0)
				(type default)
			)
			(fill yes)
			(layer "B.SilkS")
		)
		(fp_line
			(start 3.750056 -2.249932)
			(end -3.750056 -2.249932)
			(stroke
				(width 0.1)
				(type default)
			)
			(layer "B.Fab")
		)
		(fp_line
			(start -3.750056 -2.249932)
			(end -3.750056 2.249932)
			(stroke
				(width 0.1)
				(type default)
			)
			(layer "B.Fab")
		)
		(fp_line
			(start 3.750056 2.249932)
			(end 3.750056 -2.249932)
			(stroke
				(width 0.1)
				(type default)
			)
			(layer "B.Fab")
		)
		(fp_line
			(start -3.750056 2.249932)
			(end 3.750056 2.249932)
			(stroke
				(width 0.1)
				(type default)
			)
			(layer "B.Fab")
		)
		(fp_text user "+"
			(at 6.322314 0.786384 0)
			(unlocked yes)
			(layer "B.SilkS")
			(effects
				(font
					(size 1.905 1.4224)
					(thickness 0.1524)
				)
				(justify left mirror)
			)
		)
		(fp_text user "-"
			(at -4.732274 1.216152 90)
			(unlocked yes)
			(layer "B.SilkS")
			(effects
				(font
					(size 1.905 1.4224)
					(thickness 0.1524)
				)
				(justify left mirror)
			)
		)
		(fp_text user "-"
			(at -4.8514 -0.14605 90)
			(unlocked yes)
			(layer "B.Fab")
			(effects
				(font
					(size 1.905 1.4224)
					(thickness 0.1524)
				)
				(justify left mirror)
			)
		)
		(fp_text user "+"
			(at 6.322314 0.786384 0)
			(unlocked yes)
			(layer "B.Fab")
			(effects
				(font
					(size 1.905 1.4224)
					(thickness 0.1524)
				)
				(justify left mirror)
			)
		)
		(pad "1" smd rect
			(at 3.199892 0 270)
			(size 2.413 2.8194)
			(layers "B.Cu" "B.Mask" "B.Paste")
			(net "PVDDCR_SOC_P1")
		)
		(pad "2" smd rect
			(at -3.199892 0 270)
			(size 2.413 2.8194)
			(layers "B.Cu" "B.Mask" "B.Paste")
			(net "GND")
		)
	)
	(footprint ""
		(layer "B.Cu")
		(at 425.896532 -358.570276)
		(property "Reference" "PC8005"
			(at 0 0 0)
			(layer "B.SilkS")
			(hide yes)
			(effects
				(font
					(size 1.27 1.27)
				)
				(justify mirror)
			)
		)
		(property "Value" ""
			(at 0 0 0)
			(layer "B.Fab")
			(effects
				(font
					(size 1.27 1.27)
				)
				(justify mirror)
			)
		)
		(duplicate_pad_numbers_are_jumpers no)
		(fp_line
			(start -1.524 -0.762)
			(end -1.524 0.762)
			(stroke
				(width 0.1524)
				(type default)
			)
			(layer "B.SilkS")
		)
		(fp_line
			(start -1.524 0.762)
			(end 1.524 0.762)
			(stroke
				(width 0.1524)
				(type default)
			)
			(layer "B.SilkS")
		)
		(fp_line
			(start 1.524 -0.762)
			(end -1.524 -0.762)
			(stroke
				(width 0.1524)
				(type default)
			)
			(layer "B.SilkS")
		)
		(fp_line
			(start 1.524 0.762)
			(end 1.524 -0.762)
			(stroke
				(width 0.1524)
				(type default)
			)
			(layer "B.SilkS")
		)
		(fp_line
			(start -1.1049 -0.724916)
			(end 1.1049 -0.724916)
			(stroke
				(width 0.1)
				(type default)
			)
			(layer "B.Fab")
		)
		(fp_line
			(start -1.1049 0.724916)
			(end -1.1049 -0.724916)
			(stroke
				(width 0.1)
				(type default)
			)
			(layer "B.Fab")
		)
		(fp_line
			(start 1.1049 -0.724916)
			(end 1.1049 0.724916)
			(stroke
				(width 0.1)
				(type default)
			)
			(layer "B.Fab")
		)
		(fp_line
			(start 1.1049 0.724916)
			(end -1.1049 0.724916)
			(stroke
				(width 0.1)
				(type default)
			)
			(layer "B.Fab")
		)
		(pad "1" smd rect
			(at 0.889 0)
			(size 1.016 1.27)
			(layers "B.Cu" "B.Mask" "B.Paste")
			(net "SW_P12V_AUX_PVDD11_S3_P0_FLT")
		)
		(pad "2" smd rect
			(at -0.889 0)
			(size 1.016 1.27)
			(layers "B.Cu" "B.Mask" "B.Paste")
			(net "GND")
		)
	)
	(footprint ""
		(layer "B.Cu")
		(at 301.388272 -425.498768 180)
		(property "Reference" "R667"
			(at 0 0 0)
			(layer "B.SilkS")
			(hide yes)
			(effects
				(font
					(size 1.27 1.27)
				)
				(justify mirror)
			)
		)
		(property "Value" ""
			(at 0 0 0)
			(layer "B.Fab")
			(effects
				(font
					(size 1.27 1.27)
				)
				(justify mirror)
			)
		)
		(duplicate_pad_numbers_are_jumpers no)
		(fp_line
			(start 0.32512 0.175006)
			(end 0.32512 -0.175006)
			(stroke
				(width 0.1)
				(type default)
			)
			(layer "B.Fab")
		)
		(fp_line
			(start 0.32512 -0.175006)
			(end -0.32512 -0.175006)
			(stroke
				(width 0.1)
				(type default)
			)
			(layer "B.Fab")
		)
		(fp_line
			(start -0.32512 0.175006)
			(end 0.32512 0.175006)
			(stroke
				(width 0.1)
				(type default)
			)
			(layer "B.Fab")
		)
		(fp_line
			(start -0.32512 -0.175006)
			(end -0.32512 0.175006)
			(stroke
				(width 0.1)
				(type default)
			)
			(layer "B.Fab")
		)
		(pad "1" smd rect
			(at 0.2667 0)
			(size 0.3048 0.381)
			(layers "B.Cu" "B.Mask" "B.Paste")
			(net "SMB_RT_CPU0_P0_ROM_MUX_1D_SDA")
		)
		(pad "2" smd rect
			(at -0.2667 0 180)
			(size 0.3048 0.381)
			(layers "B.Cu" "B.Mask" "B.Paste")
			(net "SMB_RT_CPU0_P0_ROM_MUX_1D_R_SDA")
		)
	)
	(footprint ""
		(layer "B.Cu")
		(at 121.066306 -79.737458 90)
		(property "Reference" "R6245"
			(at 0 0 90)
			(layer "B.SilkS")
			(hide yes)
			(effects
				(font
					(size 1.27 1.27)
				)
				(justify mirror)
			)
		)
		(property "Value" ""
			(at 0 0 90)
			(layer "B.Fab")
			(effects
				(font
					(size 1.27 1.27)
				)
				(justify mirror)
			)
		)
		(duplicate_pad_numbers_are_jumpers no)
		(fp_line
			(start 0.7874 -0.4064)
			(end -0.7874 -0.4064)
			(stroke
				(width 0.1524)
				(type default)
			)
			(layer "B.SilkS")
		)
		(fp_line
			(start -0.7874 -0.4064)
			(end -0.7874 0.4064)
			(stroke
				(width 0.1524)
				(type default)
			)
			(layer "B.SilkS")
		)
		(fp_line
			(start 0.7874 0.4064)
			(end 0.7874 -0.4064)
			(stroke
				(width 0.1524)
				(type default)
			)
			(layer "B.SilkS")
		)
		(fp_line
			(start -0.7874 0.4064)
			(end 0.7874 0.4064)
			(stroke
				(width 0.1524)
				(type default)
			)
			(layer "B.SilkS")
		)
		(fp_line
			(start 0.67945 -0.305054)
			(end 0.12065 -0.305054)
			(stroke
				(width 0.1)
				(type default)
			)
			(layer "B.Fab")
		)
		(fp_line
			(start 0.12065 -0.305054)
			(end 0.12065 -0.2794)
			(stroke
				(width 0.1)
				(type default)
			)
			(layer "B.Fab")
		)
		(fp_line
			(start -0.12065 -0.3048)
			(end -0.67945 -0.3048)
			(stroke
				(width 0.1)
				(type default)
			)
			(layer "B.Fab")
		)
		(fp_line
			(start -0.67945 -0.3048)
			(end -0.67945 0.3048)
			(stroke
				(width 0.1)
				(type default)
			)
			(layer "B.Fab")
		)
		(fp_line
			(start 0.12065 -0.2794)
			(end -0.12065 -0.2794)
			(stroke
				(width 0.1)
				(type default)
			)
			(layer "B.Fab")
		)
		(fp_line
			(start -0.12065 -0.2794)
			(end -0.12065 -0.3048)
			(stroke
				(width 0.1)
				(type default)
			)
			(layer "B.Fab")
		)
		(fp_line
			(start 0.12065 0.2794)
			(end 0.12065 0.3048)
			(stroke
				(width 0.1)
				(type default)
			)
			(layer "B.Fab")
		)
		(fp_line
			(start -0.120396 0.2794)
			(end 0.12065 0.2794)
			(stroke
				(width 0.1)
				(type default)
			)
			(layer "B.Fab")
		)
		(fp_line
			(start 0.67945 0.3048)
			(end 0.67945 -0.305054)
			(stroke
				(width 0.1)
				(type default)
			)
			(layer "B.Fab")
		)
		(fp_line
			(start 0.12065 0.3048)
			(end 0.67945 0.3048)
			(stroke
				(width 0.1)
				(type default)
			)
			(layer "B.Fab")
		)
		(fp_line
			(start -0.120396 0.3048)
			(end -0.120396 0.2794)
			(stroke
				(width 0.1)
				(type default)
			)
			(layer "B.Fab")
		)
		(fp_line
			(start -0.67945 0.3048)
			(end -0.120396 0.3048)
			(stroke
				(width 0.1)
				(type default)
			)
			(layer "B.Fab")
		)
		(pad "1" smd circle
			(at 0.40005 0 270)
			(size 0 0)
			(layers "B.Cu" "B.Mask" "B.Paste")
			(net "P3V3_AUX")
		)
		(pad "2" smd circle
			(at -0.40005 0 270)
			(size 0 0)
			(layers "B.Cu" "B.Mask" "B.Paste")
			(net "P1V2_AUX_VCC")
		)
	)
	(footprint ""
		(layer "B.Cu")
		(at 237.88116 -328.724514)
		(property "Reference" "R1236"
			(at 0 0 0)
			(layer "B.SilkS")
			(hide yes)
			(effects
				(font
					(size 1.27 1.27)
				)
				(justify mirror)
			)
		)
		(property "Value" ""
			(at 0 0 0)
			(layer "B.Fab")
			(effects
				(font
					(size 1.27 1.27)
				)
				(justify mirror)
			)
		)
		(duplicate_pad_numbers_are_jumpers no)
		(fp_line
			(start -0.7874 -0.4064)
			(end -0.7874 0.4064)
			(stroke
				(width 0.1524)
				(type default)
			)
			(layer "B.SilkS")
		)
		(fp_line
			(start -0.7874 0.4064)
			(end 0.7874 0.4064)
			(stroke
				(width 0.1524)
				(type default)
			)
			(layer "B.SilkS")
		)
		(fp_line
			(start 0.7874 -0.4064)
			(end -0.7874 -0.4064)
			(stroke
				(width 0.1524)
				(type default)
			)
			(layer "B.SilkS")
		)
		(fp_line
			(start 0.7874 0.4064)
			(end 0.7874 -0.4064)
			(stroke
				(width 0.1524)
				(type default)
			)
			(layer "B.SilkS")
		)
		(fp_line
			(start -0.67945 -0.3048)
			(end -0.67945 0.3048)
			(stroke
				(width 0.1)
				(type default)
			)
			(layer "B.Fab")
		)
		(fp_line
			(start -0.67945 0.3048)
			(end -0.120396 0.3048)
			(stroke
				(width 0.1)
				(type default)
			)
			(layer "B.Fab")
		)
		(fp_line
			(start -0.12065 -0.3048)
			(end -0.67945 -0.3048)
			(stroke
				(width 0.1)
				(type default)
			)
			(layer "B.Fab")
		)
		(fp_line
			(start -0.12065 -0.2794)
			(end -0.12065 -0.3048)
			(stroke
				(width 0.1)
				(type default)
			)
			(layer "B.Fab")
		)
		(fp_line
			(start -0.120396 0.2794)
			(end 0.12065 0.2794)
			(stroke
				(width 0.1)
				(type default)
			)
			(layer "B.Fab")
		)
		(fp_line
			(start -0.120396 0.3048)
			(end -0.120396 0.2794)
			(stroke
				(width 0.1)
				(type default)
			)
			(layer "B.Fab")
		)
		(fp_line
			(start 0.12065 -0.305054)
			(end 0.12065 -0.2794)
			(stroke
				(width 0.1)
				(type default)
			)
			(layer "B.Fab")
		)
		(fp_line
			(start 0.12065 -0.2794)
			(end -0.12065 -0.2794)
			(stroke
				(width 0.1)
				(type default)
			)
			(layer "B.Fab")
		)
		(fp_line
			(start 0.12065 0.2794)
			(end 0.12065 0.3048)
			(stroke
				(width 0.1)
				(type default)
			)
			(layer "B.Fab")
		)
		(fp_line
			(start 0.12065 0.3048)
			(end 0.67945 0.3048)
			(stroke
				(width 0.1)
				(type default)
			)
			(layer "B.Fab")
		)
		(fp_line
			(start 0.67945 -0.305054)
			(end 0.12065 -0.305054)
			(stroke
				(width 0.1)
				(type default)
			)
			(layer "B.Fab")
		)
		(fp_line
			(start 0.67945 0.3048)
			(end 0.67945 -0.305054)
			(stroke
				(width 0.1)
				(type default)
			)
			(layer "B.Fab")
		)
		(pad "1" smd circle
			(at 0.40005 0 180)
			(size 0 0)
			(layers "B.Cu" "B.Mask" "B.Paste")
			(net "PVDD18_S5_P1")
		)
		(pad "2" smd circle
			(at -0.40005 0 180)
			(size 0 0)
			(layers "B.Cu" "B.Mask" "B.Paste")
			(net "PVDD18_S5_P1_ADC")
		)
	)
	(footprint ""
		(layer "B.Cu")
		(at 404.115778 -323.892672 180)
		(property "Reference" "R1593"
			(at 0 0 0)
			(layer "B.SilkS")
			(hide yes)
			(effects
				(font
					(size 1.27 1.27)
				)
				(justify mirror)
			)
		)
		(property "Value" ""
			(at 0 0 0)
			(layer "B.Fab")
			(effects
				(font
					(size 1.27 1.27)
				)
				(justify mirror)
			)
		)
		(duplicate_pad_numbers_are_jumpers no)
		(fp_line
			(start 0.7874 0.4064)
			(end 0.7874 -0.4064)
			(stroke
				(width 0.1524)
				(type default)
			)
			(layer "B.SilkS")
		)
		(fp_line
			(start 0.7874 -0.4064)
			(end -0.7874 -0.4064)
			(stroke
				(width 0.1524)
				(type default)
			)
			(layer "B.SilkS")
		)
		(fp_line
			(start -0.7874 0.4064)
			(end 0.7874 0.4064)
			(stroke
				(width 0.1524)
				(type default)
			)
			(layer "B.SilkS")
		)
		(fp_line
			(start -0.7874 -0.4064)
			(end -0.7874 0.4064)
			(stroke
				(width 0.1524)
				(type default)
			)
			(layer "B.SilkS")
		)
		(fp_line
			(start 0.67945 0.3048)
			(end 0.67945 -0.305054)
			(stroke
				(width 0.1)
				(type default)
			)
			(layer "B.Fab")
		)
		(fp_line
			(start 0.67945 -0.305054)
			(end 0.12065 -0.305054)
			(stroke
				(width 0.1)
				(type default)
			)
			(layer "B.Fab")
		)
		(fp_line
			(start 0.12065 0.3048)
			(end 0.67945 0.3048)
			(stroke
				(width 0.1)
				(type default)
			)
			(layer "B.Fab")
		)
		(fp_line
			(start 0.12065 0.2794)
			(end 0.12065 0.3048)
			(stroke
				(width 0.1)
				(type default)
			)
			(layer "B.Fab")
		)
		(fp_line
			(start 0.12065 -0.2794)
			(end -0.12065 -0.2794)
			(stroke
				(width 0.1)
				(type default)
			)
			(layer "B.Fab")
		)
		(fp_line
			(start 0.12065 -0.305054)
			(end 0.12065 -0.2794)
			(stroke
				(width 0.1)
				(type default)
			)
			(layer "B.Fab")
		)
		(fp_line
			(start -0.120396 0.3048)
			(end -0.120396 0.2794)
			(stroke
				(width 0.1)
				(type default)
			)
			(layer "B.Fab")
		)
		(fp_line
			(start -0.120396 0.2794)
			(end 0.12065 0.2794)
			(stroke
				(width 0.1)
				(type default)
			)
			(layer "B.Fab")
		)
		(fp_line
			(start -0.12065 -0.2794)
			(end -0.12065 -0.3048)
			(stroke
				(width 0.1)
				(type default)
			)
			(layer "B.Fab")
		)
		(fp_line
			(start -0.12065 -0.3048)
			(end -0.67945 -0.3048)
			(stroke
				(width 0.1)
				(type default)
			)
			(layer "B.Fab")
		)
		(fp_line
			(start -0.67945 0.3048)
			(end -0.120396 0.3048)
			(stroke
				(width 0.1)
				(type default)
			)
			(layer "B.Fab")
		)
		(fp_line
			(start -0.67945 -0.3048)
			(end -0.67945 0.3048)
			(stroke
				(width 0.1)
				(type default)
			)
			(layer "B.Fab")
		)
		(pad "1" smd rect
			(at 0.40005 0 180)
			(size 0.4572 0.508)
			(layers "B.Cu" "B.Mask" "B.Paste")
			(net "ESPI_CPU0_ALERT_P0_N")
		)
		(pad "2" smd rect
			(at -0.40005 0 180)
			(size 0.4572 0.508)
			(layers "B.Cu" "B.Mask" "B.Paste")
			(net "CPU0_ESPI0_ALERT_N")
		)
	)
	(footprint ""
		(layer "B.Cu")
		(at 239.903 -333.883)
		(property "Reference" "R1361"
			(at 0 0 0)
			(layer "B.SilkS")
			(hide yes)
			(effects
				(font
					(size 1.27 1.27)
				)
				(justify mirror)
			)
		)
		(property "Value" ""
			(at 0 0 0)
			(layer "B.Fab")
			(effects
				(font
					(size 1.27 1.27)
				)
				(justify mirror)
			)
		)
		(duplicate_pad_numbers_are_jumpers no)
		(fp_line
			(start -0.32512 -0.175006)
			(end -0.32512 0.175006)
			(stroke
				(width 0.1)
				(type default)
			)
			(layer "B.Fab")
		)
		(fp_line
			(start -0.32512 0.175006)
			(end 0.32512 0.175006)
			(stroke
				(width 0.1)
				(type default)
			)
			(layer "B.Fab")
		)
		(fp_line
			(start 0.32512 -0.175006)
			(end -0.32512 -0.175006)
			(stroke
				(width 0.1)
				(type default)
			)
			(layer "B.Fab")
		)
		(fp_line
			(start 0.32512 0.175006)
			(end 0.32512 -0.175006)
			(stroke
				(width 0.1)
				(type default)
			)
			(layer "B.Fab")
		)
		(pad "1" smd rect
			(at 0.2667 0 180)
			(size 0.3048 0.381)
			(layers "B.Cu" "B.Mask" "B.Paste")
			(net "P1V8_CPU1_RT_1D")
		)
		(pad "2" smd rect
			(at -0.2667 0)
			(size 0.3048 0.381)
			(layers "B.Cu" "B.Mask" "B.Paste")
			(net "SMB_RT_CPU1_P0_ROM_MUX_2D_R_SDA")
		)
	)
	(footprint ""
		(layer "B.Cu")
		(at 239.903 -339.598)
		(property "Reference" "R1402"
			(at 0 0 0)
			(layer "B.SilkS")
			(hide yes)
			(effects
				(font
					(size 1.27 1.27)
				)
				(justify mirror)
			)
		)
		(property "Value" ""
			(at 0 0 0)
			(layer "B.Fab")
			(effects
				(font
					(size 1.27 1.27)
				)
				(justify mirror)
			)
		)
		(duplicate_pad_numbers_are_jumpers no)
		(fp_line
			(start -0.32512 -0.175006)
			(end -0.32512 0.175006)
			(stroke
				(width 0.1)
				(type default)
			)
			(layer "B.Fab")
		)
		(fp_line
			(start -0.32512 0.175006)
			(end 0.32512 0.175006)
			(stroke
				(width 0.1)
				(type default)
			)
			(layer "B.Fab")
		)
		(fp_line
			(start 0.32512 -0.175006)
			(end -0.32512 -0.175006)
			(stroke
				(width 0.1)
				(type default)
			)
			(layer "B.Fab")
		)
		(fp_line
			(start 0.32512 0.175006)
			(end 0.32512 -0.175006)
			(stroke
				(width 0.1)
				(type default)
			)
			(layer "B.Fab")
		)
		(pad "1" smd rect
			(at 0.2667 0 180)
			(size 0.3048 0.381)
			(layers "B.Cu" "B.Mask" "B.Paste")
			(net "P1V8_CPU1_RT_1D")
		)
		(pad "2" smd rect
			(at -0.2667 0)
			(size 0.3048 0.381)
			(layers "B.Cu" "B.Mask" "B.Paste")
			(net "SMB_RT_CPU1_P3_ROM_MUX_2D_R_SCL")
		)
	)
	(footprint ""
		(layer "B.Cu")
		(at 228.4857 -324.349872 180)
		(property "Reference" "C1086"
			(at 0 0 0)
			(layer "B.SilkS")
			(hide yes)
			(effects
				(font
					(size 1.27 1.27)
				)
				(justify mirror)
			)
		)
		(property "Value" ""
			(at 0 0 0)
			(layer "B.Fab")
			(effects
				(font
					(size 1.27 1.27)
				)
				(justify mirror)
			)
		)
		(duplicate_pad_numbers_are_jumpers no)
		(fp_line
			(start 0.7874 0.4064)
			(end 0.7874 -0.4064)
			(stroke
				(width 0.1524)
				(type default)
			)
			(layer "B.SilkS")
		)
		(fp_line
			(start 0.7874 -0.4064)
			(end -0.7874 -0.4064)
			(stroke
				(width 0.1524)
				(type default)
			)
			(layer "B.SilkS")
		)
		(fp_line
			(start -0.7874 0.4064)
			(end 0.7874 0.4064)
			(stroke
				(width 0.1524)
				(type default)
			)
			(layer "B.SilkS")
		)
		(fp_line
			(start -0.7874 -0.4064)
			(end -0.7874 0.4064)
			(stroke
				(width 0.1524)
				(type default)
			)
			(layer "B.SilkS")
		)
		(fp_line
			(start 0.67945 0.3048)
			(end 0.67945 -0.305054)
			(stroke
				(width 0.1)
				(type default)
			)
			(layer "B.Fab")
		)
		(fp_line
			(start 0.67945 -0.305054)
			(end 0.12065 -0.305054)
			(stroke
				(width 0.1)
				(type default)
			)
			(layer "B.Fab")
		)
		(fp_line
			(start 0.12065 0.3048)
			(end 0.67945 0.3048)
			(stroke
				(width 0.1)
				(type default)
			)
			(layer "B.Fab")
		)
		(fp_line
			(start 0.12065 0.2794)
			(end 0.12065 0.3048)
			(stroke
				(width 0.1)
				(type default)
			)
			(layer "B.Fab")
		)
		(fp_line
			(start 0.12065 -0.2794)
			(end -0.12065 -0.2794)
			(stroke
				(width 0.1)
				(type default)
			)
			(layer "B.Fab")
		)
		(fp_line
			(start 0.12065 -0.305054)
			(end 0.12065 -0.2794)
			(stroke
				(width 0.1)
				(type default)
			)
			(layer "B.Fab")
		)
		(fp_line
			(start -0.120396 0.3048)
			(end -0.120396 0.2794)
			(stroke
				(width 0.1)
				(type default)
			)
			(layer "B.Fab")
		)
		(fp_line
			(start -0.120396 0.2794)
			(end 0.12065 0.2794)
			(stroke
				(width 0.1)
				(type default)
			)
			(layer "B.Fab")
		)
		(fp_line
			(start -0.12065 -0.2794)
			(end -0.12065 -0.3048)
			(stroke
				(width 0.1)
				(type default)
			)
			(layer "B.Fab")
		)
		(fp_line
			(start -0.12065 -0.3048)
			(end -0.67945 -0.3048)
			(stroke
				(width 0.1)
				(type default)
			)
			(layer "B.Fab")
		)
		(fp_line
			(start -0.67945 0.3048)
			(end -0.120396 0.3048)
			(stroke
				(width 0.1)
				(type default)
			)
			(layer "B.Fab")
		)
		(fp_line
			(start -0.67945 -0.3048)
			(end -0.67945 0.3048)
			(stroke
				(width 0.1)
				(type default)
			)
			(layer "B.Fab")
		)
		(pad "1" smd circle
			(at 0.40005 0)
			(size 0 0)
			(layers "B.Cu" "B.Mask" "B.Paste")
			(net "P1V2_AUX_ADC_TIC")
		)
		(pad "2" smd circle
			(at -0.40005 0)
			(size 0 0)
			(layers "B.Cu" "B.Mask" "B.Paste")
			(net "GND")
		)
	)
	(footprint ""
		(layer "B.Cu")
		(at 113.105946 -257.74523 180)
		(property "Reference" "C2264"
			(at 0 0 0)
			(layer "B.SilkS")
			(hide yes)
			(effects
				(font
					(size 1.27 1.27)
				)
				(justify mirror)
			)
		)
		(property "Value" ""
			(at 0 0 0)
			(layer "B.Fab")
			(effects
				(font
					(size 1.27 1.27)
				)
				(justify mirror)
			)
		)
		(duplicate_pad_numbers_are_jumpers no)
		(fp_line
			(start 0.7874 0.4064)
			(end 0.7874 -0.4064)
			(stroke
				(width 0.1524)
				(type default)
			)
			(layer "B.SilkS")
		)
		(fp_line
			(start 0.7874 -0.4064)
			(end -0.7874 -0.4064)
			(stroke
				(width 0.1524)
				(type default)
			)
			(layer "B.SilkS")
		)
		(fp_line
			(start -0.7874 0.4064)
			(end 0.7874 0.4064)
			(stroke
				(width 0.1524)
				(type default)
			)
			(layer "B.SilkS")
		)
		(fp_line
			(start -0.7874 -0.4064)
			(end -0.7874 0.4064)
			(stroke
				(width 0.1524)
				(type default)
			)
			(layer "B.SilkS")
		)
		(fp_line
			(start 0.67945 0.3048)
			(end 0.67945 -0.305054)
			(stroke
				(width 0.1)
				(type default)
			)
			(layer "B.Fab")
		)
		(fp_line
			(start 0.67945 -0.305054)
			(end 0.12065 -0.305054)
			(stroke
				(width 0.1)
				(type default)
			)
			(layer "B.Fab")
		)
		(fp_line
			(start 0.12065 0.3048)
			(end 0.67945 0.3048)
			(stroke
				(width 0.1)
				(type default)
			)
			(layer "B.Fab")
		)
		(fp_line
			(start 0.12065 0.2794)
			(end 0.12065 0.3048)
			(stroke
				(width 0.1)
				(type default)
			)
			(layer "B.Fab")
		)
		(fp_line
			(start 0.12065 -0.2794)
			(end -0.12065 -0.2794)
			(stroke
				(width 0.1)
				(type default)
			)
			(layer "B.Fab")
		)
		(fp_line
			(start 0.12065 -0.305054)
			(end 0.12065 -0.2794)
			(stroke
				(width 0.1)
				(type default)
			)
			(layer "B.Fab")
		)
		(fp_line
			(start -0.120396 0.3048)
			(end -0.120396 0.2794)
			(stroke
				(width 0.1)
				(type default)
			)
			(layer "B.Fab")
		)
		(fp_line
			(start -0.120396 0.2794)
			(end 0.12065 0.2794)
			(stroke
				(width 0.1)
				(type default)
			)
			(layer "B.Fab")
		)
		(fp_line
			(start -0.12065 -0.2794)
			(end -0.12065 -0.3048)
			(stroke
				(width 0.1)
				(type default)
			)
			(layer "B.Fab")
		)
		(fp_line
			(start -0.12065 -0.3048)
			(end -0.67945 -0.3048)
			(stroke
				(width 0.1)
				(type default)
			)
			(layer "B.Fab")
		)
		(fp_line
			(start -0.67945 0.3048)
			(end -0.120396 0.3048)
			(stroke
				(width 0.1)
				(type default)
			)
			(layer "B.Fab")
		)
		(fp_line
			(start -0.67945 -0.3048)
			(end -0.67945 0.3048)
			(stroke
				(width 0.1)
				(type default)
			)
			(layer "B.Fab")
		)
		(pad "1" smd circle
			(at 0.40005 0)
			(size 0 0)
			(layers "B.Cu" "B.Mask" "B.Paste")
			(net "PVDDCR_SOC_P1")
		)
		(pad "2" smd circle
			(at -0.40005 0)
			(size 0 0)
			(layers "B.Cu" "B.Mask" "B.Paste")
			(net "GND")
		)
	)
	(footprint ""
		(layer "B.Cu")
		(at 379.441202 -416.899344 90)
		(property "Reference" "C6601"
			(at 0 0 90)
			(layer "B.SilkS")
			(hide yes)
			(effects
				(font
					(size 1.27 1.27)
				)
				(justify mirror)
			)
		)
		(property "Value" ""
			(at 0 0 90)
			(layer "B.Fab")
			(effects
				(font
					(size 1.27 1.27)
				)
				(justify mirror)
			)
		)
		(duplicate_pad_numbers_are_jumpers no)
		(fp_line
			(start 0.299974 -0.150114)
			(end -0.299974 -0.150114)
			(stroke
				(width 0.1)
				(type default)
			)
			(layer "B.Fab")
		)
		(fp_line
			(start -0.299974 -0.150114)
			(end -0.299974 0.150114)
			(stroke
				(width 0.1)
				(type default)
			)
			(layer "B.Fab")
		)
		(fp_line
			(start 0.299974 0.150114)
			(end 0.299974 -0.150114)
			(stroke
				(width 0.1)
				(type default)
			)
			(layer "B.Fab")
		)
		(fp_line
			(start -0.299974 0.150114)
			(end 0.299974 0.150114)
			(stroke
				(width 0.1)
				(type default)
			)
			(layer "B.Fab")
		)
		(pad "1" smd rect
			(at 0.2667 0 270)
			(size 0.3048 0.381)
			(layers "B.Cu" "B.Mask" "B.Paste")
			(net "P5E_CPU0_P3_TX_BUF_C_DP<2>")
		)
		(pad "2" smd rect
			(at -0.2667 0 270)
			(size 0.3048 0.381)
			(layers "B.Cu" "B.Mask" "B.Paste")
			(net "P5E_CPU0_P3_TX_BUF_DP<2>")
		)
	)
	(footprint ""
		(layer "B.Cu")
		(at 304.590958 -398.942052 90)
		(property "Reference" "C565"
			(at 0 0 90)
			(layer "B.SilkS")
			(hide yes)
			(effects
				(font
					(size 1.27 1.27)
				)
				(justify mirror)
			)
		)
		(property "Value" ""
			(at 0 0 90)
			(layer "B.Fab")
			(effects
				(font
					(size 1.27 1.27)
				)
				(justify mirror)
			)
		)
		(duplicate_pad_numbers_are_jumpers no)
		(fp_line
			(start 0.7874 -0.4064)
			(end -0.7874 -0.4064)
			(stroke
				(width 0.1524)
				(type default)
			)
			(layer "B.SilkS")
		)
		(fp_line
			(start -0.7874 -0.4064)
			(end -0.7874 0.4064)
			(stroke
				(width 0.1524)
				(type default)
			)
			(layer "B.SilkS")
		)
		(fp_line
			(start 0.7874 0.4064)
			(end 0.7874 -0.4064)
			(stroke
				(width 0.1524)
				(type default)
			)
			(layer "B.SilkS")
		)
		(fp_line
			(start -0.7874 0.4064)
			(end 0.7874 0.4064)
			(stroke
				(width 0.1524)
				(type default)
			)
			(layer "B.SilkS")
		)
		(fp_line
			(start 0.67945 -0.305054)
			(end 0.12065 -0.305054)
			(stroke
				(width 0.1)
				(type default)
			)
			(layer "B.Fab")
		)
		(fp_line
			(start 0.12065 -0.305054)
			(end 0.12065 -0.2794)
			(stroke
				(width 0.1)
				(type default)
			)
			(layer "B.Fab")
		)
		(fp_line
			(start -0.12065 -0.3048)
			(end -0.67945 -0.3048)
			(stroke
				(width 0.1)
				(type default)
			)
			(layer "B.Fab")
		)
		(fp_line
			(start -0.67945 -0.3048)
			(end -0.67945 0.3048)
			(stroke
				(width 0.1)
				(type default)
			)
			(layer "B.Fab")
		)
		(fp_line
			(start 0.12065 -0.2794)
			(end -0.12065 -0.2794)
			(stroke
				(width 0.1)
				(type default)
			)
			(layer "B.Fab")
		)
		(fp_line
			(start -0.12065 -0.2794)
			(end -0.12065 -0.3048)
			(stroke
				(width 0.1)
				(type default)
			)
			(layer "B.Fab")
		)
		(fp_line
			(start 0.12065 0.2794)
			(end 0.12065 0.3048)
			(stroke
				(width 0.1)
				(type default)
			)
			(layer "B.Fab")
		)
		(fp_line
			(start -0.120396 0.2794)
			(end 0.12065 0.2794)
			(stroke
				(width 0.1)
				(type default)
			)
			(layer "B.Fab")
		)
		(fp_line
			(start 0.67945 0.3048)
			(end 0.67945 -0.305054)
			(stroke
				(width 0.1)
				(type default)
			)
			(layer "B.Fab")
		)
		(fp_line
			(start 0.12065 0.3048)
			(end 0.67945 0.3048)
			(stroke
				(width 0.1)
				(type default)
			)
			(layer "B.Fab")
		)
		(fp_line
			(start -0.120396 0.3048)
			(end -0.120396 0.2794)
			(stroke
				(width 0.1)
				(type default)
			)
			(layer "B.Fab")
		)
		(fp_line
			(start -0.67945 0.3048)
			(end -0.120396 0.3048)
			(stroke
				(width 0.1)
				(type default)
			)
			(layer "B.Fab")
		)
		(pad "1" smd circle
			(at 0.40005 0 270)
			(size 0 0)
			(layers "B.Cu" "B.Mask" "B.Paste")
			(net "P0V9_CPU0_RT0_2A")
		)
		(pad "2" smd circle
			(at -0.40005 0 270)
			(size 0 0)
			(layers "B.Cu" "B.Mask" "B.Paste")
			(net "GND")
		)
	)
	(footprint ""
		(layer "B.Cu")
		(at 268.892528 -195.859146 180)
		(property "Reference" "R1679"
			(at 0 0 0)
			(layer "B.SilkS")
			(hide yes)
			(effects
				(font
					(size 1.27 1.27)
				)
				(justify mirror)
			)
		)
		(property "Value" ""
			(at 0 0 0)
			(layer "B.Fab")
			(effects
				(font
					(size 1.27 1.27)
				)
				(justify mirror)
			)
		)
		(duplicate_pad_numbers_are_jumpers no)
		(fp_line
			(start 0.7874 0.4064)
			(end 0.7874 -0.4064)
			(stroke
				(width 0.1524)
				(type default)
			)
			(layer "B.SilkS")
		)
		(fp_line
			(start 0.7874 -0.4064)
			(end -0.7874 -0.4064)
			(stroke
				(width 0.1524)
				(type default)
			)
			(layer "B.SilkS")
		)
		(fp_line
			(start -0.7874 0.4064)
			(end 0.7874 0.4064)
			(stroke
				(width 0.1524)
				(type default)
			)
			(layer "B.SilkS")
		)
		(fp_line
			(start -0.7874 -0.4064)
			(end -0.7874 0.4064)
			(stroke
				(width 0.1524)
				(type default)
			)
			(layer "B.SilkS")
		)
		(fp_line
			(start 0.67945 0.3048)
			(end 0.67945 -0.305054)
			(stroke
				(width 0.1)
				(type default)
			)
			(layer "B.Fab")
		)
		(fp_line
			(start 0.67945 -0.305054)
			(end 0.12065 -0.305054)
			(stroke
				(width 0.1)
				(type default)
			)
			(layer "B.Fab")
		)
		(fp_line
			(start 0.12065 0.3048)
			(end 0.67945 0.3048)
			(stroke
				(width 0.1)
				(type default)
			)
			(layer "B.Fab")
		)
		(fp_line
			(start 0.12065 0.2794)
			(end 0.12065 0.3048)
			(stroke
				(width 0.1)
				(type default)
			)
			(layer "B.Fab")
		)
		(fp_line
			(start 0.12065 -0.2794)
			(end -0.12065 -0.2794)
			(stroke
				(width 0.1)
				(type default)
			)
			(layer "B.Fab")
		)
		(fp_line
			(start 0.12065 -0.305054)
			(end 0.12065 -0.2794)
			(stroke
				(width 0.1)
				(type default)
			)
			(layer "B.Fab")
		)
		(fp_line
			(start -0.120396 0.3048)
			(end -0.120396 0.2794)
			(stroke
				(width 0.1)
				(type default)
			)
			(layer "B.Fab")
		)
		(fp_line
			(start -0.120396 0.2794)
			(end 0.12065 0.2794)
			(stroke
				(width 0.1)
				(type default)
			)
			(layer "B.Fab")
		)
		(fp_line
			(start -0.12065 -0.2794)
			(end -0.12065 -0.3048)
			(stroke
				(width 0.1)
				(type default)
			)
			(layer "B.Fab")
		)
		(fp_line
			(start -0.12065 -0.3048)
			(end -0.67945 -0.3048)
			(stroke
				(width 0.1)
				(type default)
			)
			(layer "B.Fab")
		)
		(fp_line
			(start -0.67945 0.3048)
			(end -0.120396 0.3048)
			(stroke
				(width 0.1)
				(type default)
			)
			(layer "B.Fab")
		)
		(fp_line
			(start -0.67945 -0.3048)
			(end -0.67945 0.3048)
			(stroke
				(width 0.1)
				(type default)
			)
			(layer "B.Fab")
		)
		(pad "1" smd circle
			(at 0.40005 0)
			(size 0 0)
			(layers "B.Cu" "B.Mask" "B.Paste")
			(net "I3C_SPD_DDRAF_CPU0_SDA")
		)
		(pad "2" smd circle
			(at -0.40005 0)
			(size 0 0)
			(layers "B.Cu" "B.Mask" "B.Paste")
			(net "I3C_SPD_DDRF_CPU0_SDA")
		)
	)
	(footprint ""
		(layer "B.Cu")
		(at 501.233948 -298.343066 -90)
		(property "Reference" "X26"
			(at 3.089656 3.232658 270)
			(unlocked yes)
			(layer "B.SilkS")
			(effects
				(font
					(size 0.7874 0.5842)
					(thickness 0.1524)
				)
				(justify left mirror)
			)
		)
		(property "Value" ""
			(at 0 0 90)
			(layer "B.Fab")
			(effects
				(font
					(size 1.27 1.27)
				)
				(justify mirror)
			)
		)
		(property "User Part Number" "N_A"
			(at -1.30175 1.27 180)
			(unlocked yes)
			(layer "Cmts.User")
			(hide yes)
			(effects
				(font
					(size 0.635 0.4064)
					(thickness 0.1524)
				)
				(justify mirror)
			)
		)
		(property "Device Type" "TP_TDR_4P_FTS_TH-TP_TDR_4P_DIP,EMPTY,TP15"
			(at -1.30175 1.27 180)
			(unlocked yes)
			(layer "B.Fab")
			(hide yes)
			(effects
				(font
					(size 0.635 0.4064)
					(thickness 0.1524)
				)
				(justify mirror)
			)
		)
		(duplicate_pad_numbers_are_jumpers no)
		(fp_line
			(start -2.54 3.81)
			(end -2.54 3.6703)
			(stroke
				(width 0.1524)
				(type default)
			)
			(layer "B.SilkS")
		)
		(fp_line
			(start 0 3.81)
			(end -2.54 3.81)
			(stroke
				(width 0.1524)
				(type default)
			)
			(layer "B.SilkS")
		)
		(fp_line
			(start 0 3.175)
			(end 0 3.81)
			(stroke
				(width 0.1524)
				(type default)
			)
			(layer "B.SilkS")
		)
		(fp_line
			(start -2.54 1.4097)
			(end -2.54 1.1303)
			(stroke
				(width 0.1524)
				(type default)
			)
			(layer "B.SilkS")
		)
		(fp_line
			(start 0 0.635)
			(end 0 1.905)
			(stroke
				(width 0.1524)
				(type default)
			)
			(layer "B.SilkS")
		)
		(fp_line
			(start -2.54 -1.1303)
			(end -2.54 -1.27)
			(stroke
				(width 0.1524)
				(type default)
			)
			(layer "B.SilkS")
		)
		(fp_line
			(start -2.54 -1.27)
			(end 0 -1.27)
			(stroke
				(width 0.1524)
				(type default)
			)
			(layer "B.SilkS")
		)
		(fp_line
			(start 0 -1.27)
			(end 0 -0.635)
			(stroke
				(width 0.1524)
				(type default)
			)
			(layer "B.SilkS")
		)
		(fp_poly
			(pts
				(xy 2.285746 -0.762) (xy 2.285746 0.762) (xy 0.761746 0)
			)
			(stroke
				(width 0)
				(type default)
			)
			(fill yes)
			(layer "B.SilkS")
		)
		(fp_line
			(start -2.54 3.81)
			(end -2.54 -1.27)
			(stroke
				(width 0.1)
				(type default)
			)
			(layer "B.Fab")
		)
		(fp_line
			(start 0 3.81)
			(end -2.54 3.81)
			(stroke
				(width 0.1)
				(type default)
			)
			(layer "B.Fab")
		)
		(fp_line
			(start -2.54 -1.27)
			(end 0 -1.27)
			(stroke
				(width 0.1)
				(type default)
			)
			(layer "B.Fab")
		)
		(fp_line
			(start 0 -1.27)
			(end 0 3.81)
			(stroke
				(width 0.1)
				(type default)
			)
			(layer "B.Fab")
		)
		(fp_poly
			(pts
				(xy 0.761746 0) (xy 2.285746 -0.762) (xy 2.285746 0.762)
			)
			(stroke
				(width 0)
				(type default)
			)
			(fill yes)
			(layer "B.Fab")
		)
		(pad "1" thru_hole circle
			(at 0 0 90)
			(size 1.0033 1.0033)
			(drill 0.249936)
			(layers "*.Cu" "*.Mask")
			(remove_unused_layers no)
			(net "TDR_DIFF_80_IN6_DP")
			(clearance 0.10795)
			(padstack
				(mode front_inner_back)
				(layer "Inner"
					(shape circle)
					(size 0.8001 0.8001)
					(clearance 0.1524)
				)
				(layer "B.Cu"
					(shape circle)
					(size 1.0033 1.0033)
					(thermal_gap 0.10795)
					(clearance 0.10795)
				)
			)
		)
		(pad "2" thru_hole circle
			(at -2.54 0 90)
			(size 1.9939 1.9939)
			(drill 0.249936)
			(layers "*.Cu" "*.Mask")
			(remove_unused_layers no)
			(net "T1_GND")
			(clearance 0.10795)
			(padstack
				(mode front_inner_back)
				(layer "Inner"
					(shape circle)
					(size 0.8001 0.8001)
					(clearance 0.1524)
				)
				(layer "B.Cu"
					(shape circle)
					(size 1.9939 1.9939)
					(thermal_gap 0.10795)
					(clearance 0.10795)
				)
			)
		)
		(pad "3" thru_hole circle
			(at -2.54 2.54 90)
			(size 1.9939 1.9939)
			(drill 0.249936)
			(layers "*.Cu" "*.Mask")
			(remove_unused_layers no)
			(net "T1_GND")
			(clearance 0.10795)
			(padstack
				(mode front_inner_back)
				(layer "Inner"
					(shape circle)
					(size 0.8001 0.8001)
					(clearance 0.1524)
				)
				(layer "B.Cu"
					(shape circle)
					(size 1.9939 1.9939)
					(thermal_gap 0.10795)
					(clearance 0.10795)
				)
			)
		)
		(pad "4" thru_hole circle
			(at 0 2.54 90)
			(size 1.0033 1.0033)
			(drill 0.249936)
			(layers "*.Cu" "*.Mask")
			(remove_unused_layers no)
			(net "TDR_DIFF_80_IN6_DN")
			(clearance 0.10795)
			(padstack
				(mode front_inner_back)
				(layer "Inner"
					(shape circle)
					(size 0.8001 0.8001)
					(clearance 0.1524)
				)
				(layer "B.Cu"
					(shape circle)
					(size 1.0033 1.0033)
					(thermal_gap 0.10795)
					(clearance 0.10795)
				)
			)
		)
	)
	(footprint ""
		(layer "B.Cu")
		(at 178.430174 -13.756132 90)
		(property "Reference" "R1384"
			(at 0 0 90)
			(layer "B.SilkS")
			(hide yes)
			(effects
				(font
					(size 1.27 1.27)
				)
				(justify mirror)
			)
		)
		(property "Value" ""
			(at 0 0 90)
			(layer "B.Fab")
			(effects
				(font
					(size 1.27 1.27)
				)
				(justify mirror)
			)
		)
		(duplicate_pad_numbers_are_jumpers no)
		(fp_line
			(start 0.7874 -0.4064)
			(end -0.7874 -0.4064)
			(stroke
				(width 0.1524)
				(type default)
			)
			(layer "B.SilkS")
		)
		(fp_line
			(start -0.7874 -0.4064)
			(end -0.7874 0.4064)
			(stroke
				(width 0.1524)
				(type default)
			)
			(layer "B.SilkS")
		)
		(fp_line
			(start 0.7874 0.4064)
			(end 0.7874 -0.4064)
			(stroke
				(width 0.1524)
				(type default)
			)
			(layer "B.SilkS")
		)
		(fp_line
			(start -0.7874 0.4064)
			(end 0.7874 0.4064)
			(stroke
				(width 0.1524)
				(type default)
			)
			(layer "B.SilkS")
		)
		(fp_line
			(start 0.67945 -0.305054)
			(end 0.12065 -0.305054)
			(stroke
				(width 0.1)
				(type default)
			)
			(layer "B.Fab")
		)
		(fp_line
			(start 0.12065 -0.305054)
			(end 0.12065 -0.2794)
			(stroke
				(width 0.1)
				(type default)
			)
			(layer "B.Fab")
		)
		(fp_line
			(start -0.12065 -0.3048)
			(end -0.67945 -0.3048)
			(stroke
				(width 0.1)
				(type default)
			)
			(layer "B.Fab")
		)
		(fp_line
			(start -0.67945 -0.3048)
			(end -0.67945 0.3048)
			(stroke
				(width 0.1)
				(type default)
			)
			(layer "B.Fab")
		)
		(fp_line
			(start 0.12065 -0.2794)
			(end -0.12065 -0.2794)
			(stroke
				(width 0.1)
				(type default)
			)
			(layer "B.Fab")
		)
		(fp_line
			(start -0.12065 -0.2794)
			(end -0.12065 -0.3048)
			(stroke
				(width 0.1)
				(type default)
			)
			(layer "B.Fab")
		)
		(fp_line
			(start 0.12065 0.2794)
			(end 0.12065 0.3048)
			(stroke
				(width 0.1)
				(type default)
			)
			(layer "B.Fab")
		)
		(fp_line
			(start -0.120396 0.2794)
			(end 0.12065 0.2794)
			(stroke
				(width 0.1)
				(type default)
			)
			(layer "B.Fab")
		)
		(fp_line
			(start 0.67945 0.3048)
			(end 0.67945 -0.305054)
			(stroke
				(width 0.1)
				(type default)
			)
			(layer "B.Fab")
		)
		(fp_line
			(start 0.12065 0.3048)
			(end 0.67945 0.3048)
			(stroke
				(width 0.1)
				(type default)
			)
			(layer "B.Fab")
		)
		(fp_line
			(start -0.120396 0.3048)
			(end -0.120396 0.2794)
			(stroke
				(width 0.1)
				(type default)
			)
			(layer "B.Fab")
		)
		(fp_line
			(start -0.67945 0.3048)
			(end -0.120396 0.3048)
			(stroke
				(width 0.1)
				(type default)
			)
			(layer "B.Fab")
		)
		(pad "1" smd circle
			(at 0.40005 0 270)
			(size 0 0)
			(layers "B.Cu" "B.Mask" "B.Paste")
			(net "SMB_CPU0_CPU1_SEC_SCL")
		)
		(pad "2" smd circle
			(at -0.40005 0 270)
			(size 0 0)
			(layers "B.Cu" "B.Mask" "B.Paste")
			(net "P3V3_AUX")
		)
	)
	(footprint ""
		(layer "B.Cu")
		(at 442.543946 -192.660016 180)
		(property "Reference" "C167"
			(at 0 0 0)
			(layer "B.SilkS")
			(hide yes)
			(effects
				(font
					(size 1.27 1.27)
				)
				(justify mirror)
			)
		)
		(property "Value" ""
			(at 0 0 0)
			(layer "B.Fab")
			(effects
				(font
					(size 1.27 1.27)
				)
				(justify mirror)
			)
		)
		(duplicate_pad_numbers_are_jumpers no)
		(fp_line
			(start 1.524 0.762)
			(end 1.524 -0.762)
			(stroke
				(width 0.1524)
				(type default)
			)
			(layer "B.SilkS")
		)
		(fp_line
			(start 1.524 -0.762)
			(end -1.524 -0.762)
			(stroke
				(width 0.1524)
				(type default)
			)
			(layer "B.SilkS")
		)
		(fp_line
			(start -1.524 0.762)
			(end 1.524 0.762)
			(stroke
				(width 0.1524)
				(type default)
			)
			(layer "B.SilkS")
		)
		(fp_line
			(start -1.524 -0.762)
			(end -1.524 0.762)
			(stroke
				(width 0.1524)
				(type default)
			)
			(layer "B.SilkS")
		)
		(fp_line
			(start 1.1049 0.724916)
			(end -1.1049 0.724916)
			(stroke
				(width 0.1)
				(type default)
			)
			(layer "B.Fab")
		)
		(fp_line
			(start 1.1049 -0.724916)
			(end 1.1049 0.724916)
			(stroke
				(width 0.1)
				(type default)
			)
			(layer "B.Fab")
		)
		(fp_line
			(start -1.1049 0.724916)
			(end -1.1049 -0.724916)
			(stroke
				(width 0.1)
				(type default)
			)
			(layer "B.Fab")
		)
		(fp_line
			(start -1.1049 -0.724916)
			(end 1.1049 -0.724916)
			(stroke
				(width 0.1)
				(type default)
			)
			(layer "B.Fab")
		)
		(pad "1" smd rect
			(at 0.889 0 180)
			(size 1.016 1.27)
			(layers "B.Cu" "B.Mask" "B.Paste")
			(net "P12V_MEM_CPU0")
		)
		(pad "2" smd rect
			(at -0.889 0 180)
			(size 1.016 1.27)
			(layers "B.Cu" "B.Mask" "B.Paste")
			(net "GND")
		)
	)
	(footprint ""
		(layer "B.Cu")
		(at 312.547 -359.918)
		(property "Reference" "PR67"
			(at 0 0 0)
			(layer "B.SilkS")
			(hide yes)
			(effects
				(font
					(size 1.27 1.27)
				)
				(justify mirror)
			)
		)
		(property "Value" ""
			(at 0 0 0)
			(layer "B.Fab")
			(effects
				(font
					(size 1.27 1.27)
				)
				(justify mirror)
			)
		)
		(duplicate_pad_numbers_are_jumpers no)
		(fp_line
			(start -0.7874 -0.4064)
			(end -0.7874 0.4064)
			(stroke
				(width 0.1524)
				(type default)
			)
			(layer "B.SilkS")
		)
		(fp_line
			(start -0.7874 0.4064)
			(end 0.7874 0.4064)
			(stroke
				(width 0.1524)
				(type default)
			)
			(layer "B.SilkS")
		)
		(fp_line
			(start 0.7874 -0.4064)
			(end -0.7874 -0.4064)
			(stroke
				(width 0.1524)
				(type default)
			)
			(layer "B.SilkS")
		)
		(fp_line
			(start 0.7874 0.4064)
			(end 0.7874 -0.4064)
			(stroke
				(width 0.1524)
				(type default)
			)
			(layer "B.SilkS")
		)
		(fp_line
			(start -0.67945 -0.3048)
			(end -0.67945 0.3048)
			(stroke
				(width 0.1)
				(type default)
			)
			(layer "B.Fab")
		)
		(fp_line
			(start -0.67945 0.3048)
			(end -0.120396 0.3048)
			(stroke
				(width 0.1)
				(type default)
			)
			(layer "B.Fab")
		)
		(fp_line
			(start -0.12065 -0.3048)
			(end -0.67945 -0.3048)
			(stroke
				(width 0.1)
				(type default)
			)
			(layer "B.Fab")
		)
		(fp_line
			(start -0.12065 -0.2794)
			(end -0.12065 -0.3048)
			(stroke
				(width 0.1)
				(type default)
			)
			(layer "B.Fab")
		)
		(fp_line
			(start -0.120396 0.2794)
			(end 0.12065 0.2794)
			(stroke
				(width 0.1)
				(type default)
			)
			(layer "B.Fab")
		)
		(fp_line
			(start -0.120396 0.3048)
			(end -0.120396 0.2794)
			(stroke
				(width 0.1)
				(type default)
			)
			(layer "B.Fab")
		)
		(fp_line
			(start 0.12065 -0.305054)
			(end 0.12065 -0.2794)
			(stroke
				(width 0.1)
				(type default)
			)
			(layer "B.Fab")
		)
		(fp_line
			(start 0.12065 -0.2794)
			(end -0.12065 -0.2794)
			(stroke
				(width 0.1)
				(type default)
			)
			(layer "B.Fab")
		)
		(fp_line
			(start 0.12065 0.2794)
			(end 0.12065 0.3048)
			(stroke
				(width 0.1)
				(type default)
			)
			(layer "B.Fab")
		)
		(fp_line
			(start 0.12065 0.3048)
			(end 0.67945 0.3048)
			(stroke
				(width 0.1)
				(type default)
			)
			(layer "B.Fab")
		)
		(fp_line
			(start 0.67945 -0.305054)
			(end 0.12065 -0.305054)
			(stroke
				(width 0.1)
				(type default)
			)
			(layer "B.Fab")
		)
		(fp_line
			(start 0.67945 0.3048)
			(end 0.67945 -0.305054)
			(stroke
				(width 0.1)
				(type default)
			)
			(layer "B.Fab")
		)
		(pad "1" smd circle
			(at 0.40005 0 180)
			(size 0 0)
			(layers "B.Cu" "B.Mask" "B.Paste")
			(net "PVDDCR_CPU1_P0_EN1_ADDR_CFG")
		)
		(pad "2" smd circle
			(at -0.40005 0 180)
			(size 0 0)
			(layers "B.Cu" "B.Mask" "B.Paste")
			(net "GND")
		)
	)
	(footprint ""
		(layer "B.Cu")
		(at 373.018558 -396.393162 -90)
		(property "Reference" "C1011"
			(at 0 0 90)
			(layer "B.SilkS")
			(hide yes)
			(effects
				(font
					(size 1.27 1.27)
				)
				(justify mirror)
			)
		)
		(property "Value" ""
			(at 0 0 90)
			(layer "B.Fab")
			(effects
				(font
					(size 1.27 1.27)
				)
				(justify mirror)
			)
		)
		(duplicate_pad_numbers_are_jumpers no)
		(fp_line
			(start -0.299974 0.150114)
			(end 0.299974 0.150114)
			(stroke
				(width 0.1)
				(type default)
			)
			(layer "B.Fab")
		)
		(fp_line
			(start 0.299974 0.150114)
			(end 0.299974 -0.150114)
			(stroke
				(width 0.1)
				(type default)
			)
			(layer "B.Fab")
		)
		(fp_line
			(start -0.299974 -0.150114)
			(end -0.299974 0.150114)
			(stroke
				(width 0.1)
				(type default)
			)
			(layer "B.Fab")
		)
		(fp_line
			(start 0.299974 -0.150114)
			(end -0.299974 -0.150114)
			(stroke
				(width 0.1)
				(type default)
			)
			(layer "B.Fab")
		)
		(pad "1" smd rect
			(at 0.2667 0 90)
			(size 0.3048 0.381)
			(layers "B.Cu" "B.Mask" "B.Paste")
			(net "P0V9_CPU0_RT3_2A")
		)
		(pad "2" smd rect
			(at -0.2667 0 90)
			(size 0.3048 0.381)
			(layers "B.Cu" "B.Mask" "B.Paste")
			(net "GND")
		)
	)
	(footprint ""
		(layer "B.Cu")
		(at 147.018756 -390.560052 90)
		(property "Reference" "C410"
			(at 0 0 90)
			(layer "B.SilkS")
			(hide yes)
			(effects
				(font
					(size 1.27 1.27)
				)
				(justify mirror)
			)
		)
		(property "Value" ""
			(at 0 0 90)
			(layer "B.Fab")
			(effects
				(font
					(size 1.27 1.27)
				)
				(justify mirror)
			)
		)
		(duplicate_pad_numbers_are_jumpers no)
		(fp_line
			(start 0.7874 -0.4064)
			(end -0.7874 -0.4064)
			(stroke
				(width 0.1524)
				(type default)
			)
			(layer "B.SilkS")
		)
		(fp_line
			(start -0.7874 -0.4064)
			(end -0.7874 0.4064)
			(stroke
				(width 0.1524)
				(type default)
			)
			(layer "B.SilkS")
		)
		(fp_line
			(start 0.7874 0.4064)
			(end 0.7874 -0.4064)
			(stroke
				(width 0.1524)
				(type default)
			)
			(layer "B.SilkS")
		)
		(fp_line
			(start -0.7874 0.4064)
			(end 0.7874 0.4064)
			(stroke
				(width 0.1524)
				(type default)
			)
			(layer "B.SilkS")
		)
		(fp_line
			(start 0.67945 -0.305054)
			(end 0.12065 -0.305054)
			(stroke
				(width 0.1)
				(type default)
			)
			(layer "B.Fab")
		)
		(fp_line
			(start 0.12065 -0.305054)
			(end 0.12065 -0.2794)
			(stroke
				(width 0.1)
				(type default)
			)
			(layer "B.Fab")
		)
		(fp_line
			(start -0.12065 -0.3048)
			(end -0.67945 -0.3048)
			(stroke
				(width 0.1)
				(type default)
			)
			(layer "B.Fab")
		)
		(fp_line
			(start -0.67945 -0.3048)
			(end -0.67945 0.3048)
			(stroke
				(width 0.1)
				(type default)
			)
			(layer "B.Fab")
		)
		(fp_line
			(start 0.12065 -0.2794)
			(end -0.12065 -0.2794)
			(stroke
				(width 0.1)
				(type default)
			)
			(layer "B.Fab")
		)
		(fp_line
			(start -0.12065 -0.2794)
			(end -0.12065 -0.3048)
			(stroke
				(width 0.1)
				(type default)
			)
			(layer "B.Fab")
		)
		(fp_line
			(start 0.12065 0.2794)
			(end 0.12065 0.3048)
			(stroke
				(width 0.1)
				(type default)
			)
			(layer "B.Fab")
		)
		(fp_line
			(start -0.120396 0.2794)
			(end 0.12065 0.2794)
			(stroke
				(width 0.1)
				(type default)
			)
			(layer "B.Fab")
		)
		(fp_line
			(start 0.67945 0.3048)
			(end 0.67945 -0.305054)
			(stroke
				(width 0.1)
				(type default)
			)
			(layer "B.Fab")
		)
		(fp_line
			(start 0.12065 0.3048)
			(end 0.67945 0.3048)
			(stroke
				(width 0.1)
				(type default)
			)
			(layer "B.Fab")
		)
		(fp_line
			(start -0.120396 0.3048)
			(end -0.120396 0.2794)
			(stroke
				(width 0.1)
				(type default)
			)
			(layer "B.Fab")
		)
		(fp_line
			(start -0.67945 0.3048)
			(end -0.120396 0.3048)
			(stroke
				(width 0.1)
				(type default)
			)
			(layer "B.Fab")
		)
		(pad "1" smd circle
			(at 0.40005 0 270)
			(size 0 0)
			(layers "B.Cu" "B.Mask" "B.Paste")
			(net "P0V9_CPU1_RT2_2A")
		)
		(pad "2" smd circle
			(at -0.40005 0 270)
			(size 0 0)
			(layers "B.Cu" "B.Mask" "B.Paste")
			(net "GND")
		)
	)
	(footprint ""
		(layer "B.Cu")
		(at 110.177834 -248.916952 120)
		(property "Reference" "C2347"
			(at 0 0 120)
			(layer "B.SilkS")
			(hide yes)
			(effects
				(font
					(size 1.27 1.27)
				)
				(justify mirror)
			)
		)
		(property "Value" ""
			(at 0 0 120)
			(layer "B.Fab")
			(effects
				(font
					(size 1.27 1.27)
				)
				(justify mirror)
			)
		)
		(duplicate_pad_numbers_are_jumpers no)
		(fp_line
			(start 0.787516 -0.406438)
			(end -0.787425 -0.40652)
			(stroke
				(width 0.1524)
				(type default)
			)
			(layer "B.SilkS")
		)
		(fp_line
			(start 0.787425 0.40652)
			(end 0.787516 -0.406438)
			(stroke
				(width 0.1524)
				(type default)
			)
			(layer "B.SilkS")
		)
		(fp_line
			(start -0.787425 -0.40652)
			(end -0.787516 0.406438)
			(stroke
				(width 0.1524)
				(type default)
			)
			(layer "B.SilkS")
		)
		(fp_line
			(start -0.787516 0.406438)
			(end 0.787425 0.40652)
			(stroke
				(width 0.1524)
				(type default)
			)
			(layer "B.SilkS")
		)
		(fp_line
			(start 0.679475 -0.305158)
			(end 0.120732 -0.305125)
			(stroke
				(width 0.1)
				(type default)
			)
			(layer "B.Fab")
		)
		(fp_line
			(start 0.120732 -0.305125)
			(end 0.120554 -0.279418)
			(stroke
				(width 0.1)
				(type default)
			)
			(layer "B.Fab")
		)
		(fp_line
			(start 0.120554 -0.279418)
			(end -0.120587 -0.279326)
			(stroke
				(width 0.1)
				(type default)
			)
			(layer "B.Fab")
		)
		(fp_line
			(start -0.120536 -0.304813)
			(end -0.6795 -0.304908)
			(stroke
				(width 0.1)
				(type default)
			)
			(layer "B.Fab")
		)
		(fp_line
			(start -0.120587 -0.279326)
			(end -0.120536 -0.304813)
			(stroke
				(width 0.1)
				(type default)
			)
			(layer "B.Fab")
		)
		(fp_line
			(start 0.6795 0.304908)
			(end 0.679475 -0.305158)
			(stroke
				(width 0.1)
				(type default)
			)
			(layer "B.Fab")
		)
		(fp_line
			(start -0.6795 -0.304908)
			(end -0.679568 0.304811)
			(stroke
				(width 0.1)
				(type default)
			)
			(layer "B.Fab")
		)
		(fp_line
			(start 0.120587 0.279326)
			(end 0.120536 0.304813)
			(stroke
				(width 0.1)
				(type default)
			)
			(layer "B.Fab")
		)
		(fp_line
			(start 0.120536 0.304813)
			(end 0.6795 0.304908)
			(stroke
				(width 0.1)
				(type default)
			)
			(layer "B.Fab")
		)
		(fp_line
			(start -0.120334 0.279545)
			(end 0.120587 0.279326)
			(stroke
				(width 0.1)
				(type default)
			)
			(layer "B.Fab")
		)
		(fp_line
			(start -0.120258 0.304812)
			(end -0.120334 0.279545)
			(stroke
				(width 0.1)
				(type default)
			)
			(layer "B.Fab")
		)
		(fp_line
			(start -0.679568 0.304811)
			(end -0.120258 0.304812)
			(stroke
				(width 0.1)
				(type default)
			)
			(layer "B.Fab")
		)
		(pad "1" smd circle
			(at 0.40005 0 300)
			(size 0 0)
			(layers "B.Cu" "B.Mask" "B.Paste")
			(net "PVDDCR_CPU0_P1")
		)
		(pad "2" smd circle
			(at -0.40005 0 300)
			(size 0 0)
			(layers "B.Cu" "B.Mask" "B.Paste")
			(net "GND")
		)
	)
	(footprint ""
		(layer "B.Cu")
		(at 155.364434 -199.234552 -90)
		(property "Reference" "C231"
			(at 0 0 90)
			(layer "B.SilkS")
			(hide yes)
			(effects
				(font
					(size 1.27 1.27)
				)
				(justify mirror)
			)
		)
		(property "Value" ""
			(at 0 0 90)
			(layer "B.Fab")
			(effects
				(font
					(size 1.27 1.27)
				)
				(justify mirror)
			)
		)
		(duplicate_pad_numbers_are_jumpers no)
		(fp_line
			(start -0.7874 0.4064)
			(end 0.7874 0.4064)
			(stroke
				(width 0.1524)
				(type default)
			)
			(layer "B.SilkS")
		)
		(fp_line
			(start 0.7874 0.4064)
			(end 0.7874 -0.4064)
			(stroke
				(width 0.1524)
				(type default)
			)
			(layer "B.SilkS")
		)
		(fp_line
			(start -0.7874 -0.4064)
			(end -0.7874 0.4064)
			(stroke
				(width 0.1524)
				(type default)
			)
			(layer "B.SilkS")
		)
		(fp_line
			(start 0.7874 -0.4064)
			(end -0.7874 -0.4064)
			(stroke
				(width 0.1524)
				(type default)
			)
			(layer "B.SilkS")
		)
		(fp_line
			(start -0.67945 0.3048)
			(end -0.120396 0.3048)
			(stroke
				(width 0.1)
				(type default)
			)
			(layer "B.Fab")
		)
		(fp_line
			(start -0.120396 0.3048)
			(end -0.120396 0.2794)
			(stroke
				(width 0.1)
				(type default)
			)
			(layer "B.Fab")
		)
		(fp_line
			(start 0.12065 0.3048)
			(end 0.67945 0.3048)
			(stroke
				(width 0.1)
				(type default)
			)
			(layer "B.Fab")
		)
		(fp_line
			(start 0.67945 0.3048)
			(end 0.67945 -0.305054)
			(stroke
				(width 0.1)
				(type default)
			)
			(layer "B.Fab")
		)
		(fp_line
			(start -0.120396 0.2794)
			(end 0.12065 0.2794)
			(stroke
				(width 0.1)
				(type default)
			)
			(layer "B.Fab")
		)
		(fp_line
			(start 0.12065 0.2794)
			(end 0.12065 0.3048)
			(stroke
				(width 0.1)
				(type default)
			)
			(layer "B.Fab")
		)
		(fp_line
			(start -0.12065 -0.2794)
			(end -0.12065 -0.3048)
			(stroke
				(width 0.1)
				(type default)
			)
			(layer "B.Fab")
		)
		(fp_line
			(start 0.12065 -0.2794)
			(end -0.12065 -0.2794)
			(stroke
				(width 0.1)
				(type default)
			)
			(layer "B.Fab")
		)
		(fp_line
			(start -0.67945 -0.3048)
			(end -0.67945 0.3048)
			(stroke
				(width 0.1)
				(type default)
			)
			(layer "B.Fab")
		)
		(fp_line
			(start -0.12065 -0.3048)
			(end -0.67945 -0.3048)
			(stroke
				(width 0.1)
				(type default)
			)
			(layer "B.Fab")
		)
		(fp_line
			(start 0.12065 -0.305054)
			(end 0.12065 -0.2794)
			(stroke
				(width 0.1)
				(type default)
			)
			(layer "B.Fab")
		)
		(fp_line
			(start 0.67945 -0.305054)
			(end 0.12065 -0.305054)
			(stroke
				(width 0.1)
				(type default)
			)
			(layer "B.Fab")
		)
		(pad "1" smd circle
			(at 0.40005 0 90)
			(size 0 0)
			(layers "B.Cu" "B.Mask" "B.Paste")
			(net "JTAG_CPU1_TDI")
		)
		(pad "2" smd circle
			(at -0.40005 0 90)
			(size 0 0)
			(layers "B.Cu" "B.Mask" "B.Paste")
			(net "GND")
		)
	)
	(footprint ""
		(layer "B.Cu")
		(at 328.400664 -73.534778)
		(property "Reference" "Q80"
			(at 0.95885 -1.724152 0)
			(unlocked yes)
			(layer "B.SilkS")
			(effects
				(font
					(size 0.7874 0.5842)
					(thickness 0.1524)
				)
				(justify left mirror)
			)
		)
		(property "Value" ""
			(at 0 0 0)
			(layer "B.Fab")
			(effects
				(font
					(size 1.27 1.27)
				)
				(justify mirror)
			)
		)
		(duplicate_pad_numbers_are_jumpers no)
		(fp_line
			(start -1.332738 -1.100074)
			(end -1.332738 1.100074)
			(stroke
				(width 0.1524)
				(type default)
			)
			(layer "B.SilkS")
		)
		(fp_line
			(start -1.332738 1.100074)
			(end 1.332738 1.100074)
			(stroke
				(width 0.1524)
				(type default)
			)
			(layer "B.SilkS")
		)
		(fp_line
			(start -0.4826 -1.100074)
			(end -1.332738 -1.100074)
			(stroke
				(width 0.1524)
				(type default)
			)
			(layer "B.SilkS")
		)
		(fp_line
			(start 0 -0.541274)
			(end -0.4826 -1.100074)
			(stroke
				(width 0.1524)
				(type default)
			)
			(layer "B.SilkS")
		)
		(fp_line
			(start 0.4826 -1.100074)
			(end 0 -0.541274)
			(stroke
				(width 0.1524)
				(type default)
			)
			(layer "B.SilkS")
		)
		(fp_line
			(start 1.332738 -1.100074)
			(end 0.4826 -1.100074)
			(stroke
				(width 0.1524)
				(type default)
			)
			(layer "B.SilkS")
		)
		(fp_line
			(start 1.332738 1.100074)
			(end 1.332738 -1.100074)
			(stroke
				(width 0.1524)
				(type default)
			)
			(layer "B.SilkS")
		)
		(fp_poly
			(pts
				(xy 1.367536 -0.649986) (xy 2.069592 -1.001014) (xy 2.069592 -0.298958)
			)
			(stroke
				(width 0)
				(type default)
			)
			(fill yes)
			(layer "B.SilkS")
		)
		(fp_line
			(start -0.674878 -1.100074)
			(end -0.674878 1.100074)
			(stroke
				(width 0.1)
				(type default)
			)
			(layer "B.Fab")
		)
		(fp_line
			(start -0.674878 1.100074)
			(end 0.674878 1.100074)
			(stroke
				(width 0.1)
				(type default)
			)
			(layer "B.Fab")
		)
		(fp_line
			(start 0.674878 -1.100074)
			(end -0.674878 -1.100074)
			(stroke
				(width 0.1)
				(type default)
			)
			(layer "B.Fab")
		)
		(fp_line
			(start 0.674878 1.100074)
			(end 0.674878 -1.100074)
			(stroke
				(width 0.1)
				(type default)
			)
			(layer "B.Fab")
		)
		(fp_poly
			(pts
				(xy 2.2352 -0.298958) (xy 2.2352 -1.001014) (xy 1.533144 -0.649986)
			)
			(stroke
				(width 0)
				(type default)
			)
			(fill yes)
			(layer "B.Fab")
		)
		(pad "1" smd rect
			(at 0.94996 -0.649986 90)
			(size 0.4318 0.508)
			(layers "B.Cu" "B.Mask" "B.Paste")
			(net "GND")
		)
		(pad "2" smd rect
			(at 0.94996 0 90)
			(size 0.4318 0.508)
			(layers "B.Cu" "B.Mask" "B.Paste")
			(net "FM_LED_PWRGD_PVDDCR_SOC_P0")
		)
		(pad "3" smd rect
			(at 0.94996 0.649986 90)
			(size 0.4318 0.508)
			(layers "B.Cu" "B.Mask" "B.Paste")
			(net "LED_PWRGD_PVDDCR_CPU1_P0_D")
		)
		(pad "4" smd rect
			(at -0.94996 0.649986 90)
			(size 0.4318 0.508)
			(layers "B.Cu" "B.Mask" "B.Paste")
			(net "GND")
		)
		(pad "5" smd rect
			(at -0.94996 0 90)
			(size 0.4318 0.508)
			(layers "B.Cu" "B.Mask" "B.Paste")
			(net "FM_LED_PWRGD_PVDDCR_CPU1_P0")
		)
		(pad "6" smd rect
			(at -0.94996 -0.649986 90)
			(size 0.4318 0.508)
			(layers "B.Cu" "B.Mask" "B.Paste")
			(net "LED_PWRGD_PVDDCR_SOC_P0_D")
		)
	)
	(footprint ""
		(layer "B.Cu")
		(at 117.895624 -260.305296)
		(property "Reference" "C2463"
			(at 0 0 0)
			(layer "B.SilkS")
			(hide yes)
			(effects
				(font
					(size 1.27 1.27)
				)
				(justify mirror)
			)
		)
		(property "Value" ""
			(at 0 0 0)
			(layer "B.Fab")
			(effects
				(font
					(size 1.27 1.27)
				)
				(justify mirror)
			)
		)
		(duplicate_pad_numbers_are_jumpers no)
		(fp_line
			(start -0.7874 -0.4064)
			(end -0.7874 0.4064)
			(stroke
				(width 0.1524)
				(type default)
			)
			(layer "B.SilkS")
		)
		(fp_line
			(start -0.7874 0.4064)
			(end 0.7874 0.4064)
			(stroke
				(width 0.1524)
				(type default)
			)
			(layer "B.SilkS")
		)
		(fp_line
			(start 0.7874 -0.4064)
			(end -0.7874 -0.4064)
			(stroke
				(width 0.1524)
				(type default)
			)
			(layer "B.SilkS")
		)
		(fp_line
			(start 0.7874 0.4064)
			(end 0.7874 -0.4064)
			(stroke
				(width 0.1524)
				(type default)
			)
			(layer "B.SilkS")
		)
		(fp_line
			(start -0.67945 -0.3048)
			(end -0.67945 0.3048)
			(stroke
				(width 0.1)
				(type default)
			)
			(layer "B.Fab")
		)
		(fp_line
			(start -0.67945 0.3048)
			(end -0.120396 0.3048)
			(stroke
				(width 0.1)
				(type default)
			)
			(layer "B.Fab")
		)
		(fp_line
			(start -0.12065 -0.3048)
			(end -0.67945 -0.3048)
			(stroke
				(width 0.1)
				(type default)
			)
			(layer "B.Fab")
		)
		(fp_line
			(start -0.12065 -0.2794)
			(end -0.12065 -0.3048)
			(stroke
				(width 0.1)
				(type default)
			)
			(layer "B.Fab")
		)
		(fp_line
			(start -0.120396 0.2794)
			(end 0.12065 0.2794)
			(stroke
				(width 0.1)
				(type default)
			)
			(layer "B.Fab")
		)
		(fp_line
			(start -0.120396 0.3048)
			(end -0.120396 0.2794)
			(stroke
				(width 0.1)
				(type default)
			)
			(layer "B.Fab")
		)
		(fp_line
			(start 0.12065 -0.305054)
			(end 0.12065 -0.2794)
			(stroke
				(width 0.1)
				(type default)
			)
			(layer "B.Fab")
		)
		(fp_line
			(start 0.12065 -0.2794)
			(end -0.12065 -0.2794)
			(stroke
				(width 0.1)
				(type default)
			)
			(layer "B.Fab")
		)
		(fp_line
			(start 0.12065 0.2794)
			(end 0.12065 0.3048)
			(stroke
				(width 0.1)
				(type default)
			)
			(layer "B.Fab")
		)
		(fp_line
			(start 0.12065 0.3048)
			(end 0.67945 0.3048)
			(stroke
				(width 0.1)
				(type default)
			)
			(layer "B.Fab")
		)
		(fp_line
			(start 0.67945 -0.305054)
			(end 0.12065 -0.305054)
			(stroke
				(width 0.1)
				(type default)
			)
			(layer "B.Fab")
		)
		(fp_line
			(start 0.67945 0.3048)
			(end 0.67945 -0.305054)
			(stroke
				(width 0.1)
				(type default)
			)
			(layer "B.Fab")
		)
		(pad "1" smd circle
			(at 0.40005 0 180)
			(size 0 0)
			(layers "B.Cu" "B.Mask" "B.Paste")
			(net "PVDDCR_SOC_P1")
		)
		(pad "2" smd circle
			(at -0.40005 0 180)
			(size 0 0)
			(layers "B.Cu" "B.Mask" "B.Paste")
			(net "GND")
		)
	)
	(footprint ""
		(layer "B.Cu")
		(at 451.549516 -10.634726 90)
		(property "Reference" "R8421"
			(at 0 0 90)
			(layer "B.SilkS")
			(hide yes)
			(effects
				(font
					(size 1.27 1.27)
				)
				(justify mirror)
			)
		)
		(property "Value" ""
			(at 0 0 90)
			(layer "B.Fab")
			(effects
				(font
					(size 1.27 1.27)
				)
				(justify mirror)
			)
		)
		(duplicate_pad_numbers_are_jumpers no)
		(fp_line
			(start 0.7874 -0.4064)
			(end -0.7874 -0.4064)
			(stroke
				(width 0.1524)
				(type default)
			)
			(layer "B.SilkS")
		)
		(fp_line
			(start -0.7874 -0.4064)
			(end -0.7874 0.4064)
			(stroke
				(width 0.1524)
				(type default)
			)
			(layer "B.SilkS")
		)
		(fp_line
			(start 0.7874 0.4064)
			(end 0.7874 -0.4064)
			(stroke
				(width 0.1524)
				(type default)
			)
			(layer "B.SilkS")
		)
		(fp_line
			(start -0.7874 0.4064)
			(end 0.7874 0.4064)
			(stroke
				(width 0.1524)
				(type default)
			)
			(layer "B.SilkS")
		)
		(fp_line
			(start 0.67945 -0.305054)
			(end 0.12065 -0.305054)
			(stroke
				(width 0.1)
				(type default)
			)
			(layer "B.Fab")
		)
		(fp_line
			(start 0.12065 -0.305054)
			(end 0.12065 -0.2794)
			(stroke
				(width 0.1)
				(type default)
			)
			(layer "B.Fab")
		)
		(fp_line
			(start -0.12065 -0.3048)
			(end -0.67945 -0.3048)
			(stroke
				(width 0.1)
				(type default)
			)
			(layer "B.Fab")
		)
		(fp_line
			(start -0.67945 -0.3048)
			(end -0.67945 0.3048)
			(stroke
				(width 0.1)
				(type default)
			)
			(layer "B.Fab")
		)
		(fp_line
			(start 0.12065 -0.2794)
			(end -0.12065 -0.2794)
			(stroke
				(width 0.1)
				(type default)
			)
			(layer "B.Fab")
		)
		(fp_line
			(start -0.12065 -0.2794)
			(end -0.12065 -0.3048)
			(stroke
				(width 0.1)
				(type default)
			)
			(layer "B.Fab")
		)
		(fp_line
			(start 0.12065 0.2794)
			(end 0.12065 0.3048)
			(stroke
				(width 0.1)
				(type default)
			)
			(layer "B.Fab")
		)
		(fp_line
			(start -0.120396 0.2794)
			(end 0.12065 0.2794)
			(stroke
				(width 0.1)
				(type default)
			)
			(layer "B.Fab")
		)
		(fp_line
			(start 0.67945 0.3048)
			(end 0.67945 -0.305054)
			(stroke
				(width 0.1)
				(type default)
			)
			(layer "B.Fab")
		)
		(fp_line
			(start 0.12065 0.3048)
			(end 0.67945 0.3048)
			(stroke
				(width 0.1)
				(type default)
			)
			(layer "B.Fab")
		)
		(fp_line
			(start -0.120396 0.3048)
			(end -0.120396 0.2794)
			(stroke
				(width 0.1)
				(type default)
			)
			(layer "B.Fab")
		)
		(fp_line
			(start -0.67945 0.3048)
			(end -0.120396 0.3048)
			(stroke
				(width 0.1)
				(type default)
			)
			(layer "B.Fab")
		)
		(pad "1" smd circle
			(at 0.40005 0 270)
			(size 0 0)
			(layers "B.Cu" "B.Mask" "B.Paste")
			(net "SGPIO_OCP_SFF_DATAIN")
		)
		(pad "2" smd circle
			(at -0.40005 0 270)
			(size 0 0)
			(layers "B.Cu" "B.Mask" "B.Paste")
			(net "P3V3_OCP_SFF")
		)
	)
	(footprint ""
		(layer "B.Cu")
		(at 254.635 -334.01 180)
		(property "Reference" "R1383"
			(at 0 0 0)
			(layer "B.SilkS")
			(hide yes)
			(effects
				(font
					(size 1.27 1.27)
				)
				(justify mirror)
			)
		)
		(property "Value" ""
			(at 0 0 0)
			(layer "B.Fab")
			(effects
				(font
					(size 1.27 1.27)
				)
				(justify mirror)
			)
		)
		(duplicate_pad_numbers_are_jumpers no)
		(fp_line
			(start 0.32512 0.175006)
			(end 0.32512 -0.175006)
			(stroke
				(width 0.1)
				(type default)
			)
			(layer "B.Fab")
		)
		(fp_line
			(start 0.32512 -0.175006)
			(end -0.32512 -0.175006)
			(stroke
				(width 0.1)
				(type default)
			)
			(layer "B.Fab")
		)
		(fp_line
			(start -0.32512 0.175006)
			(end 0.32512 0.175006)
			(stroke
				(width 0.1)
				(type default)
			)
			(layer "B.Fab")
		)
		(fp_line
			(start -0.32512 -0.175006)
			(end -0.32512 0.175006)
			(stroke
				(width 0.1)
				(type default)
			)
			(layer "B.Fab")
		)
		(pad "1" smd rect
			(at 0.2667 0)
			(size 0.3048 0.381)
			(layers "B.Cu" "B.Mask" "B.Paste")
			(net "P1V8_CPU0_RT_1D")
		)
		(pad "2" smd rect
			(at -0.2667 0 180)
			(size 0.3048 0.381)
			(layers "B.Cu" "B.Mask" "B.Paste")
			(net "SMB_RT_CPU0_P2_ROM_MUX_2D_R_SCL")
		)
	)
	(footprint ""
		(layer "B.Cu")
		(at 67.201034 -196.95414)
		(property "Reference" "R6503"
			(at 0 0 0)
			(layer "B.SilkS")
			(hide yes)
			(effects
				(font
					(size 1.27 1.27)
				)
				(justify mirror)
			)
		)
		(property "Value" ""
			(at 0 0 0)
			(layer "B.Fab")
			(effects
				(font
					(size 1.27 1.27)
				)
				(justify mirror)
			)
		)
		(duplicate_pad_numbers_are_jumpers no)
		(fp_line
			(start -0.7874 -0.4064)
			(end -0.7874 0.4064)
			(stroke
				(width 0.1524)
				(type default)
			)
			(layer "B.SilkS")
		)
		(fp_line
			(start -0.7874 0.4064)
			(end 0.7874 0.4064)
			(stroke
				(width 0.1524)
				(type default)
			)
			(layer "B.SilkS")
		)
		(fp_line
			(start 0.7874 -0.4064)
			(end -0.7874 -0.4064)
			(stroke
				(width 0.1524)
				(type default)
			)
			(layer "B.SilkS")
		)
		(fp_line
			(start 0.7874 0.4064)
			(end 0.7874 -0.4064)
			(stroke
				(width 0.1524)
				(type default)
			)
			(layer "B.SilkS")
		)
		(fp_line
			(start -0.67945 -0.3048)
			(end -0.67945 0.3048)
			(stroke
				(width 0.1)
				(type default)
			)
			(layer "B.Fab")
		)
		(fp_line
			(start -0.67945 0.3048)
			(end -0.120396 0.3048)
			(stroke
				(width 0.1)
				(type default)
			)
			(layer "B.Fab")
		)
		(fp_line
			(start -0.12065 -0.3048)
			(end -0.67945 -0.3048)
			(stroke
				(width 0.1)
				(type default)
			)
			(layer "B.Fab")
		)
		(fp_line
			(start -0.12065 -0.2794)
			(end -0.12065 -0.3048)
			(stroke
				(width 0.1)
				(type default)
			)
			(layer "B.Fab")
		)
		(fp_line
			(start -0.120396 0.2794)
			(end 0.12065 0.2794)
			(stroke
				(width 0.1)
				(type default)
			)
			(layer "B.Fab")
		)
		(fp_line
			(start -0.120396 0.3048)
			(end -0.120396 0.2794)
			(stroke
				(width 0.1)
				(type default)
			)
			(layer "B.Fab")
		)
		(fp_line
			(start 0.12065 -0.305054)
			(end 0.12065 -0.2794)
			(stroke
				(width 0.1)
				(type default)
			)
			(layer "B.Fab")
		)
		(fp_line
			(start 0.12065 -0.2794)
			(end -0.12065 -0.2794)
			(stroke
				(width 0.1)
				(type default)
			)
			(layer "B.Fab")
		)
		(fp_line
			(start 0.12065 0.2794)
			(end 0.12065 0.3048)
			(stroke
				(width 0.1)
				(type default)
			)
			(layer "B.Fab")
		)
		(fp_line
			(start 0.12065 0.3048)
			(end 0.67945 0.3048)
			(stroke
				(width 0.1)
				(type default)
			)
			(layer "B.Fab")
		)
		(fp_line
			(start 0.67945 -0.305054)
			(end 0.12065 -0.305054)
			(stroke
				(width 0.1)
				(type default)
			)
			(layer "B.Fab")
		)
		(fp_line
			(start 0.67945 0.3048)
			(end 0.67945 -0.305054)
			(stroke
				(width 0.1)
				(type default)
			)
			(layer "B.Fab")
		)
		(pad "1" smd circle
			(at 0.40005 0 180)
			(size 0 0)
			(layers "B.Cu" "B.Mask" "B.Paste")
			(net "CPU1_FORCE_SELFREFRESH")
		)
		(pad "2" smd circle
			(at -0.40005 0 180)
			(size 0 0)
			(layers "B.Cu" "B.Mask" "B.Paste")
			(net "GND")
		)
	)
	(footprint ""
		(layer "B.Cu")
		(at 432.997102 -351.058226 90)
		(property "Reference" "PC214_2"
			(at 0 0 90)
			(layer "B.SilkS")
			(hide yes)
			(effects
				(font
					(size 1.27 1.27)
				)
				(justify mirror)
			)
		)
		(property "Value" ""
			(at 0 0 90)
			(layer "B.Fab")
			(effects
				(font
					(size 1.27 1.27)
				)
				(justify mirror)
			)
		)
		(duplicate_pad_numbers_are_jumpers no)
		(fp_line
			(start 1.524 -0.762)
			(end -1.524 -0.762)
			(stroke
				(width 0.1524)
				(type default)
			)
			(layer "B.SilkS")
		)
		(fp_line
			(start -1.524 -0.762)
			(end -1.524 0.762)
			(stroke
				(width 0.1524)
				(type default)
			)
			(layer "B.SilkS")
		)
		(fp_line
			(start 1.524 0.762)
			(end 1.524 -0.762)
			(stroke
				(width 0.1524)
				(type default)
			)
			(layer "B.SilkS")
		)
		(fp_line
			(start -1.524 0.762)
			(end 1.524 0.762)
			(stroke
				(width 0.1524)
				(type default)
			)
			(layer "B.SilkS")
		)
		(fp_line
			(start 1.1049 -0.724916)
			(end 1.1049 0.724916)
			(stroke
				(width 0.1)
				(type default)
			)
			(layer "B.Fab")
		)
		(fp_line
			(start -1.1049 -0.724916)
			(end 1.1049 -0.724916)
			(stroke
				(width 0.1)
				(type default)
			)
			(layer "B.Fab")
		)
		(fp_line
			(start 1.1049 0.724916)
			(end -1.1049 0.724916)
			(stroke
				(width 0.1)
				(type default)
			)
			(layer "B.Fab")
		)
		(fp_line
			(start -1.1049 0.724916)
			(end -1.1049 -0.724916)
			(stroke
				(width 0.1)
				(type default)
			)
			(layer "B.Fab")
		)
		(pad "1" smd rect
			(at 0.889 0 90)
			(size 1.016 1.27)
			(layers "B.Cu" "B.Mask" "B.Paste")
			(net "SW_P12V_AUX_PVDD11_S3_P0_FLT")
		)
		(pad "2" smd rect
			(at -0.889 0 90)
			(size 1.016 1.27)
			(layers "B.Cu" "B.Mask" "B.Paste")
			(net "GND")
		)
	)
	(footprint ""
		(layer "B.Cu")
		(at 117.83314 -267.529564)
		(property "Reference" "C2392"
			(at 0 0 0)
			(layer "B.SilkS")
			(hide yes)
			(effects
				(font
					(size 1.27 1.27)
				)
				(justify mirror)
			)
		)
		(property "Value" ""
			(at 0 0 0)
			(layer "B.Fab")
			(effects
				(font
					(size 1.27 1.27)
				)
				(justify mirror)
			)
		)
		(duplicate_pad_numbers_are_jumpers no)
		(fp_line
			(start -0.7874 -0.4064)
			(end -0.7874 0.4064)
			(stroke
				(width 0.1524)
				(type default)
			)
			(layer "B.SilkS")
		)
		(fp_line
			(start -0.7874 0.4064)
			(end 0.7874 0.4064)
			(stroke
				(width 0.1524)
				(type default)
			)
			(layer "B.SilkS")
		)
		(fp_line
			(start 0.7874 -0.4064)
			(end -0.7874 -0.4064)
			(stroke
				(width 0.1524)
				(type default)
			)
			(layer "B.SilkS")
		)
		(fp_line
			(start 0.7874 0.4064)
			(end 0.7874 -0.4064)
			(stroke
				(width 0.1524)
				(type default)
			)
			(layer "B.SilkS")
		)
		(fp_line
			(start -0.67945 -0.3048)
			(end -0.67945 0.3048)
			(stroke
				(width 0.1)
				(type default)
			)
			(layer "B.Fab")
		)
		(fp_line
			(start -0.67945 0.3048)
			(end -0.120396 0.3048)
			(stroke
				(width 0.1)
				(type default)
			)
			(layer "B.Fab")
		)
		(fp_line
			(start -0.12065 -0.3048)
			(end -0.67945 -0.3048)
			(stroke
				(width 0.1)
				(type default)
			)
			(layer "B.Fab")
		)
		(fp_line
			(start -0.12065 -0.2794)
			(end -0.12065 -0.3048)
			(stroke
				(width 0.1)
				(type default)
			)
			(layer "B.Fab")
		)
		(fp_line
			(start -0.120396 0.2794)
			(end 0.12065 0.2794)
			(stroke
				(width 0.1)
				(type default)
			)
			(layer "B.Fab")
		)
		(fp_line
			(start -0.120396 0.3048)
			(end -0.120396 0.2794)
			(stroke
				(width 0.1)
				(type default)
			)
			(layer "B.Fab")
		)
		(fp_line
			(start 0.12065 -0.305054)
			(end 0.12065 -0.2794)
			(stroke
				(width 0.1)
				(type default)
			)
			(layer "B.Fab")
		)
		(fp_line
			(start 0.12065 -0.2794)
			(end -0.12065 -0.2794)
			(stroke
				(width 0.1)
				(type default)
			)
			(layer "B.Fab")
		)
		(fp_line
			(start 0.12065 0.2794)
			(end 0.12065 0.3048)
			(stroke
				(width 0.1)
				(type default)
			)
			(layer "B.Fab")
		)
		(fp_line
			(start 0.12065 0.3048)
			(end 0.67945 0.3048)
			(stroke
				(width 0.1)
				(type default)
			)
			(layer "B.Fab")
		)
		(fp_line
			(start 0.67945 -0.305054)
			(end 0.12065 -0.305054)
			(stroke
				(width 0.1)
				(type default)
			)
			(layer "B.Fab")
		)
		(fp_line
			(start 0.67945 0.3048)
			(end 0.67945 -0.305054)
			(stroke
				(width 0.1)
				(type default)
			)
			(layer "B.Fab")
		)
		(pad "1" smd circle
			(at 0.40005 0 180)
			(size 0 0)
			(layers "B.Cu" "B.Mask" "B.Paste")
			(net "PVDDCR_CPU1_P1")
		)
		(pad "2" smd circle
			(at -0.40005 0 180)
			(size 0 0)
			(layers "B.Cu" "B.Mask" "B.Paste")
			(net "GND")
		)
	)
	(footprint ""
		(layer "B.Cu")
		(at 178.981608 -126.833376 90)
		(property "Reference" "R6711"
			(at 0 0 90)
			(layer "B.SilkS")
			(hide yes)
			(effects
				(font
					(size 1.27 1.27)
				)
				(justify mirror)
			)
		)
		(property "Value" ""
			(at 0 0 90)
			(layer "B.Fab")
			(effects
				(font
					(size 1.27 1.27)
				)
				(justify mirror)
			)
		)
		(duplicate_pad_numbers_are_jumpers no)
		(fp_line
			(start 0.7874 -0.4064)
			(end -0.7874 -0.4064)
			(stroke
				(width 0.1524)
				(type default)
			)
			(layer "B.SilkS")
		)
		(fp_line
			(start -0.7874 -0.4064)
			(end -0.7874 0.4064)
			(stroke
				(width 0.1524)
				(type default)
			)
			(layer "B.SilkS")
		)
		(fp_line
			(start 0.7874 0.4064)
			(end 0.7874 -0.4064)
			(stroke
				(width 0.1524)
				(type default)
			)
			(layer "B.SilkS")
		)
		(fp_line
			(start -0.7874 0.4064)
			(end 0.7874 0.4064)
			(stroke
				(width 0.1524)
				(type default)
			)
			(layer "B.SilkS")
		)
		(fp_line
			(start 0.67945 -0.305054)
			(end 0.12065 -0.305054)
			(stroke
				(width 0.1)
				(type default)
			)
			(layer "B.Fab")
		)
		(fp_line
			(start 0.12065 -0.305054)
			(end 0.12065 -0.2794)
			(stroke
				(width 0.1)
				(type default)
			)
			(layer "B.Fab")
		)
		(fp_line
			(start -0.12065 -0.3048)
			(end -0.67945 -0.3048)
			(stroke
				(width 0.1)
				(type default)
			)
			(layer "B.Fab")
		)
		(fp_line
			(start -0.67945 -0.3048)
			(end -0.67945 0.3048)
			(stroke
				(width 0.1)
				(type default)
			)
			(layer "B.Fab")
		)
		(fp_line
			(start 0.12065 -0.2794)
			(end -0.12065 -0.2794)
			(stroke
				(width 0.1)
				(type default)
			)
			(layer "B.Fab")
		)
		(fp_line
			(start -0.12065 -0.2794)
			(end -0.12065 -0.3048)
			(stroke
				(width 0.1)
				(type default)
			)
			(layer "B.Fab")
		)
		(fp_line
			(start 0.12065 0.2794)
			(end 0.12065 0.3048)
			(stroke
				(width 0.1)
				(type default)
			)
			(layer "B.Fab")
		)
		(fp_line
			(start -0.120396 0.2794)
			(end 0.12065 0.2794)
			(stroke
				(width 0.1)
				(type default)
			)
			(layer "B.Fab")
		)
		(fp_line
			(start 0.67945 0.3048)
			(end 0.67945 -0.305054)
			(stroke
				(width 0.1)
				(type default)
			)
			(layer "B.Fab")
		)
		(fp_line
			(start 0.12065 0.3048)
			(end 0.67945 0.3048)
			(stroke
				(width 0.1)
				(type default)
			)
			(layer "B.Fab")
		)
		(fp_line
			(start -0.120396 0.3048)
			(end -0.120396 0.2794)
			(stroke
				(width 0.1)
				(type default)
			)
			(layer "B.Fab")
		)
		(fp_line
			(start -0.67945 0.3048)
			(end -0.120396 0.3048)
			(stroke
				(width 0.1)
				(type default)
			)
			(layer "B.Fab")
		)
		(pad "1" smd circle
			(at 0.40005 0 270)
			(size 0 0)
			(layers "B.Cu" "B.Mask" "B.Paste")
			(net "RST_RT_CPU1_P0_RESET_R_N")
		)
		(pad "2" smd circle
			(at -0.40005 0 270)
			(size 0 0)
			(layers "B.Cu" "B.Mask" "B.Paste")
			(net "RST_RT_CPU1_P0_RESET_R2_N")
		)
	)
	(footprint ""
		(layer "B.Cu")
		(at 100.271834 -265.045952)
		(property "Reference" "C2117"
			(at 0 0 0)
			(layer "B.SilkS")
			(hide yes)
			(effects
				(font
					(size 1.27 1.27)
				)
				(justify mirror)
			)
		)
		(property "Value" ""
			(at 0 0 0)
			(layer "B.Fab")
			(effects
				(font
					(size 1.27 1.27)
				)
				(justify mirror)
			)
		)
		(duplicate_pad_numbers_are_jumpers no)
		(fp_line
			(start -0.7874 -0.4064)
			(end -0.7874 0.4064)
			(stroke
				(width 0.1524)
				(type default)
			)
			(layer "B.SilkS")
		)
		(fp_line
			(start -0.7874 0.4064)
			(end 0.7874 0.4064)
			(stroke
				(width 0.1524)
				(type default)
			)
			(layer "B.SilkS")
		)
		(fp_line
			(start 0.7874 -0.4064)
			(end -0.7874 -0.4064)
			(stroke
				(width 0.1524)
				(type default)
			)
			(layer "B.SilkS")
		)
		(fp_line
			(start 0.7874 0.4064)
			(end 0.7874 -0.4064)
			(stroke
				(width 0.1524)
				(type default)
			)
			(layer "B.SilkS")
		)
		(fp_line
			(start -0.67945 -0.3048)
			(end -0.67945 0.3048)
			(stroke
				(width 0.1)
				(type default)
			)
			(layer "B.Fab")
		)
		(fp_line
			(start -0.67945 0.3048)
			(end -0.120396 0.3048)
			(stroke
				(width 0.1)
				(type default)
			)
			(layer "B.Fab")
		)
		(fp_line
			(start -0.12065 -0.3048)
			(end -0.67945 -0.3048)
			(stroke
				(width 0.1)
				(type default)
			)
			(layer "B.Fab")
		)
		(fp_line
			(start -0.12065 -0.2794)
			(end -0.12065 -0.3048)
			(stroke
				(width 0.1)
				(type default)
			)
			(layer "B.Fab")
		)
		(fp_line
			(start -0.120396 0.2794)
			(end 0.12065 0.2794)
			(stroke
				(width 0.1)
				(type default)
			)
			(layer "B.Fab")
		)
		(fp_line
			(start -0.120396 0.3048)
			(end -0.120396 0.2794)
			(stroke
				(width 0.1)
				(type default)
			)
			(layer "B.Fab")
		)
		(fp_line
			(start 0.12065 -0.305054)
			(end 0.12065 -0.2794)
			(stroke
				(width 0.1)
				(type default)
			)
			(layer "B.Fab")
		)
		(fp_line
			(start 0.12065 -0.2794)
			(end -0.12065 -0.2794)
			(stroke
				(width 0.1)
				(type default)
			)
			(layer "B.Fab")
		)
		(fp_line
			(start 0.12065 0.2794)
			(end 0.12065 0.3048)
			(stroke
				(width 0.1)
				(type default)
			)
			(layer "B.Fab")
		)
		(fp_line
			(start 0.12065 0.3048)
			(end 0.67945 0.3048)
			(stroke
				(width 0.1)
				(type default)
			)
			(layer "B.Fab")
		)
		(fp_line
			(start 0.67945 -0.305054)
			(end 0.12065 -0.305054)
			(stroke
				(width 0.1)
				(type default)
			)
			(layer "B.Fab")
		)
		(fp_line
			(start 0.67945 0.3048)
			(end 0.67945 -0.305054)
			(stroke
				(width 0.1)
				(type default)
			)
			(layer "B.Fab")
		)
		(pad "1" smd circle
			(at 0.40005 0 180)
			(size 0 0)
			(layers "B.Cu" "B.Mask" "B.Paste")
			(net "PVDDIO_P1")
		)
		(pad "2" smd circle
			(at -0.40005 0 180)
			(size 0 0)
			(layers "B.Cu" "B.Mask" "B.Paste")
			(net "GND")
		)
	)
	(footprint ""
		(layer "B.Cu")
		(at 141.53388 -33.475422)
		(property "Reference" "L6000"
			(at 0 0 0)
			(layer "B.SilkS")
			(hide yes)
			(effects
				(font
					(size 1.27 1.27)
				)
				(justify mirror)
			)
		)
		(property "Value" ""
			(at 0 0 0)
			(layer "B.Fab")
			(effects
				(font
					(size 1.27 1.27)
				)
				(justify mirror)
			)
		)
		(duplicate_pad_numbers_are_jumpers no)
		(fp_line
			(start -1.63576 -0.8128)
			(end -1.63576 0.8128)
			(stroke
				(width 0.1524)
				(type default)
			)
			(layer "B.SilkS")
		)
		(fp_line
			(start -1.63576 0.8128)
			(end 1.63576 0.8128)
			(stroke
				(width 0.1524)
				(type default)
			)
			(layer "B.SilkS")
		)
		(fp_line
			(start 1.63576 -0.8128)
			(end -1.63576 -0.8128)
			(stroke
				(width 0.1524)
				(type default)
			)
			(layer "B.SilkS")
		)
		(fp_line
			(start 1.63576 -0.8128)
			(end 1.63576 0.8128)
			(stroke
				(width 0.1524)
				(type default)
			)
			(layer "B.SilkS")
		)
		(fp_line
			(start -1.560576 -0.738632)
			(end 1.56083 -0.738632)
			(stroke
				(width 0.1)
				(type default)
			)
			(layer "B.Fab")
		)
		(fp_line
			(start -1.560576 0.7366)
			(end -1.560576 -0.738632)
			(stroke
				(width 0.1)
				(type default)
			)
			(layer "B.Fab")
		)
		(fp_line
			(start -1.524 0.7366)
			(end -1.560576 0.7366)
			(stroke
				(width 0.1)
				(type default)
			)
			(layer "B.Fab")
		)
		(fp_line
			(start 1.524 0.7366)
			(end -1.524 0.7366)
			(stroke
				(width 0.1)
				(type default)
			)
			(layer "B.Fab")
		)
		(fp_line
			(start 1.56083 -0.738632)
			(end 1.56083 0.7366)
			(stroke
				(width 0.1)
				(type default)
			)
			(layer "B.Fab")
		)
		(fp_line
			(start 1.56083 0.7366)
			(end 1.524 0.7366)
			(stroke
				(width 0.1)
				(type default)
			)
			(layer "B.Fab")
		)
		(pad "1" smd rect
			(at 0.94996 0)
			(size 1.1176 1.3716)
			(layers "B.Cu" "B.Mask" "B.Paste")
			(net "P3V3_AUX")
		)
		(pad "2" smd rect
			(at -0.94996 0)
			(size 1.1176 1.3716)
			(layers "B.Cu" "B.Mask" "B.Paste")
			(net "P3V3_AUX_CPU0_USB_AVDD33")
		)
	)
	(footprint ""
		(layer "B.Cu")
		(at 423.256456 -193.99631)
		(property "Reference" "C120"
			(at 0 0 0)
			(layer "B.SilkS")
			(hide yes)
			(effects
				(font
					(size 1.27 1.27)
				)
				(justify mirror)
			)
		)
		(property "Value" ""
			(at 0 0 0)
			(layer "B.Fab")
			(effects
				(font
					(size 1.27 1.27)
				)
				(justify mirror)
			)
		)
		(duplicate_pad_numbers_are_jumpers no)
		(fp_line
			(start -0.7874 -0.4064)
			(end -0.7874 0.4064)
			(stroke
				(width 0.1524)
				(type default)
			)
			(layer "B.SilkS")
		)
		(fp_line
			(start -0.7874 0.4064)
			(end 0.7874 0.4064)
			(stroke
				(width 0.1524)
				(type default)
			)
			(layer "B.SilkS")
		)
		(fp_line
			(start 0.7874 -0.4064)
			(end -0.7874 -0.4064)
			(stroke
				(width 0.1524)
				(type default)
			)
			(layer "B.SilkS")
		)
		(fp_line
			(start 0.7874 0.4064)
			(end 0.7874 -0.4064)
			(stroke
				(width 0.1524)
				(type default)
			)
			(layer "B.SilkS")
		)
		(fp_line
			(start -0.67945 -0.3048)
			(end -0.67945 0.3048)
			(stroke
				(width 0.1)
				(type default)
			)
			(layer "B.Fab")
		)
		(fp_line
			(start -0.67945 0.3048)
			(end -0.120396 0.3048)
			(stroke
				(width 0.1)
				(type default)
			)
			(layer "B.Fab")
		)
		(fp_line
			(start -0.12065 -0.3048)
			(end -0.67945 -0.3048)
			(stroke
				(width 0.1)
				(type default)
			)
			(layer "B.Fab")
		)
		(fp_line
			(start -0.12065 -0.2794)
			(end -0.12065 -0.3048)
			(stroke
				(width 0.1)
				(type default)
			)
			(layer "B.Fab")
		)
		(fp_line
			(start -0.120396 0.2794)
			(end 0.12065 0.2794)
			(stroke
				(width 0.1)
				(type default)
			)
			(layer "B.Fab")
		)
		(fp_line
			(start -0.120396 0.3048)
			(end -0.120396 0.2794)
			(stroke
				(width 0.1)
				(type default)
			)
			(layer "B.Fab")
		)
		(fp_line
			(start 0.12065 -0.305054)
			(end 0.12065 -0.2794)
			(stroke
				(width 0.1)
				(type default)
			)
			(layer "B.Fab")
		)
		(fp_line
			(start 0.12065 -0.2794)
			(end -0.12065 -0.2794)
			(stroke
				(width 0.1)
				(type default)
			)
			(layer "B.Fab")
		)
		(fp_line
			(start 0.12065 0.2794)
			(end 0.12065 0.3048)
			(stroke
				(width 0.1)
				(type default)
			)
			(layer "B.Fab")
		)
		(fp_line
			(start 0.12065 0.3048)
			(end 0.67945 0.3048)
			(stroke
				(width 0.1)
				(type default)
			)
			(layer "B.Fab")
		)
		(fp_line
			(start 0.67945 -0.305054)
			(end 0.12065 -0.305054)
			(stroke
				(width 0.1)
				(type default)
			)
			(layer "B.Fab")
		)
		(fp_line
			(start 0.67945 0.3048)
			(end 0.67945 -0.305054)
			(stroke
				(width 0.1)
				(type default)
			)
			(layer "B.Fab")
		)
		(pad "1" smd circle
			(at 0.40005 0 180)
			(size 0 0)
			(layers "B.Cu" "B.Mask" "B.Paste")
			(net "P3V3_AUX")
		)
		(pad "2" smd circle
			(at -0.40005 0 180)
			(size 0 0)
			(layers "B.Cu" "B.Mask" "B.Paste")
			(net "GND")
		)
	)
	(footprint ""
		(layer "B.Cu")
		(at 403.088856 -168.717468 -90)
		(property "Reference" "PC592_2"
			(at 0 0 90)
			(layer "B.SilkS")
			(hide yes)
			(effects
				(font
					(size 1.27 1.27)
				)
				(justify mirror)
			)
		)
		(property "Value" ""
			(at 0 0 90)
			(layer "B.Fab")
			(effects
				(font
					(size 1.27 1.27)
				)
				(justify mirror)
			)
		)
		(duplicate_pad_numbers_are_jumpers no)
		(fp_line
			(start -1.524 0.762)
			(end 1.524 0.762)
			(stroke
				(width 0.1524)
				(type default)
			)
			(layer "B.SilkS")
		)
		(fp_line
			(start 1.524 0.762)
			(end 1.524 -0.762)
			(stroke
				(width 0.1524)
				(type default)
			)
			(layer "B.SilkS")
		)
		(fp_line
			(start -1.524 -0.762)
			(end -1.524 0.762)
			(stroke
				(width 0.1524)
				(type default)
			)
			(layer "B.SilkS")
		)
		(fp_line
			(start 1.524 -0.762)
			(end -1.524 -0.762)
			(stroke
				(width 0.1524)
				(type default)
			)
			(layer "B.SilkS")
		)
		(fp_line
			(start -1.1049 0.724916)
			(end -1.1049 -0.724916)
			(stroke
				(width 0.1)
				(type default)
			)
			(layer "B.Fab")
		)
		(fp_line
			(start 1.1049 0.724916)
			(end -1.1049 0.724916)
			(stroke
				(width 0.1)
				(type default)
			)
			(layer "B.Fab")
		)
		(fp_line
			(start -1.1049 -0.724916)
			(end 1.1049 -0.724916)
			(stroke
				(width 0.1)
				(type default)
			)
			(layer "B.Fab")
		)
		(fp_line
			(start 1.1049 -0.724916)
			(end 1.1049 0.724916)
			(stroke
				(width 0.1)
				(type default)
			)
			(layer "B.Fab")
		)
		(pad "1" smd rect
			(at 0.889 0 270)
			(size 1.016 1.27)
			(layers "B.Cu" "B.Mask" "B.Paste")
			(net "SW_P12V_AUX_PVDDCR_SOC_P0_FLT")
		)
		(pad "2" smd rect
			(at -0.889 0 270)
			(size 1.016 1.27)
			(layers "B.Cu" "B.Mask" "B.Paste")
			(net "GND")
		)
	)
	(footprint ""
		(layer "B.Cu")
		(at 360.366056 -256.012188 -90)
		(property "Reference" "C2135"
			(at 0 0 90)
			(layer "B.SilkS")
			(hide yes)
			(effects
				(font
					(size 1.27 1.27)
				)
				(justify mirror)
			)
		)
		(property "Value" ""
			(at 0 0 90)
			(layer "B.Fab")
			(effects
				(font
					(size 1.27 1.27)
				)
				(justify mirror)
			)
		)
		(duplicate_pad_numbers_are_jumpers no)
		(fp_line
			(start -0.7874 0.4064)
			(end 0.7874 0.4064)
			(stroke
				(width 0.1524)
				(type default)
			)
			(layer "B.SilkS")
		)
		(fp_line
			(start 0.7874 0.4064)
			(end 0.7874 -0.4064)
			(stroke
				(width 0.1524)
				(type default)
			)
			(layer "B.SilkS")
		)
		(fp_line
			(start -0.7874 -0.4064)
			(end -0.7874 0.4064)
			(stroke
				(width 0.1524)
				(type default)
			)
			(layer "B.SilkS")
		)
		(fp_line
			(start 0.7874 -0.4064)
			(end -0.7874 -0.4064)
			(stroke
				(width 0.1524)
				(type default)
			)
			(layer "B.SilkS")
		)
		(fp_line
			(start -0.67945 0.3048)
			(end -0.120396 0.3048)
			(stroke
				(width 0.1)
				(type default)
			)
			(layer "B.Fab")
		)
		(fp_line
			(start -0.120396 0.3048)
			(end -0.120396 0.2794)
			(stroke
				(width 0.1)
				(type default)
			)
			(layer "B.Fab")
		)
		(fp_line
			(start 0.12065 0.3048)
			(end 0.67945 0.3048)
			(stroke
				(width 0.1)
				(type default)
			)
			(layer "B.Fab")
		)
		(fp_line
			(start 0.67945 0.3048)
			(end 0.67945 -0.305054)
			(stroke
				(width 0.1)
				(type default)
			)
			(layer "B.Fab")
		)
		(fp_line
			(start -0.120396 0.2794)
			(end 0.12065 0.2794)
			(stroke
				(width 0.1)
				(type default)
			)
			(layer "B.Fab")
		)
		(fp_line
			(start 0.12065 0.2794)
			(end 0.12065 0.3048)
			(stroke
				(width 0.1)
				(type default)
			)
			(layer "B.Fab")
		)
		(fp_line
			(start -0.12065 -0.2794)
			(end -0.12065 -0.3048)
			(stroke
				(width 0.1)
				(type default)
			)
			(layer "B.Fab")
		)
		(fp_line
			(start 0.12065 -0.2794)
			(end -0.12065 -0.2794)
			(stroke
				(width 0.1)
				(type default)
			)
			(layer "B.Fab")
		)
		(fp_line
			(start -0.67945 -0.3048)
			(end -0.67945 0.3048)
			(stroke
				(width 0.1)
				(type default)
			)
			(layer "B.Fab")
		)
		(fp_line
			(start -0.12065 -0.3048)
			(end -0.67945 -0.3048)
			(stroke
				(width 0.1)
				(type default)
			)
			(layer "B.Fab")
		)
		(fp_line
			(start 0.12065 -0.305054)
			(end 0.12065 -0.2794)
			(stroke
				(width 0.1)
				(type default)
			)
			(layer "B.Fab")
		)
		(fp_line
			(start 0.67945 -0.305054)
			(end 0.12065 -0.305054)
			(stroke
				(width 0.1)
				(type default)
			)
			(layer "B.Fab")
		)
		(pad "1" smd circle
			(at 0.40005 0 90)
			(size 0 0)
			(layers "B.Cu" "B.Mask" "B.Paste")
			(net "PVDDCR_SOC_P0")
		)
		(pad "2" smd circle
			(at -0.40005 0 90)
			(size 0 0)
			(layers "B.Cu" "B.Mask" "B.Paste")
			(net "GND")
		)
	)
	(footprint ""
		(layer "B.Cu")
		(at 406.717754 -330.93533)
		(property "Reference" "R5028"
			(at 0 0 0)
			(layer "B.SilkS")
			(hide yes)
			(effects
				(font
					(size 1.27 1.27)
				)
				(justify mirror)
			)
		)
		(property "Value" ""
			(at 0 0 0)
			(layer "B.Fab")
			(effects
				(font
					(size 1.27 1.27)
				)
				(justify mirror)
			)
		)
		(duplicate_pad_numbers_are_jumpers no)
		(fp_line
			(start -0.7874 -0.4064)
			(end -0.7874 0.4064)
			(stroke
				(width 0.1524)
				(type default)
			)
			(layer "B.SilkS")
		)
		(fp_line
			(start -0.7874 0.4064)
			(end 0.7874 0.4064)
			(stroke
				(width 0.1524)
				(type default)
			)
			(layer "B.SilkS")
		)
		(fp_line
			(start 0.7874 -0.4064)
			(end -0.7874 -0.4064)
			(stroke
				(width 0.1524)
				(type default)
			)
			(layer "B.SilkS")
		)
		(fp_line
			(start 0.7874 0.4064)
			(end 0.7874 -0.4064)
			(stroke
				(width 0.1524)
				(type default)
			)
			(layer "B.SilkS")
		)
		(fp_line
			(start -0.67945 -0.3048)
			(end -0.67945 0.3048)
			(stroke
				(width 0.1)
				(type default)
			)
			(layer "B.Fab")
		)
		(fp_line
			(start -0.67945 0.3048)
			(end -0.120396 0.3048)
			(stroke
				(width 0.1)
				(type default)
			)
			(layer "B.Fab")
		)
		(fp_line
			(start -0.12065 -0.3048)
			(end -0.67945 -0.3048)
			(stroke
				(width 0.1)
				(type default)
			)
			(layer "B.Fab")
		)
		(fp_line
			(start -0.12065 -0.2794)
			(end -0.12065 -0.3048)
			(stroke
				(width 0.1)
				(type default)
			)
			(layer "B.Fab")
		)
		(fp_line
			(start -0.120396 0.2794)
			(end 0.12065 0.2794)
			(stroke
				(width 0.1)
				(type default)
			)
			(layer "B.Fab")
		)
		(fp_line
			(start -0.120396 0.3048)
			(end -0.120396 0.2794)
			(stroke
				(width 0.1)
				(type default)
			)
			(layer "B.Fab")
		)
		(fp_line
			(start 0.12065 -0.305054)
			(end 0.12065 -0.2794)
			(stroke
				(width 0.1)
				(type default)
			)
			(layer "B.Fab")
		)
		(fp_line
			(start 0.12065 -0.2794)
			(end -0.12065 -0.2794)
			(stroke
				(width 0.1)
				(type default)
			)
			(layer "B.Fab")
		)
		(fp_line
			(start 0.12065 0.2794)
			(end 0.12065 0.3048)
			(stroke
				(width 0.1)
				(type default)
			)
			(layer "B.Fab")
		)
		(fp_line
			(start 0.12065 0.3048)
			(end 0.67945 0.3048)
			(stroke
				(width 0.1)
				(type default)
			)
			(layer "B.Fab")
		)
		(fp_line
			(start 0.67945 -0.305054)
			(end 0.12065 -0.305054)
			(stroke
				(width 0.1)
				(type default)
			)
			(layer "B.Fab")
		)
		(fp_line
			(start 0.67945 0.3048)
			(end 0.67945 -0.305054)
			(stroke
				(width 0.1)
				(type default)
			)
			(layer "B.Fab")
		)
		(pad "1" smd circle
			(at 0.40005 0 180)
			(size 0 0)
			(layers "B.Cu" "B.Mask" "B.Paste")
			(net "GND")
		)
		(pad "2" smd circle
			(at -0.40005 0 180)
			(size 0 0)
			(layers "B.Cu" "B.Mask" "B.Paste")
			(net "IRQ_BMC_SMI_N")
		)
	)
	(footprint ""
		(layer "B.Cu")
		(at 479.100642 -353.385882)
		(property "Reference" "DB15"
			(at 2.448814 -5.35051 270)
			(unlocked yes)
			(layer "B.SilkS")
			(effects
				(font
					(size 0.7874 0.5842)
					(thickness 0.1524)
				)
				(justify left mirror)
			)
		)
		(property "Value" ""
			(at 0 0 0)
			(layer "B.Fab")
			(effects
				(font
					(size 1.27 1.27)
				)
				(justify mirror)
			)
		)
		(duplicate_pad_numbers_are_jumpers no)
		(fp_line
			(start -3.330702 -4.771136)
			(end 0 4.011168)
			(stroke
				(width 0.1524)
				(type default)
			)
			(layer "B.SilkS")
		)
		(fp_line
			(start 0 4.011168)
			(end 3.330702 -4.771136)
			(stroke
				(width 0.1524)
				(type default)
			)
			(layer "B.SilkS")
		)
		(fp_line
			(start 3.330702 -4.771136)
			(end -3.330702 -4.771136)
			(stroke
				(width 0.1524)
				(type default)
			)
			(layer "B.SilkS")
		)
		(fp_line
			(start -3.330702 -4.771136)
			(end 0 4.011168)
			(stroke
				(width 0.1)
				(type default)
			)
			(layer "B.Fab")
		)
		(fp_line
			(start 0 4.011168)
			(end 3.330702 -4.771136)
			(stroke
				(width 0.1)
				(type default)
			)
			(layer "B.Fab")
		)
		(fp_line
			(start 3.330702 -4.771136)
			(end -3.330702 -4.771136)
			(stroke
				(width 0.1)
				(type default)
			)
			(layer "B.Fab")
		)
		(pad "1" thru_hole circle
			(at 0 0 180)
			(size 2.159 2.159)
			(drill 1.7018)
			(layers "*.Cu" "*.Mask")
			(remove_unused_layers no)
			(net "T1_GND")
			(clearance 0.0254)
			(thermal_gap 0.0254)
		)
		(pad "2" thru_hole circle
			(at 1.27 -3.348736 180)
			(size 2.159 2.159)
			(drill 1.7018)
			(layers "*.Cu" "*.Mask")
			(remove_unused_layers no)
			(net "TDR_SE_50_OHM_IN5")
			(clearance 0.0254)
			(thermal_gap 0.0254)
		)
		(pad "3" thru_hole circle
			(at -1.27 -3.348736 180)
			(size 2.159 2.159)
			(drill 1.7018)
			(layers "*.Cu" "*.Mask")
			(remove_unused_layers no)
			(net "TDR_SE_50_OHM_IN5")
			(clearance 0.0254)
			(thermal_gap 0.0254)
		)
	)
	(footprint ""
		(layer "B.Cu")
		(at 117.769386 -264.354564)
		(property "Reference" "C2128"
			(at 0 0 0)
			(layer "B.SilkS")
			(hide yes)
			(effects
				(font
					(size 1.27 1.27)
				)
				(justify mirror)
			)
		)
		(property "Value" ""
			(at 0 0 0)
			(layer "B.Fab")
			(effects
				(font
					(size 1.27 1.27)
				)
				(justify mirror)
			)
		)
		(duplicate_pad_numbers_are_jumpers no)
		(fp_line
			(start -0.7874 -0.4064)
			(end -0.7874 0.4064)
			(stroke
				(width 0.1524)
				(type default)
			)
			(layer "B.SilkS")
		)
		(fp_line
			(start -0.7874 0.4064)
			(end 0.7874 0.4064)
			(stroke
				(width 0.1524)
				(type default)
			)
			(layer "B.SilkS")
		)
		(fp_line
			(start 0.7874 -0.4064)
			(end -0.7874 -0.4064)
			(stroke
				(width 0.1524)
				(type default)
			)
			(layer "B.SilkS")
		)
		(fp_line
			(start 0.7874 0.4064)
			(end 0.7874 -0.4064)
			(stroke
				(width 0.1524)
				(type default)
			)
			(layer "B.SilkS")
		)
		(fp_line
			(start -0.67945 -0.3048)
			(end -0.67945 0.3048)
			(stroke
				(width 0.1)
				(type default)
			)
			(layer "B.Fab")
		)
		(fp_line
			(start -0.67945 0.3048)
			(end -0.120396 0.3048)
			(stroke
				(width 0.1)
				(type default)
			)
			(layer "B.Fab")
		)
		(fp_line
			(start -0.12065 -0.3048)
			(end -0.67945 -0.3048)
			(stroke
				(width 0.1)
				(type default)
			)
			(layer "B.Fab")
		)
		(fp_line
			(start -0.12065 -0.2794)
			(end -0.12065 -0.3048)
			(stroke
				(width 0.1)
				(type default)
			)
			(layer "B.Fab")
		)
		(fp_line
			(start -0.120396 0.2794)
			(end 0.12065 0.2794)
			(stroke
				(width 0.1)
				(type default)
			)
			(layer "B.Fab")
		)
		(fp_line
			(start -0.120396 0.3048)
			(end -0.120396 0.2794)
			(stroke
				(width 0.1)
				(type default)
			)
			(layer "B.Fab")
		)
		(fp_line
			(start 0.12065 -0.305054)
			(end 0.12065 -0.2794)
			(stroke
				(width 0.1)
				(type default)
			)
			(layer "B.Fab")
		)
		(fp_line
			(start 0.12065 -0.2794)
			(end -0.12065 -0.2794)
			(stroke
				(width 0.1)
				(type default)
			)
			(layer "B.Fab")
		)
		(fp_line
			(start 0.12065 0.2794)
			(end 0.12065 0.3048)
			(stroke
				(width 0.1)
				(type default)
			)
			(layer "B.Fab")
		)
		(fp_line
			(start 0.12065 0.3048)
			(end 0.67945 0.3048)
			(stroke
				(width 0.1)
				(type default)
			)
			(layer "B.Fab")
		)
		(fp_line
			(start 0.67945 -0.305054)
			(end 0.12065 -0.305054)
			(stroke
				(width 0.1)
				(type default)
			)
			(layer "B.Fab")
		)
		(fp_line
			(start 0.67945 0.3048)
			(end 0.67945 -0.305054)
			(stroke
				(width 0.1)
				(type default)
			)
			(layer "B.Fab")
		)
		(pad "1" smd circle
			(at 0.40005 0 180)
			(size 0 0)
			(layers "B.Cu" "B.Mask" "B.Paste")
			(net "PVDD11_S3_P1")
		)
		(pad "2" smd circle
			(at -0.40005 0 180)
			(size 0 0)
			(layers "B.Cu" "B.Mask" "B.Paste")
			(net "GND")
		)
	)
	(footprint ""
		(layer "B.Cu")
		(at 303.518316 -396.393162 -90)
		(property "Reference" "C580"
			(at 0 0 90)
			(layer "B.SilkS")
			(hide yes)
			(effects
				(font
					(size 1.27 1.27)
				)
				(justify mirror)
			)
		)
		(property "Value" ""
			(at 0 0 90)
			(layer "B.Fab")
			(effects
				(font
					(size 1.27 1.27)
				)
				(justify mirror)
			)
		)
		(duplicate_pad_numbers_are_jumpers no)
		(fp_line
			(start -0.299974 0.150114)
			(end 0.299974 0.150114)
			(stroke
				(width 0.1)
				(type default)
			)
			(layer "B.Fab")
		)
		(fp_line
			(start 0.299974 0.150114)
			(end 0.299974 -0.150114)
			(stroke
				(width 0.1)
				(type default)
			)
			(layer "B.Fab")
		)
		(fp_line
			(start -0.299974 -0.150114)
			(end -0.299974 0.150114)
			(stroke
				(width 0.1)
				(type default)
			)
			(layer "B.Fab")
		)
		(fp_line
			(start 0.299974 -0.150114)
			(end -0.299974 -0.150114)
			(stroke
				(width 0.1)
				(type default)
			)
			(layer "B.Fab")
		)
		(pad "1" smd rect
			(at 0.2667 0 90)
			(size 0.3048 0.381)
			(layers "B.Cu" "B.Mask" "B.Paste")
			(net "P0V9_CPU0_RT0_2A")
		)
		(pad "2" smd rect
			(at -0.2667 0 90)
			(size 0.3048 0.381)
			(layers "B.Cu" "B.Mask" "B.Paste")
			(net "GND")
		)
	)
	(footprint ""
		(layer "B.Cu")
		(at 401.554696 -342.950292 -90)
		(property "Reference" "R943"
			(at 0 0 90)
			(layer "B.SilkS")
			(hide yes)
			(effects
				(font
					(size 1.27 1.27)
				)
				(justify mirror)
			)
		)
		(property "Value" ""
			(at 0 0 90)
			(layer "B.Fab")
			(effects
				(font
					(size 1.27 1.27)
				)
				(justify mirror)
			)
		)
		(duplicate_pad_numbers_are_jumpers no)
		(fp_line
			(start -0.7874 0.4064)
			(end 0.7874 0.4064)
			(stroke
				(width 0.1524)
				(type default)
			)
			(layer "B.SilkS")
		)
		(fp_line
			(start 0.7874 0.4064)
			(end 0.7874 -0.4064)
			(stroke
				(width 0.1524)
				(type default)
			)
			(layer "B.SilkS")
		)
		(fp_line
			(start -0.7874 -0.4064)
			(end -0.7874 0.4064)
			(stroke
				(width 0.1524)
				(type default)
			)
			(layer "B.SilkS")
		)
		(fp_line
			(start 0.7874 -0.4064)
			(end -0.7874 -0.4064)
			(stroke
				(width 0.1524)
				(type default)
			)
			(layer "B.SilkS")
		)
		(fp_line
			(start -0.67945 0.3048)
			(end -0.120396 0.3048)
			(stroke
				(width 0.1)
				(type default)
			)
			(layer "B.Fab")
		)
		(fp_line
			(start -0.120396 0.3048)
			(end -0.120396 0.2794)
			(stroke
				(width 0.1)
				(type default)
			)
			(layer "B.Fab")
		)
		(fp_line
			(start 0.12065 0.3048)
			(end 0.67945 0.3048)
			(stroke
				(width 0.1)
				(type default)
			)
			(layer "B.Fab")
		)
		(fp_line
			(start 0.67945 0.3048)
			(end 0.67945 -0.305054)
			(stroke
				(width 0.1)
				(type default)
			)
			(layer "B.Fab")
		)
		(fp_line
			(start -0.120396 0.2794)
			(end 0.12065 0.2794)
			(stroke
				(width 0.1)
				(type default)
			)
			(layer "B.Fab")
		)
		(fp_line
			(start 0.12065 0.2794)
			(end 0.12065 0.3048)
			(stroke
				(width 0.1)
				(type default)
			)
			(layer "B.Fab")
		)
		(fp_line
			(start -0.12065 -0.2794)
			(end -0.12065 -0.3048)
			(stroke
				(width 0.1)
				(type default)
			)
			(layer "B.Fab")
		)
		(fp_line
			(start 0.12065 -0.2794)
			(end -0.12065 -0.2794)
			(stroke
				(width 0.1)
				(type default)
			)
			(layer "B.Fab")
		)
		(fp_line
			(start -0.67945 -0.3048)
			(end -0.67945 0.3048)
			(stroke
				(width 0.1)
				(type default)
			)
			(layer "B.Fab")
		)
		(fp_line
			(start -0.12065 -0.3048)
			(end -0.67945 -0.3048)
			(stroke
				(width 0.1)
				(type default)
			)
			(layer "B.Fab")
		)
		(fp_line
			(start 0.12065 -0.305054)
			(end 0.12065 -0.2794)
			(stroke
				(width 0.1)
				(type default)
			)
			(layer "B.Fab")
		)
		(fp_line
			(start 0.67945 -0.305054)
			(end 0.12065 -0.305054)
			(stroke
				(width 0.1)
				(type default)
			)
			(layer "B.Fab")
		)
		(pad "1" smd circle
			(at 0.40005 0 90)
			(size 0 0)
			(layers "B.Cu" "B.Mask" "B.Paste")
			(net "P1V8_AUX")
		)
		(pad "2" smd circle
			(at -0.40005 0 90)
			(size 0 0)
			(layers "B.Cu" "B.Mask" "B.Paste")
			(net "FM_BIOS_POST_CMPLT_BUF_R1_N")
		)
	)
	(footprint ""
		(layer "B.Cu")
		(at 93.100144 -408.517344 90)
		(property "Reference" "C6689"
			(at 0 0 90)
			(layer "B.SilkS")
			(hide yes)
			(effects
				(font
					(size 1.27 1.27)
				)
				(justify mirror)
			)
		)
		(property "Value" ""
			(at 0 0 90)
			(layer "B.Fab")
			(effects
				(font
					(size 1.27 1.27)
				)
				(justify mirror)
			)
		)
		(duplicate_pad_numbers_are_jumpers no)
		(fp_line
			(start 0.299974 -0.150114)
			(end -0.299974 -0.150114)
			(stroke
				(width 0.1)
				(type default)
			)
			(layer "B.Fab")
		)
		(fp_line
			(start -0.299974 -0.150114)
			(end -0.299974 0.150114)
			(stroke
				(width 0.1)
				(type default)
			)
			(layer "B.Fab")
		)
		(fp_line
			(start 0.299974 0.150114)
			(end 0.299974 -0.150114)
			(stroke
				(width 0.1)
				(type default)
			)
			(layer "B.Fab")
		)
		(fp_line
			(start -0.299974 0.150114)
			(end 0.299974 0.150114)
			(stroke
				(width 0.1)
				(type default)
			)
			(layer "B.Fab")
		)
		(pad "1" smd rect
			(at 0.2667 0 270)
			(size 0.3048 0.381)
			(layers "B.Cu" "B.Mask" "B.Paste")
			(net "P5E_CPU1_P1_TX_BUF_C_DP<14>")
		)
		(pad "2" smd rect
			(at -0.2667 0 270)
			(size 0.3048 0.381)
			(layers "B.Cu" "B.Mask" "B.Paste")
			(net "P5E_CPU1_P1_TX_BUF_DP<14>")
		)
	)
	(footprint ""
		(layer "B.Cu")
		(at 310.590946 -398.942052 90)
		(property "Reference" "C574"
			(at 0 0 90)
			(layer "B.SilkS")
			(hide yes)
			(effects
				(font
					(size 1.27 1.27)
				)
				(justify mirror)
			)
		)
		(property "Value" ""
			(at 0 0 90)
			(layer "B.Fab")
			(effects
				(font
					(size 1.27 1.27)
				)
				(justify mirror)
			)
		)
		(duplicate_pad_numbers_are_jumpers no)
		(fp_line
			(start 0.7874 -0.4064)
			(end -0.7874 -0.4064)
			(stroke
				(width 0.1524)
				(type default)
			)
			(layer "B.SilkS")
		)
		(fp_line
			(start -0.7874 -0.4064)
			(end -0.7874 0.4064)
			(stroke
				(width 0.1524)
				(type default)
			)
			(layer "B.SilkS")
		)
		(fp_line
			(start 0.7874 0.4064)
			(end 0.7874 -0.4064)
			(stroke
				(width 0.1524)
				(type default)
			)
			(layer "B.SilkS")
		)
		(fp_line
			(start -0.7874 0.4064)
			(end 0.7874 0.4064)
			(stroke
				(width 0.1524)
				(type default)
			)
			(layer "B.SilkS")
		)
		(fp_line
			(start 0.67945 -0.305054)
			(end 0.12065 -0.305054)
			(stroke
				(width 0.1)
				(type default)
			)
			(layer "B.Fab")
		)
		(fp_line
			(start 0.12065 -0.305054)
			(end 0.12065 -0.2794)
			(stroke
				(width 0.1)
				(type default)
			)
			(layer "B.Fab")
		)
		(fp_line
			(start -0.12065 -0.3048)
			(end -0.67945 -0.3048)
			(stroke
				(width 0.1)
				(type default)
			)
			(layer "B.Fab")
		)
		(fp_line
			(start -0.67945 -0.3048)
			(end -0.67945 0.3048)
			(stroke
				(width 0.1)
				(type default)
			)
			(layer "B.Fab")
		)
		(fp_line
			(start 0.12065 -0.2794)
			(end -0.12065 -0.2794)
			(stroke
				(width 0.1)
				(type default)
			)
			(layer "B.Fab")
		)
		(fp_line
			(start -0.12065 -0.2794)
			(end -0.12065 -0.3048)
			(stroke
				(width 0.1)
				(type default)
			)
			(layer "B.Fab")
		)
		(fp_line
			(start 0.12065 0.2794)
			(end 0.12065 0.3048)
			(stroke
				(width 0.1)
				(type default)
			)
			(layer "B.Fab")
		)
		(fp_line
			(start -0.120396 0.2794)
			(end 0.12065 0.2794)
			(stroke
				(width 0.1)
				(type default)
			)
			(layer "B.Fab")
		)
		(fp_line
			(start 0.67945 0.3048)
			(end 0.67945 -0.305054)
			(stroke
				(width 0.1)
				(type default)
			)
			(layer "B.Fab")
		)
		(fp_line
			(start 0.12065 0.3048)
			(end 0.67945 0.3048)
			(stroke
				(width 0.1)
				(type default)
			)
			(layer "B.Fab")
		)
		(fp_line
			(start -0.120396 0.3048)
			(end -0.120396 0.2794)
			(stroke
				(width 0.1)
				(type default)
			)
			(layer "B.Fab")
		)
		(fp_line
			(start -0.67945 0.3048)
			(end -0.120396 0.3048)
			(stroke
				(width 0.1)
				(type default)
			)
			(layer "B.Fab")
		)
		(pad "1" smd circle
			(at 0.40005 0 270)
			(size 0 0)
			(layers "B.Cu" "B.Mask" "B.Paste")
			(net "P0V9_CPU0_RT_2D")
		)
		(pad "2" smd circle
			(at -0.40005 0 270)
			(size 0 0)
			(layers "B.Cu" "B.Mask" "B.Paste")
			(net "GND")
		)
	)
	(footprint ""
		(layer "B.Cu")
		(at 96.163384 -408.517344 90)
		(property "Reference" "C6691"
			(at 0 0 90)
			(layer "B.SilkS")
			(hide yes)
			(effects
				(font
					(size 1.27 1.27)
				)
				(justify mirror)
			)
		)
		(property "Value" ""
			(at 0 0 90)
			(layer "B.Fab")
			(effects
				(font
					(size 1.27 1.27)
				)
				(justify mirror)
			)
		)
		(duplicate_pad_numbers_are_jumpers no)
		(fp_line
			(start 0.299974 -0.150114)
			(end -0.299974 -0.150114)
			(stroke
				(width 0.1)
				(type default)
			)
			(layer "B.Fab")
		)
		(fp_line
			(start -0.299974 -0.150114)
			(end -0.299974 0.150114)
			(stroke
				(width 0.1)
				(type default)
			)
			(layer "B.Fab")
		)
		(fp_line
			(start 0.299974 0.150114)
			(end 0.299974 -0.150114)
			(stroke
				(width 0.1)
				(type default)
			)
			(layer "B.Fab")
		)
		(fp_line
			(start -0.299974 0.150114)
			(end 0.299974 0.150114)
			(stroke
				(width 0.1)
				(type default)
			)
			(layer "B.Fab")
		)
		(pad "1" smd rect
			(at 0.2667 0 270)
			(size 0.3048 0.381)
			(layers "B.Cu" "B.Mask" "B.Paste")
			(net "P5E_CPU1_P1_TX_BUF_C_DP<15>")
		)
		(pad "2" smd rect
			(at -0.2667 0 270)
			(size 0.3048 0.381)
			(layers "B.Cu" "B.Mask" "B.Paste")
			(net "P5E_CPU1_P1_TX_BUF_DP<15>")
		)
	)
	(footprint ""
		(layer "B.Cu")
		(at 183.364886 -133.795008 -90)
		(property "Reference" "R1288"
			(at 0 0 90)
			(layer "B.SilkS")
			(hide yes)
			(effects
				(font
					(size 1.27 1.27)
				)
				(justify mirror)
			)
		)
		(property "Value" ""
			(at 0 0 90)
			(layer "B.Fab")
			(effects
				(font
					(size 1.27 1.27)
				)
				(justify mirror)
			)
		)
		(duplicate_pad_numbers_are_jumpers no)
		(fp_line
			(start -0.7874 0.4064)
			(end 0.7874 0.4064)
			(stroke
				(width 0.1524)
				(type default)
			)
			(layer "B.SilkS")
		)
		(fp_line
			(start 0.7874 0.4064)
			(end 0.7874 -0.4064)
			(stroke
				(width 0.1524)
				(type default)
			)
			(layer "B.SilkS")
		)
		(fp_line
			(start -0.7874 -0.4064)
			(end -0.7874 0.4064)
			(stroke
				(width 0.1524)
				(type default)
			)
			(layer "B.SilkS")
		)
		(fp_line
			(start 0.7874 -0.4064)
			(end -0.7874 -0.4064)
			(stroke
				(width 0.1524)
				(type default)
			)
			(layer "B.SilkS")
		)
		(fp_line
			(start -0.67945 0.3048)
			(end -0.120396 0.3048)
			(stroke
				(width 0.1)
				(type default)
			)
			(layer "B.Fab")
		)
		(fp_line
			(start -0.120396 0.3048)
			(end -0.120396 0.2794)
			(stroke
				(width 0.1)
				(type default)
			)
			(layer "B.Fab")
		)
		(fp_line
			(start 0.12065 0.3048)
			(end 0.67945 0.3048)
			(stroke
				(width 0.1)
				(type default)
			)
			(layer "B.Fab")
		)
		(fp_line
			(start 0.67945 0.3048)
			(end 0.67945 -0.305054)
			(stroke
				(width 0.1)
				(type default)
			)
			(layer "B.Fab")
		)
		(fp_line
			(start -0.120396 0.2794)
			(end 0.12065 0.2794)
			(stroke
				(width 0.1)
				(type default)
			)
			(layer "B.Fab")
		)
		(fp_line
			(start 0.12065 0.2794)
			(end 0.12065 0.3048)
			(stroke
				(width 0.1)
				(type default)
			)
			(layer "B.Fab")
		)
		(fp_line
			(start -0.12065 -0.2794)
			(end -0.12065 -0.3048)
			(stroke
				(width 0.1)
				(type default)
			)
			(layer "B.Fab")
		)
		(fp_line
			(start 0.12065 -0.2794)
			(end -0.12065 -0.2794)
			(stroke
				(width 0.1)
				(type default)
			)
			(layer "B.Fab")
		)
		(fp_line
			(start -0.67945 -0.3048)
			(end -0.67945 0.3048)
			(stroke
				(width 0.1)
				(type default)
			)
			(layer "B.Fab")
		)
		(fp_line
			(start -0.12065 -0.3048)
			(end -0.67945 -0.3048)
			(stroke
				(width 0.1)
				(type default)
			)
			(layer "B.Fab")
		)
		(fp_line
			(start 0.12065 -0.305054)
			(end 0.12065 -0.2794)
			(stroke
				(width 0.1)
				(type default)
			)
			(layer "B.Fab")
		)
		(fp_line
			(start 0.67945 -0.305054)
			(end 0.12065 -0.305054)
			(stroke
				(width 0.1)
				(type default)
			)
			(layer "B.Fab")
		)
		(pad "1" smd circle
			(at 0.40005 0 90)
			(size 0 0)
			(layers "B.Cu" "B.Mask" "B.Paste")
			(net "FM_P0_PCC1_N")
		)
		(pad "2" smd circle
			(at -0.40005 0 90)
			(size 0 0)
			(layers "B.Cu" "B.Mask" "B.Paste")
			(net "PVDD18_S5_P0")
		)
	)
	(footprint ""
		(layer "B.Cu")
		(at 348.004638 -342.599772 -90)
		(property "Reference" "PR421"
			(at 0 0 90)
			(layer "B.SilkS")
			(hide yes)
			(effects
				(font
					(size 1.27 1.27)
				)
				(justify mirror)
			)
		)
		(property "Value" ""
			(at 0 0 90)
			(layer "B.Fab")
			(effects
				(font
					(size 1.27 1.27)
				)
				(justify mirror)
			)
		)
		(duplicate_pad_numbers_are_jumpers no)
		(fp_line
			(start -0.7874 0.4064)
			(end 0.7874 0.4064)
			(stroke
				(width 0.1524)
				(type default)
			)
			(layer "B.SilkS")
		)
		(fp_line
			(start 0.7874 0.4064)
			(end 0.7874 -0.4064)
			(stroke
				(width 0.1524)
				(type default)
			)
			(layer "B.SilkS")
		)
		(fp_line
			(start -0.7874 -0.4064)
			(end -0.7874 0.4064)
			(stroke
				(width 0.1524)
				(type default)
			)
			(layer "B.SilkS")
		)
		(fp_line
			(start 0.7874 -0.4064)
			(end -0.7874 -0.4064)
			(stroke
				(width 0.1524)
				(type default)
			)
			(layer "B.SilkS")
		)
		(fp_line
			(start -0.67945 0.3048)
			(end -0.120396 0.3048)
			(stroke
				(width 0.1)
				(type default)
			)
			(layer "B.Fab")
		)
		(fp_line
			(start -0.120396 0.3048)
			(end -0.120396 0.2794)
			(stroke
				(width 0.1)
				(type default)
			)
			(layer "B.Fab")
		)
		(fp_line
			(start 0.12065 0.3048)
			(end 0.67945 0.3048)
			(stroke
				(width 0.1)
				(type default)
			)
			(layer "B.Fab")
		)
		(fp_line
			(start 0.67945 0.3048)
			(end 0.67945 -0.305054)
			(stroke
				(width 0.1)
				(type default)
			)
			(layer "B.Fab")
		)
		(fp_line
			(start -0.120396 0.2794)
			(end 0.12065 0.2794)
			(stroke
				(width 0.1)
				(type default)
			)
			(layer "B.Fab")
		)
		(fp_line
			(start 0.12065 0.2794)
			(end 0.12065 0.3048)
			(stroke
				(width 0.1)
				(type default)
			)
			(layer "B.Fab")
		)
		(fp_line
			(start -0.12065 -0.2794)
			(end -0.12065 -0.3048)
			(stroke
				(width 0.1)
				(type default)
			)
			(layer "B.Fab")
		)
		(fp_line
			(start 0.12065 -0.2794)
			(end -0.12065 -0.2794)
			(stroke
				(width 0.1)
				(type default)
			)
			(layer "B.Fab")
		)
		(fp_line
			(start -0.67945 -0.3048)
			(end -0.67945 0.3048)
			(stroke
				(width 0.1)
				(type default)
			)
			(layer "B.Fab")
		)
		(fp_line
			(start -0.12065 -0.3048)
			(end -0.67945 -0.3048)
			(stroke
				(width 0.1)
				(type default)
			)
			(layer "B.Fab")
		)
		(fp_line
			(start 0.12065 -0.305054)
			(end 0.12065 -0.2794)
			(stroke
				(width 0.1)
				(type default)
			)
			(layer "B.Fab")
		)
		(fp_line
			(start 0.67945 -0.305054)
			(end 0.12065 -0.305054)
			(stroke
				(width 0.1)
				(type default)
			)
			(layer "B.Fab")
		)
		(pad "1" smd circle
			(at 0.40005 0 90)
			(size 0 0)
			(layers "B.Cu" "B.Mask" "B.Paste")
			(net "PVDDCR_CPU1_P0_VOS6")
		)
		(pad "2" smd circle
			(at -0.40005 0 90)
			(size 0 0)
			(layers "B.Cu" "B.Mask" "B.Paste")
			(net "PVDDCR_CPU1_P0")
		)
	)
	(footprint ""
		(layer "B.Cu")
		(at 243.713 -323.85)
		(property "Reference" "C1080"
			(at 0 0 0)
			(layer "B.SilkS")
			(hide yes)
			(effects
				(font
					(size 1.27 1.27)
				)
				(justify mirror)
			)
		)
		(property "Value" ""
			(at 0 0 0)
			(layer "B.Fab")
			(effects
				(font
					(size 1.27 1.27)
				)
				(justify mirror)
			)
		)
		(duplicate_pad_numbers_are_jumpers no)
		(fp_line
			(start -0.7874 -0.4064)
			(end -0.7874 0.4064)
			(stroke
				(width 0.1524)
				(type default)
			)
			(layer "B.SilkS")
		)
		(fp_line
			(start -0.7874 0.4064)
			(end 0.7874 0.4064)
			(stroke
				(width 0.1524)
				(type default)
			)
			(layer "B.SilkS")
		)
		(fp_line
			(start 0.7874 -0.4064)
			(end -0.7874 -0.4064)
			(stroke
				(width 0.1524)
				(type default)
			)
			(layer "B.SilkS")
		)
		(fp_line
			(start 0.7874 0.4064)
			(end 0.7874 -0.4064)
			(stroke
				(width 0.1524)
				(type default)
			)
			(layer "B.SilkS")
		)
		(fp_line
			(start -0.67945 -0.3048)
			(end -0.67945 0.3048)
			(stroke
				(width 0.1)
				(type default)
			)
			(layer "B.Fab")
		)
		(fp_line
			(start -0.67945 0.3048)
			(end -0.120396 0.3048)
			(stroke
				(width 0.1)
				(type default)
			)
			(layer "B.Fab")
		)
		(fp_line
			(start -0.12065 -0.3048)
			(end -0.67945 -0.3048)
			(stroke
				(width 0.1)
				(type default)
			)
			(layer "B.Fab")
		)
		(fp_line
			(start -0.12065 -0.2794)
			(end -0.12065 -0.3048)
			(stroke
				(width 0.1)
				(type default)
			)
			(layer "B.Fab")
		)
		(fp_line
			(start -0.120396 0.2794)
			(end 0.12065 0.2794)
			(stroke
				(width 0.1)
				(type default)
			)
			(layer "B.Fab")
		)
		(fp_line
			(start -0.120396 0.3048)
			(end -0.120396 0.2794)
			(stroke
				(width 0.1)
				(type default)
			)
			(layer "B.Fab")
		)
		(fp_line
			(start 0.12065 -0.305054)
			(end 0.12065 -0.2794)
			(stroke
				(width 0.1)
				(type default)
			)
			(layer "B.Fab")
		)
		(fp_line
			(start 0.12065 -0.2794)
			(end -0.12065 -0.2794)
			(stroke
				(width 0.1)
				(type default)
			)
			(layer "B.Fab")
		)
		(fp_line
			(start 0.12065 0.2794)
			(end 0.12065 0.3048)
			(stroke
				(width 0.1)
				(type default)
			)
			(layer "B.Fab")
		)
		(fp_line
			(start 0.12065 0.3048)
			(end 0.67945 0.3048)
			(stroke
				(width 0.1)
				(type default)
			)
			(layer "B.Fab")
		)
		(fp_line
			(start 0.67945 -0.305054)
			(end 0.12065 -0.305054)
			(stroke
				(width 0.1)
				(type default)
			)
			(layer "B.Fab")
		)
		(fp_line
			(start 0.67945 0.3048)
			(end 0.67945 -0.305054)
			(stroke
				(width 0.1)
				(type default)
			)
			(layer "B.Fab")
		)
		(pad "1" smd circle
			(at 0.40005 0 180)
			(size 0 0)
			(layers "B.Cu" "B.Mask" "B.Paste")
			(net "PVDD18_S5_P0_ADC_MAM")
		)
		(pad "2" smd circle
			(at -0.40005 0 180)
			(size 0 0)
			(layers "B.Cu" "B.Mask" "B.Paste")
			(net "GND")
		)
	)
	(footprint ""
		(layer "B.Cu")
		(at 239.395 -234.061 -90)
		(property "Reference" "R144"
			(at 0 0 90)
			(layer "B.SilkS")
			(hide yes)
			(effects
				(font
					(size 1.27 1.27)
				)
				(justify mirror)
			)
		)
		(property "Value" ""
			(at 0 0 90)
			(layer "B.Fab")
			(effects
				(font
					(size 1.27 1.27)
				)
				(justify mirror)
			)
		)
		(duplicate_pad_numbers_are_jumpers no)
		(fp_line
			(start -0.7874 0.4064)
			(end 0.7874 0.4064)
			(stroke
				(width 0.1524)
				(type default)
			)
			(layer "B.SilkS")
		)
		(fp_line
			(start 0.7874 0.4064)
			(end 0.7874 -0.4064)
			(stroke
				(width 0.1524)
				(type default)
			)
			(layer "B.SilkS")
		)
		(fp_line
			(start -0.7874 -0.4064)
			(end -0.7874 0.4064)
			(stroke
				(width 0.1524)
				(type default)
			)
			(layer "B.SilkS")
		)
		(fp_line
			(start 0.7874 -0.4064)
			(end -0.7874 -0.4064)
			(stroke
				(width 0.1524)
				(type default)
			)
			(layer "B.SilkS")
		)
		(fp_line
			(start -0.67945 0.3048)
			(end -0.120396 0.3048)
			(stroke
				(width 0.1)
				(type default)
			)
			(layer "B.Fab")
		)
		(fp_line
			(start -0.120396 0.3048)
			(end -0.120396 0.2794)
			(stroke
				(width 0.1)
				(type default)
			)
			(layer "B.Fab")
		)
		(fp_line
			(start 0.12065 0.3048)
			(end 0.67945 0.3048)
			(stroke
				(width 0.1)
				(type default)
			)
			(layer "B.Fab")
		)
		(fp_line
			(start 0.67945 0.3048)
			(end 0.67945 -0.305054)
			(stroke
				(width 0.1)
				(type default)
			)
			(layer "B.Fab")
		)
		(fp_line
			(start -0.120396 0.2794)
			(end 0.12065 0.2794)
			(stroke
				(width 0.1)
				(type default)
			)
			(layer "B.Fab")
		)
		(fp_line
			(start 0.12065 0.2794)
			(end 0.12065 0.3048)
			(stroke
				(width 0.1)
				(type default)
			)
			(layer "B.Fab")
		)
		(fp_line
			(start -0.12065 -0.2794)
			(end -0.12065 -0.3048)
			(stroke
				(width 0.1)
				(type default)
			)
			(layer "B.Fab")
		)
		(fp_line
			(start 0.12065 -0.2794)
			(end -0.12065 -0.2794)
			(stroke
				(width 0.1)
				(type default)
			)
			(layer "B.Fab")
		)
		(fp_line
			(start -0.67945 -0.3048)
			(end -0.67945 0.3048)
			(stroke
				(width 0.1)
				(type default)
			)
			(layer "B.Fab")
		)
		(fp_line
			(start -0.12065 -0.3048)
			(end -0.67945 -0.3048)
			(stroke
				(width 0.1)
				(type default)
			)
			(layer "B.Fab")
		)
		(fp_line
			(start 0.12065 -0.305054)
			(end 0.12065 -0.2794)
			(stroke
				(width 0.1)
				(type default)
			)
			(layer "B.Fab")
		)
		(fp_line
			(start 0.67945 -0.305054)
			(end 0.12065 -0.305054)
			(stroke
				(width 0.1)
				(type default)
			)
			(layer "B.Fab")
		)
		(pad "1" smd circle
			(at 0.40005 0 90)
			(size 0 0)
			(layers "B.Cu" "B.Mask" "B.Paste")
			(net "SMB_CPU0_CPU1_SEC_SDA_R2")
		)
		(pad "2" smd circle
			(at -0.40005 0 90)
			(size 0 0)
			(layers "B.Cu" "B.Mask" "B.Paste")
			(net "SMB_CPU0_SEC_R_SDA")
		)
	)
	(footprint ""
		(layer "B.Cu")
		(at 15.448788 -132.78993 90)
		(property "Reference" "C1884"
			(at 0 0 90)
			(layer "B.SilkS")
			(hide yes)
			(effects
				(font
					(size 1.27 1.27)
				)
				(justify mirror)
			)
		)
		(property "Value" ""
			(at 0 0 90)
			(layer "B.Fab")
			(effects
				(font
					(size 1.27 1.27)
				)
				(justify mirror)
			)
		)
		(duplicate_pad_numbers_are_jumpers no)
		(fp_line
			(start 0.7874 -0.4064)
			(end -0.7874 -0.4064)
			(stroke
				(width 0.1524)
				(type default)
			)
			(layer "B.SilkS")
		)
		(fp_line
			(start -0.7874 -0.4064)
			(end -0.7874 0.4064)
			(stroke
				(width 0.1524)
				(type default)
			)
			(layer "B.SilkS")
		)
		(fp_line
			(start 0.7874 0.4064)
			(end 0.7874 -0.4064)
			(stroke
				(width 0.1524)
				(type default)
			)
			(layer "B.SilkS")
		)
		(fp_line
			(start -0.7874 0.4064)
			(end 0.7874 0.4064)
			(stroke
				(width 0.1524)
				(type default)
			)
			(layer "B.SilkS")
		)
		(fp_line
			(start 0.67945 -0.305054)
			(end 0.12065 -0.305054)
			(stroke
				(width 0.1)
				(type default)
			)
			(layer "B.Fab")
		)
		(fp_line
			(start 0.12065 -0.305054)
			(end 0.12065 -0.2794)
			(stroke
				(width 0.1)
				(type default)
			)
			(layer "B.Fab")
		)
		(fp_line
			(start -0.12065 -0.3048)
			(end -0.67945 -0.3048)
			(stroke
				(width 0.1)
				(type default)
			)
			(layer "B.Fab")
		)
		(fp_line
			(start -0.67945 -0.3048)
			(end -0.67945 0.3048)
			(stroke
				(width 0.1)
				(type default)
			)
			(layer "B.Fab")
		)
		(fp_line
			(start 0.12065 -0.2794)
			(end -0.12065 -0.2794)
			(stroke
				(width 0.1)
				(type default)
			)
			(layer "B.Fab")
		)
		(fp_line
			(start -0.12065 -0.2794)
			(end -0.12065 -0.3048)
			(stroke
				(width 0.1)
				(type default)
			)
			(layer "B.Fab")
		)
		(fp_line
			(start 0.12065 0.2794)
			(end 0.12065 0.3048)
			(stroke
				(width 0.1)
				(type default)
			)
			(layer "B.Fab")
		)
		(fp_line
			(start -0.120396 0.2794)
			(end 0.12065 0.2794)
			(stroke
				(width 0.1)
				(type default)
			)
			(layer "B.Fab")
		)
		(fp_line
			(start 0.67945 0.3048)
			(end 0.67945 -0.305054)
			(stroke
				(width 0.1)
				(type default)
			)
			(layer "B.Fab")
		)
		(fp_line
			(start 0.12065 0.3048)
			(end 0.67945 0.3048)
			(stroke
				(width 0.1)
				(type default)
			)
			(layer "B.Fab")
		)
		(fp_line
			(start -0.120396 0.3048)
			(end -0.120396 0.2794)
			(stroke
				(width 0.1)
				(type default)
			)
			(layer "B.Fab")
		)
		(fp_line
			(start -0.67945 0.3048)
			(end -0.120396 0.3048)
			(stroke
				(width 0.1)
				(type default)
			)
			(layer "B.Fab")
		)
		(pad "1" smd circle
			(at 0.40005 0 270)
			(size 0 0)
			(layers "B.Cu" "B.Mask" "B.Paste")
			(net "VFG_3P3A_CLK_GEN")
		)
		(pad "2" smd circle
			(at -0.40005 0 270)
			(size 0 0)
			(layers "B.Cu" "B.Mask" "B.Paste")
			(net "GND")
		)
	)
	(footprint ""
		(layer "B.Cu")
		(at 186.230514 -131.556506 90)
		(property "Reference" "R6798"
			(at 0 0 90)
			(layer "B.SilkS")
			(hide yes)
			(effects
				(font
					(size 1.27 1.27)
				)
				(justify mirror)
			)
		)
		(property "Value" ""
			(at 0 0 90)
			(layer "B.Fab")
			(effects
				(font
					(size 1.27 1.27)
				)
				(justify mirror)
			)
		)
		(duplicate_pad_numbers_are_jumpers no)
		(fp_line
			(start 0.7874 -0.4064)
			(end -0.7874 -0.4064)
			(stroke
				(width 0.1524)
				(type default)
			)
			(layer "B.SilkS")
		)
		(fp_line
			(start -0.7874 -0.4064)
			(end -0.7874 0.4064)
			(stroke
				(width 0.1524)
				(type default)
			)
			(layer "B.SilkS")
		)
		(fp_line
			(start 0.7874 0.4064)
			(end 0.7874 -0.4064)
			(stroke
				(width 0.1524)
				(type default)
			)
			(layer "B.SilkS")
		)
		(fp_line
			(start -0.7874 0.4064)
			(end 0.7874 0.4064)
			(stroke
				(width 0.1524)
				(type default)
			)
			(layer "B.SilkS")
		)
		(fp_line
			(start 0.67945 -0.305054)
			(end 0.12065 -0.305054)
			(stroke
				(width 0.1)
				(type default)
			)
			(layer "B.Fab")
		)
		(fp_line
			(start 0.12065 -0.305054)
			(end 0.12065 -0.2794)
			(stroke
				(width 0.1)
				(type default)
			)
			(layer "B.Fab")
		)
		(fp_line
			(start -0.12065 -0.3048)
			(end -0.67945 -0.3048)
			(stroke
				(width 0.1)
				(type default)
			)
			(layer "B.Fab")
		)
		(fp_line
			(start -0.67945 -0.3048)
			(end -0.67945 0.3048)
			(stroke
				(width 0.1)
				(type default)
			)
			(layer "B.Fab")
		)
		(fp_line
			(start 0.12065 -0.2794)
			(end -0.12065 -0.2794)
			(stroke
				(width 0.1)
				(type default)
			)
			(layer "B.Fab")
		)
		(fp_line
			(start -0.12065 -0.2794)
			(end -0.12065 -0.3048)
			(stroke
				(width 0.1)
				(type default)
			)
			(layer "B.Fab")
		)
		(fp_line
			(start 0.12065 0.2794)
			(end 0.12065 0.3048)
			(stroke
				(width 0.1)
				(type default)
			)
			(layer "B.Fab")
		)
		(fp_line
			(start -0.120396 0.2794)
			(end 0.12065 0.2794)
			(stroke
				(width 0.1)
				(type default)
			)
			(layer "B.Fab")
		)
		(fp_line
			(start 0.67945 0.3048)
			(end 0.67945 -0.305054)
			(stroke
				(width 0.1)
				(type default)
			)
			(layer "B.Fab")
		)
		(fp_line
			(start 0.12065 0.3048)
			(end 0.67945 0.3048)
			(stroke
				(width 0.1)
				(type default)
			)
			(layer "B.Fab")
		)
		(fp_line
			(start -0.120396 0.3048)
			(end -0.120396 0.2794)
			(stroke
				(width 0.1)
				(type default)
			)
			(layer "B.Fab")
		)
		(fp_line
			(start -0.67945 0.3048)
			(end -0.120396 0.3048)
			(stroke
				(width 0.1)
				(type default)
			)
			(layer "B.Fab")
		)
		(pad "1" smd circle
			(at 0.40005 0 270)
			(size 0 0)
			(layers "B.Cu" "B.Mask" "B.Paste")
			(net "RST_RT_CPU1_P3_PERST_R_N")
		)
		(pad "2" smd circle
			(at -0.40005 0 270)
			(size 0 0)
			(layers "B.Cu" "B.Mask" "B.Paste")
			(net "RST_RT_CPU1_P3_PERST_R2_N")
		)
	)
	(footprint ""
		(layer "B.Cu")
		(at 245.745 -329.184 -90)
		(property "Reference" "C1075"
			(at 0 0 90)
			(layer "B.SilkS")
			(hide yes)
			(effects
				(font
					(size 1.27 1.27)
				)
				(justify mirror)
			)
		)
		(property "Value" ""
			(at 0 0 90)
			(layer "B.Fab")
			(effects
				(font
					(size 1.27 1.27)
				)
				(justify mirror)
			)
		)
		(duplicate_pad_numbers_are_jumpers no)
		(fp_line
			(start -0.7874 0.4064)
			(end 0.7874 0.4064)
			(stroke
				(width 0.1524)
				(type default)
			)
			(layer "B.SilkS")
		)
		(fp_line
			(start 0.7874 0.4064)
			(end 0.7874 -0.4064)
			(stroke
				(width 0.1524)
				(type default)
			)
			(layer "B.SilkS")
		)
		(fp_line
			(start -0.7874 -0.4064)
			(end -0.7874 0.4064)
			(stroke
				(width 0.1524)
				(type default)
			)
			(layer "B.SilkS")
		)
		(fp_line
			(start 0.7874 -0.4064)
			(end -0.7874 -0.4064)
			(stroke
				(width 0.1524)
				(type default)
			)
			(layer "B.SilkS")
		)
		(fp_line
			(start -0.67945 0.3048)
			(end -0.120396 0.3048)
			(stroke
				(width 0.1)
				(type default)
			)
			(layer "B.Fab")
		)
		(fp_line
			(start -0.120396 0.3048)
			(end -0.120396 0.2794)
			(stroke
				(width 0.1)
				(type default)
			)
			(layer "B.Fab")
		)
		(fp_line
			(start 0.12065 0.3048)
			(end 0.67945 0.3048)
			(stroke
				(width 0.1)
				(type default)
			)
			(layer "B.Fab")
		)
		(fp_line
			(start 0.67945 0.3048)
			(end 0.67945 -0.305054)
			(stroke
				(width 0.1)
				(type default)
			)
			(layer "B.Fab")
		)
		(fp_line
			(start -0.120396 0.2794)
			(end 0.12065 0.2794)
			(stroke
				(width 0.1)
				(type default)
			)
			(layer "B.Fab")
		)
		(fp_line
			(start 0.12065 0.2794)
			(end 0.12065 0.3048)
			(stroke
				(width 0.1)
				(type default)
			)
			(layer "B.Fab")
		)
		(fp_line
			(start -0.12065 -0.2794)
			(end -0.12065 -0.3048)
			(stroke
				(width 0.1)
				(type default)
			)
			(layer "B.Fab")
		)
		(fp_line
			(start 0.12065 -0.2794)
			(end -0.12065 -0.2794)
			(stroke
				(width 0.1)
				(type default)
			)
			(layer "B.Fab")
		)
		(fp_line
			(start -0.67945 -0.3048)
			(end -0.67945 0.3048)
			(stroke
				(width 0.1)
				(type default)
			)
			(layer "B.Fab")
		)
		(fp_line
			(start -0.12065 -0.3048)
			(end -0.67945 -0.3048)
			(stroke
				(width 0.1)
				(type default)
			)
			(layer "B.Fab")
		)
		(fp_line
			(start 0.12065 -0.305054)
			(end 0.12065 -0.2794)
			(stroke
				(width 0.1)
				(type default)
			)
			(layer "B.Fab")
		)
		(fp_line
			(start 0.67945 -0.305054)
			(end 0.12065 -0.305054)
			(stroke
				(width 0.1)
				(type default)
			)
			(layer "B.Fab")
		)
		(pad "1" smd circle
			(at 0.40005 0 90)
			(size 0 0)
			(layers "B.Cu" "B.Mask" "B.Paste")
			(net "P3V3_MAX11617_2_VDD")
		)
		(pad "2" smd circle
			(at -0.40005 0 90)
			(size 0 0)
			(layers "B.Cu" "B.Mask" "B.Paste")
			(net "GND")
		)
	)
	(footprint ""
		(layer "B.Cu")
		(at 100.370386 -268.418564)
		(property "Reference" "C2378"
			(at 0 0 0)
			(layer "B.SilkS")
			(hide yes)
			(effects
				(font
					(size 1.27 1.27)
				)
				(justify mirror)
			)
		)
		(property "Value" ""
			(at 0 0 0)
			(layer "B.Fab")
			(effects
				(font
					(size 1.27 1.27)
				)
				(justify mirror)
			)
		)
		(duplicate_pad_numbers_are_jumpers no)
		(fp_line
			(start -0.7874 -0.4064)
			(end -0.7874 0.4064)
			(stroke
				(width 0.1524)
				(type default)
			)
			(layer "B.SilkS")
		)
		(fp_line
			(start -0.7874 0.4064)
			(end 0.7874 0.4064)
			(stroke
				(width 0.1524)
				(type default)
			)
			(layer "B.SilkS")
		)
		(fp_line
			(start 0.7874 -0.4064)
			(end -0.7874 -0.4064)
			(stroke
				(width 0.1524)
				(type default)
			)
			(layer "B.SilkS")
		)
		(fp_line
			(start 0.7874 0.4064)
			(end 0.7874 -0.4064)
			(stroke
				(width 0.1524)
				(type default)
			)
			(layer "B.SilkS")
		)
		(fp_line
			(start -0.67945 -0.3048)
			(end -0.67945 0.3048)
			(stroke
				(width 0.1)
				(type default)
			)
			(layer "B.Fab")
		)
		(fp_line
			(start -0.67945 0.3048)
			(end -0.120396 0.3048)
			(stroke
				(width 0.1)
				(type default)
			)
			(layer "B.Fab")
		)
		(fp_line
			(start -0.12065 -0.3048)
			(end -0.67945 -0.3048)
			(stroke
				(width 0.1)
				(type default)
			)
			(layer "B.Fab")
		)
		(fp_line
			(start -0.12065 -0.2794)
			(end -0.12065 -0.3048)
			(stroke
				(width 0.1)
				(type default)
			)
			(layer "B.Fab")
		)
		(fp_line
			(start -0.120396 0.2794)
			(end 0.12065 0.2794)
			(stroke
				(width 0.1)
				(type default)
			)
			(layer "B.Fab")
		)
		(fp_line
			(start -0.120396 0.3048)
			(end -0.120396 0.2794)
			(stroke
				(width 0.1)
				(type default)
			)
			(layer "B.Fab")
		)
		(fp_line
			(start 0.12065 -0.305054)
			(end 0.12065 -0.2794)
			(stroke
				(width 0.1)
				(type default)
			)
			(layer "B.Fab")
		)
		(fp_line
			(start 0.12065 -0.2794)
			(end -0.12065 -0.2794)
			(stroke
				(width 0.1)
				(type default)
			)
			(layer "B.Fab")
		)
		(fp_line
			(start 0.12065 0.2794)
			(end 0.12065 0.3048)
			(stroke
				(width 0.1)
				(type default)
			)
			(layer "B.Fab")
		)
		(fp_line
			(start 0.12065 0.3048)
			(end 0.67945 0.3048)
			(stroke
				(width 0.1)
				(type default)
			)
			(layer "B.Fab")
		)
		(fp_line
			(start 0.67945 -0.305054)
			(end 0.12065 -0.305054)
			(stroke
				(width 0.1)
				(type default)
			)
			(layer "B.Fab")
		)
		(fp_line
			(start 0.67945 0.3048)
			(end 0.67945 -0.305054)
			(stroke
				(width 0.1)
				(type default)
			)
			(layer "B.Fab")
		)
		(pad "1" smd circle
			(at 0.40005 0 180)
			(size 0 0)
			(layers "B.Cu" "B.Mask" "B.Paste")
			(net "PVDDCR_CPU1_P1")
		)
		(pad "2" smd circle
			(at -0.40005 0 180)
			(size 0 0)
			(layers "B.Cu" "B.Mask" "B.Paste")
			(net "GND")
		)
	)
	(footprint ""
		(layer "B.Cu")
		(at 56.97855 -386.766562 90)
		(property "Reference" "C131"
			(at 0 0 90)
			(layer "B.SilkS")
			(hide yes)
			(effects
				(font
					(size 1.27 1.27)
				)
				(justify mirror)
			)
		)
		(property "Value" ""
			(at 0 0 90)
			(layer "B.Fab")
			(effects
				(font
					(size 1.27 1.27)
				)
				(justify mirror)
			)
		)
		(duplicate_pad_numbers_are_jumpers no)
		(fp_line
			(start 0.299974 -0.150114)
			(end -0.299974 -0.150114)
			(stroke
				(width 0.1)
				(type default)
			)
			(layer "B.Fab")
		)
		(fp_line
			(start -0.299974 -0.150114)
			(end -0.299974 0.150114)
			(stroke
				(width 0.1)
				(type default)
			)
			(layer "B.Fab")
		)
		(fp_line
			(start 0.299974 0.150114)
			(end 0.299974 -0.150114)
			(stroke
				(width 0.1)
				(type default)
			)
			(layer "B.Fab")
		)
		(fp_line
			(start -0.299974 0.150114)
			(end 0.299974 0.150114)
			(stroke
				(width 0.1)
				(type default)
			)
			(layer "B.Fab")
		)
		(pad "1" smd rect
			(at 0.2667 0 270)
			(size 0.3048 0.381)
			(layers "B.Cu" "B.Mask" "B.Paste")
			(net "P1V8_CPU1_RT0_1A")
		)
		(pad "2" smd rect
			(at -0.2667 0 270)
			(size 0.3048 0.381)
			(layers "B.Cu" "B.Mask" "B.Paste")
			(net "GND")
		)
	)
	(footprint ""
		(layer "B.Cu")
		(at 54.718458 -388.011162 -90)
		(property "Reference" "C123"
			(at 0 0 90)
			(layer "B.SilkS")
			(hide yes)
			(effects
				(font
					(size 1.27 1.27)
				)
				(justify mirror)
			)
		)
		(property "Value" ""
			(at 0 0 90)
			(layer "B.Fab")
			(effects
				(font
					(size 1.27 1.27)
				)
				(justify mirror)
			)
		)
		(duplicate_pad_numbers_are_jumpers no)
		(fp_line
			(start -0.299974 0.150114)
			(end 0.299974 0.150114)
			(stroke
				(width 0.1)
				(type default)
			)
			(layer "B.Fab")
		)
		(fp_line
			(start 0.299974 0.150114)
			(end 0.299974 -0.150114)
			(stroke
				(width 0.1)
				(type default)
			)
			(layer "B.Fab")
		)
		(fp_line
			(start -0.299974 -0.150114)
			(end -0.299974 0.150114)
			(stroke
				(width 0.1)
				(type default)
			)
			(layer "B.Fab")
		)
		(fp_line
			(start 0.299974 -0.150114)
			(end -0.299974 -0.150114)
			(stroke
				(width 0.1)
				(type default)
			)
			(layer "B.Fab")
		)
		(pad "1" smd rect
			(at 0.2667 0 90)
			(size 0.3048 0.381)
			(layers "B.Cu" "B.Mask" "B.Paste")
			(net "P1V8_CPU1_RT0_1A")
		)
		(pad "2" smd rect
			(at -0.2667 0 90)
			(size 0.3048 0.381)
			(layers "B.Cu" "B.Mask" "B.Paste")
			(net "GND")
		)
	)
	(footprint ""
		(layer "B.Cu")
		(at 373.329454 -249.36831)
		(property "Reference" "C272"
			(at 0 0 0)
			(layer "B.SilkS")
			(hide yes)
			(effects
				(font
					(size 1.27 1.27)
				)
				(justify mirror)
			)
		)
		(property "Value" ""
			(at 0 0 0)
			(layer "B.Fab")
			(effects
				(font
					(size 1.27 1.27)
				)
				(justify mirror)
			)
		)
		(duplicate_pad_numbers_are_jumpers no)
		(fp_line
			(start -0.7874 -0.4064)
			(end -0.7874 0.4064)
			(stroke
				(width 0.1524)
				(type default)
			)
			(layer "B.SilkS")
		)
		(fp_line
			(start -0.7874 0.4064)
			(end 0.7874 0.4064)
			(stroke
				(width 0.1524)
				(type default)
			)
			(layer "B.SilkS")
		)
		(fp_line
			(start 0.7874 -0.4064)
			(end -0.7874 -0.4064)
			(stroke
				(width 0.1524)
				(type default)
			)
			(layer "B.SilkS")
		)
		(fp_line
			(start 0.7874 0.4064)
			(end 0.7874 -0.4064)
			(stroke
				(width 0.1524)
				(type default)
			)
			(layer "B.SilkS")
		)
		(fp_line
			(start -0.67945 -0.3048)
			(end -0.67945 0.3048)
			(stroke
				(width 0.1)
				(type default)
			)
			(layer "B.Fab")
		)
		(fp_line
			(start -0.67945 0.3048)
			(end -0.120396 0.3048)
			(stroke
				(width 0.1)
				(type default)
			)
			(layer "B.Fab")
		)
		(fp_line
			(start -0.12065 -0.3048)
			(end -0.67945 -0.3048)
			(stroke
				(width 0.1)
				(type default)
			)
			(layer "B.Fab")
		)
		(fp_line
			(start -0.12065 -0.2794)
			(end -0.12065 -0.3048)
			(stroke
				(width 0.1)
				(type default)
			)
			(layer "B.Fab")
		)
		(fp_line
			(start -0.120396 0.2794)
			(end 0.12065 0.2794)
			(stroke
				(width 0.1)
				(type default)
			)
			(layer "B.Fab")
		)
		(fp_line
			(start -0.120396 0.3048)
			(end -0.120396 0.2794)
			(stroke
				(width 0.1)
				(type default)
			)
			(layer "B.Fab")
		)
		(fp_line
			(start 0.12065 -0.305054)
			(end 0.12065 -0.2794)
			(stroke
				(width 0.1)
				(type default)
			)
			(layer "B.Fab")
		)
		(fp_line
			(start 0.12065 -0.2794)
			(end -0.12065 -0.2794)
			(stroke
				(width 0.1)
				(type default)
			)
			(layer "B.Fab")
		)
		(fp_line
			(start 0.12065 0.2794)
			(end 0.12065 0.3048)
			(stroke
				(width 0.1)
				(type default)
			)
			(layer "B.Fab")
		)
		(fp_line
			(start 0.12065 0.3048)
			(end 0.67945 0.3048)
			(stroke
				(width 0.1)
				(type default)
			)
			(layer "B.Fab")
		)
		(fp_line
			(start 0.67945 -0.305054)
			(end 0.12065 -0.305054)
			(stroke
				(width 0.1)
				(type default)
			)
			(layer "B.Fab")
		)
		(fp_line
			(start 0.67945 0.3048)
			(end 0.67945 -0.305054)
			(stroke
				(width 0.1)
				(type default)
			)
			(layer "B.Fab")
		)
		(pad "1" smd circle
			(at 0.40005 0 180)
			(size 0 0)
			(layers "B.Cu" "B.Mask" "B.Paste")
			(net "PVDDCR_CPU0_P0")
		)
		(pad "2" smd circle
			(at -0.40005 0 180)
			(size 0 0)
			(layers "B.Cu" "B.Mask" "B.Paste")
			(net "GND")
		)
	)
	(footprint ""
		(layer "B.Cu")
		(at 121.452386 -267.49883)
		(property "Reference" "C2381"
			(at 0 0 0)
			(layer "B.SilkS")
			(hide yes)
			(effects
				(font
					(size 1.27 1.27)
				)
				(justify mirror)
			)
		)
		(property "Value" ""
			(at 0 0 0)
			(layer "B.Fab")
			(effects
				(font
					(size 1.27 1.27)
				)
				(justify mirror)
			)
		)
		(duplicate_pad_numbers_are_jumpers no)
		(fp_line
			(start -0.7874 -0.4064)
			(end -0.7874 0.4064)
			(stroke
				(width 0.1524)
				(type default)
			)
			(layer "B.SilkS")
		)
		(fp_line
			(start -0.7874 0.4064)
			(end 0.7874 0.4064)
			(stroke
				(width 0.1524)
				(type default)
			)
			(layer "B.SilkS")
		)
		(fp_line
			(start 0.7874 -0.4064)
			(end -0.7874 -0.4064)
			(stroke
				(width 0.1524)
				(type default)
			)
			(layer "B.SilkS")
		)
		(fp_line
			(start 0.7874 0.4064)
			(end 0.7874 -0.4064)
			(stroke
				(width 0.1524)
				(type default)
			)
			(layer "B.SilkS")
		)
		(fp_line
			(start -0.67945 -0.3048)
			(end -0.67945 0.3048)
			(stroke
				(width 0.1)
				(type default)
			)
			(layer "B.Fab")
		)
		(fp_line
			(start -0.67945 0.3048)
			(end -0.120396 0.3048)
			(stroke
				(width 0.1)
				(type default)
			)
			(layer "B.Fab")
		)
		(fp_line
			(start -0.12065 -0.3048)
			(end -0.67945 -0.3048)
			(stroke
				(width 0.1)
				(type default)
			)
			(layer "B.Fab")
		)
		(fp_line
			(start -0.12065 -0.2794)
			(end -0.12065 -0.3048)
			(stroke
				(width 0.1)
				(type default)
			)
			(layer "B.Fab")
		)
		(fp_line
			(start -0.120396 0.2794)
			(end 0.12065 0.2794)
			(stroke
				(width 0.1)
				(type default)
			)
			(layer "B.Fab")
		)
		(fp_line
			(start -0.120396 0.3048)
			(end -0.120396 0.2794)
			(stroke
				(width 0.1)
				(type default)
			)
			(layer "B.Fab")
		)
		(fp_line
			(start 0.12065 -0.305054)
			(end 0.12065 -0.2794)
			(stroke
				(width 0.1)
				(type default)
			)
			(layer "B.Fab")
		)
		(fp_line
			(start 0.12065 -0.2794)
			(end -0.12065 -0.2794)
			(stroke
				(width 0.1)
				(type default)
			)
			(layer "B.Fab")
		)
		(fp_line
			(start 0.12065 0.2794)
			(end 0.12065 0.3048)
			(stroke
				(width 0.1)
				(type default)
			)
			(layer "B.Fab")
		)
		(fp_line
			(start 0.12065 0.3048)
			(end 0.67945 0.3048)
			(stroke
				(width 0.1)
				(type default)
			)
			(layer "B.Fab")
		)
		(fp_line
			(start 0.67945 -0.305054)
			(end 0.12065 -0.305054)
			(stroke
				(width 0.1)
				(type default)
			)
			(layer "B.Fab")
		)
		(fp_line
			(start 0.67945 0.3048)
			(end 0.67945 -0.305054)
			(stroke
				(width 0.1)
				(type default)
			)
			(layer "B.Fab")
		)
		(pad "1" smd circle
			(at 0.40005 0 180)
			(size 0 0)
			(layers "B.Cu" "B.Mask" "B.Paste")
			(net "PVDDCR_CPU1_P1")
		)
		(pad "2" smd circle
			(at -0.40005 0 180)
			(size 0 0)
			(layers "B.Cu" "B.Mask" "B.Paste")
			(net "GND")
		)
	)
	(footprint ""
		(layer "B.Cu")
		(at 388.630922 -416.899344 90)
		(property "Reference" "C6607"
			(at 0 0 90)
			(layer "B.SilkS")
			(hide yes)
			(effects
				(font
					(size 1.27 1.27)
				)
				(justify mirror)
			)
		)
		(property "Value" ""
			(at 0 0 90)
			(layer "B.Fab")
			(effects
				(font
					(size 1.27 1.27)
				)
				(justify mirror)
			)
		)
		(duplicate_pad_numbers_are_jumpers no)
		(fp_line
			(start 0.299974 -0.150114)
			(end -0.299974 -0.150114)
			(stroke
				(width 0.1)
				(type default)
			)
			(layer "B.Fab")
		)
		(fp_line
			(start -0.299974 -0.150114)
			(end -0.299974 0.150114)
			(stroke
				(width 0.1)
				(type default)
			)
			(layer "B.Fab")
		)
		(fp_line
			(start 0.299974 0.150114)
			(end 0.299974 -0.150114)
			(stroke
				(width 0.1)
				(type default)
			)
			(layer "B.Fab")
		)
		(fp_line
			(start -0.299974 0.150114)
			(end 0.299974 0.150114)
			(stroke
				(width 0.1)
				(type default)
			)
			(layer "B.Fab")
		)
		(pad "1" smd rect
			(at 0.2667 0 270)
			(size 0.3048 0.381)
			(layers "B.Cu" "B.Mask" "B.Paste")
			(net "P5E_CPU0_P3_TX_BUF_C_DP<5>")
		)
		(pad "2" smd rect
			(at -0.2667 0 270)
			(size 0.3048 0.381)
			(layers "B.Cu" "B.Mask" "B.Paste")
			(net "P5E_CPU0_P3_TX_BUF_DP<5>")
		)
	)
	(footprint ""
		(layer "B.Cu")
		(at 179.705 -100.294948 -90)
		(property "Reference" "R137"
			(at 0 0 90)
			(layer "B.SilkS")
			(hide yes)
			(effects
				(font
					(size 1.27 1.27)
				)
				(justify mirror)
			)
		)
		(property "Value" ""
			(at 0 0 90)
			(layer "B.Fab")
			(effects
				(font
					(size 1.27 1.27)
				)
				(justify mirror)
			)
		)
		(duplicate_pad_numbers_are_jumpers no)
		(fp_line
			(start -0.7874 0.4064)
			(end 0.7874 0.4064)
			(stroke
				(width 0.1524)
				(type default)
			)
			(layer "B.SilkS")
		)
		(fp_line
			(start 0.7874 0.4064)
			(end 0.7874 -0.4064)
			(stroke
				(width 0.1524)
				(type default)
			)
			(layer "B.SilkS")
		)
		(fp_line
			(start -0.7874 -0.4064)
			(end -0.7874 0.4064)
			(stroke
				(width 0.1524)
				(type default)
			)
			(layer "B.SilkS")
		)
		(fp_line
			(start 0.7874 -0.4064)
			(end -0.7874 -0.4064)
			(stroke
				(width 0.1524)
				(type default)
			)
			(layer "B.SilkS")
		)
		(fp_line
			(start -0.67945 0.3048)
			(end -0.120396 0.3048)
			(stroke
				(width 0.1)
				(type default)
			)
			(layer "B.Fab")
		)
		(fp_line
			(start -0.120396 0.3048)
			(end -0.120396 0.2794)
			(stroke
				(width 0.1)
				(type default)
			)
			(layer "B.Fab")
		)
		(fp_line
			(start 0.12065 0.3048)
			(end 0.67945 0.3048)
			(stroke
				(width 0.1)
				(type default)
			)
			(layer "B.Fab")
		)
		(fp_line
			(start 0.67945 0.3048)
			(end 0.67945 -0.305054)
			(stroke
				(width 0.1)
				(type default)
			)
			(layer "B.Fab")
		)
		(fp_line
			(start -0.120396 0.2794)
			(end 0.12065 0.2794)
			(stroke
				(width 0.1)
				(type default)
			)
			(layer "B.Fab")
		)
		(fp_line
			(start 0.12065 0.2794)
			(end 0.12065 0.3048)
			(stroke
				(width 0.1)
				(type default)
			)
			(layer "B.Fab")
		)
		(fp_line
			(start -0.12065 -0.2794)
			(end -0.12065 -0.3048)
			(stroke
				(width 0.1)
				(type default)
			)
			(layer "B.Fab")
		)
		(fp_line
			(start 0.12065 -0.2794)
			(end -0.12065 -0.2794)
			(stroke
				(width 0.1)
				(type default)
			)
			(layer "B.Fab")
		)
		(fp_line
			(start -0.67945 -0.3048)
			(end -0.67945 0.3048)
			(stroke
				(width 0.1)
				(type default)
			)
			(layer "B.Fab")
		)
		(fp_line
			(start -0.12065 -0.3048)
			(end -0.67945 -0.3048)
			(stroke
				(width 0.1)
				(type default)
			)
			(layer "B.Fab")
		)
		(fp_line
			(start 0.12065 -0.305054)
			(end 0.12065 -0.2794)
			(stroke
				(width 0.1)
				(type default)
			)
			(layer "B.Fab")
		)
		(fp_line
			(start 0.67945 -0.305054)
			(end 0.12065 -0.305054)
			(stroke
				(width 0.1)
				(type default)
			)
			(layer "B.Fab")
		)
		(pad "1" smd circle
			(at 0.40005 0 90)
			(size 0 0)
			(layers "B.Cu" "B.Mask" "B.Paste")
			(net "PVDDCR_CPU1_P0_OCP_N")
		)
		(pad "2" smd circle
			(at -0.40005 0 90)
			(size 0 0)
			(layers "B.Cu" "B.Mask" "B.Paste")
			(net "FM_PVDDCR_CPU1_P0_OCP_N")
		)
	)
	(footprint ""
		(layer "B.Cu")
		(at 192.913 -100.294948 90)
		(property "Reference" "R220"
			(at 0 0 90)
			(layer "B.SilkS")
			(hide yes)
			(effects
				(font
					(size 1.27 1.27)
				)
				(justify mirror)
			)
		)
		(property "Value" ""
			(at 0 0 90)
			(layer "B.Fab")
			(effects
				(font
					(size 1.27 1.27)
				)
				(justify mirror)
			)
		)
		(duplicate_pad_numbers_are_jumpers no)
		(fp_line
			(start 0.7874 -0.4064)
			(end -0.7874 -0.4064)
			(stroke
				(width 0.1524)
				(type default)
			)
			(layer "B.SilkS")
		)
		(fp_line
			(start -0.7874 -0.4064)
			(end -0.7874 0.4064)
			(stroke
				(width 0.1524)
				(type default)
			)
			(layer "B.SilkS")
		)
		(fp_line
			(start 0.7874 0.4064)
			(end 0.7874 -0.4064)
			(stroke
				(width 0.1524)
				(type default)
			)
			(layer "B.SilkS")
		)
		(fp_line
			(start -0.7874 0.4064)
			(end 0.7874 0.4064)
			(stroke
				(width 0.1524)
				(type default)
			)
			(layer "B.SilkS")
		)
		(fp_line
			(start 0.67945 -0.305054)
			(end 0.12065 -0.305054)
			(stroke
				(width 0.1)
				(type default)
			)
			(layer "B.Fab")
		)
		(fp_line
			(start 0.12065 -0.305054)
			(end 0.12065 -0.2794)
			(stroke
				(width 0.1)
				(type default)
			)
			(layer "B.Fab")
		)
		(fp_line
			(start -0.12065 -0.3048)
			(end -0.67945 -0.3048)
			(stroke
				(width 0.1)
				(type default)
			)
			(layer "B.Fab")
		)
		(fp_line
			(start -0.67945 -0.3048)
			(end -0.67945 0.3048)
			(stroke
				(width 0.1)
				(type default)
			)
			(layer "B.Fab")
		)
		(fp_line
			(start 0.12065 -0.2794)
			(end -0.12065 -0.2794)
			(stroke
				(width 0.1)
				(type default)
			)
			(layer "B.Fab")
		)
		(fp_line
			(start -0.12065 -0.2794)
			(end -0.12065 -0.3048)
			(stroke
				(width 0.1)
				(type default)
			)
			(layer "B.Fab")
		)
		(fp_line
			(start 0.12065 0.2794)
			(end 0.12065 0.3048)
			(stroke
				(width 0.1)
				(type default)
			)
			(layer "B.Fab")
		)
		(fp_line
			(start -0.120396 0.2794)
			(end 0.12065 0.2794)
			(stroke
				(width 0.1)
				(type default)
			)
			(layer "B.Fab")
		)
		(fp_line
			(start 0.67945 0.3048)
			(end 0.67945 -0.305054)
			(stroke
				(width 0.1)
				(type default)
			)
			(layer "B.Fab")
		)
		(fp_line
			(start 0.12065 0.3048)
			(end 0.67945 0.3048)
			(stroke
				(width 0.1)
				(type default)
			)
			(layer "B.Fab")
		)
		(fp_line
			(start -0.120396 0.3048)
			(end -0.120396 0.2794)
			(stroke
				(width 0.1)
				(type default)
			)
			(layer "B.Fab")
		)
		(fp_line
			(start -0.67945 0.3048)
			(end -0.120396 0.3048)
			(stroke
				(width 0.1)
				(type default)
			)
			(layer "B.Fab")
		)
		(pad "1" smd circle
			(at 0.40005 0 270)
			(size 0 0)
			(layers "B.Cu" "B.Mask" "B.Paste")
			(net "FM_CPU0_SA0")
		)
		(pad "2" smd circle
			(at -0.40005 0 270)
			(size 0 0)
			(layers "B.Cu" "B.Mask" "B.Paste")
			(net "CPU0_SA0")
		)
	)
	(footprint ""
		(layer "B.Cu")
		(at 358.089454 -266.00531)
		(property "Reference" "C3934"
			(at 0 0 0)
			(layer "B.SilkS")
			(hide yes)
			(effects
				(font
					(size 1.27 1.27)
				)
				(justify mirror)
			)
		)
		(property "Value" ""
			(at 0 0 0)
			(layer "B.Fab")
			(effects
				(font
					(size 1.27 1.27)
				)
				(justify mirror)
			)
		)
		(duplicate_pad_numbers_are_jumpers no)
		(fp_line
			(start -0.7874 -0.4064)
			(end -0.7874 0.4064)
			(stroke
				(width 0.1524)
				(type default)
			)
			(layer "B.SilkS")
		)
		(fp_line
			(start -0.7874 0.4064)
			(end 0.7874 0.4064)
			(stroke
				(width 0.1524)
				(type default)
			)
			(layer "B.SilkS")
		)
		(fp_line
			(start 0.7874 -0.4064)
			(end -0.7874 -0.4064)
			(stroke
				(width 0.1524)
				(type default)
			)
			(layer "B.SilkS")
		)
		(fp_line
			(start 0.7874 0.4064)
			(end 0.7874 -0.4064)
			(stroke
				(width 0.1524)
				(type default)
			)
			(layer "B.SilkS")
		)
		(fp_line
			(start -0.67945 -0.3048)
			(end -0.67945 0.3048)
			(stroke
				(width 0.1)
				(type default)
			)
			(layer "B.Fab")
		)
		(fp_line
			(start -0.67945 0.3048)
			(end -0.120396 0.3048)
			(stroke
				(width 0.1)
				(type default)
			)
			(layer "B.Fab")
		)
		(fp_line
			(start -0.12065 -0.3048)
			(end -0.67945 -0.3048)
			(stroke
				(width 0.1)
				(type default)
			)
			(layer "B.Fab")
		)
		(fp_line
			(start -0.12065 -0.2794)
			(end -0.12065 -0.3048)
			(stroke
				(width 0.1)
				(type default)
			)
			(layer "B.Fab")
		)
		(fp_line
			(start -0.120396 0.2794)
			(end 0.12065 0.2794)
			(stroke
				(width 0.1)
				(type default)
			)
			(layer "B.Fab")
		)
		(fp_line
			(start -0.120396 0.3048)
			(end -0.120396 0.2794)
			(stroke
				(width 0.1)
				(type default)
			)
			(layer "B.Fab")
		)
		(fp_line
			(start 0.12065 -0.305054)
			(end 0.12065 -0.2794)
			(stroke
				(width 0.1)
				(type default)
			)
			(layer "B.Fab")
		)
		(fp_line
			(start 0.12065 -0.2794)
			(end -0.12065 -0.2794)
			(stroke
				(width 0.1)
				(type default)
			)
			(layer "B.Fab")
		)
		(fp_line
			(start 0.12065 0.2794)
			(end 0.12065 0.3048)
			(stroke
				(width 0.1)
				(type default)
			)
			(layer "B.Fab")
		)
		(fp_line
			(start 0.12065 0.3048)
			(end 0.67945 0.3048)
			(stroke
				(width 0.1)
				(type default)
			)
			(layer "B.Fab")
		)
		(fp_line
			(start 0.67945 -0.305054)
			(end 0.12065 -0.305054)
			(stroke
				(width 0.1)
				(type default)
			)
			(layer "B.Fab")
		)
		(fp_line
			(start 0.67945 0.3048)
			(end 0.67945 -0.305054)
			(stroke
				(width 0.1)
				(type default)
			)
			(layer "B.Fab")
		)
		(pad "1" smd circle
			(at 0.40005 0 180)
			(size 0 0)
			(layers "B.Cu" "B.Mask" "B.Paste")
			(net "PVDD11_S3_P0")
		)
		(pad "2" smd circle
			(at -0.40005 0 180)
			(size 0 0)
			(layers "B.Cu" "B.Mask" "B.Paste")
			(net "GND")
		)
	)
	(footprint ""
		(layer "B.Cu")
		(at 136.868154 -165.145212 90)
		(property "Reference" "PC354_3"
			(at 0 0 90)
			(layer "B.SilkS")
			(hide yes)
			(effects
				(font
					(size 1.27 1.27)
				)
				(justify mirror)
			)
		)
		(property "Value" ""
			(at 0 0 90)
			(layer "B.Fab")
			(effects
				(font
					(size 1.27 1.27)
				)
				(justify mirror)
			)
		)
		(duplicate_pad_numbers_are_jumpers no)
		(fp_line
			(start 1.524 -0.762)
			(end -1.524 -0.762)
			(stroke
				(width 0.1524)
				(type default)
			)
			(layer "B.SilkS")
		)
		(fp_line
			(start -1.524 -0.762)
			(end -1.524 0.762)
			(stroke
				(width 0.1524)
				(type default)
			)
			(layer "B.SilkS")
		)
		(fp_line
			(start 1.524 0.762)
			(end 1.524 -0.762)
			(stroke
				(width 0.1524)
				(type default)
			)
			(layer "B.SilkS")
		)
		(fp_line
			(start -1.524 0.762)
			(end 1.524 0.762)
			(stroke
				(width 0.1524)
				(type default)
			)
			(layer "B.SilkS")
		)
		(fp_line
			(start 1.1049 -0.724916)
			(end 1.1049 0.724916)
			(stroke
				(width 0.1)
				(type default)
			)
			(layer "B.Fab")
		)
		(fp_line
			(start -1.1049 -0.724916)
			(end 1.1049 -0.724916)
			(stroke
				(width 0.1)
				(type default)
			)
			(layer "B.Fab")
		)
		(fp_line
			(start 1.1049 0.724916)
			(end -1.1049 0.724916)
			(stroke
				(width 0.1)
				(type default)
			)
			(layer "B.Fab")
		)
		(fp_line
			(start -1.1049 0.724916)
			(end -1.1049 -0.724916)
			(stroke
				(width 0.1)
				(type default)
			)
			(layer "B.Fab")
		)
		(pad "1" smd rect
			(at 0.889 0 90)
			(size 1.016 1.27)
			(layers "B.Cu" "B.Mask" "B.Paste")
			(net "PVDDCR_SOC_P1")
		)
		(pad "2" smd rect
			(at -0.889 0 90)
			(size 1.016 1.27)
			(layers "B.Cu" "B.Mask" "B.Paste")
			(net "GND")
		)
	)
	(footprint ""
		(layer "B.Cu")
		(at 35.306 -361.95)
		(property "Reference" "PR230"
			(at 0 0 0)
			(layer "B.SilkS")
			(hide yes)
			(effects
				(font
					(size 1.27 1.27)
				)
				(justify mirror)
			)
		)
		(property "Value" ""
			(at 0 0 0)
			(layer "B.Fab")
			(effects
				(font
					(size 1.27 1.27)
				)
				(justify mirror)
			)
		)
		(duplicate_pad_numbers_are_jumpers no)
		(fp_line
			(start -0.7874 -0.4064)
			(end -0.7874 0.4064)
			(stroke
				(width 0.1524)
				(type default)
			)
			(layer "B.SilkS")
		)
		(fp_line
			(start -0.7874 0.4064)
			(end 0.7874 0.4064)
			(stroke
				(width 0.1524)
				(type default)
			)
			(layer "B.SilkS")
		)
		(fp_line
			(start 0.7874 -0.4064)
			(end -0.7874 -0.4064)
			(stroke
				(width 0.1524)
				(type default)
			)
			(layer "B.SilkS")
		)
		(fp_line
			(start 0.7874 0.4064)
			(end 0.7874 -0.4064)
			(stroke
				(width 0.1524)
				(type default)
			)
			(layer "B.SilkS")
		)
		(fp_line
			(start -0.67945 -0.3048)
			(end -0.67945 0.3048)
			(stroke
				(width 0.1)
				(type default)
			)
			(layer "B.Fab")
		)
		(fp_line
			(start -0.67945 0.3048)
			(end -0.120396 0.3048)
			(stroke
				(width 0.1)
				(type default)
			)
			(layer "B.Fab")
		)
		(fp_line
			(start -0.12065 -0.3048)
			(end -0.67945 -0.3048)
			(stroke
				(width 0.1)
				(type default)
			)
			(layer "B.Fab")
		)
		(fp_line
			(start -0.12065 -0.2794)
			(end -0.12065 -0.3048)
			(stroke
				(width 0.1)
				(type default)
			)
			(layer "B.Fab")
		)
		(fp_line
			(start -0.120396 0.2794)
			(end 0.12065 0.2794)
			(stroke
				(width 0.1)
				(type default)
			)
			(layer "B.Fab")
		)
		(fp_line
			(start -0.120396 0.3048)
			(end -0.120396 0.2794)
			(stroke
				(width 0.1)
				(type default)
			)
			(layer "B.Fab")
		)
		(fp_line
			(start 0.12065 -0.305054)
			(end 0.12065 -0.2794)
			(stroke
				(width 0.1)
				(type default)
			)
			(layer "B.Fab")
		)
		(fp_line
			(start 0.12065 -0.2794)
			(end -0.12065 -0.2794)
			(stroke
				(width 0.1)
				(type default)
			)
			(layer "B.Fab")
		)
		(fp_line
			(start 0.12065 0.2794)
			(end 0.12065 0.3048)
			(stroke
				(width 0.1)
				(type default)
			)
			(layer "B.Fab")
		)
		(fp_line
			(start 0.12065 0.3048)
			(end 0.67945 0.3048)
			(stroke
				(width 0.1)
				(type default)
			)
			(layer "B.Fab")
		)
		(fp_line
			(start 0.67945 -0.305054)
			(end 0.12065 -0.305054)
			(stroke
				(width 0.1)
				(type default)
			)
			(layer "B.Fab")
		)
		(fp_line
			(start 0.67945 0.3048)
			(end 0.67945 -0.305054)
			(stroke
				(width 0.1)
				(type default)
			)
			(layer "B.Fab")
		)
		(pad "1" smd circle
			(at 0.40005 0 180)
			(size 0 0)
			(layers "B.Cu" "B.Mask" "B.Paste")
			(net "P5V_AUX")
		)
		(pad "2" smd circle
			(at -0.40005 0 180)
			(size 0 0)
			(layers "B.Cu" "B.Mask" "B.Paste")
			(net "PVDDCR_CPU1_P1_VMON")
		)
	)
	(footprint ""
		(layer "B.Cu")
		(at 107.677204 -261.748016 90)
		(property "Reference" "C3921"
			(at 0 0 90)
			(layer "B.SilkS")
			(hide yes)
			(effects
				(font
					(size 1.27 1.27)
				)
				(justify mirror)
			)
		)
		(property "Value" ""
			(at 0 0 90)
			(layer "B.Fab")
			(effects
				(font
					(size 1.27 1.27)
				)
				(justify mirror)
			)
		)
		(duplicate_pad_numbers_are_jumpers no)
		(fp_line
			(start 0.7874 -0.4064)
			(end -0.7874 -0.4064)
			(stroke
				(width 0.1524)
				(type default)
			)
			(layer "B.SilkS")
		)
		(fp_line
			(start -0.7874 -0.4064)
			(end -0.7874 0.4064)
			(stroke
				(width 0.1524)
				(type default)
			)
			(layer "B.SilkS")
		)
		(fp_line
			(start 0.7874 0.4064)
			(end 0.7874 -0.4064)
			(stroke
				(width 0.1524)
				(type default)
			)
			(layer "B.SilkS")
		)
		(fp_line
			(start -0.7874 0.4064)
			(end 0.7874 0.4064)
			(stroke
				(width 0.1524)
				(type default)
			)
			(layer "B.SilkS")
		)
		(fp_line
			(start 0.67945 -0.305054)
			(end 0.12065 -0.305054)
			(stroke
				(width 0.1)
				(type default)
			)
			(layer "B.Fab")
		)
		(fp_line
			(start 0.12065 -0.305054)
			(end 0.12065 -0.2794)
			(stroke
				(width 0.1)
				(type default)
			)
			(layer "B.Fab")
		)
		(fp_line
			(start -0.12065 -0.3048)
			(end -0.67945 -0.3048)
			(stroke
				(width 0.1)
				(type default)
			)
			(layer "B.Fab")
		)
		(fp_line
			(start -0.67945 -0.3048)
			(end -0.67945 0.3048)
			(stroke
				(width 0.1)
				(type default)
			)
			(layer "B.Fab")
		)
		(fp_line
			(start 0.12065 -0.2794)
			(end -0.12065 -0.2794)
			(stroke
				(width 0.1)
				(type default)
			)
			(layer "B.Fab")
		)
		(fp_line
			(start -0.12065 -0.2794)
			(end -0.12065 -0.3048)
			(stroke
				(width 0.1)
				(type default)
			)
			(layer "B.Fab")
		)
		(fp_line
			(start 0.12065 0.2794)
			(end 0.12065 0.3048)
			(stroke
				(width 0.1)
				(type default)
			)
			(layer "B.Fab")
		)
		(fp_line
			(start -0.120396 0.2794)
			(end 0.12065 0.2794)
			(stroke
				(width 0.1)
				(type default)
			)
			(layer "B.Fab")
		)
		(fp_line
			(start 0.67945 0.3048)
			(end 0.67945 -0.305054)
			(stroke
				(width 0.1)
				(type default)
			)
			(layer "B.Fab")
		)
		(fp_line
			(start 0.12065 0.3048)
			(end 0.67945 0.3048)
			(stroke
				(width 0.1)
				(type default)
			)
			(layer "B.Fab")
		)
		(fp_line
			(start -0.120396 0.3048)
			(end -0.120396 0.2794)
			(stroke
				(width 0.1)
				(type default)
			)
			(layer "B.Fab")
		)
		(fp_line
			(start -0.67945 0.3048)
			(end -0.120396 0.3048)
			(stroke
				(width 0.1)
				(type default)
			)
			(layer "B.Fab")
		)
		(pad "1" smd circle
			(at 0.40005 0 270)
			(size 0 0)
			(layers "B.Cu" "B.Mask" "B.Paste")
			(net "PVDD11_S3_P1")
		)
		(pad "2" smd circle
			(at -0.40005 0 270)
			(size 0 0)
			(layers "B.Cu" "B.Mask" "B.Paste")
			(net "GND")
		)
	)
	(footprint ""
		(layer "B.Cu")
		(at 64.616584 -408.517344 90)
		(property "Reference" "C6672"
			(at 0 0 90)
			(layer "B.SilkS")
			(hide yes)
			(effects
				(font
					(size 1.27 1.27)
				)
				(justify mirror)
			)
		)
		(property "Value" ""
			(at 0 0 90)
			(layer "B.Fab")
			(effects
				(font
					(size 1.27 1.27)
				)
				(justify mirror)
			)
		)
		(duplicate_pad_numbers_are_jumpers no)
		(fp_line
			(start 0.299974 -0.150114)
			(end -0.299974 -0.150114)
			(stroke
				(width 0.1)
				(type default)
			)
			(layer "B.Fab")
		)
		(fp_line
			(start -0.299974 -0.150114)
			(end -0.299974 0.150114)
			(stroke
				(width 0.1)
				(type default)
			)
			(layer "B.Fab")
		)
		(fp_line
			(start 0.299974 0.150114)
			(end 0.299974 -0.150114)
			(stroke
				(width 0.1)
				(type default)
			)
			(layer "B.Fab")
		)
		(fp_line
			(start -0.299974 0.150114)
			(end 0.299974 0.150114)
			(stroke
				(width 0.1)
				(type default)
			)
			(layer "B.Fab")
		)
		(pad "1" smd rect
			(at 0.2667 0 270)
			(size 0.3048 0.381)
			(layers "B.Cu" "B.Mask" "B.Paste")
			(net "P5E_CPU1_P1_TX_BUF_C_DN<5>")
		)
		(pad "2" smd rect
			(at -0.2667 0 270)
			(size 0.3048 0.381)
			(layers "B.Cu" "B.Mask" "B.Paste")
			(net "P5E_CPU1_P1_TX_BUF_DN<5>")
		)
	)
	(footprint ""
		(layer "B.Cu")
		(at 20.489418 -413.99587)
		(property "Reference" "R6800"
			(at 0 0 0)
			(layer "B.SilkS")
			(hide yes)
			(effects
				(font
					(size 1.27 1.27)
				)
				(justify mirror)
			)
		)
		(property "Value" ""
			(at 0 0 0)
			(layer "B.Fab")
			(effects
				(font
					(size 1.27 1.27)
				)
				(justify mirror)
			)
		)
		(duplicate_pad_numbers_are_jumpers no)
		(fp_line
			(start -0.7874 -0.4064)
			(end -0.7874 0.4064)
			(stroke
				(width 0.1524)
				(type default)
			)
			(layer "B.SilkS")
		)
		(fp_line
			(start -0.7874 0.4064)
			(end 0.7874 0.4064)
			(stroke
				(width 0.1524)
				(type default)
			)
			(layer "B.SilkS")
		)
		(fp_line
			(start 0.7874 -0.4064)
			(end -0.7874 -0.4064)
			(stroke
				(width 0.1524)
				(type default)
			)
			(layer "B.SilkS")
		)
		(fp_line
			(start 0.7874 0.4064)
			(end 0.7874 -0.4064)
			(stroke
				(width 0.1524)
				(type default)
			)
			(layer "B.SilkS")
		)
		(fp_line
			(start -0.67945 -0.3048)
			(end -0.67945 0.3048)
			(stroke
				(width 0.1)
				(type default)
			)
			(layer "B.Fab")
		)
		(fp_line
			(start -0.67945 0.3048)
			(end -0.120396 0.3048)
			(stroke
				(width 0.1)
				(type default)
			)
			(layer "B.Fab")
		)
		(fp_line
			(start -0.12065 -0.3048)
			(end -0.67945 -0.3048)
			(stroke
				(width 0.1)
				(type default)
			)
			(layer "B.Fab")
		)
		(fp_line
			(start -0.12065 -0.2794)
			(end -0.12065 -0.3048)
			(stroke
				(width 0.1)
				(type default)
			)
			(layer "B.Fab")
		)
		(fp_line
			(start -0.120396 0.2794)
			(end 0.12065 0.2794)
			(stroke
				(width 0.1)
				(type default)
			)
			(layer "B.Fab")
		)
		(fp_line
			(start -0.120396 0.3048)
			(end -0.120396 0.2794)
			(stroke
				(width 0.1)
				(type default)
			)
			(layer "B.Fab")
		)
		(fp_line
			(start 0.12065 -0.305054)
			(end 0.12065 -0.2794)
			(stroke
				(width 0.1)
				(type default)
			)
			(layer "B.Fab")
		)
		(fp_line
			(start 0.12065 -0.2794)
			(end -0.12065 -0.2794)
			(stroke
				(width 0.1)
				(type default)
			)
			(layer "B.Fab")
		)
		(fp_line
			(start 0.12065 0.2794)
			(end 0.12065 0.3048)
			(stroke
				(width 0.1)
				(type default)
			)
			(layer "B.Fab")
		)
		(fp_line
			(start 0.12065 0.3048)
			(end 0.67945 0.3048)
			(stroke
				(width 0.1)
				(type default)
			)
			(layer "B.Fab")
		)
		(fp_line
			(start 0.67945 -0.305054)
			(end 0.12065 -0.305054)
			(stroke
				(width 0.1)
				(type default)
			)
			(layer "B.Fab")
		)
		(fp_line
			(start 0.67945 0.3048)
			(end 0.67945 -0.305054)
			(stroke
				(width 0.1)
				(type default)
			)
			(layer "B.Fab")
		)
		(pad "1" smd circle
			(at 0.40005 0 180)
			(size 0 0)
			(layers "B.Cu" "B.Mask" "B.Paste")
			(net "GND")
		)
		(pad "2" smd circle
			(at -0.40005 0 180)
			(size 0 0)
			(layers "B.Cu" "B.Mask" "B.Paste")
			(net "P0V9_RETIMER_CPU1_EN1_R")
		)
	)
	(footprint ""
		(layer "B.Cu")
		(at 370.122958 -245.487952)
		(property "Reference" "C2192"
			(at 0 0 0)
			(layer "B.SilkS")
			(hide yes)
			(effects
				(font
					(size 1.27 1.27)
				)
				(justify mirror)
			)
		)
		(property "Value" ""
			(at 0 0 0)
			(layer "B.Fab")
			(effects
				(font
					(size 1.27 1.27)
				)
				(justify mirror)
			)
		)
		(duplicate_pad_numbers_are_jumpers no)
		(fp_line
			(start -0.7874 -0.4064)
			(end -0.7874 0.4064)
			(stroke
				(width 0.1524)
				(type default)
			)
			(layer "B.SilkS")
		)
		(fp_line
			(start -0.7874 0.4064)
			(end 0.7874 0.4064)
			(stroke
				(width 0.1524)
				(type default)
			)
			(layer "B.SilkS")
		)
		(fp_line
			(start 0.7874 -0.4064)
			(end -0.7874 -0.4064)
			(stroke
				(width 0.1524)
				(type default)
			)
			(layer "B.SilkS")
		)
		(fp_line
			(start 0.7874 0.4064)
			(end 0.7874 -0.4064)
			(stroke
				(width 0.1524)
				(type default)
			)
			(layer "B.SilkS")
		)
		(fp_line
			(start -0.67945 -0.3048)
			(end -0.67945 0.3048)
			(stroke
				(width 0.1)
				(type default)
			)
			(layer "B.Fab")
		)
		(fp_line
			(start -0.67945 0.3048)
			(end -0.120396 0.3048)
			(stroke
				(width 0.1)
				(type default)
			)
			(layer "B.Fab")
		)
		(fp_line
			(start -0.12065 -0.3048)
			(end -0.67945 -0.3048)
			(stroke
				(width 0.1)
				(type default)
			)
			(layer "B.Fab")
		)
		(fp_line
			(start -0.12065 -0.2794)
			(end -0.12065 -0.3048)
			(stroke
				(width 0.1)
				(type default)
			)
			(layer "B.Fab")
		)
		(fp_line
			(start -0.120396 0.2794)
			(end 0.12065 0.2794)
			(stroke
				(width 0.1)
				(type default)
			)
			(layer "B.Fab")
		)
		(fp_line
			(start -0.120396 0.3048)
			(end -0.120396 0.2794)
			(stroke
				(width 0.1)
				(type default)
			)
			(layer "B.Fab")
		)
		(fp_line
			(start 0.12065 -0.305054)
			(end 0.12065 -0.2794)
			(stroke
				(width 0.1)
				(type default)
			)
			(layer "B.Fab")
		)
		(fp_line
			(start 0.12065 -0.2794)
			(end -0.12065 -0.2794)
			(stroke
				(width 0.1)
				(type default)
			)
			(layer "B.Fab")
		)
		(fp_line
			(start 0.12065 0.2794)
			(end 0.12065 0.3048)
			(stroke
				(width 0.1)
				(type default)
			)
			(layer "B.Fab")
		)
		(fp_line
			(start 0.12065 0.3048)
			(end 0.67945 0.3048)
			(stroke
				(width 0.1)
				(type default)
			)
			(layer "B.Fab")
		)
		(fp_line
			(start 0.67945 -0.305054)
			(end 0.12065 -0.305054)
			(stroke
				(width 0.1)
				(type default)
			)
			(layer "B.Fab")
		)
		(fp_line
			(start 0.67945 0.3048)
			(end 0.67945 -0.305054)
			(stroke
				(width 0.1)
				(type default)
			)
			(layer "B.Fab")
		)
		(pad "1" smd circle
			(at 0.40005 0 180)
			(size 0 0)
			(layers "B.Cu" "B.Mask" "B.Paste")
			(net "PVDDCR_CPU0_P0")
		)
		(pad "2" smd circle
			(at -0.40005 0 180)
			(size 0 0)
			(layers "B.Cu" "B.Mask" "B.Paste")
			(net "GND")
		)
	)
	(footprint ""
		(layer "B.Cu")
		(at 101.384862 -181.633876 90)
		(property "Reference" "PR193"
			(at 0 0 90)
			(layer "B.SilkS")
			(hide yes)
			(effects
				(font
					(size 1.27 1.27)
				)
				(justify mirror)
			)
		)
		(property "Value" ""
			(at 0 0 90)
			(layer "B.Fab")
			(effects
				(font
					(size 1.27 1.27)
				)
				(justify mirror)
			)
		)
		(duplicate_pad_numbers_are_jumpers no)
		(fp_line
			(start 0.7874 -0.4064)
			(end -0.7874 -0.4064)
			(stroke
				(width 0.1524)
				(type default)
			)
			(layer "B.SilkS")
		)
		(fp_line
			(start -0.7874 -0.4064)
			(end -0.7874 0.4064)
			(stroke
				(width 0.1524)
				(type default)
			)
			(layer "B.SilkS")
		)
		(fp_line
			(start 0.7874 0.4064)
			(end 0.7874 -0.4064)
			(stroke
				(width 0.1524)
				(type default)
			)
			(layer "B.SilkS")
		)
		(fp_line
			(start -0.7874 0.4064)
			(end 0.7874 0.4064)
			(stroke
				(width 0.1524)
				(type default)
			)
			(layer "B.SilkS")
		)
		(fp_line
			(start 0.67945 -0.305054)
			(end 0.12065 -0.305054)
			(stroke
				(width 0.1)
				(type default)
			)
			(layer "B.Fab")
		)
		(fp_line
			(start 0.12065 -0.305054)
			(end 0.12065 -0.2794)
			(stroke
				(width 0.1)
				(type default)
			)
			(layer "B.Fab")
		)
		(fp_line
			(start -0.12065 -0.3048)
			(end -0.67945 -0.3048)
			(stroke
				(width 0.1)
				(type default)
			)
			(layer "B.Fab")
		)
		(fp_line
			(start -0.67945 -0.3048)
			(end -0.67945 0.3048)
			(stroke
				(width 0.1)
				(type default)
			)
			(layer "B.Fab")
		)
		(fp_line
			(start 0.12065 -0.2794)
			(end -0.12065 -0.2794)
			(stroke
				(width 0.1)
				(type default)
			)
			(layer "B.Fab")
		)
		(fp_line
			(start -0.12065 -0.2794)
			(end -0.12065 -0.3048)
			(stroke
				(width 0.1)
				(type default)
			)
			(layer "B.Fab")
		)
		(fp_line
			(start 0.12065 0.2794)
			(end 0.12065 0.3048)
			(stroke
				(width 0.1)
				(type default)
			)
			(layer "B.Fab")
		)
		(fp_line
			(start -0.120396 0.2794)
			(end 0.12065 0.2794)
			(stroke
				(width 0.1)
				(type default)
			)
			(layer "B.Fab")
		)
		(fp_line
			(start 0.67945 0.3048)
			(end 0.67945 -0.305054)
			(stroke
				(width 0.1)
				(type default)
			)
			(layer "B.Fab")
		)
		(fp_line
			(start 0.12065 0.3048)
			(end 0.67945 0.3048)
			(stroke
				(width 0.1)
				(type default)
			)
			(layer "B.Fab")
		)
		(fp_line
			(start -0.120396 0.3048)
			(end -0.120396 0.2794)
			(stroke
				(width 0.1)
				(type default)
			)
			(layer "B.Fab")
		)
		(fp_line
			(start -0.67945 0.3048)
			(end -0.120396 0.3048)
			(stroke
				(width 0.1)
				(type default)
			)
			(layer "B.Fab")
		)
		(pad "1" smd circle
			(at 0.40005 0 270)
			(size 0 0)
			(layers "B.Cu" "B.Mask" "B.Paste")
			(net "PVDDCR_CPU0_P1_PVCC")
		)
		(pad "2" smd circle
			(at -0.40005 0 270)
			(size 0 0)
			(layers "B.Cu" "B.Mask" "B.Paste")
			(net "PVDDCR_CPU0_P1_VCC3")
		)
	)
	(footprint ""
		(layer "B.Cu")
		(at 372.937278 -138.424158 180)
		(property "Reference" "R8310"
			(at 0 0 0)
			(layer "B.SilkS")
			(hide yes)
			(effects
				(font
					(size 1.27 1.27)
				)
				(justify mirror)
			)
		)
		(property "Value" ""
			(at 0 0 0)
			(layer "B.Fab")
			(effects
				(font
					(size 1.27 1.27)
				)
				(justify mirror)
			)
		)
		(duplicate_pad_numbers_are_jumpers no)
		(fp_line
			(start 0.7874 0.4064)
			(end 0.7874 -0.4064)
			(stroke
				(width 0.1524)
				(type default)
			)
			(layer "B.SilkS")
		)
		(fp_line
			(start 0.7874 -0.4064)
			(end -0.7874 -0.4064)
			(stroke
				(width 0.1524)
				(type default)
			)
			(layer "B.SilkS")
		)
		(fp_line
			(start -0.7874 0.4064)
			(end 0.7874 0.4064)
			(stroke
				(width 0.1524)
				(type default)
			)
			(layer "B.SilkS")
		)
		(fp_line
			(start -0.7874 -0.4064)
			(end -0.7874 0.4064)
			(stroke
				(width 0.1524)
				(type default)
			)
			(layer "B.SilkS")
		)
		(fp_line
			(start 0.67945 0.3048)
			(end 0.67945 -0.305054)
			(stroke
				(width 0.1)
				(type default)
			)
			(layer "B.Fab")
		)
		(fp_line
			(start 0.67945 -0.305054)
			(end 0.12065 -0.305054)
			(stroke
				(width 0.1)
				(type default)
			)
			(layer "B.Fab")
		)
		(fp_line
			(start 0.12065 0.3048)
			(end 0.67945 0.3048)
			(stroke
				(width 0.1)
				(type default)
			)
			(layer "B.Fab")
		)
		(fp_line
			(start 0.12065 0.2794)
			(end 0.12065 0.3048)
			(stroke
				(width 0.1)
				(type default)
			)
			(layer "B.Fab")
		)
		(fp_line
			(start 0.12065 -0.2794)
			(end -0.12065 -0.2794)
			(stroke
				(width 0.1)
				(type default)
			)
			(layer "B.Fab")
		)
		(fp_line
			(start 0.12065 -0.305054)
			(end 0.12065 -0.2794)
			(stroke
				(width 0.1)
				(type default)
			)
			(layer "B.Fab")
		)
		(fp_line
			(start -0.120396 0.3048)
			(end -0.120396 0.2794)
			(stroke
				(width 0.1)
				(type default)
			)
			(layer "B.Fab")
		)
		(fp_line
			(start -0.120396 0.2794)
			(end 0.12065 0.2794)
			(stroke
				(width 0.1)
				(type default)
			)
			(layer "B.Fab")
		)
		(fp_line
			(start -0.12065 -0.2794)
			(end -0.12065 -0.3048)
			(stroke
				(width 0.1)
				(type default)
			)
			(layer "B.Fab")
		)
		(fp_line
			(start -0.12065 -0.3048)
			(end -0.67945 -0.3048)
			(stroke
				(width 0.1)
				(type default)
			)
			(layer "B.Fab")
		)
		(fp_line
			(start -0.67945 0.3048)
			(end -0.120396 0.3048)
			(stroke
				(width 0.1)
				(type default)
			)
			(layer "B.Fab")
		)
		(fp_line
			(start -0.67945 -0.3048)
			(end -0.67945 0.3048)
			(stroke
				(width 0.1)
				(type default)
			)
			(layer "B.Fab")
		)
		(pad "1" smd circle
			(at 0.40005 0)
			(size 0 0)
			(layers "B.Cu" "B.Mask" "B.Paste")
			(net "PVDDCR_CPU0_P0_PMALERT")
		)
		(pad "2" smd circle
			(at -0.40005 0)
			(size 0 0)
			(layers "B.Cu" "B.Mask" "B.Paste")
			(net "PVDDCR_CPU0_P0_PMALERT_R")
		)
	)
	(footprint ""
		(layer "B.Cu")
		(at 457.148184 -65.768982 90)
		(property "Reference" "PC1600"
			(at 0 0 90)
			(layer "B.SilkS")
			(hide yes)
			(effects
				(font
					(size 1.27 1.27)
				)
				(justify mirror)
			)
		)
		(property "Value" ""
			(at 0 0 90)
			(layer "B.Fab")
			(effects
				(font
					(size 1.27 1.27)
				)
				(justify mirror)
			)
		)
		(duplicate_pad_numbers_are_jumpers no)
		(fp_line
			(start 1.524 -0.762)
			(end -1.524 -0.762)
			(stroke
				(width 0.1524)
				(type default)
			)
			(layer "B.SilkS")
		)
		(fp_line
			(start -1.524 -0.762)
			(end -1.524 0.762)
			(stroke
				(width 0.1524)
				(type default)
			)
			(layer "B.SilkS")
		)
		(fp_line
			(start 1.524 0.762)
			(end 1.524 -0.762)
			(stroke
				(width 0.1524)
				(type default)
			)
			(layer "B.SilkS")
		)
		(fp_line
			(start -1.524 0.762)
			(end 1.524 0.762)
			(stroke
				(width 0.1524)
				(type default)
			)
			(layer "B.SilkS")
		)
		(fp_line
			(start 1.1049 -0.724916)
			(end 1.1049 0.724916)
			(stroke
				(width 0.1)
				(type default)
			)
			(layer "B.Fab")
		)
		(fp_line
			(start -1.1049 -0.724916)
			(end 1.1049 -0.724916)
			(stroke
				(width 0.1)
				(type default)
			)
			(layer "B.Fab")
		)
		(fp_line
			(start 1.1049 0.724916)
			(end -1.1049 0.724916)
			(stroke
				(width 0.1)
				(type default)
			)
			(layer "B.Fab")
		)
		(fp_line
			(start -1.1049 0.724916)
			(end -1.1049 -0.724916)
			(stroke
				(width 0.1)
				(type default)
			)
			(layer "B.Fab")
		)
		(pad "1" smd rect
			(at 0.889 0 90)
			(size 1.016 1.27)
			(layers "B.Cu" "B.Mask" "B.Paste")
			(net "P3V3_AUX")
		)
		(pad "2" smd rect
			(at -0.889 0 90)
			(size 1.016 1.27)
			(layers "B.Cu" "B.Mask" "B.Paste")
			(net "GND")
		)
	)
	(footprint ""
		(layer "B.Cu")
		(at 22.096984 -389.526526 -90)
		(property "Reference" "PR6627"
			(at 0 0 90)
			(layer "B.SilkS")
			(hide yes)
			(effects
				(font
					(size 1.27 1.27)
				)
				(justify mirror)
			)
		)
		(property "Value" ""
			(at 0 0 90)
			(layer "B.Fab")
			(effects
				(font
					(size 1.27 1.27)
				)
				(justify mirror)
			)
		)
		(duplicate_pad_numbers_are_jumpers no)
		(fp_line
			(start -0.7874 0.4064)
			(end 0.7874 0.4064)
			(stroke
				(width 0.1524)
				(type default)
			)
			(layer "B.SilkS")
		)
		(fp_line
			(start 0.7874 0.4064)
			(end 0.7874 -0.4064)
			(stroke
				(width 0.1524)
				(type default)
			)
			(layer "B.SilkS")
		)
		(fp_line
			(start -0.7874 -0.4064)
			(end -0.7874 0.4064)
			(stroke
				(width 0.1524)
				(type default)
			)
			(layer "B.SilkS")
		)
		(fp_line
			(start 0.7874 -0.4064)
			(end -0.7874 -0.4064)
			(stroke
				(width 0.1524)
				(type default)
			)
			(layer "B.SilkS")
		)
		(fp_line
			(start -0.67945 0.3048)
			(end -0.120396 0.3048)
			(stroke
				(width 0.1)
				(type default)
			)
			(layer "B.Fab")
		)
		(fp_line
			(start -0.120396 0.3048)
			(end -0.120396 0.2794)
			(stroke
				(width 0.1)
				(type default)
			)
			(layer "B.Fab")
		)
		(fp_line
			(start 0.12065 0.3048)
			(end 0.67945 0.3048)
			(stroke
				(width 0.1)
				(type default)
			)
			(layer "B.Fab")
		)
		(fp_line
			(start 0.67945 0.3048)
			(end 0.67945 -0.305054)
			(stroke
				(width 0.1)
				(type default)
			)
			(layer "B.Fab")
		)
		(fp_line
			(start -0.120396 0.2794)
			(end 0.12065 0.2794)
			(stroke
				(width 0.1)
				(type default)
			)
			(layer "B.Fab")
		)
		(fp_line
			(start 0.12065 0.2794)
			(end 0.12065 0.3048)
			(stroke
				(width 0.1)
				(type default)
			)
			(layer "B.Fab")
		)
		(fp_line
			(start -0.12065 -0.2794)
			(end -0.12065 -0.3048)
			(stroke
				(width 0.1)
				(type default)
			)
			(layer "B.Fab")
		)
		(fp_line
			(start 0.12065 -0.2794)
			(end -0.12065 -0.2794)
			(stroke
				(width 0.1)
				(type default)
			)
			(layer "B.Fab")
		)
		(fp_line
			(start -0.67945 -0.3048)
			(end -0.67945 0.3048)
			(stroke
				(width 0.1)
				(type default)
			)
			(layer "B.Fab")
		)
		(fp_line
			(start -0.12065 -0.3048)
			(end -0.67945 -0.3048)
			(stroke
				(width 0.1)
				(type default)
			)
			(layer "B.Fab")
		)
		(fp_line
			(start 0.12065 -0.305054)
			(end 0.12065 -0.2794)
			(stroke
				(width 0.1)
				(type default)
			)
			(layer "B.Fab")
		)
		(fp_line
			(start 0.67945 -0.305054)
			(end 0.12065 -0.305054)
			(stroke
				(width 0.1)
				(type default)
			)
			(layer "B.Fab")
		)
		(pad "1" smd circle
			(at 0.40005 0 90)
			(size 0 0)
			(layers "B.Cu" "B.Mask" "B.Paste")
			(net "P0V9_RETIMER_CPU1_PVCC")
		)
		(pad "2" smd circle
			(at -0.40005 0 90)
			(size 0 0)
			(layers "B.Cu" "B.Mask" "B.Paste")
			(net "P0V9_RETIMER_CPU1_VCC2")
		)
	)
	(footprint ""
		(layer "B.Cu")
		(at 346.705936 -395.148562 90)
		(property "Reference" "C598"
			(at 0 0 90)
			(layer "B.SilkS")
			(hide yes)
			(effects
				(font
					(size 1.27 1.27)
				)
				(justify mirror)
			)
		)
		(property "Value" ""
			(at 0 0 90)
			(layer "B.Fab")
			(effects
				(font
					(size 1.27 1.27)
				)
				(justify mirror)
			)
		)
		(duplicate_pad_numbers_are_jumpers no)
		(fp_line
			(start 0.299974 -0.150114)
			(end -0.299974 -0.150114)
			(stroke
				(width 0.1)
				(type default)
			)
			(layer "B.Fab")
		)
		(fp_line
			(start -0.299974 -0.150114)
			(end -0.299974 0.150114)
			(stroke
				(width 0.1)
				(type default)
			)
			(layer "B.Fab")
		)
		(fp_line
			(start 0.299974 0.150114)
			(end 0.299974 -0.150114)
			(stroke
				(width 0.1)
				(type default)
			)
			(layer "B.Fab")
		)
		(fp_line
			(start -0.299974 0.150114)
			(end 0.299974 0.150114)
			(stroke
				(width 0.1)
				(type default)
			)
			(layer "B.Fab")
		)
		(pad "1" smd rect
			(at 0.2667 0 270)
			(size 0.3048 0.381)
			(layers "B.Cu" "B.Mask" "B.Paste")
			(net "P1V8_CPU0_RT1_1A_1D")
		)
		(pad "2" smd rect
			(at -0.2667 0 270)
			(size 0.3048 0.381)
			(layers "B.Cu" "B.Mask" "B.Paste")
			(net "GND")
		)
	)
	(footprint ""
		(layer "B.Cu")
		(at 117.895624 -257.455416)
		(property "Reference" "C2464"
			(at 0 0 0)
			(layer "B.SilkS")
			(hide yes)
			(effects
				(font
					(size 1.27 1.27)
				)
				(justify mirror)
			)
		)
		(property "Value" ""
			(at 0 0 0)
			(layer "B.Fab")
			(effects
				(font
					(size 1.27 1.27)
				)
				(justify mirror)
			)
		)
		(duplicate_pad_numbers_are_jumpers no)
		(fp_line
			(start -0.7874 -0.4064)
			(end -0.7874 0.4064)
			(stroke
				(width 0.1524)
				(type default)
			)
			(layer "B.SilkS")
		)
		(fp_line
			(start -0.7874 0.4064)
			(end 0.7874 0.4064)
			(stroke
				(width 0.1524)
				(type default)
			)
			(layer "B.SilkS")
		)
		(fp_line
			(start 0.7874 -0.4064)
			(end -0.7874 -0.4064)
			(stroke
				(width 0.1524)
				(type default)
			)
			(layer "B.SilkS")
		)
		(fp_line
			(start 0.7874 0.4064)
			(end 0.7874 -0.4064)
			(stroke
				(width 0.1524)
				(type default)
			)
			(layer "B.SilkS")
		)
		(fp_line
			(start -0.67945 -0.3048)
			(end -0.67945 0.3048)
			(stroke
				(width 0.1)
				(type default)
			)
			(layer "B.Fab")
		)
		(fp_line
			(start -0.67945 0.3048)
			(end -0.120396 0.3048)
			(stroke
				(width 0.1)
				(type default)
			)
			(layer "B.Fab")
		)
		(fp_line
			(start -0.12065 -0.3048)
			(end -0.67945 -0.3048)
			(stroke
				(width 0.1)
				(type default)
			)
			(layer "B.Fab")
		)
		(fp_line
			(start -0.12065 -0.2794)
			(end -0.12065 -0.3048)
			(stroke
				(width 0.1)
				(type default)
			)
			(layer "B.Fab")
		)
		(fp_line
			(start -0.120396 0.2794)
			(end 0.12065 0.2794)
			(stroke
				(width 0.1)
				(type default)
			)
			(layer "B.Fab")
		)
		(fp_line
			(start -0.120396 0.3048)
			(end -0.120396 0.2794)
			(stroke
				(width 0.1)
				(type default)
			)
			(layer "B.Fab")
		)
		(fp_line
			(start 0.12065 -0.305054)
			(end 0.12065 -0.2794)
			(stroke
				(width 0.1)
				(type default)
			)
			(layer "B.Fab")
		)
		(fp_line
			(start 0.12065 -0.2794)
			(end -0.12065 -0.2794)
			(stroke
				(width 0.1)
				(type default)
			)
			(layer "B.Fab")
		)
		(fp_line
			(start 0.12065 0.2794)
			(end 0.12065 0.3048)
			(stroke
				(width 0.1)
				(type default)
			)
			(layer "B.Fab")
		)
		(fp_line
			(start 0.12065 0.3048)
			(end 0.67945 0.3048)
			(stroke
				(width 0.1)
				(type default)
			)
			(layer "B.Fab")
		)
		(fp_line
			(start 0.67945 -0.305054)
			(end 0.12065 -0.305054)
			(stroke
				(width 0.1)
				(type default)
			)
			(layer "B.Fab")
		)
		(fp_line
			(start 0.67945 0.3048)
			(end 0.67945 -0.305054)
			(stroke
				(width 0.1)
				(type default)
			)
			(layer "B.Fab")
		)
		(pad "1" smd circle
			(at 0.40005 0 180)
			(size 0 0)
			(layers "B.Cu" "B.Mask" "B.Paste")
			(net "PVDDCR_SOC_P1")
		)
		(pad "2" smd circle
			(at -0.40005 0 180)
			(size 0 0)
			(layers "B.Cu" "B.Mask" "B.Paste")
			(net "GND")
		)
	)
	(footprint ""
		(layer "B.Cu")
		(at 369.392454 -267.498576)
		(property "Reference" "C2243"
			(at 0 0 0)
			(layer "B.SilkS")
			(hide yes)
			(effects
				(font
					(size 1.27 1.27)
				)
				(justify mirror)
			)
		)
		(property "Value" ""
			(at 0 0 0)
			(layer "B.Fab")
			(effects
				(font
					(size 1.27 1.27)
				)
				(justify mirror)
			)
		)
		(duplicate_pad_numbers_are_jumpers no)
		(fp_line
			(start -0.7874 -0.4064)
			(end -0.7874 0.4064)
			(stroke
				(width 0.1524)
				(type default)
			)
			(layer "B.SilkS")
		)
		(fp_line
			(start -0.7874 0.4064)
			(end 0.7874 0.4064)
			(stroke
				(width 0.1524)
				(type default)
			)
			(layer "B.SilkS")
		)
		(fp_line
			(start 0.7874 -0.4064)
			(end -0.7874 -0.4064)
			(stroke
				(width 0.1524)
				(type default)
			)
			(layer "B.SilkS")
		)
		(fp_line
			(start 0.7874 0.4064)
			(end 0.7874 -0.4064)
			(stroke
				(width 0.1524)
				(type default)
			)
			(layer "B.SilkS")
		)
		(fp_line
			(start -0.67945 -0.3048)
			(end -0.67945 0.3048)
			(stroke
				(width 0.1)
				(type default)
			)
			(layer "B.Fab")
		)
		(fp_line
			(start -0.67945 0.3048)
			(end -0.120396 0.3048)
			(stroke
				(width 0.1)
				(type default)
			)
			(layer "B.Fab")
		)
		(fp_line
			(start -0.12065 -0.3048)
			(end -0.67945 -0.3048)
			(stroke
				(width 0.1)
				(type default)
			)
			(layer "B.Fab")
		)
		(fp_line
			(start -0.12065 -0.2794)
			(end -0.12065 -0.3048)
			(stroke
				(width 0.1)
				(type default)
			)
			(layer "B.Fab")
		)
		(fp_line
			(start -0.120396 0.2794)
			(end 0.12065 0.2794)
			(stroke
				(width 0.1)
				(type default)
			)
			(layer "B.Fab")
		)
		(fp_line
			(start -0.120396 0.3048)
			(end -0.120396 0.2794)
			(stroke
				(width 0.1)
				(type default)
			)
			(layer "B.Fab")
		)
		(fp_line
			(start 0.12065 -0.305054)
			(end 0.12065 -0.2794)
			(stroke
				(width 0.1)
				(type default)
			)
			(layer "B.Fab")
		)
		(fp_line
			(start 0.12065 -0.2794)
			(end -0.12065 -0.2794)
			(stroke
				(width 0.1)
				(type default)
			)
			(layer "B.Fab")
		)
		(fp_line
			(start 0.12065 0.2794)
			(end 0.12065 0.3048)
			(stroke
				(width 0.1)
				(type default)
			)
			(layer "B.Fab")
		)
		(fp_line
			(start 0.12065 0.3048)
			(end 0.67945 0.3048)
			(stroke
				(width 0.1)
				(type default)
			)
			(layer "B.Fab")
		)
		(fp_line
			(start 0.67945 -0.305054)
			(end 0.12065 -0.305054)
			(stroke
				(width 0.1)
				(type default)
			)
			(layer "B.Fab")
		)
		(fp_line
			(start 0.67945 0.3048)
			(end 0.67945 -0.305054)
			(stroke
				(width 0.1)
				(type default)
			)
			(layer "B.Fab")
		)
		(pad "1" smd circle
			(at 0.40005 0 180)
			(size 0 0)
			(layers "B.Cu" "B.Mask" "B.Paste")
			(net "PVDDCR_CPU1_P0")
		)
		(pad "2" smd circle
			(at -0.40005 0 180)
			(size 0 0)
			(layers "B.Cu" "B.Mask" "B.Paste")
			(net "GND")
		)
	)
	(footprint ""
		(layer "B.Cu")
		(at 94.460314 -306.714652)
		(property "Reference" "R456"
			(at 0 0 0)
			(layer "B.SilkS")
			(hide yes)
			(effects
				(font
					(size 1.27 1.27)
				)
				(justify mirror)
			)
		)
		(property "Value" ""
			(at 0 0 0)
			(layer "B.Fab")
			(effects
				(font
					(size 1.27 1.27)
				)
				(justify mirror)
			)
		)
		(duplicate_pad_numbers_are_jumpers no)
		(fp_line
			(start -0.7874 -0.4064)
			(end -0.7874 0.4064)
			(stroke
				(width 0.1524)
				(type default)
			)
			(layer "B.SilkS")
		)
		(fp_line
			(start -0.7874 0.4064)
			(end 0.7874 0.4064)
			(stroke
				(width 0.1524)
				(type default)
			)
			(layer "B.SilkS")
		)
		(fp_line
			(start 0.7874 -0.4064)
			(end -0.7874 -0.4064)
			(stroke
				(width 0.1524)
				(type default)
			)
			(layer "B.SilkS")
		)
		(fp_line
			(start 0.7874 0.4064)
			(end 0.7874 -0.4064)
			(stroke
				(width 0.1524)
				(type default)
			)
			(layer "B.SilkS")
		)
		(fp_line
			(start -0.67945 -0.3048)
			(end -0.67945 0.3048)
			(stroke
				(width 0.1)
				(type default)
			)
			(layer "B.Fab")
		)
		(fp_line
			(start -0.67945 0.3048)
			(end -0.120396 0.3048)
			(stroke
				(width 0.1)
				(type default)
			)
			(layer "B.Fab")
		)
		(fp_line
			(start -0.12065 -0.3048)
			(end -0.67945 -0.3048)
			(stroke
				(width 0.1)
				(type default)
			)
			(layer "B.Fab")
		)
		(fp_line
			(start -0.12065 -0.2794)
			(end -0.12065 -0.3048)
			(stroke
				(width 0.1)
				(type default)
			)
			(layer "B.Fab")
		)
		(fp_line
			(start -0.120396 0.2794)
			(end 0.12065 0.2794)
			(stroke
				(width 0.1)
				(type default)
			)
			(layer "B.Fab")
		)
		(fp_line
			(start -0.120396 0.3048)
			(end -0.120396 0.2794)
			(stroke
				(width 0.1)
				(type default)
			)
			(layer "B.Fab")
		)
		(fp_line
			(start 0.12065 -0.305054)
			(end 0.12065 -0.2794)
			(stroke
				(width 0.1)
				(type default)
			)
			(layer "B.Fab")
		)
		(fp_line
			(start 0.12065 -0.2794)
			(end -0.12065 -0.2794)
			(stroke
				(width 0.1)
				(type default)
			)
			(layer "B.Fab")
		)
		(fp_line
			(start 0.12065 0.2794)
			(end 0.12065 0.3048)
			(stroke
				(width 0.1)
				(type default)
			)
			(layer "B.Fab")
		)
		(fp_line
			(start 0.12065 0.3048)
			(end 0.67945 0.3048)
			(stroke
				(width 0.1)
				(type default)
			)
			(layer "B.Fab")
		)
		(fp_line
			(start 0.67945 -0.305054)
			(end 0.12065 -0.305054)
			(stroke
				(width 0.1)
				(type default)
			)
			(layer "B.Fab")
		)
		(fp_line
			(start 0.67945 0.3048)
			(end 0.67945 -0.305054)
			(stroke
				(width 0.1)
				(type default)
			)
			(layer "B.Fab")
		)
		(pad "1" smd circle
			(at 0.40005 0 180)
			(size 0 0)
			(layers "B.Cu" "B.Mask" "B.Paste")
			(net "CPU1_PWRGD_OUT")
		)
		(pad "2" smd circle
			(at -0.40005 0 180)
			(size 0 0)
			(layers "B.Cu" "B.Mask" "B.Paste")
			(net "PVDD18_S5_P1")
		)
	)
	(footprint ""
		(layer "B.Cu")
		(at 377.839986 -214.523828 90)
		(property "Reference" "R9276"
			(at 0 0 90)
			(layer "B.SilkS")
			(hide yes)
			(effects
				(font
					(size 1.27 1.27)
				)
				(justify mirror)
			)
		)
		(property "Value" ""
			(at 0 0 90)
			(layer "B.Fab")
			(effects
				(font
					(size 1.27 1.27)
				)
				(justify mirror)
			)
		)
		(duplicate_pad_numbers_are_jumpers no)
		(fp_line
			(start 0.7874 -0.4064)
			(end -0.7874 -0.4064)
			(stroke
				(width 0.1524)
				(type default)
			)
			(layer "B.SilkS")
		)
		(fp_line
			(start -0.7874 -0.4064)
			(end -0.7874 0.086614)
			(stroke
				(width 0.1524)
				(type default)
			)
			(layer "B.SilkS")
		)
		(fp_line
			(start 0.7874 0.035814)
			(end 0.7874 -0.4064)
			(stroke
				(width 0.1524)
				(type default)
			)
			(layer "B.SilkS")
		)
		(fp_line
			(start -0.376428 0.4064)
			(end 0.360172 0.4064)
			(stroke
				(width 0.1524)
				(type default)
			)
			(layer "B.SilkS")
		)
		(fp_line
			(start 0.67945 -0.305054)
			(end 0.12065 -0.305054)
			(stroke
				(width 0.1)
				(type default)
			)
			(layer "B.Fab")
		)
		(fp_line
			(start 0.12065 -0.305054)
			(end 0.12065 -0.2794)
			(stroke
				(width 0.1)
				(type default)
			)
			(layer "B.Fab")
		)
		(fp_line
			(start -0.12065 -0.3048)
			(end -0.67945 -0.3048)
			(stroke
				(width 0.1)
				(type default)
			)
			(layer "B.Fab")
		)
		(fp_line
			(start -0.67945 -0.3048)
			(end -0.67945 0.3048)
			(stroke
				(width 0.1)
				(type default)
			)
			(layer "B.Fab")
		)
		(fp_line
			(start 0.12065 -0.2794)
			(end -0.12065 -0.2794)
			(stroke
				(width 0.1)
				(type default)
			)
			(layer "B.Fab")
		)
		(fp_line
			(start -0.12065 -0.2794)
			(end -0.12065 -0.3048)
			(stroke
				(width 0.1)
				(type default)
			)
			(layer "B.Fab")
		)
		(fp_line
			(start 0.12065 0.2794)
			(end 0.12065 0.3048)
			(stroke
				(width 0.1)
				(type default)
			)
			(layer "B.Fab")
		)
		(fp_line
			(start -0.120396 0.2794)
			(end 0.12065 0.2794)
			(stroke
				(width 0.1)
				(type default)
			)
			(layer "B.Fab")
		)
		(fp_line
			(start 0.67945 0.3048)
			(end 0.67945 -0.305054)
			(stroke
				(width 0.1)
				(type default)
			)
			(layer "B.Fab")
		)
		(fp_line
			(start 0.12065 0.3048)
			(end 0.67945 0.3048)
			(stroke
				(width 0.1)
				(type default)
			)
			(layer "B.Fab")
		)
		(fp_line
			(start -0.120396 0.3048)
			(end -0.120396 0.2794)
			(stroke
				(width 0.1)
				(type default)
			)
			(layer "B.Fab")
		)
		(fp_line
			(start -0.67945 0.3048)
			(end -0.120396 0.3048)
			(stroke
				(width 0.1)
				(type default)
			)
			(layer "B.Fab")
		)
		(pad "1" smd circle
			(at 0.40005 0 270)
			(size 0 0)
			(layers "B.Cu" "B.Mask" "B.Paste")
			(net "CLK_100M_CPU0_CLK05_R_DN")
		)
		(pad "2" smd circle
			(at -0.40005 0 270)
			(size 0 0)
			(layers "B.Cu" "B.Mask" "B.Paste")
			(net "CLK_100M_CPU0_CLK05_DN")
		)
	)
	(footprint ""
		(layer "B.Cu")
		(at 236.676692 -422.849548 90)
		(property "Reference" "C67"
			(at 0 0 90)
			(layer "B.SilkS")
			(hide yes)
			(effects
				(font
					(size 1.27 1.27)
				)
				(justify mirror)
			)
		)
		(property "Value" ""
			(at 0 0 90)
			(layer "B.Fab")
			(effects
				(font
					(size 1.27 1.27)
				)
				(justify mirror)
			)
		)
		(duplicate_pad_numbers_are_jumpers no)
		(fp_line
			(start 0.7874 -0.4064)
			(end -0.7874 -0.4064)
			(stroke
				(width 0.1524)
				(type default)
			)
			(layer "B.SilkS")
		)
		(fp_line
			(start -0.7874 -0.4064)
			(end -0.7874 0.4064)
			(stroke
				(width 0.1524)
				(type default)
			)
			(layer "B.SilkS")
		)
		(fp_line
			(start 0.7874 0.4064)
			(end 0.7874 -0.4064)
			(stroke
				(width 0.1524)
				(type default)
			)
			(layer "B.SilkS")
		)
		(fp_line
			(start -0.7874 0.4064)
			(end 0.7874 0.4064)
			(stroke
				(width 0.1524)
				(type default)
			)
			(layer "B.SilkS")
		)
		(fp_line
			(start 0.67945 -0.305054)
			(end 0.12065 -0.305054)
			(stroke
				(width 0.1)
				(type default)
			)
			(layer "B.Fab")
		)
		(fp_line
			(start 0.12065 -0.305054)
			(end 0.12065 -0.2794)
			(stroke
				(width 0.1)
				(type default)
			)
			(layer "B.Fab")
		)
		(fp_line
			(start -0.12065 -0.3048)
			(end -0.67945 -0.3048)
			(stroke
				(width 0.1)
				(type default)
			)
			(layer "B.Fab")
		)
		(fp_line
			(start -0.67945 -0.3048)
			(end -0.67945 0.3048)
			(stroke
				(width 0.1)
				(type default)
			)
			(layer "B.Fab")
		)
		(fp_line
			(start 0.12065 -0.2794)
			(end -0.12065 -0.2794)
			(stroke
				(width 0.1)
				(type default)
			)
			(layer "B.Fab")
		)
		(fp_line
			(start -0.12065 -0.2794)
			(end -0.12065 -0.3048)
			(stroke
				(width 0.1)
				(type default)
			)
			(layer "B.Fab")
		)
		(fp_line
			(start 0.12065 0.2794)
			(end 0.12065 0.3048)
			(stroke
				(width 0.1)
				(type default)
			)
			(layer "B.Fab")
		)
		(fp_line
			(start -0.120396 0.2794)
			(end 0.12065 0.2794)
			(stroke
				(width 0.1)
				(type default)
			)
			(layer "B.Fab")
		)
		(fp_line
			(start 0.67945 0.3048)
			(end 0.67945 -0.305054)
			(stroke
				(width 0.1)
				(type default)
			)
			(layer "B.Fab")
		)
		(fp_line
			(start 0.12065 0.3048)
			(end 0.67945 0.3048)
			(stroke
				(width 0.1)
				(type default)
			)
			(layer "B.Fab")
		)
		(fp_line
			(start -0.120396 0.3048)
			(end -0.120396 0.2794)
			(stroke
				(width 0.1)
				(type default)
			)
			(layer "B.Fab")
		)
		(fp_line
			(start -0.67945 0.3048)
			(end -0.120396 0.3048)
			(stroke
				(width 0.1)
				(type default)
			)
			(layer "B.Fab")
		)
		(pad "1" smd circle
			(at 0.40005 0 270)
			(size 0 0)
			(layers "B.Cu" "B.Mask" "B.Paste")
			(net "FM_GPU_HSC_EN_BUF_R1")
		)
		(pad "2" smd circle
			(at -0.40005 0 270)
			(size 0 0)
			(layers "B.Cu" "B.Mask" "B.Paste")
			(net "GND")
		)
	)
	(footprint ""
		(layer "B.Cu")
		(at 163.387532 -434.15458 -90)
		(property "Reference" "R4121"
			(at 0 0 90)
			(layer "B.SilkS")
			(hide yes)
			(effects
				(font
					(size 1.27 1.27)
				)
				(justify mirror)
			)
		)
		(property "Value" ""
			(at 0 0 90)
			(layer "B.Fab")
			(effects
				(font
					(size 1.27 1.27)
				)
				(justify mirror)
			)
		)
		(duplicate_pad_numbers_are_jumpers no)
		(fp_line
			(start -0.7874 0.4064)
			(end 0.7874 0.4064)
			(stroke
				(width 0.1524)
				(type default)
			)
			(layer "B.SilkS")
		)
		(fp_line
			(start 0.7874 0.4064)
			(end 0.7874 -0.4064)
			(stroke
				(width 0.1524)
				(type default)
			)
			(layer "B.SilkS")
		)
		(fp_line
			(start -0.7874 -0.4064)
			(end -0.7874 0.4064)
			(stroke
				(width 0.1524)
				(type default)
			)
			(layer "B.SilkS")
		)
		(fp_line
			(start 0.7874 -0.4064)
			(end -0.7874 -0.4064)
			(stroke
				(width 0.1524)
				(type default)
			)
			(layer "B.SilkS")
		)
		(fp_line
			(start -0.67945 0.3048)
			(end -0.120396 0.3048)
			(stroke
				(width 0.1)
				(type default)
			)
			(layer "B.Fab")
		)
		(fp_line
			(start -0.120396 0.3048)
			(end -0.120396 0.2794)
			(stroke
				(width 0.1)
				(type default)
			)
			(layer "B.Fab")
		)
		(fp_line
			(start 0.12065 0.3048)
			(end 0.67945 0.3048)
			(stroke
				(width 0.1)
				(type default)
			)
			(layer "B.Fab")
		)
		(fp_line
			(start 0.67945 0.3048)
			(end 0.67945 -0.305054)
			(stroke
				(width 0.1)
				(type default)
			)
			(layer "B.Fab")
		)
		(fp_line
			(start -0.120396 0.2794)
			(end 0.12065 0.2794)
			(stroke
				(width 0.1)
				(type default)
			)
			(layer "B.Fab")
		)
		(fp_line
			(start 0.12065 0.2794)
			(end 0.12065 0.3048)
			(stroke
				(width 0.1)
				(type default)
			)
			(layer "B.Fab")
		)
		(fp_line
			(start -0.12065 -0.2794)
			(end -0.12065 -0.3048)
			(stroke
				(width 0.1)
				(type default)
			)
			(layer "B.Fab")
		)
		(fp_line
			(start 0.12065 -0.2794)
			(end -0.12065 -0.2794)
			(stroke
				(width 0.1)
				(type default)
			)
			(layer "B.Fab")
		)
		(fp_line
			(start -0.67945 -0.3048)
			(end -0.67945 0.3048)
			(stroke
				(width 0.1)
				(type default)
			)
			(layer "B.Fab")
		)
		(fp_line
			(start -0.12065 -0.3048)
			(end -0.67945 -0.3048)
			(stroke
				(width 0.1)
				(type default)
			)
			(layer "B.Fab")
		)
		(fp_line
			(start 0.12065 -0.305054)
			(end 0.12065 -0.2794)
			(stroke
				(width 0.1)
				(type default)
			)
			(layer "B.Fab")
		)
		(fp_line
			(start 0.67945 -0.305054)
			(end 0.12065 -0.305054)
			(stroke
				(width 0.1)
				(type default)
			)
			(layer "B.Fab")
		)
		(pad "1" smd circle
			(at 0.40005 0 90)
			(size 0 0)
			(layers "B.Cu" "B.Mask" "B.Paste")
			(net "P3V3_AUX")
		)
		(pad "2" smd circle
			(at -0.40005 0 90)
			(size 0 0)
			(layers "B.Cu" "B.Mask" "B.Paste")
			(net "PRSNT_CABLE_GPU_B3_N")
		)
	)
	(footprint ""
		(layer "B.Cu")
		(at 430.80051 -195.85051 180)
		(property "Reference" "R1683"
			(at 0 0 0)
			(layer "B.SilkS")
			(hide yes)
			(effects
				(font
					(size 1.27 1.27)
				)
				(justify mirror)
			)
		)
		(property "Value" ""
			(at 0 0 0)
			(layer "B.Fab")
			(effects
				(font
					(size 1.27 1.27)
				)
				(justify mirror)
			)
		)
		(duplicate_pad_numbers_are_jumpers no)
		(fp_line
			(start 0.7874 0.4064)
			(end 0.7874 -0.4064)
			(stroke
				(width 0.1524)
				(type default)
			)
			(layer "B.SilkS")
		)
		(fp_line
			(start 0.7874 -0.4064)
			(end -0.7874 -0.4064)
			(stroke
				(width 0.1524)
				(type default)
			)
			(layer "B.SilkS")
		)
		(fp_line
			(start -0.7874 0.4064)
			(end 0.7874 0.4064)
			(stroke
				(width 0.1524)
				(type default)
			)
			(layer "B.SilkS")
		)
		(fp_line
			(start -0.7874 -0.4064)
			(end -0.7874 0.4064)
			(stroke
				(width 0.1524)
				(type default)
			)
			(layer "B.SilkS")
		)
		(fp_line
			(start 0.67945 0.3048)
			(end 0.67945 -0.305054)
			(stroke
				(width 0.1)
				(type default)
			)
			(layer "B.Fab")
		)
		(fp_line
			(start 0.67945 -0.305054)
			(end 0.12065 -0.305054)
			(stroke
				(width 0.1)
				(type default)
			)
			(layer "B.Fab")
		)
		(fp_line
			(start 0.12065 0.3048)
			(end 0.67945 0.3048)
			(stroke
				(width 0.1)
				(type default)
			)
			(layer "B.Fab")
		)
		(fp_line
			(start 0.12065 0.2794)
			(end 0.12065 0.3048)
			(stroke
				(width 0.1)
				(type default)
			)
			(layer "B.Fab")
		)
		(fp_line
			(start 0.12065 -0.2794)
			(end -0.12065 -0.2794)
			(stroke
				(width 0.1)
				(type default)
			)
			(layer "B.Fab")
		)
		(fp_line
			(start 0.12065 -0.305054)
			(end 0.12065 -0.2794)
			(stroke
				(width 0.1)
				(type default)
			)
			(layer "B.Fab")
		)
		(fp_line
			(start -0.120396 0.3048)
			(end -0.120396 0.2794)
			(stroke
				(width 0.1)
				(type default)
			)
			(layer "B.Fab")
		)
		(fp_line
			(start -0.120396 0.2794)
			(end 0.12065 0.2794)
			(stroke
				(width 0.1)
				(type default)
			)
			(layer "B.Fab")
		)
		(fp_line
			(start -0.12065 -0.2794)
			(end -0.12065 -0.3048)
			(stroke
				(width 0.1)
				(type default)
			)
			(layer "B.Fab")
		)
		(fp_line
			(start -0.12065 -0.3048)
			(end -0.67945 -0.3048)
			(stroke
				(width 0.1)
				(type default)
			)
			(layer "B.Fab")
		)
		(fp_line
			(start -0.67945 0.3048)
			(end -0.120396 0.3048)
			(stroke
				(width 0.1)
				(type default)
			)
			(layer "B.Fab")
		)
		(fp_line
			(start -0.67945 -0.3048)
			(end -0.67945 0.3048)
			(stroke
				(width 0.1)
				(type default)
			)
			(layer "B.Fab")
		)
		(pad "1" smd circle
			(at 0.40005 0)
			(size 0 0)
			(layers "B.Cu" "B.Mask" "B.Paste")
			(net "I3C_SPD_DDRGL_CPU0_SDA")
		)
		(pad "2" smd circle
			(at -0.40005 0)
			(size 0 0)
			(layers "B.Cu" "B.Mask" "B.Paste")
			(net "I3C_SPD_DDRI_CPU0_SDA")
		)
	)
	(footprint ""
		(layer "B.Cu")
		(at 58.1914 -390.560052 90)
		(property "Reference" "C244"
			(at 0 0 90)
			(layer "B.SilkS")
			(hide yes)
			(effects
				(font
					(size 1.27 1.27)
				)
				(justify mirror)
			)
		)
		(property "Value" ""
			(at 0 0 90)
			(layer "B.Fab")
			(effects
				(font
					(size 1.27 1.27)
				)
				(justify mirror)
			)
		)
		(duplicate_pad_numbers_are_jumpers no)
		(fp_line
			(start 0.7874 -0.4064)
			(end -0.7874 -0.4064)
			(stroke
				(width 0.1524)
				(type default)
			)
			(layer "B.SilkS")
		)
		(fp_line
			(start -0.7874 -0.4064)
			(end -0.7874 0.4064)
			(stroke
				(width 0.1524)
				(type default)
			)
			(layer "B.SilkS")
		)
		(fp_line
			(start 0.7874 0.4064)
			(end 0.7874 -0.4064)
			(stroke
				(width 0.1524)
				(type default)
			)
			(layer "B.SilkS")
		)
		(fp_line
			(start -0.7874 0.4064)
			(end 0.7874 0.4064)
			(stroke
				(width 0.1524)
				(type default)
			)
			(layer "B.SilkS")
		)
		(fp_line
			(start 0.67945 -0.305054)
			(end 0.12065 -0.305054)
			(stroke
				(width 0.1)
				(type default)
			)
			(layer "B.Fab")
		)
		(fp_line
			(start 0.12065 -0.305054)
			(end 0.12065 -0.2794)
			(stroke
				(width 0.1)
				(type default)
			)
			(layer "B.Fab")
		)
		(fp_line
			(start -0.12065 -0.3048)
			(end -0.67945 -0.3048)
			(stroke
				(width 0.1)
				(type default)
			)
			(layer "B.Fab")
		)
		(fp_line
			(start -0.67945 -0.3048)
			(end -0.67945 0.3048)
			(stroke
				(width 0.1)
				(type default)
			)
			(layer "B.Fab")
		)
		(fp_line
			(start 0.12065 -0.2794)
			(end -0.12065 -0.2794)
			(stroke
				(width 0.1)
				(type default)
			)
			(layer "B.Fab")
		)
		(fp_line
			(start -0.12065 -0.2794)
			(end -0.12065 -0.3048)
			(stroke
				(width 0.1)
				(type default)
			)
			(layer "B.Fab")
		)
		(fp_line
			(start 0.12065 0.2794)
			(end 0.12065 0.3048)
			(stroke
				(width 0.1)
				(type default)
			)
			(layer "B.Fab")
		)
		(fp_line
			(start -0.120396 0.2794)
			(end 0.12065 0.2794)
			(stroke
				(width 0.1)
				(type default)
			)
			(layer "B.Fab")
		)
		(fp_line
			(start 0.67945 0.3048)
			(end 0.67945 -0.305054)
			(stroke
				(width 0.1)
				(type default)
			)
			(layer "B.Fab")
		)
		(fp_line
			(start 0.12065 0.3048)
			(end 0.67945 0.3048)
			(stroke
				(width 0.1)
				(type default)
			)
			(layer "B.Fab")
		)
		(fp_line
			(start -0.120396 0.3048)
			(end -0.120396 0.2794)
			(stroke
				(width 0.1)
				(type default)
			)
			(layer "B.Fab")
		)
		(fp_line
			(start -0.67945 0.3048)
			(end -0.120396 0.3048)
			(stroke
				(width 0.1)
				(type default)
			)
			(layer "B.Fab")
		)
		(pad "1" smd circle
			(at 0.40005 0 270)
			(size 0 0)
			(layers "B.Cu" "B.Mask" "B.Paste")
			(net "P0V9_CPU1_RT_2D")
		)
		(pad "2" smd circle
			(at -0.40005 0 270)
			(size 0 0)
			(layers "B.Cu" "B.Mask" "B.Paste")
			(net "GND")
		)
	)
	(footprint ""
		(layer "B.Cu")
		(at 164.325554 -348.180406)
		(property "Reference" "PR415"
			(at 0 0 0)
			(layer "B.SilkS")
			(hide yes)
			(effects
				(font
					(size 1.27 1.27)
				)
				(justify mirror)
			)
		)
		(property "Value" ""
			(at 0 0 0)
			(layer "B.Fab")
			(effects
				(font
					(size 1.27 1.27)
				)
				(justify mirror)
			)
		)
		(duplicate_pad_numbers_are_jumpers no)
		(fp_line
			(start -0.7874 -0.4064)
			(end -0.7874 0.4064)
			(stroke
				(width 0.1524)
				(type default)
			)
			(layer "B.SilkS")
		)
		(fp_line
			(start -0.7874 0.4064)
			(end 0.7874 0.4064)
			(stroke
				(width 0.1524)
				(type default)
			)
			(layer "B.SilkS")
		)
		(fp_line
			(start 0.7874 -0.4064)
			(end -0.7874 -0.4064)
			(stroke
				(width 0.1524)
				(type default)
			)
			(layer "B.SilkS")
		)
		(fp_line
			(start 0.7874 0.4064)
			(end 0.7874 -0.4064)
			(stroke
				(width 0.1524)
				(type default)
			)
			(layer "B.SilkS")
		)
		(fp_line
			(start -0.67945 -0.3048)
			(end -0.67945 0.3048)
			(stroke
				(width 0.1)
				(type default)
			)
			(layer "B.Fab")
		)
		(fp_line
			(start -0.67945 0.3048)
			(end -0.120396 0.3048)
			(stroke
				(width 0.1)
				(type default)
			)
			(layer "B.Fab")
		)
		(fp_line
			(start -0.12065 -0.3048)
			(end -0.67945 -0.3048)
			(stroke
				(width 0.1)
				(type default)
			)
			(layer "B.Fab")
		)
		(fp_line
			(start -0.12065 -0.2794)
			(end -0.12065 -0.3048)
			(stroke
				(width 0.1)
				(type default)
			)
			(layer "B.Fab")
		)
		(fp_line
			(start -0.120396 0.2794)
			(end 0.12065 0.2794)
			(stroke
				(width 0.1)
				(type default)
			)
			(layer "B.Fab")
		)
		(fp_line
			(start -0.120396 0.3048)
			(end -0.120396 0.2794)
			(stroke
				(width 0.1)
				(type default)
			)
			(layer "B.Fab")
		)
		(fp_line
			(start 0.12065 -0.305054)
			(end 0.12065 -0.2794)
			(stroke
				(width 0.1)
				(type default)
			)
			(layer "B.Fab")
		)
		(fp_line
			(start 0.12065 -0.2794)
			(end -0.12065 -0.2794)
			(stroke
				(width 0.1)
				(type default)
			)
			(layer "B.Fab")
		)
		(fp_line
			(start 0.12065 0.2794)
			(end 0.12065 0.3048)
			(stroke
				(width 0.1)
				(type default)
			)
			(layer "B.Fab")
		)
		(fp_line
			(start 0.12065 0.3048)
			(end 0.67945 0.3048)
			(stroke
				(width 0.1)
				(type default)
			)
			(layer "B.Fab")
		)
		(fp_line
			(start 0.67945 -0.305054)
			(end 0.12065 -0.305054)
			(stroke
				(width 0.1)
				(type default)
			)
			(layer "B.Fab")
		)
		(fp_line
			(start 0.67945 0.3048)
			(end 0.67945 -0.305054)
			(stroke
				(width 0.1)
				(type default)
			)
			(layer "B.Fab")
		)
		(pad "1" smd circle
			(at 0.40005 0 180)
			(size 0 0)
			(layers "B.Cu" "B.Mask" "B.Paste")
			(net "PVDD11_S3_P1_TEMP1")
		)
		(pad "2" smd circle
			(at -0.40005 0 180)
			(size 0 0)
			(layers "B.Cu" "B.Mask" "B.Paste")
			(net "GND")
		)
	)
	(footprint ""
		(layer "B.Cu")
		(at 117.102128 -28.457906 180)
		(property "Reference" "C6119"
			(at 0 0 0)
			(layer "B.SilkS")
			(hide yes)
			(effects
				(font
					(size 1.27 1.27)
				)
				(justify mirror)
			)
		)
		(property "Value" ""
			(at 0 0 0)
			(layer "B.Fab")
			(effects
				(font
					(size 1.27 1.27)
				)
				(justify mirror)
			)
		)
		(duplicate_pad_numbers_are_jumpers no)
		(fp_line
			(start 0.7874 0.4064)
			(end 0.7874 -0.4064)
			(stroke
				(width 0.1524)
				(type default)
			)
			(layer "B.SilkS")
		)
		(fp_line
			(start 0.7874 -0.4064)
			(end -0.7874 -0.4064)
			(stroke
				(width 0.1524)
				(type default)
			)
			(layer "B.SilkS")
		)
		(fp_line
			(start -0.7874 0.4064)
			(end 0.7874 0.4064)
			(stroke
				(width 0.1524)
				(type default)
			)
			(layer "B.SilkS")
		)
		(fp_line
			(start -0.7874 -0.4064)
			(end -0.7874 0.4064)
			(stroke
				(width 0.1524)
				(type default)
			)
			(layer "B.SilkS")
		)
		(fp_line
			(start 0.67945 0.3048)
			(end 0.67945 -0.305054)
			(stroke
				(width 0.1)
				(type default)
			)
			(layer "B.Fab")
		)
		(fp_line
			(start 0.67945 -0.305054)
			(end 0.12065 -0.305054)
			(stroke
				(width 0.1)
				(type default)
			)
			(layer "B.Fab")
		)
		(fp_line
			(start 0.12065 0.3048)
			(end 0.67945 0.3048)
			(stroke
				(width 0.1)
				(type default)
			)
			(layer "B.Fab")
		)
		(fp_line
			(start 0.12065 0.2794)
			(end 0.12065 0.3048)
			(stroke
				(width 0.1)
				(type default)
			)
			(layer "B.Fab")
		)
		(fp_line
			(start 0.12065 -0.2794)
			(end -0.12065 -0.2794)
			(stroke
				(width 0.1)
				(type default)
			)
			(layer "B.Fab")
		)
		(fp_line
			(start 0.12065 -0.305054)
			(end 0.12065 -0.2794)
			(stroke
				(width 0.1)
				(type default)
			)
			(layer "B.Fab")
		)
		(fp_line
			(start -0.120396 0.3048)
			(end -0.120396 0.2794)
			(stroke
				(width 0.1)
				(type default)
			)
			(layer "B.Fab")
		)
		(fp_line
			(start -0.120396 0.2794)
			(end 0.12065 0.2794)
			(stroke
				(width 0.1)
				(type default)
			)
			(layer "B.Fab")
		)
		(fp_line
			(start -0.12065 -0.2794)
			(end -0.12065 -0.3048)
			(stroke
				(width 0.1)
				(type default)
			)
			(layer "B.Fab")
		)
		(fp_line
			(start -0.12065 -0.3048)
			(end -0.67945 -0.3048)
			(stroke
				(width 0.1)
				(type default)
			)
			(layer "B.Fab")
		)
		(fp_line
			(start -0.67945 0.3048)
			(end -0.120396 0.3048)
			(stroke
				(width 0.1)
				(type default)
			)
			(layer "B.Fab")
		)
		(fp_line
			(start -0.67945 -0.3048)
			(end -0.67945 0.3048)
			(stroke
				(width 0.1)
				(type default)
			)
			(layer "B.Fab")
		)
		(pad "1" smd circle
			(at 0.40005 0)
			(size 0 0)
			(layers "B.Cu" "B.Mask" "B.Paste")
			(net "P1V2_CPU0_USB2_DVDD12")
		)
		(pad "2" smd circle
			(at -0.40005 0)
			(size 0 0)
			(layers "B.Cu" "B.Mask" "B.Paste")
			(net "GND")
		)
	)
	(footprint ""
		(layer "B.Cu")
		(at 114.478562 -386.766562 90)
		(property "Reference" "C455"
			(at 0 0 90)
			(layer "B.SilkS")
			(hide yes)
			(effects
				(font
					(size 1.27 1.27)
				)
				(justify mirror)
			)
		)
		(property "Value" ""
			(at 0 0 90)
			(layer "B.Fab")
			(effects
				(font
					(size 1.27 1.27)
				)
				(justify mirror)
			)
		)
		(duplicate_pad_numbers_are_jumpers no)
		(fp_line
			(start 0.299974 -0.150114)
			(end -0.299974 -0.150114)
			(stroke
				(width 0.1)
				(type default)
			)
			(layer "B.Fab")
		)
		(fp_line
			(start -0.299974 -0.150114)
			(end -0.299974 0.150114)
			(stroke
				(width 0.1)
				(type default)
			)
			(layer "B.Fab")
		)
		(fp_line
			(start 0.299974 0.150114)
			(end 0.299974 -0.150114)
			(stroke
				(width 0.1)
				(type default)
			)
			(layer "B.Fab")
		)
		(fp_line
			(start -0.299974 0.150114)
			(end 0.299974 0.150114)
			(stroke
				(width 0.1)
				(type default)
			)
			(layer "B.Fab")
		)
		(pad "1" smd rect
			(at 0.2667 0 270)
			(size 0.3048 0.381)
			(layers "B.Cu" "B.Mask" "B.Paste")
			(net "P0V9_CPU1_RT3_2A")
		)
		(pad "2" smd rect
			(at -0.2667 0 270)
			(size 0.3048 0.381)
			(layers "B.Cu" "B.Mask" "B.Paste")
			(net "GND")
		)
	)
	(footprint ""
		(layer "B.Cu")
		(at 58.65241 -149.721824 180)
		(property "Reference" "PC84"
			(at 0 0 0)
			(layer "B.SilkS")
			(hide yes)
			(effects
				(font
					(size 1.27 1.27)
				)
				(justify mirror)
			)
		)
		(property "Value" ""
			(at 0 0 0)
			(layer "B.Fab")
			(effects
				(font
					(size 1.27 1.27)
				)
				(justify mirror)
			)
		)
		(duplicate_pad_numbers_are_jumpers no)
		(fp_line
			(start 1.524 0.762)
			(end 1.524 -0.762)
			(stroke
				(width 0.1524)
				(type default)
			)
			(layer "B.SilkS")
		)
		(fp_line
			(start 1.524 -0.762)
			(end -1.524 -0.762)
			(stroke
				(width 0.1524)
				(type default)
			)
			(layer "B.SilkS")
		)
		(fp_line
			(start -1.524 0.762)
			(end 1.524 0.762)
			(stroke
				(width 0.1524)
				(type default)
			)
			(layer "B.SilkS")
		)
		(fp_line
			(start -1.524 -0.762)
			(end -1.524 0.762)
			(stroke
				(width 0.1524)
				(type default)
			)
			(layer "B.SilkS")
		)
		(fp_line
			(start 1.1049 0.724916)
			(end -1.1049 0.724916)
			(stroke
				(width 0.1)
				(type default)
			)
			(layer "B.Fab")
		)
		(fp_line
			(start 1.1049 -0.724916)
			(end 1.1049 0.724916)
			(stroke
				(width 0.1)
				(type default)
			)
			(layer "B.Fab")
		)
		(fp_line
			(start -1.1049 0.724916)
			(end -1.1049 -0.724916)
			(stroke
				(width 0.1)
				(type default)
			)
			(layer "B.Fab")
		)
		(fp_line
			(start -1.1049 -0.724916)
			(end 1.1049 -0.724916)
			(stroke
				(width 0.1)
				(type default)
			)
			(layer "B.Fab")
		)
		(pad "1" smd rect
			(at 0.889 0 180)
			(size 1.016 1.27)
			(layers "B.Cu" "B.Mask" "B.Paste")
			(net "PVDD18_S5_P1")
		)
		(pad "2" smd rect
			(at -0.889 0 180)
			(size 1.016 1.27)
			(layers "B.Cu" "B.Mask" "B.Paste")
			(net "GND")
		)
	)
	(footprint ""
		(layer "B.Cu")
		(at 445.887602 -418.58311 90)
		(property "Reference" "PR6612"
			(at 0 0 90)
			(layer "B.SilkS")
			(hide yes)
			(effects
				(font
					(size 1.27 1.27)
				)
				(justify mirror)
			)
		)
		(property "Value" ""
			(at 0 0 90)
			(layer "B.Fab")
			(effects
				(font
					(size 1.27 1.27)
				)
				(justify mirror)
			)
		)
		(duplicate_pad_numbers_are_jumpers no)
		(fp_line
			(start 0.7874 -0.4064)
			(end -0.7874 -0.4064)
			(stroke
				(width 0.1524)
				(type default)
			)
			(layer "B.SilkS")
		)
		(fp_line
			(start -0.7874 -0.4064)
			(end -0.7874 0.4064)
			(stroke
				(width 0.1524)
				(type default)
			)
			(layer "B.SilkS")
		)
		(fp_line
			(start 0.7874 0.4064)
			(end 0.7874 -0.4064)
			(stroke
				(width 0.1524)
				(type default)
			)
			(layer "B.SilkS")
		)
		(fp_line
			(start -0.7874 0.4064)
			(end 0.7874 0.4064)
			(stroke
				(width 0.1524)
				(type default)
			)
			(layer "B.SilkS")
		)
		(fp_line
			(start 0.67945 -0.305054)
			(end 0.12065 -0.305054)
			(stroke
				(width 0.1)
				(type default)
			)
			(layer "B.Fab")
		)
		(fp_line
			(start 0.12065 -0.305054)
			(end 0.12065 -0.2794)
			(stroke
				(width 0.1)
				(type default)
			)
			(layer "B.Fab")
		)
		(fp_line
			(start -0.12065 -0.3048)
			(end -0.67945 -0.3048)
			(stroke
				(width 0.1)
				(type default)
			)
			(layer "B.Fab")
		)
		(fp_line
			(start -0.67945 -0.3048)
			(end -0.67945 0.3048)
			(stroke
				(width 0.1)
				(type default)
			)
			(layer "B.Fab")
		)
		(fp_line
			(start 0.12065 -0.2794)
			(end -0.12065 -0.2794)
			(stroke
				(width 0.1)
				(type default)
			)
			(layer "B.Fab")
		)
		(fp_line
			(start -0.12065 -0.2794)
			(end -0.12065 -0.3048)
			(stroke
				(width 0.1)
				(type default)
			)
			(layer "B.Fab")
		)
		(fp_line
			(start 0.12065 0.2794)
			(end 0.12065 0.3048)
			(stroke
				(width 0.1)
				(type default)
			)
			(layer "B.Fab")
		)
		(fp_line
			(start -0.120396 0.2794)
			(end 0.12065 0.2794)
			(stroke
				(width 0.1)
				(type default)
			)
			(layer "B.Fab")
		)
		(fp_line
			(start 0.67945 0.3048)
			(end 0.67945 -0.305054)
			(stroke
				(width 0.1)
				(type default)
			)
			(layer "B.Fab")
		)
		(fp_line
			(start 0.12065 0.3048)
			(end 0.67945 0.3048)
			(stroke
				(width 0.1)
				(type default)
			)
			(layer "B.Fab")
		)
		(fp_line
			(start -0.120396 0.3048)
			(end -0.120396 0.2794)
			(stroke
				(width 0.1)
				(type default)
			)
			(layer "B.Fab")
		)
		(fp_line
			(start -0.67945 0.3048)
			(end -0.120396 0.3048)
			(stroke
				(width 0.1)
				(type default)
			)
			(layer "B.Fab")
		)
		(pad "1" smd circle
			(at 0.40005 0 270)
			(size 0 0)
			(layers "B.Cu" "B.Mask" "B.Paste")
			(net "NC_P0V9_RETIMER_CPU0_IMON6")
		)
		(pad "2" smd circle
			(at -0.40005 0 270)
			(size 0 0)
			(layers "B.Cu" "B.Mask" "B.Paste")
			(net "GND")
		)
	)
	(footprint ""
		(layer "B.Cu")
		(at 163.387532 -430.59858 90)
		(property "Reference" "R4124"
			(at 0 0 90)
			(layer "B.SilkS")
			(hide yes)
			(effects
				(font
					(size 1.27 1.27)
				)
				(justify mirror)
			)
		)
		(property "Value" ""
			(at 0 0 90)
			(layer "B.Fab")
			(effects
				(font
					(size 1.27 1.27)
				)
				(justify mirror)
			)
		)
		(duplicate_pad_numbers_are_jumpers no)
		(fp_line
			(start 0.7874 -0.4064)
			(end -0.7874 -0.4064)
			(stroke
				(width 0.1524)
				(type default)
			)
			(layer "B.SilkS")
		)
		(fp_line
			(start -0.7874 -0.4064)
			(end -0.7874 0.4064)
			(stroke
				(width 0.1524)
				(type default)
			)
			(layer "B.SilkS")
		)
		(fp_line
			(start 0.7874 0.4064)
			(end 0.7874 -0.4064)
			(stroke
				(width 0.1524)
				(type default)
			)
			(layer "B.SilkS")
		)
		(fp_line
			(start -0.7874 0.4064)
			(end 0.7874 0.4064)
			(stroke
				(width 0.1524)
				(type default)
			)
			(layer "B.SilkS")
		)
		(fp_line
			(start 0.67945 -0.305054)
			(end 0.12065 -0.305054)
			(stroke
				(width 0.1)
				(type default)
			)
			(layer "B.Fab")
		)
		(fp_line
			(start 0.12065 -0.305054)
			(end 0.12065 -0.2794)
			(stroke
				(width 0.1)
				(type default)
			)
			(layer "B.Fab")
		)
		(fp_line
			(start -0.12065 -0.3048)
			(end -0.67945 -0.3048)
			(stroke
				(width 0.1)
				(type default)
			)
			(layer "B.Fab")
		)
		(fp_line
			(start -0.67945 -0.3048)
			(end -0.67945 0.3048)
			(stroke
				(width 0.1)
				(type default)
			)
			(layer "B.Fab")
		)
		(fp_line
			(start 0.12065 -0.2794)
			(end -0.12065 -0.2794)
			(stroke
				(width 0.1)
				(type default)
			)
			(layer "B.Fab")
		)
		(fp_line
			(start -0.12065 -0.2794)
			(end -0.12065 -0.3048)
			(stroke
				(width 0.1)
				(type default)
			)
			(layer "B.Fab")
		)
		(fp_line
			(start 0.12065 0.2794)
			(end 0.12065 0.3048)
			(stroke
				(width 0.1)
				(type default)
			)
			(layer "B.Fab")
		)
		(fp_line
			(start -0.120396 0.2794)
			(end 0.12065 0.2794)
			(stroke
				(width 0.1)
				(type default)
			)
			(layer "B.Fab")
		)
		(fp_line
			(start 0.67945 0.3048)
			(end 0.67945 -0.305054)
			(stroke
				(width 0.1)
				(type default)
			)
			(layer "B.Fab")
		)
		(fp_line
			(start 0.12065 0.3048)
			(end 0.67945 0.3048)
			(stroke
				(width 0.1)
				(type default)
			)
			(layer "B.Fab")
		)
		(fp_line
			(start -0.120396 0.3048)
			(end -0.120396 0.2794)
			(stroke
				(width 0.1)
				(type default)
			)
			(layer "B.Fab")
		)
		(fp_line
			(start -0.67945 0.3048)
			(end -0.120396 0.3048)
			(stroke
				(width 0.1)
				(type default)
			)
			(layer "B.Fab")
		)
		(pad "1" smd circle
			(at 0.40005 0 270)
			(size 0 0)
			(layers "B.Cu" "B.Mask" "B.Paste")
			(net "GPU_3V3IO_RSVD1_FFU")
		)
		(pad "2" smd circle
			(at -0.40005 0 270)
			(size 0 0)
			(layers "B.Cu" "B.Mask" "B.Paste")
			(net "GND")
		)
	)
	(footprint ""
		(layer "B.Cu")
		(at 383.224278 -137.535158 90)
		(property "Reference" "PC12"
			(at 0 0 90)
			(layer "B.SilkS")
			(hide yes)
			(effects
				(font
					(size 1.27 1.27)
				)
				(justify mirror)
			)
		)
		(property "Value" ""
			(at 0 0 90)
			(layer "B.Fab")
			(effects
				(font
					(size 1.27 1.27)
				)
				(justify mirror)
			)
		)
		(duplicate_pad_numbers_are_jumpers no)
		(fp_line
			(start 0.7874 -0.4064)
			(end -0.7874 -0.4064)
			(stroke
				(width 0.1524)
				(type default)
			)
			(layer "B.SilkS")
		)
		(fp_line
			(start -0.7874 -0.4064)
			(end -0.7874 0.4064)
			(stroke
				(width 0.1524)
				(type default)
			)
			(layer "B.SilkS")
		)
		(fp_line
			(start 0.7874 0.4064)
			(end 0.7874 -0.4064)
			(stroke
				(width 0.1524)
				(type default)
			)
			(layer "B.SilkS")
		)
		(fp_line
			(start -0.7874 0.4064)
			(end 0.7874 0.4064)
			(stroke
				(width 0.1524)
				(type default)
			)
			(layer "B.SilkS")
		)
		(fp_line
			(start 0.67945 -0.305054)
			(end 0.12065 -0.305054)
			(stroke
				(width 0.1)
				(type default)
			)
			(layer "B.Fab")
		)
		(fp_line
			(start 0.12065 -0.305054)
			(end 0.12065 -0.2794)
			(stroke
				(width 0.1)
				(type default)
			)
			(layer "B.Fab")
		)
		(fp_line
			(start -0.12065 -0.3048)
			(end -0.67945 -0.3048)
			(stroke
				(width 0.1)
				(type default)
			)
			(layer "B.Fab")
		)
		(fp_line
			(start -0.67945 -0.3048)
			(end -0.67945 0.3048)
			(stroke
				(width 0.1)
				(type default)
			)
			(layer "B.Fab")
		)
		(fp_line
			(start 0.12065 -0.2794)
			(end -0.12065 -0.2794)
			(stroke
				(width 0.1)
				(type default)
			)
			(layer "B.Fab")
		)
		(fp_line
			(start -0.12065 -0.2794)
			(end -0.12065 -0.3048)
			(stroke
				(width 0.1)
				(type default)
			)
			(layer "B.Fab")
		)
		(fp_line
			(start 0.12065 0.2794)
			(end 0.12065 0.3048)
			(stroke
				(width 0.1)
				(type default)
			)
			(layer "B.Fab")
		)
		(fp_line
			(start -0.120396 0.2794)
			(end 0.12065 0.2794)
			(stroke
				(width 0.1)
				(type default)
			)
			(layer "B.Fab")
		)
		(fp_line
			(start 0.67945 0.3048)
			(end 0.67945 -0.305054)
			(stroke
				(width 0.1)
				(type default)
			)
			(layer "B.Fab")
		)
		(fp_line
			(start 0.12065 0.3048)
			(end 0.67945 0.3048)
			(stroke
				(width 0.1)
				(type default)
			)
			(layer "B.Fab")
		)
		(fp_line
			(start -0.120396 0.3048)
			(end -0.120396 0.2794)
			(stroke
				(width 0.1)
				(type default)
			)
			(layer "B.Fab")
		)
		(fp_line
			(start -0.67945 0.3048)
			(end -0.120396 0.3048)
			(stroke
				(width 0.1)
				(type default)
			)
			(layer "B.Fab")
		)
		(pad "1" smd circle
			(at 0.40005 0 270)
			(size 0 0)
			(layers "B.Cu" "B.Mask" "B.Paste")
			(net "PVDDCR_CPU0_P0_VCC")
		)
		(pad "2" smd circle
			(at -0.40005 0 270)
			(size 0 0)
			(layers "B.Cu" "B.Mask" "B.Paste")
			(net "GND")
		)
	)
	(footprint ""
		(layer "B.Cu")
		(at 171.196 -116.296948)
		(property "Reference" "R889"
			(at 0 0 0)
			(layer "B.SilkS")
			(hide yes)
			(effects
				(font
					(size 1.27 1.27)
				)
				(justify mirror)
			)
		)
		(property "Value" ""
			(at 0 0 0)
			(layer "B.Fab")
			(effects
				(font
					(size 1.27 1.27)
				)
				(justify mirror)
			)
		)
		(duplicate_pad_numbers_are_jumpers no)
		(fp_line
			(start -0.7874 -0.4064)
			(end -0.7874 0.4064)
			(stroke
				(width 0.1524)
				(type default)
			)
			(layer "B.SilkS")
		)
		(fp_line
			(start -0.7874 0.4064)
			(end 0.7874 0.4064)
			(stroke
				(width 0.1524)
				(type default)
			)
			(layer "B.SilkS")
		)
		(fp_line
			(start 0.7874 -0.4064)
			(end -0.7874 -0.4064)
			(stroke
				(width 0.1524)
				(type default)
			)
			(layer "B.SilkS")
		)
		(fp_line
			(start 0.7874 0.4064)
			(end 0.7874 -0.4064)
			(stroke
				(width 0.1524)
				(type default)
			)
			(layer "B.SilkS")
		)
		(fp_line
			(start -0.67945 -0.3048)
			(end -0.67945 0.3048)
			(stroke
				(width 0.1)
				(type default)
			)
			(layer "B.Fab")
		)
		(fp_line
			(start -0.67945 0.3048)
			(end -0.120396 0.3048)
			(stroke
				(width 0.1)
				(type default)
			)
			(layer "B.Fab")
		)
		(fp_line
			(start -0.12065 -0.3048)
			(end -0.67945 -0.3048)
			(stroke
				(width 0.1)
				(type default)
			)
			(layer "B.Fab")
		)
		(fp_line
			(start -0.12065 -0.2794)
			(end -0.12065 -0.3048)
			(stroke
				(width 0.1)
				(type default)
			)
			(layer "B.Fab")
		)
		(fp_line
			(start -0.120396 0.2794)
			(end 0.12065 0.2794)
			(stroke
				(width 0.1)
				(type default)
			)
			(layer "B.Fab")
		)
		(fp_line
			(start -0.120396 0.3048)
			(end -0.120396 0.2794)
			(stroke
				(width 0.1)
				(type default)
			)
			(layer "B.Fab")
		)
		(fp_line
			(start 0.12065 -0.305054)
			(end 0.12065 -0.2794)
			(stroke
				(width 0.1)
				(type default)
			)
			(layer "B.Fab")
		)
		(fp_line
			(start 0.12065 -0.2794)
			(end -0.12065 -0.2794)
			(stroke
				(width 0.1)
				(type default)
			)
			(layer "B.Fab")
		)
		(fp_line
			(start 0.12065 0.2794)
			(end 0.12065 0.3048)
			(stroke
				(width 0.1)
				(type default)
			)
			(layer "B.Fab")
		)
		(fp_line
			(start 0.12065 0.3048)
			(end 0.67945 0.3048)
			(stroke
				(width 0.1)
				(type default)
			)
			(layer "B.Fab")
		)
		(fp_line
			(start 0.67945 -0.305054)
			(end 0.12065 -0.305054)
			(stroke
				(width 0.1)
				(type default)
			)
			(layer "B.Fab")
		)
		(fp_line
			(start 0.67945 0.3048)
			(end 0.67945 -0.305054)
			(stroke
				(width 0.1)
				(type default)
			)
			(layer "B.Fab")
		)
		(pad "1" smd circle
			(at 0.40005 0 180)
			(size 0 0)
			(layers "B.Cu" "B.Mask" "B.Paste")
			(net "SCM_SPARE_0")
		)
		(pad "2" smd circle
			(at -0.40005 0 180)
			(size 0 0)
			(layers "B.Cu" "B.Mask" "B.Paste")
			(net "GND")
		)
	)
	(footprint ""
		(layer "B.Cu")
		(at 360.579924 -395.127988 -90)
		(property "Reference" "C591"
			(at 0 0 90)
			(layer "B.SilkS")
			(hide yes)
			(effects
				(font
					(size 1.27 1.27)
				)
				(justify mirror)
			)
		)
		(property "Value" ""
			(at 0 0 90)
			(layer "B.Fab")
			(effects
				(font
					(size 1.27 1.27)
				)
				(justify mirror)
			)
		)
		(duplicate_pad_numbers_are_jumpers no)
		(fp_line
			(start -0.7874 0.4064)
			(end 0.7874 0.4064)
			(stroke
				(width 0.1524)
				(type default)
			)
			(layer "B.SilkS")
		)
		(fp_line
			(start 0.7874 0.4064)
			(end 0.7874 -0.4064)
			(stroke
				(width 0.1524)
				(type default)
			)
			(layer "B.SilkS")
		)
		(fp_line
			(start -0.7874 -0.4064)
			(end -0.7874 0.4064)
			(stroke
				(width 0.1524)
				(type default)
			)
			(layer "B.SilkS")
		)
		(fp_line
			(start 0.7874 -0.4064)
			(end -0.7874 -0.4064)
			(stroke
				(width 0.1524)
				(type default)
			)
			(layer "B.SilkS")
		)
		(fp_line
			(start -0.67945 0.3048)
			(end -0.120396 0.3048)
			(stroke
				(width 0.1)
				(type default)
			)
			(layer "B.Fab")
		)
		(fp_line
			(start -0.120396 0.3048)
			(end -0.120396 0.2794)
			(stroke
				(width 0.1)
				(type default)
			)
			(layer "B.Fab")
		)
		(fp_line
			(start 0.12065 0.3048)
			(end 0.67945 0.3048)
			(stroke
				(width 0.1)
				(type default)
			)
			(layer "B.Fab")
		)
		(fp_line
			(start 0.67945 0.3048)
			(end 0.67945 -0.305054)
			(stroke
				(width 0.1)
				(type default)
			)
			(layer "B.Fab")
		)
		(fp_line
			(start -0.120396 0.2794)
			(end 0.12065 0.2794)
			(stroke
				(width 0.1)
				(type default)
			)
			(layer "B.Fab")
		)
		(fp_line
			(start 0.12065 0.2794)
			(end 0.12065 0.3048)
			(stroke
				(width 0.1)
				(type default)
			)
			(layer "B.Fab")
		)
		(fp_line
			(start -0.12065 -0.2794)
			(end -0.12065 -0.3048)
			(stroke
				(width 0.1)
				(type default)
			)
			(layer "B.Fab")
		)
		(fp_line
			(start 0.12065 -0.2794)
			(end -0.12065 -0.2794)
			(stroke
				(width 0.1)
				(type default)
			)
			(layer "B.Fab")
		)
		(fp_line
			(start -0.67945 -0.3048)
			(end -0.67945 0.3048)
			(stroke
				(width 0.1)
				(type default)
			)
			(layer "B.Fab")
		)
		(fp_line
			(start -0.12065 -0.3048)
			(end -0.67945 -0.3048)
			(stroke
				(width 0.1)
				(type default)
			)
			(layer "B.Fab")
		)
		(fp_line
			(start 0.12065 -0.305054)
			(end 0.12065 -0.2794)
			(stroke
				(width 0.1)
				(type default)
			)
			(layer "B.Fab")
		)
		(fp_line
			(start 0.67945 -0.305054)
			(end 0.12065 -0.305054)
			(stroke
				(width 0.1)
				(type default)
			)
			(layer "B.Fab")
		)
		(pad "1" smd circle
			(at 0.40005 0 90)
			(size 0 0)
			(layers "B.Cu" "B.Mask" "B.Paste")
			(net "P1V8_CPU0_RT_1D")
		)
		(pad "2" smd circle
			(at -0.40005 0 90)
			(size 0 0)
			(layers "B.Cu" "B.Mask" "B.Paste")
			(net "GND")
		)
	)
	(footprint ""
		(layer "B.Cu")
		(at 195.199 -137.632948 -90)
		(property "Reference" "R1616"
			(at 0 0 90)
			(layer "B.SilkS")
			(hide yes)
			(effects
				(font
					(size 1.27 1.27)
				)
				(justify mirror)
			)
		)
		(property "Value" ""
			(at 0 0 90)
			(layer "B.Fab")
			(effects
				(font
					(size 1.27 1.27)
				)
				(justify mirror)
			)
		)
		(duplicate_pad_numbers_are_jumpers no)
		(fp_line
			(start -0.7874 0.4064)
			(end 0.7874 0.4064)
			(stroke
				(width 0.1524)
				(type default)
			)
			(layer "B.SilkS")
		)
		(fp_line
			(start 0.7874 0.4064)
			(end 0.7874 -0.4064)
			(stroke
				(width 0.1524)
				(type default)
			)
			(layer "B.SilkS")
		)
		(fp_line
			(start -0.7874 -0.4064)
			(end -0.7874 0.4064)
			(stroke
				(width 0.1524)
				(type default)
			)
			(layer "B.SilkS")
		)
		(fp_line
			(start 0.7874 -0.4064)
			(end -0.7874 -0.4064)
			(stroke
				(width 0.1524)
				(type default)
			)
			(layer "B.SilkS")
		)
		(fp_line
			(start -0.67945 0.3048)
			(end -0.120396 0.3048)
			(stroke
				(width 0.1)
				(type default)
			)
			(layer "B.Fab")
		)
		(fp_line
			(start -0.120396 0.3048)
			(end -0.120396 0.2794)
			(stroke
				(width 0.1)
				(type default)
			)
			(layer "B.Fab")
		)
		(fp_line
			(start 0.12065 0.3048)
			(end 0.67945 0.3048)
			(stroke
				(width 0.1)
				(type default)
			)
			(layer "B.Fab")
		)
		(fp_line
			(start 0.67945 0.3048)
			(end 0.67945 -0.305054)
			(stroke
				(width 0.1)
				(type default)
			)
			(layer "B.Fab")
		)
		(fp_line
			(start -0.120396 0.2794)
			(end 0.12065 0.2794)
			(stroke
				(width 0.1)
				(type default)
			)
			(layer "B.Fab")
		)
		(fp_line
			(start 0.12065 0.2794)
			(end 0.12065 0.3048)
			(stroke
				(width 0.1)
				(type default)
			)
			(layer "B.Fab")
		)
		(fp_line
			(start -0.12065 -0.2794)
			(end -0.12065 -0.3048)
			(stroke
				(width 0.1)
				(type default)
			)
			(layer "B.Fab")
		)
		(fp_line
			(start 0.12065 -0.2794)
			(end -0.12065 -0.2794)
			(stroke
				(width 0.1)
				(type default)
			)
			(layer "B.Fab")
		)
		(fp_line
			(start -0.67945 -0.3048)
			(end -0.67945 0.3048)
			(stroke
				(width 0.1)
				(type default)
			)
			(layer "B.Fab")
		)
		(fp_line
			(start -0.12065 -0.3048)
			(end -0.67945 -0.3048)
			(stroke
				(width 0.1)
				(type default)
			)
			(layer "B.Fab")
		)
		(fp_line
			(start 0.12065 -0.305054)
			(end 0.12065 -0.2794)
			(stroke
				(width 0.1)
				(type default)
			)
			(layer "B.Fab")
		)
		(fp_line
			(start 0.67945 -0.305054)
			(end 0.12065 -0.305054)
			(stroke
				(width 0.1)
				(type default)
			)
			(layer "B.Fab")
		)
		(pad "1" smd circle
			(at 0.40005 0 90)
			(size 0 0)
			(layers "B.Cu" "B.Mask" "B.Paste")
			(net "FM_ROM_SD_LS_OE")
		)
		(pad "2" smd circle
			(at -0.40005 0 90)
			(size 0 0)
			(layers "B.Cu" "B.Mask" "B.Paste")
			(net "ROM_SD_LS_OE")
		)
	)
	(footprint ""
		(layer "B.Cu")
		(at 280.636218 -192.660016 180)
		(property "Reference" "C149"
			(at 0 0 0)
			(layer "B.SilkS")
			(hide yes)
			(effects
				(font
					(size 1.27 1.27)
				)
				(justify mirror)
			)
		)
		(property "Value" ""
			(at 0 0 0)
			(layer "B.Fab")
			(effects
				(font
					(size 1.27 1.27)
				)
				(justify mirror)
			)
		)
		(duplicate_pad_numbers_are_jumpers no)
		(fp_line
			(start 1.524 0.762)
			(end 1.524 -0.762)
			(stroke
				(width 0.1524)
				(type default)
			)
			(layer "B.SilkS")
		)
		(fp_line
			(start 1.524 -0.762)
			(end -1.524 -0.762)
			(stroke
				(width 0.1524)
				(type default)
			)
			(layer "B.SilkS")
		)
		(fp_line
			(start -1.524 0.762)
			(end 1.524 0.762)
			(stroke
				(width 0.1524)
				(type default)
			)
			(layer "B.SilkS")
		)
		(fp_line
			(start -1.524 -0.762)
			(end -1.524 0.762)
			(stroke
				(width 0.1524)
				(type default)
			)
			(layer "B.SilkS")
		)
		(fp_line
			(start 1.1049 0.724916)
			(end -1.1049 0.724916)
			(stroke
				(width 0.1)
				(type default)
			)
			(layer "B.Fab")
		)
		(fp_line
			(start 1.1049 -0.724916)
			(end 1.1049 0.724916)
			(stroke
				(width 0.1)
				(type default)
			)
			(layer "B.Fab")
		)
		(fp_line
			(start -1.1049 0.724916)
			(end -1.1049 -0.724916)
			(stroke
				(width 0.1)
				(type default)
			)
			(layer "B.Fab")
		)
		(fp_line
			(start -1.1049 -0.724916)
			(end 1.1049 -0.724916)
			(stroke
				(width 0.1)
				(type default)
			)
			(layer "B.Fab")
		)
		(pad "1" smd rect
			(at 0.889 0 180)
			(size 1.016 1.27)
			(layers "B.Cu" "B.Mask" "B.Paste")
			(net "P12V_MEM_CPU0")
		)
		(pad "2" smd rect
			(at -0.889 0 180)
			(size 1.016 1.27)
			(layers "B.Cu" "B.Mask" "B.Paste")
			(net "GND")
		)
	)
	(footprint ""
		(layer "B.Cu")
		(at 313.118246 -396.393162 -90)
		(property "Reference" "C519"
			(at 0 0 90)
			(layer "B.SilkS")
			(hide yes)
			(effects
				(font
					(size 1.27 1.27)
				)
				(justify mirror)
			)
		)
		(property "Value" ""
			(at 0 0 90)
			(layer "B.Fab")
			(effects
				(font
					(size 1.27 1.27)
				)
				(justify mirror)
			)
		)
		(duplicate_pad_numbers_are_jumpers no)
		(fp_line
			(start -0.299974 0.150114)
			(end 0.299974 0.150114)
			(stroke
				(width 0.1)
				(type default)
			)
			(layer "B.Fab")
		)
		(fp_line
			(start 0.299974 0.150114)
			(end 0.299974 -0.150114)
			(stroke
				(width 0.1)
				(type default)
			)
			(layer "B.Fab")
		)
		(fp_line
			(start -0.299974 -0.150114)
			(end -0.299974 0.150114)
			(stroke
				(width 0.1)
				(type default)
			)
			(layer "B.Fab")
		)
		(fp_line
			(start 0.299974 -0.150114)
			(end -0.299974 -0.150114)
			(stroke
				(width 0.1)
				(type default)
			)
			(layer "B.Fab")
		)
		(pad "1" smd rect
			(at 0.2667 0 90)
			(size 0.3048 0.381)
			(layers "B.Cu" "B.Mask" "B.Paste")
			(net "P1V8_CPU0_RT0_1A")
		)
		(pad "2" smd rect
			(at -0.2667 0 90)
			(size 0.3048 0.381)
			(layers "B.Cu" "B.Mask" "B.Paste")
			(net "GND")
		)
	)
	(footprint ""
		(layer "B.Cu")
		(at 319.467484 -338.934806 -90)
		(property "Reference" "PC126_3"
			(at 0 0 90)
			(layer "B.SilkS")
			(hide yes)
			(effects
				(font
					(size 1.27 1.27)
				)
				(justify mirror)
			)
		)
		(property "Value" ""
			(at 0 0 90)
			(layer "B.Fab")
			(effects
				(font
					(size 1.27 1.27)
				)
				(justify mirror)
			)
		)
		(duplicate_pad_numbers_are_jumpers no)
		(fp_line
			(start -1.524 0.762)
			(end 1.524 0.762)
			(stroke
				(width 0.1524)
				(type default)
			)
			(layer "B.SilkS")
		)
		(fp_line
			(start 1.524 0.762)
			(end 1.524 -0.762)
			(stroke
				(width 0.1524)
				(type default)
			)
			(layer "B.SilkS")
		)
		(fp_line
			(start -1.524 -0.762)
			(end -1.524 0.762)
			(stroke
				(width 0.1524)
				(type default)
			)
			(layer "B.SilkS")
		)
		(fp_line
			(start 1.524 -0.762)
			(end -1.524 -0.762)
			(stroke
				(width 0.1524)
				(type default)
			)
			(layer "B.SilkS")
		)
		(fp_line
			(start -1.1049 0.724916)
			(end -1.1049 -0.724916)
			(stroke
				(width 0.1)
				(type default)
			)
			(layer "B.Fab")
		)
		(fp_line
			(start 1.1049 0.724916)
			(end -1.1049 0.724916)
			(stroke
				(width 0.1)
				(type default)
			)
			(layer "B.Fab")
		)
		(fp_line
			(start -1.1049 -0.724916)
			(end 1.1049 -0.724916)
			(stroke
				(width 0.1)
				(type default)
			)
			(layer "B.Fab")
		)
		(fp_line
			(start 1.1049 -0.724916)
			(end 1.1049 0.724916)
			(stroke
				(width 0.1)
				(type default)
			)
			(layer "B.Fab")
		)
		(pad "1" smd rect
			(at 0.889 0 270)
			(size 1.016 1.27)
			(layers "B.Cu" "B.Mask" "B.Paste")
			(net "SW_P12V_AUX_PVDDCR_CPU1_P0_FLT")
		)
		(pad "2" smd rect
			(at -0.889 0 270)
			(size 1.016 1.27)
			(layers "B.Cu" "B.Mask" "B.Paste")
			(net "GND")
		)
	)
	(footprint ""
		(layer "B.Cu")
		(at 110.808008 -171.775374 -90)
		(property "Reference" "PC334_1"
			(at 0 0 90)
			(layer "B.SilkS")
			(hide yes)
			(effects
				(font
					(size 1.27 1.27)
				)
				(justify mirror)
			)
		)
		(property "Value" ""
			(at 0 0 90)
			(layer "B.Fab")
			(effects
				(font
					(size 1.27 1.27)
				)
				(justify mirror)
			)
		)
		(duplicate_pad_numbers_are_jumpers no)
		(fp_line
			(start -1.524 0.762)
			(end 1.524 0.762)
			(stroke
				(width 0.1524)
				(type default)
			)
			(layer "B.SilkS")
		)
		(fp_line
			(start 1.524 0.762)
			(end 1.524 -0.762)
			(stroke
				(width 0.1524)
				(type default)
			)
			(layer "B.SilkS")
		)
		(fp_line
			(start -1.524 -0.762)
			(end -1.524 0.762)
			(stroke
				(width 0.1524)
				(type default)
			)
			(layer "B.SilkS")
		)
		(fp_line
			(start 1.524 -0.762)
			(end -1.524 -0.762)
			(stroke
				(width 0.1524)
				(type default)
			)
			(layer "B.SilkS")
		)
		(fp_line
			(start -1.1049 0.724916)
			(end -1.1049 -0.724916)
			(stroke
				(width 0.1)
				(type default)
			)
			(layer "B.Fab")
		)
		(fp_line
			(start 1.1049 0.724916)
			(end -1.1049 0.724916)
			(stroke
				(width 0.1)
				(type default)
			)
			(layer "B.Fab")
		)
		(fp_line
			(start -1.1049 -0.724916)
			(end 1.1049 -0.724916)
			(stroke
				(width 0.1)
				(type default)
			)
			(layer "B.Fab")
		)
		(fp_line
			(start 1.1049 -0.724916)
			(end 1.1049 0.724916)
			(stroke
				(width 0.1)
				(type default)
			)
			(layer "B.Fab")
		)
		(pad "1" smd rect
			(at 0.889 0 270)
			(size 1.016 1.27)
			(layers "B.Cu" "B.Mask" "B.Paste")
			(net "SW_P12V_AUX_PVDDCR_SOC_P1_FLT")
		)
		(pad "2" smd rect
			(at -0.889 0 270)
			(size 1.016 1.27)
			(layers "B.Cu" "B.Mask" "B.Paste")
			(net "GND")
		)
	)
	(footprint ""
		(layer "B.Cu")
		(at 231.0511 -327.21169)
		(property "Reference" "R1255"
			(at 0 0 0)
			(layer "B.SilkS")
			(hide yes)
			(effects
				(font
					(size 1.27 1.27)
				)
				(justify mirror)
			)
		)
		(property "Value" ""
			(at 0 0 0)
			(layer "B.Fab")
			(effects
				(font
					(size 1.27 1.27)
				)
				(justify mirror)
			)
		)
		(duplicate_pad_numbers_are_jumpers no)
		(fp_line
			(start -0.7874 -0.4064)
			(end -0.7874 0.4064)
			(stroke
				(width 0.1524)
				(type default)
			)
			(layer "B.SilkS")
		)
		(fp_line
			(start -0.7874 0.4064)
			(end 0.7874 0.4064)
			(stroke
				(width 0.1524)
				(type default)
			)
			(layer "B.SilkS")
		)
		(fp_line
			(start 0.7874 -0.4064)
			(end -0.7874 -0.4064)
			(stroke
				(width 0.1524)
				(type default)
			)
			(layer "B.SilkS")
		)
		(fp_line
			(start 0.7874 0.4064)
			(end 0.7874 -0.4064)
			(stroke
				(width 0.1524)
				(type default)
			)
			(layer "B.SilkS")
		)
		(fp_line
			(start -0.67945 -0.3048)
			(end -0.67945 0.3048)
			(stroke
				(width 0.1)
				(type default)
			)
			(layer "B.Fab")
		)
		(fp_line
			(start -0.67945 0.3048)
			(end -0.120396 0.3048)
			(stroke
				(width 0.1)
				(type default)
			)
			(layer "B.Fab")
		)
		(fp_line
			(start -0.12065 -0.3048)
			(end -0.67945 -0.3048)
			(stroke
				(width 0.1)
				(type default)
			)
			(layer "B.Fab")
		)
		(fp_line
			(start -0.12065 -0.2794)
			(end -0.12065 -0.3048)
			(stroke
				(width 0.1)
				(type default)
			)
			(layer "B.Fab")
		)
		(fp_line
			(start -0.120396 0.2794)
			(end 0.12065 0.2794)
			(stroke
				(width 0.1)
				(type default)
			)
			(layer "B.Fab")
		)
		(fp_line
			(start -0.120396 0.3048)
			(end -0.120396 0.2794)
			(stroke
				(width 0.1)
				(type default)
			)
			(layer "B.Fab")
		)
		(fp_line
			(start 0.12065 -0.305054)
			(end 0.12065 -0.2794)
			(stroke
				(width 0.1)
				(type default)
			)
			(layer "B.Fab")
		)
		(fp_line
			(start 0.12065 -0.2794)
			(end -0.12065 -0.2794)
			(stroke
				(width 0.1)
				(type default)
			)
			(layer "B.Fab")
		)
		(fp_line
			(start 0.12065 0.2794)
			(end 0.12065 0.3048)
			(stroke
				(width 0.1)
				(type default)
			)
			(layer "B.Fab")
		)
		(fp_line
			(start 0.12065 0.3048)
			(end 0.67945 0.3048)
			(stroke
				(width 0.1)
				(type default)
			)
			(layer "B.Fab")
		)
		(fp_line
			(start 0.67945 -0.305054)
			(end 0.12065 -0.305054)
			(stroke
				(width 0.1)
				(type default)
			)
			(layer "B.Fab")
		)
		(fp_line
			(start 0.67945 0.3048)
			(end 0.67945 -0.305054)
			(stroke
				(width 0.1)
				(type default)
			)
			(layer "B.Fab")
		)
		(pad "1" smd rect
			(at 0.40005 0)
			(size 0.4572 0.508)
			(layers "B.Cu" "B.Mask" "B.Paste")
			(net "PVDD_33_S5_ADC")
		)
		(pad "2" smd rect
			(at -0.40005 0)
			(size 0.4572 0.508)
			(layers "B.Cu" "B.Mask" "B.Paste")
			(net "PVDD_33_S5_ADC_TIC")
		)
	)
	(footprint ""
		(layer "B.Cu")
		(at 413.946086 -396.393162 -90)
		(property "Reference" "C775"
			(at 0 0 90)
			(layer "B.SilkS")
			(hide yes)
			(effects
				(font
					(size 1.27 1.27)
				)
				(justify mirror)
			)
		)
		(property "Value" ""
			(at 0 0 90)
			(layer "B.Fab")
			(effects
				(font
					(size 1.27 1.27)
				)
				(justify mirror)
			)
		)
		(duplicate_pad_numbers_are_jumpers no)
		(fp_line
			(start -0.299974 0.150114)
			(end 0.299974 0.150114)
			(stroke
				(width 0.1)
				(type default)
			)
			(layer "B.Fab")
		)
		(fp_line
			(start 0.299974 0.150114)
			(end 0.299974 -0.150114)
			(stroke
				(width 0.1)
				(type default)
			)
			(layer "B.Fab")
		)
		(fp_line
			(start -0.299974 -0.150114)
			(end -0.299974 0.150114)
			(stroke
				(width 0.1)
				(type default)
			)
			(layer "B.Fab")
		)
		(fp_line
			(start 0.299974 -0.150114)
			(end -0.299974 -0.150114)
			(stroke
				(width 0.1)
				(type default)
			)
			(layer "B.Fab")
		)
		(pad "1" smd rect
			(at 0.2667 0 90)
			(size 0.3048 0.381)
			(layers "B.Cu" "B.Mask" "B.Paste")
			(net "P1V8_CPU0_RT2_1A_1D")
		)
		(pad "2" smd rect
			(at -0.2667 0 90)
			(size 0.3048 0.381)
			(layers "B.Cu" "B.Mask" "B.Paste")
			(net "GND")
		)
	)
	(footprint ""
		(layer "B.Cu")
		(at 157.806136 -386.766562 90)
		(property "Reference" "C375"
			(at 0 0 90)
			(layer "B.SilkS")
			(hide yes)
			(effects
				(font
					(size 1.27 1.27)
				)
				(justify mirror)
			)
		)
		(property "Value" ""
			(at 0 0 90)
			(layer "B.Fab")
			(effects
				(font
					(size 1.27 1.27)
				)
				(justify mirror)
			)
		)
		(duplicate_pad_numbers_are_jumpers no)
		(fp_line
			(start 0.299974 -0.150114)
			(end -0.299974 -0.150114)
			(stroke
				(width 0.1)
				(type default)
			)
			(layer "B.Fab")
		)
		(fp_line
			(start -0.299974 -0.150114)
			(end -0.299974 0.150114)
			(stroke
				(width 0.1)
				(type default)
			)
			(layer "B.Fab")
		)
		(fp_line
			(start 0.299974 0.150114)
			(end 0.299974 -0.150114)
			(stroke
				(width 0.1)
				(type default)
			)
			(layer "B.Fab")
		)
		(fp_line
			(start -0.299974 0.150114)
			(end 0.299974 0.150114)
			(stroke
				(width 0.1)
				(type default)
			)
			(layer "B.Fab")
		)
		(pad "1" smd rect
			(at 0.2667 0 270)
			(size 0.3048 0.381)
			(layers "B.Cu" "B.Mask" "B.Paste")
			(net "P1V8_CPU1_RT2_1A_1D")
		)
		(pad "2" smd rect
			(at -0.2667 0 270)
			(size 0.3048 0.381)
			(layers "B.Cu" "B.Mask" "B.Paste")
			(net "GND")
		)
	)
	(footprint ""
		(layer "B.Cu")
		(at 376.478546 -395.148562 90)
		(property "Reference" "C1007"
			(at 0 0 90)
			(layer "B.SilkS")
			(hide yes)
			(effects
				(font
					(size 1.27 1.27)
				)
				(justify mirror)
			)
		)
		(property "Value" ""
			(at 0 0 90)
			(layer "B.Fab")
			(effects
				(font
					(size 1.27 1.27)
				)
				(justify mirror)
			)
		)
		(duplicate_pad_numbers_are_jumpers no)
		(fp_line
			(start 0.299974 -0.150114)
			(end -0.299974 -0.150114)
			(stroke
				(width 0.1)
				(type default)
			)
			(layer "B.Fab")
		)
		(fp_line
			(start -0.299974 -0.150114)
			(end -0.299974 0.150114)
			(stroke
				(width 0.1)
				(type default)
			)
			(layer "B.Fab")
		)
		(fp_line
			(start 0.299974 0.150114)
			(end 0.299974 -0.150114)
			(stroke
				(width 0.1)
				(type default)
			)
			(layer "B.Fab")
		)
		(fp_line
			(start -0.299974 0.150114)
			(end 0.299974 0.150114)
			(stroke
				(width 0.1)
				(type default)
			)
			(layer "B.Fab")
		)
		(pad "1" smd rect
			(at 0.2667 0 270)
			(size 0.3048 0.381)
			(layers "B.Cu" "B.Mask" "B.Paste")
			(net "P0V9_CPU0_RT_2D")
		)
		(pad "2" smd rect
			(at -0.2667 0 270)
			(size 0.3048 0.381)
			(layers "B.Cu" "B.Mask" "B.Paste")
			(net "GND")
		)
	)
	(footprint ""
		(layer "B.Cu")
		(at 92.046298 -388.011162 -90)
		(property "Reference" "C311"
			(at 0 0 90)
			(layer "B.SilkS")
			(hide yes)
			(effects
				(font
					(size 1.27 1.27)
				)
				(justify mirror)
			)
		)
		(property "Value" ""
			(at 0 0 90)
			(layer "B.Fab")
			(effects
				(font
					(size 1.27 1.27)
				)
				(justify mirror)
			)
		)
		(duplicate_pad_numbers_are_jumpers no)
		(fp_line
			(start -0.299974 0.150114)
			(end 0.299974 0.150114)
			(stroke
				(width 0.1)
				(type default)
			)
			(layer "B.Fab")
		)
		(fp_line
			(start 0.299974 0.150114)
			(end 0.299974 -0.150114)
			(stroke
				(width 0.1)
				(type default)
			)
			(layer "B.Fab")
		)
		(fp_line
			(start -0.299974 -0.150114)
			(end -0.299974 0.150114)
			(stroke
				(width 0.1)
				(type default)
			)
			(layer "B.Fab")
		)
		(fp_line
			(start 0.299974 -0.150114)
			(end -0.299974 -0.150114)
			(stroke
				(width 0.1)
				(type default)
			)
			(layer "B.Fab")
		)
		(pad "1" smd rect
			(at 0.2667 0 90)
			(size 0.3048 0.381)
			(layers "B.Cu" "B.Mask" "B.Paste")
			(net "P0V9_CPU1_RT_2D")
		)
		(pad "2" smd rect
			(at -0.2667 0 90)
			(size 0.3048 0.381)
			(layers "B.Cu" "B.Mask" "B.Paste")
			(net "GND")
		)
	)
	(footprint ""
		(layer "B.Cu")
		(at 458.346302 -407.877264 180)
		(property "Reference" "PC6583"
			(at 0 0 0)
			(layer "B.SilkS")
			(hide yes)
			(effects
				(font
					(size 1.27 1.27)
				)
				(justify mirror)
			)
		)
		(property "Value" ""
			(at 0 0 0)
			(layer "B.Fab")
			(effects
				(font
					(size 1.27 1.27)
				)
				(justify mirror)
			)
		)
		(duplicate_pad_numbers_are_jumpers no)
		(fp_line
			(start 1.524 0.762)
			(end 1.524 -0.762)
			(stroke
				(width 0.1524)
				(type default)
			)
			(layer "B.SilkS")
		)
		(fp_line
			(start 1.524 -0.762)
			(end -1.524 -0.762)
			(stroke
				(width 0.1524)
				(type default)
			)
			(layer "B.SilkS")
		)
		(fp_line
			(start -1.524 0.762)
			(end 1.524 0.762)
			(stroke
				(width 0.1524)
				(type default)
			)
			(layer "B.SilkS")
		)
		(fp_line
			(start -1.524 -0.762)
			(end -1.524 0.762)
			(stroke
				(width 0.1524)
				(type default)
			)
			(layer "B.SilkS")
		)
		(fp_line
			(start 1.1049 0.724916)
			(end -1.1049 0.724916)
			(stroke
				(width 0.1)
				(type default)
			)
			(layer "B.Fab")
		)
		(fp_line
			(start 1.1049 -0.724916)
			(end 1.1049 0.724916)
			(stroke
				(width 0.1)
				(type default)
			)
			(layer "B.Fab")
		)
		(fp_line
			(start -1.1049 0.724916)
			(end -1.1049 -0.724916)
			(stroke
				(width 0.1)
				(type default)
			)
			(layer "B.Fab")
		)
		(fp_line
			(start -1.1049 -0.724916)
			(end 1.1049 -0.724916)
			(stroke
				(width 0.1)
				(type default)
			)
			(layer "B.Fab")
		)
		(pad "1" smd rect
			(at 0.889 0 180)
			(size 1.016 1.27)
			(layers "B.Cu" "B.Mask" "B.Paste")
			(net "SW_P12V_AUX_P0V9_RETIMER_CPU0_FLT")
		)
		(pad "2" smd rect
			(at -0.889 0 180)
			(size 1.016 1.27)
			(layers "B.Cu" "B.Mask" "B.Paste")
			(net "GND")
		)
	)
	(footprint ""
		(layer "B.Cu")
		(at 348.185486 -416.899344 90)
		(property "Reference" "C6562"
			(at 0 0 90)
			(layer "B.SilkS")
			(hide yes)
			(effects
				(font
					(size 1.27 1.27)
				)
				(justify mirror)
			)
		)
		(property "Value" ""
			(at 0 0 90)
			(layer "B.Fab")
			(effects
				(font
					(size 1.27 1.27)
				)
				(justify mirror)
			)
		)
		(duplicate_pad_numbers_are_jumpers no)
		(fp_line
			(start 0.299974 -0.150114)
			(end -0.299974 -0.150114)
			(stroke
				(width 0.1)
				(type default)
			)
			(layer "B.Fab")
		)
		(fp_line
			(start -0.299974 -0.150114)
			(end -0.299974 0.150114)
			(stroke
				(width 0.1)
				(type default)
			)
			(layer "B.Fab")
		)
		(fp_line
			(start 0.299974 0.150114)
			(end 0.299974 -0.150114)
			(stroke
				(width 0.1)
				(type default)
			)
			(layer "B.Fab")
		)
		(fp_line
			(start -0.299974 0.150114)
			(end 0.299974 0.150114)
			(stroke
				(width 0.1)
				(type default)
			)
			(layer "B.Fab")
		)
		(pad "1" smd rect
			(at 0.2667 0 270)
			(size 0.3048 0.381)
			(layers "B.Cu" "B.Mask" "B.Paste")
			(net "P5E_CPU0_P1_TX_BUF_C_DN<14>")
		)
		(pad "2" smd rect
			(at -0.2667 0 270)
			(size 0.3048 0.381)
			(layers "B.Cu" "B.Mask" "B.Paste")
			(net "P5E_CPU0_P1_TX_BUF_DN<14>")
		)
	)
	(footprint ""
		(layer "B.Cu")
		(at 400.761962 -313.782964 180)
		(property "Reference" "R433"
			(at 0 0 0)
			(layer "B.SilkS")
			(hide yes)
			(effects
				(font
					(size 1.27 1.27)
				)
				(justify mirror)
			)
		)
		(property "Value" ""
			(at 0 0 0)
			(layer "B.Fab")
			(effects
				(font
					(size 1.27 1.27)
				)
				(justify mirror)
			)
		)
		(duplicate_pad_numbers_are_jumpers no)
		(fp_line
			(start 0.7874 0.4064)
			(end 0.7874 -0.4064)
			(stroke
				(width 0.1524)
				(type default)
			)
			(layer "B.SilkS")
		)
		(fp_line
			(start 0.7874 -0.4064)
			(end -0.7874 -0.4064)
			(stroke
				(width 0.1524)
				(type default)
			)
			(layer "B.SilkS")
		)
		(fp_line
			(start -0.7874 0.4064)
			(end 0.7874 0.4064)
			(stroke
				(width 0.1524)
				(type default)
			)
			(layer "B.SilkS")
		)
		(fp_line
			(start -0.7874 -0.4064)
			(end -0.7874 0.4064)
			(stroke
				(width 0.1524)
				(type default)
			)
			(layer "B.SilkS")
		)
		(fp_line
			(start 0.67945 0.3048)
			(end 0.67945 -0.305054)
			(stroke
				(width 0.1)
				(type default)
			)
			(layer "B.Fab")
		)
		(fp_line
			(start 0.67945 -0.305054)
			(end 0.12065 -0.305054)
			(stroke
				(width 0.1)
				(type default)
			)
			(layer "B.Fab")
		)
		(fp_line
			(start 0.12065 0.3048)
			(end 0.67945 0.3048)
			(stroke
				(width 0.1)
				(type default)
			)
			(layer "B.Fab")
		)
		(fp_line
			(start 0.12065 0.2794)
			(end 0.12065 0.3048)
			(stroke
				(width 0.1)
				(type default)
			)
			(layer "B.Fab")
		)
		(fp_line
			(start 0.12065 -0.2794)
			(end -0.12065 -0.2794)
			(stroke
				(width 0.1)
				(type default)
			)
			(layer "B.Fab")
		)
		(fp_line
			(start 0.12065 -0.305054)
			(end 0.12065 -0.2794)
			(stroke
				(width 0.1)
				(type default)
			)
			(layer "B.Fab")
		)
		(fp_line
			(start -0.120396 0.3048)
			(end -0.120396 0.2794)
			(stroke
				(width 0.1)
				(type default)
			)
			(layer "B.Fab")
		)
		(fp_line
			(start -0.120396 0.2794)
			(end 0.12065 0.2794)
			(stroke
				(width 0.1)
				(type default)
			)
			(layer "B.Fab")
		)
		(fp_line
			(start -0.12065 -0.2794)
			(end -0.12065 -0.3048)
			(stroke
				(width 0.1)
				(type default)
			)
			(layer "B.Fab")
		)
		(fp_line
			(start -0.12065 -0.3048)
			(end -0.67945 -0.3048)
			(stroke
				(width 0.1)
				(type default)
			)
			(layer "B.Fab")
		)
		(fp_line
			(start -0.67945 0.3048)
			(end -0.120396 0.3048)
			(stroke
				(width 0.1)
				(type default)
			)
			(layer "B.Fab")
		)
		(fp_line
			(start -0.67945 -0.3048)
			(end -0.67945 0.3048)
			(stroke
				(width 0.1)
				(type default)
			)
			(layer "B.Fab")
		)
		(pad "1" smd circle
			(at 0.40005 0)
			(size 0 0)
			(layers "B.Cu" "B.Mask" "B.Paste")
			(net "XTAL_CPU0_X32K_X1")
		)
		(pad "2" smd circle
			(at -0.40005 0)
			(size 0 0)
			(layers "B.Cu" "B.Mask" "B.Paste")
			(net "XTAL_CPU0_X32K_X2")
		)
	)
	(footprint ""
		(layer "B.Cu")
		(at 32.552386 -190.948564 180)
		(property "Reference" "R306"
			(at 0 0 0)
			(layer "B.SilkS")
			(hide yes)
			(effects
				(font
					(size 1.27 1.27)
				)
				(justify mirror)
			)
		)
		(property "Value" ""
			(at 0 0 0)
			(layer "B.Fab")
			(effects
				(font
					(size 1.27 1.27)
				)
				(justify mirror)
			)
		)
		(duplicate_pad_numbers_are_jumpers no)
		(fp_line
			(start 0.7874 0.4064)
			(end 0.7874 -0.4064)
			(stroke
				(width 0.1524)
				(type default)
			)
			(layer "B.SilkS")
		)
		(fp_line
			(start 0.7874 -0.4064)
			(end -0.7874 -0.4064)
			(stroke
				(width 0.1524)
				(type default)
			)
			(layer "B.SilkS")
		)
		(fp_line
			(start -0.7874 0.4064)
			(end 0.7874 0.4064)
			(stroke
				(width 0.1524)
				(type default)
			)
			(layer "B.SilkS")
		)
		(fp_line
			(start -0.7874 -0.4064)
			(end -0.7874 0.4064)
			(stroke
				(width 0.1524)
				(type default)
			)
			(layer "B.SilkS")
		)
		(fp_line
			(start 0.67945 0.3048)
			(end 0.67945 -0.305054)
			(stroke
				(width 0.1)
				(type default)
			)
			(layer "B.Fab")
		)
		(fp_line
			(start 0.67945 -0.305054)
			(end 0.12065 -0.305054)
			(stroke
				(width 0.1)
				(type default)
			)
			(layer "B.Fab")
		)
		(fp_line
			(start 0.12065 0.3048)
			(end 0.67945 0.3048)
			(stroke
				(width 0.1)
				(type default)
			)
			(layer "B.Fab")
		)
		(fp_line
			(start 0.12065 0.2794)
			(end 0.12065 0.3048)
			(stroke
				(width 0.1)
				(type default)
			)
			(layer "B.Fab")
		)
		(fp_line
			(start 0.12065 -0.2794)
			(end -0.12065 -0.2794)
			(stroke
				(width 0.1)
				(type default)
			)
			(layer "B.Fab")
		)
		(fp_line
			(start 0.12065 -0.305054)
			(end 0.12065 -0.2794)
			(stroke
				(width 0.1)
				(type default)
			)
			(layer "B.Fab")
		)
		(fp_line
			(start -0.120396 0.3048)
			(end -0.120396 0.2794)
			(stroke
				(width 0.1)
				(type default)
			)
			(layer "B.Fab")
		)
		(fp_line
			(start -0.120396 0.2794)
			(end 0.12065 0.2794)
			(stroke
				(width 0.1)
				(type default)
			)
			(layer "B.Fab")
		)
		(fp_line
			(start -0.12065 -0.2794)
			(end -0.12065 -0.3048)
			(stroke
				(width 0.1)
				(type default)
			)
			(layer "B.Fab")
		)
		(fp_line
			(start -0.12065 -0.3048)
			(end -0.67945 -0.3048)
			(stroke
				(width 0.1)
				(type default)
			)
			(layer "B.Fab")
		)
		(fp_line
			(start -0.67945 0.3048)
			(end -0.120396 0.3048)
			(stroke
				(width 0.1)
				(type default)
			)
			(layer "B.Fab")
		)
		(fp_line
			(start -0.67945 -0.3048)
			(end -0.67945 0.3048)
			(stroke
				(width 0.1)
				(type default)
			)
			(layer "B.Fab")
		)
		(pad "1" smd circle
			(at 0.40005 0)
			(size 0 0)
			(layers "B.Cu" "B.Mask" "B.Paste")
			(net "PWRGD_CHD_CPU1_DIMM")
		)
		(pad "2" smd circle
			(at -0.40005 0)
			(size 0 0)
			(layers "B.Cu" "B.Mask" "B.Paste")
			(net "PWRGD_CHAF_CPU1")
		)
	)
	(footprint ""
		(layer "B.Cu")
		(at 72.689974 -173.870112 90)
		(property "Reference" "PC313_5"
			(at 0 0 90)
			(layer "B.SilkS")
			(hide yes)
			(effects
				(font
					(size 1.27 1.27)
				)
				(justify mirror)
			)
		)
		(property "Value" ""
			(at 0 0 90)
			(layer "B.Fab")
			(effects
				(font
					(size 1.27 1.27)
				)
				(justify mirror)
			)
		)
		(duplicate_pad_numbers_are_jumpers no)
		(fp_line
			(start 1.524 -0.762)
			(end -1.524 -0.762)
			(stroke
				(width 0.1524)
				(type default)
			)
			(layer "B.SilkS")
		)
		(fp_line
			(start -1.524 -0.762)
			(end -1.524 0.762)
			(stroke
				(width 0.1524)
				(type default)
			)
			(layer "B.SilkS")
		)
		(fp_line
			(start 1.524 0.762)
			(end 1.524 -0.762)
			(stroke
				(width 0.1524)
				(type default)
			)
			(layer "B.SilkS")
		)
		(fp_line
			(start -1.524 0.762)
			(end 1.524 0.762)
			(stroke
				(width 0.1524)
				(type default)
			)
			(layer "B.SilkS")
		)
		(fp_line
			(start 1.1049 -0.724916)
			(end 1.1049 0.724916)
			(stroke
				(width 0.1)
				(type default)
			)
			(layer "B.Fab")
		)
		(fp_line
			(start -1.1049 -0.724916)
			(end 1.1049 -0.724916)
			(stroke
				(width 0.1)
				(type default)
			)
			(layer "B.Fab")
		)
		(fp_line
			(start 1.1049 0.724916)
			(end -1.1049 0.724916)
			(stroke
				(width 0.1)
				(type default)
			)
			(layer "B.Fab")
		)
		(fp_line
			(start -1.1049 0.724916)
			(end -1.1049 -0.724916)
			(stroke
				(width 0.1)
				(type default)
			)
			(layer "B.Fab")
		)
		(pad "1" smd rect
			(at 0.889 0 90)
			(size 1.016 1.27)
			(layers "B.Cu" "B.Mask" "B.Paste")
			(net "SW_P12V_AUX_PVDDCR_CPU0_P1_FLT")
		)
		(pad "2" smd rect
			(at -0.889 0 90)
			(size 1.016 1.27)
			(layers "B.Cu" "B.Mask" "B.Paste")
			(net "GND")
		)
	)
	(footprint ""
		(layer "B.Cu")
		(at 180.281834 -421.37711 90)
		(property "Reference" "C9003"
			(at 0 0 90)
			(layer "B.SilkS")
			(hide yes)
			(effects
				(font
					(size 1.27 1.27)
				)
				(justify mirror)
			)
		)
		(property "Value" ""
			(at 0 0 90)
			(layer "B.Fab")
			(effects
				(font
					(size 1.27 1.27)
				)
				(justify mirror)
			)
		)
		(duplicate_pad_numbers_are_jumpers no)
		(fp_line
			(start 0.7874 -0.4064)
			(end -0.7874 -0.4064)
			(stroke
				(width 0.1524)
				(type default)
			)
			(layer "B.SilkS")
		)
		(fp_line
			(start -0.7874 -0.4064)
			(end -0.7874 0.4064)
			(stroke
				(width 0.1524)
				(type default)
			)
			(layer "B.SilkS")
		)
		(fp_line
			(start 0.7874 0.4064)
			(end 0.7874 -0.4064)
			(stroke
				(width 0.1524)
				(type default)
			)
			(layer "B.SilkS")
		)
		(fp_line
			(start -0.7874 0.4064)
			(end 0.7874 0.4064)
			(stroke
				(width 0.1524)
				(type default)
			)
			(layer "B.SilkS")
		)
		(fp_line
			(start 0.67945 -0.305054)
			(end 0.12065 -0.305054)
			(stroke
				(width 0.1)
				(type default)
			)
			(layer "B.Fab")
		)
		(fp_line
			(start 0.12065 -0.305054)
			(end 0.12065 -0.2794)
			(stroke
				(width 0.1)
				(type default)
			)
			(layer "B.Fab")
		)
		(fp_line
			(start -0.12065 -0.3048)
			(end -0.67945 -0.3048)
			(stroke
				(width 0.1)
				(type default)
			)
			(layer "B.Fab")
		)
		(fp_line
			(start -0.67945 -0.3048)
			(end -0.67945 0.3048)
			(stroke
				(width 0.1)
				(type default)
			)
			(layer "B.Fab")
		)
		(fp_line
			(start 0.12065 -0.2794)
			(end -0.12065 -0.2794)
			(stroke
				(width 0.1)
				(type default)
			)
			(layer "B.Fab")
		)
		(fp_line
			(start -0.12065 -0.2794)
			(end -0.12065 -0.3048)
			(stroke
				(width 0.1)
				(type default)
			)
			(layer "B.Fab")
		)
		(fp_line
			(start 0.12065 0.2794)
			(end 0.12065 0.3048)
			(stroke
				(width 0.1)
				(type default)
			)
			(layer "B.Fab")
		)
		(fp_line
			(start -0.120396 0.2794)
			(end 0.12065 0.2794)
			(stroke
				(width 0.1)
				(type default)
			)
			(layer "B.Fab")
		)
		(fp_line
			(start 0.67945 0.3048)
			(end 0.67945 -0.305054)
			(stroke
				(width 0.1)
				(type default)
			)
			(layer "B.Fab")
		)
		(fp_line
			(start 0.12065 0.3048)
			(end 0.67945 0.3048)
			(stroke
				(width 0.1)
				(type default)
			)
			(layer "B.Fab")
		)
		(fp_line
			(start -0.120396 0.3048)
			(end -0.120396 0.2794)
			(stroke
				(width 0.1)
				(type default)
			)
			(layer "B.Fab")
		)
		(fp_line
			(start -0.67945 0.3048)
			(end -0.120396 0.3048)
			(stroke
				(width 0.1)
				(type default)
			)
			(layer "B.Fab")
		)
		(pad "1" smd circle
			(at 0.40005 0 270)
			(size 0 0)
			(layers "B.Cu" "B.Mask" "B.Paste")
			(net "U142_VS")
		)
		(pad "2" smd circle
			(at -0.40005 0 270)
			(size 0 0)
			(layers "B.Cu" "B.Mask" "B.Paste")
			(net "GND")
		)
	)
	(footprint ""
		(layer "B.Cu")
		(at 392.961622 -398.455134 180)
		(property "Reference" "C1022"
			(at 0 0 0)
			(layer "B.SilkS")
			(hide yes)
			(effects
				(font
					(size 1.27 1.27)
				)
				(justify mirror)
			)
		)
		(property "Value" ""
			(at 0 0 0)
			(layer "B.Fab")
			(effects
				(font
					(size 1.27 1.27)
				)
				(justify mirror)
			)
		)
		(duplicate_pad_numbers_are_jumpers no)
		(fp_line
			(start 1.524 0.762)
			(end 1.524 -0.762)
			(stroke
				(width 0.1524)
				(type default)
			)
			(layer "B.SilkS")
		)
		(fp_line
			(start 1.524 -0.762)
			(end -1.524 -0.762)
			(stroke
				(width 0.1524)
				(type default)
			)
			(layer "B.SilkS")
		)
		(fp_line
			(start -1.524 0.762)
			(end 1.524 0.762)
			(stroke
				(width 0.1524)
				(type default)
			)
			(layer "B.SilkS")
		)
		(fp_line
			(start -1.524 -0.762)
			(end -1.524 0.762)
			(stroke
				(width 0.1524)
				(type default)
			)
			(layer "B.SilkS")
		)
		(fp_line
			(start 1.1049 0.724916)
			(end -1.1049 0.724916)
			(stroke
				(width 0.1)
				(type default)
			)
			(layer "B.Fab")
		)
		(fp_line
			(start 1.1049 -0.724916)
			(end 1.1049 0.724916)
			(stroke
				(width 0.1)
				(type default)
			)
			(layer "B.Fab")
		)
		(fp_line
			(start -1.1049 0.724916)
			(end -1.1049 -0.724916)
			(stroke
				(width 0.1)
				(type default)
			)
			(layer "B.Fab")
		)
		(fp_line
			(start -1.1049 -0.724916)
			(end 1.1049 -0.724916)
			(stroke
				(width 0.1)
				(type default)
			)
			(layer "B.Fab")
		)
		(pad "1" smd rect
			(at 0.889 0 180)
			(size 1.016 1.27)
			(layers "B.Cu" "B.Mask" "B.Paste")
			(net "P0V9_CPU0_RT3_2A")
		)
		(pad "2" smd rect
			(at -0.889 0 180)
			(size 1.016 1.27)
			(layers "B.Cu" "B.Mask" "B.Paste")
			(net "GND")
		)
	)
	(footprint ""
		(layer "B.Cu")
		(at 94.34322 -180.010562 90)
		(property "Reference" "PR192"
			(at 0 0 90)
			(layer "B.SilkS")
			(hide yes)
			(effects
				(font
					(size 1.27 1.27)
				)
				(justify mirror)
			)
		)
		(property "Value" ""
			(at 0 0 90)
			(layer "B.Fab")
			(effects
				(font
					(size 1.27 1.27)
				)
				(justify mirror)
			)
		)
		(duplicate_pad_numbers_are_jumpers no)
		(fp_line
			(start 0.7874 -0.4064)
			(end -0.7874 -0.4064)
			(stroke
				(width 0.1524)
				(type default)
			)
			(layer "B.SilkS")
		)
		(fp_line
			(start -0.7874 -0.4064)
			(end -0.7874 0.4064)
			(stroke
				(width 0.1524)
				(type default)
			)
			(layer "B.SilkS")
		)
		(fp_line
			(start 0.7874 0.4064)
			(end 0.7874 -0.4064)
			(stroke
				(width 0.1524)
				(type default)
			)
			(layer "B.SilkS")
		)
		(fp_line
			(start -0.7874 0.4064)
			(end 0.7874 0.4064)
			(stroke
				(width 0.1524)
				(type default)
			)
			(layer "B.SilkS")
		)
		(fp_line
			(start 0.67945 -0.305054)
			(end 0.12065 -0.305054)
			(stroke
				(width 0.1)
				(type default)
			)
			(layer "B.Fab")
		)
		(fp_line
			(start 0.12065 -0.305054)
			(end 0.12065 -0.2794)
			(stroke
				(width 0.1)
				(type default)
			)
			(layer "B.Fab")
		)
		(fp_line
			(start -0.12065 -0.3048)
			(end -0.67945 -0.3048)
			(stroke
				(width 0.1)
				(type default)
			)
			(layer "B.Fab")
		)
		(fp_line
			(start -0.67945 -0.3048)
			(end -0.67945 0.3048)
			(stroke
				(width 0.1)
				(type default)
			)
			(layer "B.Fab")
		)
		(fp_line
			(start 0.12065 -0.2794)
			(end -0.12065 -0.2794)
			(stroke
				(width 0.1)
				(type default)
			)
			(layer "B.Fab")
		)
		(fp_line
			(start -0.12065 -0.2794)
			(end -0.12065 -0.3048)
			(stroke
				(width 0.1)
				(type default)
			)
			(layer "B.Fab")
		)
		(fp_line
			(start 0.12065 0.2794)
			(end 0.12065 0.3048)
			(stroke
				(width 0.1)
				(type default)
			)
			(layer "B.Fab")
		)
		(fp_line
			(start -0.120396 0.2794)
			(end 0.12065 0.2794)
			(stroke
				(width 0.1)
				(type default)
			)
			(layer "B.Fab")
		)
		(fp_line
			(start 0.67945 0.3048)
			(end 0.67945 -0.305054)
			(stroke
				(width 0.1)
				(type default)
			)
			(layer "B.Fab")
		)
		(fp_line
			(start 0.12065 0.3048)
			(end 0.67945 0.3048)
			(stroke
				(width 0.1)
				(type default)
			)
			(layer "B.Fab")
		)
		(fp_line
			(start -0.120396 0.3048)
			(end -0.120396 0.2794)
			(stroke
				(width 0.1)
				(type default)
			)
			(layer "B.Fab")
		)
		(fp_line
			(start -0.67945 0.3048)
			(end -0.120396 0.3048)
			(stroke
				(width 0.1)
				(type default)
			)
			(layer "B.Fab")
		)
		(pad "1" smd circle
			(at 0.40005 0 270)
			(size 0 0)
			(layers "B.Cu" "B.Mask" "B.Paste")
			(net "PVDDCR_CPU0_P1_VOS2")
		)
		(pad "2" smd circle
			(at -0.40005 0 270)
			(size 0 0)
			(layers "B.Cu" "B.Mask" "B.Paste")
			(net "PVDDCR_CPU0_P1")
		)
	)
	(footprint ""
		(layer "B.Cu")
		(at 339.93582 -326.363076 -90)
		(property "Reference" "PC140_5"
			(at 0 0 90)
			(layer "B.SilkS")
			(hide yes)
			(effects
				(font
					(size 1.27 1.27)
				)
				(justify mirror)
			)
		)
		(property "Value" ""
			(at 0 0 90)
			(layer "B.Fab")
			(effects
				(font
					(size 1.27 1.27)
				)
				(justify mirror)
			)
		)
		(duplicate_pad_numbers_are_jumpers no)
		(fp_line
			(start -1.524 0.762)
			(end 1.524 0.762)
			(stroke
				(width 0.1524)
				(type default)
			)
			(layer "B.SilkS")
		)
		(fp_line
			(start 1.524 0.762)
			(end 1.524 -0.762)
			(stroke
				(width 0.1524)
				(type default)
			)
			(layer "B.SilkS")
		)
		(fp_line
			(start -1.524 -0.762)
			(end -1.524 0.762)
			(stroke
				(width 0.1524)
				(type default)
			)
			(layer "B.SilkS")
		)
		(fp_line
			(start 1.524 -0.762)
			(end -1.524 -0.762)
			(stroke
				(width 0.1524)
				(type default)
			)
			(layer "B.SilkS")
		)
		(fp_line
			(start -1.1049 0.724916)
			(end -1.1049 -0.724916)
			(stroke
				(width 0.1)
				(type default)
			)
			(layer "B.Fab")
		)
		(fp_line
			(start 1.1049 0.724916)
			(end -1.1049 0.724916)
			(stroke
				(width 0.1)
				(type default)
			)
			(layer "B.Fab")
		)
		(fp_line
			(start -1.1049 -0.724916)
			(end 1.1049 -0.724916)
			(stroke
				(width 0.1)
				(type default)
			)
			(layer "B.Fab")
		)
		(fp_line
			(start 1.1049 -0.724916)
			(end 1.1049 0.724916)
			(stroke
				(width 0.1)
				(type default)
			)
			(layer "B.Fab")
		)
		(pad "1" smd rect
			(at 0.889 0 270)
			(size 1.016 1.27)
			(layers "B.Cu" "B.Mask" "B.Paste")
			(net "PVDDCR_CPU1_P0")
		)
		(pad "2" smd rect
			(at -0.889 0 270)
			(size 1.016 1.27)
			(layers "B.Cu" "B.Mask" "B.Paste")
			(net "GND")
		)
	)
	(footprint ""
		(layer "B.Cu")
		(at 175.075088 -244.085364)
		(property "Reference" "R507"
			(at 0 0 0)
			(layer "B.SilkS")
			(hide yes)
			(effects
				(font
					(size 1.27 1.27)
				)
				(justify mirror)
			)
		)
		(property "Value" ""
			(at 0 0 0)
			(layer "B.Fab")
			(effects
				(font
					(size 1.27 1.27)
				)
				(justify mirror)
			)
		)
		(duplicate_pad_numbers_are_jumpers no)
		(fp_line
			(start -0.7874 -0.4064)
			(end -0.7874 0.4064)
			(stroke
				(width 0.1524)
				(type default)
			)
			(layer "B.SilkS")
		)
		(fp_line
			(start -0.7874 0.4064)
			(end 0.7874 0.4064)
			(stroke
				(width 0.1524)
				(type default)
			)
			(layer "B.SilkS")
		)
		(fp_line
			(start 0.7874 -0.4064)
			(end -0.7874 -0.4064)
			(stroke
				(width 0.1524)
				(type default)
			)
			(layer "B.SilkS")
		)
		(fp_line
			(start 0.7874 0.4064)
			(end 0.7874 -0.4064)
			(stroke
				(width 0.1524)
				(type default)
			)
			(layer "B.SilkS")
		)
		(fp_line
			(start -0.67945 -0.3048)
			(end -0.67945 0.3048)
			(stroke
				(width 0.1)
				(type default)
			)
			(layer "B.Fab")
		)
		(fp_line
			(start -0.67945 0.3048)
			(end -0.120396 0.3048)
			(stroke
				(width 0.1)
				(type default)
			)
			(layer "B.Fab")
		)
		(fp_line
			(start -0.12065 -0.3048)
			(end -0.67945 -0.3048)
			(stroke
				(width 0.1)
				(type default)
			)
			(layer "B.Fab")
		)
		(fp_line
			(start -0.12065 -0.2794)
			(end -0.12065 -0.3048)
			(stroke
				(width 0.1)
				(type default)
			)
			(layer "B.Fab")
		)
		(fp_line
			(start -0.120396 0.2794)
			(end 0.12065 0.2794)
			(stroke
				(width 0.1)
				(type default)
			)
			(layer "B.Fab")
		)
		(fp_line
			(start -0.120396 0.3048)
			(end -0.120396 0.2794)
			(stroke
				(width 0.1)
				(type default)
			)
			(layer "B.Fab")
		)
		(fp_line
			(start 0.12065 -0.305054)
			(end 0.12065 -0.2794)
			(stroke
				(width 0.1)
				(type default)
			)
			(layer "B.Fab")
		)
		(fp_line
			(start 0.12065 -0.2794)
			(end -0.12065 -0.2794)
			(stroke
				(width 0.1)
				(type default)
			)
			(layer "B.Fab")
		)
		(fp_line
			(start 0.12065 0.2794)
			(end 0.12065 0.3048)
			(stroke
				(width 0.1)
				(type default)
			)
			(layer "B.Fab")
		)
		(fp_line
			(start 0.12065 0.3048)
			(end 0.67945 0.3048)
			(stroke
				(width 0.1)
				(type default)
			)
			(layer "B.Fab")
		)
		(fp_line
			(start 0.67945 -0.305054)
			(end 0.12065 -0.305054)
			(stroke
				(width 0.1)
				(type default)
			)
			(layer "B.Fab")
		)
		(fp_line
			(start 0.67945 0.3048)
			(end 0.67945 -0.305054)
			(stroke
				(width 0.1)
				(type default)
			)
			(layer "B.Fab")
		)
		(pad "1" smd circle
			(at 0.40005 0 180)
			(size 0 0)
			(layers "B.Cu" "B.Mask" "B.Paste")
			(net "M_H_CPU1_ALERT_N")
		)
		(pad "2" smd circle
			(at -0.40005 0 180)
			(size 0 0)
			(layers "B.Cu" "B.Mask" "B.Paste")
			(net "M_H_CPU1_ALERT_R_N")
		)
	)
	(footprint ""
		(layer "B.Cu")
		(at 314.489846 -416.899344 90)
		(property "Reference" "C6540"
			(at 0 0 90)
			(layer "B.SilkS")
			(hide yes)
			(effects
				(font
					(size 1.27 1.27)
				)
				(justify mirror)
			)
		)
		(property "Value" ""
			(at 0 0 90)
			(layer "B.Fab")
			(effects
				(font
					(size 1.27 1.27)
				)
				(justify mirror)
			)
		)
		(duplicate_pad_numbers_are_jumpers no)
		(fp_line
			(start 0.299974 -0.150114)
			(end -0.299974 -0.150114)
			(stroke
				(width 0.1)
				(type default)
			)
			(layer "B.Fab")
		)
		(fp_line
			(start -0.299974 -0.150114)
			(end -0.299974 0.150114)
			(stroke
				(width 0.1)
				(type default)
			)
			(layer "B.Fab")
		)
		(fp_line
			(start 0.299974 0.150114)
			(end 0.299974 -0.150114)
			(stroke
				(width 0.1)
				(type default)
			)
			(layer "B.Fab")
		)
		(fp_line
			(start -0.299974 0.150114)
			(end 0.299974 0.150114)
			(stroke
				(width 0.1)
				(type default)
			)
			(layer "B.Fab")
		)
		(pad "1" smd rect
			(at 0.2667 0 270)
			(size 0.3048 0.381)
			(layers "B.Cu" "B.Mask" "B.Paste")
			(net "P5E_CPU0_P1_TX_BUF_C_DN<3>")
		)
		(pad "2" smd rect
			(at -0.2667 0 270)
			(size 0.3048 0.381)
			(layers "B.Cu" "B.Mask" "B.Paste")
			(net "P5E_CPU0_P1_TX_BUF_DN<3>")
		)
	)
	(footprint ""
		(layer "B.Cu")
		(at 117.895624 -261.255256)
		(property "Reference" "C2437"
			(at 0 0 0)
			(layer "B.SilkS")
			(hide yes)
			(effects
				(font
					(size 1.27 1.27)
				)
				(justify mirror)
			)
		)
		(property "Value" ""
			(at 0 0 0)
			(layer "B.Fab")
			(effects
				(font
					(size 1.27 1.27)
				)
				(justify mirror)
			)
		)
		(duplicate_pad_numbers_are_jumpers no)
		(fp_line
			(start -0.7874 -0.4064)
			(end -0.7874 0.4064)
			(stroke
				(width 0.1524)
				(type default)
			)
			(layer "B.SilkS")
		)
		(fp_line
			(start -0.7874 0.4064)
			(end 0.7874 0.4064)
			(stroke
				(width 0.1524)
				(type default)
			)
			(layer "B.SilkS")
		)
		(fp_line
			(start 0.7874 -0.4064)
			(end -0.7874 -0.4064)
			(stroke
				(width 0.1524)
				(type default)
			)
			(layer "B.SilkS")
		)
		(fp_line
			(start 0.7874 0.4064)
			(end 0.7874 -0.4064)
			(stroke
				(width 0.1524)
				(type default)
			)
			(layer "B.SilkS")
		)
		(fp_line
			(start -0.67945 -0.3048)
			(end -0.67945 0.3048)
			(stroke
				(width 0.1)
				(type default)
			)
			(layer "B.Fab")
		)
		(fp_line
			(start -0.67945 0.3048)
			(end -0.120396 0.3048)
			(stroke
				(width 0.1)
				(type default)
			)
			(layer "B.Fab")
		)
		(fp_line
			(start -0.12065 -0.3048)
			(end -0.67945 -0.3048)
			(stroke
				(width 0.1)
				(type default)
			)
			(layer "B.Fab")
		)
		(fp_line
			(start -0.12065 -0.2794)
			(end -0.12065 -0.3048)
			(stroke
				(width 0.1)
				(type default)
			)
			(layer "B.Fab")
		)
		(fp_line
			(start -0.120396 0.2794)
			(end 0.12065 0.2794)
			(stroke
				(width 0.1)
				(type default)
			)
			(layer "B.Fab")
		)
		(fp_line
			(start -0.120396 0.3048)
			(end -0.120396 0.2794)
			(stroke
				(width 0.1)
				(type default)
			)
			(layer "B.Fab")
		)
		(fp_line
			(start 0.12065 -0.305054)
			(end 0.12065 -0.2794)
			(stroke
				(width 0.1)
				(type default)
			)
			(layer "B.Fab")
		)
		(fp_line
			(start 0.12065 -0.2794)
			(end -0.12065 -0.2794)
			(stroke
				(width 0.1)
				(type default)
			)
			(layer "B.Fab")
		)
		(fp_line
			(start 0.12065 0.2794)
			(end 0.12065 0.3048)
			(stroke
				(width 0.1)
				(type default)
			)
			(layer "B.Fab")
		)
		(fp_line
			(start 0.12065 0.3048)
			(end 0.67945 0.3048)
			(stroke
				(width 0.1)
				(type default)
			)
			(layer "B.Fab")
		)
		(fp_line
			(start 0.67945 -0.305054)
			(end 0.12065 -0.305054)
			(stroke
				(width 0.1)
				(type default)
			)
			(layer "B.Fab")
		)
		(fp_line
			(start 0.67945 0.3048)
			(end 0.67945 -0.305054)
			(stroke
				(width 0.1)
				(type default)
			)
			(layer "B.Fab")
		)
		(pad "1" smd circle
			(at 0.40005 0 180)
			(size 0 0)
			(layers "B.Cu" "B.Mask" "B.Paste")
			(net "PVDDCR_SOC_P1")
		)
		(pad "2" smd circle
			(at -0.40005 0 180)
			(size 0 0)
			(layers "B.Cu" "B.Mask" "B.Paste")
			(net "GND")
		)
	)
	(footprint ""
		(layer "B.Cu")
		(at 127.908304 -32.867092 -90)
		(property "Reference" "C6076"
			(at 0 0 90)
			(layer "B.SilkS")
			(hide yes)
			(effects
				(font
					(size 1.27 1.27)
				)
				(justify mirror)
			)
		)
		(property "Value" ""
			(at 0 0 90)
			(layer "B.Fab")
			(effects
				(font
					(size 1.27 1.27)
				)
				(justify mirror)
			)
		)
		(duplicate_pad_numbers_are_jumpers no)
		(fp_line
			(start -0.7874 0.4064)
			(end 0.7874 0.4064)
			(stroke
				(width 0.1524)
				(type default)
			)
			(layer "B.SilkS")
		)
		(fp_line
			(start 0.7874 0.4064)
			(end 0.7874 -0.4064)
			(stroke
				(width 0.1524)
				(type default)
			)
			(layer "B.SilkS")
		)
		(fp_line
			(start -0.7874 -0.4064)
			(end -0.7874 0.4064)
			(stroke
				(width 0.1524)
				(type default)
			)
			(layer "B.SilkS")
		)
		(fp_line
			(start 0.7874 -0.4064)
			(end -0.7874 -0.4064)
			(stroke
				(width 0.1524)
				(type default)
			)
			(layer "B.SilkS")
		)
		(fp_line
			(start -0.67945 0.3048)
			(end -0.120396 0.3048)
			(stroke
				(width 0.1)
				(type default)
			)
			(layer "B.Fab")
		)
		(fp_line
			(start -0.120396 0.3048)
			(end -0.120396 0.2794)
			(stroke
				(width 0.1)
				(type default)
			)
			(layer "B.Fab")
		)
		(fp_line
			(start 0.12065 0.3048)
			(end 0.67945 0.3048)
			(stroke
				(width 0.1)
				(type default)
			)
			(layer "B.Fab")
		)
		(fp_line
			(start 0.67945 0.3048)
			(end 0.67945 -0.305054)
			(stroke
				(width 0.1)
				(type default)
			)
			(layer "B.Fab")
		)
		(fp_line
			(start -0.120396 0.2794)
			(end 0.12065 0.2794)
			(stroke
				(width 0.1)
				(type default)
			)
			(layer "B.Fab")
		)
		(fp_line
			(start 0.12065 0.2794)
			(end 0.12065 0.3048)
			(stroke
				(width 0.1)
				(type default)
			)
			(layer "B.Fab")
		)
		(fp_line
			(start -0.12065 -0.2794)
			(end -0.12065 -0.3048)
			(stroke
				(width 0.1)
				(type default)
			)
			(layer "B.Fab")
		)
		(fp_line
			(start 0.12065 -0.2794)
			(end -0.12065 -0.2794)
			(stroke
				(width 0.1)
				(type default)
			)
			(layer "B.Fab")
		)
		(fp_line
			(start -0.67945 -0.3048)
			(end -0.67945 0.3048)
			(stroke
				(width 0.1)
				(type default)
			)
			(layer "B.Fab")
		)
		(fp_line
			(start -0.12065 -0.3048)
			(end -0.67945 -0.3048)
			(stroke
				(width 0.1)
				(type default)
			)
			(layer "B.Fab")
		)
		(fp_line
			(start 0.12065 -0.305054)
			(end 0.12065 -0.2794)
			(stroke
				(width 0.1)
				(type default)
			)
			(layer "B.Fab")
		)
		(fp_line
			(start 0.67945 -0.305054)
			(end 0.12065 -0.305054)
			(stroke
				(width 0.1)
				(type default)
			)
			(layer "B.Fab")
		)
		(pad "1" smd circle
			(at 0.40005 0 90)
			(size 0 0)
			(layers "B.Cu" "B.Mask" "B.Paste")
			(net "P1V2_AUX")
		)
		(pad "2" smd circle
			(at -0.40005 0 90)
			(size 0 0)
			(layers "B.Cu" "B.Mask" "B.Paste")
			(net "GND")
		)
	)
	(footprint ""
		(layer "B.Cu")
		(at 66.747644 -337.665314 -90)
		(property "Reference" "PR269"
			(at 0 0 90)
			(layer "B.SilkS")
			(hide yes)
			(effects
				(font
					(size 1.27 1.27)
				)
				(justify mirror)
			)
		)
		(property "Value" ""
			(at 0 0 90)
			(layer "B.Fab")
			(effects
				(font
					(size 1.27 1.27)
				)
				(justify mirror)
			)
		)
		(duplicate_pad_numbers_are_jumpers no)
		(fp_line
			(start -0.7874 0.4064)
			(end 0.7874 0.4064)
			(stroke
				(width 0.1524)
				(type default)
			)
			(layer "B.SilkS")
		)
		(fp_line
			(start 0.7874 0.4064)
			(end 0.7874 -0.4064)
			(stroke
				(width 0.1524)
				(type default)
			)
			(layer "B.SilkS")
		)
		(fp_line
			(start -0.7874 -0.4064)
			(end -0.7874 0.4064)
			(stroke
				(width 0.1524)
				(type default)
			)
			(layer "B.SilkS")
		)
		(fp_line
			(start 0.7874 -0.4064)
			(end -0.7874 -0.4064)
			(stroke
				(width 0.1524)
				(type default)
			)
			(layer "B.SilkS")
		)
		(fp_line
			(start -0.67945 0.3048)
			(end -0.120396 0.3048)
			(stroke
				(width 0.1)
				(type default)
			)
			(layer "B.Fab")
		)
		(fp_line
			(start -0.120396 0.3048)
			(end -0.120396 0.2794)
			(stroke
				(width 0.1)
				(type default)
			)
			(layer "B.Fab")
		)
		(fp_line
			(start 0.12065 0.3048)
			(end 0.67945 0.3048)
			(stroke
				(width 0.1)
				(type default)
			)
			(layer "B.Fab")
		)
		(fp_line
			(start 0.67945 0.3048)
			(end 0.67945 -0.305054)
			(stroke
				(width 0.1)
				(type default)
			)
			(layer "B.Fab")
		)
		(fp_line
			(start -0.120396 0.2794)
			(end 0.12065 0.2794)
			(stroke
				(width 0.1)
				(type default)
			)
			(layer "B.Fab")
		)
		(fp_line
			(start 0.12065 0.2794)
			(end 0.12065 0.3048)
			(stroke
				(width 0.1)
				(type default)
			)
			(layer "B.Fab")
		)
		(fp_line
			(start -0.12065 -0.2794)
			(end -0.12065 -0.3048)
			(stroke
				(width 0.1)
				(type default)
			)
			(layer "B.Fab")
		)
		(fp_line
			(start 0.12065 -0.2794)
			(end -0.12065 -0.2794)
			(stroke
				(width 0.1)
				(type default)
			)
			(layer "B.Fab")
		)
		(fp_line
			(start -0.67945 -0.3048)
			(end -0.67945 0.3048)
			(stroke
				(width 0.1)
				(type default)
			)
			(layer "B.Fab")
		)
		(fp_line
			(start -0.12065 -0.3048)
			(end -0.67945 -0.3048)
			(stroke
				(width 0.1)
				(type default)
			)
			(layer "B.Fab")
		)
		(fp_line
			(start 0.12065 -0.305054)
			(end 0.12065 -0.2794)
			(stroke
				(width 0.1)
				(type default)
			)
			(layer "B.Fab")
		)
		(fp_line
			(start 0.67945 -0.305054)
			(end 0.12065 -0.305054)
			(stroke
				(width 0.1)
				(type default)
			)
			(layer "B.Fab")
		)
		(pad "1" smd circle
			(at 0.40005 0 90)
			(size 0 0)
			(layers "B.Cu" "B.Mask" "B.Paste")
			(net "PVDDCR_CPU1_P1_VOS3")
		)
		(pad "2" smd circle
			(at -0.40005 0 90)
			(size 0 0)
			(layers "B.Cu" "B.Mask" "B.Paste")
			(net "PVDDCR_CPU1_P1")
		)
	)
	(footprint ""
		(layer "B.Cu")
		(at 51.734974 -416.091116)
		(property "Reference" "C2075"
			(at 0 0 0)
			(layer "B.SilkS")
			(hide yes)
			(effects
				(font
					(size 1.27 1.27)
				)
				(justify mirror)
			)
		)
		(property "Value" ""
			(at 0 0 0)
			(layer "B.Fab")
			(effects
				(font
					(size 1.27 1.27)
				)
				(justify mirror)
			)
		)
		(duplicate_pad_numbers_are_jumpers no)
		(fp_line
			(start -0.299974 -0.150114)
			(end -0.299974 0.150114)
			(stroke
				(width 0.1)
				(type default)
			)
			(layer "B.Fab")
		)
		(fp_line
			(start -0.299974 0.150114)
			(end 0.299974 0.150114)
			(stroke
				(width 0.1)
				(type default)
			)
			(layer "B.Fab")
		)
		(fp_line
			(start 0.299974 -0.150114)
			(end -0.299974 -0.150114)
			(stroke
				(width 0.1)
				(type default)
			)
			(layer "B.Fab")
		)
		(fp_line
			(start 0.299974 0.150114)
			(end 0.299974 -0.150114)
			(stroke
				(width 0.1)
				(type default)
			)
			(layer "B.Fab")
		)
		(pad "1" smd rect
			(at 0.2667 0 180)
			(size 0.3048 0.381)
			(layers "B.Cu" "B.Mask" "B.Paste")
			(net "P3E_CPU1_P5_TX_C_DP<0>")
		)
		(pad "2" smd rect
			(at -0.2667 0 180)
			(size 0.3048 0.381)
			(layers "B.Cu" "B.Mask" "B.Paste")
			(net "P3E_CPU1_P5_TX_DP<0>")
		)
	)
	(footprint ""
		(layer "B.Cu")
		(at 450.177916 -47.505366 90)
		(property "Reference" "PC2344"
			(at 0 0 90)
			(layer "B.SilkS")
			(hide yes)
			(effects
				(font
					(size 1.27 1.27)
				)
				(justify mirror)
			)
		)
		(property "Value" ""
			(at 0 0 90)
			(layer "B.Fab")
			(effects
				(font
					(size 1.27 1.27)
				)
				(justify mirror)
			)
		)
		(duplicate_pad_numbers_are_jumpers no)
		(fp_line
			(start 1.524 -0.762)
			(end -1.524 -0.762)
			(stroke
				(width 0.1524)
				(type default)
			)
			(layer "B.SilkS")
		)
		(fp_line
			(start -1.524 -0.762)
			(end -1.524 0.762)
			(stroke
				(width 0.1524)
				(type default)
			)
			(layer "B.SilkS")
		)
		(fp_line
			(start 1.524 0.762)
			(end 1.524 -0.762)
			(stroke
				(width 0.1524)
				(type default)
			)
			(layer "B.SilkS")
		)
		(fp_line
			(start -1.524 0.762)
			(end 1.524 0.762)
			(stroke
				(width 0.1524)
				(type default)
			)
			(layer "B.SilkS")
		)
		(fp_line
			(start 1.1049 -0.724916)
			(end 1.1049 0.724916)
			(stroke
				(width 0.1)
				(type default)
			)
			(layer "B.Fab")
		)
		(fp_line
			(start -1.1049 -0.724916)
			(end 1.1049 -0.724916)
			(stroke
				(width 0.1)
				(type default)
			)
			(layer "B.Fab")
		)
		(fp_line
			(start 1.1049 0.724916)
			(end -1.1049 0.724916)
			(stroke
				(width 0.1)
				(type default)
			)
			(layer "B.Fab")
		)
		(fp_line
			(start -1.1049 0.724916)
			(end -1.1049 -0.724916)
			(stroke
				(width 0.1)
				(type default)
			)
			(layer "B.Fab")
		)
		(pad "1" smd rect
			(at 0.889 0 90)
			(size 1.016 1.27)
			(layers "B.Cu" "B.Mask" "B.Paste")
			(net "SW_P3V3_AUX_FLT")
		)
		(pad "2" smd rect
			(at -0.889 0 90)
			(size 1.016 1.27)
			(layers "B.Cu" "B.Mask" "B.Paste")
			(net "GND")
		)
	)
	(footprint ""
		(layer "B.Cu")
		(at 396.218918 -203.879958 -90)
		(property "Reference" "R6131"
			(at 0 0 90)
			(layer "B.SilkS")
			(hide yes)
			(effects
				(font
					(size 1.27 1.27)
				)
				(justify mirror)
			)
		)
		(property "Value" ""
			(at 0 0 90)
			(layer "B.Fab")
			(effects
				(font
					(size 1.27 1.27)
				)
				(justify mirror)
			)
		)
		(duplicate_pad_numbers_are_jumpers no)
		(fp_line
			(start -0.7874 0.4064)
			(end 0.7874 0.4064)
			(stroke
				(width 0.1524)
				(type default)
			)
			(layer "B.SilkS")
		)
		(fp_line
			(start 0.7874 0.4064)
			(end 0.7874 -0.4064)
			(stroke
				(width 0.1524)
				(type default)
			)
			(layer "B.SilkS")
		)
		(fp_line
			(start -0.7874 -0.4064)
			(end -0.7874 0.4064)
			(stroke
				(width 0.1524)
				(type default)
			)
			(layer "B.SilkS")
		)
		(fp_line
			(start 0.7874 -0.4064)
			(end -0.7874 -0.4064)
			(stroke
				(width 0.1524)
				(type default)
			)
			(layer "B.SilkS")
		)
		(fp_line
			(start -0.67945 0.3048)
			(end -0.120396 0.3048)
			(stroke
				(width 0.1)
				(type default)
			)
			(layer "B.Fab")
		)
		(fp_line
			(start -0.120396 0.3048)
			(end -0.120396 0.2794)
			(stroke
				(width 0.1)
				(type default)
			)
			(layer "B.Fab")
		)
		(fp_line
			(start 0.12065 0.3048)
			(end 0.67945 0.3048)
			(stroke
				(width 0.1)
				(type default)
			)
			(layer "B.Fab")
		)
		(fp_line
			(start 0.67945 0.3048)
			(end 0.67945 -0.305054)
			(stroke
				(width 0.1)
				(type default)
			)
			(layer "B.Fab")
		)
		(fp_line
			(start -0.120396 0.2794)
			(end 0.12065 0.2794)
			(stroke
				(width 0.1)
				(type default)
			)
			(layer "B.Fab")
		)
		(fp_line
			(start 0.12065 0.2794)
			(end 0.12065 0.3048)
			(stroke
				(width 0.1)
				(type default)
			)
			(layer "B.Fab")
		)
		(fp_line
			(start -0.12065 -0.2794)
			(end -0.12065 -0.3048)
			(stroke
				(width 0.1)
				(type default)
			)
			(layer "B.Fab")
		)
		(fp_line
			(start 0.12065 -0.2794)
			(end -0.12065 -0.2794)
			(stroke
				(width 0.1)
				(type default)
			)
			(layer "B.Fab")
		)
		(fp_line
			(start -0.67945 -0.3048)
			(end -0.67945 0.3048)
			(stroke
				(width 0.1)
				(type default)
			)
			(layer "B.Fab")
		)
		(fp_line
			(start -0.12065 -0.3048)
			(end -0.67945 -0.3048)
			(stroke
				(width 0.1)
				(type default)
			)
			(layer "B.Fab")
		)
		(fp_line
			(start 0.12065 -0.305054)
			(end 0.12065 -0.2794)
			(stroke
				(width 0.1)
				(type default)
			)
			(layer "B.Fab")
		)
		(fp_line
			(start 0.67945 -0.305054)
			(end 0.12065 -0.305054)
			(stroke
				(width 0.1)
				(type default)
			)
			(layer "B.Fab")
		)
		(pad "1" smd circle
			(at 0.40005 0 90)
			(size 0 0)
			(layers "B.Cu" "B.Mask" "B.Paste")
			(net "PVDD18_S5_P0")
		)
		(pad "2" smd circle
			(at -0.40005 0 90)
			(size 0 0)
			(layers "B.Cu" "B.Mask" "B.Paste")
			(net "FAB_REV_ID1")
		)
	)
	(footprint ""
		(layer "B.Cu")
		(at 33.467294 -194.885564 180)
		(property "Reference" "R772"
			(at 0 0 0)
			(layer "B.SilkS")
			(hide yes)
			(effects
				(font
					(size 1.27 1.27)
				)
				(justify mirror)
			)
		)
		(property "Value" ""
			(at 0 0 0)
			(layer "B.Fab")
			(effects
				(font
					(size 1.27 1.27)
				)
				(justify mirror)
			)
		)
		(duplicate_pad_numbers_are_jumpers no)
		(fp_line
			(start 0.7874 0.4064)
			(end 0.7874 -0.4064)
			(stroke
				(width 0.1524)
				(type default)
			)
			(layer "B.SilkS")
		)
		(fp_line
			(start 0.7874 -0.4064)
			(end -0.7874 -0.4064)
			(stroke
				(width 0.1524)
				(type default)
			)
			(layer "B.SilkS")
		)
		(fp_line
			(start -0.7874 0.4064)
			(end 0.7874 0.4064)
			(stroke
				(width 0.1524)
				(type default)
			)
			(layer "B.SilkS")
		)
		(fp_line
			(start -0.7874 -0.4064)
			(end -0.7874 0.4064)
			(stroke
				(width 0.1524)
				(type default)
			)
			(layer "B.SilkS")
		)
		(fp_line
			(start 0.67945 0.3048)
			(end 0.67945 -0.305054)
			(stroke
				(width 0.1)
				(type default)
			)
			(layer "B.Fab")
		)
		(fp_line
			(start 0.67945 -0.305054)
			(end 0.12065 -0.305054)
			(stroke
				(width 0.1)
				(type default)
			)
			(layer "B.Fab")
		)
		(fp_line
			(start 0.12065 0.3048)
			(end 0.67945 0.3048)
			(stroke
				(width 0.1)
				(type default)
			)
			(layer "B.Fab")
		)
		(fp_line
			(start 0.12065 0.2794)
			(end 0.12065 0.3048)
			(stroke
				(width 0.1)
				(type default)
			)
			(layer "B.Fab")
		)
		(fp_line
			(start 0.12065 -0.2794)
			(end -0.12065 -0.2794)
			(stroke
				(width 0.1)
				(type default)
			)
			(layer "B.Fab")
		)
		(fp_line
			(start 0.12065 -0.305054)
			(end 0.12065 -0.2794)
			(stroke
				(width 0.1)
				(type default)
			)
			(layer "B.Fab")
		)
		(fp_line
			(start -0.120396 0.3048)
			(end -0.120396 0.2794)
			(stroke
				(width 0.1)
				(type default)
			)
			(layer "B.Fab")
		)
		(fp_line
			(start -0.120396 0.2794)
			(end 0.12065 0.2794)
			(stroke
				(width 0.1)
				(type default)
			)
			(layer "B.Fab")
		)
		(fp_line
			(start -0.12065 -0.2794)
			(end -0.12065 -0.3048)
			(stroke
				(width 0.1)
				(type default)
			)
			(layer "B.Fab")
		)
		(fp_line
			(start -0.12065 -0.3048)
			(end -0.67945 -0.3048)
			(stroke
				(width 0.1)
				(type default)
			)
			(layer "B.Fab")
		)
		(fp_line
			(start -0.67945 0.3048)
			(end -0.120396 0.3048)
			(stroke
				(width 0.1)
				(type default)
			)
			(layer "B.Fab")
		)
		(fp_line
			(start -0.67945 -0.3048)
			(end -0.67945 0.3048)
			(stroke
				(width 0.1)
				(type default)
			)
			(layer "B.Fab")
		)
		(pad "1" smd circle
			(at 0.40005 0)
			(size 0 0)
			(layers "B.Cu" "B.Mask" "B.Paste")
			(net "PD_CHD_CPU1_DIMM_SAA")
		)
		(pad "2" smd circle
			(at -0.40005 0)
			(size 0 0)
			(layers "B.Cu" "B.Mask" "B.Paste")
			(net "GND")
		)
	)
	(footprint ""
		(layer "B.Cu")
		(at 143.401542 -81.786222)
		(property "Reference" "R6242"
			(at 0 0 0)
			(layer "B.SilkS")
			(hide yes)
			(effects
				(font
					(size 1.27 1.27)
				)
				(justify mirror)
			)
		)
		(property "Value" ""
			(at 0 0 0)
			(layer "B.Fab")
			(effects
				(font
					(size 1.27 1.27)
				)
				(justify mirror)
			)
		)
		(duplicate_pad_numbers_are_jumpers no)
		(fp_line
			(start -0.7874 -0.4064)
			(end -0.7874 0.4064)
			(stroke
				(width 0.1524)
				(type default)
			)
			(layer "B.SilkS")
		)
		(fp_line
			(start -0.7874 0.4064)
			(end 0.7874 0.4064)
			(stroke
				(width 0.1524)
				(type default)
			)
			(layer "B.SilkS")
		)
		(fp_line
			(start 0.7874 -0.4064)
			(end -0.7874 -0.4064)
			(stroke
				(width 0.1524)
				(type default)
			)
			(layer "B.SilkS")
		)
		(fp_line
			(start 0.7874 0.4064)
			(end 0.7874 -0.4064)
			(stroke
				(width 0.1524)
				(type default)
			)
			(layer "B.SilkS")
		)
		(fp_line
			(start -0.67945 -0.3048)
			(end -0.67945 0.3048)
			(stroke
				(width 0.1)
				(type default)
			)
			(layer "B.Fab")
		)
		(fp_line
			(start -0.67945 0.3048)
			(end -0.120396 0.3048)
			(stroke
				(width 0.1)
				(type default)
			)
			(layer "B.Fab")
		)
		(fp_line
			(start -0.12065 -0.3048)
			(end -0.67945 -0.3048)
			(stroke
				(width 0.1)
				(type default)
			)
			(layer "B.Fab")
		)
		(fp_line
			(start -0.12065 -0.2794)
			(end -0.12065 -0.3048)
			(stroke
				(width 0.1)
				(type default)
			)
			(layer "B.Fab")
		)
		(fp_line
			(start -0.120396 0.2794)
			(end 0.12065 0.2794)
			(stroke
				(width 0.1)
				(type default)
			)
			(layer "B.Fab")
		)
		(fp_line
			(start -0.120396 0.3048)
			(end -0.120396 0.2794)
			(stroke
				(width 0.1)
				(type default)
			)
			(layer "B.Fab")
		)
		(fp_line
			(start 0.12065 -0.305054)
			(end 0.12065 -0.2794)
			(stroke
				(width 0.1)
				(type default)
			)
			(layer "B.Fab")
		)
		(fp_line
			(start 0.12065 -0.2794)
			(end -0.12065 -0.2794)
			(stroke
				(width 0.1)
				(type default)
			)
			(layer "B.Fab")
		)
		(fp_line
			(start 0.12065 0.2794)
			(end 0.12065 0.3048)
			(stroke
				(width 0.1)
				(type default)
			)
			(layer "B.Fab")
		)
		(fp_line
			(start 0.12065 0.3048)
			(end 0.67945 0.3048)
			(stroke
				(width 0.1)
				(type default)
			)
			(layer "B.Fab")
		)
		(fp_line
			(start 0.67945 -0.305054)
			(end 0.12065 -0.305054)
			(stroke
				(width 0.1)
				(type default)
			)
			(layer "B.Fab")
		)
		(fp_line
			(start 0.67945 0.3048)
			(end 0.67945 -0.305054)
			(stroke
				(width 0.1)
				(type default)
			)
			(layer "B.Fab")
		)
		(pad "1" smd circle
			(at 0.40005 0 180)
			(size 0 0)
			(layers "B.Cu" "B.Mask" "B.Paste")
			(net "P3V3_AUX")
		)
		(pad "2" smd circle
			(at -0.40005 0 180)
			(size 0 0)
			(layers "B.Cu" "B.Mask" "B.Paste")
			(net "P1V8_AUX_VCC")
		)
	)
	(footprint ""
		(layer "B.Cu")
		(at 151.010366 -408.517344 90)
		(property "Reference" "C6747"
			(at 0 0 90)
			(layer "B.SilkS")
			(hide yes)
			(effects
				(font
					(size 1.27 1.27)
				)
				(justify mirror)
			)
		)
		(property "Value" ""
			(at 0 0 90)
			(layer "B.Fab")
			(effects
				(font
					(size 1.27 1.27)
				)
				(justify mirror)
			)
		)
		(duplicate_pad_numbers_are_jumpers no)
		(fp_line
			(start 0.299974 -0.150114)
			(end -0.299974 -0.150114)
			(stroke
				(width 0.1)
				(type default)
			)
			(layer "B.Fab")
		)
		(fp_line
			(start -0.299974 -0.150114)
			(end -0.299974 0.150114)
			(stroke
				(width 0.1)
				(type default)
			)
			(layer "B.Fab")
		)
		(fp_line
			(start 0.299974 0.150114)
			(end 0.299974 -0.150114)
			(stroke
				(width 0.1)
				(type default)
			)
			(layer "B.Fab")
		)
		(fp_line
			(start -0.299974 0.150114)
			(end 0.299974 0.150114)
			(stroke
				(width 0.1)
				(type default)
			)
			(layer "B.Fab")
		)
		(pad "1" smd rect
			(at 0.2667 0 270)
			(size 0.3048 0.381)
			(layers "B.Cu" "B.Mask" "B.Paste")
			(net "P5E_CPU1_P3_TX_BUF_C_DP<11>")
		)
		(pad "2" smd rect
			(at -0.2667 0 270)
			(size 0.3048 0.381)
			(layers "B.Cu" "B.Mask" "B.Paste")
			(net "P5E_CPU1_P3_TX_BUF_DP<11>")
		)
	)
	(footprint ""
		(layer "B.Cu")
		(at 149.900386 -313.45505)
		(property "Reference" "R5103"
			(at 0 0 0)
			(layer "B.SilkS")
			(hide yes)
			(effects
				(font
					(size 1.27 1.27)
				)
				(justify mirror)
			)
		)
		(property "Value" ""
			(at 0 0 0)
			(layer "B.Fab")
			(effects
				(font
					(size 1.27 1.27)
				)
				(justify mirror)
			)
		)
		(duplicate_pad_numbers_are_jumpers no)
		(fp_line
			(start -0.7874 -0.4064)
			(end -0.7874 0.4064)
			(stroke
				(width 0.1524)
				(type default)
			)
			(layer "B.SilkS")
		)
		(fp_line
			(start -0.7874 0.4064)
			(end 0.7874 0.4064)
			(stroke
				(width 0.1524)
				(type default)
			)
			(layer "B.SilkS")
		)
		(fp_line
			(start 0.7874 -0.4064)
			(end -0.7874 -0.4064)
			(stroke
				(width 0.1524)
				(type default)
			)
			(layer "B.SilkS")
		)
		(fp_line
			(start 0.7874 0.4064)
			(end 0.7874 -0.4064)
			(stroke
				(width 0.1524)
				(type default)
			)
			(layer "B.SilkS")
		)
		(fp_line
			(start -0.67945 -0.3048)
			(end -0.67945 0.3048)
			(stroke
				(width 0.1)
				(type default)
			)
			(layer "B.Fab")
		)
		(fp_line
			(start -0.67945 0.3048)
			(end -0.120396 0.3048)
			(stroke
				(width 0.1)
				(type default)
			)
			(layer "B.Fab")
		)
		(fp_line
			(start -0.12065 -0.3048)
			(end -0.67945 -0.3048)
			(stroke
				(width 0.1)
				(type default)
			)
			(layer "B.Fab")
		)
		(fp_line
			(start -0.12065 -0.2794)
			(end -0.12065 -0.3048)
			(stroke
				(width 0.1)
				(type default)
			)
			(layer "B.Fab")
		)
		(fp_line
			(start -0.120396 0.2794)
			(end 0.12065 0.2794)
			(stroke
				(width 0.1)
				(type default)
			)
			(layer "B.Fab")
		)
		(fp_line
			(start -0.120396 0.3048)
			(end -0.120396 0.2794)
			(stroke
				(width 0.1)
				(type default)
			)
			(layer "B.Fab")
		)
		(fp_line
			(start 0.12065 -0.305054)
			(end 0.12065 -0.2794)
			(stroke
				(width 0.1)
				(type default)
			)
			(layer "B.Fab")
		)
		(fp_line
			(start 0.12065 -0.2794)
			(end -0.12065 -0.2794)
			(stroke
				(width 0.1)
				(type default)
			)
			(layer "B.Fab")
		)
		(fp_line
			(start 0.12065 0.2794)
			(end 0.12065 0.3048)
			(stroke
				(width 0.1)
				(type default)
			)
			(layer "B.Fab")
		)
		(fp_line
			(start 0.12065 0.3048)
			(end 0.67945 0.3048)
			(stroke
				(width 0.1)
				(type default)
			)
			(layer "B.Fab")
		)
		(fp_line
			(start 0.67945 -0.305054)
			(end 0.12065 -0.305054)
			(stroke
				(width 0.1)
				(type default)
			)
			(layer "B.Fab")
		)
		(fp_line
			(start 0.67945 0.3048)
			(end 0.67945 -0.305054)
			(stroke
				(width 0.1)
				(type default)
			)
			(layer "B.Fab")
		)
		(pad "1" smd circle
			(at 0.40005 0 180)
			(size 0 0)
			(layers "B.Cu" "B.Mask" "B.Paste")
			(net "XTAL_CPU1_X48M_X2")
		)
		(pad "2" smd circle
			(at -0.40005 0 180)
			(size 0 0)
			(layers "B.Cu" "B.Mask" "B.Paste")
			(net "XTAL_CPU1_X48M_X2_R")
		)
	)
	(footprint ""
		(layer "B.Cu")
		(at 142.893542 -384.66268 180)
		(property "Reference" "R881"
			(at 0 0 0)
			(layer "B.SilkS")
			(hide yes)
			(effects
				(font
					(size 1.27 1.27)
				)
				(justify mirror)
			)
		)
		(property "Value" ""
			(at 0 0 0)
			(layer "B.Fab")
			(effects
				(font
					(size 1.27 1.27)
				)
				(justify mirror)
			)
		)
		(duplicate_pad_numbers_are_jumpers no)
		(fp_line
			(start 0.32512 0.175006)
			(end 0.32512 -0.175006)
			(stroke
				(width 0.1)
				(type default)
			)
			(layer "B.Fab")
		)
		(fp_line
			(start 0.32512 -0.175006)
			(end -0.32512 -0.175006)
			(stroke
				(width 0.1)
				(type default)
			)
			(layer "B.Fab")
		)
		(fp_line
			(start -0.32512 0.175006)
			(end 0.32512 0.175006)
			(stroke
				(width 0.1)
				(type default)
			)
			(layer "B.Fab")
		)
		(fp_line
			(start -0.32512 -0.175006)
			(end -0.32512 0.175006)
			(stroke
				(width 0.1)
				(type default)
			)
			(layer "B.Fab")
		)
		(pad "1" smd rect
			(at 0.2667 0)
			(size 0.3048 0.381)
			(layers "B.Cu" "B.Mask" "B.Paste")
			(net "TEST1_RT_CPU1_P2")
		)
		(pad "2" smd rect
			(at -0.2667 0 180)
			(size 0.3048 0.381)
			(layers "B.Cu" "B.Mask" "B.Paste")
			(net "GND")
		)
	)
	(footprint ""
		(layer "B.Cu")
		(at 366.566958 -272.284952 180)
		(property "Reference" "C2213"
			(at 0 0 0)
			(layer "B.SilkS")
			(hide yes)
			(effects
				(font
					(size 1.27 1.27)
				)
				(justify mirror)
			)
		)
		(property "Value" ""
			(at 0 0 0)
			(layer "B.Fab")
			(effects
				(font
					(size 1.27 1.27)
				)
				(justify mirror)
			)
		)
		(duplicate_pad_numbers_are_jumpers no)
		(fp_line
			(start 0.7874 0.4064)
			(end 0.7874 -0.4064)
			(stroke
				(width 0.1524)
				(type default)
			)
			(layer "B.SilkS")
		)
		(fp_line
			(start 0.7874 -0.4064)
			(end -0.7874 -0.4064)
			(stroke
				(width 0.1524)
				(type default)
			)
			(layer "B.SilkS")
		)
		(fp_line
			(start -0.7874 0.4064)
			(end 0.7874 0.4064)
			(stroke
				(width 0.1524)
				(type default)
			)
			(layer "B.SilkS")
		)
		(fp_line
			(start -0.7874 -0.4064)
			(end -0.7874 0.4064)
			(stroke
				(width 0.1524)
				(type default)
			)
			(layer "B.SilkS")
		)
		(fp_line
			(start 0.67945 0.3048)
			(end 0.67945 -0.305054)
			(stroke
				(width 0.1)
				(type default)
			)
			(layer "B.Fab")
		)
		(fp_line
			(start 0.67945 -0.305054)
			(end 0.12065 -0.305054)
			(stroke
				(width 0.1)
				(type default)
			)
			(layer "B.Fab")
		)
		(fp_line
			(start 0.12065 0.3048)
			(end 0.67945 0.3048)
			(stroke
				(width 0.1)
				(type default)
			)
			(layer "B.Fab")
		)
		(fp_line
			(start 0.12065 0.2794)
			(end 0.12065 0.3048)
			(stroke
				(width 0.1)
				(type default)
			)
			(layer "B.Fab")
		)
		(fp_line
			(start 0.12065 -0.2794)
			(end -0.12065 -0.2794)
			(stroke
				(width 0.1)
				(type default)
			)
			(layer "B.Fab")
		)
		(fp_line
			(start 0.12065 -0.305054)
			(end 0.12065 -0.2794)
			(stroke
				(width 0.1)
				(type default)
			)
			(layer "B.Fab")
		)
		(fp_line
			(start -0.120396 0.3048)
			(end -0.120396 0.2794)
			(stroke
				(width 0.1)
				(type default)
			)
			(layer "B.Fab")
		)
		(fp_line
			(start -0.120396 0.2794)
			(end 0.12065 0.2794)
			(stroke
				(width 0.1)
				(type default)
			)
			(layer "B.Fab")
		)
		(fp_line
			(start -0.12065 -0.2794)
			(end -0.12065 -0.3048)
			(stroke
				(width 0.1)
				(type default)
			)
			(layer "B.Fab")
		)
		(fp_line
			(start -0.12065 -0.3048)
			(end -0.67945 -0.3048)
			(stroke
				(width 0.1)
				(type default)
			)
			(layer "B.Fab")
		)
		(fp_line
			(start -0.67945 0.3048)
			(end -0.120396 0.3048)
			(stroke
				(width 0.1)
				(type default)
			)
			(layer "B.Fab")
		)
		(fp_line
			(start -0.67945 -0.3048)
			(end -0.67945 0.3048)
			(stroke
				(width 0.1)
				(type default)
			)
			(layer "B.Fab")
		)
		(pad "1" smd circle
			(at 0.40005 0)
			(size 0 0)
			(layers "B.Cu" "B.Mask" "B.Paste")
			(net "PVDDCR_CPU1_P0")
		)
		(pad "2" smd circle
			(at -0.40005 0)
			(size 0 0)
			(layers "B.Cu" "B.Mask" "B.Paste")
			(net "GND")
		)
	)
	(footprint ""
		(layer "B.Cu")
		(at 45.928788 -381.6223)
		(property "Reference" "C7022"
			(at 0 0 0)
			(layer "B.SilkS")
			(hide yes)
			(effects
				(font
					(size 1.27 1.27)
				)
				(justify mirror)
			)
		)
		(property "Value" ""
			(at 0 0 0)
			(layer "B.Fab")
			(effects
				(font
					(size 1.27 1.27)
				)
				(justify mirror)
			)
		)
		(duplicate_pad_numbers_are_jumpers no)
		(fp_line
			(start -1.524 -0.762)
			(end -1.524 0.762)
			(stroke
				(width 0.1524)
				(type default)
			)
			(layer "B.SilkS")
		)
		(fp_line
			(start -1.524 0.762)
			(end 1.524 0.762)
			(stroke
				(width 0.1524)
				(type default)
			)
			(layer "B.SilkS")
		)
		(fp_line
			(start 1.524 -0.762)
			(end -1.524 -0.762)
			(stroke
				(width 0.1524)
				(type default)
			)
			(layer "B.SilkS")
		)
		(fp_line
			(start 1.524 0.762)
			(end 1.524 -0.762)
			(stroke
				(width 0.1524)
				(type default)
			)
			(layer "B.SilkS")
		)
		(fp_line
			(start -1.1049 -0.724916)
			(end 1.1049 -0.724916)
			(stroke
				(width 0.1)
				(type default)
			)
			(layer "B.Fab")
		)
		(fp_line
			(start -1.1049 0.724916)
			(end -1.1049 -0.724916)
			(stroke
				(width 0.1)
				(type default)
			)
			(layer "B.Fab")
		)
		(fp_line
			(start 1.1049 -0.724916)
			(end 1.1049 0.724916)
			(stroke
				(width 0.1)
				(type default)
			)
			(layer "B.Fab")
		)
		(fp_line
			(start 1.1049 0.724916)
			(end -1.1049 0.724916)
			(stroke
				(width 0.1)
				(type default)
			)
			(layer "B.Fab")
		)
		(pad "1" smd rect
			(at 0.889 0)
			(size 1.016 1.27)
			(layers "B.Cu" "B.Mask" "B.Paste")
			(net "P0V9_CPU1_RT0_2A")
		)
		(pad "2" smd rect
			(at -0.889 0)
			(size 1.016 1.27)
			(layers "B.Cu" "B.Mask" "B.Paste")
			(net "GND")
		)
	)
	(footprint ""
		(layer "B.Cu")
		(at 194.094608 -126.833376 -90)
		(property "Reference" "R186"
			(at 0 0 90)
			(layer "B.SilkS")
			(hide yes)
			(effects
				(font
					(size 1.27 1.27)
				)
				(justify mirror)
			)
		)
		(property "Value" ""
			(at 0 0 90)
			(layer "B.Fab")
			(effects
				(font
					(size 1.27 1.27)
				)
				(justify mirror)
			)
		)
		(duplicate_pad_numbers_are_jumpers no)
		(fp_line
			(start -0.7874 0.4064)
			(end 0.7874 0.4064)
			(stroke
				(width 0.1524)
				(type default)
			)
			(layer "B.SilkS")
		)
		(fp_line
			(start 0.7874 0.4064)
			(end 0.7874 -0.4064)
			(stroke
				(width 0.1524)
				(type default)
			)
			(layer "B.SilkS")
		)
		(fp_line
			(start -0.7874 -0.4064)
			(end -0.7874 0.4064)
			(stroke
				(width 0.1524)
				(type default)
			)
			(layer "B.SilkS")
		)
		(fp_line
			(start 0.7874 -0.4064)
			(end -0.7874 -0.4064)
			(stroke
				(width 0.1524)
				(type default)
			)
			(layer "B.SilkS")
		)
		(fp_line
			(start -0.67945 0.3048)
			(end -0.120396 0.3048)
			(stroke
				(width 0.1)
				(type default)
			)
			(layer "B.Fab")
		)
		(fp_line
			(start -0.120396 0.3048)
			(end -0.120396 0.2794)
			(stroke
				(width 0.1)
				(type default)
			)
			(layer "B.Fab")
		)
		(fp_line
			(start 0.12065 0.3048)
			(end 0.67945 0.3048)
			(stroke
				(width 0.1)
				(type default)
			)
			(layer "B.Fab")
		)
		(fp_line
			(start 0.67945 0.3048)
			(end 0.67945 -0.305054)
			(stroke
				(width 0.1)
				(type default)
			)
			(layer "B.Fab")
		)
		(fp_line
			(start -0.120396 0.2794)
			(end 0.12065 0.2794)
			(stroke
				(width 0.1)
				(type default)
			)
			(layer "B.Fab")
		)
		(fp_line
			(start 0.12065 0.2794)
			(end 0.12065 0.3048)
			(stroke
				(width 0.1)
				(type default)
			)
			(layer "B.Fab")
		)
		(fp_line
			(start -0.12065 -0.2794)
			(end -0.12065 -0.3048)
			(stroke
				(width 0.1)
				(type default)
			)
			(layer "B.Fab")
		)
		(fp_line
			(start 0.12065 -0.2794)
			(end -0.12065 -0.2794)
			(stroke
				(width 0.1)
				(type default)
			)
			(layer "B.Fab")
		)
		(fp_line
			(start -0.67945 -0.3048)
			(end -0.67945 0.3048)
			(stroke
				(width 0.1)
				(type default)
			)
			(layer "B.Fab")
		)
		(fp_line
			(start -0.12065 -0.3048)
			(end -0.67945 -0.3048)
			(stroke
				(width 0.1)
				(type default)
			)
			(layer "B.Fab")
		)
		(fp_line
			(start 0.12065 -0.305054)
			(end 0.12065 -0.2794)
			(stroke
				(width 0.1)
				(type default)
			)
			(layer "B.Fab")
		)
		(fp_line
			(start 0.67945 -0.305054)
			(end 0.12065 -0.305054)
			(stroke
				(width 0.1)
				(type default)
			)
			(layer "B.Fab")
		)
		(pad "1" smd circle
			(at 0.40005 0 90)
			(size 0 0)
			(layers "B.Cu" "B.Mask" "B.Paste")
			(net "FM_CPU0_FORCE_SELFREFRESH")
		)
		(pad "2" smd circle
			(at -0.40005 0 90)
			(size 0 0)
			(layers "B.Cu" "B.Mask" "B.Paste")
			(net "CPU0_FORCE_SELFREFRESH")
		)
	)
	(footprint ""
		(layer "B.Cu")
		(at 363.804454 -264.35431)
		(property "Reference" "C2138"
			(at 0 0 0)
			(layer "B.SilkS")
			(hide yes)
			(effects
				(font
					(size 1.27 1.27)
				)
				(justify mirror)
			)
		)
		(property "Value" ""
			(at 0 0 0)
			(layer "B.Fab")
			(effects
				(font
					(size 1.27 1.27)
				)
				(justify mirror)
			)
		)
		(duplicate_pad_numbers_are_jumpers no)
		(fp_line
			(start -0.7874 -0.4064)
			(end -0.7874 0.4064)
			(stroke
				(width 0.1524)
				(type default)
			)
			(layer "B.SilkS")
		)
		(fp_line
			(start -0.7874 0.4064)
			(end 0.7874 0.4064)
			(stroke
				(width 0.1524)
				(type default)
			)
			(layer "B.SilkS")
		)
		(fp_line
			(start 0.7874 -0.4064)
			(end -0.7874 -0.4064)
			(stroke
				(width 0.1524)
				(type default)
			)
			(layer "B.SilkS")
		)
		(fp_line
			(start 0.7874 0.4064)
			(end 0.7874 -0.4064)
			(stroke
				(width 0.1524)
				(type default)
			)
			(layer "B.SilkS")
		)
		(fp_line
			(start -0.67945 -0.3048)
			(end -0.67945 0.3048)
			(stroke
				(width 0.1)
				(type default)
			)
			(layer "B.Fab")
		)
		(fp_line
			(start -0.67945 0.3048)
			(end -0.120396 0.3048)
			(stroke
				(width 0.1)
				(type default)
			)
			(layer "B.Fab")
		)
		(fp_line
			(start -0.12065 -0.3048)
			(end -0.67945 -0.3048)
			(stroke
				(width 0.1)
				(type default)
			)
			(layer "B.Fab")
		)
		(fp_line
			(start -0.12065 -0.2794)
			(end -0.12065 -0.3048)
			(stroke
				(width 0.1)
				(type default)
			)
			(layer "B.Fab")
		)
		(fp_line
			(start -0.120396 0.2794)
			(end 0.12065 0.2794)
			(stroke
				(width 0.1)
				(type default)
			)
			(layer "B.Fab")
		)
		(fp_line
			(start -0.120396 0.3048)
			(end -0.120396 0.2794)
			(stroke
				(width 0.1)
				(type default)
			)
			(layer "B.Fab")
		)
		(fp_line
			(start 0.12065 -0.305054)
			(end 0.12065 -0.2794)
			(stroke
				(width 0.1)
				(type default)
			)
			(layer "B.Fab")
		)
		(fp_line
			(start 0.12065 -0.2794)
			(end -0.12065 -0.2794)
			(stroke
				(width 0.1)
				(type default)
			)
			(layer "B.Fab")
		)
		(fp_line
			(start 0.12065 0.2794)
			(end 0.12065 0.3048)
			(stroke
				(width 0.1)
				(type default)
			)
			(layer "B.Fab")
		)
		(fp_line
			(start 0.12065 0.3048)
			(end 0.67945 0.3048)
			(stroke
				(width 0.1)
				(type default)
			)
			(layer "B.Fab")
		)
		(fp_line
			(start 0.67945 -0.305054)
			(end 0.12065 -0.305054)
			(stroke
				(width 0.1)
				(type default)
			)
			(layer "B.Fab")
		)
		(fp_line
			(start 0.67945 0.3048)
			(end 0.67945 -0.305054)
			(stroke
				(width 0.1)
				(type default)
			)
			(layer "B.Fab")
		)
		(pad "1" smd circle
			(at 0.40005 0 180)
			(size 0 0)
			(layers "B.Cu" "B.Mask" "B.Paste")
			(net "PVDD11_S3_P0")
		)
		(pad "2" smd circle
			(at -0.40005 0 180)
			(size 0 0)
			(layers "B.Cu" "B.Mask" "B.Paste")
			(net "GND")
		)
	)
	(footprint ""
		(layer "B.Cu")
		(at 8.19277 -113.161826)
		(property "Reference" "R5238"
			(at 0 0 0)
			(layer "B.SilkS")
			(hide yes)
			(effects
				(font
					(size 1.27 1.27)
				)
				(justify mirror)
			)
		)
		(property "Value" ""
			(at 0 0 0)
			(layer "B.Fab")
			(effects
				(font
					(size 1.27 1.27)
				)
				(justify mirror)
			)
		)
		(duplicate_pad_numbers_are_jumpers no)
		(fp_line
			(start -0.7874 -0.4064)
			(end -0.7874 0.4064)
			(stroke
				(width 0.1524)
				(type default)
			)
			(layer "B.SilkS")
		)
		(fp_line
			(start -0.7874 0.4064)
			(end 0.7874 0.4064)
			(stroke
				(width 0.1524)
				(type default)
			)
			(layer "B.SilkS")
		)
		(fp_line
			(start 0.7874 -0.4064)
			(end -0.7874 -0.4064)
			(stroke
				(width 0.1524)
				(type default)
			)
			(layer "B.SilkS")
		)
		(fp_line
			(start 0.7874 0.4064)
			(end 0.7874 -0.4064)
			(stroke
				(width 0.1524)
				(type default)
			)
			(layer "B.SilkS")
		)
		(fp_line
			(start -0.67945 -0.3048)
			(end -0.67945 0.3048)
			(stroke
				(width 0.1)
				(type default)
			)
			(layer "B.Fab")
		)
		(fp_line
			(start -0.67945 0.3048)
			(end -0.120396 0.3048)
			(stroke
				(width 0.1)
				(type default)
			)
			(layer "B.Fab")
		)
		(fp_line
			(start -0.12065 -0.3048)
			(end -0.67945 -0.3048)
			(stroke
				(width 0.1)
				(type default)
			)
			(layer "B.Fab")
		)
		(fp_line
			(start -0.12065 -0.2794)
			(end -0.12065 -0.3048)
			(stroke
				(width 0.1)
				(type default)
			)
			(layer "B.Fab")
		)
		(fp_line
			(start -0.120396 0.2794)
			(end 0.12065 0.2794)
			(stroke
				(width 0.1)
				(type default)
			)
			(layer "B.Fab")
		)
		(fp_line
			(start -0.120396 0.3048)
			(end -0.120396 0.2794)
			(stroke
				(width 0.1)
				(type default)
			)
			(layer "B.Fab")
		)
		(fp_line
			(start 0.12065 -0.305054)
			(end 0.12065 -0.2794)
			(stroke
				(width 0.1)
				(type default)
			)
			(layer "B.Fab")
		)
		(fp_line
			(start 0.12065 -0.2794)
			(end -0.12065 -0.2794)
			(stroke
				(width 0.1)
				(type default)
			)
			(layer "B.Fab")
		)
		(fp_line
			(start 0.12065 0.2794)
			(end 0.12065 0.3048)
			(stroke
				(width 0.1)
				(type default)
			)
			(layer "B.Fab")
		)
		(fp_line
			(start 0.12065 0.3048)
			(end 0.67945 0.3048)
			(stroke
				(width 0.1)
				(type default)
			)
			(layer "B.Fab")
		)
		(fp_line
			(start 0.67945 -0.305054)
			(end 0.12065 -0.305054)
			(stroke
				(width 0.1)
				(type default)
			)
			(layer "B.Fab")
		)
		(fp_line
			(start 0.67945 0.3048)
			(end 0.67945 -0.305054)
			(stroke
				(width 0.1)
				(type default)
			)
			(layer "B.Fab")
		)
		(pad "1" smd circle
			(at 0.40005 0 180)
			(size 0 0)
			(layers "B.Cu" "B.Mask" "B.Paste")
			(net "PD_U5201_EQ")
		)
		(pad "2" smd circle
			(at -0.40005 0 180)
			(size 0 0)
			(layers "B.Cu" "B.Mask" "B.Paste")
			(net "GND")
		)
	)
	(footprint ""
		(layer "B.Cu")
		(at 175.387 -425.45 90)
		(property "Reference" "U6004"
			(at 4.09067 -0.172974 0)
			(unlocked yes)
			(layer "B.SilkS")
			(effects
				(font
					(size 0.7874 0.5842)
					(thickness 0.1524)
				)
				(justify left mirror)
			)
		)
		(property "Value" ""
			(at 0 0 90)
			(layer "B.Fab")
			(effects
				(font
					(size 1.27 1.27)
				)
				(justify mirror)
			)
		)
		(duplicate_pad_numbers_are_jumpers no)
		(fp_line
			(start 1.603248 -1.500124)
			(end -1.603248 -1.500124)
			(stroke
				(width 0.1524)
				(type default)
			)
			(layer "B.SilkS")
		)
		(fp_line
			(start -1.603248 -1.500124)
			(end -1.603248 1.500124)
			(stroke
				(width 0.1524)
				(type default)
			)
			(layer "B.SilkS")
		)
		(fp_line
			(start 1.603248 1.500124)
			(end 1.603248 -1.500124)
			(stroke
				(width 0.1524)
				(type default)
			)
			(layer "B.SilkS")
		)
		(fp_line
			(start -1.603248 1.500124)
			(end 1.603248 1.500124)
			(stroke
				(width 0.1524)
				(type default)
			)
			(layer "B.SilkS")
		)
		(fp_line
			(start 0.700024 -1.500124)
			(end 0.700024 -1.169924)
			(stroke
				(width 0.1)
				(type default)
			)
			(layer "B.Fab")
		)
		(fp_line
			(start -0.700024 -1.500124)
			(end 0.700024 -1.500124)
			(stroke
				(width 0.1)
				(type default)
			)
			(layer "B.Fab")
		)
		(fp_line
			(start 1.249934 -1.169924)
			(end 1.249934 -0.729996)
			(stroke
				(width 0.1)
				(type default)
			)
			(layer "B.Fab")
		)
		(fp_line
			(start 0.700024 -1.169924)
			(end 1.249934 -1.169924)
			(stroke
				(width 0.1)
				(type default)
			)
			(layer "B.Fab")
		)
		(fp_line
			(start 1.249934 -0.729996)
			(end 0.6985 -0.729996)
			(stroke
				(width 0.1)
				(type default)
			)
			(layer "B.Fab")
		)
		(fp_line
			(start 0.6985 -0.729996)
			(end 0.6985 0.729996)
			(stroke
				(width 0.1)
				(type default)
			)
			(layer "B.Fab")
		)
		(fp_line
			(start -0.700024 -0.219964)
			(end -0.700024 -1.500124)
			(stroke
				(width 0.1)
				(type default)
			)
			(layer "B.Fab")
		)
		(fp_line
			(start -1.249934 -0.219964)
			(end -0.700024 -0.219964)
			(stroke
				(width 0.1)
				(type default)
			)
			(layer "B.Fab")
		)
		(fp_line
			(start -0.700024 0.219964)
			(end -1.249934 0.219964)
			(stroke
				(width 0.1)
				(type default)
			)
			(layer "B.Fab")
		)
		(fp_line
			(start -1.249934 0.219964)
			(end -1.249934 -0.219964)
			(stroke
				(width 0.1)
				(type default)
			)
			(layer "B.Fab")
		)
		(fp_line
			(start 1.249934 0.729996)
			(end 1.249934 1.169924)
			(stroke
				(width 0.1)
				(type default)
			)
			(layer "B.Fab")
		)
		(fp_line
			(start 0.6985 0.729996)
			(end 1.249934 0.729996)
			(stroke
				(width 0.1)
				(type default)
			)
			(layer "B.Fab")
		)
		(fp_line
			(start 1.249934 1.169924)
			(end 0.700024 1.169924)
			(stroke
				(width 0.1)
				(type default)
			)
			(layer "B.Fab")
		)
		(fp_line
			(start 0.700024 1.169924)
			(end 0.700024 1.500124)
			(stroke
				(width 0.1)
				(type default)
			)
			(layer "B.Fab")
		)
		(fp_line
			(start 0.700024 1.500124)
			(end -0.700024 1.500124)
			(stroke
				(width 0.1)
				(type default)
			)
			(layer "B.Fab")
		)
		(fp_line
			(start -0.700024 1.500124)
			(end -0.700024 0.219964)
			(stroke
				(width 0.1)
				(type default)
			)
			(layer "B.Fab")
		)
		(fp_rect
			(start 0.700024 1.500124)
			(end -0.700024 -1.500124)
			(stroke
				(width 0)
				(type default)
			)
			(fill no)
			(layer "B.Fab")
		)
		(pad "D" smd rect
			(at -0.999998 0)
			(size 0.8128 0.9144)
			(layers "B.Cu" "B.Mask" "B.Paste")
			(net "A_HSC_LOW_DRAIN")
		)
		(pad "G" smd rect
			(at 0.999998 -0.94996)
			(size 0.8128 0.9144)
			(layers "B.Cu" "B.Mask" "B.Paste")
			(net "A_HSC_LOW_GATE")
		)
		(pad "S" smd rect
			(at 0.999998 0.94996)
			(size 0.8128 0.9144)
			(layers "B.Cu" "B.Mask" "B.Paste")
			(net "GND")
		)
	)
	(footprint ""
		(layer "B.Cu")
		(at 148.122386 -313.45505 180)
		(property "Reference" "R571"
			(at 0 0 0)
			(layer "B.SilkS")
			(hide yes)
			(effects
				(font
					(size 1.27 1.27)
				)
				(justify mirror)
			)
		)
		(property "Value" ""
			(at 0 0 0)
			(layer "B.Fab")
			(effects
				(font
					(size 1.27 1.27)
				)
				(justify mirror)
			)
		)
		(duplicate_pad_numbers_are_jumpers no)
		(fp_line
			(start 0.7874 0.4064)
			(end 0.7874 -0.4064)
			(stroke
				(width 0.1524)
				(type default)
			)
			(layer "B.SilkS")
		)
		(fp_line
			(start 0.7874 -0.4064)
			(end -0.7874 -0.4064)
			(stroke
				(width 0.1524)
				(type default)
			)
			(layer "B.SilkS")
		)
		(fp_line
			(start -0.7874 0.4064)
			(end 0.7874 0.4064)
			(stroke
				(width 0.1524)
				(type default)
			)
			(layer "B.SilkS")
		)
		(fp_line
			(start -0.7874 -0.4064)
			(end -0.7874 0.4064)
			(stroke
				(width 0.1524)
				(type default)
			)
			(layer "B.SilkS")
		)
		(fp_line
			(start 0.67945 0.3048)
			(end 0.67945 -0.305054)
			(stroke
				(width 0.1)
				(type default)
			)
			(layer "B.Fab")
		)
		(fp_line
			(start 0.67945 -0.305054)
			(end 0.12065 -0.305054)
			(stroke
				(width 0.1)
				(type default)
			)
			(layer "B.Fab")
		)
		(fp_line
			(start 0.12065 0.3048)
			(end 0.67945 0.3048)
			(stroke
				(width 0.1)
				(type default)
			)
			(layer "B.Fab")
		)
		(fp_line
			(start 0.12065 0.2794)
			(end 0.12065 0.3048)
			(stroke
				(width 0.1)
				(type default)
			)
			(layer "B.Fab")
		)
		(fp_line
			(start 0.12065 -0.2794)
			(end -0.12065 -0.2794)
			(stroke
				(width 0.1)
				(type default)
			)
			(layer "B.Fab")
		)
		(fp_line
			(start 0.12065 -0.305054)
			(end 0.12065 -0.2794)
			(stroke
				(width 0.1)
				(type default)
			)
			(layer "B.Fab")
		)
		(fp_line
			(start -0.120396 0.3048)
			(end -0.120396 0.2794)
			(stroke
				(width 0.1)
				(type default)
			)
			(layer "B.Fab")
		)
		(fp_line
			(start -0.120396 0.2794)
			(end 0.12065 0.2794)
			(stroke
				(width 0.1)
				(type default)
			)
			(layer "B.Fab")
		)
		(fp_line
			(start -0.12065 -0.2794)
			(end -0.12065 -0.3048)
			(stroke
				(width 0.1)
				(type default)
			)
			(layer "B.Fab")
		)
		(fp_line
			(start -0.12065 -0.3048)
			(end -0.67945 -0.3048)
			(stroke
				(width 0.1)
				(type default)
			)
			(layer "B.Fab")
		)
		(fp_line
			(start -0.67945 0.3048)
			(end -0.120396 0.3048)
			(stroke
				(width 0.1)
				(type default)
			)
			(layer "B.Fab")
		)
		(fp_line
			(start -0.67945 -0.3048)
			(end -0.67945 0.3048)
			(stroke
				(width 0.1)
				(type default)
			)
			(layer "B.Fab")
		)
		(pad "1" smd circle
			(at 0.40005 0)
			(size 0 0)
			(layers "B.Cu" "B.Mask" "B.Paste")
			(net "XTAL_CPU1_X48M_X1")
		)
		(pad "2" smd circle
			(at -0.40005 0)
			(size 0 0)
			(layers "B.Cu" "B.Mask" "B.Paste")
			(net "XTAL_CPU1_X48M_X2_R")
		)
	)
	(footprint ""
		(layer "B.Cu")
		(at 149.718776 -17.693894 -90)
		(property "Reference" "R2213"
			(at 0 0 90)
			(layer "B.SilkS")
			(hide yes)
			(effects
				(font
					(size 1.27 1.27)
				)
				(justify mirror)
			)
		)
		(property "Value" ""
			(at 0 0 90)
			(layer "B.Fab")
			(effects
				(font
					(size 1.27 1.27)
				)
				(justify mirror)
			)
		)
		(duplicate_pad_numbers_are_jumpers no)
		(fp_line
			(start -0.7874 0.4064)
			(end 0.7874 0.4064)
			(stroke
				(width 0.1524)
				(type default)
			)
			(layer "B.SilkS")
		)
		(fp_line
			(start 0.7874 0.4064)
			(end 0.7874 -0.4064)
			(stroke
				(width 0.1524)
				(type default)
			)
			(layer "B.SilkS")
		)
		(fp_line
			(start -0.7874 -0.4064)
			(end -0.7874 0.4064)
			(stroke
				(width 0.1524)
				(type default)
			)
			(layer "B.SilkS")
		)
		(fp_line
			(start 0.7874 -0.4064)
			(end -0.7874 -0.4064)
			(stroke
				(width 0.1524)
				(type default)
			)
			(layer "B.SilkS")
		)
		(fp_line
			(start -0.67945 0.3048)
			(end -0.120396 0.3048)
			(stroke
				(width 0.1)
				(type default)
			)
			(layer "B.Fab")
		)
		(fp_line
			(start -0.120396 0.3048)
			(end -0.120396 0.2794)
			(stroke
				(width 0.1)
				(type default)
			)
			(layer "B.Fab")
		)
		(fp_line
			(start 0.12065 0.3048)
			(end 0.67945 0.3048)
			(stroke
				(width 0.1)
				(type default)
			)
			(layer "B.Fab")
		)
		(fp_line
			(start 0.67945 0.3048)
			(end 0.67945 -0.305054)
			(stroke
				(width 0.1)
				(type default)
			)
			(layer "B.Fab")
		)
		(fp_line
			(start -0.120396 0.2794)
			(end 0.12065 0.2794)
			(stroke
				(width 0.1)
				(type default)
			)
			(layer "B.Fab")
		)
		(fp_line
			(start 0.12065 0.2794)
			(end 0.12065 0.3048)
			(stroke
				(width 0.1)
				(type default)
			)
			(layer "B.Fab")
		)
		(fp_line
			(start -0.12065 -0.2794)
			(end -0.12065 -0.3048)
			(stroke
				(width 0.1)
				(type default)
			)
			(layer "B.Fab")
		)
		(fp_line
			(start 0.12065 -0.2794)
			(end -0.12065 -0.2794)
			(stroke
				(width 0.1)
				(type default)
			)
			(layer "B.Fab")
		)
		(fp_line
			(start -0.67945 -0.3048)
			(end -0.67945 0.3048)
			(stroke
				(width 0.1)
				(type default)
			)
			(layer "B.Fab")
		)
		(fp_line
			(start -0.12065 -0.3048)
			(end -0.67945 -0.3048)
			(stroke
				(width 0.1)
				(type default)
			)
			(layer "B.Fab")
		)
		(fp_line
			(start 0.12065 -0.305054)
			(end 0.12065 -0.2794)
			(stroke
				(width 0.1)
				(type default)
			)
			(layer "B.Fab")
		)
		(fp_line
			(start 0.67945 -0.305054)
			(end 0.12065 -0.305054)
			(stroke
				(width 0.1)
				(type default)
			)
			(layer "B.Fab")
		)
		(pad "1" smd circle
			(at 0.40005 0 90)
			(size 0 0)
			(layers "B.Cu" "B.Mask" "B.Paste")
			(net "SMB_HOST_CLK_3V3AUX_SDA")
		)
		(pad "2" smd circle
			(at -0.40005 0 90)
			(size 0 0)
			(layers "B.Cu" "B.Mask" "B.Paste")
			(net "P3V3_AUX")
		)
	)
	(footprint ""
		(layer "B.Cu")
		(at 359.416096 -256.012188 -90)
		(property "Reference" "C3925"
			(at 0 0 90)
			(layer "B.SilkS")
			(hide yes)
			(effects
				(font
					(size 1.27 1.27)
				)
				(justify mirror)
			)
		)
		(property "Value" ""
			(at 0 0 90)
			(layer "B.Fab")
			(effects
				(font
					(size 1.27 1.27)
				)
				(justify mirror)
			)
		)
		(duplicate_pad_numbers_are_jumpers no)
		(fp_line
			(start -0.7874 0.4064)
			(end 0.7874 0.4064)
			(stroke
				(width 0.1524)
				(type default)
			)
			(layer "B.SilkS")
		)
		(fp_line
			(start 0.7874 0.4064)
			(end 0.7874 -0.4064)
			(stroke
				(width 0.1524)
				(type default)
			)
			(layer "B.SilkS")
		)
		(fp_line
			(start -0.7874 -0.4064)
			(end -0.7874 0.4064)
			(stroke
				(width 0.1524)
				(type default)
			)
			(layer "B.SilkS")
		)
		(fp_line
			(start 0.7874 -0.4064)
			(end -0.7874 -0.4064)
			(stroke
				(width 0.1524)
				(type default)
			)
			(layer "B.SilkS")
		)
		(fp_line
			(start -0.67945 0.3048)
			(end -0.120396 0.3048)
			(stroke
				(width 0.1)
				(type default)
			)
			(layer "B.Fab")
		)
		(fp_line
			(start -0.120396 0.3048)
			(end -0.120396 0.2794)
			(stroke
				(width 0.1)
				(type default)
			)
			(layer "B.Fab")
		)
		(fp_line
			(start 0.12065 0.3048)
			(end 0.67945 0.3048)
			(stroke
				(width 0.1)
				(type default)
			)
			(layer "B.Fab")
		)
		(fp_line
			(start 0.67945 0.3048)
			(end 0.67945 -0.305054)
			(stroke
				(width 0.1)
				(type default)
			)
			(layer "B.Fab")
		)
		(fp_line
			(start -0.120396 0.2794)
			(end 0.12065 0.2794)
			(stroke
				(width 0.1)
				(type default)
			)
			(layer "B.Fab")
		)
		(fp_line
			(start 0.12065 0.2794)
			(end 0.12065 0.3048)
			(stroke
				(width 0.1)
				(type default)
			)
			(layer "B.Fab")
		)
		(fp_line
			(start -0.12065 -0.2794)
			(end -0.12065 -0.3048)
			(stroke
				(width 0.1)
				(type default)
			)
			(layer "B.Fab")
		)
		(fp_line
			(start 0.12065 -0.2794)
			(end -0.12065 -0.2794)
			(stroke
				(width 0.1)
				(type default)
			)
			(layer "B.Fab")
		)
		(fp_line
			(start -0.67945 -0.3048)
			(end -0.67945 0.3048)
			(stroke
				(width 0.1)
				(type default)
			)
			(layer "B.Fab")
		)
		(fp_line
			(start -0.12065 -0.3048)
			(end -0.67945 -0.3048)
			(stroke
				(width 0.1)
				(type default)
			)
			(layer "B.Fab")
		)
		(fp_line
			(start 0.12065 -0.305054)
			(end 0.12065 -0.2794)
			(stroke
				(width 0.1)
				(type default)
			)
			(layer "B.Fab")
		)
		(fp_line
			(start 0.67945 -0.305054)
			(end 0.12065 -0.305054)
			(stroke
				(width 0.1)
				(type default)
			)
			(layer "B.Fab")
		)
		(pad "1" smd circle
			(at 0.40005 0 90)
			(size 0 0)
			(layers "B.Cu" "B.Mask" "B.Paste")
			(net "PVDDCR_SOC_P0")
		)
		(pad "2" smd circle
			(at -0.40005 0 90)
			(size 0 0)
			(layers "B.Cu" "B.Mask" "B.Paste")
			(net "GND")
		)
	)
	(footprint ""
		(layer "B.Cu")
		(at 352.120454 -268.41831)
		(property "Reference" "C2220"
			(at 0 0 0)
			(layer "B.SilkS")
			(hide yes)
			(effects
				(font
					(size 1.27 1.27)
				)
				(justify mirror)
			)
		)
		(property "Value" ""
			(at 0 0 0)
			(layer "B.Fab")
			(effects
				(font
					(size 1.27 1.27)
				)
				(justify mirror)
			)
		)
		(duplicate_pad_numbers_are_jumpers no)
		(fp_line
			(start -0.7874 -0.4064)
			(end -0.7874 0.4064)
			(stroke
				(width 0.1524)
				(type default)
			)
			(layer "B.SilkS")
		)
		(fp_line
			(start -0.7874 0.4064)
			(end 0.7874 0.4064)
			(stroke
				(width 0.1524)
				(type default)
			)
			(layer "B.SilkS")
		)
		(fp_line
			(start 0.7874 -0.4064)
			(end -0.7874 -0.4064)
			(stroke
				(width 0.1524)
				(type default)
			)
			(layer "B.SilkS")
		)
		(fp_line
			(start 0.7874 0.4064)
			(end 0.7874 -0.4064)
			(stroke
				(width 0.1524)
				(type default)
			)
			(layer "B.SilkS")
		)
		(fp_line
			(start -0.67945 -0.3048)
			(end -0.67945 0.3048)
			(stroke
				(width 0.1)
				(type default)
			)
			(layer "B.Fab")
		)
		(fp_line
			(start -0.67945 0.3048)
			(end -0.120396 0.3048)
			(stroke
				(width 0.1)
				(type default)
			)
			(layer "B.Fab")
		)
		(fp_line
			(start -0.12065 -0.3048)
			(end -0.67945 -0.3048)
			(stroke
				(width 0.1)
				(type default)
			)
			(layer "B.Fab")
		)
		(fp_line
			(start -0.12065 -0.2794)
			(end -0.12065 -0.3048)
			(stroke
				(width 0.1)
				(type default)
			)
			(layer "B.Fab")
		)
		(fp_line
			(start -0.120396 0.2794)
			(end 0.12065 0.2794)
			(stroke
				(width 0.1)
				(type default)
			)
			(layer "B.Fab")
		)
		(fp_line
			(start -0.120396 0.3048)
			(end -0.120396 0.2794)
			(stroke
				(width 0.1)
				(type default)
			)
			(layer "B.Fab")
		)
		(fp_line
			(start 0.12065 -0.305054)
			(end 0.12065 -0.2794)
			(stroke
				(width 0.1)
				(type default)
			)
			(layer "B.Fab")
		)
		(fp_line
			(start 0.12065 -0.2794)
			(end -0.12065 -0.2794)
			(stroke
				(width 0.1)
				(type default)
			)
			(layer "B.Fab")
		)
		(fp_line
			(start 0.12065 0.2794)
			(end 0.12065 0.3048)
			(stroke
				(width 0.1)
				(type default)
			)
			(layer "B.Fab")
		)
		(fp_line
			(start 0.12065 0.3048)
			(end 0.67945 0.3048)
			(stroke
				(width 0.1)
				(type default)
			)
			(layer "B.Fab")
		)
		(fp_line
			(start 0.67945 -0.305054)
			(end 0.12065 -0.305054)
			(stroke
				(width 0.1)
				(type default)
			)
			(layer "B.Fab")
		)
		(fp_line
			(start 0.67945 0.3048)
			(end 0.67945 -0.305054)
			(stroke
				(width 0.1)
				(type default)
			)
			(layer "B.Fab")
		)
		(pad "1" smd circle
			(at 0.40005 0 180)
			(size 0 0)
			(layers "B.Cu" "B.Mask" "B.Paste")
			(net "PVDDCR_CPU1_P0")
		)
		(pad "2" smd circle
			(at -0.40005 0 180)
			(size 0 0)
			(layers "B.Cu" "B.Mask" "B.Paste")
			(net "GND")
		)
	)
	(footprint ""
		(layer "B.Cu")
		(at 156.60624 -386.766562 90)
		(property "Reference" "C380"
			(at 0 0 90)
			(layer "B.SilkS")
			(hide yes)
			(effects
				(font
					(size 1.27 1.27)
				)
				(justify mirror)
			)
		)
		(property "Value" ""
			(at 0 0 90)
			(layer "B.Fab")
			(effects
				(font
					(size 1.27 1.27)
				)
				(justify mirror)
			)
		)
		(duplicate_pad_numbers_are_jumpers no)
		(fp_line
			(start 0.299974 -0.150114)
			(end -0.299974 -0.150114)
			(stroke
				(width 0.1)
				(type default)
			)
			(layer "B.Fab")
		)
		(fp_line
			(start -0.299974 -0.150114)
			(end -0.299974 0.150114)
			(stroke
				(width 0.1)
				(type default)
			)
			(layer "B.Fab")
		)
		(fp_line
			(start 0.299974 0.150114)
			(end 0.299974 -0.150114)
			(stroke
				(width 0.1)
				(type default)
			)
			(layer "B.Fab")
		)
		(fp_line
			(start -0.299974 0.150114)
			(end 0.299974 0.150114)
			(stroke
				(width 0.1)
				(type default)
			)
			(layer "B.Fab")
		)
		(pad "1" smd rect
			(at 0.2667 0 270)
			(size 0.3048 0.381)
			(layers "B.Cu" "B.Mask" "B.Paste")
			(net "P1V8_CPU1_RT2_1A")
		)
		(pad "2" smd rect
			(at -0.2667 0 270)
			(size 0.3048 0.381)
			(layers "B.Cu" "B.Mask" "B.Paste")
			(net "GND")
		)
	)
	(footprint ""
		(layer "B.Cu")
		(at 424.664124 -428.118524 90)
		(property "Reference" "R1432"
			(at 0 0 90)
			(layer "B.SilkS")
			(hide yes)
			(effects
				(font
					(size 1.27 1.27)
				)
				(justify mirror)
			)
		)
		(property "Value" ""
			(at 0 0 90)
			(layer "B.Fab")
			(effects
				(font
					(size 1.27 1.27)
				)
				(justify mirror)
			)
		)
		(duplicate_pad_numbers_are_jumpers no)
		(fp_line
			(start 0.32512 -0.175006)
			(end -0.32512 -0.175006)
			(stroke
				(width 0.1)
				(type default)
			)
			(layer "B.Fab")
		)
		(fp_line
			(start -0.32512 -0.175006)
			(end -0.32512 0.175006)
			(stroke
				(width 0.1)
				(type default)
			)
			(layer "B.Fab")
		)
		(fp_line
			(start 0.32512 0.175006)
			(end 0.32512 -0.175006)
			(stroke
				(width 0.1)
				(type default)
			)
			(layer "B.Fab")
		)
		(fp_line
			(start -0.32512 0.175006)
			(end 0.32512 0.175006)
			(stroke
				(width 0.1)
				(type default)
			)
			(layer "B.Fab")
		)
		(pad "1" smd rect
			(at 0.2667 0 270)
			(size 0.3048 0.381)
			(layers "B.Cu" "B.Mask" "B.Paste")
			(net "P1V8_CPU0_RT_1D")
		)
		(pad "2" smd rect
			(at -0.2667 0 90)
			(size 0.3048 0.381)
			(layers "B.Cu" "B.Mask" "B.Paste")
			(net "SMB_RT_CPU0_P2_ROM_MUX_1D_SCL")
		)
	)
	(footprint ""
		(layer "B.Cu")
		(at 330.523342 -393.96416 180)
		(property "Reference" "R1030"
			(at 0 0 0)
			(layer "B.SilkS")
			(hide yes)
			(effects
				(font
					(size 1.27 1.27)
				)
				(justify mirror)
			)
		)
		(property "Value" ""
			(at 0 0 0)
			(layer "B.Fab")
			(effects
				(font
					(size 1.27 1.27)
				)
				(justify mirror)
			)
		)
		(duplicate_pad_numbers_are_jumpers no)
		(fp_line
			(start 0.32512 0.175006)
			(end 0.32512 -0.175006)
			(stroke
				(width 0.1)
				(type default)
			)
			(layer "B.Fab")
		)
		(fp_line
			(start 0.32512 -0.175006)
			(end -0.32512 -0.175006)
			(stroke
				(width 0.1)
				(type default)
			)
			(layer "B.Fab")
		)
		(fp_line
			(start -0.32512 0.175006)
			(end 0.32512 0.175006)
			(stroke
				(width 0.1)
				(type default)
			)
			(layer "B.Fab")
		)
		(fp_line
			(start -0.32512 -0.175006)
			(end -0.32512 0.175006)
			(stroke
				(width 0.1)
				(type default)
			)
			(layer "B.Fab")
		)
		(pad "1" smd rect
			(at 0.2667 0)
			(size 0.3048 0.381)
			(layers "B.Cu" "B.Mask" "B.Paste")
			(net "P1V8_CPU0_RT_1D")
		)
		(pad "2" smd rect
			(at -0.2667 0 180)
			(size 0.3048 0.381)
			(layers "B.Cu" "B.Mask" "B.Paste")
			(net "TEST0_RT_CPU0_P1")
		)
	)
	(footprint ""
		(layer "B.Cu")
		(at 28.46324 -195.926964 180)
		(property "Reference" "R1701"
			(at 0 0 0)
			(layer "B.SilkS")
			(hide yes)
			(effects
				(font
					(size 1.27 1.27)
				)
				(justify mirror)
			)
		)
		(property "Value" ""
			(at 0 0 0)
			(layer "B.Fab")
			(effects
				(font
					(size 1.27 1.27)
				)
				(justify mirror)
			)
		)
		(duplicate_pad_numbers_are_jumpers no)
		(fp_line
			(start 0.7874 0.4064)
			(end 0.7874 -0.4064)
			(stroke
				(width 0.1524)
				(type default)
			)
			(layer "B.SilkS")
		)
		(fp_line
			(start 0.7874 -0.4064)
			(end -0.7874 -0.4064)
			(stroke
				(width 0.1524)
				(type default)
			)
			(layer "B.SilkS")
		)
		(fp_line
			(start -0.7874 0.4064)
			(end 0.7874 0.4064)
			(stroke
				(width 0.1524)
				(type default)
			)
			(layer "B.SilkS")
		)
		(fp_line
			(start -0.7874 -0.4064)
			(end -0.7874 0.4064)
			(stroke
				(width 0.1524)
				(type default)
			)
			(layer "B.SilkS")
		)
		(fp_line
			(start 0.67945 0.3048)
			(end 0.67945 -0.305054)
			(stroke
				(width 0.1)
				(type default)
			)
			(layer "B.Fab")
		)
		(fp_line
			(start 0.67945 -0.305054)
			(end 0.12065 -0.305054)
			(stroke
				(width 0.1)
				(type default)
			)
			(layer "B.Fab")
		)
		(fp_line
			(start 0.12065 0.3048)
			(end 0.67945 0.3048)
			(stroke
				(width 0.1)
				(type default)
			)
			(layer "B.Fab")
		)
		(fp_line
			(start 0.12065 0.2794)
			(end 0.12065 0.3048)
			(stroke
				(width 0.1)
				(type default)
			)
			(layer "B.Fab")
		)
		(fp_line
			(start 0.12065 -0.2794)
			(end -0.12065 -0.2794)
			(stroke
				(width 0.1)
				(type default)
			)
			(layer "B.Fab")
		)
		(fp_line
			(start 0.12065 -0.305054)
			(end 0.12065 -0.2794)
			(stroke
				(width 0.1)
				(type default)
			)
			(layer "B.Fab")
		)
		(fp_line
			(start -0.120396 0.3048)
			(end -0.120396 0.2794)
			(stroke
				(width 0.1)
				(type default)
			)
			(layer "B.Fab")
		)
		(fp_line
			(start -0.120396 0.2794)
			(end 0.12065 0.2794)
			(stroke
				(width 0.1)
				(type default)
			)
			(layer "B.Fab")
		)
		(fp_line
			(start -0.12065 -0.2794)
			(end -0.12065 -0.3048)
			(stroke
				(width 0.1)
				(type default)
			)
			(layer "B.Fab")
		)
		(fp_line
			(start -0.12065 -0.3048)
			(end -0.67945 -0.3048)
			(stroke
				(width 0.1)
				(type default)
			)
			(layer "B.Fab")
		)
		(fp_line
			(start -0.67945 0.3048)
			(end -0.120396 0.3048)
			(stroke
				(width 0.1)
				(type default)
			)
			(layer "B.Fab")
		)
		(fp_line
			(start -0.67945 -0.3048)
			(end -0.67945 0.3048)
			(stroke
				(width 0.1)
				(type default)
			)
			(layer "B.Fab")
		)
		(pad "1" smd circle
			(at 0.40005 0)
			(size 0 0)
			(layers "B.Cu" "B.Mask" "B.Paste")
			(net "I3C_SPD_DDRAF_CPU1_SDA")
		)
		(pad "2" smd circle
			(at -0.40005 0)
			(size 0 0)
			(layers "B.Cu" "B.Mask" "B.Paste")
			(net "I3C_SPD_DDRE_CPU1_SDA")
		)
	)
	(footprint ""
		(layer "B.Cu")
		(at 56.341264 -408.517344 90)
		(property "Reference" "C6665"
			(at 0 0 90)
			(layer "B.SilkS")
			(hide yes)
			(effects
				(font
					(size 1.27 1.27)
				)
				(justify mirror)
			)
		)
		(property "Value" ""
			(at 0 0 90)
			(layer "B.Fab")
			(effects
				(font
					(size 1.27 1.27)
				)
				(justify mirror)
			)
		)
		(duplicate_pad_numbers_are_jumpers no)
		(fp_line
			(start 0.299974 -0.150114)
			(end -0.299974 -0.150114)
			(stroke
				(width 0.1)
				(type default)
			)
			(layer "B.Fab")
		)
		(fp_line
			(start -0.299974 -0.150114)
			(end -0.299974 0.150114)
			(stroke
				(width 0.1)
				(type default)
			)
			(layer "B.Fab")
		)
		(fp_line
			(start 0.299974 0.150114)
			(end 0.299974 -0.150114)
			(stroke
				(width 0.1)
				(type default)
			)
			(layer "B.Fab")
		)
		(fp_line
			(start -0.299974 0.150114)
			(end 0.299974 0.150114)
			(stroke
				(width 0.1)
				(type default)
			)
			(layer "B.Fab")
		)
		(pad "1" smd rect
			(at 0.2667 0 270)
			(size 0.3048 0.381)
			(layers "B.Cu" "B.Mask" "B.Paste")
			(net "P5E_CPU1_P1_TX_BUF_C_DP<2>")
		)
		(pad "2" smd rect
			(at -0.2667 0 270)
			(size 0.3048 0.381)
			(layers "B.Cu" "B.Mask" "B.Paste")
			(net "P5E_CPU1_P1_TX_BUF_DP<2>")
		)
	)
	(footprint ""
		(layer "B.Cu")
		(at 339.134958 -306.828952 180)
		(property "Reference" "R729"
			(at 0 0 0)
			(layer "B.SilkS")
			(hide yes)
			(effects
				(font
					(size 1.27 1.27)
				)
				(justify mirror)
			)
		)
		(property "Value" ""
			(at 0 0 0)
			(layer "B.Fab")
			(effects
				(font
					(size 1.27 1.27)
				)
				(justify mirror)
			)
		)
		(duplicate_pad_numbers_are_jumpers no)
		(fp_line
			(start 0.7874 0.4064)
			(end 0.7874 -0.4064)
			(stroke
				(width 0.1524)
				(type default)
			)
			(layer "B.SilkS")
		)
		(fp_line
			(start 0.7874 -0.4064)
			(end -0.7874 -0.4064)
			(stroke
				(width 0.1524)
				(type default)
			)
			(layer "B.SilkS")
		)
		(fp_line
			(start -0.7874 0.4064)
			(end 0.7874 0.4064)
			(stroke
				(width 0.1524)
				(type default)
			)
			(layer "B.SilkS")
		)
		(fp_line
			(start -0.7874 -0.4064)
			(end -0.7874 0.4064)
			(stroke
				(width 0.1524)
				(type default)
			)
			(layer "B.SilkS")
		)
		(fp_line
			(start 0.67945 0.3048)
			(end 0.67945 -0.305054)
			(stroke
				(width 0.1)
				(type default)
			)
			(layer "B.Fab")
		)
		(fp_line
			(start 0.67945 -0.305054)
			(end 0.12065 -0.305054)
			(stroke
				(width 0.1)
				(type default)
			)
			(layer "B.Fab")
		)
		(fp_line
			(start 0.12065 0.3048)
			(end 0.67945 0.3048)
			(stroke
				(width 0.1)
				(type default)
			)
			(layer "B.Fab")
		)
		(fp_line
			(start 0.12065 0.2794)
			(end 0.12065 0.3048)
			(stroke
				(width 0.1)
				(type default)
			)
			(layer "B.Fab")
		)
		(fp_line
			(start 0.12065 -0.2794)
			(end -0.12065 -0.2794)
			(stroke
				(width 0.1)
				(type default)
			)
			(layer "B.Fab")
		)
		(fp_line
			(start 0.12065 -0.305054)
			(end 0.12065 -0.2794)
			(stroke
				(width 0.1)
				(type default)
			)
			(layer "B.Fab")
		)
		(fp_line
			(start -0.120396 0.3048)
			(end -0.120396 0.2794)
			(stroke
				(width 0.1)
				(type default)
			)
			(layer "B.Fab")
		)
		(fp_line
			(start -0.120396 0.2794)
			(end 0.12065 0.2794)
			(stroke
				(width 0.1)
				(type default)
			)
			(layer "B.Fab")
		)
		(fp_line
			(start -0.12065 -0.2794)
			(end -0.12065 -0.3048)
			(stroke
				(width 0.1)
				(type default)
			)
			(layer "B.Fab")
		)
		(fp_line
			(start -0.12065 -0.3048)
			(end -0.67945 -0.3048)
			(stroke
				(width 0.1)
				(type default)
			)
			(layer "B.Fab")
		)
		(fp_line
			(start -0.67945 0.3048)
			(end -0.120396 0.3048)
			(stroke
				(width 0.1)
				(type default)
			)
			(layer "B.Fab")
		)
		(fp_line
			(start -0.67945 -0.3048)
			(end -0.67945 0.3048)
			(stroke
				(width 0.1)
				(type default)
			)
			(layer "B.Fab")
		)
		(pad "1" smd circle
			(at 0.40005 0)
			(size 0 0)
			(layers "B.Cu" "B.Mask" "B.Paste")
			(net "PVDD18_S5_P0")
		)
		(pad "2" smd circle
			(at -0.40005 0)
			(size 0 0)
			(layers "B.Cu" "B.Mask" "B.Paste")
			(net "UART_CPU0_SCM_UART1_TX")
		)
	)
	(footprint ""
		(layer "B.Cu")
		(at 233.37012 -422.849548 90)
		(property "Reference" "C64"
			(at 0 0 90)
			(layer "B.SilkS")
			(hide yes)
			(effects
				(font
					(size 1.27 1.27)
				)
				(justify mirror)
			)
		)
		(property "Value" ""
			(at 0 0 90)
			(layer "B.Fab")
			(effects
				(font
					(size 1.27 1.27)
				)
				(justify mirror)
			)
		)
		(duplicate_pad_numbers_are_jumpers no)
		(fp_line
			(start 0.7874 -0.4064)
			(end -0.7874 -0.4064)
			(stroke
				(width 0.1524)
				(type default)
			)
			(layer "B.SilkS")
		)
		(fp_line
			(start -0.7874 -0.4064)
			(end -0.7874 0.4064)
			(stroke
				(width 0.1524)
				(type default)
			)
			(layer "B.SilkS")
		)
		(fp_line
			(start 0.7874 0.4064)
			(end 0.7874 -0.4064)
			(stroke
				(width 0.1524)
				(type default)
			)
			(layer "B.SilkS")
		)
		(fp_line
			(start -0.7874 0.4064)
			(end 0.7874 0.4064)
			(stroke
				(width 0.1524)
				(type default)
			)
			(layer "B.SilkS")
		)
		(fp_line
			(start 0.67945 -0.305054)
			(end 0.12065 -0.305054)
			(stroke
				(width 0.1)
				(type default)
			)
			(layer "B.Fab")
		)
		(fp_line
			(start 0.12065 -0.305054)
			(end 0.12065 -0.2794)
			(stroke
				(width 0.1)
				(type default)
			)
			(layer "B.Fab")
		)
		(fp_line
			(start -0.12065 -0.3048)
			(end -0.67945 -0.3048)
			(stroke
				(width 0.1)
				(type default)
			)
			(layer "B.Fab")
		)
		(fp_line
			(start -0.67945 -0.3048)
			(end -0.67945 0.3048)
			(stroke
				(width 0.1)
				(type default)
			)
			(layer "B.Fab")
		)
		(fp_line
			(start 0.12065 -0.2794)
			(end -0.12065 -0.2794)
			(stroke
				(width 0.1)
				(type default)
			)
			(layer "B.Fab")
		)
		(fp_line
			(start -0.12065 -0.2794)
			(end -0.12065 -0.3048)
			(stroke
				(width 0.1)
				(type default)
			)
			(layer "B.Fab")
		)
		(fp_line
			(start 0.12065 0.2794)
			(end 0.12065 0.3048)
			(stroke
				(width 0.1)
				(type default)
			)
			(layer "B.Fab")
		)
		(fp_line
			(start -0.120396 0.2794)
			(end 0.12065 0.2794)
			(stroke
				(width 0.1)
				(type default)
			)
			(layer "B.Fab")
		)
		(fp_line
			(start 0.67945 0.3048)
			(end 0.67945 -0.305054)
			(stroke
				(width 0.1)
				(type default)
			)
			(layer "B.Fab")
		)
		(fp_line
			(start 0.12065 0.3048)
			(end 0.67945 0.3048)
			(stroke
				(width 0.1)
				(type default)
			)
			(layer "B.Fab")
		)
		(fp_line
			(start -0.120396 0.3048)
			(end -0.120396 0.2794)
			(stroke
				(width 0.1)
				(type default)
			)
			(layer "B.Fab")
		)
		(fp_line
			(start -0.67945 0.3048)
			(end -0.120396 0.3048)
			(stroke
				(width 0.1)
				(type default)
			)
			(layer "B.Fab")
		)
		(pad "1" smd circle
			(at 0.40005 0 270)
			(size 0 0)
			(layers "B.Cu" "B.Mask" "B.Paste")
			(net "PDB_PRSNT_N")
		)
		(pad "2" smd circle
			(at -0.40005 0 270)
			(size 0 0)
			(layers "B.Cu" "B.Mask" "B.Paste")
			(net "GND")
		)
	)
	(footprint ""
		(layer "B.Cu")
		(at 136.040114 -34.850578)
		(property "Reference" "C6039"
			(at 0 0 0)
			(layer "B.SilkS")
			(hide yes)
			(effects
				(font
					(size 1.27 1.27)
				)
				(justify mirror)
			)
		)
		(property "Value" ""
			(at 0 0 0)
			(layer "B.Fab")
			(effects
				(font
					(size 1.27 1.27)
				)
				(justify mirror)
			)
		)
		(duplicate_pad_numbers_are_jumpers no)
		(fp_line
			(start -0.7874 -0.4064)
			(end -0.7874 0.4064)
			(stroke
				(width 0.1524)
				(type default)
			)
			(layer "B.SilkS")
		)
		(fp_line
			(start -0.7874 0.4064)
			(end 0.7874 0.4064)
			(stroke
				(width 0.1524)
				(type default)
			)
			(layer "B.SilkS")
		)
		(fp_line
			(start 0.7874 -0.4064)
			(end -0.7874 -0.4064)
			(stroke
				(width 0.1524)
				(type default)
			)
			(layer "B.SilkS")
		)
		(fp_line
			(start 0.7874 0.4064)
			(end 0.7874 -0.4064)
			(stroke
				(width 0.1524)
				(type default)
			)
			(layer "B.SilkS")
		)
		(fp_line
			(start -0.67945 -0.3048)
			(end -0.67945 0.3048)
			(stroke
				(width 0.1)
				(type default)
			)
			(layer "B.Fab")
		)
		(fp_line
			(start -0.67945 0.3048)
			(end -0.120396 0.3048)
			(stroke
				(width 0.1)
				(type default)
			)
			(layer "B.Fab")
		)
		(fp_line
			(start -0.12065 -0.3048)
			(end -0.67945 -0.3048)
			(stroke
				(width 0.1)
				(type default)
			)
			(layer "B.Fab")
		)
		(fp_line
			(start -0.12065 -0.2794)
			(end -0.12065 -0.3048)
			(stroke
				(width 0.1)
				(type default)
			)
			(layer "B.Fab")
		)
		(fp_line
			(start -0.120396 0.2794)
			(end 0.12065 0.2794)
			(stroke
				(width 0.1)
				(type default)
			)
			(layer "B.Fab")
		)
		(fp_line
			(start -0.120396 0.3048)
			(end -0.120396 0.2794)
			(stroke
				(width 0.1)
				(type default)
			)
			(layer "B.Fab")
		)
		(fp_line
			(start 0.12065 -0.305054)
			(end 0.12065 -0.2794)
			(stroke
				(width 0.1)
				(type default)
			)
			(layer "B.Fab")
		)
		(fp_line
			(start 0.12065 -0.2794)
			(end -0.12065 -0.2794)
			(stroke
				(width 0.1)
				(type default)
			)
			(layer "B.Fab")
		)
		(fp_line
			(start 0.12065 0.2794)
			(end 0.12065 0.3048)
			(stroke
				(width 0.1)
				(type default)
			)
			(layer "B.Fab")
		)
		(fp_line
			(start 0.12065 0.3048)
			(end 0.67945 0.3048)
			(stroke
				(width 0.1)
				(type default)
			)
			(layer "B.Fab")
		)
		(fp_line
			(start 0.67945 -0.305054)
			(end 0.12065 -0.305054)
			(stroke
				(width 0.1)
				(type default)
			)
			(layer "B.Fab")
		)
		(fp_line
			(start 0.67945 0.3048)
			(end 0.67945 -0.305054)
			(stroke
				(width 0.1)
				(type default)
			)
			(layer "B.Fab")
		)
		(pad "1" smd circle
			(at 0.40005 0 180)
			(size 0 0)
			(layers "B.Cu" "B.Mask" "B.Paste")
			(net "P1V2_CPU0_USB_DVDD12")
		)
		(pad "2" smd circle
			(at -0.40005 0 180)
			(size 0 0)
			(layers "B.Cu" "B.Mask" "B.Paste")
			(net "GND")
		)
	)
	(footprint ""
		(layer "B.Cu")
		(at 411.470856 -163.891468 -90)
		(property "Reference" "PC610_3"
			(at 0 0 90)
			(layer "B.SilkS")
			(hide yes)
			(effects
				(font
					(size 1.27 1.27)
				)
				(justify mirror)
			)
		)
		(property "Value" ""
			(at 0 0 90)
			(layer "B.Fab")
			(effects
				(font
					(size 1.27 1.27)
				)
				(justify mirror)
			)
		)
		(duplicate_pad_numbers_are_jumpers no)
		(fp_line
			(start -1.524 0.762)
			(end 1.524 0.762)
			(stroke
				(width 0.1524)
				(type default)
			)
			(layer "B.SilkS")
		)
		(fp_line
			(start 1.524 0.762)
			(end 1.524 -0.762)
			(stroke
				(width 0.1524)
				(type default)
			)
			(layer "B.SilkS")
		)
		(fp_line
			(start -1.524 -0.762)
			(end -1.524 0.762)
			(stroke
				(width 0.1524)
				(type default)
			)
			(layer "B.SilkS")
		)
		(fp_line
			(start 1.524 -0.762)
			(end -1.524 -0.762)
			(stroke
				(width 0.1524)
				(type default)
			)
			(layer "B.SilkS")
		)
		(fp_line
			(start -1.1049 0.724916)
			(end -1.1049 -0.724916)
			(stroke
				(width 0.1)
				(type default)
			)
			(layer "B.Fab")
		)
		(fp_line
			(start 1.1049 0.724916)
			(end -1.1049 0.724916)
			(stroke
				(width 0.1)
				(type default)
			)
			(layer "B.Fab")
		)
		(fp_line
			(start -1.1049 -0.724916)
			(end 1.1049 -0.724916)
			(stroke
				(width 0.1)
				(type default)
			)
			(layer "B.Fab")
		)
		(fp_line
			(start 1.1049 -0.724916)
			(end 1.1049 0.724916)
			(stroke
				(width 0.1)
				(type default)
			)
			(layer "B.Fab")
		)
		(pad "1" smd rect
			(at 0.889 0 270)
			(size 1.016 1.27)
			(layers "B.Cu" "B.Mask" "B.Paste")
			(net "SW_P12V_AUX_PVDDCR_SOC_P0_FLT")
		)
		(pad "2" smd rect
			(at -0.889 0 270)
			(size 1.016 1.27)
			(layers "B.Cu" "B.Mask" "B.Paste")
			(net "GND")
		)
	)
	(footprint ""
		(layer "B.Cu")
		(at 188.712094 -116.242846)
		(property "Reference" "C360"
			(at 0 0 0)
			(layer "B.SilkS")
			(hide yes)
			(effects
				(font
					(size 1.27 1.27)
				)
				(justify mirror)
			)
		)
		(property "Value" ""
			(at 0 0 0)
			(layer "B.Fab")
			(effects
				(font
					(size 1.27 1.27)
				)
				(justify mirror)
			)
		)
		(duplicate_pad_numbers_are_jumpers no)
		(fp_line
			(start -0.69215 -0.2921)
			(end -0.69215 0.2921)
			(stroke
				(width 0.1524)
				(type default)
			)
			(layer "B.SilkS")
		)
		(fp_line
			(start -0.69215 0.2921)
			(end 0.69215 0.2921)
			(stroke
				(width 0.1524)
				(type default)
			)
			(layer "B.SilkS")
		)
		(fp_line
			(start 0.69215 -0.2921)
			(end -0.69215 -0.2921)
			(stroke
				(width 0.1524)
				(type default)
			)
			(layer "B.SilkS")
		)
		(fp_line
			(start 0.69215 0.2921)
			(end 0.69215 -0.2921)
			(stroke
				(width 0.1524)
				(type default)
			)
			(layer "B.SilkS")
		)
		(fp_line
			(start -0.51435 -0.2794)
			(end -0.51435 0.2794)
			(stroke
				(width 0.1)
				(type default)
			)
			(layer "B.Fab")
		)
		(fp_line
			(start -0.51435 0.2794)
			(end 0.51435 0.2794)
			(stroke
				(width 0.1)
				(type default)
			)
			(layer "B.Fab")
		)
		(fp_line
			(start 0.51435 -0.2794)
			(end -0.51435 -0.2794)
			(stroke
				(width 0.1)
				(type default)
			)
			(layer "B.Fab")
		)
		(fp_line
			(start 0.51435 0.2794)
			(end 0.51435 -0.2794)
			(stroke
				(width 0.1)
				(type default)
			)
			(layer "B.Fab")
		)
		(pad "1" smd circle
			(at 0.40005 0 180)
			(size 0 0)
			(layers "B.Cu" "B.Mask" "B.Paste")
			(net "P3V3_AUX")
		)
		(pad "2" smd circle
			(at -0.40005 0 180)
			(size 0 0)
			(layers "B.Cu" "B.Mask" "B.Paste")
			(net "GND")
		)
		(zone
			(layer "B.Cu")
			(hatch none 0.5)
			(connect_pads
				(clearance 0)
			)
			(min_thickness 0.25)
			(keepout
				(tracks not_allowed)
				(vias allowed)
				(pads allowed)
				(copperpour not_allowed)
				(footprints allowed)
			)
			(placement
				(enabled no)
				(sheetname "")
			)
			(fill
				(thermal_gap 0.5)
				(thermal_bridge_width 0.5)
				(island_removal_mode 0)
			)
			(polygon
				(pts
					(xy 188.521594 -116.155216) (xy 188.521594 -116.330476) (xy 188.611764 -116.388896) (xy 188.811154 -116.388896)
					(xy 188.902594 -116.33073) (xy 188.902594 -116.155216) (xy 188.811154 -116.09705) (xy 188.611764 -116.09705)
				)
			)
		)
	)
	(footprint ""
		(layer "B.Cu")
		(at 362.051346 -249.36831)
		(property "Reference" "C2175"
			(at 0 0 0)
			(layer "B.SilkS")
			(hide yes)
			(effects
				(font
					(size 1.27 1.27)
				)
				(justify mirror)
			)
		)
		(property "Value" ""
			(at 0 0 0)
			(layer "B.Fab")
			(effects
				(font
					(size 1.27 1.27)
				)
				(justify mirror)
			)
		)
		(duplicate_pad_numbers_are_jumpers no)
		(fp_line
			(start -0.7874 -0.4064)
			(end -0.7874 0.4064)
			(stroke
				(width 0.1524)
				(type default)
			)
			(layer "B.SilkS")
		)
		(fp_line
			(start -0.7874 0.4064)
			(end 0.7874 0.4064)
			(stroke
				(width 0.1524)
				(type default)
			)
			(layer "B.SilkS")
		)
		(fp_line
			(start 0.7874 -0.4064)
			(end -0.7874 -0.4064)
			(stroke
				(width 0.1524)
				(type default)
			)
			(layer "B.SilkS")
		)
		(fp_line
			(start 0.7874 0.4064)
			(end 0.7874 -0.4064)
			(stroke
				(width 0.1524)
				(type default)
			)
			(layer "B.SilkS")
		)
		(fp_line
			(start -0.67945 -0.3048)
			(end -0.67945 0.3048)
			(stroke
				(width 0.1)
				(type default)
			)
			(layer "B.Fab")
		)
		(fp_line
			(start -0.67945 0.3048)
			(end -0.120396 0.3048)
			(stroke
				(width 0.1)
				(type default)
			)
			(layer "B.Fab")
		)
		(fp_line
			(start -0.12065 -0.3048)
			(end -0.67945 -0.3048)
			(stroke
				(width 0.1)
				(type default)
			)
			(layer "B.Fab")
		)
		(fp_line
			(start -0.12065 -0.2794)
			(end -0.12065 -0.3048)
			(stroke
				(width 0.1)
				(type default)
			)
			(layer "B.Fab")
		)
		(fp_line
			(start -0.120396 0.2794)
			(end 0.12065 0.2794)
			(stroke
				(width 0.1)
				(type default)
			)
			(layer "B.Fab")
		)
		(fp_line
			(start -0.120396 0.3048)
			(end -0.120396 0.2794)
			(stroke
				(width 0.1)
				(type default)
			)
			(layer "B.Fab")
		)
		(fp_line
			(start 0.12065 -0.305054)
			(end 0.12065 -0.2794)
			(stroke
				(width 0.1)
				(type default)
			)
			(layer "B.Fab")
		)
		(fp_line
			(start 0.12065 -0.2794)
			(end -0.12065 -0.2794)
			(stroke
				(width 0.1)
				(type default)
			)
			(layer "B.Fab")
		)
		(fp_line
			(start 0.12065 0.2794)
			(end 0.12065 0.3048)
			(stroke
				(width 0.1)
				(type default)
			)
			(layer "B.Fab")
		)
		(fp_line
			(start 0.12065 0.3048)
			(end 0.67945 0.3048)
			(stroke
				(width 0.1)
				(type default)
			)
			(layer "B.Fab")
		)
		(fp_line
			(start 0.67945 -0.305054)
			(end 0.12065 -0.305054)
			(stroke
				(width 0.1)
				(type default)
			)
			(layer "B.Fab")
		)
		(fp_line
			(start 0.67945 0.3048)
			(end 0.67945 -0.305054)
			(stroke
				(width 0.1)
				(type default)
			)
			(layer "B.Fab")
		)
		(pad "1" smd circle
			(at 0.40005 0 180)
			(size 0 0)
			(layers "B.Cu" "B.Mask" "B.Paste")
			(net "PVDDCR_CPU0_P0")
		)
		(pad "2" smd circle
			(at -0.40005 0 180)
			(size 0 0)
			(layers "B.Cu" "B.Mask" "B.Paste")
			(net "GND")
		)
	)
	(footprint ""
		(layer "B.Cu")
		(at 450.666866 -397.91767 -90)
		(property "Reference" "PR6560"
			(at 0 0 90)
			(layer "B.SilkS")
			(hide yes)
			(effects
				(font
					(size 1.27 1.27)
				)
				(justify mirror)
			)
		)
		(property "Value" ""
			(at 0 0 90)
			(layer "B.Fab")
			(effects
				(font
					(size 1.27 1.27)
				)
				(justify mirror)
			)
		)
		(duplicate_pad_numbers_are_jumpers no)
		(fp_line
			(start -0.7874 0.4064)
			(end 0.7874 0.4064)
			(stroke
				(width 0.1524)
				(type default)
			)
			(layer "B.SilkS")
		)
		(fp_line
			(start 0.7874 0.4064)
			(end 0.7874 -0.4064)
			(stroke
				(width 0.1524)
				(type default)
			)
			(layer "B.SilkS")
		)
		(fp_line
			(start -0.7874 -0.4064)
			(end -0.7874 0.4064)
			(stroke
				(width 0.1524)
				(type default)
			)
			(layer "B.SilkS")
		)
		(fp_line
			(start 0.7874 -0.4064)
			(end -0.7874 -0.4064)
			(stroke
				(width 0.1524)
				(type default)
			)
			(layer "B.SilkS")
		)
		(fp_line
			(start -0.67945 0.3048)
			(end -0.120396 0.3048)
			(stroke
				(width 0.1)
				(type default)
			)
			(layer "B.Fab")
		)
		(fp_line
			(start -0.120396 0.3048)
			(end -0.120396 0.2794)
			(stroke
				(width 0.1)
				(type default)
			)
			(layer "B.Fab")
		)
		(fp_line
			(start 0.12065 0.3048)
			(end 0.67945 0.3048)
			(stroke
				(width 0.1)
				(type default)
			)
			(layer "B.Fab")
		)
		(fp_line
			(start 0.67945 0.3048)
			(end 0.67945 -0.305054)
			(stroke
				(width 0.1)
				(type default)
			)
			(layer "B.Fab")
		)
		(fp_line
			(start -0.120396 0.2794)
			(end 0.12065 0.2794)
			(stroke
				(width 0.1)
				(type default)
			)
			(layer "B.Fab")
		)
		(fp_line
			(start 0.12065 0.2794)
			(end 0.12065 0.3048)
			(stroke
				(width 0.1)
				(type default)
			)
			(layer "B.Fab")
		)
		(fp_line
			(start -0.12065 -0.2794)
			(end -0.12065 -0.3048)
			(stroke
				(width 0.1)
				(type default)
			)
			(layer "B.Fab")
		)
		(fp_line
			(start 0.12065 -0.2794)
			(end -0.12065 -0.2794)
			(stroke
				(width 0.1)
				(type default)
			)
			(layer "B.Fab")
		)
		(fp_line
			(start -0.67945 -0.3048)
			(end -0.67945 0.3048)
			(stroke
				(width 0.1)
				(type default)
			)
			(layer "B.Fab")
		)
		(fp_line
			(start -0.12065 -0.3048)
			(end -0.67945 -0.3048)
			(stroke
				(width 0.1)
				(type default)
			)
			(layer "B.Fab")
		)
		(fp_line
			(start 0.12065 -0.305054)
			(end 0.12065 -0.2794)
			(stroke
				(width 0.1)
				(type default)
			)
			(layer "B.Fab")
		)
		(fp_line
			(start 0.67945 -0.305054)
			(end 0.12065 -0.305054)
			(stroke
				(width 0.1)
				(type default)
			)
			(layer "B.Fab")
		)
		(pad "1" smd circle
			(at 0.40005 0 90)
			(size 0 0)
			(layers "B.Cu" "B.Mask" "B.Paste")
			(net "P0V9_RETIMER_CPU0_PVCC")
		)
		(pad "2" smd circle
			(at -0.40005 0 90)
			(size 0 0)
			(layers "B.Cu" "B.Mask" "B.Paste")
			(net "P0V9_RETIMER_CPU0_VCC2")
		)
	)
	(footprint ""
		(layer "B.Cu")
		(at 51.72964 -426.003212 -90)
		(property "Reference" "R3513"
			(at 0 0 90)
			(layer "B.SilkS")
			(hide yes)
			(effects
				(font
					(size 1.27 1.27)
				)
				(justify mirror)
			)
		)
		(property "Value" ""
			(at 0 0 90)
			(layer "B.Fab")
			(effects
				(font
					(size 1.27 1.27)
				)
				(justify mirror)
			)
		)
		(duplicate_pad_numbers_are_jumpers no)
		(fp_line
			(start -0.7874 0.4064)
			(end 0.7874 0.4064)
			(stroke
				(width 0.1524)
				(type default)
			)
			(layer "B.SilkS")
		)
		(fp_line
			(start 0.7874 0.4064)
			(end 0.7874 -0.4064)
			(stroke
				(width 0.1524)
				(type default)
			)
			(layer "B.SilkS")
		)
		(fp_line
			(start -0.7874 -0.4064)
			(end -0.7874 0.4064)
			(stroke
				(width 0.1524)
				(type default)
			)
			(layer "B.SilkS")
		)
		(fp_line
			(start 0.7874 -0.4064)
			(end -0.7874 -0.4064)
			(stroke
				(width 0.1524)
				(type default)
			)
			(layer "B.SilkS")
		)
		(fp_line
			(start -0.67945 0.3048)
			(end -0.120396 0.3048)
			(stroke
				(width 0.1)
				(type default)
			)
			(layer "B.Fab")
		)
		(fp_line
			(start -0.120396 0.3048)
			(end -0.120396 0.2794)
			(stroke
				(width 0.1)
				(type default)
			)
			(layer "B.Fab")
		)
		(fp_line
			(start 0.12065 0.3048)
			(end 0.67945 0.3048)
			(stroke
				(width 0.1)
				(type default)
			)
			(layer "B.Fab")
		)
		(fp_line
			(start 0.67945 0.3048)
			(end 0.67945 -0.305054)
			(stroke
				(width 0.1)
				(type default)
			)
			(layer "B.Fab")
		)
		(fp_line
			(start -0.120396 0.2794)
			(end 0.12065 0.2794)
			(stroke
				(width 0.1)
				(type default)
			)
			(layer "B.Fab")
		)
		(fp_line
			(start 0.12065 0.2794)
			(end 0.12065 0.3048)
			(stroke
				(width 0.1)
				(type default)
			)
			(layer "B.Fab")
		)
		(fp_line
			(start -0.12065 -0.2794)
			(end -0.12065 -0.3048)
			(stroke
				(width 0.1)
				(type default)
			)
			(layer "B.Fab")
		)
		(fp_line
			(start 0.12065 -0.2794)
			(end -0.12065 -0.2794)
			(stroke
				(width 0.1)
				(type default)
			)
			(layer "B.Fab")
		)
		(fp_line
			(start -0.67945 -0.3048)
			(end -0.67945 0.3048)
			(stroke
				(width 0.1)
				(type default)
			)
			(layer "B.Fab")
		)
		(fp_line
			(start -0.12065 -0.3048)
			(end -0.67945 -0.3048)
			(stroke
				(width 0.1)
				(type default)
			)
			(layer "B.Fab")
		)
		(fp_line
			(start 0.12065 -0.305054)
			(end 0.12065 -0.2794)
			(stroke
				(width 0.1)
				(type default)
			)
			(layer "B.Fab")
		)
		(fp_line
			(start 0.67945 -0.305054)
			(end 0.12065 -0.305054)
			(stroke
				(width 0.1)
				(type default)
			)
			(layer "B.Fab")
		)
		(pad "1" smd circle
			(at 0.40005 0 90)
			(size 0 0)
			(layers "B.Cu" "B.Mask" "B.Paste")
			(net "FM_GPU_PWRGD")
		)
		(pad "2" smd circle
			(at -0.40005 0 90)
			(size 0 0)
			(layers "B.Cu" "B.Mask" "B.Paste")
			(net "GND")
		)
	)
	(footprint ""
		(layer "B.Cu")
		(at 48.71847 -388.011162 -90)
		(property "Reference" "C141"
			(at 0 0 90)
			(layer "B.SilkS")
			(hide yes)
			(effects
				(font
					(size 1.27 1.27)
				)
				(justify mirror)
			)
		)
		(property "Value" ""
			(at 0 0 90)
			(layer "B.Fab")
			(effects
				(font
					(size 1.27 1.27)
				)
				(justify mirror)
			)
		)
		(duplicate_pad_numbers_are_jumpers no)
		(fp_line
			(start -0.299974 0.150114)
			(end 0.299974 0.150114)
			(stroke
				(width 0.1)
				(type default)
			)
			(layer "B.Fab")
		)
		(fp_line
			(start 0.299974 0.150114)
			(end 0.299974 -0.150114)
			(stroke
				(width 0.1)
				(type default)
			)
			(layer "B.Fab")
		)
		(fp_line
			(start -0.299974 -0.150114)
			(end -0.299974 0.150114)
			(stroke
				(width 0.1)
				(type default)
			)
			(layer "B.Fab")
		)
		(fp_line
			(start 0.299974 -0.150114)
			(end -0.299974 -0.150114)
			(stroke
				(width 0.1)
				(type default)
			)
			(layer "B.Fab")
		)
		(pad "1" smd rect
			(at 0.2667 0 90)
			(size 0.3048 0.381)
			(layers "B.Cu" "B.Mask" "B.Paste")
			(net "P0V9_CPU1_RT0_2A")
		)
		(pad "2" smd rect
			(at -0.2667 0 90)
			(size 0.3048 0.381)
			(layers "B.Cu" "B.Mask" "B.Paste")
			(net "GND")
		)
	)
	(footprint ""
		(layer "B.Cu")
		(at 388.382256 -182.867554 -90)
		(property "Reference" "PC557_4"
			(at 0 0 90)
			(layer "B.SilkS")
			(hide yes)
			(effects
				(font
					(size 1.27 1.27)
				)
				(justify mirror)
			)
		)
		(property "Value" ""
			(at 0 0 90)
			(layer "B.Fab")
			(effects
				(font
					(size 1.27 1.27)
				)
				(justify mirror)
			)
		)
		(duplicate_pad_numbers_are_jumpers no)
		(fp_line
			(start -1.524 0.762)
			(end 1.524 0.762)
			(stroke
				(width 0.1524)
				(type default)
			)
			(layer "B.SilkS")
		)
		(fp_line
			(start 1.524 0.762)
			(end 1.524 -0.762)
			(stroke
				(width 0.1524)
				(type default)
			)
			(layer "B.SilkS")
		)
		(fp_line
			(start -1.524 -0.762)
			(end -1.524 0.762)
			(stroke
				(width 0.1524)
				(type default)
			)
			(layer "B.SilkS")
		)
		(fp_line
			(start 1.524 -0.762)
			(end -1.524 -0.762)
			(stroke
				(width 0.1524)
				(type default)
			)
			(layer "B.SilkS")
		)
		(fp_line
			(start -1.1049 0.724916)
			(end -1.1049 -0.724916)
			(stroke
				(width 0.1)
				(type default)
			)
			(layer "B.Fab")
		)
		(fp_line
			(start 1.1049 0.724916)
			(end -1.1049 0.724916)
			(stroke
				(width 0.1)
				(type default)
			)
			(layer "B.Fab")
		)
		(fp_line
			(start -1.1049 -0.724916)
			(end 1.1049 -0.724916)
			(stroke
				(width 0.1)
				(type default)
			)
			(layer "B.Fab")
		)
		(fp_line
			(start 1.1049 -0.724916)
			(end 1.1049 0.724916)
			(stroke
				(width 0.1)
				(type default)
			)
			(layer "B.Fab")
		)
		(pad "1" smd rect
			(at 0.889 0 270)
			(size 1.016 1.27)
			(layers "B.Cu" "B.Mask" "B.Paste")
			(net "SW_P12V_AUX_PVDDCR_CPU0_P0_FLT")
		)
		(pad "2" smd rect
			(at -0.889 0 270)
			(size 1.016 1.27)
			(layers "B.Cu" "B.Mask" "B.Paste")
			(net "GND")
		)
	)
	(footprint ""
		(layer "B.Cu")
		(at 155.406344 -386.766562 90)
		(property "Reference" "C377"
			(at 0 0 90)
			(layer "B.SilkS")
			(hide yes)
			(effects
				(font
					(size 1.27 1.27)
				)
				(justify mirror)
			)
		)
		(property "Value" ""
			(at 0 0 90)
			(layer "B.Fab")
			(effects
				(font
					(size 1.27 1.27)
				)
				(justify mirror)
			)
		)
		(duplicate_pad_numbers_are_jumpers no)
		(fp_line
			(start 0.299974 -0.150114)
			(end -0.299974 -0.150114)
			(stroke
				(width 0.1)
				(type default)
			)
			(layer "B.Fab")
		)
		(fp_line
			(start -0.299974 -0.150114)
			(end -0.299974 0.150114)
			(stroke
				(width 0.1)
				(type default)
			)
			(layer "B.Fab")
		)
		(fp_line
			(start 0.299974 0.150114)
			(end 0.299974 -0.150114)
			(stroke
				(width 0.1)
				(type default)
			)
			(layer "B.Fab")
		)
		(fp_line
			(start -0.299974 0.150114)
			(end 0.299974 0.150114)
			(stroke
				(width 0.1)
				(type default)
			)
			(layer "B.Fab")
		)
		(pad "1" smd rect
			(at 0.2667 0 270)
			(size 0.3048 0.381)
			(layers "B.Cu" "B.Mask" "B.Paste")
			(net "P1V8_CPU1_RT2_1A")
		)
		(pad "2" smd rect
			(at -0.2667 0 270)
			(size 0.3048 0.381)
			(layers "B.Cu" "B.Mask" "B.Paste")
			(net "GND")
		)
	)
	(footprint ""
		(layer "B.Cu")
		(at 116.372386 -268.418564)
		(property "Reference" "C2400"
			(at 0 0 0)
			(layer "B.SilkS")
			(hide yes)
			(effects
				(font
					(size 1.27 1.27)
				)
				(justify mirror)
			)
		)
		(property "Value" ""
			(at 0 0 0)
			(layer "B.Fab")
			(effects
				(font
					(size 1.27 1.27)
				)
				(justify mirror)
			)
		)
		(duplicate_pad_numbers_are_jumpers no)
		(fp_line
			(start -0.7874 -0.4064)
			(end -0.7874 0.4064)
			(stroke
				(width 0.1524)
				(type default)
			)
			(layer "B.SilkS")
		)
		(fp_line
			(start -0.7874 0.4064)
			(end 0.7874 0.4064)
			(stroke
				(width 0.1524)
				(type default)
			)
			(layer "B.SilkS")
		)
		(fp_line
			(start 0.7874 -0.4064)
			(end -0.7874 -0.4064)
			(stroke
				(width 0.1524)
				(type default)
			)
			(layer "B.SilkS")
		)
		(fp_line
			(start 0.7874 0.4064)
			(end 0.7874 -0.4064)
			(stroke
				(width 0.1524)
				(type default)
			)
			(layer "B.SilkS")
		)
		(fp_line
			(start -0.67945 -0.3048)
			(end -0.67945 0.3048)
			(stroke
				(width 0.1)
				(type default)
			)
			(layer "B.Fab")
		)
		(fp_line
			(start -0.67945 0.3048)
			(end -0.120396 0.3048)
			(stroke
				(width 0.1)
				(type default)
			)
			(layer "B.Fab")
		)
		(fp_line
			(start -0.12065 -0.3048)
			(end -0.67945 -0.3048)
			(stroke
				(width 0.1)
				(type default)
			)
			(layer "B.Fab")
		)
		(fp_line
			(start -0.12065 -0.2794)
			(end -0.12065 -0.3048)
			(stroke
				(width 0.1)
				(type default)
			)
			(layer "B.Fab")
		)
		(fp_line
			(start -0.120396 0.2794)
			(end 0.12065 0.2794)
			(stroke
				(width 0.1)
				(type default)
			)
			(layer "B.Fab")
		)
		(fp_line
			(start -0.120396 0.3048)
			(end -0.120396 0.2794)
			(stroke
				(width 0.1)
				(type default)
			)
			(layer "B.Fab")
		)
		(fp_line
			(start 0.12065 -0.305054)
			(end 0.12065 -0.2794)
			(stroke
				(width 0.1)
				(type default)
			)
			(layer "B.Fab")
		)
		(fp_line
			(start 0.12065 -0.2794)
			(end -0.12065 -0.2794)
			(stroke
				(width 0.1)
				(type default)
			)
			(layer "B.Fab")
		)
		(fp_line
			(start 0.12065 0.2794)
			(end 0.12065 0.3048)
			(stroke
				(width 0.1)
				(type default)
			)
			(layer "B.Fab")
		)
		(fp_line
			(start 0.12065 0.3048)
			(end 0.67945 0.3048)
			(stroke
				(width 0.1)
				(type default)
			)
			(layer "B.Fab")
		)
		(fp_line
			(start 0.67945 -0.305054)
			(end 0.12065 -0.305054)
			(stroke
				(width 0.1)
				(type default)
			)
			(layer "B.Fab")
		)
		(fp_line
			(start 0.67945 0.3048)
			(end 0.67945 -0.305054)
			(stroke
				(width 0.1)
				(type default)
			)
			(layer "B.Fab")
		)
		(pad "1" smd circle
			(at 0.40005 0 180)
			(size 0 0)
			(layers "B.Cu" "B.Mask" "B.Paste")
			(net "PVDDCR_CPU1_P1")
		)
		(pad "2" smd circle
			(at -0.40005 0 180)
			(size 0 0)
			(layers "B.Cu" "B.Mask" "B.Paste")
			(net "GND")
		)
	)
	(footprint ""
		(layer "B.Cu")
		(at 91.392502 -205.14945 90)
		(property "Reference" "R538"
			(at 0 0 90)
			(layer "B.SilkS")
			(hide yes)
			(effects
				(font
					(size 1.27 1.27)
				)
				(justify mirror)
			)
		)
		(property "Value" ""
			(at 0 0 90)
			(layer "B.Fab")
			(effects
				(font
					(size 1.27 1.27)
				)
				(justify mirror)
			)
		)
		(duplicate_pad_numbers_are_jumpers no)
		(fp_line
			(start 0.7874 -0.4064)
			(end -0.7874 -0.4064)
			(stroke
				(width 0.1524)
				(type default)
			)
			(layer "B.SilkS")
		)
		(fp_line
			(start -0.7874 -0.4064)
			(end -0.7874 0.4064)
			(stroke
				(width 0.1524)
				(type default)
			)
			(layer "B.SilkS")
		)
		(fp_line
			(start 0.7874 0.4064)
			(end 0.7874 -0.4064)
			(stroke
				(width 0.1524)
				(type default)
			)
			(layer "B.SilkS")
		)
		(fp_line
			(start -0.7874 0.4064)
			(end 0.7874 0.4064)
			(stroke
				(width 0.1524)
				(type default)
			)
			(layer "B.SilkS")
		)
		(fp_line
			(start 0.67945 -0.305054)
			(end 0.12065 -0.305054)
			(stroke
				(width 0.1)
				(type default)
			)
			(layer "B.Fab")
		)
		(fp_line
			(start 0.12065 -0.305054)
			(end 0.12065 -0.2794)
			(stroke
				(width 0.1)
				(type default)
			)
			(layer "B.Fab")
		)
		(fp_line
			(start -0.12065 -0.3048)
			(end -0.67945 -0.3048)
			(stroke
				(width 0.1)
				(type default)
			)
			(layer "B.Fab")
		)
		(fp_line
			(start -0.67945 -0.3048)
			(end -0.67945 0.3048)
			(stroke
				(width 0.1)
				(type default)
			)
			(layer "B.Fab")
		)
		(fp_line
			(start 0.12065 -0.2794)
			(end -0.12065 -0.2794)
			(stroke
				(width 0.1)
				(type default)
			)
			(layer "B.Fab")
		)
		(fp_line
			(start -0.12065 -0.2794)
			(end -0.12065 -0.3048)
			(stroke
				(width 0.1)
				(type default)
			)
			(layer "B.Fab")
		)
		(fp_line
			(start 0.12065 0.2794)
			(end 0.12065 0.3048)
			(stroke
				(width 0.1)
				(type default)
			)
			(layer "B.Fab")
		)
		(fp_line
			(start -0.120396 0.2794)
			(end 0.12065 0.2794)
			(stroke
				(width 0.1)
				(type default)
			)
			(layer "B.Fab")
		)
		(fp_line
			(start 0.67945 0.3048)
			(end 0.67945 -0.305054)
			(stroke
				(width 0.1)
				(type default)
			)
			(layer "B.Fab")
		)
		(fp_line
			(start 0.12065 0.3048)
			(end 0.67945 0.3048)
			(stroke
				(width 0.1)
				(type default)
			)
			(layer "B.Fab")
		)
		(fp_line
			(start -0.120396 0.3048)
			(end -0.120396 0.2794)
			(stroke
				(width 0.1)
				(type default)
			)
			(layer "B.Fab")
		)
		(fp_line
			(start -0.67945 0.3048)
			(end -0.120396 0.3048)
			(stroke
				(width 0.1)
				(type default)
			)
			(layer "B.Fab")
		)
		(pad "1" smd circle
			(at 0.40005 0 270)
			(size 0 0)
			(layers "B.Cu" "B.Mask" "B.Paste")
			(net "CPU1_XTRIG_L5")
		)
		(pad "2" smd circle
			(at -0.40005 0 270)
			(size 0 0)
			(layers "B.Cu" "B.Mask" "B.Paste")
			(net "PVDD18_S5_P1")
		)
	)
	(footprint ""
		(layer "B.Cu")
		(at 81.118964 -390.560052 90)
		(property "Reference" "C329"
			(at 0 0 90)
			(layer "B.SilkS")
			(hide yes)
			(effects
				(font
					(size 1.27 1.27)
				)
				(justify mirror)
			)
		)
		(property "Value" ""
			(at 0 0 90)
			(layer "B.Fab")
			(effects
				(font
					(size 1.27 1.27)
				)
				(justify mirror)
			)
		)
		(duplicate_pad_numbers_are_jumpers no)
		(fp_line
			(start 0.7874 -0.4064)
			(end -0.7874 -0.4064)
			(stroke
				(width 0.1524)
				(type default)
			)
			(layer "B.SilkS")
		)
		(fp_line
			(start -0.7874 -0.4064)
			(end -0.7874 0.4064)
			(stroke
				(width 0.1524)
				(type default)
			)
			(layer "B.SilkS")
		)
		(fp_line
			(start 0.7874 0.4064)
			(end 0.7874 -0.4064)
			(stroke
				(width 0.1524)
				(type default)
			)
			(layer "B.SilkS")
		)
		(fp_line
			(start -0.7874 0.4064)
			(end 0.7874 0.4064)
			(stroke
				(width 0.1524)
				(type default)
			)
			(layer "B.SilkS")
		)
		(fp_line
			(start 0.67945 -0.305054)
			(end 0.12065 -0.305054)
			(stroke
				(width 0.1)
				(type default)
			)
			(layer "B.Fab")
		)
		(fp_line
			(start 0.12065 -0.305054)
			(end 0.12065 -0.2794)
			(stroke
				(width 0.1)
				(type default)
			)
			(layer "B.Fab")
		)
		(fp_line
			(start -0.12065 -0.3048)
			(end -0.67945 -0.3048)
			(stroke
				(width 0.1)
				(type default)
			)
			(layer "B.Fab")
		)
		(fp_line
			(start -0.67945 -0.3048)
			(end -0.67945 0.3048)
			(stroke
				(width 0.1)
				(type default)
			)
			(layer "B.Fab")
		)
		(fp_line
			(start 0.12065 -0.2794)
			(end -0.12065 -0.2794)
			(stroke
				(width 0.1)
				(type default)
			)
			(layer "B.Fab")
		)
		(fp_line
			(start -0.12065 -0.2794)
			(end -0.12065 -0.3048)
			(stroke
				(width 0.1)
				(type default)
			)
			(layer "B.Fab")
		)
		(fp_line
			(start 0.12065 0.2794)
			(end 0.12065 0.3048)
			(stroke
				(width 0.1)
				(type default)
			)
			(layer "B.Fab")
		)
		(fp_line
			(start -0.120396 0.2794)
			(end 0.12065 0.2794)
			(stroke
				(width 0.1)
				(type default)
			)
			(layer "B.Fab")
		)
		(fp_line
			(start 0.67945 0.3048)
			(end 0.67945 -0.305054)
			(stroke
				(width 0.1)
				(type default)
			)
			(layer "B.Fab")
		)
		(fp_line
			(start 0.12065 0.3048)
			(end 0.67945 0.3048)
			(stroke
				(width 0.1)
				(type default)
			)
			(layer "B.Fab")
		)
		(fp_line
			(start -0.120396 0.3048)
			(end -0.120396 0.2794)
			(stroke
				(width 0.1)
				(type default)
			)
			(layer "B.Fab")
		)
		(fp_line
			(start -0.67945 0.3048)
			(end -0.120396 0.3048)
			(stroke
				(width 0.1)
				(type default)
			)
			(layer "B.Fab")
		)
		(pad "1" smd circle
			(at 0.40005 0 270)
			(size 0 0)
			(layers "B.Cu" "B.Mask" "B.Paste")
			(net "P0V9_CPU1_RT1_2A")
		)
		(pad "2" smd circle
			(at -0.40005 0 270)
			(size 0 0)
			(layers "B.Cu" "B.Mask" "B.Paste")
			(net "GND")
		)
	)
	(footprint ""
		(layer "B.Cu")
		(at 218.059 -341.884 180)
		(property "Reference" "R6749"
			(at 0 0 0)
			(layer "B.SilkS")
			(hide yes)
			(effects
				(font
					(size 1.27 1.27)
				)
				(justify mirror)
			)
		)
		(property "Value" ""
			(at 0 0 0)
			(layer "B.Fab")
			(effects
				(font
					(size 1.27 1.27)
				)
				(justify mirror)
			)
		)
		(duplicate_pad_numbers_are_jumpers no)
		(fp_line
			(start 0.32512 0.175006)
			(end 0.32512 -0.175006)
			(stroke
				(width 0.1)
				(type default)
			)
			(layer "B.Fab")
		)
		(fp_line
			(start 0.32512 -0.175006)
			(end -0.32512 -0.175006)
			(stroke
				(width 0.1)
				(type default)
			)
			(layer "B.Fab")
		)
		(fp_line
			(start -0.32512 0.175006)
			(end 0.32512 0.175006)
			(stroke
				(width 0.1)
				(type default)
			)
			(layer "B.Fab")
		)
		(fp_line
			(start -0.32512 -0.175006)
			(end -0.32512 0.175006)
			(stroke
				(width 0.1)
				(type default)
			)
			(layer "B.Fab")
		)
		(pad "1" smd rect
			(at 0.2667 0)
			(size 0.3048 0.381)
			(layers "B.Cu" "B.Mask" "B.Paste")
			(net "SMB_RT_CPU1_P2_R_SCL")
		)
		(pad "2" smd rect
			(at -0.2667 0 180)
			(size 0.3048 0.381)
			(layers "B.Cu" "B.Mask" "B.Paste")
			(net "SMB_RT_CPU1_P2_SCL")
		)
	)
	(footprint ""
		(layer "B.Cu")
		(at 344.955876 -66.708782 90)
		(property "Reference" "R3099"
			(at 0 0 90)
			(layer "B.SilkS")
			(hide yes)
			(effects
				(font
					(size 1.27 1.27)
				)
				(justify mirror)
			)
		)
		(property "Value" ""
			(at 0 0 90)
			(layer "B.Fab")
			(effects
				(font
					(size 1.27 1.27)
				)
				(justify mirror)
			)
		)
		(duplicate_pad_numbers_are_jumpers no)
		(fp_line
			(start 0.7874 -0.4064)
			(end -0.7874 -0.4064)
			(stroke
				(width 0.1524)
				(type default)
			)
			(layer "B.SilkS")
		)
		(fp_line
			(start -0.7874 -0.4064)
			(end -0.7874 0.4064)
			(stroke
				(width 0.1524)
				(type default)
			)
			(layer "B.SilkS")
		)
		(fp_line
			(start 0.7874 0.4064)
			(end 0.7874 -0.4064)
			(stroke
				(width 0.1524)
				(type default)
			)
			(layer "B.SilkS")
		)
		(fp_line
			(start -0.7874 0.4064)
			(end 0.7874 0.4064)
			(stroke
				(width 0.1524)
				(type default)
			)
			(layer "B.SilkS")
		)
		(fp_line
			(start 0.67945 -0.305054)
			(end 0.12065 -0.305054)
			(stroke
				(width 0.1)
				(type default)
			)
			(layer "B.Fab")
		)
		(fp_line
			(start 0.12065 -0.305054)
			(end 0.12065 -0.2794)
			(stroke
				(width 0.1)
				(type default)
			)
			(layer "B.Fab")
		)
		(fp_line
			(start -0.12065 -0.3048)
			(end -0.67945 -0.3048)
			(stroke
				(width 0.1)
				(type default)
			)
			(layer "B.Fab")
		)
		(fp_line
			(start -0.67945 -0.3048)
			(end -0.67945 0.3048)
			(stroke
				(width 0.1)
				(type default)
			)
			(layer "B.Fab")
		)
		(fp_line
			(start 0.12065 -0.2794)
			(end -0.12065 -0.2794)
			(stroke
				(width 0.1)
				(type default)
			)
			(layer "B.Fab")
		)
		(fp_line
			(start -0.12065 -0.2794)
			(end -0.12065 -0.3048)
			(stroke
				(width 0.1)
				(type default)
			)
			(layer "B.Fab")
		)
		(fp_line
			(start 0.12065 0.2794)
			(end 0.12065 0.3048)
			(stroke
				(width 0.1)
				(type default)
			)
			(layer "B.Fab")
		)
		(fp_line
			(start -0.120396 0.2794)
			(end 0.12065 0.2794)
			(stroke
				(width 0.1)
				(type default)
			)
			(layer "B.Fab")
		)
		(fp_line
			(start 0.67945 0.3048)
			(end 0.67945 -0.305054)
			(stroke
				(width 0.1)
				(type default)
			)
			(layer "B.Fab")
		)
		(fp_line
			(start 0.12065 0.3048)
			(end 0.67945 0.3048)
			(stroke
				(width 0.1)
				(type default)
			)
			(layer "B.Fab")
		)
		(fp_line
			(start -0.120396 0.3048)
			(end -0.120396 0.2794)
			(stroke
				(width 0.1)
				(type default)
			)
			(layer "B.Fab")
		)
		(fp_line
			(start -0.67945 0.3048)
			(end -0.120396 0.3048)
			(stroke
				(width 0.1)
				(type default)
			)
			(layer "B.Fab")
		)
		(pad "1" smd circle
			(at 0.40005 0 270)
			(size 0 0)
			(layers "B.Cu" "B.Mask" "B.Paste")
			(net "LED_PWRGD_PVDD11_S3_P1_R")
		)
		(pad "2" smd circle
			(at -0.40005 0 270)
			(size 0 0)
			(layers "B.Cu" "B.Mask" "B.Paste")
			(net "P3V3_AUX")
		)
	)
	(footprint ""
		(layer "B.Cu")
		(at 58.490104 -408.517344 90)
		(property "Reference" "C6668"
			(at 0 0 90)
			(layer "B.SilkS")
			(hide yes)
			(effects
				(font
					(size 1.27 1.27)
				)
				(justify mirror)
			)
		)
		(property "Value" ""
			(at 0 0 90)
			(layer "B.Fab")
			(effects
				(font
					(size 1.27 1.27)
				)
				(justify mirror)
			)
		)
		(duplicate_pad_numbers_are_jumpers no)
		(fp_line
			(start 0.299974 -0.150114)
			(end -0.299974 -0.150114)
			(stroke
				(width 0.1)
				(type default)
			)
			(layer "B.Fab")
		)
		(fp_line
			(start -0.299974 -0.150114)
			(end -0.299974 0.150114)
			(stroke
				(width 0.1)
				(type default)
			)
			(layer "B.Fab")
		)
		(fp_line
			(start 0.299974 0.150114)
			(end 0.299974 -0.150114)
			(stroke
				(width 0.1)
				(type default)
			)
			(layer "B.Fab")
		)
		(fp_line
			(start -0.299974 0.150114)
			(end 0.299974 0.150114)
			(stroke
				(width 0.1)
				(type default)
			)
			(layer "B.Fab")
		)
		(pad "1" smd rect
			(at 0.2667 0 270)
			(size 0.3048 0.381)
			(layers "B.Cu" "B.Mask" "B.Paste")
			(net "P5E_CPU1_P1_TX_BUF_C_DN<3>")
		)
		(pad "2" smd rect
			(at -0.2667 0 270)
			(size 0.3048 0.381)
			(layers "B.Cu" "B.Mask" "B.Paste")
			(net "P5E_CPU1_P1_TX_BUF_DN<3>")
		)
	)
	(footprint ""
		(layer "B.Cu")
		(at 129.188972 -41.947592 -90)
		(property "Reference" "C6078"
			(at 0 0 90)
			(layer "B.SilkS")
			(hide yes)
			(effects
				(font
					(size 1.27 1.27)
				)
				(justify mirror)
			)
		)
		(property "Value" ""
			(at 0 0 90)
			(layer "B.Fab")
			(effects
				(font
					(size 1.27 1.27)
				)
				(justify mirror)
			)
		)
		(duplicate_pad_numbers_are_jumpers no)
		(fp_line
			(start -0.7874 0.4064)
			(end 0.7874 0.4064)
			(stroke
				(width 0.1524)
				(type default)
			)
			(layer "B.SilkS")
		)
		(fp_line
			(start 0.7874 0.4064)
			(end 0.7874 -0.4064)
			(stroke
				(width 0.1524)
				(type default)
			)
			(layer "B.SilkS")
		)
		(fp_line
			(start -0.7874 -0.4064)
			(end -0.7874 0.4064)
			(stroke
				(width 0.1524)
				(type default)
			)
			(layer "B.SilkS")
		)
		(fp_line
			(start 0.7874 -0.4064)
			(end -0.7874 -0.4064)
			(stroke
				(width 0.1524)
				(type default)
			)
			(layer "B.SilkS")
		)
		(fp_line
			(start -0.67945 0.3048)
			(end -0.120396 0.3048)
			(stroke
				(width 0.1)
				(type default)
			)
			(layer "B.Fab")
		)
		(fp_line
			(start -0.120396 0.3048)
			(end -0.120396 0.2794)
			(stroke
				(width 0.1)
				(type default)
			)
			(layer "B.Fab")
		)
		(fp_line
			(start 0.12065 0.3048)
			(end 0.67945 0.3048)
			(stroke
				(width 0.1)
				(type default)
			)
			(layer "B.Fab")
		)
		(fp_line
			(start 0.67945 0.3048)
			(end 0.67945 -0.305054)
			(stroke
				(width 0.1)
				(type default)
			)
			(layer "B.Fab")
		)
		(fp_line
			(start -0.120396 0.2794)
			(end 0.12065 0.2794)
			(stroke
				(width 0.1)
				(type default)
			)
			(layer "B.Fab")
		)
		(fp_line
			(start 0.12065 0.2794)
			(end 0.12065 0.3048)
			(stroke
				(width 0.1)
				(type default)
			)
			(layer "B.Fab")
		)
		(fp_line
			(start -0.12065 -0.2794)
			(end -0.12065 -0.3048)
			(stroke
				(width 0.1)
				(type default)
			)
			(layer "B.Fab")
		)
		(fp_line
			(start 0.12065 -0.2794)
			(end -0.12065 -0.2794)
			(stroke
				(width 0.1)
				(type default)
			)
			(layer "B.Fab")
		)
		(fp_line
			(start -0.67945 -0.3048)
			(end -0.67945 0.3048)
			(stroke
				(width 0.1)
				(type default)
			)
			(layer "B.Fab")
		)
		(fp_line
			(start -0.12065 -0.3048)
			(end -0.67945 -0.3048)
			(stroke
				(width 0.1)
				(type default)
			)
			(layer "B.Fab")
		)
		(fp_line
			(start 0.12065 -0.305054)
			(end 0.12065 -0.2794)
			(stroke
				(width 0.1)
				(type default)
			)
			(layer "B.Fab")
		)
		(fp_line
			(start 0.67945 -0.305054)
			(end 0.12065 -0.305054)
			(stroke
				(width 0.1)
				(type default)
			)
			(layer "B.Fab")
		)
		(pad "1" smd circle
			(at 0.40005 0 90)
			(size 0 0)
			(layers "B.Cu" "B.Mask" "B.Paste")
			(net "P1V2_AUX")
		)
		(pad "2" smd circle
			(at -0.40005 0 90)
			(size 0 0)
			(layers "B.Cu" "B.Mask" "B.Paste")
			(net "GND")
		)
	)
	(footprint ""
		(layer "B.Cu")
		(at 191.26454 -400.709892 90)
		(property "Reference" "R3936"
			(at 0 0 90)
			(layer "B.SilkS")
			(hide yes)
			(effects
				(font
					(size 1.27 1.27)
				)
				(justify mirror)
			)
		)
		(property "Value" ""
			(at 0 0 90)
			(layer "B.Fab")
			(effects
				(font
					(size 1.27 1.27)
				)
				(justify mirror)
			)
		)
		(duplicate_pad_numbers_are_jumpers no)
		(fp_line
			(start 0.7874 -0.4064)
			(end -0.7874 -0.4064)
			(stroke
				(width 0.1524)
				(type default)
			)
			(layer "B.SilkS")
		)
		(fp_line
			(start -0.7874 -0.4064)
			(end -0.7874 0.4064)
			(stroke
				(width 0.1524)
				(type default)
			)
			(layer "B.SilkS")
		)
		(fp_line
			(start 0.7874 0.4064)
			(end 0.7874 -0.4064)
			(stroke
				(width 0.1524)
				(type default)
			)
			(layer "B.SilkS")
		)
		(fp_line
			(start -0.7874 0.4064)
			(end 0.7874 0.4064)
			(stroke
				(width 0.1524)
				(type default)
			)
			(layer "B.SilkS")
		)
		(fp_line
			(start 0.67945 -0.305054)
			(end 0.12065 -0.305054)
			(stroke
				(width 0.1)
				(type default)
			)
			(layer "B.Fab")
		)
		(fp_line
			(start 0.12065 -0.305054)
			(end 0.12065 -0.2794)
			(stroke
				(width 0.1)
				(type default)
			)
			(layer "B.Fab")
		)
		(fp_line
			(start -0.12065 -0.3048)
			(end -0.67945 -0.3048)
			(stroke
				(width 0.1)
				(type default)
			)
			(layer "B.Fab")
		)
		(fp_line
			(start -0.67945 -0.3048)
			(end -0.67945 0.3048)
			(stroke
				(width 0.1)
				(type default)
			)
			(layer "B.Fab")
		)
		(fp_line
			(start 0.12065 -0.2794)
			(end -0.12065 -0.2794)
			(stroke
				(width 0.1)
				(type default)
			)
			(layer "B.Fab")
		)
		(fp_line
			(start -0.12065 -0.2794)
			(end -0.12065 -0.3048)
			(stroke
				(width 0.1)
				(type default)
			)
			(layer "B.Fab")
		)
		(fp_line
			(start 0.12065 0.2794)
			(end 0.12065 0.3048)
			(stroke
				(width 0.1)
				(type default)
			)
			(layer "B.Fab")
		)
		(fp_line
			(start -0.120396 0.2794)
			(end 0.12065 0.2794)
			(stroke
				(width 0.1)
				(type default)
			)
			(layer "B.Fab")
		)
		(fp_line
			(start 0.67945 0.3048)
			(end 0.67945 -0.305054)
			(stroke
				(width 0.1)
				(type default)
			)
			(layer "B.Fab")
		)
		(fp_line
			(start 0.12065 0.3048)
			(end 0.67945 0.3048)
			(stroke
				(width 0.1)
				(type default)
			)
			(layer "B.Fab")
		)
		(fp_line
			(start -0.120396 0.3048)
			(end -0.120396 0.2794)
			(stroke
				(width 0.1)
				(type default)
			)
			(layer "B.Fab")
		)
		(fp_line
			(start -0.67945 0.3048)
			(end -0.120396 0.3048)
			(stroke
				(width 0.1)
				(type default)
			)
			(layer "B.Fab")
		)
		(pad "1" smd circle
			(at 0.40005 0 270)
			(size 0 0)
			(layers "B.Cu" "B.Mask" "B.Paste")
			(net "HSC_VDD")
		)
		(pad "2" smd circle
			(at -0.40005 0 270)
			(size 0 0)
			(layers "B.Cu" "B.Mask" "B.Paste")
			(net "HSC_D_OC")
		)
	)
	(footprint ""
		(layer "B.Cu")
		(at 307.500528 -338.082128 -90)
		(property "Reference" "PC128_4"
			(at 0 0 90)
			(layer "B.SilkS")
			(hide yes)
			(effects
				(font
					(size 1.27 1.27)
				)
				(justify mirror)
			)
		)
		(property "Value" ""
			(at 0 0 90)
			(layer "B.Fab")
			(effects
				(font
					(size 1.27 1.27)
				)
				(justify mirror)
			)
		)
		(duplicate_pad_numbers_are_jumpers no)
		(fp_line
			(start -1.524 0.762)
			(end 1.524 0.762)
			(stroke
				(width 0.1524)
				(type default)
			)
			(layer "B.SilkS")
		)
		(fp_line
			(start 1.524 0.762)
			(end 1.524 -0.762)
			(stroke
				(width 0.1524)
				(type default)
			)
			(layer "B.SilkS")
		)
		(fp_line
			(start -1.524 -0.762)
			(end -1.524 0.762)
			(stroke
				(width 0.1524)
				(type default)
			)
			(layer "B.SilkS")
		)
		(fp_line
			(start 1.524 -0.762)
			(end -1.524 -0.762)
			(stroke
				(width 0.1524)
				(type default)
			)
			(layer "B.SilkS")
		)
		(fp_line
			(start -1.1049 0.724916)
			(end -1.1049 -0.724916)
			(stroke
				(width 0.1)
				(type default)
			)
			(layer "B.Fab")
		)
		(fp_line
			(start 1.1049 0.724916)
			(end -1.1049 0.724916)
			(stroke
				(width 0.1)
				(type default)
			)
			(layer "B.Fab")
		)
		(fp_line
			(start -1.1049 -0.724916)
			(end 1.1049 -0.724916)
			(stroke
				(width 0.1)
				(type default)
			)
			(layer "B.Fab")
		)
		(fp_line
			(start 1.1049 -0.724916)
			(end 1.1049 0.724916)
			(stroke
				(width 0.1)
				(type default)
			)
			(layer "B.Fab")
		)
		(pad "1" smd rect
			(at 0.889 0 270)
			(size 1.016 1.27)
			(layers "B.Cu" "B.Mask" "B.Paste")
			(net "PVDDCR_CPU1_P0")
		)
		(pad "2" smd rect
			(at -0.889 0 270)
			(size 1.016 1.27)
			(layers "B.Cu" "B.Mask" "B.Paste")
			(net "GND")
		)
	)
	(footprint ""
		(layer "B.Cu")
		(at 322.878958 -195.662296)
		(property "Reference" "R411"
			(at 0 0 0)
			(layer "B.SilkS")
			(hide yes)
			(effects
				(font
					(size 1.27 1.27)
				)
				(justify mirror)
			)
		)
		(property "Value" ""
			(at 0 0 0)
			(layer "B.Fab")
			(effects
				(font
					(size 1.27 1.27)
				)
				(justify mirror)
			)
		)
		(duplicate_pad_numbers_are_jumpers no)
		(fp_line
			(start -0.7874 -0.4064)
			(end -0.7874 0.4064)
			(stroke
				(width 0.1524)
				(type default)
			)
			(layer "B.SilkS")
		)
		(fp_line
			(start -0.7874 0.4064)
			(end 0.7874 0.4064)
			(stroke
				(width 0.1524)
				(type default)
			)
			(layer "B.SilkS")
		)
		(fp_line
			(start 0.7874 -0.4064)
			(end -0.7874 -0.4064)
			(stroke
				(width 0.1524)
				(type default)
			)
			(layer "B.SilkS")
		)
		(fp_line
			(start 0.7874 0.4064)
			(end 0.7874 -0.4064)
			(stroke
				(width 0.1524)
				(type default)
			)
			(layer "B.SilkS")
		)
		(fp_line
			(start -0.67945 -0.3048)
			(end -0.67945 0.3048)
			(stroke
				(width 0.1)
				(type default)
			)
			(layer "B.Fab")
		)
		(fp_line
			(start -0.67945 0.3048)
			(end -0.120396 0.3048)
			(stroke
				(width 0.1)
				(type default)
			)
			(layer "B.Fab")
		)
		(fp_line
			(start -0.12065 -0.3048)
			(end -0.67945 -0.3048)
			(stroke
				(width 0.1)
				(type default)
			)
			(layer "B.Fab")
		)
		(fp_line
			(start -0.12065 -0.2794)
			(end -0.12065 -0.3048)
			(stroke
				(width 0.1)
				(type default)
			)
			(layer "B.Fab")
		)
		(fp_line
			(start -0.120396 0.2794)
			(end 0.12065 0.2794)
			(stroke
				(width 0.1)
				(type default)
			)
			(layer "B.Fab")
		)
		(fp_line
			(start -0.120396 0.3048)
			(end -0.120396 0.2794)
			(stroke
				(width 0.1)
				(type default)
			)
			(layer "B.Fab")
		)
		(fp_line
			(start 0.12065 -0.305054)
			(end 0.12065 -0.2794)
			(stroke
				(width 0.1)
				(type default)
			)
			(layer "B.Fab")
		)
		(fp_line
			(start 0.12065 -0.2794)
			(end -0.12065 -0.2794)
			(stroke
				(width 0.1)
				(type default)
			)
			(layer "B.Fab")
		)
		(fp_line
			(start 0.12065 0.2794)
			(end 0.12065 0.3048)
			(stroke
				(width 0.1)
				(type default)
			)
			(layer "B.Fab")
		)
		(fp_line
			(start 0.12065 0.3048)
			(end 0.67945 0.3048)
			(stroke
				(width 0.1)
				(type default)
			)
			(layer "B.Fab")
		)
		(fp_line
			(start 0.67945 -0.305054)
			(end 0.12065 -0.305054)
			(stroke
				(width 0.1)
				(type default)
			)
			(layer "B.Fab")
		)
		(fp_line
			(start 0.67945 0.3048)
			(end 0.67945 -0.305054)
			(stroke
				(width 0.1)
				(type default)
			)
			(layer "B.Fab")
		)
		(pad "1" smd circle
			(at 0.40005 0 180)
			(size 0 0)
			(layers "B.Cu" "B.Mask" "B.Paste")
			(net "CPU0_BP3")
		)
		(pad "2" smd circle
			(at -0.40005 0 180)
			(size 0 0)
			(layers "B.Cu" "B.Mask" "B.Paste")
			(net "PVDD18_S5_P0")
		)
	)
	(footprint ""
		(layer "B.Cu")
		(at 161.276284 -193.707512 -90)
		(property "Reference" "R991"
			(at 0 0 90)
			(layer "B.SilkS")
			(hide yes)
			(effects
				(font
					(size 1.27 1.27)
				)
				(justify mirror)
			)
		)
		(property "Value" ""
			(at 0 0 90)
			(layer "B.Fab")
			(effects
				(font
					(size 1.27 1.27)
				)
				(justify mirror)
			)
		)
		(duplicate_pad_numbers_are_jumpers no)
		(fp_line
			(start -0.7874 0.4064)
			(end 0.7874 0.4064)
			(stroke
				(width 0.1524)
				(type default)
			)
			(layer "B.SilkS")
		)
		(fp_line
			(start 0.7874 0.4064)
			(end 0.7874 -0.4064)
			(stroke
				(width 0.1524)
				(type default)
			)
			(layer "B.SilkS")
		)
		(fp_line
			(start -0.7874 -0.4064)
			(end -0.7874 0.4064)
			(stroke
				(width 0.1524)
				(type default)
			)
			(layer "B.SilkS")
		)
		(fp_line
			(start 0.7874 -0.4064)
			(end -0.7874 -0.4064)
			(stroke
				(width 0.1524)
				(type default)
			)
			(layer "B.SilkS")
		)
		(fp_line
			(start -0.67945 0.3048)
			(end -0.120396 0.3048)
			(stroke
				(width 0.1)
				(type default)
			)
			(layer "B.Fab")
		)
		(fp_line
			(start -0.120396 0.3048)
			(end -0.120396 0.2794)
			(stroke
				(width 0.1)
				(type default)
			)
			(layer "B.Fab")
		)
		(fp_line
			(start 0.12065 0.3048)
			(end 0.67945 0.3048)
			(stroke
				(width 0.1)
				(type default)
			)
			(layer "B.Fab")
		)
		(fp_line
			(start 0.67945 0.3048)
			(end 0.67945 -0.305054)
			(stroke
				(width 0.1)
				(type default)
			)
			(layer "B.Fab")
		)
		(fp_line
			(start -0.120396 0.2794)
			(end 0.12065 0.2794)
			(stroke
				(width 0.1)
				(type default)
			)
			(layer "B.Fab")
		)
		(fp_line
			(start 0.12065 0.2794)
			(end 0.12065 0.3048)
			(stroke
				(width 0.1)
				(type default)
			)
			(layer "B.Fab")
		)
		(fp_line
			(start -0.12065 -0.2794)
			(end -0.12065 -0.3048)
			(stroke
				(width 0.1)
				(type default)
			)
			(layer "B.Fab")
		)
		(fp_line
			(start 0.12065 -0.2794)
			(end -0.12065 -0.2794)
			(stroke
				(width 0.1)
				(type default)
			)
			(layer "B.Fab")
		)
		(fp_line
			(start -0.67945 -0.3048)
			(end -0.67945 0.3048)
			(stroke
				(width 0.1)
				(type default)
			)
			(layer "B.Fab")
		)
		(fp_line
			(start -0.12065 -0.3048)
			(end -0.67945 -0.3048)
			(stroke
				(width 0.1)
				(type default)
			)
			(layer "B.Fab")
		)
		(fp_line
			(start 0.12065 -0.305054)
			(end 0.12065 -0.2794)
			(stroke
				(width 0.1)
				(type default)
			)
			(layer "B.Fab")
		)
		(fp_line
			(start 0.67945 -0.305054)
			(end 0.12065 -0.305054)
			(stroke
				(width 0.1)
				(type default)
			)
			(layer "B.Fab")
		)
		(pad "1" smd rect
			(at 0.40005 0 270)
			(size 0.4572 0.508)
			(layers "B.Cu" "B.Mask" "B.Paste")
			(net "I3C_1_SPD_DDRGL_CPU1_R_SDA")
		)
		(pad "2" smd rect
			(at -0.40005 0 270)
			(size 0.4572 0.508)
			(layers "B.Cu" "B.Mask" "B.Paste")
			(net "I3C_SPD_DDRGL_CPU1_BYPASS_SDA")
		)
	)
	(footprint ""
		(layer "B.Cu")
		(at 366.598454 -269.30731 180)
		(property "Reference" "C2208"
			(at 0 0 0)
			(layer "B.SilkS")
			(hide yes)
			(effects
				(font
					(size 1.27 1.27)
				)
				(justify mirror)
			)
		)
		(property "Value" ""
			(at 0 0 0)
			(layer "B.Fab")
			(effects
				(font
					(size 1.27 1.27)
				)
				(justify mirror)
			)
		)
		(duplicate_pad_numbers_are_jumpers no)
		(fp_line
			(start 0.7874 0.4064)
			(end 0.7874 -0.4064)
			(stroke
				(width 0.1524)
				(type default)
			)
			(layer "B.SilkS")
		)
		(fp_line
			(start 0.7874 -0.4064)
			(end -0.7874 -0.4064)
			(stroke
				(width 0.1524)
				(type default)
			)
			(layer "B.SilkS")
		)
		(fp_line
			(start -0.7874 0.4064)
			(end 0.7874 0.4064)
			(stroke
				(width 0.1524)
				(type default)
			)
			(layer "B.SilkS")
		)
		(fp_line
			(start -0.7874 -0.4064)
			(end -0.7874 0.4064)
			(stroke
				(width 0.1524)
				(type default)
			)
			(layer "B.SilkS")
		)
		(fp_line
			(start 0.67945 0.3048)
			(end 0.67945 -0.305054)
			(stroke
				(width 0.1)
				(type default)
			)
			(layer "B.Fab")
		)
		(fp_line
			(start 0.67945 -0.305054)
			(end 0.12065 -0.305054)
			(stroke
				(width 0.1)
				(type default)
			)
			(layer "B.Fab")
		)
		(fp_line
			(start 0.12065 0.3048)
			(end 0.67945 0.3048)
			(stroke
				(width 0.1)
				(type default)
			)
			(layer "B.Fab")
		)
		(fp_line
			(start 0.12065 0.2794)
			(end 0.12065 0.3048)
			(stroke
				(width 0.1)
				(type default)
			)
			(layer "B.Fab")
		)
		(fp_line
			(start 0.12065 -0.2794)
			(end -0.12065 -0.2794)
			(stroke
				(width 0.1)
				(type default)
			)
			(layer "B.Fab")
		)
		(fp_line
			(start 0.12065 -0.305054)
			(end 0.12065 -0.2794)
			(stroke
				(width 0.1)
				(type default)
			)
			(layer "B.Fab")
		)
		(fp_line
			(start -0.120396 0.3048)
			(end -0.120396 0.2794)
			(stroke
				(width 0.1)
				(type default)
			)
			(layer "B.Fab")
		)
		(fp_line
			(start -0.120396 0.2794)
			(end 0.12065 0.2794)
			(stroke
				(width 0.1)
				(type default)
			)
			(layer "B.Fab")
		)
		(fp_line
			(start -0.12065 -0.2794)
			(end -0.12065 -0.3048)
			(stroke
				(width 0.1)
				(type default)
			)
			(layer "B.Fab")
		)
		(fp_line
			(start -0.12065 -0.3048)
			(end -0.67945 -0.3048)
			(stroke
				(width 0.1)
				(type default)
			)
			(layer "B.Fab")
		)
		(fp_line
			(start -0.67945 0.3048)
			(end -0.120396 0.3048)
			(stroke
				(width 0.1)
				(type default)
			)
			(layer "B.Fab")
		)
		(fp_line
			(start -0.67945 -0.3048)
			(end -0.67945 0.3048)
			(stroke
				(width 0.1)
				(type default)
			)
			(layer "B.Fab")
		)
		(pad "1" smd circle
			(at 0.40005 0)
			(size 0 0)
			(layers "B.Cu" "B.Mask" "B.Paste")
			(net "PVDDCR_CPU1_P0")
		)
		(pad "2" smd circle
			(at -0.40005 0)
			(size 0 0)
			(layers "B.Cu" "B.Mask" "B.Paste")
			(net "GND")
		)
	)
	(footprint ""
		(layer "B.Cu")
		(at 393.153138 -391.2616 180)
		(property "Reference" "R1125"
			(at 0 0 0)
			(layer "B.SilkS")
			(hide yes)
			(effects
				(font
					(size 1.27 1.27)
				)
				(justify mirror)
			)
		)
		(property "Value" ""
			(at 0 0 0)
			(layer "B.Fab")
			(effects
				(font
					(size 1.27 1.27)
				)
				(justify mirror)
			)
		)
		(duplicate_pad_numbers_are_jumpers no)
		(fp_line
			(start 0.32512 0.175006)
			(end 0.32512 -0.175006)
			(stroke
				(width 0.1)
				(type default)
			)
			(layer "B.Fab")
		)
		(fp_line
			(start 0.32512 -0.175006)
			(end -0.32512 -0.175006)
			(stroke
				(width 0.1)
				(type default)
			)
			(layer "B.Fab")
		)
		(fp_line
			(start -0.32512 0.175006)
			(end 0.32512 0.175006)
			(stroke
				(width 0.1)
				(type default)
			)
			(layer "B.Fab")
		)
		(fp_line
			(start -0.32512 -0.175006)
			(end -0.32512 0.175006)
			(stroke
				(width 0.1)
				(type default)
			)
			(layer "B.Fab")
		)
		(pad "1" smd rect
			(at 0.2667 0)
			(size 0.3048 0.381)
			(layers "B.Cu" "B.Mask" "B.Paste")
			(net "NCF_CPU0_P3_GND")
		)
		(pad "2" smd rect
			(at -0.2667 0 180)
			(size 0.3048 0.381)
			(layers "B.Cu" "B.Mask" "B.Paste")
			(net "GND")
		)
	)
	(footprint ""
		(layer "B.Cu")
		(at 345.50604 -395.148562 90)
		(property "Reference" "C602"
			(at 0 0 90)
			(layer "B.SilkS")
			(hide yes)
			(effects
				(font
					(size 1.27 1.27)
				)
				(justify mirror)
			)
		)
		(property "Value" ""
			(at 0 0 90)
			(layer "B.Fab")
			(effects
				(font
					(size 1.27 1.27)
				)
				(justify mirror)
			)
		)
		(duplicate_pad_numbers_are_jumpers no)
		(fp_line
			(start 0.299974 -0.150114)
			(end -0.299974 -0.150114)
			(stroke
				(width 0.1)
				(type default)
			)
			(layer "B.Fab")
		)
		(fp_line
			(start -0.299974 -0.150114)
			(end -0.299974 0.150114)
			(stroke
				(width 0.1)
				(type default)
			)
			(layer "B.Fab")
		)
		(fp_line
			(start 0.299974 0.150114)
			(end 0.299974 -0.150114)
			(stroke
				(width 0.1)
				(type default)
			)
			(layer "B.Fab")
		)
		(fp_line
			(start -0.299974 0.150114)
			(end 0.299974 0.150114)
			(stroke
				(width 0.1)
				(type default)
			)
			(layer "B.Fab")
		)
		(pad "1" smd rect
			(at 0.2667 0 270)
			(size 0.3048 0.381)
			(layers "B.Cu" "B.Mask" "B.Paste")
			(net "P1V8_CPU0_RT1_1A")
		)
		(pad "2" smd rect
			(at -0.2667 0 270)
			(size 0.3048 0.381)
			(layers "B.Cu" "B.Mask" "B.Paste")
			(net "GND")
		)
	)
	(footprint ""
		(layer "B.Cu")
		(at 67.958462 -167.869362 90)
		(property "Reference" "PR422"
			(at 0 0 90)
			(layer "B.SilkS")
			(hide yes)
			(effects
				(font
					(size 1.27 1.27)
				)
				(justify mirror)
			)
		)
		(property "Value" ""
			(at 0 0 90)
			(layer "B.Fab")
			(effects
				(font
					(size 1.27 1.27)
				)
				(justify mirror)
			)
		)
		(duplicate_pad_numbers_are_jumpers no)
		(fp_line
			(start 0.7874 -0.4064)
			(end -0.7874 -0.4064)
			(stroke
				(width 0.1524)
				(type default)
			)
			(layer "B.SilkS")
		)
		(fp_line
			(start -0.7874 -0.4064)
			(end -0.7874 0.4064)
			(stroke
				(width 0.1524)
				(type default)
			)
			(layer "B.SilkS")
		)
		(fp_line
			(start 0.7874 0.4064)
			(end 0.7874 -0.4064)
			(stroke
				(width 0.1524)
				(type default)
			)
			(layer "B.SilkS")
		)
		(fp_line
			(start -0.7874 0.4064)
			(end 0.7874 0.4064)
			(stroke
				(width 0.1524)
				(type default)
			)
			(layer "B.SilkS")
		)
		(fp_line
			(start 0.67945 -0.305054)
			(end 0.12065 -0.305054)
			(stroke
				(width 0.1)
				(type default)
			)
			(layer "B.Fab")
		)
		(fp_line
			(start 0.12065 -0.305054)
			(end 0.12065 -0.2794)
			(stroke
				(width 0.1)
				(type default)
			)
			(layer "B.Fab")
		)
		(fp_line
			(start -0.12065 -0.3048)
			(end -0.67945 -0.3048)
			(stroke
				(width 0.1)
				(type default)
			)
			(layer "B.Fab")
		)
		(fp_line
			(start -0.67945 -0.3048)
			(end -0.67945 0.3048)
			(stroke
				(width 0.1)
				(type default)
			)
			(layer "B.Fab")
		)
		(fp_line
			(start 0.12065 -0.2794)
			(end -0.12065 -0.2794)
			(stroke
				(width 0.1)
				(type default)
			)
			(layer "B.Fab")
		)
		(fp_line
			(start -0.12065 -0.2794)
			(end -0.12065 -0.3048)
			(stroke
				(width 0.1)
				(type default)
			)
			(layer "B.Fab")
		)
		(fp_line
			(start 0.12065 0.2794)
			(end 0.12065 0.3048)
			(stroke
				(width 0.1)
				(type default)
			)
			(layer "B.Fab")
		)
		(fp_line
			(start -0.120396 0.2794)
			(end 0.12065 0.2794)
			(stroke
				(width 0.1)
				(type default)
			)
			(layer "B.Fab")
		)
		(fp_line
			(start 0.67945 0.3048)
			(end 0.67945 -0.305054)
			(stroke
				(width 0.1)
				(type default)
			)
			(layer "B.Fab")
		)
		(fp_line
			(start 0.12065 0.3048)
			(end 0.67945 0.3048)
			(stroke
				(width 0.1)
				(type default)
			)
			(layer "B.Fab")
		)
		(fp_line
			(start -0.120396 0.3048)
			(end -0.120396 0.2794)
			(stroke
				(width 0.1)
				(type default)
			)
			(layer "B.Fab")
		)
		(fp_line
			(start -0.67945 0.3048)
			(end -0.120396 0.3048)
			(stroke
				(width 0.1)
				(type default)
			)
			(layer "B.Fab")
		)
		(pad "1" smd circle
			(at 0.40005 0 270)
			(size 0 0)
			(layers "B.Cu" "B.Mask" "B.Paste")
			(net "PVDDCR_CPU0_P1_PVCC")
		)
		(pad "2" smd circle
			(at -0.40005 0 270)
			(size 0 0)
			(layers "B.Cu" "B.Mask" "B.Paste")
			(net "PVDDCR_CPU0_P1_VCC6")
		)
	)
	(footprint ""
		(layer "B.Cu")
		(at 18.039588 -399.209006)
		(property "Reference" "PC6616_1"
			(at 0 0 0)
			(layer "B.SilkS")
			(hide yes)
			(effects
				(font
					(size 1.27 1.27)
				)
				(justify mirror)
			)
		)
		(property "Value" ""
			(at 0 0 0)
			(layer "B.Fab")
			(effects
				(font
					(size 1.27 1.27)
				)
				(justify mirror)
			)
		)
		(duplicate_pad_numbers_are_jumpers no)
		(fp_line
			(start -1.524 -0.762)
			(end -1.524 0.762)
			(stroke
				(width 0.1524)
				(type default)
			)
			(layer "B.SilkS")
		)
		(fp_line
			(start -1.524 0.762)
			(end 1.524 0.762)
			(stroke
				(width 0.1524)
				(type default)
			)
			(layer "B.SilkS")
		)
		(fp_line
			(start 1.524 -0.762)
			(end -1.524 -0.762)
			(stroke
				(width 0.1524)
				(type default)
			)
			(layer "B.SilkS")
		)
		(fp_line
			(start 1.524 0.762)
			(end 1.524 -0.762)
			(stroke
				(width 0.1524)
				(type default)
			)
			(layer "B.SilkS")
		)
		(fp_line
			(start -1.1049 -0.724916)
			(end 1.1049 -0.724916)
			(stroke
				(width 0.1)
				(type default)
			)
			(layer "B.Fab")
		)
		(fp_line
			(start -1.1049 0.724916)
			(end -1.1049 -0.724916)
			(stroke
				(width 0.1)
				(type default)
			)
			(layer "B.Fab")
		)
		(fp_line
			(start 1.1049 -0.724916)
			(end 1.1049 0.724916)
			(stroke
				(width 0.1)
				(type default)
			)
			(layer "B.Fab")
		)
		(fp_line
			(start 1.1049 0.724916)
			(end -1.1049 0.724916)
			(stroke
				(width 0.1)
				(type default)
			)
			(layer "B.Fab")
		)
		(pad "1" smd rect
			(at 0.889 0)
			(size 1.016 1.27)
			(layers "B.Cu" "B.Mask" "B.Paste")
			(net "SW_P12V_AUX_P0V9_RETIMER_CPU1_FLT")
		)
		(pad "2" smd rect
			(at -0.889 0)
			(size 1.016 1.27)
			(layers "B.Cu" "B.Mask" "B.Paste")
			(net "GND")
		)
	)
	(footprint ""
		(layer "B.Cu")
		(at 128.172972 -41.947592 -90)
		(property "Reference" "C6077"
			(at 0 0 90)
			(layer "B.SilkS")
			(hide yes)
			(effects
				(font
					(size 1.27 1.27)
				)
				(justify mirror)
			)
		)
		(property "Value" ""
			(at 0 0 90)
			(layer "B.Fab")
			(effects
				(font
					(size 1.27 1.27)
				)
				(justify mirror)
			)
		)
		(duplicate_pad_numbers_are_jumpers no)
		(fp_line
			(start -0.7874 0.4064)
			(end 0.7874 0.4064)
			(stroke
				(width 0.1524)
				(type default)
			)
			(layer "B.SilkS")
		)
		(fp_line
			(start 0.7874 0.4064)
			(end 0.7874 -0.4064)
			(stroke
				(width 0.1524)
				(type default)
			)
			(layer "B.SilkS")
		)
		(fp_line
			(start -0.7874 -0.4064)
			(end -0.7874 0.4064)
			(stroke
				(width 0.1524)
				(type default)
			)
			(layer "B.SilkS")
		)
		(fp_line
			(start 0.7874 -0.4064)
			(end -0.7874 -0.4064)
			(stroke
				(width 0.1524)
				(type default)
			)
			(layer "B.SilkS")
		)
		(fp_line
			(start -0.67945 0.3048)
			(end -0.120396 0.3048)
			(stroke
				(width 0.1)
				(type default)
			)
			(layer "B.Fab")
		)
		(fp_line
			(start -0.120396 0.3048)
			(end -0.120396 0.2794)
			(stroke
				(width 0.1)
				(type default)
			)
			(layer "B.Fab")
		)
		(fp_line
			(start 0.12065 0.3048)
			(end 0.67945 0.3048)
			(stroke
				(width 0.1)
				(type default)
			)
			(layer "B.Fab")
		)
		(fp_line
			(start 0.67945 0.3048)
			(end 0.67945 -0.305054)
			(stroke
				(width 0.1)
				(type default)
			)
			(layer "B.Fab")
		)
		(fp_line
			(start -0.120396 0.2794)
			(end 0.12065 0.2794)
			(stroke
				(width 0.1)
				(type default)
			)
			(layer "B.Fab")
		)
		(fp_line
			(start 0.12065 0.2794)
			(end 0.12065 0.3048)
			(stroke
				(width 0.1)
				(type default)
			)
			(layer "B.Fab")
		)
		(fp_line
			(start -0.12065 -0.2794)
			(end -0.12065 -0.3048)
			(stroke
				(width 0.1)
				(type default)
			)
			(layer "B.Fab")
		)
		(fp_line
			(start 0.12065 -0.2794)
			(end -0.12065 -0.2794)
			(stroke
				(width 0.1)
				(type default)
			)
			(layer "B.Fab")
		)
		(fp_line
			(start -0.67945 -0.3048)
			(end -0.67945 0.3048)
			(stroke
				(width 0.1)
				(type default)
			)
			(layer "B.Fab")
		)
		(fp_line
			(start -0.12065 -0.3048)
			(end -0.67945 -0.3048)
			(stroke
				(width 0.1)
				(type default)
			)
			(layer "B.Fab")
		)
		(fp_line
			(start 0.12065 -0.305054)
			(end 0.12065 -0.2794)
			(stroke
				(width 0.1)
				(type default)
			)
			(layer "B.Fab")
		)
		(fp_line
			(start 0.67945 -0.305054)
			(end 0.12065 -0.305054)
			(stroke
				(width 0.1)
				(type default)
			)
			(layer "B.Fab")
		)
		(pad "1" smd circle
			(at 0.40005 0 90)
			(size 0 0)
			(layers "B.Cu" "B.Mask" "B.Paste")
			(net "P1V2_AUX")
		)
		(pad "2" smd circle
			(at -0.40005 0 90)
			(size 0 0)
			(layers "B.Cu" "B.Mask" "B.Paste")
			(net "GND")
		)
	)
	(footprint ""
		(layer "B.Cu")
		(at 121.685812 -258.830318)
		(property "Reference" "C3916"
			(at 0 0 0)
			(layer "B.SilkS")
			(hide yes)
			(effects
				(font
					(size 1.27 1.27)
				)
				(justify mirror)
			)
		)
		(property "Value" ""
			(at 0 0 0)
			(layer "B.Fab")
			(effects
				(font
					(size 1.27 1.27)
				)
				(justify mirror)
			)
		)
		(duplicate_pad_numbers_are_jumpers no)
		(fp_line
			(start -0.7874 -0.4064)
			(end -0.7874 0.4064)
			(stroke
				(width 0.1524)
				(type default)
			)
			(layer "B.SilkS")
		)
		(fp_line
			(start -0.7874 0.4064)
			(end 0.7874 0.4064)
			(stroke
				(width 0.1524)
				(type default)
			)
			(layer "B.SilkS")
		)
		(fp_line
			(start 0.7874 -0.4064)
			(end -0.7874 -0.4064)
			(stroke
				(width 0.1524)
				(type default)
			)
			(layer "B.SilkS")
		)
		(fp_line
			(start 0.7874 0.4064)
			(end 0.7874 -0.4064)
			(stroke
				(width 0.1524)
				(type default)
			)
			(layer "B.SilkS")
		)
		(fp_line
			(start -0.67945 -0.3048)
			(end -0.67945 0.3048)
			(stroke
				(width 0.1)
				(type default)
			)
			(layer "B.Fab")
		)
		(fp_line
			(start -0.67945 0.3048)
			(end -0.120396 0.3048)
			(stroke
				(width 0.1)
				(type default)
			)
			(layer "B.Fab")
		)
		(fp_line
			(start -0.12065 -0.3048)
			(end -0.67945 -0.3048)
			(stroke
				(width 0.1)
				(type default)
			)
			(layer "B.Fab")
		)
		(fp_line
			(start -0.12065 -0.2794)
			(end -0.12065 -0.3048)
			(stroke
				(width 0.1)
				(type default)
			)
			(layer "B.Fab")
		)
		(fp_line
			(start -0.120396 0.2794)
			(end 0.12065 0.2794)
			(stroke
				(width 0.1)
				(type default)
			)
			(layer "B.Fab")
		)
		(fp_line
			(start -0.120396 0.3048)
			(end -0.120396 0.2794)
			(stroke
				(width 0.1)
				(type default)
			)
			(layer "B.Fab")
		)
		(fp_line
			(start 0.12065 -0.305054)
			(end 0.12065 -0.2794)
			(stroke
				(width 0.1)
				(type default)
			)
			(layer "B.Fab")
		)
		(fp_line
			(start 0.12065 -0.2794)
			(end -0.12065 -0.2794)
			(stroke
				(width 0.1)
				(type default)
			)
			(layer "B.Fab")
		)
		(fp_line
			(start 0.12065 0.2794)
			(end 0.12065 0.3048)
			(stroke
				(width 0.1)
				(type default)
			)
			(layer "B.Fab")
		)
		(fp_line
			(start 0.12065 0.3048)
			(end 0.67945 0.3048)
			(stroke
				(width 0.1)
				(type default)
			)
			(layer "B.Fab")
		)
		(fp_line
			(start 0.67945 -0.305054)
			(end 0.12065 -0.305054)
			(stroke
				(width 0.1)
				(type default)
			)
			(layer "B.Fab")
		)
		(fp_line
			(start 0.67945 0.3048)
			(end 0.67945 -0.305054)
			(stroke
				(width 0.1)
				(type default)
			)
			(layer "B.Fab")
		)
		(pad "1" smd circle
			(at 0.40005 0 180)
			(size 0 0)
			(layers "B.Cu" "B.Mask" "B.Paste")
			(net "PVDDCR_SOC_P1")
		)
		(pad "2" smd circle
			(at -0.40005 0 180)
			(size 0 0)
			(layers "B.Cu" "B.Mask" "B.Paste")
			(net "GND")
		)
	)
	(footprint ""
		(layer "B.Cu")
		(at 102.378764 -257.930396 180)
		(property "Reference" "C2110"
			(at 0 0 0)
			(layer "B.SilkS")
			(hide yes)
			(effects
				(font
					(size 1.27 1.27)
				)
				(justify mirror)
			)
		)
		(property "Value" ""
			(at 0 0 0)
			(layer "B.Fab")
			(effects
				(font
					(size 1.27 1.27)
				)
				(justify mirror)
			)
		)
		(duplicate_pad_numbers_are_jumpers no)
		(fp_line
			(start 0.7874 0.4064)
			(end 0.7874 -0.4064)
			(stroke
				(width 0.1524)
				(type default)
			)
			(layer "B.SilkS")
		)
		(fp_line
			(start 0.7874 -0.4064)
			(end -0.7874 -0.4064)
			(stroke
				(width 0.1524)
				(type default)
			)
			(layer "B.SilkS")
		)
		(fp_line
			(start -0.7874 0.4064)
			(end 0.7874 0.4064)
			(stroke
				(width 0.1524)
				(type default)
			)
			(layer "B.SilkS")
		)
		(fp_line
			(start -0.7874 -0.4064)
			(end -0.7874 0.4064)
			(stroke
				(width 0.1524)
				(type default)
			)
			(layer "B.SilkS")
		)
		(fp_line
			(start 0.67945 0.3048)
			(end 0.67945 -0.305054)
			(stroke
				(width 0.1)
				(type default)
			)
			(layer "B.Fab")
		)
		(fp_line
			(start 0.67945 -0.305054)
			(end 0.12065 -0.305054)
			(stroke
				(width 0.1)
				(type default)
			)
			(layer "B.Fab")
		)
		(fp_line
			(start 0.12065 0.3048)
			(end 0.67945 0.3048)
			(stroke
				(width 0.1)
				(type default)
			)
			(layer "B.Fab")
		)
		(fp_line
			(start 0.12065 0.2794)
			(end 0.12065 0.3048)
			(stroke
				(width 0.1)
				(type default)
			)
			(layer "B.Fab")
		)
		(fp_line
			(start 0.12065 -0.2794)
			(end -0.12065 -0.2794)
			(stroke
				(width 0.1)
				(type default)
			)
			(layer "B.Fab")
		)
		(fp_line
			(start 0.12065 -0.305054)
			(end 0.12065 -0.2794)
			(stroke
				(width 0.1)
				(type default)
			)
			(layer "B.Fab")
		)
		(fp_line
			(start -0.120396 0.3048)
			(end -0.120396 0.2794)
			(stroke
				(width 0.1)
				(type default)
			)
			(layer "B.Fab")
		)
		(fp_line
			(start -0.120396 0.2794)
			(end 0.12065 0.2794)
			(stroke
				(width 0.1)
				(type default)
			)
			(layer "B.Fab")
		)
		(fp_line
			(start -0.12065 -0.2794)
			(end -0.12065 -0.3048)
			(stroke
				(width 0.1)
				(type default)
			)
			(layer "B.Fab")
		)
		(fp_line
			(start -0.12065 -0.3048)
			(end -0.67945 -0.3048)
			(stroke
				(width 0.1)
				(type default)
			)
			(layer "B.Fab")
		)
		(fp_line
			(start -0.67945 0.3048)
			(end -0.120396 0.3048)
			(stroke
				(width 0.1)
				(type default)
			)
			(layer "B.Fab")
		)
		(fp_line
			(start -0.67945 -0.3048)
			(end -0.67945 0.3048)
			(stroke
				(width 0.1)
				(type default)
			)
			(layer "B.Fab")
		)
		(pad "1" smd circle
			(at 0.40005 0)
			(size 0 0)
			(layers "B.Cu" "B.Mask" "B.Paste")
			(net "PVDDIO_P1")
		)
		(pad "2" smd circle
			(at -0.40005 0)
			(size 0 0)
			(layers "B.Cu" "B.Mask" "B.Paste")
			(net "GND")
		)
	)
	(footprint ""
		(layer "B.Cu")
		(at 82.996024 -408.517344 90)
		(property "Reference" "C6684"
			(at 0 0 90)
			(layer "B.SilkS")
			(hide yes)
			(effects
				(font
					(size 1.27 1.27)
				)
				(justify mirror)
			)
		)
		(property "Value" ""
			(at 0 0 90)
			(layer "B.Fab")
			(effects
				(font
					(size 1.27 1.27)
				)
				(justify mirror)
			)
		)
		(duplicate_pad_numbers_are_jumpers no)
		(fp_line
			(start 0.299974 -0.150114)
			(end -0.299974 -0.150114)
			(stroke
				(width 0.1)
				(type default)
			)
			(layer "B.Fab")
		)
		(fp_line
			(start -0.299974 -0.150114)
			(end -0.299974 0.150114)
			(stroke
				(width 0.1)
				(type default)
			)
			(layer "B.Fab")
		)
		(fp_line
			(start 0.299974 0.150114)
			(end 0.299974 -0.150114)
			(stroke
				(width 0.1)
				(type default)
			)
			(layer "B.Fab")
		)
		(fp_line
			(start -0.299974 0.150114)
			(end 0.299974 0.150114)
			(stroke
				(width 0.1)
				(type default)
			)
			(layer "B.Fab")
		)
		(pad "1" smd rect
			(at 0.2667 0 270)
			(size 0.3048 0.381)
			(layers "B.Cu" "B.Mask" "B.Paste")
			(net "P5E_CPU1_P1_TX_BUF_C_DN<11>")
		)
		(pad "2" smd rect
			(at -0.2667 0 270)
			(size 0.3048 0.381)
			(layers "B.Cu" "B.Mask" "B.Paste")
			(net "P5E_CPU1_P1_TX_BUF_DN<11>")
		)
	)
	(footprint ""
		(layer "B.Cu")
		(at 288.180272 -192.660016 180)
		(property "Reference" "C146"
			(at 0 0 0)
			(layer "B.SilkS")
			(hide yes)
			(effects
				(font
					(size 1.27 1.27)
				)
				(justify mirror)
			)
		)
		(property "Value" ""
			(at 0 0 0)
			(layer "B.Fab")
			(effects
				(font
					(size 1.27 1.27)
				)
				(justify mirror)
			)
		)
		(duplicate_pad_numbers_are_jumpers no)
		(fp_line
			(start 1.524 0.762)
			(end 1.524 -0.762)
			(stroke
				(width 0.1524)
				(type default)
			)
			(layer "B.SilkS")
		)
		(fp_line
			(start 1.524 -0.762)
			(end -1.524 -0.762)
			(stroke
				(width 0.1524)
				(type default)
			)
			(layer "B.SilkS")
		)
		(fp_line
			(start -1.524 0.762)
			(end 1.524 0.762)
			(stroke
				(width 0.1524)
				(type default)
			)
			(layer "B.SilkS")
		)
		(fp_line
			(start -1.524 -0.762)
			(end -1.524 0.762)
			(stroke
				(width 0.1524)
				(type default)
			)
			(layer "B.SilkS")
		)
		(fp_line
			(start 1.1049 0.724916)
			(end -1.1049 0.724916)
			(stroke
				(width 0.1)
				(type default)
			)
			(layer "B.Fab")
		)
		(fp_line
			(start 1.1049 -0.724916)
			(end 1.1049 0.724916)
			(stroke
				(width 0.1)
				(type default)
			)
			(layer "B.Fab")
		)
		(fp_line
			(start -1.1049 0.724916)
			(end -1.1049 -0.724916)
			(stroke
				(width 0.1)
				(type default)
			)
			(layer "B.Fab")
		)
		(fp_line
			(start -1.1049 -0.724916)
			(end 1.1049 -0.724916)
			(stroke
				(width 0.1)
				(type default)
			)
			(layer "B.Fab")
		)
		(pad "1" smd rect
			(at 0.889 0 180)
			(size 1.016 1.27)
			(layers "B.Cu" "B.Mask" "B.Paste")
			(net "P12V_MEM_CPU0")
		)
		(pad "2" smd rect
			(at -0.889 0 180)
			(size 1.016 1.27)
			(layers "B.Cu" "B.Mask" "B.Paste")
			(net "GND")
		)
	)
	(footprint ""
		(layer "B.Cu")
		(at 76.753974 -186.316112 90)
		(property "Reference" "PC280_2"
			(at 0 0 90)
			(layer "B.SilkS")
			(hide yes)
			(effects
				(font
					(size 1.27 1.27)
				)
				(justify mirror)
			)
		)
		(property "Value" ""
			(at 0 0 90)
			(layer "B.Fab")
			(effects
				(font
					(size 1.27 1.27)
				)
				(justify mirror)
			)
		)
		(duplicate_pad_numbers_are_jumpers no)
		(fp_line
			(start 1.524 -0.762)
			(end -1.524 -0.762)
			(stroke
				(width 0.1524)
				(type default)
			)
			(layer "B.SilkS")
		)
		(fp_line
			(start -1.524 -0.762)
			(end -1.524 0.762)
			(stroke
				(width 0.1524)
				(type default)
			)
			(layer "B.SilkS")
		)
		(fp_line
			(start 1.524 0.762)
			(end 1.524 -0.762)
			(stroke
				(width 0.1524)
				(type default)
			)
			(layer "B.SilkS")
		)
		(fp_line
			(start -1.524 0.762)
			(end 1.524 0.762)
			(stroke
				(width 0.1524)
				(type default)
			)
			(layer "B.SilkS")
		)
		(fp_line
			(start 1.1049 -0.724916)
			(end 1.1049 0.724916)
			(stroke
				(width 0.1)
				(type default)
			)
			(layer "B.Fab")
		)
		(fp_line
			(start -1.1049 -0.724916)
			(end 1.1049 -0.724916)
			(stroke
				(width 0.1)
				(type default)
			)
			(layer "B.Fab")
		)
		(fp_line
			(start 1.1049 0.724916)
			(end -1.1049 0.724916)
			(stroke
				(width 0.1)
				(type default)
			)
			(layer "B.Fab")
		)
		(fp_line
			(start -1.1049 0.724916)
			(end -1.1049 -0.724916)
			(stroke
				(width 0.1)
				(type default)
			)
			(layer "B.Fab")
		)
		(pad "1" smd rect
			(at 0.889 0 90)
			(size 1.016 1.27)
			(layers "B.Cu" "B.Mask" "B.Paste")
			(net "PVDDCR_CPU0_P1")
		)
		(pad "2" smd rect
			(at -0.889 0 90)
			(size 1.016 1.27)
			(layers "B.Cu" "B.Mask" "B.Paste")
			(net "GND")
		)
	)
	(footprint ""
		(layer "B.Cu")
		(at 59.404504 -408.517344 90)
		(property "Reference" "C6667"
			(at 0 0 90)
			(layer "B.SilkS")
			(hide yes)
			(effects
				(font
					(size 1.27 1.27)
				)
				(justify mirror)
			)
		)
		(property "Value" ""
			(at 0 0 90)
			(layer "B.Fab")
			(effects
				(font
					(size 1.27 1.27)
				)
				(justify mirror)
			)
		)
		(duplicate_pad_numbers_are_jumpers no)
		(fp_line
			(start 0.299974 -0.150114)
			(end -0.299974 -0.150114)
			(stroke
				(width 0.1)
				(type default)
			)
			(layer "B.Fab")
		)
		(fp_line
			(start -0.299974 -0.150114)
			(end -0.299974 0.150114)
			(stroke
				(width 0.1)
				(type default)
			)
			(layer "B.Fab")
		)
		(fp_line
			(start 0.299974 0.150114)
			(end 0.299974 -0.150114)
			(stroke
				(width 0.1)
				(type default)
			)
			(layer "B.Fab")
		)
		(fp_line
			(start -0.299974 0.150114)
			(end 0.299974 0.150114)
			(stroke
				(width 0.1)
				(type default)
			)
			(layer "B.Fab")
		)
		(pad "1" smd rect
			(at 0.2667 0 270)
			(size 0.3048 0.381)
			(layers "B.Cu" "B.Mask" "B.Paste")
			(net "P5E_CPU1_P1_TX_BUF_C_DP<3>")
		)
		(pad "2" smd rect
			(at -0.2667 0 270)
			(size 0.3048 0.381)
			(layers "B.Cu" "B.Mask" "B.Paste")
			(net "P5E_CPU1_P1_TX_BUF_DP<3>")
		)
	)
	(footprint ""
		(layer "B.Cu")
		(at 231.775 -216.662)
		(property "Reference" "R322"
			(at 0 0 0)
			(layer "B.SilkS")
			(hide yes)
			(effects
				(font
					(size 1.27 1.27)
				)
				(justify mirror)
			)
		)
		(property "Value" ""
			(at 0 0 0)
			(layer "B.Fab")
			(effects
				(font
					(size 1.27 1.27)
				)
				(justify mirror)
			)
		)
		(duplicate_pad_numbers_are_jumpers no)
		(fp_line
			(start -0.7874 -0.4064)
			(end -0.7874 0.4064)
			(stroke
				(width 0.1524)
				(type default)
			)
			(layer "B.SilkS")
		)
		(fp_line
			(start -0.7874 0.4064)
			(end 0.7874 0.4064)
			(stroke
				(width 0.1524)
				(type default)
			)
			(layer "B.SilkS")
		)
		(fp_line
			(start 0.7874 -0.4064)
			(end -0.7874 -0.4064)
			(stroke
				(width 0.1524)
				(type default)
			)
			(layer "B.SilkS")
		)
		(fp_line
			(start 0.7874 0.4064)
			(end 0.7874 -0.4064)
			(stroke
				(width 0.1524)
				(type default)
			)
			(layer "B.SilkS")
		)
		(fp_line
			(start -0.67945 -0.3048)
			(end -0.67945 0.3048)
			(stroke
				(width 0.1)
				(type default)
			)
			(layer "B.Fab")
		)
		(fp_line
			(start -0.67945 0.3048)
			(end -0.120396 0.3048)
			(stroke
				(width 0.1)
				(type default)
			)
			(layer "B.Fab")
		)
		(fp_line
			(start -0.12065 -0.3048)
			(end -0.67945 -0.3048)
			(stroke
				(width 0.1)
				(type default)
			)
			(layer "B.Fab")
		)
		(fp_line
			(start -0.12065 -0.2794)
			(end -0.12065 -0.3048)
			(stroke
				(width 0.1)
				(type default)
			)
			(layer "B.Fab")
		)
		(fp_line
			(start -0.120396 0.2794)
			(end 0.12065 0.2794)
			(stroke
				(width 0.1)
				(type default)
			)
			(layer "B.Fab")
		)
		(fp_line
			(start -0.120396 0.3048)
			(end -0.120396 0.2794)
			(stroke
				(width 0.1)
				(type default)
			)
			(layer "B.Fab")
		)
		(fp_line
			(start 0.12065 -0.305054)
			(end 0.12065 -0.2794)
			(stroke
				(width 0.1)
				(type default)
			)
			(layer "B.Fab")
		)
		(fp_line
			(start 0.12065 -0.2794)
			(end -0.12065 -0.2794)
			(stroke
				(width 0.1)
				(type default)
			)
			(layer "B.Fab")
		)
		(fp_line
			(start 0.12065 0.2794)
			(end 0.12065 0.3048)
			(stroke
				(width 0.1)
				(type default)
			)
			(layer "B.Fab")
		)
		(fp_line
			(start 0.12065 0.3048)
			(end 0.67945 0.3048)
			(stroke
				(width 0.1)
				(type default)
			)
			(layer "B.Fab")
		)
		(fp_line
			(start 0.67945 -0.305054)
			(end 0.12065 -0.305054)
			(stroke
				(width 0.1)
				(type default)
			)
			(layer "B.Fab")
		)
		(fp_line
			(start 0.67945 0.3048)
			(end 0.67945 -0.305054)
			(stroke
				(width 0.1)
				(type default)
			)
			(layer "B.Fab")
		)
		(pad "1" smd circle
			(at 0.40005 0 180)
			(size 0 0)
			(layers "B.Cu" "B.Mask" "B.Paste")
			(net "PVDD11_S3_P0")
		)
		(pad "2" smd circle
			(at -0.40005 0 180)
			(size 0 0)
			(layers "B.Cu" "B.Mask" "B.Paste")
			(net "SMB_CPU0_CPU1_APML_BUF2_SCL_R2")
		)
	)
	(footprint ""
		(layer "B.Cu")
		(at 90.209878 -139.80541 180)
		(property "Reference" "C5012"
			(at 0 0 0)
			(layer "B.SilkS")
			(hide yes)
			(effects
				(font
					(size 1.27 1.27)
				)
				(justify mirror)
			)
		)
		(property "Value" ""
			(at 0 0 0)
			(layer "B.Fab")
			(effects
				(font
					(size 1.27 1.27)
				)
				(justify mirror)
			)
		)
		(duplicate_pad_numbers_are_jumpers no)
		(fp_line
			(start 0.7874 0.4064)
			(end 0.7874 -0.4064)
			(stroke
				(width 0.1524)
				(type default)
			)
			(layer "B.SilkS")
		)
		(fp_line
			(start 0.7874 -0.4064)
			(end -0.7874 -0.4064)
			(stroke
				(width 0.1524)
				(type default)
			)
			(layer "B.SilkS")
		)
		(fp_line
			(start -0.7874 0.4064)
			(end 0.7874 0.4064)
			(stroke
				(width 0.1524)
				(type default)
			)
			(layer "B.SilkS")
		)
		(fp_line
			(start -0.7874 -0.4064)
			(end -0.7874 0.4064)
			(stroke
				(width 0.1524)
				(type default)
			)
			(layer "B.SilkS")
		)
		(fp_line
			(start 0.67945 0.3048)
			(end 0.67945 -0.305054)
			(stroke
				(width 0.1)
				(type default)
			)
			(layer "B.Fab")
		)
		(fp_line
			(start 0.67945 -0.305054)
			(end 0.12065 -0.305054)
			(stroke
				(width 0.1)
				(type default)
			)
			(layer "B.Fab")
		)
		(fp_line
			(start 0.12065 0.3048)
			(end 0.67945 0.3048)
			(stroke
				(width 0.1)
				(type default)
			)
			(layer "B.Fab")
		)
		(fp_line
			(start 0.12065 0.2794)
			(end 0.12065 0.3048)
			(stroke
				(width 0.1)
				(type default)
			)
			(layer "B.Fab")
		)
		(fp_line
			(start 0.12065 -0.2794)
			(end -0.12065 -0.2794)
			(stroke
				(width 0.1)
				(type default)
			)
			(layer "B.Fab")
		)
		(fp_line
			(start 0.12065 -0.305054)
			(end 0.12065 -0.2794)
			(stroke
				(width 0.1)
				(type default)
			)
			(layer "B.Fab")
		)
		(fp_line
			(start -0.120396 0.3048)
			(end -0.120396 0.2794)
			(stroke
				(width 0.1)
				(type default)
			)
			(layer "B.Fab")
		)
		(fp_line
			(start -0.120396 0.2794)
			(end 0.12065 0.2794)
			(stroke
				(width 0.1)
				(type default)
			)
			(layer "B.Fab")
		)
		(fp_line
			(start -0.12065 -0.2794)
			(end -0.12065 -0.3048)
			(stroke
				(width 0.1)
				(type default)
			)
			(layer "B.Fab")
		)
		(fp_line
			(start -0.12065 -0.3048)
			(end -0.67945 -0.3048)
			(stroke
				(width 0.1)
				(type default)
			)
			(layer "B.Fab")
		)
		(fp_line
			(start -0.67945 0.3048)
			(end -0.120396 0.3048)
			(stroke
				(width 0.1)
				(type default)
			)
			(layer "B.Fab")
		)
		(fp_line
			(start -0.67945 -0.3048)
			(end -0.67945 0.3048)
			(stroke
				(width 0.1)
				(type default)
			)
			(layer "B.Fab")
		)
		(pad "1" smd circle
			(at 0.40005 0)
			(size 0 0)
			(layers "B.Cu" "B.Mask" "B.Paste")
			(net "PVDDCR_CPU0_P1_PMALERT")
		)
		(pad "2" smd circle
			(at -0.40005 0)
			(size 0 0)
			(layers "B.Cu" "B.Mask" "B.Paste")
			(net "GND")
		)
	)
	(footprint ""
		(layer "B.Cu")
		(at 164.403532 -432.37658 -90)
		(property "Reference" "C14"
			(at 0 0 90)
			(layer "B.SilkS")
			(hide yes)
			(effects
				(font
					(size 1.27 1.27)
				)
				(justify mirror)
			)
		)
		(property "Value" ""
			(at 0 0 90)
			(layer "B.Fab")
			(effects
				(font
					(size 1.27 1.27)
				)
				(justify mirror)
			)
		)
		(duplicate_pad_numbers_are_jumpers no)
		(fp_line
			(start -0.7874 0.4064)
			(end 0.7874 0.4064)
			(stroke
				(width 0.1524)
				(type default)
			)
			(layer "B.SilkS")
		)
		(fp_line
			(start 0.7874 0.4064)
			(end 0.7874 -0.4064)
			(stroke
				(width 0.1524)
				(type default)
			)
			(layer "B.SilkS")
		)
		(fp_line
			(start -0.7874 -0.4064)
			(end -0.7874 0.4064)
			(stroke
				(width 0.1524)
				(type default)
			)
			(layer "B.SilkS")
		)
		(fp_line
			(start 0.7874 -0.4064)
			(end -0.7874 -0.4064)
			(stroke
				(width 0.1524)
				(type default)
			)
			(layer "B.SilkS")
		)
		(fp_line
			(start -0.67945 0.3048)
			(end -0.120396 0.3048)
			(stroke
				(width 0.1)
				(type default)
			)
			(layer "B.Fab")
		)
		(fp_line
			(start -0.120396 0.3048)
			(end -0.120396 0.2794)
			(stroke
				(width 0.1)
				(type default)
			)
			(layer "B.Fab")
		)
		(fp_line
			(start 0.12065 0.3048)
			(end 0.67945 0.3048)
			(stroke
				(width 0.1)
				(type default)
			)
			(layer "B.Fab")
		)
		(fp_line
			(start 0.67945 0.3048)
			(end 0.67945 -0.305054)
			(stroke
				(width 0.1)
				(type default)
			)
			(layer "B.Fab")
		)
		(fp_line
			(start -0.120396 0.2794)
			(end 0.12065 0.2794)
			(stroke
				(width 0.1)
				(type default)
			)
			(layer "B.Fab")
		)
		(fp_line
			(start 0.12065 0.2794)
			(end 0.12065 0.3048)
			(stroke
				(width 0.1)
				(type default)
			)
			(layer "B.Fab")
		)
		(fp_line
			(start -0.12065 -0.2794)
			(end -0.12065 -0.3048)
			(stroke
				(width 0.1)
				(type default)
			)
			(layer "B.Fab")
		)
		(fp_line
			(start 0.12065 -0.2794)
			(end -0.12065 -0.2794)
			(stroke
				(width 0.1)
				(type default)
			)
			(layer "B.Fab")
		)
		(fp_line
			(start -0.67945 -0.3048)
			(end -0.67945 0.3048)
			(stroke
				(width 0.1)
				(type default)
			)
			(layer "B.Fab")
		)
		(fp_line
			(start -0.12065 -0.3048)
			(end -0.67945 -0.3048)
			(stroke
				(width 0.1)
				(type default)
			)
			(layer "B.Fab")
		)
		(fp_line
			(start 0.12065 -0.305054)
			(end 0.12065 -0.2794)
			(stroke
				(width 0.1)
				(type default)
			)
			(layer "B.Fab")
		)
		(fp_line
			(start 0.67945 -0.305054)
			(end 0.12065 -0.305054)
			(stroke
				(width 0.1)
				(type default)
			)
			(layer "B.Fab")
		)
		(pad "1" smd circle
			(at 0.40005 0 90)
			(size 0 0)
			(layers "B.Cu" "B.Mask" "B.Paste")
			(net "GPU_3V3IO_RSVD1_FFU_ISO")
		)
		(pad "2" smd circle
			(at -0.40005 0 90)
			(size 0 0)
			(layers "B.Cu" "B.Mask" "B.Paste")
			(net "GND")
		)
	)
	(footprint ""
		(layer "B.Cu")
		(at 154.218894 -390.560052 90)
		(property "Reference" "C414"
			(at 0 0 90)
			(layer "B.SilkS")
			(hide yes)
			(effects
				(font
					(size 1.27 1.27)
				)
				(justify mirror)
			)
		)
		(property "Value" ""
			(at 0 0 90)
			(layer "B.Fab")
			(effects
				(font
					(size 1.27 1.27)
				)
				(justify mirror)
			)
		)
		(duplicate_pad_numbers_are_jumpers no)
		(fp_line
			(start 0.7874 -0.4064)
			(end -0.7874 -0.4064)
			(stroke
				(width 0.1524)
				(type default)
			)
			(layer "B.SilkS")
		)
		(fp_line
			(start -0.7874 -0.4064)
			(end -0.7874 0.4064)
			(stroke
				(width 0.1524)
				(type default)
			)
			(layer "B.SilkS")
		)
		(fp_line
			(start 0.7874 0.4064)
			(end 0.7874 -0.4064)
			(stroke
				(width 0.1524)
				(type default)
			)
			(layer "B.SilkS")
		)
		(fp_line
			(start -0.7874 0.4064)
			(end 0.7874 0.4064)
			(stroke
				(width 0.1524)
				(type default)
			)
			(layer "B.SilkS")
		)
		(fp_line
			(start 0.67945 -0.305054)
			(end 0.12065 -0.305054)
			(stroke
				(width 0.1)
				(type default)
			)
			(layer "B.Fab")
		)
		(fp_line
			(start 0.12065 -0.305054)
			(end 0.12065 -0.2794)
			(stroke
				(width 0.1)
				(type default)
			)
			(layer "B.Fab")
		)
		(fp_line
			(start -0.12065 -0.3048)
			(end -0.67945 -0.3048)
			(stroke
				(width 0.1)
				(type default)
			)
			(layer "B.Fab")
		)
		(fp_line
			(start -0.67945 -0.3048)
			(end -0.67945 0.3048)
			(stroke
				(width 0.1)
				(type default)
			)
			(layer "B.Fab")
		)
		(fp_line
			(start 0.12065 -0.2794)
			(end -0.12065 -0.2794)
			(stroke
				(width 0.1)
				(type default)
			)
			(layer "B.Fab")
		)
		(fp_line
			(start -0.12065 -0.2794)
			(end -0.12065 -0.3048)
			(stroke
				(width 0.1)
				(type default)
			)
			(layer "B.Fab")
		)
		(fp_line
			(start 0.12065 0.2794)
			(end 0.12065 0.3048)
			(stroke
				(width 0.1)
				(type default)
			)
			(layer "B.Fab")
		)
		(fp_line
			(start -0.120396 0.2794)
			(end 0.12065 0.2794)
			(stroke
				(width 0.1)
				(type default)
			)
			(layer "B.Fab")
		)
		(fp_line
			(start 0.67945 0.3048)
			(end 0.67945 -0.305054)
			(stroke
				(width 0.1)
				(type default)
			)
			(layer "B.Fab")
		)
		(fp_line
			(start 0.12065 0.3048)
			(end 0.67945 0.3048)
			(stroke
				(width 0.1)
				(type default)
			)
			(layer "B.Fab")
		)
		(fp_line
			(start -0.120396 0.3048)
			(end -0.120396 0.2794)
			(stroke
				(width 0.1)
				(type default)
			)
			(layer "B.Fab")
		)
		(fp_line
			(start -0.67945 0.3048)
			(end -0.120396 0.3048)
			(stroke
				(width 0.1)
				(type default)
			)
			(layer "B.Fab")
		)
		(pad "1" smd circle
			(at 0.40005 0 270)
			(size 0 0)
			(layers "B.Cu" "B.Mask" "B.Paste")
			(net "P0V9_CPU1_RT_2D")
		)
		(pad "2" smd circle
			(at -0.40005 0 270)
			(size 0 0)
			(layers "B.Cu" "B.Mask" "B.Paste")
			(net "GND")
		)
	)
	(footprint ""
		(layer "B.Cu")
		(at 234.315 -215.186514 180)
		(property "Reference" "R274"
			(at 0 0 0)
			(layer "B.SilkS")
			(hide yes)
			(effects
				(font
					(size 1.27 1.27)
				)
				(justify mirror)
			)
		)
		(property "Value" ""
			(at 0 0 0)
			(layer "B.Fab")
			(effects
				(font
					(size 1.27 1.27)
				)
				(justify mirror)
			)
		)
		(duplicate_pad_numbers_are_jumpers no)
		(fp_line
			(start 0.7874 0.4064)
			(end 0.7874 -0.4064)
			(stroke
				(width 0.1524)
				(type default)
			)
			(layer "B.SilkS")
		)
		(fp_line
			(start 0.7874 -0.4064)
			(end -0.7874 -0.4064)
			(stroke
				(width 0.1524)
				(type default)
			)
			(layer "B.SilkS")
		)
		(fp_line
			(start -0.7874 0.4064)
			(end 0.7874 0.4064)
			(stroke
				(width 0.1524)
				(type default)
			)
			(layer "B.SilkS")
		)
		(fp_line
			(start -0.7874 -0.4064)
			(end -0.7874 0.4064)
			(stroke
				(width 0.1524)
				(type default)
			)
			(layer "B.SilkS")
		)
		(fp_line
			(start 0.67945 0.3048)
			(end 0.67945 -0.305054)
			(stroke
				(width 0.1)
				(type default)
			)
			(layer "B.Fab")
		)
		(fp_line
			(start 0.67945 -0.305054)
			(end 0.12065 -0.305054)
			(stroke
				(width 0.1)
				(type default)
			)
			(layer "B.Fab")
		)
		(fp_line
			(start 0.12065 0.3048)
			(end 0.67945 0.3048)
			(stroke
				(width 0.1)
				(type default)
			)
			(layer "B.Fab")
		)
		(fp_line
			(start 0.12065 0.2794)
			(end 0.12065 0.3048)
			(stroke
				(width 0.1)
				(type default)
			)
			(layer "B.Fab")
		)
		(fp_line
			(start 0.12065 -0.2794)
			(end -0.12065 -0.2794)
			(stroke
				(width 0.1)
				(type default)
			)
			(layer "B.Fab")
		)
		(fp_line
			(start 0.12065 -0.305054)
			(end 0.12065 -0.2794)
			(stroke
				(width 0.1)
				(type default)
			)
			(layer "B.Fab")
		)
		(fp_line
			(start -0.120396 0.3048)
			(end -0.120396 0.2794)
			(stroke
				(width 0.1)
				(type default)
			)
			(layer "B.Fab")
		)
		(fp_line
			(start -0.120396 0.2794)
			(end 0.12065 0.2794)
			(stroke
				(width 0.1)
				(type default)
			)
			(layer "B.Fab")
		)
		(fp_line
			(start -0.12065 -0.2794)
			(end -0.12065 -0.3048)
			(stroke
				(width 0.1)
				(type default)
			)
			(layer "B.Fab")
		)
		(fp_line
			(start -0.12065 -0.3048)
			(end -0.67945 -0.3048)
			(stroke
				(width 0.1)
				(type default)
			)
			(layer "B.Fab")
		)
		(fp_line
			(start -0.67945 0.3048)
			(end -0.120396 0.3048)
			(stroke
				(width 0.1)
				(type default)
			)
			(layer "B.Fab")
		)
		(fp_line
			(start -0.67945 -0.3048)
			(end -0.67945 0.3048)
			(stroke
				(width 0.1)
				(type default)
			)
			(layer "B.Fab")
		)
		(pad "1" smd rect
			(at 0.40005 0 180)
			(size 0.4572 0.508)
			(layers "B.Cu" "B.Mask" "B.Paste")
			(net "SMB_CPU0_CPU1_APML_BUF2_SCL_R2")
		)
		(pad "2" smd rect
			(at -0.40005 0 180)
			(size 0.4572 0.508)
			(layers "B.Cu" "B.Mask" "B.Paste")
			(net "SMB_CPU0_CPU1_APML_SCL_R2")
		)
	)
	(footprint ""
		(layer "B.Cu")
		(at 171.2087 -111.183928)
		(property "Reference" "R171"
			(at 0 0 0)
			(layer "B.SilkS")
			(hide yes)
			(effects
				(font
					(size 1.27 1.27)
				)
				(justify mirror)
			)
		)
		(property "Value" ""
			(at 0 0 0)
			(layer "B.Fab")
			(effects
				(font
					(size 1.27 1.27)
				)
				(justify mirror)
			)
		)
		(duplicate_pad_numbers_are_jumpers no)
		(fp_line
			(start -0.7874 -0.4064)
			(end -0.7874 0.4064)
			(stroke
				(width 0.1524)
				(type default)
			)
			(layer "B.SilkS")
		)
		(fp_line
			(start -0.7874 0.4064)
			(end 0.7874 0.4064)
			(stroke
				(width 0.1524)
				(type default)
			)
			(layer "B.SilkS")
		)
		(fp_line
			(start 0.7874 -0.4064)
			(end -0.7874 -0.4064)
			(stroke
				(width 0.1524)
				(type default)
			)
			(layer "B.SilkS")
		)
		(fp_line
			(start 0.7874 0.4064)
			(end 0.7874 -0.4064)
			(stroke
				(width 0.1524)
				(type default)
			)
			(layer "B.SilkS")
		)
		(fp_line
			(start -0.67945 -0.3048)
			(end -0.67945 0.3048)
			(stroke
				(width 0.1)
				(type default)
			)
			(layer "B.Fab")
		)
		(fp_line
			(start -0.67945 0.3048)
			(end -0.120396 0.3048)
			(stroke
				(width 0.1)
				(type default)
			)
			(layer "B.Fab")
		)
		(fp_line
			(start -0.12065 -0.3048)
			(end -0.67945 -0.3048)
			(stroke
				(width 0.1)
				(type default)
			)
			(layer "B.Fab")
		)
		(fp_line
			(start -0.12065 -0.2794)
			(end -0.12065 -0.3048)
			(stroke
				(width 0.1)
				(type default)
			)
			(layer "B.Fab")
		)
		(fp_line
			(start -0.120396 0.2794)
			(end 0.12065 0.2794)
			(stroke
				(width 0.1)
				(type default)
			)
			(layer "B.Fab")
		)
		(fp_line
			(start -0.120396 0.3048)
			(end -0.120396 0.2794)
			(stroke
				(width 0.1)
				(type default)
			)
			(layer "B.Fab")
		)
		(fp_line
			(start 0.12065 -0.305054)
			(end 0.12065 -0.2794)
			(stroke
				(width 0.1)
				(type default)
			)
			(layer "B.Fab")
		)
		(fp_line
			(start 0.12065 -0.2794)
			(end -0.12065 -0.2794)
			(stroke
				(width 0.1)
				(type default)
			)
			(layer "B.Fab")
		)
		(fp_line
			(start 0.12065 0.2794)
			(end 0.12065 0.3048)
			(stroke
				(width 0.1)
				(type default)
			)
			(layer "B.Fab")
		)
		(fp_line
			(start 0.12065 0.3048)
			(end 0.67945 0.3048)
			(stroke
				(width 0.1)
				(type default)
			)
			(layer "B.Fab")
		)
		(fp_line
			(start 0.67945 -0.305054)
			(end 0.12065 -0.305054)
			(stroke
				(width 0.1)
				(type default)
			)
			(layer "B.Fab")
		)
		(fp_line
			(start 0.67945 0.3048)
			(end 0.67945 -0.305054)
			(stroke
				(width 0.1)
				(type default)
			)
			(layer "B.Fab")
		)
		(pad "1" smd circle
			(at 0.40005 0 180)
			(size 0 0)
			(layers "B.Cu" "B.Mask" "B.Paste")
			(net "FM_I3C_CPU1_MUX1_OE_R_N")
		)
		(pad "2" smd circle
			(at -0.40005 0 180)
			(size 0 0)
			(layers "B.Cu" "B.Mask" "B.Paste")
			(net "FM_I3C_CPU1_MUX1_OE_N")
		)
	)
	(footprint ""
		(layer "B.Cu")
		(at 346.545408 -254.95631)
		(property "Reference" "C2520"
			(at 0 0 0)
			(layer "B.SilkS")
			(hide yes)
			(effects
				(font
					(size 1.27 1.27)
				)
				(justify mirror)
			)
		)
		(property "Value" ""
			(at 0 0 0)
			(layer "B.Fab")
			(effects
				(font
					(size 1.27 1.27)
				)
				(justify mirror)
			)
		)
		(duplicate_pad_numbers_are_jumpers no)
		(fp_line
			(start -0.7874 -0.4064)
			(end -0.7874 0.4064)
			(stroke
				(width 0.1524)
				(type default)
			)
			(layer "B.SilkS")
		)
		(fp_line
			(start -0.7874 0.4064)
			(end 0.7874 0.4064)
			(stroke
				(width 0.1524)
				(type default)
			)
			(layer "B.SilkS")
		)
		(fp_line
			(start 0.7874 -0.4064)
			(end -0.7874 -0.4064)
			(stroke
				(width 0.1524)
				(type default)
			)
			(layer "B.SilkS")
		)
		(fp_line
			(start 0.7874 0.4064)
			(end 0.7874 -0.4064)
			(stroke
				(width 0.1524)
				(type default)
			)
			(layer "B.SilkS")
		)
		(fp_line
			(start -0.67945 -0.3048)
			(end -0.67945 0.3048)
			(stroke
				(width 0.1)
				(type default)
			)
			(layer "B.Fab")
		)
		(fp_line
			(start -0.67945 0.3048)
			(end -0.120396 0.3048)
			(stroke
				(width 0.1)
				(type default)
			)
			(layer "B.Fab")
		)
		(fp_line
			(start -0.12065 -0.3048)
			(end -0.67945 -0.3048)
			(stroke
				(width 0.1)
				(type default)
			)
			(layer "B.Fab")
		)
		(fp_line
			(start -0.12065 -0.2794)
			(end -0.12065 -0.3048)
			(stroke
				(width 0.1)
				(type default)
			)
			(layer "B.Fab")
		)
		(fp_line
			(start -0.120396 0.2794)
			(end 0.12065 0.2794)
			(stroke
				(width 0.1)
				(type default)
			)
			(layer "B.Fab")
		)
		(fp_line
			(start -0.120396 0.3048)
			(end -0.120396 0.2794)
			(stroke
				(width 0.1)
				(type default)
			)
			(layer "B.Fab")
		)
		(fp_line
			(start 0.12065 -0.305054)
			(end 0.12065 -0.2794)
			(stroke
				(width 0.1)
				(type default)
			)
			(layer "B.Fab")
		)
		(fp_line
			(start 0.12065 -0.2794)
			(end -0.12065 -0.2794)
			(stroke
				(width 0.1)
				(type default)
			)
			(layer "B.Fab")
		)
		(fp_line
			(start 0.12065 0.2794)
			(end 0.12065 0.3048)
			(stroke
				(width 0.1)
				(type default)
			)
			(layer "B.Fab")
		)
		(fp_line
			(start 0.12065 0.3048)
			(end 0.67945 0.3048)
			(stroke
				(width 0.1)
				(type default)
			)
			(layer "B.Fab")
		)
		(fp_line
			(start 0.67945 -0.305054)
			(end 0.12065 -0.305054)
			(stroke
				(width 0.1)
				(type default)
			)
			(layer "B.Fab")
		)
		(fp_line
			(start 0.67945 0.3048)
			(end 0.67945 -0.305054)
			(stroke
				(width 0.1)
				(type default)
			)
			(layer "B.Fab")
		)
		(pad "1" smd circle
			(at 0.40005 0 180)
			(size 0 0)
			(layers "B.Cu" "B.Mask" "B.Paste")
			(net "PVDD18_S5_P0")
		)
		(pad "2" smd circle
			(at -0.40005 0 180)
			(size 0 0)
			(layers "B.Cu" "B.Mask" "B.Paste")
			(net "GND")
		)
	)
	(footprint ""
		(layer "B.Cu")
		(at 116.499386 -248.479564)
		(property "Reference" "C2331"
			(at 0 0 0)
			(layer "B.SilkS")
			(hide yes)
			(effects
				(font
					(size 1.27 1.27)
				)
				(justify mirror)
			)
		)
		(property "Value" ""
			(at 0 0 0)
			(layer "B.Fab")
			(effects
				(font
					(size 1.27 1.27)
				)
				(justify mirror)
			)
		)
		(duplicate_pad_numbers_are_jumpers no)
		(fp_line
			(start -0.7874 -0.4064)
			(end -0.7874 0.4064)
			(stroke
				(width 0.1524)
				(type default)
			)
			(layer "B.SilkS")
		)
		(fp_line
			(start -0.7874 0.4064)
			(end 0.7874 0.4064)
			(stroke
				(width 0.1524)
				(type default)
			)
			(layer "B.SilkS")
		)
		(fp_line
			(start 0.7874 -0.4064)
			(end -0.7874 -0.4064)
			(stroke
				(width 0.1524)
				(type default)
			)
			(layer "B.SilkS")
		)
		(fp_line
			(start 0.7874 0.4064)
			(end 0.7874 -0.4064)
			(stroke
				(width 0.1524)
				(type default)
			)
			(layer "B.SilkS")
		)
		(fp_line
			(start -0.67945 -0.3048)
			(end -0.67945 0.3048)
			(stroke
				(width 0.1)
				(type default)
			)
			(layer "B.Fab")
		)
		(fp_line
			(start -0.67945 0.3048)
			(end -0.120396 0.3048)
			(stroke
				(width 0.1)
				(type default)
			)
			(layer "B.Fab")
		)
		(fp_line
			(start -0.12065 -0.3048)
			(end -0.67945 -0.3048)
			(stroke
				(width 0.1)
				(type default)
			)
			(layer "B.Fab")
		)
		(fp_line
			(start -0.12065 -0.2794)
			(end -0.12065 -0.3048)
			(stroke
				(width 0.1)
				(type default)
			)
			(layer "B.Fab")
		)
		(fp_line
			(start -0.120396 0.2794)
			(end 0.12065 0.2794)
			(stroke
				(width 0.1)
				(type default)
			)
			(layer "B.Fab")
		)
		(fp_line
			(start -0.120396 0.3048)
			(end -0.120396 0.2794)
			(stroke
				(width 0.1)
				(type default)
			)
			(layer "B.Fab")
		)
		(fp_line
			(start 0.12065 -0.305054)
			(end 0.12065 -0.2794)
			(stroke
				(width 0.1)
				(type default)
			)
			(layer "B.Fab")
		)
		(fp_line
			(start 0.12065 -0.2794)
			(end -0.12065 -0.2794)
			(stroke
				(width 0.1)
				(type default)
			)
			(layer "B.Fab")
		)
		(fp_line
			(start 0.12065 0.2794)
			(end 0.12065 0.3048)
			(stroke
				(width 0.1)
				(type default)
			)
			(layer "B.Fab")
		)
		(fp_line
			(start 0.12065 0.3048)
			(end 0.67945 0.3048)
			(stroke
				(width 0.1)
				(type default)
			)
			(layer "B.Fab")
		)
		(fp_line
			(start 0.67945 -0.305054)
			(end 0.12065 -0.305054)
			(stroke
				(width 0.1)
				(type default)
			)
			(layer "B.Fab")
		)
		(fp_line
			(start 0.67945 0.3048)
			(end 0.67945 -0.305054)
			(stroke
				(width 0.1)
				(type default)
			)
			(layer "B.Fab")
		)
		(pad "1" smd circle
			(at 0.40005 0 180)
			(size 0 0)
			(layers "B.Cu" "B.Mask" "B.Paste")
			(net "PVDDCR_CPU0_P1")
		)
		(pad "2" smd circle
			(at -0.40005 0 180)
			(size 0 0)
			(layers "B.Cu" "B.Mask" "B.Paste")
			(net "GND")
		)
	)
	(footprint ""
		(layer "B.Cu")
		(at 108.371386 -267.529564)
		(property "Reference" "C2380"
			(at 0 0 0)
			(layer "B.SilkS")
			(hide yes)
			(effects
				(font
					(size 1.27 1.27)
				)
				(justify mirror)
			)
		)
		(property "Value" ""
			(at 0 0 0)
			(layer "B.Fab")
			(effects
				(font
					(size 1.27 1.27)
				)
				(justify mirror)
			)
		)
		(duplicate_pad_numbers_are_jumpers no)
		(fp_line
			(start -0.7874 -0.4064)
			(end -0.7874 0.4064)
			(stroke
				(width 0.1524)
				(type default)
			)
			(layer "B.SilkS")
		)
		(fp_line
			(start -0.7874 0.4064)
			(end 0.7874 0.4064)
			(stroke
				(width 0.1524)
				(type default)
			)
			(layer "B.SilkS")
		)
		(fp_line
			(start 0.7874 -0.4064)
			(end -0.7874 -0.4064)
			(stroke
				(width 0.1524)
				(type default)
			)
			(layer "B.SilkS")
		)
		(fp_line
			(start 0.7874 0.4064)
			(end 0.7874 -0.4064)
			(stroke
				(width 0.1524)
				(type default)
			)
			(layer "B.SilkS")
		)
		(fp_line
			(start -0.67945 -0.3048)
			(end -0.67945 0.3048)
			(stroke
				(width 0.1)
				(type default)
			)
			(layer "B.Fab")
		)
		(fp_line
			(start -0.67945 0.3048)
			(end -0.120396 0.3048)
			(stroke
				(width 0.1)
				(type default)
			)
			(layer "B.Fab")
		)
		(fp_line
			(start -0.12065 -0.3048)
			(end -0.67945 -0.3048)
			(stroke
				(width 0.1)
				(type default)
			)
			(layer "B.Fab")
		)
		(fp_line
			(start -0.12065 -0.2794)
			(end -0.12065 -0.3048)
			(stroke
				(width 0.1)
				(type default)
			)
			(layer "B.Fab")
		)
		(fp_line
			(start -0.120396 0.2794)
			(end 0.12065 0.2794)
			(stroke
				(width 0.1)
				(type default)
			)
			(layer "B.Fab")
		)
		(fp_line
			(start -0.120396 0.3048)
			(end -0.120396 0.2794)
			(stroke
				(width 0.1)
				(type default)
			)
			(layer "B.Fab")
		)
		(fp_line
			(start 0.12065 -0.305054)
			(end 0.12065 -0.2794)
			(stroke
				(width 0.1)
				(type default)
			)
			(layer "B.Fab")
		)
		(fp_line
			(start 0.12065 -0.2794)
			(end -0.12065 -0.2794)
			(stroke
				(width 0.1)
				(type default)
			)
			(layer "B.Fab")
		)
		(fp_line
			(start 0.12065 0.2794)
			(end 0.12065 0.3048)
			(stroke
				(width 0.1)
				(type default)
			)
			(layer "B.Fab")
		)
		(fp_line
			(start 0.12065 0.3048)
			(end 0.67945 0.3048)
			(stroke
				(width 0.1)
				(type default)
			)
			(layer "B.Fab")
		)
		(fp_line
			(start 0.67945 -0.305054)
			(end 0.12065 -0.305054)
			(stroke
				(width 0.1)
				(type default)
			)
			(layer "B.Fab")
		)
		(fp_line
			(start 0.67945 0.3048)
			(end 0.67945 -0.305054)
			(stroke
				(width 0.1)
				(type default)
			)
			(layer "B.Fab")
		)
		(pad "1" smd circle
			(at 0.40005 0 180)
			(size 0 0)
			(layers "B.Cu" "B.Mask" "B.Paste")
			(net "PVDDCR_CPU1_P1")
		)
		(pad "2" smd circle
			(at -0.40005 0 180)
			(size 0 0)
			(layers "B.Cu" "B.Mask" "B.Paste")
			(net "GND")
		)
	)
	(footprint ""
		(layer "B.Cu")
		(at 363.287056 -177.894996 -90)
		(property "Reference" "PC485_1"
			(at 0 0 90)
			(layer "B.SilkS")
			(hide yes)
			(effects
				(font
					(size 1.27 1.27)
				)
				(justify mirror)
			)
		)
		(property "Value" ""
			(at 0 0 90)
			(layer "B.Fab")
			(effects
				(font
					(size 1.27 1.27)
				)
				(justify mirror)
			)
		)
		(duplicate_pad_numbers_are_jumpers no)
		(fp_line
			(start -1.524 0.762)
			(end 1.524 0.762)
			(stroke
				(width 0.1524)
				(type default)
			)
			(layer "B.SilkS")
		)
		(fp_line
			(start 1.524 0.762)
			(end 1.524 -0.762)
			(stroke
				(width 0.1524)
				(type default)
			)
			(layer "B.SilkS")
		)
		(fp_line
			(start -1.524 -0.762)
			(end -1.524 0.762)
			(stroke
				(width 0.1524)
				(type default)
			)
			(layer "B.SilkS")
		)
		(fp_line
			(start 1.524 -0.762)
			(end -1.524 -0.762)
			(stroke
				(width 0.1524)
				(type default)
			)
			(layer "B.SilkS")
		)
		(fp_line
			(start -1.1049 0.724916)
			(end -1.1049 -0.724916)
			(stroke
				(width 0.1)
				(type default)
			)
			(layer "B.Fab")
		)
		(fp_line
			(start 1.1049 0.724916)
			(end -1.1049 0.724916)
			(stroke
				(width 0.1)
				(type default)
			)
			(layer "B.Fab")
		)
		(fp_line
			(start -1.1049 -0.724916)
			(end 1.1049 -0.724916)
			(stroke
				(width 0.1)
				(type default)
			)
			(layer "B.Fab")
		)
		(fp_line
			(start 1.1049 -0.724916)
			(end 1.1049 0.724916)
			(stroke
				(width 0.1)
				(type default)
			)
			(layer "B.Fab")
		)
		(pad "1" smd rect
			(at 0.889 0 270)
			(size 1.016 1.27)
			(layers "B.Cu" "B.Mask" "B.Paste")
			(net "SW_P12V_AUX_PVDDCR_CPU0_P0_FLT")
		)
		(pad "2" smd rect
			(at -0.889 0 270)
			(size 1.016 1.27)
			(layers "B.Cu" "B.Mask" "B.Paste")
			(net "GND")
		)
	)
	(footprint ""
		(layer "B.Cu")
		(at 131.716526 -408.517344 90)
		(property "Reference" "C6736"
			(at 0 0 90)
			(layer "B.SilkS")
			(hide yes)
			(effects
				(font
					(size 1.27 1.27)
				)
				(justify mirror)
			)
		)
		(property "Value" ""
			(at 0 0 90)
			(layer "B.Fab")
			(effects
				(font
					(size 1.27 1.27)
				)
				(justify mirror)
			)
		)
		(duplicate_pad_numbers_are_jumpers no)
		(fp_line
			(start 0.299974 -0.150114)
			(end -0.299974 -0.150114)
			(stroke
				(width 0.1)
				(type default)
			)
			(layer "B.Fab")
		)
		(fp_line
			(start -0.299974 -0.150114)
			(end -0.299974 0.150114)
			(stroke
				(width 0.1)
				(type default)
			)
			(layer "B.Fab")
		)
		(fp_line
			(start 0.299974 0.150114)
			(end 0.299974 -0.150114)
			(stroke
				(width 0.1)
				(type default)
			)
			(layer "B.Fab")
		)
		(fp_line
			(start -0.299974 0.150114)
			(end 0.299974 0.150114)
			(stroke
				(width 0.1)
				(type default)
			)
			(layer "B.Fab")
		)
		(pad "1" smd rect
			(at 0.2667 0 270)
			(size 0.3048 0.381)
			(layers "B.Cu" "B.Mask" "B.Paste")
			(net "P5E_CPU1_P3_TX_BUF_C_DN<5>")
		)
		(pad "2" smd rect
			(at -0.2667 0 270)
			(size 0.3048 0.381)
			(layers "B.Cu" "B.Mask" "B.Paste")
			(net "P5E_CPU1_P3_TX_BUF_DN<5>")
		)
	)
	(footprint ""
		(layer "B.Cu")
		(at 125.468634 -268.855952 60)
		(property "Reference" "C2376"
			(at 0 0 60)
			(layer "B.SilkS")
			(hide yes)
			(effects
				(font
					(size 1.27 1.27)
				)
				(justify mirror)
			)
		)
		(property "Value" ""
			(at 0 0 60)
			(layer "B.Fab")
			(effects
				(font
					(size 1.27 1.27)
				)
				(justify mirror)
			)
		)
		(duplicate_pad_numbers_are_jumpers no)
		(fp_line
			(start -0.787516 -0.406438)
			(end -0.787425 0.40652)
			(stroke
				(width 0.1524)
				(type default)
			)
			(layer "B.SilkS")
		)
		(fp_line
			(start -0.787425 0.40652)
			(end 0.787516 0.406438)
			(stroke
				(width 0.1524)
				(type default)
			)
			(layer "B.SilkS")
		)
		(fp_line
			(start 0.787425 -0.40652)
			(end -0.787516 -0.406438)
			(stroke
				(width 0.1524)
				(type default)
			)
			(layer "B.SilkS")
		)
		(fp_line
			(start 0.787516 0.406438)
			(end 0.787425 -0.40652)
			(stroke
				(width 0.1524)
				(type default)
			)
			(layer "B.SilkS")
		)
		(fp_line
			(start -0.679568 -0.304811)
			(end -0.6795 0.304908)
			(stroke
				(width 0.1)
				(type default)
			)
			(layer "B.Fab")
		)
		(fp_line
			(start -0.120605 -0.304905)
			(end -0.679568 -0.304811)
			(stroke
				(width 0.1)
				(type default)
			)
			(layer "B.Fab")
		)
		(fp_line
			(start -0.120554 -0.279418)
			(end -0.120605 -0.304905)
			(stroke
				(width 0.1)
				(type default)
			)
			(layer "B.Fab")
		)
		(fp_line
			(start 0.120629 -0.30516)
			(end 0.120587 -0.279326)
			(stroke
				(width 0.1)
				(type default)
			)
			(layer "B.Fab")
		)
		(fp_line
			(start 0.120587 -0.279326)
			(end -0.120554 -0.279418)
			(stroke
				(width 0.1)
				(type default)
			)
			(layer "B.Fab")
		)
		(fp_line
			(start -0.6795 0.304908)
			(end -0.120316 0.304686)
			(stroke
				(width 0.1)
				(type default)
			)
			(layer "B.Fab")
		)
		(fp_line
			(start 0.679373 -0.305128)
			(end 0.120629 -0.30516)
			(stroke
				(width 0.1)
				(type default)
			)
			(layer "B.Fab")
		)
		(fp_line
			(start -0.12024 0.279419)
			(end 0.120554 0.279418)
			(stroke
				(width 0.1)
				(type default)
			)
			(layer "B.Fab")
		)
		(fp_line
			(start -0.120316 0.304686)
			(end -0.12024 0.279419)
			(stroke
				(width 0.1)
				(type default)
			)
			(layer "B.Fab")
		)
		(fp_line
			(start 0.120554 0.279418)
			(end 0.120605 0.304905)
			(stroke
				(width 0.1)
				(type default)
			)
			(layer "B.Fab")
		)
		(fp_line
			(start 0.120605 0.304905)
			(end 0.679568 0.304811)
			(stroke
				(width 0.1)
				(type default)
			)
			(layer "B.Fab")
		)
		(fp_line
			(start 0.679568 0.304811)
			(end 0.679373 -0.305128)
			(stroke
				(width 0.1)
				(type default)
			)
			(layer "B.Fab")
		)
		(pad "1" smd circle
			(at 0.40005 0 240)
			(size 0 0)
			(layers "B.Cu" "B.Mask" "B.Paste")
			(net "PVDDCR_CPU1_P1")
		)
		(pad "2" smd circle
			(at -0.40005 0 240)
			(size 0 0)
			(layers "B.Cu" "B.Mask" "B.Paste")
			(net "GND")
		)
	)
	(footprint ""
		(layer "B.Cu")
		(at 254.635 -337.37804 180)
		(property "Reference" "R1375"
			(at 0 0 0)
			(layer "B.SilkS")
			(hide yes)
			(effects
				(font
					(size 1.27 1.27)
				)
				(justify mirror)
			)
		)
		(property "Value" ""
			(at 0 0 0)
			(layer "B.Fab")
			(effects
				(font
					(size 1.27 1.27)
				)
				(justify mirror)
			)
		)
		(duplicate_pad_numbers_are_jumpers no)
		(fp_line
			(start 0.32512 0.175006)
			(end 0.32512 -0.175006)
			(stroke
				(width 0.1)
				(type default)
			)
			(layer "B.Fab")
		)
		(fp_line
			(start 0.32512 -0.175006)
			(end -0.32512 -0.175006)
			(stroke
				(width 0.1)
				(type default)
			)
			(layer "B.Fab")
		)
		(fp_line
			(start -0.32512 0.175006)
			(end 0.32512 0.175006)
			(stroke
				(width 0.1)
				(type default)
			)
			(layer "B.Fab")
		)
		(fp_line
			(start -0.32512 -0.175006)
			(end -0.32512 0.175006)
			(stroke
				(width 0.1)
				(type default)
			)
			(layer "B.Fab")
		)
		(pad "1" smd rect
			(at 0.2667 0)
			(size 0.3048 0.381)
			(layers "B.Cu" "B.Mask" "B.Paste")
			(net "P1V8_CPU0_RT_1D")
		)
		(pad "2" smd rect
			(at -0.2667 0 180)
			(size 0.3048 0.381)
			(layers "B.Cu" "B.Mask" "B.Paste")
			(net "SMB_RT_CPU0_P3_ROM_MUX_2D_R_SDA")
		)
	)
	(footprint ""
		(layer "B.Cu")
		(at 113.841022 -27.04846)
		(property "Reference" "C6113"
			(at 0 0 0)
			(layer "B.SilkS")
			(hide yes)
			(effects
				(font
					(size 1.27 1.27)
				)
				(justify mirror)
			)
		)
		(property "Value" ""
			(at 0 0 0)
			(layer "B.Fab")
			(effects
				(font
					(size 1.27 1.27)
				)
				(justify mirror)
			)
		)
		(duplicate_pad_numbers_are_jumpers no)
		(fp_line
			(start -0.7874 -0.4064)
			(end -0.7874 0.4064)
			(stroke
				(width 0.1524)
				(type default)
			)
			(layer "B.SilkS")
		)
		(fp_line
			(start -0.7874 0.4064)
			(end 0.7874 0.4064)
			(stroke
				(width 0.1524)
				(type default)
			)
			(layer "B.SilkS")
		)
		(fp_line
			(start 0.7874 -0.4064)
			(end -0.7874 -0.4064)
			(stroke
				(width 0.1524)
				(type default)
			)
			(layer "B.SilkS")
		)
		(fp_line
			(start 0.7874 0.4064)
			(end 0.7874 -0.4064)
			(stroke
				(width 0.1524)
				(type default)
			)
			(layer "B.SilkS")
		)
		(fp_line
			(start -0.67945 -0.3048)
			(end -0.67945 0.3048)
			(stroke
				(width 0.1)
				(type default)
			)
			(layer "B.Fab")
		)
		(fp_line
			(start -0.67945 0.3048)
			(end -0.120396 0.3048)
			(stroke
				(width 0.1)
				(type default)
			)
			(layer "B.Fab")
		)
		(fp_line
			(start -0.12065 -0.3048)
			(end -0.67945 -0.3048)
			(stroke
				(width 0.1)
				(type default)
			)
			(layer "B.Fab")
		)
		(fp_line
			(start -0.12065 -0.2794)
			(end -0.12065 -0.3048)
			(stroke
				(width 0.1)
				(type default)
			)
			(layer "B.Fab")
		)
		(fp_line
			(start -0.120396 0.2794)
			(end 0.12065 0.2794)
			(stroke
				(width 0.1)
				(type default)
			)
			(layer "B.Fab")
		)
		(fp_line
			(start -0.120396 0.3048)
			(end -0.120396 0.2794)
			(stroke
				(width 0.1)
				(type default)
			)
			(layer "B.Fab")
		)
		(fp_line
			(start 0.12065 -0.305054)
			(end 0.12065 -0.2794)
			(stroke
				(width 0.1)
				(type default)
			)
			(layer "B.Fab")
		)
		(fp_line
			(start 0.12065 -0.2794)
			(end -0.12065 -0.2794)
			(stroke
				(width 0.1)
				(type default)
			)
			(layer "B.Fab")
		)
		(fp_line
			(start 0.12065 0.2794)
			(end 0.12065 0.3048)
			(stroke
				(width 0.1)
				(type default)
			)
			(layer "B.Fab")
		)
		(fp_line
			(start 0.12065 0.3048)
			(end 0.67945 0.3048)
			(stroke
				(width 0.1)
				(type default)
			)
			(layer "B.Fab")
		)
		(fp_line
			(start 0.67945 -0.305054)
			(end 0.12065 -0.305054)
			(stroke
				(width 0.1)
				(type default)
			)
			(layer "B.Fab")
		)
		(fp_line
			(start 0.67945 0.3048)
			(end 0.67945 -0.305054)
			(stroke
				(width 0.1)
				(type default)
			)
			(layer "B.Fab")
		)
		(pad "1" smd circle
			(at 0.40005 0 180)
			(size 0 0)
			(layers "B.Cu" "B.Mask" "B.Paste")
			(net "P1V2_CPU0_USB2_DVDD12")
		)
		(pad "2" smd circle
			(at -0.40005 0 180)
			(size 0 0)
			(layers "B.Cu" "B.Mask" "B.Paste")
			(net "GND")
		)
	)
	(footprint ""
		(layer "B.Cu")
		(at 371.297454 -266.00531)
		(property "Reference" "C2652"
			(at 0 0 0)
			(layer "B.SilkS")
			(hide yes)
			(effects
				(font
					(size 1.27 1.27)
				)
				(justify mirror)
			)
		)
		(property "Value" ""
			(at 0 0 0)
			(layer "B.Fab")
			(effects
				(font
					(size 1.27 1.27)
				)
				(justify mirror)
			)
		)
		(duplicate_pad_numbers_are_jumpers no)
		(fp_line
			(start -0.7874 -0.4064)
			(end -0.7874 0.4064)
			(stroke
				(width 0.1524)
				(type default)
			)
			(layer "B.SilkS")
		)
		(fp_line
			(start -0.7874 0.4064)
			(end 0.7874 0.4064)
			(stroke
				(width 0.1524)
				(type default)
			)
			(layer "B.SilkS")
		)
		(fp_line
			(start 0.7874 -0.4064)
			(end -0.7874 -0.4064)
			(stroke
				(width 0.1524)
				(type default)
			)
			(layer "B.SilkS")
		)
		(fp_line
			(start 0.7874 0.4064)
			(end 0.7874 -0.4064)
			(stroke
				(width 0.1524)
				(type default)
			)
			(layer "B.SilkS")
		)
		(fp_line
			(start -0.67945 -0.3048)
			(end -0.67945 0.3048)
			(stroke
				(width 0.1)
				(type default)
			)
			(layer "B.Fab")
		)
		(fp_line
			(start -0.67945 0.3048)
			(end -0.120396 0.3048)
			(stroke
				(width 0.1)
				(type default)
			)
			(layer "B.Fab")
		)
		(fp_line
			(start -0.12065 -0.3048)
			(end -0.67945 -0.3048)
			(stroke
				(width 0.1)
				(type default)
			)
			(layer "B.Fab")
		)
		(fp_line
			(start -0.12065 -0.2794)
			(end -0.12065 -0.3048)
			(stroke
				(width 0.1)
				(type default)
			)
			(layer "B.Fab")
		)
		(fp_line
			(start -0.120396 0.2794)
			(end 0.12065 0.2794)
			(stroke
				(width 0.1)
				(type default)
			)
			(layer "B.Fab")
		)
		(fp_line
			(start -0.120396 0.3048)
			(end -0.120396 0.2794)
			(stroke
				(width 0.1)
				(type default)
			)
			(layer "B.Fab")
		)
		(fp_line
			(start 0.12065 -0.305054)
			(end 0.12065 -0.2794)
			(stroke
				(width 0.1)
				(type default)
			)
			(layer "B.Fab")
		)
		(fp_line
			(start 0.12065 -0.2794)
			(end -0.12065 -0.2794)
			(stroke
				(width 0.1)
				(type default)
			)
			(layer "B.Fab")
		)
		(fp_line
			(start 0.12065 0.2794)
			(end 0.12065 0.3048)
			(stroke
				(width 0.1)
				(type default)
			)
			(layer "B.Fab")
		)
		(fp_line
			(start 0.12065 0.3048)
			(end 0.67945 0.3048)
			(stroke
				(width 0.1)
				(type default)
			)
			(layer "B.Fab")
		)
		(fp_line
			(start 0.67945 -0.305054)
			(end 0.12065 -0.305054)
			(stroke
				(width 0.1)
				(type default)
			)
			(layer "B.Fab")
		)
		(fp_line
			(start 0.67945 0.3048)
			(end 0.67945 -0.305054)
			(stroke
				(width 0.1)
				(type default)
			)
			(layer "B.Fab")
		)
		(pad "1" smd circle
			(at 0.40005 0 180)
			(size 0 0)
			(layers "B.Cu" "B.Mask" "B.Paste")
			(net "PVDD11_S3_P0")
		)
		(pad "2" smd circle
			(at -0.40005 0 180)
			(size 0 0)
			(layers "B.Cu" "B.Mask" "B.Paste")
			(net "GND")
		)
	)
	(footprint ""
		(layer "B.Cu")
		(at 107.675934 -256.012442 -90)
		(property "Reference" "C2408"
			(at 0 0 90)
			(layer "B.SilkS")
			(hide yes)
			(effects
				(font
					(size 1.27 1.27)
				)
				(justify mirror)
			)
		)
		(property "Value" ""
			(at 0 0 90)
			(layer "B.Fab")
			(effects
				(font
					(size 1.27 1.27)
				)
				(justify mirror)
			)
		)
		(duplicate_pad_numbers_are_jumpers no)
		(fp_line
			(start -0.7874 0.4064)
			(end 0.7874 0.4064)
			(stroke
				(width 0.1524)
				(type default)
			)
			(layer "B.SilkS")
		)
		(fp_line
			(start 0.7874 0.4064)
			(end 0.7874 -0.4064)
			(stroke
				(width 0.1524)
				(type default)
			)
			(layer "B.SilkS")
		)
		(fp_line
			(start -0.7874 -0.4064)
			(end -0.7874 0.4064)
			(stroke
				(width 0.1524)
				(type default)
			)
			(layer "B.SilkS")
		)
		(fp_line
			(start 0.7874 -0.4064)
			(end -0.7874 -0.4064)
			(stroke
				(width 0.1524)
				(type default)
			)
			(layer "B.SilkS")
		)
		(fp_line
			(start -0.67945 0.3048)
			(end -0.120396 0.3048)
			(stroke
				(width 0.1)
				(type default)
			)
			(layer "B.Fab")
		)
		(fp_line
			(start -0.120396 0.3048)
			(end -0.120396 0.2794)
			(stroke
				(width 0.1)
				(type default)
			)
			(layer "B.Fab")
		)
		(fp_line
			(start 0.12065 0.3048)
			(end 0.67945 0.3048)
			(stroke
				(width 0.1)
				(type default)
			)
			(layer "B.Fab")
		)
		(fp_line
			(start 0.67945 0.3048)
			(end 0.67945 -0.305054)
			(stroke
				(width 0.1)
				(type default)
			)
			(layer "B.Fab")
		)
		(fp_line
			(start -0.120396 0.2794)
			(end 0.12065 0.2794)
			(stroke
				(width 0.1)
				(type default)
			)
			(layer "B.Fab")
		)
		(fp_line
			(start 0.12065 0.2794)
			(end 0.12065 0.3048)
			(stroke
				(width 0.1)
				(type default)
			)
			(layer "B.Fab")
		)
		(fp_line
			(start -0.12065 -0.2794)
			(end -0.12065 -0.3048)
			(stroke
				(width 0.1)
				(type default)
			)
			(layer "B.Fab")
		)
		(fp_line
			(start 0.12065 -0.2794)
			(end -0.12065 -0.2794)
			(stroke
				(width 0.1)
				(type default)
			)
			(layer "B.Fab")
		)
		(fp_line
			(start -0.67945 -0.3048)
			(end -0.67945 0.3048)
			(stroke
				(width 0.1)
				(type default)
			)
			(layer "B.Fab")
		)
		(fp_line
			(start -0.12065 -0.3048)
			(end -0.67945 -0.3048)
			(stroke
				(width 0.1)
				(type default)
			)
			(layer "B.Fab")
		)
		(fp_line
			(start 0.12065 -0.305054)
			(end 0.12065 -0.2794)
			(stroke
				(width 0.1)
				(type default)
			)
			(layer "B.Fab")
		)
		(fp_line
			(start 0.67945 -0.305054)
			(end 0.12065 -0.305054)
			(stroke
				(width 0.1)
				(type default)
			)
			(layer "B.Fab")
		)
		(pad "1" smd circle
			(at 0.40005 0 90)
			(size 0 0)
			(layers "B.Cu" "B.Mask" "B.Paste")
			(net "PVDDCR_SOC_P1")
		)
		(pad "2" smd circle
			(at -0.40005 0 90)
			(size 0 0)
			(layers "B.Cu" "B.Mask" "B.Paste")
			(net "GND")
		)
	)
	(footprint ""
		(layer "B.Cu")
		(at 384.113278 -139.186158 180)
		(property "Reference" "PC7"
			(at 0 0 0)
			(layer "B.SilkS")
			(hide yes)
			(effects
				(font
					(size 1.27 1.27)
				)
				(justify mirror)
			)
		)
		(property "Value" ""
			(at 0 0 0)
			(layer "B.Fab")
			(effects
				(font
					(size 1.27 1.27)
				)
				(justify mirror)
			)
		)
		(duplicate_pad_numbers_are_jumpers no)
		(fp_line
			(start 0.7874 0.4064)
			(end 0.7874 -0.4064)
			(stroke
				(width 0.1524)
				(type default)
			)
			(layer "B.SilkS")
		)
		(fp_line
			(start 0.7874 -0.4064)
			(end -0.7874 -0.4064)
			(stroke
				(width 0.1524)
				(type default)
			)
			(layer "B.SilkS")
		)
		(fp_line
			(start -0.7874 0.4064)
			(end 0.7874 0.4064)
			(stroke
				(width 0.1524)
				(type default)
			)
			(layer "B.SilkS")
		)
		(fp_line
			(start -0.7874 -0.4064)
			(end -0.7874 0.4064)
			(stroke
				(width 0.1524)
				(type default)
			)
			(layer "B.SilkS")
		)
		(fp_line
			(start 0.67945 0.3048)
			(end 0.67945 -0.305054)
			(stroke
				(width 0.1)
				(type default)
			)
			(layer "B.Fab")
		)
		(fp_line
			(start 0.67945 -0.305054)
			(end 0.12065 -0.305054)
			(stroke
				(width 0.1)
				(type default)
			)
			(layer "B.Fab")
		)
		(fp_line
			(start 0.12065 0.3048)
			(end 0.67945 0.3048)
			(stroke
				(width 0.1)
				(type default)
			)
			(layer "B.Fab")
		)
		(fp_line
			(start 0.12065 0.2794)
			(end 0.12065 0.3048)
			(stroke
				(width 0.1)
				(type default)
			)
			(layer "B.Fab")
		)
		(fp_line
			(start 0.12065 -0.2794)
			(end -0.12065 -0.2794)
			(stroke
				(width 0.1)
				(type default)
			)
			(layer "B.Fab")
		)
		(fp_line
			(start 0.12065 -0.305054)
			(end 0.12065 -0.2794)
			(stroke
				(width 0.1)
				(type default)
			)
			(layer "B.Fab")
		)
		(fp_line
			(start -0.120396 0.3048)
			(end -0.120396 0.2794)
			(stroke
				(width 0.1)
				(type default)
			)
			(layer "B.Fab")
		)
		(fp_line
			(start -0.120396 0.2794)
			(end 0.12065 0.2794)
			(stroke
				(width 0.1)
				(type default)
			)
			(layer "B.Fab")
		)
		(fp_line
			(start -0.12065 -0.2794)
			(end -0.12065 -0.3048)
			(stroke
				(width 0.1)
				(type default)
			)
			(layer "B.Fab")
		)
		(fp_line
			(start -0.12065 -0.3048)
			(end -0.67945 -0.3048)
			(stroke
				(width 0.1)
				(type default)
			)
			(layer "B.Fab")
		)
		(fp_line
			(start -0.67945 0.3048)
			(end -0.120396 0.3048)
			(stroke
				(width 0.1)
				(type default)
			)
			(layer "B.Fab")
		)
		(fp_line
			(start -0.67945 -0.3048)
			(end -0.67945 0.3048)
			(stroke
				(width 0.1)
				(type default)
			)
			(layer "B.Fab")
		)
		(pad "1" smd circle
			(at 0.40005 0)
			(size 0 0)
			(layers "B.Cu" "B.Mask" "B.Paste")
			(net "PVDDCR_CPU0_P0_VINSEN")
		)
		(pad "2" smd circle
			(at -0.40005 0)
			(size 0 0)
			(layers "B.Cu" "B.Mask" "B.Paste")
			(net "GND")
		)
	)
	(footprint ""
		(layer "B.Cu")
		(at 70.252336 -384.575558)
		(property "Reference" "L3"
			(at 0 0 0)
			(layer "B.SilkS")
			(hide yes)
			(effects
				(font
					(size 1.27 1.27)
				)
				(justify mirror)
			)
		)
		(property "Value" ""
			(at 0 0 0)
			(layer "B.Fab")
			(effects
				(font
					(size 1.27 1.27)
				)
				(justify mirror)
			)
		)
		(duplicate_pad_numbers_are_jumpers no)
		(fp_line
			(start -1.63576 -0.8128)
			(end -1.63576 0.8128)
			(stroke
				(width 0.1524)
				(type default)
			)
			(layer "B.SilkS")
		)
		(fp_line
			(start -1.63576 0.8128)
			(end 1.63576 0.8128)
			(stroke
				(width 0.1524)
				(type default)
			)
			(layer "B.SilkS")
		)
		(fp_line
			(start 1.63576 -0.8128)
			(end -1.63576 -0.8128)
			(stroke
				(width 0.1524)
				(type default)
			)
			(layer "B.SilkS")
		)
		(fp_line
			(start 1.63576 -0.8128)
			(end 1.63576 0.8128)
			(stroke
				(width 0.1524)
				(type default)
			)
			(layer "B.SilkS")
		)
		(fp_line
			(start -1.560576 -0.738632)
			(end 1.56083 -0.738632)
			(stroke
				(width 0.1)
				(type default)
			)
			(layer "B.Fab")
		)
		(fp_line
			(start -1.560576 0.7366)
			(end -1.560576 -0.738632)
			(stroke
				(width 0.1)
				(type default)
			)
			(layer "B.Fab")
		)
		(fp_line
			(start -1.524 0.7366)
			(end -1.560576 0.7366)
			(stroke
				(width 0.1)
				(type default)
			)
			(layer "B.Fab")
		)
		(fp_line
			(start 1.524 0.7366)
			(end -1.524 0.7366)
			(stroke
				(width 0.1)
				(type default)
			)
			(layer "B.Fab")
		)
		(fp_line
			(start 1.56083 -0.738632)
			(end 1.56083 0.7366)
			(stroke
				(width 0.1)
				(type default)
			)
			(layer "B.Fab")
		)
		(fp_line
			(start 1.56083 0.7366)
			(end 1.524 0.7366)
			(stroke
				(width 0.1)
				(type default)
			)
			(layer "B.Fab")
		)
		(pad "1" smd rect
			(at 0.94996 0)
			(size 1.1176 1.3716)
			(layers "B.Cu" "B.Mask" "B.Paste")
			(net "P1V8_CPU1_RT_1D")
		)
		(pad "2" smd rect
			(at -0.94996 0)
			(size 1.1176 1.3716)
			(layers "B.Cu" "B.Mask" "B.Paste")
			(net "P1V8_CPU1_RT0_1A")
		)
	)
	(footprint ""
		(layer "B.Cu")
		(at 348.913958 -249.36831 180)
		(property "Reference" "C2167"
			(at 0 0 0)
			(layer "B.SilkS")
			(hide yes)
			(effects
				(font
					(size 1.27 1.27)
				)
				(justify mirror)
			)
		)
		(property "Value" ""
			(at 0 0 0)
			(layer "B.Fab")
			(effects
				(font
					(size 1.27 1.27)
				)
				(justify mirror)
			)
		)
		(duplicate_pad_numbers_are_jumpers no)
		(fp_line
			(start 0.7874 0.4064)
			(end 0.7874 -0.4064)
			(stroke
				(width 0.1524)
				(type default)
			)
			(layer "B.SilkS")
		)
		(fp_line
			(start 0.7874 -0.4064)
			(end -0.7874 -0.4064)
			(stroke
				(width 0.1524)
				(type default)
			)
			(layer "B.SilkS")
		)
		(fp_line
			(start -0.7874 0.4064)
			(end 0.7874 0.4064)
			(stroke
				(width 0.1524)
				(type default)
			)
			(layer "B.SilkS")
		)
		(fp_line
			(start -0.7874 -0.4064)
			(end -0.7874 0.4064)
			(stroke
				(width 0.1524)
				(type default)
			)
			(layer "B.SilkS")
		)
		(fp_line
			(start 0.67945 0.3048)
			(end 0.67945 -0.305054)
			(stroke
				(width 0.1)
				(type default)
			)
			(layer "B.Fab")
		)
		(fp_line
			(start 0.67945 -0.305054)
			(end 0.12065 -0.305054)
			(stroke
				(width 0.1)
				(type default)
			)
			(layer "B.Fab")
		)
		(fp_line
			(start 0.12065 0.3048)
			(end 0.67945 0.3048)
			(stroke
				(width 0.1)
				(type default)
			)
			(layer "B.Fab")
		)
		(fp_line
			(start 0.12065 0.2794)
			(end 0.12065 0.3048)
			(stroke
				(width 0.1)
				(type default)
			)
			(layer "B.Fab")
		)
		(fp_line
			(start 0.12065 -0.2794)
			(end -0.12065 -0.2794)
			(stroke
				(width 0.1)
				(type default)
			)
			(layer "B.Fab")
		)
		(fp_line
			(start 0.12065 -0.305054)
			(end 0.12065 -0.2794)
			(stroke
				(width 0.1)
				(type default)
			)
			(layer "B.Fab")
		)
		(fp_line
			(start -0.120396 0.3048)
			(end -0.120396 0.2794)
			(stroke
				(width 0.1)
				(type default)
			)
			(layer "B.Fab")
		)
		(fp_line
			(start -0.120396 0.2794)
			(end 0.12065 0.2794)
			(stroke
				(width 0.1)
				(type default)
			)
			(layer "B.Fab")
		)
		(fp_line
			(start -0.12065 -0.2794)
			(end -0.12065 -0.3048)
			(stroke
				(width 0.1)
				(type default)
			)
			(layer "B.Fab")
		)
		(fp_line
			(start -0.12065 -0.3048)
			(end -0.67945 -0.3048)
			(stroke
				(width 0.1)
				(type default)
			)
			(layer "B.Fab")
		)
		(fp_line
			(start -0.67945 0.3048)
			(end -0.120396 0.3048)
			(stroke
				(width 0.1)
				(type default)
			)
			(layer "B.Fab")
		)
		(fp_line
			(start -0.67945 -0.3048)
			(end -0.67945 0.3048)
			(stroke
				(width 0.1)
				(type default)
			)
			(layer "B.Fab")
		)
		(pad "1" smd circle
			(at 0.40005 0)
			(size 0 0)
			(layers "B.Cu" "B.Mask" "B.Paste")
			(net "PVDDCR_CPU0_P0")
		)
		(pad "2" smd circle
			(at -0.40005 0)
			(size 0 0)
			(layers "B.Cu" "B.Mask" "B.Paste")
			(net "GND")
		)
	)
	(footprint ""
		(layer "B.Cu")
		(at 113.705386 -250.257564)
		(property "Reference" "C2316"
			(at 0 0 0)
			(layer "B.SilkS")
			(hide yes)
			(effects
				(font
					(size 1.27 1.27)
				)
				(justify mirror)
			)
		)
		(property "Value" ""
			(at 0 0 0)
			(layer "B.Fab")
			(effects
				(font
					(size 1.27 1.27)
				)
				(justify mirror)
			)
		)
		(duplicate_pad_numbers_are_jumpers no)
		(fp_line
			(start -0.7874 -0.4064)
			(end -0.7874 0.4064)
			(stroke
				(width 0.1524)
				(type default)
			)
			(layer "B.SilkS")
		)
		(fp_line
			(start -0.7874 0.4064)
			(end 0.7874 0.4064)
			(stroke
				(width 0.1524)
				(type default)
			)
			(layer "B.SilkS")
		)
		(fp_line
			(start 0.7874 -0.4064)
			(end -0.7874 -0.4064)
			(stroke
				(width 0.1524)
				(type default)
			)
			(layer "B.SilkS")
		)
		(fp_line
			(start 0.7874 0.4064)
			(end 0.7874 -0.4064)
			(stroke
				(width 0.1524)
				(type default)
			)
			(layer "B.SilkS")
		)
		(fp_line
			(start -0.67945 -0.3048)
			(end -0.67945 0.3048)
			(stroke
				(width 0.1)
				(type default)
			)
			(layer "B.Fab")
		)
		(fp_line
			(start -0.67945 0.3048)
			(end -0.120396 0.3048)
			(stroke
				(width 0.1)
				(type default)
			)
			(layer "B.Fab")
		)
		(fp_line
			(start -0.12065 -0.3048)
			(end -0.67945 -0.3048)
			(stroke
				(width 0.1)
				(type default)
			)
			(layer "B.Fab")
		)
		(fp_line
			(start -0.12065 -0.2794)
			(end -0.12065 -0.3048)
			(stroke
				(width 0.1)
				(type default)
			)
			(layer "B.Fab")
		)
		(fp_line
			(start -0.120396 0.2794)
			(end 0.12065 0.2794)
			(stroke
				(width 0.1)
				(type default)
			)
			(layer "B.Fab")
		)
		(fp_line
			(start -0.120396 0.3048)
			(end -0.120396 0.2794)
			(stroke
				(width 0.1)
				(type default)
			)
			(layer "B.Fab")
		)
		(fp_line
			(start 0.12065 -0.305054)
			(end 0.12065 -0.2794)
			(stroke
				(width 0.1)
				(type default)
			)
			(layer "B.Fab")
		)
		(fp_line
			(start 0.12065 -0.2794)
			(end -0.12065 -0.2794)
			(stroke
				(width 0.1)
				(type default)
			)
			(layer "B.Fab")
		)
		(fp_line
			(start 0.12065 0.2794)
			(end 0.12065 0.3048)
			(stroke
				(width 0.1)
				(type default)
			)
			(layer "B.Fab")
		)
		(fp_line
			(start 0.12065 0.3048)
			(end 0.67945 0.3048)
			(stroke
				(width 0.1)
				(type default)
			)
			(layer "B.Fab")
		)
		(fp_line
			(start 0.67945 -0.305054)
			(end 0.12065 -0.305054)
			(stroke
				(width 0.1)
				(type default)
			)
			(layer "B.Fab")
		)
		(fp_line
			(start 0.67945 0.3048)
			(end 0.67945 -0.305054)
			(stroke
				(width 0.1)
				(type default)
			)
			(layer "B.Fab")
		)
		(pad "1" smd circle
			(at 0.40005 0 180)
			(size 0 0)
			(layers "B.Cu" "B.Mask" "B.Paste")
			(net "PVDDCR_CPU0_P1")
		)
		(pad "2" smd circle
			(at -0.40005 0 180)
			(size 0 0)
			(layers "B.Cu" "B.Mask" "B.Paste")
			(net "GND")
		)
	)
	(footprint ""
		(layer "B.Cu")
		(at 303.172622 -393.88288 -90)
		(property "Reference" "C539"
			(at 0 0 90)
			(layer "B.SilkS")
			(hide yes)
			(effects
				(font
					(size 1.27 1.27)
				)
				(justify mirror)
			)
		)
		(property "Value" ""
			(at 0 0 90)
			(layer "B.Fab")
			(effects
				(font
					(size 1.27 1.27)
				)
				(justify mirror)
			)
		)
		(duplicate_pad_numbers_are_jumpers no)
		(fp_line
			(start -0.299974 0.150114)
			(end 0.299974 0.150114)
			(stroke
				(width 0.1)
				(type default)
			)
			(layer "B.Fab")
		)
		(fp_line
			(start 0.299974 0.150114)
			(end 0.299974 -0.150114)
			(stroke
				(width 0.1)
				(type default)
			)
			(layer "B.Fab")
		)
		(fp_line
			(start -0.299974 -0.150114)
			(end -0.299974 0.150114)
			(stroke
				(width 0.1)
				(type default)
			)
			(layer "B.Fab")
		)
		(fp_line
			(start 0.299974 -0.150114)
			(end -0.299974 -0.150114)
			(stroke
				(width 0.1)
				(type default)
			)
			(layer "B.Fab")
		)
		(pad "1" smd rect
			(at 0.2667 0 90)
			(size 0.3048 0.381)
			(layers "B.Cu" "B.Mask" "B.Paste")
			(net "P0V9_CPU0_RT0_2A")
		)
		(pad "2" smd rect
			(at -0.2667 0 90)
			(size 0.3048 0.381)
			(layers "B.Cu" "B.Mask" "B.Paste")
			(net "GND")
		)
	)
	(footprint ""
		(layer "B.Cu")
		(at 323.417184 -396.150592 180)
		(property "Reference" "C566"
			(at 0 0 0)
			(layer "B.SilkS")
			(hide yes)
			(effects
				(font
					(size 1.27 1.27)
				)
				(justify mirror)
			)
		)
		(property "Value" ""
			(at 0 0 0)
			(layer "B.Fab")
			(effects
				(font
					(size 1.27 1.27)
				)
				(justify mirror)
			)
		)
		(duplicate_pad_numbers_are_jumpers no)
		(fp_line
			(start 0.299974 0.150114)
			(end 0.299974 -0.150114)
			(stroke
				(width 0.1)
				(type default)
			)
			(layer "B.Fab")
		)
		(fp_line
			(start 0.299974 -0.150114)
			(end -0.299974 -0.150114)
			(stroke
				(width 0.1)
				(type default)
			)
			(layer "B.Fab")
		)
		(fp_line
			(start -0.299974 0.150114)
			(end 0.299974 0.150114)
			(stroke
				(width 0.1)
				(type default)
			)
			(layer "B.Fab")
		)
		(fp_line
			(start -0.299974 -0.150114)
			(end -0.299974 0.150114)
			(stroke
				(width 0.1)
				(type default)
			)
			(layer "B.Fab")
		)
		(pad "1" smd rect
			(at 0.2667 0)
			(size 0.3048 0.381)
			(layers "B.Cu" "B.Mask" "B.Paste")
			(net "P0V9_CPU0_RT0_2A")
		)
		(pad "2" smd rect
			(at -0.2667 0)
			(size 0.3048 0.381)
			(layers "B.Cu" "B.Mask" "B.Paste")
			(net "GND")
		)
	)
	(footprint ""
		(layer "B.Cu")
		(at 13.65885 -403.855174 180)
		(property "Reference" "R6858"
			(at 0 0 0)
			(layer "B.SilkS")
			(hide yes)
			(effects
				(font
					(size 1.27 1.27)
				)
				(justify mirror)
			)
		)
		(property "Value" ""
			(at 0 0 0)
			(layer "B.Fab")
			(effects
				(font
					(size 1.27 1.27)
				)
				(justify mirror)
			)
		)
		(duplicate_pad_numbers_are_jumpers no)
		(fp_line
			(start 0.7874 0.4064)
			(end 0.7874 -0.4064)
			(stroke
				(width 0.1524)
				(type default)
			)
			(layer "B.SilkS")
		)
		(fp_line
			(start 0.7874 -0.4064)
			(end -0.7874 -0.4064)
			(stroke
				(width 0.1524)
				(type default)
			)
			(layer "B.SilkS")
		)
		(fp_line
			(start -0.7874 0.4064)
			(end 0.7874 0.4064)
			(stroke
				(width 0.1524)
				(type default)
			)
			(layer "B.SilkS")
		)
		(fp_line
			(start -0.7874 -0.4064)
			(end -0.7874 0.4064)
			(stroke
				(width 0.1524)
				(type default)
			)
			(layer "B.SilkS")
		)
		(fp_line
			(start 0.67945 0.3048)
			(end 0.67945 -0.305054)
			(stroke
				(width 0.1)
				(type default)
			)
			(layer "B.Fab")
		)
		(fp_line
			(start 0.67945 -0.305054)
			(end 0.12065 -0.305054)
			(stroke
				(width 0.1)
				(type default)
			)
			(layer "B.Fab")
		)
		(fp_line
			(start 0.12065 0.3048)
			(end 0.67945 0.3048)
			(stroke
				(width 0.1)
				(type default)
			)
			(layer "B.Fab")
		)
		(fp_line
			(start 0.12065 0.2794)
			(end 0.12065 0.3048)
			(stroke
				(width 0.1)
				(type default)
			)
			(layer "B.Fab")
		)
		(fp_line
			(start 0.12065 -0.2794)
			(end -0.12065 -0.2794)
			(stroke
				(width 0.1)
				(type default)
			)
			(layer "B.Fab")
		)
		(fp_line
			(start 0.12065 -0.305054)
			(end 0.12065 -0.2794)
			(stroke
				(width 0.1)
				(type default)
			)
			(layer "B.Fab")
		)
		(fp_line
			(start -0.120396 0.3048)
			(end -0.120396 0.2794)
			(stroke
				(width 0.1)
				(type default)
			)
			(layer "B.Fab")
		)
		(fp_line
			(start -0.120396 0.2794)
			(end 0.12065 0.2794)
			(stroke
				(width 0.1)
				(type default)
			)
			(layer "B.Fab")
		)
		(fp_line
			(start -0.12065 -0.2794)
			(end -0.12065 -0.3048)
			(stroke
				(width 0.1)
				(type default)
			)
			(layer "B.Fab")
		)
		(fp_line
			(start -0.12065 -0.3048)
			(end -0.67945 -0.3048)
			(stroke
				(width 0.1)
				(type default)
			)
			(layer "B.Fab")
		)
		(fp_line
			(start -0.67945 0.3048)
			(end -0.120396 0.3048)
			(stroke
				(width 0.1)
				(type default)
			)
			(layer "B.Fab")
		)
		(fp_line
			(start -0.67945 -0.3048)
			(end -0.67945 0.3048)
			(stroke
				(width 0.1)
				(type default)
			)
			(layer "B.Fab")
		)
		(pad "1" smd circle
			(at 0.40005 0)
			(size 0 0)
			(layers "B.Cu" "B.Mask" "B.Paste")
			(net "SMB_VR_3V3STBY_SCL")
		)
		(pad "2" smd circle
			(at -0.40005 0)
			(size 0 0)
			(layers "B.Cu" "B.Mask" "B.Paste")
			(net "P0V9_RETIMER_CPU1_PMSCL")
		)
	)
	(footprint ""
		(layer "B.Cu")
		(at 356.711758 -271.395952)
		(property "Reference" "C2209"
			(at 0 0 0)
			(layer "B.SilkS")
			(hide yes)
			(effects
				(font
					(size 1.27 1.27)
				)
				(justify mirror)
			)
		)
		(property "Value" ""
			(at 0 0 0)
			(layer "B.Fab")
			(effects
				(font
					(size 1.27 1.27)
				)
				(justify mirror)
			)
		)
		(duplicate_pad_numbers_are_jumpers no)
		(fp_line
			(start -0.7874 -0.4064)
			(end -0.7874 0.4064)
			(stroke
				(width 0.1524)
				(type default)
			)
			(layer "B.SilkS")
		)
		(fp_line
			(start -0.7874 0.4064)
			(end 0.7874 0.4064)
			(stroke
				(width 0.1524)
				(type default)
			)
			(layer "B.SilkS")
		)
		(fp_line
			(start 0.7874 -0.4064)
			(end -0.7874 -0.4064)
			(stroke
				(width 0.1524)
				(type default)
			)
			(layer "B.SilkS")
		)
		(fp_line
			(start 0.7874 0.4064)
			(end 0.7874 -0.4064)
			(stroke
				(width 0.1524)
				(type default)
			)
			(layer "B.SilkS")
		)
		(fp_line
			(start -0.67945 -0.3048)
			(end -0.67945 0.3048)
			(stroke
				(width 0.1)
				(type default)
			)
			(layer "B.Fab")
		)
		(fp_line
			(start -0.67945 0.3048)
			(end -0.120396 0.3048)
			(stroke
				(width 0.1)
				(type default)
			)
			(layer "B.Fab")
		)
		(fp_line
			(start -0.12065 -0.3048)
			(end -0.67945 -0.3048)
			(stroke
				(width 0.1)
				(type default)
			)
			(layer "B.Fab")
		)
		(fp_line
			(start -0.12065 -0.2794)
			(end -0.12065 -0.3048)
			(stroke
				(width 0.1)
				(type default)
			)
			(layer "B.Fab")
		)
		(fp_line
			(start -0.120396 0.2794)
			(end 0.12065 0.2794)
			(stroke
				(width 0.1)
				(type default)
			)
			(layer "B.Fab")
		)
		(fp_line
			(start -0.120396 0.3048)
			(end -0.120396 0.2794)
			(stroke
				(width 0.1)
				(type default)
			)
			(layer "B.Fab")
		)
		(fp_line
			(start 0.12065 -0.305054)
			(end 0.12065 -0.2794)
			(stroke
				(width 0.1)
				(type default)
			)
			(layer "B.Fab")
		)
		(fp_line
			(start 0.12065 -0.2794)
			(end -0.12065 -0.2794)
			(stroke
				(width 0.1)
				(type default)
			)
			(layer "B.Fab")
		)
		(fp_line
			(start 0.12065 0.2794)
			(end 0.12065 0.3048)
			(stroke
				(width 0.1)
				(type default)
			)
			(layer "B.Fab")
		)
		(fp_line
			(start 0.12065 0.3048)
			(end 0.67945 0.3048)
			(stroke
				(width 0.1)
				(type default)
			)
			(layer "B.Fab")
		)
		(fp_line
			(start 0.67945 -0.305054)
			(end 0.12065 -0.305054)
			(stroke
				(width 0.1)
				(type default)
			)
			(layer "B.Fab")
		)
		(fp_line
			(start 0.67945 0.3048)
			(end 0.67945 -0.305054)
			(stroke
				(width 0.1)
				(type default)
			)
			(layer "B.Fab")
		)
		(pad "1" smd circle
			(at 0.40005 0 180)
			(size 0 0)
			(layers "B.Cu" "B.Mask" "B.Paste")
			(net "PVDDCR_CPU1_P0")
		)
		(pad "2" smd circle
			(at -0.40005 0 180)
			(size 0 0)
			(layers "B.Cu" "B.Mask" "B.Paste")
			(net "GND")
		)
	)
	(footprint ""
		(layer "B.Cu")
		(at 188.138562 -144.58823 180)
		(property "Reference" "C8007"
			(at 0 0 0)
			(layer "B.SilkS")
			(hide yes)
			(effects
				(font
					(size 1.27 1.27)
				)
				(justify mirror)
			)
		)
		(property "Value" ""
			(at 0 0 0)
			(layer "B.Fab")
			(effects
				(font
					(size 1.27 1.27)
				)
				(justify mirror)
			)
		)
		(duplicate_pad_numbers_are_jumpers no)
		(fp_line
			(start 0.7874 0.4064)
			(end 0.7874 -0.4064)
			(stroke
				(width 0.1524)
				(type default)
			)
			(layer "B.SilkS")
		)
		(fp_line
			(start 0.7874 -0.4064)
			(end -0.7874 -0.4064)
			(stroke
				(width 0.1524)
				(type default)
			)
			(layer "B.SilkS")
		)
		(fp_line
			(start -0.7874 0.4064)
			(end 0.7874 0.4064)
			(stroke
				(width 0.1524)
				(type default)
			)
			(layer "B.SilkS")
		)
		(fp_line
			(start -0.7874 -0.4064)
			(end -0.7874 0.4064)
			(stroke
				(width 0.1524)
				(type default)
			)
			(layer "B.SilkS")
		)
		(fp_line
			(start 0.67945 0.3048)
			(end 0.67945 -0.305054)
			(stroke
				(width 0.1)
				(type default)
			)
			(layer "B.Fab")
		)
		(fp_line
			(start 0.67945 -0.305054)
			(end 0.12065 -0.305054)
			(stroke
				(width 0.1)
				(type default)
			)
			(layer "B.Fab")
		)
		(fp_line
			(start 0.12065 0.3048)
			(end 0.67945 0.3048)
			(stroke
				(width 0.1)
				(type default)
			)
			(layer "B.Fab")
		)
		(fp_line
			(start 0.12065 0.2794)
			(end 0.12065 0.3048)
			(stroke
				(width 0.1)
				(type default)
			)
			(layer "B.Fab")
		)
		(fp_line
			(start 0.12065 -0.2794)
			(end -0.12065 -0.2794)
			(stroke
				(width 0.1)
				(type default)
			)
			(layer "B.Fab")
		)
		(fp_line
			(start 0.12065 -0.305054)
			(end 0.12065 -0.2794)
			(stroke
				(width 0.1)
				(type default)
			)
			(layer "B.Fab")
		)
		(fp_line
			(start -0.120396 0.3048)
			(end -0.120396 0.2794)
			(stroke
				(width 0.1)
				(type default)
			)
			(layer "B.Fab")
		)
		(fp_line
			(start -0.120396 0.2794)
			(end 0.12065 0.2794)
			(stroke
				(width 0.1)
				(type default)
			)
			(layer "B.Fab")
		)
		(fp_line
			(start -0.12065 -0.2794)
			(end -0.12065 -0.3048)
			(stroke
				(width 0.1)
				(type default)
			)
			(layer "B.Fab")
		)
		(fp_line
			(start -0.12065 -0.3048)
			(end -0.67945 -0.3048)
			(stroke
				(width 0.1)
				(type default)
			)
			(layer "B.Fab")
		)
		(fp_line
			(start -0.67945 0.3048)
			(end -0.120396 0.3048)
			(stroke
				(width 0.1)
				(type default)
			)
			(layer "B.Fab")
		)
		(fp_line
			(start -0.67945 -0.3048)
			(end -0.67945 0.3048)
			(stroke
				(width 0.1)
				(type default)
			)
			(layer "B.Fab")
		)
		(pad "1" smd circle
			(at 0.40005 0)
			(size 0 0)
			(layers "B.Cu" "B.Mask" "B.Paste")
			(net "P1V8_AUX")
		)
		(pad "2" smd circle
			(at -0.40005 0)
			(size 0 0)
			(layers "B.Cu" "B.Mask" "B.Paste")
			(net "GND")
		)
	)
	(footprint ""
		(layer "B.Cu")
		(at 412.618936 -398.942052 90)
		(property "Reference" "C671"
			(at 0 0 90)
			(layer "B.SilkS")
			(hide yes)
			(effects
				(font
					(size 1.27 1.27)
				)
				(justify mirror)
			)
		)
		(property "Value" ""
			(at 0 0 90)
			(layer "B.Fab")
			(effects
				(font
					(size 1.27 1.27)
				)
				(justify mirror)
			)
		)
		(duplicate_pad_numbers_are_jumpers no)
		(fp_line
			(start 0.7874 -0.4064)
			(end -0.7874 -0.4064)
			(stroke
				(width 0.1524)
				(type default)
			)
			(layer "B.SilkS")
		)
		(fp_line
			(start -0.7874 -0.4064)
			(end -0.7874 0.4064)
			(stroke
				(width 0.1524)
				(type default)
			)
			(layer "B.SilkS")
		)
		(fp_line
			(start 0.7874 0.4064)
			(end 0.7874 -0.4064)
			(stroke
				(width 0.1524)
				(type default)
			)
			(layer "B.SilkS")
		)
		(fp_line
			(start -0.7874 0.4064)
			(end 0.7874 0.4064)
			(stroke
				(width 0.1524)
				(type default)
			)
			(layer "B.SilkS")
		)
		(fp_line
			(start 0.67945 -0.305054)
			(end 0.12065 -0.305054)
			(stroke
				(width 0.1)
				(type default)
			)
			(layer "B.Fab")
		)
		(fp_line
			(start 0.12065 -0.305054)
			(end 0.12065 -0.2794)
			(stroke
				(width 0.1)
				(type default)
			)
			(layer "B.Fab")
		)
		(fp_line
			(start -0.12065 -0.3048)
			(end -0.67945 -0.3048)
			(stroke
				(width 0.1)
				(type default)
			)
			(layer "B.Fab")
		)
		(fp_line
			(start -0.67945 -0.3048)
			(end -0.67945 0.3048)
			(stroke
				(width 0.1)
				(type default)
			)
			(layer "B.Fab")
		)
		(fp_line
			(start 0.12065 -0.2794)
			(end -0.12065 -0.2794)
			(stroke
				(width 0.1)
				(type default)
			)
			(layer "B.Fab")
		)
		(fp_line
			(start -0.12065 -0.2794)
			(end -0.12065 -0.3048)
			(stroke
				(width 0.1)
				(type default)
			)
			(layer "B.Fab")
		)
		(fp_line
			(start 0.12065 0.2794)
			(end 0.12065 0.3048)
			(stroke
				(width 0.1)
				(type default)
			)
			(layer "B.Fab")
		)
		(fp_line
			(start -0.120396 0.2794)
			(end 0.12065 0.2794)
			(stroke
				(width 0.1)
				(type default)
			)
			(layer "B.Fab")
		)
		(fp_line
			(start 0.67945 0.3048)
			(end 0.67945 -0.305054)
			(stroke
				(width 0.1)
				(type default)
			)
			(layer "B.Fab")
		)
		(fp_line
			(start 0.12065 0.3048)
			(end 0.67945 0.3048)
			(stroke
				(width 0.1)
				(type default)
			)
			(layer "B.Fab")
		)
		(fp_line
			(start -0.120396 0.3048)
			(end -0.120396 0.2794)
			(stroke
				(width 0.1)
				(type default)
			)
			(layer "B.Fab")
		)
		(fp_line
			(start -0.67945 0.3048)
			(end -0.120396 0.3048)
			(stroke
				(width 0.1)
				(type default)
			)
			(layer "B.Fab")
		)
		(pad "1" smd circle
			(at 0.40005 0 270)
			(size 0 0)
			(layers "B.Cu" "B.Mask" "B.Paste")
			(net "P1V8_CPU0_RT2_1A")
		)
		(pad "2" smd circle
			(at -0.40005 0 270)
			(size 0 0)
			(layers "B.Cu" "B.Mask" "B.Paste")
			(net "GND")
		)
	)
	(footprint ""
		(layer "B.Cu")
		(at 229.8446 -341.884 180)
		(property "Reference" "R6754"
			(at 0 0 0)
			(layer "B.SilkS")
			(hide yes)
			(effects
				(font
					(size 1.27 1.27)
				)
				(justify mirror)
			)
		)
		(property "Value" ""
			(at 0 0 0)
			(layer "B.Fab")
			(effects
				(font
					(size 1.27 1.27)
				)
				(justify mirror)
			)
		)
		(duplicate_pad_numbers_are_jumpers no)
		(fp_line
			(start 0.32512 0.175006)
			(end 0.32512 -0.175006)
			(stroke
				(width 0.1)
				(type default)
			)
			(layer "B.Fab")
		)
		(fp_line
			(start 0.32512 -0.175006)
			(end -0.32512 -0.175006)
			(stroke
				(width 0.1)
				(type default)
			)
			(layer "B.Fab")
		)
		(fp_line
			(start -0.32512 0.175006)
			(end 0.32512 0.175006)
			(stroke
				(width 0.1)
				(type default)
			)
			(layer "B.Fab")
		)
		(fp_line
			(start -0.32512 -0.175006)
			(end -0.32512 0.175006)
			(stroke
				(width 0.1)
				(type default)
			)
			(layer "B.Fab")
		)
		(pad "1" smd rect
			(at 0.2667 0)
			(size 0.3048 0.381)
			(layers "B.Cu" "B.Mask" "B.Paste")
			(net "SMB_RT_CPU0_P0_SDA")
		)
		(pad "2" smd rect
			(at -0.2667 0 180)
			(size 0.3048 0.381)
			(layers "B.Cu" "B.Mask" "B.Paste")
			(net "SMB_RT_CPU0_P0_R_SDA")
		)
	)
	(footprint ""
		(layer "B.Cu")
		(at 347.897958 -245.868952 -90)
		(property "Reference" "C2183"
			(at 0 0 90)
			(layer "B.SilkS")
			(hide yes)
			(effects
				(font
					(size 1.27 1.27)
				)
				(justify mirror)
			)
		)
		(property "Value" ""
			(at 0 0 90)
			(layer "B.Fab")
			(effects
				(font
					(size 1.27 1.27)
				)
				(justify mirror)
			)
		)
		(duplicate_pad_numbers_are_jumpers no)
		(fp_line
			(start -0.7874 0.4064)
			(end 0.7874 0.4064)
			(stroke
				(width 0.1524)
				(type default)
			)
			(layer "B.SilkS")
		)
		(fp_line
			(start 0.7874 0.4064)
			(end 0.7874 -0.4064)
			(stroke
				(width 0.1524)
				(type default)
			)
			(layer "B.SilkS")
		)
		(fp_line
			(start -0.7874 -0.4064)
			(end -0.7874 0.4064)
			(stroke
				(width 0.1524)
				(type default)
			)
			(layer "B.SilkS")
		)
		(fp_line
			(start 0.7874 -0.4064)
			(end -0.7874 -0.4064)
			(stroke
				(width 0.1524)
				(type default)
			)
			(layer "B.SilkS")
		)
		(fp_line
			(start -0.67945 0.3048)
			(end -0.120396 0.3048)
			(stroke
				(width 0.1)
				(type default)
			)
			(layer "B.Fab")
		)
		(fp_line
			(start -0.120396 0.3048)
			(end -0.120396 0.2794)
			(stroke
				(width 0.1)
				(type default)
			)
			(layer "B.Fab")
		)
		(fp_line
			(start 0.12065 0.3048)
			(end 0.67945 0.3048)
			(stroke
				(width 0.1)
				(type default)
			)
			(layer "B.Fab")
		)
		(fp_line
			(start 0.67945 0.3048)
			(end 0.67945 -0.305054)
			(stroke
				(width 0.1)
				(type default)
			)
			(layer "B.Fab")
		)
		(fp_line
			(start -0.120396 0.2794)
			(end 0.12065 0.2794)
			(stroke
				(width 0.1)
				(type default)
			)
			(layer "B.Fab")
		)
		(fp_line
			(start 0.12065 0.2794)
			(end 0.12065 0.3048)
			(stroke
				(width 0.1)
				(type default)
			)
			(layer "B.Fab")
		)
		(fp_line
			(start -0.12065 -0.2794)
			(end -0.12065 -0.3048)
			(stroke
				(width 0.1)
				(type default)
			)
			(layer "B.Fab")
		)
		(fp_line
			(start 0.12065 -0.2794)
			(end -0.12065 -0.2794)
			(stroke
				(width 0.1)
				(type default)
			)
			(layer "B.Fab")
		)
		(fp_line
			(start -0.67945 -0.3048)
			(end -0.67945 0.3048)
			(stroke
				(width 0.1)
				(type default)
			)
			(layer "B.Fab")
		)
		(fp_line
			(start -0.12065 -0.3048)
			(end -0.67945 -0.3048)
			(stroke
				(width 0.1)
				(type default)
			)
			(layer "B.Fab")
		)
		(fp_line
			(start 0.12065 -0.305054)
			(end 0.12065 -0.2794)
			(stroke
				(width 0.1)
				(type default)
			)
			(layer "B.Fab")
		)
		(fp_line
			(start 0.67945 -0.305054)
			(end 0.12065 -0.305054)
			(stroke
				(width 0.1)
				(type default)
			)
			(layer "B.Fab")
		)
		(pad "1" smd circle
			(at 0.40005 0 90)
			(size 0 0)
			(layers "B.Cu" "B.Mask" "B.Paste")
			(net "PVDDCR_CPU0_P0")
		)
		(pad "2" smd circle
			(at -0.40005 0 90)
			(size 0 0)
			(layers "B.Cu" "B.Mask" "B.Paste")
			(net "GND")
		)
	)
	(footprint ""
		(layer "B.Cu")
		(at 190.668402 -19.311366 180)
		(property "Reference" "R1801"
			(at 0 0 0)
			(layer "B.SilkS")
			(hide yes)
			(effects
				(font
					(size 1.27 1.27)
				)
				(justify mirror)
			)
		)
		(property "Value" ""
			(at 0 0 0)
			(layer "B.Fab")
			(effects
				(font
					(size 1.27 1.27)
				)
				(justify mirror)
			)
		)
		(duplicate_pad_numbers_are_jumpers no)
		(fp_line
			(start 0.7874 0.4064)
			(end 0.7874 -0.4064)
			(stroke
				(width 0.1524)
				(type default)
			)
			(layer "B.SilkS")
		)
		(fp_line
			(start 0.7874 -0.4064)
			(end -0.7874 -0.4064)
			(stroke
				(width 0.1524)
				(type default)
			)
			(layer "B.SilkS")
		)
		(fp_line
			(start -0.7874 0.4064)
			(end 0.7874 0.4064)
			(stroke
				(width 0.1524)
				(type default)
			)
			(layer "B.SilkS")
		)
		(fp_line
			(start -0.7874 -0.4064)
			(end -0.7874 0.4064)
			(stroke
				(width 0.1524)
				(type default)
			)
			(layer "B.SilkS")
		)
		(fp_line
			(start 0.67945 0.3048)
			(end 0.67945 -0.305054)
			(stroke
				(width 0.1)
				(type default)
			)
			(layer "B.Fab")
		)
		(fp_line
			(start 0.67945 -0.305054)
			(end 0.12065 -0.305054)
			(stroke
				(width 0.1)
				(type default)
			)
			(layer "B.Fab")
		)
		(fp_line
			(start 0.12065 0.3048)
			(end 0.67945 0.3048)
			(stroke
				(width 0.1)
				(type default)
			)
			(layer "B.Fab")
		)
		(fp_line
			(start 0.12065 0.2794)
			(end 0.12065 0.3048)
			(stroke
				(width 0.1)
				(type default)
			)
			(layer "B.Fab")
		)
		(fp_line
			(start 0.12065 -0.2794)
			(end -0.12065 -0.2794)
			(stroke
				(width 0.1)
				(type default)
			)
			(layer "B.Fab")
		)
		(fp_line
			(start 0.12065 -0.305054)
			(end 0.12065 -0.2794)
			(stroke
				(width 0.1)
				(type default)
			)
			(layer "B.Fab")
		)
		(fp_line
			(start -0.120396 0.3048)
			(end -0.120396 0.2794)
			(stroke
				(width 0.1)
				(type default)
			)
			(layer "B.Fab")
		)
		(fp_line
			(start -0.120396 0.2794)
			(end 0.12065 0.2794)
			(stroke
				(width 0.1)
				(type default)
			)
			(layer "B.Fab")
		)
		(fp_line
			(start -0.12065 -0.2794)
			(end -0.12065 -0.3048)
			(stroke
				(width 0.1)
				(type default)
			)
			(layer "B.Fab")
		)
		(fp_line
			(start -0.12065 -0.3048)
			(end -0.67945 -0.3048)
			(stroke
				(width 0.1)
				(type default)
			)
			(layer "B.Fab")
		)
		(fp_line
			(start -0.67945 0.3048)
			(end -0.120396 0.3048)
			(stroke
				(width 0.1)
				(type default)
			)
			(layer "B.Fab")
		)
		(fp_line
			(start -0.67945 -0.3048)
			(end -0.67945 0.3048)
			(stroke
				(width 0.1)
				(type default)
			)
			(layer "B.Fab")
		)
		(pad "1" smd circle
			(at 0.40005 0)
			(size 0 0)
			(layers "B.Cu" "B.Mask" "B.Paste")
			(net "PRSNT0_N")
		)
		(pad "2" smd circle
			(at -0.40005 0)
			(size 0 0)
			(layers "B.Cu" "B.Mask" "B.Paste")
			(net "GND")
		)
	)
	(footprint ""
		(layer "B.Cu")
		(at 346.84589 -396.393162 -90)
		(property "Reference" "C601"
			(at 0 0 90)
			(layer "B.SilkS")
			(hide yes)
			(effects
				(font
					(size 1.27 1.27)
				)
				(justify mirror)
			)
		)
		(property "Value" ""
			(at 0 0 90)
			(layer "B.Fab")
			(effects
				(font
					(size 1.27 1.27)
				)
				(justify mirror)
			)
		)
		(duplicate_pad_numbers_are_jumpers no)
		(fp_line
			(start -0.299974 0.150114)
			(end 0.299974 0.150114)
			(stroke
				(width 0.1)
				(type default)
			)
			(layer "B.Fab")
		)
		(fp_line
			(start 0.299974 0.150114)
			(end 0.299974 -0.150114)
			(stroke
				(width 0.1)
				(type default)
			)
			(layer "B.Fab")
		)
		(fp_line
			(start -0.299974 -0.150114)
			(end -0.299974 0.150114)
			(stroke
				(width 0.1)
				(type default)
			)
			(layer "B.Fab")
		)
		(fp_line
			(start 0.299974 -0.150114)
			(end -0.299974 -0.150114)
			(stroke
				(width 0.1)
				(type default)
			)
			(layer "B.Fab")
		)
		(pad "1" smd rect
			(at 0.2667 0 90)
			(size 0.3048 0.381)
			(layers "B.Cu" "B.Mask" "B.Paste")
			(net "P1V8_CPU0_RT1_1A_1D")
		)
		(pad "2" smd rect
			(at -0.2667 0 90)
			(size 0.3048 0.381)
			(layers "B.Cu" "B.Mask" "B.Paste")
			(net "GND")
		)
	)
	(footprint ""
		(layer "B.Cu")
		(at 405.406352 -395.148562 90)
		(property "Reference" "C978"
			(at 0 0 90)
			(layer "B.SilkS")
			(hide yes)
			(effects
				(font
					(size 1.27 1.27)
				)
				(justify mirror)
			)
		)
		(property "Value" ""
			(at 0 0 90)
			(layer "B.Fab")
			(effects
				(font
					(size 1.27 1.27)
				)
				(justify mirror)
			)
		)
		(duplicate_pad_numbers_are_jumpers no)
		(fp_line
			(start 0.299974 -0.150114)
			(end -0.299974 -0.150114)
			(stroke
				(width 0.1)
				(type default)
			)
			(layer "B.Fab")
		)
		(fp_line
			(start -0.299974 -0.150114)
			(end -0.299974 0.150114)
			(stroke
				(width 0.1)
				(type default)
			)
			(layer "B.Fab")
		)
		(fp_line
			(start 0.299974 0.150114)
			(end 0.299974 -0.150114)
			(stroke
				(width 0.1)
				(type default)
			)
			(layer "B.Fab")
		)
		(fp_line
			(start -0.299974 0.150114)
			(end 0.299974 0.150114)
			(stroke
				(width 0.1)
				(type default)
			)
			(layer "B.Fab")
		)
		(pad "1" smd rect
			(at 0.2667 0 270)
			(size 0.3048 0.381)
			(layers "B.Cu" "B.Mask" "B.Paste")
			(net "P0V9_CPU0_RT2_2A")
		)
		(pad "2" smd rect
			(at -0.2667 0 270)
			(size 0.3048 0.381)
			(layers "B.Cu" "B.Mask" "B.Paste")
			(net "GND")
		)
	)
	(footprint ""
		(layer "B.Cu")
		(at 388.491222 -398.942052 90)
		(property "Reference" "C1036"
			(at 0 0 90)
			(layer "B.SilkS")
			(hide yes)
			(effects
				(font
					(size 1.27 1.27)
				)
				(justify mirror)
			)
		)
		(property "Value" ""
			(at 0 0 90)
			(layer "B.Fab")
			(effects
				(font
					(size 1.27 1.27)
				)
				(justify mirror)
			)
		)
		(duplicate_pad_numbers_are_jumpers no)
		(fp_line
			(start 0.7874 -0.4064)
			(end -0.7874 -0.4064)
			(stroke
				(width 0.1524)
				(type default)
			)
			(layer "B.SilkS")
		)
		(fp_line
			(start -0.7874 -0.4064)
			(end -0.7874 0.4064)
			(stroke
				(width 0.1524)
				(type default)
			)
			(layer "B.SilkS")
		)
		(fp_line
			(start 0.7874 0.4064)
			(end 0.7874 -0.4064)
			(stroke
				(width 0.1524)
				(type default)
			)
			(layer "B.SilkS")
		)
		(fp_line
			(start -0.7874 0.4064)
			(end 0.7874 0.4064)
			(stroke
				(width 0.1524)
				(type default)
			)
			(layer "B.SilkS")
		)
		(fp_line
			(start 0.67945 -0.305054)
			(end 0.12065 -0.305054)
			(stroke
				(width 0.1)
				(type default)
			)
			(layer "B.Fab")
		)
		(fp_line
			(start 0.12065 -0.305054)
			(end 0.12065 -0.2794)
			(stroke
				(width 0.1)
				(type default)
			)
			(layer "B.Fab")
		)
		(fp_line
			(start -0.12065 -0.3048)
			(end -0.67945 -0.3048)
			(stroke
				(width 0.1)
				(type default)
			)
			(layer "B.Fab")
		)
		(fp_line
			(start -0.67945 -0.3048)
			(end -0.67945 0.3048)
			(stroke
				(width 0.1)
				(type default)
			)
			(layer "B.Fab")
		)
		(fp_line
			(start 0.12065 -0.2794)
			(end -0.12065 -0.2794)
			(stroke
				(width 0.1)
				(type default)
			)
			(layer "B.Fab")
		)
		(fp_line
			(start -0.12065 -0.2794)
			(end -0.12065 -0.3048)
			(stroke
				(width 0.1)
				(type default)
			)
			(layer "B.Fab")
		)
		(fp_line
			(start 0.12065 0.2794)
			(end 0.12065 0.3048)
			(stroke
				(width 0.1)
				(type default)
			)
			(layer "B.Fab")
		)
		(fp_line
			(start -0.120396 0.2794)
			(end 0.12065 0.2794)
			(stroke
				(width 0.1)
				(type default)
			)
			(layer "B.Fab")
		)
		(fp_line
			(start 0.67945 0.3048)
			(end 0.67945 -0.305054)
			(stroke
				(width 0.1)
				(type default)
			)
			(layer "B.Fab")
		)
		(fp_line
			(start 0.12065 0.3048)
			(end 0.67945 0.3048)
			(stroke
				(width 0.1)
				(type default)
			)
			(layer "B.Fab")
		)
		(fp_line
			(start -0.120396 0.3048)
			(end -0.120396 0.2794)
			(stroke
				(width 0.1)
				(type default)
			)
			(layer "B.Fab")
		)
		(fp_line
			(start -0.67945 0.3048)
			(end -0.120396 0.3048)
			(stroke
				(width 0.1)
				(type default)
			)
			(layer "B.Fab")
		)
		(pad "1" smd circle
			(at 0.40005 0 270)
			(size 0 0)
			(layers "B.Cu" "B.Mask" "B.Paste")
			(net "P0V9_CPU0_RT3_2A")
		)
		(pad "2" smd circle
			(at -0.40005 0 270)
			(size 0 0)
			(layers "B.Cu" "B.Mask" "B.Paste")
			(net "GND")
		)
	)
	(footprint ""
		(layer "B.Cu")
		(at 293.12997 -350.65589 -90)
		(property "Reference" "PC157_2"
			(at 0 0 90)
			(layer "B.SilkS")
			(hide yes)
			(effects
				(font
					(size 1.27 1.27)
				)
				(justify mirror)
			)
		)
		(property "Value" ""
			(at 0 0 90)
			(layer "B.Fab")
			(effects
				(font
					(size 1.27 1.27)
				)
				(justify mirror)
			)
		)
		(duplicate_pad_numbers_are_jumpers no)
		(fp_line
			(start -1.524 0.762)
			(end 1.524 0.762)
			(stroke
				(width 0.1524)
				(type default)
			)
			(layer "B.SilkS")
		)
		(fp_line
			(start 1.524 0.762)
			(end 1.524 -0.762)
			(stroke
				(width 0.1524)
				(type default)
			)
			(layer "B.SilkS")
		)
		(fp_line
			(start -1.524 -0.762)
			(end -1.524 0.762)
			(stroke
				(width 0.1524)
				(type default)
			)
			(layer "B.SilkS")
		)
		(fp_line
			(start 1.524 -0.762)
			(end -1.524 -0.762)
			(stroke
				(width 0.1524)
				(type default)
			)
			(layer "B.SilkS")
		)
		(fp_line
			(start -1.1049 0.724916)
			(end -1.1049 -0.724916)
			(stroke
				(width 0.1)
				(type default)
			)
			(layer "B.Fab")
		)
		(fp_line
			(start 1.1049 0.724916)
			(end -1.1049 0.724916)
			(stroke
				(width 0.1)
				(type default)
			)
			(layer "B.Fab")
		)
		(fp_line
			(start -1.1049 -0.724916)
			(end 1.1049 -0.724916)
			(stroke
				(width 0.1)
				(type default)
			)
			(layer "B.Fab")
		)
		(fp_line
			(start 1.1049 -0.724916)
			(end 1.1049 0.724916)
			(stroke
				(width 0.1)
				(type default)
			)
			(layer "B.Fab")
		)
		(pad "1" smd rect
			(at 0.889 0 270)
			(size 1.016 1.27)
			(layers "B.Cu" "B.Mask" "B.Paste")
			(net "SW_P12V_AUX_PVDDIO_P0_FLT")
		)
		(pad "2" smd rect
			(at -0.889 0 270)
			(size 1.016 1.27)
			(layers "B.Cu" "B.Mask" "B.Paste")
			(net "GND")
		)
	)
	(footprint ""
		(layer "B.Cu")
		(at 460.405988 -44.416726)
		(property "Reference" "C5015"
			(at 0 0 0)
			(layer "B.SilkS")
			(hide yes)
			(effects
				(font
					(size 1.27 1.27)
				)
				(justify mirror)
			)
		)
		(property "Value" ""
			(at 0 0 0)
			(layer "B.Fab")
			(effects
				(font
					(size 1.27 1.27)
				)
				(justify mirror)
			)
		)
		(duplicate_pad_numbers_are_jumpers no)
		(fp_line
			(start -0.7874 -0.4064)
			(end -0.7874 0.4064)
			(stroke
				(width 0.1524)
				(type default)
			)
			(layer "B.SilkS")
		)
		(fp_line
			(start -0.7874 0.4064)
			(end 0.7874 0.4064)
			(stroke
				(width 0.1524)
				(type default)
			)
			(layer "B.SilkS")
		)
		(fp_line
			(start 0.7874 -0.4064)
			(end -0.7874 -0.4064)
			(stroke
				(width 0.1524)
				(type default)
			)
			(layer "B.SilkS")
		)
		(fp_line
			(start 0.7874 0.4064)
			(end 0.7874 -0.4064)
			(stroke
				(width 0.1524)
				(type default)
			)
			(layer "B.SilkS")
		)
		(fp_line
			(start -0.67945 -0.3048)
			(end -0.67945 0.3048)
			(stroke
				(width 0.1)
				(type default)
			)
			(layer "B.Fab")
		)
		(fp_line
			(start -0.67945 0.3048)
			(end -0.120396 0.3048)
			(stroke
				(width 0.1)
				(type default)
			)
			(layer "B.Fab")
		)
		(fp_line
			(start -0.12065 -0.3048)
			(end -0.67945 -0.3048)
			(stroke
				(width 0.1)
				(type default)
			)
			(layer "B.Fab")
		)
		(fp_line
			(start -0.12065 -0.2794)
			(end -0.12065 -0.3048)
			(stroke
				(width 0.1)
				(type default)
			)
			(layer "B.Fab")
		)
		(fp_line
			(start -0.120396 0.2794)
			(end 0.12065 0.2794)
			(stroke
				(width 0.1)
				(type default)
			)
			(layer "B.Fab")
		)
		(fp_line
			(start -0.120396 0.3048)
			(end -0.120396 0.2794)
			(stroke
				(width 0.1)
				(type default)
			)
			(layer "B.Fab")
		)
		(fp_line
			(start 0.12065 -0.305054)
			(end 0.12065 -0.2794)
			(stroke
				(width 0.1)
				(type default)
			)
			(layer "B.Fab")
		)
		(fp_line
			(start 0.12065 -0.2794)
			(end -0.12065 -0.2794)
			(stroke
				(width 0.1)
				(type default)
			)
			(layer "B.Fab")
		)
		(fp_line
			(start 0.12065 0.2794)
			(end 0.12065 0.3048)
			(stroke
				(width 0.1)
				(type default)
			)
			(layer "B.Fab")
		)
		(fp_line
			(start 0.12065 0.3048)
			(end 0.67945 0.3048)
			(stroke
				(width 0.1)
				(type default)
			)
			(layer "B.Fab")
		)
		(fp_line
			(start 0.67945 -0.305054)
			(end 0.12065 -0.305054)
			(stroke
				(width 0.1)
				(type default)
			)
			(layer "B.Fab")
		)
		(fp_line
			(start 0.67945 0.3048)
			(end 0.67945 -0.305054)
			(stroke
				(width 0.1)
				(type default)
			)
			(layer "B.Fab")
		)
		(pad "1" smd circle
			(at 0.40005 0 180)
			(size 0 0)
			(layers "B.Cu" "B.Mask" "B.Paste")
			(net "PWRGD_P3V3_AUX")
		)
		(pad "2" smd circle
			(at -0.40005 0 180)
			(size 0 0)
			(layers "B.Cu" "B.Mask" "B.Paste")
			(net "GND")
		)
	)
	(footprint ""
		(layer "B.Cu")
		(at 346.373958 -263.521952)
		(property "Reference" "C2604"
			(at 0 0 0)
			(layer "B.SilkS")
			(hide yes)
			(effects
				(font
					(size 1.27 1.27)
				)
				(justify mirror)
			)
		)
		(property "Value" ""
			(at 0 0 0)
			(layer "B.Fab")
			(effects
				(font
					(size 1.27 1.27)
				)
				(justify mirror)
			)
		)
		(duplicate_pad_numbers_are_jumpers no)
		(fp_line
			(start -0.7874 -0.4064)
			(end -0.7874 0.4064)
			(stroke
				(width 0.1524)
				(type default)
			)
			(layer "B.SilkS")
		)
		(fp_line
			(start -0.7874 0.4064)
			(end 0.7874 0.4064)
			(stroke
				(width 0.1524)
				(type default)
			)
			(layer "B.SilkS")
		)
		(fp_line
			(start 0.7874 -0.4064)
			(end -0.7874 -0.4064)
			(stroke
				(width 0.1524)
				(type default)
			)
			(layer "B.SilkS")
		)
		(fp_line
			(start 0.7874 0.4064)
			(end 0.7874 -0.4064)
			(stroke
				(width 0.1524)
				(type default)
			)
			(layer "B.SilkS")
		)
		(fp_line
			(start -0.67945 -0.3048)
			(end -0.67945 0.3048)
			(stroke
				(width 0.1)
				(type default)
			)
			(layer "B.Fab")
		)
		(fp_line
			(start -0.67945 0.3048)
			(end -0.120396 0.3048)
			(stroke
				(width 0.1)
				(type default)
			)
			(layer "B.Fab")
		)
		(fp_line
			(start -0.12065 -0.3048)
			(end -0.67945 -0.3048)
			(stroke
				(width 0.1)
				(type default)
			)
			(layer "B.Fab")
		)
		(fp_line
			(start -0.12065 -0.2794)
			(end -0.12065 -0.3048)
			(stroke
				(width 0.1)
				(type default)
			)
			(layer "B.Fab")
		)
		(fp_line
			(start -0.120396 0.2794)
			(end 0.12065 0.2794)
			(stroke
				(width 0.1)
				(type default)
			)
			(layer "B.Fab")
		)
		(fp_line
			(start -0.120396 0.3048)
			(end -0.120396 0.2794)
			(stroke
				(width 0.1)
				(type default)
			)
			(layer "B.Fab")
		)
		(fp_line
			(start 0.12065 -0.305054)
			(end 0.12065 -0.2794)
			(stroke
				(width 0.1)
				(type default)
			)
			(layer "B.Fab")
		)
		(fp_line
			(start 0.12065 -0.2794)
			(end -0.12065 -0.2794)
			(stroke
				(width 0.1)
				(type default)
			)
			(layer "B.Fab")
		)
		(fp_line
			(start 0.12065 0.2794)
			(end 0.12065 0.3048)
			(stroke
				(width 0.1)
				(type default)
			)
			(layer "B.Fab")
		)
		(fp_line
			(start 0.12065 0.3048)
			(end 0.67945 0.3048)
			(stroke
				(width 0.1)
				(type default)
			)
			(layer "B.Fab")
		)
		(fp_line
			(start 0.67945 -0.305054)
			(end 0.12065 -0.305054)
			(stroke
				(width 0.1)
				(type default)
			)
			(layer "B.Fab")
		)
		(fp_line
			(start 0.67945 0.3048)
			(end 0.67945 -0.305054)
			(stroke
				(width 0.1)
				(type default)
			)
			(layer "B.Fab")
		)
		(pad "1" smd circle
			(at 0.40005 0 180)
			(size 0 0)
			(layers "B.Cu" "B.Mask" "B.Paste")
			(net "PVDDIO_P0")
		)
		(pad "2" smd circle
			(at -0.40005 0 180)
			(size 0 0)
			(layers "B.Cu" "B.Mask" "B.Paste")
			(net "GND")
		)
	)
	(footprint ""
		(layer "B.Cu")
		(at 149.900386 -314.47105 180)
		(property "Reference" "C237"
			(at 0 0 0)
			(layer "B.SilkS")
			(hide yes)
			(effects
				(font
					(size 1.27 1.27)
				)
				(justify mirror)
			)
		)
		(property "Value" ""
			(at 0 0 0)
			(layer "B.Fab")
			(effects
				(font
					(size 1.27 1.27)
				)
				(justify mirror)
			)
		)
		(duplicate_pad_numbers_are_jumpers no)
		(fp_line
			(start 0.7874 0.4064)
			(end 0.7874 -0.4064)
			(stroke
				(width 0.1524)
				(type default)
			)
			(layer "B.SilkS")
		)
		(fp_line
			(start 0.7874 -0.4064)
			(end -0.7874 -0.4064)
			(stroke
				(width 0.1524)
				(type default)
			)
			(layer "B.SilkS")
		)
		(fp_line
			(start -0.7874 0.4064)
			(end 0.7874 0.4064)
			(stroke
				(width 0.1524)
				(type default)
			)
			(layer "B.SilkS")
		)
		(fp_line
			(start -0.7874 -0.4064)
			(end -0.7874 0.4064)
			(stroke
				(width 0.1524)
				(type default)
			)
			(layer "B.SilkS")
		)
		(fp_line
			(start 0.67945 0.3048)
			(end 0.67945 -0.305054)
			(stroke
				(width 0.1)
				(type default)
			)
			(layer "B.Fab")
		)
		(fp_line
			(start 0.67945 -0.305054)
			(end 0.12065 -0.305054)
			(stroke
				(width 0.1)
				(type default)
			)
			(layer "B.Fab")
		)
		(fp_line
			(start 0.12065 0.3048)
			(end 0.67945 0.3048)
			(stroke
				(width 0.1)
				(type default)
			)
			(layer "B.Fab")
		)
		(fp_line
			(start 0.12065 0.2794)
			(end 0.12065 0.3048)
			(stroke
				(width 0.1)
				(type default)
			)
			(layer "B.Fab")
		)
		(fp_line
			(start 0.12065 -0.2794)
			(end -0.12065 -0.2794)
			(stroke
				(width 0.1)
				(type default)
			)
			(layer "B.Fab")
		)
		(fp_line
			(start 0.12065 -0.305054)
			(end 0.12065 -0.2794)
			(stroke
				(width 0.1)
				(type default)
			)
			(layer "B.Fab")
		)
		(fp_line
			(start -0.120396 0.3048)
			(end -0.120396 0.2794)
			(stroke
				(width 0.1)
				(type default)
			)
			(layer "B.Fab")
		)
		(fp_line
			(start -0.120396 0.2794)
			(end 0.12065 0.2794)
			(stroke
				(width 0.1)
				(type default)
			)
			(layer "B.Fab")
		)
		(fp_line
			(start -0.12065 -0.2794)
			(end -0.12065 -0.3048)
			(stroke
				(width 0.1)
				(type default)
			)
			(layer "B.Fab")
		)
		(fp_line
			(start -0.12065 -0.3048)
			(end -0.67945 -0.3048)
			(stroke
				(width 0.1)
				(type default)
			)
			(layer "B.Fab")
		)
		(fp_line
			(start -0.67945 0.3048)
			(end -0.120396 0.3048)
			(stroke
				(width 0.1)
				(type default)
			)
			(layer "B.Fab")
		)
		(fp_line
			(start -0.67945 -0.3048)
			(end -0.67945 0.3048)
			(stroke
				(width 0.1)
				(type default)
			)
			(layer "B.Fab")
		)
		(pad "1" smd circle
			(at 0.40005 0)
			(size 0 0)
			(layers "B.Cu" "B.Mask" "B.Paste")
			(net "XTAL_CPU1_X48M_X2_R")
		)
		(pad "2" smd circle
			(at -0.40005 0)
			(size 0 0)
			(layers "B.Cu" "B.Mask" "B.Paste")
			(net "GND")
		)
	)
	(footprint ""
		(layer "B.Cu")
		(at 288.346896 -349.381572 -90)
		(property "Reference" "PR104"
			(at 0 0 90)
			(layer "B.SilkS")
			(hide yes)
			(effects
				(font
					(size 1.27 1.27)
				)
				(justify mirror)
			)
		)
		(property "Value" ""
			(at 0 0 90)
			(layer "B.Fab")
			(effects
				(font
					(size 1.27 1.27)
				)
				(justify mirror)
			)
		)
		(duplicate_pad_numbers_are_jumpers no)
		(fp_line
			(start -0.7874 0.4064)
			(end 0.7874 0.4064)
			(stroke
				(width 0.1524)
				(type default)
			)
			(layer "B.SilkS")
		)
		(fp_line
			(start 0.7874 0.4064)
			(end 0.7874 -0.4064)
			(stroke
				(width 0.1524)
				(type default)
			)
			(layer "B.SilkS")
		)
		(fp_line
			(start -0.7874 -0.4064)
			(end -0.7874 0.4064)
			(stroke
				(width 0.1524)
				(type default)
			)
			(layer "B.SilkS")
		)
		(fp_line
			(start 0.7874 -0.4064)
			(end -0.7874 -0.4064)
			(stroke
				(width 0.1524)
				(type default)
			)
			(layer "B.SilkS")
		)
		(fp_line
			(start -0.67945 0.3048)
			(end -0.120396 0.3048)
			(stroke
				(width 0.1)
				(type default)
			)
			(layer "B.Fab")
		)
		(fp_line
			(start -0.120396 0.3048)
			(end -0.120396 0.2794)
			(stroke
				(width 0.1)
				(type default)
			)
			(layer "B.Fab")
		)
		(fp_line
			(start 0.12065 0.3048)
			(end 0.67945 0.3048)
			(stroke
				(width 0.1)
				(type default)
			)
			(layer "B.Fab")
		)
		(fp_line
			(start 0.67945 0.3048)
			(end 0.67945 -0.305054)
			(stroke
				(width 0.1)
				(type default)
			)
			(layer "B.Fab")
		)
		(fp_line
			(start -0.120396 0.2794)
			(end 0.12065 0.2794)
			(stroke
				(width 0.1)
				(type default)
			)
			(layer "B.Fab")
		)
		(fp_line
			(start 0.12065 0.2794)
			(end 0.12065 0.3048)
			(stroke
				(width 0.1)
				(type default)
			)
			(layer "B.Fab")
		)
		(fp_line
			(start -0.12065 -0.2794)
			(end -0.12065 -0.3048)
			(stroke
				(width 0.1)
				(type default)
			)
			(layer "B.Fab")
		)
		(fp_line
			(start 0.12065 -0.2794)
			(end -0.12065 -0.2794)
			(stroke
				(width 0.1)
				(type default)
			)
			(layer "B.Fab")
		)
		(fp_line
			(start -0.67945 -0.3048)
			(end -0.67945 0.3048)
			(stroke
				(width 0.1)
				(type default)
			)
			(layer "B.Fab")
		)
		(fp_line
			(start -0.12065 -0.3048)
			(end -0.67945 -0.3048)
			(stroke
				(width 0.1)
				(type default)
			)
			(layer "B.Fab")
		)
		(fp_line
			(start 0.12065 -0.305054)
			(end 0.12065 -0.2794)
			(stroke
				(width 0.1)
				(type default)
			)
			(layer "B.Fab")
		)
		(fp_line
			(start 0.67945 -0.305054)
			(end 0.12065 -0.305054)
			(stroke
				(width 0.1)
				(type default)
			)
			(layer "B.Fab")
		)
		(pad "1" smd circle
			(at 0.40005 0 90)
			(size 0 0)
			(layers "B.Cu" "B.Mask" "B.Paste")
			(net "PVDDIO_P0_VOS2")
		)
		(pad "2" smd circle
			(at -0.40005 0 90)
			(size 0 0)
			(layers "B.Cu" "B.Mask" "B.Paste")
			(net "PVDDIO_P0")
		)
	)
	(footprint ""
		(layer "B.Cu")
		(at 215.0618 -337.312)
		(property "Reference" "R779"
			(at 0 0 0)
			(layer "B.SilkS")
			(hide yes)
			(effects
				(font
					(size 1.27 1.27)
				)
				(justify mirror)
			)
		)
		(property "Value" ""
			(at 0 0 0)
			(layer "B.Fab")
			(effects
				(font
					(size 1.27 1.27)
				)
				(justify mirror)
			)
		)
		(duplicate_pad_numbers_are_jumpers no)
		(fp_line
			(start -0.32512 -0.175006)
			(end -0.32512 0.175006)
			(stroke
				(width 0.1)
				(type default)
			)
			(layer "B.Fab")
		)
		(fp_line
			(start -0.32512 0.175006)
			(end 0.32512 0.175006)
			(stroke
				(width 0.1)
				(type default)
			)
			(layer "B.Fab")
		)
		(fp_line
			(start 0.32512 -0.175006)
			(end -0.32512 -0.175006)
			(stroke
				(width 0.1)
				(type default)
			)
			(layer "B.Fab")
		)
		(fp_line
			(start 0.32512 0.175006)
			(end 0.32512 -0.175006)
			(stroke
				(width 0.1)
				(type default)
			)
			(layer "B.Fab")
		)
		(pad "1" smd rect
			(at 0.2667 0 180)
			(size 0.3048 0.381)
			(layers "B.Cu" "B.Mask" "B.Paste")
			(net "SMB_RT_CPU1_P1_R_SCL")
		)
		(pad "2" smd rect
			(at -0.2667 0)
			(size 0.3048 0.381)
			(layers "B.Cu" "B.Mask" "B.Paste")
			(net "SMB_RT_CPU1_P1_R2_SCL")
		)
	)
	(footprint ""
		(layer "B.Cu")
		(at 106.466386 -266.005564)
		(property "Reference" "C2287"
			(at 0 0 0)
			(layer "B.SilkS")
			(hide yes)
			(effects
				(font
					(size 1.27 1.27)
				)
				(justify mirror)
			)
		)
		(property "Value" ""
			(at 0 0 0)
			(layer "B.Fab")
			(effects
				(font
					(size 1.27 1.27)
				)
				(justify mirror)
			)
		)
		(duplicate_pad_numbers_are_jumpers no)
		(fp_line
			(start -0.7874 -0.4064)
			(end -0.7874 0.4064)
			(stroke
				(width 0.1524)
				(type default)
			)
			(layer "B.SilkS")
		)
		(fp_line
			(start -0.7874 0.4064)
			(end 0.7874 0.4064)
			(stroke
				(width 0.1524)
				(type default)
			)
			(layer "B.SilkS")
		)
		(fp_line
			(start 0.7874 -0.4064)
			(end -0.7874 -0.4064)
			(stroke
				(width 0.1524)
				(type default)
			)
			(layer "B.SilkS")
		)
		(fp_line
			(start 0.7874 0.4064)
			(end 0.7874 -0.4064)
			(stroke
				(width 0.1524)
				(type default)
			)
			(layer "B.SilkS")
		)
		(fp_line
			(start -0.67945 -0.3048)
			(end -0.67945 0.3048)
			(stroke
				(width 0.1)
				(type default)
			)
			(layer "B.Fab")
		)
		(fp_line
			(start -0.67945 0.3048)
			(end -0.120396 0.3048)
			(stroke
				(width 0.1)
				(type default)
			)
			(layer "B.Fab")
		)
		(fp_line
			(start -0.12065 -0.3048)
			(end -0.67945 -0.3048)
			(stroke
				(width 0.1)
				(type default)
			)
			(layer "B.Fab")
		)
		(fp_line
			(start -0.12065 -0.2794)
			(end -0.12065 -0.3048)
			(stroke
				(width 0.1)
				(type default)
			)
			(layer "B.Fab")
		)
		(fp_line
			(start -0.120396 0.2794)
			(end 0.12065 0.2794)
			(stroke
				(width 0.1)
				(type default)
			)
			(layer "B.Fab")
		)
		(fp_line
			(start -0.120396 0.3048)
			(end -0.120396 0.2794)
			(stroke
				(width 0.1)
				(type default)
			)
			(layer "B.Fab")
		)
		(fp_line
			(start 0.12065 -0.305054)
			(end 0.12065 -0.2794)
			(stroke
				(width 0.1)
				(type default)
			)
			(layer "B.Fab")
		)
		(fp_line
			(start 0.12065 -0.2794)
			(end -0.12065 -0.2794)
			(stroke
				(width 0.1)
				(type default)
			)
			(layer "B.Fab")
		)
		(fp_line
			(start 0.12065 0.2794)
			(end 0.12065 0.3048)
			(stroke
				(width 0.1)
				(type default)
			)
			(layer "B.Fab")
		)
		(fp_line
			(start 0.12065 0.3048)
			(end 0.67945 0.3048)
			(stroke
				(width 0.1)
				(type default)
			)
			(layer "B.Fab")
		)
		(fp_line
			(start 0.67945 -0.305054)
			(end 0.12065 -0.305054)
			(stroke
				(width 0.1)
				(type default)
			)
			(layer "B.Fab")
		)
		(fp_line
			(start 0.67945 0.3048)
			(end 0.67945 -0.305054)
			(stroke
				(width 0.1)
				(type default)
			)
			(layer "B.Fab")
		)
		(pad "1" smd circle
			(at 0.40005 0 180)
			(size 0 0)
			(layers "B.Cu" "B.Mask" "B.Paste")
			(net "PVDD11_S3_P1")
		)
		(pad "2" smd circle
			(at -0.40005 0 180)
			(size 0 0)
			(layers "B.Cu" "B.Mask" "B.Paste")
			(net "GND")
		)
	)
	(footprint ""
		(layer "B.Cu")
		(at 241.756692 -420.80688 -90)
		(property "Reference" "R9000"
			(at 0 0 90)
			(layer "B.SilkS")
			(hide yes)
			(effects
				(font
					(size 1.27 1.27)
				)
				(justify mirror)
			)
		)
		(property "Value" ""
			(at 0 0 90)
			(layer "B.Fab")
			(effects
				(font
					(size 1.27 1.27)
				)
				(justify mirror)
			)
		)
		(duplicate_pad_numbers_are_jumpers no)
		(fp_line
			(start -0.7874 0.4064)
			(end 0.7874 0.4064)
			(stroke
				(width 0.1524)
				(type default)
			)
			(layer "B.SilkS")
		)
		(fp_line
			(start 0.7874 0.4064)
			(end 0.7874 -0.4064)
			(stroke
				(width 0.1524)
				(type default)
			)
			(layer "B.SilkS")
		)
		(fp_line
			(start -0.7874 -0.4064)
			(end -0.7874 0.4064)
			(stroke
				(width 0.1524)
				(type default)
			)
			(layer "B.SilkS")
		)
		(fp_line
			(start 0.7874 -0.4064)
			(end -0.7874 -0.4064)
			(stroke
				(width 0.1524)
				(type default)
			)
			(layer "B.SilkS")
		)
		(fp_line
			(start -0.67945 0.3048)
			(end -0.120396 0.3048)
			(stroke
				(width 0.1)
				(type default)
			)
			(layer "B.Fab")
		)
		(fp_line
			(start -0.120396 0.3048)
			(end -0.120396 0.2794)
			(stroke
				(width 0.1)
				(type default)
			)
			(layer "B.Fab")
		)
		(fp_line
			(start 0.12065 0.3048)
			(end 0.67945 0.3048)
			(stroke
				(width 0.1)
				(type default)
			)
			(layer "B.Fab")
		)
		(fp_line
			(start 0.67945 0.3048)
			(end 0.67945 -0.305054)
			(stroke
				(width 0.1)
				(type default)
			)
			(layer "B.Fab")
		)
		(fp_line
			(start -0.120396 0.2794)
			(end 0.12065 0.2794)
			(stroke
				(width 0.1)
				(type default)
			)
			(layer "B.Fab")
		)
		(fp_line
			(start 0.12065 0.2794)
			(end 0.12065 0.3048)
			(stroke
				(width 0.1)
				(type default)
			)
			(layer "B.Fab")
		)
		(fp_line
			(start -0.12065 -0.2794)
			(end -0.12065 -0.3048)
			(stroke
				(width 0.1)
				(type default)
			)
			(layer "B.Fab")
		)
		(fp_line
			(start 0.12065 -0.2794)
			(end -0.12065 -0.2794)
			(stroke
				(width 0.1)
				(type default)
			)
			(layer "B.Fab")
		)
		(fp_line
			(start -0.67945 -0.3048)
			(end -0.67945 0.3048)
			(stroke
				(width 0.1)
				(type default)
			)
			(layer "B.Fab")
		)
		(fp_line
			(start -0.12065 -0.3048)
			(end -0.67945 -0.3048)
			(stroke
				(width 0.1)
				(type default)
			)
			(layer "B.Fab")
		)
		(fp_line
			(start 0.12065 -0.305054)
			(end 0.12065 -0.2794)
			(stroke
				(width 0.1)
				(type default)
			)
			(layer "B.Fab")
		)
		(fp_line
			(start 0.67945 -0.305054)
			(end 0.12065 -0.305054)
			(stroke
				(width 0.1)
				(type default)
			)
			(layer "B.Fab")
		)
		(pad "1" smd circle
			(at 0.40005 0 90)
			(size 0 0)
			(layers "B.Cu" "B.Mask" "B.Paste")
			(net "P3V3_AUX")
		)
		(pad "2" smd circle
			(at -0.40005 0 90)
			(size 0 0)
			(layers "B.Cu" "B.Mask" "B.Paste")
			(net "FM_FAN_PWR_EN")
		)
	)
	(footprint ""
		(layer "B.Cu")
		(at 349.099886 -416.899344 90)
		(property "Reference" "C6561"
			(at 0 0 90)
			(layer "B.SilkS")
			(hide yes)
			(effects
				(font
					(size 1.27 1.27)
				)
				(justify mirror)
			)
		)
		(property "Value" ""
			(at 0 0 90)
			(layer "B.Fab")
			(effects
				(font
					(size 1.27 1.27)
				)
				(justify mirror)
			)
		)
		(duplicate_pad_numbers_are_jumpers no)
		(fp_line
			(start 0.299974 -0.150114)
			(end -0.299974 -0.150114)
			(stroke
				(width 0.1)
				(type default)
			)
			(layer "B.Fab")
		)
		(fp_line
			(start -0.299974 -0.150114)
			(end -0.299974 0.150114)
			(stroke
				(width 0.1)
				(type default)
			)
			(layer "B.Fab")
		)
		(fp_line
			(start 0.299974 0.150114)
			(end 0.299974 -0.150114)
			(stroke
				(width 0.1)
				(type default)
			)
			(layer "B.Fab")
		)
		(fp_line
			(start -0.299974 0.150114)
			(end 0.299974 0.150114)
			(stroke
				(width 0.1)
				(type default)
			)
			(layer "B.Fab")
		)
		(pad "1" smd rect
			(at 0.2667 0 270)
			(size 0.3048 0.381)
			(layers "B.Cu" "B.Mask" "B.Paste")
			(net "P5E_CPU0_P1_TX_BUF_C_DP<14>")
		)
		(pad "2" smd rect
			(at -0.2667 0 270)
			(size 0.3048 0.381)
			(layers "B.Cu" "B.Mask" "B.Paste")
			(net "P5E_CPU0_P1_TX_BUF_DP<14>")
		)
	)
	(footprint ""
		(layer "B.Cu")
		(at 288.29 -426.466 180)
		(property "Reference" "R2675"
			(at 0 0 0)
			(layer "B.SilkS")
			(hide yes)
			(effects
				(font
					(size 1.27 1.27)
				)
				(justify mirror)
			)
		)
		(property "Value" ""
			(at 0 0 0)
			(layer "B.Fab")
			(effects
				(font
					(size 1.27 1.27)
				)
				(justify mirror)
			)
		)
		(duplicate_pad_numbers_are_jumpers no)
		(fp_line
			(start 0.7874 0.4064)
			(end 0.7874 -0.4064)
			(stroke
				(width 0.1524)
				(type default)
			)
			(layer "B.SilkS")
		)
		(fp_line
			(start 0.7874 -0.4064)
			(end -0.7874 -0.4064)
			(stroke
				(width 0.1524)
				(type default)
			)
			(layer "B.SilkS")
		)
		(fp_line
			(start -0.7874 0.4064)
			(end 0.7874 0.4064)
			(stroke
				(width 0.1524)
				(type default)
			)
			(layer "B.SilkS")
		)
		(fp_line
			(start -0.7874 -0.4064)
			(end -0.7874 0.4064)
			(stroke
				(width 0.1524)
				(type default)
			)
			(layer "B.SilkS")
		)
		(fp_line
			(start 0.67945 0.3048)
			(end 0.67945 -0.305054)
			(stroke
				(width 0.1)
				(type default)
			)
			(layer "B.Fab")
		)
		(fp_line
			(start 0.67945 -0.305054)
			(end 0.12065 -0.305054)
			(stroke
				(width 0.1)
				(type default)
			)
			(layer "B.Fab")
		)
		(fp_line
			(start 0.12065 0.3048)
			(end 0.67945 0.3048)
			(stroke
				(width 0.1)
				(type default)
			)
			(layer "B.Fab")
		)
		(fp_line
			(start 0.12065 0.2794)
			(end 0.12065 0.3048)
			(stroke
				(width 0.1)
				(type default)
			)
			(layer "B.Fab")
		)
		(fp_line
			(start 0.12065 -0.2794)
			(end -0.12065 -0.2794)
			(stroke
				(width 0.1)
				(type default)
			)
			(layer "B.Fab")
		)
		(fp_line
			(start 0.12065 -0.305054)
			(end 0.12065 -0.2794)
			(stroke
				(width 0.1)
				(type default)
			)
			(layer "B.Fab")
		)
		(fp_line
			(start -0.120396 0.3048)
			(end -0.120396 0.2794)
			(stroke
				(width 0.1)
				(type default)
			)
			(layer "B.Fab")
		)
		(fp_line
			(start -0.120396 0.2794)
			(end 0.12065 0.2794)
			(stroke
				(width 0.1)
				(type default)
			)
			(layer "B.Fab")
		)
		(fp_line
			(start -0.12065 -0.2794)
			(end -0.12065 -0.3048)
			(stroke
				(width 0.1)
				(type default)
			)
			(layer "B.Fab")
		)
		(fp_line
			(start -0.12065 -0.3048)
			(end -0.67945 -0.3048)
			(stroke
				(width 0.1)
				(type default)
			)
			(layer "B.Fab")
		)
		(fp_line
			(start -0.67945 0.3048)
			(end -0.120396 0.3048)
			(stroke
				(width 0.1)
				(type default)
			)
			(layer "B.Fab")
		)
		(fp_line
			(start -0.67945 -0.3048)
			(end -0.67945 0.3048)
			(stroke
				(width 0.1)
				(type default)
			)
			(layer "B.Fab")
		)
		(pad "1" smd circle
			(at 0.40005 0)
			(size 0 0)
			(layers "B.Cu" "B.Mask" "B.Paste")
			(net "I3C_BMC_SWB_BUF_R_SCL")
		)
		(pad "2" smd circle
			(at -0.40005 0)
			(size 0 0)
			(layers "B.Cu" "B.Mask" "B.Paste")
			(net "I3C_BMC_SWB_BUF_SCL")
		)
	)
	(footprint ""
		(layer "B.Cu")
		(at 394.757402 -416.899344 90)
		(property "Reference" "C6611"
			(at 0 0 90)
			(layer "B.SilkS")
			(hide yes)
			(effects
				(font
					(size 1.27 1.27)
				)
				(justify mirror)
			)
		)
		(property "Value" ""
			(at 0 0 90)
			(layer "B.Fab")
			(effects
				(font
					(size 1.27 1.27)
				)
				(justify mirror)
			)
		)
		(duplicate_pad_numbers_are_jumpers no)
		(fp_line
			(start 0.299974 -0.150114)
			(end -0.299974 -0.150114)
			(stroke
				(width 0.1)
				(type default)
			)
			(layer "B.Fab")
		)
		(fp_line
			(start -0.299974 -0.150114)
			(end -0.299974 0.150114)
			(stroke
				(width 0.1)
				(type default)
			)
			(layer "B.Fab")
		)
		(fp_line
			(start 0.299974 0.150114)
			(end 0.299974 -0.150114)
			(stroke
				(width 0.1)
				(type default)
			)
			(layer "B.Fab")
		)
		(fp_line
			(start -0.299974 0.150114)
			(end 0.299974 0.150114)
			(stroke
				(width 0.1)
				(type default)
			)
			(layer "B.Fab")
		)
		(pad "1" smd rect
			(at 0.2667 0 270)
			(size 0.3048 0.381)
			(layers "B.Cu" "B.Mask" "B.Paste")
			(net "P5E_CPU0_P3_TX_BUF_C_DP<7>")
		)
		(pad "2" smd rect
			(at -0.2667 0 270)
			(size 0.3048 0.381)
			(layers "B.Cu" "B.Mask" "B.Paste")
			(net "P5E_CPU0_P3_TX_BUF_DP<7>")
		)
	)
	(footprint ""
		(layer "B.Cu")
		(at 361.899454 -266.00531)
		(property "Reference" "C2646"
			(at 0 0 0)
			(layer "B.SilkS")
			(hide yes)
			(effects
				(font
					(size 1.27 1.27)
				)
				(justify mirror)
			)
		)
		(property "Value" ""
			(at 0 0 0)
			(layer "B.Fab")
			(effects
				(font
					(size 1.27 1.27)
				)
				(justify mirror)
			)
		)
		(duplicate_pad_numbers_are_jumpers no)
		(fp_line
			(start -0.7874 -0.4064)
			(end -0.7874 0.4064)
			(stroke
				(width 0.1524)
				(type default)
			)
			(layer "B.SilkS")
		)
		(fp_line
			(start -0.7874 0.4064)
			(end 0.7874 0.4064)
			(stroke
				(width 0.1524)
				(type default)
			)
			(layer "B.SilkS")
		)
		(fp_line
			(start 0.7874 -0.4064)
			(end -0.7874 -0.4064)
			(stroke
				(width 0.1524)
				(type default)
			)
			(layer "B.SilkS")
		)
		(fp_line
			(start 0.7874 0.4064)
			(end 0.7874 -0.4064)
			(stroke
				(width 0.1524)
				(type default)
			)
			(layer "B.SilkS")
		)
		(fp_line
			(start -0.67945 -0.3048)
			(end -0.67945 0.3048)
			(stroke
				(width 0.1)
				(type default)
			)
			(layer "B.Fab")
		)
		(fp_line
			(start -0.67945 0.3048)
			(end -0.120396 0.3048)
			(stroke
				(width 0.1)
				(type default)
			)
			(layer "B.Fab")
		)
		(fp_line
			(start -0.12065 -0.3048)
			(end -0.67945 -0.3048)
			(stroke
				(width 0.1)
				(type default)
			)
			(layer "B.Fab")
		)
		(fp_line
			(start -0.12065 -0.2794)
			(end -0.12065 -0.3048)
			(stroke
				(width 0.1)
				(type default)
			)
			(layer "B.Fab")
		)
		(fp_line
			(start -0.120396 0.2794)
			(end 0.12065 0.2794)
			(stroke
				(width 0.1)
				(type default)
			)
			(layer "B.Fab")
		)
		(fp_line
			(start -0.120396 0.3048)
			(end -0.120396 0.2794)
			(stroke
				(width 0.1)
				(type default)
			)
			(layer "B.Fab")
		)
		(fp_line
			(start 0.12065 -0.305054)
			(end 0.12065 -0.2794)
			(stroke
				(width 0.1)
				(type default)
			)
			(layer "B.Fab")
		)
		(fp_line
			(start 0.12065 -0.2794)
			(end -0.12065 -0.2794)
			(stroke
				(width 0.1)
				(type default)
			)
			(layer "B.Fab")
		)
		(fp_line
			(start 0.12065 0.2794)
			(end 0.12065 0.3048)
			(stroke
				(width 0.1)
				(type default)
			)
			(layer "B.Fab")
		)
		(fp_line
			(start 0.12065 0.3048)
			(end 0.67945 0.3048)
			(stroke
				(width 0.1)
				(type default)
			)
			(layer "B.Fab")
		)
		(fp_line
			(start 0.67945 -0.305054)
			(end 0.12065 -0.305054)
			(stroke
				(width 0.1)
				(type default)
			)
			(layer "B.Fab")
		)
		(fp_line
			(start 0.67945 0.3048)
			(end 0.67945 -0.305054)
			(stroke
				(width 0.1)
				(type default)
			)
			(layer "B.Fab")
		)
		(pad "1" smd circle
			(at 0.40005 0 180)
			(size 0 0)
			(layers "B.Cu" "B.Mask" "B.Paste")
			(net "PVDD11_S3_P0")
		)
		(pad "2" smd circle
			(at -0.40005 0 180)
			(size 0 0)
			(layers "B.Cu" "B.Mask" "B.Paste")
			(net "GND")
		)
	)
	(footprint ""
		(layer "B.Cu")
		(at 447.563748 -10.567162 90)
		(property "Reference" "R32"
			(at 0 0 90)
			(layer "B.SilkS")
			(hide yes)
			(effects
				(font
					(size 1.27 1.27)
				)
				(justify mirror)
			)
		)
		(property "Value" ""
			(at 0 0 90)
			(layer "B.Fab")
			(effects
				(font
					(size 1.27 1.27)
				)
				(justify mirror)
			)
		)
		(duplicate_pad_numbers_are_jumpers no)
		(fp_line
			(start 0.7874 -0.4064)
			(end -0.7874 -0.4064)
			(stroke
				(width 0.1524)
				(type default)
			)
			(layer "B.SilkS")
		)
		(fp_line
			(start -0.7874 -0.4064)
			(end -0.7874 0.4064)
			(stroke
				(width 0.1524)
				(type default)
			)
			(layer "B.SilkS")
		)
		(fp_line
			(start 0.7874 0.4064)
			(end 0.7874 -0.4064)
			(stroke
				(width 0.1524)
				(type default)
			)
			(layer "B.SilkS")
		)
		(fp_line
			(start -0.7874 0.4064)
			(end 0.7874 0.4064)
			(stroke
				(width 0.1524)
				(type default)
			)
			(layer "B.SilkS")
		)
		(fp_line
			(start 0.67945 -0.305054)
			(end 0.12065 -0.305054)
			(stroke
				(width 0.1)
				(type default)
			)
			(layer "B.Fab")
		)
		(fp_line
			(start 0.12065 -0.305054)
			(end 0.12065 -0.2794)
			(stroke
				(width 0.1)
				(type default)
			)
			(layer "B.Fab")
		)
		(fp_line
			(start -0.12065 -0.3048)
			(end -0.67945 -0.3048)
			(stroke
				(width 0.1)
				(type default)
			)
			(layer "B.Fab")
		)
		(fp_line
			(start -0.67945 -0.3048)
			(end -0.67945 0.3048)
			(stroke
				(width 0.1)
				(type default)
			)
			(layer "B.Fab")
		)
		(fp_line
			(start 0.12065 -0.2794)
			(end -0.12065 -0.2794)
			(stroke
				(width 0.1)
				(type default)
			)
			(layer "B.Fab")
		)
		(fp_line
			(start -0.12065 -0.2794)
			(end -0.12065 -0.3048)
			(stroke
				(width 0.1)
				(type default)
			)
			(layer "B.Fab")
		)
		(fp_line
			(start 0.12065 0.2794)
			(end 0.12065 0.3048)
			(stroke
				(width 0.1)
				(type default)
			)
			(layer "B.Fab")
		)
		(fp_line
			(start -0.120396 0.2794)
			(end 0.12065 0.2794)
			(stroke
				(width 0.1)
				(type default)
			)
			(layer "B.Fab")
		)
		(fp_line
			(start 0.67945 0.3048)
			(end 0.67945 -0.305054)
			(stroke
				(width 0.1)
				(type default)
			)
			(layer "B.Fab")
		)
		(fp_line
			(start 0.12065 0.3048)
			(end 0.67945 0.3048)
			(stroke
				(width 0.1)
				(type default)
			)
			(layer "B.Fab")
		)
		(fp_line
			(start -0.120396 0.3048)
			(end -0.120396 0.2794)
			(stroke
				(width 0.1)
				(type default)
			)
			(layer "B.Fab")
		)
		(fp_line
			(start -0.67945 0.3048)
			(end -0.120396 0.3048)
			(stroke
				(width 0.1)
				(type default)
			)
			(layer "B.Fab")
		)
		(pad "1" smd circle
			(at 0.40005 0 270)
			(size 0 0)
			(layers "B.Cu" "B.Mask" "B.Paste")
			(net "OCP_SFF_ID0")
		)
		(pad "2" smd circle
			(at -0.40005 0 270)
			(size 0 0)
			(layers "B.Cu" "B.Mask" "B.Paste")
			(net "GND")
		)
	)
	(footprint ""
		(layer "B.Cu")
		(at 359.994454 -264.86231)
		(property "Reference" "C2623"
			(at 0 0 0)
			(layer "B.SilkS")
			(hide yes)
			(effects
				(font
					(size 1.27 1.27)
				)
				(justify mirror)
			)
		)
		(property "Value" ""
			(at 0 0 0)
			(layer "B.Fab")
			(effects
				(font
					(size 1.27 1.27)
				)
				(justify mirror)
			)
		)
		(duplicate_pad_numbers_are_jumpers no)
		(fp_line
			(start -0.7874 -0.4064)
			(end -0.7874 0.4064)
			(stroke
				(width 0.1524)
				(type default)
			)
			(layer "B.SilkS")
		)
		(fp_line
			(start -0.7874 0.4064)
			(end 0.7874 0.4064)
			(stroke
				(width 0.1524)
				(type default)
			)
			(layer "B.SilkS")
		)
		(fp_line
			(start 0.7874 -0.4064)
			(end -0.7874 -0.4064)
			(stroke
				(width 0.1524)
				(type default)
			)
			(layer "B.SilkS")
		)
		(fp_line
			(start 0.7874 0.4064)
			(end 0.7874 -0.4064)
			(stroke
				(width 0.1524)
				(type default)
			)
			(layer "B.SilkS")
		)
		(fp_line
			(start -0.67945 -0.3048)
			(end -0.67945 0.3048)
			(stroke
				(width 0.1)
				(type default)
			)
			(layer "B.Fab")
		)
		(fp_line
			(start -0.67945 0.3048)
			(end -0.120396 0.3048)
			(stroke
				(width 0.1)
				(type default)
			)
			(layer "B.Fab")
		)
		(fp_line
			(start -0.12065 -0.3048)
			(end -0.67945 -0.3048)
			(stroke
				(width 0.1)
				(type default)
			)
			(layer "B.Fab")
		)
		(fp_line
			(start -0.12065 -0.2794)
			(end -0.12065 -0.3048)
			(stroke
				(width 0.1)
				(type default)
			)
			(layer "B.Fab")
		)
		(fp_line
			(start -0.120396 0.2794)
			(end 0.12065 0.2794)
			(stroke
				(width 0.1)
				(type default)
			)
			(layer "B.Fab")
		)
		(fp_line
			(start -0.120396 0.3048)
			(end -0.120396 0.2794)
			(stroke
				(width 0.1)
				(type default)
			)
			(layer "B.Fab")
		)
		(fp_line
			(start 0.12065 -0.305054)
			(end 0.12065 -0.2794)
			(stroke
				(width 0.1)
				(type default)
			)
			(layer "B.Fab")
		)
		(fp_line
			(start 0.12065 -0.2794)
			(end -0.12065 -0.2794)
			(stroke
				(width 0.1)
				(type default)
			)
			(layer "B.Fab")
		)
		(fp_line
			(start 0.12065 0.2794)
			(end 0.12065 0.3048)
			(stroke
				(width 0.1)
				(type default)
			)
			(layer "B.Fab")
		)
		(fp_line
			(start 0.12065 0.3048)
			(end 0.67945 0.3048)
			(stroke
				(width 0.1)
				(type default)
			)
			(layer "B.Fab")
		)
		(fp_line
			(start 0.67945 -0.305054)
			(end 0.12065 -0.305054)
			(stroke
				(width 0.1)
				(type default)
			)
			(layer "B.Fab")
		)
		(fp_line
			(start 0.67945 0.3048)
			(end 0.67945 -0.305054)
			(stroke
				(width 0.1)
				(type default)
			)
			(layer "B.Fab")
		)
		(pad "1" smd circle
			(at 0.40005 0 180)
			(size 0 0)
			(layers "B.Cu" "B.Mask" "B.Paste")
			(net "PVDD11_S3_P0")
		)
		(pad "2" smd circle
			(at -0.40005 0 180)
			(size 0 0)
			(layers "B.Cu" "B.Mask" "B.Paste")
			(net "GND")
		)
	)
	(footprint ""
		(layer "B.Cu")
		(at 439.020966 -427.089824 180)
		(property "Reference" "R643"
			(at 0 0 0)
			(layer "B.SilkS")
			(hide yes)
			(effects
				(font
					(size 1.27 1.27)
				)
				(justify mirror)
			)
		)
		(property "Value" ""
			(at 0 0 0)
			(layer "B.Fab")
			(effects
				(font
					(size 1.27 1.27)
				)
				(justify mirror)
			)
		)
		(duplicate_pad_numbers_are_jumpers no)
		(fp_line
			(start 0.7874 0.4064)
			(end 0.7874 -0.4064)
			(stroke
				(width 0.1524)
				(type default)
			)
			(layer "B.SilkS")
		)
		(fp_line
			(start 0.7874 -0.4064)
			(end -0.7874 -0.4064)
			(stroke
				(width 0.1524)
				(type default)
			)
			(layer "B.SilkS")
		)
		(fp_line
			(start -0.7874 0.4064)
			(end 0.7874 0.4064)
			(stroke
				(width 0.1524)
				(type default)
			)
			(layer "B.SilkS")
		)
		(fp_line
			(start -0.7874 -0.4064)
			(end -0.7874 0.4064)
			(stroke
				(width 0.1524)
				(type default)
			)
			(layer "B.SilkS")
		)
		(fp_line
			(start 0.67945 0.3048)
			(end 0.67945 -0.305054)
			(stroke
				(width 0.1)
				(type default)
			)
			(layer "B.Fab")
		)
		(fp_line
			(start 0.67945 -0.305054)
			(end 0.12065 -0.305054)
			(stroke
				(width 0.1)
				(type default)
			)
			(layer "B.Fab")
		)
		(fp_line
			(start 0.12065 0.3048)
			(end 0.67945 0.3048)
			(stroke
				(width 0.1)
				(type default)
			)
			(layer "B.Fab")
		)
		(fp_line
			(start 0.12065 0.2794)
			(end 0.12065 0.3048)
			(stroke
				(width 0.1)
				(type default)
			)
			(layer "B.Fab")
		)
		(fp_line
			(start 0.12065 -0.2794)
			(end -0.12065 -0.2794)
			(stroke
				(width 0.1)
				(type default)
			)
			(layer "B.Fab")
		)
		(fp_line
			(start 0.12065 -0.305054)
			(end 0.12065 -0.2794)
			(stroke
				(width 0.1)
				(type default)
			)
			(layer "B.Fab")
		)
		(fp_line
			(start -0.120396 0.3048)
			(end -0.120396 0.2794)
			(stroke
				(width 0.1)
				(type default)
			)
			(layer "B.Fab")
		)
		(fp_line
			(start -0.120396 0.2794)
			(end 0.12065 0.2794)
			(stroke
				(width 0.1)
				(type default)
			)
			(layer "B.Fab")
		)
		(fp_line
			(start -0.12065 -0.2794)
			(end -0.12065 -0.3048)
			(stroke
				(width 0.1)
				(type default)
			)
			(layer "B.Fab")
		)
		(fp_line
			(start -0.12065 -0.3048)
			(end -0.67945 -0.3048)
			(stroke
				(width 0.1)
				(type default)
			)
			(layer "B.Fab")
		)
		(fp_line
			(start -0.67945 0.3048)
			(end -0.120396 0.3048)
			(stroke
				(width 0.1)
				(type default)
			)
			(layer "B.Fab")
		)
		(fp_line
			(start -0.67945 -0.3048)
			(end -0.67945 0.3048)
			(stroke
				(width 0.1)
				(type default)
			)
			(layer "B.Fab")
		)
		(pad "1" smd circle
			(at 0.40005 0)
			(size 0 0)
			(layers "B.Cu" "B.Mask" "B.Paste")
			(net "P3V3_AUX")
		)
		(pad "2" smd circle
			(at -0.40005 0)
			(size 0 0)
			(layers "B.Cu" "B.Mask" "B.Paste")
			(net "PWRGD_P0V9_RETIMER_CPU0_R")
		)
	)
	(footprint ""
		(layer "B.Cu")
		(at 401.650962 -316.917578 180)
		(property "Reference" "Y3"
			(at 1.188974 2.370836 0)
			(unlocked yes)
			(layer "B.SilkS")
			(effects
				(font
					(size 0.7874 0.5842)
					(thickness 0.1524)
				)
				(justify left mirror)
			)
		)
		(property "Value" ""
			(at 0 0 0)
			(layer "B.Fab")
			(effects
				(font
					(size 1.27 1.27)
				)
				(justify mirror)
			)
		)
		(duplicate_pad_numbers_are_jumpers no)
		(fp_line
			(start 1.905 1.0414)
			(end -1.905 1.0414)
			(stroke
				(width 0.1524)
				(type default)
			)
			(layer "B.SilkS")
		)
		(fp_line
			(start 1.905 -1.0414)
			(end 1.905 1.0414)
			(stroke
				(width 0.1524)
				(type default)
			)
			(layer "B.SilkS")
		)
		(fp_line
			(start -1.905 1.0414)
			(end -1.905 -1.0414)
			(stroke
				(width 0.1524)
				(type default)
			)
			(layer "B.SilkS")
		)
		(fp_line
			(start -1.905 -1.0414)
			(end 1.905 -1.0414)
			(stroke
				(width 0.1524)
				(type default)
			)
			(layer "B.SilkS")
		)
		(fp_line
			(start 1.649984 0.824992)
			(end -1.649984 0.824992)
			(stroke
				(width 0.1)
				(type default)
			)
			(layer "B.Fab")
		)
		(fp_line
			(start 1.649984 -0.824992)
			(end 1.649984 0.824992)
			(stroke
				(width 0.1)
				(type default)
			)
			(layer "B.Fab")
		)
		(fp_line
			(start -1.649984 0.824992)
			(end -1.649984 -0.824992)
			(stroke
				(width 0.1)
				(type default)
			)
			(layer "B.Fab")
		)
		(fp_line
			(start -1.649984 -0.824992)
			(end 1.649984 -0.824992)
			(stroke
				(width 0.1)
				(type default)
			)
			(layer "B.Fab")
		)
		(pad "1" smd rect
			(at 1.249934 0)
			(size 1.016 1.8034)
			(layers "B.Cu" "B.Mask" "B.Paste")
			(net "XTAL_CPU0_X32K_X1")
		)
		(pad "2" smd rect
			(at -1.249934 0 180)
			(size 1.016 1.8034)
			(layers "B.Cu" "B.Mask" "B.Paste")
			(net "XTAL_CPU0_X32K_X2")
		)
		(zone
			(layer "B.Cu")
			(hatch none 0.5)
			(connect_pads
				(clearance 0)
			)
			(min_thickness 0.25)
			(keepout
				(tracks not_allowed)
				(vias allowed)
				(pads allowed)
				(copperpour not_allowed)
				(footprints allowed)
			)
			(placement
				(enabled no)
				(sheetname "")
			)
			(fill
				(thermal_gap 0.5)
				(thermal_bridge_width 0.5)
				(island_removal_mode 0)
			)
			(polygon
				(pts
					(xy 400.959828 -315.965078) (xy 400.959828 -317.870078) (xy 402.342096 -317.870078) (xy 402.342096 -315.965078)
				)
			)
		)
	)
	(footprint ""
		(layer "B.Cu")
		(at 389.731758 -321.179952)
		(property "Reference" "R469"
			(at 0 0 0)
			(layer "B.SilkS")
			(hide yes)
			(effects
				(font
					(size 1.27 1.27)
				)
				(justify mirror)
			)
		)
		(property "Value" ""
			(at 0 0 0)
			(layer "B.Fab")
			(effects
				(font
					(size 1.27 1.27)
				)
				(justify mirror)
			)
		)
		(duplicate_pad_numbers_are_jumpers no)
		(fp_line
			(start -0.7874 -0.4064)
			(end -0.7874 0.4064)
			(stroke
				(width 0.1524)
				(type default)
			)
			(layer "B.SilkS")
		)
		(fp_line
			(start -0.7874 0.4064)
			(end 0.7874 0.4064)
			(stroke
				(width 0.1524)
				(type default)
			)
			(layer "B.SilkS")
		)
		(fp_line
			(start 0.7874 -0.4064)
			(end -0.7874 -0.4064)
			(stroke
				(width 0.1524)
				(type default)
			)
			(layer "B.SilkS")
		)
		(fp_line
			(start 0.7874 0.4064)
			(end 0.7874 -0.4064)
			(stroke
				(width 0.1524)
				(type default)
			)
			(layer "B.SilkS")
		)
		(fp_line
			(start -0.67945 -0.3048)
			(end -0.67945 0.3048)
			(stroke
				(width 0.1)
				(type default)
			)
			(layer "B.Fab")
		)
		(fp_line
			(start -0.67945 0.3048)
			(end -0.120396 0.3048)
			(stroke
				(width 0.1)
				(type default)
			)
			(layer "B.Fab")
		)
		(fp_line
			(start -0.12065 -0.3048)
			(end -0.67945 -0.3048)
			(stroke
				(width 0.1)
				(type default)
			)
			(layer "B.Fab")
		)
		(fp_line
			(start -0.12065 -0.2794)
			(end -0.12065 -0.3048)
			(stroke
				(width 0.1)
				(type default)
			)
			(layer "B.Fab")
		)
		(fp_line
			(start -0.120396 0.2794)
			(end 0.12065 0.2794)
			(stroke
				(width 0.1)
				(type default)
			)
			(layer "B.Fab")
		)
		(fp_line
			(start -0.120396 0.3048)
			(end -0.120396 0.2794)
			(stroke
				(width 0.1)
				(type default)
			)
			(layer "B.Fab")
		)
		(fp_line
			(start 0.12065 -0.305054)
			(end 0.12065 -0.2794)
			(stroke
				(width 0.1)
				(type default)
			)
			(layer "B.Fab")
		)
		(fp_line
			(start 0.12065 -0.2794)
			(end -0.12065 -0.2794)
			(stroke
				(width 0.1)
				(type default)
			)
			(layer "B.Fab")
		)
		(fp_line
			(start 0.12065 0.2794)
			(end 0.12065 0.3048)
			(stroke
				(width 0.1)
				(type default)
			)
			(layer "B.Fab")
		)
		(fp_line
			(start 0.12065 0.3048)
			(end 0.67945 0.3048)
			(stroke
				(width 0.1)
				(type default)
			)
			(layer "B.Fab")
		)
		(fp_line
			(start 0.67945 -0.305054)
			(end 0.12065 -0.305054)
			(stroke
				(width 0.1)
				(type default)
			)
			(layer "B.Fab")
		)
		(fp_line
			(start 0.67945 0.3048)
			(end 0.67945 -0.305054)
			(stroke
				(width 0.1)
				(type default)
			)
			(layer "B.Fab")
		)
		(pad "1" smd circle
			(at 0.40005 0 180)
			(size 0 0)
			(layers "B.Cu" "B.Mask" "B.Paste")
			(net "ESPI_CPU0_D1")
		)
		(pad "2" smd circle
			(at -0.40005 0 180)
			(size 0 0)
			(layers "B.Cu" "B.Mask" "B.Paste")
			(net "ESPI_CPU0_R_D1")
		)
	)
	(footprint ""
		(layer "B.Cu")
		(at 143.3068 -13.762228 90)
		(property "Reference" "R1815"
			(at 0 0 90)
			(layer "B.SilkS")
			(hide yes)
			(effects
				(font
					(size 1.27 1.27)
				)
				(justify mirror)
			)
		)
		(property "Value" ""
			(at 0 0 90)
			(layer "B.Fab")
			(effects
				(font
					(size 1.27 1.27)
				)
				(justify mirror)
			)
		)
		(duplicate_pad_numbers_are_jumpers no)
		(fp_line
			(start 0.7874 -0.4064)
			(end -0.7874 -0.4064)
			(stroke
				(width 0.1524)
				(type default)
			)
			(layer "B.SilkS")
		)
		(fp_line
			(start -0.7874 -0.4064)
			(end -0.7874 0.4064)
			(stroke
				(width 0.1524)
				(type default)
			)
			(layer "B.SilkS")
		)
		(fp_line
			(start 0.7874 0.4064)
			(end 0.7874 -0.4064)
			(stroke
				(width 0.1524)
				(type default)
			)
			(layer "B.SilkS")
		)
		(fp_line
			(start -0.7874 0.4064)
			(end 0.7874 0.4064)
			(stroke
				(width 0.1524)
				(type default)
			)
			(layer "B.SilkS")
		)
		(fp_line
			(start 0.67945 -0.305054)
			(end 0.12065 -0.305054)
			(stroke
				(width 0.1)
				(type default)
			)
			(layer "B.Fab")
		)
		(fp_line
			(start 0.12065 -0.305054)
			(end 0.12065 -0.2794)
			(stroke
				(width 0.1)
				(type default)
			)
			(layer "B.Fab")
		)
		(fp_line
			(start -0.12065 -0.3048)
			(end -0.67945 -0.3048)
			(stroke
				(width 0.1)
				(type default)
			)
			(layer "B.Fab")
		)
		(fp_line
			(start -0.67945 -0.3048)
			(end -0.67945 0.3048)
			(stroke
				(width 0.1)
				(type default)
			)
			(layer "B.Fab")
		)
		(fp_line
			(start 0.12065 -0.2794)
			(end -0.12065 -0.2794)
			(stroke
				(width 0.1)
				(type default)
			)
			(layer "B.Fab")
		)
		(fp_line
			(start -0.12065 -0.2794)
			(end -0.12065 -0.3048)
			(stroke
				(width 0.1)
				(type default)
			)
			(layer "B.Fab")
		)
		(fp_line
			(start 0.12065 0.2794)
			(end 0.12065 0.3048)
			(stroke
				(width 0.1)
				(type default)
			)
			(layer "B.Fab")
		)
		(fp_line
			(start -0.120396 0.2794)
			(end 0.12065 0.2794)
			(stroke
				(width 0.1)
				(type default)
			)
			(layer "B.Fab")
		)
		(fp_line
			(start 0.67945 0.3048)
			(end 0.67945 -0.305054)
			(stroke
				(width 0.1)
				(type default)
			)
			(layer "B.Fab")
		)
		(fp_line
			(start 0.12065 0.3048)
			(end 0.67945 0.3048)
			(stroke
				(width 0.1)
				(type default)
			)
			(layer "B.Fab")
		)
		(fp_line
			(start -0.120396 0.3048)
			(end -0.120396 0.2794)
			(stroke
				(width 0.1)
				(type default)
			)
			(layer "B.Fab")
		)
		(fp_line
			(start -0.67945 0.3048)
			(end -0.120396 0.3048)
			(stroke
				(width 0.1)
				(type default)
			)
			(layer "B.Fab")
		)
		(pad "1" smd circle
			(at 0.40005 0 270)
			(size 0 0)
			(layers "B.Cu" "B.Mask" "B.Paste")
			(net "SCM_SYS_PWRBTN_N")
		)
		(pad "2" smd circle
			(at -0.40005 0 270)
			(size 0 0)
			(layers "B.Cu" "B.Mask" "B.Paste")
			(net "SCM_SYS_PWRBTN_R_N")
		)
	)
	(footprint ""
		(layer "B.Cu")
		(at 373.329454 -250.89231)
		(property "Reference" "C2592"
			(at 0 0 0)
			(layer "B.SilkS")
			(hide yes)
			(effects
				(font
					(size 1.27 1.27)
				)
				(justify mirror)
			)
		)
		(property "Value" ""
			(at 0 0 0)
			(layer "B.Fab")
			(effects
				(font
					(size 1.27 1.27)
				)
				(justify mirror)
			)
		)
		(duplicate_pad_numbers_are_jumpers no)
		(fp_line
			(start -0.7874 -0.4064)
			(end -0.7874 0.4064)
			(stroke
				(width 0.1524)
				(type default)
			)
			(layer "B.SilkS")
		)
		(fp_line
			(start -0.7874 0.4064)
			(end 0.7874 0.4064)
			(stroke
				(width 0.1524)
				(type default)
			)
			(layer "B.SilkS")
		)
		(fp_line
			(start 0.7874 -0.4064)
			(end -0.7874 -0.4064)
			(stroke
				(width 0.1524)
				(type default)
			)
			(layer "B.SilkS")
		)
		(fp_line
			(start 0.7874 0.4064)
			(end 0.7874 -0.4064)
			(stroke
				(width 0.1524)
				(type default)
			)
			(layer "B.SilkS")
		)
		(fp_line
			(start -0.67945 -0.3048)
			(end -0.67945 0.3048)
			(stroke
				(width 0.1)
				(type default)
			)
			(layer "B.Fab")
		)
		(fp_line
			(start -0.67945 0.3048)
			(end -0.120396 0.3048)
			(stroke
				(width 0.1)
				(type default)
			)
			(layer "B.Fab")
		)
		(fp_line
			(start -0.12065 -0.3048)
			(end -0.67945 -0.3048)
			(stroke
				(width 0.1)
				(type default)
			)
			(layer "B.Fab")
		)
		(fp_line
			(start -0.12065 -0.2794)
			(end -0.12065 -0.3048)
			(stroke
				(width 0.1)
				(type default)
			)
			(layer "B.Fab")
		)
		(fp_line
			(start -0.120396 0.2794)
			(end 0.12065 0.2794)
			(stroke
				(width 0.1)
				(type default)
			)
			(layer "B.Fab")
		)
		(fp_line
			(start -0.120396 0.3048)
			(end -0.120396 0.2794)
			(stroke
				(width 0.1)
				(type default)
			)
			(layer "B.Fab")
		)
		(fp_line
			(start 0.12065 -0.305054)
			(end 0.12065 -0.2794)
			(stroke
				(width 0.1)
				(type default)
			)
			(layer "B.Fab")
		)
		(fp_line
			(start 0.12065 -0.2794)
			(end -0.12065 -0.2794)
			(stroke
				(width 0.1)
				(type default)
			)
			(layer "B.Fab")
		)
		(fp_line
			(start 0.12065 0.2794)
			(end 0.12065 0.3048)
			(stroke
				(width 0.1)
				(type default)
			)
			(layer "B.Fab")
		)
		(fp_line
			(start 0.12065 0.3048)
			(end 0.67945 0.3048)
			(stroke
				(width 0.1)
				(type default)
			)
			(layer "B.Fab")
		)
		(fp_line
			(start 0.67945 -0.305054)
			(end 0.12065 -0.305054)
			(stroke
				(width 0.1)
				(type default)
			)
			(layer "B.Fab")
		)
		(fp_line
			(start 0.67945 0.3048)
			(end 0.67945 -0.305054)
			(stroke
				(width 0.1)
				(type default)
			)
			(layer "B.Fab")
		)
		(pad "1" smd circle
			(at 0.40005 0 180)
			(size 0 0)
			(layers "B.Cu" "B.Mask" "B.Paste")
			(net "PVDDCR_SOC_P0")
		)
		(pad "2" smd circle
			(at -0.40005 0 180)
			(size 0 0)
			(layers "B.Cu" "B.Mask" "B.Paste")
			(net "GND")
		)
	)
	(footprint ""
		(layer "B.Cu")
		(at 52.178458 -386.766562 90)
		(property "Reference" "C201"
			(at 0 0 90)
			(layer "B.SilkS")
			(hide yes)
			(effects
				(font
					(size 1.27 1.27)
				)
				(justify mirror)
			)
		)
		(property "Value" ""
			(at 0 0 90)
			(layer "B.Fab")
			(effects
				(font
					(size 1.27 1.27)
				)
				(justify mirror)
			)
		)
		(duplicate_pad_numbers_are_jumpers no)
		(fp_line
			(start 0.299974 -0.150114)
			(end -0.299974 -0.150114)
			(stroke
				(width 0.1)
				(type default)
			)
			(layer "B.Fab")
		)
		(fp_line
			(start -0.299974 -0.150114)
			(end -0.299974 0.150114)
			(stroke
				(width 0.1)
				(type default)
			)
			(layer "B.Fab")
		)
		(fp_line
			(start 0.299974 0.150114)
			(end 0.299974 -0.150114)
			(stroke
				(width 0.1)
				(type default)
			)
			(layer "B.Fab")
		)
		(fp_line
			(start -0.299974 0.150114)
			(end 0.299974 0.150114)
			(stroke
				(width 0.1)
				(type default)
			)
			(layer "B.Fab")
		)
		(pad "1" smd rect
			(at 0.2667 0 270)
			(size 0.3048 0.381)
			(layers "B.Cu" "B.Mask" "B.Paste")
			(net "P0V9_CPU1_RT0_2A_2D")
		)
		(pad "2" smd rect
			(at -0.2667 0 270)
			(size 0.3048 0.381)
			(layers "B.Cu" "B.Mask" "B.Paste")
			(net "GND")
		)
	)
	(footprint ""
		(layer "B.Cu")
		(at 130.657092 -50.302922 90)
		(property "Reference" "R6067"
			(at 0 0 90)
			(layer "B.SilkS")
			(hide yes)
			(effects
				(font
					(size 1.27 1.27)
				)
				(justify mirror)
			)
		)
		(property "Value" ""
			(at 0 0 90)
			(layer "B.Fab")
			(effects
				(font
					(size 1.27 1.27)
				)
				(justify mirror)
			)
		)
		(duplicate_pad_numbers_are_jumpers no)
		(fp_line
			(start 0.7874 -0.4064)
			(end -0.7874 -0.4064)
			(stroke
				(width 0.1524)
				(type default)
			)
			(layer "B.SilkS")
		)
		(fp_line
			(start -0.7874 -0.4064)
			(end -0.7874 0.4064)
			(stroke
				(width 0.1524)
				(type default)
			)
			(layer "B.SilkS")
		)
		(fp_line
			(start 0.7874 0.4064)
			(end 0.7874 -0.4064)
			(stroke
				(width 0.1524)
				(type default)
			)
			(layer "B.SilkS")
		)
		(fp_line
			(start -0.7874 0.4064)
			(end 0.7874 0.4064)
			(stroke
				(width 0.1524)
				(type default)
			)
			(layer "B.SilkS")
		)
		(fp_line
			(start 0.67945 -0.305054)
			(end 0.12065 -0.305054)
			(stroke
				(width 0.1)
				(type default)
			)
			(layer "B.Fab")
		)
		(fp_line
			(start 0.12065 -0.305054)
			(end 0.12065 -0.2794)
			(stroke
				(width 0.1)
				(type default)
			)
			(layer "B.Fab")
		)
		(fp_line
			(start -0.12065 -0.3048)
			(end -0.67945 -0.3048)
			(stroke
				(width 0.1)
				(type default)
			)
			(layer "B.Fab")
		)
		(fp_line
			(start -0.67945 -0.3048)
			(end -0.67945 0.3048)
			(stroke
				(width 0.1)
				(type default)
			)
			(layer "B.Fab")
		)
		(fp_line
			(start 0.12065 -0.2794)
			(end -0.12065 -0.2794)
			(stroke
				(width 0.1)
				(type default)
			)
			(layer "B.Fab")
		)
		(fp_line
			(start -0.12065 -0.2794)
			(end -0.12065 -0.3048)
			(stroke
				(width 0.1)
				(type default)
			)
			(layer "B.Fab")
		)
		(fp_line
			(start 0.12065 0.2794)
			(end 0.12065 0.3048)
			(stroke
				(width 0.1)
				(type default)
			)
			(layer "B.Fab")
		)
		(fp_line
			(start -0.120396 0.2794)
			(end 0.12065 0.2794)
			(stroke
				(width 0.1)
				(type default)
			)
			(layer "B.Fab")
		)
		(fp_line
			(start 0.67945 0.3048)
			(end 0.67945 -0.305054)
			(stroke
				(width 0.1)
				(type default)
			)
			(layer "B.Fab")
		)
		(fp_line
			(start 0.12065 0.3048)
			(end 0.67945 0.3048)
			(stroke
				(width 0.1)
				(type default)
			)
			(layer "B.Fab")
		)
		(fp_line
			(start -0.120396 0.3048)
			(end -0.120396 0.2794)
			(stroke
				(width 0.1)
				(type default)
			)
			(layer "B.Fab")
		)
		(fp_line
			(start -0.67945 0.3048)
			(end -0.120396 0.3048)
			(stroke
				(width 0.1)
				(type default)
			)
			(layer "B.Fab")
		)
		(pad "1" smd rect
			(at 0.40005 0 90)
			(size 0.4572 0.508)
			(layers "B.Cu" "B.Mask" "B.Paste")
			(net "JTAG_SCM_TDO_R")
		)
		(pad "2" smd rect
			(at -0.40005 0 90)
			(size 0.4572 0.508)
			(layers "B.Cu" "B.Mask" "B.Paste")
			(net "JTAG_SCM_TDI")
		)
	)
	(footprint ""
		(layer "B.Cu")
		(at 375.278396 -395.148562 90)
		(property "Reference" "C1020"
			(at 0 0 90)
			(layer "B.SilkS")
			(hide yes)
			(effects
				(font
					(size 1.27 1.27)
				)
				(justify mirror)
			)
		)
		(property "Value" ""
			(at 0 0 90)
			(layer "B.Fab")
			(effects
				(font
					(size 1.27 1.27)
				)
				(justify mirror)
			)
		)
		(duplicate_pad_numbers_are_jumpers no)
		(fp_line
			(start 0.299974 -0.150114)
			(end -0.299974 -0.150114)
			(stroke
				(width 0.1)
				(type default)
			)
			(layer "B.Fab")
		)
		(fp_line
			(start -0.299974 -0.150114)
			(end -0.299974 0.150114)
			(stroke
				(width 0.1)
				(type default)
			)
			(layer "B.Fab")
		)
		(fp_line
			(start 0.299974 0.150114)
			(end 0.299974 -0.150114)
			(stroke
				(width 0.1)
				(type default)
			)
			(layer "B.Fab")
		)
		(fp_line
			(start -0.299974 0.150114)
			(end 0.299974 0.150114)
			(stroke
				(width 0.1)
				(type default)
			)
			(layer "B.Fab")
		)
		(pad "1" smd rect
			(at 0.2667 0 270)
			(size 0.3048 0.381)
			(layers "B.Cu" "B.Mask" "B.Paste")
			(net "P0V9_CPU0_RT3_2A_2D")
		)
		(pad "2" smd rect
			(at -0.2667 0 270)
			(size 0.3048 0.381)
			(layers "B.Cu" "B.Mask" "B.Paste")
			(net "GND")
		)
	)
	(footprint ""
		(layer "B.Cu")
		(at 240.327942 -290.564062)
		(property "Reference" "PR6500"
			(at 0 0 0)
			(layer "B.SilkS")
			(hide yes)
			(effects
				(font
					(size 1.27 1.27)
				)
				(justify mirror)
			)
		)
		(property "Value" ""
			(at 0 0 0)
			(layer "B.Fab")
			(effects
				(font
					(size 1.27 1.27)
				)
				(justify mirror)
			)
		)
		(duplicate_pad_numbers_are_jumpers no)
		(fp_line
			(start -0.7874 -0.4064)
			(end -0.7874 0.4064)
			(stroke
				(width 0.1524)
				(type default)
			)
			(layer "B.SilkS")
		)
		(fp_line
			(start -0.7874 0.4064)
			(end 0.7874 0.4064)
			(stroke
				(width 0.1524)
				(type default)
			)
			(layer "B.SilkS")
		)
		(fp_line
			(start 0.7874 -0.4064)
			(end -0.7874 -0.4064)
			(stroke
				(width 0.1524)
				(type default)
			)
			(layer "B.SilkS")
		)
		(fp_line
			(start 0.7874 0.4064)
			(end 0.7874 -0.4064)
			(stroke
				(width 0.1524)
				(type default)
			)
			(layer "B.SilkS")
		)
		(fp_line
			(start -0.67945 -0.3048)
			(end -0.67945 0.3048)
			(stroke
				(width 0.1)
				(type default)
			)
			(layer "B.Fab")
		)
		(fp_line
			(start -0.67945 0.3048)
			(end -0.120396 0.3048)
			(stroke
				(width 0.1)
				(type default)
			)
			(layer "B.Fab")
		)
		(fp_line
			(start -0.12065 -0.3048)
			(end -0.67945 -0.3048)
			(stroke
				(width 0.1)
				(type default)
			)
			(layer "B.Fab")
		)
		(fp_line
			(start -0.12065 -0.2794)
			(end -0.12065 -0.3048)
			(stroke
				(width 0.1)
				(type default)
			)
			(layer "B.Fab")
		)
		(fp_line
			(start -0.120396 0.2794)
			(end 0.12065 0.2794)
			(stroke
				(width 0.1)
				(type default)
			)
			(layer "B.Fab")
		)
		(fp_line
			(start -0.120396 0.3048)
			(end -0.120396 0.2794)
			(stroke
				(width 0.1)
				(type default)
			)
			(layer "B.Fab")
		)
		(fp_line
			(start 0.12065 -0.305054)
			(end 0.12065 -0.2794)
			(stroke
				(width 0.1)
				(type default)
			)
			(layer "B.Fab")
		)
		(fp_line
			(start 0.12065 -0.2794)
			(end -0.12065 -0.2794)
			(stroke
				(width 0.1)
				(type default)
			)
			(layer "B.Fab")
		)
		(fp_line
			(start 0.12065 0.2794)
			(end 0.12065 0.3048)
			(stroke
				(width 0.1)
				(type default)
			)
			(layer "B.Fab")
		)
		(fp_line
			(start 0.12065 0.3048)
			(end 0.67945 0.3048)
			(stroke
				(width 0.1)
				(type default)
			)
			(layer "B.Fab")
		)
		(fp_line
			(start 0.67945 -0.305054)
			(end 0.12065 -0.305054)
			(stroke
				(width 0.1)
				(type default)
			)
			(layer "B.Fab")
		)
		(fp_line
			(start 0.67945 0.3048)
			(end 0.67945 -0.305054)
			(stroke
				(width 0.1)
				(type default)
			)
			(layer "B.Fab")
		)
		(pad "1" smd circle
			(at 0.40005 0 180)
			(size 0 0)
			(layers "B.Cu" "B.Mask" "B.Paste")
			(net "GND")
		)
		(pad "2" smd circle
			(at -0.40005 0 180)
			(size 0 0)
			(layers "B.Cu" "B.Mask" "B.Paste")
			(net "P1V8_RETIMER_CPU0_MODE")
		)
	)
	(footprint ""
		(layer "B.Cu")
		(at 423.015156 -244.08511)
		(property "Reference" "R382"
			(at 0 0 0)
			(layer "B.SilkS")
			(hide yes)
			(effects
				(font
					(size 1.27 1.27)
				)
				(justify mirror)
			)
		)
		(property "Value" ""
			(at 0 0 0)
			(layer "B.Fab")
			(effects
				(font
					(size 1.27 1.27)
				)
				(justify mirror)
			)
		)
		(duplicate_pad_numbers_are_jumpers no)
		(fp_line
			(start -0.7874 -0.4064)
			(end -0.7874 0.4064)
			(stroke
				(width 0.1524)
				(type default)
			)
			(layer "B.SilkS")
		)
		(fp_line
			(start -0.7874 0.4064)
			(end 0.7874 0.4064)
			(stroke
				(width 0.1524)
				(type default)
			)
			(layer "B.SilkS")
		)
		(fp_line
			(start 0.7874 -0.4064)
			(end -0.7874 -0.4064)
			(stroke
				(width 0.1524)
				(type default)
			)
			(layer "B.SilkS")
		)
		(fp_line
			(start 0.7874 0.4064)
			(end 0.7874 -0.4064)
			(stroke
				(width 0.1524)
				(type default)
			)
			(layer "B.SilkS")
		)
		(fp_line
			(start -0.67945 -0.3048)
			(end -0.67945 0.3048)
			(stroke
				(width 0.1)
				(type default)
			)
			(layer "B.Fab")
		)
		(fp_line
			(start -0.67945 0.3048)
			(end -0.120396 0.3048)
			(stroke
				(width 0.1)
				(type default)
			)
			(layer "B.Fab")
		)
		(fp_line
			(start -0.12065 -0.3048)
			(end -0.67945 -0.3048)
			(stroke
				(width 0.1)
				(type default)
			)
			(layer "B.Fab")
		)
		(fp_line
			(start -0.12065 -0.2794)
			(end -0.12065 -0.3048)
			(stroke
				(width 0.1)
				(type default)
			)
			(layer "B.Fab")
		)
		(fp_line
			(start -0.120396 0.2794)
			(end 0.12065 0.2794)
			(stroke
				(width 0.1)
				(type default)
			)
			(layer "B.Fab")
		)
		(fp_line
			(start -0.120396 0.3048)
			(end -0.120396 0.2794)
			(stroke
				(width 0.1)
				(type default)
			)
			(layer "B.Fab")
		)
		(fp_line
			(start 0.12065 -0.305054)
			(end 0.12065 -0.2794)
			(stroke
				(width 0.1)
				(type default)
			)
			(layer "B.Fab")
		)
		(fp_line
			(start 0.12065 -0.2794)
			(end -0.12065 -0.2794)
			(stroke
				(width 0.1)
				(type default)
			)
			(layer "B.Fab")
		)
		(fp_line
			(start 0.12065 0.2794)
			(end 0.12065 0.3048)
			(stroke
				(width 0.1)
				(type default)
			)
			(layer "B.Fab")
		)
		(fp_line
			(start 0.12065 0.3048)
			(end 0.67945 0.3048)
			(stroke
				(width 0.1)
				(type default)
			)
			(layer "B.Fab")
		)
		(fp_line
			(start 0.67945 -0.305054)
			(end 0.12065 -0.305054)
			(stroke
				(width 0.1)
				(type default)
			)
			(layer "B.Fab")
		)
		(fp_line
			(start 0.67945 0.3048)
			(end 0.67945 -0.305054)
			(stroke
				(width 0.1)
				(type default)
			)
			(layer "B.Fab")
		)
		(pad "1" smd circle
			(at 0.40005 0 180)
			(size 0 0)
			(layers "B.Cu" "B.Mask" "B.Paste")
			(net "M_H_CPU0_ALERT_N")
		)
		(pad "2" smd circle
			(at -0.40005 0 180)
			(size 0 0)
			(layers "B.Cu" "B.Mask" "B.Paste")
			(net "M_H_CPU0_ALERT_R_N")
		)
	)
	(footprint ""
		(layer "B.Cu")
		(at 208.748376 -120.944386 180)
		(property "Reference" "R757"
			(at 0 0 0)
			(layer "B.SilkS")
			(hide yes)
			(effects
				(font
					(size 1.27 1.27)
				)
				(justify mirror)
			)
		)
		(property "Value" ""
			(at 0 0 0)
			(layer "B.Fab")
			(effects
				(font
					(size 1.27 1.27)
				)
				(justify mirror)
			)
		)
		(duplicate_pad_numbers_are_jumpers no)
		(fp_line
			(start 0.7874 0.4064)
			(end 0.7874 -0.4064)
			(stroke
				(width 0.1524)
				(type default)
			)
			(layer "B.SilkS")
		)
		(fp_line
			(start 0.7874 -0.4064)
			(end -0.7874 -0.4064)
			(stroke
				(width 0.1524)
				(type default)
			)
			(layer "B.SilkS")
		)
		(fp_line
			(start -0.7874 0.4064)
			(end 0.7874 0.4064)
			(stroke
				(width 0.1524)
				(type default)
			)
			(layer "B.SilkS")
		)
		(fp_line
			(start -0.7874 -0.4064)
			(end -0.7874 0.4064)
			(stroke
				(width 0.1524)
				(type default)
			)
			(layer "B.SilkS")
		)
		(fp_line
			(start 0.67945 0.3048)
			(end 0.67945 -0.305054)
			(stroke
				(width 0.1)
				(type default)
			)
			(layer "B.Fab")
		)
		(fp_line
			(start 0.67945 -0.305054)
			(end 0.12065 -0.305054)
			(stroke
				(width 0.1)
				(type default)
			)
			(layer "B.Fab")
		)
		(fp_line
			(start 0.12065 0.3048)
			(end 0.67945 0.3048)
			(stroke
				(width 0.1)
				(type default)
			)
			(layer "B.Fab")
		)
		(fp_line
			(start 0.12065 0.2794)
			(end 0.12065 0.3048)
			(stroke
				(width 0.1)
				(type default)
			)
			(layer "B.Fab")
		)
		(fp_line
			(start 0.12065 -0.2794)
			(end -0.12065 -0.2794)
			(stroke
				(width 0.1)
				(type default)
			)
			(layer "B.Fab")
		)
		(fp_line
			(start 0.12065 -0.305054)
			(end 0.12065 -0.2794)
			(stroke
				(width 0.1)
				(type default)
			)
			(layer "B.Fab")
		)
		(fp_line
			(start -0.120396 0.3048)
			(end -0.120396 0.2794)
			(stroke
				(width 0.1)
				(type default)
			)
			(layer "B.Fab")
		)
		(fp_line
			(start -0.120396 0.2794)
			(end 0.12065 0.2794)
			(stroke
				(width 0.1)
				(type default)
			)
			(layer "B.Fab")
		)
		(fp_line
			(start -0.12065 -0.2794)
			(end -0.12065 -0.3048)
			(stroke
				(width 0.1)
				(type default)
			)
			(layer "B.Fab")
		)
		(fp_line
			(start -0.12065 -0.3048)
			(end -0.67945 -0.3048)
			(stroke
				(width 0.1)
				(type default)
			)
			(layer "B.Fab")
		)
		(fp_line
			(start -0.67945 0.3048)
			(end -0.120396 0.3048)
			(stroke
				(width 0.1)
				(type default)
			)
			(layer "B.Fab")
		)
		(fp_line
			(start -0.67945 -0.3048)
			(end -0.67945 0.3048)
			(stroke
				(width 0.1)
				(type default)
			)
			(layer "B.Fab")
		)
		(pad "1" smd circle
			(at 0.40005 0)
			(size 0 0)
			(layers "B.Cu" "B.Mask" "B.Paste")
			(net "E1S_0_P3V3_EN")
		)
		(pad "2" smd circle
			(at -0.40005 0)
			(size 0 0)
			(layers "B.Cu" "B.Mask" "B.Paste")
			(net "P3V3_AUX")
		)
	)
	(footprint ""
		(layer "B.Cu")
		(at 108.501434 -246.402352)
		(property "Reference" "C2304"
			(at 0 0 0)
			(layer "B.SilkS")
			(hide yes)
			(effects
				(font
					(size 1.27 1.27)
				)
				(justify mirror)
			)
		)
		(property "Value" ""
			(at 0 0 0)
			(layer "B.Fab")
			(effects
				(font
					(size 1.27 1.27)
				)
				(justify mirror)
			)
		)
		(duplicate_pad_numbers_are_jumpers no)
		(fp_line
			(start -0.7874 -0.4064)
			(end -0.7874 0.4064)
			(stroke
				(width 0.1524)
				(type default)
			)
			(layer "B.SilkS")
		)
		(fp_line
			(start -0.7874 0.4064)
			(end 0.7874 0.4064)
			(stroke
				(width 0.1524)
				(type default)
			)
			(layer "B.SilkS")
		)
		(fp_line
			(start 0.7874 -0.4064)
			(end -0.7874 -0.4064)
			(stroke
				(width 0.1524)
				(type default)
			)
			(layer "B.SilkS")
		)
		(fp_line
			(start 0.7874 0.4064)
			(end 0.7874 -0.4064)
			(stroke
				(width 0.1524)
				(type default)
			)
			(layer "B.SilkS")
		)
		(fp_line
			(start -0.67945 -0.3048)
			(end -0.67945 0.3048)
			(stroke
				(width 0.1)
				(type default)
			)
			(layer "B.Fab")
		)
		(fp_line
			(start -0.67945 0.3048)
			(end -0.120396 0.3048)
			(stroke
				(width 0.1)
				(type default)
			)
			(layer "B.Fab")
		)
		(fp_line
			(start -0.12065 -0.3048)
			(end -0.67945 -0.3048)
			(stroke
				(width 0.1)
				(type default)
			)
			(layer "B.Fab")
		)
		(fp_line
			(start -0.12065 -0.2794)
			(end -0.12065 -0.3048)
			(stroke
				(width 0.1)
				(type default)
			)
			(layer "B.Fab")
		)
		(fp_line
			(start -0.120396 0.2794)
			(end 0.12065 0.2794)
			(stroke
				(width 0.1)
				(type default)
			)
			(layer "B.Fab")
		)
		(fp_line
			(start -0.120396 0.3048)
			(end -0.120396 0.2794)
			(stroke
				(width 0.1)
				(type default)
			)
			(layer "B.Fab")
		)
		(fp_line
			(start 0.12065 -0.305054)
			(end 0.12065 -0.2794)
			(stroke
				(width 0.1)
				(type default)
			)
			(layer "B.Fab")
		)
		(fp_line
			(start 0.12065 -0.2794)
			(end -0.12065 -0.2794)
			(stroke
				(width 0.1)
				(type default)
			)
			(layer "B.Fab")
		)
		(fp_line
			(start 0.12065 0.2794)
			(end 0.12065 0.3048)
			(stroke
				(width 0.1)
				(type default)
			)
			(layer "B.Fab")
		)
		(fp_line
			(start 0.12065 0.3048)
			(end 0.67945 0.3048)
			(stroke
				(width 0.1)
				(type default)
			)
			(layer "B.Fab")
		)
		(fp_line
			(start 0.67945 -0.305054)
			(end 0.12065 -0.305054)
			(stroke
				(width 0.1)
				(type default)
			)
			(layer "B.Fab")
		)
		(fp_line
			(start 0.67945 0.3048)
			(end 0.67945 -0.305054)
			(stroke
				(width 0.1)
				(type default)
			)
			(layer "B.Fab")
		)
		(pad "1" smd circle
			(at 0.40005 0 180)
			(size 0 0)
			(layers "B.Cu" "B.Mask" "B.Paste")
			(net "PVDDCR_CPU0_P1")
		)
		(pad "2" smd circle
			(at -0.40005 0 180)
			(size 0 0)
			(layers "B.Cu" "B.Mask" "B.Paste")
			(net "GND")
		)
	)
	(footprint ""
		(layer "B.Cu")
		(at 188.712094 -115.022376)
		(property "Reference" "C361"
			(at 0 0 0)
			(layer "B.SilkS")
			(hide yes)
			(effects
				(font
					(size 1.27 1.27)
				)
				(justify mirror)
			)
		)
		(property "Value" ""
			(at 0 0 0)
			(layer "B.Fab")
			(effects
				(font
					(size 1.27 1.27)
				)
				(justify mirror)
			)
		)
		(duplicate_pad_numbers_are_jumpers no)
		(fp_line
			(start -0.69215 -0.2921)
			(end -0.69215 0.2921)
			(stroke
				(width 0.1524)
				(type default)
			)
			(layer "B.SilkS")
		)
		(fp_line
			(start -0.69215 0.2921)
			(end 0.69215 0.2921)
			(stroke
				(width 0.1524)
				(type default)
			)
			(layer "B.SilkS")
		)
		(fp_line
			(start 0.69215 -0.2921)
			(end -0.69215 -0.2921)
			(stroke
				(width 0.1524)
				(type default)
			)
			(layer "B.SilkS")
		)
		(fp_line
			(start 0.69215 0.2921)
			(end 0.69215 -0.2921)
			(stroke
				(width 0.1524)
				(type default)
			)
			(layer "B.SilkS")
		)
		(fp_line
			(start -0.51435 -0.2794)
			(end -0.51435 0.2794)
			(stroke
				(width 0.1)
				(type default)
			)
			(layer "B.Fab")
		)
		(fp_line
			(start -0.51435 0.2794)
			(end 0.51435 0.2794)
			(stroke
				(width 0.1)
				(type default)
			)
			(layer "B.Fab")
		)
		(fp_line
			(start 0.51435 -0.2794)
			(end -0.51435 -0.2794)
			(stroke
				(width 0.1)
				(type default)
			)
			(layer "B.Fab")
		)
		(fp_line
			(start 0.51435 0.2794)
			(end 0.51435 -0.2794)
			(stroke
				(width 0.1)
				(type default)
			)
			(layer "B.Fab")
		)
		(pad "1" smd circle
			(at 0.40005 0 180)
			(size 0 0)
			(layers "B.Cu" "B.Mask" "B.Paste")
			(net "P3V3_AUX")
		)
		(pad "2" smd circle
			(at -0.40005 0 180)
			(size 0 0)
			(layers "B.Cu" "B.Mask" "B.Paste")
			(net "GND")
		)
		(zone
			(layer "B.Cu")
			(hatch none 0.5)
			(connect_pads
				(clearance 0)
			)
			(min_thickness 0.25)
			(keepout
				(tracks not_allowed)
				(vias allowed)
				(pads allowed)
				(copperpour not_allowed)
				(footprints allowed)
			)
			(placement
				(enabled no)
				(sheetname "")
			)
			(fill
				(thermal_gap 0.5)
				(thermal_bridge_width 0.5)
				(island_removal_mode 0)
			)
			(polygon
				(pts
					(xy 188.521594 -114.934746) (xy 188.521594 -115.110006) (xy 188.611764 -115.168426) (xy 188.811154 -115.168426)
					(xy 188.902594 -115.11026) (xy 188.902594 -114.934746) (xy 188.811154 -114.87658) (xy 188.611764 -114.87658)
				)
			)
		)
	)
	(footprint ""
		(layer "B.Cu")
		(at 403.377146 -354.439728 -90)
		(property "Reference" "R6126"
			(at 0 0 90)
			(layer "B.SilkS")
			(hide yes)
			(effects
				(font
					(size 1.27 1.27)
				)
				(justify mirror)
			)
		)
		(property "Value" ""
			(at 0 0 90)
			(layer "B.Fab")
			(effects
				(font
					(size 1.27 1.27)
				)
				(justify mirror)
			)
		)
		(duplicate_pad_numbers_are_jumpers no)
		(fp_line
			(start -0.7874 0.4064)
			(end 0.7874 0.4064)
			(stroke
				(width 0.1524)
				(type default)
			)
			(layer "B.SilkS")
		)
		(fp_line
			(start 0.7874 0.4064)
			(end 0.7874 -0.4064)
			(stroke
				(width 0.1524)
				(type default)
			)
			(layer "B.SilkS")
		)
		(fp_line
			(start -0.7874 -0.4064)
			(end -0.7874 0.4064)
			(stroke
				(width 0.1524)
				(type default)
			)
			(layer "B.SilkS")
		)
		(fp_line
			(start 0.7874 -0.4064)
			(end -0.7874 -0.4064)
			(stroke
				(width 0.1524)
				(type default)
			)
			(layer "B.SilkS")
		)
		(fp_line
			(start -0.67945 0.3048)
			(end -0.120396 0.3048)
			(stroke
				(width 0.1)
				(type default)
			)
			(layer "B.Fab")
		)
		(fp_line
			(start -0.120396 0.3048)
			(end -0.120396 0.2794)
			(stroke
				(width 0.1)
				(type default)
			)
			(layer "B.Fab")
		)
		(fp_line
			(start 0.12065 0.3048)
			(end 0.67945 0.3048)
			(stroke
				(width 0.1)
				(type default)
			)
			(layer "B.Fab")
		)
		(fp_line
			(start 0.67945 0.3048)
			(end 0.67945 -0.305054)
			(stroke
				(width 0.1)
				(type default)
			)
			(layer "B.Fab")
		)
		(fp_line
			(start -0.120396 0.2794)
			(end 0.12065 0.2794)
			(stroke
				(width 0.1)
				(type default)
			)
			(layer "B.Fab")
		)
		(fp_line
			(start 0.12065 0.2794)
			(end 0.12065 0.3048)
			(stroke
				(width 0.1)
				(type default)
			)
			(layer "B.Fab")
		)
		(fp_line
			(start -0.12065 -0.2794)
			(end -0.12065 -0.3048)
			(stroke
				(width 0.1)
				(type default)
			)
			(layer "B.Fab")
		)
		(fp_line
			(start 0.12065 -0.2794)
			(end -0.12065 -0.2794)
			(stroke
				(width 0.1)
				(type default)
			)
			(layer "B.Fab")
		)
		(fp_line
			(start -0.67945 -0.3048)
			(end -0.67945 0.3048)
			(stroke
				(width 0.1)
				(type default)
			)
			(layer "B.Fab")
		)
		(fp_line
			(start -0.12065 -0.3048)
			(end -0.67945 -0.3048)
			(stroke
				(width 0.1)
				(type default)
			)
			(layer "B.Fab")
		)
		(fp_line
			(start 0.12065 -0.305054)
			(end 0.12065 -0.2794)
			(stroke
				(width 0.1)
				(type default)
			)
			(layer "B.Fab")
		)
		(fp_line
			(start 0.67945 -0.305054)
			(end 0.12065 -0.305054)
			(stroke
				(width 0.1)
				(type default)
			)
			(layer "B.Fab")
		)
		(pad "1" smd circle
			(at 0.40005 0 90)
			(size 0 0)
			(layers "B.Cu" "B.Mask" "B.Paste")
			(net "FM_BOARD_SKU_ID3")
		)
		(pad "2" smd circle
			(at -0.40005 0 90)
			(size 0 0)
			(layers "B.Cu" "B.Mask" "B.Paste")
			(net "GND")
		)
	)
	(footprint ""
		(layer "B.Cu")
		(at 300.82109 -244.08511 180)
		(property "Reference" "R376"
			(at 0 0 0)
			(layer "B.SilkS")
			(hide yes)
			(effects
				(font
					(size 1.27 1.27)
				)
				(justify mirror)
			)
		)
		(property "Value" ""
			(at 0 0 0)
			(layer "B.Fab")
			(effects
				(font
					(size 1.27 1.27)
				)
				(justify mirror)
			)
		)
		(duplicate_pad_numbers_are_jumpers no)
		(fp_line
			(start 0.7874 0.4064)
			(end 0.7874 -0.4064)
			(stroke
				(width 0.1524)
				(type default)
			)
			(layer "B.SilkS")
		)
		(fp_line
			(start 0.7874 -0.4064)
			(end -0.7874 -0.4064)
			(stroke
				(width 0.1524)
				(type default)
			)
			(layer "B.SilkS")
		)
		(fp_line
			(start -0.7874 0.4064)
			(end 0.7874 0.4064)
			(stroke
				(width 0.1524)
				(type default)
			)
			(layer "B.SilkS")
		)
		(fp_line
			(start -0.7874 -0.4064)
			(end -0.7874 0.4064)
			(stroke
				(width 0.1524)
				(type default)
			)
			(layer "B.SilkS")
		)
		(fp_line
			(start 0.67945 0.3048)
			(end 0.67945 -0.305054)
			(stroke
				(width 0.1)
				(type default)
			)
			(layer "B.Fab")
		)
		(fp_line
			(start 0.67945 -0.305054)
			(end 0.12065 -0.305054)
			(stroke
				(width 0.1)
				(type default)
			)
			(layer "B.Fab")
		)
		(fp_line
			(start 0.12065 0.3048)
			(end 0.67945 0.3048)
			(stroke
				(width 0.1)
				(type default)
			)
			(layer "B.Fab")
		)
		(fp_line
			(start 0.12065 0.2794)
			(end 0.12065 0.3048)
			(stroke
				(width 0.1)
				(type default)
			)
			(layer "B.Fab")
		)
		(fp_line
			(start 0.12065 -0.2794)
			(end -0.12065 -0.2794)
			(stroke
				(width 0.1)
				(type default)
			)
			(layer "B.Fab")
		)
		(fp_line
			(start 0.12065 -0.305054)
			(end 0.12065 -0.2794)
			(stroke
				(width 0.1)
				(type default)
			)
			(layer "B.Fab")
		)
		(fp_line
			(start -0.120396 0.3048)
			(end -0.120396 0.2794)
			(stroke
				(width 0.1)
				(type default)
			)
			(layer "B.Fab")
		)
		(fp_line
			(start -0.120396 0.2794)
			(end 0.12065 0.2794)
			(stroke
				(width 0.1)
				(type default)
			)
			(layer "B.Fab")
		)
		(fp_line
			(start -0.12065 -0.2794)
			(end -0.12065 -0.3048)
			(stroke
				(width 0.1)
				(type default)
			)
			(layer "B.Fab")
		)
		(fp_line
			(start -0.12065 -0.3048)
			(end -0.67945 -0.3048)
			(stroke
				(width 0.1)
				(type default)
			)
			(layer "B.Fab")
		)
		(fp_line
			(start -0.67945 0.3048)
			(end -0.120396 0.3048)
			(stroke
				(width 0.1)
				(type default)
			)
			(layer "B.Fab")
		)
		(fp_line
			(start -0.67945 -0.3048)
			(end -0.67945 0.3048)
			(stroke
				(width 0.1)
				(type default)
			)
			(layer "B.Fab")
		)
		(pad "1" smd circle
			(at 0.40005 0)
			(size 0 0)
			(layers "B.Cu" "B.Mask" "B.Paste")
			(net "M_B_CPU0_ALERT_N")
		)
		(pad "2" smd circle
			(at -0.40005 0)
			(size 0 0)
			(layers "B.Cu" "B.Mask" "B.Paste")
			(net "M_B_CPU0_ALERT_R_N")
		)
	)
	(footprint ""
		(layer "B.Cu")
		(at 361.595924 -395.127988 -90)
		(property "Reference" "C596"
			(at 0 0 90)
			(layer "B.SilkS")
			(hide yes)
			(effects
				(font
					(size 1.27 1.27)
				)
				(justify mirror)
			)
		)
		(property "Value" ""
			(at 0 0 90)
			(layer "B.Fab")
			(effects
				(font
					(size 1.27 1.27)
				)
				(justify mirror)
			)
		)
		(duplicate_pad_numbers_are_jumpers no)
		(fp_line
			(start -0.7874 0.4064)
			(end 0.7874 0.4064)
			(stroke
				(width 0.1524)
				(type default)
			)
			(layer "B.SilkS")
		)
		(fp_line
			(start 0.7874 0.4064)
			(end 0.7874 -0.4064)
			(stroke
				(width 0.1524)
				(type default)
			)
			(layer "B.SilkS")
		)
		(fp_line
			(start -0.7874 -0.4064)
			(end -0.7874 0.4064)
			(stroke
				(width 0.1524)
				(type default)
			)
			(layer "B.SilkS")
		)
		(fp_line
			(start 0.7874 -0.4064)
			(end -0.7874 -0.4064)
			(stroke
				(width 0.1524)
				(type default)
			)
			(layer "B.SilkS")
		)
		(fp_line
			(start -0.67945 0.3048)
			(end -0.120396 0.3048)
			(stroke
				(width 0.1)
				(type default)
			)
			(layer "B.Fab")
		)
		(fp_line
			(start -0.120396 0.3048)
			(end -0.120396 0.2794)
			(stroke
				(width 0.1)
				(type default)
			)
			(layer "B.Fab")
		)
		(fp_line
			(start 0.12065 0.3048)
			(end 0.67945 0.3048)
			(stroke
				(width 0.1)
				(type default)
			)
			(layer "B.Fab")
		)
		(fp_line
			(start 0.67945 0.3048)
			(end 0.67945 -0.305054)
			(stroke
				(width 0.1)
				(type default)
			)
			(layer "B.Fab")
		)
		(fp_line
			(start -0.120396 0.2794)
			(end 0.12065 0.2794)
			(stroke
				(width 0.1)
				(type default)
			)
			(layer "B.Fab")
		)
		(fp_line
			(start 0.12065 0.2794)
			(end 0.12065 0.3048)
			(stroke
				(width 0.1)
				(type default)
			)
			(layer "B.Fab")
		)
		(fp_line
			(start -0.12065 -0.2794)
			(end -0.12065 -0.3048)
			(stroke
				(width 0.1)
				(type default)
			)
			(layer "B.Fab")
		)
		(fp_line
			(start 0.12065 -0.2794)
			(end -0.12065 -0.2794)
			(stroke
				(width 0.1)
				(type default)
			)
			(layer "B.Fab")
		)
		(fp_line
			(start -0.67945 -0.3048)
			(end -0.67945 0.3048)
			(stroke
				(width 0.1)
				(type default)
			)
			(layer "B.Fab")
		)
		(fp_line
			(start -0.12065 -0.3048)
			(end -0.67945 -0.3048)
			(stroke
				(width 0.1)
				(type default)
			)
			(layer "B.Fab")
		)
		(fp_line
			(start 0.12065 -0.305054)
			(end 0.12065 -0.2794)
			(stroke
				(width 0.1)
				(type default)
			)
			(layer "B.Fab")
		)
		(fp_line
			(start 0.67945 -0.305054)
			(end 0.12065 -0.305054)
			(stroke
				(width 0.1)
				(type default)
			)
			(layer "B.Fab")
		)
		(pad "1" smd circle
			(at 0.40005 0 90)
			(size 0 0)
			(layers "B.Cu" "B.Mask" "B.Paste")
			(net "P1V8_CPU0_RT_1D")
		)
		(pad "2" smd circle
			(at -0.40005 0 90)
			(size 0 0)
			(layers "B.Cu" "B.Mask" "B.Paste")
			(net "GND")
		)
	)
	(footprint ""
		(layer "B.Cu")
		(at 167.132 -118.328948 180)
		(property "Reference" "R890"
			(at 0 0 0)
			(layer "B.SilkS")
			(hide yes)
			(effects
				(font
					(size 1.27 1.27)
				)
				(justify mirror)
			)
		)
		(property "Value" ""
			(at 0 0 0)
			(layer "B.Fab")
			(effects
				(font
					(size 1.27 1.27)
				)
				(justify mirror)
			)
		)
		(duplicate_pad_numbers_are_jumpers no)
		(fp_line
			(start 0.7874 0.4064)
			(end 0.7874 -0.4064)
			(stroke
				(width 0.1524)
				(type default)
			)
			(layer "B.SilkS")
		)
		(fp_line
			(start 0.7874 -0.4064)
			(end -0.7874 -0.4064)
			(stroke
				(width 0.1524)
				(type default)
			)
			(layer "B.SilkS")
		)
		(fp_line
			(start -0.7874 0.4064)
			(end 0.7874 0.4064)
			(stroke
				(width 0.1524)
				(type default)
			)
			(layer "B.SilkS")
		)
		(fp_line
			(start -0.7874 -0.4064)
			(end -0.7874 0.4064)
			(stroke
				(width 0.1524)
				(type default)
			)
			(layer "B.SilkS")
		)
		(fp_line
			(start 0.67945 0.3048)
			(end 0.67945 -0.305054)
			(stroke
				(width 0.1)
				(type default)
			)
			(layer "B.Fab")
		)
		(fp_line
			(start 0.67945 -0.305054)
			(end 0.12065 -0.305054)
			(stroke
				(width 0.1)
				(type default)
			)
			(layer "B.Fab")
		)
		(fp_line
			(start 0.12065 0.3048)
			(end 0.67945 0.3048)
			(stroke
				(width 0.1)
				(type default)
			)
			(layer "B.Fab")
		)
		(fp_line
			(start 0.12065 0.2794)
			(end 0.12065 0.3048)
			(stroke
				(width 0.1)
				(type default)
			)
			(layer "B.Fab")
		)
		(fp_line
			(start 0.12065 -0.2794)
			(end -0.12065 -0.2794)
			(stroke
				(width 0.1)
				(type default)
			)
			(layer "B.Fab")
		)
		(fp_line
			(start 0.12065 -0.305054)
			(end 0.12065 -0.2794)
			(stroke
				(width 0.1)
				(type default)
			)
			(layer "B.Fab")
		)
		(fp_line
			(start -0.120396 0.3048)
			(end -0.120396 0.2794)
			(stroke
				(width 0.1)
				(type default)
			)
			(layer "B.Fab")
		)
		(fp_line
			(start -0.120396 0.2794)
			(end 0.12065 0.2794)
			(stroke
				(width 0.1)
				(type default)
			)
			(layer "B.Fab")
		)
		(fp_line
			(start -0.12065 -0.2794)
			(end -0.12065 -0.3048)
			(stroke
				(width 0.1)
				(type default)
			)
			(layer "B.Fab")
		)
		(fp_line
			(start -0.12065 -0.3048)
			(end -0.67945 -0.3048)
			(stroke
				(width 0.1)
				(type default)
			)
			(layer "B.Fab")
		)
		(fp_line
			(start -0.67945 0.3048)
			(end -0.120396 0.3048)
			(stroke
				(width 0.1)
				(type default)
			)
			(layer "B.Fab")
		)
		(fp_line
			(start -0.67945 -0.3048)
			(end -0.67945 0.3048)
			(stroke
				(width 0.1)
				(type default)
			)
			(layer "B.Fab")
		)
		(pad "1" smd circle
			(at 0.40005 0)
			(size 0 0)
			(layers "B.Cu" "B.Mask" "B.Paste")
			(net "P3V3_AUX")
		)
		(pad "2" smd circle
			(at -0.40005 0)
			(size 0 0)
			(layers "B.Cu" "B.Mask" "B.Paste")
			(net "SCM_SPARE_1")
		)
	)
	(footprint ""
		(layer "B.Cu")
		(at 326.667876 -66.708782 90)
		(property "Reference" "R3089"
			(at 0 0 90)
			(layer "B.SilkS")
			(hide yes)
			(effects
				(font
					(size 1.27 1.27)
				)
				(justify mirror)
			)
		)
		(property "Value" ""
			(at 0 0 90)
			(layer "B.Fab")
			(effects
				(font
					(size 1.27 1.27)
				)
				(justify mirror)
			)
		)
		(duplicate_pad_numbers_are_jumpers no)
		(fp_line
			(start 0.7874 -0.4064)
			(end -0.7874 -0.4064)
			(stroke
				(width 0.1524)
				(type default)
			)
			(layer "B.SilkS")
		)
		(fp_line
			(start -0.7874 -0.4064)
			(end -0.7874 0.4064)
			(stroke
				(width 0.1524)
				(type default)
			)
			(layer "B.SilkS")
		)
		(fp_line
			(start 0.7874 0.4064)
			(end 0.7874 -0.4064)
			(stroke
				(width 0.1524)
				(type default)
			)
			(layer "B.SilkS")
		)
		(fp_line
			(start -0.7874 0.4064)
			(end 0.7874 0.4064)
			(stroke
				(width 0.1524)
				(type default)
			)
			(layer "B.SilkS")
		)
		(fp_line
			(start 0.67945 -0.305054)
			(end 0.12065 -0.305054)
			(stroke
				(width 0.1)
				(type default)
			)
			(layer "B.Fab")
		)
		(fp_line
			(start 0.12065 -0.305054)
			(end 0.12065 -0.2794)
			(stroke
				(width 0.1)
				(type default)
			)
			(layer "B.Fab")
		)
		(fp_line
			(start -0.12065 -0.3048)
			(end -0.67945 -0.3048)
			(stroke
				(width 0.1)
				(type default)
			)
			(layer "B.Fab")
		)
		(fp_line
			(start -0.67945 -0.3048)
			(end -0.67945 0.3048)
			(stroke
				(width 0.1)
				(type default)
			)
			(layer "B.Fab")
		)
		(fp_line
			(start 0.12065 -0.2794)
			(end -0.12065 -0.2794)
			(stroke
				(width 0.1)
				(type default)
			)
			(layer "B.Fab")
		)
		(fp_line
			(start -0.12065 -0.2794)
			(end -0.12065 -0.3048)
			(stroke
				(width 0.1)
				(type default)
			)
			(layer "B.Fab")
		)
		(fp_line
			(start 0.12065 0.2794)
			(end 0.12065 0.3048)
			(stroke
				(width 0.1)
				(type default)
			)
			(layer "B.Fab")
		)
		(fp_line
			(start -0.120396 0.2794)
			(end 0.12065 0.2794)
			(stroke
				(width 0.1)
				(type default)
			)
			(layer "B.Fab")
		)
		(fp_line
			(start 0.67945 0.3048)
			(end 0.67945 -0.305054)
			(stroke
				(width 0.1)
				(type default)
			)
			(layer "B.Fab")
		)
		(fp_line
			(start 0.12065 0.3048)
			(end 0.67945 0.3048)
			(stroke
				(width 0.1)
				(type default)
			)
			(layer "B.Fab")
		)
		(fp_line
			(start -0.120396 0.3048)
			(end -0.120396 0.2794)
			(stroke
				(width 0.1)
				(type default)
			)
			(layer "B.Fab")
		)
		(fp_line
			(start -0.67945 0.3048)
			(end -0.120396 0.3048)
			(stroke
				(width 0.1)
				(type default)
			)
			(layer "B.Fab")
		)
		(pad "1" smd circle
			(at 0.40005 0 270)
			(size 0 0)
			(layers "B.Cu" "B.Mask" "B.Paste")
			(net "LED_PWRGD_PVDDCR_SOC_P0_R")
		)
		(pad "2" smd circle
			(at -0.40005 0 270)
			(size 0 0)
			(layers "B.Cu" "B.Mask" "B.Paste")
			(net "P3V3_AUX")
		)
	)
	(footprint ""
		(layer "B.Cu")
		(at 192.511426 -355.078284 -90)
		(property "Reference" "PC518_2"
			(at 0 0 90)
			(layer "B.SilkS")
			(hide yes)
			(effects
				(font
					(size 1.27 1.27)
				)
				(justify mirror)
			)
		)
		(property "Value" ""
			(at 0 0 90)
			(layer "B.Fab")
			(effects
				(font
					(size 1.27 1.27)
				)
				(justify mirror)
			)
		)
		(duplicate_pad_numbers_are_jumpers no)
		(fp_line
			(start -1.524 0.762)
			(end 1.524 0.762)
			(stroke
				(width 0.1524)
				(type default)
			)
			(layer "B.SilkS")
		)
		(fp_line
			(start 1.524 0.762)
			(end 1.524 -0.762)
			(stroke
				(width 0.1524)
				(type default)
			)
			(layer "B.SilkS")
		)
		(fp_line
			(start -1.524 -0.762)
			(end -1.524 0.762)
			(stroke
				(width 0.1524)
				(type default)
			)
			(layer "B.SilkS")
		)
		(fp_line
			(start 1.524 -0.762)
			(end -1.524 -0.762)
			(stroke
				(width 0.1524)
				(type default)
			)
			(layer "B.SilkS")
		)
		(fp_line
			(start -1.1049 0.724916)
			(end -1.1049 -0.724916)
			(stroke
				(width 0.1)
				(type default)
			)
			(layer "B.Fab")
		)
		(fp_line
			(start 1.1049 0.724916)
			(end -1.1049 0.724916)
			(stroke
				(width 0.1)
				(type default)
			)
			(layer "B.Fab")
		)
		(fp_line
			(start -1.1049 -0.724916)
			(end 1.1049 -0.724916)
			(stroke
				(width 0.1)
				(type default)
			)
			(layer "B.Fab")
		)
		(fp_line
			(start 1.1049 -0.724916)
			(end 1.1049 0.724916)
			(stroke
				(width 0.1)
				(type default)
			)
			(layer "B.Fab")
		)
		(pad "1" smd rect
			(at 0.889 0 270)
			(size 1.016 1.27)
			(layers "B.Cu" "B.Mask" "B.Paste")
			(net "SW_P12V_AUX_PVDD11_S3_P1_FLT")
		)
		(pad "2" smd rect
			(at -0.889 0 270)
			(size 1.016 1.27)
			(layers "B.Cu" "B.Mask" "B.Paste")
			(net "GND")
		)
	)
	(footprint ""
		(layer "B.Cu")
		(at 377.678442 -395.148562 90)
		(property "Reference" "C1001"
			(at 0 0 90)
			(layer "B.SilkS")
			(hide yes)
			(effects
				(font
					(size 1.27 1.27)
				)
				(justify mirror)
			)
		)
		(property "Value" ""
			(at 0 0 90)
			(layer "B.Fab")
			(effects
				(font
					(size 1.27 1.27)
				)
				(justify mirror)
			)
		)
		(duplicate_pad_numbers_are_jumpers no)
		(fp_line
			(start 0.299974 -0.150114)
			(end -0.299974 -0.150114)
			(stroke
				(width 0.1)
				(type default)
			)
			(layer "B.Fab")
		)
		(fp_line
			(start -0.299974 -0.150114)
			(end -0.299974 0.150114)
			(stroke
				(width 0.1)
				(type default)
			)
			(layer "B.Fab")
		)
		(fp_line
			(start 0.299974 0.150114)
			(end 0.299974 -0.150114)
			(stroke
				(width 0.1)
				(type default)
			)
			(layer "B.Fab")
		)
		(fp_line
			(start -0.299974 0.150114)
			(end 0.299974 0.150114)
			(stroke
				(width 0.1)
				(type default)
			)
			(layer "B.Fab")
		)
		(pad "1" smd rect
			(at 0.2667 0 270)
			(size 0.3048 0.381)
			(layers "B.Cu" "B.Mask" "B.Paste")
			(net "P1V8_CPU0_RT3_1A")
		)
		(pad "2" smd rect
			(at -0.2667 0 270)
			(size 0.3048 0.381)
			(layers "B.Cu" "B.Mask" "B.Paste")
			(net "GND")
		)
	)
	(footprint ""
		(layer "B.Cu")
		(at 197.269608 -120.737376 180)
		(property "Reference" "R4143"
			(at 0 0 0)
			(layer "B.SilkS")
			(hide yes)
			(effects
				(font
					(size 1.27 1.27)
				)
				(justify mirror)
			)
		)
		(property "Value" ""
			(at 0 0 0)
			(layer "B.Fab")
			(effects
				(font
					(size 1.27 1.27)
				)
				(justify mirror)
			)
		)
		(duplicate_pad_numbers_are_jumpers no)
		(fp_line
			(start 0.7874 0.4064)
			(end 0.7874 -0.4064)
			(stroke
				(width 0.1524)
				(type default)
			)
			(layer "B.SilkS")
		)
		(fp_line
			(start 0.7874 -0.4064)
			(end -0.7874 -0.4064)
			(stroke
				(width 0.1524)
				(type default)
			)
			(layer "B.SilkS")
		)
		(fp_line
			(start -0.7874 0.4064)
			(end 0.7874 0.4064)
			(stroke
				(width 0.1524)
				(type default)
			)
			(layer "B.SilkS")
		)
		(fp_line
			(start -0.7874 -0.4064)
			(end -0.7874 0.4064)
			(stroke
				(width 0.1524)
				(type default)
			)
			(layer "B.SilkS")
		)
		(fp_line
			(start 0.67945 0.3048)
			(end 0.67945 -0.305054)
			(stroke
				(width 0.1)
				(type default)
			)
			(layer "B.Fab")
		)
		(fp_line
			(start 0.67945 -0.305054)
			(end 0.12065 -0.305054)
			(stroke
				(width 0.1)
				(type default)
			)
			(layer "B.Fab")
		)
		(fp_line
			(start 0.12065 0.3048)
			(end 0.67945 0.3048)
			(stroke
				(width 0.1)
				(type default)
			)
			(layer "B.Fab")
		)
		(fp_line
			(start 0.12065 0.2794)
			(end 0.12065 0.3048)
			(stroke
				(width 0.1)
				(type default)
			)
			(layer "B.Fab")
		)
		(fp_line
			(start 0.12065 -0.2794)
			(end -0.12065 -0.2794)
			(stroke
				(width 0.1)
				(type default)
			)
			(layer "B.Fab")
		)
		(fp_line
			(start 0.12065 -0.305054)
			(end 0.12065 -0.2794)
			(stroke
				(width 0.1)
				(type default)
			)
			(layer "B.Fab")
		)
		(fp_line
			(start -0.120396 0.3048)
			(end -0.120396 0.2794)
			(stroke
				(width 0.1)
				(type default)
			)
			(layer "B.Fab")
		)
		(fp_line
			(start -0.120396 0.2794)
			(end 0.12065 0.2794)
			(stroke
				(width 0.1)
				(type default)
			)
			(layer "B.Fab")
		)
		(fp_line
			(start -0.12065 -0.2794)
			(end -0.12065 -0.3048)
			(stroke
				(width 0.1)
				(type default)
			)
			(layer "B.Fab")
		)
		(fp_line
			(start -0.12065 -0.3048)
			(end -0.67945 -0.3048)
			(stroke
				(width 0.1)
				(type default)
			)
			(layer "B.Fab")
		)
		(fp_line
			(start -0.67945 0.3048)
			(end -0.120396 0.3048)
			(stroke
				(width 0.1)
				(type default)
			)
			(layer "B.Fab")
		)
		(fp_line
			(start -0.67945 -0.3048)
			(end -0.67945 0.3048)
			(stroke
				(width 0.1)
				(type default)
			)
			(layer "B.Fab")
		)
		(pad "1" smd circle
			(at 0.40005 0)
			(size 0 0)
			(layers "B.Cu" "B.Mask" "B.Paste")
			(net "GPU_3V3IO_RSVD0_FFU_ISO_R")
		)
		(pad "2" smd circle
			(at -0.40005 0)
			(size 0 0)
			(layers "B.Cu" "B.Mask" "B.Paste")
			(net "GPU_3V3IO_RSVD0_FFU_ISO")
		)
	)
	(footprint ""
		(layer "B.Cu")
		(at 206.429356 -381.222504 180)
		(property "Reference" "PR2526"
			(at 0 0 0)
			(layer "B.SilkS")
			(hide yes)
			(effects
				(font
					(size 1.27 1.27)
				)
				(justify mirror)
			)
		)
		(property "Value" ""
			(at 0 0 0)
			(layer "B.Fab")
			(effects
				(font
					(size 1.27 1.27)
				)
				(justify mirror)
			)
		)
		(duplicate_pad_numbers_are_jumpers no)
		(fp_line
			(start 0.7874 0.4064)
			(end 0.7874 -0.4064)
			(stroke
				(width 0.1524)
				(type default)
			)
			(layer "B.SilkS")
		)
		(fp_line
			(start 0.7874 -0.4064)
			(end -0.7874 -0.4064)
			(stroke
				(width 0.1524)
				(type default)
			)
			(layer "B.SilkS")
		)
		(fp_line
			(start -0.7874 0.4064)
			(end 0.7874 0.4064)
			(stroke
				(width 0.1524)
				(type default)
			)
			(layer "B.SilkS")
		)
		(fp_line
			(start -0.7874 -0.4064)
			(end -0.7874 0.4064)
			(stroke
				(width 0.1524)
				(type default)
			)
			(layer "B.SilkS")
		)
		(fp_line
			(start 0.67945 0.3048)
			(end 0.67945 -0.305054)
			(stroke
				(width 0.1)
				(type default)
			)
			(layer "B.Fab")
		)
		(fp_line
			(start 0.67945 -0.305054)
			(end 0.12065 -0.305054)
			(stroke
				(width 0.1)
				(type default)
			)
			(layer "B.Fab")
		)
		(fp_line
			(start 0.12065 0.3048)
			(end 0.67945 0.3048)
			(stroke
				(width 0.1)
				(type default)
			)
			(layer "B.Fab")
		)
		(fp_line
			(start 0.12065 0.2794)
			(end 0.12065 0.3048)
			(stroke
				(width 0.1)
				(type default)
			)
			(layer "B.Fab")
		)
		(fp_line
			(start 0.12065 -0.2794)
			(end -0.12065 -0.2794)
			(stroke
				(width 0.1)
				(type default)
			)
			(layer "B.Fab")
		)
		(fp_line
			(start 0.12065 -0.305054)
			(end 0.12065 -0.2794)
			(stroke
				(width 0.1)
				(type default)
			)
			(layer "B.Fab")
		)
		(fp_line
			(start -0.120396 0.3048)
			(end -0.120396 0.2794)
			(stroke
				(width 0.1)
				(type default)
			)
			(layer "B.Fab")
		)
		(fp_line
			(start -0.120396 0.2794)
			(end 0.12065 0.2794)
			(stroke
				(width 0.1)
				(type default)
			)
			(layer "B.Fab")
		)
		(fp_line
			(start -0.12065 -0.2794)
			(end -0.12065 -0.3048)
			(stroke
				(width 0.1)
				(type default)
			)
			(layer "B.Fab")
		)
		(fp_line
			(start -0.12065 -0.3048)
			(end -0.67945 -0.3048)
			(stroke
				(width 0.1)
				(type default)
			)
			(layer "B.Fab")
		)
		(fp_line
			(start -0.67945 0.3048)
			(end -0.120396 0.3048)
			(stroke
				(width 0.1)
				(type default)
			)
			(layer "B.Fab")
		)
		(fp_line
			(start -0.67945 -0.3048)
			(end -0.67945 0.3048)
			(stroke
				(width 0.1)
				(type default)
			)
			(layer "B.Fab")
		)
		(pad "1" smd circle
			(at 0.40005 0)
			(size 0 0)
			(layers "B.Cu" "B.Mask" "B.Paste")
			(net "P12V_HSC_SENSE2_N")
		)
		(pad "2" smd circle
			(at -0.40005 0)
			(size 0 0)
			(layers "B.Cu" "B.Mask" "B.Paste")
			(net "P12V_HSC_SENSE2_R3_N")
		)
	)
	(footprint ""
		(layer "B.Cu")
		(at 189.35065 -13.60043 -90)
		(property "Reference" "R6001"
			(at 0 0 90)
			(layer "B.SilkS")
			(hide yes)
			(effects
				(font
					(size 1.27 1.27)
				)
				(justify mirror)
			)
		)
		(property "Value" ""
			(at 0 0 90)
			(layer "B.Fab")
			(effects
				(font
					(size 1.27 1.27)
				)
				(justify mirror)
			)
		)
		(duplicate_pad_numbers_are_jumpers no)
		(fp_line
			(start -0.7874 0.4064)
			(end 0.7874 0.4064)
			(stroke
				(width 0.1524)
				(type default)
			)
			(layer "B.SilkS")
		)
		(fp_line
			(start 0.7874 0.4064)
			(end 0.7874 -0.4064)
			(stroke
				(width 0.1524)
				(type default)
			)
			(layer "B.SilkS")
		)
		(fp_line
			(start -0.7874 -0.4064)
			(end -0.7874 0.4064)
			(stroke
				(width 0.1524)
				(type default)
			)
			(layer "B.SilkS")
		)
		(fp_line
			(start 0.7874 -0.4064)
			(end -0.7874 -0.4064)
			(stroke
				(width 0.1524)
				(type default)
			)
			(layer "B.SilkS")
		)
		(fp_line
			(start -0.67945 0.3048)
			(end -0.120396 0.3048)
			(stroke
				(width 0.1)
				(type default)
			)
			(layer "B.Fab")
		)
		(fp_line
			(start -0.120396 0.3048)
			(end -0.120396 0.2794)
			(stroke
				(width 0.1)
				(type default)
			)
			(layer "B.Fab")
		)
		(fp_line
			(start 0.12065 0.3048)
			(end 0.67945 0.3048)
			(stroke
				(width 0.1)
				(type default)
			)
			(layer "B.Fab")
		)
		(fp_line
			(start 0.67945 0.3048)
			(end 0.67945 -0.305054)
			(stroke
				(width 0.1)
				(type default)
			)
			(layer "B.Fab")
		)
		(fp_line
			(start -0.120396 0.2794)
			(end 0.12065 0.2794)
			(stroke
				(width 0.1)
				(type default)
			)
			(layer "B.Fab")
		)
		(fp_line
			(start 0.12065 0.2794)
			(end 0.12065 0.3048)
			(stroke
				(width 0.1)
				(type default)
			)
			(layer "B.Fab")
		)
		(fp_line
			(start -0.12065 -0.2794)
			(end -0.12065 -0.3048)
			(stroke
				(width 0.1)
				(type default)
			)
			(layer "B.Fab")
		)
		(fp_line
			(start 0.12065 -0.2794)
			(end -0.12065 -0.2794)
			(stroke
				(width 0.1)
				(type default)
			)
			(layer "B.Fab")
		)
		(fp_line
			(start -0.67945 -0.3048)
			(end -0.67945 0.3048)
			(stroke
				(width 0.1)
				(type default)
			)
			(layer "B.Fab")
		)
		(fp_line
			(start -0.12065 -0.3048)
			(end -0.67945 -0.3048)
			(stroke
				(width 0.1)
				(type default)
			)
			(layer "B.Fab")
		)
		(fp_line
			(start 0.12065 -0.305054)
			(end 0.12065 -0.2794)
			(stroke
				(width 0.1)
				(type default)
			)
			(layer "B.Fab")
		)
		(fp_line
			(start 0.67945 -0.305054)
			(end 0.12065 -0.305054)
			(stroke
				(width 0.1)
				(type default)
			)
			(layer "B.Fab")
		)
		(pad "1" smd circle
			(at 0.40005 0 90)
			(size 0 0)
			(layers "B.Cu" "B.Mask" "B.Paste")
			(net "I3C_SCM_0_SDA")
		)
		(pad "2" smd circle
			(at -0.40005 0 90)
			(size 0 0)
			(layers "B.Cu" "B.Mask" "B.Paste")
			(net "I3C_SCM_0_R_SDA")
		)
	)
	(footprint ""
		(layer "B.Cu")
		(at 189.087506 -126.833376 -90)
		(property "Reference" "R1550"
			(at 0 0 90)
			(layer "B.SilkS")
			(hide yes)
			(effects
				(font
					(size 1.27 1.27)
				)
				(justify mirror)
			)
		)
		(property "Value" ""
			(at 0 0 90)
			(layer "B.Fab")
			(effects
				(font
					(size 1.27 1.27)
				)
				(justify mirror)
			)
		)
		(duplicate_pad_numbers_are_jumpers no)
		(fp_line
			(start -0.7874 0.4064)
			(end 0.7874 0.4064)
			(stroke
				(width 0.1524)
				(type default)
			)
			(layer "B.SilkS")
		)
		(fp_line
			(start 0.7874 0.4064)
			(end 0.7874 -0.4064)
			(stroke
				(width 0.1524)
				(type default)
			)
			(layer "B.SilkS")
		)
		(fp_line
			(start -0.7874 -0.4064)
			(end -0.7874 0.4064)
			(stroke
				(width 0.1524)
				(type default)
			)
			(layer "B.SilkS")
		)
		(fp_line
			(start 0.7874 -0.4064)
			(end -0.7874 -0.4064)
			(stroke
				(width 0.1524)
				(type default)
			)
			(layer "B.SilkS")
		)
		(fp_line
			(start -0.67945 0.3048)
			(end -0.120396 0.3048)
			(stroke
				(width 0.1)
				(type default)
			)
			(layer "B.Fab")
		)
		(fp_line
			(start -0.120396 0.3048)
			(end -0.120396 0.2794)
			(stroke
				(width 0.1)
				(type default)
			)
			(layer "B.Fab")
		)
		(fp_line
			(start 0.12065 0.3048)
			(end 0.67945 0.3048)
			(stroke
				(width 0.1)
				(type default)
			)
			(layer "B.Fab")
		)
		(fp_line
			(start 0.67945 0.3048)
			(end 0.67945 -0.305054)
			(stroke
				(width 0.1)
				(type default)
			)
			(layer "B.Fab")
		)
		(fp_line
			(start -0.120396 0.2794)
			(end 0.12065 0.2794)
			(stroke
				(width 0.1)
				(type default)
			)
			(layer "B.Fab")
		)
		(fp_line
			(start 0.12065 0.2794)
			(end 0.12065 0.3048)
			(stroke
				(width 0.1)
				(type default)
			)
			(layer "B.Fab")
		)
		(fp_line
			(start -0.12065 -0.2794)
			(end -0.12065 -0.3048)
			(stroke
				(width 0.1)
				(type default)
			)
			(layer "B.Fab")
		)
		(fp_line
			(start 0.12065 -0.2794)
			(end -0.12065 -0.2794)
			(stroke
				(width 0.1)
				(type default)
			)
			(layer "B.Fab")
		)
		(fp_line
			(start -0.67945 -0.3048)
			(end -0.67945 0.3048)
			(stroke
				(width 0.1)
				(type default)
			)
			(layer "B.Fab")
		)
		(fp_line
			(start -0.12065 -0.3048)
			(end -0.67945 -0.3048)
			(stroke
				(width 0.1)
				(type default)
			)
			(layer "B.Fab")
		)
		(fp_line
			(start 0.12065 -0.305054)
			(end 0.12065 -0.2794)
			(stroke
				(width 0.1)
				(type default)
			)
			(layer "B.Fab")
		)
		(fp_line
			(start 0.67945 -0.305054)
			(end 0.12065 -0.305054)
			(stroke
				(width 0.1)
				(type default)
			)
			(layer "B.Fab")
		)
		(pad "1" smd circle
			(at 0.40005 0 90)
			(size 0 0)
			(layers "B.Cu" "B.Mask" "B.Paste")
			(net "ESPI_CPU0_R1_D1")
		)
		(pad "2" smd circle
			(at -0.40005 0 90)
			(size 0 0)
			(layers "B.Cu" "B.Mask" "B.Paste")
			(net "ESPI_CPU0_D1")
		)
	)
	(footprint ""
		(layer "B.Cu")
		(at 446.579752 -390.405874 -90)
		(property "Reference" "PC6811"
			(at -0.754126 2.995422 270)
			(unlocked yes)
			(layer "B.SilkS")
			(effects
				(font
					(size 0.7874 0.5842)
					(thickness 0.1524)
				)
				(justify left mirror)
			)
		)
		(property "Value" ""
			(at 0 0 90)
			(layer "B.Fab")
			(effects
				(font
					(size 1.27 1.27)
				)
				(justify mirror)
			)
		)
		(duplicate_pad_numbers_are_jumpers no)
		(fp_line
			(start 4.83108 2.150364)
			(end 4.447794 2.149348)
			(stroke
				(width 0.1524)
				(type default)
			)
			(layer "B.SilkS")
		)
		(fp_line
			(start -4.53898 2.15011)
			(end 4.53898 2.15011)
			(stroke
				(width 0.1524)
				(type default)
			)
			(layer "B.SilkS")
		)
		(fp_line
			(start 4.53898 2.15011)
			(end 4.53898 -2.15011)
			(stroke
				(width 0.1524)
				(type default)
			)
			(layer "B.SilkS")
		)
		(fp_line
			(start -4.53898 -2.15011)
			(end -4.53898 2.15011)
			(stroke
				(width 0.1524)
				(type default)
			)
			(layer "B.SilkS")
		)
		(fp_line
			(start 4.53898 -2.15011)
			(end -4.53898 -2.15011)
			(stroke
				(width 0.1524)
				(type default)
			)
			(layer "B.SilkS")
		)
		(fp_line
			(start 4.53898 -2.150618)
			(end 4.539742 2.152142)
			(stroke
				(width 0.1524)
				(type default)
			)
			(layer "B.SilkS")
		)
		(fp_line
			(start 4.69138 -2.150618)
			(end 4.692396 2.161032)
			(stroke
				(width 0.1524)
				(type default)
			)
			(layer "B.SilkS")
		)
		(fp_line
			(start 4.84378 -2.150618)
			(end 4.842256 2.163064)
			(stroke
				(width 0.1524)
				(type default)
			)
			(layer "B.SilkS")
		)
		(fp_line
			(start 4.84378 -2.150618)
			(end 4.53898 -2.150618)
			(stroke
				(width 0.1524)
				(type default)
			)
			(layer "B.SilkS")
		)
		(fp_line
			(start -3.64998 2.15011)
			(end 3.64998 2.15011)
			(stroke
				(width 0.1)
				(type default)
			)
			(layer "B.Fab")
		)
		(fp_line
			(start 3.64998 2.15011)
			(end 3.64998 -2.15011)
			(stroke
				(width 0.1)
				(type default)
			)
			(layer "B.Fab")
		)
		(fp_line
			(start -3.64998 -2.15011)
			(end -3.64998 2.15011)
			(stroke
				(width 0.1)
				(type default)
			)
			(layer "B.Fab")
		)
		(fp_line
			(start 3.64998 -2.15011)
			(end -3.64998 -2.15011)
			(stroke
				(width 0.1)
				(type default)
			)
			(layer "B.Fab")
		)
		(fp_text user "+"
			(at 6.329172 -0.680212 270)
			(unlocked yes)
			(layer "B.SilkS")
			(effects
				(font
					(size 1.905 1.4224)
					(thickness 0.1524)
				)
				(justify left mirror)
			)
		)
		(fp_text user "-"
			(at -4.731512 -3.37566 270)
			(unlocked yes)
			(layer "B.SilkS")
			(effects
				(font
					(size 1.905 1.4224)
					(thickness 0.1524)
				)
				(justify left mirror)
			)
		)
		(fp_text user "-"
			(at -4.313174 -0.094488 270)
			(unlocked yes)
			(layer "B.Fab")
			(effects
				(font
					(size 1.905 1.4224)
					(thickness 0.1524)
				)
				(justify left mirror)
			)
		)
		(fp_text user "+"
			(at 6.214872 -0.337058 270)
			(unlocked yes)
			(layer "B.Fab")
			(effects
				(font
					(size 1.905 1.4224)
					(thickness 0.1524)
				)
				(justify left mirror)
			)
		)
		(pad "1" smd rect
			(at 3.199892 0 90)
			(size 2.413 2.8194)
			(layers "B.Cu" "B.Mask" "B.Paste")
			(net "P0V9_CPU0_RT_2D")
		)
		(pad "2" smd rect
			(at -3.199892 0 90)
			(size 2.413 2.8194)
			(layers "B.Cu" "B.Mask" "B.Paste")
			(net "GND")
		)
	)
	(footprint ""
		(layer "B.Cu")
		(at 175.50638 -422.234614 180)
		(property "Reference" "R6238"
			(at 0 0 0)
			(layer "B.SilkS")
			(hide yes)
			(effects
				(font
					(size 1.27 1.27)
				)
				(justify mirror)
			)
		)
		(property "Value" ""
			(at 0 0 0)
			(layer "B.Fab")
			(effects
				(font
					(size 1.27 1.27)
				)
				(justify mirror)
			)
		)
		(duplicate_pad_numbers_are_jumpers no)
		(fp_line
			(start 0.7874 0.4064)
			(end 0.7874 -0.4064)
			(stroke
				(width 0.1524)
				(type default)
			)
			(layer "B.SilkS")
		)
		(fp_line
			(start 0.7874 -0.4064)
			(end -0.7874 -0.4064)
			(stroke
				(width 0.1524)
				(type default)
			)
			(layer "B.SilkS")
		)
		(fp_line
			(start -0.7874 0.4064)
			(end 0.7874 0.4064)
			(stroke
				(width 0.1524)
				(type default)
			)
			(layer "B.SilkS")
		)
		(fp_line
			(start -0.7874 -0.4064)
			(end -0.7874 0.4064)
			(stroke
				(width 0.1524)
				(type default)
			)
			(layer "B.SilkS")
		)
		(fp_line
			(start 0.67945 0.3048)
			(end 0.67945 -0.305054)
			(stroke
				(width 0.1)
				(type default)
			)
			(layer "B.Fab")
		)
		(fp_line
			(start 0.67945 -0.305054)
			(end 0.12065 -0.305054)
			(stroke
				(width 0.1)
				(type default)
			)
			(layer "B.Fab")
		)
		(fp_line
			(start 0.12065 0.3048)
			(end 0.67945 0.3048)
			(stroke
				(width 0.1)
				(type default)
			)
			(layer "B.Fab")
		)
		(fp_line
			(start 0.12065 0.2794)
			(end 0.12065 0.3048)
			(stroke
				(width 0.1)
				(type default)
			)
			(layer "B.Fab")
		)
		(fp_line
			(start 0.12065 -0.2794)
			(end -0.12065 -0.2794)
			(stroke
				(width 0.1)
				(type default)
			)
			(layer "B.Fab")
		)
		(fp_line
			(start 0.12065 -0.305054)
			(end 0.12065 -0.2794)
			(stroke
				(width 0.1)
				(type default)
			)
			(layer "B.Fab")
		)
		(fp_line
			(start -0.120396 0.3048)
			(end -0.120396 0.2794)
			(stroke
				(width 0.1)
				(type default)
			)
			(layer "B.Fab")
		)
		(fp_line
			(start -0.120396 0.2794)
			(end 0.12065 0.2794)
			(stroke
				(width 0.1)
				(type default)
			)
			(layer "B.Fab")
		)
		(fp_line
			(start -0.12065 -0.2794)
			(end -0.12065 -0.3048)
			(stroke
				(width 0.1)
				(type default)
			)
			(layer "B.Fab")
		)
		(fp_line
			(start -0.12065 -0.3048)
			(end -0.67945 -0.3048)
			(stroke
				(width 0.1)
				(type default)
			)
			(layer "B.Fab")
		)
		(fp_line
			(start -0.67945 0.3048)
			(end -0.120396 0.3048)
			(stroke
				(width 0.1)
				(type default)
			)
			(layer "B.Fab")
		)
		(fp_line
			(start -0.67945 -0.3048)
			(end -0.67945 0.3048)
			(stroke
				(width 0.1)
				(type default)
			)
			(layer "B.Fab")
		)
		(pad "1" smd circle
			(at 0.40005 0)
			(size 0 0)
			(layers "B.Cu" "B.Mask" "B.Paste")
			(net "A_HSC_LOW_DRAIN")
		)
		(pad "2" smd circle
			(at -0.40005 0)
			(size 0 0)
			(layers "B.Cu" "B.Mask" "B.Paste")
			(net "HSC_D_OC")
		)
	)
	(footprint ""
		(layer "B.Cu")
		(at 116.891308 -390.560052 90)
		(property "Reference" "C472"
			(at 0 0 90)
			(layer "B.SilkS")
			(hide yes)
			(effects
				(font
					(size 1.27 1.27)
				)
				(justify mirror)
			)
		)
		(property "Value" ""
			(at 0 0 90)
			(layer "B.Fab")
			(effects
				(font
					(size 1.27 1.27)
				)
				(justify mirror)
			)
		)
		(duplicate_pad_numbers_are_jumpers no)
		(fp_line
			(start 0.7874 -0.4064)
			(end -0.7874 -0.4064)
			(stroke
				(width 0.1524)
				(type default)
			)
			(layer "B.SilkS")
		)
		(fp_line
			(start -0.7874 -0.4064)
			(end -0.7874 0.4064)
			(stroke
				(width 0.1524)
				(type default)
			)
			(layer "B.SilkS")
		)
		(fp_line
			(start 0.7874 0.4064)
			(end 0.7874 -0.4064)
			(stroke
				(width 0.1524)
				(type default)
			)
			(layer "B.SilkS")
		)
		(fp_line
			(start -0.7874 0.4064)
			(end 0.7874 0.4064)
			(stroke
				(width 0.1524)
				(type default)
			)
			(layer "B.SilkS")
		)
		(fp_line
			(start 0.67945 -0.305054)
			(end 0.12065 -0.305054)
			(stroke
				(width 0.1)
				(type default)
			)
			(layer "B.Fab")
		)
		(fp_line
			(start 0.12065 -0.305054)
			(end 0.12065 -0.2794)
			(stroke
				(width 0.1)
				(type default)
			)
			(layer "B.Fab")
		)
		(fp_line
			(start -0.12065 -0.3048)
			(end -0.67945 -0.3048)
			(stroke
				(width 0.1)
				(type default)
			)
			(layer "B.Fab")
		)
		(fp_line
			(start -0.67945 -0.3048)
			(end -0.67945 0.3048)
			(stroke
				(width 0.1)
				(type default)
			)
			(layer "B.Fab")
		)
		(fp_line
			(start 0.12065 -0.2794)
			(end -0.12065 -0.2794)
			(stroke
				(width 0.1)
				(type default)
			)
			(layer "B.Fab")
		)
		(fp_line
			(start -0.12065 -0.2794)
			(end -0.12065 -0.3048)
			(stroke
				(width 0.1)
				(type default)
			)
			(layer "B.Fab")
		)
		(fp_line
			(start 0.12065 0.2794)
			(end 0.12065 0.3048)
			(stroke
				(width 0.1)
				(type default)
			)
			(layer "B.Fab")
		)
		(fp_line
			(start -0.120396 0.2794)
			(end 0.12065 0.2794)
			(stroke
				(width 0.1)
				(type default)
			)
			(layer "B.Fab")
		)
		(fp_line
			(start 0.67945 0.3048)
			(end 0.67945 -0.305054)
			(stroke
				(width 0.1)
				(type default)
			)
			(layer "B.Fab")
		)
		(fp_line
			(start 0.12065 0.3048)
			(end 0.67945 0.3048)
			(stroke
				(width 0.1)
				(type default)
			)
			(layer "B.Fab")
		)
		(fp_line
			(start -0.120396 0.3048)
			(end -0.120396 0.2794)
			(stroke
				(width 0.1)
				(type default)
			)
			(layer "B.Fab")
		)
		(fp_line
			(start -0.67945 0.3048)
			(end -0.120396 0.3048)
			(stroke
				(width 0.1)
				(type default)
			)
			(layer "B.Fab")
		)
		(pad "1" smd circle
			(at 0.40005 0 270)
			(size 0 0)
			(layers "B.Cu" "B.Mask" "B.Paste")
			(net "P0V9_CPU1_RT3_2A")
		)
		(pad "2" smd circle
			(at -0.40005 0 270)
			(size 0 0)
			(layers "B.Cu" "B.Mask" "B.Paste")
			(net "GND")
		)
	)
	(footprint ""
		(layer "B.Cu")
		(at 398.249902 -152.29078 -90)
		(property "Reference" "R4638"
			(at 0 0 90)
			(layer "B.SilkS")
			(hide yes)
			(effects
				(font
					(size 1.27 1.27)
				)
				(justify mirror)
			)
		)
		(property "Value" ""
			(at 0 0 90)
			(layer "B.Fab")
			(effects
				(font
					(size 1.27 1.27)
				)
				(justify mirror)
			)
		)
		(duplicate_pad_numbers_are_jumpers no)
		(fp_line
			(start -2.234946 0.9271)
			(end 2.234946 0.9271)
			(stroke
				(width 0.1524)
				(type default)
			)
			(layer "B.SilkS")
		)
		(fp_line
			(start 2.234946 0.9271)
			(end 2.234946 -0.9271)
			(stroke
				(width 0.1524)
				(type default)
			)
			(layer "B.SilkS")
		)
		(fp_line
			(start -2.234946 -0.9271)
			(end -2.234946 0.9271)
			(stroke
				(width 0.1524)
				(type default)
			)
			(layer "B.SilkS")
		)
		(fp_line
			(start 2.234946 -0.9271)
			(end -2.234946 -0.9271)
			(stroke
				(width 0.1524)
				(type default)
			)
			(layer "B.SilkS")
		)
		(fp_line
			(start -1.575054 0.824992)
			(end -1.575054 -0.824992)
			(stroke
				(width 0.1)
				(type default)
			)
			(layer "B.Fab")
		)
		(fp_line
			(start 1.575054 0.824992)
			(end -1.575054 0.824992)
			(stroke
				(width 0.1)
				(type default)
			)
			(layer "B.Fab")
		)
		(fp_line
			(start -1.575054 -0.824992)
			(end 1.575054 -0.824992)
			(stroke
				(width 0.1)
				(type default)
			)
			(layer "B.Fab")
		)
		(fp_line
			(start 1.575054 -0.824992)
			(end 1.575054 0.824992)
			(stroke
				(width 0.1)
				(type default)
			)
			(layer "B.Fab")
		)
		(pad "1" smd rect
			(at 1.599946 0 90)
			(size 1.016 1.6002)
			(layers "B.Cu" "B.Mask" "B.Paste")
			(net "P5V")
		)
		(pad "2" smd rect
			(at -1.599946 0 90)
			(size 1.016 1.6002)
			(layers "B.Cu" "B.Mask" "B.Paste")
			(net "VR_P5V_EN_D")
		)
	)
	(footprint ""
		(layer "B.Cu")
		(at 76.20508 -11.267948 90)
		(property "Reference" "R3173"
			(at 0 0 90)
			(layer "B.SilkS")
			(hide yes)
			(effects
				(font
					(size 1.27 1.27)
				)
				(justify mirror)
			)
		)
		(property "Value" ""
			(at 0 0 90)
			(layer "B.Fab")
			(effects
				(font
					(size 1.27 1.27)
				)
				(justify mirror)
			)
		)
		(duplicate_pad_numbers_are_jumpers no)
		(fp_line
			(start 0.7874 -0.4064)
			(end -0.7874 -0.4064)
			(stroke
				(width 0.1524)
				(type default)
			)
			(layer "B.SilkS")
		)
		(fp_line
			(start -0.7874 -0.4064)
			(end -0.7874 0.4064)
			(stroke
				(width 0.1524)
				(type default)
			)
			(layer "B.SilkS")
		)
		(fp_line
			(start 0.7874 0.4064)
			(end 0.7874 -0.4064)
			(stroke
				(width 0.1524)
				(type default)
			)
			(layer "B.SilkS")
		)
		(fp_line
			(start -0.7874 0.4064)
			(end 0.7874 0.4064)
			(stroke
				(width 0.1524)
				(type default)
			)
			(layer "B.SilkS")
		)
		(fp_line
			(start 0.67945 -0.305054)
			(end 0.12065 -0.305054)
			(stroke
				(width 0.1)
				(type default)
			)
			(layer "B.Fab")
		)
		(fp_line
			(start 0.12065 -0.305054)
			(end 0.12065 -0.2794)
			(stroke
				(width 0.1)
				(type default)
			)
			(layer "B.Fab")
		)
		(fp_line
			(start -0.12065 -0.3048)
			(end -0.67945 -0.3048)
			(stroke
				(width 0.1)
				(type default)
			)
			(layer "B.Fab")
		)
		(fp_line
			(start -0.67945 -0.3048)
			(end -0.67945 0.3048)
			(stroke
				(width 0.1)
				(type default)
			)
			(layer "B.Fab")
		)
		(fp_line
			(start 0.12065 -0.2794)
			(end -0.12065 -0.2794)
			(stroke
				(width 0.1)
				(type default)
			)
			(layer "B.Fab")
		)
		(fp_line
			(start -0.12065 -0.2794)
			(end -0.12065 -0.3048)
			(stroke
				(width 0.1)
				(type default)
			)
			(layer "B.Fab")
		)
		(fp_line
			(start 0.12065 0.2794)
			(end 0.12065 0.3048)
			(stroke
				(width 0.1)
				(type default)
			)
			(layer "B.Fab")
		)
		(fp_line
			(start -0.120396 0.2794)
			(end 0.12065 0.2794)
			(stroke
				(width 0.1)
				(type default)
			)
			(layer "B.Fab")
		)
		(fp_line
			(start 0.67945 0.3048)
			(end 0.67945 -0.305054)
			(stroke
				(width 0.1)
				(type default)
			)
			(layer "B.Fab")
		)
		(fp_line
			(start 0.12065 0.3048)
			(end 0.67945 0.3048)
			(stroke
				(width 0.1)
				(type default)
			)
			(layer "B.Fab")
		)
		(fp_line
			(start -0.120396 0.3048)
			(end -0.120396 0.2794)
			(stroke
				(width 0.1)
				(type default)
			)
			(layer "B.Fab")
		)
		(fp_line
			(start -0.67945 0.3048)
			(end -0.120396 0.3048)
			(stroke
				(width 0.1)
				(type default)
			)
			(layer "B.Fab")
		)
		(pad "1" smd circle
			(at 0.40005 0 270)
			(size 0 0)
			(layers "B.Cu" "B.Mask" "B.Paste")
			(net "SGPIO_OCP_V3_2_LD_N")
		)
		(pad "2" smd circle
			(at -0.40005 0 270)
			(size 0 0)
			(layers "B.Cu" "B.Mask" "B.Paste")
			(net "P3V3_OCP_V3_2")
		)
	)
	(footprint ""
		(layer "B.Cu")
		(at 368.51844 -395.43228)
		(property "Reference" "C1050"
			(at 0 0 0)
			(layer "B.SilkS")
			(hide yes)
			(effects
				(font
					(size 1.27 1.27)
				)
				(justify mirror)
			)
		)
		(property "Value" ""
			(at 0 0 0)
			(layer "B.Fab")
			(effects
				(font
					(size 1.27 1.27)
				)
				(justify mirror)
			)
		)
		(duplicate_pad_numbers_are_jumpers no)
		(fp_line
			(start -0.299974 -0.150114)
			(end -0.299974 0.150114)
			(stroke
				(width 0.1)
				(type default)
			)
			(layer "B.Fab")
		)
		(fp_line
			(start -0.299974 0.150114)
			(end 0.299974 0.150114)
			(stroke
				(width 0.1)
				(type default)
			)
			(layer "B.Fab")
		)
		(fp_line
			(start 0.299974 -0.150114)
			(end -0.299974 -0.150114)
			(stroke
				(width 0.1)
				(type default)
			)
			(layer "B.Fab")
		)
		(fp_line
			(start 0.299974 0.150114)
			(end 0.299974 -0.150114)
			(stroke
				(width 0.1)
				(type default)
			)
			(layer "B.Fab")
		)
		(pad "1" smd rect
			(at 0.2667 0 180)
			(size 0.3048 0.381)
			(layers "B.Cu" "B.Mask" "B.Paste")
			(net "P0V9_CPU0_RT3_2A")
		)
		(pad "2" smd rect
			(at -0.2667 0 180)
			(size 0.3048 0.381)
			(layers "B.Cu" "B.Mask" "B.Paste")
			(net "GND")
		)
	)
	(footprint ""
		(layer "B.Cu")
		(at 413.975804 -361.427014 -90)
		(property "Reference" "PR127"
			(at 0 0 90)
			(layer "B.SilkS")
			(hide yes)
			(effects
				(font
					(size 1.27 1.27)
				)
				(justify mirror)
			)
		)
		(property "Value" ""
			(at 0 0 90)
			(layer "B.Fab")
			(effects
				(font
					(size 1.27 1.27)
				)
				(justify mirror)
			)
		)
		(duplicate_pad_numbers_are_jumpers no)
		(fp_line
			(start -0.7874 0.4064)
			(end 0.7874 0.4064)
			(stroke
				(width 0.1524)
				(type default)
			)
			(layer "B.SilkS")
		)
		(fp_line
			(start 0.7874 0.4064)
			(end 0.7874 -0.4064)
			(stroke
				(width 0.1524)
				(type default)
			)
			(layer "B.SilkS")
		)
		(fp_line
			(start -0.7874 -0.4064)
			(end -0.7874 0.4064)
			(stroke
				(width 0.1524)
				(type default)
			)
			(layer "B.SilkS")
		)
		(fp_line
			(start 0.7874 -0.4064)
			(end -0.7874 -0.4064)
			(stroke
				(width 0.1524)
				(type default)
			)
			(layer "B.SilkS")
		)
		(fp_line
			(start -0.67945 0.3048)
			(end -0.120396 0.3048)
			(stroke
				(width 0.1)
				(type default)
			)
			(layer "B.Fab")
		)
		(fp_line
			(start -0.120396 0.3048)
			(end -0.120396 0.2794)
			(stroke
				(width 0.1)
				(type default)
			)
			(layer "B.Fab")
		)
		(fp_line
			(start 0.12065 0.3048)
			(end 0.67945 0.3048)
			(stroke
				(width 0.1)
				(type default)
			)
			(layer "B.Fab")
		)
		(fp_line
			(start 0.67945 0.3048)
			(end 0.67945 -0.305054)
			(stroke
				(width 0.1)
				(type default)
			)
			(layer "B.Fab")
		)
		(fp_line
			(start -0.120396 0.2794)
			(end 0.12065 0.2794)
			(stroke
				(width 0.1)
				(type default)
			)
			(layer "B.Fab")
		)
		(fp_line
			(start 0.12065 0.2794)
			(end 0.12065 0.3048)
			(stroke
				(width 0.1)
				(type default)
			)
			(layer "B.Fab")
		)
		(fp_line
			(start -0.12065 -0.2794)
			(end -0.12065 -0.3048)
			(stroke
				(width 0.1)
				(type default)
			)
			(layer "B.Fab")
		)
		(fp_line
			(start 0.12065 -0.2794)
			(end -0.12065 -0.2794)
			(stroke
				(width 0.1)
				(type default)
			)
			(layer "B.Fab")
		)
		(fp_line
			(start -0.67945 -0.3048)
			(end -0.67945 0.3048)
			(stroke
				(width 0.1)
				(type default)
			)
			(layer "B.Fab")
		)
		(fp_line
			(start -0.12065 -0.3048)
			(end -0.67945 -0.3048)
			(stroke
				(width 0.1)
				(type default)
			)
			(layer "B.Fab")
		)
		(fp_line
			(start 0.12065 -0.305054)
			(end 0.12065 -0.2794)
			(stroke
				(width 0.1)
				(type default)
			)
			(layer "B.Fab")
		)
		(fp_line
			(start 0.67945 -0.305054)
			(end 0.12065 -0.305054)
			(stroke
				(width 0.1)
				(type default)
			)
			(layer "B.Fab")
		)
		(pad "1" smd circle
			(at 0.40005 0 90)
			(size 0 0)
			(layers "B.Cu" "B.Mask" "B.Paste")
			(net "PVDD11_S3_P0_RESET_N_R")
		)
		(pad "2" smd circle
			(at -0.40005 0 90)
			(size 0 0)
			(layers "B.Cu" "B.Mask" "B.Paste")
			(net "GND")
		)
	)
	(footprint ""
		(layer "B.Cu")
		(at 14.840458 -418.817298)
		(property "Reference" "C6010"
			(at 0 0 0)
			(layer "B.SilkS")
			(hide yes)
			(effects
				(font
					(size 1.27 1.27)
				)
				(justify mirror)
			)
		)
		(property "Value" ""
			(at 0 0 0)
			(layer "B.Fab")
			(effects
				(font
					(size 1.27 1.27)
				)
				(justify mirror)
			)
		)
		(duplicate_pad_numbers_are_jumpers no)
		(fp_line
			(start -1.524 -0.762)
			(end -1.524 0.762)
			(stroke
				(width 0.1524)
				(type default)
			)
			(layer "B.SilkS")
		)
		(fp_line
			(start -1.524 0.762)
			(end 1.524 0.762)
			(stroke
				(width 0.1524)
				(type default)
			)
			(layer "B.SilkS")
		)
		(fp_line
			(start 1.524 -0.762)
			(end -1.524 -0.762)
			(stroke
				(width 0.1524)
				(type default)
			)
			(layer "B.SilkS")
		)
		(fp_line
			(start 1.524 0.762)
			(end 1.524 -0.762)
			(stroke
				(width 0.1524)
				(type default)
			)
			(layer "B.SilkS")
		)
		(fp_line
			(start -1.1049 -0.724916)
			(end 1.1049 -0.724916)
			(stroke
				(width 0.1)
				(type default)
			)
			(layer "B.Fab")
		)
		(fp_line
			(start -1.1049 0.724916)
			(end -1.1049 -0.724916)
			(stroke
				(width 0.1)
				(type default)
			)
			(layer "B.Fab")
		)
		(fp_line
			(start 1.1049 -0.724916)
			(end 1.1049 0.724916)
			(stroke
				(width 0.1)
				(type default)
			)
			(layer "B.Fab")
		)
		(fp_line
			(start 1.1049 0.724916)
			(end -1.1049 0.724916)
			(stroke
				(width 0.1)
				(type default)
			)
			(layer "B.Fab")
		)
		(pad "1" smd rect
			(at 0.889 0)
			(size 1.016 1.27)
			(layers "B.Cu" "B.Mask" "B.Paste")
			(net "P3V3_AUX")
		)
		(pad "2" smd rect
			(at -0.889 0)
			(size 1.016 1.27)
			(layers "B.Cu" "B.Mask" "B.Paste")
			(net "GND")
		)
	)
	(footprint ""
		(layer "B.Cu")
		(at 94.488 -301.716948)
		(property "Reference" "R5032"
			(at 0 0 0)
			(layer "B.SilkS")
			(hide yes)
			(effects
				(font
					(size 1.27 1.27)
				)
				(justify mirror)
			)
		)
		(property "Value" ""
			(at 0 0 0)
			(layer "B.Fab")
			(effects
				(font
					(size 1.27 1.27)
				)
				(justify mirror)
			)
		)
		(duplicate_pad_numbers_are_jumpers no)
		(fp_line
			(start -0.7874 -0.4064)
			(end -0.7874 0.4064)
			(stroke
				(width 0.1524)
				(type default)
			)
			(layer "B.SilkS")
		)
		(fp_line
			(start -0.7874 0.4064)
			(end 0.7874 0.4064)
			(stroke
				(width 0.1524)
				(type default)
			)
			(layer "B.SilkS")
		)
		(fp_line
			(start 0.7874 -0.4064)
			(end -0.7874 -0.4064)
			(stroke
				(width 0.1524)
				(type default)
			)
			(layer "B.SilkS")
		)
		(fp_line
			(start 0.7874 0.4064)
			(end 0.7874 -0.4064)
			(stroke
				(width 0.1524)
				(type default)
			)
			(layer "B.SilkS")
		)
		(fp_line
			(start -0.67945 -0.3048)
			(end -0.67945 0.3048)
			(stroke
				(width 0.1)
				(type default)
			)
			(layer "B.Fab")
		)
		(fp_line
			(start -0.67945 0.3048)
			(end -0.120396 0.3048)
			(stroke
				(width 0.1)
				(type default)
			)
			(layer "B.Fab")
		)
		(fp_line
			(start -0.12065 -0.3048)
			(end -0.67945 -0.3048)
			(stroke
				(width 0.1)
				(type default)
			)
			(layer "B.Fab")
		)
		(fp_line
			(start -0.12065 -0.2794)
			(end -0.12065 -0.3048)
			(stroke
				(width 0.1)
				(type default)
			)
			(layer "B.Fab")
		)
		(fp_line
			(start -0.120396 0.2794)
			(end 0.12065 0.2794)
			(stroke
				(width 0.1)
				(type default)
			)
			(layer "B.Fab")
		)
		(fp_line
			(start -0.120396 0.3048)
			(end -0.120396 0.2794)
			(stroke
				(width 0.1)
				(type default)
			)
			(layer "B.Fab")
		)
		(fp_line
			(start 0.12065 -0.305054)
			(end 0.12065 -0.2794)
			(stroke
				(width 0.1)
				(type default)
			)
			(layer "B.Fab")
		)
		(fp_line
			(start 0.12065 -0.2794)
			(end -0.12065 -0.2794)
			(stroke
				(width 0.1)
				(type default)
			)
			(layer "B.Fab")
		)
		(fp_line
			(start 0.12065 0.2794)
			(end 0.12065 0.3048)
			(stroke
				(width 0.1)
				(type default)
			)
			(layer "B.Fab")
		)
		(fp_line
			(start 0.12065 0.3048)
			(end 0.67945 0.3048)
			(stroke
				(width 0.1)
				(type default)
			)
			(layer "B.Fab")
		)
		(fp_line
			(start 0.67945 -0.305054)
			(end 0.12065 -0.305054)
			(stroke
				(width 0.1)
				(type default)
			)
			(layer "B.Fab")
		)
		(fp_line
			(start 0.67945 0.3048)
			(end 0.67945 -0.305054)
			(stroke
				(width 0.1)
				(type default)
			)
			(layer "B.Fab")
		)
		(pad "1" smd circle
			(at 0.40005 0 180)
			(size 0 0)
			(layers "B.Cu" "B.Mask" "B.Paste")
			(net "GND")
		)
		(pad "2" smd circle
			(at -0.40005 0 180)
			(size 0 0)
			(layers "B.Cu" "B.Mask" "B.Paste")
			(net "IRQ_CPU_BMC_NMI_N")
		)
	)
	(footprint ""
		(layer "B.Cu")
		(at 246.01932 -53.923946 -90)
		(property "Reference" "PC2280"
			(at 0 0 90)
			(layer "B.SilkS")
			(hide yes)
			(effects
				(font
					(size 1.27 1.27)
				)
				(justify mirror)
			)
		)
		(property "Value" ""
			(at 0 0 90)
			(layer "B.Fab")
			(effects
				(font
					(size 1.27 1.27)
				)
				(justify mirror)
			)
		)
		(duplicate_pad_numbers_are_jumpers no)
		(fp_line
			(start -1.524 0.762)
			(end 1.524 0.762)
			(stroke
				(width 0.1524)
				(type default)
			)
			(layer "B.SilkS")
		)
		(fp_line
			(start 1.524 0.762)
			(end 1.524 -0.762)
			(stroke
				(width 0.1524)
				(type default)
			)
			(layer "B.SilkS")
		)
		(fp_line
			(start -1.524 -0.762)
			(end -1.524 0.762)
			(stroke
				(width 0.1524)
				(type default)
			)
			(layer "B.SilkS")
		)
		(fp_line
			(start 1.524 -0.762)
			(end -1.524 -0.762)
			(stroke
				(width 0.1524)
				(type default)
			)
			(layer "B.SilkS")
		)
		(fp_line
			(start -1.1049 0.724916)
			(end -1.1049 -0.724916)
			(stroke
				(width 0.1)
				(type default)
			)
			(layer "B.Fab")
		)
		(fp_line
			(start 1.1049 0.724916)
			(end -1.1049 0.724916)
			(stroke
				(width 0.1)
				(type default)
			)
			(layer "B.Fab")
		)
		(fp_line
			(start -1.1049 -0.724916)
			(end 1.1049 -0.724916)
			(stroke
				(width 0.1)
				(type default)
			)
			(layer "B.Fab")
		)
		(fp_line
			(start 1.1049 -0.724916)
			(end 1.1049 0.724916)
			(stroke
				(width 0.1)
				(type default)
			)
			(layer "B.Fab")
		)
		(pad "1" smd rect
			(at 0.889 0 270)
			(size 1.016 1.27)
			(layers "B.Cu" "B.Mask" "B.Paste")
			(net "P12V_E1S_0")
		)
		(pad "2" smd rect
			(at -0.889 0 270)
			(size 1.016 1.27)
			(layers "B.Cu" "B.Mask" "B.Paste")
			(net "GND")
		)
	)
	(footprint ""
		(layer "B.Cu")
		(at 346.373958 -261.870952)
		(property "Reference" "C2605"
			(at 0 0 0)
			(layer "B.SilkS")
			(hide yes)
			(effects
				(font
					(size 1.27 1.27)
				)
				(justify mirror)
			)
		)
		(property "Value" ""
			(at 0 0 0)
			(layer "B.Fab")
			(effects
				(font
					(size 1.27 1.27)
				)
				(justify mirror)
			)
		)
		(duplicate_pad_numbers_are_jumpers no)
		(fp_line
			(start -0.7874 -0.4064)
			(end -0.7874 0.4064)
			(stroke
				(width 0.1524)
				(type default)
			)
			(layer "B.SilkS")
		)
		(fp_line
			(start -0.7874 0.4064)
			(end 0.7874 0.4064)
			(stroke
				(width 0.1524)
				(type default)
			)
			(layer "B.SilkS")
		)
		(fp_line
			(start 0.7874 -0.4064)
			(end -0.7874 -0.4064)
			(stroke
				(width 0.1524)
				(type default)
			)
			(layer "B.SilkS")
		)
		(fp_line
			(start 0.7874 0.4064)
			(end 0.7874 -0.4064)
			(stroke
				(width 0.1524)
				(type default)
			)
			(layer "B.SilkS")
		)
		(fp_line
			(start -0.67945 -0.3048)
			(end -0.67945 0.3048)
			(stroke
				(width 0.1)
				(type default)
			)
			(layer "B.Fab")
		)
		(fp_line
			(start -0.67945 0.3048)
			(end -0.120396 0.3048)
			(stroke
				(width 0.1)
				(type default)
			)
			(layer "B.Fab")
		)
		(fp_line
			(start -0.12065 -0.3048)
			(end -0.67945 -0.3048)
			(stroke
				(width 0.1)
				(type default)
			)
			(layer "B.Fab")
		)
		(fp_line
			(start -0.12065 -0.2794)
			(end -0.12065 -0.3048)
			(stroke
				(width 0.1)
				(type default)
			)
			(layer "B.Fab")
		)
		(fp_line
			(start -0.120396 0.2794)
			(end 0.12065 0.2794)
			(stroke
				(width 0.1)
				(type default)
			)
			(layer "B.Fab")
		)
		(fp_line
			(start -0.120396 0.3048)
			(end -0.120396 0.2794)
			(stroke
				(width 0.1)
				(type default)
			)
			(layer "B.Fab")
		)
		(fp_line
			(start 0.12065 -0.305054)
			(end 0.12065 -0.2794)
			(stroke
				(width 0.1)
				(type default)
			)
			(layer "B.Fab")
		)
		(fp_line
			(start 0.12065 -0.2794)
			(end -0.12065 -0.2794)
			(stroke
				(width 0.1)
				(type default)
			)
			(layer "B.Fab")
		)
		(fp_line
			(start 0.12065 0.2794)
			(end 0.12065 0.3048)
			(stroke
				(width 0.1)
				(type default)
			)
			(layer "B.Fab")
		)
		(fp_line
			(start 0.12065 0.3048)
			(end 0.67945 0.3048)
			(stroke
				(width 0.1)
				(type default)
			)
			(layer "B.Fab")
		)
		(fp_line
			(start 0.67945 -0.305054)
			(end 0.12065 -0.305054)
			(stroke
				(width 0.1)
				(type default)
			)
			(layer "B.Fab")
		)
		(fp_line
			(start 0.67945 0.3048)
			(end 0.67945 -0.305054)
			(stroke
				(width 0.1)
				(type default)
			)
			(layer "B.Fab")
		)
		(pad "1" smd circle
			(at 0.40005 0 180)
			(size 0 0)
			(layers "B.Cu" "B.Mask" "B.Paste")
			(net "PVDDIO_P0")
		)
		(pad "2" smd circle
			(at -0.40005 0 180)
			(size 0 0)
			(layers "B.Cu" "B.Mask" "B.Paste")
			(net "GND")
		)
	)
	(footprint ""
		(layer "B.Cu")
		(at 396.052802 -314.366148)
		(property "Reference" "C213"
			(at 0 0 0)
			(layer "B.SilkS")
			(hide yes)
			(effects
				(font
					(size 1.27 1.27)
				)
				(justify mirror)
			)
		)
		(property "Value" ""
			(at 0 0 0)
			(layer "B.Fab")
			(effects
				(font
					(size 1.27 1.27)
				)
				(justify mirror)
			)
		)
		(duplicate_pad_numbers_are_jumpers no)
		(fp_line
			(start -0.7874 -0.4064)
			(end -0.7874 0.4064)
			(stroke
				(width 0.1524)
				(type default)
			)
			(layer "B.SilkS")
		)
		(fp_line
			(start -0.7874 0.4064)
			(end 0.7874 0.4064)
			(stroke
				(width 0.1524)
				(type default)
			)
			(layer "B.SilkS")
		)
		(fp_line
			(start 0.7874 -0.4064)
			(end -0.7874 -0.4064)
			(stroke
				(width 0.1524)
				(type default)
			)
			(layer "B.SilkS")
		)
		(fp_line
			(start 0.7874 0.4064)
			(end 0.7874 -0.4064)
			(stroke
				(width 0.1524)
				(type default)
			)
			(layer "B.SilkS")
		)
		(fp_line
			(start -0.67945 -0.3048)
			(end -0.67945 0.3048)
			(stroke
				(width 0.1)
				(type default)
			)
			(layer "B.Fab")
		)
		(fp_line
			(start -0.67945 0.3048)
			(end -0.120396 0.3048)
			(stroke
				(width 0.1)
				(type default)
			)
			(layer "B.Fab")
		)
		(fp_line
			(start -0.12065 -0.3048)
			(end -0.67945 -0.3048)
			(stroke
				(width 0.1)
				(type default)
			)
			(layer "B.Fab")
		)
		(fp_line
			(start -0.12065 -0.2794)
			(end -0.12065 -0.3048)
			(stroke
				(width 0.1)
				(type default)
			)
			(layer "B.Fab")
		)
		(fp_line
			(start -0.120396 0.2794)
			(end 0.12065 0.2794)
			(stroke
				(width 0.1)
				(type default)
			)
			(layer "B.Fab")
		)
		(fp_line
			(start -0.120396 0.3048)
			(end -0.120396 0.2794)
			(stroke
				(width 0.1)
				(type default)
			)
			(layer "B.Fab")
		)
		(fp_line
			(start 0.12065 -0.305054)
			(end 0.12065 -0.2794)
			(stroke
				(width 0.1)
				(type default)
			)
			(layer "B.Fab")
		)
		(fp_line
			(start 0.12065 -0.2794)
			(end -0.12065 -0.2794)
			(stroke
				(width 0.1)
				(type default)
			)
			(layer "B.Fab")
		)
		(fp_line
			(start 0.12065 0.2794)
			(end 0.12065 0.3048)
			(stroke
				(width 0.1)
				(type default)
			)
			(layer "B.Fab")
		)
		(fp_line
			(start 0.12065 0.3048)
			(end 0.67945 0.3048)
			(stroke
				(width 0.1)
				(type default)
			)
			(layer "B.Fab")
		)
		(fp_line
			(start 0.67945 -0.305054)
			(end 0.12065 -0.305054)
			(stroke
				(width 0.1)
				(type default)
			)
			(layer "B.Fab")
		)
		(fp_line
			(start 0.67945 0.3048)
			(end 0.67945 -0.305054)
			(stroke
				(width 0.1)
				(type default)
			)
			(layer "B.Fab")
		)
		(pad "1" smd circle
			(at 0.40005 0 180)
			(size 0 0)
			(layers "B.Cu" "B.Mask" "B.Paste")
			(net "XTAL_CPU0_X48M_X1")
		)
		(pad "2" smd circle
			(at -0.40005 0 180)
			(size 0 0)
			(layers "B.Cu" "B.Mask" "B.Paste")
			(net "GND")
		)
	)
	(footprint ""
		(layer "B.Cu")
		(at 239.903 -216.027)
		(property "Reference" "R365"
			(at 0 0 0)
			(layer "B.SilkS")
			(hide yes)
			(effects
				(font
					(size 1.27 1.27)
				)
				(justify mirror)
			)
		)
		(property "Value" ""
			(at 0 0 0)
			(layer "B.Fab")
			(effects
				(font
					(size 1.27 1.27)
				)
				(justify mirror)
			)
		)
		(duplicate_pad_numbers_are_jumpers no)
		(fp_line
			(start -0.7874 -0.4064)
			(end -0.7874 0.4064)
			(stroke
				(width 0.1524)
				(type default)
			)
			(layer "B.SilkS")
		)
		(fp_line
			(start -0.7874 0.4064)
			(end 0.7874 0.4064)
			(stroke
				(width 0.1524)
				(type default)
			)
			(layer "B.SilkS")
		)
		(fp_line
			(start 0.7874 -0.4064)
			(end -0.7874 -0.4064)
			(stroke
				(width 0.1524)
				(type default)
			)
			(layer "B.SilkS")
		)
		(fp_line
			(start 0.7874 0.4064)
			(end 0.7874 -0.4064)
			(stroke
				(width 0.1524)
				(type default)
			)
			(layer "B.SilkS")
		)
		(fp_line
			(start -0.67945 -0.3048)
			(end -0.67945 0.3048)
			(stroke
				(width 0.1)
				(type default)
			)
			(layer "B.Fab")
		)
		(fp_line
			(start -0.67945 0.3048)
			(end -0.120396 0.3048)
			(stroke
				(width 0.1)
				(type default)
			)
			(layer "B.Fab")
		)
		(fp_line
			(start -0.12065 -0.3048)
			(end -0.67945 -0.3048)
			(stroke
				(width 0.1)
				(type default)
			)
			(layer "B.Fab")
		)
		(fp_line
			(start -0.12065 -0.2794)
			(end -0.12065 -0.3048)
			(stroke
				(width 0.1)
				(type default)
			)
			(layer "B.Fab")
		)
		(fp_line
			(start -0.120396 0.2794)
			(end 0.12065 0.2794)
			(stroke
				(width 0.1)
				(type default)
			)
			(layer "B.Fab")
		)
		(fp_line
			(start -0.120396 0.3048)
			(end -0.120396 0.2794)
			(stroke
				(width 0.1)
				(type default)
			)
			(layer "B.Fab")
		)
		(fp_line
			(start 0.12065 -0.305054)
			(end 0.12065 -0.2794)
			(stroke
				(width 0.1)
				(type default)
			)
			(layer "B.Fab")
		)
		(fp_line
			(start 0.12065 -0.2794)
			(end -0.12065 -0.2794)
			(stroke
				(width 0.1)
				(type default)
			)
			(layer "B.Fab")
		)
		(fp_line
			(start 0.12065 0.2794)
			(end 0.12065 0.3048)
			(stroke
				(width 0.1)
				(type default)
			)
			(layer "B.Fab")
		)
		(fp_line
			(start 0.12065 0.3048)
			(end 0.67945 0.3048)
			(stroke
				(width 0.1)
				(type default)
			)
			(layer "B.Fab")
		)
		(fp_line
			(start 0.67945 -0.305054)
			(end 0.12065 -0.305054)
			(stroke
				(width 0.1)
				(type default)
			)
			(layer "B.Fab")
		)
		(fp_line
			(start 0.67945 0.3048)
			(end 0.67945 -0.305054)
			(stroke
				(width 0.1)
				(type default)
			)
			(layer "B.Fab")
		)
		(pad "1" smd circle
			(at 0.40005 0 180)
			(size 0 0)
			(layers "B.Cu" "B.Mask" "B.Paste")
			(net "P3V3")
		)
		(pad "2" smd circle
			(at -0.40005 0 180)
			(size 0 0)
			(layers "B.Cu" "B.Mask" "B.Paste")
			(net "SMB_CPU0_CPU1_APML_BUF1_SDA_R2")
		)
	)
	(footprint ""
		(layer "B.Cu")
		(at 368.199924 -396.991078 90)
		(property "Reference" "C1053"
			(at 0 0 90)
			(layer "B.SilkS")
			(hide yes)
			(effects
				(font
					(size 1.27 1.27)
				)
				(justify mirror)
			)
		)
		(property "Value" ""
			(at 0 0 90)
			(layer "B.Fab")
			(effects
				(font
					(size 1.27 1.27)
				)
				(justify mirror)
			)
		)
		(duplicate_pad_numbers_are_jumpers no)
		(fp_line
			(start 0.299974 -0.150114)
			(end -0.299974 -0.150114)
			(stroke
				(width 0.1)
				(type default)
			)
			(layer "B.Fab")
		)
		(fp_line
			(start -0.299974 -0.150114)
			(end -0.299974 0.150114)
			(stroke
				(width 0.1)
				(type default)
			)
			(layer "B.Fab")
		)
		(fp_line
			(start 0.299974 0.150114)
			(end 0.299974 -0.150114)
			(stroke
				(width 0.1)
				(type default)
			)
			(layer "B.Fab")
		)
		(fp_line
			(start -0.299974 0.150114)
			(end 0.299974 0.150114)
			(stroke
				(width 0.1)
				(type default)
			)
			(layer "B.Fab")
		)
		(pad "1" smd rect
			(at 0.2667 0 270)
			(size 0.3048 0.381)
			(layers "B.Cu" "B.Mask" "B.Paste")
			(net "P0V9_CPU0_RT3_2A")
		)
		(pad "2" smd rect
			(at -0.2667 0 270)
			(size 0.3048 0.381)
			(layers "B.Cu" "B.Mask" "B.Paste")
			(net "GND")
		)
	)
	(footprint ""
		(layer "B.Cu")
		(at 139.679426 -9.058148 -90)
		(property "Reference" "R1798"
			(at 0 0 90)
			(layer "B.SilkS")
			(hide yes)
			(effects
				(font
					(size 1.27 1.27)
				)
				(justify mirror)
			)
		)
		(property "Value" ""
			(at 0 0 90)
			(layer "B.Fab")
			(effects
				(font
					(size 1.27 1.27)
				)
				(justify mirror)
			)
		)
		(duplicate_pad_numbers_are_jumpers no)
		(fp_line
			(start -0.7874 0.4064)
			(end 0.7874 0.4064)
			(stroke
				(width 0.1524)
				(type default)
			)
			(layer "B.SilkS")
		)
		(fp_line
			(start 0.7874 0.4064)
			(end 0.7874 -0.4064)
			(stroke
				(width 0.1524)
				(type default)
			)
			(layer "B.SilkS")
		)
		(fp_line
			(start -0.7874 -0.4064)
			(end -0.7874 0.4064)
			(stroke
				(width 0.1524)
				(type default)
			)
			(layer "B.SilkS")
		)
		(fp_line
			(start 0.7874 -0.4064)
			(end -0.7874 -0.4064)
			(stroke
				(width 0.1524)
				(type default)
			)
			(layer "B.SilkS")
		)
		(fp_line
			(start -0.67945 0.3048)
			(end -0.120396 0.3048)
			(stroke
				(width 0.1)
				(type default)
			)
			(layer "B.Fab")
		)
		(fp_line
			(start -0.120396 0.3048)
			(end -0.120396 0.2794)
			(stroke
				(width 0.1)
				(type default)
			)
			(layer "B.Fab")
		)
		(fp_line
			(start 0.12065 0.3048)
			(end 0.67945 0.3048)
			(stroke
				(width 0.1)
				(type default)
			)
			(layer "B.Fab")
		)
		(fp_line
			(start 0.67945 0.3048)
			(end 0.67945 -0.305054)
			(stroke
				(width 0.1)
				(type default)
			)
			(layer "B.Fab")
		)
		(fp_line
			(start -0.120396 0.2794)
			(end 0.12065 0.2794)
			(stroke
				(width 0.1)
				(type default)
			)
			(layer "B.Fab")
		)
		(fp_line
			(start 0.12065 0.2794)
			(end 0.12065 0.3048)
			(stroke
				(width 0.1)
				(type default)
			)
			(layer "B.Fab")
		)
		(fp_line
			(start -0.12065 -0.2794)
			(end -0.12065 -0.3048)
			(stroke
				(width 0.1)
				(type default)
			)
			(layer "B.Fab")
		)
		(fp_line
			(start 0.12065 -0.2794)
			(end -0.12065 -0.2794)
			(stroke
				(width 0.1)
				(type default)
			)
			(layer "B.Fab")
		)
		(fp_line
			(start -0.67945 -0.3048)
			(end -0.67945 0.3048)
			(stroke
				(width 0.1)
				(type default)
			)
			(layer "B.Fab")
		)
		(fp_line
			(start -0.12065 -0.3048)
			(end -0.67945 -0.3048)
			(stroke
				(width 0.1)
				(type default)
			)
			(layer "B.Fab")
		)
		(fp_line
			(start 0.12065 -0.305054)
			(end 0.12065 -0.2794)
			(stroke
				(width 0.1)
				(type default)
			)
			(layer "B.Fab")
		)
		(fp_line
			(start 0.67945 -0.305054)
			(end 0.12065 -0.305054)
			(stroke
				(width 0.1)
				(type default)
			)
			(layer "B.Fab")
		)
		(pad "1" smd circle
			(at 0.40005 0 90)
			(size 0 0)
			(layers "B.Cu" "B.Mask" "B.Paste")
			(net "SCM_ROT_CPU_RST_R_N")
		)
		(pad "2" smd circle
			(at -0.40005 0 90)
			(size 0 0)
			(layers "B.Cu" "B.Mask" "B.Paste")
			(net "SCM_ROT_CPU_RST_N")
		)
	)
	(footprint ""
		(layer "B.Cu")
		(at 208.461356 -378.682504)
		(property "Reference" "PR2515"
			(at 0 0 0)
			(layer "B.SilkS")
			(hide yes)
			(effects
				(font
					(size 1.27 1.27)
				)
				(justify mirror)
			)
		)
		(property "Value" ""
			(at 0 0 0)
			(layer "B.Fab")
			(effects
				(font
					(size 1.27 1.27)
				)
				(justify mirror)
			)
		)
		(duplicate_pad_numbers_are_jumpers no)
		(fp_line
			(start -0.7874 -0.4064)
			(end -0.7874 0.4064)
			(stroke
				(width 0.1524)
				(type default)
			)
			(layer "B.SilkS")
		)
		(fp_line
			(start -0.7874 0.4064)
			(end 0.7874 0.4064)
			(stroke
				(width 0.1524)
				(type default)
			)
			(layer "B.SilkS")
		)
		(fp_line
			(start 0.7874 -0.4064)
			(end -0.7874 -0.4064)
			(stroke
				(width 0.1524)
				(type default)
			)
			(layer "B.SilkS")
		)
		(fp_line
			(start 0.7874 0.4064)
			(end 0.7874 -0.4064)
			(stroke
				(width 0.1524)
				(type default)
			)
			(layer "B.SilkS")
		)
		(fp_line
			(start -0.67945 -0.3048)
			(end -0.67945 0.3048)
			(stroke
				(width 0.1)
				(type default)
			)
			(layer "B.Fab")
		)
		(fp_line
			(start -0.67945 0.3048)
			(end -0.120396 0.3048)
			(stroke
				(width 0.1)
				(type default)
			)
			(layer "B.Fab")
		)
		(fp_line
			(start -0.12065 -0.3048)
			(end -0.67945 -0.3048)
			(stroke
				(width 0.1)
				(type default)
			)
			(layer "B.Fab")
		)
		(fp_line
			(start -0.12065 -0.2794)
			(end -0.12065 -0.3048)
			(stroke
				(width 0.1)
				(type default)
			)
			(layer "B.Fab")
		)
		(fp_line
			(start -0.120396 0.2794)
			(end 0.12065 0.2794)
			(stroke
				(width 0.1)
				(type default)
			)
			(layer "B.Fab")
		)
		(fp_line
			(start -0.120396 0.3048)
			(end -0.120396 0.2794)
			(stroke
				(width 0.1)
				(type default)
			)
			(layer "B.Fab")
		)
		(fp_line
			(start 0.12065 -0.305054)
			(end 0.12065 -0.2794)
			(stroke
				(width 0.1)
				(type default)
			)
			(layer "B.Fab")
		)
		(fp_line
			(start 0.12065 -0.2794)
			(end -0.12065 -0.2794)
			(stroke
				(width 0.1)
				(type default)
			)
			(layer "B.Fab")
		)
		(fp_line
			(start 0.12065 0.2794)
			(end 0.12065 0.3048)
			(stroke
				(width 0.1)
				(type default)
			)
			(layer "B.Fab")
		)
		(fp_line
			(start 0.12065 0.3048)
			(end 0.67945 0.3048)
			(stroke
				(width 0.1)
				(type default)
			)
			(layer "B.Fab")
		)
		(fp_line
			(start 0.67945 -0.305054)
			(end 0.12065 -0.305054)
			(stroke
				(width 0.1)
				(type default)
			)
			(layer "B.Fab")
		)
		(fp_line
			(start 0.67945 0.3048)
			(end 0.67945 -0.305054)
			(stroke
				(width 0.1)
				(type default)
			)
			(layer "B.Fab")
		)
		(pad "1" smd circle
			(at 0.40005 0 180)
			(size 0 0)
			(layers "B.Cu" "B.Mask" "B.Paste")
			(net "P12V_HSC_ADC_N")
		)
		(pad "2" smd circle
			(at -0.40005 0 180)
			(size 0 0)
			(layers "B.Cu" "B.Mask" "B.Paste")
			(net "P12V_HSC_SENSE2_R1_N")
		)
	)
	(footprint ""
		(layer "B.Cu")
		(at 351.739454 -255.84531 180)
		(property "Reference" "C2575"
			(at 0 0 0)
			(layer "B.SilkS")
			(hide yes)
			(effects
				(font
					(size 1.27 1.27)
				)
				(justify mirror)
			)
		)
		(property "Value" ""
			(at 0 0 0)
			(layer "B.Fab")
			(effects
				(font
					(size 1.27 1.27)
				)
				(justify mirror)
			)
		)
		(duplicate_pad_numbers_are_jumpers no)
		(fp_line
			(start 0.7874 0.4064)
			(end 0.7874 -0.4064)
			(stroke
				(width 0.1524)
				(type default)
			)
			(layer "B.SilkS")
		)
		(fp_line
			(start 0.7874 -0.4064)
			(end -0.7874 -0.4064)
			(stroke
				(width 0.1524)
				(type default)
			)
			(layer "B.SilkS")
		)
		(fp_line
			(start -0.7874 0.4064)
			(end 0.7874 0.4064)
			(stroke
				(width 0.1524)
				(type default)
			)
			(layer "B.SilkS")
		)
		(fp_line
			(start -0.7874 -0.4064)
			(end -0.7874 0.4064)
			(stroke
				(width 0.1524)
				(type default)
			)
			(layer "B.SilkS")
		)
		(fp_line
			(start 0.67945 0.3048)
			(end 0.67945 -0.305054)
			(stroke
				(width 0.1)
				(type default)
			)
			(layer "B.Fab")
		)
		(fp_line
			(start 0.67945 -0.305054)
			(end 0.12065 -0.305054)
			(stroke
				(width 0.1)
				(type default)
			)
			(layer "B.Fab")
		)
		(fp_line
			(start 0.12065 0.3048)
			(end 0.67945 0.3048)
			(stroke
				(width 0.1)
				(type default)
			)
			(layer "B.Fab")
		)
		(fp_line
			(start 0.12065 0.2794)
			(end 0.12065 0.3048)
			(stroke
				(width 0.1)
				(type default)
			)
			(layer "B.Fab")
		)
		(fp_line
			(start 0.12065 -0.2794)
			(end -0.12065 -0.2794)
			(stroke
				(width 0.1)
				(type default)
			)
			(layer "B.Fab")
		)
		(fp_line
			(start 0.12065 -0.305054)
			(end 0.12065 -0.2794)
			(stroke
				(width 0.1)
				(type default)
			)
			(layer "B.Fab")
		)
		(fp_line
			(start -0.120396 0.3048)
			(end -0.120396 0.2794)
			(stroke
				(width 0.1)
				(type default)
			)
			(layer "B.Fab")
		)
		(fp_line
			(start -0.120396 0.2794)
			(end 0.12065 0.2794)
			(stroke
				(width 0.1)
				(type default)
			)
			(layer "B.Fab")
		)
		(fp_line
			(start -0.12065 -0.2794)
			(end -0.12065 -0.3048)
			(stroke
				(width 0.1)
				(type default)
			)
			(layer "B.Fab")
		)
		(fp_line
			(start -0.12065 -0.3048)
			(end -0.67945 -0.3048)
			(stroke
				(width 0.1)
				(type default)
			)
			(layer "B.Fab")
		)
		(fp_line
			(start -0.67945 0.3048)
			(end -0.120396 0.3048)
			(stroke
				(width 0.1)
				(type default)
			)
			(layer "B.Fab")
		)
		(fp_line
			(start -0.67945 -0.3048)
			(end -0.67945 0.3048)
			(stroke
				(width 0.1)
				(type default)
			)
			(layer "B.Fab")
		)
		(pad "1" smd circle
			(at 0.40005 0)
			(size 0 0)
			(layers "B.Cu" "B.Mask" "B.Paste")
			(net "PVDDCR_SOC_P0")
		)
		(pad "2" smd circle
			(at -0.40005 0)
			(size 0 0)
			(layers "B.Cu" "B.Mask" "B.Paste")
			(net "GND")
		)
	)
	(footprint ""
		(layer "B.Cu")
		(at 69.861684 -390.073134 180)
		(property "Reference" "C225"
			(at 0 0 0)
			(layer "B.SilkS")
			(hide yes)
			(effects
				(font
					(size 1.27 1.27)
				)
				(justify mirror)
			)
		)
		(property "Value" ""
			(at 0 0 0)
			(layer "B.Fab")
			(effects
				(font
					(size 1.27 1.27)
				)
				(justify mirror)
			)
		)
		(duplicate_pad_numbers_are_jumpers no)
		(fp_line
			(start 1.524 0.762)
			(end 1.524 -0.762)
			(stroke
				(width 0.1524)
				(type default)
			)
			(layer "B.SilkS")
		)
		(fp_line
			(start 1.524 -0.762)
			(end -1.524 -0.762)
			(stroke
				(width 0.1524)
				(type default)
			)
			(layer "B.SilkS")
		)
		(fp_line
			(start -1.524 0.762)
			(end 1.524 0.762)
			(stroke
				(width 0.1524)
				(type default)
			)
			(layer "B.SilkS")
		)
		(fp_line
			(start -1.524 -0.762)
			(end -1.524 0.762)
			(stroke
				(width 0.1524)
				(type default)
			)
			(layer "B.SilkS")
		)
		(fp_line
			(start 1.1049 0.724916)
			(end -1.1049 0.724916)
			(stroke
				(width 0.1)
				(type default)
			)
			(layer "B.Fab")
		)
		(fp_line
			(start 1.1049 -0.724916)
			(end 1.1049 0.724916)
			(stroke
				(width 0.1)
				(type default)
			)
			(layer "B.Fab")
		)
		(fp_line
			(start -1.1049 0.724916)
			(end -1.1049 -0.724916)
			(stroke
				(width 0.1)
				(type default)
			)
			(layer "B.Fab")
		)
		(fp_line
			(start -1.1049 -0.724916)
			(end 1.1049 -0.724916)
			(stroke
				(width 0.1)
				(type default)
			)
			(layer "B.Fab")
		)
		(pad "1" smd rect
			(at 0.889 0 180)
			(size 1.016 1.27)
			(layers "B.Cu" "B.Mask" "B.Paste")
			(net "P0V9_CPU1_RT0_2A")
		)
		(pad "2" smd rect
			(at -0.889 0 180)
			(size 1.016 1.27)
			(layers "B.Cu" "B.Mask" "B.Paste")
			(net "GND")
		)
	)
	(footprint ""
		(layer "B.Cu")
		(at 104.521762 -410.3116 180)
		(property "Reference" "C98"
			(at 0 0 0)
			(layer "B.SilkS")
			(hide yes)
			(effects
				(font
					(size 1.27 1.27)
				)
				(justify mirror)
			)
		)
		(property "Value" ""
			(at 0 0 0)
			(layer "B.Fab")
			(effects
				(font
					(size 1.27 1.27)
				)
				(justify mirror)
			)
		)
		(duplicate_pad_numbers_are_jumpers no)
		(fp_line
			(start 0.7874 0.4064)
			(end 0.7874 -0.4064)
			(stroke
				(width 0.1524)
				(type default)
			)
			(layer "B.SilkS")
		)
		(fp_line
			(start 0.7874 -0.4064)
			(end -0.7874 -0.4064)
			(stroke
				(width 0.1524)
				(type default)
			)
			(layer "B.SilkS")
		)
		(fp_line
			(start -0.7874 0.4064)
			(end 0.7874 0.4064)
			(stroke
				(width 0.1524)
				(type default)
			)
			(layer "B.SilkS")
		)
		(fp_line
			(start -0.7874 -0.4064)
			(end -0.7874 0.4064)
			(stroke
				(width 0.1524)
				(type default)
			)
			(layer "B.SilkS")
		)
		(fp_line
			(start 0.67945 0.3048)
			(end 0.67945 -0.305054)
			(stroke
				(width 0.1)
				(type default)
			)
			(layer "B.Fab")
		)
		(fp_line
			(start 0.67945 -0.305054)
			(end 0.12065 -0.305054)
			(stroke
				(width 0.1)
				(type default)
			)
			(layer "B.Fab")
		)
		(fp_line
			(start 0.12065 0.3048)
			(end 0.67945 0.3048)
			(stroke
				(width 0.1)
				(type default)
			)
			(layer "B.Fab")
		)
		(fp_line
			(start 0.12065 0.2794)
			(end 0.12065 0.3048)
			(stroke
				(width 0.1)
				(type default)
			)
			(layer "B.Fab")
		)
		(fp_line
			(start 0.12065 -0.2794)
			(end -0.12065 -0.2794)
			(stroke
				(width 0.1)
				(type default)
			)
			(layer "B.Fab")
		)
		(fp_line
			(start 0.12065 -0.305054)
			(end 0.12065 -0.2794)
			(stroke
				(width 0.1)
				(type default)
			)
			(layer "B.Fab")
		)
		(fp_line
			(start -0.120396 0.3048)
			(end -0.120396 0.2794)
			(stroke
				(width 0.1)
				(type default)
			)
			(layer "B.Fab")
		)
		(fp_line
			(start -0.120396 0.2794)
			(end 0.12065 0.2794)
			(stroke
				(width 0.1)
				(type default)
			)
			(layer "B.Fab")
		)
		(fp_line
			(start -0.12065 -0.2794)
			(end -0.12065 -0.3048)
			(stroke
				(width 0.1)
				(type default)
			)
			(layer "B.Fab")
		)
		(fp_line
			(start -0.12065 -0.3048)
			(end -0.67945 -0.3048)
			(stroke
				(width 0.1)
				(type default)
			)
			(layer "B.Fab")
		)
		(fp_line
			(start -0.67945 0.3048)
			(end -0.120396 0.3048)
			(stroke
				(width 0.1)
				(type default)
			)
			(layer "B.Fab")
		)
		(fp_line
			(start -0.67945 -0.3048)
			(end -0.67945 0.3048)
			(stroke
				(width 0.1)
				(type default)
			)
			(layer "B.Fab")
		)
		(pad "1" smd circle
			(at 0.40005 0)
			(size 0 0)
			(layers "B.Cu" "B.Mask" "B.Paste")
			(net "P3V3_9ZXL045_P1_VDD")
		)
		(pad "2" smd circle
			(at -0.40005 0)
			(size 0 0)
			(layers "B.Cu" "B.Mask" "B.Paste")
			(net "GND")
		)
	)
	(footprint ""
		(layer "B.Cu")
		(at 366.288574 2.542794)
		(property "Reference" "J64"
			(at 4.258818 1.085596 270)
			(unlocked yes)
			(layer "B.SilkS")
			(effects
				(font
					(size 0.7874 0.5842)
					(thickness 0.1524)
				)
				(justify left mirror)
			)
		)
		(property "Value" ""
			(at 0 0 0)
			(layer "B.Fab")
			(effects
				(font
					(size 1.27 1.27)
				)
				(justify mirror)
			)
		)
		(duplicate_pad_numbers_are_jumpers no)
		(fp_line
			(start -1.2192 -2.06756)
			(end -1.2192 2.06756)
			(stroke
				(width 0.1524)
				(type default)
			)
			(layer "B.SilkS")
		)
		(fp_line
			(start -1.2192 2.06756)
			(end 1.2192 2.06756)
			(stroke
				(width 0.1524)
				(type default)
			)
			(layer "B.SilkS")
		)
		(fp_line
			(start 1.2192 -2.06756)
			(end -1.2192 -2.06756)
			(stroke
				(width 0.1524)
				(type default)
			)
			(layer "B.SilkS")
		)
		(fp_line
			(start 1.2192 2.06756)
			(end 1.2192 -2.06756)
			(stroke
				(width 0.1524)
				(type default)
			)
			(layer "B.SilkS")
		)
		(pad "" np_thru_hole circle
			(at -3.4671 -1.27 270)
			(size 1.0414 1.0414)
			(drill 1.0414)
			(layers "*.Cu" "*.Mask")
			(clearance 0.381)
			(thermal_gap 0.381)
		)
		(pad "" np_thru_hole circle
			(at -3.4671 1.27 270)
			(size 1.0414 1.0414)
			(drill 1.0414)
			(layers "*.Cu" "*.Mask")
			(clearance 0.381)
			(thermal_gap 0.381)
		)
		(pad "" np_thru_hole circle
			(at 2.8829 -1.27 270)
			(size 1.0414 1.0414)
			(drill 1.0414)
			(layers "*.Cu" "*.Mask")
			(clearance 0.381)
			(thermal_gap 0.381)
		)
		(pad "" np_thru_hole circle
			(at 2.8829 1.27 270)
			(size 1.0414 1.0414)
			(drill 1.0414)
			(layers "*.Cu" "*.Mask")
			(clearance 0.381)
			(thermal_gap 0.381)
		)
		(pad "1" smd rect
			(at -0.8255 -0.249936 270)
			(size 0.3048 0.508)
			(layers "B.Cu" "B.Mask" "B.Paste")
			(net "DELTA_L_85_5INCH_BOT_DP")
		)
		(pad "2" smd rect
			(at -0.8255 0.249936 270)
			(size 0.3048 0.508)
			(layers "B.Cu" "B.Mask" "B.Paste")
			(net "DELTA_L_85_5INCH_BOT_DN")
		)
		(pad "3" smd circle
			(at 0 0 180)
			(size 0 0)
			(layers "B.Cu" "B.Mask" "B.Paste")
			(net "DELTA_L_GND_1")
		)
		(zone
			(layers "F.Cu" "B.Cu" "In1.Cu" "In2.Cu" "In3.Cu" "In4.Cu" "In5.Cu" "In6.Cu"
				"In7.Cu" "In8.Cu" "In9.Cu" "In10.Cu" "In11.Cu" "In12.Cu" "In13.Cu" "In14.Cu"
				"In15.Cu" "In16.Cu"
			)
			(hatch none 0.5)
			(connect_pads
				(clearance 0)
			)
			(min_thickness 0.25)
			(keepout
				(tracks not_allowed)
				(vias allowed)
				(pads allowed)
				(copperpour not_allowed)
				(footprints allowed)
			)
			(placement
				(enabled no)
				(sheetname "")
			)
			(fill
				(thermal_gap 0.5)
				(thermal_bridge_width 0.5)
				(island_removal_mode 0)
			)
			(polygon
				(pts
					(arc
						(start 363.748574 1.272794)
						(mid 361.894374 1.272794)
						(end 363.748574 1.272794)
					)
				)
			)
		)
		(zone
			(layers "F.Cu" "B.Cu" "In1.Cu" "In2.Cu" "In3.Cu" "In4.Cu" "In5.Cu" "In6.Cu"
				"In7.Cu" "In8.Cu" "In9.Cu" "In10.Cu" "In11.Cu" "In12.Cu" "In13.Cu" "In14.Cu"
				"In15.Cu" "In16.Cu"
			)
			(hatch none 0.5)
			(connect_pads
				(clearance 0)
			)
			(min_thickness 0.25)
			(keepout
				(tracks not_allowed)
				(vias allowed)
				(pads allowed)
				(copperpour not_allowed)
				(footprints allowed)
			)
			(placement
				(enabled no)
				(sheetname "")
			)
			(fill
				(thermal_gap 0.5)
				(thermal_bridge_width 0.5)
				(island_removal_mode 0)
			)
			(polygon
				(pts
					(arc
						(start 363.748574 3.812794)
						(mid 361.894374 3.812794)
						(end 363.748574 3.812794)
					)
				)
			)
		)
		(zone
			(layers "F.Cu" "B.Cu" "In1.Cu" "In2.Cu" "In3.Cu" "In4.Cu" "In5.Cu" "In6.Cu"
				"In7.Cu" "In8.Cu" "In9.Cu" "In10.Cu" "In11.Cu" "In12.Cu" "In13.Cu" "In14.Cu"
				"In15.Cu" "In16.Cu"
			)
			(hatch none 0.5)
			(connect_pads
				(clearance 0)
			)
			(min_thickness 0.25)
			(keepout
				(tracks not_allowed)
				(vias allowed)
				(pads allowed)
				(copperpour not_allowed)
				(footprints allowed)
			)
			(placement
				(enabled no)
				(sheetname "")
			)
			(fill
				(thermal_gap 0.5)
				(thermal_bridge_width 0.5)
				(island_removal_mode 0)
			)
			(polygon
				(pts
					(arc
						(start 370.098574 1.272794)
						(mid 368.244374 1.272794)
						(end 370.098574 1.272794)
					)
				)
			)
		)
		(zone
			(layers "F.Cu" "B.Cu" "In1.Cu" "In2.Cu" "In3.Cu" "In4.Cu" "In5.Cu" "In6.Cu"
				"In7.Cu" "In8.Cu" "In9.Cu" "In10.Cu" "In11.Cu" "In12.Cu" "In13.Cu" "In14.Cu"
				"In15.Cu" "In16.Cu"
			)
			(hatch none 0.5)
			(connect_pads
				(clearance 0)
			)
			(min_thickness 0.25)
			(keepout
				(tracks not_allowed)
				(vias allowed)
				(pads allowed)
				(copperpour not_allowed)
				(footprints allowed)
			)
			(placement
				(enabled no)
				(sheetname "")
			)
			(fill
				(thermal_gap 0.5)
				(thermal_bridge_width 0.5)
				(island_removal_mode 0)
			)
			(polygon
				(pts
					(arc
						(start 370.098574 3.812794)
						(mid 368.244374 3.812794)
						(end 370.098574 3.812794)
					)
				)
			)
		)
		(zone
			(layer "B.Cu")
			(hatch none 0.5)
			(connect_pads
				(clearance 0)
			)
			(min_thickness 0.25)
			(keepout
				(tracks not_allowed)
				(vias allowed)
				(pads allowed)
				(copperpour not_allowed)
				(footprints allowed)
			)
			(placement
				(enabled no)
				(sheetname "")
			)
			(fill
				(thermal_gap 0.5)
				(thermal_bridge_width 0.5)
				(island_removal_mode 0)
			)
			(polygon
				(pts
					(xy 365.170974 1.994154) (xy 365.170974 2.089658) (xy 365.767874 2.089658) (xy 365.767874 2.496058)
					(xy 365.170974 2.496058) (xy 365.170974 2.58953) (xy 365.767874 2.58953) (xy 365.767874 2.99593)
					(xy 365.170974 2.99593) (xy 365.170974 3.091434) (xy 365.869474 3.091434) (xy 365.869474 1.994154)
				)
			)
		)
	)
	(footprint ""
		(layer "B.Cu")
		(at 287.149286 -427.37151)
		(property "Reference" "R2676"
			(at 0 0 0)
			(layer "B.SilkS")
			(hide yes)
			(effects
				(font
					(size 1.27 1.27)
				)
				(justify mirror)
			)
		)
		(property "Value" ""
			(at 0 0 0)
			(layer "B.Fab")
			(effects
				(font
					(size 1.27 1.27)
				)
				(justify mirror)
			)
		)
		(duplicate_pad_numbers_are_jumpers no)
		(fp_line
			(start -0.7874 -0.4064)
			(end -0.7874 0.4064)
			(stroke
				(width 0.1524)
				(type default)
			)
			(layer "B.SilkS")
		)
		(fp_line
			(start -0.7874 0.4064)
			(end 0.7874 0.4064)
			(stroke
				(width 0.1524)
				(type default)
			)
			(layer "B.SilkS")
		)
		(fp_line
			(start 0.7874 -0.4064)
			(end -0.7874 -0.4064)
			(stroke
				(width 0.1524)
				(type default)
			)
			(layer "B.SilkS")
		)
		(fp_line
			(start 0.7874 0.4064)
			(end 0.7874 -0.4064)
			(stroke
				(width 0.1524)
				(type default)
			)
			(layer "B.SilkS")
		)
		(fp_line
			(start -0.67945 -0.3048)
			(end -0.67945 0.3048)
			(stroke
				(width 0.1)
				(type default)
			)
			(layer "B.Fab")
		)
		(fp_line
			(start -0.67945 0.3048)
			(end -0.120396 0.3048)
			(stroke
				(width 0.1)
				(type default)
			)
			(layer "B.Fab")
		)
		(fp_line
			(start -0.12065 -0.3048)
			(end -0.67945 -0.3048)
			(stroke
				(width 0.1)
				(type default)
			)
			(layer "B.Fab")
		)
		(fp_line
			(start -0.12065 -0.2794)
			(end -0.12065 -0.3048)
			(stroke
				(width 0.1)
				(type default)
			)
			(layer "B.Fab")
		)
		(fp_line
			(start -0.120396 0.2794)
			(end 0.12065 0.2794)
			(stroke
				(width 0.1)
				(type default)
			)
			(layer "B.Fab")
		)
		(fp_line
			(start -0.120396 0.3048)
			(end -0.120396 0.2794)
			(stroke
				(width 0.1)
				(type default)
			)
			(layer "B.Fab")
		)
		(fp_line
			(start 0.12065 -0.305054)
			(end 0.12065 -0.2794)
			(stroke
				(width 0.1)
				(type default)
			)
			(layer "B.Fab")
		)
		(fp_line
			(start 0.12065 -0.2794)
			(end -0.12065 -0.2794)
			(stroke
				(width 0.1)
				(type default)
			)
			(layer "B.Fab")
		)
		(fp_line
			(start 0.12065 0.2794)
			(end 0.12065 0.3048)
			(stroke
				(width 0.1)
				(type default)
			)
			(layer "B.Fab")
		)
		(fp_line
			(start 0.12065 0.3048)
			(end 0.67945 0.3048)
			(stroke
				(width 0.1)
				(type default)
			)
			(layer "B.Fab")
		)
		(fp_line
			(start 0.67945 -0.305054)
			(end 0.12065 -0.305054)
			(stroke
				(width 0.1)
				(type default)
			)
			(layer "B.Fab")
		)
		(fp_line
			(start 0.67945 0.3048)
			(end 0.67945 -0.305054)
			(stroke
				(width 0.1)
				(type default)
			)
			(layer "B.Fab")
		)
		(pad "1" smd circle
			(at 0.40005 0 180)
			(size 0 0)
			(layers "B.Cu" "B.Mask" "B.Paste")
			(net "SMB_BMC_SWB_EN")
		)
		(pad "2" smd circle
			(at -0.40005 0 180)
			(size 0 0)
			(layers "B.Cu" "B.Mask" "B.Paste")
			(net "SMB_BMC_SWB_EN_R2")
		)
	)
	(footprint ""
		(layer "B.Cu")
		(at 377.488958 -208.530952 -90)
		(property "Reference" "R401"
			(at 0 0 90)
			(layer "B.SilkS")
			(hide yes)
			(effects
				(font
					(size 1.27 1.27)
				)
				(justify mirror)
			)
		)
		(property "Value" ""
			(at 0 0 90)
			(layer "B.Fab")
			(effects
				(font
					(size 1.27 1.27)
				)
				(justify mirror)
			)
		)
		(duplicate_pad_numbers_are_jumpers no)
		(fp_line
			(start -0.7874 0.4064)
			(end 0.7874 0.4064)
			(stroke
				(width 0.1524)
				(type default)
			)
			(layer "B.SilkS")
		)
		(fp_line
			(start 0.7874 0.4064)
			(end 0.7874 -0.4064)
			(stroke
				(width 0.1524)
				(type default)
			)
			(layer "B.SilkS")
		)
		(fp_line
			(start -0.7874 -0.4064)
			(end -0.7874 0.4064)
			(stroke
				(width 0.1524)
				(type default)
			)
			(layer "B.SilkS")
		)
		(fp_line
			(start 0.7874 -0.4064)
			(end -0.7874 -0.4064)
			(stroke
				(width 0.1524)
				(type default)
			)
			(layer "B.SilkS")
		)
		(fp_line
			(start -0.67945 0.3048)
			(end -0.120396 0.3048)
			(stroke
				(width 0.1)
				(type default)
			)
			(layer "B.Fab")
		)
		(fp_line
			(start -0.120396 0.3048)
			(end -0.120396 0.2794)
			(stroke
				(width 0.1)
				(type default)
			)
			(layer "B.Fab")
		)
		(fp_line
			(start 0.12065 0.3048)
			(end 0.67945 0.3048)
			(stroke
				(width 0.1)
				(type default)
			)
			(layer "B.Fab")
		)
		(fp_line
			(start 0.67945 0.3048)
			(end 0.67945 -0.305054)
			(stroke
				(width 0.1)
				(type default)
			)
			(layer "B.Fab")
		)
		(fp_line
			(start -0.120396 0.2794)
			(end 0.12065 0.2794)
			(stroke
				(width 0.1)
				(type default)
			)
			(layer "B.Fab")
		)
		(fp_line
			(start 0.12065 0.2794)
			(end 0.12065 0.3048)
			(stroke
				(width 0.1)
				(type default)
			)
			(layer "B.Fab")
		)
		(fp_line
			(start -0.12065 -0.2794)
			(end -0.12065 -0.3048)
			(stroke
				(width 0.1)
				(type default)
			)
			(layer "B.Fab")
		)
		(fp_line
			(start 0.12065 -0.2794)
			(end -0.12065 -0.2794)
			(stroke
				(width 0.1)
				(type default)
			)
			(layer "B.Fab")
		)
		(fp_line
			(start -0.67945 -0.3048)
			(end -0.67945 0.3048)
			(stroke
				(width 0.1)
				(type default)
			)
			(layer "B.Fab")
		)
		(fp_line
			(start -0.12065 -0.3048)
			(end -0.67945 -0.3048)
			(stroke
				(width 0.1)
				(type default)
			)
			(layer "B.Fab")
		)
		(fp_line
			(start 0.12065 -0.305054)
			(end 0.12065 -0.2794)
			(stroke
				(width 0.1)
				(type default)
			)
			(layer "B.Fab")
		)
		(fp_line
			(start 0.67945 -0.305054)
			(end 0.12065 -0.305054)
			(stroke
				(width 0.1)
				(type default)
			)
			(layer "B.Fab")
		)
		(pad "1" smd circle
			(at 0.40005 0 90)
			(size 0 0)
			(layers "B.Cu" "B.Mask" "B.Paste")
			(net "PVDD18_S5_P0")
		)
		(pad "2" smd circle
			(at -0.40005 0 90)
			(size 0 0)
			(layers "B.Cu" "B.Mask" "B.Paste")
			(net "JTAG_CPU0_TCK")
		)
	)
	(footprint ""
		(layer "B.Cu")
		(at 384.113278 -140.202158 180)
		(property "Reference" "PC462"
			(at 0 0 0)
			(layer "B.SilkS")
			(hide yes)
			(effects
				(font
					(size 1.27 1.27)
				)
				(justify mirror)
			)
		)
		(property "Value" ""
			(at 0 0 0)
			(layer "B.Fab")
			(effects
				(font
					(size 1.27 1.27)
				)
				(justify mirror)
			)
		)
		(duplicate_pad_numbers_are_jumpers no)
		(fp_line
			(start 0.7874 0.4064)
			(end 0.7874 -0.4064)
			(stroke
				(width 0.1524)
				(type default)
			)
			(layer "B.SilkS")
		)
		(fp_line
			(start 0.7874 -0.4064)
			(end -0.7874 -0.4064)
			(stroke
				(width 0.1524)
				(type default)
			)
			(layer "B.SilkS")
		)
		(fp_line
			(start -0.7874 0.4064)
			(end 0.7874 0.4064)
			(stroke
				(width 0.1524)
				(type default)
			)
			(layer "B.SilkS")
		)
		(fp_line
			(start -0.7874 -0.4064)
			(end -0.7874 0.4064)
			(stroke
				(width 0.1524)
				(type default)
			)
			(layer "B.SilkS")
		)
		(fp_line
			(start 0.67945 0.3048)
			(end 0.67945 -0.305054)
			(stroke
				(width 0.1)
				(type default)
			)
			(layer "B.Fab")
		)
		(fp_line
			(start 0.67945 -0.305054)
			(end 0.12065 -0.305054)
			(stroke
				(width 0.1)
				(type default)
			)
			(layer "B.Fab")
		)
		(fp_line
			(start 0.12065 0.3048)
			(end 0.67945 0.3048)
			(stroke
				(width 0.1)
				(type default)
			)
			(layer "B.Fab")
		)
		(fp_line
			(start 0.12065 0.2794)
			(end 0.12065 0.3048)
			(stroke
				(width 0.1)
				(type default)
			)
			(layer "B.Fab")
		)
		(fp_line
			(start 0.12065 -0.2794)
			(end -0.12065 -0.2794)
			(stroke
				(width 0.1)
				(type default)
			)
			(layer "B.Fab")
		)
		(fp_line
			(start 0.12065 -0.305054)
			(end 0.12065 -0.2794)
			(stroke
				(width 0.1)
				(type default)
			)
			(layer "B.Fab")
		)
		(fp_line
			(start -0.120396 0.3048)
			(end -0.120396 0.2794)
			(stroke
				(width 0.1)
				(type default)
			)
			(layer "B.Fab")
		)
		(fp_line
			(start -0.120396 0.2794)
			(end 0.12065 0.2794)
			(stroke
				(width 0.1)
				(type default)
			)
			(layer "B.Fab")
		)
		(fp_line
			(start -0.12065 -0.2794)
			(end -0.12065 -0.3048)
			(stroke
				(width 0.1)
				(type default)
			)
			(layer "B.Fab")
		)
		(fp_line
			(start -0.12065 -0.3048)
			(end -0.67945 -0.3048)
			(stroke
				(width 0.1)
				(type default)
			)
			(layer "B.Fab")
		)
		(fp_line
			(start -0.67945 0.3048)
			(end -0.120396 0.3048)
			(stroke
				(width 0.1)
				(type default)
			)
			(layer "B.Fab")
		)
		(fp_line
			(start -0.67945 -0.3048)
			(end -0.67945 0.3048)
			(stroke
				(width 0.1)
				(type default)
			)
			(layer "B.Fab")
		)
		(pad "1" smd circle
			(at 0.40005 0)
			(size 0 0)
			(layers "B.Cu" "B.Mask" "B.Paste")
			(net "PVDDCR_CPU0_P0_VMON")
		)
		(pad "2" smd circle
			(at -0.40005 0)
			(size 0 0)
			(layers "B.Cu" "B.Mask" "B.Paste")
			(net "GND")
		)
	)
	(footprint ""
		(layer "B.Cu")
		(at 94.488 -303.748948)
		(property "Reference" "R545"
			(at 0 0 0)
			(layer "B.SilkS")
			(hide yes)
			(effects
				(font
					(size 1.27 1.27)
				)
				(justify mirror)
			)
		)
		(property "Value" ""
			(at 0 0 0)
			(layer "B.Fab")
			(effects
				(font
					(size 1.27 1.27)
				)
				(justify mirror)
			)
		)
		(duplicate_pad_numbers_are_jumpers no)
		(fp_line
			(start -0.7874 -0.4064)
			(end -0.7874 0.4064)
			(stroke
				(width 0.1524)
				(type default)
			)
			(layer "B.SilkS")
		)
		(fp_line
			(start -0.7874 0.4064)
			(end 0.7874 0.4064)
			(stroke
				(width 0.1524)
				(type default)
			)
			(layer "B.SilkS")
		)
		(fp_line
			(start 0.7874 -0.4064)
			(end -0.7874 -0.4064)
			(stroke
				(width 0.1524)
				(type default)
			)
			(layer "B.SilkS")
		)
		(fp_line
			(start 0.7874 0.4064)
			(end 0.7874 -0.4064)
			(stroke
				(width 0.1524)
				(type default)
			)
			(layer "B.SilkS")
		)
		(fp_line
			(start -0.67945 -0.3048)
			(end -0.67945 0.3048)
			(stroke
				(width 0.1)
				(type default)
			)
			(layer "B.Fab")
		)
		(fp_line
			(start -0.67945 0.3048)
			(end -0.120396 0.3048)
			(stroke
				(width 0.1)
				(type default)
			)
			(layer "B.Fab")
		)
		(fp_line
			(start -0.12065 -0.3048)
			(end -0.67945 -0.3048)
			(stroke
				(width 0.1)
				(type default)
			)
			(layer "B.Fab")
		)
		(fp_line
			(start -0.12065 -0.2794)
			(end -0.12065 -0.3048)
			(stroke
				(width 0.1)
				(type default)
			)
			(layer "B.Fab")
		)
		(fp_line
			(start -0.120396 0.2794)
			(end 0.12065 0.2794)
			(stroke
				(width 0.1)
				(type default)
			)
			(layer "B.Fab")
		)
		(fp_line
			(start -0.120396 0.3048)
			(end -0.120396 0.2794)
			(stroke
				(width 0.1)
				(type default)
			)
			(layer "B.Fab")
		)
		(fp_line
			(start 0.12065 -0.305054)
			(end 0.12065 -0.2794)
			(stroke
				(width 0.1)
				(type default)
			)
			(layer "B.Fab")
		)
		(fp_line
			(start 0.12065 -0.2794)
			(end -0.12065 -0.2794)
			(stroke
				(width 0.1)
				(type default)
			)
			(layer "B.Fab")
		)
		(fp_line
			(start 0.12065 0.2794)
			(end 0.12065 0.3048)
			(stroke
				(width 0.1)
				(type default)
			)
			(layer "B.Fab")
		)
		(fp_line
			(start 0.12065 0.3048)
			(end 0.67945 0.3048)
			(stroke
				(width 0.1)
				(type default)
			)
			(layer "B.Fab")
		)
		(fp_line
			(start 0.67945 -0.305054)
			(end 0.12065 -0.305054)
			(stroke
				(width 0.1)
				(type default)
			)
			(layer "B.Fab")
		)
		(fp_line
			(start 0.67945 0.3048)
			(end 0.67945 -0.305054)
			(stroke
				(width 0.1)
				(type default)
			)
			(layer "B.Fab")
		)
		(pad "1" smd circle
			(at 0.40005 0 180)
			(size 0 0)
			(layers "B.Cu" "B.Mask" "B.Paste")
			(net "FM_BMC_READY_N")
		)
		(pad "2" smd circle
			(at -0.40005 0 180)
			(size 0 0)
			(layers "B.Cu" "B.Mask" "B.Paste")
			(net "PVDD18_S5_P1")
		)
	)
	(footprint ""
		(layer "B.Cu")
		(at 412.222442 -416.899344 90)
		(property "Reference" "C6624"
			(at 0 0 90)
			(layer "B.SilkS")
			(hide yes)
			(effects
				(font
					(size 1.27 1.27)
				)
				(justify mirror)
			)
		)
		(property "Value" ""
			(at 0 0 90)
			(layer "B.Fab")
			(effects
				(font
					(size 1.27 1.27)
				)
				(justify mirror)
			)
		)
		(duplicate_pad_numbers_are_jumpers no)
		(fp_line
			(start 0.299974 -0.150114)
			(end -0.299974 -0.150114)
			(stroke
				(width 0.1)
				(type default)
			)
			(layer "B.Fab")
		)
		(fp_line
			(start -0.299974 -0.150114)
			(end -0.299974 0.150114)
			(stroke
				(width 0.1)
				(type default)
			)
			(layer "B.Fab")
		)
		(fp_line
			(start 0.299974 0.150114)
			(end 0.299974 -0.150114)
			(stroke
				(width 0.1)
				(type default)
			)
			(layer "B.Fab")
		)
		(fp_line
			(start -0.299974 0.150114)
			(end 0.299974 0.150114)
			(stroke
				(width 0.1)
				(type default)
			)
			(layer "B.Fab")
		)
		(pad "1" smd rect
			(at 0.2667 0 270)
			(size 0.3048 0.381)
			(layers "B.Cu" "B.Mask" "B.Paste")
			(net "P5E_CPU0_P3_TX_BUF_C_DN<13>")
		)
		(pad "2" smd rect
			(at -0.2667 0 270)
			(size 0.3048 0.381)
			(layers "B.Cu" "B.Mask" "B.Paste")
			(net "P5E_CPU0_P3_TX_BUF_DN<13>")
		)
	)
	(footprint ""
		(layer "B.Cu")
		(at 159.018986 -390.909302 90)
		(property "Reference" "C423"
			(at 0 0 90)
			(layer "B.SilkS")
			(hide yes)
			(effects
				(font
					(size 1.27 1.27)
				)
				(justify mirror)
			)
		)
		(property "Value" ""
			(at 0 0 90)
			(layer "B.Fab")
			(effects
				(font
					(size 1.27 1.27)
				)
				(justify mirror)
			)
		)
		(duplicate_pad_numbers_are_jumpers no)
		(fp_line
			(start 0.299974 -0.150114)
			(end -0.299974 -0.150114)
			(stroke
				(width 0.1)
				(type default)
			)
			(layer "B.Fab")
		)
		(fp_line
			(start -0.299974 -0.150114)
			(end -0.299974 0.150114)
			(stroke
				(width 0.1)
				(type default)
			)
			(layer "B.Fab")
		)
		(fp_line
			(start 0.299974 0.150114)
			(end 0.299974 -0.150114)
			(stroke
				(width 0.1)
				(type default)
			)
			(layer "B.Fab")
		)
		(fp_line
			(start -0.299974 0.150114)
			(end 0.299974 0.150114)
			(stroke
				(width 0.1)
				(type default)
			)
			(layer "B.Fab")
		)
		(pad "1" smd rect
			(at 0.2667 0 270)
			(size 0.3048 0.381)
			(layers "B.Cu" "B.Mask" "B.Paste")
			(net "P0V9_CPU1_RT_2D")
		)
		(pad "2" smd rect
			(at -0.2667 0 270)
			(size 0.3048 0.381)
			(layers "B.Cu" "B.Mask" "B.Paste")
			(net "GND")
		)
	)
	(footprint ""
		(layer "B.Cu")
		(at 348.818454 -266.00531)
		(property "Reference" "C2603"
			(at 0 0 0)
			(layer "B.SilkS")
			(hide yes)
			(effects
				(font
					(size 1.27 1.27)
				)
				(justify mirror)
			)
		)
		(property "Value" ""
			(at 0 0 0)
			(layer "B.Fab")
			(effects
				(font
					(size 1.27 1.27)
				)
				(justify mirror)
			)
		)
		(duplicate_pad_numbers_are_jumpers no)
		(fp_line
			(start -0.7874 -0.4064)
			(end -0.7874 0.4064)
			(stroke
				(width 0.1524)
				(type default)
			)
			(layer "B.SilkS")
		)
		(fp_line
			(start -0.7874 0.4064)
			(end 0.7874 0.4064)
			(stroke
				(width 0.1524)
				(type default)
			)
			(layer "B.SilkS")
		)
		(fp_line
			(start 0.7874 -0.4064)
			(end -0.7874 -0.4064)
			(stroke
				(width 0.1524)
				(type default)
			)
			(layer "B.SilkS")
		)
		(fp_line
			(start 0.7874 0.4064)
			(end 0.7874 -0.4064)
			(stroke
				(width 0.1524)
				(type default)
			)
			(layer "B.SilkS")
		)
		(fp_line
			(start -0.67945 -0.3048)
			(end -0.67945 0.3048)
			(stroke
				(width 0.1)
				(type default)
			)
			(layer "B.Fab")
		)
		(fp_line
			(start -0.67945 0.3048)
			(end -0.120396 0.3048)
			(stroke
				(width 0.1)
				(type default)
			)
			(layer "B.Fab")
		)
		(fp_line
			(start -0.12065 -0.3048)
			(end -0.67945 -0.3048)
			(stroke
				(width 0.1)
				(type default)
			)
			(layer "B.Fab")
		)
		(fp_line
			(start -0.12065 -0.2794)
			(end -0.12065 -0.3048)
			(stroke
				(width 0.1)
				(type default)
			)
			(layer "B.Fab")
		)
		(fp_line
			(start -0.120396 0.2794)
			(end 0.12065 0.2794)
			(stroke
				(width 0.1)
				(type default)
			)
			(layer "B.Fab")
		)
		(fp_line
			(start -0.120396 0.3048)
			(end -0.120396 0.2794)
			(stroke
				(width 0.1)
				(type default)
			)
			(layer "B.Fab")
		)
		(fp_line
			(start 0.12065 -0.305054)
			(end 0.12065 -0.2794)
			(stroke
				(width 0.1)
				(type default)
			)
			(layer "B.Fab")
		)
		(fp_line
			(start 0.12065 -0.2794)
			(end -0.12065 -0.2794)
			(stroke
				(width 0.1)
				(type default)
			)
			(layer "B.Fab")
		)
		(fp_line
			(start 0.12065 0.2794)
			(end 0.12065 0.3048)
			(stroke
				(width 0.1)
				(type default)
			)
			(layer "B.Fab")
		)
		(fp_line
			(start 0.12065 0.3048)
			(end 0.67945 0.3048)
			(stroke
				(width 0.1)
				(type default)
			)
			(layer "B.Fab")
		)
		(fp_line
			(start 0.67945 -0.305054)
			(end 0.12065 -0.305054)
			(stroke
				(width 0.1)
				(type default)
			)
			(layer "B.Fab")
		)
		(fp_line
			(start 0.67945 0.3048)
			(end 0.67945 -0.305054)
			(stroke
				(width 0.1)
				(type default)
			)
			(layer "B.Fab")
		)
		(pad "1" smd circle
			(at 0.40005 0 180)
			(size 0 0)
			(layers "B.Cu" "B.Mask" "B.Paste")
			(net "PVDD11_S3_P0")
		)
		(pad "2" smd circle
			(at -0.40005 0 180)
			(size 0 0)
			(layers "B.Cu" "B.Mask" "B.Paste")
			(net "GND")
		)
	)
	(footprint ""
		(layer "B.Cu")
		(at 100.067872 -342.604598 -90)
		(property "Reference" "PR429"
			(at 0 0 90)
			(layer "B.SilkS")
			(hide yes)
			(effects
				(font
					(size 1.27 1.27)
				)
				(justify mirror)
			)
		)
		(property "Value" ""
			(at 0 0 90)
			(layer "B.Fab")
			(effects
				(font
					(size 1.27 1.27)
				)
				(justify mirror)
			)
		)
		(duplicate_pad_numbers_are_jumpers no)
		(fp_line
			(start -0.7874 0.4064)
			(end 0.7874 0.4064)
			(stroke
				(width 0.1524)
				(type default)
			)
			(layer "B.SilkS")
		)
		(fp_line
			(start 0.7874 0.4064)
			(end 0.7874 -0.4064)
			(stroke
				(width 0.1524)
				(type default)
			)
			(layer "B.SilkS")
		)
		(fp_line
			(start -0.7874 -0.4064)
			(end -0.7874 0.4064)
			(stroke
				(width 0.1524)
				(type default)
			)
			(layer "B.SilkS")
		)
		(fp_line
			(start 0.7874 -0.4064)
			(end -0.7874 -0.4064)
			(stroke
				(width 0.1524)
				(type default)
			)
			(layer "B.SilkS")
		)
		(fp_line
			(start -0.67945 0.3048)
			(end -0.120396 0.3048)
			(stroke
				(width 0.1)
				(type default)
			)
			(layer "B.Fab")
		)
		(fp_line
			(start -0.120396 0.3048)
			(end -0.120396 0.2794)
			(stroke
				(width 0.1)
				(type default)
			)
			(layer "B.Fab")
		)
		(fp_line
			(start 0.12065 0.3048)
			(end 0.67945 0.3048)
			(stroke
				(width 0.1)
				(type default)
			)
			(layer "B.Fab")
		)
		(fp_line
			(start 0.67945 0.3048)
			(end 0.67945 -0.305054)
			(stroke
				(width 0.1)
				(type default)
			)
			(layer "B.Fab")
		)
		(fp_line
			(start -0.120396 0.2794)
			(end 0.12065 0.2794)
			(stroke
				(width 0.1)
				(type default)
			)
			(layer "B.Fab")
		)
		(fp_line
			(start 0.12065 0.2794)
			(end 0.12065 0.3048)
			(stroke
				(width 0.1)
				(type default)
			)
			(layer "B.Fab")
		)
		(fp_line
			(start -0.12065 -0.2794)
			(end -0.12065 -0.3048)
			(stroke
				(width 0.1)
				(type default)
			)
			(layer "B.Fab")
		)
		(fp_line
			(start 0.12065 -0.2794)
			(end -0.12065 -0.2794)
			(stroke
				(width 0.1)
				(type default)
			)
			(layer "B.Fab")
		)
		(fp_line
			(start -0.67945 -0.3048)
			(end -0.67945 0.3048)
			(stroke
				(width 0.1)
				(type default)
			)
			(layer "B.Fab")
		)
		(fp_line
			(start -0.12065 -0.3048)
			(end -0.67945 -0.3048)
			(stroke
				(width 0.1)
				(type default)
			)
			(layer "B.Fab")
		)
		(fp_line
			(start 0.12065 -0.305054)
			(end 0.12065 -0.2794)
			(stroke
				(width 0.1)
				(type default)
			)
			(layer "B.Fab")
		)
		(fp_line
			(start 0.67945 -0.305054)
			(end 0.12065 -0.305054)
			(stroke
				(width 0.1)
				(type default)
			)
			(layer "B.Fab")
		)
		(pad "1" smd circle
			(at 0.40005 0 90)
			(size 0 0)
			(layers "B.Cu" "B.Mask" "B.Paste")
			(net "PVDDCR_CPU1_P1_VOS6")
		)
		(pad "2" smd circle
			(at -0.40005 0 90)
			(size 0 0)
			(layers "B.Cu" "B.Mask" "B.Paste")
			(net "PVDDCR_CPU1_P1")
		)
	)
	(footprint ""
		(layer "B.Cu")
		(at 234.644692 -422.849548 90)
		(property "Reference" "C65"
			(at 0 0 90)
			(layer "B.SilkS")
			(hide yes)
			(effects
				(font
					(size 1.27 1.27)
				)
				(justify mirror)
			)
		)
		(property "Value" ""
			(at 0 0 90)
			(layer "B.Fab")
			(effects
				(font
					(size 1.27 1.27)
				)
				(justify mirror)
			)
		)
		(duplicate_pad_numbers_are_jumpers no)
		(fp_line
			(start 0.7874 -0.4064)
			(end -0.7874 -0.4064)
			(stroke
				(width 0.1524)
				(type default)
			)
			(layer "B.SilkS")
		)
		(fp_line
			(start -0.7874 -0.4064)
			(end -0.7874 0.4064)
			(stroke
				(width 0.1524)
				(type default)
			)
			(layer "B.SilkS")
		)
		(fp_line
			(start 0.7874 0.4064)
			(end 0.7874 -0.4064)
			(stroke
				(width 0.1524)
				(type default)
			)
			(layer "B.SilkS")
		)
		(fp_line
			(start -0.7874 0.4064)
			(end 0.7874 0.4064)
			(stroke
				(width 0.1524)
				(type default)
			)
			(layer "B.SilkS")
		)
		(fp_line
			(start 0.67945 -0.305054)
			(end 0.12065 -0.305054)
			(stroke
				(width 0.1)
				(type default)
			)
			(layer "B.Fab")
		)
		(fp_line
			(start 0.12065 -0.305054)
			(end 0.12065 -0.2794)
			(stroke
				(width 0.1)
				(type default)
			)
			(layer "B.Fab")
		)
		(fp_line
			(start -0.12065 -0.3048)
			(end -0.67945 -0.3048)
			(stroke
				(width 0.1)
				(type default)
			)
			(layer "B.Fab")
		)
		(fp_line
			(start -0.67945 -0.3048)
			(end -0.67945 0.3048)
			(stroke
				(width 0.1)
				(type default)
			)
			(layer "B.Fab")
		)
		(fp_line
			(start 0.12065 -0.2794)
			(end -0.12065 -0.2794)
			(stroke
				(width 0.1)
				(type default)
			)
			(layer "B.Fab")
		)
		(fp_line
			(start -0.12065 -0.2794)
			(end -0.12065 -0.3048)
			(stroke
				(width 0.1)
				(type default)
			)
			(layer "B.Fab")
		)
		(fp_line
			(start 0.12065 0.2794)
			(end 0.12065 0.3048)
			(stroke
				(width 0.1)
				(type default)
			)
			(layer "B.Fab")
		)
		(fp_line
			(start -0.120396 0.2794)
			(end 0.12065 0.2794)
			(stroke
				(width 0.1)
				(type default)
			)
			(layer "B.Fab")
		)
		(fp_line
			(start 0.67945 0.3048)
			(end 0.67945 -0.305054)
			(stroke
				(width 0.1)
				(type default)
			)
			(layer "B.Fab")
		)
		(fp_line
			(start 0.12065 0.3048)
			(end 0.67945 0.3048)
			(stroke
				(width 0.1)
				(type default)
			)
			(layer "B.Fab")
		)
		(fp_line
			(start -0.120396 0.3048)
			(end -0.120396 0.2794)
			(stroke
				(width 0.1)
				(type default)
			)
			(layer "B.Fab")
		)
		(fp_line
			(start -0.67945 0.3048)
			(end -0.120396 0.3048)
			(stroke
				(width 0.1)
				(type default)
			)
			(layer "B.Fab")
		)
		(pad "1" smd circle
			(at 0.40005 0 270)
			(size 0 0)
			(layers "B.Cu" "B.Mask" "B.Paste")
			(net "HPDB_HSC_PWRGD_R")
		)
		(pad "2" smd circle
			(at -0.40005 0 270)
			(size 0 0)
			(layers "B.Cu" "B.Mask" "B.Paste")
			(net "GND")
		)
	)
	(footprint ""
		(layer "B.Cu")
		(at 184.061608 -126.833376 90)
		(property "Reference" "R1281"
			(at 0 0 90)
			(layer "B.SilkS")
			(hide yes)
			(effects
				(font
					(size 1.27 1.27)
				)
				(justify mirror)
			)
		)
		(property "Value" ""
			(at 0 0 90)
			(layer "B.Fab")
			(effects
				(font
					(size 1.27 1.27)
				)
				(justify mirror)
			)
		)
		(duplicate_pad_numbers_are_jumpers no)
		(fp_line
			(start 0.7874 -0.4064)
			(end -0.7874 -0.4064)
			(stroke
				(width 0.1524)
				(type default)
			)
			(layer "B.SilkS")
		)
		(fp_line
			(start -0.7874 -0.4064)
			(end -0.7874 0.4064)
			(stroke
				(width 0.1524)
				(type default)
			)
			(layer "B.SilkS")
		)
		(fp_line
			(start 0.7874 0.4064)
			(end 0.7874 -0.4064)
			(stroke
				(width 0.1524)
				(type default)
			)
			(layer "B.SilkS")
		)
		(fp_line
			(start -0.7874 0.4064)
			(end 0.7874 0.4064)
			(stroke
				(width 0.1524)
				(type default)
			)
			(layer "B.SilkS")
		)
		(fp_line
			(start 0.67945 -0.305054)
			(end 0.12065 -0.305054)
			(stroke
				(width 0.1)
				(type default)
			)
			(layer "B.Fab")
		)
		(fp_line
			(start 0.12065 -0.305054)
			(end 0.12065 -0.2794)
			(stroke
				(width 0.1)
				(type default)
			)
			(layer "B.Fab")
		)
		(fp_line
			(start -0.12065 -0.3048)
			(end -0.67945 -0.3048)
			(stroke
				(width 0.1)
				(type default)
			)
			(layer "B.Fab")
		)
		(fp_line
			(start -0.67945 -0.3048)
			(end -0.67945 0.3048)
			(stroke
				(width 0.1)
				(type default)
			)
			(layer "B.Fab")
		)
		(fp_line
			(start 0.12065 -0.2794)
			(end -0.12065 -0.2794)
			(stroke
				(width 0.1)
				(type default)
			)
			(layer "B.Fab")
		)
		(fp_line
			(start -0.12065 -0.2794)
			(end -0.12065 -0.3048)
			(stroke
				(width 0.1)
				(type default)
			)
			(layer "B.Fab")
		)
		(fp_line
			(start 0.12065 0.2794)
			(end 0.12065 0.3048)
			(stroke
				(width 0.1)
				(type default)
			)
			(layer "B.Fab")
		)
		(fp_line
			(start -0.120396 0.2794)
			(end 0.12065 0.2794)
			(stroke
				(width 0.1)
				(type default)
			)
			(layer "B.Fab")
		)
		(fp_line
			(start 0.67945 0.3048)
			(end 0.67945 -0.305054)
			(stroke
				(width 0.1)
				(type default)
			)
			(layer "B.Fab")
		)
		(fp_line
			(start 0.12065 0.3048)
			(end 0.67945 0.3048)
			(stroke
				(width 0.1)
				(type default)
			)
			(layer "B.Fab")
		)
		(fp_line
			(start -0.120396 0.3048)
			(end -0.120396 0.2794)
			(stroke
				(width 0.1)
				(type default)
			)
			(layer "B.Fab")
		)
		(fp_line
			(start -0.67945 0.3048)
			(end -0.120396 0.3048)
			(stroke
				(width 0.1)
				(type default)
			)
			(layer "B.Fab")
		)
		(pad "1" smd circle
			(at 0.40005 0 270)
			(size 0 0)
			(layers "B.Cu" "B.Mask" "B.Paste")
			(net "FM_P0_PCC1_N")
		)
		(pad "2" smd circle
			(at -0.40005 0 270)
			(size 0 0)
			(layers "B.Cu" "B.Mask" "B.Paste")
			(net "FM_P0_PCC1_R_N")
		)
	)
	(footprint ""
		(layer "B.Cu")
		(at 390.51738 -396.150592 180)
		(property "Reference" "C1047"
			(at 0 0 0)
			(layer "B.SilkS")
			(hide yes)
			(effects
				(font
					(size 1.27 1.27)
				)
				(justify mirror)
			)
		)
		(property "Value" ""
			(at 0 0 0)
			(layer "B.Fab")
			(effects
				(font
					(size 1.27 1.27)
				)
				(justify mirror)
			)
		)
		(duplicate_pad_numbers_are_jumpers no)
		(fp_line
			(start 0.299974 0.150114)
			(end 0.299974 -0.150114)
			(stroke
				(width 0.1)
				(type default)
			)
			(layer "B.Fab")
		)
		(fp_line
			(start 0.299974 -0.150114)
			(end -0.299974 -0.150114)
			(stroke
				(width 0.1)
				(type default)
			)
			(layer "B.Fab")
		)
		(fp_line
			(start -0.299974 0.150114)
			(end 0.299974 0.150114)
			(stroke
				(width 0.1)
				(type default)
			)
			(layer "B.Fab")
		)
		(fp_line
			(start -0.299974 -0.150114)
			(end -0.299974 0.150114)
			(stroke
				(width 0.1)
				(type default)
			)
			(layer "B.Fab")
		)
		(pad "1" smd rect
			(at 0.2667 0)
			(size 0.3048 0.381)
			(layers "B.Cu" "B.Mask" "B.Paste")
			(net "P0V9_CPU0_RT3_2A")
		)
		(pad "2" smd rect
			(at -0.2667 0)
			(size 0.3048 0.381)
			(layers "B.Cu" "B.Mask" "B.Paste")
			(net "GND")
		)
	)
	(footprint ""
		(layer "B.Cu")
		(at 346.700856 -161.263076 -90)
		(property "Reference" "PC158_6"
			(at 0 0 90)
			(layer "B.SilkS")
			(hide yes)
			(effects
				(font
					(size 1.27 1.27)
				)
				(justify mirror)
			)
		)
		(property "Value" ""
			(at 0 0 90)
			(layer "B.Fab")
			(effects
				(font
					(size 1.27 1.27)
				)
				(justify mirror)
			)
		)
		(duplicate_pad_numbers_are_jumpers no)
		(fp_line
			(start -1.524 0.762)
			(end 1.524 0.762)
			(stroke
				(width 0.1524)
				(type default)
			)
			(layer "B.SilkS")
		)
		(fp_line
			(start 1.524 0.762)
			(end 1.524 -0.762)
			(stroke
				(width 0.1524)
				(type default)
			)
			(layer "B.SilkS")
		)
		(fp_line
			(start -1.524 -0.762)
			(end -1.524 0.762)
			(stroke
				(width 0.1524)
				(type default)
			)
			(layer "B.SilkS")
		)
		(fp_line
			(start 1.524 -0.762)
			(end -1.524 -0.762)
			(stroke
				(width 0.1524)
				(type default)
			)
			(layer "B.SilkS")
		)
		(fp_line
			(start -1.1049 0.724916)
			(end -1.1049 -0.724916)
			(stroke
				(width 0.1)
				(type default)
			)
			(layer "B.Fab")
		)
		(fp_line
			(start 1.1049 0.724916)
			(end -1.1049 0.724916)
			(stroke
				(width 0.1)
				(type default)
			)
			(layer "B.Fab")
		)
		(fp_line
			(start -1.1049 -0.724916)
			(end 1.1049 -0.724916)
			(stroke
				(width 0.1)
				(type default)
			)
			(layer "B.Fab")
		)
		(fp_line
			(start 1.1049 -0.724916)
			(end 1.1049 0.724916)
			(stroke
				(width 0.1)
				(type default)
			)
			(layer "B.Fab")
		)
		(pad "1" smd rect
			(at 0.889 0 270)
			(size 1.016 1.27)
			(layers "B.Cu" "B.Mask" "B.Paste")
			(net "SW_P12V_AUX_PVDDCR_CPU0_P0_FLT")
		)
		(pad "2" smd rect
			(at -0.889 0 270)
			(size 1.016 1.27)
			(layers "B.Cu" "B.Mask" "B.Paste")
			(net "GND")
		)
	)
	(footprint ""
		(layer "B.Cu")
		(at 110.365794 -384.66268 180)
		(property "Reference" "R921"
			(at 0 0 0)
			(layer "B.SilkS")
			(hide yes)
			(effects
				(font
					(size 1.27 1.27)
				)
				(justify mirror)
			)
		)
		(property "Value" ""
			(at 0 0 0)
			(layer "B.Fab")
			(effects
				(font
					(size 1.27 1.27)
				)
				(justify mirror)
			)
		)
		(duplicate_pad_numbers_are_jumpers no)
		(fp_line
			(start 0.32512 0.175006)
			(end 0.32512 -0.175006)
			(stroke
				(width 0.1)
				(type default)
			)
			(layer "B.Fab")
		)
		(fp_line
			(start 0.32512 -0.175006)
			(end -0.32512 -0.175006)
			(stroke
				(width 0.1)
				(type default)
			)
			(layer "B.Fab")
		)
		(fp_line
			(start -0.32512 0.175006)
			(end 0.32512 0.175006)
			(stroke
				(width 0.1)
				(type default)
			)
			(layer "B.Fab")
		)
		(fp_line
			(start -0.32512 -0.175006)
			(end -0.32512 0.175006)
			(stroke
				(width 0.1)
				(type default)
			)
			(layer "B.Fab")
		)
		(pad "1" smd rect
			(at 0.2667 0)
			(size 0.3048 0.381)
			(layers "B.Cu" "B.Mask" "B.Paste")
			(net "TEST1_RT_CPU1_P3")
		)
		(pad "2" smd rect
			(at -0.2667 0 180)
			(size 0.3048 0.381)
			(layers "B.Cu" "B.Mask" "B.Paste")
			(net "GND")
		)
	)
	(footprint ""
		(layer "B.Cu")
		(at 182.753 -100.294948 90)
		(property "Reference" "R81"
			(at 0 0 90)
			(layer "B.SilkS")
			(hide yes)
			(effects
				(font
					(size 1.27 1.27)
				)
				(justify mirror)
			)
		)
		(property "Value" ""
			(at 0 0 90)
			(layer "B.Fab")
			(effects
				(font
					(size 1.27 1.27)
				)
				(justify mirror)
			)
		)
		(duplicate_pad_numbers_are_jumpers no)
		(fp_line
			(start 0.7874 -0.4064)
			(end -0.7874 -0.4064)
			(stroke
				(width 0.1524)
				(type default)
			)
			(layer "B.SilkS")
		)
		(fp_line
			(start -0.7874 -0.4064)
			(end -0.7874 0.4064)
			(stroke
				(width 0.1524)
				(type default)
			)
			(layer "B.SilkS")
		)
		(fp_line
			(start 0.7874 0.4064)
			(end 0.7874 -0.4064)
			(stroke
				(width 0.1524)
				(type default)
			)
			(layer "B.SilkS")
		)
		(fp_line
			(start -0.7874 0.4064)
			(end 0.7874 0.4064)
			(stroke
				(width 0.1524)
				(type default)
			)
			(layer "B.SilkS")
		)
		(fp_line
			(start 0.67945 -0.305054)
			(end 0.12065 -0.305054)
			(stroke
				(width 0.1)
				(type default)
			)
			(layer "B.Fab")
		)
		(fp_line
			(start 0.12065 -0.305054)
			(end 0.12065 -0.2794)
			(stroke
				(width 0.1)
				(type default)
			)
			(layer "B.Fab")
		)
		(fp_line
			(start -0.12065 -0.3048)
			(end -0.67945 -0.3048)
			(stroke
				(width 0.1)
				(type default)
			)
			(layer "B.Fab")
		)
		(fp_line
			(start -0.67945 -0.3048)
			(end -0.67945 0.3048)
			(stroke
				(width 0.1)
				(type default)
			)
			(layer "B.Fab")
		)
		(fp_line
			(start 0.12065 -0.2794)
			(end -0.12065 -0.2794)
			(stroke
				(width 0.1)
				(type default)
			)
			(layer "B.Fab")
		)
		(fp_line
			(start -0.12065 -0.2794)
			(end -0.12065 -0.3048)
			(stroke
				(width 0.1)
				(type default)
			)
			(layer "B.Fab")
		)
		(fp_line
			(start 0.12065 0.2794)
			(end 0.12065 0.3048)
			(stroke
				(width 0.1)
				(type default)
			)
			(layer "B.Fab")
		)
		(fp_line
			(start -0.120396 0.2794)
			(end 0.12065 0.2794)
			(stroke
				(width 0.1)
				(type default)
			)
			(layer "B.Fab")
		)
		(fp_line
			(start 0.67945 0.3048)
			(end 0.67945 -0.305054)
			(stroke
				(width 0.1)
				(type default)
			)
			(layer "B.Fab")
		)
		(fp_line
			(start 0.12065 0.3048)
			(end 0.67945 0.3048)
			(stroke
				(width 0.1)
				(type default)
			)
			(layer "B.Fab")
		)
		(fp_line
			(start -0.120396 0.3048)
			(end -0.120396 0.2794)
			(stroke
				(width 0.1)
				(type default)
			)
			(layer "B.Fab")
		)
		(fp_line
			(start -0.67945 0.3048)
			(end -0.120396 0.3048)
			(stroke
				(width 0.1)
				(type default)
			)
			(layer "B.Fab")
		)
		(pad "1" smd circle
			(at 0.40005 0 270)
			(size 0 0)
			(layers "B.Cu" "B.Mask" "B.Paste")
			(net "FM_INT_CPU0_HP_UBM_R_N")
		)
		(pad "2" smd circle
			(at -0.40005 0 270)
			(size 0 0)
			(layers "B.Cu" "B.Mask" "B.Paste")
			(net "FM_INT_CPU0_HP_UBM_N")
		)
	)
	(footprint ""
		(layer "B.Cu")
		(at 159.285686 -408.517344 90)
		(property "Reference" "C6754"
			(at 0 0 90)
			(layer "B.SilkS")
			(hide yes)
			(effects
				(font
					(size 1.27 1.27)
				)
				(justify mirror)
			)
		)
		(property "Value" ""
			(at 0 0 90)
			(layer "B.Fab")
			(effects
				(font
					(size 1.27 1.27)
				)
				(justify mirror)
			)
		)
		(duplicate_pad_numbers_are_jumpers no)
		(fp_line
			(start 0.299974 -0.150114)
			(end -0.299974 -0.150114)
			(stroke
				(width 0.1)
				(type default)
			)
			(layer "B.Fab")
		)
		(fp_line
			(start -0.299974 -0.150114)
			(end -0.299974 0.150114)
			(stroke
				(width 0.1)
				(type default)
			)
			(layer "B.Fab")
		)
		(fp_line
			(start 0.299974 0.150114)
			(end 0.299974 -0.150114)
			(stroke
				(width 0.1)
				(type default)
			)
			(layer "B.Fab")
		)
		(fp_line
			(start -0.299974 0.150114)
			(end 0.299974 0.150114)
			(stroke
				(width 0.1)
				(type default)
			)
			(layer "B.Fab")
		)
		(pad "1" smd rect
			(at 0.2667 0 270)
			(size 0.3048 0.381)
			(layers "B.Cu" "B.Mask" "B.Paste")
			(net "P5E_CPU1_P3_TX_BUF_C_DN<14>")
		)
		(pad "2" smd rect
			(at -0.2667 0 270)
			(size 0.3048 0.381)
			(layers "B.Cu" "B.Mask" "B.Paste")
			(net "P5E_CPU1_P3_TX_BUF_DN<14>")
		)
	)
	(footprint ""
		(layer "B.Cu")
		(at 243.713 -326.898 180)
		(property "Reference" "R1227"
			(at 0 0 0)
			(layer "B.SilkS")
			(hide yes)
			(effects
				(font
					(size 1.27 1.27)
				)
				(justify mirror)
			)
		)
		(property "Value" ""
			(at 0 0 0)
			(layer "B.Fab")
			(effects
				(font
					(size 1.27 1.27)
				)
				(justify mirror)
			)
		)
		(duplicate_pad_numbers_are_jumpers no)
		(fp_line
			(start 0.7874 0.4064)
			(end 0.7874 -0.4064)
			(stroke
				(width 0.1524)
				(type default)
			)
			(layer "B.SilkS")
		)
		(fp_line
			(start 0.7874 -0.4064)
			(end -0.7874 -0.4064)
			(stroke
				(width 0.1524)
				(type default)
			)
			(layer "B.SilkS")
		)
		(fp_line
			(start -0.7874 0.4064)
			(end 0.7874 0.4064)
			(stroke
				(width 0.1524)
				(type default)
			)
			(layer "B.SilkS")
		)
		(fp_line
			(start -0.7874 -0.4064)
			(end -0.7874 0.4064)
			(stroke
				(width 0.1524)
				(type default)
			)
			(layer "B.SilkS")
		)
		(fp_line
			(start 0.67945 0.3048)
			(end 0.67945 -0.305054)
			(stroke
				(width 0.1)
				(type default)
			)
			(layer "B.Fab")
		)
		(fp_line
			(start 0.67945 -0.305054)
			(end 0.12065 -0.305054)
			(stroke
				(width 0.1)
				(type default)
			)
			(layer "B.Fab")
		)
		(fp_line
			(start 0.12065 0.3048)
			(end 0.67945 0.3048)
			(stroke
				(width 0.1)
				(type default)
			)
			(layer "B.Fab")
		)
		(fp_line
			(start 0.12065 0.2794)
			(end 0.12065 0.3048)
			(stroke
				(width 0.1)
				(type default)
			)
			(layer "B.Fab")
		)
		(fp_line
			(start 0.12065 -0.2794)
			(end -0.12065 -0.2794)
			(stroke
				(width 0.1)
				(type default)
			)
			(layer "B.Fab")
		)
		(fp_line
			(start 0.12065 -0.305054)
			(end 0.12065 -0.2794)
			(stroke
				(width 0.1)
				(type default)
			)
			(layer "B.Fab")
		)
		(fp_line
			(start -0.120396 0.3048)
			(end -0.120396 0.2794)
			(stroke
				(width 0.1)
				(type default)
			)
			(layer "B.Fab")
		)
		(fp_line
			(start -0.120396 0.2794)
			(end 0.12065 0.2794)
			(stroke
				(width 0.1)
				(type default)
			)
			(layer "B.Fab")
		)
		(fp_line
			(start -0.12065 -0.2794)
			(end -0.12065 -0.3048)
			(stroke
				(width 0.1)
				(type default)
			)
			(layer "B.Fab")
		)
		(fp_line
			(start -0.12065 -0.3048)
			(end -0.67945 -0.3048)
			(stroke
				(width 0.1)
				(type default)
			)
			(layer "B.Fab")
		)
		(fp_line
			(start -0.67945 0.3048)
			(end -0.120396 0.3048)
			(stroke
				(width 0.1)
				(type default)
			)
			(layer "B.Fab")
		)
		(fp_line
			(start -0.67945 -0.3048)
			(end -0.67945 0.3048)
			(stroke
				(width 0.1)
				(type default)
			)
			(layer "B.Fab")
		)
		(pad "1" smd circle
			(at 0.40005 0)
			(size 0 0)
			(layers "B.Cu" "B.Mask" "B.Paste")
			(net "SMB_ADC_SDA_R")
		)
		(pad "2" smd circle
			(at -0.40005 0)
			(size 0 0)
			(layers "B.Cu" "B.Mask" "B.Paste")
			(net "SMB_SEN_MAM_2_3V3AUX_SDA")
		)
	)
	(footprint ""
		(layer "B.Cu")
		(at 365.835692 -257.455162)
		(property "Reference" "C2587"
			(at 0 0 0)
			(layer "B.SilkS")
			(hide yes)
			(effects
				(font
					(size 1.27 1.27)
				)
				(justify mirror)
			)
		)
		(property "Value" ""
			(at 0 0 0)
			(layer "B.Fab")
			(effects
				(font
					(size 1.27 1.27)
				)
				(justify mirror)
			)
		)
		(duplicate_pad_numbers_are_jumpers no)
		(fp_line
			(start -0.7874 -0.4064)
			(end -0.7874 0.4064)
			(stroke
				(width 0.1524)
				(type default)
			)
			(layer "B.SilkS")
		)
		(fp_line
			(start -0.7874 0.4064)
			(end 0.7874 0.4064)
			(stroke
				(width 0.1524)
				(type default)
			)
			(layer "B.SilkS")
		)
		(fp_line
			(start 0.7874 -0.4064)
			(end -0.7874 -0.4064)
			(stroke
				(width 0.1524)
				(type default)
			)
			(layer "B.SilkS")
		)
		(fp_line
			(start 0.7874 0.4064)
			(end 0.7874 -0.4064)
			(stroke
				(width 0.1524)
				(type default)
			)
			(layer "B.SilkS")
		)
		(fp_line
			(start -0.67945 -0.3048)
			(end -0.67945 0.3048)
			(stroke
				(width 0.1)
				(type default)
			)
			(layer "B.Fab")
		)
		(fp_line
			(start -0.67945 0.3048)
			(end -0.120396 0.3048)
			(stroke
				(width 0.1)
				(type default)
			)
			(layer "B.Fab")
		)
		(fp_line
			(start -0.12065 -0.3048)
			(end -0.67945 -0.3048)
			(stroke
				(width 0.1)
				(type default)
			)
			(layer "B.Fab")
		)
		(fp_line
			(start -0.12065 -0.2794)
			(end -0.12065 -0.3048)
			(stroke
				(width 0.1)
				(type default)
			)
			(layer "B.Fab")
		)
		(fp_line
			(start -0.120396 0.2794)
			(end 0.12065 0.2794)
			(stroke
				(width 0.1)
				(type default)
			)
			(layer "B.Fab")
		)
		(fp_line
			(start -0.120396 0.3048)
			(end -0.120396 0.2794)
			(stroke
				(width 0.1)
				(type default)
			)
			(layer "B.Fab")
		)
		(fp_line
			(start 0.12065 -0.305054)
			(end 0.12065 -0.2794)
			(stroke
				(width 0.1)
				(type default)
			)
			(layer "B.Fab")
		)
		(fp_line
			(start 0.12065 -0.2794)
			(end -0.12065 -0.2794)
			(stroke
				(width 0.1)
				(type default)
			)
			(layer "B.Fab")
		)
		(fp_line
			(start 0.12065 0.2794)
			(end 0.12065 0.3048)
			(stroke
				(width 0.1)
				(type default)
			)
			(layer "B.Fab")
		)
		(fp_line
			(start 0.12065 0.3048)
			(end 0.67945 0.3048)
			(stroke
				(width 0.1)
				(type default)
			)
			(layer "B.Fab")
		)
		(fp_line
			(start 0.67945 -0.305054)
			(end 0.12065 -0.305054)
			(stroke
				(width 0.1)
				(type default)
			)
			(layer "B.Fab")
		)
		(fp_line
			(start 0.67945 0.3048)
			(end 0.67945 -0.305054)
			(stroke
				(width 0.1)
				(type default)
			)
			(layer "B.Fab")
		)
		(pad "1" smd circle
			(at 0.40005 0 180)
			(size 0 0)
			(layers "B.Cu" "B.Mask" "B.Paste")
			(net "PVDDCR_SOC_P0")
		)
		(pad "2" smd circle
			(at -0.40005 0 180)
			(size 0 0)
			(layers "B.Cu" "B.Mask" "B.Paste")
			(net "GND")
		)
	)
	(footprint ""
		(layer "B.Cu")
		(at 121.452386 -264.354564)
		(property "Reference" "C2114"
			(at 0 0 0)
			(layer "B.SilkS")
			(hide yes)
			(effects
				(font
					(size 1.27 1.27)
				)
				(justify mirror)
			)
		)
		(property "Value" ""
			(at 0 0 0)
			(layer "B.Fab")
			(effects
				(font
					(size 1.27 1.27)
				)
				(justify mirror)
			)
		)
		(duplicate_pad_numbers_are_jumpers no)
		(fp_line
			(start -0.7874 -0.4064)
			(end -0.7874 0.4064)
			(stroke
				(width 0.1524)
				(type default)
			)
			(layer "B.SilkS")
		)
		(fp_line
			(start -0.7874 0.4064)
			(end 0.7874 0.4064)
			(stroke
				(width 0.1524)
				(type default)
			)
			(layer "B.SilkS")
		)
		(fp_line
			(start 0.7874 -0.4064)
			(end -0.7874 -0.4064)
			(stroke
				(width 0.1524)
				(type default)
			)
			(layer "B.SilkS")
		)
		(fp_line
			(start 0.7874 0.4064)
			(end 0.7874 -0.4064)
			(stroke
				(width 0.1524)
				(type default)
			)
			(layer "B.SilkS")
		)
		(fp_line
			(start -0.67945 -0.3048)
			(end -0.67945 0.3048)
			(stroke
				(width 0.1)
				(type default)
			)
			(layer "B.Fab")
		)
		(fp_line
			(start -0.67945 0.3048)
			(end -0.120396 0.3048)
			(stroke
				(width 0.1)
				(type default)
			)
			(layer "B.Fab")
		)
		(fp_line
			(start -0.12065 -0.3048)
			(end -0.67945 -0.3048)
			(stroke
				(width 0.1)
				(type default)
			)
			(layer "B.Fab")
		)
		(fp_line
			(start -0.12065 -0.2794)
			(end -0.12065 -0.3048)
			(stroke
				(width 0.1)
				(type default)
			)
			(layer "B.Fab")
		)
		(fp_line
			(start -0.120396 0.2794)
			(end 0.12065 0.2794)
			(stroke
				(width 0.1)
				(type default)
			)
			(layer "B.Fab")
		)
		(fp_line
			(start -0.120396 0.3048)
			(end -0.120396 0.2794)
			(stroke
				(width 0.1)
				(type default)
			)
			(layer "B.Fab")
		)
		(fp_line
			(start 0.12065 -0.305054)
			(end 0.12065 -0.2794)
			(stroke
				(width 0.1)
				(type default)
			)
			(layer "B.Fab")
		)
		(fp_line
			(start 0.12065 -0.2794)
			(end -0.12065 -0.2794)
			(stroke
				(width 0.1)
				(type default)
			)
			(layer "B.Fab")
		)
		(fp_line
			(start 0.12065 0.2794)
			(end 0.12065 0.3048)
			(stroke
				(width 0.1)
				(type default)
			)
			(layer "B.Fab")
		)
		(fp_line
			(start 0.12065 0.3048)
			(end 0.67945 0.3048)
			(stroke
				(width 0.1)
				(type default)
			)
			(layer "B.Fab")
		)
		(fp_line
			(start 0.67945 -0.305054)
			(end 0.12065 -0.305054)
			(stroke
				(width 0.1)
				(type default)
			)
			(layer "B.Fab")
		)
		(fp_line
			(start 0.67945 0.3048)
			(end 0.67945 -0.305054)
			(stroke
				(width 0.1)
				(type default)
			)
			(layer "B.Fab")
		)
		(pad "1" smd circle
			(at 0.40005 0 180)
			(size 0 0)
			(layers "B.Cu" "B.Mask" "B.Paste")
			(net "PVDD11_S3_P1")
		)
		(pad "2" smd circle
			(at -0.40005 0 180)
			(size 0 0)
			(layers "B.Cu" "B.Mask" "B.Paste")
			(net "GND")
		)
	)
	(footprint ""
		(layer "B.Cu")
		(at 371.297454 -264.35431)
		(property "Reference" "C2651"
			(at 0 0 0)
			(layer "B.SilkS")
			(hide yes)
			(effects
				(font
					(size 1.27 1.27)
				)
				(justify mirror)
			)
		)
		(property "Value" ""
			(at 0 0 0)
			(layer "B.Fab")
			(effects
				(font
					(size 1.27 1.27)
				)
				(justify mirror)
			)
		)
		(duplicate_pad_numbers_are_jumpers no)
		(fp_line
			(start -0.7874 -0.4064)
			(end -0.7874 0.4064)
			(stroke
				(width 0.1524)
				(type default)
			)
			(layer "B.SilkS")
		)
		(fp_line
			(start -0.7874 0.4064)
			(end 0.7874 0.4064)
			(stroke
				(width 0.1524)
				(type default)
			)
			(layer "B.SilkS")
		)
		(fp_line
			(start 0.7874 -0.4064)
			(end -0.7874 -0.4064)
			(stroke
				(width 0.1524)
				(type default)
			)
			(layer "B.SilkS")
		)
		(fp_line
			(start 0.7874 0.4064)
			(end 0.7874 -0.4064)
			(stroke
				(width 0.1524)
				(type default)
			)
			(layer "B.SilkS")
		)
		(fp_line
			(start -0.67945 -0.3048)
			(end -0.67945 0.3048)
			(stroke
				(width 0.1)
				(type default)
			)
			(layer "B.Fab")
		)
		(fp_line
			(start -0.67945 0.3048)
			(end -0.120396 0.3048)
			(stroke
				(width 0.1)
				(type default)
			)
			(layer "B.Fab")
		)
		(fp_line
			(start -0.12065 -0.3048)
			(end -0.67945 -0.3048)
			(stroke
				(width 0.1)
				(type default)
			)
			(layer "B.Fab")
		)
		(fp_line
			(start -0.12065 -0.2794)
			(end -0.12065 -0.3048)
			(stroke
				(width 0.1)
				(type default)
			)
			(layer "B.Fab")
		)
		(fp_line
			(start -0.120396 0.2794)
			(end 0.12065 0.2794)
			(stroke
				(width 0.1)
				(type default)
			)
			(layer "B.Fab")
		)
		(fp_line
			(start -0.120396 0.3048)
			(end -0.120396 0.2794)
			(stroke
				(width 0.1)
				(type default)
			)
			(layer "B.Fab")
		)
		(fp_line
			(start 0.12065 -0.305054)
			(end 0.12065 -0.2794)
			(stroke
				(width 0.1)
				(type default)
			)
			(layer "B.Fab")
		)
		(fp_line
			(start 0.12065 -0.2794)
			(end -0.12065 -0.2794)
			(stroke
				(width 0.1)
				(type default)
			)
			(layer "B.Fab")
		)
		(fp_line
			(start 0.12065 0.2794)
			(end 0.12065 0.3048)
			(stroke
				(width 0.1)
				(type default)
			)
			(layer "B.Fab")
		)
		(fp_line
			(start 0.12065 0.3048)
			(end 0.67945 0.3048)
			(stroke
				(width 0.1)
				(type default)
			)
			(layer "B.Fab")
		)
		(fp_line
			(start 0.67945 -0.305054)
			(end 0.12065 -0.305054)
			(stroke
				(width 0.1)
				(type default)
			)
			(layer "B.Fab")
		)
		(fp_line
			(start 0.67945 0.3048)
			(end 0.67945 -0.305054)
			(stroke
				(width 0.1)
				(type default)
			)
			(layer "B.Fab")
		)
		(pad "1" smd circle
			(at 0.40005 0 180)
			(size 0 0)
			(layers "B.Cu" "B.Mask" "B.Paste")
			(net "PVDD11_S3_P0")
		)
		(pad "2" smd circle
			(at -0.40005 0 180)
			(size 0 0)
			(layers "B.Cu" "B.Mask" "B.Paste")
			(net "GND")
		)
	)
	(footprint ""
		(layer "B.Cu")
		(at 295.724072 -192.660016 180)
		(property "Reference" "C145"
			(at 0 0 0)
			(layer "B.SilkS")
			(hide yes)
			(effects
				(font
					(size 1.27 1.27)
				)
				(justify mirror)
			)
		)
		(property "Value" ""
			(at 0 0 0)
			(layer "B.Fab")
			(effects
				(font
					(size 1.27 1.27)
				)
				(justify mirror)
			)
		)
		(duplicate_pad_numbers_are_jumpers no)
		(fp_line
			(start 1.524 0.762)
			(end 1.524 -0.762)
			(stroke
				(width 0.1524)
				(type default)
			)
			(layer "B.SilkS")
		)
		(fp_line
			(start 1.524 -0.762)
			(end -1.524 -0.762)
			(stroke
				(width 0.1524)
				(type default)
			)
			(layer "B.SilkS")
		)
		(fp_line
			(start -1.524 0.762)
			(end 1.524 0.762)
			(stroke
				(width 0.1524)
				(type default)
			)
			(layer "B.SilkS")
		)
		(fp_line
			(start -1.524 -0.762)
			(end -1.524 0.762)
			(stroke
				(width 0.1524)
				(type default)
			)
			(layer "B.SilkS")
		)
		(fp_line
			(start 1.1049 0.724916)
			(end -1.1049 0.724916)
			(stroke
				(width 0.1)
				(type default)
			)
			(layer "B.Fab")
		)
		(fp_line
			(start 1.1049 -0.724916)
			(end 1.1049 0.724916)
			(stroke
				(width 0.1)
				(type default)
			)
			(layer "B.Fab")
		)
		(fp_line
			(start -1.1049 0.724916)
			(end -1.1049 -0.724916)
			(stroke
				(width 0.1)
				(type default)
			)
			(layer "B.Fab")
		)
		(fp_line
			(start -1.1049 -0.724916)
			(end 1.1049 -0.724916)
			(stroke
				(width 0.1)
				(type default)
			)
			(layer "B.Fab")
		)
		(pad "1" smd rect
			(at 0.889 0 180)
			(size 1.016 1.27)
			(layers "B.Cu" "B.Mask" "B.Paste")
			(net "P12V_MEM_CPU0")
		)
		(pad "2" smd rect
			(at -0.889 0 180)
			(size 1.016 1.27)
			(layers "B.Cu" "B.Mask" "B.Paste")
			(net "GND")
		)
	)
	(footprint ""
		(layer "B.Cu")
		(at 413.502856 -163.891468 -90)
		(property "Reference" "PC613_3"
			(at 0 0 90)
			(layer "B.SilkS")
			(hide yes)
			(effects
				(font
					(size 1.27 1.27)
				)
				(justify mirror)
			)
		)
		(property "Value" ""
			(at 0 0 90)
			(layer "B.Fab")
			(effects
				(font
					(size 1.27 1.27)
				)
				(justify mirror)
			)
		)
		(duplicate_pad_numbers_are_jumpers no)
		(fp_line
			(start -1.524 0.762)
			(end 1.524 0.762)
			(stroke
				(width 0.1524)
				(type default)
			)
			(layer "B.SilkS")
		)
		(fp_line
			(start 1.524 0.762)
			(end 1.524 -0.762)
			(stroke
				(width 0.1524)
				(type default)
			)
			(layer "B.SilkS")
		)
		(fp_line
			(start -1.524 -0.762)
			(end -1.524 0.762)
			(stroke
				(width 0.1524)
				(type default)
			)
			(layer "B.SilkS")
		)
		(fp_line
			(start 1.524 -0.762)
			(end -1.524 -0.762)
			(stroke
				(width 0.1524)
				(type default)
			)
			(layer "B.SilkS")
		)
		(fp_line
			(start -1.1049 0.724916)
			(end -1.1049 -0.724916)
			(stroke
				(width 0.1)
				(type default)
			)
			(layer "B.Fab")
		)
		(fp_line
			(start 1.1049 0.724916)
			(end -1.1049 0.724916)
			(stroke
				(width 0.1)
				(type default)
			)
			(layer "B.Fab")
		)
		(fp_line
			(start -1.1049 -0.724916)
			(end 1.1049 -0.724916)
			(stroke
				(width 0.1)
				(type default)
			)
			(layer "B.Fab")
		)
		(fp_line
			(start 1.1049 -0.724916)
			(end 1.1049 0.724916)
			(stroke
				(width 0.1)
				(type default)
			)
			(layer "B.Fab")
		)
		(pad "1" smd rect
			(at 0.889 0 270)
			(size 1.016 1.27)
			(layers "B.Cu" "B.Mask" "B.Paste")
			(net "SW_P12V_AUX_PVDDCR_SOC_P0_FLT")
		)
		(pad "2" smd rect
			(at -0.889 0 270)
			(size 1.016 1.27)
			(layers "B.Cu" "B.Mask" "B.Paste")
			(net "GND")
		)
	)
	(footprint ""
		(layer "B.Cu")
		(at 175.316642 -195.8594 180)
		(property "Reference" "R1707"
			(at 0 0 0)
			(layer "B.SilkS")
			(hide yes)
			(effects
				(font
					(size 1.27 1.27)
				)
				(justify mirror)
			)
		)
		(property "Value" ""
			(at 0 0 0)
			(layer "B.Fab")
			(effects
				(font
					(size 1.27 1.27)
				)
				(justify mirror)
			)
		)
		(duplicate_pad_numbers_are_jumpers no)
		(fp_line
			(start 0.7874 0.4064)
			(end 0.7874 -0.4064)
			(stroke
				(width 0.1524)
				(type default)
			)
			(layer "B.SilkS")
		)
		(fp_line
			(start 0.7874 -0.4064)
			(end -0.7874 -0.4064)
			(stroke
				(width 0.1524)
				(type default)
			)
			(layer "B.SilkS")
		)
		(fp_line
			(start -0.7874 0.4064)
			(end 0.7874 0.4064)
			(stroke
				(width 0.1524)
				(type default)
			)
			(layer "B.SilkS")
		)
		(fp_line
			(start -0.7874 -0.4064)
			(end -0.7874 0.4064)
			(stroke
				(width 0.1524)
				(type default)
			)
			(layer "B.SilkS")
		)
		(fp_line
			(start 0.67945 0.3048)
			(end 0.67945 -0.305054)
			(stroke
				(width 0.1)
				(type default)
			)
			(layer "B.Fab")
		)
		(fp_line
			(start 0.67945 -0.305054)
			(end 0.12065 -0.305054)
			(stroke
				(width 0.1)
				(type default)
			)
			(layer "B.Fab")
		)
		(fp_line
			(start 0.12065 0.3048)
			(end 0.67945 0.3048)
			(stroke
				(width 0.1)
				(type default)
			)
			(layer "B.Fab")
		)
		(fp_line
			(start 0.12065 0.2794)
			(end 0.12065 0.3048)
			(stroke
				(width 0.1)
				(type default)
			)
			(layer "B.Fab")
		)
		(fp_line
			(start 0.12065 -0.2794)
			(end -0.12065 -0.2794)
			(stroke
				(width 0.1)
				(type default)
			)
			(layer "B.Fab")
		)
		(fp_line
			(start 0.12065 -0.305054)
			(end 0.12065 -0.2794)
			(stroke
				(width 0.1)
				(type default)
			)
			(layer "B.Fab")
		)
		(fp_line
			(start -0.120396 0.3048)
			(end -0.120396 0.2794)
			(stroke
				(width 0.1)
				(type default)
			)
			(layer "B.Fab")
		)
		(fp_line
			(start -0.120396 0.2794)
			(end 0.12065 0.2794)
			(stroke
				(width 0.1)
				(type default)
			)
			(layer "B.Fab")
		)
		(fp_line
			(start -0.12065 -0.2794)
			(end -0.12065 -0.3048)
			(stroke
				(width 0.1)
				(type default)
			)
			(layer "B.Fab")
		)
		(fp_line
			(start -0.12065 -0.3048)
			(end -0.67945 -0.3048)
			(stroke
				(width 0.1)
				(type default)
			)
			(layer "B.Fab")
		)
		(fp_line
			(start -0.67945 0.3048)
			(end -0.120396 0.3048)
			(stroke
				(width 0.1)
				(type default)
			)
			(layer "B.Fab")
		)
		(fp_line
			(start -0.67945 -0.3048)
			(end -0.67945 0.3048)
			(stroke
				(width 0.1)
				(type default)
			)
			(layer "B.Fab")
		)
		(pad "1" smd circle
			(at 0.40005 0)
			(size 0 0)
			(layers "B.Cu" "B.Mask" "B.Paste")
			(net "I3C_SPD_DDRGL_CPU1_SDA")
		)
		(pad "2" smd circle
			(at -0.40005 0)
			(size 0 0)
			(layers "B.Cu" "B.Mask" "B.Paste")
			(net "I3C_SPD_DDRH_CPU1_SDA")
		)
	)
	(footprint ""
		(layer "B.Cu")
		(at 206.22133 -193.99631)
		(property "Reference" "C180"
			(at 0 0 0)
			(layer "B.SilkS")
			(hide yes)
			(effects
				(font
					(size 1.27 1.27)
				)
				(justify mirror)
			)
		)
		(property "Value" ""
			(at 0 0 0)
			(layer "B.Fab")
			(effects
				(font
					(size 1.27 1.27)
				)
				(justify mirror)
			)
		)
		(duplicate_pad_numbers_are_jumpers no)
		(fp_line
			(start -0.7874 -0.4064)
			(end -0.7874 0.4064)
			(stroke
				(width 0.1524)
				(type default)
			)
			(layer "B.SilkS")
		)
		(fp_line
			(start -0.7874 0.4064)
			(end 0.7874 0.4064)
			(stroke
				(width 0.1524)
				(type default)
			)
			(layer "B.SilkS")
		)
		(fp_line
			(start 0.7874 -0.4064)
			(end -0.7874 -0.4064)
			(stroke
				(width 0.1524)
				(type default)
			)
			(layer "B.SilkS")
		)
		(fp_line
			(start 0.7874 0.4064)
			(end 0.7874 -0.4064)
			(stroke
				(width 0.1524)
				(type default)
			)
			(layer "B.SilkS")
		)
		(fp_line
			(start -0.67945 -0.3048)
			(end -0.67945 0.3048)
			(stroke
				(width 0.1)
				(type default)
			)
			(layer "B.Fab")
		)
		(fp_line
			(start -0.67945 0.3048)
			(end -0.120396 0.3048)
			(stroke
				(width 0.1)
				(type default)
			)
			(layer "B.Fab")
		)
		(fp_line
			(start -0.12065 -0.3048)
			(end -0.67945 -0.3048)
			(stroke
				(width 0.1)
				(type default)
			)
			(layer "B.Fab")
		)
		(fp_line
			(start -0.12065 -0.2794)
			(end -0.12065 -0.3048)
			(stroke
				(width 0.1)
				(type default)
			)
			(layer "B.Fab")
		)
		(fp_line
			(start -0.120396 0.2794)
			(end 0.12065 0.2794)
			(stroke
				(width 0.1)
				(type default)
			)
			(layer "B.Fab")
		)
		(fp_line
			(start -0.120396 0.3048)
			(end -0.120396 0.2794)
			(stroke
				(width 0.1)
				(type default)
			)
			(layer "B.Fab")
		)
		(fp_line
			(start 0.12065 -0.305054)
			(end 0.12065 -0.2794)
			(stroke
				(width 0.1)
				(type default)
			)
			(layer "B.Fab")
		)
		(fp_line
			(start 0.12065 -0.2794)
			(end -0.12065 -0.2794)
			(stroke
				(width 0.1)
				(type default)
			)
			(layer "B.Fab")
		)
		(fp_line
			(start 0.12065 0.2794)
			(end 0.12065 0.3048)
			(stroke
				(width 0.1)
				(type default)
			)
			(layer "B.Fab")
		)
		(fp_line
			(start 0.12065 0.3048)
			(end 0.67945 0.3048)
			(stroke
				(width 0.1)
				(type default)
			)
			(layer "B.Fab")
		)
		(fp_line
			(start 0.67945 -0.305054)
			(end 0.12065 -0.305054)
			(stroke
				(width 0.1)
				(type default)
			)
			(layer "B.Fab")
		)
		(fp_line
			(start 0.67945 0.3048)
			(end 0.67945 -0.305054)
			(stroke
				(width 0.1)
				(type default)
			)
			(layer "B.Fab")
		)
		(pad "1" smd circle
			(at 0.40005 0 180)
			(size 0 0)
			(layers "B.Cu" "B.Mask" "B.Paste")
			(net "P3V3_AUX")
		)
		(pad "2" smd circle
			(at -0.40005 0 180)
			(size 0 0)
			(layers "B.Cu" "B.Mask" "B.Paste")
			(net "GND")
		)
	)
	(footprint ""
		(layer "B.Cu")
		(at 110.16234 -62.01791 90)
		(property "Reference" "R6223"
			(at 0 0 90)
			(layer "B.SilkS")
			(hide yes)
			(effects
				(font
					(size 1.27 1.27)
				)
				(justify mirror)
			)
		)
		(property "Value" ""
			(at 0 0 90)
			(layer "B.Fab")
			(effects
				(font
					(size 1.27 1.27)
				)
				(justify mirror)
			)
		)
		(duplicate_pad_numbers_are_jumpers no)
		(fp_line
			(start 0.7874 -0.4064)
			(end -0.7874 -0.4064)
			(stroke
				(width 0.1524)
				(type default)
			)
			(layer "B.SilkS")
		)
		(fp_line
			(start -0.7874 -0.4064)
			(end -0.7874 0.4064)
			(stroke
				(width 0.1524)
				(type default)
			)
			(layer "B.SilkS")
		)
		(fp_line
			(start 0.7874 0.4064)
			(end 0.7874 -0.4064)
			(stroke
				(width 0.1524)
				(type default)
			)
			(layer "B.SilkS")
		)
		(fp_line
			(start -0.7874 0.4064)
			(end 0.7874 0.4064)
			(stroke
				(width 0.1524)
				(type default)
			)
			(layer "B.SilkS")
		)
		(fp_line
			(start 0.67945 -0.305054)
			(end 0.12065 -0.305054)
			(stroke
				(width 0.1)
				(type default)
			)
			(layer "B.Fab")
		)
		(fp_line
			(start 0.12065 -0.305054)
			(end 0.12065 -0.2794)
			(stroke
				(width 0.1)
				(type default)
			)
			(layer "B.Fab")
		)
		(fp_line
			(start -0.12065 -0.3048)
			(end -0.67945 -0.3048)
			(stroke
				(width 0.1)
				(type default)
			)
			(layer "B.Fab")
		)
		(fp_line
			(start -0.67945 -0.3048)
			(end -0.67945 0.3048)
			(stroke
				(width 0.1)
				(type default)
			)
			(layer "B.Fab")
		)
		(fp_line
			(start 0.12065 -0.2794)
			(end -0.12065 -0.2794)
			(stroke
				(width 0.1)
				(type default)
			)
			(layer "B.Fab")
		)
		(fp_line
			(start -0.12065 -0.2794)
			(end -0.12065 -0.3048)
			(stroke
				(width 0.1)
				(type default)
			)
			(layer "B.Fab")
		)
		(fp_line
			(start 0.12065 0.2794)
			(end 0.12065 0.3048)
			(stroke
				(width 0.1)
				(type default)
			)
			(layer "B.Fab")
		)
		(fp_line
			(start -0.120396 0.2794)
			(end 0.12065 0.2794)
			(stroke
				(width 0.1)
				(type default)
			)
			(layer "B.Fab")
		)
		(fp_line
			(start 0.67945 0.3048)
			(end 0.67945 -0.305054)
			(stroke
				(width 0.1)
				(type default)
			)
			(layer "B.Fab")
		)
		(fp_line
			(start 0.12065 0.3048)
			(end 0.67945 0.3048)
			(stroke
				(width 0.1)
				(type default)
			)
			(layer "B.Fab")
		)
		(fp_line
			(start -0.120396 0.3048)
			(end -0.120396 0.2794)
			(stroke
				(width 0.1)
				(type default)
			)
			(layer "B.Fab")
		)
		(fp_line
			(start -0.67945 0.3048)
			(end -0.120396 0.3048)
			(stroke
				(width 0.1)
				(type default)
			)
			(layer "B.Fab")
		)
		(pad "1" smd circle
			(at 0.40005 0 270)
			(size 0 0)
			(layers "B.Cu" "B.Mask" "B.Paste")
			(net "PD_USB_CPU0_WP")
		)
		(pad "2" smd circle
			(at -0.40005 0 270)
			(size 0 0)
			(layers "B.Cu" "B.Mask" "B.Paste")
			(net "GND")
		)
	)
	(footprint ""
		(layer "B.Cu")
		(at 406.698958 -329.942952 180)
		(property "Reference" "R444"
			(at 0 0 0)
			(layer "B.SilkS")
			(hide yes)
			(effects
				(font
					(size 1.27 1.27)
				)
				(justify mirror)
			)
		)
		(property "Value" ""
			(at 0 0 0)
			(layer "B.Fab")
			(effects
				(font
					(size 1.27 1.27)
				)
				(justify mirror)
			)
		)
		(duplicate_pad_numbers_are_jumpers no)
		(fp_line
			(start 0.7874 0.4064)
			(end 0.7874 -0.4064)
			(stroke
				(width 0.1524)
				(type default)
			)
			(layer "B.SilkS")
		)
		(fp_line
			(start 0.7874 -0.4064)
			(end -0.7874 -0.4064)
			(stroke
				(width 0.1524)
				(type default)
			)
			(layer "B.SilkS")
		)
		(fp_line
			(start -0.7874 0.4064)
			(end 0.7874 0.4064)
			(stroke
				(width 0.1524)
				(type default)
			)
			(layer "B.SilkS")
		)
		(fp_line
			(start -0.7874 -0.4064)
			(end -0.7874 0.4064)
			(stroke
				(width 0.1524)
				(type default)
			)
			(layer "B.SilkS")
		)
		(fp_line
			(start 0.67945 0.3048)
			(end 0.67945 -0.305054)
			(stroke
				(width 0.1)
				(type default)
			)
			(layer "B.Fab")
		)
		(fp_line
			(start 0.67945 -0.305054)
			(end 0.12065 -0.305054)
			(stroke
				(width 0.1)
				(type default)
			)
			(layer "B.Fab")
		)
		(fp_line
			(start 0.12065 0.3048)
			(end 0.67945 0.3048)
			(stroke
				(width 0.1)
				(type default)
			)
			(layer "B.Fab")
		)
		(fp_line
			(start 0.12065 0.2794)
			(end 0.12065 0.3048)
			(stroke
				(width 0.1)
				(type default)
			)
			(layer "B.Fab")
		)
		(fp_line
			(start 0.12065 -0.2794)
			(end -0.12065 -0.2794)
			(stroke
				(width 0.1)
				(type default)
			)
			(layer "B.Fab")
		)
		(fp_line
			(start 0.12065 -0.305054)
			(end 0.12065 -0.2794)
			(stroke
				(width 0.1)
				(type default)
			)
			(layer "B.Fab")
		)
		(fp_line
			(start -0.120396 0.3048)
			(end -0.120396 0.2794)
			(stroke
				(width 0.1)
				(type default)
			)
			(layer "B.Fab")
		)
		(fp_line
			(start -0.120396 0.2794)
			(end 0.12065 0.2794)
			(stroke
				(width 0.1)
				(type default)
			)
			(layer "B.Fab")
		)
		(fp_line
			(start -0.12065 -0.2794)
			(end -0.12065 -0.3048)
			(stroke
				(width 0.1)
				(type default)
			)
			(layer "B.Fab")
		)
		(fp_line
			(start -0.12065 -0.3048)
			(end -0.67945 -0.3048)
			(stroke
				(width 0.1)
				(type default)
			)
			(layer "B.Fab")
		)
		(fp_line
			(start -0.67945 0.3048)
			(end -0.120396 0.3048)
			(stroke
				(width 0.1)
				(type default)
			)
			(layer "B.Fab")
		)
		(fp_line
			(start -0.67945 -0.3048)
			(end -0.67945 0.3048)
			(stroke
				(width 0.1)
				(type default)
			)
			(layer "B.Fab")
		)
		(pad "1" smd circle
			(at 0.40005 0)
			(size 0 0)
			(layers "B.Cu" "B.Mask" "B.Paste")
			(net "FM_SMM_CRASHDUMP")
		)
		(pad "2" smd circle
			(at -0.40005 0)
			(size 0 0)
			(layers "B.Cu" "B.Mask" "B.Paste")
			(net "PVDD18_S5_P0")
		)
	)
	(footprint ""
		(layer "B.Cu")
		(at 50.586386 -190.821564 180)
		(property "Reference" "R102"
			(at 0 0 0)
			(layer "B.SilkS")
			(hide yes)
			(effects
				(font
					(size 1.27 1.27)
				)
				(justify mirror)
			)
		)
		(property "Value" ""
			(at 0 0 0)
			(layer "B.Fab")
			(effects
				(font
					(size 1.27 1.27)
				)
				(justify mirror)
			)
		)
		(duplicate_pad_numbers_are_jumpers no)
		(fp_line
			(start 0.7874 0.4064)
			(end 0.7874 -0.4064)
			(stroke
				(width 0.1524)
				(type default)
			)
			(layer "B.SilkS")
		)
		(fp_line
			(start 0.7874 -0.4064)
			(end -0.7874 -0.4064)
			(stroke
				(width 0.1524)
				(type default)
			)
			(layer "B.SilkS")
		)
		(fp_line
			(start -0.7874 0.4064)
			(end 0.7874 0.4064)
			(stroke
				(width 0.1524)
				(type default)
			)
			(layer "B.SilkS")
		)
		(fp_line
			(start -0.7874 -0.4064)
			(end -0.7874 0.4064)
			(stroke
				(width 0.1524)
				(type default)
			)
			(layer "B.SilkS")
		)
		(fp_line
			(start 0.67945 0.3048)
			(end 0.67945 -0.305054)
			(stroke
				(width 0.1)
				(type default)
			)
			(layer "B.Fab")
		)
		(fp_line
			(start 0.67945 -0.305054)
			(end 0.12065 -0.305054)
			(stroke
				(width 0.1)
				(type default)
			)
			(layer "B.Fab")
		)
		(fp_line
			(start 0.12065 0.3048)
			(end 0.67945 0.3048)
			(stroke
				(width 0.1)
				(type default)
			)
			(layer "B.Fab")
		)
		(fp_line
			(start 0.12065 0.2794)
			(end 0.12065 0.3048)
			(stroke
				(width 0.1)
				(type default)
			)
			(layer "B.Fab")
		)
		(fp_line
			(start 0.12065 -0.2794)
			(end -0.12065 -0.2794)
			(stroke
				(width 0.1)
				(type default)
			)
			(layer "B.Fab")
		)
		(fp_line
			(start 0.12065 -0.305054)
			(end 0.12065 -0.2794)
			(stroke
				(width 0.1)
				(type default)
			)
			(layer "B.Fab")
		)
		(fp_line
			(start -0.120396 0.3048)
			(end -0.120396 0.2794)
			(stroke
				(width 0.1)
				(type default)
			)
			(layer "B.Fab")
		)
		(fp_line
			(start -0.120396 0.2794)
			(end 0.12065 0.2794)
			(stroke
				(width 0.1)
				(type default)
			)
			(layer "B.Fab")
		)
		(fp_line
			(start -0.12065 -0.2794)
			(end -0.12065 -0.3048)
			(stroke
				(width 0.1)
				(type default)
			)
			(layer "B.Fab")
		)
		(fp_line
			(start -0.12065 -0.3048)
			(end -0.67945 -0.3048)
			(stroke
				(width 0.1)
				(type default)
			)
			(layer "B.Fab")
		)
		(fp_line
			(start -0.67945 0.3048)
			(end -0.120396 0.3048)
			(stroke
				(width 0.1)
				(type default)
			)
			(layer "B.Fab")
		)
		(fp_line
			(start -0.67945 -0.3048)
			(end -0.67945 0.3048)
			(stroke
				(width 0.1)
				(type default)
			)
			(layer "B.Fab")
		)
		(pad "1" smd circle
			(at 0.40005 0)
			(size 0 0)
			(layers "B.Cu" "B.Mask" "B.Paste")
			(net "P3V3")
		)
		(pad "2" smd circle
			(at -0.40005 0)
			(size 0 0)
			(layers "B.Cu" "B.Mask" "B.Paste")
			(net "PWRGD_CHAF_CPU1")
		)
	)
	(footprint ""
		(layer "B.Cu")
		(at 310.411876 -66.708782 90)
		(property "Reference" "R3074"
			(at 0 0 90)
			(layer "B.SilkS")
			(hide yes)
			(effects
				(font
					(size 1.27 1.27)
				)
				(justify mirror)
			)
		)
		(property "Value" ""
			(at 0 0 90)
			(layer "B.Fab")
			(effects
				(font
					(size 1.27 1.27)
				)
				(justify mirror)
			)
		)
		(duplicate_pad_numbers_are_jumpers no)
		(fp_line
			(start 0.7874 -0.4064)
			(end -0.7874 -0.4064)
			(stroke
				(width 0.1524)
				(type default)
			)
			(layer "B.SilkS")
		)
		(fp_line
			(start -0.7874 -0.4064)
			(end -0.7874 0.4064)
			(stroke
				(width 0.1524)
				(type default)
			)
			(layer "B.SilkS")
		)
		(fp_line
			(start 0.7874 0.4064)
			(end 0.7874 -0.4064)
			(stroke
				(width 0.1524)
				(type default)
			)
			(layer "B.SilkS")
		)
		(fp_line
			(start -0.7874 0.4064)
			(end 0.7874 0.4064)
			(stroke
				(width 0.1524)
				(type default)
			)
			(layer "B.SilkS")
		)
		(fp_line
			(start 0.67945 -0.305054)
			(end 0.12065 -0.305054)
			(stroke
				(width 0.1)
				(type default)
			)
			(layer "B.Fab")
		)
		(fp_line
			(start 0.12065 -0.305054)
			(end 0.12065 -0.2794)
			(stroke
				(width 0.1)
				(type default)
			)
			(layer "B.Fab")
		)
		(fp_line
			(start -0.12065 -0.3048)
			(end -0.67945 -0.3048)
			(stroke
				(width 0.1)
				(type default)
			)
			(layer "B.Fab")
		)
		(fp_line
			(start -0.67945 -0.3048)
			(end -0.67945 0.3048)
			(stroke
				(width 0.1)
				(type default)
			)
			(layer "B.Fab")
		)
		(fp_line
			(start 0.12065 -0.2794)
			(end -0.12065 -0.2794)
			(stroke
				(width 0.1)
				(type default)
			)
			(layer "B.Fab")
		)
		(fp_line
			(start -0.12065 -0.2794)
			(end -0.12065 -0.3048)
			(stroke
				(width 0.1)
				(type default)
			)
			(layer "B.Fab")
		)
		(fp_line
			(start 0.12065 0.2794)
			(end 0.12065 0.3048)
			(stroke
				(width 0.1)
				(type default)
			)
			(layer "B.Fab")
		)
		(fp_line
			(start -0.120396 0.2794)
			(end 0.12065 0.2794)
			(stroke
				(width 0.1)
				(type default)
			)
			(layer "B.Fab")
		)
		(fp_line
			(start 0.67945 0.3048)
			(end 0.67945 -0.305054)
			(stroke
				(width 0.1)
				(type default)
			)
			(layer "B.Fab")
		)
		(fp_line
			(start 0.12065 0.3048)
			(end 0.67945 0.3048)
			(stroke
				(width 0.1)
				(type default)
			)
			(layer "B.Fab")
		)
		(fp_line
			(start -0.120396 0.3048)
			(end -0.120396 0.2794)
			(stroke
				(width 0.1)
				(type default)
			)
			(layer "B.Fab")
		)
		(fp_line
			(start -0.67945 0.3048)
			(end -0.120396 0.3048)
			(stroke
				(width 0.1)
				(type default)
			)
			(layer "B.Fab")
		)
		(pad "1" smd circle
			(at 0.40005 0 270)
			(size 0 0)
			(layers "B.Cu" "B.Mask" "B.Paste")
			(net "LED_RST_RSMRST_PLD_R_N")
		)
		(pad "2" smd circle
			(at -0.40005 0 270)
			(size 0 0)
			(layers "B.Cu" "B.Mask" "B.Paste")
			(net "P3V3_AUX")
		)
	)
	(footprint ""
		(layer "B.Cu")
		(at 114.327178 -261.748016 90)
		(property "Reference" "C2506"
			(at 0 0 90)
			(layer "B.SilkS")
			(hide yes)
			(effects
				(font
					(size 1.27 1.27)
				)
				(justify mirror)
			)
		)
		(property "Value" ""
			(at 0 0 90)
			(layer "B.Fab")
			(effects
				(font
					(size 1.27 1.27)
				)
				(justify mirror)
			)
		)
		(duplicate_pad_numbers_are_jumpers no)
		(fp_line
			(start 0.7874 -0.4064)
			(end -0.7874 -0.4064)
			(stroke
				(width 0.1524)
				(type default)
			)
			(layer "B.SilkS")
		)
		(fp_line
			(start -0.7874 -0.4064)
			(end -0.7874 0.4064)
			(stroke
				(width 0.1524)
				(type default)
			)
			(layer "B.SilkS")
		)
		(fp_line
			(start 0.7874 0.4064)
			(end 0.7874 -0.4064)
			(stroke
				(width 0.1524)
				(type default)
			)
			(layer "B.SilkS")
		)
		(fp_line
			(start -0.7874 0.4064)
			(end 0.7874 0.4064)
			(stroke
				(width 0.1524)
				(type default)
			)
			(layer "B.SilkS")
		)
		(fp_line
			(start 0.67945 -0.305054)
			(end 0.12065 -0.305054)
			(stroke
				(width 0.1)
				(type default)
			)
			(layer "B.Fab")
		)
		(fp_line
			(start 0.12065 -0.305054)
			(end 0.12065 -0.2794)
			(stroke
				(width 0.1)
				(type default)
			)
			(layer "B.Fab")
		)
		(fp_line
			(start -0.12065 -0.3048)
			(end -0.67945 -0.3048)
			(stroke
				(width 0.1)
				(type default)
			)
			(layer "B.Fab")
		)
		(fp_line
			(start -0.67945 -0.3048)
			(end -0.67945 0.3048)
			(stroke
				(width 0.1)
				(type default)
			)
			(layer "B.Fab")
		)
		(fp_line
			(start 0.12065 -0.2794)
			(end -0.12065 -0.2794)
			(stroke
				(width 0.1)
				(type default)
			)
			(layer "B.Fab")
		)
		(fp_line
			(start -0.12065 -0.2794)
			(end -0.12065 -0.3048)
			(stroke
				(width 0.1)
				(type default)
			)
			(layer "B.Fab")
		)
		(fp_line
			(start 0.12065 0.2794)
			(end 0.12065 0.3048)
			(stroke
				(width 0.1)
				(type default)
			)
			(layer "B.Fab")
		)
		(fp_line
			(start -0.120396 0.2794)
			(end 0.12065 0.2794)
			(stroke
				(width 0.1)
				(type default)
			)
			(layer "B.Fab")
		)
		(fp_line
			(start 0.67945 0.3048)
			(end 0.67945 -0.305054)
			(stroke
				(width 0.1)
				(type default)
			)
			(layer "B.Fab")
		)
		(fp_line
			(start 0.12065 0.3048)
			(end 0.67945 0.3048)
			(stroke
				(width 0.1)
				(type default)
			)
			(layer "B.Fab")
		)
		(fp_line
			(start -0.120396 0.3048)
			(end -0.120396 0.2794)
			(stroke
				(width 0.1)
				(type default)
			)
			(layer "B.Fab")
		)
		(fp_line
			(start -0.67945 0.3048)
			(end -0.120396 0.3048)
			(stroke
				(width 0.1)
				(type default)
			)
			(layer "B.Fab")
		)
		(pad "1" smd circle
			(at 0.40005 0 270)
			(size 0 0)
			(layers "B.Cu" "B.Mask" "B.Paste")
			(net "PVDD11_S3_P1")
		)
		(pad "2" smd circle
			(at -0.40005 0 270)
			(size 0 0)
			(layers "B.Cu" "B.Mask" "B.Paste")
			(net "GND")
		)
	)
	(footprint ""
		(layer "B.Cu")
		(at 24.765 -362.204 180)
		(property "Reference" "R8242"
			(at 0 0 0)
			(layer "B.SilkS")
			(hide yes)
			(effects
				(font
					(size 1.27 1.27)
				)
				(justify mirror)
			)
		)
		(property "Value" ""
			(at 0 0 0)
			(layer "B.Fab")
			(effects
				(font
					(size 1.27 1.27)
				)
				(justify mirror)
			)
		)
		(duplicate_pad_numbers_are_jumpers no)
		(fp_line
			(start 0.7874 0.4064)
			(end 0.7874 -0.4064)
			(stroke
				(width 0.1524)
				(type default)
			)
			(layer "B.SilkS")
		)
		(fp_line
			(start 0.7874 -0.4064)
			(end -0.7874 -0.4064)
			(stroke
				(width 0.1524)
				(type default)
			)
			(layer "B.SilkS")
		)
		(fp_line
			(start -0.7874 0.4064)
			(end 0.7874 0.4064)
			(stroke
				(width 0.1524)
				(type default)
			)
			(layer "B.SilkS")
		)
		(fp_line
			(start -0.7874 -0.4064)
			(end -0.7874 0.4064)
			(stroke
				(width 0.1524)
				(type default)
			)
			(layer "B.SilkS")
		)
		(fp_line
			(start 0.67945 0.3048)
			(end 0.67945 -0.305054)
			(stroke
				(width 0.1)
				(type default)
			)
			(layer "B.Fab")
		)
		(fp_line
			(start 0.67945 -0.305054)
			(end 0.12065 -0.305054)
			(stroke
				(width 0.1)
				(type default)
			)
			(layer "B.Fab")
		)
		(fp_line
			(start 0.12065 0.3048)
			(end 0.67945 0.3048)
			(stroke
				(width 0.1)
				(type default)
			)
			(layer "B.Fab")
		)
		(fp_line
			(start 0.12065 0.2794)
			(end 0.12065 0.3048)
			(stroke
				(width 0.1)
				(type default)
			)
			(layer "B.Fab")
		)
		(fp_line
			(start 0.12065 -0.2794)
			(end -0.12065 -0.2794)
			(stroke
				(width 0.1)
				(type default)
			)
			(layer "B.Fab")
		)
		(fp_line
			(start 0.12065 -0.305054)
			(end 0.12065 -0.2794)
			(stroke
				(width 0.1)
				(type default)
			)
			(layer "B.Fab")
		)
		(fp_line
			(start -0.120396 0.3048)
			(end -0.120396 0.2794)
			(stroke
				(width 0.1)
				(type default)
			)
			(layer "B.Fab")
		)
		(fp_line
			(start -0.120396 0.2794)
			(end 0.12065 0.2794)
			(stroke
				(width 0.1)
				(type default)
			)
			(layer "B.Fab")
		)
		(fp_line
			(start -0.12065 -0.2794)
			(end -0.12065 -0.3048)
			(stroke
				(width 0.1)
				(type default)
			)
			(layer "B.Fab")
		)
		(fp_line
			(start -0.12065 -0.3048)
			(end -0.67945 -0.3048)
			(stroke
				(width 0.1)
				(type default)
			)
			(layer "B.Fab")
		)
		(fp_line
			(start -0.67945 0.3048)
			(end -0.120396 0.3048)
			(stroke
				(width 0.1)
				(type default)
			)
			(layer "B.Fab")
		)
		(fp_line
			(start -0.67945 -0.3048)
			(end -0.67945 0.3048)
			(stroke
				(width 0.1)
				(type default)
			)
			(layer "B.Fab")
		)
		(pad "1" smd circle
			(at 0.40005 0)
			(size 0 0)
			(layers "B.Cu" "B.Mask" "B.Paste")
			(net "P3V3_AUX")
		)
		(pad "2" smd circle
			(at -0.40005 0)
			(size 0 0)
			(layers "B.Cu" "B.Mask" "B.Paste")
			(net "PWRGD_PVDDIO_P1_R")
		)
	)
	(footprint ""
		(layer "B.Cu")
		(at 172.456094 -415.808668 180)
		(property "Reference" "R2909"
			(at 0 0 0)
			(layer "B.SilkS")
			(hide yes)
			(effects
				(font
					(size 1.27 1.27)
				)
				(justify mirror)
			)
		)
		(property "Value" ""
			(at 0 0 0)
			(layer "B.Fab")
			(effects
				(font
					(size 1.27 1.27)
				)
				(justify mirror)
			)
		)
		(duplicate_pad_numbers_are_jumpers no)
		(fp_line
			(start 0.7874 0.4064)
			(end 0.7874 -0.4064)
			(stroke
				(width 0.1524)
				(type default)
			)
			(layer "B.SilkS")
		)
		(fp_line
			(start 0.7874 -0.4064)
			(end -0.7874 -0.4064)
			(stroke
				(width 0.1524)
				(type default)
			)
			(layer "B.SilkS")
		)
		(fp_line
			(start -0.7874 0.4064)
			(end 0.7874 0.4064)
			(stroke
				(width 0.1524)
				(type default)
			)
			(layer "B.SilkS")
		)
		(fp_line
			(start -0.7874 -0.4064)
			(end -0.7874 0.4064)
			(stroke
				(width 0.1524)
				(type default)
			)
			(layer "B.SilkS")
		)
		(fp_line
			(start 0.67945 0.3048)
			(end 0.67945 -0.305054)
			(stroke
				(width 0.1)
				(type default)
			)
			(layer "B.Fab")
		)
		(fp_line
			(start 0.67945 -0.305054)
			(end 0.12065 -0.305054)
			(stroke
				(width 0.1)
				(type default)
			)
			(layer "B.Fab")
		)
		(fp_line
			(start 0.12065 0.3048)
			(end 0.67945 0.3048)
			(stroke
				(width 0.1)
				(type default)
			)
			(layer "B.Fab")
		)
		(fp_line
			(start 0.12065 0.2794)
			(end 0.12065 0.3048)
			(stroke
				(width 0.1)
				(type default)
			)
			(layer "B.Fab")
		)
		(fp_line
			(start 0.12065 -0.2794)
			(end -0.12065 -0.2794)
			(stroke
				(width 0.1)
				(type default)
			)
			(layer "B.Fab")
		)
		(fp_line
			(start 0.12065 -0.305054)
			(end 0.12065 -0.2794)
			(stroke
				(width 0.1)
				(type default)
			)
			(layer "B.Fab")
		)
		(fp_line
			(start -0.120396 0.3048)
			(end -0.120396 0.2794)
			(stroke
				(width 0.1)
				(type default)
			)
			(layer "B.Fab")
		)
		(fp_line
			(start -0.120396 0.2794)
			(end 0.12065 0.2794)
			(stroke
				(width 0.1)
				(type default)
			)
			(layer "B.Fab")
		)
		(fp_line
			(start -0.12065 -0.2794)
			(end -0.12065 -0.3048)
			(stroke
				(width 0.1)
				(type default)
			)
			(layer "B.Fab")
		)
		(fp_line
			(start -0.12065 -0.3048)
			(end -0.67945 -0.3048)
			(stroke
				(width 0.1)
				(type default)
			)
			(layer "B.Fab")
		)
		(fp_line
			(start -0.67945 0.3048)
			(end -0.120396 0.3048)
			(stroke
				(width 0.1)
				(type default)
			)
			(layer "B.Fab")
		)
		(fp_line
			(start -0.67945 -0.3048)
			(end -0.67945 0.3048)
			(stroke
				(width 0.1)
				(type default)
			)
			(layer "B.Fab")
		)
		(pad "1" smd circle
			(at 0.40005 0)
			(size 0 0)
			(layers "B.Cu" "B.Mask" "B.Paste")
			(net "P3V3_AUX")
		)
		(pad "2" smd circle
			(at -0.40005 0)
			(size 0 0)
			(layers "B.Cu" "B.Mask" "B.Paste")
			(net "RST_SWB_BIC_R_N")
		)
	)
	(footprint ""
		(layer "B.Cu")
		(at 14.892782 -415.644584 -90)
		(property "Reference" "PR6540"
			(at 0 0 90)
			(layer "B.SilkS")
			(hide yes)
			(effects
				(font
					(size 1.27 1.27)
				)
				(justify mirror)
			)
		)
		(property "Value" ""
			(at 0 0 90)
			(layer "B.Fab")
			(effects
				(font
					(size 1.27 1.27)
				)
				(justify mirror)
			)
		)
		(duplicate_pad_numbers_are_jumpers no)
		(fp_line
			(start -0.7874 0.4064)
			(end 0.7874 0.4064)
			(stroke
				(width 0.1524)
				(type default)
			)
			(layer "B.SilkS")
		)
		(fp_line
			(start 0.7874 0.4064)
			(end 0.7874 -0.4064)
			(stroke
				(width 0.1524)
				(type default)
			)
			(layer "B.SilkS")
		)
		(fp_line
			(start -0.7874 -0.4064)
			(end -0.7874 0.4064)
			(stroke
				(width 0.1524)
				(type default)
			)
			(layer "B.SilkS")
		)
		(fp_line
			(start 0.7874 -0.4064)
			(end -0.7874 -0.4064)
			(stroke
				(width 0.1524)
				(type default)
			)
			(layer "B.SilkS")
		)
		(fp_line
			(start -0.67945 0.3048)
			(end -0.120396 0.3048)
			(stroke
				(width 0.1)
				(type default)
			)
			(layer "B.Fab")
		)
		(fp_line
			(start -0.120396 0.3048)
			(end -0.120396 0.2794)
			(stroke
				(width 0.1)
				(type default)
			)
			(layer "B.Fab")
		)
		(fp_line
			(start 0.12065 0.3048)
			(end 0.67945 0.3048)
			(stroke
				(width 0.1)
				(type default)
			)
			(layer "B.Fab")
		)
		(fp_line
			(start 0.67945 0.3048)
			(end 0.67945 -0.305054)
			(stroke
				(width 0.1)
				(type default)
			)
			(layer "B.Fab")
		)
		(fp_line
			(start -0.120396 0.2794)
			(end 0.12065 0.2794)
			(stroke
				(width 0.1)
				(type default)
			)
			(layer "B.Fab")
		)
		(fp_line
			(start 0.12065 0.2794)
			(end 0.12065 0.3048)
			(stroke
				(width 0.1)
				(type default)
			)
			(layer "B.Fab")
		)
		(fp_line
			(start -0.12065 -0.2794)
			(end -0.12065 -0.3048)
			(stroke
				(width 0.1)
				(type default)
			)
			(layer "B.Fab")
		)
		(fp_line
			(start 0.12065 -0.2794)
			(end -0.12065 -0.2794)
			(stroke
				(width 0.1)
				(type default)
			)
			(layer "B.Fab")
		)
		(fp_line
			(start -0.67945 -0.3048)
			(end -0.67945 0.3048)
			(stroke
				(width 0.1)
				(type default)
			)
			(layer "B.Fab")
		)
		(fp_line
			(start -0.12065 -0.3048)
			(end -0.67945 -0.3048)
			(stroke
				(width 0.1)
				(type default)
			)
			(layer "B.Fab")
		)
		(fp_line
			(start 0.12065 -0.305054)
			(end 0.12065 -0.2794)
			(stroke
				(width 0.1)
				(type default)
			)
			(layer "B.Fab")
		)
		(fp_line
			(start 0.67945 -0.305054)
			(end 0.12065 -0.305054)
			(stroke
				(width 0.1)
				(type default)
			)
			(layer "B.Fab")
		)
		(pad "1" smd circle
			(at 0.40005 0 90)
			(size 0 0)
			(layers "B.Cu" "B.Mask" "B.Paste")
			(net "NC_P0V9_RETIMER_CPU1_IMON4")
		)
		(pad "2" smd circle
			(at -0.40005 0 90)
			(size 0 0)
			(layers "B.Cu" "B.Mask" "B.Paste")
			(net "GND")
		)
	)
	(footprint ""
		(layer "B.Cu")
		(at 108.371386 -264.354564)
		(property "Reference" "C3902"
			(at 0 0 0)
			(layer "B.SilkS")
			(hide yes)
			(effects
				(font
					(size 1.27 1.27)
				)
				(justify mirror)
			)
		)
		(property "Value" ""
			(at 0 0 0)
			(layer "B.Fab")
			(effects
				(font
					(size 1.27 1.27)
				)
				(justify mirror)
			)
		)
		(duplicate_pad_numbers_are_jumpers no)
		(fp_line
			(start -0.7874 -0.4064)
			(end -0.7874 0.4064)
			(stroke
				(width 0.1524)
				(type default)
			)
			(layer "B.SilkS")
		)
		(fp_line
			(start -0.7874 0.4064)
			(end 0.7874 0.4064)
			(stroke
				(width 0.1524)
				(type default)
			)
			(layer "B.SilkS")
		)
		(fp_line
			(start 0.7874 -0.4064)
			(end -0.7874 -0.4064)
			(stroke
				(width 0.1524)
				(type default)
			)
			(layer "B.SilkS")
		)
		(fp_line
			(start 0.7874 0.4064)
			(end 0.7874 -0.4064)
			(stroke
				(width 0.1524)
				(type default)
			)
			(layer "B.SilkS")
		)
		(fp_line
			(start -0.67945 -0.3048)
			(end -0.67945 0.3048)
			(stroke
				(width 0.1)
				(type default)
			)
			(layer "B.Fab")
		)
		(fp_line
			(start -0.67945 0.3048)
			(end -0.120396 0.3048)
			(stroke
				(width 0.1)
				(type default)
			)
			(layer "B.Fab")
		)
		(fp_line
			(start -0.12065 -0.3048)
			(end -0.67945 -0.3048)
			(stroke
				(width 0.1)
				(type default)
			)
			(layer "B.Fab")
		)
		(fp_line
			(start -0.12065 -0.2794)
			(end -0.12065 -0.3048)
			(stroke
				(width 0.1)
				(type default)
			)
			(layer "B.Fab")
		)
		(fp_line
			(start -0.120396 0.2794)
			(end 0.12065 0.2794)
			(stroke
				(width 0.1)
				(type default)
			)
			(layer "B.Fab")
		)
		(fp_line
			(start -0.120396 0.3048)
			(end -0.120396 0.2794)
			(stroke
				(width 0.1)
				(type default)
			)
			(layer "B.Fab")
		)
		(fp_line
			(start 0.12065 -0.305054)
			(end 0.12065 -0.2794)
			(stroke
				(width 0.1)
				(type default)
			)
			(layer "B.Fab")
		)
		(fp_line
			(start 0.12065 -0.2794)
			(end -0.12065 -0.2794)
			(stroke
				(width 0.1)
				(type default)
			)
			(layer "B.Fab")
		)
		(fp_line
			(start 0.12065 0.2794)
			(end 0.12065 0.3048)
			(stroke
				(width 0.1)
				(type default)
			)
			(layer "B.Fab")
		)
		(fp_line
			(start 0.12065 0.3048)
			(end 0.67945 0.3048)
			(stroke
				(width 0.1)
				(type default)
			)
			(layer "B.Fab")
		)
		(fp_line
			(start 0.67945 -0.305054)
			(end 0.12065 -0.305054)
			(stroke
				(width 0.1)
				(type default)
			)
			(layer "B.Fab")
		)
		(fp_line
			(start 0.67945 0.3048)
			(end 0.67945 -0.305054)
			(stroke
				(width 0.1)
				(type default)
			)
			(layer "B.Fab")
		)
		(pad "1" smd circle
			(at 0.40005 0 180)
			(size 0 0)
			(layers "B.Cu" "B.Mask" "B.Paste")
			(net "PVDD11_S3_P1")
		)
		(pad "2" smd circle
			(at -0.40005 0 180)
			(size 0 0)
			(layers "B.Cu" "B.Mask" "B.Paste")
			(net "GND")
		)
	)
	(footprint ""
		(layer "B.Cu")
		(at 205.146148 -129.074164)
		(property "Reference" "R6807"
			(at 0 0 0)
			(layer "B.SilkS")
			(hide yes)
			(effects
				(font
					(size 1.27 1.27)
				)
				(justify mirror)
			)
		)
		(property "Value" ""
			(at 0 0 0)
			(layer "B.Fab")
			(effects
				(font
					(size 1.27 1.27)
				)
				(justify mirror)
			)
		)
		(duplicate_pad_numbers_are_jumpers no)
		(fp_line
			(start -0.7874 -0.4064)
			(end -0.7874 0.4064)
			(stroke
				(width 0.1524)
				(type default)
			)
			(layer "B.SilkS")
		)
		(fp_line
			(start -0.7874 0.4064)
			(end 0.7874 0.4064)
			(stroke
				(width 0.1524)
				(type default)
			)
			(layer "B.SilkS")
		)
		(fp_line
			(start 0.7874 -0.4064)
			(end -0.7874 -0.4064)
			(stroke
				(width 0.1524)
				(type default)
			)
			(layer "B.SilkS")
		)
		(fp_line
			(start 0.7874 0.4064)
			(end 0.7874 -0.4064)
			(stroke
				(width 0.1524)
				(type default)
			)
			(layer "B.SilkS")
		)
		(fp_line
			(start -0.67945 -0.3048)
			(end -0.67945 0.3048)
			(stroke
				(width 0.1)
				(type default)
			)
			(layer "B.Fab")
		)
		(fp_line
			(start -0.67945 0.3048)
			(end -0.120396 0.3048)
			(stroke
				(width 0.1)
				(type default)
			)
			(layer "B.Fab")
		)
		(fp_line
			(start -0.12065 -0.3048)
			(end -0.67945 -0.3048)
			(stroke
				(width 0.1)
				(type default)
			)
			(layer "B.Fab")
		)
		(fp_line
			(start -0.12065 -0.2794)
			(end -0.12065 -0.3048)
			(stroke
				(width 0.1)
				(type default)
			)
			(layer "B.Fab")
		)
		(fp_line
			(start -0.120396 0.2794)
			(end 0.12065 0.2794)
			(stroke
				(width 0.1)
				(type default)
			)
			(layer "B.Fab")
		)
		(fp_line
			(start -0.120396 0.3048)
			(end -0.120396 0.2794)
			(stroke
				(width 0.1)
				(type default)
			)
			(layer "B.Fab")
		)
		(fp_line
			(start 0.12065 -0.305054)
			(end 0.12065 -0.2794)
			(stroke
				(width 0.1)
				(type default)
			)
			(layer "B.Fab")
		)
		(fp_line
			(start 0.12065 -0.2794)
			(end -0.12065 -0.2794)
			(stroke
				(width 0.1)
				(type default)
			)
			(layer "B.Fab")
		)
		(fp_line
			(start 0.12065 0.2794)
			(end 0.12065 0.3048)
			(stroke
				(width 0.1)
				(type default)
			)
			(layer "B.Fab")
		)
		(fp_line
			(start 0.12065 0.3048)
			(end 0.67945 0.3048)
			(stroke
				(width 0.1)
				(type default)
			)
			(layer "B.Fab")
		)
		(fp_line
			(start 0.67945 -0.305054)
			(end 0.12065 -0.305054)
			(stroke
				(width 0.1)
				(type default)
			)
			(layer "B.Fab")
		)
		(fp_line
			(start 0.67945 0.3048)
			(end 0.67945 -0.305054)
			(stroke
				(width 0.1)
				(type default)
			)
			(layer "B.Fab")
		)
		(pad "1" smd circle
			(at 0.40005 0 180)
			(size 0 0)
			(layers "B.Cu" "B.Mask" "B.Paste")
			(net "RST_RT_CPU0_P1_RESET_R_N")
		)
		(pad "2" smd circle
			(at -0.40005 0 180)
			(size 0 0)
			(layers "B.Cu" "B.Mask" "B.Paste")
			(net "RST_RT_CPU0_P1_RESET_R2_N")
		)
	)
	(footprint ""
		(layer "B.Cu")
		(at 364.461806 -401.624546 180)
		(property "Reference" "R1095"
			(at 0 0 0)
			(layer "B.SilkS")
			(hide yes)
			(effects
				(font
					(size 1.27 1.27)
				)
				(justify mirror)
			)
		)
		(property "Value" ""
			(at 0 0 0)
			(layer "B.Fab")
			(effects
				(font
					(size 1.27 1.27)
				)
				(justify mirror)
			)
		)
		(duplicate_pad_numbers_are_jumpers no)
		(fp_line
			(start 1.2954 0.5842)
			(end 1.2954 -0.5842)
			(stroke
				(width 0.1524)
				(type default)
			)
			(layer "B.SilkS")
		)
		(fp_line
			(start 1.2954 -0.5842)
			(end -1.2954 -0.5842)
			(stroke
				(width 0.1524)
				(type default)
			)
			(layer "B.SilkS")
		)
		(fp_line
			(start -1.2954 0.5842)
			(end 1.2954 0.5842)
			(stroke
				(width 0.1524)
				(type default)
			)
			(layer "B.SilkS")
		)
		(fp_line
			(start -1.2954 -0.5842)
			(end -1.2954 0.5842)
			(stroke
				(width 0.1524)
				(type default)
			)
			(layer "B.SilkS")
		)
		(fp_line
			(start 1.1938 0.4064)
			(end 1.1938 -0.406654)
			(stroke
				(width 0.1)
				(type default)
			)
			(layer "B.Fab")
		)
		(fp_line
			(start 1.1938 -0.406654)
			(end 0.8636 -0.406654)
			(stroke
				(width 0.1)
				(type default)
			)
			(layer "B.Fab")
		)
		(fp_line
			(start 0.8636 0.4572)
			(end 0.8636 0.4318)
			(stroke
				(width 0.1)
				(type default)
			)
			(layer "B.Fab")
		)
		(fp_line
			(start 0.8636 0.4318)
			(end 0.8636 0.4064)
			(stroke
				(width 0.1)
				(type default)
			)
			(layer "B.Fab")
		)
		(fp_line
			(start 0.8636 0.4064)
			(end 1.1938 0.4064)
			(stroke
				(width 0.1)
				(type default)
			)
			(layer "B.Fab")
		)
		(fp_line
			(start 0.8636 -0.406654)
			(end 0.8636 -0.4572)
			(stroke
				(width 0.1)
				(type default)
			)
			(layer "B.Fab")
		)
		(fp_line
			(start 0.8636 -0.4572)
			(end -0.8636 -0.4572)
			(stroke
				(width 0.1)
				(type default)
			)
			(layer "B.Fab")
		)
		(fp_line
			(start -0.8636 0.4572)
			(end 0.8636 0.4572)
			(stroke
				(width 0.1)
				(type default)
			)
			(layer "B.Fab")
		)
		(fp_line
			(start -0.8636 0.4064)
			(end -0.8636 0.4572)
			(stroke
				(width 0.1)
				(type default)
			)
			(layer "B.Fab")
		)
		(fp_line
			(start -0.8636 -0.406654)
			(end -1.1938 -0.406654)
			(stroke
				(width 0.1)
				(type default)
			)
			(layer "B.Fab")
		)
		(fp_line
			(start -0.8636 -0.4572)
			(end -0.8636 -0.406654)
			(stroke
				(width 0.1)
				(type default)
			)
			(layer "B.Fab")
		)
		(fp_line
			(start -1.1938 0.4064)
			(end -0.8636 0.4064)
			(stroke
				(width 0.1)
				(type default)
			)
			(layer "B.Fab")
		)
		(fp_line
			(start -1.1938 -0.406654)
			(end -1.1938 0.4064)
			(stroke
				(width 0.1)
				(type default)
			)
			(layer "B.Fab")
		)
		(pad "1" smd rect
			(at 0.7366 0 90)
			(size 0.7112 0.8128)
			(layers "B.Cu" "B.Mask" "B.Paste")
			(net "P0V9_CPU0_RT3_2A_2D")
		)
		(pad "2" smd rect
			(at -0.7366 0 90)
			(size 0.7112 0.8128)
			(layers "B.Cu" "B.Mask" "B.Paste")
			(net "P0V9_CPU0_RT3_2A")
		)
	)
	(footprint ""
		(layer "B.Cu")
		(at 228.473508 -325.425562 180)
		(property "Reference" "C1087"
			(at 0 0 0)
			(layer "B.SilkS")
			(hide yes)
			(effects
				(font
					(size 1.27 1.27)
				)
				(justify mirror)
			)
		)
		(property "Value" ""
			(at 0 0 0)
			(layer "B.Fab")
			(effects
				(font
					(size 1.27 1.27)
				)
				(justify mirror)
			)
		)
		(duplicate_pad_numbers_are_jumpers no)
		(fp_line
			(start 0.7874 0.4064)
			(end 0.7874 -0.4064)
			(stroke
				(width 0.1524)
				(type default)
			)
			(layer "B.SilkS")
		)
		(fp_line
			(start 0.7874 -0.4064)
			(end -0.7874 -0.4064)
			(stroke
				(width 0.1524)
				(type default)
			)
			(layer "B.SilkS")
		)
		(fp_line
			(start -0.7874 0.4064)
			(end 0.7874 0.4064)
			(stroke
				(width 0.1524)
				(type default)
			)
			(layer "B.SilkS")
		)
		(fp_line
			(start -0.7874 -0.4064)
			(end -0.7874 0.4064)
			(stroke
				(width 0.1524)
				(type default)
			)
			(layer "B.SilkS")
		)
		(fp_line
			(start 0.67945 0.3048)
			(end 0.67945 -0.305054)
			(stroke
				(width 0.1)
				(type default)
			)
			(layer "B.Fab")
		)
		(fp_line
			(start 0.67945 -0.305054)
			(end 0.12065 -0.305054)
			(stroke
				(width 0.1)
				(type default)
			)
			(layer "B.Fab")
		)
		(fp_line
			(start 0.12065 0.3048)
			(end 0.67945 0.3048)
			(stroke
				(width 0.1)
				(type default)
			)
			(layer "B.Fab")
		)
		(fp_line
			(start 0.12065 0.2794)
			(end 0.12065 0.3048)
			(stroke
				(width 0.1)
				(type default)
			)
			(layer "B.Fab")
		)
		(fp_line
			(start 0.12065 -0.2794)
			(end -0.12065 -0.2794)
			(stroke
				(width 0.1)
				(type default)
			)
			(layer "B.Fab")
		)
		(fp_line
			(start 0.12065 -0.305054)
			(end 0.12065 -0.2794)
			(stroke
				(width 0.1)
				(type default)
			)
			(layer "B.Fab")
		)
		(fp_line
			(start -0.120396 0.3048)
			(end -0.120396 0.2794)
			(stroke
				(width 0.1)
				(type default)
			)
			(layer "B.Fab")
		)
		(fp_line
			(start -0.120396 0.2794)
			(end 0.12065 0.2794)
			(stroke
				(width 0.1)
				(type default)
			)
			(layer "B.Fab")
		)
		(fp_line
			(start -0.12065 -0.2794)
			(end -0.12065 -0.3048)
			(stroke
				(width 0.1)
				(type default)
			)
			(layer "B.Fab")
		)
		(fp_line
			(start -0.12065 -0.3048)
			(end -0.67945 -0.3048)
			(stroke
				(width 0.1)
				(type default)
			)
			(layer "B.Fab")
		)
		(fp_line
			(start -0.67945 0.3048)
			(end -0.120396 0.3048)
			(stroke
				(width 0.1)
				(type default)
			)
			(layer "B.Fab")
		)
		(fp_line
			(start -0.67945 -0.3048)
			(end -0.67945 0.3048)
			(stroke
				(width 0.1)
				(type default)
			)
			(layer "B.Fab")
		)
		(pad "1" smd circle
			(at 0.40005 0)
			(size 0 0)
			(layers "B.Cu" "B.Mask" "B.Paste")
			(net "P1V8_CPU0_RT_1D_ADC_TIC")
		)
		(pad "2" smd circle
			(at -0.40005 0)
			(size 0 0)
			(layers "B.Cu" "B.Mask" "B.Paste")
			(net "GND")
		)
	)
	(footprint ""
		(layer "B.Cu")
		(at 249.904504 -325.613522)
		(property "Reference" "U50"
			(at 1.648968 -3.641852 0)
			(unlocked yes)
			(layer "B.SilkS")
			(effects
				(font
					(size 0.7874 0.5842)
					(thickness 0.1524)
				)
				(justify left mirror)
			)
		)
		(property "Value" ""
			(at 0 0 0)
			(layer "B.Fab")
			(effects
				(font
					(size 1.27 1.27)
				)
				(justify mirror)
			)
		)
		(duplicate_pad_numbers_are_jumpers no)
		(fp_line
			(start -1.715516 -2.489962)
			(end -1.092962 -2.489962)
			(stroke
				(width 0.1524)
				(type default)
			)
			(layer "B.SilkS")
		)
		(fp_line
			(start -1.715516 2.489962)
			(end -1.715516 -2.489962)
			(stroke
				(width 0.1524)
				(type default)
			)
			(layer "B.SilkS")
		)
		(fp_line
			(start -1.092962 -2.489962)
			(end 0 -1.397)
			(stroke
				(width 0.1524)
				(type default)
			)
			(layer "B.SilkS")
		)
		(fp_line
			(start 0 -1.397)
			(end 1.092962 -2.489962)
			(stroke
				(width 0.1524)
				(type default)
			)
			(layer "B.SilkS")
		)
		(fp_line
			(start 1.092962 -2.489962)
			(end 1.715516 -2.489962)
			(stroke
				(width 0.1524)
				(type default)
			)
			(layer "B.SilkS")
		)
		(fp_line
			(start 1.715516 -2.489962)
			(end 1.715516 2.489962)
			(stroke
				(width 0.1524)
				(type default)
			)
			(layer "B.SilkS")
		)
		(fp_line
			(start 1.715516 2.489962)
			(end -1.715516 2.489962)
			(stroke
				(width 0.1524)
				(type default)
			)
			(layer "B.SilkS")
		)
		(fp_poly
			(pts
				(xy 5.225796 -2.72161) (xy 5.225796 -1.70561) (xy 4.209796 -2.21361)
			)
			(stroke
				(width 0)
				(type default)
			)
			(fill yes)
			(layer "B.SilkS")
		)
		(fp_line
			(start -1.994916 -2.489962)
			(end 1.994916 -2.489962)
			(stroke
				(width 0.1)
				(type default)
			)
			(layer "B.Fab")
		)
		(fp_line
			(start -1.994916 2.489962)
			(end -1.994916 -2.489962)
			(stroke
				(width 0.1)
				(type default)
			)
			(layer "B.Fab")
		)
		(fp_line
			(start 1.994916 -2.489962)
			(end 1.994916 2.489962)
			(stroke
				(width 0.1)
				(type default)
			)
			(layer "B.Fab")
		)
		(fp_line
			(start 1.994916 2.489962)
			(end -1.994916 2.489962)
			(stroke
				(width 0.1)
				(type default)
			)
			(layer "B.Fab")
		)
		(fp_poly
			(pts
				(xy 4.699 -2.7305) (xy 4.699 -1.7145) (xy 3.683 -2.2225)
			)
			(stroke
				(width 0)
				(type default)
			)
			(fill yes)
			(layer "B.Fab")
		)
		(pad "1" smd rect
			(at 2.655062 -2.2225 90)
			(size 0.381 1.6002)
			(layers "B.Cu" "B.Mask" "B.Paste")
			(net "MAX11617_2_VREF_R")
		)
		(pad "2" smd rect
			(at 2.655062 -1.5875 90)
			(size 0.381 1.6002)
			(layers "B.Cu" "B.Mask" "B.Paste")
			(net "GND")
		)
		(pad "3" smd rect
			(at 2.655062 -0.9525 90)
			(size 0.381 1.6002)
			(layers "B.Cu" "B.Mask" "B.Paste")
			(net "GND")
		)
		(pad "4" smd rect
			(at 2.655062 -0.3175 90)
			(size 0.381 1.6002)
			(layers "B.Cu" "B.Mask" "B.Paste")
			(net "GND")
		)
		(pad "5" smd rect
			(at 2.655062 0.3175 90)
			(size 0.381 1.6002)
			(layers "B.Cu" "B.Mask" "B.Paste")
			(net "P5V_AUX_ADC_MAM")
		)
		(pad "6" smd rect
			(at 2.655062 0.9525 90)
			(size 0.381 1.6002)
			(layers "B.Cu" "B.Mask" "B.Paste")
			(net "P1V8_AUX_ADC_MAM")
		)
		(pad "7" smd rect
			(at 2.655062 1.5875 90)
			(size 0.381 1.6002)
			(layers "B.Cu" "B.Mask" "B.Paste")
			(net "P1V2_AUX_ADC_MAM")
		)
		(pad "8" smd rect
			(at 2.655062 2.2225 90)
			(size 0.381 1.6002)
			(layers "B.Cu" "B.Mask" "B.Paste")
			(net "P1V8_CPU0_RT_1D_ADC_MAM")
		)
		(pad "9" smd rect
			(at -2.655062 2.2225 90)
			(size 0.381 1.6002)
			(layers "B.Cu" "B.Mask" "B.Paste")
			(net "P1V8_CPU1_RT_1D_ADC_MAM")
		)
		(pad "10" smd rect
			(at -2.655062 1.5875 90)
			(size 0.381 1.6002)
			(layers "B.Cu" "B.Mask" "B.Paste")
			(net "PVDD_33_S5_ADC_MAM")
		)
		(pad "11" smd rect
			(at -2.655062 0.9525 90)
			(size 0.381 1.6002)
			(layers "B.Cu" "B.Mask" "B.Paste")
			(net "PVDD18_S5_P0_ADC_MAM")
		)
		(pad "12" smd rect
			(at -2.655062 0.3175 90)
			(size 0.381 1.6002)
			(layers "B.Cu" "B.Mask" "B.Paste")
			(net "PVDD18_S5_P1_ADC_MAM")
		)
		(pad "13" smd rect
			(at -2.655062 -0.3175 90)
			(size 0.381 1.6002)
			(layers "B.Cu" "B.Mask" "B.Paste")
			(net "SMB_SEN_MAM_2_3V3AUX_SCL")
		)
		(pad "14" smd rect
			(at -2.655062 -0.9525 90)
			(size 0.381 1.6002)
			(layers "B.Cu" "B.Mask" "B.Paste")
			(net "SMB_SEN_MAM_2_3V3AUX_SDA")
		)
		(pad "15" smd rect
			(at -2.655062 -1.5875 90)
			(size 0.381 1.6002)
			(layers "B.Cu" "B.Mask" "B.Paste")
			(net "GND")
		)
		(pad "16" smd rect
			(at -2.655062 -2.2225 90)
			(size 0.381 1.6002)
			(layers "B.Cu" "B.Mask" "B.Paste")
			(net "P3V3_MAX11617_2_VDD")
		)
	)
	(footprint ""
		(layer "B.Cu")
		(at 109.550454 -32.587438 180)
		(property "Reference" "C6092"
			(at 0 0 0)
			(layer "B.SilkS")
			(hide yes)
			(effects
				(font
					(size 1.27 1.27)
				)
				(justify mirror)
			)
		)
		(property "Value" ""
			(at 0 0 0)
			(layer "B.Fab")
			(effects
				(font
					(size 1.27 1.27)
				)
				(justify mirror)
			)
		)
		(duplicate_pad_numbers_are_jumpers no)
		(fp_line
			(start 0.7874 0.4064)
			(end 0.7874 -0.4064)
			(stroke
				(width 0.1524)
				(type default)
			)
			(layer "B.SilkS")
		)
		(fp_line
			(start 0.7874 -0.4064)
			(end -0.7874 -0.4064)
			(stroke
				(width 0.1524)
				(type default)
			)
			(layer "B.SilkS")
		)
		(fp_line
			(start -0.7874 0.4064)
			(end 0.7874 0.4064)
			(stroke
				(width 0.1524)
				(type default)
			)
			(layer "B.SilkS")
		)
		(fp_line
			(start -0.7874 -0.4064)
			(end -0.7874 0.4064)
			(stroke
				(width 0.1524)
				(type default)
			)
			(layer "B.SilkS")
		)
		(fp_line
			(start 0.67945 0.3048)
			(end 0.67945 -0.305054)
			(stroke
				(width 0.1)
				(type default)
			)
			(layer "B.Fab")
		)
		(fp_line
			(start 0.67945 -0.305054)
			(end 0.12065 -0.305054)
			(stroke
				(width 0.1)
				(type default)
			)
			(layer "B.Fab")
		)
		(fp_line
			(start 0.12065 0.3048)
			(end 0.67945 0.3048)
			(stroke
				(width 0.1)
				(type default)
			)
			(layer "B.Fab")
		)
		(fp_line
			(start 0.12065 0.2794)
			(end 0.12065 0.3048)
			(stroke
				(width 0.1)
				(type default)
			)
			(layer "B.Fab")
		)
		(fp_line
			(start 0.12065 -0.2794)
			(end -0.12065 -0.2794)
			(stroke
				(width 0.1)
				(type default)
			)
			(layer "B.Fab")
		)
		(fp_line
			(start 0.12065 -0.305054)
			(end 0.12065 -0.2794)
			(stroke
				(width 0.1)
				(type default)
			)
			(layer "B.Fab")
		)
		(fp_line
			(start -0.120396 0.3048)
			(end -0.120396 0.2794)
			(stroke
				(width 0.1)
				(type default)
			)
			(layer "B.Fab")
		)
		(fp_line
			(start -0.120396 0.2794)
			(end 0.12065 0.2794)
			(stroke
				(width 0.1)
				(type default)
			)
			(layer "B.Fab")
		)
		(fp_line
			(start -0.12065 -0.2794)
			(end -0.12065 -0.3048)
			(stroke
				(width 0.1)
				(type default)
			)
			(layer "B.Fab")
		)
		(fp_line
			(start -0.12065 -0.3048)
			(end -0.67945 -0.3048)
			(stroke
				(width 0.1)
				(type default)
			)
			(layer "B.Fab")
		)
		(fp_line
			(start -0.67945 0.3048)
			(end -0.120396 0.3048)
			(stroke
				(width 0.1)
				(type default)
			)
			(layer "B.Fab")
		)
		(fp_line
			(start -0.67945 -0.3048)
			(end -0.67945 0.3048)
			(stroke
				(width 0.1)
				(type default)
			)
			(layer "B.Fab")
		)
		(pad "1" smd circle
			(at 0.40005 0)
			(size 0 0)
			(layers "B.Cu" "B.Mask" "B.Paste")
			(net "P3V3_AUX_CPU0_USB2_AVDD33")
		)
		(pad "2" smd circle
			(at -0.40005 0)
			(size 0 0)
			(layers "B.Cu" "B.Mask" "B.Paste")
			(net "GND")
		)
	)
	(footprint ""
		(layer "B.Cu")
		(at 320.616326 -416.899344 90)
		(property "Reference" "C6544"
			(at 0 0 90)
			(layer "B.SilkS")
			(hide yes)
			(effects
				(font
					(size 1.27 1.27)
				)
				(justify mirror)
			)
		)
		(property "Value" ""
			(at 0 0 90)
			(layer "B.Fab")
			(effects
				(font
					(size 1.27 1.27)
				)
				(justify mirror)
			)
		)
		(duplicate_pad_numbers_are_jumpers no)
		(fp_line
			(start 0.299974 -0.150114)
			(end -0.299974 -0.150114)
			(stroke
				(width 0.1)
				(type default)
			)
			(layer "B.Fab")
		)
		(fp_line
			(start -0.299974 -0.150114)
			(end -0.299974 0.150114)
			(stroke
				(width 0.1)
				(type default)
			)
			(layer "B.Fab")
		)
		(fp_line
			(start 0.299974 0.150114)
			(end 0.299974 -0.150114)
			(stroke
				(width 0.1)
				(type default)
			)
			(layer "B.Fab")
		)
		(fp_line
			(start -0.299974 0.150114)
			(end 0.299974 0.150114)
			(stroke
				(width 0.1)
				(type default)
			)
			(layer "B.Fab")
		)
		(pad "1" smd rect
			(at 0.2667 0 270)
			(size 0.3048 0.381)
			(layers "B.Cu" "B.Mask" "B.Paste")
			(net "P5E_CPU0_P1_TX_BUF_C_DN<5>")
		)
		(pad "2" smd rect
			(at -0.2667 0 270)
			(size 0.3048 0.381)
			(layers "B.Cu" "B.Mask" "B.Paste")
			(net "P5E_CPU0_P1_TX_BUF_DN<5>")
		)
	)
	(footprint ""
		(layer "B.Cu")
		(at 428.98695 -42.357548 180)
		(property "Reference" "R1261"
			(at 0 0 0)
			(layer "B.SilkS")
			(hide yes)
			(effects
				(font
					(size 1.27 1.27)
				)
				(justify mirror)
			)
		)
		(property "Value" ""
			(at 0 0 0)
			(layer "B.Fab")
			(effects
				(font
					(size 1.27 1.27)
				)
				(justify mirror)
			)
		)
		(duplicate_pad_numbers_are_jumpers no)
		(fp_line
			(start 0.7874 0.4064)
			(end 0.7874 -0.4064)
			(stroke
				(width 0.1524)
				(type default)
			)
			(layer "B.SilkS")
		)
		(fp_line
			(start 0.7874 -0.4064)
			(end -0.7874 -0.4064)
			(stroke
				(width 0.1524)
				(type default)
			)
			(layer "B.SilkS")
		)
		(fp_line
			(start -0.7874 0.4064)
			(end 0.7874 0.4064)
			(stroke
				(width 0.1524)
				(type default)
			)
			(layer "B.SilkS")
		)
		(fp_line
			(start -0.7874 -0.4064)
			(end -0.7874 0.4064)
			(stroke
				(width 0.1524)
				(type default)
			)
			(layer "B.SilkS")
		)
		(fp_line
			(start 0.67945 0.3048)
			(end 0.67945 -0.305054)
			(stroke
				(width 0.1)
				(type default)
			)
			(layer "B.Fab")
		)
		(fp_line
			(start 0.67945 -0.305054)
			(end 0.12065 -0.305054)
			(stroke
				(width 0.1)
				(type default)
			)
			(layer "B.Fab")
		)
		(fp_line
			(start 0.12065 0.3048)
			(end 0.67945 0.3048)
			(stroke
				(width 0.1)
				(type default)
			)
			(layer "B.Fab")
		)
		(fp_line
			(start 0.12065 0.2794)
			(end 0.12065 0.3048)
			(stroke
				(width 0.1)
				(type default)
			)
			(layer "B.Fab")
		)
		(fp_line
			(start 0.12065 -0.2794)
			(end -0.12065 -0.2794)
			(stroke
				(width 0.1)
				(type default)
			)
			(layer "B.Fab")
		)
		(fp_line
			(start 0.12065 -0.305054)
			(end 0.12065 -0.2794)
			(stroke
				(width 0.1)
				(type default)
			)
			(layer "B.Fab")
		)
		(fp_line
			(start -0.120396 0.3048)
			(end -0.120396 0.2794)
			(stroke
				(width 0.1)
				(type default)
			)
			(layer "B.Fab")
		)
		(fp_line
			(start -0.120396 0.2794)
			(end 0.12065 0.2794)
			(stroke
				(width 0.1)
				(type default)
			)
			(layer "B.Fab")
		)
		(fp_line
			(start -0.12065 -0.2794)
			(end -0.12065 -0.3048)
			(stroke
				(width 0.1)
				(type default)
			)
			(layer "B.Fab")
		)
		(fp_line
			(start -0.12065 -0.3048)
			(end -0.67945 -0.3048)
			(stroke
				(width 0.1)
				(type default)
			)
			(layer "B.Fab")
		)
		(fp_line
			(start -0.67945 0.3048)
			(end -0.120396 0.3048)
			(stroke
				(width 0.1)
				(type default)
			)
			(layer "B.Fab")
		)
		(fp_line
			(start -0.67945 -0.3048)
			(end -0.67945 0.3048)
			(stroke
				(width 0.1)
				(type default)
			)
			(layer "B.Fab")
		)
		(pad "1" smd circle
			(at 0.40005 0)
			(size 0 0)
			(layers "B.Cu" "B.Mask" "B.Paste")
			(net "P1V8_AUX")
		)
		(pad "2" smd circle
			(at -0.40005 0)
			(size 0 0)
			(layers "B.Cu" "B.Mask" "B.Paste")
			(net "FM_SPD_CPU0_SWITCH_CTRL_N")
		)
	)
	(footprint ""
		(layer "B.Cu")
		(at 285.732982 -244.08511 180)
		(property "Reference" "R378"
			(at 0 0 0)
			(layer "B.SilkS")
			(hide yes)
			(effects
				(font
					(size 1.27 1.27)
				)
				(justify mirror)
			)
		)
		(property "Value" ""
			(at 0 0 0)
			(layer "B.Fab")
			(effects
				(font
					(size 1.27 1.27)
				)
				(justify mirror)
			)
		)
		(duplicate_pad_numbers_are_jumpers no)
		(fp_line
			(start 0.7874 0.4064)
			(end 0.7874 -0.4064)
			(stroke
				(width 0.1524)
				(type default)
			)
			(layer "B.SilkS")
		)
		(fp_line
			(start 0.7874 -0.4064)
			(end -0.7874 -0.4064)
			(stroke
				(width 0.1524)
				(type default)
			)
			(layer "B.SilkS")
		)
		(fp_line
			(start -0.7874 0.4064)
			(end 0.7874 0.4064)
			(stroke
				(width 0.1524)
				(type default)
			)
			(layer "B.SilkS")
		)
		(fp_line
			(start -0.7874 -0.4064)
			(end -0.7874 0.4064)
			(stroke
				(width 0.1524)
				(type default)
			)
			(layer "B.SilkS")
		)
		(fp_line
			(start 0.67945 0.3048)
			(end 0.67945 -0.305054)
			(stroke
				(width 0.1)
				(type default)
			)
			(layer "B.Fab")
		)
		(fp_line
			(start 0.67945 -0.305054)
			(end 0.12065 -0.305054)
			(stroke
				(width 0.1)
				(type default)
			)
			(layer "B.Fab")
		)
		(fp_line
			(start 0.12065 0.3048)
			(end 0.67945 0.3048)
			(stroke
				(width 0.1)
				(type default)
			)
			(layer "B.Fab")
		)
		(fp_line
			(start 0.12065 0.2794)
			(end 0.12065 0.3048)
			(stroke
				(width 0.1)
				(type default)
			)
			(layer "B.Fab")
		)
		(fp_line
			(start 0.12065 -0.2794)
			(end -0.12065 -0.2794)
			(stroke
				(width 0.1)
				(type default)
			)
			(layer "B.Fab")
		)
		(fp_line
			(start 0.12065 -0.305054)
			(end 0.12065 -0.2794)
			(stroke
				(width 0.1)
				(type default)
			)
			(layer "B.Fab")
		)
		(fp_line
			(start -0.120396 0.3048)
			(end -0.120396 0.2794)
			(stroke
				(width 0.1)
				(type default)
			)
			(layer "B.Fab")
		)
		(fp_line
			(start -0.120396 0.2794)
			(end 0.12065 0.2794)
			(stroke
				(width 0.1)
				(type default)
			)
			(layer "B.Fab")
		)
		(fp_line
			(start -0.12065 -0.2794)
			(end -0.12065 -0.3048)
			(stroke
				(width 0.1)
				(type default)
			)
			(layer "B.Fab")
		)
		(fp_line
			(start -0.12065 -0.3048)
			(end -0.67945 -0.3048)
			(stroke
				(width 0.1)
				(type default)
			)
			(layer "B.Fab")
		)
		(fp_line
			(start -0.67945 0.3048)
			(end -0.120396 0.3048)
			(stroke
				(width 0.1)
				(type default)
			)
			(layer "B.Fab")
		)
		(fp_line
			(start -0.67945 -0.3048)
			(end -0.67945 0.3048)
			(stroke
				(width 0.1)
				(type default)
			)
			(layer "B.Fab")
		)
		(pad "1" smd circle
			(at 0.40005 0)
			(size 0 0)
			(layers "B.Cu" "B.Mask" "B.Paste")
			(net "M_D_CPU0_ALERT_N")
		)
		(pad "2" smd circle
			(at -0.40005 0)
			(size 0 0)
			(layers "B.Cu" "B.Mask" "B.Paste")
			(net "M_D_CPU0_ALERT_R_N")
		)
	)
	(footprint ""
		(layer "B.Cu")
		(at 356.567232 -261.747762 90)
		(property "Reference" "C2609"
			(at 0 0 90)
			(layer "B.SilkS")
			(hide yes)
			(effects
				(font
					(size 1.27 1.27)
				)
				(justify mirror)
			)
		)
		(property "Value" ""
			(at 0 0 90)
			(layer "B.Fab")
			(effects
				(font
					(size 1.27 1.27)
				)
				(justify mirror)
			)
		)
		(duplicate_pad_numbers_are_jumpers no)
		(fp_line
			(start 0.7874 -0.4064)
			(end -0.7874 -0.4064)
			(stroke
				(width 0.1524)
				(type default)
			)
			(layer "B.SilkS")
		)
		(fp_line
			(start -0.7874 -0.4064)
			(end -0.7874 0.4064)
			(stroke
				(width 0.1524)
				(type default)
			)
			(layer "B.SilkS")
		)
		(fp_line
			(start 0.7874 0.4064)
			(end 0.7874 -0.4064)
			(stroke
				(width 0.1524)
				(type default)
			)
			(layer "B.SilkS")
		)
		(fp_line
			(start -0.7874 0.4064)
			(end 0.7874 0.4064)
			(stroke
				(width 0.1524)
				(type default)
			)
			(layer "B.SilkS")
		)
		(fp_line
			(start 0.67945 -0.305054)
			(end 0.12065 -0.305054)
			(stroke
				(width 0.1)
				(type default)
			)
			(layer "B.Fab")
		)
		(fp_line
			(start 0.12065 -0.305054)
			(end 0.12065 -0.2794)
			(stroke
				(width 0.1)
				(type default)
			)
			(layer "B.Fab")
		)
		(fp_line
			(start -0.12065 -0.3048)
			(end -0.67945 -0.3048)
			(stroke
				(width 0.1)
				(type default)
			)
			(layer "B.Fab")
		)
		(fp_line
			(start -0.67945 -0.3048)
			(end -0.67945 0.3048)
			(stroke
				(width 0.1)
				(type default)
			)
			(layer "B.Fab")
		)
		(fp_line
			(start 0.12065 -0.2794)
			(end -0.12065 -0.2794)
			(stroke
				(width 0.1)
				(type default)
			)
			(layer "B.Fab")
		)
		(fp_line
			(start -0.12065 -0.2794)
			(end -0.12065 -0.3048)
			(stroke
				(width 0.1)
				(type default)
			)
			(layer "B.Fab")
		)
		(fp_line
			(start 0.12065 0.2794)
			(end 0.12065 0.3048)
			(stroke
				(width 0.1)
				(type default)
			)
			(layer "B.Fab")
		)
		(fp_line
			(start -0.120396 0.2794)
			(end 0.12065 0.2794)
			(stroke
				(width 0.1)
				(type default)
			)
			(layer "B.Fab")
		)
		(fp_line
			(start 0.67945 0.3048)
			(end 0.67945 -0.305054)
			(stroke
				(width 0.1)
				(type default)
			)
			(layer "B.Fab")
		)
		(fp_line
			(start 0.12065 0.3048)
			(end 0.67945 0.3048)
			(stroke
				(width 0.1)
				(type default)
			)
			(layer "B.Fab")
		)
		(fp_line
			(start -0.120396 0.3048)
			(end -0.120396 0.2794)
			(stroke
				(width 0.1)
				(type default)
			)
			(layer "B.Fab")
		)
		(fp_line
			(start -0.67945 0.3048)
			(end -0.120396 0.3048)
			(stroke
				(width 0.1)
				(type default)
			)
			(layer "B.Fab")
		)
		(pad "1" smd circle
			(at 0.40005 0 270)
			(size 0 0)
			(layers "B.Cu" "B.Mask" "B.Paste")
			(net "PVDD11_S3_P0")
		)
		(pad "2" smd circle
			(at -0.40005 0 270)
			(size 0 0)
			(layers "B.Cu" "B.Mask" "B.Paste")
			(net "GND")
		)
	)
	(footprint ""
		(layer "B.Cu")
		(at 171.195492 -102.780084 180)
		(property "Reference" "R6147"
			(at 0 0 0)
			(layer "B.SilkS")
			(hide yes)
			(effects
				(font
					(size 1.27 1.27)
				)
				(justify mirror)
			)
		)
		(property "Value" ""
			(at 0 0 0)
			(layer "B.Fab")
			(effects
				(font
					(size 1.27 1.27)
				)
				(justify mirror)
			)
		)
		(duplicate_pad_numbers_are_jumpers no)
		(fp_line
			(start 0.7874 0.4064)
			(end 0.7874 -0.4064)
			(stroke
				(width 0.1524)
				(type default)
			)
			(layer "B.SilkS")
		)
		(fp_line
			(start 0.7874 -0.4064)
			(end -0.7874 -0.4064)
			(stroke
				(width 0.1524)
				(type default)
			)
			(layer "B.SilkS")
		)
		(fp_line
			(start -0.7874 0.4064)
			(end 0.7874 0.4064)
			(stroke
				(width 0.1524)
				(type default)
			)
			(layer "B.SilkS")
		)
		(fp_line
			(start -0.7874 -0.4064)
			(end -0.7874 0.4064)
			(stroke
				(width 0.1524)
				(type default)
			)
			(layer "B.SilkS")
		)
		(fp_line
			(start 0.67945 0.3048)
			(end 0.67945 -0.305054)
			(stroke
				(width 0.1)
				(type default)
			)
			(layer "B.Fab")
		)
		(fp_line
			(start 0.67945 -0.305054)
			(end 0.12065 -0.305054)
			(stroke
				(width 0.1)
				(type default)
			)
			(layer "B.Fab")
		)
		(fp_line
			(start 0.12065 0.3048)
			(end 0.67945 0.3048)
			(stroke
				(width 0.1)
				(type default)
			)
			(layer "B.Fab")
		)
		(fp_line
			(start 0.12065 0.2794)
			(end 0.12065 0.3048)
			(stroke
				(width 0.1)
				(type default)
			)
			(layer "B.Fab")
		)
		(fp_line
			(start 0.12065 -0.2794)
			(end -0.12065 -0.2794)
			(stroke
				(width 0.1)
				(type default)
			)
			(layer "B.Fab")
		)
		(fp_line
			(start 0.12065 -0.305054)
			(end 0.12065 -0.2794)
			(stroke
				(width 0.1)
				(type default)
			)
			(layer "B.Fab")
		)
		(fp_line
			(start -0.120396 0.3048)
			(end -0.120396 0.2794)
			(stroke
				(width 0.1)
				(type default)
			)
			(layer "B.Fab")
		)
		(fp_line
			(start -0.120396 0.2794)
			(end 0.12065 0.2794)
			(stroke
				(width 0.1)
				(type default)
			)
			(layer "B.Fab")
		)
		(fp_line
			(start -0.12065 -0.2794)
			(end -0.12065 -0.3048)
			(stroke
				(width 0.1)
				(type default)
			)
			(layer "B.Fab")
		)
		(fp_line
			(start -0.12065 -0.3048)
			(end -0.67945 -0.3048)
			(stroke
				(width 0.1)
				(type default)
			)
			(layer "B.Fab")
		)
		(fp_line
			(start -0.67945 0.3048)
			(end -0.120396 0.3048)
			(stroke
				(width 0.1)
				(type default)
			)
			(layer "B.Fab")
		)
		(fp_line
			(start -0.67945 -0.3048)
			(end -0.67945 0.3048)
			(stroke
				(width 0.1)
				(type default)
			)
			(layer "B.Fab")
		)
		(pad "1" smd circle
			(at 0.40005 0)
			(size 0 0)
			(layers "B.Cu" "B.Mask" "B.Paste")
			(net "P1V8_AUX")
		)
		(pad "2" smd circle
			(at -0.40005 0)
			(size 0 0)
			(layers "B.Cu" "B.Mask" "B.Paste")
			(net "FAB_BMC_REV_ID1")
		)
	)
	(footprint ""
		(layer "B.Cu")
		(at 329.459082 -326.30745 -90)
		(property "Reference" "PC106_2"
			(at 0 0 90)
			(layer "B.SilkS")
			(hide yes)
			(effects
				(font
					(size 1.27 1.27)
				)
				(justify mirror)
			)
		)
		(property "Value" ""
			(at 0 0 90)
			(layer "B.Fab")
			(effects
				(font
					(size 1.27 1.27)
				)
				(justify mirror)
			)
		)
		(duplicate_pad_numbers_are_jumpers no)
		(fp_line
			(start -1.524 0.762)
			(end 1.524 0.762)
			(stroke
				(width 0.1524)
				(type default)
			)
			(layer "B.SilkS")
		)
		(fp_line
			(start 1.524 0.762)
			(end 1.524 -0.762)
			(stroke
				(width 0.1524)
				(type default)
			)
			(layer "B.SilkS")
		)
		(fp_line
			(start -1.524 -0.762)
			(end -1.524 0.762)
			(stroke
				(width 0.1524)
				(type default)
			)
			(layer "B.SilkS")
		)
		(fp_line
			(start 1.524 -0.762)
			(end -1.524 -0.762)
			(stroke
				(width 0.1524)
				(type default)
			)
			(layer "B.SilkS")
		)
		(fp_line
			(start -1.1049 0.724916)
			(end -1.1049 -0.724916)
			(stroke
				(width 0.1)
				(type default)
			)
			(layer "B.Fab")
		)
		(fp_line
			(start 1.1049 0.724916)
			(end -1.1049 0.724916)
			(stroke
				(width 0.1)
				(type default)
			)
			(layer "B.Fab")
		)
		(fp_line
			(start -1.1049 -0.724916)
			(end 1.1049 -0.724916)
			(stroke
				(width 0.1)
				(type default)
			)
			(layer "B.Fab")
		)
		(fp_line
			(start 1.1049 -0.724916)
			(end 1.1049 0.724916)
			(stroke
				(width 0.1)
				(type default)
			)
			(layer "B.Fab")
		)
		(pad "1" smd rect
			(at 0.889 0 270)
			(size 1.016 1.27)
			(layers "B.Cu" "B.Mask" "B.Paste")
			(net "PVDDCR_CPU1_P0")
		)
		(pad "2" smd rect
			(at -0.889 0 270)
			(size 1.016 1.27)
			(layers "B.Cu" "B.Mask" "B.Paste")
			(net "GND")
		)
	)
	(footprint ""
		(layer "B.Cu")
		(at 330.731876 -66.708782 90)
		(property "Reference" "R3092"
			(at 0 0 90)
			(layer "B.SilkS")
			(hide yes)
			(effects
				(font
					(size 1.27 1.27)
				)
				(justify mirror)
			)
		)
		(property "Value" ""
			(at 0 0 90)
			(layer "B.Fab")
			(effects
				(font
					(size 1.27 1.27)
				)
				(justify mirror)
			)
		)
		(duplicate_pad_numbers_are_jumpers no)
		(fp_line
			(start 0.7874 -0.4064)
			(end -0.7874 -0.4064)
			(stroke
				(width 0.1524)
				(type default)
			)
			(layer "B.SilkS")
		)
		(fp_line
			(start -0.7874 -0.4064)
			(end -0.7874 0.4064)
			(stroke
				(width 0.1524)
				(type default)
			)
			(layer "B.SilkS")
		)
		(fp_line
			(start 0.7874 0.4064)
			(end 0.7874 -0.4064)
			(stroke
				(width 0.1524)
				(type default)
			)
			(layer "B.SilkS")
		)
		(fp_line
			(start -0.7874 0.4064)
			(end 0.7874 0.4064)
			(stroke
				(width 0.1524)
				(type default)
			)
			(layer "B.SilkS")
		)
		(fp_line
			(start 0.67945 -0.305054)
			(end 0.12065 -0.305054)
			(stroke
				(width 0.1)
				(type default)
			)
			(layer "B.Fab")
		)
		(fp_line
			(start 0.12065 -0.305054)
			(end 0.12065 -0.2794)
			(stroke
				(width 0.1)
				(type default)
			)
			(layer "B.Fab")
		)
		(fp_line
			(start -0.12065 -0.3048)
			(end -0.67945 -0.3048)
			(stroke
				(width 0.1)
				(type default)
			)
			(layer "B.Fab")
		)
		(fp_line
			(start -0.67945 -0.3048)
			(end -0.67945 0.3048)
			(stroke
				(width 0.1)
				(type default)
			)
			(layer "B.Fab")
		)
		(fp_line
			(start 0.12065 -0.2794)
			(end -0.12065 -0.2794)
			(stroke
				(width 0.1)
				(type default)
			)
			(layer "B.Fab")
		)
		(fp_line
			(start -0.12065 -0.2794)
			(end -0.12065 -0.3048)
			(stroke
				(width 0.1)
				(type default)
			)
			(layer "B.Fab")
		)
		(fp_line
			(start 0.12065 0.2794)
			(end 0.12065 0.3048)
			(stroke
				(width 0.1)
				(type default)
			)
			(layer "B.Fab")
		)
		(fp_line
			(start -0.120396 0.2794)
			(end 0.12065 0.2794)
			(stroke
				(width 0.1)
				(type default)
			)
			(layer "B.Fab")
		)
		(fp_line
			(start 0.67945 0.3048)
			(end 0.67945 -0.305054)
			(stroke
				(width 0.1)
				(type default)
			)
			(layer "B.Fab")
		)
		(fp_line
			(start 0.12065 0.3048)
			(end 0.67945 0.3048)
			(stroke
				(width 0.1)
				(type default)
			)
			(layer "B.Fab")
		)
		(fp_line
			(start -0.120396 0.3048)
			(end -0.120396 0.2794)
			(stroke
				(width 0.1)
				(type default)
			)
			(layer "B.Fab")
		)
		(fp_line
			(start -0.67945 0.3048)
			(end -0.120396 0.3048)
			(stroke
				(width 0.1)
				(type default)
			)
			(layer "B.Fab")
		)
		(pad "1" smd circle
			(at 0.40005 0 270)
			(size 0 0)
			(layers "B.Cu" "B.Mask" "B.Paste")
			(net "LED_PWRGD_PVDDIO_P0_R")
		)
		(pad "2" smd circle
			(at -0.40005 0 270)
			(size 0 0)
			(layers "B.Cu" "B.Mask" "B.Paste")
			(net "P3V3_AUX")
		)
	)
	(footprint ""
		(layer "B.Cu")
		(at 403.14626 -396.393162 -90)
		(property "Reference" "C968"
			(at 0 0 90)
			(layer "B.SilkS")
			(hide yes)
			(effects
				(font
					(size 1.27 1.27)
				)
				(justify mirror)
			)
		)
		(property "Value" ""
			(at 0 0 90)
			(layer "B.Fab")
			(effects
				(font
					(size 1.27 1.27)
				)
				(justify mirror)
			)
		)
		(duplicate_pad_numbers_are_jumpers no)
		(fp_line
			(start -0.299974 0.150114)
			(end 0.299974 0.150114)
			(stroke
				(width 0.1)
				(type default)
			)
			(layer "B.Fab")
		)
		(fp_line
			(start 0.299974 0.150114)
			(end 0.299974 -0.150114)
			(stroke
				(width 0.1)
				(type default)
			)
			(layer "B.Fab")
		)
		(fp_line
			(start -0.299974 -0.150114)
			(end -0.299974 0.150114)
			(stroke
				(width 0.1)
				(type default)
			)
			(layer "B.Fab")
		)
		(fp_line
			(start 0.299974 -0.150114)
			(end -0.299974 -0.150114)
			(stroke
				(width 0.1)
				(type default)
			)
			(layer "B.Fab")
		)
		(pad "1" smd rect
			(at 0.2667 0 90)
			(size 0.3048 0.381)
			(layers "B.Cu" "B.Mask" "B.Paste")
			(net "P0V9_CPU0_RT2_2A")
		)
		(pad "2" smd rect
			(at -0.2667 0 90)
			(size 0.3048 0.381)
			(layers "B.Cu" "B.Mask" "B.Paste")
			(net "GND")
		)
	)
	(footprint ""
		(layer "B.Cu")
		(at 354.425758 -250.89231 180)
		(property "Reference" "C2170"
			(at 0 0 0)
			(layer "B.SilkS")
			(hide yes)
			(effects
				(font
					(size 1.27 1.27)
				)
				(justify mirror)
			)
		)
		(property "Value" ""
			(at 0 0 0)
			(layer "B.Fab")
			(effects
				(font
					(size 1.27 1.27)
				)
				(justify mirror)
			)
		)
		(duplicate_pad_numbers_are_jumpers no)
		(fp_line
			(start 0.7874 0.4064)
			(end 0.7874 -0.4064)
			(stroke
				(width 0.1524)
				(type default)
			)
			(layer "B.SilkS")
		)
		(fp_line
			(start 0.7874 -0.4064)
			(end -0.7874 -0.4064)
			(stroke
				(width 0.1524)
				(type default)
			)
			(layer "B.SilkS")
		)
		(fp_line
			(start -0.7874 0.4064)
			(end 0.7874 0.4064)
			(stroke
				(width 0.1524)
				(type default)
			)
			(layer "B.SilkS")
		)
		(fp_line
			(start -0.7874 -0.4064)
			(end -0.7874 0.4064)
			(stroke
				(width 0.1524)
				(type default)
			)
			(layer "B.SilkS")
		)
		(fp_line
			(start 0.67945 0.3048)
			(end 0.67945 -0.305054)
			(stroke
				(width 0.1)
				(type default)
			)
			(layer "B.Fab")
		)
		(fp_line
			(start 0.67945 -0.305054)
			(end 0.12065 -0.305054)
			(stroke
				(width 0.1)
				(type default)
			)
			(layer "B.Fab")
		)
		(fp_line
			(start 0.12065 0.3048)
			(end 0.67945 0.3048)
			(stroke
				(width 0.1)
				(type default)
			)
			(layer "B.Fab")
		)
		(fp_line
			(start 0.12065 0.2794)
			(end 0.12065 0.3048)
			(stroke
				(width 0.1)
				(type default)
			)
			(layer "B.Fab")
		)
		(fp_line
			(start 0.12065 -0.2794)
			(end -0.12065 -0.2794)
			(stroke
				(width 0.1)
				(type default)
			)
			(layer "B.Fab")
		)
		(fp_line
			(start 0.12065 -0.305054)
			(end 0.12065 -0.2794)
			(stroke
				(width 0.1)
				(type default)
			)
			(layer "B.Fab")
		)
		(fp_line
			(start -0.120396 0.3048)
			(end -0.120396 0.2794)
			(stroke
				(width 0.1)
				(type default)
			)
			(layer "B.Fab")
		)
		(fp_line
			(start -0.120396 0.2794)
			(end 0.12065 0.2794)
			(stroke
				(width 0.1)
				(type default)
			)
			(layer "B.Fab")
		)
		(fp_line
			(start -0.12065 -0.2794)
			(end -0.12065 -0.3048)
			(stroke
				(width 0.1)
				(type default)
			)
			(layer "B.Fab")
		)
		(fp_line
			(start -0.12065 -0.3048)
			(end -0.67945 -0.3048)
			(stroke
				(width 0.1)
				(type default)
			)
			(layer "B.Fab")
		)
		(fp_line
			(start -0.67945 0.3048)
			(end -0.120396 0.3048)
			(stroke
				(width 0.1)
				(type default)
			)
			(layer "B.Fab")
		)
		(fp_line
			(start -0.67945 -0.3048)
			(end -0.67945 0.3048)
			(stroke
				(width 0.1)
				(type default)
			)
			(layer "B.Fab")
		)
		(pad "1" smd circle
			(at 0.40005 0)
			(size 0 0)
			(layers "B.Cu" "B.Mask" "B.Paste")
			(net "PVDDCR_CPU0_P0")
		)
		(pad "2" smd circle
			(at -0.40005 0)
			(size 0 0)
			(layers "B.Cu" "B.Mask" "B.Paste")
			(net "GND")
		)
	)
	(footprint ""
		(layer "B.Cu")
		(at 208.461356 -383.612136)
		(property "Reference" "PR2518"
			(at 0 0 0)
			(layer "B.SilkS")
			(hide yes)
			(effects
				(font
					(size 1.27 1.27)
				)
				(justify mirror)
			)
		)
		(property "Value" ""
			(at 0 0 0)
			(layer "B.Fab")
			(effects
				(font
					(size 1.27 1.27)
				)
				(justify mirror)
			)
		)
		(duplicate_pad_numbers_are_jumpers no)
		(fp_line
			(start -0.7874 -0.4064)
			(end -0.7874 0.4064)
			(stroke
				(width 0.1524)
				(type default)
			)
			(layer "B.SilkS")
		)
		(fp_line
			(start -0.7874 0.4064)
			(end 0.7874 0.4064)
			(stroke
				(width 0.1524)
				(type default)
			)
			(layer "B.SilkS")
		)
		(fp_line
			(start 0.7874 -0.4064)
			(end -0.7874 -0.4064)
			(stroke
				(width 0.1524)
				(type default)
			)
			(layer "B.SilkS")
		)
		(fp_line
			(start 0.7874 0.4064)
			(end 0.7874 -0.4064)
			(stroke
				(width 0.1524)
				(type default)
			)
			(layer "B.SilkS")
		)
		(fp_line
			(start -0.67945 -0.3048)
			(end -0.67945 0.3048)
			(stroke
				(width 0.1)
				(type default)
			)
			(layer "B.Fab")
		)
		(fp_line
			(start -0.67945 0.3048)
			(end -0.120396 0.3048)
			(stroke
				(width 0.1)
				(type default)
			)
			(layer "B.Fab")
		)
		(fp_line
			(start -0.12065 -0.3048)
			(end -0.67945 -0.3048)
			(stroke
				(width 0.1)
				(type default)
			)
			(layer "B.Fab")
		)
		(fp_line
			(start -0.12065 -0.2794)
			(end -0.12065 -0.3048)
			(stroke
				(width 0.1)
				(type default)
			)
			(layer "B.Fab")
		)
		(fp_line
			(start -0.120396 0.2794)
			(end 0.12065 0.2794)
			(stroke
				(width 0.1)
				(type default)
			)
			(layer "B.Fab")
		)
		(fp_line
			(start -0.120396 0.3048)
			(end -0.120396 0.2794)
			(stroke
				(width 0.1)
				(type default)
			)
			(layer "B.Fab")
		)
		(fp_line
			(start 0.12065 -0.305054)
			(end 0.12065 -0.2794)
			(stroke
				(width 0.1)
				(type default)
			)
			(layer "B.Fab")
		)
		(fp_line
			(start 0.12065 -0.2794)
			(end -0.12065 -0.2794)
			(stroke
				(width 0.1)
				(type default)
			)
			(layer "B.Fab")
		)
		(fp_line
			(start 0.12065 0.2794)
			(end 0.12065 0.3048)
			(stroke
				(width 0.1)
				(type default)
			)
			(layer "B.Fab")
		)
		(fp_line
			(start 0.12065 0.3048)
			(end 0.67945 0.3048)
			(stroke
				(width 0.1)
				(type default)
			)
			(layer "B.Fab")
		)
		(fp_line
			(start 0.67945 -0.305054)
			(end 0.12065 -0.305054)
			(stroke
				(width 0.1)
				(type default)
			)
			(layer "B.Fab")
		)
		(fp_line
			(start 0.67945 0.3048)
			(end 0.67945 -0.305054)
			(stroke
				(width 0.1)
				(type default)
			)
			(layer "B.Fab")
		)
		(pad "1" smd circle
			(at 0.40005 0 180)
			(size 0 0)
			(layers "B.Cu" "B.Mask" "B.Paste")
			(net "P12V_HSC_ADC_N")
		)
		(pad "2" smd circle
			(at -0.40005 0 180)
			(size 0 0)
			(layers "B.Cu" "B.Mask" "B.Paste")
			(net "P12V_HSC_SENSE2_R4_N")
		)
	)
	(footprint ""
		(layer "B.Cu")
		(at 400.883882 -416.899344 90)
		(property "Reference" "C6615"
			(at 0 0 90)
			(layer "B.SilkS")
			(hide yes)
			(effects
				(font
					(size 1.27 1.27)
				)
				(justify mirror)
			)
		)
		(property "Value" ""
			(at 0 0 90)
			(layer "B.Fab")
			(effects
				(font
					(size 1.27 1.27)
				)
				(justify mirror)
			)
		)
		(duplicate_pad_numbers_are_jumpers no)
		(fp_line
			(start 0.299974 -0.150114)
			(end -0.299974 -0.150114)
			(stroke
				(width 0.1)
				(type default)
			)
			(layer "B.Fab")
		)
		(fp_line
			(start -0.299974 -0.150114)
			(end -0.299974 0.150114)
			(stroke
				(width 0.1)
				(type default)
			)
			(layer "B.Fab")
		)
		(fp_line
			(start 0.299974 0.150114)
			(end 0.299974 -0.150114)
			(stroke
				(width 0.1)
				(type default)
			)
			(layer "B.Fab")
		)
		(fp_line
			(start -0.299974 0.150114)
			(end 0.299974 0.150114)
			(stroke
				(width 0.1)
				(type default)
			)
			(layer "B.Fab")
		)
		(pad "1" smd rect
			(at 0.2667 0 270)
			(size 0.3048 0.381)
			(layers "B.Cu" "B.Mask" "B.Paste")
			(net "P5E_CPU0_P3_TX_BUF_C_DP<9>")
		)
		(pad "2" smd rect
			(at -0.2667 0 270)
			(size 0.3048 0.381)
			(layers "B.Cu" "B.Mask" "B.Paste")
			(net "P5E_CPU0_P3_TX_BUF_DP<9>")
		)
	)
	(footprint ""
		(layer "B.Cu")
		(at 312.674 -358.14 -90)
		(property "Reference" "PR532"
			(at 0 0 90)
			(layer "B.SilkS")
			(hide yes)
			(effects
				(font
					(size 1.27 1.27)
				)
				(justify mirror)
			)
		)
		(property "Value" ""
			(at 0 0 90)
			(layer "B.Fab")
			(effects
				(font
					(size 1.27 1.27)
				)
				(justify mirror)
			)
		)
		(duplicate_pad_numbers_are_jumpers no)
		(fp_line
			(start -0.7874 0.4064)
			(end 0.7874 0.4064)
			(stroke
				(width 0.1524)
				(type default)
			)
			(layer "B.SilkS")
		)
		(fp_line
			(start 0.7874 0.4064)
			(end 0.7874 -0.4064)
			(stroke
				(width 0.1524)
				(type default)
			)
			(layer "B.SilkS")
		)
		(fp_line
			(start -0.7874 -0.4064)
			(end -0.7874 0.4064)
			(stroke
				(width 0.1524)
				(type default)
			)
			(layer "B.SilkS")
		)
		(fp_line
			(start 0.7874 -0.4064)
			(end -0.7874 -0.4064)
			(stroke
				(width 0.1524)
				(type default)
			)
			(layer "B.SilkS")
		)
		(fp_line
			(start -0.67945 0.3048)
			(end -0.120396 0.3048)
			(stroke
				(width 0.1)
				(type default)
			)
			(layer "B.Fab")
		)
		(fp_line
			(start -0.120396 0.3048)
			(end -0.120396 0.2794)
			(stroke
				(width 0.1)
				(type default)
			)
			(layer "B.Fab")
		)
		(fp_line
			(start 0.12065 0.3048)
			(end 0.67945 0.3048)
			(stroke
				(width 0.1)
				(type default)
			)
			(layer "B.Fab")
		)
		(fp_line
			(start 0.67945 0.3048)
			(end 0.67945 -0.305054)
			(stroke
				(width 0.1)
				(type default)
			)
			(layer "B.Fab")
		)
		(fp_line
			(start -0.120396 0.2794)
			(end 0.12065 0.2794)
			(stroke
				(width 0.1)
				(type default)
			)
			(layer "B.Fab")
		)
		(fp_line
			(start 0.12065 0.2794)
			(end 0.12065 0.3048)
			(stroke
				(width 0.1)
				(type default)
			)
			(layer "B.Fab")
		)
		(fp_line
			(start -0.12065 -0.2794)
			(end -0.12065 -0.3048)
			(stroke
				(width 0.1)
				(type default)
			)
			(layer "B.Fab")
		)
		(fp_line
			(start 0.12065 -0.2794)
			(end -0.12065 -0.2794)
			(stroke
				(width 0.1)
				(type default)
			)
			(layer "B.Fab")
		)
		(fp_line
			(start -0.67945 -0.3048)
			(end -0.67945 0.3048)
			(stroke
				(width 0.1)
				(type default)
			)
			(layer "B.Fab")
		)
		(fp_line
			(start -0.12065 -0.3048)
			(end -0.67945 -0.3048)
			(stroke
				(width 0.1)
				(type default)
			)
			(layer "B.Fab")
		)
		(fp_line
			(start 0.12065 -0.305054)
			(end 0.12065 -0.2794)
			(stroke
				(width 0.1)
				(type default)
			)
			(layer "B.Fab")
		)
		(fp_line
			(start 0.67945 -0.305054)
			(end 0.12065 -0.305054)
			(stroke
				(width 0.1)
				(type default)
			)
			(layer "B.Fab")
		)
		(pad "1" smd circle
			(at 0.40005 0 90)
			(size 0 0)
			(layers "B.Cu" "B.Mask" "B.Paste")
			(net "NC_PVDDCR_CPU1_P0_IMON7")
		)
		(pad "2" smd circle
			(at -0.40005 0 90)
			(size 0 0)
			(layers "B.Cu" "B.Mask" "B.Paste")
			(net "GND")
		)
	)
	(footprint ""
		(layer "B.Cu")
		(at 10.91057 -383.051558 -90)
		(property "Reference" "PC6625_1"
			(at 0 0 90)
			(layer "B.SilkS")
			(hide yes)
			(effects
				(font
					(size 1.27 1.27)
				)
				(justify mirror)
			)
		)
		(property "Value" ""
			(at 0 0 90)
			(layer "B.Fab")
			(effects
				(font
					(size 1.27 1.27)
				)
				(justify mirror)
			)
		)
		(duplicate_pad_numbers_are_jumpers no)
		(fp_line
			(start -1.524 0.762)
			(end 1.524 0.762)
			(stroke
				(width 0.1524)
				(type default)
			)
			(layer "B.SilkS")
		)
		(fp_line
			(start 1.524 0.762)
			(end 1.524 -0.762)
			(stroke
				(width 0.1524)
				(type default)
			)
			(layer "B.SilkS")
		)
		(fp_line
			(start -1.524 -0.762)
			(end -1.524 0.762)
			(stroke
				(width 0.1524)
				(type default)
			)
			(layer "B.SilkS")
		)
		(fp_line
			(start 1.524 -0.762)
			(end -1.524 -0.762)
			(stroke
				(width 0.1524)
				(type default)
			)
			(layer "B.SilkS")
		)
		(fp_line
			(start -1.1049 0.724916)
			(end -1.1049 -0.724916)
			(stroke
				(width 0.1)
				(type default)
			)
			(layer "B.Fab")
		)
		(fp_line
			(start 1.1049 0.724916)
			(end -1.1049 0.724916)
			(stroke
				(width 0.1)
				(type default)
			)
			(layer "B.Fab")
		)
		(fp_line
			(start -1.1049 -0.724916)
			(end 1.1049 -0.724916)
			(stroke
				(width 0.1)
				(type default)
			)
			(layer "B.Fab")
		)
		(fp_line
			(start 1.1049 -0.724916)
			(end 1.1049 0.724916)
			(stroke
				(width 0.1)
				(type default)
			)
			(layer "B.Fab")
		)
		(pad "1" smd rect
			(at 0.889 0 270)
			(size 1.016 1.27)
			(layers "B.Cu" "B.Mask" "B.Paste")
			(net "P0V9_CPU1_RT_2D")
		)
		(pad "2" smd rect
			(at -0.889 0 270)
			(size 1.016 1.27)
			(layers "B.Cu" "B.Mask" "B.Paste")
			(net "GND")
		)
	)
	(footprint ""
		(layer "B.Cu")
		(at 162.7124 -424.60037 -90)
		(property "Reference" "R1512"
			(at 0 0 90)
			(layer "B.SilkS")
			(hide yes)
			(effects
				(font
					(size 1.27 1.27)
				)
				(justify mirror)
			)
		)
		(property "Value" ""
			(at 0 0 90)
			(layer "B.Fab")
			(effects
				(font
					(size 1.27 1.27)
				)
				(justify mirror)
			)
		)
		(duplicate_pad_numbers_are_jumpers no)
		(fp_line
			(start -0.32512 0.175006)
			(end 0.32512 0.175006)
			(stroke
				(width 0.1)
				(type default)
			)
			(layer "B.Fab")
		)
		(fp_line
			(start 0.32512 0.175006)
			(end 0.32512 -0.175006)
			(stroke
				(width 0.1)
				(type default)
			)
			(layer "B.Fab")
		)
		(fp_line
			(start -0.32512 -0.175006)
			(end -0.32512 0.175006)
			(stroke
				(width 0.1)
				(type default)
			)
			(layer "B.Fab")
		)
		(fp_line
			(start 0.32512 -0.175006)
			(end -0.32512 -0.175006)
			(stroke
				(width 0.1)
				(type default)
			)
			(layer "B.Fab")
		)
		(pad "1" smd rect
			(at 0.2667 0 90)
			(size 0.3048 0.381)
			(layers "B.Cu" "B.Mask" "B.Paste")
			(net "P1V8_CPU1_RT_1D")
		)
		(pad "2" smd rect
			(at -0.2667 0 270)
			(size 0.3048 0.381)
			(layers "B.Cu" "B.Mask" "B.Paste")
			(net "JTAG_TDO_RT_CPU1_P3")
		)
	)
	(footprint ""
		(layer "B.Cu")
		(at 403.018752 -398.942052 90)
		(property "Reference" "C803"
			(at 0 0 90)
			(layer "B.SilkS")
			(hide yes)
			(effects
				(font
					(size 1.27 1.27)
				)
				(justify mirror)
			)
		)
		(property "Value" ""
			(at 0 0 90)
			(layer "B.Fab")
			(effects
				(font
					(size 1.27 1.27)
				)
				(justify mirror)
			)
		)
		(duplicate_pad_numbers_are_jumpers no)
		(fp_line
			(start 0.7874 -0.4064)
			(end -0.7874 -0.4064)
			(stroke
				(width 0.1524)
				(type default)
			)
			(layer "B.SilkS")
		)
		(fp_line
			(start -0.7874 -0.4064)
			(end -0.7874 0.4064)
			(stroke
				(width 0.1524)
				(type default)
			)
			(layer "B.SilkS")
		)
		(fp_line
			(start 0.7874 0.4064)
			(end 0.7874 -0.4064)
			(stroke
				(width 0.1524)
				(type default)
			)
			(layer "B.SilkS")
		)
		(fp_line
			(start -0.7874 0.4064)
			(end 0.7874 0.4064)
			(stroke
				(width 0.1524)
				(type default)
			)
			(layer "B.SilkS")
		)
		(fp_line
			(start 0.67945 -0.305054)
			(end 0.12065 -0.305054)
			(stroke
				(width 0.1)
				(type default)
			)
			(layer "B.Fab")
		)
		(fp_line
			(start 0.12065 -0.305054)
			(end 0.12065 -0.2794)
			(stroke
				(width 0.1)
				(type default)
			)
			(layer "B.Fab")
		)
		(fp_line
			(start -0.12065 -0.3048)
			(end -0.67945 -0.3048)
			(stroke
				(width 0.1)
				(type default)
			)
			(layer "B.Fab")
		)
		(fp_line
			(start -0.67945 -0.3048)
			(end -0.67945 0.3048)
			(stroke
				(width 0.1)
				(type default)
			)
			(layer "B.Fab")
		)
		(fp_line
			(start 0.12065 -0.2794)
			(end -0.12065 -0.2794)
			(stroke
				(width 0.1)
				(type default)
			)
			(layer "B.Fab")
		)
		(fp_line
			(start -0.12065 -0.2794)
			(end -0.12065 -0.3048)
			(stroke
				(width 0.1)
				(type default)
			)
			(layer "B.Fab")
		)
		(fp_line
			(start 0.12065 0.2794)
			(end 0.12065 0.3048)
			(stroke
				(width 0.1)
				(type default)
			)
			(layer "B.Fab")
		)
		(fp_line
			(start -0.120396 0.2794)
			(end 0.12065 0.2794)
			(stroke
				(width 0.1)
				(type default)
			)
			(layer "B.Fab")
		)
		(fp_line
			(start 0.67945 0.3048)
			(end 0.67945 -0.305054)
			(stroke
				(width 0.1)
				(type default)
			)
			(layer "B.Fab")
		)
		(fp_line
			(start 0.12065 0.3048)
			(end 0.67945 0.3048)
			(stroke
				(width 0.1)
				(type default)
			)
			(layer "B.Fab")
		)
		(fp_line
			(start -0.120396 0.3048)
			(end -0.120396 0.2794)
			(stroke
				(width 0.1)
				(type default)
			)
			(layer "B.Fab")
		)
		(fp_line
			(start -0.67945 0.3048)
			(end -0.120396 0.3048)
			(stroke
				(width 0.1)
				(type default)
			)
			(layer "B.Fab")
		)
		(pad "1" smd circle
			(at 0.40005 0 270)
			(size 0 0)
			(layers "B.Cu" "B.Mask" "B.Paste")
			(net "P0V9_CPU0_RT2_2A")
		)
		(pad "2" smd circle
			(at -0.40005 0 270)
			(size 0 0)
			(layers "B.Cu" "B.Mask" "B.Paste")
			(net "GND")
		)
	)
	(footprint ""
		(layer "B.Cu")
		(at 216.127076 -327.009252)
		(property "Reference" "R1267"
			(at 0 0 0)
			(layer "B.SilkS")
			(hide yes)
			(effects
				(font
					(size 1.27 1.27)
				)
				(justify mirror)
			)
		)
		(property "Value" ""
			(at 0 0 0)
			(layer "B.Fab")
			(effects
				(font
					(size 1.27 1.27)
				)
				(justify mirror)
			)
		)
		(duplicate_pad_numbers_are_jumpers no)
		(fp_line
			(start -0.7874 -0.4064)
			(end -0.7874 0.4064)
			(stroke
				(width 0.1524)
				(type default)
			)
			(layer "B.SilkS")
		)
		(fp_line
			(start -0.7874 0.4064)
			(end 0.7874 0.4064)
			(stroke
				(width 0.1524)
				(type default)
			)
			(layer "B.SilkS")
		)
		(fp_line
			(start 0.7874 -0.4064)
			(end -0.7874 -0.4064)
			(stroke
				(width 0.1524)
				(type default)
			)
			(layer "B.SilkS")
		)
		(fp_line
			(start 0.7874 0.4064)
			(end 0.7874 -0.4064)
			(stroke
				(width 0.1524)
				(type default)
			)
			(layer "B.SilkS")
		)
		(fp_line
			(start -0.67945 -0.3048)
			(end -0.67945 0.3048)
			(stroke
				(width 0.1)
				(type default)
			)
			(layer "B.Fab")
		)
		(fp_line
			(start -0.67945 0.3048)
			(end -0.120396 0.3048)
			(stroke
				(width 0.1)
				(type default)
			)
			(layer "B.Fab")
		)
		(fp_line
			(start -0.12065 -0.3048)
			(end -0.67945 -0.3048)
			(stroke
				(width 0.1)
				(type default)
			)
			(layer "B.Fab")
		)
		(fp_line
			(start -0.12065 -0.2794)
			(end -0.12065 -0.3048)
			(stroke
				(width 0.1)
				(type default)
			)
			(layer "B.Fab")
		)
		(fp_line
			(start -0.120396 0.2794)
			(end 0.12065 0.2794)
			(stroke
				(width 0.1)
				(type default)
			)
			(layer "B.Fab")
		)
		(fp_line
			(start -0.120396 0.3048)
			(end -0.120396 0.2794)
			(stroke
				(width 0.1)
				(type default)
			)
			(layer "B.Fab")
		)
		(fp_line
			(start 0.12065 -0.305054)
			(end 0.12065 -0.2794)
			(stroke
				(width 0.1)
				(type default)
			)
			(layer "B.Fab")
		)
		(fp_line
			(start 0.12065 -0.2794)
			(end -0.12065 -0.2794)
			(stroke
				(width 0.1)
				(type default)
			)
			(layer "B.Fab")
		)
		(fp_line
			(start 0.12065 0.2794)
			(end 0.12065 0.3048)
			(stroke
				(width 0.1)
				(type default)
			)
			(layer "B.Fab")
		)
		(fp_line
			(start 0.12065 0.3048)
			(end 0.67945 0.3048)
			(stroke
				(width 0.1)
				(type default)
			)
			(layer "B.Fab")
		)
		(fp_line
			(start 0.67945 -0.305054)
			(end 0.12065 -0.305054)
			(stroke
				(width 0.1)
				(type default)
			)
			(layer "B.Fab")
		)
		(fp_line
			(start 0.67945 0.3048)
			(end 0.67945 -0.305054)
			(stroke
				(width 0.1)
				(type default)
			)
			(layer "B.Fab")
		)
		(pad "1" smd circle
			(at 0.40005 0 180)
			(size 0 0)
			(layers "B.Cu" "B.Mask" "B.Paste")
			(net "P3V3_ADC128_2_VCC")
		)
		(pad "2" smd circle
			(at -0.40005 0 180)
			(size 0 0)
			(layers "B.Cu" "B.Mask" "B.Paste")
			(net "ADC128_2_VREF")
		)
	)
	(footprint ""
		(layer "B.Cu")
		(at 359.994454 -263.84631)
		(property "Reference" "C2648"
			(at 0 0 0)
			(layer "B.SilkS")
			(hide yes)
			(effects
				(font
					(size 1.27 1.27)
				)
				(justify mirror)
			)
		)
		(property "Value" ""
			(at 0 0 0)
			(layer "B.Fab")
			(effects
				(font
					(size 1.27 1.27)
				)
				(justify mirror)
			)
		)
		(duplicate_pad_numbers_are_jumpers no)
		(fp_line
			(start -0.7874 -0.4064)
			(end -0.7874 0.4064)
			(stroke
				(width 0.1524)
				(type default)
			)
			(layer "B.SilkS")
		)
		(fp_line
			(start -0.7874 0.4064)
			(end 0.7874 0.4064)
			(stroke
				(width 0.1524)
				(type default)
			)
			(layer "B.SilkS")
		)
		(fp_line
			(start 0.7874 -0.4064)
			(end -0.7874 -0.4064)
			(stroke
				(width 0.1524)
				(type default)
			)
			(layer "B.SilkS")
		)
		(fp_line
			(start 0.7874 0.4064)
			(end 0.7874 -0.4064)
			(stroke
				(width 0.1524)
				(type default)
			)
			(layer "B.SilkS")
		)
		(fp_line
			(start -0.67945 -0.3048)
			(end -0.67945 0.3048)
			(stroke
				(width 0.1)
				(type default)
			)
			(layer "B.Fab")
		)
		(fp_line
			(start -0.67945 0.3048)
			(end -0.120396 0.3048)
			(stroke
				(width 0.1)
				(type default)
			)
			(layer "B.Fab")
		)
		(fp_line
			(start -0.12065 -0.3048)
			(end -0.67945 -0.3048)
			(stroke
				(width 0.1)
				(type default)
			)
			(layer "B.Fab")
		)
		(fp_line
			(start -0.12065 -0.2794)
			(end -0.12065 -0.3048)
			(stroke
				(width 0.1)
				(type default)
			)
			(layer "B.Fab")
		)
		(fp_line
			(start -0.120396 0.2794)
			(end 0.12065 0.2794)
			(stroke
				(width 0.1)
				(type default)
			)
			(layer "B.Fab")
		)
		(fp_line
			(start -0.120396 0.3048)
			(end -0.120396 0.2794)
			(stroke
				(width 0.1)
				(type default)
			)
			(layer "B.Fab")
		)
		(fp_line
			(start 0.12065 -0.305054)
			(end 0.12065 -0.2794)
			(stroke
				(width 0.1)
				(type default)
			)
			(layer "B.Fab")
		)
		(fp_line
			(start 0.12065 -0.2794)
			(end -0.12065 -0.2794)
			(stroke
				(width 0.1)
				(type default)
			)
			(layer "B.Fab")
		)
		(fp_line
			(start 0.12065 0.2794)
			(end 0.12065 0.3048)
			(stroke
				(width 0.1)
				(type default)
			)
			(layer "B.Fab")
		)
		(fp_line
			(start 0.12065 0.3048)
			(end 0.67945 0.3048)
			(stroke
				(width 0.1)
				(type default)
			)
			(layer "B.Fab")
		)
		(fp_line
			(start 0.67945 -0.305054)
			(end 0.12065 -0.305054)
			(stroke
				(width 0.1)
				(type default)
			)
			(layer "B.Fab")
		)
		(fp_line
			(start 0.67945 0.3048)
			(end 0.67945 -0.305054)
			(stroke
				(width 0.1)
				(type default)
			)
			(layer "B.Fab")
		)
		(pad "1" smd circle
			(at 0.40005 0 180)
			(size 0 0)
			(layers "B.Cu" "B.Mask" "B.Paste")
			(net "PVDD11_S3_P0")
		)
		(pad "2" smd circle
			(at -0.40005 0 180)
			(size 0 0)
			(layers "B.Cu" "B.Mask" "B.Paste")
			(net "GND")
		)
	)
	(footprint ""
		(layer "B.Cu")
		(at 356.057454 -251.78131)
		(property "Reference" "C2589"
			(at 0 0 0)
			(layer "B.SilkS")
			(hide yes)
			(effects
				(font
					(size 1.27 1.27)
				)
				(justify mirror)
			)
		)
		(property "Value" ""
			(at 0 0 0)
			(layer "B.Fab")
			(effects
				(font
					(size 1.27 1.27)
				)
				(justify mirror)
			)
		)
		(duplicate_pad_numbers_are_jumpers no)
		(fp_line
			(start -0.7874 -0.4064)
			(end -0.7874 0.4064)
			(stroke
				(width 0.1524)
				(type default)
			)
			(layer "B.SilkS")
		)
		(fp_line
			(start -0.7874 0.4064)
			(end 0.7874 0.4064)
			(stroke
				(width 0.1524)
				(type default)
			)
			(layer "B.SilkS")
		)
		(fp_line
			(start 0.7874 -0.4064)
			(end -0.7874 -0.4064)
			(stroke
				(width 0.1524)
				(type default)
			)
			(layer "B.SilkS")
		)
		(fp_line
			(start 0.7874 0.4064)
			(end 0.7874 -0.4064)
			(stroke
				(width 0.1524)
				(type default)
			)
			(layer "B.SilkS")
		)
		(fp_line
			(start -0.67945 -0.3048)
			(end -0.67945 0.3048)
			(stroke
				(width 0.1)
				(type default)
			)
			(layer "B.Fab")
		)
		(fp_line
			(start -0.67945 0.3048)
			(end -0.120396 0.3048)
			(stroke
				(width 0.1)
				(type default)
			)
			(layer "B.Fab")
		)
		(fp_line
			(start -0.12065 -0.3048)
			(end -0.67945 -0.3048)
			(stroke
				(width 0.1)
				(type default)
			)
			(layer "B.Fab")
		)
		(fp_line
			(start -0.12065 -0.2794)
			(end -0.12065 -0.3048)
			(stroke
				(width 0.1)
				(type default)
			)
			(layer "B.Fab")
		)
		(fp_line
			(start -0.120396 0.2794)
			(end 0.12065 0.2794)
			(stroke
				(width 0.1)
				(type default)
			)
			(layer "B.Fab")
		)
		(fp_line
			(start -0.120396 0.3048)
			(end -0.120396 0.2794)
			(stroke
				(width 0.1)
				(type default)
			)
			(layer "B.Fab")
		)
		(fp_line
			(start 0.12065 -0.305054)
			(end 0.12065 -0.2794)
			(stroke
				(width 0.1)
				(type default)
			)
			(layer "B.Fab")
		)
		(fp_line
			(start 0.12065 -0.2794)
			(end -0.12065 -0.2794)
			(stroke
				(width 0.1)
				(type default)
			)
			(layer "B.Fab")
		)
		(fp_line
			(start 0.12065 0.2794)
			(end 0.12065 0.3048)
			(stroke
				(width 0.1)
				(type default)
			)
			(layer "B.Fab")
		)
		(fp_line
			(start 0.12065 0.3048)
			(end 0.67945 0.3048)
			(stroke
				(width 0.1)
				(type default)
			)
			(layer "B.Fab")
		)
		(fp_line
			(start 0.67945 -0.305054)
			(end 0.12065 -0.305054)
			(stroke
				(width 0.1)
				(type default)
			)
			(layer "B.Fab")
		)
		(fp_line
			(start 0.67945 0.3048)
			(end 0.67945 -0.305054)
			(stroke
				(width 0.1)
				(type default)
			)
			(layer "B.Fab")
		)
		(pad "1" smd circle
			(at 0.40005 0 180)
			(size 0 0)
			(layers "B.Cu" "B.Mask" "B.Paste")
			(net "PVDDCR_SOC_P0")
		)
		(pad "2" smd circle
			(at -0.40005 0 180)
			(size 0 0)
			(layers "B.Cu" "B.Mask" "B.Paste")
			(net "GND")
		)
	)
	(footprint ""
		(layer "B.Cu")
		(at 180.858922 -20.378166 90)
		(property "Reference" "R2420"
			(at 0 0 90)
			(layer "B.SilkS")
			(hide yes)
			(effects
				(font
					(size 1.27 1.27)
				)
				(justify mirror)
			)
		)
		(property "Value" ""
			(at 0 0 90)
			(layer "B.Fab")
			(effects
				(font
					(size 1.27 1.27)
				)
				(justify mirror)
			)
		)
		(duplicate_pad_numbers_are_jumpers no)
		(fp_line
			(start 0.7874 -0.4064)
			(end -0.7874 -0.4064)
			(stroke
				(width 0.1524)
				(type default)
			)
			(layer "B.SilkS")
		)
		(fp_line
			(start -0.7874 -0.4064)
			(end -0.7874 0.4064)
			(stroke
				(width 0.1524)
				(type default)
			)
			(layer "B.SilkS")
		)
		(fp_line
			(start 0.7874 0.4064)
			(end 0.7874 -0.4064)
			(stroke
				(width 0.1524)
				(type default)
			)
			(layer "B.SilkS")
		)
		(fp_line
			(start -0.7874 0.4064)
			(end 0.7874 0.4064)
			(stroke
				(width 0.1524)
				(type default)
			)
			(layer "B.SilkS")
		)
		(fp_line
			(start 0.67945 -0.305054)
			(end 0.12065 -0.305054)
			(stroke
				(width 0.1)
				(type default)
			)
			(layer "B.Fab")
		)
		(fp_line
			(start 0.12065 -0.305054)
			(end 0.12065 -0.2794)
			(stroke
				(width 0.1)
				(type default)
			)
			(layer "B.Fab")
		)
		(fp_line
			(start -0.12065 -0.3048)
			(end -0.67945 -0.3048)
			(stroke
				(width 0.1)
				(type default)
			)
			(layer "B.Fab")
		)
		(fp_line
			(start -0.67945 -0.3048)
			(end -0.67945 0.3048)
			(stroke
				(width 0.1)
				(type default)
			)
			(layer "B.Fab")
		)
		(fp_line
			(start 0.12065 -0.2794)
			(end -0.12065 -0.2794)
			(stroke
				(width 0.1)
				(type default)
			)
			(layer "B.Fab")
		)
		(fp_line
			(start -0.12065 -0.2794)
			(end -0.12065 -0.3048)
			(stroke
				(width 0.1)
				(type default)
			)
			(layer "B.Fab")
		)
		(fp_line
			(start 0.12065 0.2794)
			(end 0.12065 0.3048)
			(stroke
				(width 0.1)
				(type default)
			)
			(layer "B.Fab")
		)
		(fp_line
			(start -0.120396 0.2794)
			(end 0.12065 0.2794)
			(stroke
				(width 0.1)
				(type default)
			)
			(layer "B.Fab")
		)
		(fp_line
			(start 0.67945 0.3048)
			(end 0.67945 -0.305054)
			(stroke
				(width 0.1)
				(type default)
			)
			(layer "B.Fab")
		)
		(fp_line
			(start 0.12065 0.3048)
			(end 0.67945 0.3048)
			(stroke
				(width 0.1)
				(type default)
			)
			(layer "B.Fab")
		)
		(fp_line
			(start -0.120396 0.3048)
			(end -0.120396 0.2794)
			(stroke
				(width 0.1)
				(type default)
			)
			(layer "B.Fab")
		)
		(fp_line
			(start -0.67945 0.3048)
			(end -0.120396 0.3048)
			(stroke
				(width 0.1)
				(type default)
			)
			(layer "B.Fab")
		)
		(pad "1" smd circle
			(at 0.40005 0 270)
			(size 0 0)
			(layers "B.Cu" "B.Mask" "B.Paste")
			(net "SMB_CPU0_CPU1_APML_SDA")
		)
		(pad "2" smd circle
			(at -0.40005 0 270)
			(size 0 0)
			(layers "B.Cu" "B.Mask" "B.Paste")
			(net "SMB_CPU0_CPU1_APML_SDA_R")
		)
	)
	(footprint ""
		(layer "B.Cu")
		(at 215.2523 -402.744432 -90)
		(property "Reference" "PR3980"
			(at 0 0 90)
			(layer "B.SilkS")
			(hide yes)
			(effects
				(font
					(size 1.27 1.27)
				)
				(justify mirror)
			)
		)
		(property "Value" ""
			(at 0 0 90)
			(layer "B.Fab")
			(effects
				(font
					(size 1.27 1.27)
				)
				(justify mirror)
			)
		)
		(duplicate_pad_numbers_are_jumpers no)
		(fp_line
			(start -0.7874 0.4064)
			(end 0.7874 0.4064)
			(stroke
				(width 0.1524)
				(type default)
			)
			(layer "B.SilkS")
		)
		(fp_line
			(start 0.7874 0.4064)
			(end 0.7874 -0.4064)
			(stroke
				(width 0.1524)
				(type default)
			)
			(layer "B.SilkS")
		)
		(fp_line
			(start -0.7874 -0.4064)
			(end -0.7874 0.4064)
			(stroke
				(width 0.1524)
				(type default)
			)
			(layer "B.SilkS")
		)
		(fp_line
			(start 0.7874 -0.4064)
			(end -0.7874 -0.4064)
			(stroke
				(width 0.1524)
				(type default)
			)
			(layer "B.SilkS")
		)
		(fp_line
			(start -0.67945 0.3048)
			(end -0.120396 0.3048)
			(stroke
				(width 0.1)
				(type default)
			)
			(layer "B.Fab")
		)
		(fp_line
			(start -0.120396 0.3048)
			(end -0.120396 0.2794)
			(stroke
				(width 0.1)
				(type default)
			)
			(layer "B.Fab")
		)
		(fp_line
			(start 0.12065 0.3048)
			(end 0.67945 0.3048)
			(stroke
				(width 0.1)
				(type default)
			)
			(layer "B.Fab")
		)
		(fp_line
			(start 0.67945 0.3048)
			(end 0.67945 -0.305054)
			(stroke
				(width 0.1)
				(type default)
			)
			(layer "B.Fab")
		)
		(fp_line
			(start -0.120396 0.2794)
			(end 0.12065 0.2794)
			(stroke
				(width 0.1)
				(type default)
			)
			(layer "B.Fab")
		)
		(fp_line
			(start 0.12065 0.2794)
			(end 0.12065 0.3048)
			(stroke
				(width 0.1)
				(type default)
			)
			(layer "B.Fab")
		)
		(fp_line
			(start -0.12065 -0.2794)
			(end -0.12065 -0.3048)
			(stroke
				(width 0.1)
				(type default)
			)
			(layer "B.Fab")
		)
		(fp_line
			(start 0.12065 -0.2794)
			(end -0.12065 -0.2794)
			(stroke
				(width 0.1)
				(type default)
			)
			(layer "B.Fab")
		)
		(fp_line
			(start -0.67945 -0.3048)
			(end -0.67945 0.3048)
			(stroke
				(width 0.1)
				(type default)
			)
			(layer "B.Fab")
		)
		(fp_line
			(start -0.12065 -0.3048)
			(end -0.67945 -0.3048)
			(stroke
				(width 0.1)
				(type default)
			)
			(layer "B.Fab")
		)
		(fp_line
			(start 0.12065 -0.305054)
			(end 0.12065 -0.2794)
			(stroke
				(width 0.1)
				(type default)
			)
			(layer "B.Fab")
		)
		(fp_line
			(start 0.67945 -0.305054)
			(end 0.12065 -0.305054)
			(stroke
				(width 0.1)
				(type default)
			)
			(layer "B.Fab")
		)
		(pad "1" smd circle
			(at 0.40005 0 90)
			(size 0 0)
			(layers "B.Cu" "B.Mask" "B.Paste")
			(net "HSC_VDD_R_3")
		)
		(pad "2" smd circle
			(at -0.40005 0 90)
			(size 0 0)
			(layers "B.Cu" "B.Mask" "B.Paste")
			(net "HSC_VDD")
		)
	)
	(footprint ""
		(layer "B.Cu")
		(at 100.878386 -267.529564)
		(property "Reference" "C2360"
			(at 0 0 0)
			(layer "B.SilkS")
			(hide yes)
			(effects
				(font
					(size 1.27 1.27)
				)
				(justify mirror)
			)
		)
		(property "Value" ""
			(at 0 0 0)
			(layer "B.Fab")
			(effects
				(font
					(size 1.27 1.27)
				)
				(justify mirror)
			)
		)
		(duplicate_pad_numbers_are_jumpers no)
		(fp_line
			(start -0.7874 -0.4064)
			(end -0.7874 0.4064)
			(stroke
				(width 0.1524)
				(type default)
			)
			(layer "B.SilkS")
		)
		(fp_line
			(start -0.7874 0.4064)
			(end 0.7874 0.4064)
			(stroke
				(width 0.1524)
				(type default)
			)
			(layer "B.SilkS")
		)
		(fp_line
			(start 0.7874 -0.4064)
			(end -0.7874 -0.4064)
			(stroke
				(width 0.1524)
				(type default)
			)
			(layer "B.SilkS")
		)
		(fp_line
			(start 0.7874 0.4064)
			(end 0.7874 -0.4064)
			(stroke
				(width 0.1524)
				(type default)
			)
			(layer "B.SilkS")
		)
		(fp_line
			(start -0.67945 -0.3048)
			(end -0.67945 0.3048)
			(stroke
				(width 0.1)
				(type default)
			)
			(layer "B.Fab")
		)
		(fp_line
			(start -0.67945 0.3048)
			(end -0.120396 0.3048)
			(stroke
				(width 0.1)
				(type default)
			)
			(layer "B.Fab")
		)
		(fp_line
			(start -0.12065 -0.3048)
			(end -0.67945 -0.3048)
			(stroke
				(width 0.1)
				(type default)
			)
			(layer "B.Fab")
		)
		(fp_line
			(start -0.12065 -0.2794)
			(end -0.12065 -0.3048)
			(stroke
				(width 0.1)
				(type default)
			)
			(layer "B.Fab")
		)
		(fp_line
			(start -0.120396 0.2794)
			(end 0.12065 0.2794)
			(stroke
				(width 0.1)
				(type default)
			)
			(layer "B.Fab")
		)
		(fp_line
			(start -0.120396 0.3048)
			(end -0.120396 0.2794)
			(stroke
				(width 0.1)
				(type default)
			)
			(layer "B.Fab")
		)
		(fp_line
			(start 0.12065 -0.305054)
			(end 0.12065 -0.2794)
			(stroke
				(width 0.1)
				(type default)
			)
			(layer "B.Fab")
		)
		(fp_line
			(start 0.12065 -0.2794)
			(end -0.12065 -0.2794)
			(stroke
				(width 0.1)
				(type default)
			)
			(layer "B.Fab")
		)
		(fp_line
			(start 0.12065 0.2794)
			(end 0.12065 0.3048)
			(stroke
				(width 0.1)
				(type default)
			)
			(layer "B.Fab")
		)
		(fp_line
			(start 0.12065 0.3048)
			(end 0.67945 0.3048)
			(stroke
				(width 0.1)
				(type default)
			)
			(layer "B.Fab")
		)
		(fp_line
			(start 0.67945 -0.305054)
			(end 0.12065 -0.305054)
			(stroke
				(width 0.1)
				(type default)
			)
			(layer "B.Fab")
		)
		(fp_line
			(start 0.67945 0.3048)
			(end 0.67945 -0.305054)
			(stroke
				(width 0.1)
				(type default)
			)
			(layer "B.Fab")
		)
		(pad "1" smd circle
			(at 0.40005 0 180)
			(size 0 0)
			(layers "B.Cu" "B.Mask" "B.Paste")
			(net "PVDDCR_CPU1_P1")
		)
		(pad "2" smd circle
			(at -0.40005 0 180)
			(size 0 0)
			(layers "B.Cu" "B.Mask" "B.Paste")
			(net "GND")
		)
	)
	(footprint ""
		(layer "B.Cu")
		(at 353.900232 -259.355082 180)
		(property "Reference" "C2620"
			(at 0 0 0)
			(layer "B.SilkS")
			(hide yes)
			(effects
				(font
					(size 1.27 1.27)
				)
				(justify mirror)
			)
		)
		(property "Value" ""
			(at 0 0 0)
			(layer "B.Fab")
			(effects
				(font
					(size 1.27 1.27)
				)
				(justify mirror)
			)
		)
		(duplicate_pad_numbers_are_jumpers no)
		(fp_line
			(start 0.7874 0.4064)
			(end 0.7874 -0.4064)
			(stroke
				(width 0.1524)
				(type default)
			)
			(layer "B.SilkS")
		)
		(fp_line
			(start 0.7874 -0.4064)
			(end -0.7874 -0.4064)
			(stroke
				(width 0.1524)
				(type default)
			)
			(layer "B.SilkS")
		)
		(fp_line
			(start -0.7874 0.4064)
			(end 0.7874 0.4064)
			(stroke
				(width 0.1524)
				(type default)
			)
			(layer "B.SilkS")
		)
		(fp_line
			(start -0.7874 -0.4064)
			(end -0.7874 0.4064)
			(stroke
				(width 0.1524)
				(type default)
			)
			(layer "B.SilkS")
		)
		(fp_line
			(start 0.67945 0.3048)
			(end 0.67945 -0.305054)
			(stroke
				(width 0.1)
				(type default)
			)
			(layer "B.Fab")
		)
		(fp_line
			(start 0.67945 -0.305054)
			(end 0.12065 -0.305054)
			(stroke
				(width 0.1)
				(type default)
			)
			(layer "B.Fab")
		)
		(fp_line
			(start 0.12065 0.3048)
			(end 0.67945 0.3048)
			(stroke
				(width 0.1)
				(type default)
			)
			(layer "B.Fab")
		)
		(fp_line
			(start 0.12065 0.2794)
			(end 0.12065 0.3048)
			(stroke
				(width 0.1)
				(type default)
			)
			(layer "B.Fab")
		)
		(fp_line
			(start 0.12065 -0.2794)
			(end -0.12065 -0.2794)
			(stroke
				(width 0.1)
				(type default)
			)
			(layer "B.Fab")
		)
		(fp_line
			(start 0.12065 -0.305054)
			(end 0.12065 -0.2794)
			(stroke
				(width 0.1)
				(type default)
			)
			(layer "B.Fab")
		)
		(fp_line
			(start -0.120396 0.3048)
			(end -0.120396 0.2794)
			(stroke
				(width 0.1)
				(type default)
			)
			(layer "B.Fab")
		)
		(fp_line
			(start -0.120396 0.2794)
			(end 0.12065 0.2794)
			(stroke
				(width 0.1)
				(type default)
			)
			(layer "B.Fab")
		)
		(fp_line
			(start -0.12065 -0.2794)
			(end -0.12065 -0.3048)
			(stroke
				(width 0.1)
				(type default)
			)
			(layer "B.Fab")
		)
		(fp_line
			(start -0.12065 -0.3048)
			(end -0.67945 -0.3048)
			(stroke
				(width 0.1)
				(type default)
			)
			(layer "B.Fab")
		)
		(fp_line
			(start -0.67945 0.3048)
			(end -0.120396 0.3048)
			(stroke
				(width 0.1)
				(type default)
			)
			(layer "B.Fab")
		)
		(fp_line
			(start -0.67945 -0.3048)
			(end -0.67945 0.3048)
			(stroke
				(width 0.1)
				(type default)
			)
			(layer "B.Fab")
		)
		(pad "1" smd circle
			(at 0.40005 0)
			(size 0 0)
			(layers "B.Cu" "B.Mask" "B.Paste")
			(net "PVDDIO_P0")
		)
		(pad "2" smd circle
			(at -0.40005 0)
			(size 0 0)
			(layers "B.Cu" "B.Mask" "B.Paste")
			(net "GND")
		)
	)
	(footprint ""
		(layer "B.Cu")
		(at 239.522 -217.678 90)
		(property "Reference" "R1152"
			(at 0 0 90)
			(layer "B.SilkS")
			(hide yes)
			(effects
				(font
					(size 1.27 1.27)
				)
				(justify mirror)
			)
		)
		(property "Value" ""
			(at 0 0 90)
			(layer "B.Fab")
			(effects
				(font
					(size 1.27 1.27)
				)
				(justify mirror)
			)
		)
		(duplicate_pad_numbers_are_jumpers no)
		(fp_line
			(start 0.7874 -0.4064)
			(end -0.7874 -0.4064)
			(stroke
				(width 0.1524)
				(type default)
			)
			(layer "B.SilkS")
		)
		(fp_line
			(start -0.7874 -0.4064)
			(end -0.7874 0.4064)
			(stroke
				(width 0.1524)
				(type default)
			)
			(layer "B.SilkS")
		)
		(fp_line
			(start 0.7874 0.4064)
			(end 0.7874 -0.4064)
			(stroke
				(width 0.1524)
				(type default)
			)
			(layer "B.SilkS")
		)
		(fp_line
			(start -0.7874 0.4064)
			(end 0.7874 0.4064)
			(stroke
				(width 0.1524)
				(type default)
			)
			(layer "B.SilkS")
		)
		(fp_line
			(start 0.67945 -0.305054)
			(end 0.12065 -0.305054)
			(stroke
				(width 0.1)
				(type default)
			)
			(layer "B.Fab")
		)
		(fp_line
			(start 0.12065 -0.305054)
			(end 0.12065 -0.2794)
			(stroke
				(width 0.1)
				(type default)
			)
			(layer "B.Fab")
		)
		(fp_line
			(start -0.12065 -0.3048)
			(end -0.67945 -0.3048)
			(stroke
				(width 0.1)
				(type default)
			)
			(layer "B.Fab")
		)
		(fp_line
			(start -0.67945 -0.3048)
			(end -0.67945 0.3048)
			(stroke
				(width 0.1)
				(type default)
			)
			(layer "B.Fab")
		)
		(fp_line
			(start 0.12065 -0.2794)
			(end -0.12065 -0.2794)
			(stroke
				(width 0.1)
				(type default)
			)
			(layer "B.Fab")
		)
		(fp_line
			(start -0.12065 -0.2794)
			(end -0.12065 -0.3048)
			(stroke
				(width 0.1)
				(type default)
			)
			(layer "B.Fab")
		)
		(fp_line
			(start 0.12065 0.2794)
			(end 0.12065 0.3048)
			(stroke
				(width 0.1)
				(type default)
			)
			(layer "B.Fab")
		)
		(fp_line
			(start -0.120396 0.2794)
			(end 0.12065 0.2794)
			(stroke
				(width 0.1)
				(type default)
			)
			(layer "B.Fab")
		)
		(fp_line
			(start 0.67945 0.3048)
			(end 0.67945 -0.305054)
			(stroke
				(width 0.1)
				(type default)
			)
			(layer "B.Fab")
		)
		(fp_line
			(start 0.12065 0.3048)
			(end 0.67945 0.3048)
			(stroke
				(width 0.1)
				(type default)
			)
			(layer "B.Fab")
		)
		(fp_line
			(start -0.120396 0.3048)
			(end -0.120396 0.2794)
			(stroke
				(width 0.1)
				(type default)
			)
			(layer "B.Fab")
		)
		(fp_line
			(start -0.67945 0.3048)
			(end -0.120396 0.3048)
			(stroke
				(width 0.1)
				(type default)
			)
			(layer "B.Fab")
		)
		(pad "1" smd circle
			(at 0.40005 0 270)
			(size 0 0)
			(layers "B.Cu" "B.Mask" "B.Paste")
			(net "SMB_CPU0_CPU1_APML_BUF1_SDA_R1")
		)
		(pad "2" smd circle
			(at -0.40005 0 270)
			(size 0 0)
			(layers "B.Cu" "B.Mask" "B.Paste")
			(net "SMB_CPU0_CPU1_APML_BUF1_SDA_R2")
		)
	)
	(footprint ""
		(layer "B.Cu")
		(at 438.103264 -244.08511)
		(property "Reference" "R384"
			(at 0 0 0)
			(layer "B.SilkS")
			(hide yes)
			(effects
				(font
					(size 1.27 1.27)
				)
				(justify mirror)
			)
		)
		(property "Value" ""
			(at 0 0 0)
			(layer "B.Fab")
			(effects
				(font
					(size 1.27 1.27)
				)
				(justify mirror)
			)
		)
		(duplicate_pad_numbers_are_jumpers no)
		(fp_line
			(start -0.7874 -0.4064)
			(end -0.7874 0.4064)
			(stroke
				(width 0.1524)
				(type default)
			)
			(layer "B.SilkS")
		)
		(fp_line
			(start -0.7874 0.4064)
			(end 0.7874 0.4064)
			(stroke
				(width 0.1524)
				(type default)
			)
			(layer "B.SilkS")
		)
		(fp_line
			(start 0.7874 -0.4064)
			(end -0.7874 -0.4064)
			(stroke
				(width 0.1524)
				(type default)
			)
			(layer "B.SilkS")
		)
		(fp_line
			(start 0.7874 0.4064)
			(end 0.7874 -0.4064)
			(stroke
				(width 0.1524)
				(type default)
			)
			(layer "B.SilkS")
		)
		(fp_line
			(start -0.67945 -0.3048)
			(end -0.67945 0.3048)
			(stroke
				(width 0.1)
				(type default)
			)
			(layer "B.Fab")
		)
		(fp_line
			(start -0.67945 0.3048)
			(end -0.120396 0.3048)
			(stroke
				(width 0.1)
				(type default)
			)
			(layer "B.Fab")
		)
		(fp_line
			(start -0.12065 -0.3048)
			(end -0.67945 -0.3048)
			(stroke
				(width 0.1)
				(type default)
			)
			(layer "B.Fab")
		)
		(fp_line
			(start -0.12065 -0.2794)
			(end -0.12065 -0.3048)
			(stroke
				(width 0.1)
				(type default)
			)
			(layer "B.Fab")
		)
		(fp_line
			(start -0.120396 0.2794)
			(end 0.12065 0.2794)
			(stroke
				(width 0.1)
				(type default)
			)
			(layer "B.Fab")
		)
		(fp_line
			(start -0.120396 0.3048)
			(end -0.120396 0.2794)
			(stroke
				(width 0.1)
				(type default)
			)
			(layer "B.Fab")
		)
		(fp_line
			(start 0.12065 -0.305054)
			(end 0.12065 -0.2794)
			(stroke
				(width 0.1)
				(type default)
			)
			(layer "B.Fab")
		)
		(fp_line
			(start 0.12065 -0.2794)
			(end -0.12065 -0.2794)
			(stroke
				(width 0.1)
				(type default)
			)
			(layer "B.Fab")
		)
		(fp_line
			(start 0.12065 0.2794)
			(end 0.12065 0.3048)
			(stroke
				(width 0.1)
				(type default)
			)
			(layer "B.Fab")
		)
		(fp_line
			(start 0.12065 0.3048)
			(end 0.67945 0.3048)
			(stroke
				(width 0.1)
				(type default)
			)
			(layer "B.Fab")
		)
		(fp_line
			(start 0.67945 -0.305054)
			(end 0.12065 -0.305054)
			(stroke
				(width 0.1)
				(type default)
			)
			(layer "B.Fab")
		)
		(fp_line
			(start 0.67945 0.3048)
			(end 0.67945 -0.305054)
			(stroke
				(width 0.1)
				(type default)
			)
			(layer "B.Fab")
		)
		(pad "1" smd circle
			(at 0.40005 0 180)
			(size 0 0)
			(layers "B.Cu" "B.Mask" "B.Paste")
			(net "M_J_CPU0_ALERT_N")
		)
		(pad "2" smd circle
			(at -0.40005 0 180)
			(size 0 0)
			(layers "B.Cu" "B.Mask" "B.Paste")
			(net "M_J_CPU0_ALERT_R_N")
		)
	)
	(footprint ""
		(layer "B.Cu")
		(at 115.686078 -26.025856 90)
		(property "Reference" "C6116"
			(at 0 0 90)
			(layer "B.SilkS")
			(hide yes)
			(effects
				(font
					(size 1.27 1.27)
				)
				(justify mirror)
			)
		)
		(property "Value" ""
			(at 0 0 90)
			(layer "B.Fab")
			(effects
				(font
					(size 1.27 1.27)
				)
				(justify mirror)
			)
		)
		(duplicate_pad_numbers_are_jumpers no)
		(fp_line
			(start 0.7874 -0.4064)
			(end -0.7874 -0.4064)
			(stroke
				(width 0.1524)
				(type default)
			)
			(layer "B.SilkS")
		)
		(fp_line
			(start -0.7874 -0.4064)
			(end -0.7874 0.4064)
			(stroke
				(width 0.1524)
				(type default)
			)
			(layer "B.SilkS")
		)
		(fp_line
			(start 0.7874 0.4064)
			(end 0.7874 -0.4064)
			(stroke
				(width 0.1524)
				(type default)
			)
			(layer "B.SilkS")
		)
		(fp_line
			(start -0.7874 0.4064)
			(end 0.7874 0.4064)
			(stroke
				(width 0.1524)
				(type default)
			)
			(layer "B.SilkS")
		)
		(fp_line
			(start 0.67945 -0.305054)
			(end 0.12065 -0.305054)
			(stroke
				(width 0.1)
				(type default)
			)
			(layer "B.Fab")
		)
		(fp_line
			(start 0.12065 -0.305054)
			(end 0.12065 -0.2794)
			(stroke
				(width 0.1)
				(type default)
			)
			(layer "B.Fab")
		)
		(fp_line
			(start -0.12065 -0.3048)
			(end -0.67945 -0.3048)
			(stroke
				(width 0.1)
				(type default)
			)
			(layer "B.Fab")
		)
		(fp_line
			(start -0.67945 -0.3048)
			(end -0.67945 0.3048)
			(stroke
				(width 0.1)
				(type default)
			)
			(layer "B.Fab")
		)
		(fp_line
			(start 0.12065 -0.2794)
			(end -0.12065 -0.2794)
			(stroke
				(width 0.1)
				(type default)
			)
			(layer "B.Fab")
		)
		(fp_line
			(start -0.12065 -0.2794)
			(end -0.12065 -0.3048)
			(stroke
				(width 0.1)
				(type default)
			)
			(layer "B.Fab")
		)
		(fp_line
			(start 0.12065 0.2794)
			(end 0.12065 0.3048)
			(stroke
				(width 0.1)
				(type default)
			)
			(layer "B.Fab")
		)
		(fp_line
			(start -0.120396 0.2794)
			(end 0.12065 0.2794)
			(stroke
				(width 0.1)
				(type default)
			)
			(layer "B.Fab")
		)
		(fp_line
			(start 0.67945 0.3048)
			(end 0.67945 -0.305054)
			(stroke
				(width 0.1)
				(type default)
			)
			(layer "B.Fab")
		)
		(fp_line
			(start 0.12065 0.3048)
			(end 0.67945 0.3048)
			(stroke
				(width 0.1)
				(type default)
			)
			(layer "B.Fab")
		)
		(fp_line
			(start -0.120396 0.3048)
			(end -0.120396 0.2794)
			(stroke
				(width 0.1)
				(type default)
			)
			(layer "B.Fab")
		)
		(fp_line
			(start -0.67945 0.3048)
			(end -0.120396 0.3048)
			(stroke
				(width 0.1)
				(type default)
			)
			(layer "B.Fab")
		)
		(pad "1" smd circle
			(at 0.40005 0 270)
			(size 0 0)
			(layers "B.Cu" "B.Mask" "B.Paste")
			(net "P1V2_CPU0_USB2_DVDD12")
		)
		(pad "2" smd circle
			(at -0.40005 0 270)
			(size 0 0)
			(layers "B.Cu" "B.Mask" "B.Paste")
			(net "GND")
		)
	)
	(footprint ""
		(layer "B.Cu")
		(at 16.550386 -196.952616 -90)
		(property "Reference" "R773"
			(at 0 0 90)
			(layer "B.SilkS")
			(hide yes)
			(effects
				(font
					(size 1.27 1.27)
				)
				(justify mirror)
			)
		)
		(property "Value" ""
			(at 0 0 90)
			(layer "B.Fab")
			(effects
				(font
					(size 1.27 1.27)
				)
				(justify mirror)
			)
		)
		(duplicate_pad_numbers_are_jumpers no)
		(fp_line
			(start -0.7874 0.4064)
			(end 0.7874 0.4064)
			(stroke
				(width 0.1524)
				(type default)
			)
			(layer "B.SilkS")
		)
		(fp_line
			(start 0.7874 0.4064)
			(end 0.7874 -0.4064)
			(stroke
				(width 0.1524)
				(type default)
			)
			(layer "B.SilkS")
		)
		(fp_line
			(start -0.7874 -0.4064)
			(end -0.7874 0.4064)
			(stroke
				(width 0.1524)
				(type default)
			)
			(layer "B.SilkS")
		)
		(fp_line
			(start 0.7874 -0.4064)
			(end -0.7874 -0.4064)
			(stroke
				(width 0.1524)
				(type default)
			)
			(layer "B.SilkS")
		)
		(fp_line
			(start -0.67945 0.3048)
			(end -0.120396 0.3048)
			(stroke
				(width 0.1)
				(type default)
			)
			(layer "B.Fab")
		)
		(fp_line
			(start -0.120396 0.3048)
			(end -0.120396 0.2794)
			(stroke
				(width 0.1)
				(type default)
			)
			(layer "B.Fab")
		)
		(fp_line
			(start 0.12065 0.3048)
			(end 0.67945 0.3048)
			(stroke
				(width 0.1)
				(type default)
			)
			(layer "B.Fab")
		)
		(fp_line
			(start 0.67945 0.3048)
			(end 0.67945 -0.305054)
			(stroke
				(width 0.1)
				(type default)
			)
			(layer "B.Fab")
		)
		(fp_line
			(start -0.120396 0.2794)
			(end 0.12065 0.2794)
			(stroke
				(width 0.1)
				(type default)
			)
			(layer "B.Fab")
		)
		(fp_line
			(start 0.12065 0.2794)
			(end 0.12065 0.3048)
			(stroke
				(width 0.1)
				(type default)
			)
			(layer "B.Fab")
		)
		(fp_line
			(start -0.12065 -0.2794)
			(end -0.12065 -0.3048)
			(stroke
				(width 0.1)
				(type default)
			)
			(layer "B.Fab")
		)
		(fp_line
			(start 0.12065 -0.2794)
			(end -0.12065 -0.2794)
			(stroke
				(width 0.1)
				(type default)
			)
			(layer "B.Fab")
		)
		(fp_line
			(start -0.67945 -0.3048)
			(end -0.67945 0.3048)
			(stroke
				(width 0.1)
				(type default)
			)
			(layer "B.Fab")
		)
		(fp_line
			(start -0.12065 -0.3048)
			(end -0.67945 -0.3048)
			(stroke
				(width 0.1)
				(type default)
			)
			(layer "B.Fab")
		)
		(fp_line
			(start 0.12065 -0.305054)
			(end 0.12065 -0.2794)
			(stroke
				(width 0.1)
				(type default)
			)
			(layer "B.Fab")
		)
		(fp_line
			(start 0.67945 -0.305054)
			(end 0.12065 -0.305054)
			(stroke
				(width 0.1)
				(type default)
			)
			(layer "B.Fab")
		)
		(pad "1" smd circle
			(at 0.40005 0 90)
			(size 0 0)
			(layers "B.Cu" "B.Mask" "B.Paste")
			(net "PD_CHF_CPU1_DIMM_SAA")
		)
		(pad "2" smd circle
			(at -0.40005 0 90)
			(size 0 0)
			(layers "B.Cu" "B.Mask" "B.Paste")
			(net "GND")
		)
	)
	(footprint ""
		(layer "B.Cu")
		(at 156.151834 -321.814952 180)
		(property "Reference" "R548"
			(at 0 0 0)
			(layer "B.SilkS")
			(hide yes)
			(effects
				(font
					(size 1.27 1.27)
				)
				(justify mirror)
			)
		)
		(property "Value" ""
			(at 0 0 0)
			(layer "B.Fab")
			(effects
				(font
					(size 1.27 1.27)
				)
				(justify mirror)
			)
		)
		(duplicate_pad_numbers_are_jumpers no)
		(fp_line
			(start 0.7874 0.4064)
			(end 0.7874 -0.4064)
			(stroke
				(width 0.1524)
				(type default)
			)
			(layer "B.SilkS")
		)
		(fp_line
			(start 0.7874 -0.4064)
			(end -0.7874 -0.4064)
			(stroke
				(width 0.1524)
				(type default)
			)
			(layer "B.SilkS")
		)
		(fp_line
			(start -0.7874 0.4064)
			(end 0.7874 0.4064)
			(stroke
				(width 0.1524)
				(type default)
			)
			(layer "B.SilkS")
		)
		(fp_line
			(start -0.7874 -0.4064)
			(end -0.7874 0.4064)
			(stroke
				(width 0.1524)
				(type default)
			)
			(layer "B.SilkS")
		)
		(fp_line
			(start 0.67945 0.3048)
			(end 0.67945 -0.305054)
			(stroke
				(width 0.1)
				(type default)
			)
			(layer "B.Fab")
		)
		(fp_line
			(start 0.67945 -0.305054)
			(end 0.12065 -0.305054)
			(stroke
				(width 0.1)
				(type default)
			)
			(layer "B.Fab")
		)
		(fp_line
			(start 0.12065 0.3048)
			(end 0.67945 0.3048)
			(stroke
				(width 0.1)
				(type default)
			)
			(layer "B.Fab")
		)
		(fp_line
			(start 0.12065 0.2794)
			(end 0.12065 0.3048)
			(stroke
				(width 0.1)
				(type default)
			)
			(layer "B.Fab")
		)
		(fp_line
			(start 0.12065 -0.2794)
			(end -0.12065 -0.2794)
			(stroke
				(width 0.1)
				(type default)
			)
			(layer "B.Fab")
		)
		(fp_line
			(start 0.12065 -0.305054)
			(end 0.12065 -0.2794)
			(stroke
				(width 0.1)
				(type default)
			)
			(layer "B.Fab")
		)
		(fp_line
			(start -0.120396 0.3048)
			(end -0.120396 0.2794)
			(stroke
				(width 0.1)
				(type default)
			)
			(layer "B.Fab")
		)
		(fp_line
			(start -0.120396 0.2794)
			(end 0.12065 0.2794)
			(stroke
				(width 0.1)
				(type default)
			)
			(layer "B.Fab")
		)
		(fp_line
			(start -0.12065 -0.2794)
			(end -0.12065 -0.3048)
			(stroke
				(width 0.1)
				(type default)
			)
			(layer "B.Fab")
		)
		(fp_line
			(start -0.12065 -0.3048)
			(end -0.67945 -0.3048)
			(stroke
				(width 0.1)
				(type default)
			)
			(layer "B.Fab")
		)
		(fp_line
			(start -0.67945 0.3048)
			(end -0.120396 0.3048)
			(stroke
				(width 0.1)
				(type default)
			)
			(layer "B.Fab")
		)
		(fp_line
			(start -0.67945 -0.3048)
			(end -0.67945 0.3048)
			(stroke
				(width 0.1)
				(type default)
			)
			(layer "B.Fab")
		)
		(pad "1" smd circle
			(at 0.40005 0)
			(size 0 0)
			(layers "B.Cu" "B.Mask" "B.Paste")
			(net "CPU1_SLP_S5_N")
		)
		(pad "2" smd circle
			(at -0.40005 0)
			(size 0 0)
			(layers "B.Cu" "B.Mask" "B.Paste")
			(net "PVDD18_S5_P1")
		)
	)
	(footprint ""
		(layer "B.Cu")
		(at 337.24596 -396.393162 -90)
		(property "Reference" "C650"
			(at 0 0 90)
			(layer "B.SilkS")
			(hide yes)
			(effects
				(font
					(size 1.27 1.27)
				)
				(justify mirror)
			)
		)
		(property "Value" ""
			(at 0 0 90)
			(layer "B.Fab")
			(effects
				(font
					(size 1.27 1.27)
				)
				(justify mirror)
			)
		)
		(duplicate_pad_numbers_are_jumpers no)
		(fp_line
			(start -0.299974 0.150114)
			(end 0.299974 0.150114)
			(stroke
				(width 0.1)
				(type default)
			)
			(layer "B.Fab")
		)
		(fp_line
			(start 0.299974 0.150114)
			(end 0.299974 -0.150114)
			(stroke
				(width 0.1)
				(type default)
			)
			(layer "B.Fab")
		)
		(fp_line
			(start -0.299974 -0.150114)
			(end -0.299974 0.150114)
			(stroke
				(width 0.1)
				(type default)
			)
			(layer "B.Fab")
		)
		(fp_line
			(start 0.299974 -0.150114)
			(end -0.299974 -0.150114)
			(stroke
				(width 0.1)
				(type default)
			)
			(layer "B.Fab")
		)
		(pad "1" smd rect
			(at 0.2667 0 90)
			(size 0.3048 0.381)
			(layers "B.Cu" "B.Mask" "B.Paste")
			(net "P0V9_CPU0_RT1_2A")
		)
		(pad "2" smd rect
			(at -0.2667 0 90)
			(size 0.3048 0.381)
			(layers "B.Cu" "B.Mask" "B.Paste")
			(net "GND")
		)
	)
	(footprint ""
		(layer "B.Cu")
		(at 373.329454 -252.54331)
		(property "Reference" "C2545"
			(at 0 0 0)
			(layer "B.SilkS")
			(hide yes)
			(effects
				(font
					(size 1.27 1.27)
				)
				(justify mirror)
			)
		)
		(property "Value" ""
			(at 0 0 0)
			(layer "B.Fab")
			(effects
				(font
					(size 1.27 1.27)
				)
				(justify mirror)
			)
		)
		(duplicate_pad_numbers_are_jumpers no)
		(fp_line
			(start -0.7874 -0.4064)
			(end -0.7874 0.4064)
			(stroke
				(width 0.1524)
				(type default)
			)
			(layer "B.SilkS")
		)
		(fp_line
			(start -0.7874 0.4064)
			(end 0.7874 0.4064)
			(stroke
				(width 0.1524)
				(type default)
			)
			(layer "B.SilkS")
		)
		(fp_line
			(start 0.7874 -0.4064)
			(end -0.7874 -0.4064)
			(stroke
				(width 0.1524)
				(type default)
			)
			(layer "B.SilkS")
		)
		(fp_line
			(start 0.7874 0.4064)
			(end 0.7874 -0.4064)
			(stroke
				(width 0.1524)
				(type default)
			)
			(layer "B.SilkS")
		)
		(fp_line
			(start -0.67945 -0.3048)
			(end -0.67945 0.3048)
			(stroke
				(width 0.1)
				(type default)
			)
			(layer "B.Fab")
		)
		(fp_line
			(start -0.67945 0.3048)
			(end -0.120396 0.3048)
			(stroke
				(width 0.1)
				(type default)
			)
			(layer "B.Fab")
		)
		(fp_line
			(start -0.12065 -0.3048)
			(end -0.67945 -0.3048)
			(stroke
				(width 0.1)
				(type default)
			)
			(layer "B.Fab")
		)
		(fp_line
			(start -0.12065 -0.2794)
			(end -0.12065 -0.3048)
			(stroke
				(width 0.1)
				(type default)
			)
			(layer "B.Fab")
		)
		(fp_line
			(start -0.120396 0.2794)
			(end 0.12065 0.2794)
			(stroke
				(width 0.1)
				(type default)
			)
			(layer "B.Fab")
		)
		(fp_line
			(start -0.120396 0.3048)
			(end -0.120396 0.2794)
			(stroke
				(width 0.1)
				(type default)
			)
			(layer "B.Fab")
		)
		(fp_line
			(start 0.12065 -0.305054)
			(end 0.12065 -0.2794)
			(stroke
				(width 0.1)
				(type default)
			)
			(layer "B.Fab")
		)
		(fp_line
			(start 0.12065 -0.2794)
			(end -0.12065 -0.2794)
			(stroke
				(width 0.1)
				(type default)
			)
			(layer "B.Fab")
		)
		(fp_line
			(start 0.12065 0.2794)
			(end 0.12065 0.3048)
			(stroke
				(width 0.1)
				(type default)
			)
			(layer "B.Fab")
		)
		(fp_line
			(start 0.12065 0.3048)
			(end 0.67945 0.3048)
			(stroke
				(width 0.1)
				(type default)
			)
			(layer "B.Fab")
		)
		(fp_line
			(start 0.67945 -0.305054)
			(end 0.12065 -0.305054)
			(stroke
				(width 0.1)
				(type default)
			)
			(layer "B.Fab")
		)
		(fp_line
			(start 0.67945 0.3048)
			(end 0.67945 -0.305054)
			(stroke
				(width 0.1)
				(type default)
			)
			(layer "B.Fab")
		)
		(pad "1" smd circle
			(at 0.40005 0 180)
			(size 0 0)
			(layers "B.Cu" "B.Mask" "B.Paste")
			(net "PVDDCR_SOC_P0")
		)
		(pad "2" smd circle
			(at -0.40005 0 180)
			(size 0 0)
			(layers "B.Cu" "B.Mask" "B.Paste")
			(net "GND")
		)
	)
	(footprint ""
		(layer "B.Cu")
		(at 229.576122 -228.143308 90)
		(property "Reference" "R201"
			(at 0 0 90)
			(layer "B.SilkS")
			(hide yes)
			(effects
				(font
					(size 1.27 1.27)
				)
				(justify mirror)
			)
		)
		(property "Value" ""
			(at 0 0 90)
			(layer "B.Fab")
			(effects
				(font
					(size 1.27 1.27)
				)
				(justify mirror)
			)
		)
		(duplicate_pad_numbers_are_jumpers no)
		(fp_line
			(start 0.7874 -0.4064)
			(end -0.7874 -0.4064)
			(stroke
				(width 0.1524)
				(type default)
			)
			(layer "B.SilkS")
		)
		(fp_line
			(start -0.7874 -0.4064)
			(end -0.7874 0.4064)
			(stroke
				(width 0.1524)
				(type default)
			)
			(layer "B.SilkS")
		)
		(fp_line
			(start 0.7874 0.4064)
			(end 0.7874 -0.4064)
			(stroke
				(width 0.1524)
				(type default)
			)
			(layer "B.SilkS")
		)
		(fp_line
			(start -0.7874 0.4064)
			(end 0.7874 0.4064)
			(stroke
				(width 0.1524)
				(type default)
			)
			(layer "B.SilkS")
		)
		(fp_line
			(start 0.67945 -0.305054)
			(end 0.12065 -0.305054)
			(stroke
				(width 0.1)
				(type default)
			)
			(layer "B.Fab")
		)
		(fp_line
			(start 0.12065 -0.305054)
			(end 0.12065 -0.2794)
			(stroke
				(width 0.1)
				(type default)
			)
			(layer "B.Fab")
		)
		(fp_line
			(start -0.12065 -0.3048)
			(end -0.67945 -0.3048)
			(stroke
				(width 0.1)
				(type default)
			)
			(layer "B.Fab")
		)
		(fp_line
			(start -0.67945 -0.3048)
			(end -0.67945 0.3048)
			(stroke
				(width 0.1)
				(type default)
			)
			(layer "B.Fab")
		)
		(fp_line
			(start 0.12065 -0.2794)
			(end -0.12065 -0.2794)
			(stroke
				(width 0.1)
				(type default)
			)
			(layer "B.Fab")
		)
		(fp_line
			(start -0.12065 -0.2794)
			(end -0.12065 -0.3048)
			(stroke
				(width 0.1)
				(type default)
			)
			(layer "B.Fab")
		)
		(fp_line
			(start 0.12065 0.2794)
			(end 0.12065 0.3048)
			(stroke
				(width 0.1)
				(type default)
			)
			(layer "B.Fab")
		)
		(fp_line
			(start -0.120396 0.2794)
			(end 0.12065 0.2794)
			(stroke
				(width 0.1)
				(type default)
			)
			(layer "B.Fab")
		)
		(fp_line
			(start 0.67945 0.3048)
			(end 0.67945 -0.305054)
			(stroke
				(width 0.1)
				(type default)
			)
			(layer "B.Fab")
		)
		(fp_line
			(start 0.12065 0.3048)
			(end 0.67945 0.3048)
			(stroke
				(width 0.1)
				(type default)
			)
			(layer "B.Fab")
		)
		(fp_line
			(start -0.120396 0.3048)
			(end -0.120396 0.2794)
			(stroke
				(width 0.1)
				(type default)
			)
			(layer "B.Fab")
		)
		(fp_line
			(start -0.67945 0.3048)
			(end -0.120396 0.3048)
			(stroke
				(width 0.1)
				(type default)
			)
			(layer "B.Fab")
		)
		(pad "1" smd circle
			(at 0.40005 0 270)
			(size 0 0)
			(layers "B.Cu" "B.Mask" "B.Paste")
			(net "P3V3_AUX")
		)
		(pad "2" smd circle
			(at -0.40005 0 270)
			(size 0 0)
			(layers "B.Cu" "B.Mask" "B.Paste")
			(net "PU_U2_EN")
		)
	)
	(footprint ""
		(layer "B.Cu")
		(at 231.082596 -324.980554)
		(property "Reference" "R1252"
			(at 0 0 0)
			(layer "B.SilkS")
			(hide yes)
			(effects
				(font
					(size 1.27 1.27)
				)
				(justify mirror)
			)
		)
		(property "Value" ""
			(at 0 0 0)
			(layer "B.Fab")
			(effects
				(font
					(size 1.27 1.27)
				)
				(justify mirror)
			)
		)
		(duplicate_pad_numbers_are_jumpers no)
		(fp_line
			(start -0.7874 -0.4064)
			(end -0.7874 0.4064)
			(stroke
				(width 0.1524)
				(type default)
			)
			(layer "B.SilkS")
		)
		(fp_line
			(start -0.7874 0.4064)
			(end 0.7874 0.4064)
			(stroke
				(width 0.1524)
				(type default)
			)
			(layer "B.SilkS")
		)
		(fp_line
			(start 0.7874 -0.4064)
			(end -0.7874 -0.4064)
			(stroke
				(width 0.1524)
				(type default)
			)
			(layer "B.SilkS")
		)
		(fp_line
			(start 0.7874 0.4064)
			(end 0.7874 -0.4064)
			(stroke
				(width 0.1524)
				(type default)
			)
			(layer "B.SilkS")
		)
		(fp_line
			(start -0.67945 -0.3048)
			(end -0.67945 0.3048)
			(stroke
				(width 0.1)
				(type default)
			)
			(layer "B.Fab")
		)
		(fp_line
			(start -0.67945 0.3048)
			(end -0.120396 0.3048)
			(stroke
				(width 0.1)
				(type default)
			)
			(layer "B.Fab")
		)
		(fp_line
			(start -0.12065 -0.3048)
			(end -0.67945 -0.3048)
			(stroke
				(width 0.1)
				(type default)
			)
			(layer "B.Fab")
		)
		(fp_line
			(start -0.12065 -0.2794)
			(end -0.12065 -0.3048)
			(stroke
				(width 0.1)
				(type default)
			)
			(layer "B.Fab")
		)
		(fp_line
			(start -0.120396 0.2794)
			(end 0.12065 0.2794)
			(stroke
				(width 0.1)
				(type default)
			)
			(layer "B.Fab")
		)
		(fp_line
			(start -0.120396 0.3048)
			(end -0.120396 0.2794)
			(stroke
				(width 0.1)
				(type default)
			)
			(layer "B.Fab")
		)
		(fp_line
			(start 0.12065 -0.305054)
			(end 0.12065 -0.2794)
			(stroke
				(width 0.1)
				(type default)
			)
			(layer "B.Fab")
		)
		(fp_line
			(start 0.12065 -0.2794)
			(end -0.12065 -0.2794)
			(stroke
				(width 0.1)
				(type default)
			)
			(layer "B.Fab")
		)
		(fp_line
			(start 0.12065 0.2794)
			(end 0.12065 0.3048)
			(stroke
				(width 0.1)
				(type default)
			)
			(layer "B.Fab")
		)
		(fp_line
			(start 0.12065 0.3048)
			(end 0.67945 0.3048)
			(stroke
				(width 0.1)
				(type default)
			)
			(layer "B.Fab")
		)
		(fp_line
			(start 0.67945 -0.305054)
			(end 0.12065 -0.305054)
			(stroke
				(width 0.1)
				(type default)
			)
			(layer "B.Fab")
		)
		(fp_line
			(start 0.67945 0.3048)
			(end 0.67945 -0.305054)
			(stroke
				(width 0.1)
				(type default)
			)
			(layer "B.Fab")
		)
		(pad "1" smd rect
			(at 0.40005 0)
			(size 0.4572 0.508)
			(layers "B.Cu" "B.Mask" "B.Paste")
			(net "P1V8_CPU0_RT_1D_ADC")
		)
		(pad "2" smd rect
			(at -0.40005 0)
			(size 0.4572 0.508)
			(layers "B.Cu" "B.Mask" "B.Paste")
			(net "P1V8_CPU0_RT_1D_ADC_TIC")
		)
	)
	(footprint ""
		(layer "B.Cu")
		(at 224.310194 -336.846164 180)
		(property "Reference" "U6020"
			(at -1.980438 -5.745734 0)
			(unlocked yes)
			(layer "B.SilkS")
			(effects
				(font
					(size 0.7874 0.5842)
					(thickness 0.1524)
				)
				(justify left mirror)
			)
		)
		(property "Value" ""
			(at 0 0 0)
			(layer "B.Fab")
			(effects
				(font
					(size 1.27 1.27)
				)
				(justify mirror)
			)
		)
		(duplicate_pad_numbers_are_jumpers no)
		(fp_line
			(start 1.8542 3.949954)
			(end -1.8542 3.949954)
			(stroke
				(width 0.1524)
				(type default)
			)
			(layer "B.SilkS")
		)
		(fp_line
			(start 1.8542 -3.949954)
			(end 1.8542 3.949954)
			(stroke
				(width 0.1524)
				(type default)
			)
			(layer "B.SilkS")
		)
		(fp_line
			(start 1.282954 -3.949954)
			(end 1.8542 -3.949954)
			(stroke
				(width 0.1524)
				(type default)
			)
			(layer "B.SilkS")
		)
		(fp_line
			(start 0 -2.667)
			(end 1.282954 -3.949954)
			(stroke
				(width 0.1524)
				(type default)
			)
			(layer "B.SilkS")
		)
		(fp_line
			(start -1.282954 -3.949954)
			(end 0 -2.667)
			(stroke
				(width 0.1524)
				(type default)
			)
			(layer "B.SilkS")
		)
		(fp_line
			(start -1.8542 3.949954)
			(end -1.8542 -3.949954)
			(stroke
				(width 0.1524)
				(type default)
			)
			(layer "B.SilkS")
		)
		(fp_line
			(start -1.8542 -3.949954)
			(end -1.282954 -3.949954)
			(stroke
				(width 0.1524)
				(type default)
			)
			(layer "B.SilkS")
		)
		(fp_poly
			(pts
				(xy 2.737358 -5.05968) (xy 3.753358 -5.05968) (xy 3.245358 -4.04368)
			)
			(stroke
				(width 0)
				(type default)
			)
			(fill yes)
			(layer "B.SilkS")
		)
		(fp_line
			(start 2.249932 3.949954)
			(end -2.249932 3.949954)
			(stroke
				(width 0.1)
				(type default)
			)
			(layer "B.Fab")
		)
		(fp_line
			(start 2.249932 -3.949954)
			(end 2.249932 3.949954)
			(stroke
				(width 0.1)
				(type default)
			)
			(layer "B.Fab")
		)
		(fp_line
			(start -2.249932 3.949954)
			(end -2.249932 -3.949954)
			(stroke
				(width 0.1)
				(type default)
			)
			(layer "B.Fab")
		)
		(fp_line
			(start -2.249932 -3.949954)
			(end 2.249932 -3.949954)
			(stroke
				(width 0.1)
				(type default)
			)
			(layer "B.Fab")
		)
		(fp_poly
			(pts
				(xy 4.8006 -4.08305) (xy 4.8006 -3.06705) (xy 3.7846 -3.57505)
			)
			(stroke
				(width 0)
				(type default)
			)
			(fill yes)
			(layer "B.Fab")
		)
		(pad "1" smd rect
			(at 2.800096 -3.57505 90)
			(size 0.3048 1.6002)
			(layers "B.Cu" "B.Mask" "B.Paste")
			(net "RT_SMB_MUX_ADDR0")
		)
		(pad "2" smd rect
			(at 2.800096 -2.925064 90)
			(size 0.3048 1.6002)
			(layers "B.Cu" "B.Mask" "B.Paste")
			(net "RT_SMB_MUX_ADDR1")
		)
		(pad "3" smd rect
			(at 2.800096 -2.275078 90)
			(size 0.3048 1.6002)
			(layers "B.Cu" "B.Mask" "B.Paste")
			(net "RST_SMB_RT_N")
		)
		(pad "4" smd rect
			(at 2.800096 -1.625092 90)
			(size 0.3048 1.6002)
			(layers "B.Cu" "B.Mask" "B.Paste")
			(net "SMB_RT_CPU1_P0_SDA")
		)
		(pad "5" smd rect
			(at 2.800096 -0.975106 90)
			(size 0.3048 1.6002)
			(layers "B.Cu" "B.Mask" "B.Paste")
			(net "SMB_RT_CPU1_P0_SCL")
		)
		(pad "6" smd rect
			(at 2.800096 -0.32512 90)
			(size 0.3048 1.6002)
			(layers "B.Cu" "B.Mask" "B.Paste")
			(net "SMB_RT_CPU1_P1_SDA")
		)
		(pad "7" smd rect
			(at 2.800096 0.32512 90)
			(size 0.3048 1.6002)
			(layers "B.Cu" "B.Mask" "B.Paste")
			(net "SMB_RT_CPU1_P1_SCL")
		)
		(pad "8" smd rect
			(at 2.800096 0.975106 90)
			(size 0.3048 1.6002)
			(layers "B.Cu" "B.Mask" "B.Paste")
			(net "SMB_RT_CPU1_P3_SDA")
		)
		(pad "9" smd rect
			(at 2.800096 1.625092 90)
			(size 0.3048 1.6002)
			(layers "B.Cu" "B.Mask" "B.Paste")
			(net "SMB_RT_CPU1_P3_SCL")
		)
		(pad "10" smd rect
			(at 2.800096 2.275078 90)
			(size 0.3048 1.6002)
			(layers "B.Cu" "B.Mask" "B.Paste")
			(net "SMB_RT_CPU1_P2_SDA")
		)
		(pad "11" smd rect
			(at 2.800096 2.925064 90)
			(size 0.3048 1.6002)
			(layers "B.Cu" "B.Mask" "B.Paste")
			(net "SMB_RT_CPU1_P2_SCL")
		)
		(pad "12" smd rect
			(at 2.800096 3.57505 90)
			(size 0.3048 1.6002)
			(layers "B.Cu" "B.Mask" "B.Paste")
			(net "GND")
		)
		(pad "13" smd rect
			(at -2.800096 3.57505 90)
			(size 0.3048 1.6002)
			(layers "B.Cu" "B.Mask" "B.Paste")
			(net "SMB_RT_CPU0_P0_SDA")
		)
		(pad "14" smd rect
			(at -2.800096 2.925064 90)
			(size 0.3048 1.6002)
			(layers "B.Cu" "B.Mask" "B.Paste")
			(net "SMB_RT_CPU0_P0_SCL")
		)
		(pad "15" smd rect
			(at -2.800096 2.275078 90)
			(size 0.3048 1.6002)
			(layers "B.Cu" "B.Mask" "B.Paste")
			(net "SMB_RT_CPU0_P1_SDA")
		)
		(pad "16" smd rect
			(at -2.800096 1.625092 90)
			(size 0.3048 1.6002)
			(layers "B.Cu" "B.Mask" "B.Paste")
			(net "SMB_RT_CPU0_P1_SCL")
		)
		(pad "17" smd rect
			(at -2.800096 0.975106 90)
			(size 0.3048 1.6002)
			(layers "B.Cu" "B.Mask" "B.Paste")
			(net "SMB_RT_CPU0_P3_SDA")
		)
		(pad "18" smd rect
			(at -2.800096 0.32512 90)
			(size 0.3048 1.6002)
			(layers "B.Cu" "B.Mask" "B.Paste")
			(net "SMB_RT_CPU0_P3_SCL")
		)
		(pad "19" smd rect
			(at -2.800096 -0.32512 90)
			(size 0.3048 1.6002)
			(layers "B.Cu" "B.Mask" "B.Paste")
			(net "SMB_RT_CPU0_P2_SDA")
		)
		(pad "20" smd rect
			(at -2.800096 -0.975106 90)
			(size 0.3048 1.6002)
			(layers "B.Cu" "B.Mask" "B.Paste")
			(net "SMB_RT_CPU0_P2_SCL")
		)
		(pad "21" smd rect
			(at -2.800096 -1.625092 90)
			(size 0.3048 1.6002)
			(layers "B.Cu" "B.Mask" "B.Paste")
			(net "RT_SMB_MUX_ADDR2")
		)
		(pad "22" smd rect
			(at -2.800096 -2.275078 90)
			(size 0.3048 1.6002)
			(layers "B.Cu" "B.Mask" "B.Paste")
			(net "SMB_MUX_RT_SCL")
		)
		(pad "23" smd rect
			(at -2.800096 -2.925064 90)
			(size 0.3048 1.6002)
			(layers "B.Cu" "B.Mask" "B.Paste")
			(net "SMB_MUX_RT_SDA")
		)
		(pad "24" smd rect
			(at -2.800096 -3.57505 90)
			(size 0.3048 1.6002)
			(layers "B.Cu" "B.Mask" "B.Paste")
			(net "P1V8_AUX")
		)
	)
	(footprint ""
		(layer "B.Cu")
		(at 94.446344 -388.011162 -90)
		(property "Reference" "C350"
			(at 0 0 90)
			(layer "B.SilkS")
			(hide yes)
			(effects
				(font
					(size 1.27 1.27)
				)
				(justify mirror)
			)
		)
		(property "Value" ""
			(at 0 0 90)
			(layer "B.Fab")
			(effects
				(font
					(size 1.27 1.27)
				)
				(justify mirror)
			)
		)
		(duplicate_pad_numbers_are_jumpers no)
		(fp_line
			(start -0.299974 0.150114)
			(end 0.299974 0.150114)
			(stroke
				(width 0.1)
				(type default)
			)
			(layer "B.Fab")
		)
		(fp_line
			(start 0.299974 0.150114)
			(end 0.299974 -0.150114)
			(stroke
				(width 0.1)
				(type default)
			)
			(layer "B.Fab")
		)
		(fp_line
			(start -0.299974 -0.150114)
			(end -0.299974 0.150114)
			(stroke
				(width 0.1)
				(type default)
			)
			(layer "B.Fab")
		)
		(fp_line
			(start 0.299974 -0.150114)
			(end -0.299974 -0.150114)
			(stroke
				(width 0.1)
				(type default)
			)
			(layer "B.Fab")
		)
		(pad "1" smd rect
			(at 0.2667 0 90)
			(size 0.3048 0.381)
			(layers "B.Cu" "B.Mask" "B.Paste")
			(net "P0V9_CPU1_RT1_2A")
		)
		(pad "2" smd rect
			(at -0.2667 0 90)
			(size 0.3048 0.381)
			(layers "B.Cu" "B.Mask" "B.Paste")
			(net "GND")
		)
	)
	(footprint ""
		(layer "B.Cu")
		(at 86.973664 -408.517344 90)
		(property "Reference" "C6685"
			(at 0 0 90)
			(layer "B.SilkS")
			(hide yes)
			(effects
				(font
					(size 1.27 1.27)
				)
				(justify mirror)
			)
		)
		(property "Value" ""
			(at 0 0 90)
			(layer "B.Fab")
			(effects
				(font
					(size 1.27 1.27)
				)
				(justify mirror)
			)
		)
		(duplicate_pad_numbers_are_jumpers no)
		(fp_line
			(start 0.299974 -0.150114)
			(end -0.299974 -0.150114)
			(stroke
				(width 0.1)
				(type default)
			)
			(layer "B.Fab")
		)
		(fp_line
			(start -0.299974 -0.150114)
			(end -0.299974 0.150114)
			(stroke
				(width 0.1)
				(type default)
			)
			(layer "B.Fab")
		)
		(fp_line
			(start 0.299974 0.150114)
			(end 0.299974 -0.150114)
			(stroke
				(width 0.1)
				(type default)
			)
			(layer "B.Fab")
		)
		(fp_line
			(start -0.299974 0.150114)
			(end 0.299974 0.150114)
			(stroke
				(width 0.1)
				(type default)
			)
			(layer "B.Fab")
		)
		(pad "1" smd rect
			(at 0.2667 0 270)
			(size 0.3048 0.381)
			(layers "B.Cu" "B.Mask" "B.Paste")
			(net "P5E_CPU1_P1_TX_BUF_C_DP<12>")
		)
		(pad "2" smd rect
			(at -0.2667 0 270)
			(size 0.3048 0.381)
			(layers "B.Cu" "B.Mask" "B.Paste")
			(net "P5E_CPU1_P1_TX_BUF_DP<12>")
		)
	)
	(footprint ""
		(layer "B.Cu")
		(at 231.072436 -326.07885)
		(property "Reference" "R1257"
			(at 0 0 0)
			(layer "B.SilkS")
			(hide yes)
			(effects
				(font
					(size 1.27 1.27)
				)
				(justify mirror)
			)
		)
		(property "Value" ""
			(at 0 0 0)
			(layer "B.Fab")
			(effects
				(font
					(size 1.27 1.27)
				)
				(justify mirror)
			)
		)
		(duplicate_pad_numbers_are_jumpers no)
		(fp_line
			(start -0.7874 -0.4064)
			(end -0.7874 0.4064)
			(stroke
				(width 0.1524)
				(type default)
			)
			(layer "B.SilkS")
		)
		(fp_line
			(start -0.7874 0.4064)
			(end 0.7874 0.4064)
			(stroke
				(width 0.1524)
				(type default)
			)
			(layer "B.SilkS")
		)
		(fp_line
			(start 0.7874 -0.4064)
			(end -0.7874 -0.4064)
			(stroke
				(width 0.1524)
				(type default)
			)
			(layer "B.SilkS")
		)
		(fp_line
			(start 0.7874 0.4064)
			(end 0.7874 -0.4064)
			(stroke
				(width 0.1524)
				(type default)
			)
			(layer "B.SilkS")
		)
		(fp_line
			(start -0.67945 -0.3048)
			(end -0.67945 0.3048)
			(stroke
				(width 0.1)
				(type default)
			)
			(layer "B.Fab")
		)
		(fp_line
			(start -0.67945 0.3048)
			(end -0.120396 0.3048)
			(stroke
				(width 0.1)
				(type default)
			)
			(layer "B.Fab")
		)
		(fp_line
			(start -0.12065 -0.3048)
			(end -0.67945 -0.3048)
			(stroke
				(width 0.1)
				(type default)
			)
			(layer "B.Fab")
		)
		(fp_line
			(start -0.12065 -0.2794)
			(end -0.12065 -0.3048)
			(stroke
				(width 0.1)
				(type default)
			)
			(layer "B.Fab")
		)
		(fp_line
			(start -0.120396 0.2794)
			(end 0.12065 0.2794)
			(stroke
				(width 0.1)
				(type default)
			)
			(layer "B.Fab")
		)
		(fp_line
			(start -0.120396 0.3048)
			(end -0.120396 0.2794)
			(stroke
				(width 0.1)
				(type default)
			)
			(layer "B.Fab")
		)
		(fp_line
			(start 0.12065 -0.305054)
			(end 0.12065 -0.2794)
			(stroke
				(width 0.1)
				(type default)
			)
			(layer "B.Fab")
		)
		(fp_line
			(start 0.12065 -0.2794)
			(end -0.12065 -0.2794)
			(stroke
				(width 0.1)
				(type default)
			)
			(layer "B.Fab")
		)
		(fp_line
			(start 0.12065 0.2794)
			(end 0.12065 0.3048)
			(stroke
				(width 0.1)
				(type default)
			)
			(layer "B.Fab")
		)
		(fp_line
			(start 0.12065 0.3048)
			(end 0.67945 0.3048)
			(stroke
				(width 0.1)
				(type default)
			)
			(layer "B.Fab")
		)
		(fp_line
			(start 0.67945 -0.305054)
			(end 0.12065 -0.305054)
			(stroke
				(width 0.1)
				(type default)
			)
			(layer "B.Fab")
		)
		(fp_line
			(start 0.67945 0.3048)
			(end 0.67945 -0.305054)
			(stroke
				(width 0.1)
				(type default)
			)
			(layer "B.Fab")
		)
		(pad "1" smd rect
			(at 0.40005 0)
			(size 0.4572 0.508)
			(layers "B.Cu" "B.Mask" "B.Paste")
			(net "P1V8_CPU1_RT_1D_ADC")
		)
		(pad "2" smd rect
			(at -0.40005 0)
			(size 0.4572 0.508)
			(layers "B.Cu" "B.Mask" "B.Paste")
			(net "P1V8_CPU1_RT_1D_ADC_TIC")
		)
	)
	(footprint ""
		(layer "B.Cu")
		(at 359.421176 -179.67452 90)
		(property "Reference" "PC575_5"
			(at 0 0 90)
			(layer "B.SilkS")
			(hide yes)
			(effects
				(font
					(size 1.27 1.27)
				)
				(justify mirror)
			)
		)
		(property "Value" ""
			(at 0 0 90)
			(layer "B.Fab")
			(effects
				(font
					(size 1.27 1.27)
				)
				(justify mirror)
			)
		)
		(duplicate_pad_numbers_are_jumpers no)
		(fp_line
			(start 1.524 -0.762)
			(end -1.524 -0.762)
			(stroke
				(width 0.1524)
				(type default)
			)
			(layer "B.SilkS")
		)
		(fp_line
			(start -1.524 -0.762)
			(end -1.524 0.762)
			(stroke
				(width 0.1524)
				(type default)
			)
			(layer "B.SilkS")
		)
		(fp_line
			(start 1.524 0.762)
			(end 1.524 -0.762)
			(stroke
				(width 0.1524)
				(type default)
			)
			(layer "B.SilkS")
		)
		(fp_line
			(start -1.524 0.762)
			(end 1.524 0.762)
			(stroke
				(width 0.1524)
				(type default)
			)
			(layer "B.SilkS")
		)
		(fp_line
			(start 1.1049 -0.724916)
			(end 1.1049 0.724916)
			(stroke
				(width 0.1)
				(type default)
			)
			(layer "B.Fab")
		)
		(fp_line
			(start -1.1049 -0.724916)
			(end 1.1049 -0.724916)
			(stroke
				(width 0.1)
				(type default)
			)
			(layer "B.Fab")
		)
		(fp_line
			(start 1.1049 0.724916)
			(end -1.1049 0.724916)
			(stroke
				(width 0.1)
				(type default)
			)
			(layer "B.Fab")
		)
		(fp_line
			(start -1.1049 0.724916)
			(end -1.1049 -0.724916)
			(stroke
				(width 0.1)
				(type default)
			)
			(layer "B.Fab")
		)
		(pad "1" smd rect
			(at 0.889 0 90)
			(size 1.016 1.27)
			(layers "B.Cu" "B.Mask" "B.Paste")
			(net "PVDDCR_CPU0_P0")
		)
		(pad "2" smd rect
			(at -0.889 0 90)
			(size 1.016 1.27)
			(layers "B.Cu" "B.Mask" "B.Paste")
			(net "GND")
		)
	)
	(footprint ""
		(layer "B.Cu")
		(at 380.282958 -205.902052 -90)
		(property "Reference" "R986"
			(at 0 0 90)
			(layer "B.SilkS")
			(hide yes)
			(effects
				(font
					(size 1.27 1.27)
				)
				(justify mirror)
			)
		)
		(property "Value" ""
			(at 0 0 90)
			(layer "B.Fab")
			(effects
				(font
					(size 1.27 1.27)
				)
				(justify mirror)
			)
		)
		(duplicate_pad_numbers_are_jumpers no)
		(fp_line
			(start -0.7874 0.4064)
			(end 0.7874 0.4064)
			(stroke
				(width 0.1524)
				(type default)
			)
			(layer "B.SilkS")
		)
		(fp_line
			(start 0.7874 0.4064)
			(end 0.7874 -0.4064)
			(stroke
				(width 0.1524)
				(type default)
			)
			(layer "B.SilkS")
		)
		(fp_line
			(start -0.7874 -0.4064)
			(end -0.7874 0.4064)
			(stroke
				(width 0.1524)
				(type default)
			)
			(layer "B.SilkS")
		)
		(fp_line
			(start 0.7874 -0.4064)
			(end -0.7874 -0.4064)
			(stroke
				(width 0.1524)
				(type default)
			)
			(layer "B.SilkS")
		)
		(fp_line
			(start -0.67945 0.3048)
			(end -0.120396 0.3048)
			(stroke
				(width 0.1)
				(type default)
			)
			(layer "B.Fab")
		)
		(fp_line
			(start -0.120396 0.3048)
			(end -0.120396 0.2794)
			(stroke
				(width 0.1)
				(type default)
			)
			(layer "B.Fab")
		)
		(fp_line
			(start 0.12065 0.3048)
			(end 0.67945 0.3048)
			(stroke
				(width 0.1)
				(type default)
			)
			(layer "B.Fab")
		)
		(fp_line
			(start 0.67945 0.3048)
			(end 0.67945 -0.305054)
			(stroke
				(width 0.1)
				(type default)
			)
			(layer "B.Fab")
		)
		(fp_line
			(start -0.120396 0.2794)
			(end 0.12065 0.2794)
			(stroke
				(width 0.1)
				(type default)
			)
			(layer "B.Fab")
		)
		(fp_line
			(start 0.12065 0.2794)
			(end 0.12065 0.3048)
			(stroke
				(width 0.1)
				(type default)
			)
			(layer "B.Fab")
		)
		(fp_line
			(start -0.12065 -0.2794)
			(end -0.12065 -0.3048)
			(stroke
				(width 0.1)
				(type default)
			)
			(layer "B.Fab")
		)
		(fp_line
			(start 0.12065 -0.2794)
			(end -0.12065 -0.2794)
			(stroke
				(width 0.1)
				(type default)
			)
			(layer "B.Fab")
		)
		(fp_line
			(start -0.67945 -0.3048)
			(end -0.67945 0.3048)
			(stroke
				(width 0.1)
				(type default)
			)
			(layer "B.Fab")
		)
		(fp_line
			(start -0.12065 -0.3048)
			(end -0.67945 -0.3048)
			(stroke
				(width 0.1)
				(type default)
			)
			(layer "B.Fab")
		)
		(fp_line
			(start 0.12065 -0.305054)
			(end 0.12065 -0.2794)
			(stroke
				(width 0.1)
				(type default)
			)
			(layer "B.Fab")
		)
		(fp_line
			(start 0.67945 -0.305054)
			(end 0.12065 -0.305054)
			(stroke
				(width 0.1)
				(type default)
			)
			(layer "B.Fab")
		)
		(pad "1" smd rect
			(at 0.40005 0 270)
			(size 0.4572 0.508)
			(layers "B.Cu" "B.Mask" "B.Paste")
			(net "I3C_1_SPD_DDRGL_CPU0_R_SCL")
		)
		(pad "2" smd rect
			(at -0.40005 0 270)
			(size 0.4572 0.508)
			(layers "B.Cu" "B.Mask" "B.Paste")
			(net "I3C_SPD_DDRGL_CPU0_BYPASS_SCL")
		)
	)
	(footprint ""
		(layer "B.Cu")
		(at 232.537 -339.725 90)
		(property "Reference" "R6764"
			(at 0 0 90)
			(layer "B.SilkS")
			(hide yes)
			(effects
				(font
					(size 1.27 1.27)
				)
				(justify mirror)
			)
		)
		(property "Value" ""
			(at 0 0 90)
			(layer "B.Fab")
			(effects
				(font
					(size 1.27 1.27)
				)
				(justify mirror)
			)
		)
		(duplicate_pad_numbers_are_jumpers no)
		(fp_line
			(start 0.32512 -0.175006)
			(end -0.32512 -0.175006)
			(stroke
				(width 0.1)
				(type default)
			)
			(layer "B.Fab")
		)
		(fp_line
			(start -0.32512 -0.175006)
			(end -0.32512 0.175006)
			(stroke
				(width 0.1)
				(type default)
			)
			(layer "B.Fab")
		)
		(fp_line
			(start 0.32512 0.175006)
			(end 0.32512 -0.175006)
			(stroke
				(width 0.1)
				(type default)
			)
			(layer "B.Fab")
		)
		(fp_line
			(start -0.32512 0.175006)
			(end 0.32512 0.175006)
			(stroke
				(width 0.1)
				(type default)
			)
			(layer "B.Fab")
		)
		(pad "1" smd rect
			(at 0.2667 0 270)
			(size 0.3048 0.381)
			(layers "B.Cu" "B.Mask" "B.Paste")
			(net "P1V8_CPU0_RT_1D")
		)
		(pad "2" smd rect
			(at -0.2667 0 90)
			(size 0.3048 0.381)
			(layers "B.Cu" "B.Mask" "B.Paste")
			(net "SMB_RT_CPU0_P1_R_SDA")
		)
	)
	(footprint ""
		(layer "B.Cu")
		(at 187.055506 -126.833376 -90)
		(property "Reference" "R161"
			(at 0 0 90)
			(layer "B.SilkS")
			(hide yes)
			(effects
				(font
					(size 1.27 1.27)
				)
				(justify mirror)
			)
		)
		(property "Value" ""
			(at 0 0 90)
			(layer "B.Fab")
			(effects
				(font
					(size 1.27 1.27)
				)
				(justify mirror)
			)
		)
		(duplicate_pad_numbers_are_jumpers no)
		(fp_line
			(start -0.7874 0.4064)
			(end 0.7874 0.4064)
			(stroke
				(width 0.1524)
				(type default)
			)
			(layer "B.SilkS")
		)
		(fp_line
			(start 0.7874 0.4064)
			(end 0.7874 -0.4064)
			(stroke
				(width 0.1524)
				(type default)
			)
			(layer "B.SilkS")
		)
		(fp_line
			(start -0.7874 -0.4064)
			(end -0.7874 0.4064)
			(stroke
				(width 0.1524)
				(type default)
			)
			(layer "B.SilkS")
		)
		(fp_line
			(start 0.7874 -0.4064)
			(end -0.7874 -0.4064)
			(stroke
				(width 0.1524)
				(type default)
			)
			(layer "B.SilkS")
		)
		(fp_line
			(start -0.67945 0.3048)
			(end -0.120396 0.3048)
			(stroke
				(width 0.1)
				(type default)
			)
			(layer "B.Fab")
		)
		(fp_line
			(start -0.120396 0.3048)
			(end -0.120396 0.2794)
			(stroke
				(width 0.1)
				(type default)
			)
			(layer "B.Fab")
		)
		(fp_line
			(start 0.12065 0.3048)
			(end 0.67945 0.3048)
			(stroke
				(width 0.1)
				(type default)
			)
			(layer "B.Fab")
		)
		(fp_line
			(start 0.67945 0.3048)
			(end 0.67945 -0.305054)
			(stroke
				(width 0.1)
				(type default)
			)
			(layer "B.Fab")
		)
		(fp_line
			(start -0.120396 0.2794)
			(end 0.12065 0.2794)
			(stroke
				(width 0.1)
				(type default)
			)
			(layer "B.Fab")
		)
		(fp_line
			(start 0.12065 0.2794)
			(end 0.12065 0.3048)
			(stroke
				(width 0.1)
				(type default)
			)
			(layer "B.Fab")
		)
		(fp_line
			(start -0.12065 -0.2794)
			(end -0.12065 -0.3048)
			(stroke
				(width 0.1)
				(type default)
			)
			(layer "B.Fab")
		)
		(fp_line
			(start 0.12065 -0.2794)
			(end -0.12065 -0.2794)
			(stroke
				(width 0.1)
				(type default)
			)
			(layer "B.Fab")
		)
		(fp_line
			(start -0.67945 -0.3048)
			(end -0.67945 0.3048)
			(stroke
				(width 0.1)
				(type default)
			)
			(layer "B.Fab")
		)
		(fp_line
			(start -0.12065 -0.3048)
			(end -0.67945 -0.3048)
			(stroke
				(width 0.1)
				(type default)
			)
			(layer "B.Fab")
		)
		(fp_line
			(start 0.12065 -0.305054)
			(end 0.12065 -0.2794)
			(stroke
				(width 0.1)
				(type default)
			)
			(layer "B.Fab")
		)
		(fp_line
			(start 0.67945 -0.305054)
			(end 0.12065 -0.305054)
			(stroke
				(width 0.1)
				(type default)
			)
			(layer "B.Fab")
		)
		(pad "1" smd circle
			(at 0.40005 0 90)
			(size 0 0)
			(layers "B.Cu" "B.Mask" "B.Paste")
			(net "CPU1_JTAG_BUF_R_OE")
		)
		(pad "2" smd circle
			(at -0.40005 0 90)
			(size 0 0)
			(layers "B.Cu" "B.Mask" "B.Paste")
			(net "CPU1_JTAG_BUF_OE")
		)
	)
	(footprint ""
		(layer "B.Cu")
		(at 214.122 -334.01)
		(property "Reference" "R6813"
			(at 0 0 0)
			(layer "B.SilkS")
			(hide yes)
			(effects
				(font
					(size 1.27 1.27)
				)
				(justify mirror)
			)
		)
		(property "Value" ""
			(at 0 0 0)
			(layer "B.Fab")
			(effects
				(font
					(size 1.27 1.27)
				)
				(justify mirror)
			)
		)
		(duplicate_pad_numbers_are_jumpers no)
		(fp_line
			(start -0.32512 -0.175006)
			(end -0.32512 0.175006)
			(stroke
				(width 0.1)
				(type default)
			)
			(layer "B.Fab")
		)
		(fp_line
			(start -0.32512 0.175006)
			(end 0.32512 0.175006)
			(stroke
				(width 0.1)
				(type default)
			)
			(layer "B.Fab")
		)
		(fp_line
			(start 0.32512 -0.175006)
			(end -0.32512 -0.175006)
			(stroke
				(width 0.1)
				(type default)
			)
			(layer "B.Fab")
		)
		(fp_line
			(start 0.32512 0.175006)
			(end 0.32512 -0.175006)
			(stroke
				(width 0.1)
				(type default)
			)
			(layer "B.Fab")
		)
		(pad "1" smd rect
			(at 0.2667 0 180)
			(size 0.3048 0.381)
			(layers "B.Cu" "B.Mask" "B.Paste")
			(net "SMB_RT_CPU1_P0_R_SDA")
		)
		(pad "2" smd rect
			(at -0.2667 0)
			(size 0.3048 0.381)
			(layers "B.Cu" "B.Mask" "B.Paste")
			(net "SMB_RT_CPU1_P0_R2_SDA")
		)
	)
	(footprint ""
		(layer "B.Cu")
		(at 180.721 -100.294948 90)
		(property "Reference" "R278"
			(at 0 0 90)
			(layer "B.SilkS")
			(hide yes)
			(effects
				(font
					(size 1.27 1.27)
				)
				(justify mirror)
			)
		)
		(property "Value" ""
			(at 0 0 90)
			(layer "B.Fab")
			(effects
				(font
					(size 1.27 1.27)
				)
				(justify mirror)
			)
		)
		(duplicate_pad_numbers_are_jumpers no)
		(fp_line
			(start 0.7874 -0.4064)
			(end -0.7874 -0.4064)
			(stroke
				(width 0.1524)
				(type default)
			)
			(layer "B.SilkS")
		)
		(fp_line
			(start -0.7874 -0.4064)
			(end -0.7874 0.4064)
			(stroke
				(width 0.1524)
				(type default)
			)
			(layer "B.SilkS")
		)
		(fp_line
			(start 0.7874 0.4064)
			(end 0.7874 -0.4064)
			(stroke
				(width 0.1524)
				(type default)
			)
			(layer "B.SilkS")
		)
		(fp_line
			(start -0.7874 0.4064)
			(end 0.7874 0.4064)
			(stroke
				(width 0.1524)
				(type default)
			)
			(layer "B.SilkS")
		)
		(fp_line
			(start 0.67945 -0.305054)
			(end 0.12065 -0.305054)
			(stroke
				(width 0.1)
				(type default)
			)
			(layer "B.Fab")
		)
		(fp_line
			(start 0.12065 -0.305054)
			(end 0.12065 -0.2794)
			(stroke
				(width 0.1)
				(type default)
			)
			(layer "B.Fab")
		)
		(fp_line
			(start -0.12065 -0.3048)
			(end -0.67945 -0.3048)
			(stroke
				(width 0.1)
				(type default)
			)
			(layer "B.Fab")
		)
		(fp_line
			(start -0.67945 -0.3048)
			(end -0.67945 0.3048)
			(stroke
				(width 0.1)
				(type default)
			)
			(layer "B.Fab")
		)
		(fp_line
			(start 0.12065 -0.2794)
			(end -0.12065 -0.2794)
			(stroke
				(width 0.1)
				(type default)
			)
			(layer "B.Fab")
		)
		(fp_line
			(start -0.12065 -0.2794)
			(end -0.12065 -0.3048)
			(stroke
				(width 0.1)
				(type default)
			)
			(layer "B.Fab")
		)
		(fp_line
			(start 0.12065 0.2794)
			(end 0.12065 0.3048)
			(stroke
				(width 0.1)
				(type default)
			)
			(layer "B.Fab")
		)
		(fp_line
			(start -0.120396 0.2794)
			(end 0.12065 0.2794)
			(stroke
				(width 0.1)
				(type default)
			)
			(layer "B.Fab")
		)
		(fp_line
			(start 0.67945 0.3048)
			(end 0.67945 -0.305054)
			(stroke
				(width 0.1)
				(type default)
			)
			(layer "B.Fab")
		)
		(fp_line
			(start 0.12065 0.3048)
			(end 0.67945 0.3048)
			(stroke
				(width 0.1)
				(type default)
			)
			(layer "B.Fab")
		)
		(fp_line
			(start -0.120396 0.3048)
			(end -0.120396 0.2794)
			(stroke
				(width 0.1)
				(type default)
			)
			(layer "B.Fab")
		)
		(fp_line
			(start -0.67945 0.3048)
			(end -0.120396 0.3048)
			(stroke
				(width 0.1)
				(type default)
			)
			(layer "B.Fab")
		)
		(pad "1" smd circle
			(at 0.40005 0 270)
			(size 0 0)
			(layers "B.Cu" "B.Mask" "B.Paste")
			(net "FM_PVDD11_S3_P1_OCP_N")
		)
		(pad "2" smd circle
			(at -0.40005 0 270)
			(size 0 0)
			(layers "B.Cu" "B.Mask" "B.Paste")
			(net "PVDD11_S3_P1_OCP_N")
		)
	)
	(footprint ""
		(layer "B.Cu")
		(at 202.15225 -341.864442 180)
		(property "Reference" "R453"
			(at 0 0 0)
			(layer "B.SilkS")
			(hide yes)
			(effects
				(font
					(size 1.27 1.27)
				)
				(justify mirror)
			)
		)
		(property "Value" ""
			(at 0 0 0)
			(layer "B.Fab")
			(effects
				(font
					(size 1.27 1.27)
				)
				(justify mirror)
			)
		)
		(duplicate_pad_numbers_are_jumpers no)
		(fp_line
			(start 0.7874 0.4064)
			(end 0.7874 -0.4064)
			(stroke
				(width 0.1524)
				(type default)
			)
			(layer "B.SilkS")
		)
		(fp_line
			(start 0.7874 -0.4064)
			(end -0.7874 -0.4064)
			(stroke
				(width 0.1524)
				(type default)
			)
			(layer "B.SilkS")
		)
		(fp_line
			(start -0.7874 0.4064)
			(end 0.7874 0.4064)
			(stroke
				(width 0.1524)
				(type default)
			)
			(layer "B.SilkS")
		)
		(fp_line
			(start -0.7874 -0.4064)
			(end -0.7874 0.4064)
			(stroke
				(width 0.1524)
				(type default)
			)
			(layer "B.SilkS")
		)
		(fp_line
			(start 0.67945 0.3048)
			(end 0.67945 -0.305054)
			(stroke
				(width 0.1)
				(type default)
			)
			(layer "B.Fab")
		)
		(fp_line
			(start 0.67945 -0.305054)
			(end 0.12065 -0.305054)
			(stroke
				(width 0.1)
				(type default)
			)
			(layer "B.Fab")
		)
		(fp_line
			(start 0.12065 0.3048)
			(end 0.67945 0.3048)
			(stroke
				(width 0.1)
				(type default)
			)
			(layer "B.Fab")
		)
		(fp_line
			(start 0.12065 0.2794)
			(end 0.12065 0.3048)
			(stroke
				(width 0.1)
				(type default)
			)
			(layer "B.Fab")
		)
		(fp_line
			(start 0.12065 -0.2794)
			(end -0.12065 -0.2794)
			(stroke
				(width 0.1)
				(type default)
			)
			(layer "B.Fab")
		)
		(fp_line
			(start 0.12065 -0.305054)
			(end 0.12065 -0.2794)
			(stroke
				(width 0.1)
				(type default)
			)
			(layer "B.Fab")
		)
		(fp_line
			(start -0.120396 0.3048)
			(end -0.120396 0.2794)
			(stroke
				(width 0.1)
				(type default)
			)
			(layer "B.Fab")
		)
		(fp_line
			(start -0.120396 0.2794)
			(end 0.12065 0.2794)
			(stroke
				(width 0.1)
				(type default)
			)
			(layer "B.Fab")
		)
		(fp_line
			(start -0.12065 -0.2794)
			(end -0.12065 -0.3048)
			(stroke
				(width 0.1)
				(type default)
			)
			(layer "B.Fab")
		)
		(fp_line
			(start -0.12065 -0.3048)
			(end -0.67945 -0.3048)
			(stroke
				(width 0.1)
				(type default)
			)
			(layer "B.Fab")
		)
		(fp_line
			(start -0.67945 0.3048)
			(end -0.120396 0.3048)
			(stroke
				(width 0.1)
				(type default)
			)
			(layer "B.Fab")
		)
		(fp_line
			(start -0.67945 -0.3048)
			(end -0.67945 0.3048)
			(stroke
				(width 0.1)
				(type default)
			)
			(layer "B.Fab")
		)
		(pad "1" smd circle
			(at 0.40005 0)
			(size 0 0)
			(layers "B.Cu" "B.Mask" "B.Paste")
			(net "PVDD_33_S5_VCC")
		)
		(pad "2" smd circle
			(at -0.40005 0)
			(size 0 0)
			(layers "B.Cu" "B.Mask" "B.Paste")
			(net "PWRGD_PVDD33_S5")
		)
	)
	(footprint ""
		(layer "B.Cu")
		(at 118.658386 -269.307564 180)
		(property "Reference" "C2362"
			(at 0 0 0)
			(layer "B.SilkS")
			(hide yes)
			(effects
				(font
					(size 1.27 1.27)
				)
				(justify mirror)
			)
		)
		(property "Value" ""
			(at 0 0 0)
			(layer "B.Fab")
			(effects
				(font
					(size 1.27 1.27)
				)
				(justify mirror)
			)
		)
		(duplicate_pad_numbers_are_jumpers no)
		(fp_line
			(start 0.7874 0.4064)
			(end 0.7874 -0.4064)
			(stroke
				(width 0.1524)
				(type default)
			)
			(layer "B.SilkS")
		)
		(fp_line
			(start 0.7874 -0.4064)
			(end -0.7874 -0.4064)
			(stroke
				(width 0.1524)
				(type default)
			)
			(layer "B.SilkS")
		)
		(fp_line
			(start -0.7874 0.4064)
			(end 0.7874 0.4064)
			(stroke
				(width 0.1524)
				(type default)
			)
			(layer "B.SilkS")
		)
		(fp_line
			(start -0.7874 -0.4064)
			(end -0.7874 0.4064)
			(stroke
				(width 0.1524)
				(type default)
			)
			(layer "B.SilkS")
		)
		(fp_line
			(start 0.67945 0.3048)
			(end 0.67945 -0.305054)
			(stroke
				(width 0.1)
				(type default)
			)
			(layer "B.Fab")
		)
		(fp_line
			(start 0.67945 -0.305054)
			(end 0.12065 -0.305054)
			(stroke
				(width 0.1)
				(type default)
			)
			(layer "B.Fab")
		)
		(fp_line
			(start 0.12065 0.3048)
			(end 0.67945 0.3048)
			(stroke
				(width 0.1)
				(type default)
			)
			(layer "B.Fab")
		)
		(fp_line
			(start 0.12065 0.2794)
			(end 0.12065 0.3048)
			(stroke
				(width 0.1)
				(type default)
			)
			(layer "B.Fab")
		)
		(fp_line
			(start 0.12065 -0.2794)
			(end -0.12065 -0.2794)
			(stroke
				(width 0.1)
				(type default)
			)
			(layer "B.Fab")
		)
		(fp_line
			(start 0.12065 -0.305054)
			(end 0.12065 -0.2794)
			(stroke
				(width 0.1)
				(type default)
			)
			(layer "B.Fab")
		)
		(fp_line
			(start -0.120396 0.3048)
			(end -0.120396 0.2794)
			(stroke
				(width 0.1)
				(type default)
			)
			(layer "B.Fab")
		)
		(fp_line
			(start -0.120396 0.2794)
			(end 0.12065 0.2794)
			(stroke
				(width 0.1)
				(type default)
			)
			(layer "B.Fab")
		)
		(fp_line
			(start -0.12065 -0.2794)
			(end -0.12065 -0.3048)
			(stroke
				(width 0.1)
				(type default)
			)
			(layer "B.Fab")
		)
		(fp_line
			(start -0.12065 -0.3048)
			(end -0.67945 -0.3048)
			(stroke
				(width 0.1)
				(type default)
			)
			(layer "B.Fab")
		)
		(fp_line
			(start -0.67945 0.3048)
			(end -0.120396 0.3048)
			(stroke
				(width 0.1)
				(type default)
			)
			(layer "B.Fab")
		)
		(fp_line
			(start -0.67945 -0.3048)
			(end -0.67945 0.3048)
			(stroke
				(width 0.1)
				(type default)
			)
			(layer "B.Fab")
		)
		(pad "1" smd circle
			(at 0.40005 0)
			(size 0 0)
			(layers "B.Cu" "B.Mask" "B.Paste")
			(net "PVDDCR_CPU1_P1")
		)
		(pad "2" smd circle
			(at -0.40005 0)
			(size 0 0)
			(layers "B.Cu" "B.Mask" "B.Paste")
			(net "GND")
		)
	)
	(footprint ""
		(layer "B.Cu")
		(at 125.389386 -257.930396)
		(property "Reference" "C2469"
			(at 0 0 0)
			(layer "B.SilkS")
			(hide yes)
			(effects
				(font
					(size 1.27 1.27)
				)
				(justify mirror)
			)
		)
		(property "Value" ""
			(at 0 0 0)
			(layer "B.Fab")
			(effects
				(font
					(size 1.27 1.27)
				)
				(justify mirror)
			)
		)
		(duplicate_pad_numbers_are_jumpers no)
		(fp_line
			(start -0.7874 -0.4064)
			(end -0.7874 0.4064)
			(stroke
				(width 0.1524)
				(type default)
			)
			(layer "B.SilkS")
		)
		(fp_line
			(start -0.7874 0.4064)
			(end 0.7874 0.4064)
			(stroke
				(width 0.1524)
				(type default)
			)
			(layer "B.SilkS")
		)
		(fp_line
			(start 0.7874 -0.4064)
			(end -0.7874 -0.4064)
			(stroke
				(width 0.1524)
				(type default)
			)
			(layer "B.SilkS")
		)
		(fp_line
			(start 0.7874 0.4064)
			(end 0.7874 -0.4064)
			(stroke
				(width 0.1524)
				(type default)
			)
			(layer "B.SilkS")
		)
		(fp_line
			(start -0.67945 -0.3048)
			(end -0.67945 0.3048)
			(stroke
				(width 0.1)
				(type default)
			)
			(layer "B.Fab")
		)
		(fp_line
			(start -0.67945 0.3048)
			(end -0.120396 0.3048)
			(stroke
				(width 0.1)
				(type default)
			)
			(layer "B.Fab")
		)
		(fp_line
			(start -0.12065 -0.3048)
			(end -0.67945 -0.3048)
			(stroke
				(width 0.1)
				(type default)
			)
			(layer "B.Fab")
		)
		(fp_line
			(start -0.12065 -0.2794)
			(end -0.12065 -0.3048)
			(stroke
				(width 0.1)
				(type default)
			)
			(layer "B.Fab")
		)
		(fp_line
			(start -0.120396 0.2794)
			(end 0.12065 0.2794)
			(stroke
				(width 0.1)
				(type default)
			)
			(layer "B.Fab")
		)
		(fp_line
			(start -0.120396 0.3048)
			(end -0.120396 0.2794)
			(stroke
				(width 0.1)
				(type default)
			)
			(layer "B.Fab")
		)
		(fp_line
			(start 0.12065 -0.305054)
			(end 0.12065 -0.2794)
			(stroke
				(width 0.1)
				(type default)
			)
			(layer "B.Fab")
		)
		(fp_line
			(start 0.12065 -0.2794)
			(end -0.12065 -0.2794)
			(stroke
				(width 0.1)
				(type default)
			)
			(layer "B.Fab")
		)
		(fp_line
			(start 0.12065 0.2794)
			(end 0.12065 0.3048)
			(stroke
				(width 0.1)
				(type default)
			)
			(layer "B.Fab")
		)
		(fp_line
			(start 0.12065 0.3048)
			(end 0.67945 0.3048)
			(stroke
				(width 0.1)
				(type default)
			)
			(layer "B.Fab")
		)
		(fp_line
			(start 0.67945 -0.305054)
			(end 0.12065 -0.305054)
			(stroke
				(width 0.1)
				(type default)
			)
			(layer "B.Fab")
		)
		(fp_line
			(start 0.67945 0.3048)
			(end 0.67945 -0.305054)
			(stroke
				(width 0.1)
				(type default)
			)
			(layer "B.Fab")
		)
		(pad "1" smd circle
			(at 0.40005 0 180)
			(size 0 0)
			(layers "B.Cu" "B.Mask" "B.Paste")
			(net "PVDDCR_SOC_P1")
		)
		(pad "2" smd circle
			(at -0.40005 0 180)
			(size 0 0)
			(layers "B.Cu" "B.Mask" "B.Paste")
			(net "GND")
		)
	)
	(footprint ""
		(layer "B.Cu")
		(at 95.497904 -328.21753 -90)
		(property "Reference" "PC389"
			(at 7.567676 -3.601466 270)
			(unlocked yes)
			(layer "B.SilkS")
			(effects
				(font
					(size 0.7874 0.5842)
					(thickness 0.1524)
				)
				(justify left mirror)
			)
		)
		(property "Value" ""
			(at 0 0 90)
			(layer "B.Fab")
			(effects
				(font
					(size 1.27 1.27)
				)
				(justify mirror)
			)
		)
		(duplicate_pad_numbers_are_jumpers no)
		(fp_line
			(start -4.533392 2.249932)
			(end 4.533392 2.249932)
			(stroke
				(width 0.1524)
				(type default)
			)
			(layer "B.SilkS")
		)
		(fp_line
			(start 4.533392 2.249932)
			(end 4.533392 -2.249932)
			(stroke
				(width 0.1524)
				(type default)
			)
			(layer "B.SilkS")
		)
		(fp_line
			(start -4.533392 -2.249932)
			(end -4.533392 2.249932)
			(stroke
				(width 0.1524)
				(type default)
			)
			(layer "B.SilkS")
		)
		(fp_line
			(start 4.533392 -2.249932)
			(end -4.533392 -2.249932)
			(stroke
				(width 0.1524)
				(type default)
			)
			(layer "B.SilkS")
		)
		(fp_rect
			(start 5.39242 2.326132)
			(end 4.533392 -2.326132)
			(stroke
				(width 0)
				(type default)
			)
			(fill yes)
			(layer "B.SilkS")
		)
		(fp_line
			(start -3.750056 2.249932)
			(end 3.750056 2.249932)
			(stroke
				(width 0.1)
				(type default)
			)
			(layer "B.Fab")
		)
		(fp_line
			(start 3.750056 2.249932)
			(end 3.750056 -2.249932)
			(stroke
				(width 0.1)
				(type default)
			)
			(layer "B.Fab")
		)
		(fp_line
			(start -3.750056 -2.249932)
			(end -3.750056 2.249932)
			(stroke
				(width 0.1)
				(type default)
			)
			(layer "B.Fab")
		)
		(fp_line
			(start 3.750056 -2.249932)
			(end -3.750056 -2.249932)
			(stroke
				(width 0.1)
				(type default)
			)
			(layer "B.Fab")
		)
		(fp_text user "-"
			(at -4.603242 2.397252 270)
			(unlocked yes)
			(layer "B.SilkS")
			(effects
				(font
					(size 1.905 1.4224)
					(thickness 0.1524)
				)
				(justify left mirror)
			)
		)
		(fp_text user "+"
			(at 6.322314 0.786384 180)
			(unlocked yes)
			(layer "B.SilkS")
			(effects
				(font
					(size 1.905 1.4224)
					(thickness 0.1524)
				)
				(justify left mirror)
			)
		)
		(fp_text user "+"
			(at 6.322314 0.786384 180)
			(unlocked yes)
			(layer "B.Fab")
			(effects
				(font
					(size 1.905 1.4224)
					(thickness 0.1524)
				)
				(justify left mirror)
			)
		)
		(fp_text user "-"
			(at -4.8514 -0.14605 270)
			(unlocked yes)
			(layer "B.Fab")
			(effects
				(font
					(size 1.905 1.4224)
					(thickness 0.1524)
				)
				(justify left mirror)
			)
		)
		(pad "1" smd rect
			(at 3.199892 0 90)
			(size 2.413 2.8194)
			(layers "B.Cu" "B.Mask" "B.Paste")
			(net "PVDDCR_CPU1_P1")
		)
		(pad "2" smd rect
			(at -3.199892 0 90)
			(size 2.413 2.8194)
			(layers "B.Cu" "B.Mask" "B.Paste")
			(net "GND")
		)
	)
	(footprint ""
		(layer "B.Cu")
		(at 52.497228 -381.11303 180)
		(property "Reference" "C7021"
			(at -1.543304 -3.222752 0)
			(unlocked yes)
			(layer "B.SilkS")
			(effects
				(font
					(size 0.7874 0.5842)
					(thickness 0.1524)
				)
				(justify left mirror)
			)
		)
		(property "Value" ""
			(at 0 0 0)
			(layer "B.Fab")
			(effects
				(font
					(size 1.27 1.27)
				)
				(justify mirror)
			)
		)
		(duplicate_pad_numbers_are_jumpers no)
		(fp_line
			(start 4.84378 -2.150618)
			(end 4.842256 2.163064)
			(stroke
				(width 0.1524)
				(type default)
			)
			(layer "B.SilkS")
		)
		(fp_line
			(start 4.84378 -2.150618)
			(end 4.53898 -2.150618)
			(stroke
				(width 0.1524)
				(type default)
			)
			(layer "B.SilkS")
		)
		(fp_line
			(start 4.83108 2.150364)
			(end 4.447794 2.149348)
			(stroke
				(width 0.1524)
				(type default)
			)
			(layer "B.SilkS")
		)
		(fp_line
			(start 4.69138 -2.150618)
			(end 4.692396 2.161032)
			(stroke
				(width 0.1524)
				(type default)
			)
			(layer "B.SilkS")
		)
		(fp_line
			(start 4.53898 2.15011)
			(end 4.53898 -2.15011)
			(stroke
				(width 0.1524)
				(type default)
			)
			(layer "B.SilkS")
		)
		(fp_line
			(start 4.53898 -2.15011)
			(end -4.53898 -2.15011)
			(stroke
				(width 0.1524)
				(type default)
			)
			(layer "B.SilkS")
		)
		(fp_line
			(start 4.53898 -2.150618)
			(end 4.539742 2.152142)
			(stroke
				(width 0.1524)
				(type default)
			)
			(layer "B.SilkS")
		)
		(fp_line
			(start -4.53898 2.15011)
			(end 4.53898 2.15011)
			(stroke
				(width 0.1524)
				(type default)
			)
			(layer "B.SilkS")
		)
		(fp_line
			(start -4.53898 -2.15011)
			(end -4.53898 2.15011)
			(stroke
				(width 0.1524)
				(type default)
			)
			(layer "B.SilkS")
		)
		(fp_line
			(start 3.64998 2.15011)
			(end 3.64998 -2.15011)
			(stroke
				(width 0.1)
				(type default)
			)
			(layer "B.Fab")
		)
		(fp_line
			(start 3.64998 -2.15011)
			(end -3.64998 -2.15011)
			(stroke
				(width 0.1)
				(type default)
			)
			(layer "B.Fab")
		)
		(fp_line
			(start -3.64998 2.15011)
			(end 3.64998 2.15011)
			(stroke
				(width 0.1)
				(type default)
			)
			(layer "B.Fab")
		)
		(fp_line
			(start -3.64998 -2.15011)
			(end -3.64998 2.15011)
			(stroke
				(width 0.1)
				(type default)
			)
			(layer "B.Fab")
		)
		(fp_text user "+"
			(at 4.345432 -3.037078 180)
			(unlocked yes)
			(layer "B.SilkS")
			(effects
				(font
					(size 1.905 1.4224)
					(thickness 0.1524)
				)
				(justify left mirror)
			)
		)
		(fp_text user "-"
			(at -5.580634 -2.769108 180)
			(unlocked yes)
			(layer "B.SilkS")
			(effects
				(font
					(size 1.905 1.4224)
					(thickness 0.1524)
				)
				(justify left mirror)
			)
		)
		(fp_text user "+"
			(at 6.214872 -0.337058 180)
			(unlocked yes)
			(layer "B.Fab")
			(effects
				(font
					(size 1.905 1.4224)
					(thickness 0.1524)
				)
				(justify left mirror)
			)
		)
		(fp_text user "-"
			(at -4.313174 -0.094488 180)
			(unlocked yes)
			(layer "B.Fab")
			(effects
				(font
					(size 1.905 1.4224)
					(thickness 0.1524)
				)
				(justify left mirror)
			)
		)
		(pad "1" smd rect
			(at 3.199892 0)
			(size 2.413 2.8194)
			(layers "B.Cu" "B.Mask" "B.Paste")
			(net "P0V9_CPU1_RT0_2A")
		)
		(pad "2" smd rect
			(at -3.199892 0)
			(size 2.413 2.8194)
			(layers "B.Cu" "B.Mask" "B.Paste")
			(net "GND")
		)
	)
	(footprint ""
		(layer "B.Cu")
		(at 353.906074 -395.148562 90)
		(property "Reference" "C609"
			(at 0 0 90)
			(layer "B.SilkS")
			(hide yes)
			(effects
				(font
					(size 1.27 1.27)
				)
				(justify mirror)
			)
		)
		(property "Value" ""
			(at 0 0 90)
			(layer "B.Fab")
			(effects
				(font
					(size 1.27 1.27)
				)
				(justify mirror)
			)
		)
		(duplicate_pad_numbers_are_jumpers no)
		(fp_line
			(start 0.299974 -0.150114)
			(end -0.299974 -0.150114)
			(stroke
				(width 0.1)
				(type default)
			)
			(layer "B.Fab")
		)
		(fp_line
			(start -0.299974 -0.150114)
			(end -0.299974 0.150114)
			(stroke
				(width 0.1)
				(type default)
			)
			(layer "B.Fab")
		)
		(fp_line
			(start 0.299974 0.150114)
			(end 0.299974 -0.150114)
			(stroke
				(width 0.1)
				(type default)
			)
			(layer "B.Fab")
		)
		(fp_line
			(start -0.299974 0.150114)
			(end 0.299974 0.150114)
			(stroke
				(width 0.1)
				(type default)
			)
			(layer "B.Fab")
		)
		(pad "1" smd rect
			(at 0.2667 0 270)
			(size 0.3048 0.381)
			(layers "B.Cu" "B.Mask" "B.Paste")
			(net "P0V9_CPU0_RT1_2A")
		)
		(pad "2" smd rect
			(at -0.2667 0 270)
			(size 0.3048 0.381)
			(layers "B.Cu" "B.Mask" "B.Paste")
			(net "GND")
		)
	)
	(footprint ""
		(layer "B.Cu")
		(at 92.350082 -149.981666 180)
		(property "Reference" "PC244"
			(at 0 0 0)
			(layer "B.SilkS")
			(hide yes)
			(effects
				(font
					(size 1.27 1.27)
				)
				(justify mirror)
			)
		)
		(property "Value" ""
			(at 0 0 0)
			(layer "B.Fab")
			(effects
				(font
					(size 1.27 1.27)
				)
				(justify mirror)
			)
		)
		(duplicate_pad_numbers_are_jumpers no)
		(fp_line
			(start 0.7874 0.4064)
			(end 0.7874 -0.4064)
			(stroke
				(width 0.1524)
				(type default)
			)
			(layer "B.SilkS")
		)
		(fp_line
			(start 0.7874 -0.4064)
			(end -0.7874 -0.4064)
			(stroke
				(width 0.1524)
				(type default)
			)
			(layer "B.SilkS")
		)
		(fp_line
			(start -0.7874 0.4064)
			(end 0.7874 0.4064)
			(stroke
				(width 0.1524)
				(type default)
			)
			(layer "B.SilkS")
		)
		(fp_line
			(start -0.7874 -0.4064)
			(end -0.7874 0.4064)
			(stroke
				(width 0.1524)
				(type default)
			)
			(layer "B.SilkS")
		)
		(fp_line
			(start 0.67945 0.3048)
			(end 0.67945 -0.305054)
			(stroke
				(width 0.1)
				(type default)
			)
			(layer "B.Fab")
		)
		(fp_line
			(start 0.67945 -0.305054)
			(end 0.12065 -0.305054)
			(stroke
				(width 0.1)
				(type default)
			)
			(layer "B.Fab")
		)
		(fp_line
			(start 0.12065 0.3048)
			(end 0.67945 0.3048)
			(stroke
				(width 0.1)
				(type default)
			)
			(layer "B.Fab")
		)
		(fp_line
			(start 0.12065 0.2794)
			(end 0.12065 0.3048)
			(stroke
				(width 0.1)
				(type default)
			)
			(layer "B.Fab")
		)
		(fp_line
			(start 0.12065 -0.2794)
			(end -0.12065 -0.2794)
			(stroke
				(width 0.1)
				(type default)
			)
			(layer "B.Fab")
		)
		(fp_line
			(start 0.12065 -0.305054)
			(end 0.12065 -0.2794)
			(stroke
				(width 0.1)
				(type default)
			)
			(layer "B.Fab")
		)
		(fp_line
			(start -0.120396 0.3048)
			(end -0.120396 0.2794)
			(stroke
				(width 0.1)
				(type default)
			)
			(layer "B.Fab")
		)
		(fp_line
			(start -0.120396 0.2794)
			(end 0.12065 0.2794)
			(stroke
				(width 0.1)
				(type default)
			)
			(layer "B.Fab")
		)
		(fp_line
			(start -0.12065 -0.2794)
			(end -0.12065 -0.3048)
			(stroke
				(width 0.1)
				(type default)
			)
			(layer "B.Fab")
		)
		(fp_line
			(start -0.12065 -0.3048)
			(end -0.67945 -0.3048)
			(stroke
				(width 0.1)
				(type default)
			)
			(layer "B.Fab")
		)
		(fp_line
			(start -0.67945 0.3048)
			(end -0.120396 0.3048)
			(stroke
				(width 0.1)
				(type default)
			)
			(layer "B.Fab")
		)
		(fp_line
			(start -0.67945 -0.3048)
			(end -0.67945 0.3048)
			(stroke
				(width 0.1)
				(type default)
			)
			(layer "B.Fab")
		)
		(pad "1" smd circle
			(at 0.40005 0)
			(size 0 0)
			(layers "B.Cu" "B.Mask" "B.Paste")
			(net "VSENSE_PVDDCR_CPU0_P1_VSEN0")
		)
		(pad "2" smd circle
			(at -0.40005 0)
			(size 0 0)
			(layers "B.Cu" "B.Mask" "B.Paste")
			(net "VSENSE_VSS_SENSE_A_P1")
		)
	)
	(footprint ""
		(layer "B.Cu")
		(at 302.133 -354.711 180)
		(property "Reference" "PR41"
			(at 0 0 0)
			(layer "B.SilkS")
			(hide yes)
			(effects
				(font
					(size 1.27 1.27)
				)
				(justify mirror)
			)
		)
		(property "Value" ""
			(at 0 0 0)
			(layer "B.Fab")
			(effects
				(font
					(size 1.27 1.27)
				)
				(justify mirror)
			)
		)
		(duplicate_pad_numbers_are_jumpers no)
		(fp_line
			(start 0.7874 0.4064)
			(end 0.7874 -0.4064)
			(stroke
				(width 0.1524)
				(type default)
			)
			(layer "B.SilkS")
		)
		(fp_line
			(start 0.7874 -0.4064)
			(end -0.7874 -0.4064)
			(stroke
				(width 0.1524)
				(type default)
			)
			(layer "B.SilkS")
		)
		(fp_line
			(start -0.7874 0.4064)
			(end 0.7874 0.4064)
			(stroke
				(width 0.1524)
				(type default)
			)
			(layer "B.SilkS")
		)
		(fp_line
			(start -0.7874 -0.4064)
			(end -0.7874 0.4064)
			(stroke
				(width 0.1524)
				(type default)
			)
			(layer "B.SilkS")
		)
		(fp_line
			(start 0.67945 0.3048)
			(end 0.67945 -0.305054)
			(stroke
				(width 0.1)
				(type default)
			)
			(layer "B.Fab")
		)
		(fp_line
			(start 0.67945 -0.305054)
			(end 0.12065 -0.305054)
			(stroke
				(width 0.1)
				(type default)
			)
			(layer "B.Fab")
		)
		(fp_line
			(start 0.12065 0.3048)
			(end 0.67945 0.3048)
			(stroke
				(width 0.1)
				(type default)
			)
			(layer "B.Fab")
		)
		(fp_line
			(start 0.12065 0.2794)
			(end 0.12065 0.3048)
			(stroke
				(width 0.1)
				(type default)
			)
			(layer "B.Fab")
		)
		(fp_line
			(start 0.12065 -0.2794)
			(end -0.12065 -0.2794)
			(stroke
				(width 0.1)
				(type default)
			)
			(layer "B.Fab")
		)
		(fp_line
			(start 0.12065 -0.305054)
			(end 0.12065 -0.2794)
			(stroke
				(width 0.1)
				(type default)
			)
			(layer "B.Fab")
		)
		(fp_line
			(start -0.120396 0.3048)
			(end -0.120396 0.2794)
			(stroke
				(width 0.1)
				(type default)
			)
			(layer "B.Fab")
		)
		(fp_line
			(start -0.120396 0.2794)
			(end 0.12065 0.2794)
			(stroke
				(width 0.1)
				(type default)
			)
			(layer "B.Fab")
		)
		(fp_line
			(start -0.12065 -0.2794)
			(end -0.12065 -0.3048)
			(stroke
				(width 0.1)
				(type default)
			)
			(layer "B.Fab")
		)
		(fp_line
			(start -0.12065 -0.3048)
			(end -0.67945 -0.3048)
			(stroke
				(width 0.1)
				(type default)
			)
			(layer "B.Fab")
		)
		(fp_line
			(start -0.67945 0.3048)
			(end -0.120396 0.3048)
			(stroke
				(width 0.1)
				(type default)
			)
			(layer "B.Fab")
		)
		(fp_line
			(start -0.67945 -0.3048)
			(end -0.67945 0.3048)
			(stroke
				(width 0.1)
				(type default)
			)
			(layer "B.Fab")
		)
		(pad "1" smd circle
			(at 0.40005 0)
			(size 0 0)
			(layers "B.Cu" "B.Mask" "B.Paste")
			(net "PVDD18_S5_P0")
		)
		(pad "2" smd circle
			(at -0.40005 0)
			(size 0 0)
			(layers "B.Cu" "B.Mask" "B.Paste")
			(net "SVID_PVDDCR_CPU1_P0_SVTI")
		)
	)
	(footprint ""
		(layer "B.Cu")
		(at 109.575854 -256.012442 -90)
		(property "Reference" "C2263"
			(at 0 0 90)
			(layer "B.SilkS")
			(hide yes)
			(effects
				(font
					(size 1.27 1.27)
				)
				(justify mirror)
			)
		)
		(property "Value" ""
			(at 0 0 90)
			(layer "B.Fab")
			(effects
				(font
					(size 1.27 1.27)
				)
				(justify mirror)
			)
		)
		(duplicate_pad_numbers_are_jumpers no)
		(fp_line
			(start -0.7874 0.4064)
			(end 0.7874 0.4064)
			(stroke
				(width 0.1524)
				(type default)
			)
			(layer "B.SilkS")
		)
		(fp_line
			(start 0.7874 0.4064)
			(end 0.7874 -0.4064)
			(stroke
				(width 0.1524)
				(type default)
			)
			(layer "B.SilkS")
		)
		(fp_line
			(start -0.7874 -0.4064)
			(end -0.7874 0.4064)
			(stroke
				(width 0.1524)
				(type default)
			)
			(layer "B.SilkS")
		)
		(fp_line
			(start 0.7874 -0.4064)
			(end -0.7874 -0.4064)
			(stroke
				(width 0.1524)
				(type default)
			)
			(layer "B.SilkS")
		)
		(fp_line
			(start -0.67945 0.3048)
			(end -0.120396 0.3048)
			(stroke
				(width 0.1)
				(type default)
			)
			(layer "B.Fab")
		)
		(fp_line
			(start -0.120396 0.3048)
			(end -0.120396 0.2794)
			(stroke
				(width 0.1)
				(type default)
			)
			(layer "B.Fab")
		)
		(fp_line
			(start 0.12065 0.3048)
			(end 0.67945 0.3048)
			(stroke
				(width 0.1)
				(type default)
			)
			(layer "B.Fab")
		)
		(fp_line
			(start 0.67945 0.3048)
			(end 0.67945 -0.305054)
			(stroke
				(width 0.1)
				(type default)
			)
			(layer "B.Fab")
		)
		(fp_line
			(start -0.120396 0.2794)
			(end 0.12065 0.2794)
			(stroke
				(width 0.1)
				(type default)
			)
			(layer "B.Fab")
		)
		(fp_line
			(start 0.12065 0.2794)
			(end 0.12065 0.3048)
			(stroke
				(width 0.1)
				(type default)
			)
			(layer "B.Fab")
		)
		(fp_line
			(start -0.12065 -0.2794)
			(end -0.12065 -0.3048)
			(stroke
				(width 0.1)
				(type default)
			)
			(layer "B.Fab")
		)
		(fp_line
			(start 0.12065 -0.2794)
			(end -0.12065 -0.2794)
			(stroke
				(width 0.1)
				(type default)
			)
			(layer "B.Fab")
		)
		(fp_line
			(start -0.67945 -0.3048)
			(end -0.67945 0.3048)
			(stroke
				(width 0.1)
				(type default)
			)
			(layer "B.Fab")
		)
		(fp_line
			(start -0.12065 -0.3048)
			(end -0.67945 -0.3048)
			(stroke
				(width 0.1)
				(type default)
			)
			(layer "B.Fab")
		)
		(fp_line
			(start 0.12065 -0.305054)
			(end 0.12065 -0.2794)
			(stroke
				(width 0.1)
				(type default)
			)
			(layer "B.Fab")
		)
		(fp_line
			(start 0.67945 -0.305054)
			(end 0.12065 -0.305054)
			(stroke
				(width 0.1)
				(type default)
			)
			(layer "B.Fab")
		)
		(pad "1" smd circle
			(at 0.40005 0 90)
			(size 0 0)
			(layers "B.Cu" "B.Mask" "B.Paste")
			(net "PVDDCR_SOC_P1")
		)
		(pad "2" smd circle
			(at -0.40005 0 90)
			(size 0 0)
			(layers "B.Cu" "B.Mask" "B.Paste")
			(net "GND")
		)
	)
	(footprint ""
		(layer "B.Cu")
		(at 109.768386 -268.418564)
		(property "Reference" "C2404"
			(at 0 0 0)
			(layer "B.SilkS")
			(hide yes)
			(effects
				(font
					(size 1.27 1.27)
				)
				(justify mirror)
			)
		)
		(property "Value" ""
			(at 0 0 0)
			(layer "B.Fab")
			(effects
				(font
					(size 1.27 1.27)
				)
				(justify mirror)
			)
		)
		(duplicate_pad_numbers_are_jumpers no)
		(fp_line
			(start -0.7874 -0.4064)
			(end -0.7874 0.4064)
			(stroke
				(width 0.1524)
				(type default)
			)
			(layer "B.SilkS")
		)
		(fp_line
			(start -0.7874 0.4064)
			(end 0.7874 0.4064)
			(stroke
				(width 0.1524)
				(type default)
			)
			(layer "B.SilkS")
		)
		(fp_line
			(start 0.7874 -0.4064)
			(end -0.7874 -0.4064)
			(stroke
				(width 0.1524)
				(type default)
			)
			(layer "B.SilkS")
		)
		(fp_line
			(start 0.7874 0.4064)
			(end 0.7874 -0.4064)
			(stroke
				(width 0.1524)
				(type default)
			)
			(layer "B.SilkS")
		)
		(fp_line
			(start -0.67945 -0.3048)
			(end -0.67945 0.3048)
			(stroke
				(width 0.1)
				(type default)
			)
			(layer "B.Fab")
		)
		(fp_line
			(start -0.67945 0.3048)
			(end -0.120396 0.3048)
			(stroke
				(width 0.1)
				(type default)
			)
			(layer "B.Fab")
		)
		(fp_line
			(start -0.12065 -0.3048)
			(end -0.67945 -0.3048)
			(stroke
				(width 0.1)
				(type default)
			)
			(layer "B.Fab")
		)
		(fp_line
			(start -0.12065 -0.2794)
			(end -0.12065 -0.3048)
			(stroke
				(width 0.1)
				(type default)
			)
			(layer "B.Fab")
		)
		(fp_line
			(start -0.120396 0.2794)
			(end 0.12065 0.2794)
			(stroke
				(width 0.1)
				(type default)
			)
			(layer "B.Fab")
		)
		(fp_line
			(start -0.120396 0.3048)
			(end -0.120396 0.2794)
			(stroke
				(width 0.1)
				(type default)
			)
			(layer "B.Fab")
		)
		(fp_line
			(start 0.12065 -0.305054)
			(end 0.12065 -0.2794)
			(stroke
				(width 0.1)
				(type default)
			)
			(layer "B.Fab")
		)
		(fp_line
			(start 0.12065 -0.2794)
			(end -0.12065 -0.2794)
			(stroke
				(width 0.1)
				(type default)
			)
			(layer "B.Fab")
		)
		(fp_line
			(start 0.12065 0.2794)
			(end 0.12065 0.3048)
			(stroke
				(width 0.1)
				(type default)
			)
			(layer "B.Fab")
		)
		(fp_line
			(start 0.12065 0.3048)
			(end 0.67945 0.3048)
			(stroke
				(width 0.1)
				(type default)
			)
			(layer "B.Fab")
		)
		(fp_line
			(start 0.67945 -0.305054)
			(end 0.12065 -0.305054)
			(stroke
				(width 0.1)
				(type default)
			)
			(layer "B.Fab")
		)
		(fp_line
			(start 0.67945 0.3048)
			(end 0.67945 -0.305054)
			(stroke
				(width 0.1)
				(type default)
			)
			(layer "B.Fab")
		)
		(pad "1" smd circle
			(at 0.40005 0 180)
			(size 0 0)
			(layers "B.Cu" "B.Mask" "B.Paste")
			(net "PVDDCR_CPU1_P1")
		)
		(pad "2" smd circle
			(at -0.40005 0 180)
			(size 0 0)
			(layers "B.Cu" "B.Mask" "B.Paste")
			(net "GND")
		)
	)
	(footprint ""
		(layer "B.Cu")
		(at 166.327582 -413.847788 90)
		(property "Reference" "Q128"
			(at -1.578102 2.42443 270)
			(unlocked yes)
			(layer "B.SilkS")
			(effects
				(font
					(size 0.7874 0.5842)
					(thickness 0.1524)
				)
				(justify left mirror)
			)
		)
		(property "Value" ""
			(at 0 0 90)
			(layer "B.Fab")
			(effects
				(font
					(size 1.27 1.27)
				)
				(justify mirror)
			)
		)
		(duplicate_pad_numbers_are_jumpers no)
		(fp_line
			(start 1.332738 -1.100074)
			(end 0.4826 -1.100074)
			(stroke
				(width 0.1524)
				(type default)
			)
			(layer "B.SilkS")
		)
		(fp_line
			(start 0.4826 -1.100074)
			(end 0 -0.541274)
			(stroke
				(width 0.1524)
				(type default)
			)
			(layer "B.SilkS")
		)
		(fp_line
			(start -0.4826 -1.100074)
			(end -1.332738 -1.100074)
			(stroke
				(width 0.1524)
				(type default)
			)
			(layer "B.SilkS")
		)
		(fp_line
			(start -1.332738 -1.100074)
			(end -1.332738 1.100074)
			(stroke
				(width 0.1524)
				(type default)
			)
			(layer "B.SilkS")
		)
		(fp_line
			(start 0 -0.541274)
			(end -0.4826 -1.100074)
			(stroke
				(width 0.1524)
				(type default)
			)
			(layer "B.SilkS")
		)
		(fp_line
			(start 1.332738 1.100074)
			(end 1.332738 -1.100074)
			(stroke
				(width 0.1524)
				(type default)
			)
			(layer "B.SilkS")
		)
		(fp_line
			(start -1.332738 1.100074)
			(end 1.332738 1.100074)
			(stroke
				(width 0.1524)
				(type default)
			)
			(layer "B.SilkS")
		)
		(fp_poly
			(pts
				(xy 1.463802 -1.014476) (xy 2.165604 -0.663448) (xy 2.165604 -1.365504)
			)
			(stroke
				(width 0)
				(type default)
			)
			(fill yes)
			(layer "B.SilkS")
		)
		(fp_line
			(start 0.674878 -1.100074)
			(end -0.674878 -1.100074)
			(stroke
				(width 0.1)
				(type default)
			)
			(layer "B.Fab")
		)
		(fp_line
			(start -0.674878 -1.100074)
			(end -0.674878 1.100074)
			(stroke
				(width 0.1)
				(type default)
			)
			(layer "B.Fab")
		)
		(fp_line
			(start 0.674878 1.100074)
			(end 0.674878 -1.100074)
			(stroke
				(width 0.1)
				(type default)
			)
			(layer "B.Fab")
		)
		(fp_line
			(start -0.674878 1.100074)
			(end 0.674878 1.100074)
			(stroke
				(width 0.1)
				(type default)
			)
			(layer "B.Fab")
		)
		(fp_poly
			(pts
				(xy 2.2352 -0.298958) (xy 2.2352 -1.001014) (xy 1.533144 -0.649986)
			)
			(stroke
				(width 0)
				(type default)
			)
			(fill yes)
			(layer "B.Fab")
		)
		(pad "1" smd rect
			(at 0.94996 -0.649986 180)
			(size 0.4318 0.508)
			(layers "B.Cu" "B.Mask" "B.Paste")
			(net "GND")
		)
		(pad "2" smd rect
			(at 0.94996 0 180)
			(size 0.4318 0.508)
			(layers "B.Cu" "B.Mask" "B.Paste")
			(net "GPU_3V3IO_RSVD0_FFU")
		)
		(pad "3" smd rect
			(at 0.94996 0.649986 180)
			(size 0.4318 0.508)
			(layers "B.Cu" "B.Mask" "B.Paste")
			(net "GPU_3V3IO_RSVD0_FFU_ISO")
		)
		(pad "4" smd rect
			(at -0.94996 0.649986 180)
			(size 0.4318 0.508)
			(layers "B.Cu" "B.Mask" "B.Paste")
			(net "GND")
		)
		(pad "5" smd rect
			(at -0.94996 0 180)
			(size 0.4318 0.508)
			(layers "B.Cu" "B.Mask" "B.Paste")
			(net "GPU_3V3IO_RSVD0_FFU_N")
		)
		(pad "6" smd rect
			(at -0.94996 -0.649986 180)
			(size 0.4318 0.508)
			(layers "B.Cu" "B.Mask" "B.Paste")
			(net "GPU_3V3IO_RSVD0_FFU_N")
		)
	)
	(footprint ""
		(layer "B.Cu")
		(at 125.262386 -266.005564)
		(property "Reference" "C2126"
			(at 0 0 0)
			(layer "B.SilkS")
			(hide yes)
			(effects
				(font
					(size 1.27 1.27)
				)
				(justify mirror)
			)
		)
		(property "Value" ""
			(at 0 0 0)
			(layer "B.Fab")
			(effects
				(font
					(size 1.27 1.27)
				)
				(justify mirror)
			)
		)
		(duplicate_pad_numbers_are_jumpers no)
		(fp_line
			(start -0.7874 -0.4064)
			(end -0.7874 0.4064)
			(stroke
				(width 0.1524)
				(type default)
			)
			(layer "B.SilkS")
		)
		(fp_line
			(start -0.7874 0.4064)
			(end 0.7874 0.4064)
			(stroke
				(width 0.1524)
				(type default)
			)
			(layer "B.SilkS")
		)
		(fp_line
			(start 0.7874 -0.4064)
			(end -0.7874 -0.4064)
			(stroke
				(width 0.1524)
				(type default)
			)
			(layer "B.SilkS")
		)
		(fp_line
			(start 0.7874 0.4064)
			(end 0.7874 -0.4064)
			(stroke
				(width 0.1524)
				(type default)
			)
			(layer "B.SilkS")
		)
		(fp_line
			(start -0.67945 -0.3048)
			(end -0.67945 0.3048)
			(stroke
				(width 0.1)
				(type default)
			)
			(layer "B.Fab")
		)
		(fp_line
			(start -0.67945 0.3048)
			(end -0.120396 0.3048)
			(stroke
				(width 0.1)
				(type default)
			)
			(layer "B.Fab")
		)
		(fp_line
			(start -0.12065 -0.3048)
			(end -0.67945 -0.3048)
			(stroke
				(width 0.1)
				(type default)
			)
			(layer "B.Fab")
		)
		(fp_line
			(start -0.12065 -0.2794)
			(end -0.12065 -0.3048)
			(stroke
				(width 0.1)
				(type default)
			)
			(layer "B.Fab")
		)
		(fp_line
			(start -0.120396 0.2794)
			(end 0.12065 0.2794)
			(stroke
				(width 0.1)
				(type default)
			)
			(layer "B.Fab")
		)
		(fp_line
			(start -0.120396 0.3048)
			(end -0.120396 0.2794)
			(stroke
				(width 0.1)
				(type default)
			)
			(layer "B.Fab")
		)
		(fp_line
			(start 0.12065 -0.305054)
			(end 0.12065 -0.2794)
			(stroke
				(width 0.1)
				(type default)
			)
			(layer "B.Fab")
		)
		(fp_line
			(start 0.12065 -0.2794)
			(end -0.12065 -0.2794)
			(stroke
				(width 0.1)
				(type default)
			)
			(layer "B.Fab")
		)
		(fp_line
			(start 0.12065 0.2794)
			(end 0.12065 0.3048)
			(stroke
				(width 0.1)
				(type default)
			)
			(layer "B.Fab")
		)
		(fp_line
			(start 0.12065 0.3048)
			(end 0.67945 0.3048)
			(stroke
				(width 0.1)
				(type default)
			)
			(layer "B.Fab")
		)
		(fp_line
			(start 0.67945 -0.305054)
			(end 0.12065 -0.305054)
			(stroke
				(width 0.1)
				(type default)
			)
			(layer "B.Fab")
		)
		(fp_line
			(start 0.67945 0.3048)
			(end 0.67945 -0.305054)
			(stroke
				(width 0.1)
				(type default)
			)
			(layer "B.Fab")
		)
		(pad "1" smd circle
			(at 0.40005 0 180)
			(size 0 0)
			(layers "B.Cu" "B.Mask" "B.Paste")
			(net "PVDD11_S3_P1")
		)
		(pad "2" smd circle
			(at -0.40005 0 180)
			(size 0 0)
			(layers "B.Cu" "B.Mask" "B.Paste")
			(net "GND")
		)
	)
	(footprint ""
		(layer "B.Cu")
		(at 369.646454 -252.54331)
		(property "Reference" "C2134"
			(at 0 0 0)
			(layer "B.SilkS")
			(hide yes)
			(effects
				(font
					(size 1.27 1.27)
				)
				(justify mirror)
			)
		)
		(property "Value" ""
			(at 0 0 0)
			(layer "B.Fab")
			(effects
				(font
					(size 1.27 1.27)
				)
				(justify mirror)
			)
		)
		(duplicate_pad_numbers_are_jumpers no)
		(fp_line
			(start -0.7874 -0.4064)
			(end -0.7874 0.4064)
			(stroke
				(width 0.1524)
				(type default)
			)
			(layer "B.SilkS")
		)
		(fp_line
			(start -0.7874 0.4064)
			(end 0.7874 0.4064)
			(stroke
				(width 0.1524)
				(type default)
			)
			(layer "B.SilkS")
		)
		(fp_line
			(start 0.7874 -0.4064)
			(end -0.7874 -0.4064)
			(stroke
				(width 0.1524)
				(type default)
			)
			(layer "B.SilkS")
		)
		(fp_line
			(start 0.7874 0.4064)
			(end 0.7874 -0.4064)
			(stroke
				(width 0.1524)
				(type default)
			)
			(layer "B.SilkS")
		)
		(fp_line
			(start -0.67945 -0.3048)
			(end -0.67945 0.3048)
			(stroke
				(width 0.1)
				(type default)
			)
			(layer "B.Fab")
		)
		(fp_line
			(start -0.67945 0.3048)
			(end -0.120396 0.3048)
			(stroke
				(width 0.1)
				(type default)
			)
			(layer "B.Fab")
		)
		(fp_line
			(start -0.12065 -0.3048)
			(end -0.67945 -0.3048)
			(stroke
				(width 0.1)
				(type default)
			)
			(layer "B.Fab")
		)
		(fp_line
			(start -0.12065 -0.2794)
			(end -0.12065 -0.3048)
			(stroke
				(width 0.1)
				(type default)
			)
			(layer "B.Fab")
		)
		(fp_line
			(start -0.120396 0.2794)
			(end 0.12065 0.2794)
			(stroke
				(width 0.1)
				(type default)
			)
			(layer "B.Fab")
		)
		(fp_line
			(start -0.120396 0.3048)
			(end -0.120396 0.2794)
			(stroke
				(width 0.1)
				(type default)
			)
			(layer "B.Fab")
		)
		(fp_line
			(start 0.12065 -0.305054)
			(end 0.12065 -0.2794)
			(stroke
				(width 0.1)
				(type default)
			)
			(layer "B.Fab")
		)
		(fp_line
			(start 0.12065 -0.2794)
			(end -0.12065 -0.2794)
			(stroke
				(width 0.1)
				(type default)
			)
			(layer "B.Fab")
		)
		(fp_line
			(start 0.12065 0.2794)
			(end 0.12065 0.3048)
			(stroke
				(width 0.1)
				(type default)
			)
			(layer "B.Fab")
		)
		(fp_line
			(start 0.12065 0.3048)
			(end 0.67945 0.3048)
			(stroke
				(width 0.1)
				(type default)
			)
			(layer "B.Fab")
		)
		(fp_line
			(start 0.67945 -0.305054)
			(end 0.12065 -0.305054)
			(stroke
				(width 0.1)
				(type default)
			)
			(layer "B.Fab")
		)
		(fp_line
			(start 0.67945 0.3048)
			(end 0.67945 -0.305054)
			(stroke
				(width 0.1)
				(type default)
			)
			(layer "B.Fab")
		)
		(pad "1" smd circle
			(at 0.40005 0 180)
			(size 0 0)
			(layers "B.Cu" "B.Mask" "B.Paste")
			(net "PVDDCR_SOC_P0")
		)
		(pad "2" smd circle
			(at -0.40005 0 180)
			(size 0 0)
			(layers "B.Cu" "B.Mask" "B.Paste")
			(net "GND")
		)
	)
	(footprint ""
		(layer "B.Cu")
		(at 311.427876 -76.489814 -90)
		(property "Reference" "R3047"
			(at 0 0 90)
			(layer "B.SilkS")
			(hide yes)
			(effects
				(font
					(size 1.27 1.27)
				)
				(justify mirror)
			)
		)
		(property "Value" ""
			(at 0 0 90)
			(layer "B.Fab")
			(effects
				(font
					(size 1.27 1.27)
				)
				(justify mirror)
			)
		)
		(duplicate_pad_numbers_are_jumpers no)
		(fp_line
			(start -0.7874 0.4064)
			(end 0.7874 0.4064)
			(stroke
				(width 0.1524)
				(type default)
			)
			(layer "B.SilkS")
		)
		(fp_line
			(start 0.7874 0.4064)
			(end 0.7874 -0.4064)
			(stroke
				(width 0.1524)
				(type default)
			)
			(layer "B.SilkS")
		)
		(fp_line
			(start -0.7874 -0.4064)
			(end -0.7874 0.4064)
			(stroke
				(width 0.1524)
				(type default)
			)
			(layer "B.SilkS")
		)
		(fp_line
			(start 0.7874 -0.4064)
			(end -0.7874 -0.4064)
			(stroke
				(width 0.1524)
				(type default)
			)
			(layer "B.SilkS")
		)
		(fp_line
			(start -0.67945 0.3048)
			(end -0.120396 0.3048)
			(stroke
				(width 0.1)
				(type default)
			)
			(layer "B.Fab")
		)
		(fp_line
			(start -0.120396 0.3048)
			(end -0.120396 0.2794)
			(stroke
				(width 0.1)
				(type default)
			)
			(layer "B.Fab")
		)
		(fp_line
			(start 0.12065 0.3048)
			(end 0.67945 0.3048)
			(stroke
				(width 0.1)
				(type default)
			)
			(layer "B.Fab")
		)
		(fp_line
			(start 0.67945 0.3048)
			(end 0.67945 -0.305054)
			(stroke
				(width 0.1)
				(type default)
			)
			(layer "B.Fab")
		)
		(fp_line
			(start -0.120396 0.2794)
			(end 0.12065 0.2794)
			(stroke
				(width 0.1)
				(type default)
			)
			(layer "B.Fab")
		)
		(fp_line
			(start 0.12065 0.2794)
			(end 0.12065 0.3048)
			(stroke
				(width 0.1)
				(type default)
			)
			(layer "B.Fab")
		)
		(fp_line
			(start -0.12065 -0.2794)
			(end -0.12065 -0.3048)
			(stroke
				(width 0.1)
				(type default)
			)
			(layer "B.Fab")
		)
		(fp_line
			(start 0.12065 -0.2794)
			(end -0.12065 -0.2794)
			(stroke
				(width 0.1)
				(type default)
			)
			(layer "B.Fab")
		)
		(fp_line
			(start -0.67945 -0.3048)
			(end -0.67945 0.3048)
			(stroke
				(width 0.1)
				(type default)
			)
			(layer "B.Fab")
		)
		(fp_line
			(start -0.12065 -0.3048)
			(end -0.67945 -0.3048)
			(stroke
				(width 0.1)
				(type default)
			)
			(layer "B.Fab")
		)
		(fp_line
			(start 0.12065 -0.305054)
			(end 0.12065 -0.2794)
			(stroke
				(width 0.1)
				(type default)
			)
			(layer "B.Fab")
		)
		(fp_line
			(start 0.67945 -0.305054)
			(end 0.12065 -0.305054)
			(stroke
				(width 0.1)
				(type default)
			)
			(layer "B.Fab")
		)
		(pad "1" smd circle
			(at 0.40005 0 90)
			(size 0 0)
			(layers "B.Cu" "B.Mask" "B.Paste")
			(net "MB0_P12V_STBY_PWRGD")
		)
		(pad "2" smd circle
			(at -0.40005 0 90)
			(size 0 0)
			(layers "B.Cu" "B.Mask" "B.Paste")
			(net "PWRGD_PS_PWROK_PLD")
		)
	)
	(footprint ""
		(layer "B.Cu")
		(at 193.205608 -126.833376 -90)
		(property "Reference" "R395"
			(at 0 0 90)
			(layer "B.SilkS")
			(hide yes)
			(effects
				(font
					(size 1.27 1.27)
				)
				(justify mirror)
			)
		)
		(property "Value" ""
			(at 0 0 90)
			(layer "B.Fab")
			(effects
				(font
					(size 1.27 1.27)
				)
				(justify mirror)
			)
		)
		(duplicate_pad_numbers_are_jumpers no)
		(fp_line
			(start -0.7874 0.4064)
			(end 0.7874 0.4064)
			(stroke
				(width 0.1524)
				(type default)
			)
			(layer "B.SilkS")
		)
		(fp_line
			(start 0.7874 0.4064)
			(end 0.7874 -0.4064)
			(stroke
				(width 0.1524)
				(type default)
			)
			(layer "B.SilkS")
		)
		(fp_line
			(start -0.7874 -0.4064)
			(end -0.7874 0.4064)
			(stroke
				(width 0.1524)
				(type default)
			)
			(layer "B.SilkS")
		)
		(fp_line
			(start 0.7874 -0.4064)
			(end -0.7874 -0.4064)
			(stroke
				(width 0.1524)
				(type default)
			)
			(layer "B.SilkS")
		)
		(fp_line
			(start -0.67945 0.3048)
			(end -0.120396 0.3048)
			(stroke
				(width 0.1)
				(type default)
			)
			(layer "B.Fab")
		)
		(fp_line
			(start -0.120396 0.3048)
			(end -0.120396 0.2794)
			(stroke
				(width 0.1)
				(type default)
			)
			(layer "B.Fab")
		)
		(fp_line
			(start 0.12065 0.3048)
			(end 0.67945 0.3048)
			(stroke
				(width 0.1)
				(type default)
			)
			(layer "B.Fab")
		)
		(fp_line
			(start 0.67945 0.3048)
			(end 0.67945 -0.305054)
			(stroke
				(width 0.1)
				(type default)
			)
			(layer "B.Fab")
		)
		(fp_line
			(start -0.120396 0.2794)
			(end 0.12065 0.2794)
			(stroke
				(width 0.1)
				(type default)
			)
			(layer "B.Fab")
		)
		(fp_line
			(start 0.12065 0.2794)
			(end 0.12065 0.3048)
			(stroke
				(width 0.1)
				(type default)
			)
			(layer "B.Fab")
		)
		(fp_line
			(start -0.12065 -0.2794)
			(end -0.12065 -0.3048)
			(stroke
				(width 0.1)
				(type default)
			)
			(layer "B.Fab")
		)
		(fp_line
			(start 0.12065 -0.2794)
			(end -0.12065 -0.2794)
			(stroke
				(width 0.1)
				(type default)
			)
			(layer "B.Fab")
		)
		(fp_line
			(start -0.67945 -0.3048)
			(end -0.67945 0.3048)
			(stroke
				(width 0.1)
				(type default)
			)
			(layer "B.Fab")
		)
		(fp_line
			(start -0.12065 -0.3048)
			(end -0.67945 -0.3048)
			(stroke
				(width 0.1)
				(type default)
			)
			(layer "B.Fab")
		)
		(fp_line
			(start 0.12065 -0.305054)
			(end 0.12065 -0.2794)
			(stroke
				(width 0.1)
				(type default)
			)
			(layer "B.Fab")
		)
		(fp_line
			(start 0.67945 -0.305054)
			(end 0.12065 -0.305054)
			(stroke
				(width 0.1)
				(type default)
			)
			(layer "B.Fab")
		)
		(pad "1" smd circle
			(at 0.40005 0 90)
			(size 0 0)
			(layers "B.Cu" "B.Mask" "B.Paste")
			(net "FM_SPD_CPU0_SWITCH_CTRL_R_N")
		)
		(pad "2" smd circle
			(at -0.40005 0 90)
			(size 0 0)
			(layers "B.Cu" "B.Mask" "B.Paste")
			(net "FM_SPD_CPU0_SWITCH_CTRL_N")
		)
	)
	(footprint ""
		(layer "B.Cu")
		(at 195.359782 -194.885564 180)
		(property "Reference" "R777"
			(at 0 0 0)
			(layer "B.SilkS")
			(hide yes)
			(effects
				(font
					(size 1.27 1.27)
				)
				(justify mirror)
			)
		)
		(property "Value" ""
			(at 0 0 0)
			(layer "B.Fab")
			(effects
				(font
					(size 1.27 1.27)
				)
				(justify mirror)
			)
		)
		(duplicate_pad_numbers_are_jumpers no)
		(fp_line
			(start 0.7874 0.4064)
			(end 0.7874 -0.4064)
			(stroke
				(width 0.1524)
				(type default)
			)
			(layer "B.SilkS")
		)
		(fp_line
			(start 0.7874 -0.4064)
			(end -0.7874 -0.4064)
			(stroke
				(width 0.1524)
				(type default)
			)
			(layer "B.SilkS")
		)
		(fp_line
			(start -0.7874 0.4064)
			(end 0.7874 0.4064)
			(stroke
				(width 0.1524)
				(type default)
			)
			(layer "B.SilkS")
		)
		(fp_line
			(start -0.7874 -0.4064)
			(end -0.7874 0.4064)
			(stroke
				(width 0.1524)
				(type default)
			)
			(layer "B.SilkS")
		)
		(fp_line
			(start 0.67945 0.3048)
			(end 0.67945 -0.305054)
			(stroke
				(width 0.1)
				(type default)
			)
			(layer "B.Fab")
		)
		(fp_line
			(start 0.67945 -0.305054)
			(end 0.12065 -0.305054)
			(stroke
				(width 0.1)
				(type default)
			)
			(layer "B.Fab")
		)
		(fp_line
			(start 0.12065 0.3048)
			(end 0.67945 0.3048)
			(stroke
				(width 0.1)
				(type default)
			)
			(layer "B.Fab")
		)
		(fp_line
			(start 0.12065 0.2794)
			(end 0.12065 0.3048)
			(stroke
				(width 0.1)
				(type default)
			)
			(layer "B.Fab")
		)
		(fp_line
			(start 0.12065 -0.2794)
			(end -0.12065 -0.2794)
			(stroke
				(width 0.1)
				(type default)
			)
			(layer "B.Fab")
		)
		(fp_line
			(start 0.12065 -0.305054)
			(end 0.12065 -0.2794)
			(stroke
				(width 0.1)
				(type default)
			)
			(layer "B.Fab")
		)
		(fp_line
			(start -0.120396 0.3048)
			(end -0.120396 0.2794)
			(stroke
				(width 0.1)
				(type default)
			)
			(layer "B.Fab")
		)
		(fp_line
			(start -0.120396 0.2794)
			(end 0.12065 0.2794)
			(stroke
				(width 0.1)
				(type default)
			)
			(layer "B.Fab")
		)
		(fp_line
			(start -0.12065 -0.2794)
			(end -0.12065 -0.3048)
			(stroke
				(width 0.1)
				(type default)
			)
			(layer "B.Fab")
		)
		(fp_line
			(start -0.12065 -0.3048)
			(end -0.67945 -0.3048)
			(stroke
				(width 0.1)
				(type default)
			)
			(layer "B.Fab")
		)
		(fp_line
			(start -0.67945 0.3048)
			(end -0.120396 0.3048)
			(stroke
				(width 0.1)
				(type default)
			)
			(layer "B.Fab")
		)
		(fp_line
			(start -0.67945 -0.3048)
			(end -0.67945 0.3048)
			(stroke
				(width 0.1)
				(type default)
			)
			(layer "B.Fab")
		)
		(pad "1" smd circle
			(at 0.40005 0)
			(size 0 0)
			(layers "B.Cu" "B.Mask" "B.Paste")
			(net "PD_CHK_CPU1_DIMM_SAA")
		)
		(pad "2" smd circle
			(at -0.40005 0)
			(size 0 0)
			(layers "B.Cu" "B.Mask" "B.Paste")
			(net "GND")
		)
	)
	(footprint ""
		(layer "B.Cu")
		(at 359.721404 -254.44831 180)
		(property "Reference" "C2140"
			(at 0 0 0)
			(layer "B.SilkS")
			(hide yes)
			(effects
				(font
					(size 1.27 1.27)
				)
				(justify mirror)
			)
		)
		(property "Value" ""
			(at 0 0 0)
			(layer "B.Fab")
			(effects
				(font
					(size 1.27 1.27)
				)
				(justify mirror)
			)
		)
		(duplicate_pad_numbers_are_jumpers no)
		(fp_line
			(start 0.7874 0.4064)
			(end 0.7874 -0.4064)
			(stroke
				(width 0.1524)
				(type default)
			)
			(layer "B.SilkS")
		)
		(fp_line
			(start 0.7874 -0.4064)
			(end -0.7874 -0.4064)
			(stroke
				(width 0.1524)
				(type default)
			)
			(layer "B.SilkS")
		)
		(fp_line
			(start -0.7874 0.4064)
			(end 0.7874 0.4064)
			(stroke
				(width 0.1524)
				(type default)
			)
			(layer "B.SilkS")
		)
		(fp_line
			(start -0.7874 -0.4064)
			(end -0.7874 0.4064)
			(stroke
				(width 0.1524)
				(type default)
			)
			(layer "B.SilkS")
		)
		(fp_line
			(start 0.67945 0.3048)
			(end 0.67945 -0.305054)
			(stroke
				(width 0.1)
				(type default)
			)
			(layer "B.Fab")
		)
		(fp_line
			(start 0.67945 -0.305054)
			(end 0.12065 -0.305054)
			(stroke
				(width 0.1)
				(type default)
			)
			(layer "B.Fab")
		)
		(fp_line
			(start 0.12065 0.3048)
			(end 0.67945 0.3048)
			(stroke
				(width 0.1)
				(type default)
			)
			(layer "B.Fab")
		)
		(fp_line
			(start 0.12065 0.2794)
			(end 0.12065 0.3048)
			(stroke
				(width 0.1)
				(type default)
			)
			(layer "B.Fab")
		)
		(fp_line
			(start 0.12065 -0.2794)
			(end -0.12065 -0.2794)
			(stroke
				(width 0.1)
				(type default)
			)
			(layer "B.Fab")
		)
		(fp_line
			(start 0.12065 -0.305054)
			(end 0.12065 -0.2794)
			(stroke
				(width 0.1)
				(type default)
			)
			(layer "B.Fab")
		)
		(fp_line
			(start -0.120396 0.3048)
			(end -0.120396 0.2794)
			(stroke
				(width 0.1)
				(type default)
			)
			(layer "B.Fab")
		)
		(fp_line
			(start -0.120396 0.2794)
			(end 0.12065 0.2794)
			(stroke
				(width 0.1)
				(type default)
			)
			(layer "B.Fab")
		)
		(fp_line
			(start -0.12065 -0.2794)
			(end -0.12065 -0.3048)
			(stroke
				(width 0.1)
				(type default)
			)
			(layer "B.Fab")
		)
		(fp_line
			(start -0.12065 -0.3048)
			(end -0.67945 -0.3048)
			(stroke
				(width 0.1)
				(type default)
			)
			(layer "B.Fab")
		)
		(fp_line
			(start -0.67945 0.3048)
			(end -0.120396 0.3048)
			(stroke
				(width 0.1)
				(type default)
			)
			(layer "B.Fab")
		)
		(fp_line
			(start -0.67945 -0.3048)
			(end -0.67945 0.3048)
			(stroke
				(width 0.1)
				(type default)
			)
			(layer "B.Fab")
		)
		(pad "1" smd circle
			(at 0.40005 0)
			(size 0 0)
			(layers "B.Cu" "B.Mask" "B.Paste")
			(net "PVDDCR_SOC_P0")
		)
		(pad "2" smd circle
			(at -0.40005 0)
			(size 0 0)
			(layers "B.Cu" "B.Mask" "B.Paste")
			(net "GND")
		)
	)
	(footprint ""
		(layer "B.Cu")
		(at 217.17 -330.708 180)
		(property "Reference" "R6772"
			(at 0 0 0)
			(layer "B.SilkS")
			(hide yes)
			(effects
				(font
					(size 1.27 1.27)
				)
				(justify mirror)
			)
		)
		(property "Value" ""
			(at 0 0 0)
			(layer "B.Fab")
			(effects
				(font
					(size 1.27 1.27)
				)
				(justify mirror)
			)
		)
		(duplicate_pad_numbers_are_jumpers no)
		(fp_line
			(start 0.32512 0.175006)
			(end 0.32512 -0.175006)
			(stroke
				(width 0.1)
				(type default)
			)
			(layer "B.Fab")
		)
		(fp_line
			(start 0.32512 -0.175006)
			(end -0.32512 -0.175006)
			(stroke
				(width 0.1)
				(type default)
			)
			(layer "B.Fab")
		)
		(fp_line
			(start -0.32512 0.175006)
			(end 0.32512 0.175006)
			(stroke
				(width 0.1)
				(type default)
			)
			(layer "B.Fab")
		)
		(fp_line
			(start -0.32512 -0.175006)
			(end -0.32512 0.175006)
			(stroke
				(width 0.1)
				(type default)
			)
			(layer "B.Fab")
		)
		(pad "1" smd rect
			(at 0.2667 0)
			(size 0.3048 0.381)
			(layers "B.Cu" "B.Mask" "B.Paste")
			(net "P1V8_AUX")
		)
		(pad "2" smd rect
			(at -0.2667 0 180)
			(size 0.3048 0.381)
			(layers "B.Cu" "B.Mask" "B.Paste")
			(net "RT_SMB_MUX_ADDR0")
		)
	)
	(footprint ""
		(layer "B.Cu")
		(at 346.518992 -259.729986 180)
		(property "Reference" "C2655"
			(at 0 0 0)
			(layer "B.SilkS")
			(hide yes)
			(effects
				(font
					(size 1.27 1.27)
				)
				(justify mirror)
			)
		)
		(property "Value" ""
			(at 0 0 0)
			(layer "B.Fab")
			(effects
				(font
					(size 1.27 1.27)
				)
				(justify mirror)
			)
		)
		(duplicate_pad_numbers_are_jumpers no)
		(fp_line
			(start 0.7874 0.4064)
			(end 0.7874 -0.4064)
			(stroke
				(width 0.1524)
				(type default)
			)
			(layer "B.SilkS")
		)
		(fp_line
			(start 0.7874 -0.4064)
			(end -0.7874 -0.4064)
			(stroke
				(width 0.1524)
				(type default)
			)
			(layer "B.SilkS")
		)
		(fp_line
			(start -0.7874 0.4064)
			(end 0.7874 0.4064)
			(stroke
				(width 0.1524)
				(type default)
			)
			(layer "B.SilkS")
		)
		(fp_line
			(start -0.7874 -0.4064)
			(end -0.7874 0.4064)
			(stroke
				(width 0.1524)
				(type default)
			)
			(layer "B.SilkS")
		)
		(fp_line
			(start 0.67945 0.3048)
			(end 0.67945 -0.305054)
			(stroke
				(width 0.1)
				(type default)
			)
			(layer "B.Fab")
		)
		(fp_line
			(start 0.67945 -0.305054)
			(end 0.12065 -0.305054)
			(stroke
				(width 0.1)
				(type default)
			)
			(layer "B.Fab")
		)
		(fp_line
			(start 0.12065 0.3048)
			(end 0.67945 0.3048)
			(stroke
				(width 0.1)
				(type default)
			)
			(layer "B.Fab")
		)
		(fp_line
			(start 0.12065 0.2794)
			(end 0.12065 0.3048)
			(stroke
				(width 0.1)
				(type default)
			)
			(layer "B.Fab")
		)
		(fp_line
			(start 0.12065 -0.2794)
			(end -0.12065 -0.2794)
			(stroke
				(width 0.1)
				(type default)
			)
			(layer "B.Fab")
		)
		(fp_line
			(start 0.12065 -0.305054)
			(end 0.12065 -0.2794)
			(stroke
				(width 0.1)
				(type default)
			)
			(layer "B.Fab")
		)
		(fp_line
			(start -0.120396 0.3048)
			(end -0.120396 0.2794)
			(stroke
				(width 0.1)
				(type default)
			)
			(layer "B.Fab")
		)
		(fp_line
			(start -0.120396 0.2794)
			(end 0.12065 0.2794)
			(stroke
				(width 0.1)
				(type default)
			)
			(layer "B.Fab")
		)
		(fp_line
			(start -0.12065 -0.2794)
			(end -0.12065 -0.3048)
			(stroke
				(width 0.1)
				(type default)
			)
			(layer "B.Fab")
		)
		(fp_line
			(start -0.12065 -0.3048)
			(end -0.67945 -0.3048)
			(stroke
				(width 0.1)
				(type default)
			)
			(layer "B.Fab")
		)
		(fp_line
			(start -0.67945 0.3048)
			(end -0.120396 0.3048)
			(stroke
				(width 0.1)
				(type default)
			)
			(layer "B.Fab")
		)
		(fp_line
			(start -0.67945 -0.3048)
			(end -0.67945 0.3048)
			(stroke
				(width 0.1)
				(type default)
			)
			(layer "B.Fab")
		)
		(pad "1" smd circle
			(at 0.40005 0)
			(size 0 0)
			(layers "B.Cu" "B.Mask" "B.Paste")
			(net "PVDDIO_P0")
		)
		(pad "2" smd circle
			(at -0.40005 0)
			(size 0 0)
			(layers "B.Cu" "B.Mask" "B.Paste")
			(net "GND")
		)
	)
	(footprint ""
		(layer "B.Cu")
		(at 393.440158 -327.644252)
		(property "Reference" "R460"
			(at 0 0 0)
			(layer "B.SilkS")
			(hide yes)
			(effects
				(font
					(size 1.27 1.27)
				)
				(justify mirror)
			)
		)
		(property "Value" ""
			(at 0 0 0)
			(layer "B.Fab")
			(effects
				(font
					(size 1.27 1.27)
				)
				(justify mirror)
			)
		)
		(duplicate_pad_numbers_are_jumpers no)
		(fp_line
			(start -0.7874 -0.4064)
			(end -0.7874 0.4064)
			(stroke
				(width 0.1524)
				(type default)
			)
			(layer "B.SilkS")
		)
		(fp_line
			(start -0.7874 0.4064)
			(end 0.7874 0.4064)
			(stroke
				(width 0.1524)
				(type default)
			)
			(layer "B.SilkS")
		)
		(fp_line
			(start 0.7874 -0.4064)
			(end -0.7874 -0.4064)
			(stroke
				(width 0.1524)
				(type default)
			)
			(layer "B.SilkS")
		)
		(fp_line
			(start 0.7874 0.4064)
			(end 0.7874 -0.4064)
			(stroke
				(width 0.1524)
				(type default)
			)
			(layer "B.SilkS")
		)
		(fp_line
			(start -0.67945 -0.3048)
			(end -0.67945 0.3048)
			(stroke
				(width 0.1)
				(type default)
			)
			(layer "B.Fab")
		)
		(fp_line
			(start -0.67945 0.3048)
			(end -0.120396 0.3048)
			(stroke
				(width 0.1)
				(type default)
			)
			(layer "B.Fab")
		)
		(fp_line
			(start -0.12065 -0.3048)
			(end -0.67945 -0.3048)
			(stroke
				(width 0.1)
				(type default)
			)
			(layer "B.Fab")
		)
		(fp_line
			(start -0.12065 -0.2794)
			(end -0.12065 -0.3048)
			(stroke
				(width 0.1)
				(type default)
			)
			(layer "B.Fab")
		)
		(fp_line
			(start -0.120396 0.2794)
			(end 0.12065 0.2794)
			(stroke
				(width 0.1)
				(type default)
			)
			(layer "B.Fab")
		)
		(fp_line
			(start -0.120396 0.3048)
			(end -0.120396 0.2794)
			(stroke
				(width 0.1)
				(type default)
			)
			(layer "B.Fab")
		)
		(fp_line
			(start 0.12065 -0.305054)
			(end 0.12065 -0.2794)
			(stroke
				(width 0.1)
				(type default)
			)
			(layer "B.Fab")
		)
		(fp_line
			(start 0.12065 -0.2794)
			(end -0.12065 -0.2794)
			(stroke
				(width 0.1)
				(type default)
			)
			(layer "B.Fab")
		)
		(fp_line
			(start 0.12065 0.2794)
			(end 0.12065 0.3048)
			(stroke
				(width 0.1)
				(type default)
			)
			(layer "B.Fab")
		)
		(fp_line
			(start 0.12065 0.3048)
			(end 0.67945 0.3048)
			(stroke
				(width 0.1)
				(type default)
			)
			(layer "B.Fab")
		)
		(fp_line
			(start 0.67945 -0.305054)
			(end 0.12065 -0.305054)
			(stroke
				(width 0.1)
				(type default)
			)
			(layer "B.Fab")
		)
		(fp_line
			(start 0.67945 0.3048)
			(end 0.67945 -0.305054)
			(stroke
				(width 0.1)
				(type default)
			)
			(layer "B.Fab")
		)
		(pad "1" smd circle
			(at 0.40005 0 180)
			(size 0 0)
			(layers "B.Cu" "B.Mask" "B.Paste")
			(net "SPI_CPU0_CS1_N")
		)
		(pad "2" smd circle
			(at -0.40005 0 180)
			(size 0 0)
			(layers "B.Cu" "B.Mask" "B.Paste")
			(net "SPI_CPU0_R_CS1_N")
		)
	)
	(footprint ""
		(layer "B.Cu")
		(at 109.550454 -30.533086 180)
		(property "Reference" "C6121"
			(at 0 0 0)
			(layer "B.SilkS")
			(hide yes)
			(effects
				(font
					(size 1.27 1.27)
				)
				(justify mirror)
			)
		)
		(property "Value" ""
			(at 0 0 0)
			(layer "B.Fab")
			(effects
				(font
					(size 1.27 1.27)
				)
				(justify mirror)
			)
		)
		(duplicate_pad_numbers_are_jumpers no)
		(fp_line
			(start 0.7874 0.4064)
			(end 0.7874 -0.4064)
			(stroke
				(width 0.1524)
				(type default)
			)
			(layer "B.SilkS")
		)
		(fp_line
			(start 0.7874 -0.4064)
			(end -0.7874 -0.4064)
			(stroke
				(width 0.1524)
				(type default)
			)
			(layer "B.SilkS")
		)
		(fp_line
			(start -0.7874 0.4064)
			(end 0.7874 0.4064)
			(stroke
				(width 0.1524)
				(type default)
			)
			(layer "B.SilkS")
		)
		(fp_line
			(start -0.7874 -0.4064)
			(end -0.7874 0.4064)
			(stroke
				(width 0.1524)
				(type default)
			)
			(layer "B.SilkS")
		)
		(fp_line
			(start 0.67945 0.3048)
			(end 0.67945 -0.305054)
			(stroke
				(width 0.1)
				(type default)
			)
			(layer "B.Fab")
		)
		(fp_line
			(start 0.67945 -0.305054)
			(end 0.12065 -0.305054)
			(stroke
				(width 0.1)
				(type default)
			)
			(layer "B.Fab")
		)
		(fp_line
			(start 0.12065 0.3048)
			(end 0.67945 0.3048)
			(stroke
				(width 0.1)
				(type default)
			)
			(layer "B.Fab")
		)
		(fp_line
			(start 0.12065 0.2794)
			(end 0.12065 0.3048)
			(stroke
				(width 0.1)
				(type default)
			)
			(layer "B.Fab")
		)
		(fp_line
			(start 0.12065 -0.2794)
			(end -0.12065 -0.2794)
			(stroke
				(width 0.1)
				(type default)
			)
			(layer "B.Fab")
		)
		(fp_line
			(start 0.12065 -0.305054)
			(end 0.12065 -0.2794)
			(stroke
				(width 0.1)
				(type default)
			)
			(layer "B.Fab")
		)
		(fp_line
			(start -0.120396 0.3048)
			(end -0.120396 0.2794)
			(stroke
				(width 0.1)
				(type default)
			)
			(layer "B.Fab")
		)
		(fp_line
			(start -0.120396 0.2794)
			(end 0.12065 0.2794)
			(stroke
				(width 0.1)
				(type default)
			)
			(layer "B.Fab")
		)
		(fp_line
			(start -0.12065 -0.2794)
			(end -0.12065 -0.3048)
			(stroke
				(width 0.1)
				(type default)
			)
			(layer "B.Fab")
		)
		(fp_line
			(start -0.12065 -0.3048)
			(end -0.67945 -0.3048)
			(stroke
				(width 0.1)
				(type default)
			)
			(layer "B.Fab")
		)
		(fp_line
			(start -0.67945 0.3048)
			(end -0.120396 0.3048)
			(stroke
				(width 0.1)
				(type default)
			)
			(layer "B.Fab")
		)
		(fp_line
			(start -0.67945 -0.3048)
			(end -0.67945 0.3048)
			(stroke
				(width 0.1)
				(type default)
			)
			(layer "B.Fab")
		)
		(pad "1" smd circle
			(at 0.40005 0)
			(size 0 0)
			(layers "B.Cu" "B.Mask" "B.Paste")
			(net "P1V2_CPU0_USB2_DVDD12")
		)
		(pad "2" smd circle
			(at -0.40005 0)
			(size 0 0)
			(layers "B.Cu" "B.Mask" "B.Paste")
			(net "GND")
		)
	)
	(footprint ""
		(layer "B.Cu")
		(at 107.355386 -269.307564 180)
		(property "Reference" "C2402"
			(at 0 0 0)
			(layer "B.SilkS")
			(hide yes)
			(effects
				(font
					(size 1.27 1.27)
				)
				(justify mirror)
			)
		)
		(property "Value" ""
			(at 0 0 0)
			(layer "B.Fab")
			(effects
				(font
					(size 1.27 1.27)
				)
				(justify mirror)
			)
		)
		(duplicate_pad_numbers_are_jumpers no)
		(fp_line
			(start 0.7874 0.4064)
			(end 0.7874 -0.4064)
			(stroke
				(width 0.1524)
				(type default)
			)
			(layer "B.SilkS")
		)
		(fp_line
			(start 0.7874 -0.4064)
			(end -0.7874 -0.4064)
			(stroke
				(width 0.1524)
				(type default)
			)
			(layer "B.SilkS")
		)
		(fp_line
			(start -0.7874 0.4064)
			(end 0.7874 0.4064)
			(stroke
				(width 0.1524)
				(type default)
			)
			(layer "B.SilkS")
		)
		(fp_line
			(start -0.7874 -0.4064)
			(end -0.7874 0.4064)
			(stroke
				(width 0.1524)
				(type default)
			)
			(layer "B.SilkS")
		)
		(fp_line
			(start 0.67945 0.3048)
			(end 0.67945 -0.305054)
			(stroke
				(width 0.1)
				(type default)
			)
			(layer "B.Fab")
		)
		(fp_line
			(start 0.67945 -0.305054)
			(end 0.12065 -0.305054)
			(stroke
				(width 0.1)
				(type default)
			)
			(layer "B.Fab")
		)
		(fp_line
			(start 0.12065 0.3048)
			(end 0.67945 0.3048)
			(stroke
				(width 0.1)
				(type default)
			)
			(layer "B.Fab")
		)
		(fp_line
			(start 0.12065 0.2794)
			(end 0.12065 0.3048)
			(stroke
				(width 0.1)
				(type default)
			)
			(layer "B.Fab")
		)
		(fp_line
			(start 0.12065 -0.2794)
			(end -0.12065 -0.2794)
			(stroke
				(width 0.1)
				(type default)
			)
			(layer "B.Fab")
		)
		(fp_line
			(start 0.12065 -0.305054)
			(end 0.12065 -0.2794)
			(stroke
				(width 0.1)
				(type default)
			)
			(layer "B.Fab")
		)
		(fp_line
			(start -0.120396 0.3048)
			(end -0.120396 0.2794)
			(stroke
				(width 0.1)
				(type default)
			)
			(layer "B.Fab")
		)
		(fp_line
			(start -0.120396 0.2794)
			(end 0.12065 0.2794)
			(stroke
				(width 0.1)
				(type default)
			)
			(layer "B.Fab")
		)
		(fp_line
			(start -0.12065 -0.2794)
			(end -0.12065 -0.3048)
			(stroke
				(width 0.1)
				(type default)
			)
			(layer "B.Fab")
		)
		(fp_line
			(start -0.12065 -0.3048)
			(end -0.67945 -0.3048)
			(stroke
				(width 0.1)
				(type default)
			)
			(layer "B.Fab")
		)
		(fp_line
			(start -0.67945 0.3048)
			(end -0.120396 0.3048)
			(stroke
				(width 0.1)
				(type default)
			)
			(layer "B.Fab")
		)
		(fp_line
			(start -0.67945 -0.3048)
			(end -0.67945 0.3048)
			(stroke
				(width 0.1)
				(type default)
			)
			(layer "B.Fab")
		)
		(pad "1" smd circle
			(at 0.40005 0)
			(size 0 0)
			(layers "B.Cu" "B.Mask" "B.Paste")
			(net "PVDDCR_CPU1_P1")
		)
		(pad "2" smd circle
			(at -0.40005 0)
			(size 0 0)
			(layers "B.Cu" "B.Mask" "B.Paste")
			(net "GND")
		)
	)
	(footprint ""
		(layer "B.Cu")
		(at 140.906246 -408.517344 90)
		(property "Reference" "C6742"
			(at 0 0 90)
			(layer "B.SilkS")
			(hide yes)
			(effects
				(font
					(size 1.27 1.27)
				)
				(justify mirror)
			)
		)
		(property "Value" ""
			(at 0 0 90)
			(layer "B.Fab")
			(effects
				(font
					(size 1.27 1.27)
				)
				(justify mirror)
			)
		)
		(duplicate_pad_numbers_are_jumpers no)
		(fp_line
			(start 0.299974 -0.150114)
			(end -0.299974 -0.150114)
			(stroke
				(width 0.1)
				(type default)
			)
			(layer "B.Fab")
		)
		(fp_line
			(start -0.299974 -0.150114)
			(end -0.299974 0.150114)
			(stroke
				(width 0.1)
				(type default)
			)
			(layer "B.Fab")
		)
		(fp_line
			(start 0.299974 0.150114)
			(end 0.299974 -0.150114)
			(stroke
				(width 0.1)
				(type default)
			)
			(layer "B.Fab")
		)
		(fp_line
			(start -0.299974 0.150114)
			(end 0.299974 0.150114)
			(stroke
				(width 0.1)
				(type default)
			)
			(layer "B.Fab")
		)
		(pad "1" smd rect
			(at 0.2667 0 270)
			(size 0.3048 0.381)
			(layers "B.Cu" "B.Mask" "B.Paste")
			(net "P5E_CPU1_P3_TX_BUF_C_DN<8>")
		)
		(pad "2" smd rect
			(at -0.2667 0 270)
			(size 0.3048 0.381)
			(layers "B.Cu" "B.Mask" "B.Paste")
			(net "P5E_CPU1_P3_TX_BUF_DN<8>")
		)
	)
	(footprint ""
		(layer "B.Cu")
		(at 203.33208 -36.642548 180)
		(property "Reference" "R3578"
			(at 0 0 0)
			(layer "B.SilkS")
			(hide yes)
			(effects
				(font
					(size 1.27 1.27)
				)
				(justify mirror)
			)
		)
		(property "Value" ""
			(at 0 0 0)
			(layer "B.Fab")
			(effects
				(font
					(size 1.27 1.27)
				)
				(justify mirror)
			)
		)
		(duplicate_pad_numbers_are_jumpers no)
		(fp_line
			(start 0.7874 0.4064)
			(end 0.7874 -0.4064)
			(stroke
				(width 0.1524)
				(type default)
			)
			(layer "B.SilkS")
		)
		(fp_line
			(start 0.7874 -0.4064)
			(end -0.7874 -0.4064)
			(stroke
				(width 0.1524)
				(type default)
			)
			(layer "B.SilkS")
		)
		(fp_line
			(start -0.7874 0.4064)
			(end 0.7874 0.4064)
			(stroke
				(width 0.1524)
				(type default)
			)
			(layer "B.SilkS")
		)
		(fp_line
			(start -0.7874 -0.4064)
			(end -0.7874 0.4064)
			(stroke
				(width 0.1524)
				(type default)
			)
			(layer "B.SilkS")
		)
		(fp_line
			(start 0.67945 0.3048)
			(end 0.67945 -0.305054)
			(stroke
				(width 0.1)
				(type default)
			)
			(layer "B.Fab")
		)
		(fp_line
			(start 0.67945 -0.305054)
			(end 0.12065 -0.305054)
			(stroke
				(width 0.1)
				(type default)
			)
			(layer "B.Fab")
		)
		(fp_line
			(start 0.12065 0.3048)
			(end 0.67945 0.3048)
			(stroke
				(width 0.1)
				(type default)
			)
			(layer "B.Fab")
		)
		(fp_line
			(start 0.12065 0.2794)
			(end 0.12065 0.3048)
			(stroke
				(width 0.1)
				(type default)
			)
			(layer "B.Fab")
		)
		(fp_line
			(start 0.12065 -0.2794)
			(end -0.12065 -0.2794)
			(stroke
				(width 0.1)
				(type default)
			)
			(layer "B.Fab")
		)
		(fp_line
			(start 0.12065 -0.305054)
			(end 0.12065 -0.2794)
			(stroke
				(width 0.1)
				(type default)
			)
			(layer "B.Fab")
		)
		(fp_line
			(start -0.120396 0.3048)
			(end -0.120396 0.2794)
			(stroke
				(width 0.1)
				(type default)
			)
			(layer "B.Fab")
		)
		(fp_line
			(start -0.120396 0.2794)
			(end 0.12065 0.2794)
			(stroke
				(width 0.1)
				(type default)
			)
			(layer "B.Fab")
		)
		(fp_line
			(start -0.12065 -0.2794)
			(end -0.12065 -0.3048)
			(stroke
				(width 0.1)
				(type default)
			)
			(layer "B.Fab")
		)
		(fp_line
			(start -0.12065 -0.3048)
			(end -0.67945 -0.3048)
			(stroke
				(width 0.1)
				(type default)
			)
			(layer "B.Fab")
		)
		(fp_line
			(start -0.67945 0.3048)
			(end -0.120396 0.3048)
			(stroke
				(width 0.1)
				(type default)
			)
			(layer "B.Fab")
		)
		(fp_line
			(start -0.67945 -0.3048)
			(end -0.67945 0.3048)
			(stroke
				(width 0.1)
				(type default)
			)
			(layer "B.Fab")
		)
		(pad "1" smd circle
			(at 0.40005 0)
			(size 0 0)
			(layers "B.Cu" "B.Mask" "B.Paste")
			(net "P12V_SCM_R")
		)
		(pad "2" smd circle
			(at -0.40005 0)
			(size 0 0)
			(layers "B.Cu" "B.Mask" "B.Paste")
			(net "VSENSE_P12V_INA230_5_INP")
		)
	)
	(footprint ""
		(layer "B.Cu")
		(at 162.46983 -16.77416 180)
		(property "Reference" "R4151"
			(at 0 0 0)
			(layer "B.SilkS")
			(hide yes)
			(effects
				(font
					(size 1.27 1.27)
				)
				(justify mirror)
			)
		)
		(property "Value" ""
			(at 0 0 0)
			(layer "B.Fab")
			(effects
				(font
					(size 1.27 1.27)
				)
				(justify mirror)
			)
		)
		(duplicate_pad_numbers_are_jumpers no)
		(fp_line
			(start 0.7874 0.4064)
			(end 0.7874 -0.4064)
			(stroke
				(width 0.1524)
				(type default)
			)
			(layer "B.SilkS")
		)
		(fp_line
			(start 0.7874 -0.4064)
			(end -0.7874 -0.4064)
			(stroke
				(width 0.1524)
				(type default)
			)
			(layer "B.SilkS")
		)
		(fp_line
			(start -0.7874 0.4064)
			(end 0.7874 0.4064)
			(stroke
				(width 0.1524)
				(type default)
			)
			(layer "B.SilkS")
		)
		(fp_line
			(start -0.7874 -0.4064)
			(end -0.7874 0.4064)
			(stroke
				(width 0.1524)
				(type default)
			)
			(layer "B.SilkS")
		)
		(fp_line
			(start 0.67945 0.3048)
			(end 0.67945 -0.305054)
			(stroke
				(width 0.1)
				(type default)
			)
			(layer "B.Fab")
		)
		(fp_line
			(start 0.67945 -0.305054)
			(end 0.12065 -0.305054)
			(stroke
				(width 0.1)
				(type default)
			)
			(layer "B.Fab")
		)
		(fp_line
			(start 0.12065 0.3048)
			(end 0.67945 0.3048)
			(stroke
				(width 0.1)
				(type default)
			)
			(layer "B.Fab")
		)
		(fp_line
			(start 0.12065 0.2794)
			(end 0.12065 0.3048)
			(stroke
				(width 0.1)
				(type default)
			)
			(layer "B.Fab")
		)
		(fp_line
			(start 0.12065 -0.2794)
			(end -0.12065 -0.2794)
			(stroke
				(width 0.1)
				(type default)
			)
			(layer "B.Fab")
		)
		(fp_line
			(start 0.12065 -0.305054)
			(end 0.12065 -0.2794)
			(stroke
				(width 0.1)
				(type default)
			)
			(layer "B.Fab")
		)
		(fp_line
			(start -0.120396 0.3048)
			(end -0.120396 0.2794)
			(stroke
				(width 0.1)
				(type default)
			)
			(layer "B.Fab")
		)
		(fp_line
			(start -0.120396 0.2794)
			(end 0.12065 0.2794)
			(stroke
				(width 0.1)
				(type default)
			)
			(layer "B.Fab")
		)
		(fp_line
			(start -0.12065 -0.2794)
			(end -0.12065 -0.3048)
			(stroke
				(width 0.1)
				(type default)
			)
			(layer "B.Fab")
		)
		(fp_line
			(start -0.12065 -0.3048)
			(end -0.67945 -0.3048)
			(stroke
				(width 0.1)
				(type default)
			)
			(layer "B.Fab")
		)
		(fp_line
			(start -0.67945 0.3048)
			(end -0.120396 0.3048)
			(stroke
				(width 0.1)
				(type default)
			)
			(layer "B.Fab")
		)
		(fp_line
			(start -0.67945 -0.3048)
			(end -0.67945 0.3048)
			(stroke
				(width 0.1)
				(type default)
			)
			(layer "B.Fab")
		)
		(pad "1" smd circle
			(at 0.40005 0)
			(size 0 0)
			(layers "B.Cu" "B.Mask" "B.Paste")
			(net "SMB_1_PLD_3V3AUX_SCL")
		)
		(pad "2" smd circle
			(at -0.40005 0)
			(size 0 0)
			(layers "B.Cu" "B.Mask" "B.Paste")
			(net "SMB_2_PLD_3V3AUX_SCL_R1")
		)
	)
	(footprint ""
		(layer "B.Cu")
		(at 185.458608 -111.466376 -90)
		(property "Reference" "R1189"
			(at 0 0 90)
			(layer "B.SilkS")
			(hide yes)
			(effects
				(font
					(size 1.27 1.27)
				)
				(justify mirror)
			)
		)
		(property "Value" ""
			(at 0 0 90)
			(layer "B.Fab")
			(effects
				(font
					(size 1.27 1.27)
				)
				(justify mirror)
			)
		)
		(duplicate_pad_numbers_are_jumpers no)
		(fp_line
			(start -0.7874 0.4064)
			(end 0.7874 0.4064)
			(stroke
				(width 0.1524)
				(type default)
			)
			(layer "B.SilkS")
		)
		(fp_line
			(start 0.7874 0.4064)
			(end 0.7874 -0.4064)
			(stroke
				(width 0.1524)
				(type default)
			)
			(layer "B.SilkS")
		)
		(fp_line
			(start -0.7874 -0.4064)
			(end -0.7874 0.4064)
			(stroke
				(width 0.1524)
				(type default)
			)
			(layer "B.SilkS")
		)
		(fp_line
			(start 0.7874 -0.4064)
			(end -0.7874 -0.4064)
			(stroke
				(width 0.1524)
				(type default)
			)
			(layer "B.SilkS")
		)
		(fp_line
			(start -0.67945 0.3048)
			(end -0.120396 0.3048)
			(stroke
				(width 0.1)
				(type default)
			)
			(layer "B.Fab")
		)
		(fp_line
			(start -0.120396 0.3048)
			(end -0.120396 0.2794)
			(stroke
				(width 0.1)
				(type default)
			)
			(layer "B.Fab")
		)
		(fp_line
			(start 0.12065 0.3048)
			(end 0.67945 0.3048)
			(stroke
				(width 0.1)
				(type default)
			)
			(layer "B.Fab")
		)
		(fp_line
			(start 0.67945 0.3048)
			(end 0.67945 -0.305054)
			(stroke
				(width 0.1)
				(type default)
			)
			(layer "B.Fab")
		)
		(fp_line
			(start -0.120396 0.2794)
			(end 0.12065 0.2794)
			(stroke
				(width 0.1)
				(type default)
			)
			(layer "B.Fab")
		)
		(fp_line
			(start 0.12065 0.2794)
			(end 0.12065 0.3048)
			(stroke
				(width 0.1)
				(type default)
			)
			(layer "B.Fab")
		)
		(fp_line
			(start -0.12065 -0.2794)
			(end -0.12065 -0.3048)
			(stroke
				(width 0.1)
				(type default)
			)
			(layer "B.Fab")
		)
		(fp_line
			(start 0.12065 -0.2794)
			(end -0.12065 -0.2794)
			(stroke
				(width 0.1)
				(type default)
			)
			(layer "B.Fab")
		)
		(fp_line
			(start -0.67945 -0.3048)
			(end -0.67945 0.3048)
			(stroke
				(width 0.1)
				(type default)
			)
			(layer "B.Fab")
		)
		(fp_line
			(start -0.12065 -0.3048)
			(end -0.67945 -0.3048)
			(stroke
				(width 0.1)
				(type default)
			)
			(layer "B.Fab")
		)
		(fp_line
			(start 0.12065 -0.305054)
			(end 0.12065 -0.2794)
			(stroke
				(width 0.1)
				(type default)
			)
			(layer "B.Fab")
		)
		(fp_line
			(start 0.67945 -0.305054)
			(end 0.12065 -0.305054)
			(stroke
				(width 0.1)
				(type default)
			)
			(layer "B.Fab")
		)
		(pad "1" smd circle
			(at 0.40005 0 90)
			(size 0 0)
			(layers "B.Cu" "B.Mask" "B.Paste")
			(net "PVDD11_S3_P0_PMALERT")
		)
		(pad "2" smd circle
			(at -0.40005 0 90)
			(size 0 0)
			(layers "B.Cu" "B.Mask" "B.Paste")
			(net "P3V3_AUX")
		)
	)
	(footprint ""
		(layer "B.Cu")
		(at 399.796 -144.018 -90)
		(property "Reference" "R335"
			(at 0 0 90)
			(layer "B.SilkS")
			(hide yes)
			(effects
				(font
					(size 1.27 1.27)
				)
				(justify mirror)
			)
		)
		(property "Value" ""
			(at 0 0 90)
			(layer "B.Fab")
			(effects
				(font
					(size 1.27 1.27)
				)
				(justify mirror)
			)
		)
		(duplicate_pad_numbers_are_jumpers no)
		(fp_line
			(start -0.7874 0.4064)
			(end 0.7874 0.4064)
			(stroke
				(width 0.1524)
				(type default)
			)
			(layer "B.SilkS")
		)
		(fp_line
			(start 0.7874 0.4064)
			(end 0.7874 -0.4064)
			(stroke
				(width 0.1524)
				(type default)
			)
			(layer "B.SilkS")
		)
		(fp_line
			(start -0.7874 -0.4064)
			(end -0.7874 0.4064)
			(stroke
				(width 0.1524)
				(type default)
			)
			(layer "B.SilkS")
		)
		(fp_line
			(start 0.7874 -0.4064)
			(end -0.7874 -0.4064)
			(stroke
				(width 0.1524)
				(type default)
			)
			(layer "B.SilkS")
		)
		(fp_line
			(start -0.67945 0.3048)
			(end -0.120396 0.3048)
			(stroke
				(width 0.1)
				(type default)
			)
			(layer "B.Fab")
		)
		(fp_line
			(start -0.120396 0.3048)
			(end -0.120396 0.2794)
			(stroke
				(width 0.1)
				(type default)
			)
			(layer "B.Fab")
		)
		(fp_line
			(start 0.12065 0.3048)
			(end 0.67945 0.3048)
			(stroke
				(width 0.1)
				(type default)
			)
			(layer "B.Fab")
		)
		(fp_line
			(start 0.67945 0.3048)
			(end 0.67945 -0.305054)
			(stroke
				(width 0.1)
				(type default)
			)
			(layer "B.Fab")
		)
		(fp_line
			(start -0.120396 0.2794)
			(end 0.12065 0.2794)
			(stroke
				(width 0.1)
				(type default)
			)
			(layer "B.Fab")
		)
		(fp_line
			(start 0.12065 0.2794)
			(end 0.12065 0.3048)
			(stroke
				(width 0.1)
				(type default)
			)
			(layer "B.Fab")
		)
		(fp_line
			(start -0.12065 -0.2794)
			(end -0.12065 -0.3048)
			(stroke
				(width 0.1)
				(type default)
			)
			(layer "B.Fab")
		)
		(fp_line
			(start 0.12065 -0.2794)
			(end -0.12065 -0.2794)
			(stroke
				(width 0.1)
				(type default)
			)
			(layer "B.Fab")
		)
		(fp_line
			(start -0.67945 -0.3048)
			(end -0.67945 0.3048)
			(stroke
				(width 0.1)
				(type default)
			)
			(layer "B.Fab")
		)
		(fp_line
			(start -0.12065 -0.3048)
			(end -0.67945 -0.3048)
			(stroke
				(width 0.1)
				(type default)
			)
			(layer "B.Fab")
		)
		(fp_line
			(start 0.12065 -0.305054)
			(end 0.12065 -0.2794)
			(stroke
				(width 0.1)
				(type default)
			)
			(layer "B.Fab")
		)
		(fp_line
			(start 0.67945 -0.305054)
			(end 0.12065 -0.305054)
			(stroke
				(width 0.1)
				(type default)
			)
			(layer "B.Fab")
		)
		(pad "1" smd circle
			(at 0.40005 0 90)
			(size 0 0)
			(layers "B.Cu" "B.Mask" "B.Paste")
			(net "P12V_AUX")
		)
		(pad "2" smd circle
			(at -0.40005 0 90)
			(size 0 0)
			(layers "B.Cu" "B.Mask" "B.Paste")
			(net "VR_P5V_EN_D_R")
		)
	)
	(footprint ""
		(layer "B.Cu")
		(at 396.906242 -416.899344 90)
		(property "Reference" "C6614"
			(at 0 0 90)
			(layer "B.SilkS")
			(hide yes)
			(effects
				(font
					(size 1.27 1.27)
				)
				(justify mirror)
			)
		)
		(property "Value" ""
			(at 0 0 90)
			(layer "B.Fab")
			(effects
				(font
					(size 1.27 1.27)
				)
				(justify mirror)
			)
		)
		(duplicate_pad_numbers_are_jumpers no)
		(fp_line
			(start 0.299974 -0.150114)
			(end -0.299974 -0.150114)
			(stroke
				(width 0.1)
				(type default)
			)
			(layer "B.Fab")
		)
		(fp_line
			(start -0.299974 -0.150114)
			(end -0.299974 0.150114)
			(stroke
				(width 0.1)
				(type default)
			)
			(layer "B.Fab")
		)
		(fp_line
			(start 0.299974 0.150114)
			(end 0.299974 -0.150114)
			(stroke
				(width 0.1)
				(type default)
			)
			(layer "B.Fab")
		)
		(fp_line
			(start -0.299974 0.150114)
			(end 0.299974 0.150114)
			(stroke
				(width 0.1)
				(type default)
			)
			(layer "B.Fab")
		)
		(pad "1" smd rect
			(at 0.2667 0 270)
			(size 0.3048 0.381)
			(layers "B.Cu" "B.Mask" "B.Paste")
			(net "P5E_CPU0_P3_TX_BUF_C_DN<8>")
		)
		(pad "2" smd rect
			(at -0.2667 0 270)
			(size 0.3048 0.381)
			(layers "B.Cu" "B.Mask" "B.Paste")
			(net "P5E_CPU0_P3_TX_BUF_DN<8>")
		)
	)
	(footprint ""
		(layer "B.Cu")
		(at 56.99125 -390.560052 90)
		(property "Reference" "C119"
			(at 0 0 90)
			(layer "B.SilkS")
			(hide yes)
			(effects
				(font
					(size 1.27 1.27)
				)
				(justify mirror)
			)
		)
		(property "Value" ""
			(at 0 0 90)
			(layer "B.Fab")
			(effects
				(font
					(size 1.27 1.27)
				)
				(justify mirror)
			)
		)
		(duplicate_pad_numbers_are_jumpers no)
		(fp_line
			(start 0.7874 -0.4064)
			(end -0.7874 -0.4064)
			(stroke
				(width 0.1524)
				(type default)
			)
			(layer "B.SilkS")
		)
		(fp_line
			(start -0.7874 -0.4064)
			(end -0.7874 0.4064)
			(stroke
				(width 0.1524)
				(type default)
			)
			(layer "B.SilkS")
		)
		(fp_line
			(start 0.7874 0.4064)
			(end 0.7874 -0.4064)
			(stroke
				(width 0.1524)
				(type default)
			)
			(layer "B.SilkS")
		)
		(fp_line
			(start -0.7874 0.4064)
			(end 0.7874 0.4064)
			(stroke
				(width 0.1524)
				(type default)
			)
			(layer "B.SilkS")
		)
		(fp_line
			(start 0.67945 -0.305054)
			(end 0.12065 -0.305054)
			(stroke
				(width 0.1)
				(type default)
			)
			(layer "B.Fab")
		)
		(fp_line
			(start 0.12065 -0.305054)
			(end 0.12065 -0.2794)
			(stroke
				(width 0.1)
				(type default)
			)
			(layer "B.Fab")
		)
		(fp_line
			(start -0.12065 -0.3048)
			(end -0.67945 -0.3048)
			(stroke
				(width 0.1)
				(type default)
			)
			(layer "B.Fab")
		)
		(fp_line
			(start -0.67945 -0.3048)
			(end -0.67945 0.3048)
			(stroke
				(width 0.1)
				(type default)
			)
			(layer "B.Fab")
		)
		(fp_line
			(start 0.12065 -0.2794)
			(end -0.12065 -0.2794)
			(stroke
				(width 0.1)
				(type default)
			)
			(layer "B.Fab")
		)
		(fp_line
			(start -0.12065 -0.2794)
			(end -0.12065 -0.3048)
			(stroke
				(width 0.1)
				(type default)
			)
			(layer "B.Fab")
		)
		(fp_line
			(start 0.12065 0.2794)
			(end 0.12065 0.3048)
			(stroke
				(width 0.1)
				(type default)
			)
			(layer "B.Fab")
		)
		(fp_line
			(start -0.120396 0.2794)
			(end 0.12065 0.2794)
			(stroke
				(width 0.1)
				(type default)
			)
			(layer "B.Fab")
		)
		(fp_line
			(start 0.67945 0.3048)
			(end 0.67945 -0.305054)
			(stroke
				(width 0.1)
				(type default)
			)
			(layer "B.Fab")
		)
		(fp_line
			(start 0.12065 0.3048)
			(end 0.67945 0.3048)
			(stroke
				(width 0.1)
				(type default)
			)
			(layer "B.Fab")
		)
		(fp_line
			(start -0.120396 0.3048)
			(end -0.120396 0.2794)
			(stroke
				(width 0.1)
				(type default)
			)
			(layer "B.Fab")
		)
		(fp_line
			(start -0.67945 0.3048)
			(end -0.120396 0.3048)
			(stroke
				(width 0.1)
				(type default)
			)
			(layer "B.Fab")
		)
		(pad "1" smd circle
			(at 0.40005 0 270)
			(size 0 0)
			(layers "B.Cu" "B.Mask" "B.Paste")
			(net "P1V8_CPU1_RT0_1A")
		)
		(pad "2" smd circle
			(at -0.40005 0 270)
			(size 0 0)
			(layers "B.Cu" "B.Mask" "B.Paste")
			(net "GND")
		)
	)
	(footprint ""
		(layer "B.Cu")
		(at 107.863386 -268.418564)
		(property "Reference" "C2374"
			(at 0 0 0)
			(layer "B.SilkS")
			(hide yes)
			(effects
				(font
					(size 1.27 1.27)
				)
				(justify mirror)
			)
		)
		(property "Value" ""
			(at 0 0 0)
			(layer "B.Fab")
			(effects
				(font
					(size 1.27 1.27)
				)
				(justify mirror)
			)
		)
		(duplicate_pad_numbers_are_jumpers no)
		(fp_line
			(start -0.7874 -0.4064)
			(end -0.7874 0.4064)
			(stroke
				(width 0.1524)
				(type default)
			)
			(layer "B.SilkS")
		)
		(fp_line
			(start -0.7874 0.4064)
			(end 0.7874 0.4064)
			(stroke
				(width 0.1524)
				(type default)
			)
			(layer "B.SilkS")
		)
		(fp_line
			(start 0.7874 -0.4064)
			(end -0.7874 -0.4064)
			(stroke
				(width 0.1524)
				(type default)
			)
			(layer "B.SilkS")
		)
		(fp_line
			(start 0.7874 0.4064)
			(end 0.7874 -0.4064)
			(stroke
				(width 0.1524)
				(type default)
			)
			(layer "B.SilkS")
		)
		(fp_line
			(start -0.67945 -0.3048)
			(end -0.67945 0.3048)
			(stroke
				(width 0.1)
				(type default)
			)
			(layer "B.Fab")
		)
		(fp_line
			(start -0.67945 0.3048)
			(end -0.120396 0.3048)
			(stroke
				(width 0.1)
				(type default)
			)
			(layer "B.Fab")
		)
		(fp_line
			(start -0.12065 -0.3048)
			(end -0.67945 -0.3048)
			(stroke
				(width 0.1)
				(type default)
			)
			(layer "B.Fab")
		)
		(fp_line
			(start -0.12065 -0.2794)
			(end -0.12065 -0.3048)
			(stroke
				(width 0.1)
				(type default)
			)
			(layer "B.Fab")
		)
		(fp_line
			(start -0.120396 0.2794)
			(end 0.12065 0.2794)
			(stroke
				(width 0.1)
				(type default)
			)
			(layer "B.Fab")
		)
		(fp_line
			(start -0.120396 0.3048)
			(end -0.120396 0.2794)
			(stroke
				(width 0.1)
				(type default)
			)
			(layer "B.Fab")
		)
		(fp_line
			(start 0.12065 -0.305054)
			(end 0.12065 -0.2794)
			(stroke
				(width 0.1)
				(type default)
			)
			(layer "B.Fab")
		)
		(fp_line
			(start 0.12065 -0.2794)
			(end -0.12065 -0.2794)
			(stroke
				(width 0.1)
				(type default)
			)
			(layer "B.Fab")
		)
		(fp_line
			(start 0.12065 0.2794)
			(end 0.12065 0.3048)
			(stroke
				(width 0.1)
				(type default)
			)
			(layer "B.Fab")
		)
		(fp_line
			(start 0.12065 0.3048)
			(end 0.67945 0.3048)
			(stroke
				(width 0.1)
				(type default)
			)
			(layer "B.Fab")
		)
		(fp_line
			(start 0.67945 -0.305054)
			(end 0.12065 -0.305054)
			(stroke
				(width 0.1)
				(type default)
			)
			(layer "B.Fab")
		)
		(fp_line
			(start 0.67945 0.3048)
			(end 0.67945 -0.305054)
			(stroke
				(width 0.1)
				(type default)
			)
			(layer "B.Fab")
		)
		(pad "1" smd circle
			(at 0.40005 0 180)
			(size 0 0)
			(layers "B.Cu" "B.Mask" "B.Paste")
			(net "PVDDCR_CPU1_P1")
		)
		(pad "2" smd circle
			(at -0.40005 0 180)
			(size 0 0)
			(layers "B.Cu" "B.Mask" "B.Paste")
			(net "GND")
		)
	)
	(footprint ""
		(layer "B.Cu")
		(at 107.034838 -389.673084 90)
		(property "Reference" "C474"
			(at 0 0 90)
			(layer "B.SilkS")
			(hide yes)
			(effects
				(font
					(size 1.27 1.27)
				)
				(justify mirror)
			)
		)
		(property "Value" ""
			(at 0 0 90)
			(layer "B.Fab")
			(effects
				(font
					(size 1.27 1.27)
				)
				(justify mirror)
			)
		)
		(duplicate_pad_numbers_are_jumpers no)
		(fp_line
			(start 1.524 -0.762)
			(end -1.524 -0.762)
			(stroke
				(width 0.1524)
				(type default)
			)
			(layer "B.SilkS")
		)
		(fp_line
			(start -1.524 -0.762)
			(end -1.524 0.762)
			(stroke
				(width 0.1524)
				(type default)
			)
			(layer "B.SilkS")
		)
		(fp_line
			(start 1.524 0.762)
			(end 1.524 -0.762)
			(stroke
				(width 0.1524)
				(type default)
			)
			(layer "B.SilkS")
		)
		(fp_line
			(start -1.524 0.762)
			(end 1.524 0.762)
			(stroke
				(width 0.1524)
				(type default)
			)
			(layer "B.SilkS")
		)
		(fp_line
			(start 1.1049 -0.724916)
			(end 1.1049 0.724916)
			(stroke
				(width 0.1)
				(type default)
			)
			(layer "B.Fab")
		)
		(fp_line
			(start -1.1049 -0.724916)
			(end 1.1049 -0.724916)
			(stroke
				(width 0.1)
				(type default)
			)
			(layer "B.Fab")
		)
		(fp_line
			(start 1.1049 0.724916)
			(end -1.1049 0.724916)
			(stroke
				(width 0.1)
				(type default)
			)
			(layer "B.Fab")
		)
		(fp_line
			(start -1.1049 0.724916)
			(end -1.1049 -0.724916)
			(stroke
				(width 0.1)
				(type default)
			)
			(layer "B.Fab")
		)
		(pad "1" smd rect
			(at 0.889 0 90)
			(size 1.016 1.27)
			(layers "B.Cu" "B.Mask" "B.Paste")
			(net "P0V9_CPU1_RT_2D")
		)
		(pad "2" smd rect
			(at -0.889 0 90)
			(size 1.016 1.27)
			(layers "B.Cu" "B.Mask" "B.Paste")
			(net "GND")
		)
	)
	(footprint ""
		(layer "B.Cu")
		(at 359.694988 -166.830756 90)
		(property "Reference" "PR355"
			(at 0 0 90)
			(layer "B.SilkS")
			(hide yes)
			(effects
				(font
					(size 1.27 1.27)
				)
				(justify mirror)
			)
		)
		(property "Value" ""
			(at 0 0 90)
			(layer "B.Fab")
			(effects
				(font
					(size 1.27 1.27)
				)
				(justify mirror)
			)
		)
		(duplicate_pad_numbers_are_jumpers no)
		(fp_line
			(start 0.7874 -0.4064)
			(end -0.7874 -0.4064)
			(stroke
				(width 0.1524)
				(type default)
			)
			(layer "B.SilkS")
		)
		(fp_line
			(start -0.7874 -0.4064)
			(end -0.7874 0.4064)
			(stroke
				(width 0.1524)
				(type default)
			)
			(layer "B.SilkS")
		)
		(fp_line
			(start 0.7874 0.4064)
			(end 0.7874 -0.4064)
			(stroke
				(width 0.1524)
				(type default)
			)
			(layer "B.SilkS")
		)
		(fp_line
			(start -0.7874 0.4064)
			(end 0.7874 0.4064)
			(stroke
				(width 0.1524)
				(type default)
			)
			(layer "B.SilkS")
		)
		(fp_line
			(start 0.67945 -0.305054)
			(end 0.12065 -0.305054)
			(stroke
				(width 0.1)
				(type default)
			)
			(layer "B.Fab")
		)
		(fp_line
			(start 0.12065 -0.305054)
			(end 0.12065 -0.2794)
			(stroke
				(width 0.1)
				(type default)
			)
			(layer "B.Fab")
		)
		(fp_line
			(start -0.12065 -0.3048)
			(end -0.67945 -0.3048)
			(stroke
				(width 0.1)
				(type default)
			)
			(layer "B.Fab")
		)
		(fp_line
			(start -0.67945 -0.3048)
			(end -0.67945 0.3048)
			(stroke
				(width 0.1)
				(type default)
			)
			(layer "B.Fab")
		)
		(fp_line
			(start 0.12065 -0.2794)
			(end -0.12065 -0.2794)
			(stroke
				(width 0.1)
				(type default)
			)
			(layer "B.Fab")
		)
		(fp_line
			(start -0.12065 -0.2794)
			(end -0.12065 -0.3048)
			(stroke
				(width 0.1)
				(type default)
			)
			(layer "B.Fab")
		)
		(fp_line
			(start 0.12065 0.2794)
			(end 0.12065 0.3048)
			(stroke
				(width 0.1)
				(type default)
			)
			(layer "B.Fab")
		)
		(fp_line
			(start -0.120396 0.2794)
			(end 0.12065 0.2794)
			(stroke
				(width 0.1)
				(type default)
			)
			(layer "B.Fab")
		)
		(fp_line
			(start 0.67945 0.3048)
			(end 0.67945 -0.305054)
			(stroke
				(width 0.1)
				(type default)
			)
			(layer "B.Fab")
		)
		(fp_line
			(start 0.12065 0.3048)
			(end 0.67945 0.3048)
			(stroke
				(width 0.1)
				(type default)
			)
			(layer "B.Fab")
		)
		(fp_line
			(start -0.120396 0.3048)
			(end -0.120396 0.2794)
			(stroke
				(width 0.1)
				(type default)
			)
			(layer "B.Fab")
		)
		(fp_line
			(start -0.67945 0.3048)
			(end -0.120396 0.3048)
			(stroke
				(width 0.1)
				(type default)
			)
			(layer "B.Fab")
		)
		(pad "1" smd circle
			(at 0.40005 0 270)
			(size 0 0)
			(layers "B.Cu" "B.Mask" "B.Paste")
			(net "PVDDCR_CPU0_P0_VOS5")
		)
		(pad "2" smd circle
			(at -0.40005 0 270)
			(size 0 0)
			(layers "B.Cu" "B.Mask" "B.Paste")
			(net "PVDDCR_CPU0_P0")
		)
	)
	(footprint ""
		(layer "B.Cu")
		(at 23.235158 -383.53873 -90)
		(property "Reference" "PC6815"
			(at 1.64973 -4.043172 270)
			(unlocked yes)
			(layer "B.SilkS")
			(effects
				(font
					(size 0.7874 0.5842)
					(thickness 0.1524)
				)
				(justify left mirror)
			)
		)
		(property "Value" ""
			(at 0 0 90)
			(layer "B.Fab")
			(effects
				(font
					(size 1.27 1.27)
				)
				(justify mirror)
			)
		)
		(duplicate_pad_numbers_are_jumpers no)
		(fp_line
			(start 4.83108 2.150364)
			(end 4.447794 2.149348)
			(stroke
				(width 0.1524)
				(type default)
			)
			(layer "B.SilkS")
		)
		(fp_line
			(start -4.53898 2.15011)
			(end 4.53898 2.15011)
			(stroke
				(width 0.1524)
				(type default)
			)
			(layer "B.SilkS")
		)
		(fp_line
			(start 4.53898 2.15011)
			(end 4.53898 -2.15011)
			(stroke
				(width 0.1524)
				(type default)
			)
			(layer "B.SilkS")
		)
		(fp_line
			(start -4.53898 -2.15011)
			(end -4.53898 2.15011)
			(stroke
				(width 0.1524)
				(type default)
			)
			(layer "B.SilkS")
		)
		(fp_line
			(start 4.53898 -2.15011)
			(end -4.53898 -2.15011)
			(stroke
				(width 0.1524)
				(type default)
			)
			(layer "B.SilkS")
		)
		(fp_line
			(start 4.53898 -2.150618)
			(end 4.539742 2.152142)
			(stroke
				(width 0.1524)
				(type default)
			)
			(layer "B.SilkS")
		)
		(fp_line
			(start 4.69138 -2.150618)
			(end 4.692396 2.161032)
			(stroke
				(width 0.1524)
				(type default)
			)
			(layer "B.SilkS")
		)
		(fp_line
			(start 4.84378 -2.150618)
			(end 4.842256 2.163064)
			(stroke
				(width 0.1524)
				(type default)
			)
			(layer "B.SilkS")
		)
		(fp_line
			(start 4.84378 -2.150618)
			(end 4.53898 -2.150618)
			(stroke
				(width 0.1524)
				(type default)
			)
			(layer "B.SilkS")
		)
		(fp_line
			(start -3.64998 2.15011)
			(end 3.64998 2.15011)
			(stroke
				(width 0.1)
				(type default)
			)
			(layer "B.Fab")
		)
		(fp_line
			(start 3.64998 2.15011)
			(end 3.64998 -2.15011)
			(stroke
				(width 0.1)
				(type default)
			)
			(layer "B.Fab")
		)
		(fp_line
			(start -3.64998 -2.15011)
			(end -3.64998 2.15011)
			(stroke
				(width 0.1)
				(type default)
			)
			(layer "B.Fab")
		)
		(fp_line
			(start 3.64998 -2.15011)
			(end -3.64998 -2.15011)
			(stroke
				(width 0.1)
				(type default)
			)
			(layer "B.Fab")
		)
		(fp_text user "+"
			(at 6.87451 1.371854 270)
			(unlocked yes)
			(layer "B.SilkS")
			(effects
				(font
					(size 1.905 1.4224)
					(thickness 0.1524)
				)
				(justify left mirror)
			)
		)
		(fp_text user "-"
			(at -4.313174 -0.094488 270)
			(unlocked yes)
			(layer "B.SilkS")
			(effects
				(font
					(size 1.905 1.4224)
					(thickness 0.1524)
				)
				(justify left mirror)
			)
		)
		(fp_text user "-"
			(at -4.313174 -0.094488 270)
			(unlocked yes)
			(layer "B.Fab")
			(effects
				(font
					(size 1.905 1.4224)
					(thickness 0.1524)
				)
				(justify left mirror)
			)
		)
		(fp_text user "+"
			(at 6.214872 -0.337058 270)
			(unlocked yes)
			(layer "B.Fab")
			(effects
				(font
					(size 1.905 1.4224)
					(thickness 0.1524)
				)
				(justify left mirror)
			)
		)
		(pad "1" smd rect
			(at 3.199892 0 90)
			(size 2.413 2.8194)
			(layers "B.Cu" "B.Mask" "B.Paste")
			(net "P0V9_CPU1_RT_2D")
		)
		(pad "2" smd rect
			(at -3.199892 0 90)
			(size 2.413 2.8194)
			(layers "B.Cu" "B.Mask" "B.Paste")
			(net "GND")
		)
	)
	(footprint ""
		(layer "B.Cu")
		(at 316.034928 -336.054446 -90)
		(property "Reference" "PR88"
			(at 0 0 90)
			(layer "B.SilkS")
			(hide yes)
			(effects
				(font
					(size 1.27 1.27)
				)
				(justify mirror)
			)
		)
		(property "Value" ""
			(at 0 0 90)
			(layer "B.Fab")
			(effects
				(font
					(size 1.27 1.27)
				)
				(justify mirror)
			)
		)
		(duplicate_pad_numbers_are_jumpers no)
		(fp_line
			(start -0.7874 0.4064)
			(end 0.7874 0.4064)
			(stroke
				(width 0.1524)
				(type default)
			)
			(layer "B.SilkS")
		)
		(fp_line
			(start 0.7874 0.4064)
			(end 0.7874 -0.4064)
			(stroke
				(width 0.1524)
				(type default)
			)
			(layer "B.SilkS")
		)
		(fp_line
			(start -0.7874 -0.4064)
			(end -0.7874 0.4064)
			(stroke
				(width 0.1524)
				(type default)
			)
			(layer "B.SilkS")
		)
		(fp_line
			(start 0.7874 -0.4064)
			(end -0.7874 -0.4064)
			(stroke
				(width 0.1524)
				(type default)
			)
			(layer "B.SilkS")
		)
		(fp_line
			(start -0.67945 0.3048)
			(end -0.120396 0.3048)
			(stroke
				(width 0.1)
				(type default)
			)
			(layer "B.Fab")
		)
		(fp_line
			(start -0.120396 0.3048)
			(end -0.120396 0.2794)
			(stroke
				(width 0.1)
				(type default)
			)
			(layer "B.Fab")
		)
		(fp_line
			(start 0.12065 0.3048)
			(end 0.67945 0.3048)
			(stroke
				(width 0.1)
				(type default)
			)
			(layer "B.Fab")
		)
		(fp_line
			(start 0.67945 0.3048)
			(end 0.67945 -0.305054)
			(stroke
				(width 0.1)
				(type default)
			)
			(layer "B.Fab")
		)
		(fp_line
			(start -0.120396 0.2794)
			(end 0.12065 0.2794)
			(stroke
				(width 0.1)
				(type default)
			)
			(layer "B.Fab")
		)
		(fp_line
			(start 0.12065 0.2794)
			(end 0.12065 0.3048)
			(stroke
				(width 0.1)
				(type default)
			)
			(layer "B.Fab")
		)
		(fp_line
			(start -0.12065 -0.2794)
			(end -0.12065 -0.3048)
			(stroke
				(width 0.1)
				(type default)
			)
			(layer "B.Fab")
		)
		(fp_line
			(start 0.12065 -0.2794)
			(end -0.12065 -0.2794)
			(stroke
				(width 0.1)
				(type default)
			)
			(layer "B.Fab")
		)
		(fp_line
			(start -0.67945 -0.3048)
			(end -0.67945 0.3048)
			(stroke
				(width 0.1)
				(type default)
			)
			(layer "B.Fab")
		)
		(fp_line
			(start -0.12065 -0.3048)
			(end -0.67945 -0.3048)
			(stroke
				(width 0.1)
				(type default)
			)
			(layer "B.Fab")
		)
		(fp_line
			(start 0.12065 -0.305054)
			(end 0.12065 -0.2794)
			(stroke
				(width 0.1)
				(type default)
			)
			(layer "B.Fab")
		)
		(fp_line
			(start 0.67945 -0.305054)
			(end 0.12065 -0.305054)
			(stroke
				(width 0.1)
				(type default)
			)
			(layer "B.Fab")
		)
		(pad "1" smd circle
			(at 0.40005 0 90)
			(size 0 0)
			(layers "B.Cu" "B.Mask" "B.Paste")
			(net "PVDDCR_CPU1_P0_PVCC")
		)
		(pad "2" smd circle
			(at -0.40005 0 90)
			(size 0 0)
			(layers "B.Cu" "B.Mask" "B.Paste")
			(net "PVDDCR_CPU1_P0_VCC3")
		)
	)
	(footprint ""
		(layer "B.Cu")
		(at 301.082202 -427.668436 90)
		(property "Reference" "R1411"
			(at 0 0 90)
			(layer "B.SilkS")
			(hide yes)
			(effects
				(font
					(size 1.27 1.27)
				)
				(justify mirror)
			)
		)
		(property "Value" ""
			(at 0 0 90)
			(layer "B.Fab")
			(effects
				(font
					(size 1.27 1.27)
				)
				(justify mirror)
			)
		)
		(duplicate_pad_numbers_are_jumpers no)
		(fp_line
			(start 0.32512 -0.175006)
			(end -0.32512 -0.175006)
			(stroke
				(width 0.1)
				(type default)
			)
			(layer "B.Fab")
		)
		(fp_line
			(start -0.32512 -0.175006)
			(end -0.32512 0.175006)
			(stroke
				(width 0.1)
				(type default)
			)
			(layer "B.Fab")
		)
		(fp_line
			(start 0.32512 0.175006)
			(end 0.32512 -0.175006)
			(stroke
				(width 0.1)
				(type default)
			)
			(layer "B.Fab")
		)
		(fp_line
			(start -0.32512 0.175006)
			(end 0.32512 0.175006)
			(stroke
				(width 0.1)
				(type default)
			)
			(layer "B.Fab")
		)
		(pad "1" smd rect
			(at 0.2667 0 270)
			(size 0.3048 0.381)
			(layers "B.Cu" "B.Mask" "B.Paste")
			(net "P1V8_CPU0_RT_1D")
		)
		(pad "2" smd rect
			(at -0.2667 0 90)
			(size 0.3048 0.381)
			(layers "B.Cu" "B.Mask" "B.Paste")
			(net "SMB_RT_CPU0_P0_ROM_MUX_1D_SCL")
		)
	)
	(footprint ""
		(layer "B.Cu")
		(at 201.041 -137.922 90)
		(property "Reference" "C8013"
			(at 0 0 90)
			(layer "B.SilkS")
			(hide yes)
			(effects
				(font
					(size 1.27 1.27)
				)
				(justify mirror)
			)
		)
		(property "Value" ""
			(at 0 0 90)
			(layer "B.Fab")
			(effects
				(font
					(size 1.27 1.27)
				)
				(justify mirror)
			)
		)
		(duplicate_pad_numbers_are_jumpers no)
		(fp_line
			(start 0.7874 -0.4064)
			(end -0.7874 -0.4064)
			(stroke
				(width 0.1524)
				(type default)
			)
			(layer "B.SilkS")
		)
		(fp_line
			(start -0.7874 -0.4064)
			(end -0.7874 0.4064)
			(stroke
				(width 0.1524)
				(type default)
			)
			(layer "B.SilkS")
		)
		(fp_line
			(start 0.7874 0.4064)
			(end 0.7874 -0.4064)
			(stroke
				(width 0.1524)
				(type default)
			)
			(layer "B.SilkS")
		)
		(fp_line
			(start -0.7874 0.4064)
			(end 0.7874 0.4064)
			(stroke
				(width 0.1524)
				(type default)
			)
			(layer "B.SilkS")
		)
		(fp_line
			(start 0.67945 -0.305054)
			(end 0.12065 -0.305054)
			(stroke
				(width 0.1)
				(type default)
			)
			(layer "B.Fab")
		)
		(fp_line
			(start 0.12065 -0.305054)
			(end 0.12065 -0.2794)
			(stroke
				(width 0.1)
				(type default)
			)
			(layer "B.Fab")
		)
		(fp_line
			(start -0.12065 -0.3048)
			(end -0.67945 -0.3048)
			(stroke
				(width 0.1)
				(type default)
			)
			(layer "B.Fab")
		)
		(fp_line
			(start -0.67945 -0.3048)
			(end -0.67945 0.3048)
			(stroke
				(width 0.1)
				(type default)
			)
			(layer "B.Fab")
		)
		(fp_line
			(start 0.12065 -0.2794)
			(end -0.12065 -0.2794)
			(stroke
				(width 0.1)
				(type default)
			)
			(layer "B.Fab")
		)
		(fp_line
			(start -0.12065 -0.2794)
			(end -0.12065 -0.3048)
			(stroke
				(width 0.1)
				(type default)
			)
			(layer "B.Fab")
		)
		(fp_line
			(start 0.12065 0.2794)
			(end 0.12065 0.3048)
			(stroke
				(width 0.1)
				(type default)
			)
			(layer "B.Fab")
		)
		(fp_line
			(start -0.120396 0.2794)
			(end 0.12065 0.2794)
			(stroke
				(width 0.1)
				(type default)
			)
			(layer "B.Fab")
		)
		(fp_line
			(start 0.67945 0.3048)
			(end 0.67945 -0.305054)
			(stroke
				(width 0.1)
				(type default)
			)
			(layer "B.Fab")
		)
		(fp_line
			(start 0.12065 0.3048)
			(end 0.67945 0.3048)
			(stroke
				(width 0.1)
				(type default)
			)
			(layer "B.Fab")
		)
		(fp_line
			(start -0.120396 0.3048)
			(end -0.120396 0.2794)
			(stroke
				(width 0.1)
				(type default)
			)
			(layer "B.Fab")
		)
		(fp_line
			(start -0.67945 0.3048)
			(end -0.120396 0.3048)
			(stroke
				(width 0.1)
				(type default)
			)
			(layer "B.Fab")
		)
		(pad "1" smd circle
			(at 0.40005 0 270)
			(size 0 0)
			(layers "B.Cu" "B.Mask" "B.Paste")
			(net "P3V3_AUX")
		)
		(pad "2" smd circle
			(at -0.40005 0 270)
			(size 0 0)
			(layers "B.Cu" "B.Mask" "B.Paste")
			(net "GND")
		)
	)
	(footprint ""
		(layer "B.Cu")
		(at 37.792914 -244.085364 180)
		(property "Reference" "R503"
			(at 0 0 0)
			(layer "B.SilkS")
			(hide yes)
			(effects
				(font
					(size 1.27 1.27)
				)
				(justify mirror)
			)
		)
		(property "Value" ""
			(at 0 0 0)
			(layer "B.Fab")
			(effects
				(font
					(size 1.27 1.27)
				)
				(justify mirror)
			)
		)
		(duplicate_pad_numbers_are_jumpers no)
		(fp_line
			(start 0.7874 0.4064)
			(end 0.7874 -0.4064)
			(stroke
				(width 0.1524)
				(type default)
			)
			(layer "B.SilkS")
		)
		(fp_line
			(start 0.7874 -0.4064)
			(end -0.7874 -0.4064)
			(stroke
				(width 0.1524)
				(type default)
			)
			(layer "B.SilkS")
		)
		(fp_line
			(start -0.7874 0.4064)
			(end 0.7874 0.4064)
			(stroke
				(width 0.1524)
				(type default)
			)
			(layer "B.SilkS")
		)
		(fp_line
			(start -0.7874 -0.4064)
			(end -0.7874 0.4064)
			(stroke
				(width 0.1524)
				(type default)
			)
			(layer "B.SilkS")
		)
		(fp_line
			(start 0.67945 0.3048)
			(end 0.67945 -0.305054)
			(stroke
				(width 0.1)
				(type default)
			)
			(layer "B.Fab")
		)
		(fp_line
			(start 0.67945 -0.305054)
			(end 0.12065 -0.305054)
			(stroke
				(width 0.1)
				(type default)
			)
			(layer "B.Fab")
		)
		(fp_line
			(start 0.12065 0.3048)
			(end 0.67945 0.3048)
			(stroke
				(width 0.1)
				(type default)
			)
			(layer "B.Fab")
		)
		(fp_line
			(start 0.12065 0.2794)
			(end 0.12065 0.3048)
			(stroke
				(width 0.1)
				(type default)
			)
			(layer "B.Fab")
		)
		(fp_line
			(start 0.12065 -0.2794)
			(end -0.12065 -0.2794)
			(stroke
				(width 0.1)
				(type default)
			)
			(layer "B.Fab")
		)
		(fp_line
			(start 0.12065 -0.305054)
			(end 0.12065 -0.2794)
			(stroke
				(width 0.1)
				(type default)
			)
			(layer "B.Fab")
		)
		(fp_line
			(start -0.120396 0.3048)
			(end -0.120396 0.2794)
			(stroke
				(width 0.1)
				(type default)
			)
			(layer "B.Fab")
		)
		(fp_line
			(start -0.120396 0.2794)
			(end 0.12065 0.2794)
			(stroke
				(width 0.1)
				(type default)
			)
			(layer "B.Fab")
		)
		(fp_line
			(start -0.12065 -0.2794)
			(end -0.12065 -0.3048)
			(stroke
				(width 0.1)
				(type default)
			)
			(layer "B.Fab")
		)
		(fp_line
			(start -0.12065 -0.3048)
			(end -0.67945 -0.3048)
			(stroke
				(width 0.1)
				(type default)
			)
			(layer "B.Fab")
		)
		(fp_line
			(start -0.67945 0.3048)
			(end -0.120396 0.3048)
			(stroke
				(width 0.1)
				(type default)
			)
			(layer "B.Fab")
		)
		(fp_line
			(start -0.67945 -0.3048)
			(end -0.67945 0.3048)
			(stroke
				(width 0.1)
				(type default)
			)
			(layer "B.Fab")
		)
		(pad "1" smd circle
			(at 0.40005 0)
			(size 0 0)
			(layers "B.Cu" "B.Mask" "B.Paste")
			(net "M_D_CPU1_ALERT_N")
		)
		(pad "2" smd circle
			(at -0.40005 0)
			(size 0 0)
			(layers "B.Cu" "B.Mask" "B.Paste")
			(net "M_D_CPU1_ALERT_R_N")
		)
	)
	(footprint ""
		(layer "B.Cu")
		(at 93.10624 -386.766562 90)
		(property "Reference" "C315"
			(at 0 0 90)
			(layer "B.SilkS")
			(hide yes)
			(effects
				(font
					(size 1.27 1.27)
				)
				(justify mirror)
			)
		)
		(property "Value" ""
			(at 0 0 90)
			(layer "B.Fab")
			(effects
				(font
					(size 1.27 1.27)
				)
				(justify mirror)
			)
		)
		(duplicate_pad_numbers_are_jumpers no)
		(fp_line
			(start 0.299974 -0.150114)
			(end -0.299974 -0.150114)
			(stroke
				(width 0.1)
				(type default)
			)
			(layer "B.Fab")
		)
		(fp_line
			(start -0.299974 -0.150114)
			(end -0.299974 0.150114)
			(stroke
				(width 0.1)
				(type default)
			)
			(layer "B.Fab")
		)
		(fp_line
			(start 0.299974 0.150114)
			(end 0.299974 -0.150114)
			(stroke
				(width 0.1)
				(type default)
			)
			(layer "B.Fab")
		)
		(fp_line
			(start -0.299974 0.150114)
			(end 0.299974 0.150114)
			(stroke
				(width 0.1)
				(type default)
			)
			(layer "B.Fab")
		)
		(pad "1" smd rect
			(at 0.2667 0 270)
			(size 0.3048 0.381)
			(layers "B.Cu" "B.Mask" "B.Paste")
			(net "P0V9_CPU1_RT1_2A_2D")
		)
		(pad "2" smd rect
			(at -0.2667 0 270)
			(size 0.3048 0.381)
			(layers "B.Cu" "B.Mask" "B.Paste")
			(net "GND")
		)
	)
	(footprint ""
		(layer "B.Cu")
		(at 112.054386 -267.529564 -90)
		(property "Reference" "C2377"
			(at 0 0 90)
			(layer "B.SilkS")
			(hide yes)
			(effects
				(font
					(size 1.27 1.27)
				)
				(justify mirror)
			)
		)
		(property "Value" ""
			(at 0 0 90)
			(layer "B.Fab")
			(effects
				(font
					(size 1.27 1.27)
				)
				(justify mirror)
			)
		)
		(duplicate_pad_numbers_are_jumpers no)
		(fp_line
			(start -0.7874 0.4064)
			(end 0.7874 0.4064)
			(stroke
				(width 0.1524)
				(type default)
			)
			(layer "B.SilkS")
		)
		(fp_line
			(start 0.7874 0.4064)
			(end 0.7874 -0.4064)
			(stroke
				(width 0.1524)
				(type default)
			)
			(layer "B.SilkS")
		)
		(fp_line
			(start -0.7874 -0.4064)
			(end -0.7874 0.4064)
			(stroke
				(width 0.1524)
				(type default)
			)
			(layer "B.SilkS")
		)
		(fp_line
			(start 0.7874 -0.4064)
			(end -0.7874 -0.4064)
			(stroke
				(width 0.1524)
				(type default)
			)
			(layer "B.SilkS")
		)
		(fp_line
			(start -0.67945 0.3048)
			(end -0.120396 0.3048)
			(stroke
				(width 0.1)
				(type default)
			)
			(layer "B.Fab")
		)
		(fp_line
			(start -0.120396 0.3048)
			(end -0.120396 0.2794)
			(stroke
				(width 0.1)
				(type default)
			)
			(layer "B.Fab")
		)
		(fp_line
			(start 0.12065 0.3048)
			(end 0.67945 0.3048)
			(stroke
				(width 0.1)
				(type default)
			)
			(layer "B.Fab")
		)
		(fp_line
			(start 0.67945 0.3048)
			(end 0.67945 -0.305054)
			(stroke
				(width 0.1)
				(type default)
			)
			(layer "B.Fab")
		)
		(fp_line
			(start -0.120396 0.2794)
			(end 0.12065 0.2794)
			(stroke
				(width 0.1)
				(type default)
			)
			(layer "B.Fab")
		)
		(fp_line
			(start 0.12065 0.2794)
			(end 0.12065 0.3048)
			(stroke
				(width 0.1)
				(type default)
			)
			(layer "B.Fab")
		)
		(fp_line
			(start -0.12065 -0.2794)
			(end -0.12065 -0.3048)
			(stroke
				(width 0.1)
				(type default)
			)
			(layer "B.Fab")
		)
		(fp_line
			(start 0.12065 -0.2794)
			(end -0.12065 -0.2794)
			(stroke
				(width 0.1)
				(type default)
			)
			(layer "B.Fab")
		)
		(fp_line
			(start -0.67945 -0.3048)
			(end -0.67945 0.3048)
			(stroke
				(width 0.1)
				(type default)
			)
			(layer "B.Fab")
		)
		(fp_line
			(start -0.12065 -0.3048)
			(end -0.67945 -0.3048)
			(stroke
				(width 0.1)
				(type default)
			)
			(layer "B.Fab")
		)
		(fp_line
			(start 0.12065 -0.305054)
			(end 0.12065 -0.2794)
			(stroke
				(width 0.1)
				(type default)
			)
			(layer "B.Fab")
		)
		(fp_line
			(start 0.67945 -0.305054)
			(end 0.12065 -0.305054)
			(stroke
				(width 0.1)
				(type default)
			)
			(layer "B.Fab")
		)
		(pad "1" smd circle
			(at 0.40005 0 90)
			(size 0 0)
			(layers "B.Cu" "B.Mask" "B.Paste")
			(net "PVDDCR_CPU1_P1")
		)
		(pad "2" smd circle
			(at -0.40005 0 90)
			(size 0 0)
			(layers "B.Cu" "B.Mask" "B.Paste")
			(net "GND")
		)
	)
	(footprint ""
		(layer "B.Cu")
		(at 150.095966 -408.517344 90)
		(property "Reference" "C6748"
			(at 0 0 90)
			(layer "B.SilkS")
			(hide yes)
			(effects
				(font
					(size 1.27 1.27)
				)
				(justify mirror)
			)
		)
		(property "Value" ""
			(at 0 0 90)
			(layer "B.Fab")
			(effects
				(font
					(size 1.27 1.27)
				)
				(justify mirror)
			)
		)
		(duplicate_pad_numbers_are_jumpers no)
		(fp_line
			(start 0.299974 -0.150114)
			(end -0.299974 -0.150114)
			(stroke
				(width 0.1)
				(type default)
			)
			(layer "B.Fab")
		)
		(fp_line
			(start -0.299974 -0.150114)
			(end -0.299974 0.150114)
			(stroke
				(width 0.1)
				(type default)
			)
			(layer "B.Fab")
		)
		(fp_line
			(start 0.299974 0.150114)
			(end 0.299974 -0.150114)
			(stroke
				(width 0.1)
				(type default)
			)
			(layer "B.Fab")
		)
		(fp_line
			(start -0.299974 0.150114)
			(end 0.299974 0.150114)
			(stroke
				(width 0.1)
				(type default)
			)
			(layer "B.Fab")
		)
		(pad "1" smd rect
			(at 0.2667 0 270)
			(size 0.3048 0.381)
			(layers "B.Cu" "B.Mask" "B.Paste")
			(net "P5E_CPU1_P3_TX_BUF_C_DN<11>")
		)
		(pad "2" smd rect
			(at -0.2667 0 270)
			(size 0.3048 0.381)
			(layers "B.Cu" "B.Mask" "B.Paste")
			(net "P5E_CPU1_P3_TX_BUF_DN<11>")
		)
	)
	(footprint ""
		(layer "B.Cu")
		(at 42.875962 -347.780356 -90)
		(property "Reference" "PR276"
			(at 0 0 90)
			(layer "B.SilkS")
			(hide yes)
			(effects
				(font
					(size 1.27 1.27)
				)
				(justify mirror)
			)
		)
		(property "Value" ""
			(at 0 0 90)
			(layer "B.Fab")
			(effects
				(font
					(size 1.27 1.27)
				)
				(justify mirror)
			)
		)
		(duplicate_pad_numbers_are_jumpers no)
		(fp_line
			(start -0.7874 0.4064)
			(end 0.7874 0.4064)
			(stroke
				(width 0.1524)
				(type default)
			)
			(layer "B.SilkS")
		)
		(fp_line
			(start 0.7874 0.4064)
			(end 0.7874 -0.4064)
			(stroke
				(width 0.1524)
				(type default)
			)
			(layer "B.SilkS")
		)
		(fp_line
			(start -0.7874 -0.4064)
			(end -0.7874 0.4064)
			(stroke
				(width 0.1524)
				(type default)
			)
			(layer "B.SilkS")
		)
		(fp_line
			(start 0.7874 -0.4064)
			(end -0.7874 -0.4064)
			(stroke
				(width 0.1524)
				(type default)
			)
			(layer "B.SilkS")
		)
		(fp_line
			(start -0.67945 0.3048)
			(end -0.120396 0.3048)
			(stroke
				(width 0.1)
				(type default)
			)
			(layer "B.Fab")
		)
		(fp_line
			(start -0.120396 0.3048)
			(end -0.120396 0.2794)
			(stroke
				(width 0.1)
				(type default)
			)
			(layer "B.Fab")
		)
		(fp_line
			(start 0.12065 0.3048)
			(end 0.67945 0.3048)
			(stroke
				(width 0.1)
				(type default)
			)
			(layer "B.Fab")
		)
		(fp_line
			(start 0.67945 0.3048)
			(end 0.67945 -0.305054)
			(stroke
				(width 0.1)
				(type default)
			)
			(layer "B.Fab")
		)
		(fp_line
			(start -0.120396 0.2794)
			(end 0.12065 0.2794)
			(stroke
				(width 0.1)
				(type default)
			)
			(layer "B.Fab")
		)
		(fp_line
			(start 0.12065 0.2794)
			(end 0.12065 0.3048)
			(stroke
				(width 0.1)
				(type default)
			)
			(layer "B.Fab")
		)
		(fp_line
			(start -0.12065 -0.2794)
			(end -0.12065 -0.3048)
			(stroke
				(width 0.1)
				(type default)
			)
			(layer "B.Fab")
		)
		(fp_line
			(start 0.12065 -0.2794)
			(end -0.12065 -0.2794)
			(stroke
				(width 0.1)
				(type default)
			)
			(layer "B.Fab")
		)
		(fp_line
			(start -0.67945 -0.3048)
			(end -0.67945 0.3048)
			(stroke
				(width 0.1)
				(type default)
			)
			(layer "B.Fab")
		)
		(fp_line
			(start -0.12065 -0.3048)
			(end -0.67945 -0.3048)
			(stroke
				(width 0.1)
				(type default)
			)
			(layer "B.Fab")
		)
		(fp_line
			(start 0.12065 -0.305054)
			(end 0.12065 -0.2794)
			(stroke
				(width 0.1)
				(type default)
			)
			(layer "B.Fab")
		)
		(fp_line
			(start 0.67945 -0.305054)
			(end 0.12065 -0.305054)
			(stroke
				(width 0.1)
				(type default)
			)
			(layer "B.Fab")
		)
		(pad "1" smd circle
			(at 0.40005 0 90)
			(size 0 0)
			(layers "B.Cu" "B.Mask" "B.Paste")
			(net "PVDDCR_CPU1_P1_PVCC")
		)
		(pad "2" smd circle
			(at -0.40005 0 90)
			(size 0 0)
			(layers "B.Cu" "B.Mask" "B.Paste")
			(net "PVDDIO_P1_VCC2")
		)
	)
	(footprint ""
		(layer "B.Cu")
		(at 85.852 -146.939)
		(property "Reference" "C296"
			(at 0 0 0)
			(layer "B.SilkS")
			(hide yes)
			(effects
				(font
					(size 1.27 1.27)
				)
				(justify mirror)
			)
		)
		(property "Value" ""
			(at 0 0 0)
			(layer "B.Fab")
			(effects
				(font
					(size 1.27 1.27)
				)
				(justify mirror)
			)
		)
		(duplicate_pad_numbers_are_jumpers no)
		(fp_line
			(start -0.7874 -0.4064)
			(end -0.7874 0.4064)
			(stroke
				(width 0.1524)
				(type default)
			)
			(layer "B.SilkS")
		)
		(fp_line
			(start -0.7874 0.4064)
			(end 0.7874 0.4064)
			(stroke
				(width 0.1524)
				(type default)
			)
			(layer "B.SilkS")
		)
		(fp_line
			(start 0.7874 -0.4064)
			(end -0.7874 -0.4064)
			(stroke
				(width 0.1524)
				(type default)
			)
			(layer "B.SilkS")
		)
		(fp_line
			(start 0.7874 0.4064)
			(end 0.7874 -0.4064)
			(stroke
				(width 0.1524)
				(type default)
			)
			(layer "B.SilkS")
		)
		(fp_line
			(start -0.67945 -0.3048)
			(end -0.67945 0.3048)
			(stroke
				(width 0.1)
				(type default)
			)
			(layer "B.Fab")
		)
		(fp_line
			(start -0.67945 0.3048)
			(end -0.120396 0.3048)
			(stroke
				(width 0.1)
				(type default)
			)
			(layer "B.Fab")
		)
		(fp_line
			(start -0.12065 -0.3048)
			(end -0.67945 -0.3048)
			(stroke
				(width 0.1)
				(type default)
			)
			(layer "B.Fab")
		)
		(fp_line
			(start -0.12065 -0.2794)
			(end -0.12065 -0.3048)
			(stroke
				(width 0.1)
				(type default)
			)
			(layer "B.Fab")
		)
		(fp_line
			(start -0.120396 0.2794)
			(end 0.12065 0.2794)
			(stroke
				(width 0.1)
				(type default)
			)
			(layer "B.Fab")
		)
		(fp_line
			(start -0.120396 0.3048)
			(end -0.120396 0.2794)
			(stroke
				(width 0.1)
				(type default)
			)
			(layer "B.Fab")
		)
		(fp_line
			(start 0.12065 -0.305054)
			(end 0.12065 -0.2794)
			(stroke
				(width 0.1)
				(type default)
			)
			(layer "B.Fab")
		)
		(fp_line
			(start 0.12065 -0.2794)
			(end -0.12065 -0.2794)
			(stroke
				(width 0.1)
				(type default)
			)
			(layer "B.Fab")
		)
		(fp_line
			(start 0.12065 0.2794)
			(end 0.12065 0.3048)
			(stroke
				(width 0.1)
				(type default)
			)
			(layer "B.Fab")
		)
		(fp_line
			(start 0.12065 0.3048)
			(end 0.67945 0.3048)
			(stroke
				(width 0.1)
				(type default)
			)
			(layer "B.Fab")
		)
		(fp_line
			(start 0.67945 -0.305054)
			(end 0.12065 -0.305054)
			(stroke
				(width 0.1)
				(type default)
			)
			(layer "B.Fab")
		)
		(fp_line
			(start 0.67945 0.3048)
			(end 0.67945 -0.305054)
			(stroke
				(width 0.1)
				(type default)
			)
			(layer "B.Fab")
		)
		(pad "1" smd circle
			(at 0.40005 0 180)
			(size 0 0)
			(layers "B.Cu" "B.Mask" "B.Paste")
			(net "SVID_PVDDCR_CPU0_P1_SVD_R")
		)
		(pad "2" smd circle
			(at -0.40005 0 180)
			(size 0 0)
			(layers "B.Cu" "B.Mask" "B.Paste")
			(net "GND")
		)
	)
	(footprint ""
		(layer "B.Cu")
		(at 136.040114 -38.914578)
		(property "Reference" "C6068"
			(at 0 0 0)
			(layer "B.SilkS")
			(hide yes)
			(effects
				(font
					(size 1.27 1.27)
				)
				(justify mirror)
			)
		)
		(property "Value" ""
			(at 0 0 0)
			(layer "B.Fab")
			(effects
				(font
					(size 1.27 1.27)
				)
				(justify mirror)
			)
		)
		(duplicate_pad_numbers_are_jumpers no)
		(fp_line
			(start -0.7874 -0.4064)
			(end -0.7874 0.4064)
			(stroke
				(width 0.1524)
				(type default)
			)
			(layer "B.SilkS")
		)
		(fp_line
			(start -0.7874 0.4064)
			(end 0.7874 0.4064)
			(stroke
				(width 0.1524)
				(type default)
			)
			(layer "B.SilkS")
		)
		(fp_line
			(start 0.7874 -0.4064)
			(end -0.7874 -0.4064)
			(stroke
				(width 0.1524)
				(type default)
			)
			(layer "B.SilkS")
		)
		(fp_line
			(start 0.7874 0.4064)
			(end 0.7874 -0.4064)
			(stroke
				(width 0.1524)
				(type default)
			)
			(layer "B.SilkS")
		)
		(fp_line
			(start -0.67945 -0.3048)
			(end -0.67945 0.3048)
			(stroke
				(width 0.1)
				(type default)
			)
			(layer "B.Fab")
		)
		(fp_line
			(start -0.67945 0.3048)
			(end -0.120396 0.3048)
			(stroke
				(width 0.1)
				(type default)
			)
			(layer "B.Fab")
		)
		(fp_line
			(start -0.12065 -0.3048)
			(end -0.67945 -0.3048)
			(stroke
				(width 0.1)
				(type default)
			)
			(layer "B.Fab")
		)
		(fp_line
			(start -0.12065 -0.2794)
			(end -0.12065 -0.3048)
			(stroke
				(width 0.1)
				(type default)
			)
			(layer "B.Fab")
		)
		(fp_line
			(start -0.120396 0.2794)
			(end 0.12065 0.2794)
			(stroke
				(width 0.1)
				(type default)
			)
			(layer "B.Fab")
		)
		(fp_line
			(start -0.120396 0.3048)
			(end -0.120396 0.2794)
			(stroke
				(width 0.1)
				(type default)
			)
			(layer "B.Fab")
		)
		(fp_line
			(start 0.12065 -0.305054)
			(end 0.12065 -0.2794)
			(stroke
				(width 0.1)
				(type default)
			)
			(layer "B.Fab")
		)
		(fp_line
			(start 0.12065 -0.2794)
			(end -0.12065 -0.2794)
			(stroke
				(width 0.1)
				(type default)
			)
			(layer "B.Fab")
		)
		(fp_line
			(start 0.12065 0.2794)
			(end 0.12065 0.3048)
			(stroke
				(width 0.1)
				(type default)
			)
			(layer "B.Fab")
		)
		(fp_line
			(start 0.12065 0.3048)
			(end 0.67945 0.3048)
			(stroke
				(width 0.1)
				(type default)
			)
			(layer "B.Fab")
		)
		(fp_line
			(start 0.67945 -0.305054)
			(end 0.12065 -0.305054)
			(stroke
				(width 0.1)
				(type default)
			)
			(layer "B.Fab")
		)
		(fp_line
			(start 0.67945 0.3048)
			(end 0.67945 -0.305054)
			(stroke
				(width 0.1)
				(type default)
			)
			(layer "B.Fab")
		)
		(pad "1" smd circle
			(at 0.40005 0 180)
			(size 0 0)
			(layers "B.Cu" "B.Mask" "B.Paste")
			(net "P1V2_AUX")
		)
		(pad "2" smd circle
			(at -0.40005 0 180)
			(size 0 0)
			(layers "B.Cu" "B.Mask" "B.Paste")
			(net "GND")
		)
	)
	(footprint ""
		(layer "B.Cu")
		(at 380.149354 -189.461648 90)
		(property "Reference" "PC108"
			(at 6.027928 1.101598 270)
			(unlocked yes)
			(layer "B.SilkS")
			(effects
				(font
					(size 0.7874 0.5842)
					(thickness 0.1524)
				)
				(justify left mirror)
			)
		)
		(property "Value" ""
			(at 0 0 90)
			(layer "B.Fab")
			(effects
				(font
					(size 1.27 1.27)
				)
				(justify mirror)
			)
		)
		(duplicate_pad_numbers_are_jumpers no)
		(fp_line
			(start 4.533392 -2.249932)
			(end -4.533392 -2.249932)
			(stroke
				(width 0.1524)
				(type default)
			)
			(layer "B.SilkS")
		)
		(fp_line
			(start -4.533392 -2.249932)
			(end -4.533392 2.249932)
			(stroke
				(width 0.1524)
				(type default)
			)
			(layer "B.SilkS")
		)
		(fp_line
			(start 4.533392 2.249932)
			(end 4.533392 -2.249932)
			(stroke
				(width 0.1524)
				(type default)
			)
			(layer "B.SilkS")
		)
		(fp_line
			(start -4.533392 2.249932)
			(end 4.533392 2.249932)
			(stroke
				(width 0.1524)
				(type default)
			)
			(layer "B.SilkS")
		)
		(fp_rect
			(start 4.533392 -2.326132)
			(end 5.39242 2.326132)
			(stroke
				(width 0)
				(type default)
			)
			(fill yes)
			(layer "B.SilkS")
		)
		(fp_line
			(start 3.750056 -2.249932)
			(end -3.750056 -2.249932)
			(stroke
				(width 0.1)
				(type default)
			)
			(layer "B.Fab")
		)
		(fp_line
			(start -3.750056 -2.249932)
			(end -3.750056 2.249932)
			(stroke
				(width 0.1)
				(type default)
			)
			(layer "B.Fab")
		)
		(fp_line
			(start 3.750056 2.249932)
			(end 3.750056 -2.249932)
			(stroke
				(width 0.1)
				(type default)
			)
			(layer "B.Fab")
		)
		(fp_line
			(start -3.750056 2.249932)
			(end 3.750056 2.249932)
			(stroke
				(width 0.1)
				(type default)
			)
			(layer "B.Fab")
		)
		(fp_text user "+"
			(at 6.322314 0.786384 0)
			(unlocked yes)
			(layer "B.SilkS")
			(effects
				(font
					(size 1.905 1.4224)
					(thickness 0.1524)
				)
				(justify left mirror)
			)
		)
		(fp_text user "-"
			(at -4.728718 1.129792 90)
			(unlocked yes)
			(layer "B.SilkS")
			(effects
				(font
					(size 1.905 1.4224)
					(thickness 0.1524)
				)
				(justify left mirror)
			)
		)
		(fp_text user "-"
			(at -4.8514 -0.14605 90)
			(unlocked yes)
			(layer "B.Fab")
			(effects
				(font
					(size 1.905 1.4224)
					(thickness 0.1524)
				)
				(justify left mirror)
			)
		)
		(fp_text user "+"
			(at 6.322314 0.786384 0)
			(unlocked yes)
			(layer "B.Fab")
			(effects
				(font
					(size 1.905 1.4224)
					(thickness 0.1524)
				)
				(justify left mirror)
			)
		)
		(pad "1" smd rect
			(at 3.199892 0 270)
			(size 2.413 2.8194)
			(layers "B.Cu" "B.Mask" "B.Paste")
			(net "PVDDCR_CPU0_P0")
		)
		(pad "2" smd rect
			(at -3.199892 0 270)
			(size 2.413 2.8194)
			(layers "B.Cu" "B.Mask" "B.Paste")
			(net "GND")
		)
	)
	(footprint ""
		(layer "B.Cu")
		(at 110.525814 -256.012442 -90)
		(property "Reference" "C2431"
			(at 0 0 90)
			(layer "B.SilkS")
			(hide yes)
			(effects
				(font
					(size 1.27 1.27)
				)
				(justify mirror)
			)
		)
		(property "Value" ""
			(at 0 0 90)
			(layer "B.Fab")
			(effects
				(font
					(size 1.27 1.27)
				)
				(justify mirror)
			)
		)
		(duplicate_pad_numbers_are_jumpers no)
		(fp_line
			(start -0.7874 0.4064)
			(end 0.7874 0.4064)
			(stroke
				(width 0.1524)
				(type default)
			)
			(layer "B.SilkS")
		)
		(fp_line
			(start 0.7874 0.4064)
			(end 0.7874 -0.4064)
			(stroke
				(width 0.1524)
				(type default)
			)
			(layer "B.SilkS")
		)
		(fp_line
			(start -0.7874 -0.4064)
			(end -0.7874 0.4064)
			(stroke
				(width 0.1524)
				(type default)
			)
			(layer "B.SilkS")
		)
		(fp_line
			(start 0.7874 -0.4064)
			(end -0.7874 -0.4064)
			(stroke
				(width 0.1524)
				(type default)
			)
			(layer "B.SilkS")
		)
		(fp_line
			(start -0.67945 0.3048)
			(end -0.120396 0.3048)
			(stroke
				(width 0.1)
				(type default)
			)
			(layer "B.Fab")
		)
		(fp_line
			(start -0.120396 0.3048)
			(end -0.120396 0.2794)
			(stroke
				(width 0.1)
				(type default)
			)
			(layer "B.Fab")
		)
		(fp_line
			(start 0.12065 0.3048)
			(end 0.67945 0.3048)
			(stroke
				(width 0.1)
				(type default)
			)
			(layer "B.Fab")
		)
		(fp_line
			(start 0.67945 0.3048)
			(end 0.67945 -0.305054)
			(stroke
				(width 0.1)
				(type default)
			)
			(layer "B.Fab")
		)
		(fp_line
			(start -0.120396 0.2794)
			(end 0.12065 0.2794)
			(stroke
				(width 0.1)
				(type default)
			)
			(layer "B.Fab")
		)
		(fp_line
			(start 0.12065 0.2794)
			(end 0.12065 0.3048)
			(stroke
				(width 0.1)
				(type default)
			)
			(layer "B.Fab")
		)
		(fp_line
			(start -0.12065 -0.2794)
			(end -0.12065 -0.3048)
			(stroke
				(width 0.1)
				(type default)
			)
			(layer "B.Fab")
		)
		(fp_line
			(start 0.12065 -0.2794)
			(end -0.12065 -0.2794)
			(stroke
				(width 0.1)
				(type default)
			)
			(layer "B.Fab")
		)
		(fp_line
			(start -0.67945 -0.3048)
			(end -0.67945 0.3048)
			(stroke
				(width 0.1)
				(type default)
			)
			(layer "B.Fab")
		)
		(fp_line
			(start -0.12065 -0.3048)
			(end -0.67945 -0.3048)
			(stroke
				(width 0.1)
				(type default)
			)
			(layer "B.Fab")
		)
		(fp_line
			(start 0.12065 -0.305054)
			(end 0.12065 -0.2794)
			(stroke
				(width 0.1)
				(type default)
			)
			(layer "B.Fab")
		)
		(fp_line
			(start 0.67945 -0.305054)
			(end 0.12065 -0.305054)
			(stroke
				(width 0.1)
				(type default)
			)
			(layer "B.Fab")
		)
		(pad "1" smd circle
			(at 0.40005 0 90)
			(size 0 0)
			(layers "B.Cu" "B.Mask" "B.Paste")
			(net "PVDDCR_SOC_P1")
		)
		(pad "2" smd circle
			(at -0.40005 0 90)
			(size 0 0)
			(layers "B.Cu" "B.Mask" "B.Paste")
			(net "GND")
		)
	)
	(footprint ""
		(layer "B.Cu")
		(at 355.263958 -272.284952 180)
		(property "Reference" "C2239"
			(at 0 0 0)
			(layer "B.SilkS")
			(hide yes)
			(effects
				(font
					(size 1.27 1.27)
				)
				(justify mirror)
			)
		)
		(property "Value" ""
			(at 0 0 0)
			(layer "B.Fab")
			(effects
				(font
					(size 1.27 1.27)
				)
				(justify mirror)
			)
		)
		(duplicate_pad_numbers_are_jumpers no)
		(fp_line
			(start 0.7874 0.4064)
			(end 0.7874 -0.4064)
			(stroke
				(width 0.1524)
				(type default)
			)
			(layer "B.SilkS")
		)
		(fp_line
			(start 0.7874 -0.4064)
			(end -0.7874 -0.4064)
			(stroke
				(width 0.1524)
				(type default)
			)
			(layer "B.SilkS")
		)
		(fp_line
			(start -0.7874 0.4064)
			(end 0.7874 0.4064)
			(stroke
				(width 0.1524)
				(type default)
			)
			(layer "B.SilkS")
		)
		(fp_line
			(start -0.7874 -0.4064)
			(end -0.7874 0.4064)
			(stroke
				(width 0.1524)
				(type default)
			)
			(layer "B.SilkS")
		)
		(fp_line
			(start 0.67945 0.3048)
			(end 0.67945 -0.305054)
			(stroke
				(width 0.1)
				(type default)
			)
			(layer "B.Fab")
		)
		(fp_line
			(start 0.67945 -0.305054)
			(end 0.12065 -0.305054)
			(stroke
				(width 0.1)
				(type default)
			)
			(layer "B.Fab")
		)
		(fp_line
			(start 0.12065 0.3048)
			(end 0.67945 0.3048)
			(stroke
				(width 0.1)
				(type default)
			)
			(layer "B.Fab")
		)
		(fp_line
			(start 0.12065 0.2794)
			(end 0.12065 0.3048)
			(stroke
				(width 0.1)
				(type default)
			)
			(layer "B.Fab")
		)
		(fp_line
			(start 0.12065 -0.2794)
			(end -0.12065 -0.2794)
			(stroke
				(width 0.1)
				(type default)
			)
			(layer "B.Fab")
		)
		(fp_line
			(start 0.12065 -0.305054)
			(end 0.12065 -0.2794)
			(stroke
				(width 0.1)
				(type default)
			)
			(layer "B.Fab")
		)
		(fp_line
			(start -0.120396 0.3048)
			(end -0.120396 0.2794)
			(stroke
				(width 0.1)
				(type default)
			)
			(layer "B.Fab")
		)
		(fp_line
			(start -0.120396 0.2794)
			(end 0.12065 0.2794)
			(stroke
				(width 0.1)
				(type default)
			)
			(layer "B.Fab")
		)
		(fp_line
			(start -0.12065 -0.2794)
			(end -0.12065 -0.3048)
			(stroke
				(width 0.1)
				(type default)
			)
			(layer "B.Fab")
		)
		(fp_line
			(start -0.12065 -0.3048)
			(end -0.67945 -0.3048)
			(stroke
				(width 0.1)
				(type default)
			)
			(layer "B.Fab")
		)
		(fp_line
			(start -0.67945 0.3048)
			(end -0.120396 0.3048)
			(stroke
				(width 0.1)
				(type default)
			)
			(layer "B.Fab")
		)
		(fp_line
			(start -0.67945 -0.3048)
			(end -0.67945 0.3048)
			(stroke
				(width 0.1)
				(type default)
			)
			(layer "B.Fab")
		)
		(pad "1" smd circle
			(at 0.40005 0)
			(size 0 0)
			(layers "B.Cu" "B.Mask" "B.Paste")
			(net "PVDDCR_CPU1_P0")
		)
		(pad "2" smd circle
			(at -0.40005 0)
			(size 0 0)
			(layers "B.Cu" "B.Mask" "B.Paste")
			(net "GND")
		)
	)
	(footprint ""
		(layer "B.Cu")
		(at 438.344564 -193.99631)
		(property "Reference" "C128"
			(at 0 0 0)
			(layer "B.SilkS")
			(hide yes)
			(effects
				(font
					(size 1.27 1.27)
				)
				(justify mirror)
			)
		)
		(property "Value" ""
			(at 0 0 0)
			(layer "B.Fab")
			(effects
				(font
					(size 1.27 1.27)
				)
				(justify mirror)
			)
		)
		(duplicate_pad_numbers_are_jumpers no)
		(fp_line
			(start -0.7874 -0.4064)
			(end -0.7874 0.4064)
			(stroke
				(width 0.1524)
				(type default)
			)
			(layer "B.SilkS")
		)
		(fp_line
			(start -0.7874 0.4064)
			(end 0.7874 0.4064)
			(stroke
				(width 0.1524)
				(type default)
			)
			(layer "B.SilkS")
		)
		(fp_line
			(start 0.7874 -0.4064)
			(end -0.7874 -0.4064)
			(stroke
				(width 0.1524)
				(type default)
			)
			(layer "B.SilkS")
		)
		(fp_line
			(start 0.7874 0.4064)
			(end 0.7874 -0.4064)
			(stroke
				(width 0.1524)
				(type default)
			)
			(layer "B.SilkS")
		)
		(fp_line
			(start -0.67945 -0.3048)
			(end -0.67945 0.3048)
			(stroke
				(width 0.1)
				(type default)
			)
			(layer "B.Fab")
		)
		(fp_line
			(start -0.67945 0.3048)
			(end -0.120396 0.3048)
			(stroke
				(width 0.1)
				(type default)
			)
			(layer "B.Fab")
		)
		(fp_line
			(start -0.12065 -0.3048)
			(end -0.67945 -0.3048)
			(stroke
				(width 0.1)
				(type default)
			)
			(layer "B.Fab")
		)
		(fp_line
			(start -0.12065 -0.2794)
			(end -0.12065 -0.3048)
			(stroke
				(width 0.1)
				(type default)
			)
			(layer "B.Fab")
		)
		(fp_line
			(start -0.120396 0.2794)
			(end 0.12065 0.2794)
			(stroke
				(width 0.1)
				(type default)
			)
			(layer "B.Fab")
		)
		(fp_line
			(start -0.120396 0.3048)
			(end -0.120396 0.2794)
			(stroke
				(width 0.1)
				(type default)
			)
			(layer "B.Fab")
		)
		(fp_line
			(start 0.12065 -0.305054)
			(end 0.12065 -0.2794)
			(stroke
				(width 0.1)
				(type default)
			)
			(layer "B.Fab")
		)
		(fp_line
			(start 0.12065 -0.2794)
			(end -0.12065 -0.2794)
			(stroke
				(width 0.1)
				(type default)
			)
			(layer "B.Fab")
		)
		(fp_line
			(start 0.12065 0.2794)
			(end 0.12065 0.3048)
			(stroke
				(width 0.1)
				(type default)
			)
			(layer "B.Fab")
		)
		(fp_line
			(start 0.12065 0.3048)
			(end 0.67945 0.3048)
			(stroke
				(width 0.1)
				(type default)
			)
			(layer "B.Fab")
		)
		(fp_line
			(start 0.67945 -0.305054)
			(end 0.12065 -0.305054)
			(stroke
				(width 0.1)
				(type default)
			)
			(layer "B.Fab")
		)
		(fp_line
			(start 0.67945 0.3048)
			(end 0.67945 -0.305054)
			(stroke
				(width 0.1)
				(type default)
			)
			(layer "B.Fab")
		)
		(pad "1" smd circle
			(at 0.40005 0 180)
			(size 0 0)
			(layers "B.Cu" "B.Mask" "B.Paste")
			(net "P3V3_AUX")
		)
		(pad "2" smd circle
			(at -0.40005 0 180)
			(size 0 0)
			(layers "B.Cu" "B.Mask" "B.Paste")
			(net "GND")
		)
	)
	(footprint ""
		(layer "B.Cu")
		(at 450.431408 -389.600694 -90)
		(property "Reference" "PC6586_2"
			(at 0 0 90)
			(layer "B.SilkS")
			(hide yes)
			(effects
				(font
					(size 1.27 1.27)
				)
				(justify mirror)
			)
		)
		(property "Value" ""
			(at 0 0 90)
			(layer "B.Fab")
			(effects
				(font
					(size 1.27 1.27)
				)
				(justify mirror)
			)
		)
		(duplicate_pad_numbers_are_jumpers no)
		(fp_line
			(start -1.524 0.762)
			(end 1.524 0.762)
			(stroke
				(width 0.1524)
				(type default)
			)
			(layer "B.SilkS")
		)
		(fp_line
			(start 1.524 0.762)
			(end 1.524 -0.762)
			(stroke
				(width 0.1524)
				(type default)
			)
			(layer "B.SilkS")
		)
		(fp_line
			(start -1.524 -0.762)
			(end -1.524 0.762)
			(stroke
				(width 0.1524)
				(type default)
			)
			(layer "B.SilkS")
		)
		(fp_line
			(start 1.524 -0.762)
			(end -1.524 -0.762)
			(stroke
				(width 0.1524)
				(type default)
			)
			(layer "B.SilkS")
		)
		(fp_line
			(start -1.1049 0.724916)
			(end -1.1049 -0.724916)
			(stroke
				(width 0.1)
				(type default)
			)
			(layer "B.Fab")
		)
		(fp_line
			(start 1.1049 0.724916)
			(end -1.1049 0.724916)
			(stroke
				(width 0.1)
				(type default)
			)
			(layer "B.Fab")
		)
		(fp_line
			(start -1.1049 -0.724916)
			(end 1.1049 -0.724916)
			(stroke
				(width 0.1)
				(type default)
			)
			(layer "B.Fab")
		)
		(fp_line
			(start 1.1049 -0.724916)
			(end 1.1049 0.724916)
			(stroke
				(width 0.1)
				(type default)
			)
			(layer "B.Fab")
		)
		(pad "1" smd rect
			(at 0.889 0 270)
			(size 1.016 1.27)
			(layers "B.Cu" "B.Mask" "B.Paste")
			(net "P0V9_CPU0_RT_2D")
		)
		(pad "2" smd rect
			(at -0.889 0 270)
			(size 1.016 1.27)
			(layers "B.Cu" "B.Mask" "B.Paste")
			(net "GND")
		)
	)
	(footprint ""
		(layer "B.Cu")
		(at 316.578234 -395.148562 90)
		(property "Reference" "C545"
			(at 0 0 90)
			(layer "B.SilkS")
			(hide yes)
			(effects
				(font
					(size 1.27 1.27)
				)
				(justify mirror)
			)
		)
		(property "Value" ""
			(at 0 0 90)
			(layer "B.Fab")
			(effects
				(font
					(size 1.27 1.27)
				)
				(justify mirror)
			)
		)
		(duplicate_pad_numbers_are_jumpers no)
		(fp_line
			(start 0.299974 -0.150114)
			(end -0.299974 -0.150114)
			(stroke
				(width 0.1)
				(type default)
			)
			(layer "B.Fab")
		)
		(fp_line
			(start -0.299974 -0.150114)
			(end -0.299974 0.150114)
			(stroke
				(width 0.1)
				(type default)
			)
			(layer "B.Fab")
		)
		(fp_line
			(start 0.299974 0.150114)
			(end 0.299974 -0.150114)
			(stroke
				(width 0.1)
				(type default)
			)
			(layer "B.Fab")
		)
		(fp_line
			(start -0.299974 0.150114)
			(end 0.299974 0.150114)
			(stroke
				(width 0.1)
				(type default)
			)
			(layer "B.Fab")
		)
		(pad "1" smd rect
			(at 0.2667 0 270)
			(size 0.3048 0.381)
			(layers "B.Cu" "B.Mask" "B.Paste")
			(net "P0V9_CPU0_RT0_2A_2D")
		)
		(pad "2" smd rect
			(at -0.2667 0 270)
			(size 0.3048 0.381)
			(layers "B.Cu" "B.Mask" "B.Paste")
			(net "GND")
		)
	)
	(footprint ""
		(layer "B.Cu")
		(at 416.200082 -416.899344 90)
		(property "Reference" "C6625"
			(at 0 0 90)
			(layer "B.SilkS")
			(hide yes)
			(effects
				(font
					(size 1.27 1.27)
				)
				(justify mirror)
			)
		)
		(property "Value" ""
			(at 0 0 90)
			(layer "B.Fab")
			(effects
				(font
					(size 1.27 1.27)
				)
				(justify mirror)
			)
		)
		(duplicate_pad_numbers_are_jumpers no)
		(fp_line
			(start 0.299974 -0.150114)
			(end -0.299974 -0.150114)
			(stroke
				(width 0.1)
				(type default)
			)
			(layer "B.Fab")
		)
		(fp_line
			(start -0.299974 -0.150114)
			(end -0.299974 0.150114)
			(stroke
				(width 0.1)
				(type default)
			)
			(layer "B.Fab")
		)
		(fp_line
			(start 0.299974 0.150114)
			(end 0.299974 -0.150114)
			(stroke
				(width 0.1)
				(type default)
			)
			(layer "B.Fab")
		)
		(fp_line
			(start -0.299974 0.150114)
			(end 0.299974 0.150114)
			(stroke
				(width 0.1)
				(type default)
			)
			(layer "B.Fab")
		)
		(pad "1" smd rect
			(at 0.2667 0 270)
			(size 0.3048 0.381)
			(layers "B.Cu" "B.Mask" "B.Paste")
			(net "P5E_CPU0_P3_TX_BUF_C_DP<14>")
		)
		(pad "2" smd rect
			(at -0.2667 0 270)
			(size 0.3048 0.381)
			(layers "B.Cu" "B.Mask" "B.Paste")
			(net "P5E_CPU0_P3_TX_BUF_DP<14>")
		)
	)
	(footprint ""
		(layer "B.Cu")
		(at 301.562008 -389.444738)
		(property "Reference" "C7010"
			(at 0 0 0)
			(layer "B.SilkS")
			(hide yes)
			(effects
				(font
					(size 1.27 1.27)
				)
				(justify mirror)
			)
		)
		(property "Value" ""
			(at 0 0 0)
			(layer "B.Fab")
			(effects
				(font
					(size 1.27 1.27)
				)
				(justify mirror)
			)
		)
		(duplicate_pad_numbers_are_jumpers no)
		(fp_line
			(start -1.524 -0.762)
			(end -1.524 0.762)
			(stroke
				(width 0.1524)
				(type default)
			)
			(layer "B.SilkS")
		)
		(fp_line
			(start -1.524 0.762)
			(end 1.524 0.762)
			(stroke
				(width 0.1524)
				(type default)
			)
			(layer "B.SilkS")
		)
		(fp_line
			(start 1.524 -0.762)
			(end -1.524 -0.762)
			(stroke
				(width 0.1524)
				(type default)
			)
			(layer "B.SilkS")
		)
		(fp_line
			(start 1.524 0.762)
			(end 1.524 -0.762)
			(stroke
				(width 0.1524)
				(type default)
			)
			(layer "B.SilkS")
		)
		(fp_line
			(start -1.1049 -0.724916)
			(end 1.1049 -0.724916)
			(stroke
				(width 0.1)
				(type default)
			)
			(layer "B.Fab")
		)
		(fp_line
			(start -1.1049 0.724916)
			(end -1.1049 -0.724916)
			(stroke
				(width 0.1)
				(type default)
			)
			(layer "B.Fab")
		)
		(fp_line
			(start 1.1049 -0.724916)
			(end 1.1049 0.724916)
			(stroke
				(width 0.1)
				(type default)
			)
			(layer "B.Fab")
		)
		(fp_line
			(start 1.1049 0.724916)
			(end -1.1049 0.724916)
			(stroke
				(width 0.1)
				(type default)
			)
			(layer "B.Fab")
		)
		(pad "1" smd rect
			(at 0.889 0)
			(size 1.016 1.27)
			(layers "B.Cu" "B.Mask" "B.Paste")
			(net "P0V9_CPU0_RT0_2A")
		)
		(pad "2" smd rect
			(at -0.889 0)
			(size 1.016 1.27)
			(layers "B.Cu" "B.Mask" "B.Paste")
			(net "GND")
		)
	)
	(footprint ""
		(layer "B.Cu")
		(at 52.74564 -426.003212 90)
		(property "Reference" "R3512"
			(at 0 0 90)
			(layer "B.SilkS")
			(hide yes)
			(effects
				(font
					(size 1.27 1.27)
				)
				(justify mirror)
			)
		)
		(property "Value" ""
			(at 0 0 90)
			(layer "B.Fab")
			(effects
				(font
					(size 1.27 1.27)
				)
				(justify mirror)
			)
		)
		(duplicate_pad_numbers_are_jumpers no)
		(fp_line
			(start 0.7874 -0.4064)
			(end -0.7874 -0.4064)
			(stroke
				(width 0.1524)
				(type default)
			)
			(layer "B.SilkS")
		)
		(fp_line
			(start -0.7874 -0.4064)
			(end -0.7874 0.4064)
			(stroke
				(width 0.1524)
				(type default)
			)
			(layer "B.SilkS")
		)
		(fp_line
			(start 0.7874 0.4064)
			(end 0.7874 -0.4064)
			(stroke
				(width 0.1524)
				(type default)
			)
			(layer "B.SilkS")
		)
		(fp_line
			(start -0.7874 0.4064)
			(end 0.7874 0.4064)
			(stroke
				(width 0.1524)
				(type default)
			)
			(layer "B.SilkS")
		)
		(fp_line
			(start 0.67945 -0.305054)
			(end 0.12065 -0.305054)
			(stroke
				(width 0.1)
				(type default)
			)
			(layer "B.Fab")
		)
		(fp_line
			(start 0.12065 -0.305054)
			(end 0.12065 -0.2794)
			(stroke
				(width 0.1)
				(type default)
			)
			(layer "B.Fab")
		)
		(fp_line
			(start -0.12065 -0.3048)
			(end -0.67945 -0.3048)
			(stroke
				(width 0.1)
				(type default)
			)
			(layer "B.Fab")
		)
		(fp_line
			(start -0.67945 -0.3048)
			(end -0.67945 0.3048)
			(stroke
				(width 0.1)
				(type default)
			)
			(layer "B.Fab")
		)
		(fp_line
			(start 0.12065 -0.2794)
			(end -0.12065 -0.2794)
			(stroke
				(width 0.1)
				(type default)
			)
			(layer "B.Fab")
		)
		(fp_line
			(start -0.12065 -0.2794)
			(end -0.12065 -0.3048)
			(stroke
				(width 0.1)
				(type default)
			)
			(layer "B.Fab")
		)
		(fp_line
			(start 0.12065 0.2794)
			(end 0.12065 0.3048)
			(stroke
				(width 0.1)
				(type default)
			)
			(layer "B.Fab")
		)
		(fp_line
			(start -0.120396 0.2794)
			(end 0.12065 0.2794)
			(stroke
				(width 0.1)
				(type default)
			)
			(layer "B.Fab")
		)
		(fp_line
			(start 0.67945 0.3048)
			(end 0.67945 -0.305054)
			(stroke
				(width 0.1)
				(type default)
			)
			(layer "B.Fab")
		)
		(fp_line
			(start 0.12065 0.3048)
			(end 0.67945 0.3048)
			(stroke
				(width 0.1)
				(type default)
			)
			(layer "B.Fab")
		)
		(fp_line
			(start -0.120396 0.3048)
			(end -0.120396 0.2794)
			(stroke
				(width 0.1)
				(type default)
			)
			(layer "B.Fab")
		)
		(fp_line
			(start -0.67945 0.3048)
			(end -0.120396 0.3048)
			(stroke
				(width 0.1)
				(type default)
			)
			(layer "B.Fab")
		)
		(pad "1" smd circle
			(at 0.40005 0 270)
			(size 0 0)
			(layers "B.Cu" "B.Mask" "B.Paste")
			(net "P3V3_AUX")
		)
		(pad "2" smd circle
			(at -0.40005 0 270)
			(size 0 0)
			(layers "B.Cu" "B.Mask" "B.Paste")
			(net "FM_GPU_PWRGD")
		)
	)
	(footprint ""
		(layer "B.Cu")
		(at 58.65241 -151.779224 180)
		(property "Reference" "PC87"
			(at 0 0 0)
			(layer "B.SilkS")
			(hide yes)
			(effects
				(font
					(size 1.27 1.27)
				)
				(justify mirror)
			)
		)
		(property "Value" ""
			(at 0 0 0)
			(layer "B.Fab")
			(effects
				(font
					(size 1.27 1.27)
				)
				(justify mirror)
			)
		)
		(duplicate_pad_numbers_are_jumpers no)
		(fp_line
			(start 1.524 0.762)
			(end 1.524 -0.762)
			(stroke
				(width 0.1524)
				(type default)
			)
			(layer "B.SilkS")
		)
		(fp_line
			(start 1.524 -0.762)
			(end -1.524 -0.762)
			(stroke
				(width 0.1524)
				(type default)
			)
			(layer "B.SilkS")
		)
		(fp_line
			(start -1.524 0.762)
			(end 1.524 0.762)
			(stroke
				(width 0.1524)
				(type default)
			)
			(layer "B.SilkS")
		)
		(fp_line
			(start -1.524 -0.762)
			(end -1.524 0.762)
			(stroke
				(width 0.1524)
				(type default)
			)
			(layer "B.SilkS")
		)
		(fp_line
			(start 1.1049 0.724916)
			(end -1.1049 0.724916)
			(stroke
				(width 0.1)
				(type default)
			)
			(layer "B.Fab")
		)
		(fp_line
			(start 1.1049 -0.724916)
			(end 1.1049 0.724916)
			(stroke
				(width 0.1)
				(type default)
			)
			(layer "B.Fab")
		)
		(fp_line
			(start -1.1049 0.724916)
			(end -1.1049 -0.724916)
			(stroke
				(width 0.1)
				(type default)
			)
			(layer "B.Fab")
		)
		(fp_line
			(start -1.1049 -0.724916)
			(end 1.1049 -0.724916)
			(stroke
				(width 0.1)
				(type default)
			)
			(layer "B.Fab")
		)
		(pad "1" smd rect
			(at 0.889 0 180)
			(size 1.016 1.27)
			(layers "B.Cu" "B.Mask" "B.Paste")
			(net "PVDD18_S5_P1")
		)
		(pad "2" smd rect
			(at -0.889 0 180)
			(size 1.016 1.27)
			(layers "B.Cu" "B.Mask" "B.Paste")
			(net "GND")
		)
	)
	(footprint ""
		(layer "B.Cu")
		(at 156.355034 -199.234552 90)
		(property "Reference" "R524"
			(at 0 0 90)
			(layer "B.SilkS")
			(hide yes)
			(effects
				(font
					(size 1.27 1.27)
				)
				(justify mirror)
			)
		)
		(property "Value" ""
			(at 0 0 90)
			(layer "B.Fab")
			(effects
				(font
					(size 1.27 1.27)
				)
				(justify mirror)
			)
		)
		(duplicate_pad_numbers_are_jumpers no)
		(fp_line
			(start 0.7874 -0.4064)
			(end -0.7874 -0.4064)
			(stroke
				(width 0.1524)
				(type default)
			)
			(layer "B.SilkS")
		)
		(fp_line
			(start -0.7874 -0.4064)
			(end -0.7874 0.4064)
			(stroke
				(width 0.1524)
				(type default)
			)
			(layer "B.SilkS")
		)
		(fp_line
			(start 0.7874 0.4064)
			(end 0.7874 -0.4064)
			(stroke
				(width 0.1524)
				(type default)
			)
			(layer "B.SilkS")
		)
		(fp_line
			(start -0.7874 0.4064)
			(end 0.7874 0.4064)
			(stroke
				(width 0.1524)
				(type default)
			)
			(layer "B.SilkS")
		)
		(fp_line
			(start 0.67945 -0.305054)
			(end 0.12065 -0.305054)
			(stroke
				(width 0.1)
				(type default)
			)
			(layer "B.Fab")
		)
		(fp_line
			(start 0.12065 -0.305054)
			(end 0.12065 -0.2794)
			(stroke
				(width 0.1)
				(type default)
			)
			(layer "B.Fab")
		)
		(fp_line
			(start -0.12065 -0.3048)
			(end -0.67945 -0.3048)
			(stroke
				(width 0.1)
				(type default)
			)
			(layer "B.Fab")
		)
		(fp_line
			(start -0.67945 -0.3048)
			(end -0.67945 0.3048)
			(stroke
				(width 0.1)
				(type default)
			)
			(layer "B.Fab")
		)
		(fp_line
			(start 0.12065 -0.2794)
			(end -0.12065 -0.2794)
			(stroke
				(width 0.1)
				(type default)
			)
			(layer "B.Fab")
		)
		(fp_line
			(start -0.12065 -0.2794)
			(end -0.12065 -0.3048)
			(stroke
				(width 0.1)
				(type default)
			)
			(layer "B.Fab")
		)
		(fp_line
			(start 0.12065 0.2794)
			(end 0.12065 0.3048)
			(stroke
				(width 0.1)
				(type default)
			)
			(layer "B.Fab")
		)
		(fp_line
			(start -0.120396 0.2794)
			(end 0.12065 0.2794)
			(stroke
				(width 0.1)
				(type default)
			)
			(layer "B.Fab")
		)
		(fp_line
			(start 0.67945 0.3048)
			(end 0.67945 -0.305054)
			(stroke
				(width 0.1)
				(type default)
			)
			(layer "B.Fab")
		)
		(fp_line
			(start 0.12065 0.3048)
			(end 0.67945 0.3048)
			(stroke
				(width 0.1)
				(type default)
			)
			(layer "B.Fab")
		)
		(fp_line
			(start -0.120396 0.3048)
			(end -0.120396 0.2794)
			(stroke
				(width 0.1)
				(type default)
			)
			(layer "B.Fab")
		)
		(fp_line
			(start -0.67945 0.3048)
			(end -0.120396 0.3048)
			(stroke
				(width 0.1)
				(type default)
			)
			(layer "B.Fab")
		)
		(pad "1" smd circle
			(at 0.40005 0 270)
			(size 0 0)
			(layers "B.Cu" "B.Mask" "B.Paste")
			(net "PVDD18_S5_P1")
		)
		(pad "2" smd circle
			(at -0.40005 0 270)
			(size 0 0)
			(layers "B.Cu" "B.Mask" "B.Paste")
			(net "JTAG_CPU1_TDI")
		)
	)
	(footprint ""
		(layer "B.Cu")
		(at 122.891296 -390.560052 90)
		(property "Reference" "C438"
			(at 0 0 90)
			(layer "B.SilkS")
			(hide yes)
			(effects
				(font
					(size 1.27 1.27)
				)
				(justify mirror)
			)
		)
		(property "Value" ""
			(at 0 0 90)
			(layer "B.Fab")
			(effects
				(font
					(size 1.27 1.27)
				)
				(justify mirror)
			)
		)
		(duplicate_pad_numbers_are_jumpers no)
		(fp_line
			(start 0.7874 -0.4064)
			(end -0.7874 -0.4064)
			(stroke
				(width 0.1524)
				(type default)
			)
			(layer "B.SilkS")
		)
		(fp_line
			(start -0.7874 -0.4064)
			(end -0.7874 0.4064)
			(stroke
				(width 0.1524)
				(type default)
			)
			(layer "B.SilkS")
		)
		(fp_line
			(start 0.7874 0.4064)
			(end 0.7874 -0.4064)
			(stroke
				(width 0.1524)
				(type default)
			)
			(layer "B.SilkS")
		)
		(fp_line
			(start -0.7874 0.4064)
			(end 0.7874 0.4064)
			(stroke
				(width 0.1524)
				(type default)
			)
			(layer "B.SilkS")
		)
		(fp_line
			(start 0.67945 -0.305054)
			(end 0.12065 -0.305054)
			(stroke
				(width 0.1)
				(type default)
			)
			(layer "B.Fab")
		)
		(fp_line
			(start 0.12065 -0.305054)
			(end 0.12065 -0.2794)
			(stroke
				(width 0.1)
				(type default)
			)
			(layer "B.Fab")
		)
		(fp_line
			(start -0.12065 -0.3048)
			(end -0.67945 -0.3048)
			(stroke
				(width 0.1)
				(type default)
			)
			(layer "B.Fab")
		)
		(fp_line
			(start -0.67945 -0.3048)
			(end -0.67945 0.3048)
			(stroke
				(width 0.1)
				(type default)
			)
			(layer "B.Fab")
		)
		(fp_line
			(start 0.12065 -0.2794)
			(end -0.12065 -0.2794)
			(stroke
				(width 0.1)
				(type default)
			)
			(layer "B.Fab")
		)
		(fp_line
			(start -0.12065 -0.2794)
			(end -0.12065 -0.3048)
			(stroke
				(width 0.1)
				(type default)
			)
			(layer "B.Fab")
		)
		(fp_line
			(start 0.12065 0.2794)
			(end 0.12065 0.3048)
			(stroke
				(width 0.1)
				(type default)
			)
			(layer "B.Fab")
		)
		(fp_line
			(start -0.120396 0.2794)
			(end 0.12065 0.2794)
			(stroke
				(width 0.1)
				(type default)
			)
			(layer "B.Fab")
		)
		(fp_line
			(start 0.67945 0.3048)
			(end 0.67945 -0.305054)
			(stroke
				(width 0.1)
				(type default)
			)
			(layer "B.Fab")
		)
		(fp_line
			(start 0.12065 0.3048)
			(end 0.67945 0.3048)
			(stroke
				(width 0.1)
				(type default)
			)
			(layer "B.Fab")
		)
		(fp_line
			(start -0.120396 0.3048)
			(end -0.120396 0.2794)
			(stroke
				(width 0.1)
				(type default)
			)
			(layer "B.Fab")
		)
		(fp_line
			(start -0.67945 0.3048)
			(end -0.120396 0.3048)
			(stroke
				(width 0.1)
				(type default)
			)
			(layer "B.Fab")
		)
		(pad "1" smd circle
			(at 0.40005 0 270)
			(size 0 0)
			(layers "B.Cu" "B.Mask" "B.Paste")
			(net "P1V8_CPU1_RT3_1A")
		)
		(pad "2" smd circle
			(at -0.40005 0 270)
			(size 0 0)
			(layers "B.Cu" "B.Mask" "B.Paste")
			(net "GND")
		)
	)
	(footprint ""
		(layer "B.Cu")
		(at 47.37862 -386.766562 90)
		(property "Reference" "C135"
			(at 0 0 90)
			(layer "B.SilkS")
			(hide yes)
			(effects
				(font
					(size 1.27 1.27)
				)
				(justify mirror)
			)
		)
		(property "Value" ""
			(at 0 0 90)
			(layer "B.Fab")
			(effects
				(font
					(size 1.27 1.27)
				)
				(justify mirror)
			)
		)
		(duplicate_pad_numbers_are_jumpers no)
		(fp_line
			(start 0.299974 -0.150114)
			(end -0.299974 -0.150114)
			(stroke
				(width 0.1)
				(type default)
			)
			(layer "B.Fab")
		)
		(fp_line
			(start -0.299974 -0.150114)
			(end -0.299974 0.150114)
			(stroke
				(width 0.1)
				(type default)
			)
			(layer "B.Fab")
		)
		(fp_line
			(start 0.299974 0.150114)
			(end 0.299974 -0.150114)
			(stroke
				(width 0.1)
				(type default)
			)
			(layer "B.Fab")
		)
		(fp_line
			(start -0.299974 0.150114)
			(end 0.299974 0.150114)
			(stroke
				(width 0.1)
				(type default)
			)
			(layer "B.Fab")
		)
		(pad "1" smd rect
			(at 0.2667 0 270)
			(size 0.3048 0.381)
			(layers "B.Cu" "B.Mask" "B.Paste")
			(net "P0V9_CPU1_RT0_2A")
		)
		(pad "2" smd rect
			(at -0.2667 0 270)
			(size 0.3048 0.381)
			(layers "B.Cu" "B.Mask" "B.Paste")
			(net "GND")
		)
	)
	(footprint ""
		(layer "B.Cu")
		(at 73.889616 -393.242546 180)
		(property "Reference" "R712"
			(at 0 0 0)
			(layer "B.SilkS")
			(hide yes)
			(effects
				(font
					(size 1.27 1.27)
				)
				(justify mirror)
			)
		)
		(property "Value" ""
			(at 0 0 0)
			(layer "B.Fab")
			(effects
				(font
					(size 1.27 1.27)
				)
				(justify mirror)
			)
		)
		(duplicate_pad_numbers_are_jumpers no)
		(fp_line
			(start 1.2954 0.5842)
			(end 1.2954 -0.5842)
			(stroke
				(width 0.1524)
				(type default)
			)
			(layer "B.SilkS")
		)
		(fp_line
			(start 1.2954 -0.5842)
			(end -1.2954 -0.5842)
			(stroke
				(width 0.1524)
				(type default)
			)
			(layer "B.SilkS")
		)
		(fp_line
			(start -1.2954 0.5842)
			(end 1.2954 0.5842)
			(stroke
				(width 0.1524)
				(type default)
			)
			(layer "B.SilkS")
		)
		(fp_line
			(start -1.2954 -0.5842)
			(end -1.2954 0.5842)
			(stroke
				(width 0.1524)
				(type default)
			)
			(layer "B.SilkS")
		)
		(fp_line
			(start 1.1938 0.4064)
			(end 1.1938 -0.406654)
			(stroke
				(width 0.1)
				(type default)
			)
			(layer "B.Fab")
		)
		(fp_line
			(start 1.1938 -0.406654)
			(end 0.8636 -0.406654)
			(stroke
				(width 0.1)
				(type default)
			)
			(layer "B.Fab")
		)
		(fp_line
			(start 0.8636 0.4572)
			(end 0.8636 0.4318)
			(stroke
				(width 0.1)
				(type default)
			)
			(layer "B.Fab")
		)
		(fp_line
			(start 0.8636 0.4318)
			(end 0.8636 0.4064)
			(stroke
				(width 0.1)
				(type default)
			)
			(layer "B.Fab")
		)
		(fp_line
			(start 0.8636 0.4064)
			(end 1.1938 0.4064)
			(stroke
				(width 0.1)
				(type default)
			)
			(layer "B.Fab")
		)
		(fp_line
			(start 0.8636 -0.406654)
			(end 0.8636 -0.4572)
			(stroke
				(width 0.1)
				(type default)
			)
			(layer "B.Fab")
		)
		(fp_line
			(start 0.8636 -0.4572)
			(end -0.8636 -0.4572)
			(stroke
				(width 0.1)
				(type default)
			)
			(layer "B.Fab")
		)
		(fp_line
			(start -0.8636 0.4572)
			(end 0.8636 0.4572)
			(stroke
				(width 0.1)
				(type default)
			)
			(layer "B.Fab")
		)
		(fp_line
			(start -0.8636 0.4064)
			(end -0.8636 0.4572)
			(stroke
				(width 0.1)
				(type default)
			)
			(layer "B.Fab")
		)
		(fp_line
			(start -0.8636 -0.406654)
			(end -1.1938 -0.406654)
			(stroke
				(width 0.1)
				(type default)
			)
			(layer "B.Fab")
		)
		(fp_line
			(start -0.8636 -0.4572)
			(end -0.8636 -0.406654)
			(stroke
				(width 0.1)
				(type default)
			)
			(layer "B.Fab")
		)
		(fp_line
			(start -1.1938 0.4064)
			(end -0.8636 0.4064)
			(stroke
				(width 0.1)
				(type default)
			)
			(layer "B.Fab")
		)
		(fp_line
			(start -1.1938 -0.406654)
			(end -1.1938 0.4064)
			(stroke
				(width 0.1)
				(type default)
			)
			(layer "B.Fab")
		)
		(pad "1" smd rect
			(at 0.7366 0 90)
			(size 0.7112 0.8128)
			(layers "B.Cu" "B.Mask" "B.Paste")
			(net "P0V9_CPU1_RT1_2A_2D")
		)
		(pad "2" smd rect
			(at -0.7366 0 90)
			(size 0.7112 0.8128)
			(layers "B.Cu" "B.Mask" "B.Paste")
			(net "P0V9_CPU1_RT1_2A")
		)
	)
	(footprint ""
		(layer "B.Cu")
		(at 293.12997 -346.784168 90)
		(property "Reference" "PC153_2"
			(at 0 0 90)
			(layer "B.SilkS")
			(hide yes)
			(effects
				(font
					(size 1.27 1.27)
				)
				(justify mirror)
			)
		)
		(property "Value" ""
			(at 0 0 90)
			(layer "B.Fab")
			(effects
				(font
					(size 1.27 1.27)
				)
				(justify mirror)
			)
		)
		(duplicate_pad_numbers_are_jumpers no)
		(fp_line
			(start 1.524 -0.762)
			(end -1.524 -0.762)
			(stroke
				(width 0.1524)
				(type default)
			)
			(layer "B.SilkS")
		)
		(fp_line
			(start -1.524 -0.762)
			(end -1.524 0.762)
			(stroke
				(width 0.1524)
				(type default)
			)
			(layer "B.SilkS")
		)
		(fp_line
			(start 1.524 0.762)
			(end 1.524 -0.762)
			(stroke
				(width 0.1524)
				(type default)
			)
			(layer "B.SilkS")
		)
		(fp_line
			(start -1.524 0.762)
			(end 1.524 0.762)
			(stroke
				(width 0.1524)
				(type default)
			)
			(layer "B.SilkS")
		)
		(fp_line
			(start 1.1049 -0.724916)
			(end 1.1049 0.724916)
			(stroke
				(width 0.1)
				(type default)
			)
			(layer "B.Fab")
		)
		(fp_line
			(start -1.1049 -0.724916)
			(end 1.1049 -0.724916)
			(stroke
				(width 0.1)
				(type default)
			)
			(layer "B.Fab")
		)
		(fp_line
			(start 1.1049 0.724916)
			(end -1.1049 0.724916)
			(stroke
				(width 0.1)
				(type default)
			)
			(layer "B.Fab")
		)
		(fp_line
			(start -1.1049 0.724916)
			(end -1.1049 -0.724916)
			(stroke
				(width 0.1)
				(type default)
			)
			(layer "B.Fab")
		)
		(pad "1" smd rect
			(at 0.889 0 90)
			(size 1.016 1.27)
			(layers "B.Cu" "B.Mask" "B.Paste")
			(net "SW_P12V_AUX_PVDDIO_P0_FLT")
		)
		(pad "2" smd rect
			(at -0.889 0 90)
			(size 1.016 1.27)
			(layers "B.Cu" "B.Mask" "B.Paste")
			(net "GND")
		)
	)
	(footprint ""
		(layer "B.Cu")
		(at 119.621554 -177.007012 90)
		(property "Reference" "PC344_1"
			(at 0 0 90)
			(layer "B.SilkS")
			(hide yes)
			(effects
				(font
					(size 1.27 1.27)
				)
				(justify mirror)
			)
		)
		(property "Value" ""
			(at 0 0 90)
			(layer "B.Fab")
			(effects
				(font
					(size 1.27 1.27)
				)
				(justify mirror)
			)
		)
		(duplicate_pad_numbers_are_jumpers no)
		(fp_line
			(start 1.524 -0.762)
			(end -1.524 -0.762)
			(stroke
				(width 0.1524)
				(type default)
			)
			(layer "B.SilkS")
		)
		(fp_line
			(start -1.524 -0.762)
			(end -1.524 0.762)
			(stroke
				(width 0.1524)
				(type default)
			)
			(layer "B.SilkS")
		)
		(fp_line
			(start 1.524 0.762)
			(end 1.524 -0.762)
			(stroke
				(width 0.1524)
				(type default)
			)
			(layer "B.SilkS")
		)
		(fp_line
			(start -1.524 0.762)
			(end 1.524 0.762)
			(stroke
				(width 0.1524)
				(type default)
			)
			(layer "B.SilkS")
		)
		(fp_line
			(start 1.1049 -0.724916)
			(end 1.1049 0.724916)
			(stroke
				(width 0.1)
				(type default)
			)
			(layer "B.Fab")
		)
		(fp_line
			(start -1.1049 -0.724916)
			(end 1.1049 -0.724916)
			(stroke
				(width 0.1)
				(type default)
			)
			(layer "B.Fab")
		)
		(fp_line
			(start 1.1049 0.724916)
			(end -1.1049 0.724916)
			(stroke
				(width 0.1)
				(type default)
			)
			(layer "B.Fab")
		)
		(fp_line
			(start -1.1049 0.724916)
			(end -1.1049 -0.724916)
			(stroke
				(width 0.1)
				(type default)
			)
			(layer "B.Fab")
		)
		(pad "1" smd rect
			(at 0.889 0 90)
			(size 1.016 1.27)
			(layers "B.Cu" "B.Mask" "B.Paste")
			(net "PVDDCR_SOC_P1")
		)
		(pad "2" smd rect
			(at -0.889 0 90)
			(size 1.016 1.27)
			(layers "B.Cu" "B.Mask" "B.Paste")
			(net "GND")
		)
	)
	(footprint ""
		(layer "B.Cu")
		(at 75.7936 -385.58216 180)
		(property "Reference" "R785"
			(at 0 0 0)
			(layer "B.SilkS")
			(hide yes)
			(effects
				(font
					(size 1.27 1.27)
				)
				(justify mirror)
			)
		)
		(property "Value" ""
			(at 0 0 0)
			(layer "B.Fab")
			(effects
				(font
					(size 1.27 1.27)
				)
				(justify mirror)
			)
		)
		(duplicate_pad_numbers_are_jumpers no)
		(fp_line
			(start 0.32512 0.175006)
			(end 0.32512 -0.175006)
			(stroke
				(width 0.1)
				(type default)
			)
			(layer "B.Fab")
		)
		(fp_line
			(start 0.32512 -0.175006)
			(end -0.32512 -0.175006)
			(stroke
				(width 0.1)
				(type default)
			)
			(layer "B.Fab")
		)
		(fp_line
			(start -0.32512 0.175006)
			(end 0.32512 0.175006)
			(stroke
				(width 0.1)
				(type default)
			)
			(layer "B.Fab")
		)
		(fp_line
			(start -0.32512 -0.175006)
			(end -0.32512 0.175006)
			(stroke
				(width 0.1)
				(type default)
			)
			(layer "B.Fab")
		)
		(pad "1" smd rect
			(at 0.2667 0)
			(size 0.3048 0.381)
			(layers "B.Cu" "B.Mask" "B.Paste")
			(net "TEST0_RT_CPU1_P1")
		)
		(pad "2" smd rect
			(at -0.2667 0 180)
			(size 0.3048 0.381)
			(layers "B.Cu" "B.Mask" "B.Paste")
			(net "GND")
		)
	)
	(footprint ""
		(layer "B.Cu")
		(at 315.378338 -395.148562 90)
		(property "Reference" "C578"
			(at 0 0 90)
			(layer "B.SilkS")
			(hide yes)
			(effects
				(font
					(size 1.27 1.27)
				)
				(justify mirror)
			)
		)
		(property "Value" ""
			(at 0 0 90)
			(layer "B.Fab")
			(effects
				(font
					(size 1.27 1.27)
				)
				(justify mirror)
			)
		)
		(duplicate_pad_numbers_are_jumpers no)
		(fp_line
			(start 0.299974 -0.150114)
			(end -0.299974 -0.150114)
			(stroke
				(width 0.1)
				(type default)
			)
			(layer "B.Fab")
		)
		(fp_line
			(start -0.299974 -0.150114)
			(end -0.299974 0.150114)
			(stroke
				(width 0.1)
				(type default)
			)
			(layer "B.Fab")
		)
		(fp_line
			(start 0.299974 0.150114)
			(end 0.299974 -0.150114)
			(stroke
				(width 0.1)
				(type default)
			)
			(layer "B.Fab")
		)
		(fp_line
			(start -0.299974 0.150114)
			(end 0.299974 0.150114)
			(stroke
				(width 0.1)
				(type default)
			)
			(layer "B.Fab")
		)
		(pad "1" smd rect
			(at 0.2667 0 270)
			(size 0.3048 0.381)
			(layers "B.Cu" "B.Mask" "B.Paste")
			(net "P0V9_CPU0_RT_2D")
		)
		(pad "2" smd rect
			(at -0.2667 0 270)
			(size 0.3048 0.381)
			(layers "B.Cu" "B.Mask" "B.Paste")
			(net "GND")
		)
	)
	(footprint ""
		(layer "B.Cu")
		(at 94.435422 -60.820808)
		(property "Reference" "R3807"
			(at 0 0 0)
			(layer "B.SilkS")
			(hide yes)
			(effects
				(font
					(size 1.27 1.27)
				)
				(justify mirror)
			)
		)
		(property "Value" ""
			(at 0 0 0)
			(layer "B.Fab")
			(effects
				(font
					(size 1.27 1.27)
				)
				(justify mirror)
			)
		)
		(duplicate_pad_numbers_are_jumpers no)
		(fp_line
			(start -0.7874 -0.4064)
			(end -0.7874 0.4064)
			(stroke
				(width 0.1524)
				(type default)
			)
			(layer "B.SilkS")
		)
		(fp_line
			(start -0.7874 0.4064)
			(end 0.7874 0.4064)
			(stroke
				(width 0.1524)
				(type default)
			)
			(layer "B.SilkS")
		)
		(fp_line
			(start 0.7874 -0.4064)
			(end -0.7874 -0.4064)
			(stroke
				(width 0.1524)
				(type default)
			)
			(layer "B.SilkS")
		)
		(fp_line
			(start 0.7874 0.4064)
			(end 0.7874 -0.4064)
			(stroke
				(width 0.1524)
				(type default)
			)
			(layer "B.SilkS")
		)
		(fp_line
			(start -0.67945 -0.3048)
			(end -0.67945 0.3048)
			(stroke
				(width 0.1)
				(type default)
			)
			(layer "B.Fab")
		)
		(fp_line
			(start -0.67945 0.3048)
			(end -0.120396 0.3048)
			(stroke
				(width 0.1)
				(type default)
			)
			(layer "B.Fab")
		)
		(fp_line
			(start -0.12065 -0.3048)
			(end -0.67945 -0.3048)
			(stroke
				(width 0.1)
				(type default)
			)
			(layer "B.Fab")
		)
		(fp_line
			(start -0.12065 -0.2794)
			(end -0.12065 -0.3048)
			(stroke
				(width 0.1)
				(type default)
			)
			(layer "B.Fab")
		)
		(fp_line
			(start -0.120396 0.2794)
			(end 0.12065 0.2794)
			(stroke
				(width 0.1)
				(type default)
			)
			(layer "B.Fab")
		)
		(fp_line
			(start -0.120396 0.3048)
			(end -0.120396 0.2794)
			(stroke
				(width 0.1)
				(type default)
			)
			(layer "B.Fab")
		)
		(fp_line
			(start 0.12065 -0.305054)
			(end 0.12065 -0.2794)
			(stroke
				(width 0.1)
				(type default)
			)
			(layer "B.Fab")
		)
		(fp_line
			(start 0.12065 -0.2794)
			(end -0.12065 -0.2794)
			(stroke
				(width 0.1)
				(type default)
			)
			(layer "B.Fab")
		)
		(fp_line
			(start 0.12065 0.2794)
			(end 0.12065 0.3048)
			(stroke
				(width 0.1)
				(type default)
			)
			(layer "B.Fab")
		)
		(fp_line
			(start 0.12065 0.3048)
			(end 0.67945 0.3048)
			(stroke
				(width 0.1)
				(type default)
			)
			(layer "B.Fab")
		)
		(fp_line
			(start 0.67945 -0.305054)
			(end 0.12065 -0.305054)
			(stroke
				(width 0.1)
				(type default)
			)
			(layer "B.Fab")
		)
		(fp_line
			(start 0.67945 0.3048)
			(end 0.67945 -0.305054)
			(stroke
				(width 0.1)
				(type default)
			)
			(layer "B.Fab")
		)
		(pad "1" smd circle
			(at 0.40005 0 180)
			(size 0 0)
			(layers "B.Cu" "B.Mask" "B.Paste")
			(net "P3V3_OCP_UV_2_R1")
		)
		(pad "2" smd circle
			(at -0.40005 0 180)
			(size 0 0)
			(layers "B.Cu" "B.Mask" "B.Paste")
			(net "P3V3_OCP_UV_2")
		)
	)
	(footprint ""
		(layer "B.Cu")
		(at 125.895608 -38.87343 90)
		(property "Reference" "C6061"
			(at 0 0 90)
			(layer "B.SilkS")
			(hide yes)
			(effects
				(font
					(size 1.27 1.27)
				)
				(justify mirror)
			)
		)
		(property "Value" ""
			(at 0 0 90)
			(layer "B.Fab")
			(effects
				(font
					(size 1.27 1.27)
				)
				(justify mirror)
			)
		)
		(duplicate_pad_numbers_are_jumpers no)
		(fp_line
			(start 0.7874 -0.4064)
			(end -0.7874 -0.4064)
			(stroke
				(width 0.1524)
				(type default)
			)
			(layer "B.SilkS")
		)
		(fp_line
			(start -0.7874 -0.4064)
			(end -0.7874 0.4064)
			(stroke
				(width 0.1524)
				(type default)
			)
			(layer "B.SilkS")
		)
		(fp_line
			(start 0.7874 0.4064)
			(end 0.7874 -0.4064)
			(stroke
				(width 0.1524)
				(type default)
			)
			(layer "B.SilkS")
		)
		(fp_line
			(start -0.7874 0.4064)
			(end 0.7874 0.4064)
			(stroke
				(width 0.1524)
				(type default)
			)
			(layer "B.SilkS")
		)
		(fp_line
			(start 0.67945 -0.305054)
			(end 0.12065 -0.305054)
			(stroke
				(width 0.1)
				(type default)
			)
			(layer "B.Fab")
		)
		(fp_line
			(start 0.12065 -0.305054)
			(end 0.12065 -0.2794)
			(stroke
				(width 0.1)
				(type default)
			)
			(layer "B.Fab")
		)
		(fp_line
			(start -0.12065 -0.3048)
			(end -0.67945 -0.3048)
			(stroke
				(width 0.1)
				(type default)
			)
			(layer "B.Fab")
		)
		(fp_line
			(start -0.67945 -0.3048)
			(end -0.67945 0.3048)
			(stroke
				(width 0.1)
				(type default)
			)
			(layer "B.Fab")
		)
		(fp_line
			(start 0.12065 -0.2794)
			(end -0.12065 -0.2794)
			(stroke
				(width 0.1)
				(type default)
			)
			(layer "B.Fab")
		)
		(fp_line
			(start -0.12065 -0.2794)
			(end -0.12065 -0.3048)
			(stroke
				(width 0.1)
				(type default)
			)
			(layer "B.Fab")
		)
		(fp_line
			(start 0.12065 0.2794)
			(end 0.12065 0.3048)
			(stroke
				(width 0.1)
				(type default)
			)
			(layer "B.Fab")
		)
		(fp_line
			(start -0.120396 0.2794)
			(end 0.12065 0.2794)
			(stroke
				(width 0.1)
				(type default)
			)
			(layer "B.Fab")
		)
		(fp_line
			(start 0.67945 0.3048)
			(end 0.67945 -0.305054)
			(stroke
				(width 0.1)
				(type default)
			)
			(layer "B.Fab")
		)
		(fp_line
			(start 0.12065 0.3048)
			(end 0.67945 0.3048)
			(stroke
				(width 0.1)
				(type default)
			)
			(layer "B.Fab")
		)
		(fp_line
			(start -0.120396 0.3048)
			(end -0.120396 0.2794)
			(stroke
				(width 0.1)
				(type default)
			)
			(layer "B.Fab")
		)
		(fp_line
			(start -0.67945 0.3048)
			(end -0.120396 0.3048)
			(stroke
				(width 0.1)
				(type default)
			)
			(layer "B.Fab")
		)
		(pad "1" smd circle
			(at 0.40005 0 270)
			(size 0 0)
			(layers "B.Cu" "B.Mask" "B.Paste")
			(net "P1V2_AUX")
		)
		(pad "2" smd circle
			(at -0.40005 0 270)
			(size 0 0)
			(layers "B.Cu" "B.Mask" "B.Paste")
			(net "GND")
		)
	)
	(footprint ""
		(layer "B.Cu")
		(at 302.133 -358.14 180)
		(property "Reference" "R8045"
			(at 0 0 0)
			(layer "B.SilkS")
			(hide yes)
			(effects
				(font
					(size 1.27 1.27)
				)
				(justify mirror)
			)
		)
		(property "Value" ""
			(at 0 0 0)
			(layer "B.Fab")
			(effects
				(font
					(size 1.27 1.27)
				)
				(justify mirror)
			)
		)
		(duplicate_pad_numbers_are_jumpers no)
		(fp_line
			(start 0.7874 0.4064)
			(end 0.7874 -0.4064)
			(stroke
				(width 0.1524)
				(type default)
			)
			(layer "B.SilkS")
		)
		(fp_line
			(start 0.7874 -0.4064)
			(end -0.7874 -0.4064)
			(stroke
				(width 0.1524)
				(type default)
			)
			(layer "B.SilkS")
		)
		(fp_line
			(start -0.7874 0.4064)
			(end 0.7874 0.4064)
			(stroke
				(width 0.1524)
				(type default)
			)
			(layer "B.SilkS")
		)
		(fp_line
			(start -0.7874 -0.4064)
			(end -0.7874 0.4064)
			(stroke
				(width 0.1524)
				(type default)
			)
			(layer "B.SilkS")
		)
		(fp_line
			(start 0.67945 0.3048)
			(end 0.67945 -0.305054)
			(stroke
				(width 0.1)
				(type default)
			)
			(layer "B.Fab")
		)
		(fp_line
			(start 0.67945 -0.305054)
			(end 0.12065 -0.305054)
			(stroke
				(width 0.1)
				(type default)
			)
			(layer "B.Fab")
		)
		(fp_line
			(start 0.12065 0.3048)
			(end 0.67945 0.3048)
			(stroke
				(width 0.1)
				(type default)
			)
			(layer "B.Fab")
		)
		(fp_line
			(start 0.12065 0.2794)
			(end 0.12065 0.3048)
			(stroke
				(width 0.1)
				(type default)
			)
			(layer "B.Fab")
		)
		(fp_line
			(start 0.12065 -0.2794)
			(end -0.12065 -0.2794)
			(stroke
				(width 0.1)
				(type default)
			)
			(layer "B.Fab")
		)
		(fp_line
			(start 0.12065 -0.305054)
			(end 0.12065 -0.2794)
			(stroke
				(width 0.1)
				(type default)
			)
			(layer "B.Fab")
		)
		(fp_line
			(start -0.120396 0.3048)
			(end -0.120396 0.2794)
			(stroke
				(width 0.1)
				(type default)
			)
			(layer "B.Fab")
		)
		(fp_line
			(start -0.120396 0.2794)
			(end 0.12065 0.2794)
			(stroke
				(width 0.1)
				(type default)
			)
			(layer "B.Fab")
		)
		(fp_line
			(start -0.12065 -0.2794)
			(end -0.12065 -0.3048)
			(stroke
				(width 0.1)
				(type default)
			)
			(layer "B.Fab")
		)
		(fp_line
			(start -0.12065 -0.3048)
			(end -0.67945 -0.3048)
			(stroke
				(width 0.1)
				(type default)
			)
			(layer "B.Fab")
		)
		(fp_line
			(start -0.67945 0.3048)
			(end -0.120396 0.3048)
			(stroke
				(width 0.1)
				(type default)
			)
			(layer "B.Fab")
		)
		(fp_line
			(start -0.67945 -0.3048)
			(end -0.67945 0.3048)
			(stroke
				(width 0.1)
				(type default)
			)
			(layer "B.Fab")
		)
		(pad "1" smd circle
			(at 0.40005 0)
			(size 0 0)
			(layers "B.Cu" "B.Mask" "B.Paste")
			(net "PVDD18_S5_P0")
		)
		(pad "2" smd circle
			(at -0.40005 0)
			(size 0 0)
			(layers "B.Cu" "B.Mask" "B.Paste")
			(net "SVID_PVDDCR_CPU1_P0_SVD_R")
		)
	)
	(footprint ""
		(layer "B.Cu")
		(at 152.959054 -313.96305 90)
		(property "Reference" "R574"
			(at 0 0 90)
			(layer "B.SilkS")
			(hide yes)
			(effects
				(font
					(size 1.27 1.27)
				)
				(justify mirror)
			)
		)
		(property "Value" ""
			(at 0 0 90)
			(layer "B.Fab")
			(effects
				(font
					(size 1.27 1.27)
				)
				(justify mirror)
			)
		)
		(duplicate_pad_numbers_are_jumpers no)
		(fp_line
			(start 0.7874 -0.4064)
			(end -0.7874 -0.4064)
			(stroke
				(width 0.1524)
				(type default)
			)
			(layer "B.SilkS")
		)
		(fp_line
			(start -0.7874 -0.4064)
			(end -0.7874 0.4064)
			(stroke
				(width 0.1524)
				(type default)
			)
			(layer "B.SilkS")
		)
		(fp_line
			(start 0.7874 0.4064)
			(end 0.7874 -0.4064)
			(stroke
				(width 0.1524)
				(type default)
			)
			(layer "B.SilkS")
		)
		(fp_line
			(start -0.7874 0.4064)
			(end 0.7874 0.4064)
			(stroke
				(width 0.1524)
				(type default)
			)
			(layer "B.SilkS")
		)
		(fp_line
			(start 0.67945 -0.305054)
			(end 0.12065 -0.305054)
			(stroke
				(width 0.1)
				(type default)
			)
			(layer "B.Fab")
		)
		(fp_line
			(start 0.12065 -0.305054)
			(end 0.12065 -0.2794)
			(stroke
				(width 0.1)
				(type default)
			)
			(layer "B.Fab")
		)
		(fp_line
			(start -0.12065 -0.3048)
			(end -0.67945 -0.3048)
			(stroke
				(width 0.1)
				(type default)
			)
			(layer "B.Fab")
		)
		(fp_line
			(start -0.67945 -0.3048)
			(end -0.67945 0.3048)
			(stroke
				(width 0.1)
				(type default)
			)
			(layer "B.Fab")
		)
		(fp_line
			(start 0.12065 -0.2794)
			(end -0.12065 -0.2794)
			(stroke
				(width 0.1)
				(type default)
			)
			(layer "B.Fab")
		)
		(fp_line
			(start -0.12065 -0.2794)
			(end -0.12065 -0.3048)
			(stroke
				(width 0.1)
				(type default)
			)
			(layer "B.Fab")
		)
		(fp_line
			(start 0.12065 0.2794)
			(end 0.12065 0.3048)
			(stroke
				(width 0.1)
				(type default)
			)
			(layer "B.Fab")
		)
		(fp_line
			(start -0.120396 0.2794)
			(end 0.12065 0.2794)
			(stroke
				(width 0.1)
				(type default)
			)
			(layer "B.Fab")
		)
		(fp_line
			(start 0.67945 0.3048)
			(end 0.67945 -0.305054)
			(stroke
				(width 0.1)
				(type default)
			)
			(layer "B.Fab")
		)
		(fp_line
			(start 0.12065 0.3048)
			(end 0.67945 0.3048)
			(stroke
				(width 0.1)
				(type default)
			)
			(layer "B.Fab")
		)
		(fp_line
			(start -0.120396 0.3048)
			(end -0.120396 0.2794)
			(stroke
				(width 0.1)
				(type default)
			)
			(layer "B.Fab")
		)
		(fp_line
			(start -0.67945 0.3048)
			(end -0.120396 0.3048)
			(stroke
				(width 0.1)
				(type default)
			)
			(layer "B.Fab")
		)
		(pad "1" smd circle
			(at 0.40005 0 270)
			(size 0 0)
			(layers "B.Cu" "B.Mask" "B.Paste")
			(net "XTAL_CPU1_R_X32K_X1")
		)
		(pad "2" smd circle
			(at -0.40005 0 270)
			(size 0 0)
			(layers "B.Cu" "B.Mask" "B.Paste")
			(net "XTAL_CPU1_X32K_X1")
		)
	)
	(footprint ""
		(layer "B.Cu")
		(at 356.081838 -250.25731)
		(property "Reference" "C270"
			(at 0 0 0)
			(layer "B.SilkS")
			(hide yes)
			(effects
				(font
					(size 1.27 1.27)
				)
				(justify mirror)
			)
		)
		(property "Value" ""
			(at 0 0 0)
			(layer "B.Fab")
			(effects
				(font
					(size 1.27 1.27)
				)
				(justify mirror)
			)
		)
		(duplicate_pad_numbers_are_jumpers no)
		(fp_line
			(start -0.7874 -0.4064)
			(end -0.7874 0.4064)
			(stroke
				(width 0.1524)
				(type default)
			)
			(layer "B.SilkS")
		)
		(fp_line
			(start -0.7874 0.4064)
			(end 0.7874 0.4064)
			(stroke
				(width 0.1524)
				(type default)
			)
			(layer "B.SilkS")
		)
		(fp_line
			(start 0.7874 -0.4064)
			(end -0.7874 -0.4064)
			(stroke
				(width 0.1524)
				(type default)
			)
			(layer "B.SilkS")
		)
		(fp_line
			(start 0.7874 0.4064)
			(end 0.7874 -0.4064)
			(stroke
				(width 0.1524)
				(type default)
			)
			(layer "B.SilkS")
		)
		(fp_line
			(start -0.67945 -0.3048)
			(end -0.67945 0.3048)
			(stroke
				(width 0.1)
				(type default)
			)
			(layer "B.Fab")
		)
		(fp_line
			(start -0.67945 0.3048)
			(end -0.120396 0.3048)
			(stroke
				(width 0.1)
				(type default)
			)
			(layer "B.Fab")
		)
		(fp_line
			(start -0.12065 -0.3048)
			(end -0.67945 -0.3048)
			(stroke
				(width 0.1)
				(type default)
			)
			(layer "B.Fab")
		)
		(fp_line
			(start -0.12065 -0.2794)
			(end -0.12065 -0.3048)
			(stroke
				(width 0.1)
				(type default)
			)
			(layer "B.Fab")
		)
		(fp_line
			(start -0.120396 0.2794)
			(end 0.12065 0.2794)
			(stroke
				(width 0.1)
				(type default)
			)
			(layer "B.Fab")
		)
		(fp_line
			(start -0.120396 0.3048)
			(end -0.120396 0.2794)
			(stroke
				(width 0.1)
				(type default)
			)
			(layer "B.Fab")
		)
		(fp_line
			(start 0.12065 -0.305054)
			(end 0.12065 -0.2794)
			(stroke
				(width 0.1)
				(type default)
			)
			(layer "B.Fab")
		)
		(fp_line
			(start 0.12065 -0.2794)
			(end -0.12065 -0.2794)
			(stroke
				(width 0.1)
				(type default)
			)
			(layer "B.Fab")
		)
		(fp_line
			(start 0.12065 0.2794)
			(end 0.12065 0.3048)
			(stroke
				(width 0.1)
				(type default)
			)
			(layer "B.Fab")
		)
		(fp_line
			(start 0.12065 0.3048)
			(end 0.67945 0.3048)
			(stroke
				(width 0.1)
				(type default)
			)
			(layer "B.Fab")
		)
		(fp_line
			(start 0.67945 -0.305054)
			(end 0.12065 -0.305054)
			(stroke
				(width 0.1)
				(type default)
			)
			(layer "B.Fab")
		)
		(fp_line
			(start 0.67945 0.3048)
			(end 0.67945 -0.305054)
			(stroke
				(width 0.1)
				(type default)
			)
			(layer "B.Fab")
		)
		(pad "1" smd circle
			(at 0.40005 0 180)
			(size 0 0)
			(layers "B.Cu" "B.Mask" "B.Paste")
			(net "PVDDCR_CPU0_P0")
		)
		(pad "2" smd circle
			(at -0.40005 0 180)
			(size 0 0)
			(layers "B.Cu" "B.Mask" "B.Paste")
			(net "GND")
		)
	)
	(footprint ""
		(layer "B.Cu")
		(at 175.886364 -10.1473 -90)
		(property "Reference" "R2422"
			(at 0 0 90)
			(layer "B.SilkS")
			(hide yes)
			(effects
				(font
					(size 1.27 1.27)
				)
				(justify mirror)
			)
		)
		(property "Value" ""
			(at 0 0 90)
			(layer "B.Fab")
			(effects
				(font
					(size 1.27 1.27)
				)
				(justify mirror)
			)
		)
		(duplicate_pad_numbers_are_jumpers no)
		(fp_line
			(start -0.7874 0.4064)
			(end 0.7874 0.4064)
			(stroke
				(width 0.1524)
				(type default)
			)
			(layer "B.SilkS")
		)
		(fp_line
			(start 0.7874 0.4064)
			(end 0.7874 -0.4064)
			(stroke
				(width 0.1524)
				(type default)
			)
			(layer "B.SilkS")
		)
		(fp_line
			(start -0.7874 -0.4064)
			(end -0.7874 0.4064)
			(stroke
				(width 0.1524)
				(type default)
			)
			(layer "B.SilkS")
		)
		(fp_line
			(start 0.7874 -0.4064)
			(end -0.7874 -0.4064)
			(stroke
				(width 0.1524)
				(type default)
			)
			(layer "B.SilkS")
		)
		(fp_line
			(start -0.67945 0.3048)
			(end -0.120396 0.3048)
			(stroke
				(width 0.1)
				(type default)
			)
			(layer "B.Fab")
		)
		(fp_line
			(start -0.120396 0.3048)
			(end -0.120396 0.2794)
			(stroke
				(width 0.1)
				(type default)
			)
			(layer "B.Fab")
		)
		(fp_line
			(start 0.12065 0.3048)
			(end 0.67945 0.3048)
			(stroke
				(width 0.1)
				(type default)
			)
			(layer "B.Fab")
		)
		(fp_line
			(start 0.67945 0.3048)
			(end 0.67945 -0.305054)
			(stroke
				(width 0.1)
				(type default)
			)
			(layer "B.Fab")
		)
		(fp_line
			(start -0.120396 0.2794)
			(end 0.12065 0.2794)
			(stroke
				(width 0.1)
				(type default)
			)
			(layer "B.Fab")
		)
		(fp_line
			(start 0.12065 0.2794)
			(end 0.12065 0.3048)
			(stroke
				(width 0.1)
				(type default)
			)
			(layer "B.Fab")
		)
		(fp_line
			(start -0.12065 -0.2794)
			(end -0.12065 -0.3048)
			(stroke
				(width 0.1)
				(type default)
			)
			(layer "B.Fab")
		)
		(fp_line
			(start 0.12065 -0.2794)
			(end -0.12065 -0.2794)
			(stroke
				(width 0.1)
				(type default)
			)
			(layer "B.Fab")
		)
		(fp_line
			(start -0.67945 -0.3048)
			(end -0.67945 0.3048)
			(stroke
				(width 0.1)
				(type default)
			)
			(layer "B.Fab")
		)
		(fp_line
			(start -0.12065 -0.3048)
			(end -0.67945 -0.3048)
			(stroke
				(width 0.1)
				(type default)
			)
			(layer "B.Fab")
		)
		(fp_line
			(start 0.12065 -0.305054)
			(end 0.12065 -0.2794)
			(stroke
				(width 0.1)
				(type default)
			)
			(layer "B.Fab")
		)
		(fp_line
			(start 0.67945 -0.305054)
			(end 0.12065 -0.305054)
			(stroke
				(width 0.1)
				(type default)
			)
			(layer "B.Fab")
		)
		(pad "1" smd circle
			(at 0.40005 0 90)
			(size 0 0)
			(layers "B.Cu" "B.Mask" "B.Paste")
			(net "SMB_VR_SENSOR_3V3AUX_SDA")
		)
		(pad "2" smd circle
			(at -0.40005 0 90)
			(size 0 0)
			(layers "B.Cu" "B.Mask" "B.Paste")
			(net "SMB_VR_3V3AUX_SDA_R0")
		)
	)
	(footprint ""
		(layer "B.Cu")
		(at 299.265594 -393.48156 180)
		(property "Reference" "R983"
			(at 0 0 0)
			(layer "B.SilkS")
			(hide yes)
			(effects
				(font
					(size 1.27 1.27)
				)
				(justify mirror)
			)
		)
		(property "Value" ""
			(at 0 0 0)
			(layer "B.Fab")
			(effects
				(font
					(size 1.27 1.27)
				)
				(justify mirror)
			)
		)
		(duplicate_pad_numbers_are_jumpers no)
		(fp_line
			(start 0.32512 0.175006)
			(end 0.32512 -0.175006)
			(stroke
				(width 0.1)
				(type default)
			)
			(layer "B.Fab")
		)
		(fp_line
			(start 0.32512 -0.175006)
			(end -0.32512 -0.175006)
			(stroke
				(width 0.1)
				(type default)
			)
			(layer "B.Fab")
		)
		(fp_line
			(start -0.32512 0.175006)
			(end 0.32512 0.175006)
			(stroke
				(width 0.1)
				(type default)
			)
			(layer "B.Fab")
		)
		(fp_line
			(start -0.32512 -0.175006)
			(end -0.32512 0.175006)
			(stroke
				(width 0.1)
				(type default)
			)
			(layer "B.Fab")
		)
		(pad "1" smd rect
			(at 0.2667 0)
			(size 0.3048 0.381)
			(layers "B.Cu" "B.Mask" "B.Paste")
			(net "P1V8_CPU0_RT_1D")
		)
		(pad "2" smd rect
			(at -0.2667 0 180)
			(size 0.3048 0.381)
			(layers "B.Cu" "B.Mask" "B.Paste")
			(net "TEST1_RT_CPU0_P0")
		)
	)
	(footprint ""
		(layer "B.Cu")
		(at 318.99098 -398.942052 90)
		(property "Reference" "C586"
			(at 0 0 90)
			(layer "B.SilkS")
			(hide yes)
			(effects
				(font
					(size 1.27 1.27)
				)
				(justify mirror)
			)
		)
		(property "Value" ""
			(at 0 0 90)
			(layer "B.Fab")
			(effects
				(font
					(size 1.27 1.27)
				)
				(justify mirror)
			)
		)
		(duplicate_pad_numbers_are_jumpers no)
		(fp_line
			(start 0.7874 -0.4064)
			(end -0.7874 -0.4064)
			(stroke
				(width 0.1524)
				(type default)
			)
			(layer "B.SilkS")
		)
		(fp_line
			(start -0.7874 -0.4064)
			(end -0.7874 0.4064)
			(stroke
				(width 0.1524)
				(type default)
			)
			(layer "B.SilkS")
		)
		(fp_line
			(start 0.7874 0.4064)
			(end 0.7874 -0.4064)
			(stroke
				(width 0.1524)
				(type default)
			)
			(layer "B.SilkS")
		)
		(fp_line
			(start -0.7874 0.4064)
			(end 0.7874 0.4064)
			(stroke
				(width 0.1524)
				(type default)
			)
			(layer "B.SilkS")
		)
		(fp_line
			(start 0.67945 -0.305054)
			(end 0.12065 -0.305054)
			(stroke
				(width 0.1)
				(type default)
			)
			(layer "B.Fab")
		)
		(fp_line
			(start 0.12065 -0.305054)
			(end 0.12065 -0.2794)
			(stroke
				(width 0.1)
				(type default)
			)
			(layer "B.Fab")
		)
		(fp_line
			(start -0.12065 -0.3048)
			(end -0.67945 -0.3048)
			(stroke
				(width 0.1)
				(type default)
			)
			(layer "B.Fab")
		)
		(fp_line
			(start -0.67945 -0.3048)
			(end -0.67945 0.3048)
			(stroke
				(width 0.1)
				(type default)
			)
			(layer "B.Fab")
		)
		(fp_line
			(start 0.12065 -0.2794)
			(end -0.12065 -0.2794)
			(stroke
				(width 0.1)
				(type default)
			)
			(layer "B.Fab")
		)
		(fp_line
			(start -0.12065 -0.2794)
			(end -0.12065 -0.3048)
			(stroke
				(width 0.1)
				(type default)
			)
			(layer "B.Fab")
		)
		(fp_line
			(start 0.12065 0.2794)
			(end 0.12065 0.3048)
			(stroke
				(width 0.1)
				(type default)
			)
			(layer "B.Fab")
		)
		(fp_line
			(start -0.120396 0.2794)
			(end 0.12065 0.2794)
			(stroke
				(width 0.1)
				(type default)
			)
			(layer "B.Fab")
		)
		(fp_line
			(start 0.67945 0.3048)
			(end 0.67945 -0.305054)
			(stroke
				(width 0.1)
				(type default)
			)
			(layer "B.Fab")
		)
		(fp_line
			(start 0.12065 0.3048)
			(end 0.67945 0.3048)
			(stroke
				(width 0.1)
				(type default)
			)
			(layer "B.Fab")
		)
		(fp_line
			(start -0.120396 0.3048)
			(end -0.120396 0.2794)
			(stroke
				(width 0.1)
				(type default)
			)
			(layer "B.Fab")
		)
		(fp_line
			(start -0.67945 0.3048)
			(end -0.120396 0.3048)
			(stroke
				(width 0.1)
				(type default)
			)
			(layer "B.Fab")
		)
		(pad "1" smd circle
			(at 0.40005 0 270)
			(size 0 0)
			(layers "B.Cu" "B.Mask" "B.Paste")
			(net "P0V9_CPU0_RT0_2A")
		)
		(pad "2" smd circle
			(at -0.40005 0 270)
			(size 0 0)
			(layers "B.Cu" "B.Mask" "B.Paste")
			(net "GND")
		)
	)
	(footprint ""
		(layer "B.Cu")
		(at 89.560146 -182.607966 -90)
		(property "Reference" "PC265_2"
			(at 0 0 90)
			(layer "B.SilkS")
			(hide yes)
			(effects
				(font
					(size 1.27 1.27)
				)
				(justify mirror)
			)
		)
		(property "Value" ""
			(at 0 0 90)
			(layer "B.Fab")
			(effects
				(font
					(size 1.27 1.27)
				)
				(justify mirror)
			)
		)
		(duplicate_pad_numbers_are_jumpers no)
		(fp_line
			(start -1.524 0.762)
			(end 1.524 0.762)
			(stroke
				(width 0.1524)
				(type default)
			)
			(layer "B.SilkS")
		)
		(fp_line
			(start 1.524 0.762)
			(end 1.524 -0.762)
			(stroke
				(width 0.1524)
				(type default)
			)
			(layer "B.SilkS")
		)
		(fp_line
			(start -1.524 -0.762)
			(end -1.524 0.762)
			(stroke
				(width 0.1524)
				(type default)
			)
			(layer "B.SilkS")
		)
		(fp_line
			(start 1.524 -0.762)
			(end -1.524 -0.762)
			(stroke
				(width 0.1524)
				(type default)
			)
			(layer "B.SilkS")
		)
		(fp_line
			(start -1.1049 0.724916)
			(end -1.1049 -0.724916)
			(stroke
				(width 0.1)
				(type default)
			)
			(layer "B.Fab")
		)
		(fp_line
			(start 1.1049 0.724916)
			(end -1.1049 0.724916)
			(stroke
				(width 0.1)
				(type default)
			)
			(layer "B.Fab")
		)
		(fp_line
			(start -1.1049 -0.724916)
			(end 1.1049 -0.724916)
			(stroke
				(width 0.1)
				(type default)
			)
			(layer "B.Fab")
		)
		(fp_line
			(start 1.1049 -0.724916)
			(end 1.1049 0.724916)
			(stroke
				(width 0.1)
				(type default)
			)
			(layer "B.Fab")
		)
		(pad "1" smd rect
			(at 0.889 0 270)
			(size 1.016 1.27)
			(layers "B.Cu" "B.Mask" "B.Paste")
			(net "SW_P12V_AUX_PVDDCR_CPU0_P1_FLT")
		)
		(pad "2" smd rect
			(at -0.889 0 270)
			(size 1.016 1.27)
			(layers "B.Cu" "B.Mask" "B.Paste")
			(net "GND")
		)
	)
	(footprint ""
		(layer "B.Cu")
		(at 187.822078 -97.085912 -90)
		(property "Reference" "R262"
			(at 0 0 90)
			(layer "B.SilkS")
			(hide yes)
			(effects
				(font
					(size 1.27 1.27)
				)
				(justify mirror)
			)
		)
		(property "Value" ""
			(at 0 0 90)
			(layer "B.Fab")
			(effects
				(font
					(size 1.27 1.27)
				)
				(justify mirror)
			)
		)
		(duplicate_pad_numbers_are_jumpers no)
		(fp_line
			(start -0.7874 0.4064)
			(end 0.7874 0.4064)
			(stroke
				(width 0.1524)
				(type default)
			)
			(layer "B.SilkS")
		)
		(fp_line
			(start 0.7874 0.4064)
			(end 0.7874 -0.4064)
			(stroke
				(width 0.1524)
				(type default)
			)
			(layer "B.SilkS")
		)
		(fp_line
			(start -0.7874 -0.4064)
			(end -0.7874 0.4064)
			(stroke
				(width 0.1524)
				(type default)
			)
			(layer "B.SilkS")
		)
		(fp_line
			(start 0.7874 -0.4064)
			(end -0.7874 -0.4064)
			(stroke
				(width 0.1524)
				(type default)
			)
			(layer "B.SilkS")
		)
		(fp_line
			(start -0.67945 0.3048)
			(end -0.120396 0.3048)
			(stroke
				(width 0.1)
				(type default)
			)
			(layer "B.Fab")
		)
		(fp_line
			(start -0.120396 0.3048)
			(end -0.120396 0.2794)
			(stroke
				(width 0.1)
				(type default)
			)
			(layer "B.Fab")
		)
		(fp_line
			(start 0.12065 0.3048)
			(end 0.67945 0.3048)
			(stroke
				(width 0.1)
				(type default)
			)
			(layer "B.Fab")
		)
		(fp_line
			(start 0.67945 0.3048)
			(end 0.67945 -0.305054)
			(stroke
				(width 0.1)
				(type default)
			)
			(layer "B.Fab")
		)
		(fp_line
			(start -0.120396 0.2794)
			(end 0.12065 0.2794)
			(stroke
				(width 0.1)
				(type default)
			)
			(layer "B.Fab")
		)
		(fp_line
			(start 0.12065 0.2794)
			(end 0.12065 0.3048)
			(stroke
				(width 0.1)
				(type default)
			)
			(layer "B.Fab")
		)
		(fp_line
			(start -0.12065 -0.2794)
			(end -0.12065 -0.3048)
			(stroke
				(width 0.1)
				(type default)
			)
			(layer "B.Fab")
		)
		(fp_line
			(start 0.12065 -0.2794)
			(end -0.12065 -0.2794)
			(stroke
				(width 0.1)
				(type default)
			)
			(layer "B.Fab")
		)
		(fp_line
			(start -0.67945 -0.3048)
			(end -0.67945 0.3048)
			(stroke
				(width 0.1)
				(type default)
			)
			(layer "B.Fab")
		)
		(fp_line
			(start -0.12065 -0.3048)
			(end -0.67945 -0.3048)
			(stroke
				(width 0.1)
				(type default)
			)
			(layer "B.Fab")
		)
		(fp_line
			(start 0.12065 -0.305054)
			(end 0.12065 -0.2794)
			(stroke
				(width 0.1)
				(type default)
			)
			(layer "B.Fab")
		)
		(fp_line
			(start 0.67945 -0.305054)
			(end 0.12065 -0.305054)
			(stroke
				(width 0.1)
				(type default)
			)
			(layer "B.Fab")
		)
		(pad "1" smd circle
			(at 0.40005 0 90)
			(size 0 0)
			(layers "B.Cu" "B.Mask" "B.Paste")
			(net "CPU1_CORETYPE0")
		)
		(pad "2" smd circle
			(at -0.40005 0 90)
			(size 0 0)
			(layers "B.Cu" "B.Mask" "B.Paste")
			(net "FM_CPU1_CORETYPE0")
		)
	)
	(footprint ""
		(layer "B.Cu")
		(at 178.303428 -418.4015)
		(property "Reference" "U192"
			(at -0.814578 2.297176 0)
			(unlocked yes)
			(layer "B.SilkS")
			(effects
				(font
					(size 0.7874 0.5842)
					(thickness 0.1524)
				)
				(justify left mirror)
			)
		)
		(property "Value" ""
			(at 0 0 0)
			(layer "B.Fab")
			(effects
				(font
					(size 1.27 1.27)
				)
				(justify mirror)
			)
		)
		(duplicate_pad_numbers_are_jumpers no)
		(fp_line
			(start -1.3716 -1.524)
			(end -1.3716 1.524)
			(stroke
				(width 0.1524)
				(type default)
			)
			(layer "B.SilkS")
		)
		(fp_line
			(start -1.3716 1.524)
			(end 1.3716 1.524)
			(stroke
				(width 0.1524)
				(type default)
			)
			(layer "B.SilkS")
		)
		(fp_line
			(start -0.508 -1.524)
			(end -1.3716 -1.524)
			(stroke
				(width 0.1524)
				(type default)
			)
			(layer "B.SilkS")
		)
		(fp_line
			(start 0 -1.016)
			(end -0.508 -1.524)
			(stroke
				(width 0.1524)
				(type default)
			)
			(layer "B.SilkS")
		)
		(fp_line
			(start 0.508 -1.524)
			(end 0 -1.016)
			(stroke
				(width 0.1524)
				(type default)
			)
			(layer "B.SilkS")
		)
		(fp_line
			(start 1.3716 -1.524)
			(end 0.508 -1.524)
			(stroke
				(width 0.1524)
				(type default)
			)
			(layer "B.SilkS")
		)
		(fp_line
			(start 1.3716 1.524)
			(end 1.3716 -1.524)
			(stroke
				(width 0.1524)
				(type default)
			)
			(layer "B.SilkS")
		)
		(fp_poly
			(pts
				(xy 3.631946 -1.31826) (xy 3.19024 -1.76022) (xy 3.030728 -1.13665)
			)
			(stroke
				(width 0)
				(type default)
			)
			(fill yes)
			(layer "B.SilkS")
		)
		(fp_line
			(start -2.54 -1.0668)
			(end -2.54 1.0668)
			(stroke
				(width 0.1)
				(type default)
			)
			(layer "B.Fab")
		)
		(fp_line
			(start -2.54 1.0668)
			(end -1.5494 1.0668)
			(stroke
				(width 0.1)
				(type default)
			)
			(layer "B.Fab")
		)
		(fp_line
			(start -1.5494 -1.524)
			(end -1.5494 -1.0668)
			(stroke
				(width 0.1)
				(type default)
			)
			(layer "B.Fab")
		)
		(fp_line
			(start -1.5494 -1.0668)
			(end -2.54 -1.0668)
			(stroke
				(width 0.1)
				(type default)
			)
			(layer "B.Fab")
		)
		(fp_line
			(start -1.5494 -1.0668)
			(end -1.5494 1.0668)
			(stroke
				(width 0.1)
				(type default)
			)
			(layer "B.Fab")
		)
		(fp_line
			(start -1.5494 1.0668)
			(end -1.5494 1.524)
			(stroke
				(width 0.1)
				(type default)
			)
			(layer "B.Fab")
		)
		(fp_line
			(start -1.5494 1.524)
			(end 1.5494 1.524)
			(stroke
				(width 0.1)
				(type default)
			)
			(layer "B.Fab")
		)
		(fp_line
			(start 1.5494 -1.524)
			(end -1.5494 -1.524)
			(stroke
				(width 0.1)
				(type default)
			)
			(layer "B.Fab")
		)
		(fp_line
			(start 1.5494 -1.0668)
			(end 1.5494 -1.524)
			(stroke
				(width 0.1)
				(type default)
			)
			(layer "B.Fab")
		)
		(fp_line
			(start 1.5494 1.0668)
			(end 1.5494 -1.0668)
			(stroke
				(width 0.1)
				(type default)
			)
			(layer "B.Fab")
		)
		(fp_line
			(start 1.5494 1.0668)
			(end 2.54 1.0668)
			(stroke
				(width 0.1)
				(type default)
			)
			(layer "B.Fab")
		)
		(fp_line
			(start 1.5494 1.524)
			(end 1.5494 1.0668)
			(stroke
				(width 0.1)
				(type default)
			)
			(layer "B.Fab")
		)
		(fp_line
			(start 2.54 -1.0668)
			(end 1.5494 -1.0668)
			(stroke
				(width 0.1)
				(type default)
			)
			(layer "B.Fab")
		)
		(fp_line
			(start 2.54 1.0668)
			(end 2.54 -1.0668)
			(stroke
				(width 0.1)
				(type default)
			)
			(layer "B.Fab")
		)
		(fp_poly
			(pts
				(xy 3.60172 -0.719328) (xy 3.60172 -1.344168) (xy 3.048 -1.016)
			)
			(stroke
				(width 0)
				(type default)
			)
			(fill yes)
			(layer "B.Fab")
		)
		(pad "1" smd rect
			(at 2.232406 -0.975106 270)
			(size 0.3556 1.4224)
			(layers "B.Cu" "B.Mask" "B.Paste")
			(net "MB_PDB_SMB9_R_EN")
		)
		(pad "2" smd rect
			(at 2.232406 -0.32512 270)
			(size 0.3556 1.4224)
			(layers "B.Cu" "B.Mask" "B.Paste")
			(net "SMB_FAN_3V3AUX_BUF_SCL")
		)
		(pad "3" smd rect
			(at 2.232406 0.32512 270)
			(size 0.3556 1.4224)
			(layers "B.Cu" "B.Mask" "B.Paste")
			(net "SMB_FAN_3V3AUX_R_SCL")
		)
		(pad "4" smd rect
			(at 2.232406 0.975106 270)
			(size 0.3556 1.4224)
			(layers "B.Cu" "B.Mask" "B.Paste")
			(net "GND")
		)
		(pad "5" smd rect
			(at -2.232406 0.975106 270)
			(size 0.3556 1.4224)
			(layers "B.Cu" "B.Mask" "B.Paste")
			(net "Net_10751")
		)
		(pad "6" smd rect
			(at -2.232406 0.32512 270)
			(size 0.3556 1.4224)
			(layers "B.Cu" "B.Mask" "B.Paste")
			(net "SMB_FAN_3V3AUX_R_SDA")
		)
		(pad "7" smd rect
			(at -2.232406 -0.32512 270)
			(size 0.3556 1.4224)
			(layers "B.Cu" "B.Mask" "B.Paste")
			(net "SMB_FAN_3V3AUX_BUF_SDA")
		)
		(pad "8" smd rect
			(at -2.232406 -0.975106 270)
			(size 0.3556 1.4224)
			(layers "B.Cu" "B.Mask" "B.Paste")
			(net "P3V3_AUX")
		)
	)
	(footprint ""
		(layer "B.Cu")
		(at 129.018538 -388.011162 -90)
		(property "Reference" "C473"
			(at 0 0 90)
			(layer "B.SilkS")
			(hide yes)
			(effects
				(font
					(size 1.27 1.27)
				)
				(justify mirror)
			)
		)
		(property "Value" ""
			(at 0 0 90)
			(layer "B.Fab")
			(effects
				(font
					(size 1.27 1.27)
				)
				(justify mirror)
			)
		)
		(duplicate_pad_numbers_are_jumpers no)
		(fp_line
			(start -0.299974 0.150114)
			(end 0.299974 0.150114)
			(stroke
				(width 0.1)
				(type default)
			)
			(layer "B.Fab")
		)
		(fp_line
			(start 0.299974 0.150114)
			(end 0.299974 -0.150114)
			(stroke
				(width 0.1)
				(type default)
			)
			(layer "B.Fab")
		)
		(fp_line
			(start -0.299974 -0.150114)
			(end -0.299974 0.150114)
			(stroke
				(width 0.1)
				(type default)
			)
			(layer "B.Fab")
		)
		(fp_line
			(start 0.299974 -0.150114)
			(end -0.299974 -0.150114)
			(stroke
				(width 0.1)
				(type default)
			)
			(layer "B.Fab")
		)
		(pad "1" smd rect
			(at 0.2667 0 90)
			(size 0.3048 0.381)
			(layers "B.Cu" "B.Mask" "B.Paste")
			(net "P0V9_CPU1_RT3_2A")
		)
		(pad "2" smd rect
			(at -0.2667 0 90)
			(size 0.3048 0.381)
			(layers "B.Cu" "B.Mask" "B.Paste")
			(net "GND")
		)
	)
	(footprint ""
		(layer "B.Cu")
		(at 184.3405 -397.848582)
		(property "Reference" "PR3931"
			(at 0 0 0)
			(layer "B.SilkS")
			(hide yes)
			(effects
				(font
					(size 1.27 1.27)
				)
				(justify mirror)
			)
		)
		(property "Value" ""
			(at 0 0 0)
			(layer "B.Fab")
			(effects
				(font
					(size 1.27 1.27)
				)
				(justify mirror)
			)
		)
		(duplicate_pad_numbers_are_jumpers no)
		(fp_line
			(start -0.7874 -0.4064)
			(end -0.7874 0.4064)
			(stroke
				(width 0.1524)
				(type default)
			)
			(layer "B.SilkS")
		)
		(fp_line
			(start -0.7874 0.4064)
			(end 0.7874 0.4064)
			(stroke
				(width 0.1524)
				(type default)
			)
			(layer "B.SilkS")
		)
		(fp_line
			(start 0.7874 -0.4064)
			(end -0.7874 -0.4064)
			(stroke
				(width 0.1524)
				(type default)
			)
			(layer "B.SilkS")
		)
		(fp_line
			(start 0.7874 0.4064)
			(end 0.7874 -0.4064)
			(stroke
				(width 0.1524)
				(type default)
			)
			(layer "B.SilkS")
		)
		(fp_line
			(start -0.67945 -0.3048)
			(end -0.67945 0.3048)
			(stroke
				(width 0.1)
				(type default)
			)
			(layer "B.Fab")
		)
		(fp_line
			(start -0.67945 0.3048)
			(end -0.120396 0.3048)
			(stroke
				(width 0.1)
				(type default)
			)
			(layer "B.Fab")
		)
		(fp_line
			(start -0.12065 -0.3048)
			(end -0.67945 -0.3048)
			(stroke
				(width 0.1)
				(type default)
			)
			(layer "B.Fab")
		)
		(fp_line
			(start -0.12065 -0.2794)
			(end -0.12065 -0.3048)
			(stroke
				(width 0.1)
				(type default)
			)
			(layer "B.Fab")
		)
		(fp_line
			(start -0.120396 0.2794)
			(end 0.12065 0.2794)
			(stroke
				(width 0.1)
				(type default)
			)
			(layer "B.Fab")
		)
		(fp_line
			(start -0.120396 0.3048)
			(end -0.120396 0.2794)
			(stroke
				(width 0.1)
				(type default)
			)
			(layer "B.Fab")
		)
		(fp_line
			(start 0.12065 -0.305054)
			(end 0.12065 -0.2794)
			(stroke
				(width 0.1)
				(type default)
			)
			(layer "B.Fab")
		)
		(fp_line
			(start 0.12065 -0.2794)
			(end -0.12065 -0.2794)
			(stroke
				(width 0.1)
				(type default)
			)
			(layer "B.Fab")
		)
		(fp_line
			(start 0.12065 0.2794)
			(end 0.12065 0.3048)
			(stroke
				(width 0.1)
				(type default)
			)
			(layer "B.Fab")
		)
		(fp_line
			(start 0.12065 0.3048)
			(end 0.67945 0.3048)
			(stroke
				(width 0.1)
				(type default)
			)
			(layer "B.Fab")
		)
		(fp_line
			(start 0.67945 -0.305054)
			(end 0.12065 -0.305054)
			(stroke
				(width 0.1)
				(type default)
			)
			(layer "B.Fab")
		)
		(fp_line
			(start 0.67945 0.3048)
			(end 0.67945 -0.305054)
			(stroke
				(width 0.1)
				(type default)
			)
			(layer "B.Fab")
		)
		(pad "1" smd circle
			(at 0.40005 0 180)
			(size 0 0)
			(layers "B.Cu" "B.Mask" "B.Paste")
			(net "P12V_AUX")
		)
		(pad "2" smd circle
			(at -0.40005 0 180)
			(size 0 0)
			(layers "B.Cu" "B.Mask" "B.Paste")
			(net "HSC_VOSEN")
		)
	)
	(footprint ""
		(layer "B.Cu")
		(at 75.57008 -4.251198 -90)
		(property "Reference" "R3166"
			(at 0 0 90)
			(layer "B.SilkS")
			(hide yes)
			(effects
				(font
					(size 1.27 1.27)
				)
				(justify mirror)
			)
		)
		(property "Value" ""
			(at 0 0 90)
			(layer "B.Fab")
			(effects
				(font
					(size 1.27 1.27)
				)
				(justify mirror)
			)
		)
		(duplicate_pad_numbers_are_jumpers no)
		(fp_line
			(start -0.7874 0.4064)
			(end 0.7874 0.4064)
			(stroke
				(width 0.1524)
				(type default)
			)
			(layer "B.SilkS")
		)
		(fp_line
			(start 0.7874 0.4064)
			(end 0.7874 -0.4064)
			(stroke
				(width 0.1524)
				(type default)
			)
			(layer "B.SilkS")
		)
		(fp_line
			(start -0.7874 -0.4064)
			(end -0.7874 0.4064)
			(stroke
				(width 0.1524)
				(type default)
			)
			(layer "B.SilkS")
		)
		(fp_line
			(start 0.7874 -0.4064)
			(end -0.7874 -0.4064)
			(stroke
				(width 0.1524)
				(type default)
			)
			(layer "B.SilkS")
		)
		(fp_line
			(start -0.67945 0.3048)
			(end -0.120396 0.3048)
			(stroke
				(width 0.1)
				(type default)
			)
			(layer "B.Fab")
		)
		(fp_line
			(start -0.120396 0.3048)
			(end -0.120396 0.2794)
			(stroke
				(width 0.1)
				(type default)
			)
			(layer "B.Fab")
		)
		(fp_line
			(start 0.12065 0.3048)
			(end 0.67945 0.3048)
			(stroke
				(width 0.1)
				(type default)
			)
			(layer "B.Fab")
		)
		(fp_line
			(start 0.67945 0.3048)
			(end 0.67945 -0.305054)
			(stroke
				(width 0.1)
				(type default)
			)
			(layer "B.Fab")
		)
		(fp_line
			(start -0.120396 0.2794)
			(end 0.12065 0.2794)
			(stroke
				(width 0.1)
				(type default)
			)
			(layer "B.Fab")
		)
		(fp_line
			(start 0.12065 0.2794)
			(end 0.12065 0.3048)
			(stroke
				(width 0.1)
				(type default)
			)
			(layer "B.Fab")
		)
		(fp_line
			(start -0.12065 -0.2794)
			(end -0.12065 -0.3048)
			(stroke
				(width 0.1)
				(type default)
			)
			(layer "B.Fab")
		)
		(fp_line
			(start 0.12065 -0.2794)
			(end -0.12065 -0.2794)
			(stroke
				(width 0.1)
				(type default)
			)
			(layer "B.Fab")
		)
		(fp_line
			(start -0.67945 -0.3048)
			(end -0.67945 0.3048)
			(stroke
				(width 0.1)
				(type default)
			)
			(layer "B.Fab")
		)
		(fp_line
			(start -0.12065 -0.3048)
			(end -0.67945 -0.3048)
			(stroke
				(width 0.1)
				(type default)
			)
			(layer "B.Fab")
		)
		(fp_line
			(start 0.12065 -0.305054)
			(end 0.12065 -0.2794)
			(stroke
				(width 0.1)
				(type default)
			)
			(layer "B.Fab")
		)
		(fp_line
			(start 0.67945 -0.305054)
			(end 0.12065 -0.305054)
			(stroke
				(width 0.1)
				(type default)
			)
			(layer "B.Fab")
		)
		(pad "1" smd circle
			(at 0.40005 0 90)
			(size 0 0)
			(layers "B.Cu" "B.Mask" "B.Paste")
			(net "P3V3_OCP_V3_2")
		)
		(pad "2" smd circle
			(at -0.40005 0 90)
			(size 0 0)
			(layers "B.Cu" "B.Mask" "B.Paste")
			(net "OCP_V3_2_ID1")
		)
	)
	(footprint ""
		(layer "B.Cu")
		(at 115.991386 -250.892564)
		(property "Reference" "C2302"
			(at 0 0 0)
			(layer "B.SilkS")
			(hide yes)
			(effects
				(font
					(size 1.27 1.27)
				)
				(justify mirror)
			)
		)
		(property "Value" ""
			(at 0 0 0)
			(layer "B.Fab")
			(effects
				(font
					(size 1.27 1.27)
				)
				(justify mirror)
			)
		)
		(duplicate_pad_numbers_are_jumpers no)
		(fp_line
			(start -0.7874 -0.4064)
			(end -0.7874 0.4064)
			(stroke
				(width 0.1524)
				(type default)
			)
			(layer "B.SilkS")
		)
		(fp_line
			(start -0.7874 0.4064)
			(end 0.7874 0.4064)
			(stroke
				(width 0.1524)
				(type default)
			)
			(layer "B.SilkS")
		)
		(fp_line
			(start 0.7874 -0.4064)
			(end -0.7874 -0.4064)
			(stroke
				(width 0.1524)
				(type default)
			)
			(layer "B.SilkS")
		)
		(fp_line
			(start 0.7874 0.4064)
			(end 0.7874 -0.4064)
			(stroke
				(width 0.1524)
				(type default)
			)
			(layer "B.SilkS")
		)
		(fp_line
			(start -0.67945 -0.3048)
			(end -0.67945 0.3048)
			(stroke
				(width 0.1)
				(type default)
			)
			(layer "B.Fab")
		)
		(fp_line
			(start -0.67945 0.3048)
			(end -0.120396 0.3048)
			(stroke
				(width 0.1)
				(type default)
			)
			(layer "B.Fab")
		)
		(fp_line
			(start -0.12065 -0.3048)
			(end -0.67945 -0.3048)
			(stroke
				(width 0.1)
				(type default)
			)
			(layer "B.Fab")
		)
		(fp_line
			(start -0.12065 -0.2794)
			(end -0.12065 -0.3048)
			(stroke
				(width 0.1)
				(type default)
			)
			(layer "B.Fab")
		)
		(fp_line
			(start -0.120396 0.2794)
			(end 0.12065 0.2794)
			(stroke
				(width 0.1)
				(type default)
			)
			(layer "B.Fab")
		)
		(fp_line
			(start -0.120396 0.3048)
			(end -0.120396 0.2794)
			(stroke
				(width 0.1)
				(type default)
			)
			(layer "B.Fab")
		)
		(fp_line
			(start 0.12065 -0.305054)
			(end 0.12065 -0.2794)
			(stroke
				(width 0.1)
				(type default)
			)
			(layer "B.Fab")
		)
		(fp_line
			(start 0.12065 -0.2794)
			(end -0.12065 -0.2794)
			(stroke
				(width 0.1)
				(type default)
			)
			(layer "B.Fab")
		)
		(fp_line
			(start 0.12065 0.2794)
			(end 0.12065 0.3048)
			(stroke
				(width 0.1)
				(type default)
			)
			(layer "B.Fab")
		)
		(fp_line
			(start 0.12065 0.3048)
			(end 0.67945 0.3048)
			(stroke
				(width 0.1)
				(type default)
			)
			(layer "B.Fab")
		)
		(fp_line
			(start 0.67945 -0.305054)
			(end 0.12065 -0.305054)
			(stroke
				(width 0.1)
				(type default)
			)
			(layer "B.Fab")
		)
		(fp_line
			(start 0.67945 0.3048)
			(end 0.67945 -0.305054)
			(stroke
				(width 0.1)
				(type default)
			)
			(layer "B.Fab")
		)
		(pad "1" smd circle
			(at 0.40005 0 180)
			(size 0 0)
			(layers "B.Cu" "B.Mask" "B.Paste")
			(net "PVDDCR_CPU0_P1")
		)
		(pad "2" smd circle
			(at -0.40005 0 180)
			(size 0 0)
			(layers "B.Cu" "B.Mask" "B.Paste")
			(net "GND")
		)
	)
	(footprint ""
		(layer "B.Cu")
		(at 310.7182 -396.393162 -90)
		(property "Reference" "C512"
			(at 0 0 90)
			(layer "B.SilkS")
			(hide yes)
			(effects
				(font
					(size 1.27 1.27)
				)
				(justify mirror)
			)
		)
		(property "Value" ""
			(at 0 0 90)
			(layer "B.Fab")
			(effects
				(font
					(size 1.27 1.27)
				)
				(justify mirror)
			)
		)
		(duplicate_pad_numbers_are_jumpers no)
		(fp_line
			(start -0.299974 0.150114)
			(end 0.299974 0.150114)
			(stroke
				(width 0.1)
				(type default)
			)
			(layer "B.Fab")
		)
		(fp_line
			(start 0.299974 0.150114)
			(end 0.299974 -0.150114)
			(stroke
				(width 0.1)
				(type default)
			)
			(layer "B.Fab")
		)
		(fp_line
			(start -0.299974 -0.150114)
			(end -0.299974 0.150114)
			(stroke
				(width 0.1)
				(type default)
			)
			(layer "B.Fab")
		)
		(fp_line
			(start 0.299974 -0.150114)
			(end -0.299974 -0.150114)
			(stroke
				(width 0.1)
				(type default)
			)
			(layer "B.Fab")
		)
		(pad "1" smd rect
			(at 0.2667 0 90)
			(size 0.3048 0.381)
			(layers "B.Cu" "B.Mask" "B.Paste")
			(net "P1V8_CPU0_RT0_1A")
		)
		(pad "2" smd rect
			(at -0.2667 0 90)
			(size 0.3048 0.381)
			(layers "B.Cu" "B.Mask" "B.Paste")
			(net "GND")
		)
	)
	(footprint ""
		(layer "B.Cu")
		(at 236.20095 -50.193448 180)
		(property "Reference" "R3771"
			(at 0 0 0)
			(layer "B.SilkS")
			(hide yes)
			(effects
				(font
					(size 1.27 1.27)
				)
				(justify mirror)
			)
		)
		(property "Value" ""
			(at 0 0 0)
			(layer "B.Fab")
			(effects
				(font
					(size 1.27 1.27)
				)
				(justify mirror)
			)
		)
		(duplicate_pad_numbers_are_jumpers no)
		(fp_line
			(start 0.7874 0.4064)
			(end 0.7874 -0.4064)
			(stroke
				(width 0.1524)
				(type default)
			)
			(layer "B.SilkS")
		)
		(fp_line
			(start 0.7874 -0.4064)
			(end -0.7874 -0.4064)
			(stroke
				(width 0.1524)
				(type default)
			)
			(layer "B.SilkS")
		)
		(fp_line
			(start -0.7874 0.4064)
			(end 0.7874 0.4064)
			(stroke
				(width 0.1524)
				(type default)
			)
			(layer "B.SilkS")
		)
		(fp_line
			(start -0.7874 -0.4064)
			(end -0.7874 0.4064)
			(stroke
				(width 0.1524)
				(type default)
			)
			(layer "B.SilkS")
		)
		(fp_line
			(start 0.67945 0.3048)
			(end 0.67945 -0.305054)
			(stroke
				(width 0.1)
				(type default)
			)
			(layer "B.Fab")
		)
		(fp_line
			(start 0.67945 -0.305054)
			(end 0.12065 -0.305054)
			(stroke
				(width 0.1)
				(type default)
			)
			(layer "B.Fab")
		)
		(fp_line
			(start 0.12065 0.3048)
			(end 0.67945 0.3048)
			(stroke
				(width 0.1)
				(type default)
			)
			(layer "B.Fab")
		)
		(fp_line
			(start 0.12065 0.2794)
			(end 0.12065 0.3048)
			(stroke
				(width 0.1)
				(type default)
			)
			(layer "B.Fab")
		)
		(fp_line
			(start 0.12065 -0.2794)
			(end -0.12065 -0.2794)
			(stroke
				(width 0.1)
				(type default)
			)
			(layer "B.Fab")
		)
		(fp_line
			(start 0.12065 -0.305054)
			(end 0.12065 -0.2794)
			(stroke
				(width 0.1)
				(type default)
			)
			(layer "B.Fab")
		)
		(fp_line
			(start -0.120396 0.3048)
			(end -0.120396 0.2794)
			(stroke
				(width 0.1)
				(type default)
			)
			(layer "B.Fab")
		)
		(fp_line
			(start -0.120396 0.2794)
			(end 0.12065 0.2794)
			(stroke
				(width 0.1)
				(type default)
			)
			(layer "B.Fab")
		)
		(fp_line
			(start -0.12065 -0.2794)
			(end -0.12065 -0.3048)
			(stroke
				(width 0.1)
				(type default)
			)
			(layer "B.Fab")
		)
		(fp_line
			(start -0.12065 -0.3048)
			(end -0.67945 -0.3048)
			(stroke
				(width 0.1)
				(type default)
			)
			(layer "B.Fab")
		)
		(fp_line
			(start -0.67945 0.3048)
			(end -0.120396 0.3048)
			(stroke
				(width 0.1)
				(type default)
			)
			(layer "B.Fab")
		)
		(fp_line
			(start -0.67945 -0.3048)
			(end -0.67945 0.3048)
			(stroke
				(width 0.1)
				(type default)
			)
			(layer "B.Fab")
		)
		(pad "1" smd circle
			(at 0.40005 0)
			(size 0 0)
			(layers "B.Cu" "B.Mask" "B.Paste")
			(net "P3V3_AUX")
		)
		(pad "2" smd circle
			(at -0.40005 0)
			(size 0 0)
			(layers "B.Cu" "B.Mask" "B.Paste")
			(net "E1S_0_PWRDIS")
		)
	)
	(footprint ""
		(layer "B.Cu")
		(at 358.389174 -400.19605 180)
		(property "Reference" "C625"
			(at 0 0 0)
			(layer "B.SilkS")
			(hide yes)
			(effects
				(font
					(size 1.27 1.27)
				)
				(justify mirror)
			)
		)
		(property "Value" ""
			(at 0 0 0)
			(layer "B.Fab")
			(effects
				(font
					(size 1.27 1.27)
				)
				(justify mirror)
			)
		)
		(duplicate_pad_numbers_are_jumpers no)
		(fp_line
			(start 1.524 0.762)
			(end 1.524 -0.762)
			(stroke
				(width 0.1524)
				(type default)
			)
			(layer "B.SilkS")
		)
		(fp_line
			(start 1.524 -0.762)
			(end -1.524 -0.762)
			(stroke
				(width 0.1524)
				(type default)
			)
			(layer "B.SilkS")
		)
		(fp_line
			(start -1.524 0.762)
			(end 1.524 0.762)
			(stroke
				(width 0.1524)
				(type default)
			)
			(layer "B.SilkS")
		)
		(fp_line
			(start -1.524 -0.762)
			(end -1.524 0.762)
			(stroke
				(width 0.1524)
				(type default)
			)
			(layer "B.SilkS")
		)
		(fp_line
			(start 1.1049 0.724916)
			(end -1.1049 0.724916)
			(stroke
				(width 0.1)
				(type default)
			)
			(layer "B.Fab")
		)
		(fp_line
			(start 1.1049 -0.724916)
			(end 1.1049 0.724916)
			(stroke
				(width 0.1)
				(type default)
			)
			(layer "B.Fab")
		)
		(fp_line
			(start -1.1049 0.724916)
			(end -1.1049 -0.724916)
			(stroke
				(width 0.1)
				(type default)
			)
			(layer "B.Fab")
		)
		(fp_line
			(start -1.1049 -0.724916)
			(end 1.1049 -0.724916)
			(stroke
				(width 0.1)
				(type default)
			)
			(layer "B.Fab")
		)
		(pad "1" smd rect
			(at 0.889 0 180)
			(size 1.016 1.27)
			(layers "B.Cu" "B.Mask" "B.Paste")
			(net "P0V9_CPU0_RT1_2A")
		)
		(pad "2" smd rect
			(at -0.889 0 180)
			(size 1.016 1.27)
			(layers "B.Cu" "B.Mask" "B.Paste")
			(net "GND")
		)
	)
	(footprint ""
		(layer "B.Cu")
		(at 415.569654 -170.48988 90)
		(property "Reference" "PC597"
			(at 5.924804 -1.286002 270)
			(unlocked yes)
			(layer "B.SilkS")
			(effects
				(font
					(size 0.7874 0.5842)
					(thickness 0.1524)
				)
				(justify left mirror)
			)
		)
		(property "Value" ""
			(at 0 0 90)
			(layer "B.Fab")
			(effects
				(font
					(size 1.27 1.27)
				)
				(justify mirror)
			)
		)
		(duplicate_pad_numbers_are_jumpers no)
		(fp_line
			(start 4.533392 -2.249932)
			(end -4.533392 -2.249932)
			(stroke
				(width 0.1524)
				(type default)
			)
			(layer "B.SilkS")
		)
		(fp_line
			(start -4.533392 -2.249932)
			(end -4.533392 2.249932)
			(stroke
				(width 0.1524)
				(type default)
			)
			(layer "B.SilkS")
		)
		(fp_line
			(start 4.533392 2.249932)
			(end 4.533392 -2.249932)
			(stroke
				(width 0.1524)
				(type default)
			)
			(layer "B.SilkS")
		)
		(fp_line
			(start -4.533392 2.249932)
			(end 4.533392 2.249932)
			(stroke
				(width 0.1524)
				(type default)
			)
			(layer "B.SilkS")
		)
		(fp_rect
			(start 4.533392 -2.326132)
			(end 5.39242 2.326132)
			(stroke
				(width 0)
				(type default)
			)
			(fill yes)
			(layer "B.SilkS")
		)
		(fp_line
			(start 3.750056 -2.249932)
			(end -3.750056 -2.249932)
			(stroke
				(width 0.1)
				(type default)
			)
			(layer "B.Fab")
		)
		(fp_line
			(start -3.750056 -2.249932)
			(end -3.750056 2.249932)
			(stroke
				(width 0.1)
				(type default)
			)
			(layer "B.Fab")
		)
		(fp_line
			(start 3.750056 2.249932)
			(end 3.750056 -2.249932)
			(stroke
				(width 0.1)
				(type default)
			)
			(layer "B.Fab")
		)
		(fp_line
			(start -3.750056 2.249932)
			(end 3.750056 2.249932)
			(stroke
				(width 0.1)
				(type default)
			)
			(layer "B.Fab")
		)
		(fp_text user "+"
			(at 6.322314 0.786384 0)
			(unlocked yes)
			(layer "B.SilkS")
			(effects
				(font
					(size 1.905 1.4224)
					(thickness 0.1524)
				)
				(justify left mirror)
			)
		)
		(fp_text user "-"
			(at -4.582668 1.44018 90)
			(unlocked yes)
			(layer "B.SilkS")
			(effects
				(font
					(size 1.905 1.4224)
					(thickness 0.1524)
				)
				(justify left mirror)
			)
		)
		(fp_text user "-"
			(at -4.8514 -0.14605 90)
			(unlocked yes)
			(layer "B.Fab")
			(effects
				(font
					(size 1.905 1.4224)
					(thickness 0.1524)
				)
				(justify left mirror)
			)
		)
		(fp_text user "+"
			(at 6.322314 0.786384 0)
			(unlocked yes)
			(layer "B.Fab")
			(effects
				(font
					(size 1.905 1.4224)
					(thickness 0.1524)
				)
				(justify left mirror)
			)
		)
		(pad "1" smd rect
			(at 3.199892 0 270)
			(size 2.413 2.8194)
			(layers "B.Cu" "B.Mask" "B.Paste")
			(net "PVDDCR_SOC_P0")
		)
		(pad "2" smd rect
			(at -3.199892 0 270)
			(size 2.413 2.8194)
			(layers "B.Cu" "B.Mask" "B.Paste")
			(net "GND")
		)
	)
	(footprint ""
		(layer "B.Cu")
		(at 378.878592 -395.148562 90)
		(property "Reference" "C1004"
			(at 0 0 90)
			(layer "B.SilkS")
			(hide yes)
			(effects
				(font
					(size 1.27 1.27)
				)
				(justify mirror)
			)
		)
		(property "Value" ""
			(at 0 0 90)
			(layer "B.Fab")
			(effects
				(font
					(size 1.27 1.27)
				)
				(justify mirror)
			)
		)
		(duplicate_pad_numbers_are_jumpers no)
		(fp_line
			(start 0.299974 -0.150114)
			(end -0.299974 -0.150114)
			(stroke
				(width 0.1)
				(type default)
			)
			(layer "B.Fab")
		)
		(fp_line
			(start -0.299974 -0.150114)
			(end -0.299974 0.150114)
			(stroke
				(width 0.1)
				(type default)
			)
			(layer "B.Fab")
		)
		(fp_line
			(start 0.299974 0.150114)
			(end 0.299974 -0.150114)
			(stroke
				(width 0.1)
				(type default)
			)
			(layer "B.Fab")
		)
		(fp_line
			(start -0.299974 0.150114)
			(end 0.299974 0.150114)
			(stroke
				(width 0.1)
				(type default)
			)
			(layer "B.Fab")
		)
		(pad "1" smd rect
			(at 0.2667 0 270)
			(size 0.3048 0.381)
			(layers "B.Cu" "B.Mask" "B.Paste")
			(net "P1V8_CPU0_RT3_1A")
		)
		(pad "2" smd rect
			(at -0.2667 0 270)
			(size 0.3048 0.381)
			(layers "B.Cu" "B.Mask" "B.Paste")
			(net "GND")
		)
	)
	(footprint ""
		(layer "B.Cu")
		(at 377.691142 -398.942052 90)
		(property "Reference" "C1044"
			(at 0 0 90)
			(layer "B.SilkS")
			(hide yes)
			(effects
				(font
					(size 1.27 1.27)
				)
				(justify mirror)
			)
		)
		(property "Value" ""
			(at 0 0 90)
			(layer "B.Fab")
			(effects
				(font
					(size 1.27 1.27)
				)
				(justify mirror)
			)
		)
		(duplicate_pad_numbers_are_jumpers no)
		(fp_line
			(start 0.7874 -0.4064)
			(end -0.7874 -0.4064)
			(stroke
				(width 0.1524)
				(type default)
			)
			(layer "B.SilkS")
		)
		(fp_line
			(start -0.7874 -0.4064)
			(end -0.7874 0.4064)
			(stroke
				(width 0.1524)
				(type default)
			)
			(layer "B.SilkS")
		)
		(fp_line
			(start 0.7874 0.4064)
			(end 0.7874 -0.4064)
			(stroke
				(width 0.1524)
				(type default)
			)
			(layer "B.SilkS")
		)
		(fp_line
			(start -0.7874 0.4064)
			(end 0.7874 0.4064)
			(stroke
				(width 0.1524)
				(type default)
			)
			(layer "B.SilkS")
		)
		(fp_line
			(start 0.67945 -0.305054)
			(end 0.12065 -0.305054)
			(stroke
				(width 0.1)
				(type default)
			)
			(layer "B.Fab")
		)
		(fp_line
			(start 0.12065 -0.305054)
			(end 0.12065 -0.2794)
			(stroke
				(width 0.1)
				(type default)
			)
			(layer "B.Fab")
		)
		(fp_line
			(start -0.12065 -0.3048)
			(end -0.67945 -0.3048)
			(stroke
				(width 0.1)
				(type default)
			)
			(layer "B.Fab")
		)
		(fp_line
			(start -0.67945 -0.3048)
			(end -0.67945 0.3048)
			(stroke
				(width 0.1)
				(type default)
			)
			(layer "B.Fab")
		)
		(fp_line
			(start 0.12065 -0.2794)
			(end -0.12065 -0.2794)
			(stroke
				(width 0.1)
				(type default)
			)
			(layer "B.Fab")
		)
		(fp_line
			(start -0.12065 -0.2794)
			(end -0.12065 -0.3048)
			(stroke
				(width 0.1)
				(type default)
			)
			(layer "B.Fab")
		)
		(fp_line
			(start 0.12065 0.2794)
			(end 0.12065 0.3048)
			(stroke
				(width 0.1)
				(type default)
			)
			(layer "B.Fab")
		)
		(fp_line
			(start -0.120396 0.2794)
			(end 0.12065 0.2794)
			(stroke
				(width 0.1)
				(type default)
			)
			(layer "B.Fab")
		)
		(fp_line
			(start 0.67945 0.3048)
			(end 0.67945 -0.305054)
			(stroke
				(width 0.1)
				(type default)
			)
			(layer "B.Fab")
		)
		(fp_line
			(start 0.12065 0.3048)
			(end 0.67945 0.3048)
			(stroke
				(width 0.1)
				(type default)
			)
			(layer "B.Fab")
		)
		(fp_line
			(start -0.120396 0.3048)
			(end -0.120396 0.2794)
			(stroke
				(width 0.1)
				(type default)
			)
			(layer "B.Fab")
		)
		(fp_line
			(start -0.67945 0.3048)
			(end -0.120396 0.3048)
			(stroke
				(width 0.1)
				(type default)
			)
			(layer "B.Fab")
		)
		(pad "1" smd circle
			(at 0.40005 0 270)
			(size 0 0)
			(layers "B.Cu" "B.Mask" "B.Paste")
			(net "P0V9_CPU0_RT_2D")
		)
		(pad "2" smd circle
			(at -0.40005 0 270)
			(size 0 0)
			(layers "B.Cu" "B.Mask" "B.Paste")
			(net "GND")
		)
	)
	(footprint ""
		(layer "B.Cu")
		(at 179.997608 -126.833376 90)
		(property "Reference" "R242"
			(at 0 0 90)
			(layer "B.SilkS")
			(hide yes)
			(effects
				(font
					(size 1.27 1.27)
				)
				(justify mirror)
			)
		)
		(property "Value" ""
			(at 0 0 90)
			(layer "B.Fab")
			(effects
				(font
					(size 1.27 1.27)
				)
				(justify mirror)
			)
		)
		(duplicate_pad_numbers_are_jumpers no)
		(fp_line
			(start 0.7874 -0.4064)
			(end -0.7874 -0.4064)
			(stroke
				(width 0.1524)
				(type default)
			)
			(layer "B.SilkS")
		)
		(fp_line
			(start -0.7874 -0.4064)
			(end -0.7874 0.4064)
			(stroke
				(width 0.1524)
				(type default)
			)
			(layer "B.SilkS")
		)
		(fp_line
			(start 0.7874 0.4064)
			(end 0.7874 -0.4064)
			(stroke
				(width 0.1524)
				(type default)
			)
			(layer "B.SilkS")
		)
		(fp_line
			(start -0.7874 0.4064)
			(end 0.7874 0.4064)
			(stroke
				(width 0.1524)
				(type default)
			)
			(layer "B.SilkS")
		)
		(fp_line
			(start 0.67945 -0.305054)
			(end 0.12065 -0.305054)
			(stroke
				(width 0.1)
				(type default)
			)
			(layer "B.Fab")
		)
		(fp_line
			(start 0.12065 -0.305054)
			(end 0.12065 -0.2794)
			(stroke
				(width 0.1)
				(type default)
			)
			(layer "B.Fab")
		)
		(fp_line
			(start -0.12065 -0.3048)
			(end -0.67945 -0.3048)
			(stroke
				(width 0.1)
				(type default)
			)
			(layer "B.Fab")
		)
		(fp_line
			(start -0.67945 -0.3048)
			(end -0.67945 0.3048)
			(stroke
				(width 0.1)
				(type default)
			)
			(layer "B.Fab")
		)
		(fp_line
			(start 0.12065 -0.2794)
			(end -0.12065 -0.2794)
			(stroke
				(width 0.1)
				(type default)
			)
			(layer "B.Fab")
		)
		(fp_line
			(start -0.12065 -0.2794)
			(end -0.12065 -0.3048)
			(stroke
				(width 0.1)
				(type default)
			)
			(layer "B.Fab")
		)
		(fp_line
			(start 0.12065 0.2794)
			(end 0.12065 0.3048)
			(stroke
				(width 0.1)
				(type default)
			)
			(layer "B.Fab")
		)
		(fp_line
			(start -0.120396 0.2794)
			(end 0.12065 0.2794)
			(stroke
				(width 0.1)
				(type default)
			)
			(layer "B.Fab")
		)
		(fp_line
			(start 0.67945 0.3048)
			(end 0.67945 -0.305054)
			(stroke
				(width 0.1)
				(type default)
			)
			(layer "B.Fab")
		)
		(fp_line
			(start 0.12065 0.3048)
			(end 0.67945 0.3048)
			(stroke
				(width 0.1)
				(type default)
			)
			(layer "B.Fab")
		)
		(fp_line
			(start -0.120396 0.3048)
			(end -0.120396 0.2794)
			(stroke
				(width 0.1)
				(type default)
			)
			(layer "B.Fab")
		)
		(fp_line
			(start -0.67945 0.3048)
			(end -0.120396 0.3048)
			(stroke
				(width 0.1)
				(type default)
			)
			(layer "B.Fab")
		)
		(pad "1" smd circle
			(at 0.40005 0 270)
			(size 0 0)
			(layers "B.Cu" "B.Mask" "B.Paste")
			(net "PWRGD_CPU0_PWROK")
		)
		(pad "2" smd circle
			(at -0.40005 0 270)
			(size 0 0)
			(layers "B.Cu" "B.Mask" "B.Paste")
			(net "FM_PWRGD_CPU0_PWROK")
		)
	)
	(footprint ""
		(layer "B.Cu")
		(at 181.525164 -23.655782 -90)
		(property "Reference" "R1319"
			(at 0 0 90)
			(layer "B.SilkS")
			(hide yes)
			(effects
				(font
					(size 1.27 1.27)
				)
				(justify mirror)
			)
		)
		(property "Value" ""
			(at 0 0 90)
			(layer "B.Fab")
			(effects
				(font
					(size 1.27 1.27)
				)
				(justify mirror)
			)
		)
		(duplicate_pad_numbers_are_jumpers no)
		(fp_line
			(start -0.7874 0.4064)
			(end 0.7874 0.4064)
			(stroke
				(width 0.1524)
				(type default)
			)
			(layer "B.SilkS")
		)
		(fp_line
			(start 0.7874 0.4064)
			(end 0.7874 -0.4064)
			(stroke
				(width 0.1524)
				(type default)
			)
			(layer "B.SilkS")
		)
		(fp_line
			(start -0.7874 -0.4064)
			(end -0.7874 0.4064)
			(stroke
				(width 0.1524)
				(type default)
			)
			(layer "B.SilkS")
		)
		(fp_line
			(start 0.7874 -0.4064)
			(end -0.7874 -0.4064)
			(stroke
				(width 0.1524)
				(type default)
			)
			(layer "B.SilkS")
		)
		(fp_line
			(start -0.67945 0.3048)
			(end -0.120396 0.3048)
			(stroke
				(width 0.1)
				(type default)
			)
			(layer "B.Fab")
		)
		(fp_line
			(start -0.120396 0.3048)
			(end -0.120396 0.2794)
			(stroke
				(width 0.1)
				(type default)
			)
			(layer "B.Fab")
		)
		(fp_line
			(start 0.12065 0.3048)
			(end 0.67945 0.3048)
			(stroke
				(width 0.1)
				(type default)
			)
			(layer "B.Fab")
		)
		(fp_line
			(start 0.67945 0.3048)
			(end 0.67945 -0.305054)
			(stroke
				(width 0.1)
				(type default)
			)
			(layer "B.Fab")
		)
		(fp_line
			(start -0.120396 0.2794)
			(end 0.12065 0.2794)
			(stroke
				(width 0.1)
				(type default)
			)
			(layer "B.Fab")
		)
		(fp_line
			(start 0.12065 0.2794)
			(end 0.12065 0.3048)
			(stroke
				(width 0.1)
				(type default)
			)
			(layer "B.Fab")
		)
		(fp_line
			(start -0.12065 -0.2794)
			(end -0.12065 -0.3048)
			(stroke
				(width 0.1)
				(type default)
			)
			(layer "B.Fab")
		)
		(fp_line
			(start 0.12065 -0.2794)
			(end -0.12065 -0.2794)
			(stroke
				(width 0.1)
				(type default)
			)
			(layer "B.Fab")
		)
		(fp_line
			(start -0.67945 -0.3048)
			(end -0.67945 0.3048)
			(stroke
				(width 0.1)
				(type default)
			)
			(layer "B.Fab")
		)
		(fp_line
			(start -0.12065 -0.3048)
			(end -0.67945 -0.3048)
			(stroke
				(width 0.1)
				(type default)
			)
			(layer "B.Fab")
		)
		(fp_line
			(start 0.12065 -0.305054)
			(end 0.12065 -0.2794)
			(stroke
				(width 0.1)
				(type default)
			)
			(layer "B.Fab")
		)
		(fp_line
			(start 0.67945 -0.305054)
			(end 0.12065 -0.305054)
			(stroke
				(width 0.1)
				(type default)
			)
			(layer "B.Fab")
		)
		(pad "1" smd circle
			(at 0.40005 0 90)
			(size 0 0)
			(layers "B.Cu" "B.Mask" "B.Paste")
			(net "SMB_CPU0_CPU1_APML_SCL")
		)
		(pad "2" smd circle
			(at -0.40005 0 90)
			(size 0 0)
			(layers "B.Cu" "B.Mask" "B.Paste")
			(net "P3V3_AUX")
		)
	)
	(footprint ""
		(layer "B.Cu")
		(at 204.438758 -68.229734)
		(property "Reference" "R74"
			(at 0 0 0)
			(layer "B.SilkS")
			(hide yes)
			(effects
				(font
					(size 1.27 1.27)
				)
				(justify mirror)
			)
		)
		(property "Value" ""
			(at 0 0 0)
			(layer "B.Fab")
			(effects
				(font
					(size 1.27 1.27)
				)
				(justify mirror)
			)
		)
		(duplicate_pad_numbers_are_jumpers no)
		(fp_line
			(start -0.7874 -0.4064)
			(end -0.7874 0.4064)
			(stroke
				(width 0.1524)
				(type default)
			)
			(layer "B.SilkS")
		)
		(fp_line
			(start -0.7874 0.4064)
			(end 0.7874 0.4064)
			(stroke
				(width 0.1524)
				(type default)
			)
			(layer "B.SilkS")
		)
		(fp_line
			(start 0.7874 -0.4064)
			(end -0.7874 -0.4064)
			(stroke
				(width 0.1524)
				(type default)
			)
			(layer "B.SilkS")
		)
		(fp_line
			(start 0.7874 0.4064)
			(end 0.7874 -0.4064)
			(stroke
				(width 0.1524)
				(type default)
			)
			(layer "B.SilkS")
		)
		(fp_line
			(start -0.67945 -0.3048)
			(end -0.67945 0.3048)
			(stroke
				(width 0.1)
				(type default)
			)
			(layer "B.Fab")
		)
		(fp_line
			(start -0.67945 0.3048)
			(end -0.120396 0.3048)
			(stroke
				(width 0.1)
				(type default)
			)
			(layer "B.Fab")
		)
		(fp_line
			(start -0.12065 -0.3048)
			(end -0.67945 -0.3048)
			(stroke
				(width 0.1)
				(type default)
			)
			(layer "B.Fab")
		)
		(fp_line
			(start -0.12065 -0.2794)
			(end -0.12065 -0.3048)
			(stroke
				(width 0.1)
				(type default)
			)
			(layer "B.Fab")
		)
		(fp_line
			(start -0.120396 0.2794)
			(end 0.12065 0.2794)
			(stroke
				(width 0.1)
				(type default)
			)
			(layer "B.Fab")
		)
		(fp_line
			(start -0.120396 0.3048)
			(end -0.120396 0.2794)
			(stroke
				(width 0.1)
				(type default)
			)
			(layer "B.Fab")
		)
		(fp_line
			(start 0.12065 -0.305054)
			(end 0.12065 -0.2794)
			(stroke
				(width 0.1)
				(type default)
			)
			(layer "B.Fab")
		)
		(fp_line
			(start 0.12065 -0.2794)
			(end -0.12065 -0.2794)
			(stroke
				(width 0.1)
				(type default)
			)
			(layer "B.Fab")
		)
		(fp_line
			(start 0.12065 0.2794)
			(end 0.12065 0.3048)
			(stroke
				(width 0.1)
				(type default)
			)
			(layer "B.Fab")
		)
		(fp_line
			(start 0.12065 0.3048)
			(end 0.67945 0.3048)
			(stroke
				(width 0.1)
				(type default)
			)
			(layer "B.Fab")
		)
		(fp_line
			(start 0.67945 -0.305054)
			(end 0.12065 -0.305054)
			(stroke
				(width 0.1)
				(type default)
			)
			(layer "B.Fab")
		)
		(fp_line
			(start 0.67945 0.3048)
			(end 0.67945 -0.305054)
			(stroke
				(width 0.1)
				(type default)
			)
			(layer "B.Fab")
		)
		(pad "1" smd circle
			(at 0.40005 0 180)
			(size 0 0)
			(layers "B.Cu" "B.Mask" "B.Paste")
			(net "NCSI_BMC_TX_EN_R")
		)
		(pad "2" smd circle
			(at -0.40005 0 180)
			(size 0 0)
			(layers "B.Cu" "B.Mask" "B.Paste")
			(net "RMII_BMC_OCP_TX_EN")
		)
	)
	(footprint ""
		(layer "B.Cu")
		(at 108.46181 -393.242546 180)
		(property "Reference" "R900"
			(at 0 0 0)
			(layer "B.SilkS")
			(hide yes)
			(effects
				(font
					(size 1.27 1.27)
				)
				(justify mirror)
			)
		)
		(property "Value" ""
			(at 0 0 0)
			(layer "B.Fab")
			(effects
				(font
					(size 1.27 1.27)
				)
				(justify mirror)
			)
		)
		(duplicate_pad_numbers_are_jumpers no)
		(fp_line
			(start 1.2954 0.5842)
			(end 1.2954 -0.5842)
			(stroke
				(width 0.1524)
				(type default)
			)
			(layer "B.SilkS")
		)
		(fp_line
			(start 1.2954 -0.5842)
			(end -1.2954 -0.5842)
			(stroke
				(width 0.1524)
				(type default)
			)
			(layer "B.SilkS")
		)
		(fp_line
			(start -1.2954 0.5842)
			(end 1.2954 0.5842)
			(stroke
				(width 0.1524)
				(type default)
			)
			(layer "B.SilkS")
		)
		(fp_line
			(start -1.2954 -0.5842)
			(end -1.2954 0.5842)
			(stroke
				(width 0.1524)
				(type default)
			)
			(layer "B.SilkS")
		)
		(fp_line
			(start 1.1938 0.4064)
			(end 1.1938 -0.406654)
			(stroke
				(width 0.1)
				(type default)
			)
			(layer "B.Fab")
		)
		(fp_line
			(start 1.1938 -0.406654)
			(end 0.8636 -0.406654)
			(stroke
				(width 0.1)
				(type default)
			)
			(layer "B.Fab")
		)
		(fp_line
			(start 0.8636 0.4572)
			(end 0.8636 0.4318)
			(stroke
				(width 0.1)
				(type default)
			)
			(layer "B.Fab")
		)
		(fp_line
			(start 0.8636 0.4318)
			(end 0.8636 0.4064)
			(stroke
				(width 0.1)
				(type default)
			)
			(layer "B.Fab")
		)
		(fp_line
			(start 0.8636 0.4064)
			(end 1.1938 0.4064)
			(stroke
				(width 0.1)
				(type default)
			)
			(layer "B.Fab")
		)
		(fp_line
			(start 0.8636 -0.406654)
			(end 0.8636 -0.4572)
			(stroke
				(width 0.1)
				(type default)
			)
			(layer "B.Fab")
		)
		(fp_line
			(start 0.8636 -0.4572)
			(end -0.8636 -0.4572)
			(stroke
				(width 0.1)
				(type default)
			)
			(layer "B.Fab")
		)
		(fp_line
			(start -0.8636 0.4572)
			(end 0.8636 0.4572)
			(stroke
				(width 0.1)
				(type default)
			)
			(layer "B.Fab")
		)
		(fp_line
			(start -0.8636 0.4064)
			(end -0.8636 0.4572)
			(stroke
				(width 0.1)
				(type default)
			)
			(layer "B.Fab")
		)
		(fp_line
			(start -0.8636 -0.406654)
			(end -1.1938 -0.406654)
			(stroke
				(width 0.1)
				(type default)
			)
			(layer "B.Fab")
		)
		(fp_line
			(start -0.8636 -0.4572)
			(end -0.8636 -0.406654)
			(stroke
				(width 0.1)
				(type default)
			)
			(layer "B.Fab")
		)
		(fp_line
			(start -1.1938 0.4064)
			(end -0.8636 0.4064)
			(stroke
				(width 0.1)
				(type default)
			)
			(layer "B.Fab")
		)
		(fp_line
			(start -1.1938 -0.406654)
			(end -1.1938 0.4064)
			(stroke
				(width 0.1)
				(type default)
			)
			(layer "B.Fab")
		)
		(pad "1" smd rect
			(at 0.7366 0 90)
			(size 0.7112 0.8128)
			(layers "B.Cu" "B.Mask" "B.Paste")
			(net "P0V9_CPU1_RT3_2A_2D")
		)
		(pad "2" smd rect
			(at -0.7366 0 90)
			(size 0.7112 0.8128)
			(layers "B.Cu" "B.Mask" "B.Paste")
			(net "P0V9_CPU1_RT3_2A")
		)
	)
	(footprint ""
		(layer "B.Cu")
		(at 112.19434 -62.01791 -90)
		(property "Reference" "R6226"
			(at 0 0 90)
			(layer "B.SilkS")
			(hide yes)
			(effects
				(font
					(size 1.27 1.27)
				)
				(justify mirror)
			)
		)
		(property "Value" ""
			(at 0 0 90)
			(layer "B.Fab")
			(effects
				(font
					(size 1.27 1.27)
				)
				(justify mirror)
			)
		)
		(duplicate_pad_numbers_are_jumpers no)
		(fp_line
			(start -0.7874 0.4064)
			(end 0.7874 0.4064)
			(stroke
				(width 0.1524)
				(type default)
			)
			(layer "B.SilkS")
		)
		(fp_line
			(start 0.7874 0.4064)
			(end 0.7874 -0.4064)
			(stroke
				(width 0.1524)
				(type default)
			)
			(layer "B.SilkS")
		)
		(fp_line
			(start -0.7874 -0.4064)
			(end -0.7874 0.4064)
			(stroke
				(width 0.1524)
				(type default)
			)
			(layer "B.SilkS")
		)
		(fp_line
			(start 0.7874 -0.4064)
			(end -0.7874 -0.4064)
			(stroke
				(width 0.1524)
				(type default)
			)
			(layer "B.SilkS")
		)
		(fp_line
			(start -0.67945 0.3048)
			(end -0.120396 0.3048)
			(stroke
				(width 0.1)
				(type default)
			)
			(layer "B.Fab")
		)
		(fp_line
			(start -0.120396 0.3048)
			(end -0.120396 0.2794)
			(stroke
				(width 0.1)
				(type default)
			)
			(layer "B.Fab")
		)
		(fp_line
			(start 0.12065 0.3048)
			(end 0.67945 0.3048)
			(stroke
				(width 0.1)
				(type default)
			)
			(layer "B.Fab")
		)
		(fp_line
			(start 0.67945 0.3048)
			(end 0.67945 -0.305054)
			(stroke
				(width 0.1)
				(type default)
			)
			(layer "B.Fab")
		)
		(fp_line
			(start -0.120396 0.2794)
			(end 0.12065 0.2794)
			(stroke
				(width 0.1)
				(type default)
			)
			(layer "B.Fab")
		)
		(fp_line
			(start 0.12065 0.2794)
			(end 0.12065 0.3048)
			(stroke
				(width 0.1)
				(type default)
			)
			(layer "B.Fab")
		)
		(fp_line
			(start -0.12065 -0.2794)
			(end -0.12065 -0.3048)
			(stroke
				(width 0.1)
				(type default)
			)
			(layer "B.Fab")
		)
		(fp_line
			(start 0.12065 -0.2794)
			(end -0.12065 -0.2794)
			(stroke
				(width 0.1)
				(type default)
			)
			(layer "B.Fab")
		)
		(fp_line
			(start -0.67945 -0.3048)
			(end -0.67945 0.3048)
			(stroke
				(width 0.1)
				(type default)
			)
			(layer "B.Fab")
		)
		(fp_line
			(start -0.12065 -0.3048)
			(end -0.67945 -0.3048)
			(stroke
				(width 0.1)
				(type default)
			)
			(layer "B.Fab")
		)
		(fp_line
			(start 0.12065 -0.305054)
			(end 0.12065 -0.2794)
			(stroke
				(width 0.1)
				(type default)
			)
			(layer "B.Fab")
		)
		(fp_line
			(start 0.67945 -0.305054)
			(end 0.12065 -0.305054)
			(stroke
				(width 0.1)
				(type default)
			)
			(layer "B.Fab")
		)
		(pad "1" smd circle
			(at 0.40005 0 90)
			(size 0 0)
			(layers "B.Cu" "B.Mask" "B.Paste")
			(net "P3V3_AUX")
		)
		(pad "2" smd circle
			(at -0.40005 0 90)
			(size 0 0)
			(layers "B.Cu" "B.Mask" "B.Paste")
			(net "SMB_USB_CPU0_HUB1_SCL_R2")
		)
	)
	(footprint ""
		(layer "B.Cu")
		(at 163.263326 -408.517344 90)
		(property "Reference" "C6755"
			(at 0 0 90)
			(layer "B.SilkS")
			(hide yes)
			(effects
				(font
					(size 1.27 1.27)
				)
				(justify mirror)
			)
		)
		(property "Value" ""
			(at 0 0 90)
			(layer "B.Fab")
			(effects
				(font
					(size 1.27 1.27)
				)
				(justify mirror)
			)
		)
		(duplicate_pad_numbers_are_jumpers no)
		(fp_line
			(start 0.299974 -0.150114)
			(end -0.299974 -0.150114)
			(stroke
				(width 0.1)
				(type default)
			)
			(layer "B.Fab")
		)
		(fp_line
			(start -0.299974 -0.150114)
			(end -0.299974 0.150114)
			(stroke
				(width 0.1)
				(type default)
			)
			(layer "B.Fab")
		)
		(fp_line
			(start 0.299974 0.150114)
			(end 0.299974 -0.150114)
			(stroke
				(width 0.1)
				(type default)
			)
			(layer "B.Fab")
		)
		(fp_line
			(start -0.299974 0.150114)
			(end 0.299974 0.150114)
			(stroke
				(width 0.1)
				(type default)
			)
			(layer "B.Fab")
		)
		(pad "1" smd rect
			(at 0.2667 0 270)
			(size 0.3048 0.381)
			(layers "B.Cu" "B.Mask" "B.Paste")
			(net "P5E_CPU1_P3_TX_BUF_C_DP<15>")
		)
		(pad "2" smd rect
			(at -0.2667 0 270)
			(size 0.3048 0.381)
			(layers "B.Cu" "B.Mask" "B.Paste")
			(net "P5E_CPU1_P3_TX_BUF_DP<15>")
		)
	)
	(footprint ""
		(layer "B.Cu")
		(at 99.001834 -249.368564 180)
		(property "Reference" "C2670"
			(at 0 0 0)
			(layer "B.SilkS")
			(hide yes)
			(effects
				(font
					(size 1.27 1.27)
				)
				(justify mirror)
			)
		)
		(property "Value" ""
			(at 0 0 0)
			(layer "B.Fab")
			(effects
				(font
					(size 1.27 1.27)
				)
				(justify mirror)
			)
		)
		(duplicate_pad_numbers_are_jumpers no)
		(fp_line
			(start 0.7874 0.4064)
			(end 0.7874 -0.4064)
			(stroke
				(width 0.1524)
				(type default)
			)
			(layer "B.SilkS")
		)
		(fp_line
			(start 0.7874 -0.4064)
			(end -0.7874 -0.4064)
			(stroke
				(width 0.1524)
				(type default)
			)
			(layer "B.SilkS")
		)
		(fp_line
			(start -0.7874 0.4064)
			(end 0.7874 0.4064)
			(stroke
				(width 0.1524)
				(type default)
			)
			(layer "B.SilkS")
		)
		(fp_line
			(start -0.7874 -0.4064)
			(end -0.7874 0.4064)
			(stroke
				(width 0.1524)
				(type default)
			)
			(layer "B.SilkS")
		)
		(fp_line
			(start 0.67945 0.3048)
			(end 0.67945 -0.305054)
			(stroke
				(width 0.1)
				(type default)
			)
			(layer "B.Fab")
		)
		(fp_line
			(start 0.67945 -0.305054)
			(end 0.12065 -0.305054)
			(stroke
				(width 0.1)
				(type default)
			)
			(layer "B.Fab")
		)
		(fp_line
			(start 0.12065 0.3048)
			(end 0.67945 0.3048)
			(stroke
				(width 0.1)
				(type default)
			)
			(layer "B.Fab")
		)
		(fp_line
			(start 0.12065 0.2794)
			(end 0.12065 0.3048)
			(stroke
				(width 0.1)
				(type default)
			)
			(layer "B.Fab")
		)
		(fp_line
			(start 0.12065 -0.2794)
			(end -0.12065 -0.2794)
			(stroke
				(width 0.1)
				(type default)
			)
			(layer "B.Fab")
		)
		(fp_line
			(start 0.12065 -0.305054)
			(end 0.12065 -0.2794)
			(stroke
				(width 0.1)
				(type default)
			)
			(layer "B.Fab")
		)
		(fp_line
			(start -0.120396 0.3048)
			(end -0.120396 0.2794)
			(stroke
				(width 0.1)
				(type default)
			)
			(layer "B.Fab")
		)
		(fp_line
			(start -0.120396 0.2794)
			(end 0.12065 0.2794)
			(stroke
				(width 0.1)
				(type default)
			)
			(layer "B.Fab")
		)
		(fp_line
			(start -0.12065 -0.2794)
			(end -0.12065 -0.3048)
			(stroke
				(width 0.1)
				(type default)
			)
			(layer "B.Fab")
		)
		(fp_line
			(start -0.12065 -0.3048)
			(end -0.67945 -0.3048)
			(stroke
				(width 0.1)
				(type default)
			)
			(layer "B.Fab")
		)
		(fp_line
			(start -0.67945 0.3048)
			(end -0.120396 0.3048)
			(stroke
				(width 0.1)
				(type default)
			)
			(layer "B.Fab")
		)
		(fp_line
			(start -0.67945 -0.3048)
			(end -0.67945 0.3048)
			(stroke
				(width 0.1)
				(type default)
			)
			(layer "B.Fab")
		)
		(pad "1" smd circle
			(at 0.40005 0)
			(size 0 0)
			(layers "B.Cu" "B.Mask" "B.Paste")
			(net "PVDD18_S5_P1")
		)
		(pad "2" smd circle
			(at -0.40005 0)
			(size 0 0)
			(layers "B.Cu" "B.Mask" "B.Paste")
			(net "GND")
		)
	)
	(footprint ""
		(layer "B.Cu")
		(at 428.98695 -36.007548 180)
		(property "Reference" "R1264"
			(at 0 0 0)
			(layer "B.SilkS")
			(hide yes)
			(effects
				(font
					(size 1.27 1.27)
				)
				(justify mirror)
			)
		)
		(property "Value" ""
			(at 0 0 0)
			(layer "B.Fab")
			(effects
				(font
					(size 1.27 1.27)
				)
				(justify mirror)
			)
		)
		(duplicate_pad_numbers_are_jumpers no)
		(fp_line
			(start 0.7874 0.4064)
			(end 0.7874 -0.4064)
			(stroke
				(width 0.1524)
				(type default)
			)
			(layer "B.SilkS")
		)
		(fp_line
			(start 0.7874 -0.4064)
			(end -0.7874 -0.4064)
			(stroke
				(width 0.1524)
				(type default)
			)
			(layer "B.SilkS")
		)
		(fp_line
			(start -0.7874 0.4064)
			(end 0.7874 0.4064)
			(stroke
				(width 0.1524)
				(type default)
			)
			(layer "B.SilkS")
		)
		(fp_line
			(start -0.7874 -0.4064)
			(end -0.7874 0.4064)
			(stroke
				(width 0.1524)
				(type default)
			)
			(layer "B.SilkS")
		)
		(fp_line
			(start 0.67945 0.3048)
			(end 0.67945 -0.305054)
			(stroke
				(width 0.1)
				(type default)
			)
			(layer "B.Fab")
		)
		(fp_line
			(start 0.67945 -0.305054)
			(end 0.12065 -0.305054)
			(stroke
				(width 0.1)
				(type default)
			)
			(layer "B.Fab")
		)
		(fp_line
			(start 0.12065 0.3048)
			(end 0.67945 0.3048)
			(stroke
				(width 0.1)
				(type default)
			)
			(layer "B.Fab")
		)
		(fp_line
			(start 0.12065 0.2794)
			(end 0.12065 0.3048)
			(stroke
				(width 0.1)
				(type default)
			)
			(layer "B.Fab")
		)
		(fp_line
			(start 0.12065 -0.2794)
			(end -0.12065 -0.2794)
			(stroke
				(width 0.1)
				(type default)
			)
			(layer "B.Fab")
		)
		(fp_line
			(start 0.12065 -0.305054)
			(end 0.12065 -0.2794)
			(stroke
				(width 0.1)
				(type default)
			)
			(layer "B.Fab")
		)
		(fp_line
			(start -0.120396 0.3048)
			(end -0.120396 0.2794)
			(stroke
				(width 0.1)
				(type default)
			)
			(layer "B.Fab")
		)
		(fp_line
			(start -0.120396 0.2794)
			(end 0.12065 0.2794)
			(stroke
				(width 0.1)
				(type default)
			)
			(layer "B.Fab")
		)
		(fp_line
			(start -0.12065 -0.2794)
			(end -0.12065 -0.3048)
			(stroke
				(width 0.1)
				(type default)
			)
			(layer "B.Fab")
		)
		(fp_line
			(start -0.12065 -0.3048)
			(end -0.67945 -0.3048)
			(stroke
				(width 0.1)
				(type default)
			)
			(layer "B.Fab")
		)
		(fp_line
			(start -0.67945 0.3048)
			(end -0.120396 0.3048)
			(stroke
				(width 0.1)
				(type default)
			)
			(layer "B.Fab")
		)
		(fp_line
			(start -0.67945 -0.3048)
			(end -0.67945 0.3048)
			(stroke
				(width 0.1)
				(type default)
			)
			(layer "B.Fab")
		)
		(pad "1" smd circle
			(at 0.40005 0)
			(size 0 0)
			(layers "B.Cu" "B.Mask" "B.Paste")
			(net "P1V8_AUX")
		)
		(pad "2" smd circle
			(at -0.40005 0)
			(size 0 0)
			(layers "B.Cu" "B.Mask" "B.Paste")
			(net "BIOS_DEBUG_MODE")
		)
	)
	(footprint ""
		(layer "B.Cu")
		(at 374.186958 -205.101952 90)
		(property "Reference" "R404"
			(at 0 0 90)
			(layer "B.SilkS")
			(hide yes)
			(effects
				(font
					(size 1.27 1.27)
				)
				(justify mirror)
			)
		)
		(property "Value" ""
			(at 0 0 90)
			(layer "B.Fab")
			(effects
				(font
					(size 1.27 1.27)
				)
				(justify mirror)
			)
		)
		(duplicate_pad_numbers_are_jumpers no)
		(fp_line
			(start 0.7874 -0.4064)
			(end -0.7874 -0.4064)
			(stroke
				(width 0.1524)
				(type default)
			)
			(layer "B.SilkS")
		)
		(fp_line
			(start -0.7874 -0.4064)
			(end -0.7874 0.4064)
			(stroke
				(width 0.1524)
				(type default)
			)
			(layer "B.SilkS")
		)
		(fp_line
			(start 0.7874 0.4064)
			(end 0.7874 -0.4064)
			(stroke
				(width 0.1524)
				(type default)
			)
			(layer "B.SilkS")
		)
		(fp_line
			(start -0.7874 0.4064)
			(end 0.7874 0.4064)
			(stroke
				(width 0.1524)
				(type default)
			)
			(layer "B.SilkS")
		)
		(fp_line
			(start 0.67945 -0.305054)
			(end 0.12065 -0.305054)
			(stroke
				(width 0.1)
				(type default)
			)
			(layer "B.Fab")
		)
		(fp_line
			(start 0.12065 -0.305054)
			(end 0.12065 -0.2794)
			(stroke
				(width 0.1)
				(type default)
			)
			(layer "B.Fab")
		)
		(fp_line
			(start -0.12065 -0.3048)
			(end -0.67945 -0.3048)
			(stroke
				(width 0.1)
				(type default)
			)
			(layer "B.Fab")
		)
		(fp_line
			(start -0.67945 -0.3048)
			(end -0.67945 0.3048)
			(stroke
				(width 0.1)
				(type default)
			)
			(layer "B.Fab")
		)
		(fp_line
			(start 0.12065 -0.2794)
			(end -0.12065 -0.2794)
			(stroke
				(width 0.1)
				(type default)
			)
			(layer "B.Fab")
		)
		(fp_line
			(start -0.12065 -0.2794)
			(end -0.12065 -0.3048)
			(stroke
				(width 0.1)
				(type default)
			)
			(layer "B.Fab")
		)
		(fp_line
			(start 0.12065 0.2794)
			(end 0.12065 0.3048)
			(stroke
				(width 0.1)
				(type default)
			)
			(layer "B.Fab")
		)
		(fp_line
			(start -0.120396 0.2794)
			(end 0.12065 0.2794)
			(stroke
				(width 0.1)
				(type default)
			)
			(layer "B.Fab")
		)
		(fp_line
			(start 0.67945 0.3048)
			(end 0.67945 -0.305054)
			(stroke
				(width 0.1)
				(type default)
			)
			(layer "B.Fab")
		)
		(fp_line
			(start 0.12065 0.3048)
			(end 0.67945 0.3048)
			(stroke
				(width 0.1)
				(type default)
			)
			(layer "B.Fab")
		)
		(fp_line
			(start -0.120396 0.3048)
			(end -0.120396 0.2794)
			(stroke
				(width 0.1)
				(type default)
			)
			(layer "B.Fab")
		)
		(fp_line
			(start -0.67945 0.3048)
			(end -0.120396 0.3048)
			(stroke
				(width 0.1)
				(type default)
			)
			(layer "B.Fab")
		)
		(pad "1" smd circle
			(at 0.40005 0 270)
			(size 0 0)
			(layers "B.Cu" "B.Mask" "B.Paste")
			(net "JTAG_CPU0_R_TDO")
		)
		(pad "2" smd circle
			(at -0.40005 0 270)
			(size 0 0)
			(layers "B.Cu" "B.Mask" "B.Paste")
			(net "JTAG_CPU0_TDO")
		)
	)
	(footprint ""
		(layer "B.Cu")
		(at 350.318832 -257.930142 180)
		(property "Reference" "C2637"
			(at 0 0 0)
			(layer "B.SilkS")
			(hide yes)
			(effects
				(font
					(size 1.27 1.27)
				)
				(justify mirror)
			)
		)
		(property "Value" ""
			(at 0 0 0)
			(layer "B.Fab")
			(effects
				(font
					(size 1.27 1.27)
				)
				(justify mirror)
			)
		)
		(duplicate_pad_numbers_are_jumpers no)
		(fp_line
			(start 0.7874 0.4064)
			(end 0.7874 -0.4064)
			(stroke
				(width 0.1524)
				(type default)
			)
			(layer "B.SilkS")
		)
		(fp_line
			(start 0.7874 -0.4064)
			(end -0.7874 -0.4064)
			(stroke
				(width 0.1524)
				(type default)
			)
			(layer "B.SilkS")
		)
		(fp_line
			(start -0.7874 0.4064)
			(end 0.7874 0.4064)
			(stroke
				(width 0.1524)
				(type default)
			)
			(layer "B.SilkS")
		)
		(fp_line
			(start -0.7874 -0.4064)
			(end -0.7874 0.4064)
			(stroke
				(width 0.1524)
				(type default)
			)
			(layer "B.SilkS")
		)
		(fp_line
			(start 0.67945 0.3048)
			(end 0.67945 -0.305054)
			(stroke
				(width 0.1)
				(type default)
			)
			(layer "B.Fab")
		)
		(fp_line
			(start 0.67945 -0.305054)
			(end 0.12065 -0.305054)
			(stroke
				(width 0.1)
				(type default)
			)
			(layer "B.Fab")
		)
		(fp_line
			(start 0.12065 0.3048)
			(end 0.67945 0.3048)
			(stroke
				(width 0.1)
				(type default)
			)
			(layer "B.Fab")
		)
		(fp_line
			(start 0.12065 0.2794)
			(end 0.12065 0.3048)
			(stroke
				(width 0.1)
				(type default)
			)
			(layer "B.Fab")
		)
		(fp_line
			(start 0.12065 -0.2794)
			(end -0.12065 -0.2794)
			(stroke
				(width 0.1)
				(type default)
			)
			(layer "B.Fab")
		)
		(fp_line
			(start 0.12065 -0.305054)
			(end 0.12065 -0.2794)
			(stroke
				(width 0.1)
				(type default)
			)
			(layer "B.Fab")
		)
		(fp_line
			(start -0.120396 0.3048)
			(end -0.120396 0.2794)
			(stroke
				(width 0.1)
				(type default)
			)
			(layer "B.Fab")
		)
		(fp_line
			(start -0.120396 0.2794)
			(end 0.12065 0.2794)
			(stroke
				(width 0.1)
				(type default)
			)
			(layer "B.Fab")
		)
		(fp_line
			(start -0.12065 -0.2794)
			(end -0.12065 -0.3048)
			(stroke
				(width 0.1)
				(type default)
			)
			(layer "B.Fab")
		)
		(fp_line
			(start -0.12065 -0.3048)
			(end -0.67945 -0.3048)
			(stroke
				(width 0.1)
				(type default)
			)
			(layer "B.Fab")
		)
		(fp_line
			(start -0.67945 0.3048)
			(end -0.120396 0.3048)
			(stroke
				(width 0.1)
				(type default)
			)
			(layer "B.Fab")
		)
		(fp_line
			(start -0.67945 -0.3048)
			(end -0.67945 0.3048)
			(stroke
				(width 0.1)
				(type default)
			)
			(layer "B.Fab")
		)
		(pad "1" smd circle
			(at 0.40005 0)
			(size 0 0)
			(layers "B.Cu" "B.Mask" "B.Paste")
			(net "PVDDIO_P0")
		)
		(pad "2" smd circle
			(at -0.40005 0)
			(size 0 0)
			(layers "B.Cu" "B.Mask" "B.Paste")
			(net "GND")
		)
	)
	(footprint ""
		(layer "B.Cu")
		(at 118.432834 -245.487952 180)
		(property "Reference" "C2330"
			(at 0 0 0)
			(layer "B.SilkS")
			(hide yes)
			(effects
				(font
					(size 1.27 1.27)
				)
				(justify mirror)
			)
		)
		(property "Value" ""
			(at 0 0 0)
			(layer "B.Fab")
			(effects
				(font
					(size 1.27 1.27)
				)
				(justify mirror)
			)
		)
		(duplicate_pad_numbers_are_jumpers no)
		(fp_line
			(start 0.7874 0.4064)
			(end 0.7874 -0.4064)
			(stroke
				(width 0.1524)
				(type default)
			)
			(layer "B.SilkS")
		)
		(fp_line
			(start 0.7874 -0.4064)
			(end -0.7874 -0.4064)
			(stroke
				(width 0.1524)
				(type default)
			)
			(layer "B.SilkS")
		)
		(fp_line
			(start -0.7874 0.4064)
			(end 0.7874 0.4064)
			(stroke
				(width 0.1524)
				(type default)
			)
			(layer "B.SilkS")
		)
		(fp_line
			(start -0.7874 -0.4064)
			(end -0.7874 0.4064)
			(stroke
				(width 0.1524)
				(type default)
			)
			(layer "B.SilkS")
		)
		(fp_line
			(start 0.67945 0.3048)
			(end 0.67945 -0.305054)
			(stroke
				(width 0.1)
				(type default)
			)
			(layer "B.Fab")
		)
		(fp_line
			(start 0.67945 -0.305054)
			(end 0.12065 -0.305054)
			(stroke
				(width 0.1)
				(type default)
			)
			(layer "B.Fab")
		)
		(fp_line
			(start 0.12065 0.3048)
			(end 0.67945 0.3048)
			(stroke
				(width 0.1)
				(type default)
			)
			(layer "B.Fab")
		)
		(fp_line
			(start 0.12065 0.2794)
			(end 0.12065 0.3048)
			(stroke
				(width 0.1)
				(type default)
			)
			(layer "B.Fab")
		)
		(fp_line
			(start 0.12065 -0.2794)
			(end -0.12065 -0.2794)
			(stroke
				(width 0.1)
				(type default)
			)
			(layer "B.Fab")
		)
		(fp_line
			(start 0.12065 -0.305054)
			(end 0.12065 -0.2794)
			(stroke
				(width 0.1)
				(type default)
			)
			(layer "B.Fab")
		)
		(fp_line
			(start -0.120396 0.3048)
			(end -0.120396 0.2794)
			(stroke
				(width 0.1)
				(type default)
			)
			(layer "B.Fab")
		)
		(fp_line
			(start -0.120396 0.2794)
			(end 0.12065 0.2794)
			(stroke
				(width 0.1)
				(type default)
			)
			(layer "B.Fab")
		)
		(fp_line
			(start -0.12065 -0.2794)
			(end -0.12065 -0.3048)
			(stroke
				(width 0.1)
				(type default)
			)
			(layer "B.Fab")
		)
		(fp_line
			(start -0.12065 -0.3048)
			(end -0.67945 -0.3048)
			(stroke
				(width 0.1)
				(type default)
			)
			(layer "B.Fab")
		)
		(fp_line
			(start -0.67945 0.3048)
			(end -0.120396 0.3048)
			(stroke
				(width 0.1)
				(type default)
			)
			(layer "B.Fab")
		)
		(fp_line
			(start -0.67945 -0.3048)
			(end -0.67945 0.3048)
			(stroke
				(width 0.1)
				(type default)
			)
			(layer "B.Fab")
		)
		(pad "1" smd circle
			(at 0.40005 0)
			(size 0 0)
			(layers "B.Cu" "B.Mask" "B.Paste")
			(net "PVDDCR_CPU0_P1")
		)
		(pad "2" smd circle
			(at -0.40005 0)
			(size 0 0)
			(layers "B.Cu" "B.Mask" "B.Paste")
			(net "GND")
		)
	)
	(footprint ""
		(layer "B.Cu")
		(at 349.834454 -262.70331)
		(property "Reference" "C2574"
			(at 0 0 0)
			(layer "B.SilkS")
			(hide yes)
			(effects
				(font
					(size 1.27 1.27)
				)
				(justify mirror)
			)
		)
		(property "Value" ""
			(at 0 0 0)
			(layer "B.Fab")
			(effects
				(font
					(size 1.27 1.27)
				)
				(justify mirror)
			)
		)
		(duplicate_pad_numbers_are_jumpers no)
		(fp_line
			(start -0.7874 -0.4064)
			(end -0.7874 0.4064)
			(stroke
				(width 0.1524)
				(type default)
			)
			(layer "B.SilkS")
		)
		(fp_line
			(start -0.7874 0.4064)
			(end 0.7874 0.4064)
			(stroke
				(width 0.1524)
				(type default)
			)
			(layer "B.SilkS")
		)
		(fp_line
			(start 0.7874 -0.4064)
			(end -0.7874 -0.4064)
			(stroke
				(width 0.1524)
				(type default)
			)
			(layer "B.SilkS")
		)
		(fp_line
			(start 0.7874 0.4064)
			(end 0.7874 -0.4064)
			(stroke
				(width 0.1524)
				(type default)
			)
			(layer "B.SilkS")
		)
		(fp_line
			(start -0.67945 -0.3048)
			(end -0.67945 0.3048)
			(stroke
				(width 0.1)
				(type default)
			)
			(layer "B.Fab")
		)
		(fp_line
			(start -0.67945 0.3048)
			(end -0.120396 0.3048)
			(stroke
				(width 0.1)
				(type default)
			)
			(layer "B.Fab")
		)
		(fp_line
			(start -0.12065 -0.3048)
			(end -0.67945 -0.3048)
			(stroke
				(width 0.1)
				(type default)
			)
			(layer "B.Fab")
		)
		(fp_line
			(start -0.12065 -0.2794)
			(end -0.12065 -0.3048)
			(stroke
				(width 0.1)
				(type default)
			)
			(layer "B.Fab")
		)
		(fp_line
			(start -0.120396 0.2794)
			(end 0.12065 0.2794)
			(stroke
				(width 0.1)
				(type default)
			)
			(layer "B.Fab")
		)
		(fp_line
			(start -0.120396 0.3048)
			(end -0.120396 0.2794)
			(stroke
				(width 0.1)
				(type default)
			)
			(layer "B.Fab")
		)
		(fp_line
			(start 0.12065 -0.305054)
			(end 0.12065 -0.2794)
			(stroke
				(width 0.1)
				(type default)
			)
			(layer "B.Fab")
		)
		(fp_line
			(start 0.12065 -0.2794)
			(end -0.12065 -0.2794)
			(stroke
				(width 0.1)
				(type default)
			)
			(layer "B.Fab")
		)
		(fp_line
			(start 0.12065 0.2794)
			(end 0.12065 0.3048)
			(stroke
				(width 0.1)
				(type default)
			)
			(layer "B.Fab")
		)
		(fp_line
			(start 0.12065 0.3048)
			(end 0.67945 0.3048)
			(stroke
				(width 0.1)
				(type default)
			)
			(layer "B.Fab")
		)
		(fp_line
			(start 0.67945 -0.305054)
			(end 0.12065 -0.305054)
			(stroke
				(width 0.1)
				(type default)
			)
			(layer "B.Fab")
		)
		(fp_line
			(start 0.67945 0.3048)
			(end 0.67945 -0.305054)
			(stroke
				(width 0.1)
				(type default)
			)
			(layer "B.Fab")
		)
		(pad "1" smd circle
			(at 0.40005 0 180)
			(size 0 0)
			(layers "B.Cu" "B.Mask" "B.Paste")
			(net "PVDDCR_SOC_P0")
		)
		(pad "2" smd circle
			(at -0.40005 0 180)
			(size 0 0)
			(layers "B.Cu" "B.Mask" "B.Paste")
			(net "GND")
		)
	)
	(footprint ""
		(layer "B.Cu")
		(at 65.3796 -14.8336)
		(property "Reference" "C1839"
			(at 0 0 0)
			(layer "B.SilkS")
			(hide yes)
			(effects
				(font
					(size 1.27 1.27)
				)
				(justify mirror)
			)
		)
		(property "Value" ""
			(at 0 0 0)
			(layer "B.Fab")
			(effects
				(font
					(size 1.27 1.27)
				)
				(justify mirror)
			)
		)
		(duplicate_pad_numbers_are_jumpers no)
		(fp_line
			(start -0.7874 -0.4064)
			(end -0.7874 0.4064)
			(stroke
				(width 0.1524)
				(type default)
			)
			(layer "B.SilkS")
		)
		(fp_line
			(start -0.7874 0.4064)
			(end 0.7874 0.4064)
			(stroke
				(width 0.1524)
				(type default)
			)
			(layer "B.SilkS")
		)
		(fp_line
			(start 0.7874 -0.4064)
			(end -0.7874 -0.4064)
			(stroke
				(width 0.1524)
				(type default)
			)
			(layer "B.SilkS")
		)
		(fp_line
			(start 0.7874 0.4064)
			(end 0.7874 -0.4064)
			(stroke
				(width 0.1524)
				(type default)
			)
			(layer "B.SilkS")
		)
		(fp_line
			(start -0.67945 -0.3048)
			(end -0.67945 0.3048)
			(stroke
				(width 0.1)
				(type default)
			)
			(layer "B.Fab")
		)
		(fp_line
			(start -0.67945 0.3048)
			(end -0.120396 0.3048)
			(stroke
				(width 0.1)
				(type default)
			)
			(layer "B.Fab")
		)
		(fp_line
			(start -0.12065 -0.3048)
			(end -0.67945 -0.3048)
			(stroke
				(width 0.1)
				(type default)
			)
			(layer "B.Fab")
		)
		(fp_line
			(start -0.12065 -0.2794)
			(end -0.12065 -0.3048)
			(stroke
				(width 0.1)
				(type default)
			)
			(layer "B.Fab")
		)
		(fp_line
			(start -0.120396 0.2794)
			(end 0.12065 0.2794)
			(stroke
				(width 0.1)
				(type default)
			)
			(layer "B.Fab")
		)
		(fp_line
			(start -0.120396 0.3048)
			(end -0.120396 0.2794)
			(stroke
				(width 0.1)
				(type default)
			)
			(layer "B.Fab")
		)
		(fp_line
			(start 0.12065 -0.305054)
			(end 0.12065 -0.2794)
			(stroke
				(width 0.1)
				(type default)
			)
			(layer "B.Fab")
		)
		(fp_line
			(start 0.12065 -0.2794)
			(end -0.12065 -0.2794)
			(stroke
				(width 0.1)
				(type default)
			)
			(layer "B.Fab")
		)
		(fp_line
			(start 0.12065 0.2794)
			(end 0.12065 0.3048)
			(stroke
				(width 0.1)
				(type default)
			)
			(layer "B.Fab")
		)
		(fp_line
			(start 0.12065 0.3048)
			(end 0.67945 0.3048)
			(stroke
				(width 0.1)
				(type default)
			)
			(layer "B.Fab")
		)
		(fp_line
			(start 0.67945 -0.305054)
			(end 0.12065 -0.305054)
			(stroke
				(width 0.1)
				(type default)
			)
			(layer "B.Fab")
		)
		(fp_line
			(start 0.67945 0.3048)
			(end 0.67945 -0.305054)
			(stroke
				(width 0.1)
				(type default)
			)
			(layer "B.Fab")
		)
		(pad "1" smd circle
			(at 0.40005 0 180)
			(size 0 0)
			(layers "B.Cu" "B.Mask" "B.Paste")
			(net "P12V_OCP_V3_2_R")
		)
		(pad "2" smd circle
			(at -0.40005 0 180)
			(size 0 0)
			(layers "B.Cu" "B.Mask" "B.Paste")
			(net "GND")
		)
	)
	(footprint ""
		(layer "B.Cu")
		(at 433.05222 -418.942266 180)
		(property "Reference" ""
			(at 0 0 0)
			(layer "B.SilkS")
			(hide yes)
			(effects
				(font
					(size 1.27 1.27)
				)
				(justify mirror)
			)
		)
		(property "Value" ""
			(at 0 0 0)
			(layer "B.Fab")
			(effects
				(font
					(size 1.27 1.27)
				)
				(justify mirror)
			)
		)
		(duplicate_pad_numbers_are_jumpers no)
		(pad "1" smd circle
			(at 0 0)
			(size 0.9906 0.9906)
			(layers "B.Cu" "B.Mask" "B.Paste")
			(net "Net_655")
		)
		(zone
			(layer "B.Cu")
			(hatch none 0.5)
			(connect_pads
				(clearance 0)
			)
			(min_thickness 0.25)
			(keepout
				(tracks not_allowed)
				(vias allowed)
				(pads allowed)
				(copperpour not_allowed)
				(footprints allowed)
			)
			(placement
				(enabled no)
				(sheetname "")
			)
			(fill
				(thermal_gap 0.5)
				(thermal_bridge_width 0.5)
				(island_removal_mode 0)
			)
			(polygon
				(pts
					(arc
						(start 434.67782 -418.942266)
						(mid 431.42662 -418.942266)
						(end 434.67782 -418.942266)
					)
				)
			)
		)
	)
	(footprint ""
		(layer "B.Cu")
		(at 317.967614 -389.49503)
		(property "Reference" "C7009"
			(at 3.4925 3.131312 0)
			(unlocked yes)
			(layer "B.SilkS")
			(effects
				(font
					(size 0.7874 0.5842)
					(thickness 0.1524)
				)
				(justify left mirror)
			)
		)
		(property "Value" ""
			(at 0 0 0)
			(layer "B.Fab")
			(effects
				(font
					(size 1.27 1.27)
				)
				(justify mirror)
			)
		)
		(duplicate_pad_numbers_are_jumpers no)
		(fp_line
			(start -4.53898 -2.15011)
			(end -4.53898 2.15011)
			(stroke
				(width 0.1524)
				(type default)
			)
			(layer "B.SilkS")
		)
		(fp_line
			(start -4.53898 2.15011)
			(end 4.53898 2.15011)
			(stroke
				(width 0.1524)
				(type default)
			)
			(layer "B.SilkS")
		)
		(fp_line
			(start 4.53898 -2.150618)
			(end 4.539742 2.152142)
			(stroke
				(width 0.1524)
				(type default)
			)
			(layer "B.SilkS")
		)
		(fp_line
			(start 4.53898 -2.15011)
			(end -4.53898 -2.15011)
			(stroke
				(width 0.1524)
				(type default)
			)
			(layer "B.SilkS")
		)
		(fp_line
			(start 4.53898 2.15011)
			(end 4.53898 -2.15011)
			(stroke
				(width 0.1524)
				(type default)
			)
			(layer "B.SilkS")
		)
		(fp_line
			(start 4.69138 -2.150618)
			(end 4.692396 2.161032)
			(stroke
				(width 0.1524)
				(type default)
			)
			(layer "B.SilkS")
		)
		(fp_line
			(start 4.83108 2.150364)
			(end 4.447794 2.149348)
			(stroke
				(width 0.1524)
				(type default)
			)
			(layer "B.SilkS")
		)
		(fp_line
			(start 4.84378 -2.150618)
			(end 4.53898 -2.150618)
			(stroke
				(width 0.1524)
				(type default)
			)
			(layer "B.SilkS")
		)
		(fp_line
			(start 4.84378 -2.150618)
			(end 4.842256 2.163064)
			(stroke
				(width 0.1524)
				(type default)
			)
			(layer "B.SilkS")
		)
		(fp_line
			(start -3.64998 -2.15011)
			(end -3.64998 2.15011)
			(stroke
				(width 0.1)
				(type default)
			)
			(layer "B.Fab")
		)
		(fp_line
			(start -3.64998 2.15011)
			(end 3.64998 2.15011)
			(stroke
				(width 0.1)
				(type default)
			)
			(layer "B.Fab")
		)
		(fp_line
			(start 3.64998 -2.15011)
			(end -3.64998 -2.15011)
			(stroke
				(width 0.1)
				(type default)
			)
			(layer "B.Fab")
		)
		(fp_line
			(start 3.64998 2.15011)
			(end 3.64998 -2.15011)
			(stroke
				(width 0.1)
				(type default)
			)
			(layer "B.Fab")
		)
		(fp_text user "-"
			(at -3.109214 2.382012 0)
			(unlocked yes)
			(layer "B.SilkS")
			(effects
				(font
					(size 1.905 1.4224)
					(thickness 0.1524)
				)
				(justify left mirror)
			)
		)
		(fp_text user "+"
			(at 6.214872 -0.337058 0)
			(unlocked yes)
			(layer "B.SilkS")
			(effects
				(font
					(size 1.905 1.4224)
					(thickness 0.1524)
				)
				(justify left mirror)
			)
		)
		(fp_text user "-"
			(at -4.313174 -0.094488 0)
			(unlocked yes)
			(layer "B.Fab")
			(effects
				(font
					(size 1.905 1.4224)
					(thickness 0.1524)
				)
				(justify left mirror)
			)
		)
		(fp_text user "+"
			(at 6.214872 -0.337058 0)
			(unlocked yes)
			(layer "B.Fab")
			(effects
				(font
					(size 1.905 1.4224)
					(thickness 0.1524)
				)
				(justify left mirror)
			)
		)
		(pad "1" smd rect
			(at 3.199892 0 180)
			(size 2.413 2.8194)
			(layers "B.Cu" "B.Mask" "B.Paste")
			(net "P0V9_CPU0_RT0_2A")
		)
		(pad "2" smd rect
			(at -3.199892 0 180)
			(size 2.413 2.8194)
			(layers "B.Cu" "B.Mask" "B.Paste")
			(net "GND")
		)
	)
	(footprint ""
		(layer "B.Cu")
		(at 121.706386 -254.194564)
		(property "Reference" "C2472"
			(at 0 0 0)
			(layer "B.SilkS")
			(hide yes)
			(effects
				(font
					(size 1.27 1.27)
				)
				(justify mirror)
			)
		)
		(property "Value" ""
			(at 0 0 0)
			(layer "B.Fab")
			(effects
				(font
					(size 1.27 1.27)
				)
				(justify mirror)
			)
		)
		(duplicate_pad_numbers_are_jumpers no)
		(fp_line
			(start -0.7874 -0.4064)
			(end -0.7874 0.4064)
			(stroke
				(width 0.1524)
				(type default)
			)
			(layer "B.SilkS")
		)
		(fp_line
			(start -0.7874 0.4064)
			(end 0.7874 0.4064)
			(stroke
				(width 0.1524)
				(type default)
			)
			(layer "B.SilkS")
		)
		(fp_line
			(start 0.7874 -0.4064)
			(end -0.7874 -0.4064)
			(stroke
				(width 0.1524)
				(type default)
			)
			(layer "B.SilkS")
		)
		(fp_line
			(start 0.7874 0.4064)
			(end 0.7874 -0.4064)
			(stroke
				(width 0.1524)
				(type default)
			)
			(layer "B.SilkS")
		)
		(fp_line
			(start -0.67945 -0.3048)
			(end -0.67945 0.3048)
			(stroke
				(width 0.1)
				(type default)
			)
			(layer "B.Fab")
		)
		(fp_line
			(start -0.67945 0.3048)
			(end -0.120396 0.3048)
			(stroke
				(width 0.1)
				(type default)
			)
			(layer "B.Fab")
		)
		(fp_line
			(start -0.12065 -0.3048)
			(end -0.67945 -0.3048)
			(stroke
				(width 0.1)
				(type default)
			)
			(layer "B.Fab")
		)
		(fp_line
			(start -0.12065 -0.2794)
			(end -0.12065 -0.3048)
			(stroke
				(width 0.1)
				(type default)
			)
			(layer "B.Fab")
		)
		(fp_line
			(start -0.120396 0.2794)
			(end 0.12065 0.2794)
			(stroke
				(width 0.1)
				(type default)
			)
			(layer "B.Fab")
		)
		(fp_line
			(start -0.120396 0.3048)
			(end -0.120396 0.2794)
			(stroke
				(width 0.1)
				(type default)
			)
			(layer "B.Fab")
		)
		(fp_line
			(start 0.12065 -0.305054)
			(end 0.12065 -0.2794)
			(stroke
				(width 0.1)
				(type default)
			)
			(layer "B.Fab")
		)
		(fp_line
			(start 0.12065 -0.2794)
			(end -0.12065 -0.2794)
			(stroke
				(width 0.1)
				(type default)
			)
			(layer "B.Fab")
		)
		(fp_line
			(start 0.12065 0.2794)
			(end 0.12065 0.3048)
			(stroke
				(width 0.1)
				(type default)
			)
			(layer "B.Fab")
		)
		(fp_line
			(start 0.12065 0.3048)
			(end 0.67945 0.3048)
			(stroke
				(width 0.1)
				(type default)
			)
			(layer "B.Fab")
		)
		(fp_line
			(start 0.67945 -0.305054)
			(end 0.12065 -0.305054)
			(stroke
				(width 0.1)
				(type default)
			)
			(layer "B.Fab")
		)
		(fp_line
			(start 0.67945 0.3048)
			(end 0.67945 -0.305054)
			(stroke
				(width 0.1)
				(type default)
			)
			(layer "B.Fab")
		)
		(pad "1" smd circle
			(at 0.40005 0 180)
			(size 0 0)
			(layers "B.Cu" "B.Mask" "B.Paste")
			(net "PVDDCR_SOC_P1")
		)
		(pad "2" smd circle
			(at -0.40005 0 180)
			(size 0 0)
			(layers "B.Cu" "B.Mask" "B.Paste")
			(net "GND")
		)
	)
	(footprint ""
		(layer "B.Cu")
		(at 149.419056 -390.560052 90)
		(property "Reference" "C406"
			(at 0 0 90)
			(layer "B.SilkS")
			(hide yes)
			(effects
				(font
					(size 1.27 1.27)
				)
				(justify mirror)
			)
		)
		(property "Value" ""
			(at 0 0 90)
			(layer "B.Fab")
			(effects
				(font
					(size 1.27 1.27)
				)
				(justify mirror)
			)
		)
		(duplicate_pad_numbers_are_jumpers no)
		(fp_line
			(start 0.7874 -0.4064)
			(end -0.7874 -0.4064)
			(stroke
				(width 0.1524)
				(type default)
			)
			(layer "B.SilkS")
		)
		(fp_line
			(start -0.7874 -0.4064)
			(end -0.7874 0.4064)
			(stroke
				(width 0.1524)
				(type default)
			)
			(layer "B.SilkS")
		)
		(fp_line
			(start 0.7874 0.4064)
			(end 0.7874 -0.4064)
			(stroke
				(width 0.1524)
				(type default)
			)
			(layer "B.SilkS")
		)
		(fp_line
			(start -0.7874 0.4064)
			(end 0.7874 0.4064)
			(stroke
				(width 0.1524)
				(type default)
			)
			(layer "B.SilkS")
		)
		(fp_line
			(start 0.67945 -0.305054)
			(end 0.12065 -0.305054)
			(stroke
				(width 0.1)
				(type default)
			)
			(layer "B.Fab")
		)
		(fp_line
			(start 0.12065 -0.305054)
			(end 0.12065 -0.2794)
			(stroke
				(width 0.1)
				(type default)
			)
			(layer "B.Fab")
		)
		(fp_line
			(start -0.12065 -0.3048)
			(end -0.67945 -0.3048)
			(stroke
				(width 0.1)
				(type default)
			)
			(layer "B.Fab")
		)
		(fp_line
			(start -0.67945 -0.3048)
			(end -0.67945 0.3048)
			(stroke
				(width 0.1)
				(type default)
			)
			(layer "B.Fab")
		)
		(fp_line
			(start 0.12065 -0.2794)
			(end -0.12065 -0.2794)
			(stroke
				(width 0.1)
				(type default)
			)
			(layer "B.Fab")
		)
		(fp_line
			(start -0.12065 -0.2794)
			(end -0.12065 -0.3048)
			(stroke
				(width 0.1)
				(type default)
			)
			(layer "B.Fab")
		)
		(fp_line
			(start 0.12065 0.2794)
			(end 0.12065 0.3048)
			(stroke
				(width 0.1)
				(type default)
			)
			(layer "B.Fab")
		)
		(fp_line
			(start -0.120396 0.2794)
			(end 0.12065 0.2794)
			(stroke
				(width 0.1)
				(type default)
			)
			(layer "B.Fab")
		)
		(fp_line
			(start 0.67945 0.3048)
			(end 0.67945 -0.305054)
			(stroke
				(width 0.1)
				(type default)
			)
			(layer "B.Fab")
		)
		(fp_line
			(start 0.12065 0.3048)
			(end 0.67945 0.3048)
			(stroke
				(width 0.1)
				(type default)
			)
			(layer "B.Fab")
		)
		(fp_line
			(start -0.120396 0.3048)
			(end -0.120396 0.2794)
			(stroke
				(width 0.1)
				(type default)
			)
			(layer "B.Fab")
		)
		(fp_line
			(start -0.67945 0.3048)
			(end -0.120396 0.3048)
			(stroke
				(width 0.1)
				(type default)
			)
			(layer "B.Fab")
		)
		(pad "1" smd circle
			(at 0.40005 0 270)
			(size 0 0)
			(layers "B.Cu" "B.Mask" "B.Paste")
			(net "P0V9_CPU1_RT2_2A")
		)
		(pad "2" smd circle
			(at -0.40005 0 270)
			(size 0 0)
			(layers "B.Cu" "B.Mask" "B.Paste")
			(net "GND")
		)
	)
	(footprint ""
		(layer "B.Cu")
		(at 169.686732 -435.851808 90)
		(property "Reference" "R4126"
			(at 0 0 90)
			(layer "B.SilkS")
			(hide yes)
			(effects
				(font
					(size 1.27 1.27)
				)
				(justify mirror)
			)
		)
		(property "Value" ""
			(at 0 0 90)
			(layer "B.Fab")
			(effects
				(font
					(size 1.27 1.27)
				)
				(justify mirror)
			)
		)
		(duplicate_pad_numbers_are_jumpers no)
		(fp_line
			(start 0.7874 -0.4064)
			(end -0.7874 -0.4064)
			(stroke
				(width 0.1524)
				(type default)
			)
			(layer "B.SilkS")
		)
		(fp_line
			(start -0.7874 -0.4064)
			(end -0.7874 0.4064)
			(stroke
				(width 0.1524)
				(type default)
			)
			(layer "B.SilkS")
		)
		(fp_line
			(start 0.7874 0.4064)
			(end 0.7874 -0.4064)
			(stroke
				(width 0.1524)
				(type default)
			)
			(layer "B.SilkS")
		)
		(fp_line
			(start -0.7874 0.4064)
			(end 0.7874 0.4064)
			(stroke
				(width 0.1524)
				(type default)
			)
			(layer "B.SilkS")
		)
		(fp_line
			(start 0.67945 -0.305054)
			(end 0.12065 -0.305054)
			(stroke
				(width 0.1)
				(type default)
			)
			(layer "B.Fab")
		)
		(fp_line
			(start 0.12065 -0.305054)
			(end 0.12065 -0.2794)
			(stroke
				(width 0.1)
				(type default)
			)
			(layer "B.Fab")
		)
		(fp_line
			(start -0.12065 -0.3048)
			(end -0.67945 -0.3048)
			(stroke
				(width 0.1)
				(type default)
			)
			(layer "B.Fab")
		)
		(fp_line
			(start -0.67945 -0.3048)
			(end -0.67945 0.3048)
			(stroke
				(width 0.1)
				(type default)
			)
			(layer "B.Fab")
		)
		(fp_line
			(start 0.12065 -0.2794)
			(end -0.12065 -0.2794)
			(stroke
				(width 0.1)
				(type default)
			)
			(layer "B.Fab")
		)
		(fp_line
			(start -0.12065 -0.2794)
			(end -0.12065 -0.3048)
			(stroke
				(width 0.1)
				(type default)
			)
			(layer "B.Fab")
		)
		(fp_line
			(start 0.12065 0.2794)
			(end 0.12065 0.3048)
			(stroke
				(width 0.1)
				(type default)
			)
			(layer "B.Fab")
		)
		(fp_line
			(start -0.120396 0.2794)
			(end 0.12065 0.2794)
			(stroke
				(width 0.1)
				(type default)
			)
			(layer "B.Fab")
		)
		(fp_line
			(start 0.67945 0.3048)
			(end 0.67945 -0.305054)
			(stroke
				(width 0.1)
				(type default)
			)
			(layer "B.Fab")
		)
		(fp_line
			(start 0.12065 0.3048)
			(end 0.67945 0.3048)
			(stroke
				(width 0.1)
				(type default)
			)
			(layer "B.Fab")
		)
		(fp_line
			(start -0.120396 0.3048)
			(end -0.120396 0.2794)
			(stroke
				(width 0.1)
				(type default)
			)
			(layer "B.Fab")
		)
		(fp_line
			(start -0.67945 0.3048)
			(end -0.120396 0.3048)
			(stroke
				(width 0.1)
				(type default)
			)
			(layer "B.Fab")
		)
		(pad "1" smd circle
			(at 0.40005 0 270)
			(size 0 0)
			(layers "B.Cu" "B.Mask" "B.Paste")
			(net "P3V3_AUX")
		)
		(pad "2" smd circle
			(at -0.40005 0 270)
			(size 0 0)
			(layers "B.Cu" "B.Mask" "B.Paste")
			(net "PRSNT_CABLE_GPU_B3")
		)
	)
	(footprint ""
		(layer "B.Cu")
		(at 344.306144 -395.148562 90)
		(property "Reference" "C603"
			(at 0 0 90)
			(layer "B.SilkS")
			(hide yes)
			(effects
				(font
					(size 1.27 1.27)
				)
				(justify mirror)
			)
		)
		(property "Value" ""
			(at 0 0 90)
			(layer "B.Fab")
			(effects
				(font
					(size 1.27 1.27)
				)
				(justify mirror)
			)
		)
		(duplicate_pad_numbers_are_jumpers no)
		(fp_line
			(start 0.299974 -0.150114)
			(end -0.299974 -0.150114)
			(stroke
				(width 0.1)
				(type default)
			)
			(layer "B.Fab")
		)
		(fp_line
			(start -0.299974 -0.150114)
			(end -0.299974 0.150114)
			(stroke
				(width 0.1)
				(type default)
			)
			(layer "B.Fab")
		)
		(fp_line
			(start 0.299974 0.150114)
			(end 0.299974 -0.150114)
			(stroke
				(width 0.1)
				(type default)
			)
			(layer "B.Fab")
		)
		(fp_line
			(start -0.299974 0.150114)
			(end 0.299974 0.150114)
			(stroke
				(width 0.1)
				(type default)
			)
			(layer "B.Fab")
		)
		(pad "1" smd rect
			(at 0.2667 0 270)
			(size 0.3048 0.381)
			(layers "B.Cu" "B.Mask" "B.Paste")
			(net "P1V8_CPU0_RT1_1A")
		)
		(pad "2" smd rect
			(at -0.2667 0 270)
			(size 0.3048 0.381)
			(layers "B.Cu" "B.Mask" "B.Paste")
			(net "GND")
		)
	)
	(footprint ""
		(layer "B.Cu")
		(at 404.922736 -164.804852 90)
		(property "Reference" "PC588_2"
			(at 0 0 90)
			(layer "B.SilkS")
			(hide yes)
			(effects
				(font
					(size 1.27 1.27)
				)
				(justify mirror)
			)
		)
		(property "Value" ""
			(at 0 0 90)
			(layer "B.Fab")
			(effects
				(font
					(size 1.27 1.27)
				)
				(justify mirror)
			)
		)
		(duplicate_pad_numbers_are_jumpers no)
		(fp_line
			(start 1.524 -0.762)
			(end -1.524 -0.762)
			(stroke
				(width 0.1524)
				(type default)
			)
			(layer "B.SilkS")
		)
		(fp_line
			(start -1.524 -0.762)
			(end -1.524 0.762)
			(stroke
				(width 0.1524)
				(type default)
			)
			(layer "B.SilkS")
		)
		(fp_line
			(start 1.524 0.762)
			(end 1.524 -0.762)
			(stroke
				(width 0.1524)
				(type default)
			)
			(layer "B.SilkS")
		)
		(fp_line
			(start -1.524 0.762)
			(end 1.524 0.762)
			(stroke
				(width 0.1524)
				(type default)
			)
			(layer "B.SilkS")
		)
		(fp_line
			(start 1.1049 -0.724916)
			(end 1.1049 0.724916)
			(stroke
				(width 0.1)
				(type default)
			)
			(layer "B.Fab")
		)
		(fp_line
			(start -1.1049 -0.724916)
			(end 1.1049 -0.724916)
			(stroke
				(width 0.1)
				(type default)
			)
			(layer "B.Fab")
		)
		(fp_line
			(start 1.1049 0.724916)
			(end -1.1049 0.724916)
			(stroke
				(width 0.1)
				(type default)
			)
			(layer "B.Fab")
		)
		(fp_line
			(start -1.1049 0.724916)
			(end -1.1049 -0.724916)
			(stroke
				(width 0.1)
				(type default)
			)
			(layer "B.Fab")
		)
		(pad "1" smd rect
			(at 0.889 0 90)
			(size 1.016 1.27)
			(layers "B.Cu" "B.Mask" "B.Paste")
			(net "SW_P12V_AUX_PVDDCR_SOC_P0_FLT")
		)
		(pad "2" smd rect
			(at -0.889 0 90)
			(size 1.016 1.27)
			(layers "B.Cu" "B.Mask" "B.Paste")
			(net "GND")
		)
	)
	(footprint ""
		(layer "B.Cu")
		(at 138.65352 -37.717222 180)
		(property "Reference" "C6056"
			(at 0 0 0)
			(layer "B.SilkS")
			(hide yes)
			(effects
				(font
					(size 1.27 1.27)
				)
				(justify mirror)
			)
		)
		(property "Value" ""
			(at 0 0 0)
			(layer "B.Fab")
			(effects
				(font
					(size 1.27 1.27)
				)
				(justify mirror)
			)
		)
		(duplicate_pad_numbers_are_jumpers no)
		(fp_line
			(start 0.7874 0.4064)
			(end 0.7874 -0.4064)
			(stroke
				(width 0.1524)
				(type default)
			)
			(layer "B.SilkS")
		)
		(fp_line
			(start 0.7874 -0.4064)
			(end -0.7874 -0.4064)
			(stroke
				(width 0.1524)
				(type default)
			)
			(layer "B.SilkS")
		)
		(fp_line
			(start -0.7874 0.4064)
			(end 0.7874 0.4064)
			(stroke
				(width 0.1524)
				(type default)
			)
			(layer "B.SilkS")
		)
		(fp_line
			(start -0.7874 -0.4064)
			(end -0.7874 0.4064)
			(stroke
				(width 0.1524)
				(type default)
			)
			(layer "B.SilkS")
		)
		(fp_line
			(start 0.67945 0.3048)
			(end 0.67945 -0.305054)
			(stroke
				(width 0.1)
				(type default)
			)
			(layer "B.Fab")
		)
		(fp_line
			(start 0.67945 -0.305054)
			(end 0.12065 -0.305054)
			(stroke
				(width 0.1)
				(type default)
			)
			(layer "B.Fab")
		)
		(fp_line
			(start 0.12065 0.3048)
			(end 0.67945 0.3048)
			(stroke
				(width 0.1)
				(type default)
			)
			(layer "B.Fab")
		)
		(fp_line
			(start 0.12065 0.2794)
			(end 0.12065 0.3048)
			(stroke
				(width 0.1)
				(type default)
			)
			(layer "B.Fab")
		)
		(fp_line
			(start 0.12065 -0.2794)
			(end -0.12065 -0.2794)
			(stroke
				(width 0.1)
				(type default)
			)
			(layer "B.Fab")
		)
		(fp_line
			(start 0.12065 -0.305054)
			(end 0.12065 -0.2794)
			(stroke
				(width 0.1)
				(type default)
			)
			(layer "B.Fab")
		)
		(fp_line
			(start -0.120396 0.3048)
			(end -0.120396 0.2794)
			(stroke
				(width 0.1)
				(type default)
			)
			(layer "B.Fab")
		)
		(fp_line
			(start -0.120396 0.2794)
			(end 0.12065 0.2794)
			(stroke
				(width 0.1)
				(type default)
			)
			(layer "B.Fab")
		)
		(fp_line
			(start -0.12065 -0.2794)
			(end -0.12065 -0.3048)
			(stroke
				(width 0.1)
				(type default)
			)
			(layer "B.Fab")
		)
		(fp_line
			(start -0.12065 -0.3048)
			(end -0.67945 -0.3048)
			(stroke
				(width 0.1)
				(type default)
			)
			(layer "B.Fab")
		)
		(fp_line
			(start -0.67945 0.3048)
			(end -0.120396 0.3048)
			(stroke
				(width 0.1)
				(type default)
			)
			(layer "B.Fab")
		)
		(fp_line
			(start -0.67945 -0.3048)
			(end -0.67945 0.3048)
			(stroke
				(width 0.1)
				(type default)
			)
			(layer "B.Fab")
		)
		(pad "1" smd circle
			(at 0.40005 0)
			(size 0 0)
			(layers "B.Cu" "B.Mask" "B.Paste")
			(net "P1V2_AUX")
		)
		(pad "2" smd circle
			(at -0.40005 0)
			(size 0 0)
			(layers "B.Cu" "B.Mask" "B.Paste")
			(net "GND")
		)
	)
	(footprint ""
		(layer "B.Cu")
		(at 370.046758 -248.47931)
		(property "Reference" "C2195"
			(at 0 0 0)
			(layer "B.SilkS")
			(hide yes)
			(effects
				(font
					(size 1.27 1.27)
				)
				(justify mirror)
			)
		)
		(property "Value" ""
			(at 0 0 0)
			(layer "B.Fab")
			(effects
				(font
					(size 1.27 1.27)
				)
				(justify mirror)
			)
		)
		(duplicate_pad_numbers_are_jumpers no)
		(fp_line
			(start -0.7874 -0.4064)
			(end -0.7874 0.4064)
			(stroke
				(width 0.1524)
				(type default)
			)
			(layer "B.SilkS")
		)
		(fp_line
			(start -0.7874 0.4064)
			(end 0.7874 0.4064)
			(stroke
				(width 0.1524)
				(type default)
			)
			(layer "B.SilkS")
		)
		(fp_line
			(start 0.7874 -0.4064)
			(end -0.7874 -0.4064)
			(stroke
				(width 0.1524)
				(type default)
			)
			(layer "B.SilkS")
		)
		(fp_line
			(start 0.7874 0.4064)
			(end 0.7874 -0.4064)
			(stroke
				(width 0.1524)
				(type default)
			)
			(layer "B.SilkS")
		)
		(fp_line
			(start -0.67945 -0.3048)
			(end -0.67945 0.3048)
			(stroke
				(width 0.1)
				(type default)
			)
			(layer "B.Fab")
		)
		(fp_line
			(start -0.67945 0.3048)
			(end -0.120396 0.3048)
			(stroke
				(width 0.1)
				(type default)
			)
			(layer "B.Fab")
		)
		(fp_line
			(start -0.12065 -0.3048)
			(end -0.67945 -0.3048)
			(stroke
				(width 0.1)
				(type default)
			)
			(layer "B.Fab")
		)
		(fp_line
			(start -0.12065 -0.2794)
			(end -0.12065 -0.3048)
			(stroke
				(width 0.1)
				(type default)
			)
			(layer "B.Fab")
		)
		(fp_line
			(start -0.120396 0.2794)
			(end 0.12065 0.2794)
			(stroke
				(width 0.1)
				(type default)
			)
			(layer "B.Fab")
		)
		(fp_line
			(start -0.120396 0.3048)
			(end -0.120396 0.2794)
			(stroke
				(width 0.1)
				(type default)
			)
			(layer "B.Fab")
		)
		(fp_line
			(start 0.12065 -0.305054)
			(end 0.12065 -0.2794)
			(stroke
				(width 0.1)
				(type default)
			)
			(layer "B.Fab")
		)
		(fp_line
			(start 0.12065 -0.2794)
			(end -0.12065 -0.2794)
			(stroke
				(width 0.1)
				(type default)
			)
			(layer "B.Fab")
		)
		(fp_line
			(start 0.12065 0.2794)
			(end 0.12065 0.3048)
			(stroke
				(width 0.1)
				(type default)
			)
			(layer "B.Fab")
		)
		(fp_line
			(start 0.12065 0.3048)
			(end 0.67945 0.3048)
			(stroke
				(width 0.1)
				(type default)
			)
			(layer "B.Fab")
		)
		(fp_line
			(start 0.67945 -0.305054)
			(end 0.12065 -0.305054)
			(stroke
				(width 0.1)
				(type default)
			)
			(layer "B.Fab")
		)
		(fp_line
			(start 0.67945 0.3048)
			(end 0.67945 -0.305054)
			(stroke
				(width 0.1)
				(type default)
			)
			(layer "B.Fab")
		)
		(pad "1" smd circle
			(at 0.40005 0 180)
			(size 0 0)
			(layers "B.Cu" "B.Mask" "B.Paste")
			(net "PVDDCR_CPU0_P0")
		)
		(pad "2" smd circle
			(at -0.40005 0 180)
			(size 0 0)
			(layers "B.Cu" "B.Mask" "B.Paste")
			(net "GND")
		)
	)
	(footprint ""
		(layer "B.Cu")
		(at 199.517 -136.652 90)
		(property "Reference" "R8105"
			(at 0 0 90)
			(layer "B.SilkS")
			(hide yes)
			(effects
				(font
					(size 1.27 1.27)
				)
				(justify mirror)
			)
		)
		(property "Value" ""
			(at 0 0 90)
			(layer "B.Fab")
			(effects
				(font
					(size 1.27 1.27)
				)
				(justify mirror)
			)
		)
		(duplicate_pad_numbers_are_jumpers no)
		(fp_line
			(start 0.7874 -0.4064)
			(end -0.7874 -0.4064)
			(stroke
				(width 0.1524)
				(type default)
			)
			(layer "B.SilkS")
		)
		(fp_line
			(start -0.7874 -0.4064)
			(end -0.7874 0.4064)
			(stroke
				(width 0.1524)
				(type default)
			)
			(layer "B.SilkS")
		)
		(fp_line
			(start 0.7874 0.4064)
			(end 0.7874 -0.4064)
			(stroke
				(width 0.1524)
				(type default)
			)
			(layer "B.SilkS")
		)
		(fp_line
			(start -0.7874 0.4064)
			(end 0.7874 0.4064)
			(stroke
				(width 0.1524)
				(type default)
			)
			(layer "B.SilkS")
		)
		(fp_line
			(start 0.67945 -0.305054)
			(end 0.12065 -0.305054)
			(stroke
				(width 0.1)
				(type default)
			)
			(layer "B.Fab")
		)
		(fp_line
			(start 0.12065 -0.305054)
			(end 0.12065 -0.2794)
			(stroke
				(width 0.1)
				(type default)
			)
			(layer "B.Fab")
		)
		(fp_line
			(start -0.12065 -0.3048)
			(end -0.67945 -0.3048)
			(stroke
				(width 0.1)
				(type default)
			)
			(layer "B.Fab")
		)
		(fp_line
			(start -0.67945 -0.3048)
			(end -0.67945 0.3048)
			(stroke
				(width 0.1)
				(type default)
			)
			(layer "B.Fab")
		)
		(fp_line
			(start 0.12065 -0.2794)
			(end -0.12065 -0.2794)
			(stroke
				(width 0.1)
				(type default)
			)
			(layer "B.Fab")
		)
		(fp_line
			(start -0.12065 -0.2794)
			(end -0.12065 -0.3048)
			(stroke
				(width 0.1)
				(type default)
			)
			(layer "B.Fab")
		)
		(fp_line
			(start 0.12065 0.2794)
			(end 0.12065 0.3048)
			(stroke
				(width 0.1)
				(type default)
			)
			(layer "B.Fab")
		)
		(fp_line
			(start -0.120396 0.2794)
			(end 0.12065 0.2794)
			(stroke
				(width 0.1)
				(type default)
			)
			(layer "B.Fab")
		)
		(fp_line
			(start 0.67945 0.3048)
			(end 0.67945 -0.305054)
			(stroke
				(width 0.1)
				(type default)
			)
			(layer "B.Fab")
		)
		(fp_line
			(start 0.12065 0.3048)
			(end 0.67945 0.3048)
			(stroke
				(width 0.1)
				(type default)
			)
			(layer "B.Fab")
		)
		(fp_line
			(start -0.120396 0.3048)
			(end -0.120396 0.2794)
			(stroke
				(width 0.1)
				(type default)
			)
			(layer "B.Fab")
		)
		(fp_line
			(start -0.67945 0.3048)
			(end -0.120396 0.3048)
			(stroke
				(width 0.1)
				(type default)
			)
			(layer "B.Fab")
		)
		(pad "1" smd circle
			(at 0.40005 0 270)
			(size 0 0)
			(layers "B.Cu" "B.Mask" "B.Paste")
			(net "FM_AC_PWR_BTN_PLD_ISO_R_N")
		)
		(pad "2" smd circle
			(at -0.40005 0 270)
			(size 0 0)
			(layers "B.Cu" "B.Mask" "B.Paste")
			(net "FM_AC_PWR_BTN_PLD_ISO_N")
		)
	)
	(footprint ""
		(layer "B.Cu")
		(at 173.71314 -427.92904 180)
		(property "Reference" "R6237"
			(at 0 0 0)
			(layer "B.SilkS")
			(hide yes)
			(effects
				(font
					(size 1.27 1.27)
				)
				(justify mirror)
			)
		)
		(property "Value" ""
			(at 0 0 0)
			(layer "B.Fab")
			(effects
				(font
					(size 1.27 1.27)
				)
				(justify mirror)
			)
		)
		(duplicate_pad_numbers_are_jumpers no)
		(fp_line
			(start 0.7874 0.4064)
			(end 0.7874 -0.4064)
			(stroke
				(width 0.1524)
				(type default)
			)
			(layer "B.SilkS")
		)
		(fp_line
			(start 0.7874 -0.4064)
			(end -0.7874 -0.4064)
			(stroke
				(width 0.1524)
				(type default)
			)
			(layer "B.SilkS")
		)
		(fp_line
			(start -0.7874 0.4064)
			(end 0.7874 0.4064)
			(stroke
				(width 0.1524)
				(type default)
			)
			(layer "B.SilkS")
		)
		(fp_line
			(start -0.7874 -0.4064)
			(end -0.7874 0.4064)
			(stroke
				(width 0.1524)
				(type default)
			)
			(layer "B.SilkS")
		)
		(fp_line
			(start 0.67945 0.3048)
			(end 0.67945 -0.305054)
			(stroke
				(width 0.1)
				(type default)
			)
			(layer "B.Fab")
		)
		(fp_line
			(start 0.67945 -0.305054)
			(end 0.12065 -0.305054)
			(stroke
				(width 0.1)
				(type default)
			)
			(layer "B.Fab")
		)
		(fp_line
			(start 0.12065 0.3048)
			(end 0.67945 0.3048)
			(stroke
				(width 0.1)
				(type default)
			)
			(layer "B.Fab")
		)
		(fp_line
			(start 0.12065 0.2794)
			(end 0.12065 0.3048)
			(stroke
				(width 0.1)
				(type default)
			)
			(layer "B.Fab")
		)
		(fp_line
			(start 0.12065 -0.2794)
			(end -0.12065 -0.2794)
			(stroke
				(width 0.1)
				(type default)
			)
			(layer "B.Fab")
		)
		(fp_line
			(start 0.12065 -0.305054)
			(end 0.12065 -0.2794)
			(stroke
				(width 0.1)
				(type default)
			)
			(layer "B.Fab")
		)
		(fp_line
			(start -0.120396 0.3048)
			(end -0.120396 0.2794)
			(stroke
				(width 0.1)
				(type default)
			)
			(layer "B.Fab")
		)
		(fp_line
			(start -0.120396 0.2794)
			(end 0.12065 0.2794)
			(stroke
				(width 0.1)
				(type default)
			)
			(layer "B.Fab")
		)
		(fp_line
			(start -0.12065 -0.2794)
			(end -0.12065 -0.3048)
			(stroke
				(width 0.1)
				(type default)
			)
			(layer "B.Fab")
		)
		(fp_line
			(start -0.12065 -0.3048)
			(end -0.67945 -0.3048)
			(stroke
				(width 0.1)
				(type default)
			)
			(layer "B.Fab")
		)
		(fp_line
			(start -0.67945 0.3048)
			(end -0.120396 0.3048)
			(stroke
				(width 0.1)
				(type default)
			)
			(layer "B.Fab")
		)
		(fp_line
			(start -0.67945 -0.3048)
			(end -0.67945 0.3048)
			(stroke
				(width 0.1)
				(type default)
			)
			(layer "B.Fab")
		)
		(pad "1" smd circle
			(at 0.40005 0)
			(size 0 0)
			(layers "B.Cu" "B.Mask" "B.Paste")
			(net "A_HSC_LOW_GATE")
		)
		(pad "2" smd circle
			(at -0.40005 0)
			(size 0 0)
			(layers "B.Cu" "B.Mask" "B.Paste")
			(net "GND")
		)
	)
	(footprint ""
		(layer "B.Cu")
		(at 159.14624 -388.011162 -90)
		(property "Reference" "C388"
			(at 0 0 90)
			(layer "B.SilkS")
			(hide yes)
			(effects
				(font
					(size 1.27 1.27)
				)
				(justify mirror)
			)
		)
		(property "Value" ""
			(at 0 0 90)
			(layer "B.Fab")
			(effects
				(font
					(size 1.27 1.27)
				)
				(justify mirror)
			)
		)
		(duplicate_pad_numbers_are_jumpers no)
		(fp_line
			(start -0.299974 0.150114)
			(end 0.299974 0.150114)
			(stroke
				(width 0.1)
				(type default)
			)
			(layer "B.Fab")
		)
		(fp_line
			(start 0.299974 0.150114)
			(end 0.299974 -0.150114)
			(stroke
				(width 0.1)
				(type default)
			)
			(layer "B.Fab")
		)
		(fp_line
			(start -0.299974 -0.150114)
			(end -0.299974 0.150114)
			(stroke
				(width 0.1)
				(type default)
			)
			(layer "B.Fab")
		)
		(fp_line
			(start 0.299974 -0.150114)
			(end -0.299974 -0.150114)
			(stroke
				(width 0.1)
				(type default)
			)
			(layer "B.Fab")
		)
		(pad "1" smd rect
			(at 0.2667 0 90)
			(size 0.3048 0.381)
			(layers "B.Cu" "B.Mask" "B.Paste")
			(net "P0V9_CPU1_RT_2D")
		)
		(pad "2" smd rect
			(at -0.2667 0 90)
			(size 0.3048 0.381)
			(layers "B.Cu" "B.Mask" "B.Paste")
			(net "GND")
		)
	)
	(footprint ""
		(layer "B.Cu")
		(at 136.08558 -153.865834 90)
		(property "Reference" "PR216"
			(at 0 0 90)
			(layer "B.SilkS")
			(hide yes)
			(effects
				(font
					(size 1.27 1.27)
				)
				(justify mirror)
			)
		)
		(property "Value" ""
			(at 0 0 90)
			(layer "B.Fab")
			(effects
				(font
					(size 1.27 1.27)
				)
				(justify mirror)
			)
		)
		(duplicate_pad_numbers_are_jumpers no)
		(fp_line
			(start 0.7874 -0.4064)
			(end -0.7874 -0.4064)
			(stroke
				(width 0.1524)
				(type default)
			)
			(layer "B.SilkS")
		)
		(fp_line
			(start -0.7874 -0.4064)
			(end -0.7874 0.4064)
			(stroke
				(width 0.1524)
				(type default)
			)
			(layer "B.SilkS")
		)
		(fp_line
			(start 0.7874 0.4064)
			(end 0.7874 -0.4064)
			(stroke
				(width 0.1524)
				(type default)
			)
			(layer "B.SilkS")
		)
		(fp_line
			(start -0.7874 0.4064)
			(end 0.7874 0.4064)
			(stroke
				(width 0.1524)
				(type default)
			)
			(layer "B.SilkS")
		)
		(fp_line
			(start 0.67945 -0.305054)
			(end 0.12065 -0.305054)
			(stroke
				(width 0.1)
				(type default)
			)
			(layer "B.Fab")
		)
		(fp_line
			(start 0.12065 -0.305054)
			(end 0.12065 -0.2794)
			(stroke
				(width 0.1)
				(type default)
			)
			(layer "B.Fab")
		)
		(fp_line
			(start -0.12065 -0.3048)
			(end -0.67945 -0.3048)
			(stroke
				(width 0.1)
				(type default)
			)
			(layer "B.Fab")
		)
		(fp_line
			(start -0.67945 -0.3048)
			(end -0.67945 0.3048)
			(stroke
				(width 0.1)
				(type default)
			)
			(layer "B.Fab")
		)
		(fp_line
			(start 0.12065 -0.2794)
			(end -0.12065 -0.2794)
			(stroke
				(width 0.1)
				(type default)
			)
			(layer "B.Fab")
		)
		(fp_line
			(start -0.12065 -0.2794)
			(end -0.12065 -0.3048)
			(stroke
				(width 0.1)
				(type default)
			)
			(layer "B.Fab")
		)
		(fp_line
			(start 0.12065 0.2794)
			(end 0.12065 0.3048)
			(stroke
				(width 0.1)
				(type default)
			)
			(layer "B.Fab")
		)
		(fp_line
			(start -0.120396 0.2794)
			(end 0.12065 0.2794)
			(stroke
				(width 0.1)
				(type default)
			)
			(layer "B.Fab")
		)
		(fp_line
			(start 0.67945 0.3048)
			(end 0.67945 -0.305054)
			(stroke
				(width 0.1)
				(type default)
			)
			(layer "B.Fab")
		)
		(fp_line
			(start 0.12065 0.3048)
			(end 0.67945 0.3048)
			(stroke
				(width 0.1)
				(type default)
			)
			(layer "B.Fab")
		)
		(fp_line
			(start -0.120396 0.3048)
			(end -0.120396 0.2794)
			(stroke
				(width 0.1)
				(type default)
			)
			(layer "B.Fab")
		)
		(fp_line
			(start -0.67945 0.3048)
			(end -0.120396 0.3048)
			(stroke
				(width 0.1)
				(type default)
			)
			(layer "B.Fab")
		)
		(pad "1" smd circle
			(at 0.40005 0 270)
			(size 0 0)
			(layers "B.Cu" "B.Mask" "B.Paste")
			(net "PVDDCR_SOC_P1_VOS3")
		)
		(pad "2" smd circle
			(at -0.40005 0 270)
			(size 0 0)
			(layers "B.Cu" "B.Mask" "B.Paste")
			(net "PVDDCR_SOC_P1")
		)
	)
	(footprint ""
		(layer "B.Cu")
		(at 103.799386 -255.845564 180)
		(property "Reference" "C2453"
			(at 0 0 0)
			(layer "B.SilkS")
			(hide yes)
			(effects
				(font
					(size 1.27 1.27)
				)
				(justify mirror)
			)
		)
		(property "Value" ""
			(at 0 0 0)
			(layer "B.Fab")
			(effects
				(font
					(size 1.27 1.27)
				)
				(justify mirror)
			)
		)
		(duplicate_pad_numbers_are_jumpers no)
		(fp_line
			(start 0.7874 0.4064)
			(end 0.7874 -0.4064)
			(stroke
				(width 0.1524)
				(type default)
			)
			(layer "B.SilkS")
		)
		(fp_line
			(start 0.7874 -0.4064)
			(end -0.7874 -0.4064)
			(stroke
				(width 0.1524)
				(type default)
			)
			(layer "B.SilkS")
		)
		(fp_line
			(start -0.7874 0.4064)
			(end 0.7874 0.4064)
			(stroke
				(width 0.1524)
				(type default)
			)
			(layer "B.SilkS")
		)
		(fp_line
			(start -0.7874 -0.4064)
			(end -0.7874 0.4064)
			(stroke
				(width 0.1524)
				(type default)
			)
			(layer "B.SilkS")
		)
		(fp_line
			(start 0.67945 0.3048)
			(end 0.67945 -0.305054)
			(stroke
				(width 0.1)
				(type default)
			)
			(layer "B.Fab")
		)
		(fp_line
			(start 0.67945 -0.305054)
			(end 0.12065 -0.305054)
			(stroke
				(width 0.1)
				(type default)
			)
			(layer "B.Fab")
		)
		(fp_line
			(start 0.12065 0.3048)
			(end 0.67945 0.3048)
			(stroke
				(width 0.1)
				(type default)
			)
			(layer "B.Fab")
		)
		(fp_line
			(start 0.12065 0.2794)
			(end 0.12065 0.3048)
			(stroke
				(width 0.1)
				(type default)
			)
			(layer "B.Fab")
		)
		(fp_line
			(start 0.12065 -0.2794)
			(end -0.12065 -0.2794)
			(stroke
				(width 0.1)
				(type default)
			)
			(layer "B.Fab")
		)
		(fp_line
			(start 0.12065 -0.305054)
			(end 0.12065 -0.2794)
			(stroke
				(width 0.1)
				(type default)
			)
			(layer "B.Fab")
		)
		(fp_line
			(start -0.120396 0.3048)
			(end -0.120396 0.2794)
			(stroke
				(width 0.1)
				(type default)
			)
			(layer "B.Fab")
		)
		(fp_line
			(start -0.120396 0.2794)
			(end 0.12065 0.2794)
			(stroke
				(width 0.1)
				(type default)
			)
			(layer "B.Fab")
		)
		(fp_line
			(start -0.12065 -0.2794)
			(end -0.12065 -0.3048)
			(stroke
				(width 0.1)
				(type default)
			)
			(layer "B.Fab")
		)
		(fp_line
			(start -0.12065 -0.3048)
			(end -0.67945 -0.3048)
			(stroke
				(width 0.1)
				(type default)
			)
			(layer "B.Fab")
		)
		(fp_line
			(start -0.67945 0.3048)
			(end -0.120396 0.3048)
			(stroke
				(width 0.1)
				(type default)
			)
			(layer "B.Fab")
		)
		(fp_line
			(start -0.67945 -0.3048)
			(end -0.67945 0.3048)
			(stroke
				(width 0.1)
				(type default)
			)
			(layer "B.Fab")
		)
		(pad "1" smd circle
			(at 0.40005 0)
			(size 0 0)
			(layers "B.Cu" "B.Mask" "B.Paste")
			(net "PVDDCR_SOC_P1")
		)
		(pad "2" smd circle
			(at -0.40005 0)
			(size 0 0)
			(layers "B.Cu" "B.Mask" "B.Paste")
			(net "GND")
		)
	)
	(footprint ""
		(layer "B.Cu")
		(at 371.818408 -396.393162 -90)
		(property "Reference" "C1008"
			(at 0 0 90)
			(layer "B.SilkS")
			(hide yes)
			(effects
				(font
					(size 1.27 1.27)
				)
				(justify mirror)
			)
		)
		(property "Value" ""
			(at 0 0 90)
			(layer "B.Fab")
			(effects
				(font
					(size 1.27 1.27)
				)
				(justify mirror)
			)
		)
		(duplicate_pad_numbers_are_jumpers no)
		(fp_line
			(start -0.299974 0.150114)
			(end 0.299974 0.150114)
			(stroke
				(width 0.1)
				(type default)
			)
			(layer "B.Fab")
		)
		(fp_line
			(start 0.299974 0.150114)
			(end 0.299974 -0.150114)
			(stroke
				(width 0.1)
				(type default)
			)
			(layer "B.Fab")
		)
		(fp_line
			(start -0.299974 -0.150114)
			(end -0.299974 0.150114)
			(stroke
				(width 0.1)
				(type default)
			)
			(layer "B.Fab")
		)
		(fp_line
			(start 0.299974 -0.150114)
			(end -0.299974 -0.150114)
			(stroke
				(width 0.1)
				(type default)
			)
			(layer "B.Fab")
		)
		(pad "1" smd rect
			(at 0.2667 0 90)
			(size 0.3048 0.381)
			(layers "B.Cu" "B.Mask" "B.Paste")
			(net "P0V9_CPU0_RT3_2A")
		)
		(pad "2" smd rect
			(at -0.2667 0 90)
			(size 0.3048 0.381)
			(layers "B.Cu" "B.Mask" "B.Paste")
			(net "GND")
		)
	)
	(footprint ""
		(layer "B.Cu")
		(at 239.141 -331.47)
		(property "Reference" "R846"
			(at 0 0 0)
			(layer "B.SilkS")
			(hide yes)
			(effects
				(font
					(size 1.27 1.27)
				)
				(justify mirror)
			)
		)
		(property "Value" ""
			(at 0 0 0)
			(layer "B.Fab")
			(effects
				(font
					(size 1.27 1.27)
				)
				(justify mirror)
			)
		)
		(duplicate_pad_numbers_are_jumpers no)
		(fp_line
			(start -0.32512 -0.175006)
			(end -0.32512 0.175006)
			(stroke
				(width 0.1)
				(type default)
			)
			(layer "B.Fab")
		)
		(fp_line
			(start -0.32512 0.175006)
			(end 0.32512 0.175006)
			(stroke
				(width 0.1)
				(type default)
			)
			(layer "B.Fab")
		)
		(fp_line
			(start 0.32512 -0.175006)
			(end -0.32512 -0.175006)
			(stroke
				(width 0.1)
				(type default)
			)
			(layer "B.Fab")
		)
		(fp_line
			(start 0.32512 0.175006)
			(end 0.32512 -0.175006)
			(stroke
				(width 0.1)
				(type default)
			)
			(layer "B.Fab")
		)
		(pad "1" smd rect
			(at 0.2667 0 180)
			(size 0.3048 0.381)
			(layers "B.Cu" "B.Mask" "B.Paste")
			(net "RT_ROM_SMB_MUX_ADDR1")
		)
		(pad "2" smd rect
			(at -0.2667 0)
			(size 0.3048 0.381)
			(layers "B.Cu" "B.Mask" "B.Paste")
			(net "GND")
		)
	)
	(footprint ""
		(layer "B.Cu")
		(at 228.485192 -326.49668 180)
		(property "Reference" "C1091"
			(at 0 0 0)
			(layer "B.SilkS")
			(hide yes)
			(effects
				(font
					(size 1.27 1.27)
				)
				(justify mirror)
			)
		)
		(property "Value" ""
			(at 0 0 0)
			(layer "B.Fab")
			(effects
				(font
					(size 1.27 1.27)
				)
				(justify mirror)
			)
		)
		(duplicate_pad_numbers_are_jumpers no)
		(fp_line
			(start 0.7874 0.4064)
			(end 0.7874 -0.4064)
			(stroke
				(width 0.1524)
				(type default)
			)
			(layer "B.SilkS")
		)
		(fp_line
			(start 0.7874 -0.4064)
			(end -0.7874 -0.4064)
			(stroke
				(width 0.1524)
				(type default)
			)
			(layer "B.SilkS")
		)
		(fp_line
			(start -0.7874 0.4064)
			(end 0.7874 0.4064)
			(stroke
				(width 0.1524)
				(type default)
			)
			(layer "B.SilkS")
		)
		(fp_line
			(start -0.7874 -0.4064)
			(end -0.7874 0.4064)
			(stroke
				(width 0.1524)
				(type default)
			)
			(layer "B.SilkS")
		)
		(fp_line
			(start 0.67945 0.3048)
			(end 0.67945 -0.305054)
			(stroke
				(width 0.1)
				(type default)
			)
			(layer "B.Fab")
		)
		(fp_line
			(start 0.67945 -0.305054)
			(end 0.12065 -0.305054)
			(stroke
				(width 0.1)
				(type default)
			)
			(layer "B.Fab")
		)
		(fp_line
			(start 0.12065 0.3048)
			(end 0.67945 0.3048)
			(stroke
				(width 0.1)
				(type default)
			)
			(layer "B.Fab")
		)
		(fp_line
			(start 0.12065 0.2794)
			(end 0.12065 0.3048)
			(stroke
				(width 0.1)
				(type default)
			)
			(layer "B.Fab")
		)
		(fp_line
			(start 0.12065 -0.2794)
			(end -0.12065 -0.2794)
			(stroke
				(width 0.1)
				(type default)
			)
			(layer "B.Fab")
		)
		(fp_line
			(start 0.12065 -0.305054)
			(end 0.12065 -0.2794)
			(stroke
				(width 0.1)
				(type default)
			)
			(layer "B.Fab")
		)
		(fp_line
			(start -0.120396 0.3048)
			(end -0.120396 0.2794)
			(stroke
				(width 0.1)
				(type default)
			)
			(layer "B.Fab")
		)
		(fp_line
			(start -0.120396 0.2794)
			(end 0.12065 0.2794)
			(stroke
				(width 0.1)
				(type default)
			)
			(layer "B.Fab")
		)
		(fp_line
			(start -0.12065 -0.2794)
			(end -0.12065 -0.3048)
			(stroke
				(width 0.1)
				(type default)
			)
			(layer "B.Fab")
		)
		(fp_line
			(start -0.12065 -0.3048)
			(end -0.67945 -0.3048)
			(stroke
				(width 0.1)
				(type default)
			)
			(layer "B.Fab")
		)
		(fp_line
			(start -0.67945 0.3048)
			(end -0.120396 0.3048)
			(stroke
				(width 0.1)
				(type default)
			)
			(layer "B.Fab")
		)
		(fp_line
			(start -0.67945 -0.3048)
			(end -0.67945 0.3048)
			(stroke
				(width 0.1)
				(type default)
			)
			(layer "B.Fab")
		)
		(pad "1" smd circle
			(at 0.40005 0)
			(size 0 0)
			(layers "B.Cu" "B.Mask" "B.Paste")
			(net "P1V8_CPU1_RT_1D_ADC_TIC")
		)
		(pad "2" smd circle
			(at -0.40005 0)
			(size 0 0)
			(layers "B.Cu" "B.Mask" "B.Paste")
			(net "GND")
		)
	)
	(footprint ""
		(layer "B.Cu")
		(at 11.049 -81.153 90)
		(property "Reference" "R8013"
			(at 0 0 90)
			(layer "B.SilkS")
			(hide yes)
			(effects
				(font
					(size 1.27 1.27)
				)
				(justify mirror)
			)
		)
		(property "Value" ""
			(at 0 0 90)
			(layer "B.Fab")
			(effects
				(font
					(size 1.27 1.27)
				)
				(justify mirror)
			)
		)
		(duplicate_pad_numbers_are_jumpers no)
		(fp_line
			(start 0.7874 -0.4064)
			(end -0.7874 -0.4064)
			(stroke
				(width 0.1524)
				(type default)
			)
			(layer "B.SilkS")
		)
		(fp_line
			(start -0.7874 -0.4064)
			(end -0.7874 0.4064)
			(stroke
				(width 0.1524)
				(type default)
			)
			(layer "B.SilkS")
		)
		(fp_line
			(start 0.7874 0.4064)
			(end 0.7874 -0.4064)
			(stroke
				(width 0.1524)
				(type default)
			)
			(layer "B.SilkS")
		)
		(fp_line
			(start -0.7874 0.4064)
			(end 0.7874 0.4064)
			(stroke
				(width 0.1524)
				(type default)
			)
			(layer "B.SilkS")
		)
		(fp_line
			(start 0.67945 -0.305054)
			(end 0.12065 -0.305054)
			(stroke
				(width 0.1)
				(type default)
			)
			(layer "B.Fab")
		)
		(fp_line
			(start 0.12065 -0.305054)
			(end 0.12065 -0.2794)
			(stroke
				(width 0.1)
				(type default)
			)
			(layer "B.Fab")
		)
		(fp_line
			(start -0.12065 -0.3048)
			(end -0.67945 -0.3048)
			(stroke
				(width 0.1)
				(type default)
			)
			(layer "B.Fab")
		)
		(fp_line
			(start -0.67945 -0.3048)
			(end -0.67945 0.3048)
			(stroke
				(width 0.1)
				(type default)
			)
			(layer "B.Fab")
		)
		(fp_line
			(start 0.12065 -0.2794)
			(end -0.12065 -0.2794)
			(stroke
				(width 0.1)
				(type default)
			)
			(layer "B.Fab")
		)
		(fp_line
			(start -0.12065 -0.2794)
			(end -0.12065 -0.3048)
			(stroke
				(width 0.1)
				(type default)
			)
			(layer "B.Fab")
		)
		(fp_line
			(start 0.12065 0.2794)
			(end 0.12065 0.3048)
			(stroke
				(width 0.1)
				(type default)
			)
			(layer "B.Fab")
		)
		(fp_line
			(start -0.120396 0.2794)
			(end 0.12065 0.2794)
			(stroke
				(width 0.1)
				(type default)
			)
			(layer "B.Fab")
		)
		(fp_line
			(start 0.67945 0.3048)
			(end 0.67945 -0.305054)
			(stroke
				(width 0.1)
				(type default)
			)
			(layer "B.Fab")
		)
		(fp_line
			(start 0.12065 0.3048)
			(end 0.67945 0.3048)
			(stroke
				(width 0.1)
				(type default)
			)
			(layer "B.Fab")
		)
		(fp_line
			(start -0.120396 0.3048)
			(end -0.120396 0.2794)
			(stroke
				(width 0.1)
				(type default)
			)
			(layer "B.Fab")
		)
		(fp_line
			(start -0.67945 0.3048)
			(end -0.120396 0.3048)
			(stroke
				(width 0.1)
				(type default)
			)
			(layer "B.Fab")
		)
		(pad "1" smd circle
			(at 0.40005 0 270)
			(size 0 0)
			(layers "B.Cu" "B.Mask" "B.Paste")
			(net "OCP_SFF_PRSNT01_R_N")
		)
		(pad "2" smd circle
			(at -0.40005 0 270)
			(size 0 0)
			(layers "B.Cu" "B.Mask" "B.Paste")
			(net "OCP_SFF_PRSNT01_R1_N")
		)
	)
	(footprint ""
		(layer "B.Cu")
		(at 79.918814 -390.560052 90)
		(property "Reference" "C332"
			(at 0 0 90)
			(layer "B.SilkS")
			(hide yes)
			(effects
				(font
					(size 1.27 1.27)
				)
				(justify mirror)
			)
		)
		(property "Value" ""
			(at 0 0 90)
			(layer "B.Fab")
			(effects
				(font
					(size 1.27 1.27)
				)
				(justify mirror)
			)
		)
		(duplicate_pad_numbers_are_jumpers no)
		(fp_line
			(start 0.7874 -0.4064)
			(end -0.7874 -0.4064)
			(stroke
				(width 0.1524)
				(type default)
			)
			(layer "B.SilkS")
		)
		(fp_line
			(start -0.7874 -0.4064)
			(end -0.7874 0.4064)
			(stroke
				(width 0.1524)
				(type default)
			)
			(layer "B.SilkS")
		)
		(fp_line
			(start 0.7874 0.4064)
			(end 0.7874 -0.4064)
			(stroke
				(width 0.1524)
				(type default)
			)
			(layer "B.SilkS")
		)
		(fp_line
			(start -0.7874 0.4064)
			(end 0.7874 0.4064)
			(stroke
				(width 0.1524)
				(type default)
			)
			(layer "B.SilkS")
		)
		(fp_line
			(start 0.67945 -0.305054)
			(end 0.12065 -0.305054)
			(stroke
				(width 0.1)
				(type default)
			)
			(layer "B.Fab")
		)
		(fp_line
			(start 0.12065 -0.305054)
			(end 0.12065 -0.2794)
			(stroke
				(width 0.1)
				(type default)
			)
			(layer "B.Fab")
		)
		(fp_line
			(start -0.12065 -0.3048)
			(end -0.67945 -0.3048)
			(stroke
				(width 0.1)
				(type default)
			)
			(layer "B.Fab")
		)
		(fp_line
			(start -0.67945 -0.3048)
			(end -0.67945 0.3048)
			(stroke
				(width 0.1)
				(type default)
			)
			(layer "B.Fab")
		)
		(fp_line
			(start 0.12065 -0.2794)
			(end -0.12065 -0.2794)
			(stroke
				(width 0.1)
				(type default)
			)
			(layer "B.Fab")
		)
		(fp_line
			(start -0.12065 -0.2794)
			(end -0.12065 -0.3048)
			(stroke
				(width 0.1)
				(type default)
			)
			(layer "B.Fab")
		)
		(fp_line
			(start 0.12065 0.2794)
			(end 0.12065 0.3048)
			(stroke
				(width 0.1)
				(type default)
			)
			(layer "B.Fab")
		)
		(fp_line
			(start -0.120396 0.2794)
			(end 0.12065 0.2794)
			(stroke
				(width 0.1)
				(type default)
			)
			(layer "B.Fab")
		)
		(fp_line
			(start 0.67945 0.3048)
			(end 0.67945 -0.305054)
			(stroke
				(width 0.1)
				(type default)
			)
			(layer "B.Fab")
		)
		(fp_line
			(start 0.12065 0.3048)
			(end 0.67945 0.3048)
			(stroke
				(width 0.1)
				(type default)
			)
			(layer "B.Fab")
		)
		(fp_line
			(start -0.120396 0.3048)
			(end -0.120396 0.2794)
			(stroke
				(width 0.1)
				(type default)
			)
			(layer "B.Fab")
		)
		(fp_line
			(start -0.67945 0.3048)
			(end -0.120396 0.3048)
			(stroke
				(width 0.1)
				(type default)
			)
			(layer "B.Fab")
		)
		(pad "1" smd circle
			(at 0.40005 0 270)
			(size 0 0)
			(layers "B.Cu" "B.Mask" "B.Paste")
			(net "P0V9_CPU1_RT1_2A")
		)
		(pad "2" smd circle
			(at -0.40005 0 270)
			(size 0 0)
			(layers "B.Cu" "B.Mask" "B.Paste")
			(net "GND")
		)
	)
	(footprint ""
		(layer "B.Cu")
		(at 108.089192 -29.55544 -90)
		(property "Reference" "C6099"
			(at 0 0 90)
			(layer "B.SilkS")
			(hide yes)
			(effects
				(font
					(size 1.27 1.27)
				)
				(justify mirror)
			)
		)
		(property "Value" ""
			(at 0 0 90)
			(layer "B.Fab")
			(effects
				(font
					(size 1.27 1.27)
				)
				(justify mirror)
			)
		)
		(duplicate_pad_numbers_are_jumpers no)
		(fp_line
			(start -0.7874 0.4064)
			(end 0.7874 0.4064)
			(stroke
				(width 0.1524)
				(type default)
			)
			(layer "B.SilkS")
		)
		(fp_line
			(start 0.7874 0.4064)
			(end 0.7874 -0.4064)
			(stroke
				(width 0.1524)
				(type default)
			)
			(layer "B.SilkS")
		)
		(fp_line
			(start -0.7874 -0.4064)
			(end -0.7874 0.4064)
			(stroke
				(width 0.1524)
				(type default)
			)
			(layer "B.SilkS")
		)
		(fp_line
			(start 0.7874 -0.4064)
			(end -0.7874 -0.4064)
			(stroke
				(width 0.1524)
				(type default)
			)
			(layer "B.SilkS")
		)
		(fp_line
			(start -0.67945 0.3048)
			(end -0.120396 0.3048)
			(stroke
				(width 0.1)
				(type default)
			)
			(layer "B.Fab")
		)
		(fp_line
			(start -0.120396 0.3048)
			(end -0.120396 0.2794)
			(stroke
				(width 0.1)
				(type default)
			)
			(layer "B.Fab")
		)
		(fp_line
			(start 0.12065 0.3048)
			(end 0.67945 0.3048)
			(stroke
				(width 0.1)
				(type default)
			)
			(layer "B.Fab")
		)
		(fp_line
			(start 0.67945 0.3048)
			(end 0.67945 -0.305054)
			(stroke
				(width 0.1)
				(type default)
			)
			(layer "B.Fab")
		)
		(fp_line
			(start -0.120396 0.2794)
			(end 0.12065 0.2794)
			(stroke
				(width 0.1)
				(type default)
			)
			(layer "B.Fab")
		)
		(fp_line
			(start 0.12065 0.2794)
			(end 0.12065 0.3048)
			(stroke
				(width 0.1)
				(type default)
			)
			(layer "B.Fab")
		)
		(fp_line
			(start -0.12065 -0.2794)
			(end -0.12065 -0.3048)
			(stroke
				(width 0.1)
				(type default)
			)
			(layer "B.Fab")
		)
		(fp_line
			(start 0.12065 -0.2794)
			(end -0.12065 -0.2794)
			(stroke
				(width 0.1)
				(type default)
			)
			(layer "B.Fab")
		)
		(fp_line
			(start -0.67945 -0.3048)
			(end -0.67945 0.3048)
			(stroke
				(width 0.1)
				(type default)
			)
			(layer "B.Fab")
		)
		(fp_line
			(start -0.12065 -0.3048)
			(end -0.67945 -0.3048)
			(stroke
				(width 0.1)
				(type default)
			)
			(layer "B.Fab")
		)
		(fp_line
			(start 0.12065 -0.305054)
			(end 0.12065 -0.2794)
			(stroke
				(width 0.1)
				(type default)
			)
			(layer "B.Fab")
		)
		(fp_line
			(start 0.67945 -0.305054)
			(end 0.12065 -0.305054)
			(stroke
				(width 0.1)
				(type default)
			)
			(layer "B.Fab")
		)
		(pad "1" smd circle
			(at 0.40005 0 90)
			(size 0 0)
			(layers "B.Cu" "B.Mask" "B.Paste")
			(net "P3V3_AUX_CPU0_USB2_AVDD33")
		)
		(pad "2" smd circle
			(at -0.40005 0 90)
			(size 0 0)
			(layers "B.Cu" "B.Mask" "B.Paste")
			(net "GND")
		)
	)
	(footprint ""
		(layer "B.Cu")
		(at 181.182518 -412.949644 90)
		(property "Reference" "R2820"
			(at 0 0 90)
			(layer "B.SilkS")
			(hide yes)
			(effects
				(font
					(size 1.27 1.27)
				)
				(justify mirror)
			)
		)
		(property "Value" ""
			(at 0 0 90)
			(layer "B.Fab")
			(effects
				(font
					(size 1.27 1.27)
				)
				(justify mirror)
			)
		)
		(duplicate_pad_numbers_are_jumpers no)
		(fp_line
			(start 0.7874 -0.4064)
			(end -0.7874 -0.4064)
			(stroke
				(width 0.1524)
				(type default)
			)
			(layer "B.SilkS")
		)
		(fp_line
			(start -0.7874 -0.4064)
			(end -0.7874 0.4064)
			(stroke
				(width 0.1524)
				(type default)
			)
			(layer "B.SilkS")
		)
		(fp_line
			(start 0.7874 0.4064)
			(end 0.7874 -0.4064)
			(stroke
				(width 0.1524)
				(type default)
			)
			(layer "B.SilkS")
		)
		(fp_line
			(start -0.7874 0.4064)
			(end 0.7874 0.4064)
			(stroke
				(width 0.1524)
				(type default)
			)
			(layer "B.SilkS")
		)
		(fp_line
			(start 0.67945 -0.305054)
			(end 0.12065 -0.305054)
			(stroke
				(width 0.1)
				(type default)
			)
			(layer "B.Fab")
		)
		(fp_line
			(start 0.12065 -0.305054)
			(end 0.12065 -0.2794)
			(stroke
				(width 0.1)
				(type default)
			)
			(layer "B.Fab")
		)
		(fp_line
			(start -0.12065 -0.3048)
			(end -0.67945 -0.3048)
			(stroke
				(width 0.1)
				(type default)
			)
			(layer "B.Fab")
		)
		(fp_line
			(start -0.67945 -0.3048)
			(end -0.67945 0.3048)
			(stroke
				(width 0.1)
				(type default)
			)
			(layer "B.Fab")
		)
		(fp_line
			(start 0.12065 -0.2794)
			(end -0.12065 -0.2794)
			(stroke
				(width 0.1)
				(type default)
			)
			(layer "B.Fab")
		)
		(fp_line
			(start -0.12065 -0.2794)
			(end -0.12065 -0.3048)
			(stroke
				(width 0.1)
				(type default)
			)
			(layer "B.Fab")
		)
		(fp_line
			(start 0.12065 0.2794)
			(end 0.12065 0.3048)
			(stroke
				(width 0.1)
				(type default)
			)
			(layer "B.Fab")
		)
		(fp_line
			(start -0.120396 0.2794)
			(end 0.12065 0.2794)
			(stroke
				(width 0.1)
				(type default)
			)
			(layer "B.Fab")
		)
		(fp_line
			(start 0.67945 0.3048)
			(end 0.67945 -0.305054)
			(stroke
				(width 0.1)
				(type default)
			)
			(layer "B.Fab")
		)
		(fp_line
			(start 0.12065 0.3048)
			(end 0.67945 0.3048)
			(stroke
				(width 0.1)
				(type default)
			)
			(layer "B.Fab")
		)
		(fp_line
			(start -0.120396 0.3048)
			(end -0.120396 0.2794)
			(stroke
				(width 0.1)
				(type default)
			)
			(layer "B.Fab")
		)
		(fp_line
			(start -0.67945 0.3048)
			(end -0.120396 0.3048)
			(stroke
				(width 0.1)
				(type default)
			)
			(layer "B.Fab")
		)
		(pad "1" smd circle
			(at 0.40005 0 270)
			(size 0 0)
			(layers "B.Cu" "B.Mask" "B.Paste")
			(net "P3V3_AUX")
		)
		(pad "2" smd circle
			(at -0.40005 0 270)
			(size 0 0)
			(layers "B.Cu" "B.Mask" "B.Paste")
			(net "BMC_MONITER_BUF_R")
		)
	)
	(footprint ""
		(layer "B.Cu")
		(at 511.511042 -457.330048 -90)
		(property "Reference" "X9011"
			(at 4.7244 -1.61163 270)
			(unlocked yes)
			(layer "B.SilkS")
			(effects
				(font
					(size 0.7874 0.5842)
					(thickness 0.1524)
				)
				(justify left mirror)
			)
		)
		(property "Value" ""
			(at 0 0 90)
			(layer "B.Fab")
			(effects
				(font
					(size 1.27 1.27)
				)
				(justify mirror)
			)
		)
		(property "User Part Number" "N_A"
			(at -1.30175 1.27 180)
			(unlocked yes)
			(layer "Cmts.User")
			(hide yes)
			(effects
				(font
					(size 0.635 0.4064)
					(thickness 0.1524)
				)
				(justify mirror)
			)
		)
		(property "Device Type" "TP_TDR_4P_FTS_TH-TP_TDR_4P_DIP,EMPTY,TP15"
			(at -1.30175 1.27 180)
			(unlocked yes)
			(layer "B.Fab")
			(hide yes)
			(effects
				(font
					(size 0.635 0.4064)
					(thickness 0.1524)
				)
				(justify mirror)
			)
		)
		(duplicate_pad_numbers_are_jumpers no)
		(fp_line
			(start -2.54 3.81)
			(end -2.54 3.6703)
			(stroke
				(width 0.1524)
				(type default)
			)
			(layer "B.SilkS")
		)
		(fp_line
			(start 0 3.81)
			(end -2.54 3.81)
			(stroke
				(width 0.1524)
				(type default)
			)
			(layer "B.SilkS")
		)
		(fp_line
			(start 0 3.175)
			(end 0 3.81)
			(stroke
				(width 0.1524)
				(type default)
			)
			(layer "B.SilkS")
		)
		(fp_line
			(start -2.54 1.4097)
			(end -2.54 1.1303)
			(stroke
				(width 0.1524)
				(type default)
			)
			(layer "B.SilkS")
		)
		(fp_line
			(start 0 0.635)
			(end 0 1.905)
			(stroke
				(width 0.1524)
				(type default)
			)
			(layer "B.SilkS")
		)
		(fp_line
			(start -2.54 -1.1303)
			(end -2.54 -1.27)
			(stroke
				(width 0.1524)
				(type default)
			)
			(layer "B.SilkS")
		)
		(fp_line
			(start -2.54 -1.27)
			(end 0 -1.27)
			(stroke
				(width 0.1524)
				(type default)
			)
			(layer "B.SilkS")
		)
		(fp_line
			(start 0 -1.27)
			(end 0 -0.635)
			(stroke
				(width 0.1524)
				(type default)
			)
			(layer "B.SilkS")
		)
		(fp_poly
			(pts
				(xy 0.761746 0) (xy 2.285746 -0.762) (xy 2.285746 0.762)
			)
			(stroke
				(width 0)
				(type default)
			)
			(fill yes)
			(layer "B.SilkS")
		)
		(fp_line
			(start -2.54 3.81)
			(end -2.54 -1.27)
			(stroke
				(width 0.1)
				(type default)
			)
			(layer "B.Fab")
		)
		(fp_line
			(start 0 3.81)
			(end -2.54 3.81)
			(stroke
				(width 0.1)
				(type default)
			)
			(layer "B.Fab")
		)
		(fp_line
			(start -2.54 -1.27)
			(end 0 -1.27)
			(stroke
				(width 0.1)
				(type default)
			)
			(layer "B.Fab")
		)
		(fp_line
			(start 0 -1.27)
			(end 0 3.81)
			(stroke
				(width 0.1)
				(type default)
			)
			(layer "B.Fab")
		)
		(fp_poly
			(pts
				(xy 0.761746 0) (xy 2.285746 -0.762) (xy 2.285746 0.762)
			)
			(stroke
				(width 0)
				(type default)
			)
			(fill yes)
			(layer "B.Fab")
		)
		(pad "1" thru_hole circle
			(at 0 0 90)
			(size 1.0033 1.0033)
			(drill 0.249936)
			(layers "*.Cu" "*.Mask")
			(remove_unused_layers no)
			(net "TDR_DIFF_85_NECK_IN4_DN")
			(clearance 0.10795)
			(padstack
				(mode front_inner_back)
				(layer "Inner"
					(shape circle)
					(size 0.8001 0.8001)
					(clearance 0.1524)
				)
				(layer "B.Cu"
					(shape circle)
					(size 1.0033 1.0033)
					(thermal_gap 0.10795)
					(clearance 0.10795)
				)
			)
		)
		(pad "2" thru_hole circle
			(at -2.54 0 90)
			(size 1.9939 1.9939)
			(drill 0.249936)
			(layers "*.Cu" "*.Mask")
			(remove_unused_layers no)
			(net "T1_GND")
			(clearance 0.10795)
			(padstack
				(mode front_inner_back)
				(layer "Inner"
					(shape circle)
					(size 0.8001 0.8001)
					(clearance 0.1524)
				)
				(layer "B.Cu"
					(shape circle)
					(size 1.9939 1.9939)
					(thermal_gap 0.10795)
					(clearance 0.10795)
				)
			)
		)
		(pad "3" thru_hole circle
			(at -2.54 2.54 90)
			(size 1.9939 1.9939)
			(drill 0.249936)
			(layers "*.Cu" "*.Mask")
			(remove_unused_layers no)
			(net "T1_GND")
			(clearance 0.10795)
			(padstack
				(mode front_inner_back)
				(layer "Inner"
					(shape circle)
					(size 0.8001 0.8001)
					(clearance 0.1524)
				)
				(layer "B.Cu"
					(shape circle)
					(size 1.9939 1.9939)
					(thermal_gap 0.10795)
					(clearance 0.10795)
				)
			)
		)
		(pad "4" thru_hole circle
			(at 0 2.54 90)
			(size 1.0033 1.0033)
			(drill 0.249936)
			(layers "*.Cu" "*.Mask")
			(remove_unused_layers no)
			(net "TDR_DIFF_85_NECK_IN4_DP")
			(clearance 0.10795)
			(padstack
				(mode front_inner_back)
				(layer "Inner"
					(shape circle)
					(size 0.8001 0.8001)
					(clearance 0.1524)
				)
				(layer "B.Cu"
					(shape circle)
					(size 1.0033 1.0033)
					(thermal_gap 0.10795)
					(clearance 0.10795)
				)
			)
		)
	)
	(footprint ""
		(layer "B.Cu")
		(at 312.443876 -66.708782 90)
		(property "Reference" "R3069"
			(at 0 0 90)
			(layer "B.SilkS")
			(hide yes)
			(effects
				(font
					(size 1.27 1.27)
				)
				(justify mirror)
			)
		)
		(property "Value" ""
			(at 0 0 90)
			(layer "B.Fab")
			(effects
				(font
					(size 1.27 1.27)
				)
				(justify mirror)
			)
		)
		(duplicate_pad_numbers_are_jumpers no)
		(fp_line
			(start 0.7874 -0.4064)
			(end -0.7874 -0.4064)
			(stroke
				(width 0.1524)
				(type default)
			)
			(layer "B.SilkS")
		)
		(fp_line
			(start -0.7874 -0.4064)
			(end -0.7874 0.4064)
			(stroke
				(width 0.1524)
				(type default)
			)
			(layer "B.SilkS")
		)
		(fp_line
			(start 0.7874 0.4064)
			(end 0.7874 -0.4064)
			(stroke
				(width 0.1524)
				(type default)
			)
			(layer "B.SilkS")
		)
		(fp_line
			(start -0.7874 0.4064)
			(end 0.7874 0.4064)
			(stroke
				(width 0.1524)
				(type default)
			)
			(layer "B.SilkS")
		)
		(fp_line
			(start 0.67945 -0.305054)
			(end 0.12065 -0.305054)
			(stroke
				(width 0.1)
				(type default)
			)
			(layer "B.Fab")
		)
		(fp_line
			(start 0.12065 -0.305054)
			(end 0.12065 -0.2794)
			(stroke
				(width 0.1)
				(type default)
			)
			(layer "B.Fab")
		)
		(fp_line
			(start -0.12065 -0.3048)
			(end -0.67945 -0.3048)
			(stroke
				(width 0.1)
				(type default)
			)
			(layer "B.Fab")
		)
		(fp_line
			(start -0.67945 -0.3048)
			(end -0.67945 0.3048)
			(stroke
				(width 0.1)
				(type default)
			)
			(layer "B.Fab")
		)
		(fp_line
			(start 0.12065 -0.2794)
			(end -0.12065 -0.2794)
			(stroke
				(width 0.1)
				(type default)
			)
			(layer "B.Fab")
		)
		(fp_line
			(start -0.12065 -0.2794)
			(end -0.12065 -0.3048)
			(stroke
				(width 0.1)
				(type default)
			)
			(layer "B.Fab")
		)
		(fp_line
			(start 0.12065 0.2794)
			(end 0.12065 0.3048)
			(stroke
				(width 0.1)
				(type default)
			)
			(layer "B.Fab")
		)
		(fp_line
			(start -0.120396 0.2794)
			(end 0.12065 0.2794)
			(stroke
				(width 0.1)
				(type default)
			)
			(layer "B.Fab")
		)
		(fp_line
			(start 0.67945 0.3048)
			(end 0.67945 -0.305054)
			(stroke
				(width 0.1)
				(type default)
			)
			(layer "B.Fab")
		)
		(fp_line
			(start 0.12065 0.3048)
			(end 0.67945 0.3048)
			(stroke
				(width 0.1)
				(type default)
			)
			(layer "B.Fab")
		)
		(fp_line
			(start -0.120396 0.3048)
			(end -0.120396 0.2794)
			(stroke
				(width 0.1)
				(type default)
			)
			(layer "B.Fab")
		)
		(fp_line
			(start -0.67945 0.3048)
			(end -0.120396 0.3048)
			(stroke
				(width 0.1)
				(type default)
			)
			(layer "B.Fab")
		)
		(pad "1" smd circle
			(at 0.40005 0 270)
			(size 0 0)
			(layers "B.Cu" "B.Mask" "B.Paste")
			(net "LED_PWRGD_SYS_PWROK_R")
		)
		(pad "2" smd circle
			(at -0.40005 0 270)
			(size 0 0)
			(layers "B.Cu" "B.Mask" "B.Paste")
			(net "P3V3_AUX")
		)
	)
	(footprint ""
		(layer "B.Cu")
		(at 355.272848 -398.942052 90)
		(property "Reference" "C663"
			(at 0 0 90)
			(layer "B.SilkS")
			(hide yes)
			(effects
				(font
					(size 1.27 1.27)
				)
				(justify mirror)
			)
		)
		(property "Value" ""
			(at 0 0 90)
			(layer "B.Fab")
			(effects
				(font
					(size 1.27 1.27)
				)
				(justify mirror)
			)
		)
		(duplicate_pad_numbers_are_jumpers no)
		(fp_line
			(start 0.7874 -0.4064)
			(end -0.7874 -0.4064)
			(stroke
				(width 0.1524)
				(type default)
			)
			(layer "B.SilkS")
		)
		(fp_line
			(start -0.7874 -0.4064)
			(end -0.7874 0.4064)
			(stroke
				(width 0.1524)
				(type default)
			)
			(layer "B.SilkS")
		)
		(fp_line
			(start 0.7874 0.4064)
			(end 0.7874 -0.4064)
			(stroke
				(width 0.1524)
				(type default)
			)
			(layer "B.SilkS")
		)
		(fp_line
			(start -0.7874 0.4064)
			(end 0.7874 0.4064)
			(stroke
				(width 0.1524)
				(type default)
			)
			(layer "B.SilkS")
		)
		(fp_line
			(start 0.67945 -0.305054)
			(end 0.12065 -0.305054)
			(stroke
				(width 0.1)
				(type default)
			)
			(layer "B.Fab")
		)
		(fp_line
			(start 0.12065 -0.305054)
			(end 0.12065 -0.2794)
			(stroke
				(width 0.1)
				(type default)
			)
			(layer "B.Fab")
		)
		(fp_line
			(start -0.12065 -0.3048)
			(end -0.67945 -0.3048)
			(stroke
				(width 0.1)
				(type default)
			)
			(layer "B.Fab")
		)
		(fp_line
			(start -0.67945 -0.3048)
			(end -0.67945 0.3048)
			(stroke
				(width 0.1)
				(type default)
			)
			(layer "B.Fab")
		)
		(fp_line
			(start 0.12065 -0.2794)
			(end -0.12065 -0.2794)
			(stroke
				(width 0.1)
				(type default)
			)
			(layer "B.Fab")
		)
		(fp_line
			(start -0.12065 -0.2794)
			(end -0.12065 -0.3048)
			(stroke
				(width 0.1)
				(type default)
			)
			(layer "B.Fab")
		)
		(fp_line
			(start 0.12065 0.2794)
			(end 0.12065 0.3048)
			(stroke
				(width 0.1)
				(type default)
			)
			(layer "B.Fab")
		)
		(fp_line
			(start -0.120396 0.2794)
			(end 0.12065 0.2794)
			(stroke
				(width 0.1)
				(type default)
			)
			(layer "B.Fab")
		)
		(fp_line
			(start 0.67945 0.3048)
			(end 0.67945 -0.305054)
			(stroke
				(width 0.1)
				(type default)
			)
			(layer "B.Fab")
		)
		(fp_line
			(start 0.12065 0.3048)
			(end 0.67945 0.3048)
			(stroke
				(width 0.1)
				(type default)
			)
			(layer "B.Fab")
		)
		(fp_line
			(start -0.120396 0.3048)
			(end -0.120396 0.2794)
			(stroke
				(width 0.1)
				(type default)
			)
			(layer "B.Fab")
		)
		(fp_line
			(start -0.67945 0.3048)
			(end -0.120396 0.3048)
			(stroke
				(width 0.1)
				(type default)
			)
			(layer "B.Fab")
		)
		(pad "1" smd circle
			(at 0.40005 0 270)
			(size 0 0)
			(layers "B.Cu" "B.Mask" "B.Paste")
			(net "P0V9_CPU0_RT1_2A")
		)
		(pad "2" smd circle
			(at -0.40005 0 270)
			(size 0 0)
			(layers "B.Cu" "B.Mask" "B.Paste")
			(net "GND")
		)
	)
	(footprint ""
		(layer "B.Cu")
		(at 51.415442 -421.17518)
		(property "Reference" "C1881"
			(at 0 0 0)
			(layer "B.SilkS")
			(hide yes)
			(effects
				(font
					(size 1.27 1.27)
				)
				(justify mirror)
			)
		)
		(property "Value" ""
			(at 0 0 0)
			(layer "B.Fab")
			(effects
				(font
					(size 1.27 1.27)
				)
				(justify mirror)
			)
		)
		(duplicate_pad_numbers_are_jumpers no)
		(fp_line
			(start -0.7874 -0.4064)
			(end -0.7874 0.4064)
			(stroke
				(width 0.1524)
				(type default)
			)
			(layer "B.SilkS")
		)
		(fp_line
			(start -0.7874 0.4064)
			(end 0.7874 0.4064)
			(stroke
				(width 0.1524)
				(type default)
			)
			(layer "B.SilkS")
		)
		(fp_line
			(start 0.7874 -0.4064)
			(end -0.7874 -0.4064)
			(stroke
				(width 0.1524)
				(type default)
			)
			(layer "B.SilkS")
		)
		(fp_line
			(start 0.7874 0.4064)
			(end 0.7874 -0.4064)
			(stroke
				(width 0.1524)
				(type default)
			)
			(layer "B.SilkS")
		)
		(fp_line
			(start -0.67945 -0.3048)
			(end -0.67945 0.3048)
			(stroke
				(width 0.1)
				(type default)
			)
			(layer "B.Fab")
		)
		(fp_line
			(start -0.67945 0.3048)
			(end -0.120396 0.3048)
			(stroke
				(width 0.1)
				(type default)
			)
			(layer "B.Fab")
		)
		(fp_line
			(start -0.12065 -0.3048)
			(end -0.67945 -0.3048)
			(stroke
				(width 0.1)
				(type default)
			)
			(layer "B.Fab")
		)
		(fp_line
			(start -0.12065 -0.2794)
			(end -0.12065 -0.3048)
			(stroke
				(width 0.1)
				(type default)
			)
			(layer "B.Fab")
		)
		(fp_line
			(start -0.120396 0.2794)
			(end 0.12065 0.2794)
			(stroke
				(width 0.1)
				(type default)
			)
			(layer "B.Fab")
		)
		(fp_line
			(start -0.120396 0.3048)
			(end -0.120396 0.2794)
			(stroke
				(width 0.1)
				(type default)
			)
			(layer "B.Fab")
		)
		(fp_line
			(start 0.12065 -0.305054)
			(end 0.12065 -0.2794)
			(stroke
				(width 0.1)
				(type default)
			)
			(layer "B.Fab")
		)
		(fp_line
			(start 0.12065 -0.2794)
			(end -0.12065 -0.2794)
			(stroke
				(width 0.1)
				(type default)
			)
			(layer "B.Fab")
		)
		(fp_line
			(start 0.12065 0.2794)
			(end 0.12065 0.3048)
			(stroke
				(width 0.1)
				(type default)
			)
			(layer "B.Fab")
		)
		(fp_line
			(start 0.12065 0.3048)
			(end 0.67945 0.3048)
			(stroke
				(width 0.1)
				(type default)
			)
			(layer "B.Fab")
		)
		(fp_line
			(start 0.67945 -0.305054)
			(end 0.12065 -0.305054)
			(stroke
				(width 0.1)
				(type default)
			)
			(layer "B.Fab")
		)
		(fp_line
			(start 0.67945 0.3048)
			(end 0.67945 -0.305054)
			(stroke
				(width 0.1)
				(type default)
			)
			(layer "B.Fab")
		)
		(pad "1" smd circle
			(at 0.40005 0 180)
			(size 0 0)
			(layers "B.Cu" "B.Mask" "B.Paste")
			(net "GPU_FPGA_READY_ISO")
		)
		(pad "2" smd circle
			(at -0.40005 0 180)
			(size 0 0)
			(layers "B.Cu" "B.Mask" "B.Paste")
			(net "GND")
		)
	)
	(footprint ""
		(layer "B.Cu")
		(at 108.907834 -271.395952)
		(property "Reference" "C2357"
			(at 0 0 0)
			(layer "B.SilkS")
			(hide yes)
			(effects
				(font
					(size 1.27 1.27)
				)
				(justify mirror)
			)
		)
		(property "Value" ""
			(at 0 0 0)
			(layer "B.Fab")
			(effects
				(font
					(size 1.27 1.27)
				)
				(justify mirror)
			)
		)
		(duplicate_pad_numbers_are_jumpers no)
		(fp_line
			(start -0.7874 -0.4064)
			(end -0.7874 0.4064)
			(stroke
				(width 0.1524)
				(type default)
			)
			(layer "B.SilkS")
		)
		(fp_line
			(start -0.7874 0.4064)
			(end 0.7874 0.4064)
			(stroke
				(width 0.1524)
				(type default)
			)
			(layer "B.SilkS")
		)
		(fp_line
			(start 0.7874 -0.4064)
			(end -0.7874 -0.4064)
			(stroke
				(width 0.1524)
				(type default)
			)
			(layer "B.SilkS")
		)
		(fp_line
			(start 0.7874 0.4064)
			(end 0.7874 -0.4064)
			(stroke
				(width 0.1524)
				(type default)
			)
			(layer "B.SilkS")
		)
		(fp_line
			(start -0.67945 -0.3048)
			(end -0.67945 0.3048)
			(stroke
				(width 0.1)
				(type default)
			)
			(layer "B.Fab")
		)
		(fp_line
			(start -0.67945 0.3048)
			(end -0.120396 0.3048)
			(stroke
				(width 0.1)
				(type default)
			)
			(layer "B.Fab")
		)
		(fp_line
			(start -0.12065 -0.3048)
			(end -0.67945 -0.3048)
			(stroke
				(width 0.1)
				(type default)
			)
			(layer "B.Fab")
		)
		(fp_line
			(start -0.12065 -0.2794)
			(end -0.12065 -0.3048)
			(stroke
				(width 0.1)
				(type default)
			)
			(layer "B.Fab")
		)
		(fp_line
			(start -0.120396 0.2794)
			(end 0.12065 0.2794)
			(stroke
				(width 0.1)
				(type default)
			)
			(layer "B.Fab")
		)
		(fp_line
			(start -0.120396 0.3048)
			(end -0.120396 0.2794)
			(stroke
				(width 0.1)
				(type default)
			)
			(layer "B.Fab")
		)
		(fp_line
			(start 0.12065 -0.305054)
			(end 0.12065 -0.2794)
			(stroke
				(width 0.1)
				(type default)
			)
			(layer "B.Fab")
		)
		(fp_line
			(start 0.12065 -0.2794)
			(end -0.12065 -0.2794)
			(stroke
				(width 0.1)
				(type default)
			)
			(layer "B.Fab")
		)
		(fp_line
			(start 0.12065 0.2794)
			(end 0.12065 0.3048)
			(stroke
				(width 0.1)
				(type default)
			)
			(layer "B.Fab")
		)
		(fp_line
			(start 0.12065 0.3048)
			(end 0.67945 0.3048)
			(stroke
				(width 0.1)
				(type default)
			)
			(layer "B.Fab")
		)
		(fp_line
			(start 0.67945 -0.305054)
			(end 0.12065 -0.305054)
			(stroke
				(width 0.1)
				(type default)
			)
			(layer "B.Fab")
		)
		(fp_line
			(start 0.67945 0.3048)
			(end 0.67945 -0.305054)
			(stroke
				(width 0.1)
				(type default)
			)
			(layer "B.Fab")
		)
		(pad "1" smd circle
			(at 0.40005 0 180)
			(size 0 0)
			(layers "B.Cu" "B.Mask" "B.Paste")
			(net "PVDDCR_CPU1_P1")
		)
		(pad "2" smd circle
			(at -0.40005 0 180)
			(size 0 0)
			(layers "B.Cu" "B.Mask" "B.Paste")
			(net "GND")
		)
	)
	(footprint ""
		(layer "B.Cu")
		(at 342.624664 -73.534778)
		(property "Reference" "Q85"
			(at 1.4224 -1.768348 0)
			(unlocked yes)
			(layer "B.SilkS")
			(effects
				(font
					(size 0.7874 0.5842)
					(thickness 0.1524)
				)
				(justify left mirror)
			)
		)
		(property "Value" ""
			(at 0 0 0)
			(layer "B.Fab")
			(effects
				(font
					(size 1.27 1.27)
				)
				(justify mirror)
			)
		)
		(duplicate_pad_numbers_are_jumpers no)
		(fp_line
			(start -1.332738 -1.100074)
			(end -1.332738 1.100074)
			(stroke
				(width 0.1524)
				(type default)
			)
			(layer "B.SilkS")
		)
		(fp_line
			(start -1.332738 1.100074)
			(end 1.332738 1.100074)
			(stroke
				(width 0.1524)
				(type default)
			)
			(layer "B.SilkS")
		)
		(fp_line
			(start -0.4826 -1.100074)
			(end -1.332738 -1.100074)
			(stroke
				(width 0.1524)
				(type default)
			)
			(layer "B.SilkS")
		)
		(fp_line
			(start 0 -0.541274)
			(end -0.4826 -1.100074)
			(stroke
				(width 0.1524)
				(type default)
			)
			(layer "B.SilkS")
		)
		(fp_line
			(start 0.4826 -1.100074)
			(end 0 -0.541274)
			(stroke
				(width 0.1524)
				(type default)
			)
			(layer "B.SilkS")
		)
		(fp_line
			(start 1.332738 -1.100074)
			(end 0.4826 -1.100074)
			(stroke
				(width 0.1524)
				(type default)
			)
			(layer "B.SilkS")
		)
		(fp_line
			(start 1.332738 1.100074)
			(end 1.332738 -1.100074)
			(stroke
				(width 0.1524)
				(type default)
			)
			(layer "B.SilkS")
		)
		(fp_poly
			(pts
				(xy 1.345692 -0.649986) (xy 2.047748 -1.001014) (xy 2.047748 -0.298958)
			)
			(stroke
				(width 0)
				(type default)
			)
			(fill yes)
			(layer "B.SilkS")
		)
		(fp_line
			(start -0.674878 -1.100074)
			(end -0.674878 1.100074)
			(stroke
				(width 0.1)
				(type default)
			)
			(layer "B.Fab")
		)
		(fp_line
			(start -0.674878 1.100074)
			(end 0.674878 1.100074)
			(stroke
				(width 0.1)
				(type default)
			)
			(layer "B.Fab")
		)
		(fp_line
			(start 0.674878 -1.100074)
			(end -0.674878 -1.100074)
			(stroke
				(width 0.1)
				(type default)
			)
			(layer "B.Fab")
		)
		(fp_line
			(start 0.674878 1.100074)
			(end 0.674878 -1.100074)
			(stroke
				(width 0.1)
				(type default)
			)
			(layer "B.Fab")
		)
		(fp_poly
			(pts
				(xy 2.2352 -0.298958) (xy 2.2352 -1.001014) (xy 1.533144 -0.649986)
			)
			(stroke
				(width 0)
				(type default)
			)
			(fill yes)
			(layer "B.Fab")
		)
		(pad "1" smd rect
			(at 0.94996 -0.649986 90)
			(size 0.4318 0.508)
			(layers "B.Cu" "B.Mask" "B.Paste")
			(net "GND")
		)
		(pad "2" smd rect
			(at 0.94996 0 90)
			(size 0.4318 0.508)
			(layers "B.Cu" "B.Mask" "B.Paste")
			(net "FM_LED_PWRGD_PVDDCR_CPU1_P1")
		)
		(pad "3" smd rect
			(at 0.94996 0.649986 90)
			(size 0.4318 0.508)
			(layers "B.Cu" "B.Mask" "B.Paste")
			(net "LED_PWRGD_PVDDIO_P1_D")
		)
		(pad "4" smd rect
			(at -0.94996 0.649986 90)
			(size 0.4318 0.508)
			(layers "B.Cu" "B.Mask" "B.Paste")
			(net "GND")
		)
		(pad "5" smd rect
			(at -0.94996 0 90)
			(size 0.4318 0.508)
			(layers "B.Cu" "B.Mask" "B.Paste")
			(net "FM_LED_PWRGD_PVDDIO_P1")
		)
		(pad "6" smd rect
			(at -0.94996 -0.649986 90)
			(size 0.4318 0.508)
			(layers "B.Cu" "B.Mask" "B.Paste")
			(net "LED_PWRGD_PVDDCR_CPU1_P1_D")
		)
	)
	(footprint ""
		(layer "B.Cu")
		(at 161.406332 -386.766562 90)
		(property "Reference" "C387"
			(at 0 0 90)
			(layer "B.SilkS")
			(hide yes)
			(effects
				(font
					(size 1.27 1.27)
				)
				(justify mirror)
			)
		)
		(property "Value" ""
			(at 0 0 90)
			(layer "B.Fab")
			(effects
				(font
					(size 1.27 1.27)
				)
				(justify mirror)
			)
		)
		(duplicate_pad_numbers_are_jumpers no)
		(fp_line
			(start 0.299974 -0.150114)
			(end -0.299974 -0.150114)
			(stroke
				(width 0.1)
				(type default)
			)
			(layer "B.Fab")
		)
		(fp_line
			(start -0.299974 -0.150114)
			(end -0.299974 0.150114)
			(stroke
				(width 0.1)
				(type default)
			)
			(layer "B.Fab")
		)
		(fp_line
			(start 0.299974 0.150114)
			(end 0.299974 -0.150114)
			(stroke
				(width 0.1)
				(type default)
			)
			(layer "B.Fab")
		)
		(fp_line
			(start -0.299974 0.150114)
			(end 0.299974 0.150114)
			(stroke
				(width 0.1)
				(type default)
			)
			(layer "B.Fab")
		)
		(pad "1" smd rect
			(at 0.2667 0 270)
			(size 0.3048 0.381)
			(layers "B.Cu" "B.Mask" "B.Paste")
			(net "P0V9_CPU1_RT2_2A")
		)
		(pad "2" smd rect
			(at -0.2667 0 270)
			(size 0.3048 0.381)
			(layers "B.Cu" "B.Mask" "B.Paste")
			(net "GND")
		)
	)
	(footprint ""
		(layer "B.Cu")
		(at 72.072754 -204.228192 180)
		(property "Reference" "R557"
			(at 0 0 0)
			(layer "B.SilkS")
			(hide yes)
			(effects
				(font
					(size 1.27 1.27)
				)
				(justify mirror)
			)
		)
		(property "Value" ""
			(at 0 0 0)
			(layer "B.Fab")
			(effects
				(font
					(size 1.27 1.27)
				)
				(justify mirror)
			)
		)
		(duplicate_pad_numbers_are_jumpers no)
		(fp_line
			(start 0.7874 0.4064)
			(end 0.7874 -0.4064)
			(stroke
				(width 0.1524)
				(type default)
			)
			(layer "B.SilkS")
		)
		(fp_line
			(start 0.7874 -0.4064)
			(end -0.7874 -0.4064)
			(stroke
				(width 0.1524)
				(type default)
			)
			(layer "B.SilkS")
		)
		(fp_line
			(start -0.7874 0.4064)
			(end 0.7874 0.4064)
			(stroke
				(width 0.1524)
				(type default)
			)
			(layer "B.SilkS")
		)
		(fp_line
			(start -0.7874 -0.4064)
			(end -0.7874 0.4064)
			(stroke
				(width 0.1524)
				(type default)
			)
			(layer "B.SilkS")
		)
		(fp_line
			(start 0.67945 0.3048)
			(end 0.67945 -0.305054)
			(stroke
				(width 0.1)
				(type default)
			)
			(layer "B.Fab")
		)
		(fp_line
			(start 0.67945 -0.305054)
			(end 0.12065 -0.305054)
			(stroke
				(width 0.1)
				(type default)
			)
			(layer "B.Fab")
		)
		(fp_line
			(start 0.12065 0.3048)
			(end 0.67945 0.3048)
			(stroke
				(width 0.1)
				(type default)
			)
			(layer "B.Fab")
		)
		(fp_line
			(start 0.12065 0.2794)
			(end 0.12065 0.3048)
			(stroke
				(width 0.1)
				(type default)
			)
			(layer "B.Fab")
		)
		(fp_line
			(start 0.12065 -0.2794)
			(end -0.12065 -0.2794)
			(stroke
				(width 0.1)
				(type default)
			)
			(layer "B.Fab")
		)
		(fp_line
			(start 0.12065 -0.305054)
			(end 0.12065 -0.2794)
			(stroke
				(width 0.1)
				(type default)
			)
			(layer "B.Fab")
		)
		(fp_line
			(start -0.120396 0.3048)
			(end -0.120396 0.2794)
			(stroke
				(width 0.1)
				(type default)
			)
			(layer "B.Fab")
		)
		(fp_line
			(start -0.120396 0.2794)
			(end 0.12065 0.2794)
			(stroke
				(width 0.1)
				(type default)
			)
			(layer "B.Fab")
		)
		(fp_line
			(start -0.12065 -0.2794)
			(end -0.12065 -0.3048)
			(stroke
				(width 0.1)
				(type default)
			)
			(layer "B.Fab")
		)
		(fp_line
			(start -0.12065 -0.3048)
			(end -0.67945 -0.3048)
			(stroke
				(width 0.1)
				(type default)
			)
			(layer "B.Fab")
		)
		(fp_line
			(start -0.67945 0.3048)
			(end -0.120396 0.3048)
			(stroke
				(width 0.1)
				(type default)
			)
			(layer "B.Fab")
		)
		(fp_line
			(start -0.67945 -0.3048)
			(end -0.67945 0.3048)
			(stroke
				(width 0.1)
				(type default)
			)
			(layer "B.Fab")
		)
		(pad "1" smd circle
			(at 0.40005 0)
			(size 0 0)
			(layers "B.Cu" "B.Mask" "B.Paste")
			(net "PVDD18_S5_P1")
		)
		(pad "2" smd circle
			(at -0.40005 0)
			(size 0 0)
			(layers "B.Cu" "B.Mask" "B.Paste")
			(net "PWRGD_CPU1_PWROK")
		)
	)
	(footprint ""
		(layer "B.Cu")
		(at 157.94609 -388.011162 -90)
		(property "Reference" "C378"
			(at 0 0 90)
			(layer "B.SilkS")
			(hide yes)
			(effects
				(font
					(size 1.27 1.27)
				)
				(justify mirror)
			)
		)
		(property "Value" ""
			(at 0 0 90)
			(layer "B.Fab")
			(effects
				(font
					(size 1.27 1.27)
				)
				(justify mirror)
			)
		)
		(duplicate_pad_numbers_are_jumpers no)
		(fp_line
			(start -0.299974 0.150114)
			(end 0.299974 0.150114)
			(stroke
				(width 0.1)
				(type default)
			)
			(layer "B.Fab")
		)
		(fp_line
			(start 0.299974 0.150114)
			(end 0.299974 -0.150114)
			(stroke
				(width 0.1)
				(type default)
			)
			(layer "B.Fab")
		)
		(fp_line
			(start -0.299974 -0.150114)
			(end -0.299974 0.150114)
			(stroke
				(width 0.1)
				(type default)
			)
			(layer "B.Fab")
		)
		(fp_line
			(start 0.299974 -0.150114)
			(end -0.299974 -0.150114)
			(stroke
				(width 0.1)
				(type default)
			)
			(layer "B.Fab")
		)
		(pad "1" smd rect
			(at 0.2667 0 90)
			(size 0.3048 0.381)
			(layers "B.Cu" "B.Mask" "B.Paste")
			(net "P1V8_CPU1_RT2_1A_1D")
		)
		(pad "2" smd rect
			(at -0.2667 0 90)
			(size 0.3048 0.381)
			(layers "B.Cu" "B.Mask" "B.Paste")
			(net "GND")
		)
	)
	(footprint ""
		(layer "B.Cu")
		(at 307.34127 -193.99631)
		(property "Reference" "C88"
			(at 0 0 0)
			(layer "B.SilkS")
			(hide yes)
			(effects
				(font
					(size 1.27 1.27)
				)
				(justify mirror)
			)
		)
		(property "Value" ""
			(at 0 0 0)
			(layer "B.Fab")
			(effects
				(font
					(size 1.27 1.27)
				)
				(justify mirror)
			)
		)
		(duplicate_pad_numbers_are_jumpers no)
		(fp_line
			(start -0.7874 -0.4064)
			(end -0.7874 0.4064)
			(stroke
				(width 0.1524)
				(type default)
			)
			(layer "B.SilkS")
		)
		(fp_line
			(start -0.7874 0.4064)
			(end 0.7874 0.4064)
			(stroke
				(width 0.1524)
				(type default)
			)
			(layer "B.SilkS")
		)
		(fp_line
			(start 0.7874 -0.4064)
			(end -0.7874 -0.4064)
			(stroke
				(width 0.1524)
				(type default)
			)
			(layer "B.SilkS")
		)
		(fp_line
			(start 0.7874 0.4064)
			(end 0.7874 -0.4064)
			(stroke
				(width 0.1524)
				(type default)
			)
			(layer "B.SilkS")
		)
		(fp_line
			(start -0.67945 -0.3048)
			(end -0.67945 0.3048)
			(stroke
				(width 0.1)
				(type default)
			)
			(layer "B.Fab")
		)
		(fp_line
			(start -0.67945 0.3048)
			(end -0.120396 0.3048)
			(stroke
				(width 0.1)
				(type default)
			)
			(layer "B.Fab")
		)
		(fp_line
			(start -0.12065 -0.3048)
			(end -0.67945 -0.3048)
			(stroke
				(width 0.1)
				(type default)
			)
			(layer "B.Fab")
		)
		(fp_line
			(start -0.12065 -0.2794)
			(end -0.12065 -0.3048)
			(stroke
				(width 0.1)
				(type default)
			)
			(layer "B.Fab")
		)
		(fp_line
			(start -0.120396 0.2794)
			(end 0.12065 0.2794)
			(stroke
				(width 0.1)
				(type default)
			)
			(layer "B.Fab")
		)
		(fp_line
			(start -0.120396 0.3048)
			(end -0.120396 0.2794)
			(stroke
				(width 0.1)
				(type default)
			)
			(layer "B.Fab")
		)
		(fp_line
			(start 0.12065 -0.305054)
			(end 0.12065 -0.2794)
			(stroke
				(width 0.1)
				(type default)
			)
			(layer "B.Fab")
		)
		(fp_line
			(start 0.12065 -0.2794)
			(end -0.12065 -0.2794)
			(stroke
				(width 0.1)
				(type default)
			)
			(layer "B.Fab")
		)
		(fp_line
			(start 0.12065 0.2794)
			(end 0.12065 0.3048)
			(stroke
				(width 0.1)
				(type default)
			)
			(layer "B.Fab")
		)
		(fp_line
			(start 0.12065 0.3048)
			(end 0.67945 0.3048)
			(stroke
				(width 0.1)
				(type default)
			)
			(layer "B.Fab")
		)
		(fp_line
			(start 0.67945 -0.305054)
			(end 0.12065 -0.305054)
			(stroke
				(width 0.1)
				(type default)
			)
			(layer "B.Fab")
		)
		(fp_line
			(start 0.67945 0.3048)
			(end 0.67945 -0.305054)
			(stroke
				(width 0.1)
				(type default)
			)
			(layer "B.Fab")
		)
		(pad "1" smd circle
			(at 0.40005 0 180)
			(size 0 0)
			(layers "B.Cu" "B.Mask" "B.Paste")
			(net "P3V3_AUX")
		)
		(pad "2" smd circle
			(at -0.40005 0 180)
			(size 0 0)
			(layers "B.Cu" "B.Mask" "B.Paste")
			(net "GND")
		)
	)
	(footprint ""
		(layer "B.Cu")
		(at 212.471508 -2.537206 180)
		(property "Reference" "J80"
			(at 4.56946 -1.086358 270)
			(unlocked yes)
			(layer "B.SilkS")
			(effects
				(font
					(size 0.7874 0.5842)
					(thickness 0.1524)
				)
				(justify left mirror)
			)
		)
		(property "Value" ""
			(at 0 0 0)
			(layer "B.Fab")
			(effects
				(font
					(size 1.27 1.27)
				)
				(justify mirror)
			)
		)
		(duplicate_pad_numbers_are_jumpers no)
		(fp_line
			(start 1.2192 2.06756)
			(end 1.2192 -2.06756)
			(stroke
				(width 0.1524)
				(type default)
			)
			(layer "B.SilkS")
		)
		(fp_line
			(start 1.2192 -2.06756)
			(end -1.2192 -2.06756)
			(stroke
				(width 0.1524)
				(type default)
			)
			(layer "B.SilkS")
		)
		(fp_line
			(start -1.2192 2.06756)
			(end 1.2192 2.06756)
			(stroke
				(width 0.1524)
				(type default)
			)
			(layer "B.SilkS")
		)
		(fp_line
			(start -1.2192 -2.06756)
			(end -1.2192 2.06756)
			(stroke
				(width 0.1524)
				(type default)
			)
			(layer "B.SilkS")
		)
		(pad "" np_thru_hole circle
			(at -3.4671 -1.27 90)
			(size 1.0414 1.0414)
			(drill 1.0414)
			(layers "*.Cu" "*.Mask")
			(clearance 0.381)
			(thermal_gap 0.381)
		)
		(pad "" np_thru_hole circle
			(at -3.4671 1.27 90)
			(size 1.0414 1.0414)
			(drill 1.0414)
			(layers "*.Cu" "*.Mask")
			(clearance 0.381)
			(thermal_gap 0.381)
		)
		(pad "" np_thru_hole circle
			(at 2.8829 -1.27 90)
			(size 1.0414 1.0414)
			(drill 1.0414)
			(layers "*.Cu" "*.Mask")
			(clearance 0.381)
			(thermal_gap 0.381)
		)
		(pad "" np_thru_hole circle
			(at 2.8829 1.27 90)
			(size 1.0414 1.0414)
			(drill 1.0414)
			(layers "*.Cu" "*.Mask")
			(clearance 0.381)
			(thermal_gap 0.381)
		)
		(pad "1" smd rect
			(at -0.8255 -0.249936 90)
			(size 0.3048 0.508)
			(layers "B.Cu" "B.Mask" "B.Paste")
			(net "DELTA_L_85_10INCH_IN4_DP")
		)
		(pad "2" smd rect
			(at -0.8255 0.249936 90)
			(size 0.3048 0.508)
			(layers "B.Cu" "B.Mask" "B.Paste")
			(net "DELTA_L_85_10INCH_IN4_DN")
		)
		(pad "3" smd circle
			(at 0 0)
			(size 0 0)
			(layers "B.Cu" "B.Mask" "B.Paste")
			(net "DELTA_L_GND_1")
		)
		(zone
			(layers "F.Cu" "B.Cu" "In1.Cu" "In2.Cu" "In3.Cu" "In4.Cu" "In5.Cu" "In6.Cu"
				"In7.Cu" "In8.Cu" "In9.Cu" "In10.Cu" "In11.Cu" "In12.Cu" "In13.Cu" "In14.Cu"
				"In15.Cu" "In16.Cu"
			)
			(hatch none 0.5)
			(connect_pads
				(clearance 0)
			)
			(min_thickness 0.25)
			(keepout
				(tracks not_allowed)
				(vias allowed)
				(pads allowed)
				(copperpour not_allowed)
				(footprints allowed)
			)
			(placement
				(enabled no)
				(sheetname "")
			)
			(fill
				(thermal_gap 0.5)
				(thermal_bridge_width 0.5)
				(island_removal_mode 0)
			)
			(polygon
				(pts
					(arc
						(start 210.515708 -3.807206)
						(mid 208.661508 -3.807206)
						(end 210.515708 -3.807206)
					)
				)
			)
		)
		(zone
			(layers "F.Cu" "B.Cu" "In1.Cu" "In2.Cu" "In3.Cu" "In4.Cu" "In5.Cu" "In6.Cu"
				"In7.Cu" "In8.Cu" "In9.Cu" "In10.Cu" "In11.Cu" "In12.Cu" "In13.Cu" "In14.Cu"
				"In15.Cu" "In16.Cu"
			)
			(hatch none 0.5)
			(connect_pads
				(clearance 0)
			)
			(min_thickness 0.25)
			(keepout
				(tracks not_allowed)
				(vias allowed)
				(pads allowed)
				(copperpour not_allowed)
				(footprints allowed)
			)
			(placement
				(enabled no)
				(sheetname "")
			)
			(fill
				(thermal_gap 0.5)
				(thermal_bridge_width 0.5)
				(island_removal_mode 0)
			)
			(polygon
				(pts
					(arc
						(start 210.515708 -1.267206)
						(mid 208.661508 -1.267206)
						(end 210.515708 -1.267206)
					)
				)
			)
		)
		(zone
			(layers "F.Cu" "B.Cu" "In1.Cu" "In2.Cu" "In3.Cu" "In4.Cu" "In5.Cu" "In6.Cu"
				"In7.Cu" "In8.Cu" "In9.Cu" "In10.Cu" "In11.Cu" "In12.Cu" "In13.Cu" "In14.Cu"
				"In15.Cu" "In16.Cu"
			)
			(hatch none 0.5)
			(connect_pads
				(clearance 0)
			)
			(min_thickness 0.25)
			(keepout
				(tracks not_allowed)
				(vias allowed)
				(pads allowed)
				(copperpour not_allowed)
				(footprints allowed)
			)
			(placement
				(enabled no)
				(sheetname "")
			)
			(fill
				(thermal_gap 0.5)
				(thermal_bridge_width 0.5)
				(island_removal_mode 0)
			)
			(polygon
				(pts
					(arc
						(start 216.865708 -3.807206)
						(mid 215.011508 -3.807206)
						(end 216.865708 -3.807206)
					)
				)
			)
		)
		(zone
			(layers "F.Cu" "B.Cu" "In1.Cu" "In2.Cu" "In3.Cu" "In4.Cu" "In5.Cu" "In6.Cu"
				"In7.Cu" "In8.Cu" "In9.Cu" "In10.Cu" "In11.Cu" "In12.Cu" "In13.Cu" "In14.Cu"
				"In15.Cu" "In16.Cu"
			)
			(hatch none 0.5)
			(connect_pads
				(clearance 0)
			)
			(min_thickness 0.25)
			(keepout
				(tracks not_allowed)
				(vias allowed)
				(pads allowed)
				(copperpour not_allowed)
				(footprints allowed)
			)
			(placement
				(enabled no)
				(sheetname "")
			)
			(fill
				(thermal_gap 0.5)
				(thermal_bridge_width 0.5)
				(island_removal_mode 0)
			)
			(polygon
				(pts
					(arc
						(start 216.865708 -1.267206)
						(mid 215.011508 -1.267206)
						(end 216.865708 -1.267206)
					)
				)
			)
		)
		(zone
			(layer "B.Cu")
			(hatch none 0.5)
			(connect_pads
				(clearance 0)
			)
			(min_thickness 0.25)
			(keepout
				(tracks not_allowed)
				(vias allowed)
				(pads allowed)
				(copperpour not_allowed)
				(footprints allowed)
			)
			(placement
				(enabled no)
				(sheetname "")
			)
			(fill
				(thermal_gap 0.5)
				(thermal_bridge_width 0.5)
				(island_removal_mode 0)
			)
			(polygon
				(pts
					(xy 213.589108 -1.988566) (xy 213.589108 -2.08407) (xy 212.992208 -2.08407) (xy 212.992208 -2.49047)
					(xy 213.589108 -2.49047) (xy 213.589108 -2.583942) (xy 212.992208 -2.583942) (xy 212.992208 -2.990342)
					(xy 213.589108 -2.990342) (xy 213.589108 -3.085846) (xy 212.890608 -3.085846) (xy 212.890608 -1.988566)
				)
			)
		)
	)
	(footprint ""
		(layer "B.Cu")
		(at 110.856014 -259.845302 180)
		(property "Reference" "C2502"
			(at 0 0 0)
			(layer "B.SilkS")
			(hide yes)
			(effects
				(font
					(size 1.27 1.27)
				)
				(justify mirror)
			)
		)
		(property "Value" ""
			(at 0 0 0)
			(layer "B.Fab")
			(effects
				(font
					(size 1.27 1.27)
				)
				(justify mirror)
			)
		)
		(duplicate_pad_numbers_are_jumpers no)
		(fp_line
			(start 0.7874 0.4064)
			(end 0.7874 -0.4064)
			(stroke
				(width 0.1524)
				(type default)
			)
			(layer "B.SilkS")
		)
		(fp_line
			(start 0.7874 -0.4064)
			(end -0.7874 -0.4064)
			(stroke
				(width 0.1524)
				(type default)
			)
			(layer "B.SilkS")
		)
		(fp_line
			(start -0.7874 0.4064)
			(end 0.7874 0.4064)
			(stroke
				(width 0.1524)
				(type default)
			)
			(layer "B.SilkS")
		)
		(fp_line
			(start -0.7874 -0.4064)
			(end -0.7874 0.4064)
			(stroke
				(width 0.1524)
				(type default)
			)
			(layer "B.SilkS")
		)
		(fp_line
			(start 0.67945 0.3048)
			(end 0.67945 -0.305054)
			(stroke
				(width 0.1)
				(type default)
			)
			(layer "B.Fab")
		)
		(fp_line
			(start 0.67945 -0.305054)
			(end 0.12065 -0.305054)
			(stroke
				(width 0.1)
				(type default)
			)
			(layer "B.Fab")
		)
		(fp_line
			(start 0.12065 0.3048)
			(end 0.67945 0.3048)
			(stroke
				(width 0.1)
				(type default)
			)
			(layer "B.Fab")
		)
		(fp_line
			(start 0.12065 0.2794)
			(end 0.12065 0.3048)
			(stroke
				(width 0.1)
				(type default)
			)
			(layer "B.Fab")
		)
		(fp_line
			(start 0.12065 -0.2794)
			(end -0.12065 -0.2794)
			(stroke
				(width 0.1)
				(type default)
			)
			(layer "B.Fab")
		)
		(fp_line
			(start 0.12065 -0.305054)
			(end 0.12065 -0.2794)
			(stroke
				(width 0.1)
				(type default)
			)
			(layer "B.Fab")
		)
		(fp_line
			(start -0.120396 0.3048)
			(end -0.120396 0.2794)
			(stroke
				(width 0.1)
				(type default)
			)
			(layer "B.Fab")
		)
		(fp_line
			(start -0.120396 0.2794)
			(end 0.12065 0.2794)
			(stroke
				(width 0.1)
				(type default)
			)
			(layer "B.Fab")
		)
		(fp_line
			(start -0.12065 -0.2794)
			(end -0.12065 -0.3048)
			(stroke
				(width 0.1)
				(type default)
			)
			(layer "B.Fab")
		)
		(fp_line
			(start -0.12065 -0.3048)
			(end -0.67945 -0.3048)
			(stroke
				(width 0.1)
				(type default)
			)
			(layer "B.Fab")
		)
		(fp_line
			(start -0.67945 0.3048)
			(end -0.120396 0.3048)
			(stroke
				(width 0.1)
				(type default)
			)
			(layer "B.Fab")
		)
		(fp_line
			(start -0.67945 -0.3048)
			(end -0.67945 0.3048)
			(stroke
				(width 0.1)
				(type default)
			)
			(layer "B.Fab")
		)
		(pad "1" smd circle
			(at 0.40005 0)
			(size 0 0)
			(layers "B.Cu" "B.Mask" "B.Paste")
			(net "PVDD11_S3_P1")
		)
		(pad "2" smd circle
			(at -0.40005 0)
			(size 0 0)
			(layers "B.Cu" "B.Mask" "B.Paste")
			(net "GND")
		)
	)
	(footprint ""
		(layer "B.Cu")
		(at 358.037892 -416.91687 180)
		(property "Reference" "R2934"
			(at 0 0 0)
			(layer "B.SilkS")
			(hide yes)
			(effects
				(font
					(size 1.27 1.27)
				)
				(justify mirror)
			)
		)
		(property "Value" ""
			(at 0 0 0)
			(layer "B.Fab")
			(effects
				(font
					(size 1.27 1.27)
				)
				(justify mirror)
			)
		)
		(duplicate_pad_numbers_are_jumpers no)
		(fp_line
			(start 0.7874 0.4064)
			(end 0.7874 -0.4064)
			(stroke
				(width 0.1524)
				(type default)
			)
			(layer "B.SilkS")
		)
		(fp_line
			(start 0.7874 -0.4064)
			(end -0.7874 -0.4064)
			(stroke
				(width 0.1524)
				(type default)
			)
			(layer "B.SilkS")
		)
		(fp_line
			(start -0.7874 0.4064)
			(end 0.7874 0.4064)
			(stroke
				(width 0.1524)
				(type default)
			)
			(layer "B.SilkS")
		)
		(fp_line
			(start -0.7874 -0.4064)
			(end -0.7874 0.4064)
			(stroke
				(width 0.1524)
				(type default)
			)
			(layer "B.SilkS")
		)
		(fp_line
			(start 0.67945 0.3048)
			(end 0.67945 -0.305054)
			(stroke
				(width 0.1)
				(type default)
			)
			(layer "B.Fab")
		)
		(fp_line
			(start 0.67945 -0.305054)
			(end 0.12065 -0.305054)
			(stroke
				(width 0.1)
				(type default)
			)
			(layer "B.Fab")
		)
		(fp_line
			(start 0.12065 0.3048)
			(end 0.67945 0.3048)
			(stroke
				(width 0.1)
				(type default)
			)
			(layer "B.Fab")
		)
		(fp_line
			(start 0.12065 0.2794)
			(end 0.12065 0.3048)
			(stroke
				(width 0.1)
				(type default)
			)
			(layer "B.Fab")
		)
		(fp_line
			(start 0.12065 -0.2794)
			(end -0.12065 -0.2794)
			(stroke
				(width 0.1)
				(type default)
			)
			(layer "B.Fab")
		)
		(fp_line
			(start 0.12065 -0.305054)
			(end 0.12065 -0.2794)
			(stroke
				(width 0.1)
				(type default)
			)
			(layer "B.Fab")
		)
		(fp_line
			(start -0.120396 0.3048)
			(end -0.120396 0.2794)
			(stroke
				(width 0.1)
				(type default)
			)
			(layer "B.Fab")
		)
		(fp_line
			(start -0.120396 0.2794)
			(end 0.12065 0.2794)
			(stroke
				(width 0.1)
				(type default)
			)
			(layer "B.Fab")
		)
		(fp_line
			(start -0.12065 -0.2794)
			(end -0.12065 -0.3048)
			(stroke
				(width 0.1)
				(type default)
			)
			(layer "B.Fab")
		)
		(fp_line
			(start -0.12065 -0.3048)
			(end -0.67945 -0.3048)
			(stroke
				(width 0.1)
				(type default)
			)
			(layer "B.Fab")
		)
		(fp_line
			(start -0.67945 0.3048)
			(end -0.120396 0.3048)
			(stroke
				(width 0.1)
				(type default)
			)
			(layer "B.Fab")
		)
		(fp_line
			(start -0.67945 -0.3048)
			(end -0.67945 0.3048)
			(stroke
				(width 0.1)
				(type default)
			)
			(layer "B.Fab")
		)
		(pad "1" smd circle
			(at 0.40005 0)
			(size 0 0)
			(layers "B.Cu" "B.Mask" "B.Paste")
			(net "P3V3_AUX")
		)
		(pad "2" smd circle
			(at -0.40005 0)
			(size 0 0)
			(layers "B.Cu" "B.Mask" "B.Paste")
			(net "FM_SWB_PWRGD_ISO")
		)
	)
	(footprint ""
		(layer "B.Cu")
		(at 378.526802 -416.899344 90)
		(property "Reference" "C6602"
			(at 0 0 90)
			(layer "B.SilkS")
			(hide yes)
			(effects
				(font
					(size 1.27 1.27)
				)
				(justify mirror)
			)
		)
		(property "Value" ""
			(at 0 0 90)
			(layer "B.Fab")
			(effects
				(font
					(size 1.27 1.27)
				)
				(justify mirror)
			)
		)
		(duplicate_pad_numbers_are_jumpers no)
		(fp_line
			(start 0.299974 -0.150114)
			(end -0.299974 -0.150114)
			(stroke
				(width 0.1)
				(type default)
			)
			(layer "B.Fab")
		)
		(fp_line
			(start -0.299974 -0.150114)
			(end -0.299974 0.150114)
			(stroke
				(width 0.1)
				(type default)
			)
			(layer "B.Fab")
		)
		(fp_line
			(start 0.299974 0.150114)
			(end 0.299974 -0.150114)
			(stroke
				(width 0.1)
				(type default)
			)
			(layer "B.Fab")
		)
		(fp_line
			(start -0.299974 0.150114)
			(end 0.299974 0.150114)
			(stroke
				(width 0.1)
				(type default)
			)
			(layer "B.Fab")
		)
		(pad "1" smd rect
			(at 0.2667 0 270)
			(size 0.3048 0.381)
			(layers "B.Cu" "B.Mask" "B.Paste")
			(net "P5E_CPU0_P3_TX_BUF_C_DN<2>")
		)
		(pad "2" smd rect
			(at -0.2667 0 270)
			(size 0.3048 0.381)
			(layers "B.Cu" "B.Mask" "B.Paste")
			(net "P5E_CPU0_P3_TX_BUF_DN<2>")
		)
	)
	(footprint ""
		(layer "B.Cu")
		(at 214.884 -331.724)
		(property "Reference" "R6774"
			(at 0 0 0)
			(layer "B.SilkS")
			(hide yes)
			(effects
				(font
					(size 1.27 1.27)
				)
				(justify mirror)
			)
		)
		(property "Value" ""
			(at 0 0 0)
			(layer "B.Fab")
			(effects
				(font
					(size 1.27 1.27)
				)
				(justify mirror)
			)
		)
		(duplicate_pad_numbers_are_jumpers no)
		(fp_line
			(start -0.32512 -0.175006)
			(end -0.32512 0.175006)
			(stroke
				(width 0.1)
				(type default)
			)
			(layer "B.Fab")
		)
		(fp_line
			(start -0.32512 0.175006)
			(end 0.32512 0.175006)
			(stroke
				(width 0.1)
				(type default)
			)
			(layer "B.Fab")
		)
		(fp_line
			(start 0.32512 -0.175006)
			(end -0.32512 -0.175006)
			(stroke
				(width 0.1)
				(type default)
			)
			(layer "B.Fab")
		)
		(fp_line
			(start 0.32512 0.175006)
			(end 0.32512 -0.175006)
			(stroke
				(width 0.1)
				(type default)
			)
			(layer "B.Fab")
		)
		(pad "1" smd rect
			(at 0.2667 0 180)
			(size 0.3048 0.381)
			(layers "B.Cu" "B.Mask" "B.Paste")
			(net "RT_SMB_MUX_ADDR1")
		)
		(pad "2" smd rect
			(at -0.2667 0)
			(size 0.3048 0.381)
			(layers "B.Cu" "B.Mask" "B.Paste")
			(net "GND")
		)
	)
	(footprint ""
		(layer "B.Cu")
		(at 346.532454 -266.64031)
		(property "Reference" "C2515"
			(at 0 0 0)
			(layer "B.SilkS")
			(hide yes)
			(effects
				(font
					(size 1.27 1.27)
				)
				(justify mirror)
			)
		)
		(property "Value" ""
			(at 0 0 0)
			(layer "B.Fab")
			(effects
				(font
					(size 1.27 1.27)
				)
				(justify mirror)
			)
		)
		(duplicate_pad_numbers_are_jumpers no)
		(fp_line
			(start -0.7874 -0.4064)
			(end -0.7874 0.4064)
			(stroke
				(width 0.1524)
				(type default)
			)
			(layer "B.SilkS")
		)
		(fp_line
			(start -0.7874 0.4064)
			(end 0.7874 0.4064)
			(stroke
				(width 0.1524)
				(type default)
			)
			(layer "B.SilkS")
		)
		(fp_line
			(start 0.7874 -0.4064)
			(end -0.7874 -0.4064)
			(stroke
				(width 0.1524)
				(type default)
			)
			(layer "B.SilkS")
		)
		(fp_line
			(start 0.7874 0.4064)
			(end 0.7874 -0.4064)
			(stroke
				(width 0.1524)
				(type default)
			)
			(layer "B.SilkS")
		)
		(fp_line
			(start -0.67945 -0.3048)
			(end -0.67945 0.3048)
			(stroke
				(width 0.1)
				(type default)
			)
			(layer "B.Fab")
		)
		(fp_line
			(start -0.67945 0.3048)
			(end -0.120396 0.3048)
			(stroke
				(width 0.1)
				(type default)
			)
			(layer "B.Fab")
		)
		(fp_line
			(start -0.12065 -0.3048)
			(end -0.67945 -0.3048)
			(stroke
				(width 0.1)
				(type default)
			)
			(layer "B.Fab")
		)
		(fp_line
			(start -0.12065 -0.2794)
			(end -0.12065 -0.3048)
			(stroke
				(width 0.1)
				(type default)
			)
			(layer "B.Fab")
		)
		(fp_line
			(start -0.120396 0.2794)
			(end 0.12065 0.2794)
			(stroke
				(width 0.1)
				(type default)
			)
			(layer "B.Fab")
		)
		(fp_line
			(start -0.120396 0.3048)
			(end -0.120396 0.2794)
			(stroke
				(width 0.1)
				(type default)
			)
			(layer "B.Fab")
		)
		(fp_line
			(start 0.12065 -0.305054)
			(end 0.12065 -0.2794)
			(stroke
				(width 0.1)
				(type default)
			)
			(layer "B.Fab")
		)
		(fp_line
			(start 0.12065 -0.2794)
			(end -0.12065 -0.2794)
			(stroke
				(width 0.1)
				(type default)
			)
			(layer "B.Fab")
		)
		(fp_line
			(start 0.12065 0.2794)
			(end 0.12065 0.3048)
			(stroke
				(width 0.1)
				(type default)
			)
			(layer "B.Fab")
		)
		(fp_line
			(start 0.12065 0.3048)
			(end 0.67945 0.3048)
			(stroke
				(width 0.1)
				(type default)
			)
			(layer "B.Fab")
		)
		(fp_line
			(start 0.67945 -0.305054)
			(end 0.12065 -0.305054)
			(stroke
				(width 0.1)
				(type default)
			)
			(layer "B.Fab")
		)
		(fp_line
			(start 0.67945 0.3048)
			(end 0.67945 -0.305054)
			(stroke
				(width 0.1)
				(type default)
			)
			(layer "B.Fab")
		)
		(pad "1" smd circle
			(at 0.40005 0 180)
			(size 0 0)
			(layers "B.Cu" "B.Mask" "B.Paste")
			(net "PVDD_33_S5")
		)
		(pad "2" smd circle
			(at -0.40005 0 180)
			(size 0 0)
			(layers "B.Cu" "B.Mask" "B.Paste")
			(net "GND")
		)
	)
	(footprint ""
		(layer "B.Cu")
		(at 71.530718 -335.06791 90)
		(property "Reference" "PC416_3"
			(at 0 0 90)
			(layer "B.SilkS")
			(hide yes)
			(effects
				(font
					(size 1.27 1.27)
				)
				(justify mirror)
			)
		)
		(property "Value" ""
			(at 0 0 90)
			(layer "B.Fab")
			(effects
				(font
					(size 1.27 1.27)
				)
				(justify mirror)
			)
		)
		(duplicate_pad_numbers_are_jumpers no)
		(fp_line
			(start 1.524 -0.762)
			(end -1.524 -0.762)
			(stroke
				(width 0.1524)
				(type default)
			)
			(layer "B.SilkS")
		)
		(fp_line
			(start -1.524 -0.762)
			(end -1.524 0.762)
			(stroke
				(width 0.1524)
				(type default)
			)
			(layer "B.SilkS")
		)
		(fp_line
			(start 1.524 0.762)
			(end 1.524 -0.762)
			(stroke
				(width 0.1524)
				(type default)
			)
			(layer "B.SilkS")
		)
		(fp_line
			(start -1.524 0.762)
			(end 1.524 0.762)
			(stroke
				(width 0.1524)
				(type default)
			)
			(layer "B.SilkS")
		)
		(fp_line
			(start 1.1049 -0.724916)
			(end 1.1049 0.724916)
			(stroke
				(width 0.1)
				(type default)
			)
			(layer "B.Fab")
		)
		(fp_line
			(start -1.1049 -0.724916)
			(end 1.1049 -0.724916)
			(stroke
				(width 0.1)
				(type default)
			)
			(layer "B.Fab")
		)
		(fp_line
			(start 1.1049 0.724916)
			(end -1.1049 0.724916)
			(stroke
				(width 0.1)
				(type default)
			)
			(layer "B.Fab")
		)
		(fp_line
			(start -1.1049 0.724916)
			(end -1.1049 -0.724916)
			(stroke
				(width 0.1)
				(type default)
			)
			(layer "B.Fab")
		)
		(pad "1" smd rect
			(at 0.889 0 90)
			(size 1.016 1.27)
			(layers "B.Cu" "B.Mask" "B.Paste")
			(net "SW_P12V_AUX_PVDDCR_CPU1_P1_FLT")
		)
		(pad "2" smd rect
			(at -0.889 0 90)
			(size 1.016 1.27)
			(layers "B.Cu" "B.Mask" "B.Paste")
			(net "GND")
		)
	)
	(footprint ""
		(layer "B.Cu")
		(at 435.406292 -341.921846 -90)
		(property "Reference" "PC227_1"
			(at 0 0 90)
			(layer "B.SilkS")
			(hide yes)
			(effects
				(font
					(size 1.27 1.27)
				)
				(justify mirror)
			)
		)
		(property "Value" ""
			(at 0 0 90)
			(layer "B.Fab")
			(effects
				(font
					(size 1.27 1.27)
				)
				(justify mirror)
			)
		)
		(duplicate_pad_numbers_are_jumpers no)
		(fp_line
			(start -1.524 0.762)
			(end 1.524 0.762)
			(stroke
				(width 0.1524)
				(type default)
			)
			(layer "B.SilkS")
		)
		(fp_line
			(start 1.524 0.762)
			(end 1.524 -0.762)
			(stroke
				(width 0.1524)
				(type default)
			)
			(layer "B.SilkS")
		)
		(fp_line
			(start -1.524 -0.762)
			(end -1.524 0.762)
			(stroke
				(width 0.1524)
				(type default)
			)
			(layer "B.SilkS")
		)
		(fp_line
			(start 1.524 -0.762)
			(end -1.524 -0.762)
			(stroke
				(width 0.1524)
				(type default)
			)
			(layer "B.SilkS")
		)
		(fp_line
			(start -1.1049 0.724916)
			(end -1.1049 -0.724916)
			(stroke
				(width 0.1)
				(type default)
			)
			(layer "B.Fab")
		)
		(fp_line
			(start 1.1049 0.724916)
			(end -1.1049 0.724916)
			(stroke
				(width 0.1)
				(type default)
			)
			(layer "B.Fab")
		)
		(fp_line
			(start -1.1049 -0.724916)
			(end 1.1049 -0.724916)
			(stroke
				(width 0.1)
				(type default)
			)
			(layer "B.Fab")
		)
		(fp_line
			(start 1.1049 -0.724916)
			(end 1.1049 0.724916)
			(stroke
				(width 0.1)
				(type default)
			)
			(layer "B.Fab")
		)
		(pad "1" smd rect
			(at 0.889 0 270)
			(size 1.016 1.27)
			(layers "B.Cu" "B.Mask" "B.Paste")
			(net "PVDD11_S3_P0")
		)
		(pad "2" smd rect
			(at -0.889 0 270)
			(size 1.016 1.27)
			(layers "B.Cu" "B.Mask" "B.Paste")
			(net "GND")
		)
	)
	(footprint ""
		(layer "B.Cu")
		(at 29.722318 -346.788994 90)
		(property "Reference" "PC633_4"
			(at 0 0 90)
			(layer "B.SilkS")
			(hide yes)
			(effects
				(font
					(size 1.27 1.27)
				)
				(justify mirror)
			)
		)
		(property "Value" ""
			(at 0 0 90)
			(layer "B.Fab")
			(effects
				(font
					(size 1.27 1.27)
				)
				(justify mirror)
			)
		)
		(duplicate_pad_numbers_are_jumpers no)
		(fp_line
			(start 1.524 -0.762)
			(end -1.524 -0.762)
			(stroke
				(width 0.1524)
				(type default)
			)
			(layer "B.SilkS")
		)
		(fp_line
			(start -1.524 -0.762)
			(end -1.524 0.762)
			(stroke
				(width 0.1524)
				(type default)
			)
			(layer "B.SilkS")
		)
		(fp_line
			(start 1.524 0.762)
			(end 1.524 -0.762)
			(stroke
				(width 0.1524)
				(type default)
			)
			(layer "B.SilkS")
		)
		(fp_line
			(start -1.524 0.762)
			(end 1.524 0.762)
			(stroke
				(width 0.1524)
				(type default)
			)
			(layer "B.SilkS")
		)
		(fp_line
			(start 1.1049 -0.724916)
			(end 1.1049 0.724916)
			(stroke
				(width 0.1)
				(type default)
			)
			(layer "B.Fab")
		)
		(fp_line
			(start -1.1049 -0.724916)
			(end 1.1049 -0.724916)
			(stroke
				(width 0.1)
				(type default)
			)
			(layer "B.Fab")
		)
		(fp_line
			(start 1.1049 0.724916)
			(end -1.1049 0.724916)
			(stroke
				(width 0.1)
				(type default)
			)
			(layer "B.Fab")
		)
		(fp_line
			(start -1.1049 0.724916)
			(end -1.1049 -0.724916)
			(stroke
				(width 0.1)
				(type default)
			)
			(layer "B.Fab")
		)
		(pad "1" smd rect
			(at 0.889 0 90)
			(size 1.016 1.27)
			(layers "B.Cu" "B.Mask" "B.Paste")
			(net "SW_P12V_AUX_PVDDIO_P1_FLT")
		)
		(pad "2" smd rect
			(at -0.889 0 90)
			(size 1.016 1.27)
			(layers "B.Cu" "B.Mask" "B.Paste")
			(net "GND")
		)
	)
	(footprint ""
		(layer "B.Cu")
		(at 366.62487 -176.712118 90)
		(property "Reference" "PR318"
			(at 0 0 90)
			(layer "B.SilkS")
			(hide yes)
			(effects
				(font
					(size 1.27 1.27)
				)
				(justify mirror)
			)
		)
		(property "Value" ""
			(at 0 0 90)
			(layer "B.Fab")
			(effects
				(font
					(size 1.27 1.27)
				)
				(justify mirror)
			)
		)
		(duplicate_pad_numbers_are_jumpers no)
		(fp_line
			(start 0.7874 -0.4064)
			(end -0.7874 -0.4064)
			(stroke
				(width 0.1524)
				(type default)
			)
			(layer "B.SilkS")
		)
		(fp_line
			(start -0.7874 -0.4064)
			(end -0.7874 0.4064)
			(stroke
				(width 0.1524)
				(type default)
			)
			(layer "B.SilkS")
		)
		(fp_line
			(start 0.7874 0.4064)
			(end 0.7874 -0.4064)
			(stroke
				(width 0.1524)
				(type default)
			)
			(layer "B.SilkS")
		)
		(fp_line
			(start -0.7874 0.4064)
			(end 0.7874 0.4064)
			(stroke
				(width 0.1524)
				(type default)
			)
			(layer "B.SilkS")
		)
		(fp_line
			(start 0.67945 -0.305054)
			(end 0.12065 -0.305054)
			(stroke
				(width 0.1)
				(type default)
			)
			(layer "B.Fab")
		)
		(fp_line
			(start 0.12065 -0.305054)
			(end 0.12065 -0.2794)
			(stroke
				(width 0.1)
				(type default)
			)
			(layer "B.Fab")
		)
		(fp_line
			(start -0.12065 -0.3048)
			(end -0.67945 -0.3048)
			(stroke
				(width 0.1)
				(type default)
			)
			(layer "B.Fab")
		)
		(fp_line
			(start -0.67945 -0.3048)
			(end -0.67945 0.3048)
			(stroke
				(width 0.1)
				(type default)
			)
			(layer "B.Fab")
		)
		(fp_line
			(start 0.12065 -0.2794)
			(end -0.12065 -0.2794)
			(stroke
				(width 0.1)
				(type default)
			)
			(layer "B.Fab")
		)
		(fp_line
			(start -0.12065 -0.2794)
			(end -0.12065 -0.3048)
			(stroke
				(width 0.1)
				(type default)
			)
			(layer "B.Fab")
		)
		(fp_line
			(start 0.12065 0.2794)
			(end 0.12065 0.3048)
			(stroke
				(width 0.1)
				(type default)
			)
			(layer "B.Fab")
		)
		(fp_line
			(start -0.120396 0.2794)
			(end 0.12065 0.2794)
			(stroke
				(width 0.1)
				(type default)
			)
			(layer "B.Fab")
		)
		(fp_line
			(start 0.67945 0.3048)
			(end 0.67945 -0.305054)
			(stroke
				(width 0.1)
				(type default)
			)
			(layer "B.Fab")
		)
		(fp_line
			(start 0.12065 0.3048)
			(end 0.67945 0.3048)
			(stroke
				(width 0.1)
				(type default)
			)
			(layer "B.Fab")
		)
		(fp_line
			(start -0.120396 0.3048)
			(end -0.120396 0.2794)
			(stroke
				(width 0.1)
				(type default)
			)
			(layer "B.Fab")
		)
		(fp_line
			(start -0.67945 0.3048)
			(end -0.120396 0.3048)
			(stroke
				(width 0.1)
				(type default)
			)
			(layer "B.Fab")
		)
		(pad "1" smd circle
			(at 0.40005 0 270)
			(size 0 0)
			(layers "B.Cu" "B.Mask" "B.Paste")
			(net "PVDDCR_CPU0_P0_PVCC")
		)
		(pad "2" smd circle
			(at -0.40005 0 270)
			(size 0 0)
			(layers "B.Cu" "B.Mask" "B.Paste")
			(net "PVDDCR_CPU0_P0_VCC1")
		)
	)
	(footprint ""
		(layer "B.Cu")
		(at 150.746206 -388.011162 -90)
		(property "Reference" "C403"
			(at 0 0 90)
			(layer "B.SilkS")
			(hide yes)
			(effects
				(font
					(size 1.27 1.27)
				)
				(justify mirror)
			)
		)
		(property "Value" ""
			(at 0 0 90)
			(layer "B.Fab")
			(effects
				(font
					(size 1.27 1.27)
				)
				(justify mirror)
			)
		)
		(duplicate_pad_numbers_are_jumpers no)
		(fp_line
			(start -0.299974 0.150114)
			(end 0.299974 0.150114)
			(stroke
				(width 0.1)
				(type default)
			)
			(layer "B.Fab")
		)
		(fp_line
			(start 0.299974 0.150114)
			(end 0.299974 -0.150114)
			(stroke
				(width 0.1)
				(type default)
			)
			(layer "B.Fab")
		)
		(fp_line
			(start -0.299974 -0.150114)
			(end -0.299974 0.150114)
			(stroke
				(width 0.1)
				(type default)
			)
			(layer "B.Fab")
		)
		(fp_line
			(start 0.299974 -0.150114)
			(end -0.299974 -0.150114)
			(stroke
				(width 0.1)
				(type default)
			)
			(layer "B.Fab")
		)
		(pad "1" smd rect
			(at 0.2667 0 90)
			(size 0.3048 0.381)
			(layers "B.Cu" "B.Mask" "B.Paste")
			(net "P0V9_CPU1_RT2_2A")
		)
		(pad "2" smd rect
			(at -0.2667 0 90)
			(size 0.3048 0.381)
			(layers "B.Cu" "B.Mask" "B.Paste")
			(net "GND")
		)
	)
	(footprint ""
		(layer "B.Cu")
		(at 352.974656 -169.619676 -90)
		(property "Reference" "PC572_5"
			(at 0 0 90)
			(layer "B.SilkS")
			(hide yes)
			(effects
				(font
					(size 1.27 1.27)
				)
				(justify mirror)
			)
		)
		(property "Value" ""
			(at 0 0 90)
			(layer "B.Fab")
			(effects
				(font
					(size 1.27 1.27)
				)
				(justify mirror)
			)
		)
		(duplicate_pad_numbers_are_jumpers no)
		(fp_line
			(start -1.524 0.762)
			(end 1.524 0.762)
			(stroke
				(width 0.1524)
				(type default)
			)
			(layer "B.SilkS")
		)
		(fp_line
			(start 1.524 0.762)
			(end 1.524 -0.762)
			(stroke
				(width 0.1524)
				(type default)
			)
			(layer "B.SilkS")
		)
		(fp_line
			(start -1.524 -0.762)
			(end -1.524 0.762)
			(stroke
				(width 0.1524)
				(type default)
			)
			(layer "B.SilkS")
		)
		(fp_line
			(start 1.524 -0.762)
			(end -1.524 -0.762)
			(stroke
				(width 0.1524)
				(type default)
			)
			(layer "B.SilkS")
		)
		(fp_line
			(start -1.1049 0.724916)
			(end -1.1049 -0.724916)
			(stroke
				(width 0.1)
				(type default)
			)
			(layer "B.Fab")
		)
		(fp_line
			(start 1.1049 0.724916)
			(end -1.1049 0.724916)
			(stroke
				(width 0.1)
				(type default)
			)
			(layer "B.Fab")
		)
		(fp_line
			(start -1.1049 -0.724916)
			(end 1.1049 -0.724916)
			(stroke
				(width 0.1)
				(type default)
			)
			(layer "B.Fab")
		)
		(fp_line
			(start 1.1049 -0.724916)
			(end 1.1049 0.724916)
			(stroke
				(width 0.1)
				(type default)
			)
			(layer "B.Fab")
		)
		(pad "1" smd rect
			(at 0.889 0 270)
			(size 1.016 1.27)
			(layers "B.Cu" "B.Mask" "B.Paste")
			(net "SW_P12V_AUX_PVDDCR_CPU0_P0_FLT")
		)
		(pad "2" smd rect
			(at -0.889 0 270)
			(size 1.016 1.27)
			(layers "B.Cu" "B.Mask" "B.Paste")
			(net "GND")
		)
	)
	(footprint ""
		(layer "B.Cu")
		(at 379.266958 -205.101952 -90)
		(property "Reference" "R421"
			(at 0 0 90)
			(layer "B.SilkS")
			(hide yes)
			(effects
				(font
					(size 1.27 1.27)
				)
				(justify mirror)
			)
		)
		(property "Value" ""
			(at 0 0 90)
			(layer "B.Fab")
			(effects
				(font
					(size 1.27 1.27)
				)
				(justify mirror)
			)
		)
		(duplicate_pad_numbers_are_jumpers no)
		(fp_line
			(start -0.7874 0.4064)
			(end 0.7874 0.4064)
			(stroke
				(width 0.1524)
				(type default)
			)
			(layer "B.SilkS")
		)
		(fp_line
			(start 0.7874 0.4064)
			(end 0.7874 -0.4064)
			(stroke
				(width 0.1524)
				(type default)
			)
			(layer "B.SilkS")
		)
		(fp_line
			(start -0.7874 -0.4064)
			(end -0.7874 0.4064)
			(stroke
				(width 0.1524)
				(type default)
			)
			(layer "B.SilkS")
		)
		(fp_line
			(start 0.7874 -0.4064)
			(end -0.7874 -0.4064)
			(stroke
				(width 0.1524)
				(type default)
			)
			(layer "B.SilkS")
		)
		(fp_line
			(start -0.67945 0.3048)
			(end -0.120396 0.3048)
			(stroke
				(width 0.1)
				(type default)
			)
			(layer "B.Fab")
		)
		(fp_line
			(start -0.120396 0.3048)
			(end -0.120396 0.2794)
			(stroke
				(width 0.1)
				(type default)
			)
			(layer "B.Fab")
		)
		(fp_line
			(start 0.12065 0.3048)
			(end 0.67945 0.3048)
			(stroke
				(width 0.1)
				(type default)
			)
			(layer "B.Fab")
		)
		(fp_line
			(start 0.67945 0.3048)
			(end 0.67945 -0.305054)
			(stroke
				(width 0.1)
				(type default)
			)
			(layer "B.Fab")
		)
		(fp_line
			(start -0.120396 0.2794)
			(end 0.12065 0.2794)
			(stroke
				(width 0.1)
				(type default)
			)
			(layer "B.Fab")
		)
		(fp_line
			(start 0.12065 0.2794)
			(end 0.12065 0.3048)
			(stroke
				(width 0.1)
				(type default)
			)
			(layer "B.Fab")
		)
		(fp_line
			(start -0.12065 -0.2794)
			(end -0.12065 -0.3048)
			(stroke
				(width 0.1)
				(type default)
			)
			(layer "B.Fab")
		)
		(fp_line
			(start 0.12065 -0.2794)
			(end -0.12065 -0.2794)
			(stroke
				(width 0.1)
				(type default)
			)
			(layer "B.Fab")
		)
		(fp_line
			(start -0.67945 -0.3048)
			(end -0.67945 0.3048)
			(stroke
				(width 0.1)
				(type default)
			)
			(layer "B.Fab")
		)
		(fp_line
			(start -0.12065 -0.3048)
			(end -0.67945 -0.3048)
			(stroke
				(width 0.1)
				(type default)
			)
			(layer "B.Fab")
		)
		(fp_line
			(start 0.12065 -0.305054)
			(end 0.12065 -0.2794)
			(stroke
				(width 0.1)
				(type default)
			)
			(layer "B.Fab")
		)
		(fp_line
			(start 0.67945 -0.305054)
			(end 0.12065 -0.305054)
			(stroke
				(width 0.1)
				(type default)
			)
			(layer "B.Fab")
		)
		(pad "1" smd circle
			(at 0.40005 0 90)
			(size 0 0)
			(layers "B.Cu" "B.Mask" "B.Paste")
			(net "PVDD11_S3_P0")
		)
		(pad "2" smd circle
			(at -0.40005 0 90)
			(size 0 0)
			(layers "B.Cu" "B.Mask" "B.Paste")
			(net "I3C_1_SPD_DDRGL_CPU0_R_SCL")
		)
	)
	(footprint ""
		(layer "B.Cu")
		(at 121.706386 -255.845564)
		(property "Reference" "C2457"
			(at 0 0 0)
			(layer "B.SilkS")
			(hide yes)
			(effects
				(font
					(size 1.27 1.27)
				)
				(justify mirror)
			)
		)
		(property "Value" ""
			(at 0 0 0)
			(layer "B.Fab")
			(effects
				(font
					(size 1.27 1.27)
				)
				(justify mirror)
			)
		)
		(duplicate_pad_numbers_are_jumpers no)
		(fp_line
			(start -0.7874 -0.4064)
			(end -0.7874 0.4064)
			(stroke
				(width 0.1524)
				(type default)
			)
			(layer "B.SilkS")
		)
		(fp_line
			(start -0.7874 0.4064)
			(end 0.7874 0.4064)
			(stroke
				(width 0.1524)
				(type default)
			)
			(layer "B.SilkS")
		)
		(fp_line
			(start 0.7874 -0.4064)
			(end -0.7874 -0.4064)
			(stroke
				(width 0.1524)
				(type default)
			)
			(layer "B.SilkS")
		)
		(fp_line
			(start 0.7874 0.4064)
			(end 0.7874 -0.4064)
			(stroke
				(width 0.1524)
				(type default)
			)
			(layer "B.SilkS")
		)
		(fp_line
			(start -0.67945 -0.3048)
			(end -0.67945 0.3048)
			(stroke
				(width 0.1)
				(type default)
			)
			(layer "B.Fab")
		)
		(fp_line
			(start -0.67945 0.3048)
			(end -0.120396 0.3048)
			(stroke
				(width 0.1)
				(type default)
			)
			(layer "B.Fab")
		)
		(fp_line
			(start -0.12065 -0.3048)
			(end -0.67945 -0.3048)
			(stroke
				(width 0.1)
				(type default)
			)
			(layer "B.Fab")
		)
		(fp_line
			(start -0.12065 -0.2794)
			(end -0.12065 -0.3048)
			(stroke
				(width 0.1)
				(type default)
			)
			(layer "B.Fab")
		)
		(fp_line
			(start -0.120396 0.2794)
			(end 0.12065 0.2794)
			(stroke
				(width 0.1)
				(type default)
			)
			(layer "B.Fab")
		)
		(fp_line
			(start -0.120396 0.3048)
			(end -0.120396 0.2794)
			(stroke
				(width 0.1)
				(type default)
			)
			(layer "B.Fab")
		)
		(fp_line
			(start 0.12065 -0.305054)
			(end 0.12065 -0.2794)
			(stroke
				(width 0.1)
				(type default)
			)
			(layer "B.Fab")
		)
		(fp_line
			(start 0.12065 -0.2794)
			(end -0.12065 -0.2794)
			(stroke
				(width 0.1)
				(type default)
			)
			(layer "B.Fab")
		)
		(fp_line
			(start 0.12065 0.2794)
			(end 0.12065 0.3048)
			(stroke
				(width 0.1)
				(type default)
			)
			(layer "B.Fab")
		)
		(fp_line
			(start 0.12065 0.3048)
			(end 0.67945 0.3048)
			(stroke
				(width 0.1)
				(type default)
			)
			(layer "B.Fab")
		)
		(fp_line
			(start 0.67945 -0.305054)
			(end 0.12065 -0.305054)
			(stroke
				(width 0.1)
				(type default)
			)
			(layer "B.Fab")
		)
		(fp_line
			(start 0.67945 0.3048)
			(end 0.67945 -0.305054)
			(stroke
				(width 0.1)
				(type default)
			)
			(layer "B.Fab")
		)
		(pad "1" smd circle
			(at 0.40005 0 180)
			(size 0 0)
			(layers "B.Cu" "B.Mask" "B.Paste")
			(net "PVDDCR_SOC_P1")
		)
		(pad "2" smd circle
			(at -0.40005 0 180)
			(size 0 0)
			(layers "B.Cu" "B.Mask" "B.Paste")
			(net "GND")
		)
	)
	(footprint ""
		(layer "B.Cu")
		(at 110.856014 -258.795266 180)
		(property "Reference" "C2486"
			(at 0 0 0)
			(layer "B.SilkS")
			(hide yes)
			(effects
				(font
					(size 1.27 1.27)
				)
				(justify mirror)
			)
		)
		(property "Value" ""
			(at 0 0 0)
			(layer "B.Fab")
			(effects
				(font
					(size 1.27 1.27)
				)
				(justify mirror)
			)
		)
		(duplicate_pad_numbers_are_jumpers no)
		(fp_line
			(start 0.7874 0.4064)
			(end 0.7874 -0.4064)
			(stroke
				(width 0.1524)
				(type default)
			)
			(layer "B.SilkS")
		)
		(fp_line
			(start 0.7874 -0.4064)
			(end -0.7874 -0.4064)
			(stroke
				(width 0.1524)
				(type default)
			)
			(layer "B.SilkS")
		)
		(fp_line
			(start -0.7874 0.4064)
			(end 0.7874 0.4064)
			(stroke
				(width 0.1524)
				(type default)
			)
			(layer "B.SilkS")
		)
		(fp_line
			(start -0.7874 -0.4064)
			(end -0.7874 0.4064)
			(stroke
				(width 0.1524)
				(type default)
			)
			(layer "B.SilkS")
		)
		(fp_line
			(start 0.67945 0.3048)
			(end 0.67945 -0.305054)
			(stroke
				(width 0.1)
				(type default)
			)
			(layer "B.Fab")
		)
		(fp_line
			(start 0.67945 -0.305054)
			(end 0.12065 -0.305054)
			(stroke
				(width 0.1)
				(type default)
			)
			(layer "B.Fab")
		)
		(fp_line
			(start 0.12065 0.3048)
			(end 0.67945 0.3048)
			(stroke
				(width 0.1)
				(type default)
			)
			(layer "B.Fab")
		)
		(fp_line
			(start 0.12065 0.2794)
			(end 0.12065 0.3048)
			(stroke
				(width 0.1)
				(type default)
			)
			(layer "B.Fab")
		)
		(fp_line
			(start 0.12065 -0.2794)
			(end -0.12065 -0.2794)
			(stroke
				(width 0.1)
				(type default)
			)
			(layer "B.Fab")
		)
		(fp_line
			(start 0.12065 -0.305054)
			(end 0.12065 -0.2794)
			(stroke
				(width 0.1)
				(type default)
			)
			(layer "B.Fab")
		)
		(fp_line
			(start -0.120396 0.3048)
			(end -0.120396 0.2794)
			(stroke
				(width 0.1)
				(type default)
			)
			(layer "B.Fab")
		)
		(fp_line
			(start -0.120396 0.2794)
			(end 0.12065 0.2794)
			(stroke
				(width 0.1)
				(type default)
			)
			(layer "B.Fab")
		)
		(fp_line
			(start -0.12065 -0.2794)
			(end -0.12065 -0.3048)
			(stroke
				(width 0.1)
				(type default)
			)
			(layer "B.Fab")
		)
		(fp_line
			(start -0.12065 -0.3048)
			(end -0.67945 -0.3048)
			(stroke
				(width 0.1)
				(type default)
			)
			(layer "B.Fab")
		)
		(fp_line
			(start -0.67945 0.3048)
			(end -0.120396 0.3048)
			(stroke
				(width 0.1)
				(type default)
			)
			(layer "B.Fab")
		)
		(fp_line
			(start -0.67945 -0.3048)
			(end -0.67945 0.3048)
			(stroke
				(width 0.1)
				(type default)
			)
			(layer "B.Fab")
		)
		(pad "1" smd circle
			(at 0.40005 0)
			(size 0 0)
			(layers "B.Cu" "B.Mask" "B.Paste")
			(net "PVDD11_S3_P1")
		)
		(pad "2" smd circle
			(at -0.40005 0)
			(size 0 0)
			(layers "B.Cu" "B.Mask" "B.Paste")
			(net "GND")
		)
	)
	(footprint ""
		(layer "B.Cu")
		(at 170.1292 -431.841656)
		(property "Reference" "R4127"
			(at 0 0 0)
			(layer "B.SilkS")
			(hide yes)
			(effects
				(font
					(size 1.27 1.27)
				)
				(justify mirror)
			)
		)
		(property "Value" ""
			(at 0 0 0)
			(layer "B.Fab")
			(effects
				(font
					(size 1.27 1.27)
				)
				(justify mirror)
			)
		)
		(duplicate_pad_numbers_are_jumpers no)
		(fp_line
			(start -0.7874 -0.4064)
			(end -0.7874 0.4064)
			(stroke
				(width 0.1524)
				(type default)
			)
			(layer "B.SilkS")
		)
		(fp_line
			(start -0.7874 0.4064)
			(end 0.7874 0.4064)
			(stroke
				(width 0.1524)
				(type default)
			)
			(layer "B.SilkS")
		)
		(fp_line
			(start 0.7874 -0.4064)
			(end -0.7874 -0.4064)
			(stroke
				(width 0.1524)
				(type default)
			)
			(layer "B.SilkS")
		)
		(fp_line
			(start 0.7874 0.4064)
			(end 0.7874 -0.4064)
			(stroke
				(width 0.1524)
				(type default)
			)
			(layer "B.SilkS")
		)
		(fp_line
			(start -0.67945 -0.3048)
			(end -0.67945 0.3048)
			(stroke
				(width 0.1)
				(type default)
			)
			(layer "B.Fab")
		)
		(fp_line
			(start -0.67945 0.3048)
			(end -0.120396 0.3048)
			(stroke
				(width 0.1)
				(type default)
			)
			(layer "B.Fab")
		)
		(fp_line
			(start -0.12065 -0.3048)
			(end -0.67945 -0.3048)
			(stroke
				(width 0.1)
				(type default)
			)
			(layer "B.Fab")
		)
		(fp_line
			(start -0.12065 -0.2794)
			(end -0.12065 -0.3048)
			(stroke
				(width 0.1)
				(type default)
			)
			(layer "B.Fab")
		)
		(fp_line
			(start -0.120396 0.2794)
			(end 0.12065 0.2794)
			(stroke
				(width 0.1)
				(type default)
			)
			(layer "B.Fab")
		)
		(fp_line
			(start -0.120396 0.3048)
			(end -0.120396 0.2794)
			(stroke
				(width 0.1)
				(type default)
			)
			(layer "B.Fab")
		)
		(fp_line
			(start 0.12065 -0.305054)
			(end 0.12065 -0.2794)
			(stroke
				(width 0.1)
				(type default)
			)
			(layer "B.Fab")
		)
		(fp_line
			(start 0.12065 -0.2794)
			(end -0.12065 -0.2794)
			(stroke
				(width 0.1)
				(type default)
			)
			(layer "B.Fab")
		)
		(fp_line
			(start 0.12065 0.2794)
			(end 0.12065 0.3048)
			(stroke
				(width 0.1)
				(type default)
			)
			(layer "B.Fab")
		)
		(fp_line
			(start 0.12065 0.3048)
			(end 0.67945 0.3048)
			(stroke
				(width 0.1)
				(type default)
			)
			(layer "B.Fab")
		)
		(fp_line
			(start 0.67945 -0.305054)
			(end 0.12065 -0.305054)
			(stroke
				(width 0.1)
				(type default)
			)
			(layer "B.Fab")
		)
		(fp_line
			(start 0.67945 0.3048)
			(end 0.67945 -0.305054)
			(stroke
				(width 0.1)
				(type default)
			)
			(layer "B.Fab")
		)
		(pad "1" smd circle
			(at 0.40005 0 180)
			(size 0 0)
			(layers "B.Cu" "B.Mask" "B.Paste")
			(net "P3V3_AUX")
		)
		(pad "2" smd circle
			(at -0.40005 0 180)
			(size 0 0)
			(layers "B.Cu" "B.Mask" "B.Paste")
			(net "GPU_3V3IO_RSVD1_FFU_N")
		)
	)
	(footprint ""
		(layer "B.Cu")
		(at 378.504958 -208.530952 -90)
		(property "Reference" "R402"
			(at 0 0 90)
			(layer "B.SilkS")
			(hide yes)
			(effects
				(font
					(size 1.27 1.27)
				)
				(justify mirror)
			)
		)
		(property "Value" ""
			(at 0 0 90)
			(layer "B.Fab")
			(effects
				(font
					(size 1.27 1.27)
				)
				(justify mirror)
			)
		)
		(duplicate_pad_numbers_are_jumpers no)
		(fp_line
			(start -0.7874 0.4064)
			(end 0.7874 0.4064)
			(stroke
				(width 0.1524)
				(type default)
			)
			(layer "B.SilkS")
		)
		(fp_line
			(start 0.7874 0.4064)
			(end 0.7874 -0.4064)
			(stroke
				(width 0.1524)
				(type default)
			)
			(layer "B.SilkS")
		)
		(fp_line
			(start -0.7874 -0.4064)
			(end -0.7874 0.4064)
			(stroke
				(width 0.1524)
				(type default)
			)
			(layer "B.SilkS")
		)
		(fp_line
			(start 0.7874 -0.4064)
			(end -0.7874 -0.4064)
			(stroke
				(width 0.1524)
				(type default)
			)
			(layer "B.SilkS")
		)
		(fp_line
			(start -0.67945 0.3048)
			(end -0.120396 0.3048)
			(stroke
				(width 0.1)
				(type default)
			)
			(layer "B.Fab")
		)
		(fp_line
			(start -0.120396 0.3048)
			(end -0.120396 0.2794)
			(stroke
				(width 0.1)
				(type default)
			)
			(layer "B.Fab")
		)
		(fp_line
			(start 0.12065 0.3048)
			(end 0.67945 0.3048)
			(stroke
				(width 0.1)
				(type default)
			)
			(layer "B.Fab")
		)
		(fp_line
			(start 0.67945 0.3048)
			(end 0.67945 -0.305054)
			(stroke
				(width 0.1)
				(type default)
			)
			(layer "B.Fab")
		)
		(fp_line
			(start -0.120396 0.2794)
			(end 0.12065 0.2794)
			(stroke
				(width 0.1)
				(type default)
			)
			(layer "B.Fab")
		)
		(fp_line
			(start 0.12065 0.2794)
			(end 0.12065 0.3048)
			(stroke
				(width 0.1)
				(type default)
			)
			(layer "B.Fab")
		)
		(fp_line
			(start -0.12065 -0.2794)
			(end -0.12065 -0.3048)
			(stroke
				(width 0.1)
				(type default)
			)
			(layer "B.Fab")
		)
		(fp_line
			(start 0.12065 -0.2794)
			(end -0.12065 -0.2794)
			(stroke
				(width 0.1)
				(type default)
			)
			(layer "B.Fab")
		)
		(fp_line
			(start -0.67945 -0.3048)
			(end -0.67945 0.3048)
			(stroke
				(width 0.1)
				(type default)
			)
			(layer "B.Fab")
		)
		(fp_line
			(start -0.12065 -0.3048)
			(end -0.67945 -0.3048)
			(stroke
				(width 0.1)
				(type default)
			)
			(layer "B.Fab")
		)
		(fp_line
			(start 0.12065 -0.305054)
			(end 0.12065 -0.2794)
			(stroke
				(width 0.1)
				(type default)
			)
			(layer "B.Fab")
		)
		(fp_line
			(start 0.67945 -0.305054)
			(end 0.12065 -0.305054)
			(stroke
				(width 0.1)
				(type default)
			)
			(layer "B.Fab")
		)
		(pad "1" smd circle
			(at 0.40005 0 90)
			(size 0 0)
			(layers "B.Cu" "B.Mask" "B.Paste")
			(net "PVDD18_S5_P0")
		)
		(pad "2" smd circle
			(at -0.40005 0 90)
			(size 0 0)
			(layers "B.Cu" "B.Mask" "B.Paste")
			(net "JTAG_CPU0_TMS")
		)
	)
	(footprint ""
		(layer "B.Cu")
		(at 238.379 -231.648 -90)
		(property "Reference" "R366"
			(at 0 0 90)
			(layer "B.SilkS")
			(hide yes)
			(effects
				(font
					(size 1.27 1.27)
				)
				(justify mirror)
			)
		)
		(property "Value" ""
			(at 0 0 90)
			(layer "B.Fab")
			(effects
				(font
					(size 1.27 1.27)
				)
				(justify mirror)
			)
		)
		(duplicate_pad_numbers_are_jumpers no)
		(fp_line
			(start -0.7874 0.4064)
			(end 0.7874 0.4064)
			(stroke
				(width 0.1524)
				(type default)
			)
			(layer "B.SilkS")
		)
		(fp_line
			(start 0.7874 0.4064)
			(end 0.7874 -0.4064)
			(stroke
				(width 0.1524)
				(type default)
			)
			(layer "B.SilkS")
		)
		(fp_line
			(start -0.7874 -0.4064)
			(end -0.7874 0.4064)
			(stroke
				(width 0.1524)
				(type default)
			)
			(layer "B.SilkS")
		)
		(fp_line
			(start 0.7874 -0.4064)
			(end -0.7874 -0.4064)
			(stroke
				(width 0.1524)
				(type default)
			)
			(layer "B.SilkS")
		)
		(fp_line
			(start -0.67945 0.3048)
			(end -0.120396 0.3048)
			(stroke
				(width 0.1)
				(type default)
			)
			(layer "B.Fab")
		)
		(fp_line
			(start -0.120396 0.3048)
			(end -0.120396 0.2794)
			(stroke
				(width 0.1)
				(type default)
			)
			(layer "B.Fab")
		)
		(fp_line
			(start 0.12065 0.3048)
			(end 0.67945 0.3048)
			(stroke
				(width 0.1)
				(type default)
			)
			(layer "B.Fab")
		)
		(fp_line
			(start 0.67945 0.3048)
			(end 0.67945 -0.305054)
			(stroke
				(width 0.1)
				(type default)
			)
			(layer "B.Fab")
		)
		(fp_line
			(start -0.120396 0.2794)
			(end 0.12065 0.2794)
			(stroke
				(width 0.1)
				(type default)
			)
			(layer "B.Fab")
		)
		(fp_line
			(start 0.12065 0.2794)
			(end 0.12065 0.3048)
			(stroke
				(width 0.1)
				(type default)
			)
			(layer "B.Fab")
		)
		(fp_line
			(start -0.12065 -0.2794)
			(end -0.12065 -0.3048)
			(stroke
				(width 0.1)
				(type default)
			)
			(layer "B.Fab")
		)
		(fp_line
			(start 0.12065 -0.2794)
			(end -0.12065 -0.2794)
			(stroke
				(width 0.1)
				(type default)
			)
			(layer "B.Fab")
		)
		(fp_line
			(start -0.67945 -0.3048)
			(end -0.67945 0.3048)
			(stroke
				(width 0.1)
				(type default)
			)
			(layer "B.Fab")
		)
		(fp_line
			(start -0.12065 -0.3048)
			(end -0.67945 -0.3048)
			(stroke
				(width 0.1)
				(type default)
			)
			(layer "B.Fab")
		)
		(fp_line
			(start 0.12065 -0.305054)
			(end 0.12065 -0.2794)
			(stroke
				(width 0.1)
				(type default)
			)
			(layer "B.Fab")
		)
		(fp_line
			(start 0.67945 -0.305054)
			(end 0.12065 -0.305054)
			(stroke
				(width 0.1)
				(type default)
			)
			(layer "B.Fab")
		)
		(pad "1" smd circle
			(at 0.40005 0 90)
			(size 0 0)
			(layers "B.Cu" "B.Mask" "B.Paste")
			(net "PVDD18_S5_P1")
		)
		(pad "2" smd circle
			(at -0.40005 0 90)
			(size 0 0)
			(layers "B.Cu" "B.Mask" "B.Paste")
			(net "SMB_CPU1_SEC_SCL")
		)
	)
	(footprint ""
		(layer "B.Cu")
		(at 128.171194 -171.930568 90)
		(property "Reference" "PC340"
			(at 5.751576 1.613154 270)
			(unlocked yes)
			(layer "B.SilkS")
			(effects
				(font
					(size 0.7874 0.5842)
					(thickness 0.1524)
				)
				(justify left mirror)
			)
		)
		(property "Value" ""
			(at 0 0 90)
			(layer "B.Fab")
			(effects
				(font
					(size 1.27 1.27)
				)
				(justify mirror)
			)
		)
		(duplicate_pad_numbers_are_jumpers no)
		(fp_line
			(start 4.533392 -2.249932)
			(end -4.533392 -2.249932)
			(stroke
				(width 0.1524)
				(type default)
			)
			(layer "B.SilkS")
		)
		(fp_line
			(start -4.533392 -2.249932)
			(end -4.533392 2.249932)
			(stroke
				(width 0.1524)
				(type default)
			)
			(layer "B.SilkS")
		)
		(fp_line
			(start 4.533392 2.249932)
			(end 4.533392 -2.249932)
			(stroke
				(width 0.1524)
				(type default)
			)
			(layer "B.SilkS")
		)
		(fp_line
			(start -4.533392 2.249932)
			(end 4.533392 2.249932)
			(stroke
				(width 0.1524)
				(type default)
			)
			(layer "B.SilkS")
		)
		(fp_rect
			(start 4.533392 -2.326132)
			(end 5.39242 2.326132)
			(stroke
				(width 0)
				(type default)
			)
			(fill yes)
			(layer "B.SilkS")
		)
		(fp_line
			(start 3.750056 -2.249932)
			(end -3.750056 -2.249932)
			(stroke
				(width 0.1)
				(type default)
			)
			(layer "B.Fab")
		)
		(fp_line
			(start -3.750056 -2.249932)
			(end -3.750056 2.249932)
			(stroke
				(width 0.1)
				(type default)
			)
			(layer "B.Fab")
		)
		(fp_line
			(start 3.750056 2.249932)
			(end 3.750056 -2.249932)
			(stroke
				(width 0.1)
				(type default)
			)
			(layer "B.Fab")
		)
		(fp_line
			(start -3.750056 2.249932)
			(end 3.750056 2.249932)
			(stroke
				(width 0.1)
				(type default)
			)
			(layer "B.Fab")
		)
		(fp_text user "-"
			(at -4.8514 -0.14605 90)
			(unlocked yes)
			(layer "B.SilkS")
			(effects
				(font
					(size 1.905 1.4224)
					(thickness 0.1524)
				)
				(justify left mirror)
			)
		)
		(fp_text user "+"
			(at 6.322314 0.786384 0)
			(unlocked yes)
			(layer "B.SilkS")
			(effects
				(font
					(size 1.905 1.4224)
					(thickness 0.1524)
				)
				(justify left mirror)
			)
		)
		(fp_text user "-"
			(at -4.8514 -0.14605 90)
			(unlocked yes)
			(layer "B.Fab")
			(effects
				(font
					(size 1.905 1.4224)
					(thickness 0.1524)
				)
				(justify left mirror)
			)
		)
		(fp_text user "+"
			(at 6.322314 0.786384 0)
			(unlocked yes)
			(layer "B.Fab")
			(effects
				(font
					(size 1.905 1.4224)
					(thickness 0.1524)
				)
				(justify left mirror)
			)
		)
		(pad "1" smd rect
			(at 3.199892 0 270)
			(size 2.413 2.8194)
			(layers "B.Cu" "B.Mask" "B.Paste")
			(net "PVDDCR_SOC_P1")
		)
		(pad "2" smd rect
			(at -3.199892 0 270)
			(size 2.413 2.8194)
			(layers "B.Cu" "B.Mask" "B.Paste")
			(net "GND")
		)
	)
	(footprint ""
		(layer "B.Cu")
		(at 91.919044 -390.909302 90)
		(property "Reference" "C342"
			(at 0 0 90)
			(layer "B.SilkS")
			(hide yes)
			(effects
				(font
					(size 1.27 1.27)
				)
				(justify mirror)
			)
		)
		(property "Value" ""
			(at 0 0 90)
			(layer "B.Fab")
			(effects
				(font
					(size 1.27 1.27)
				)
				(justify mirror)
			)
		)
		(duplicate_pad_numbers_are_jumpers no)
		(fp_line
			(start 0.299974 -0.150114)
			(end -0.299974 -0.150114)
			(stroke
				(width 0.1)
				(type default)
			)
			(layer "B.Fab")
		)
		(fp_line
			(start -0.299974 -0.150114)
			(end -0.299974 0.150114)
			(stroke
				(width 0.1)
				(type default)
			)
			(layer "B.Fab")
		)
		(fp_line
			(start 0.299974 0.150114)
			(end 0.299974 -0.150114)
			(stroke
				(width 0.1)
				(type default)
			)
			(layer "B.Fab")
		)
		(fp_line
			(start -0.299974 0.150114)
			(end 0.299974 0.150114)
			(stroke
				(width 0.1)
				(type default)
			)
			(layer "B.Fab")
		)
		(pad "1" smd rect
			(at 0.2667 0 270)
			(size 0.3048 0.381)
			(layers "B.Cu" "B.Mask" "B.Paste")
			(net "P0V9_CPU1_RT_2D")
		)
		(pad "2" smd rect
			(at -0.2667 0 270)
			(size 0.3048 0.381)
			(layers "B.Cu" "B.Mask" "B.Paste")
			(net "GND")
		)
	)
	(footprint ""
		(layer "B.Cu")
		(at 145.217134 -322.101972)
		(property "Reference" "R738"
			(at 0 0 0)
			(layer "B.SilkS")
			(hide yes)
			(effects
				(font
					(size 1.27 1.27)
				)
				(justify mirror)
			)
		)
		(property "Value" ""
			(at 0 0 0)
			(layer "B.Fab")
			(effects
				(font
					(size 1.27 1.27)
				)
				(justify mirror)
			)
		)
		(duplicate_pad_numbers_are_jumpers no)
		(fp_line
			(start -0.7874 -0.4064)
			(end -0.7874 0.4064)
			(stroke
				(width 0.1524)
				(type default)
			)
			(layer "B.SilkS")
		)
		(fp_line
			(start -0.7874 0.4064)
			(end 0.7874 0.4064)
			(stroke
				(width 0.1524)
				(type default)
			)
			(layer "B.SilkS")
		)
		(fp_line
			(start 0.7874 -0.4064)
			(end -0.7874 -0.4064)
			(stroke
				(width 0.1524)
				(type default)
			)
			(layer "B.SilkS")
		)
		(fp_line
			(start 0.7874 0.4064)
			(end 0.7874 -0.4064)
			(stroke
				(width 0.1524)
				(type default)
			)
			(layer "B.SilkS")
		)
		(fp_line
			(start -0.67945 -0.3048)
			(end -0.67945 0.3048)
			(stroke
				(width 0.1)
				(type default)
			)
			(layer "B.Fab")
		)
		(fp_line
			(start -0.67945 0.3048)
			(end -0.120396 0.3048)
			(stroke
				(width 0.1)
				(type default)
			)
			(layer "B.Fab")
		)
		(fp_line
			(start -0.12065 -0.3048)
			(end -0.67945 -0.3048)
			(stroke
				(width 0.1)
				(type default)
			)
			(layer "B.Fab")
		)
		(fp_line
			(start -0.12065 -0.2794)
			(end -0.12065 -0.3048)
			(stroke
				(width 0.1)
				(type default)
			)
			(layer "B.Fab")
		)
		(fp_line
			(start -0.120396 0.2794)
			(end 0.12065 0.2794)
			(stroke
				(width 0.1)
				(type default)
			)
			(layer "B.Fab")
		)
		(fp_line
			(start -0.120396 0.3048)
			(end -0.120396 0.2794)
			(stroke
				(width 0.1)
				(type default)
			)
			(layer "B.Fab")
		)
		(fp_line
			(start 0.12065 -0.305054)
			(end 0.12065 -0.2794)
			(stroke
				(width 0.1)
				(type default)
			)
			(layer "B.Fab")
		)
		(fp_line
			(start 0.12065 -0.2794)
			(end -0.12065 -0.2794)
			(stroke
				(width 0.1)
				(type default)
			)
			(layer "B.Fab")
		)
		(fp_line
			(start 0.12065 0.2794)
			(end 0.12065 0.3048)
			(stroke
				(width 0.1)
				(type default)
			)
			(layer "B.Fab")
		)
		(fp_line
			(start 0.12065 0.3048)
			(end 0.67945 0.3048)
			(stroke
				(width 0.1)
				(type default)
			)
			(layer "B.Fab")
		)
		(fp_line
			(start 0.67945 -0.305054)
			(end 0.12065 -0.305054)
			(stroke
				(width 0.1)
				(type default)
			)
			(layer "B.Fab")
		)
		(fp_line
			(start 0.67945 0.3048)
			(end 0.67945 -0.305054)
			(stroke
				(width 0.1)
				(type default)
			)
			(layer "B.Fab")
		)
		(pad "1" smd circle
			(at 0.40005 0 180)
			(size 0 0)
			(layers "B.Cu" "B.Mask" "B.Paste")
			(net "SPI_CPU1_CLK")
		)
		(pad "2" smd circle
			(at -0.40005 0 180)
			(size 0 0)
			(layers "B.Cu" "B.Mask" "B.Paste")
			(net "SPI_CPU1_R_CLK")
		)
	)
	(footprint ""
		(layer "B.Cu")
		(at 233.68 -226.822)
		(property "Reference" "R151"
			(at 0 0 0)
			(layer "B.SilkS")
			(hide yes)
			(effects
				(font
					(size 1.27 1.27)
				)
				(justify mirror)
			)
		)
		(property "Value" ""
			(at 0 0 0)
			(layer "B.Fab")
			(effects
				(font
					(size 1.27 1.27)
				)
				(justify mirror)
			)
		)
		(duplicate_pad_numbers_are_jumpers no)
		(fp_line
			(start -0.7874 -0.4064)
			(end -0.7874 0.4064)
			(stroke
				(width 0.1524)
				(type default)
			)
			(layer "B.SilkS")
		)
		(fp_line
			(start -0.7874 0.4064)
			(end 0.7874 0.4064)
			(stroke
				(width 0.1524)
				(type default)
			)
			(layer "B.SilkS")
		)
		(fp_line
			(start 0.7874 -0.4064)
			(end -0.7874 -0.4064)
			(stroke
				(width 0.1524)
				(type default)
			)
			(layer "B.SilkS")
		)
		(fp_line
			(start 0.7874 0.4064)
			(end 0.7874 -0.4064)
			(stroke
				(width 0.1524)
				(type default)
			)
			(layer "B.SilkS")
		)
		(fp_line
			(start -0.67945 -0.3048)
			(end -0.67945 0.3048)
			(stroke
				(width 0.1)
				(type default)
			)
			(layer "B.Fab")
		)
		(fp_line
			(start -0.67945 0.3048)
			(end -0.120396 0.3048)
			(stroke
				(width 0.1)
				(type default)
			)
			(layer "B.Fab")
		)
		(fp_line
			(start -0.12065 -0.3048)
			(end -0.67945 -0.3048)
			(stroke
				(width 0.1)
				(type default)
			)
			(layer "B.Fab")
		)
		(fp_line
			(start -0.12065 -0.2794)
			(end -0.12065 -0.3048)
			(stroke
				(width 0.1)
				(type default)
			)
			(layer "B.Fab")
		)
		(fp_line
			(start -0.120396 0.2794)
			(end 0.12065 0.2794)
			(stroke
				(width 0.1)
				(type default)
			)
			(layer "B.Fab")
		)
		(fp_line
			(start -0.120396 0.3048)
			(end -0.120396 0.2794)
			(stroke
				(width 0.1)
				(type default)
			)
			(layer "B.Fab")
		)
		(fp_line
			(start 0.12065 -0.305054)
			(end 0.12065 -0.2794)
			(stroke
				(width 0.1)
				(type default)
			)
			(layer "B.Fab")
		)
		(fp_line
			(start 0.12065 -0.2794)
			(end -0.12065 -0.2794)
			(stroke
				(width 0.1)
				(type default)
			)
			(layer "B.Fab")
		)
		(fp_line
			(start 0.12065 0.2794)
			(end 0.12065 0.3048)
			(stroke
				(width 0.1)
				(type default)
			)
			(layer "B.Fab")
		)
		(fp_line
			(start 0.12065 0.3048)
			(end 0.67945 0.3048)
			(stroke
				(width 0.1)
				(type default)
			)
			(layer "B.Fab")
		)
		(fp_line
			(start 0.67945 -0.305054)
			(end 0.12065 -0.305054)
			(stroke
				(width 0.1)
				(type default)
			)
			(layer "B.Fab")
		)
		(fp_line
			(start 0.67945 0.3048)
			(end 0.67945 -0.305054)
			(stroke
				(width 0.1)
				(type default)
			)
			(layer "B.Fab")
		)
		(pad "1" smd rect
			(at 0.40005 0)
			(size 0.4572 0.508)
			(layers "B.Cu" "B.Mask" "B.Paste")
			(net "SMB_CPU0_CPU1_APML_SCL")
		)
		(pad "2" smd rect
			(at -0.40005 0)
			(size 0.4572 0.508)
			(layers "B.Cu" "B.Mask" "B.Paste")
			(net "SMB_CPU0_CPU1_APML_BUF2_SCL")
		)
	)
	(footprint ""
		(layer "B.Cu")
		(at 370.905278 -144.520158)
		(property "Reference" "C299"
			(at 0 0 0)
			(layer "B.SilkS")
			(hide yes)
			(effects
				(font
					(size 1.27 1.27)
				)
				(justify mirror)
			)
		)
		(property "Value" ""
			(at 0 0 0)
			(layer "B.Fab")
			(effects
				(font
					(size 1.27 1.27)
				)
				(justify mirror)
			)
		)
		(duplicate_pad_numbers_are_jumpers no)
		(fp_line
			(start -0.7874 -0.4064)
			(end -0.7874 0.4064)
			(stroke
				(width 0.1524)
				(type default)
			)
			(layer "B.SilkS")
		)
		(fp_line
			(start -0.7874 0.4064)
			(end 0.7874 0.4064)
			(stroke
				(width 0.1524)
				(type default)
			)
			(layer "B.SilkS")
		)
		(fp_line
			(start 0.7874 -0.4064)
			(end -0.7874 -0.4064)
			(stroke
				(width 0.1524)
				(type default)
			)
			(layer "B.SilkS")
		)
		(fp_line
			(start 0.7874 0.4064)
			(end 0.7874 -0.4064)
			(stroke
				(width 0.1524)
				(type default)
			)
			(layer "B.SilkS")
		)
		(fp_line
			(start -0.67945 -0.3048)
			(end -0.67945 0.3048)
			(stroke
				(width 0.1)
				(type default)
			)
			(layer "B.Fab")
		)
		(fp_line
			(start -0.67945 0.3048)
			(end -0.120396 0.3048)
			(stroke
				(width 0.1)
				(type default)
			)
			(layer "B.Fab")
		)
		(fp_line
			(start -0.12065 -0.3048)
			(end -0.67945 -0.3048)
			(stroke
				(width 0.1)
				(type default)
			)
			(layer "B.Fab")
		)
		(fp_line
			(start -0.12065 -0.2794)
			(end -0.12065 -0.3048)
			(stroke
				(width 0.1)
				(type default)
			)
			(layer "B.Fab")
		)
		(fp_line
			(start -0.120396 0.2794)
			(end 0.12065 0.2794)
			(stroke
				(width 0.1)
				(type default)
			)
			(layer "B.Fab")
		)
		(fp_line
			(start -0.120396 0.3048)
			(end -0.120396 0.2794)
			(stroke
				(width 0.1)
				(type default)
			)
			(layer "B.Fab")
		)
		(fp_line
			(start 0.12065 -0.305054)
			(end 0.12065 -0.2794)
			(stroke
				(width 0.1)
				(type default)
			)
			(layer "B.Fab")
		)
		(fp_line
			(start 0.12065 -0.2794)
			(end -0.12065 -0.2794)
			(stroke
				(width 0.1)
				(type default)
			)
			(layer "B.Fab")
		)
		(fp_line
			(start 0.12065 0.2794)
			(end 0.12065 0.3048)
			(stroke
				(width 0.1)
				(type default)
			)
			(layer "B.Fab")
		)
		(fp_line
			(start 0.12065 0.3048)
			(end 0.67945 0.3048)
			(stroke
				(width 0.1)
				(type default)
			)
			(layer "B.Fab")
		)
		(fp_line
			(start 0.67945 -0.305054)
			(end 0.12065 -0.305054)
			(stroke
				(width 0.1)
				(type default)
			)
			(layer "B.Fab")
		)
		(fp_line
			(start 0.67945 0.3048)
			(end 0.67945 -0.305054)
			(stroke
				(width 0.1)
				(type default)
			)
			(layer "B.Fab")
		)
		(pad "1" smd circle
			(at 0.40005 0 180)
			(size 0 0)
			(layers "B.Cu" "B.Mask" "B.Paste")
			(net "SVID_PVDDCR_CPU0_P0_SVD_R")
		)
		(pad "2" smd circle
			(at -0.40005 0 180)
			(size 0 0)
			(layers "B.Cu" "B.Mask" "B.Paste")
			(net "GND")
		)
	)
	(footprint ""
		(layer "B.Cu")
		(at 404.574502 -152.29078 -90)
		(property "Reference" "R4639"
			(at 0 0 90)
			(layer "B.SilkS")
			(hide yes)
			(effects
				(font
					(size 1.27 1.27)
				)
				(justify mirror)
			)
		)
		(property "Value" ""
			(at 0 0 90)
			(layer "B.Fab")
			(effects
				(font
					(size 1.27 1.27)
				)
				(justify mirror)
			)
		)
		(duplicate_pad_numbers_are_jumpers no)
		(fp_line
			(start -2.234946 0.9271)
			(end 2.234946 0.9271)
			(stroke
				(width 0.1524)
				(type default)
			)
			(layer "B.SilkS")
		)
		(fp_line
			(start 2.234946 0.9271)
			(end 2.234946 -0.9271)
			(stroke
				(width 0.1524)
				(type default)
			)
			(layer "B.SilkS")
		)
		(fp_line
			(start -2.234946 -0.9271)
			(end -2.234946 0.9271)
			(stroke
				(width 0.1524)
				(type default)
			)
			(layer "B.SilkS")
		)
		(fp_line
			(start 2.234946 -0.9271)
			(end -2.234946 -0.9271)
			(stroke
				(width 0.1524)
				(type default)
			)
			(layer "B.SilkS")
		)
		(fp_line
			(start -1.575054 0.824992)
			(end -1.575054 -0.824992)
			(stroke
				(width 0.1)
				(type default)
			)
			(layer "B.Fab")
		)
		(fp_line
			(start 1.575054 0.824992)
			(end -1.575054 0.824992)
			(stroke
				(width 0.1)
				(type default)
			)
			(layer "B.Fab")
		)
		(fp_line
			(start -1.575054 -0.824992)
			(end 1.575054 -0.824992)
			(stroke
				(width 0.1)
				(type default)
			)
			(layer "B.Fab")
		)
		(fp_line
			(start 1.575054 -0.824992)
			(end 1.575054 0.824992)
			(stroke
				(width 0.1)
				(type default)
			)
			(layer "B.Fab")
		)
		(pad "1" smd rect
			(at 1.599946 0 90)
			(size 1.016 1.6002)
			(layers "B.Cu" "B.Mask" "B.Paste")
			(net "P5V")
		)
		(pad "2" smd rect
			(at -1.599946 0 90)
			(size 1.016 1.6002)
			(layers "B.Cu" "B.Mask" "B.Paste")
			(net "VR_P5V_EN_D")
		)
	)
	(footprint ""
		(layer "B.Cu")
		(at 347.389958 -268.41831 180)
		(property "Reference" "C2217"
			(at 0 0 0)
			(layer "B.SilkS")
			(hide yes)
			(effects
				(font
					(size 1.27 1.27)
				)
				(justify mirror)
			)
		)
		(property "Value" ""
			(at 0 0 0)
			(layer "B.Fab")
			(effects
				(font
					(size 1.27 1.27)
				)
				(justify mirror)
			)
		)
		(duplicate_pad_numbers_are_jumpers no)
		(fp_line
			(start 0.7874 0.4064)
			(end 0.7874 -0.4064)
			(stroke
				(width 0.1524)
				(type default)
			)
			(layer "B.SilkS")
		)
		(fp_line
			(start 0.7874 -0.4064)
			(end -0.7874 -0.4064)
			(stroke
				(width 0.1524)
				(type default)
			)
			(layer "B.SilkS")
		)
		(fp_line
			(start -0.7874 0.4064)
			(end 0.7874 0.4064)
			(stroke
				(width 0.1524)
				(type default)
			)
			(layer "B.SilkS")
		)
		(fp_line
			(start -0.7874 -0.4064)
			(end -0.7874 0.4064)
			(stroke
				(width 0.1524)
				(type default)
			)
			(layer "B.SilkS")
		)
		(fp_line
			(start 0.67945 0.3048)
			(end 0.67945 -0.305054)
			(stroke
				(width 0.1)
				(type default)
			)
			(layer "B.Fab")
		)
		(fp_line
			(start 0.67945 -0.305054)
			(end 0.12065 -0.305054)
			(stroke
				(width 0.1)
				(type default)
			)
			(layer "B.Fab")
		)
		(fp_line
			(start 0.12065 0.3048)
			(end 0.67945 0.3048)
			(stroke
				(width 0.1)
				(type default)
			)
			(layer "B.Fab")
		)
		(fp_line
			(start 0.12065 0.2794)
			(end 0.12065 0.3048)
			(stroke
				(width 0.1)
				(type default)
			)
			(layer "B.Fab")
		)
		(fp_line
			(start 0.12065 -0.2794)
			(end -0.12065 -0.2794)
			(stroke
				(width 0.1)
				(type default)
			)
			(layer "B.Fab")
		)
		(fp_line
			(start 0.12065 -0.305054)
			(end 0.12065 -0.2794)
			(stroke
				(width 0.1)
				(type default)
			)
			(layer "B.Fab")
		)
		(fp_line
			(start -0.120396 0.3048)
			(end -0.120396 0.2794)
			(stroke
				(width 0.1)
				(type default)
			)
			(layer "B.Fab")
		)
		(fp_line
			(start -0.120396 0.2794)
			(end 0.12065 0.2794)
			(stroke
				(width 0.1)
				(type default)
			)
			(layer "B.Fab")
		)
		(fp_line
			(start -0.12065 -0.2794)
			(end -0.12065 -0.3048)
			(stroke
				(width 0.1)
				(type default)
			)
			(layer "B.Fab")
		)
		(fp_line
			(start -0.12065 -0.3048)
			(end -0.67945 -0.3048)
			(stroke
				(width 0.1)
				(type default)
			)
			(layer "B.Fab")
		)
		(fp_line
			(start -0.67945 0.3048)
			(end -0.120396 0.3048)
			(stroke
				(width 0.1)
				(type default)
			)
			(layer "B.Fab")
		)
		(fp_line
			(start -0.67945 -0.3048)
			(end -0.67945 0.3048)
			(stroke
				(width 0.1)
				(type default)
			)
			(layer "B.Fab")
		)
		(pad "1" smd circle
			(at 0.40005 0)
			(size 0 0)
			(layers "B.Cu" "B.Mask" "B.Paste")
			(net "PVDDCR_CPU1_P0")
		)
		(pad "2" smd circle
			(at -0.40005 0)
			(size 0 0)
			(layers "B.Cu" "B.Mask" "B.Paste")
			(net "GND")
		)
	)
	(footprint ""
		(layer "B.Cu")
		(at 117.769386 -266.005564)
		(property "Reference" "C2511"
			(at 0 0 0)
			(layer "B.SilkS")
			(hide yes)
			(effects
				(font
					(size 1.27 1.27)
				)
				(justify mirror)
			)
		)
		(property "Value" ""
			(at 0 0 0)
			(layer "B.Fab")
			(effects
				(font
					(size 1.27 1.27)
				)
				(justify mirror)
			)
		)
		(duplicate_pad_numbers_are_jumpers no)
		(fp_line
			(start -0.7874 -0.4064)
			(end -0.7874 0.4064)
			(stroke
				(width 0.1524)
				(type default)
			)
			(layer "B.SilkS")
		)
		(fp_line
			(start -0.7874 0.4064)
			(end 0.7874 0.4064)
			(stroke
				(width 0.1524)
				(type default)
			)
			(layer "B.SilkS")
		)
		(fp_line
			(start 0.7874 -0.4064)
			(end -0.7874 -0.4064)
			(stroke
				(width 0.1524)
				(type default)
			)
			(layer "B.SilkS")
		)
		(fp_line
			(start 0.7874 0.4064)
			(end 0.7874 -0.4064)
			(stroke
				(width 0.1524)
				(type default)
			)
			(layer "B.SilkS")
		)
		(fp_line
			(start -0.67945 -0.3048)
			(end -0.67945 0.3048)
			(stroke
				(width 0.1)
				(type default)
			)
			(layer "B.Fab")
		)
		(fp_line
			(start -0.67945 0.3048)
			(end -0.120396 0.3048)
			(stroke
				(width 0.1)
				(type default)
			)
			(layer "B.Fab")
		)
		(fp_line
			(start -0.12065 -0.3048)
			(end -0.67945 -0.3048)
			(stroke
				(width 0.1)
				(type default)
			)
			(layer "B.Fab")
		)
		(fp_line
			(start -0.12065 -0.2794)
			(end -0.12065 -0.3048)
			(stroke
				(width 0.1)
				(type default)
			)
			(layer "B.Fab")
		)
		(fp_line
			(start -0.120396 0.2794)
			(end 0.12065 0.2794)
			(stroke
				(width 0.1)
				(type default)
			)
			(layer "B.Fab")
		)
		(fp_line
			(start -0.120396 0.3048)
			(end -0.120396 0.2794)
			(stroke
				(width 0.1)
				(type default)
			)
			(layer "B.Fab")
		)
		(fp_line
			(start 0.12065 -0.305054)
			(end 0.12065 -0.2794)
			(stroke
				(width 0.1)
				(type default)
			)
			(layer "B.Fab")
		)
		(fp_line
			(start 0.12065 -0.2794)
			(end -0.12065 -0.2794)
			(stroke
				(width 0.1)
				(type default)
			)
			(layer "B.Fab")
		)
		(fp_line
			(start 0.12065 0.2794)
			(end 0.12065 0.3048)
			(stroke
				(width 0.1)
				(type default)
			)
			(layer "B.Fab")
		)
		(fp_line
			(start 0.12065 0.3048)
			(end 0.67945 0.3048)
			(stroke
				(width 0.1)
				(type default)
			)
			(layer "B.Fab")
		)
		(fp_line
			(start 0.67945 -0.305054)
			(end 0.12065 -0.305054)
			(stroke
				(width 0.1)
				(type default)
			)
			(layer "B.Fab")
		)
		(fp_line
			(start 0.67945 0.3048)
			(end 0.67945 -0.305054)
			(stroke
				(width 0.1)
				(type default)
			)
			(layer "B.Fab")
		)
		(pad "1" smd circle
			(at 0.40005 0 180)
			(size 0 0)
			(layers "B.Cu" "B.Mask" "B.Paste")
			(net "PVDD11_S3_P1")
		)
		(pad "2" smd circle
			(at -0.40005 0 180)
			(size 0 0)
			(layers "B.Cu" "B.Mask" "B.Paste")
			(net "GND")
		)
	)
	(footprint ""
		(layer "B.Cu")
		(at 381.192278 -137.535158 90)
		(property "Reference" "PC13"
			(at 0 0 90)
			(layer "B.SilkS")
			(hide yes)
			(effects
				(font
					(size 1.27 1.27)
				)
				(justify mirror)
			)
		)
		(property "Value" ""
			(at 0 0 90)
			(layer "B.Fab")
			(effects
				(font
					(size 1.27 1.27)
				)
				(justify mirror)
			)
		)
		(duplicate_pad_numbers_are_jumpers no)
		(fp_line
			(start 0.539242 -0.4064)
			(end -0.7874 -0.4064)
			(stroke
				(width 0.1524)
				(type default)
			)
			(layer "B.SilkS")
		)
		(fp_line
			(start -0.7874 -0.4064)
			(end -0.7874 0.4064)
			(stroke
				(width 0.1524)
				(type default)
			)
			(layer "B.SilkS")
		)
		(fp_line
			(start 0.7874 0.4064)
			(end 0.7874 -0.039878)
			(stroke
				(width 0.1524)
				(type default)
			)
			(layer "B.SilkS")
		)
		(fp_line
			(start -0.7874 0.4064)
			(end 0.7874 0.4064)
			(stroke
				(width 0.1524)
				(type default)
			)
			(layer "B.SilkS")
		)
		(fp_line
			(start 0.67945 -0.305054)
			(end 0.12065 -0.305054)
			(stroke
				(width 0.1)
				(type default)
			)
			(layer "B.Fab")
		)
		(fp_line
			(start 0.12065 -0.305054)
			(end 0.12065 -0.2794)
			(stroke
				(width 0.1)
				(type default)
			)
			(layer "B.Fab")
		)
		(fp_line
			(start -0.12065 -0.3048)
			(end -0.67945 -0.3048)
			(stroke
				(width 0.1)
				(type default)
			)
			(layer "B.Fab")
		)
		(fp_line
			(start -0.67945 -0.3048)
			(end -0.67945 0.3048)
			(stroke
				(width 0.1)
				(type default)
			)
			(layer "B.Fab")
		)
		(fp_line
			(start 0.12065 -0.2794)
			(end -0.12065 -0.2794)
			(stroke
				(width 0.1)
				(type default)
			)
			(layer "B.Fab")
		)
		(fp_line
			(start -0.12065 -0.2794)
			(end -0.12065 -0.3048)
			(stroke
				(width 0.1)
				(type default)
			)
			(layer "B.Fab")
		)
		(fp_line
			(start 0.12065 0.2794)
			(end 0.12065 0.3048)
			(stroke
				(width 0.1)
				(type default)
			)
			(layer "B.Fab")
		)
		(fp_line
			(start -0.120396 0.2794)
			(end 0.12065 0.2794)
			(stroke
				(width 0.1)
				(type default)
			)
			(layer "B.Fab")
		)
		(fp_line
			(start 0.67945 0.3048)
			(end 0.67945 -0.305054)
			(stroke
				(width 0.1)
				(type default)
			)
			(layer "B.Fab")
		)
		(fp_line
			(start 0.12065 0.3048)
			(end 0.67945 0.3048)
			(stroke
				(width 0.1)
				(type default)
			)
			(layer "B.Fab")
		)
		(fp_line
			(start -0.120396 0.3048)
			(end -0.120396 0.2794)
			(stroke
				(width 0.1)
				(type default)
			)
			(layer "B.Fab")
		)
		(fp_line
			(start -0.67945 0.3048)
			(end -0.120396 0.3048)
			(stroke
				(width 0.1)
				(type default)
			)
			(layer "B.Fab")
		)
		(pad "1" smd circle
			(at 0.40005 0 270)
			(size 0 0)
			(layers "B.Cu" "B.Mask" "B.Paste")
			(net "PVDDCR_CPU0_P0_VCCS")
		)
		(pad "2" smd circle
			(at -0.40005 0 270)
			(size 0 0)
			(layers "B.Cu" "B.Mask" "B.Paste")
			(net "GND")
		)
	)
	(footprint ""
		(layer "B.Cu")
		(at 342.059006 -416.899344 90)
		(property "Reference" "C6558"
			(at 0 0 90)
			(layer "B.SilkS")
			(hide yes)
			(effects
				(font
					(size 1.27 1.27)
				)
				(justify mirror)
			)
		)
		(property "Value" ""
			(at 0 0 90)
			(layer "B.Fab")
			(effects
				(font
					(size 1.27 1.27)
				)
				(justify mirror)
			)
		)
		(duplicate_pad_numbers_are_jumpers no)
		(fp_line
			(start 0.299974 -0.150114)
			(end -0.299974 -0.150114)
			(stroke
				(width 0.1)
				(type default)
			)
			(layer "B.Fab")
		)
		(fp_line
			(start -0.299974 -0.150114)
			(end -0.299974 0.150114)
			(stroke
				(width 0.1)
				(type default)
			)
			(layer "B.Fab")
		)
		(fp_line
			(start 0.299974 0.150114)
			(end 0.299974 -0.150114)
			(stroke
				(width 0.1)
				(type default)
			)
			(layer "B.Fab")
		)
		(fp_line
			(start -0.299974 0.150114)
			(end 0.299974 0.150114)
			(stroke
				(width 0.1)
				(type default)
			)
			(layer "B.Fab")
		)
		(pad "1" smd rect
			(at 0.2667 0 270)
			(size 0.3048 0.381)
			(layers "B.Cu" "B.Mask" "B.Paste")
			(net "P5E_CPU0_P1_TX_BUF_C_DN<12>")
		)
		(pad "2" smd rect
			(at -0.2667 0 270)
			(size 0.3048 0.381)
			(layers "B.Cu" "B.Mask" "B.Paste")
			(net "P5E_CPU0_P1_TX_BUF_DN<12>")
		)
	)
	(footprint ""
		(layer "B.Cu")
		(at 171.194984 -106.136186)
		(property "Reference" "R165"
			(at 0 0 0)
			(layer "B.SilkS")
			(hide yes)
			(effects
				(font
					(size 1.27 1.27)
				)
				(justify mirror)
			)
		)
		(property "Value" ""
			(at 0 0 0)
			(layer "B.Fab")
			(effects
				(font
					(size 1.27 1.27)
				)
				(justify mirror)
			)
		)
		(duplicate_pad_numbers_are_jumpers no)
		(fp_line
			(start -0.7874 -0.4064)
			(end -0.7874 0.4064)
			(stroke
				(width 0.1524)
				(type default)
			)
			(layer "B.SilkS")
		)
		(fp_line
			(start -0.7874 0.4064)
			(end 0.7874 0.4064)
			(stroke
				(width 0.1524)
				(type default)
			)
			(layer "B.SilkS")
		)
		(fp_line
			(start 0.7874 -0.4064)
			(end -0.7874 -0.4064)
			(stroke
				(width 0.1524)
				(type default)
			)
			(layer "B.SilkS")
		)
		(fp_line
			(start 0.7874 0.4064)
			(end 0.7874 -0.4064)
			(stroke
				(width 0.1524)
				(type default)
			)
			(layer "B.SilkS")
		)
		(fp_line
			(start -0.67945 -0.3048)
			(end -0.67945 0.3048)
			(stroke
				(width 0.1)
				(type default)
			)
			(layer "B.Fab")
		)
		(fp_line
			(start -0.67945 0.3048)
			(end -0.120396 0.3048)
			(stroke
				(width 0.1)
				(type default)
			)
			(layer "B.Fab")
		)
		(fp_line
			(start -0.12065 -0.3048)
			(end -0.67945 -0.3048)
			(stroke
				(width 0.1)
				(type default)
			)
			(layer "B.Fab")
		)
		(fp_line
			(start -0.12065 -0.2794)
			(end -0.12065 -0.3048)
			(stroke
				(width 0.1)
				(type default)
			)
			(layer "B.Fab")
		)
		(fp_line
			(start -0.120396 0.2794)
			(end 0.12065 0.2794)
			(stroke
				(width 0.1)
				(type default)
			)
			(layer "B.Fab")
		)
		(fp_line
			(start -0.120396 0.3048)
			(end -0.120396 0.2794)
			(stroke
				(width 0.1)
				(type default)
			)
			(layer "B.Fab")
		)
		(fp_line
			(start 0.12065 -0.305054)
			(end 0.12065 -0.2794)
			(stroke
				(width 0.1)
				(type default)
			)
			(layer "B.Fab")
		)
		(fp_line
			(start 0.12065 -0.2794)
			(end -0.12065 -0.2794)
			(stroke
				(width 0.1)
				(type default)
			)
			(layer "B.Fab")
		)
		(fp_line
			(start 0.12065 0.2794)
			(end 0.12065 0.3048)
			(stroke
				(width 0.1)
				(type default)
			)
			(layer "B.Fab")
		)
		(fp_line
			(start 0.12065 0.3048)
			(end 0.67945 0.3048)
			(stroke
				(width 0.1)
				(type default)
			)
			(layer "B.Fab")
		)
		(fp_line
			(start 0.67945 -0.305054)
			(end 0.12065 -0.305054)
			(stroke
				(width 0.1)
				(type default)
			)
			(layer "B.Fab")
		)
		(fp_line
			(start 0.67945 0.3048)
			(end 0.67945 -0.305054)
			(stroke
				(width 0.1)
				(type default)
			)
			(layer "B.Fab")
		)
		(pad "1" smd circle
			(at 0.40005 0 180)
			(size 0 0)
			(layers "B.Cu" "B.Mask" "B.Paste")
			(net "FM_I3C_CPU0_MUX1_OE_R_N")
		)
		(pad "2" smd circle
			(at -0.40005 0 180)
			(size 0 0)
			(layers "B.Cu" "B.Mask" "B.Paste")
			(net "FM_I3C_CPU0_MUX1_OE_N")
		)
	)
	(footprint ""
		(layer "B.Cu")
		(at 111.887 -414.02)
		(property "Reference" "R580"
			(at 0 0 0)
			(layer "B.SilkS")
			(hide yes)
			(effects
				(font
					(size 1.27 1.27)
				)
				(justify mirror)
			)
		)
		(property "Value" ""
			(at 0 0 0)
			(layer "B.Fab")
			(effects
				(font
					(size 1.27 1.27)
				)
				(justify mirror)
			)
		)
		(duplicate_pad_numbers_are_jumpers no)
		(fp_line
			(start -0.7874 -0.4064)
			(end -0.7874 0.4064)
			(stroke
				(width 0.1524)
				(type default)
			)
			(layer "B.SilkS")
		)
		(fp_line
			(start -0.7874 0.4064)
			(end 0.7874 0.4064)
			(stroke
				(width 0.1524)
				(type default)
			)
			(layer "B.SilkS")
		)
		(fp_line
			(start 0.7874 -0.4064)
			(end -0.7874 -0.4064)
			(stroke
				(width 0.1524)
				(type default)
			)
			(layer "B.SilkS")
		)
		(fp_line
			(start 0.7874 0.4064)
			(end 0.7874 -0.4064)
			(stroke
				(width 0.1524)
				(type default)
			)
			(layer "B.SilkS")
		)
		(fp_line
			(start -0.67945 -0.3048)
			(end -0.67945 0.3048)
			(stroke
				(width 0.1)
				(type default)
			)
			(layer "B.Fab")
		)
		(fp_line
			(start -0.67945 0.3048)
			(end -0.120396 0.3048)
			(stroke
				(width 0.1)
				(type default)
			)
			(layer "B.Fab")
		)
		(fp_line
			(start -0.12065 -0.3048)
			(end -0.67945 -0.3048)
			(stroke
				(width 0.1)
				(type default)
			)
			(layer "B.Fab")
		)
		(fp_line
			(start -0.12065 -0.2794)
			(end -0.12065 -0.3048)
			(stroke
				(width 0.1)
				(type default)
			)
			(layer "B.Fab")
		)
		(fp_line
			(start -0.120396 0.2794)
			(end 0.12065 0.2794)
			(stroke
				(width 0.1)
				(type default)
			)
			(layer "B.Fab")
		)
		(fp_line
			(start -0.120396 0.3048)
			(end -0.120396 0.2794)
			(stroke
				(width 0.1)
				(type default)
			)
			(layer "B.Fab")
		)
		(fp_line
			(start 0.12065 -0.305054)
			(end 0.12065 -0.2794)
			(stroke
				(width 0.1)
				(type default)
			)
			(layer "B.Fab")
		)
		(fp_line
			(start 0.12065 -0.2794)
			(end -0.12065 -0.2794)
			(stroke
				(width 0.1)
				(type default)
			)
			(layer "B.Fab")
		)
		(fp_line
			(start 0.12065 0.2794)
			(end 0.12065 0.3048)
			(stroke
				(width 0.1)
				(type default)
			)
			(layer "B.Fab")
		)
		(fp_line
			(start 0.12065 0.3048)
			(end 0.67945 0.3048)
			(stroke
				(width 0.1)
				(type default)
			)
			(layer "B.Fab")
		)
		(fp_line
			(start 0.67945 -0.305054)
			(end 0.12065 -0.305054)
			(stroke
				(width 0.1)
				(type default)
			)
			(layer "B.Fab")
		)
		(fp_line
			(start 0.67945 0.3048)
			(end 0.67945 -0.305054)
			(stroke
				(width 0.1)
				(type default)
			)
			(layer "B.Fab")
		)
		(pad "1" smd circle
			(at 0.40005 0 180)
			(size 0 0)
			(layers "B.Cu" "B.Mask" "B.Paste")
			(net "P3V3_AUX")
		)
		(pad "2" smd circle
			(at -0.40005 0 180)
			(size 0 0)
			(layers "B.Cu" "B.Mask" "B.Paste")
			(net "CLK_9ZXL045_P1_HIBW")
		)
	)
	(footprint ""
		(layer "B.Cu")
		(at 165.183566 -194.885564 180)
		(property "Reference" "R37"
			(at 0 0 0)
			(layer "B.SilkS")
			(hide yes)
			(effects
				(font
					(size 1.27 1.27)
				)
				(justify mirror)
			)
		)
		(property "Value" ""
			(at 0 0 0)
			(layer "B.Fab")
			(effects
				(font
					(size 1.27 1.27)
				)
				(justify mirror)
			)
		)
		(duplicate_pad_numbers_are_jumpers no)
		(fp_line
			(start 0.7874 0.4064)
			(end 0.7874 -0.4064)
			(stroke
				(width 0.1524)
				(type default)
			)
			(layer "B.SilkS")
		)
		(fp_line
			(start 0.7874 -0.4064)
			(end -0.7874 -0.4064)
			(stroke
				(width 0.1524)
				(type default)
			)
			(layer "B.SilkS")
		)
		(fp_line
			(start -0.7874 0.4064)
			(end 0.7874 0.4064)
			(stroke
				(width 0.1524)
				(type default)
			)
			(layer "B.SilkS")
		)
		(fp_line
			(start -0.7874 -0.4064)
			(end -0.7874 0.4064)
			(stroke
				(width 0.1524)
				(type default)
			)
			(layer "B.SilkS")
		)
		(fp_line
			(start 0.67945 0.3048)
			(end 0.67945 -0.305054)
			(stroke
				(width 0.1)
				(type default)
			)
			(layer "B.Fab")
		)
		(fp_line
			(start 0.67945 -0.305054)
			(end 0.12065 -0.305054)
			(stroke
				(width 0.1)
				(type default)
			)
			(layer "B.Fab")
		)
		(fp_line
			(start 0.12065 0.3048)
			(end 0.67945 0.3048)
			(stroke
				(width 0.1)
				(type default)
			)
			(layer "B.Fab")
		)
		(fp_line
			(start 0.12065 0.2794)
			(end 0.12065 0.3048)
			(stroke
				(width 0.1)
				(type default)
			)
			(layer "B.Fab")
		)
		(fp_line
			(start 0.12065 -0.2794)
			(end -0.12065 -0.2794)
			(stroke
				(width 0.1)
				(type default)
			)
			(layer "B.Fab")
		)
		(fp_line
			(start 0.12065 -0.305054)
			(end 0.12065 -0.2794)
			(stroke
				(width 0.1)
				(type default)
			)
			(layer "B.Fab")
		)
		(fp_line
			(start -0.120396 0.3048)
			(end -0.120396 0.2794)
			(stroke
				(width 0.1)
				(type default)
			)
			(layer "B.Fab")
		)
		(fp_line
			(start -0.120396 0.2794)
			(end 0.12065 0.2794)
			(stroke
				(width 0.1)
				(type default)
			)
			(layer "B.Fab")
		)
		(fp_line
			(start -0.12065 -0.2794)
			(end -0.12065 -0.3048)
			(stroke
				(width 0.1)
				(type default)
			)
			(layer "B.Fab")
		)
		(fp_line
			(start -0.12065 -0.3048)
			(end -0.67945 -0.3048)
			(stroke
				(width 0.1)
				(type default)
			)
			(layer "B.Fab")
		)
		(fp_line
			(start -0.67945 0.3048)
			(end -0.120396 0.3048)
			(stroke
				(width 0.1)
				(type default)
			)
			(layer "B.Fab")
		)
		(fp_line
			(start -0.67945 -0.3048)
			(end -0.67945 0.3048)
			(stroke
				(width 0.1)
				(type default)
			)
			(layer "B.Fab")
		)
		(pad "1" smd circle
			(at 0.40005 0)
			(size 0 0)
			(layers "B.Cu" "B.Mask" "B.Paste")
			(net "PD_CHG_CPU1_DIMM0_SAA")
		)
		(pad "2" smd circle
			(at -0.40005 0)
			(size 0 0)
			(layers "B.Cu" "B.Mask" "B.Paste")
			(net "GND")
		)
	)
	(footprint ""
		(layer "B.Cu")
		(at 199.39 -144.272 90)
		(property "Reference" "C8012"
			(at 0 0 90)
			(layer "B.SilkS")
			(hide yes)
			(effects
				(font
					(size 1.27 1.27)
				)
				(justify mirror)
			)
		)
		(property "Value" ""
			(at 0 0 90)
			(layer "B.Fab")
			(effects
				(font
					(size 1.27 1.27)
				)
				(justify mirror)
			)
		)
		(duplicate_pad_numbers_are_jumpers no)
		(fp_line
			(start 0.7874 -0.4064)
			(end -0.7874 -0.4064)
			(stroke
				(width 0.1524)
				(type default)
			)
			(layer "B.SilkS")
		)
		(fp_line
			(start -0.7874 -0.4064)
			(end -0.7874 0.4064)
			(stroke
				(width 0.1524)
				(type default)
			)
			(layer "B.SilkS")
		)
		(fp_line
			(start 0.7874 0.4064)
			(end 0.7874 -0.4064)
			(stroke
				(width 0.1524)
				(type default)
			)
			(layer "B.SilkS")
		)
		(fp_line
			(start -0.7874 0.4064)
			(end 0.7874 0.4064)
			(stroke
				(width 0.1524)
				(type default)
			)
			(layer "B.SilkS")
		)
		(fp_line
			(start 0.67945 -0.305054)
			(end 0.12065 -0.305054)
			(stroke
				(width 0.1)
				(type default)
			)
			(layer "B.Fab")
		)
		(fp_line
			(start 0.12065 -0.305054)
			(end 0.12065 -0.2794)
			(stroke
				(width 0.1)
				(type default)
			)
			(layer "B.Fab")
		)
		(fp_line
			(start -0.12065 -0.3048)
			(end -0.67945 -0.3048)
			(stroke
				(width 0.1)
				(type default)
			)
			(layer "B.Fab")
		)
		(fp_line
			(start -0.67945 -0.3048)
			(end -0.67945 0.3048)
			(stroke
				(width 0.1)
				(type default)
			)
			(layer "B.Fab")
		)
		(fp_line
			(start 0.12065 -0.2794)
			(end -0.12065 -0.2794)
			(stroke
				(width 0.1)
				(type default)
			)
			(layer "B.Fab")
		)
		(fp_line
			(start -0.12065 -0.2794)
			(end -0.12065 -0.3048)
			(stroke
				(width 0.1)
				(type default)
			)
			(layer "B.Fab")
		)
		(fp_line
			(start 0.12065 0.2794)
			(end 0.12065 0.3048)
			(stroke
				(width 0.1)
				(type default)
			)
			(layer "B.Fab")
		)
		(fp_line
			(start -0.120396 0.2794)
			(end 0.12065 0.2794)
			(stroke
				(width 0.1)
				(type default)
			)
			(layer "B.Fab")
		)
		(fp_line
			(start 0.67945 0.3048)
			(end 0.67945 -0.305054)
			(stroke
				(width 0.1)
				(type default)
			)
			(layer "B.Fab")
		)
		(fp_line
			(start 0.12065 0.3048)
			(end 0.67945 0.3048)
			(stroke
				(width 0.1)
				(type default)
			)
			(layer "B.Fab")
		)
		(fp_line
			(start -0.120396 0.3048)
			(end -0.120396 0.2794)
			(stroke
				(width 0.1)
				(type default)
			)
			(layer "B.Fab")
		)
		(fp_line
			(start -0.67945 0.3048)
			(end -0.120396 0.3048)
			(stroke
				(width 0.1)
				(type default)
			)
			(layer "B.Fab")
		)
		(pad "1" smd circle
			(at 0.40005 0 270)
			(size 0 0)
			(layers "B.Cu" "B.Mask" "B.Paste")
			(net "FM_AC_PWR_BTN_R_N")
		)
		(pad "2" smd circle
			(at -0.40005 0 270)
			(size 0 0)
			(layers "B.Cu" "B.Mask" "B.Paste")
			(net "GND")
		)
	)
	(footprint ""
		(layer "B.Cu")
		(at 142.047214 -390.587484)
		(property "Reference" "C405"
			(at 0 0 0)
			(layer "B.SilkS")
			(hide yes)
			(effects
				(font
					(size 1.27 1.27)
				)
				(justify mirror)
			)
		)
		(property "Value" ""
			(at 0 0 0)
			(layer "B.Fab")
			(effects
				(font
					(size 1.27 1.27)
				)
				(justify mirror)
			)
		)
		(duplicate_pad_numbers_are_jumpers no)
		(fp_line
			(start -1.524 -0.762)
			(end -1.524 0.762)
			(stroke
				(width 0.1524)
				(type default)
			)
			(layer "B.SilkS")
		)
		(fp_line
			(start -1.524 0.762)
			(end 1.524 0.762)
			(stroke
				(width 0.1524)
				(type default)
			)
			(layer "B.SilkS")
		)
		(fp_line
			(start 1.524 -0.762)
			(end -1.524 -0.762)
			(stroke
				(width 0.1524)
				(type default)
			)
			(layer "B.SilkS")
		)
		(fp_line
			(start 1.524 0.762)
			(end 1.524 -0.762)
			(stroke
				(width 0.1524)
				(type default)
			)
			(layer "B.SilkS")
		)
		(fp_line
			(start -1.1049 -0.724916)
			(end 1.1049 -0.724916)
			(stroke
				(width 0.1)
				(type default)
			)
			(layer "B.Fab")
		)
		(fp_line
			(start -1.1049 0.724916)
			(end -1.1049 -0.724916)
			(stroke
				(width 0.1)
				(type default)
			)
			(layer "B.Fab")
		)
		(fp_line
			(start 1.1049 -0.724916)
			(end 1.1049 0.724916)
			(stroke
				(width 0.1)
				(type default)
			)
			(layer "B.Fab")
		)
		(fp_line
			(start 1.1049 0.724916)
			(end -1.1049 0.724916)
			(stroke
				(width 0.1)
				(type default)
			)
			(layer "B.Fab")
		)
		(pad "1" smd rect
			(at 0.889 0)
			(size 1.016 1.27)
			(layers "B.Cu" "B.Mask" "B.Paste")
			(net "P0V9_CPU1_RT2_2A")
		)
		(pad "2" smd rect
			(at -0.889 0)
			(size 1.016 1.27)
			(layers "B.Cu" "B.Mask" "B.Paste")
			(net "GND")
		)
	)
	(footprint ""
		(layer "B.Cu")
		(at 85.906356 -386.766562 90)
		(property "Reference" "C292"
			(at 0 0 90)
			(layer "B.SilkS")
			(hide yes)
			(effects
				(font
					(size 1.27 1.27)
				)
				(justify mirror)
			)
		)
		(property "Value" ""
			(at 0 0 90)
			(layer "B.Fab")
			(effects
				(font
					(size 1.27 1.27)
				)
				(justify mirror)
			)
		)
		(duplicate_pad_numbers_are_jumpers no)
		(fp_line
			(start 0.299974 -0.150114)
			(end -0.299974 -0.150114)
			(stroke
				(width 0.1)
				(type default)
			)
			(layer "B.Fab")
		)
		(fp_line
			(start -0.299974 -0.150114)
			(end -0.299974 0.150114)
			(stroke
				(width 0.1)
				(type default)
			)
			(layer "B.Fab")
		)
		(fp_line
			(start 0.299974 0.150114)
			(end 0.299974 -0.150114)
			(stroke
				(width 0.1)
				(type default)
			)
			(layer "B.Fab")
		)
		(fp_line
			(start -0.299974 0.150114)
			(end 0.299974 0.150114)
			(stroke
				(width 0.1)
				(type default)
			)
			(layer "B.Fab")
		)
		(pad "1" smd rect
			(at 0.2667 0 270)
			(size 0.3048 0.381)
			(layers "B.Cu" "B.Mask" "B.Paste")
			(net "P0V9_CPU1_RT_2D")
		)
		(pad "2" smd rect
			(at -0.2667 0 270)
			(size 0.3048 0.381)
			(layers "B.Cu" "B.Mask" "B.Paste")
			(net "GND")
		)
	)
	(footprint ""
		(layer "B.Cu")
		(at 332.869286 -416.899344 90)
		(property "Reference" "C6552"
			(at 0 0 90)
			(layer "B.SilkS")
			(hide yes)
			(effects
				(font
					(size 1.27 1.27)
				)
				(justify mirror)
			)
		)
		(property "Value" ""
			(at 0 0 90)
			(layer "B.Fab")
			(effects
				(font
					(size 1.27 1.27)
				)
				(justify mirror)
			)
		)
		(duplicate_pad_numbers_are_jumpers no)
		(fp_line
			(start 0.299974 -0.150114)
			(end -0.299974 -0.150114)
			(stroke
				(width 0.1)
				(type default)
			)
			(layer "B.Fab")
		)
		(fp_line
			(start -0.299974 -0.150114)
			(end -0.299974 0.150114)
			(stroke
				(width 0.1)
				(type default)
			)
			(layer "B.Fab")
		)
		(fp_line
			(start 0.299974 0.150114)
			(end 0.299974 -0.150114)
			(stroke
				(width 0.1)
				(type default)
			)
			(layer "B.Fab")
		)
		(fp_line
			(start -0.299974 0.150114)
			(end 0.299974 0.150114)
			(stroke
				(width 0.1)
				(type default)
			)
			(layer "B.Fab")
		)
		(pad "1" smd rect
			(at 0.2667 0 270)
			(size 0.3048 0.381)
			(layers "B.Cu" "B.Mask" "B.Paste")
			(net "P5E_CPU0_P1_TX_BUF_C_DN<9>")
		)
		(pad "2" smd rect
			(at -0.2667 0 270)
			(size 0.3048 0.381)
			(layers "B.Cu" "B.Mask" "B.Paste")
			(net "P5E_CPU0_P1_TX_BUF_DN<9>")
		)
	)
	(footprint ""
		(layer "B.Cu")
		(at 230.6828 -335.026 180)
		(property "Reference" "R6760"
			(at 0 0 0)
			(layer "B.SilkS")
			(hide yes)
			(effects
				(font
					(size 1.27 1.27)
				)
				(justify mirror)
			)
		)
		(property "Value" ""
			(at 0 0 0)
			(layer "B.Fab")
			(effects
				(font
					(size 1.27 1.27)
				)
				(justify mirror)
			)
		)
		(duplicate_pad_numbers_are_jumpers no)
		(fp_line
			(start 0.32512 0.175006)
			(end 0.32512 -0.175006)
			(stroke
				(width 0.1)
				(type default)
			)
			(layer "B.Fab")
		)
		(fp_line
			(start 0.32512 -0.175006)
			(end -0.32512 -0.175006)
			(stroke
				(width 0.1)
				(type default)
			)
			(layer "B.Fab")
		)
		(fp_line
			(start -0.32512 0.175006)
			(end 0.32512 0.175006)
			(stroke
				(width 0.1)
				(type default)
			)
			(layer "B.Fab")
		)
		(fp_line
			(start -0.32512 -0.175006)
			(end -0.32512 0.175006)
			(stroke
				(width 0.1)
				(type default)
			)
			(layer "B.Fab")
		)
		(pad "1" smd rect
			(at 0.2667 0)
			(size 0.3048 0.381)
			(layers "B.Cu" "B.Mask" "B.Paste")
			(net "SMB_RT_CPU0_P2_SDA")
		)
		(pad "2" smd rect
			(at -0.2667 0 180)
			(size 0.3048 0.381)
			(layers "B.Cu" "B.Mask" "B.Paste")
			(net "SMB_RT_CPU0_P2_R_SDA")
		)
	)
	(footprint ""
		(layer "B.Cu")
		(at 443.013592 -389.14832 -90)
		(property "Reference" "PC6587_2"
			(at 0 0 90)
			(layer "B.SilkS")
			(hide yes)
			(effects
				(font
					(size 1.27 1.27)
				)
				(justify mirror)
			)
		)
		(property "Value" ""
			(at 0 0 90)
			(layer "B.Fab")
			(effects
				(font
					(size 1.27 1.27)
				)
				(justify mirror)
			)
		)
		(duplicate_pad_numbers_are_jumpers no)
		(fp_line
			(start -1.524 0.762)
			(end 1.524 0.762)
			(stroke
				(width 0.1524)
				(type default)
			)
			(layer "B.SilkS")
		)
		(fp_line
			(start 1.524 0.762)
			(end 1.524 -0.762)
			(stroke
				(width 0.1524)
				(type default)
			)
			(layer "B.SilkS")
		)
		(fp_line
			(start -1.524 -0.762)
			(end -1.524 0.762)
			(stroke
				(width 0.1524)
				(type default)
			)
			(layer "B.SilkS")
		)
		(fp_line
			(start 1.524 -0.762)
			(end -1.524 -0.762)
			(stroke
				(width 0.1524)
				(type default)
			)
			(layer "B.SilkS")
		)
		(fp_line
			(start -1.1049 0.724916)
			(end -1.1049 -0.724916)
			(stroke
				(width 0.1)
				(type default)
			)
			(layer "B.Fab")
		)
		(fp_line
			(start 1.1049 0.724916)
			(end -1.1049 0.724916)
			(stroke
				(width 0.1)
				(type default)
			)
			(layer "B.Fab")
		)
		(fp_line
			(start -1.1049 -0.724916)
			(end 1.1049 -0.724916)
			(stroke
				(width 0.1)
				(type default)
			)
			(layer "B.Fab")
		)
		(fp_line
			(start 1.1049 -0.724916)
			(end 1.1049 0.724916)
			(stroke
				(width 0.1)
				(type default)
			)
			(layer "B.Fab")
		)
		(pad "1" smd rect
			(at 0.889 0 270)
			(size 1.016 1.27)
			(layers "B.Cu" "B.Mask" "B.Paste")
			(net "P0V9_CPU0_RT_2D")
		)
		(pad "2" smd rect
			(at -0.889 0 270)
			(size 1.016 1.27)
			(layers "B.Cu" "B.Mask" "B.Paste")
			(net "GND")
		)
	)
	(footprint ""
		(layer "B.Cu")
		(at 448.579748 -10.567162 -90)
		(property "Reference" "R31"
			(at 0 0 90)
			(layer "B.SilkS")
			(hide yes)
			(effects
				(font
					(size 1.27 1.27)
				)
				(justify mirror)
			)
		)
		(property "Value" ""
			(at 0 0 90)
			(layer "B.Fab")
			(effects
				(font
					(size 1.27 1.27)
				)
				(justify mirror)
			)
		)
		(duplicate_pad_numbers_are_jumpers no)
		(fp_line
			(start -0.7874 0.4064)
			(end 0.7874 0.4064)
			(stroke
				(width 0.1524)
				(type default)
			)
			(layer "B.SilkS")
		)
		(fp_line
			(start 0.7874 0.4064)
			(end 0.7874 -0.4064)
			(stroke
				(width 0.1524)
				(type default)
			)
			(layer "B.SilkS")
		)
		(fp_line
			(start -0.7874 -0.4064)
			(end -0.7874 0.4064)
			(stroke
				(width 0.1524)
				(type default)
			)
			(layer "B.SilkS")
		)
		(fp_line
			(start 0.7874 -0.4064)
			(end -0.7874 -0.4064)
			(stroke
				(width 0.1524)
				(type default)
			)
			(layer "B.SilkS")
		)
		(fp_line
			(start -0.67945 0.3048)
			(end -0.120396 0.3048)
			(stroke
				(width 0.1)
				(type default)
			)
			(layer "B.Fab")
		)
		(fp_line
			(start -0.120396 0.3048)
			(end -0.120396 0.2794)
			(stroke
				(width 0.1)
				(type default)
			)
			(layer "B.Fab")
		)
		(fp_line
			(start 0.12065 0.3048)
			(end 0.67945 0.3048)
			(stroke
				(width 0.1)
				(type default)
			)
			(layer "B.Fab")
		)
		(fp_line
			(start 0.67945 0.3048)
			(end 0.67945 -0.305054)
			(stroke
				(width 0.1)
				(type default)
			)
			(layer "B.Fab")
		)
		(fp_line
			(start -0.120396 0.2794)
			(end 0.12065 0.2794)
			(stroke
				(width 0.1)
				(type default)
			)
			(layer "B.Fab")
		)
		(fp_line
			(start 0.12065 0.2794)
			(end 0.12065 0.3048)
			(stroke
				(width 0.1)
				(type default)
			)
			(layer "B.Fab")
		)
		(fp_line
			(start -0.12065 -0.2794)
			(end -0.12065 -0.3048)
			(stroke
				(width 0.1)
				(type default)
			)
			(layer "B.Fab")
		)
		(fp_line
			(start 0.12065 -0.2794)
			(end -0.12065 -0.2794)
			(stroke
				(width 0.1)
				(type default)
			)
			(layer "B.Fab")
		)
		(fp_line
			(start -0.67945 -0.3048)
			(end -0.67945 0.3048)
			(stroke
				(width 0.1)
				(type default)
			)
			(layer "B.Fab")
		)
		(fp_line
			(start -0.12065 -0.3048)
			(end -0.67945 -0.3048)
			(stroke
				(width 0.1)
				(type default)
			)
			(layer "B.Fab")
		)
		(fp_line
			(start 0.12065 -0.305054)
			(end 0.12065 -0.2794)
			(stroke
				(width 0.1)
				(type default)
			)
			(layer "B.Fab")
		)
		(fp_line
			(start 0.67945 -0.305054)
			(end 0.12065 -0.305054)
			(stroke
				(width 0.1)
				(type default)
			)
			(layer "B.Fab")
		)
		(pad "1" smd circle
			(at 0.40005 0 90)
			(size 0 0)
			(layers "B.Cu" "B.Mask" "B.Paste")
			(net "P3V3_OCP_SFF")
		)
		(pad "2" smd circle
			(at -0.40005 0 90)
			(size 0 0)
			(layers "B.Cu" "B.Mask" "B.Paste")
			(net "OCP_SFF_ID0")
		)
	)
	(footprint ""
		(layer "B.Cu")
		(at 228.410516 -328.638662 180)
		(property "Reference" "C1088"
			(at 0 0 0)
			(layer "B.SilkS")
			(hide yes)
			(effects
				(font
					(size 1.27 1.27)
				)
				(justify mirror)
			)
		)
		(property "Value" ""
			(at 0 0 0)
			(layer "B.Fab")
			(effects
				(font
					(size 1.27 1.27)
				)
				(justify mirror)
			)
		)
		(duplicate_pad_numbers_are_jumpers no)
		(fp_line
			(start 0.7874 0.4064)
			(end 0.7874 -0.4064)
			(stroke
				(width 0.1524)
				(type default)
			)
			(layer "B.SilkS")
		)
		(fp_line
			(start 0.7874 -0.4064)
			(end -0.7874 -0.4064)
			(stroke
				(width 0.1524)
				(type default)
			)
			(layer "B.SilkS")
		)
		(fp_line
			(start -0.7874 0.4064)
			(end 0.7874 0.4064)
			(stroke
				(width 0.1524)
				(type default)
			)
			(layer "B.SilkS")
		)
		(fp_line
			(start -0.7874 -0.4064)
			(end -0.7874 0.4064)
			(stroke
				(width 0.1524)
				(type default)
			)
			(layer "B.SilkS")
		)
		(fp_line
			(start 0.67945 0.3048)
			(end 0.67945 -0.305054)
			(stroke
				(width 0.1)
				(type default)
			)
			(layer "B.Fab")
		)
		(fp_line
			(start 0.67945 -0.305054)
			(end 0.12065 -0.305054)
			(stroke
				(width 0.1)
				(type default)
			)
			(layer "B.Fab")
		)
		(fp_line
			(start 0.12065 0.3048)
			(end 0.67945 0.3048)
			(stroke
				(width 0.1)
				(type default)
			)
			(layer "B.Fab")
		)
		(fp_line
			(start 0.12065 0.2794)
			(end 0.12065 0.3048)
			(stroke
				(width 0.1)
				(type default)
			)
			(layer "B.Fab")
		)
		(fp_line
			(start 0.12065 -0.2794)
			(end -0.12065 -0.2794)
			(stroke
				(width 0.1)
				(type default)
			)
			(layer "B.Fab")
		)
		(fp_line
			(start 0.12065 -0.305054)
			(end 0.12065 -0.2794)
			(stroke
				(width 0.1)
				(type default)
			)
			(layer "B.Fab")
		)
		(fp_line
			(start -0.120396 0.3048)
			(end -0.120396 0.2794)
			(stroke
				(width 0.1)
				(type default)
			)
			(layer "B.Fab")
		)
		(fp_line
			(start -0.120396 0.2794)
			(end 0.12065 0.2794)
			(stroke
				(width 0.1)
				(type default)
			)
			(layer "B.Fab")
		)
		(fp_line
			(start -0.12065 -0.2794)
			(end -0.12065 -0.3048)
			(stroke
				(width 0.1)
				(type default)
			)
			(layer "B.Fab")
		)
		(fp_line
			(start -0.12065 -0.3048)
			(end -0.67945 -0.3048)
			(stroke
				(width 0.1)
				(type default)
			)
			(layer "B.Fab")
		)
		(fp_line
			(start -0.67945 0.3048)
			(end -0.120396 0.3048)
			(stroke
				(width 0.1)
				(type default)
			)
			(layer "B.Fab")
		)
		(fp_line
			(start -0.67945 -0.3048)
			(end -0.67945 0.3048)
			(stroke
				(width 0.1)
				(type default)
			)
			(layer "B.Fab")
		)
		(pad "1" smd circle
			(at 0.40005 0)
			(size 0 0)
			(layers "B.Cu" "B.Mask" "B.Paste")
			(net "PVDD18_S5_P0_ADC_TIC")
		)
		(pad "2" smd circle
			(at -0.40005 0)
			(size 0 0)
			(layers "B.Cu" "B.Mask" "B.Paste")
			(net "GND")
		)
	)
	(footprint ""
		(layer "B.Cu")
		(at 215.521286 -73.050908)
		(property "Reference" "R76"
			(at 0 0 0)
			(layer "B.SilkS")
			(hide yes)
			(effects
				(font
					(size 1.27 1.27)
				)
				(justify mirror)
			)
		)
		(property "Value" ""
			(at 0 0 0)
			(layer "B.Fab")
			(effects
				(font
					(size 1.27 1.27)
				)
				(justify mirror)
			)
		)
		(duplicate_pad_numbers_are_jumpers no)
		(fp_line
			(start -0.7874 -0.4064)
			(end -0.7874 0.4064)
			(stroke
				(width 0.1524)
				(type default)
			)
			(layer "B.SilkS")
		)
		(fp_line
			(start -0.7874 0.4064)
			(end 0.7874 0.4064)
			(stroke
				(width 0.1524)
				(type default)
			)
			(layer "B.SilkS")
		)
		(fp_line
			(start 0.7874 -0.4064)
			(end -0.7874 -0.4064)
			(stroke
				(width 0.1524)
				(type default)
			)
			(layer "B.SilkS")
		)
		(fp_line
			(start 0.7874 0.4064)
			(end 0.7874 -0.4064)
			(stroke
				(width 0.1524)
				(type default)
			)
			(layer "B.SilkS")
		)
		(fp_line
			(start -0.67945 -0.3048)
			(end -0.67945 0.3048)
			(stroke
				(width 0.1)
				(type default)
			)
			(layer "B.Fab")
		)
		(fp_line
			(start -0.67945 0.3048)
			(end -0.120396 0.3048)
			(stroke
				(width 0.1)
				(type default)
			)
			(layer "B.Fab")
		)
		(fp_line
			(start -0.12065 -0.3048)
			(end -0.67945 -0.3048)
			(stroke
				(width 0.1)
				(type default)
			)
			(layer "B.Fab")
		)
		(fp_line
			(start -0.12065 -0.2794)
			(end -0.12065 -0.3048)
			(stroke
				(width 0.1)
				(type default)
			)
			(layer "B.Fab")
		)
		(fp_line
			(start -0.120396 0.2794)
			(end 0.12065 0.2794)
			(stroke
				(width 0.1)
				(type default)
			)
			(layer "B.Fab")
		)
		(fp_line
			(start -0.120396 0.3048)
			(end -0.120396 0.2794)
			(stroke
				(width 0.1)
				(type default)
			)
			(layer "B.Fab")
		)
		(fp_line
			(start 0.12065 -0.305054)
			(end 0.12065 -0.2794)
			(stroke
				(width 0.1)
				(type default)
			)
			(layer "B.Fab")
		)
		(fp_line
			(start 0.12065 -0.2794)
			(end -0.12065 -0.2794)
			(stroke
				(width 0.1)
				(type default)
			)
			(layer "B.Fab")
		)
		(fp_line
			(start 0.12065 0.2794)
			(end 0.12065 0.3048)
			(stroke
				(width 0.1)
				(type default)
			)
			(layer "B.Fab")
		)
		(fp_line
			(start 0.12065 0.3048)
			(end 0.67945 0.3048)
			(stroke
				(width 0.1)
				(type default)
			)
			(layer "B.Fab")
		)
		(fp_line
			(start 0.67945 -0.305054)
			(end 0.12065 -0.305054)
			(stroke
				(width 0.1)
				(type default)
			)
			(layer "B.Fab")
		)
		(fp_line
			(start 0.67945 0.3048)
			(end 0.67945 -0.305054)
			(stroke
				(width 0.1)
				(type default)
			)
			(layer "B.Fab")
		)
		(pad "1" smd circle
			(at 0.40005 0 180)
			(size 0 0)
			(layers "B.Cu" "B.Mask" "B.Paste")
			(net "NCSI_BMC_TXD1_R")
		)
		(pad "2" smd circle
			(at -0.40005 0 180)
			(size 0 0)
			(layers "B.Cu" "B.Mask" "B.Paste")
			(net "RMII_BMC_OCP_TXD_1")
		)
	)
	(footprint ""
		(layer "B.Cu")
		(at 245.7704 -332.0796 180)
		(property "Reference" "R1514"
			(at 0 0 0)
			(layer "B.SilkS")
			(hide yes)
			(effects
				(font
					(size 1.27 1.27)
				)
				(justify mirror)
			)
		)
		(property "Value" ""
			(at 0 0 0)
			(layer "B.Fab")
			(effects
				(font
					(size 1.27 1.27)
				)
				(justify mirror)
			)
		)
		(duplicate_pad_numbers_are_jumpers no)
		(fp_line
			(start 0.32512 0.175006)
			(end 0.32512 -0.175006)
			(stroke
				(width 0.1)
				(type default)
			)
			(layer "B.Fab")
		)
		(fp_line
			(start 0.32512 -0.175006)
			(end -0.32512 -0.175006)
			(stroke
				(width 0.1)
				(type default)
			)
			(layer "B.Fab")
		)
		(fp_line
			(start -0.32512 0.175006)
			(end 0.32512 0.175006)
			(stroke
				(width 0.1)
				(type default)
			)
			(layer "B.Fab")
		)
		(fp_line
			(start -0.32512 -0.175006)
			(end -0.32512 0.175006)
			(stroke
				(width 0.1)
				(type default)
			)
			(layer "B.Fab")
		)
		(pad "1" smd rect
			(at 0.2667 0)
			(size 0.3048 0.381)
			(layers "B.Cu" "B.Mask" "B.Paste")
			(net "SMB_MUX_RT_R1_SCL")
		)
		(pad "2" smd rect
			(at -0.2667 0 180)
			(size 0.3048 0.381)
			(layers "B.Cu" "B.Mask" "B.Paste")
			(net "SMB_MUX_RT_R2_SCL")
		)
	)
	(footprint ""
		(layer "B.Cu")
		(at 98.493834 -261.947152)
		(property "Reference" "C2116"
			(at 0 0 0)
			(layer "B.SilkS")
			(hide yes)
			(effects
				(font
					(size 1.27 1.27)
				)
				(justify mirror)
			)
		)
		(property "Value" ""
			(at 0 0 0)
			(layer "B.Fab")
			(effects
				(font
					(size 1.27 1.27)
				)
				(justify mirror)
			)
		)
		(duplicate_pad_numbers_are_jumpers no)
		(fp_line
			(start -0.7874 -0.4064)
			(end -0.7874 0.4064)
			(stroke
				(width 0.1524)
				(type default)
			)
			(layer "B.SilkS")
		)
		(fp_line
			(start -0.7874 0.4064)
			(end 0.7874 0.4064)
			(stroke
				(width 0.1524)
				(type default)
			)
			(layer "B.SilkS")
		)
		(fp_line
			(start 0.7874 -0.4064)
			(end -0.7874 -0.4064)
			(stroke
				(width 0.1524)
				(type default)
			)
			(layer "B.SilkS")
		)
		(fp_line
			(start 0.7874 0.4064)
			(end 0.7874 -0.4064)
			(stroke
				(width 0.1524)
				(type default)
			)
			(layer "B.SilkS")
		)
		(fp_line
			(start -0.67945 -0.3048)
			(end -0.67945 0.3048)
			(stroke
				(width 0.1)
				(type default)
			)
			(layer "B.Fab")
		)
		(fp_line
			(start -0.67945 0.3048)
			(end -0.120396 0.3048)
			(stroke
				(width 0.1)
				(type default)
			)
			(layer "B.Fab")
		)
		(fp_line
			(start -0.12065 -0.3048)
			(end -0.67945 -0.3048)
			(stroke
				(width 0.1)
				(type default)
			)
			(layer "B.Fab")
		)
		(fp_line
			(start -0.12065 -0.2794)
			(end -0.12065 -0.3048)
			(stroke
				(width 0.1)
				(type default)
			)
			(layer "B.Fab")
		)
		(fp_line
			(start -0.120396 0.2794)
			(end 0.12065 0.2794)
			(stroke
				(width 0.1)
				(type default)
			)
			(layer "B.Fab")
		)
		(fp_line
			(start -0.120396 0.3048)
			(end -0.120396 0.2794)
			(stroke
				(width 0.1)
				(type default)
			)
			(layer "B.Fab")
		)
		(fp_line
			(start 0.12065 -0.305054)
			(end 0.12065 -0.2794)
			(stroke
				(width 0.1)
				(type default)
			)
			(layer "B.Fab")
		)
		(fp_line
			(start 0.12065 -0.2794)
			(end -0.12065 -0.2794)
			(stroke
				(width 0.1)
				(type default)
			)
			(layer "B.Fab")
		)
		(fp_line
			(start 0.12065 0.2794)
			(end 0.12065 0.3048)
			(stroke
				(width 0.1)
				(type default)
			)
			(layer "B.Fab")
		)
		(fp_line
			(start 0.12065 0.3048)
			(end 0.67945 0.3048)
			(stroke
				(width 0.1)
				(type default)
			)
			(layer "B.Fab")
		)
		(fp_line
			(start 0.67945 -0.305054)
			(end 0.12065 -0.305054)
			(stroke
				(width 0.1)
				(type default)
			)
			(layer "B.Fab")
		)
		(fp_line
			(start 0.67945 0.3048)
			(end 0.67945 -0.305054)
			(stroke
				(width 0.1)
				(type default)
			)
			(layer "B.Fab")
		)
		(pad "1" smd circle
			(at 0.40005 0 180)
			(size 0 0)
			(layers "B.Cu" "B.Mask" "B.Paste")
			(net "PVDDIO_P1")
		)
		(pad "2" smd circle
			(at -0.40005 0 180)
			(size 0 0)
			(layers "B.Cu" "B.Mask" "B.Paste")
			(net "GND")
		)
	)
	(footprint ""
		(layer "B.Cu")
		(at 163.946332 -388.011162 -90)
		(property "Reference" "C430"
			(at 0 0 90)
			(layer "B.SilkS")
			(hide yes)
			(effects
				(font
					(size 1.27 1.27)
				)
				(justify mirror)
			)
		)
		(property "Value" ""
			(at 0 0 90)
			(layer "B.Fab")
			(effects
				(font
					(size 1.27 1.27)
				)
				(justify mirror)
			)
		)
		(duplicate_pad_numbers_are_jumpers no)
		(fp_line
			(start -0.299974 0.150114)
			(end 0.299974 0.150114)
			(stroke
				(width 0.1)
				(type default)
			)
			(layer "B.Fab")
		)
		(fp_line
			(start 0.299974 0.150114)
			(end 0.299974 -0.150114)
			(stroke
				(width 0.1)
				(type default)
			)
			(layer "B.Fab")
		)
		(fp_line
			(start -0.299974 -0.150114)
			(end -0.299974 0.150114)
			(stroke
				(width 0.1)
				(type default)
			)
			(layer "B.Fab")
		)
		(fp_line
			(start 0.299974 -0.150114)
			(end -0.299974 -0.150114)
			(stroke
				(width 0.1)
				(type default)
			)
			(layer "B.Fab")
		)
		(pad "1" smd rect
			(at 0.2667 0 90)
			(size 0.3048 0.381)
			(layers "B.Cu" "B.Mask" "B.Paste")
			(net "P0V9_CPU1_RT2_2A")
		)
		(pad "2" smd rect
			(at -0.2667 0 90)
			(size 0.3048 0.381)
			(layers "B.Cu" "B.Mask" "B.Paste")
			(net "GND")
		)
	)
	(footprint ""
		(layer "B.Cu")
		(at 435.549802 -10.072116 180)
		(property "Reference" "C1240"
			(at 0 0 0)
			(layer "B.SilkS")
			(hide yes)
			(effects
				(font
					(size 1.27 1.27)
				)
				(justify mirror)
			)
		)
		(property "Value" ""
			(at 0 0 0)
			(layer "B.Fab")
			(effects
				(font
					(size 1.27 1.27)
				)
				(justify mirror)
			)
		)
		(duplicate_pad_numbers_are_jumpers no)
		(fp_line
			(start 0.7874 0.4064)
			(end 0.7874 -0.4064)
			(stroke
				(width 0.1524)
				(type default)
			)
			(layer "B.SilkS")
		)
		(fp_line
			(start 0.7874 -0.4064)
			(end -0.7874 -0.4064)
			(stroke
				(width 0.1524)
				(type default)
			)
			(layer "B.SilkS")
		)
		(fp_line
			(start -0.7874 0.4064)
			(end 0.7874 0.4064)
			(stroke
				(width 0.1524)
				(type default)
			)
			(layer "B.SilkS")
		)
		(fp_line
			(start -0.7874 -0.4064)
			(end -0.7874 0.4064)
			(stroke
				(width 0.1524)
				(type default)
			)
			(layer "B.SilkS")
		)
		(fp_line
			(start 0.67945 0.3048)
			(end 0.67945 -0.305054)
			(stroke
				(width 0.1)
				(type default)
			)
			(layer "B.Fab")
		)
		(fp_line
			(start 0.67945 -0.305054)
			(end 0.12065 -0.305054)
			(stroke
				(width 0.1)
				(type default)
			)
			(layer "B.Fab")
		)
		(fp_line
			(start 0.12065 0.3048)
			(end 0.67945 0.3048)
			(stroke
				(width 0.1)
				(type default)
			)
			(layer "B.Fab")
		)
		(fp_line
			(start 0.12065 0.2794)
			(end 0.12065 0.3048)
			(stroke
				(width 0.1)
				(type default)
			)
			(layer "B.Fab")
		)
		(fp_line
			(start 0.12065 -0.2794)
			(end -0.12065 -0.2794)
			(stroke
				(width 0.1)
				(type default)
			)
			(layer "B.Fab")
		)
		(fp_line
			(start 0.12065 -0.305054)
			(end 0.12065 -0.2794)
			(stroke
				(width 0.1)
				(type default)
			)
			(layer "B.Fab")
		)
		(fp_line
			(start -0.120396 0.3048)
			(end -0.120396 0.2794)
			(stroke
				(width 0.1)
				(type default)
			)
			(layer "B.Fab")
		)
		(fp_line
			(start -0.120396 0.2794)
			(end 0.12065 0.2794)
			(stroke
				(width 0.1)
				(type default)
			)
			(layer "B.Fab")
		)
		(fp_line
			(start -0.12065 -0.2794)
			(end -0.12065 -0.3048)
			(stroke
				(width 0.1)
				(type default)
			)
			(layer "B.Fab")
		)
		(fp_line
			(start -0.12065 -0.3048)
			(end -0.67945 -0.3048)
			(stroke
				(width 0.1)
				(type default)
			)
			(layer "B.Fab")
		)
		(fp_line
			(start -0.67945 0.3048)
			(end -0.120396 0.3048)
			(stroke
				(width 0.1)
				(type default)
			)
			(layer "B.Fab")
		)
		(fp_line
			(start -0.67945 -0.3048)
			(end -0.67945 0.3048)
			(stroke
				(width 0.1)
				(type default)
			)
			(layer "B.Fab")
		)
		(pad "1" smd circle
			(at 0.40005 0)
			(size 0 0)
			(layers "B.Cu" "B.Mask" "B.Paste")
			(net "P3V3_OCP_SFF")
		)
		(pad "2" smd circle
			(at -0.40005 0)
			(size 0 0)
			(layers "B.Cu" "B.Mask" "B.Paste")
			(net "GND")
		)
	)
	(footprint ""
		(layer "B.Cu")
		(at 185.324496 -133.577076 90)
		(property "Reference" "R497"
			(at 0 0 90)
			(layer "B.SilkS")
			(hide yes)
			(effects
				(font
					(size 1.27 1.27)
				)
				(justify mirror)
			)
		)
		(property "Value" ""
			(at 0 0 90)
			(layer "B.Fab")
			(effects
				(font
					(size 1.27 1.27)
				)
				(justify mirror)
			)
		)
		(duplicate_pad_numbers_are_jumpers no)
		(fp_line
			(start 0.7874 -0.4064)
			(end -0.7874 -0.4064)
			(stroke
				(width 0.1524)
				(type default)
			)
			(layer "B.SilkS")
		)
		(fp_line
			(start -0.7874 -0.4064)
			(end -0.7874 0.4064)
			(stroke
				(width 0.1524)
				(type default)
			)
			(layer "B.SilkS")
		)
		(fp_line
			(start 0.7874 0.4064)
			(end 0.7874 -0.4064)
			(stroke
				(width 0.1524)
				(type default)
			)
			(layer "B.SilkS")
		)
		(fp_line
			(start -0.7874 0.4064)
			(end 0.7874 0.4064)
			(stroke
				(width 0.1524)
				(type default)
			)
			(layer "B.SilkS")
		)
		(fp_line
			(start 0.67945 -0.305054)
			(end 0.12065 -0.305054)
			(stroke
				(width 0.1)
				(type default)
			)
			(layer "B.Fab")
		)
		(fp_line
			(start 0.12065 -0.305054)
			(end 0.12065 -0.2794)
			(stroke
				(width 0.1)
				(type default)
			)
			(layer "B.Fab")
		)
		(fp_line
			(start -0.12065 -0.3048)
			(end -0.67945 -0.3048)
			(stroke
				(width 0.1)
				(type default)
			)
			(layer "B.Fab")
		)
		(fp_line
			(start -0.67945 -0.3048)
			(end -0.67945 0.3048)
			(stroke
				(width 0.1)
				(type default)
			)
			(layer "B.Fab")
		)
		(fp_line
			(start 0.12065 -0.2794)
			(end -0.12065 -0.2794)
			(stroke
				(width 0.1)
				(type default)
			)
			(layer "B.Fab")
		)
		(fp_line
			(start -0.12065 -0.2794)
			(end -0.12065 -0.3048)
			(stroke
				(width 0.1)
				(type default)
			)
			(layer "B.Fab")
		)
		(fp_line
			(start 0.12065 0.2794)
			(end 0.12065 0.3048)
			(stroke
				(width 0.1)
				(type default)
			)
			(layer "B.Fab")
		)
		(fp_line
			(start -0.120396 0.2794)
			(end 0.12065 0.2794)
			(stroke
				(width 0.1)
				(type default)
			)
			(layer "B.Fab")
		)
		(fp_line
			(start 0.67945 0.3048)
			(end 0.67945 -0.305054)
			(stroke
				(width 0.1)
				(type default)
			)
			(layer "B.Fab")
		)
		(fp_line
			(start 0.12065 0.3048)
			(end 0.67945 0.3048)
			(stroke
				(width 0.1)
				(type default)
			)
			(layer "B.Fab")
		)
		(fp_line
			(start -0.120396 0.3048)
			(end -0.120396 0.2794)
			(stroke
				(width 0.1)
				(type default)
			)
			(layer "B.Fab")
		)
		(fp_line
			(start -0.67945 0.3048)
			(end -0.120396 0.3048)
			(stroke
				(width 0.1)
				(type default)
			)
			(layer "B.Fab")
		)
		(pad "1" smd circle
			(at 0.40005 0 270)
			(size 0 0)
			(layers "B.Cu" "B.Mask" "B.Paste")
			(net "APML_CPU1_ALERT_N")
		)
		(pad "2" smd circle
			(at -0.40005 0 270)
			(size 0 0)
			(layers "B.Cu" "B.Mask" "B.Paste")
			(net "APML_CPU1_ALERT_R_N")
		)
	)
	(footprint ""
		(layer "B.Cu")
		(at 460.405988 -43.400726 180)
		(property "Reference" "PR8073"
			(at 0 0 0)
			(layer "B.SilkS")
			(hide yes)
			(effects
				(font
					(size 1.27 1.27)
				)
				(justify mirror)
			)
		)
		(property "Value" ""
			(at 0 0 0)
			(layer "B.Fab")
			(effects
				(font
					(size 1.27 1.27)
				)
				(justify mirror)
			)
		)
		(duplicate_pad_numbers_are_jumpers no)
		(fp_line
			(start 0.7874 0.4064)
			(end 0.7874 -0.4064)
			(stroke
				(width 0.1524)
				(type default)
			)
			(layer "B.SilkS")
		)
		(fp_line
			(start 0.7874 -0.4064)
			(end -0.7874 -0.4064)
			(stroke
				(width 0.1524)
				(type default)
			)
			(layer "B.SilkS")
		)
		(fp_line
			(start -0.7874 0.4064)
			(end 0.7874 0.4064)
			(stroke
				(width 0.1524)
				(type default)
			)
			(layer "B.SilkS")
		)
		(fp_line
			(start -0.7874 -0.4064)
			(end -0.7874 0.4064)
			(stroke
				(width 0.1524)
				(type default)
			)
			(layer "B.SilkS")
		)
		(fp_line
			(start 0.67945 0.3048)
			(end 0.67945 -0.305054)
			(stroke
				(width 0.1)
				(type default)
			)
			(layer "B.Fab")
		)
		(fp_line
			(start 0.67945 -0.305054)
			(end 0.12065 -0.305054)
			(stroke
				(width 0.1)
				(type default)
			)
			(layer "B.Fab")
		)
		(fp_line
			(start 0.12065 0.3048)
			(end 0.67945 0.3048)
			(stroke
				(width 0.1)
				(type default)
			)
			(layer "B.Fab")
		)
		(fp_line
			(start 0.12065 0.2794)
			(end 0.12065 0.3048)
			(stroke
				(width 0.1)
				(type default)
			)
			(layer "B.Fab")
		)
		(fp_line
			(start 0.12065 -0.2794)
			(end -0.12065 -0.2794)
			(stroke
				(width 0.1)
				(type default)
			)
			(layer "B.Fab")
		)
		(fp_line
			(start 0.12065 -0.305054)
			(end 0.12065 -0.2794)
			(stroke
				(width 0.1)
				(type default)
			)
			(layer "B.Fab")
		)
		(fp_line
			(start -0.120396 0.3048)
			(end -0.120396 0.2794)
			(stroke
				(width 0.1)
				(type default)
			)
			(layer "B.Fab")
		)
		(fp_line
			(start -0.120396 0.2794)
			(end 0.12065 0.2794)
			(stroke
				(width 0.1)
				(type default)
			)
			(layer "B.Fab")
		)
		(fp_line
			(start -0.12065 -0.2794)
			(end -0.12065 -0.3048)
			(stroke
				(width 0.1)
				(type default)
			)
			(layer "B.Fab")
		)
		(fp_line
			(start -0.12065 -0.3048)
			(end -0.67945 -0.3048)
			(stroke
				(width 0.1)
				(type default)
			)
			(layer "B.Fab")
		)
		(fp_line
			(start -0.67945 0.3048)
			(end -0.120396 0.3048)
			(stroke
				(width 0.1)
				(type default)
			)
			(layer "B.Fab")
		)
		(fp_line
			(start -0.67945 -0.3048)
			(end -0.67945 0.3048)
			(stroke
				(width 0.1)
				(type default)
			)
			(layer "B.Fab")
		)
		(pad "1" smd circle
			(at 0.40005 0)
			(size 0 0)
			(layers "B.Cu" "B.Mask" "B.Paste")
			(net "P3V3_AUX")
		)
		(pad "2" smd circle
			(at -0.40005 0)
			(size 0 0)
			(layers "B.Cu" "B.Mask" "B.Paste")
			(net "PWRGD_P3V3_AUX_R1")
		)
	)
	(footprint ""
		(layer "B.Cu")
		(at 182.541164 -23.655782 -90)
		(property "Reference" "R3241"
			(at 0 0 90)
			(layer "B.SilkS")
			(hide yes)
			(effects
				(font
					(size 1.27 1.27)
				)
				(justify mirror)
			)
		)
		(property "Value" ""
			(at 0 0 90)
			(layer "B.Fab")
			(effects
				(font
					(size 1.27 1.27)
				)
				(justify mirror)
			)
		)
		(duplicate_pad_numbers_are_jumpers no)
		(fp_line
			(start -0.7874 0.4064)
			(end 0.7874 0.4064)
			(stroke
				(width 0.1524)
				(type default)
			)
			(layer "B.SilkS")
		)
		(fp_line
			(start 0.7874 0.4064)
			(end 0.7874 -0.4064)
			(stroke
				(width 0.1524)
				(type default)
			)
			(layer "B.SilkS")
		)
		(fp_line
			(start -0.7874 -0.4064)
			(end -0.7874 0.4064)
			(stroke
				(width 0.1524)
				(type default)
			)
			(layer "B.SilkS")
		)
		(fp_line
			(start 0.7874 -0.4064)
			(end -0.7874 -0.4064)
			(stroke
				(width 0.1524)
				(type default)
			)
			(layer "B.SilkS")
		)
		(fp_line
			(start -0.67945 0.3048)
			(end -0.120396 0.3048)
			(stroke
				(width 0.1)
				(type default)
			)
			(layer "B.Fab")
		)
		(fp_line
			(start -0.120396 0.3048)
			(end -0.120396 0.2794)
			(stroke
				(width 0.1)
				(type default)
			)
			(layer "B.Fab")
		)
		(fp_line
			(start 0.12065 0.3048)
			(end 0.67945 0.3048)
			(stroke
				(width 0.1)
				(type default)
			)
			(layer "B.Fab")
		)
		(fp_line
			(start 0.67945 0.3048)
			(end 0.67945 -0.305054)
			(stroke
				(width 0.1)
				(type default)
			)
			(layer "B.Fab")
		)
		(fp_line
			(start -0.120396 0.2794)
			(end 0.12065 0.2794)
			(stroke
				(width 0.1)
				(type default)
			)
			(layer "B.Fab")
		)
		(fp_line
			(start 0.12065 0.2794)
			(end 0.12065 0.3048)
			(stroke
				(width 0.1)
				(type default)
			)
			(layer "B.Fab")
		)
		(fp_line
			(start -0.12065 -0.2794)
			(end -0.12065 -0.3048)
			(stroke
				(width 0.1)
				(type default)
			)
			(layer "B.Fab")
		)
		(fp_line
			(start 0.12065 -0.2794)
			(end -0.12065 -0.2794)
			(stroke
				(width 0.1)
				(type default)
			)
			(layer "B.Fab")
		)
		(fp_line
			(start -0.67945 -0.3048)
			(end -0.67945 0.3048)
			(stroke
				(width 0.1)
				(type default)
			)
			(layer "B.Fab")
		)
		(fp_line
			(start -0.12065 -0.3048)
			(end -0.67945 -0.3048)
			(stroke
				(width 0.1)
				(type default)
			)
			(layer "B.Fab")
		)
		(fp_line
			(start 0.12065 -0.305054)
			(end 0.12065 -0.2794)
			(stroke
				(width 0.1)
				(type default)
			)
			(layer "B.Fab")
		)
		(fp_line
			(start 0.67945 -0.305054)
			(end 0.12065 -0.305054)
			(stroke
				(width 0.1)
				(type default)
			)
			(layer "B.Fab")
		)
		(pad "1" smd circle
			(at 0.40005 0 90)
			(size 0 0)
			(layers "B.Cu" "B.Mask" "B.Paste")
			(net "SMB_OCP_SFF_3V3AUX_SDA")
		)
		(pad "2" smd circle
			(at -0.40005 0 90)
			(size 0 0)
			(layers "B.Cu" "B.Mask" "B.Paste")
			(net "P3V3_AUX")
		)
	)
	(footprint ""
		(layer "B.Cu")
		(at 290.68268 -352.95332 90)
		(property "Reference" "PC7000"
			(at 0 0 90)
			(layer "B.SilkS")
			(hide yes)
			(effects
				(font
					(size 1.27 1.27)
				)
				(justify mirror)
			)
		)
		(property "Value" ""
			(at 0 0 90)
			(layer "B.Fab")
			(effects
				(font
					(size 1.27 1.27)
				)
				(justify mirror)
			)
		)
		(duplicate_pad_numbers_are_jumpers no)
		(fp_line
			(start 1.524 -0.762)
			(end -1.524 -0.762)
			(stroke
				(width 0.1524)
				(type default)
			)
			(layer "B.SilkS")
		)
		(fp_line
			(start -1.524 -0.762)
			(end -1.524 0.762)
			(stroke
				(width 0.1524)
				(type default)
			)
			(layer "B.SilkS")
		)
		(fp_line
			(start 1.524 0.762)
			(end 1.524 -0.762)
			(stroke
				(width 0.1524)
				(type default)
			)
			(layer "B.SilkS")
		)
		(fp_line
			(start -1.524 0.762)
			(end 1.524 0.762)
			(stroke
				(width 0.1524)
				(type default)
			)
			(layer "B.SilkS")
		)
		(fp_line
			(start 1.1049 -0.724916)
			(end 1.1049 0.724916)
			(stroke
				(width 0.1)
				(type default)
			)
			(layer "B.Fab")
		)
		(fp_line
			(start -1.1049 -0.724916)
			(end 1.1049 -0.724916)
			(stroke
				(width 0.1)
				(type default)
			)
			(layer "B.Fab")
		)
		(fp_line
			(start 1.1049 0.724916)
			(end -1.1049 0.724916)
			(stroke
				(width 0.1)
				(type default)
			)
			(layer "B.Fab")
		)
		(fp_line
			(start -1.1049 0.724916)
			(end -1.1049 -0.724916)
			(stroke
				(width 0.1)
				(type default)
			)
			(layer "B.Fab")
		)
		(pad "1" smd rect
			(at 0.889 0 90)
			(size 1.016 1.27)
			(layers "B.Cu" "B.Mask" "B.Paste")
			(net "SW_P12V_AUX_PVDDIO_P0_FLT")
		)
		(pad "2" smd rect
			(at -0.889 0 90)
			(size 1.016 1.27)
			(layers "B.Cu" "B.Mask" "B.Paste")
			(net "GND")
		)
	)
	(footprint ""
		(layer "B.Cu")
		(at 419.98265 -353.78009 -90)
		(property "Reference" "PR137"
			(at 0 0 90)
			(layer "B.SilkS")
			(hide yes)
			(effects
				(font
					(size 1.27 1.27)
				)
				(justify mirror)
			)
		)
		(property "Value" ""
			(at 0 0 90)
			(layer "B.Fab")
			(effects
				(font
					(size 1.27 1.27)
				)
				(justify mirror)
			)
		)
		(duplicate_pad_numbers_are_jumpers no)
		(fp_line
			(start -0.7874 0.4064)
			(end 0.7874 0.4064)
			(stroke
				(width 0.1524)
				(type default)
			)
			(layer "B.SilkS")
		)
		(fp_line
			(start 0.7874 0.4064)
			(end 0.7874 -0.4064)
			(stroke
				(width 0.1524)
				(type default)
			)
			(layer "B.SilkS")
		)
		(fp_line
			(start -0.7874 -0.4064)
			(end -0.7874 0.4064)
			(stroke
				(width 0.1524)
				(type default)
			)
			(layer "B.SilkS")
		)
		(fp_line
			(start 0.7874 -0.4064)
			(end -0.7874 -0.4064)
			(stroke
				(width 0.1524)
				(type default)
			)
			(layer "B.SilkS")
		)
		(fp_line
			(start -0.67945 0.3048)
			(end -0.120396 0.3048)
			(stroke
				(width 0.1)
				(type default)
			)
			(layer "B.Fab")
		)
		(fp_line
			(start -0.120396 0.3048)
			(end -0.120396 0.2794)
			(stroke
				(width 0.1)
				(type default)
			)
			(layer "B.Fab")
		)
		(fp_line
			(start 0.12065 0.3048)
			(end 0.67945 0.3048)
			(stroke
				(width 0.1)
				(type default)
			)
			(layer "B.Fab")
		)
		(fp_line
			(start 0.67945 0.3048)
			(end 0.67945 -0.305054)
			(stroke
				(width 0.1)
				(type default)
			)
			(layer "B.Fab")
		)
		(fp_line
			(start -0.120396 0.2794)
			(end 0.12065 0.2794)
			(stroke
				(width 0.1)
				(type default)
			)
			(layer "B.Fab")
		)
		(fp_line
			(start 0.12065 0.2794)
			(end 0.12065 0.3048)
			(stroke
				(width 0.1)
				(type default)
			)
			(layer "B.Fab")
		)
		(fp_line
			(start -0.12065 -0.2794)
			(end -0.12065 -0.3048)
			(stroke
				(width 0.1)
				(type default)
			)
			(layer "B.Fab")
		)
		(fp_line
			(start 0.12065 -0.2794)
			(end -0.12065 -0.2794)
			(stroke
				(width 0.1)
				(type default)
			)
			(layer "B.Fab")
		)
		(fp_line
			(start -0.67945 -0.3048)
			(end -0.67945 0.3048)
			(stroke
				(width 0.1)
				(type default)
			)
			(layer "B.Fab")
		)
		(fp_line
			(start -0.12065 -0.3048)
			(end -0.67945 -0.3048)
			(stroke
				(width 0.1)
				(type default)
			)
			(layer "B.Fab")
		)
		(fp_line
			(start 0.12065 -0.305054)
			(end 0.12065 -0.2794)
			(stroke
				(width 0.1)
				(type default)
			)
			(layer "B.Fab")
		)
		(fp_line
			(start 0.67945 -0.305054)
			(end 0.12065 -0.305054)
			(stroke
				(width 0.1)
				(type default)
			)
			(layer "B.Fab")
		)
		(pad "1" smd circle
			(at 0.40005 0 90)
			(size 0 0)
			(layers "B.Cu" "B.Mask" "B.Paste")
			(net "PVDD11_S3_P0_VOS1")
		)
		(pad "2" smd circle
			(at -0.40005 0 90)
			(size 0 0)
			(layers "B.Cu" "B.Mask" "B.Paste")
			(net "PVDD11_S3_P0")
		)
	)
	(footprint ""
		(layer "B.Cu")
		(at 346.036646 -416.899344 90)
		(property "Reference" "C6559"
			(at 0 0 90)
			(layer "B.SilkS")
			(hide yes)
			(effects
				(font
					(size 1.27 1.27)
				)
				(justify mirror)
			)
		)
		(property "Value" ""
			(at 0 0 90)
			(layer "B.Fab")
			(effects
				(font
					(size 1.27 1.27)
				)
				(justify mirror)
			)
		)
		(duplicate_pad_numbers_are_jumpers no)
		(fp_line
			(start 0.299974 -0.150114)
			(end -0.299974 -0.150114)
			(stroke
				(width 0.1)
				(type default)
			)
			(layer "B.Fab")
		)
		(fp_line
			(start -0.299974 -0.150114)
			(end -0.299974 0.150114)
			(stroke
				(width 0.1)
				(type default)
			)
			(layer "B.Fab")
		)
		(fp_line
			(start 0.299974 0.150114)
			(end 0.299974 -0.150114)
			(stroke
				(width 0.1)
				(type default)
			)
			(layer "B.Fab")
		)
		(fp_line
			(start -0.299974 0.150114)
			(end 0.299974 0.150114)
			(stroke
				(width 0.1)
				(type default)
			)
			(layer "B.Fab")
		)
		(pad "1" smd rect
			(at 0.2667 0 270)
			(size 0.3048 0.381)
			(layers "B.Cu" "B.Mask" "B.Paste")
			(net "P5E_CPU0_P1_TX_BUF_C_DP<13>")
		)
		(pad "2" smd rect
			(at -0.2667 0 270)
			(size 0.3048 0.381)
			(layers "B.Cu" "B.Mask" "B.Paste")
			(net "P5E_CPU0_P1_TX_BUF_DP<13>")
		)
	)
	(footprint ""
		(layer "B.Cu")
		(at 115.93322 -267.529564)
		(property "Reference" "C2352"
			(at 0 0 0)
			(layer "B.SilkS")
			(hide yes)
			(effects
				(font
					(size 1.27 1.27)
				)
				(justify mirror)
			)
		)
		(property "Value" ""
			(at 0 0 0)
			(layer "B.Fab")
			(effects
				(font
					(size 1.27 1.27)
				)
				(justify mirror)
			)
		)
		(duplicate_pad_numbers_are_jumpers no)
		(fp_line
			(start -0.7874 -0.4064)
			(end -0.7874 0.4064)
			(stroke
				(width 0.1524)
				(type default)
			)
			(layer "B.SilkS")
		)
		(fp_line
			(start -0.7874 0.4064)
			(end 0.7874 0.4064)
			(stroke
				(width 0.1524)
				(type default)
			)
			(layer "B.SilkS")
		)
		(fp_line
			(start 0.7874 -0.4064)
			(end -0.7874 -0.4064)
			(stroke
				(width 0.1524)
				(type default)
			)
			(layer "B.SilkS")
		)
		(fp_line
			(start 0.7874 0.4064)
			(end 0.7874 -0.4064)
			(stroke
				(width 0.1524)
				(type default)
			)
			(layer "B.SilkS")
		)
		(fp_line
			(start -0.67945 -0.3048)
			(end -0.67945 0.3048)
			(stroke
				(width 0.1)
				(type default)
			)
			(layer "B.Fab")
		)
		(fp_line
			(start -0.67945 0.3048)
			(end -0.120396 0.3048)
			(stroke
				(width 0.1)
				(type default)
			)
			(layer "B.Fab")
		)
		(fp_line
			(start -0.12065 -0.3048)
			(end -0.67945 -0.3048)
			(stroke
				(width 0.1)
				(type default)
			)
			(layer "B.Fab")
		)
		(fp_line
			(start -0.12065 -0.2794)
			(end -0.12065 -0.3048)
			(stroke
				(width 0.1)
				(type default)
			)
			(layer "B.Fab")
		)
		(fp_line
			(start -0.120396 0.2794)
			(end 0.12065 0.2794)
			(stroke
				(width 0.1)
				(type default)
			)
			(layer "B.Fab")
		)
		(fp_line
			(start -0.120396 0.3048)
			(end -0.120396 0.2794)
			(stroke
				(width 0.1)
				(type default)
			)
			(layer "B.Fab")
		)
		(fp_line
			(start 0.12065 -0.305054)
			(end 0.12065 -0.2794)
			(stroke
				(width 0.1)
				(type default)
			)
			(layer "B.Fab")
		)
		(fp_line
			(start 0.12065 -0.2794)
			(end -0.12065 -0.2794)
			(stroke
				(width 0.1)
				(type default)
			)
			(layer "B.Fab")
		)
		(fp_line
			(start 0.12065 0.2794)
			(end 0.12065 0.3048)
			(stroke
				(width 0.1)
				(type default)
			)
			(layer "B.Fab")
		)
		(fp_line
			(start 0.12065 0.3048)
			(end 0.67945 0.3048)
			(stroke
				(width 0.1)
				(type default)
			)
			(layer "B.Fab")
		)
		(fp_line
			(start 0.67945 -0.305054)
			(end 0.12065 -0.305054)
			(stroke
				(width 0.1)
				(type default)
			)
			(layer "B.Fab")
		)
		(fp_line
			(start 0.67945 0.3048)
			(end 0.67945 -0.305054)
			(stroke
				(width 0.1)
				(type default)
			)
			(layer "B.Fab")
		)
		(pad "1" smd circle
			(at 0.40005 0 180)
			(size 0 0)
			(layers "B.Cu" "B.Mask" "B.Paste")
			(net "PVDDCR_CPU1_P1")
		)
		(pad "2" smd circle
			(at -0.40005 0 180)
			(size 0 0)
			(layers "B.Cu" "B.Mask" "B.Paste")
			(net "GND")
		)
	)
	(footprint ""
		(layer "B.Cu")
		(at 167.936418 -349.716344)
		(property "Reference" "PR376"
			(at 0 0 0)
			(layer "B.SilkS")
			(hide yes)
			(effects
				(font
					(size 1.27 1.27)
				)
				(justify mirror)
			)
		)
		(property "Value" ""
			(at 0 0 0)
			(layer "B.Fab")
			(effects
				(font
					(size 1.27 1.27)
				)
				(justify mirror)
			)
		)
		(duplicate_pad_numbers_are_jumpers no)
		(fp_line
			(start -0.7874 -0.4064)
			(end -0.7874 0.4064)
			(stroke
				(width 0.1524)
				(type default)
			)
			(layer "B.SilkS")
		)
		(fp_line
			(start -0.7874 0.4064)
			(end 0.7874 0.4064)
			(stroke
				(width 0.1524)
				(type default)
			)
			(layer "B.SilkS")
		)
		(fp_line
			(start 0.7874 -0.4064)
			(end -0.7874 -0.4064)
			(stroke
				(width 0.1524)
				(type default)
			)
			(layer "B.SilkS")
		)
		(fp_line
			(start 0.7874 0.4064)
			(end 0.7874 -0.4064)
			(stroke
				(width 0.1524)
				(type default)
			)
			(layer "B.SilkS")
		)
		(fp_line
			(start -0.67945 -0.3048)
			(end -0.67945 0.3048)
			(stroke
				(width 0.1)
				(type default)
			)
			(layer "B.Fab")
		)
		(fp_line
			(start -0.67945 0.3048)
			(end -0.120396 0.3048)
			(stroke
				(width 0.1)
				(type default)
			)
			(layer "B.Fab")
		)
		(fp_line
			(start -0.12065 -0.3048)
			(end -0.67945 -0.3048)
			(stroke
				(width 0.1)
				(type default)
			)
			(layer "B.Fab")
		)
		(fp_line
			(start -0.12065 -0.2794)
			(end -0.12065 -0.3048)
			(stroke
				(width 0.1)
				(type default)
			)
			(layer "B.Fab")
		)
		(fp_line
			(start -0.120396 0.2794)
			(end 0.12065 0.2794)
			(stroke
				(width 0.1)
				(type default)
			)
			(layer "B.Fab")
		)
		(fp_line
			(start -0.120396 0.3048)
			(end -0.120396 0.2794)
			(stroke
				(width 0.1)
				(type default)
			)
			(layer "B.Fab")
		)
		(fp_line
			(start 0.12065 -0.305054)
			(end 0.12065 -0.2794)
			(stroke
				(width 0.1)
				(type default)
			)
			(layer "B.Fab")
		)
		(fp_line
			(start 0.12065 -0.2794)
			(end -0.12065 -0.2794)
			(stroke
				(width 0.1)
				(type default)
			)
			(layer "B.Fab")
		)
		(fp_line
			(start 0.12065 0.2794)
			(end 0.12065 0.3048)
			(stroke
				(width 0.1)
				(type default)
			)
			(layer "B.Fab")
		)
		(fp_line
			(start 0.12065 0.3048)
			(end 0.67945 0.3048)
			(stroke
				(width 0.1)
				(type default)
			)
			(layer "B.Fab")
		)
		(fp_line
			(start 0.67945 -0.305054)
			(end 0.12065 -0.305054)
			(stroke
				(width 0.1)
				(type default)
			)
			(layer "B.Fab")
		)
		(fp_line
			(start 0.67945 0.3048)
			(end 0.67945 -0.305054)
			(stroke
				(width 0.1)
				(type default)
			)
			(layer "B.Fab")
		)
		(pad "1" smd circle
			(at 0.40005 0 180)
			(size 0 0)
			(layers "B.Cu" "B.Mask" "B.Paste")
			(net "P5V_AUX")
		)
		(pad "2" smd circle
			(at -0.40005 0 180)
			(size 0 0)
			(layers "B.Cu" "B.Mask" "B.Paste")
			(net "PVDD11_S3_P1_VMON")
		)
	)
	(footprint ""
		(layer "B.Cu")
		(at 154.577288 -9.48055 90)
		(property "Reference" "R6068"
			(at 0 0 90)
			(layer "B.SilkS")
			(hide yes)
			(effects
				(font
					(size 1.27 1.27)
				)
				(justify mirror)
			)
		)
		(property "Value" ""
			(at 0 0 90)
			(layer "B.Fab")
			(effects
				(font
					(size 1.27 1.27)
				)
				(justify mirror)
			)
		)
		(duplicate_pad_numbers_are_jumpers no)
		(fp_line
			(start 0.7874 -0.4064)
			(end -0.7874 -0.4064)
			(stroke
				(width 0.1524)
				(type default)
			)
			(layer "B.SilkS")
		)
		(fp_line
			(start -0.7874 -0.4064)
			(end -0.7874 0.4064)
			(stroke
				(width 0.1524)
				(type default)
			)
			(layer "B.SilkS")
		)
		(fp_line
			(start 0.7874 0.4064)
			(end 0.7874 -0.4064)
			(stroke
				(width 0.1524)
				(type default)
			)
			(layer "B.SilkS")
		)
		(fp_line
			(start -0.7874 0.4064)
			(end 0.7874 0.4064)
			(stroke
				(width 0.1524)
				(type default)
			)
			(layer "B.SilkS")
		)
		(fp_line
			(start 0.67945 -0.305054)
			(end 0.12065 -0.305054)
			(stroke
				(width 0.1)
				(type default)
			)
			(layer "B.Fab")
		)
		(fp_line
			(start 0.12065 -0.305054)
			(end 0.12065 -0.2794)
			(stroke
				(width 0.1)
				(type default)
			)
			(layer "B.Fab")
		)
		(fp_line
			(start -0.12065 -0.3048)
			(end -0.67945 -0.3048)
			(stroke
				(width 0.1)
				(type default)
			)
			(layer "B.Fab")
		)
		(fp_line
			(start -0.67945 -0.3048)
			(end -0.67945 0.3048)
			(stroke
				(width 0.1)
				(type default)
			)
			(layer "B.Fab")
		)
		(fp_line
			(start 0.12065 -0.2794)
			(end -0.12065 -0.2794)
			(stroke
				(width 0.1)
				(type default)
			)
			(layer "B.Fab")
		)
		(fp_line
			(start -0.12065 -0.2794)
			(end -0.12065 -0.3048)
			(stroke
				(width 0.1)
				(type default)
			)
			(layer "B.Fab")
		)
		(fp_line
			(start 0.12065 0.2794)
			(end 0.12065 0.3048)
			(stroke
				(width 0.1)
				(type default)
			)
			(layer "B.Fab")
		)
		(fp_line
			(start -0.120396 0.2794)
			(end 0.12065 0.2794)
			(stroke
				(width 0.1)
				(type default)
			)
			(layer "B.Fab")
		)
		(fp_line
			(start 0.67945 0.3048)
			(end 0.67945 -0.305054)
			(stroke
				(width 0.1)
				(type default)
			)
			(layer "B.Fab")
		)
		(fp_line
			(start 0.12065 0.3048)
			(end 0.67945 0.3048)
			(stroke
				(width 0.1)
				(type default)
			)
			(layer "B.Fab")
		)
		(fp_line
			(start -0.120396 0.3048)
			(end -0.120396 0.2794)
			(stroke
				(width 0.1)
				(type default)
			)
			(layer "B.Fab")
		)
		(fp_line
			(start -0.67945 0.3048)
			(end -0.120396 0.3048)
			(stroke
				(width 0.1)
				(type default)
			)
			(layer "B.Fab")
		)
		(pad "1" smd rect
			(at 0.40005 0 90)
			(size 0.4572 0.508)
			(layers "B.Cu" "B.Mask" "B.Paste")
			(net "JTAG_SCM_TDO_R")
		)
		(pad "2" smd rect
			(at -0.40005 0 90)
			(size 0.4572 0.508)
			(layers "B.Cu" "B.Mask" "B.Paste")
			(net "JTAG_SCM_TDO")
		)
	)
	(footprint ""
		(layer "B.Cu")
		(at 102.73538 -180.027834 90)
		(property "Reference" "PR199"
			(at 0 0 90)
			(layer "B.SilkS")
			(hide yes)
			(effects
				(font
					(size 1.27 1.27)
				)
				(justify mirror)
			)
		)
		(property "Value" ""
			(at 0 0 90)
			(layer "B.Fab")
			(effects
				(font
					(size 1.27 1.27)
				)
				(justify mirror)
			)
		)
		(duplicate_pad_numbers_are_jumpers no)
		(fp_line
			(start 0.7874 -0.4064)
			(end -0.7874 -0.4064)
			(stroke
				(width 0.1524)
				(type default)
			)
			(layer "B.SilkS")
		)
		(fp_line
			(start -0.7874 -0.4064)
			(end -0.7874 0.4064)
			(stroke
				(width 0.1524)
				(type default)
			)
			(layer "B.SilkS")
		)
		(fp_line
			(start 0.7874 0.4064)
			(end 0.7874 -0.4064)
			(stroke
				(width 0.1524)
				(type default)
			)
			(layer "B.SilkS")
		)
		(fp_line
			(start -0.7874 0.4064)
			(end 0.7874 0.4064)
			(stroke
				(width 0.1524)
				(type default)
			)
			(layer "B.SilkS")
		)
		(fp_line
			(start 0.67945 -0.305054)
			(end 0.12065 -0.305054)
			(stroke
				(width 0.1)
				(type default)
			)
			(layer "B.Fab")
		)
		(fp_line
			(start 0.12065 -0.305054)
			(end 0.12065 -0.2794)
			(stroke
				(width 0.1)
				(type default)
			)
			(layer "B.Fab")
		)
		(fp_line
			(start -0.12065 -0.3048)
			(end -0.67945 -0.3048)
			(stroke
				(width 0.1)
				(type default)
			)
			(layer "B.Fab")
		)
		(fp_line
			(start -0.67945 -0.3048)
			(end -0.67945 0.3048)
			(stroke
				(width 0.1)
				(type default)
			)
			(layer "B.Fab")
		)
		(fp_line
			(start 0.12065 -0.2794)
			(end -0.12065 -0.2794)
			(stroke
				(width 0.1)
				(type default)
			)
			(layer "B.Fab")
		)
		(fp_line
			(start -0.12065 -0.2794)
			(end -0.12065 -0.3048)
			(stroke
				(width 0.1)
				(type default)
			)
			(layer "B.Fab")
		)
		(fp_line
			(start 0.12065 0.2794)
			(end 0.12065 0.3048)
			(stroke
				(width 0.1)
				(type default)
			)
			(layer "B.Fab")
		)
		(fp_line
			(start -0.120396 0.2794)
			(end 0.12065 0.2794)
			(stroke
				(width 0.1)
				(type default)
			)
			(layer "B.Fab")
		)
		(fp_line
			(start 0.67945 0.3048)
			(end 0.67945 -0.305054)
			(stroke
				(width 0.1)
				(type default)
			)
			(layer "B.Fab")
		)
		(fp_line
			(start 0.12065 0.3048)
			(end 0.67945 0.3048)
			(stroke
				(width 0.1)
				(type default)
			)
			(layer "B.Fab")
		)
		(fp_line
			(start -0.120396 0.3048)
			(end -0.120396 0.2794)
			(stroke
				(width 0.1)
				(type default)
			)
			(layer "B.Fab")
		)
		(fp_line
			(start -0.67945 0.3048)
			(end -0.120396 0.3048)
			(stroke
				(width 0.1)
				(type default)
			)
			(layer "B.Fab")
		)
		(pad "1" smd circle
			(at 0.40005 0 270)
			(size 0 0)
			(layers "B.Cu" "B.Mask" "B.Paste")
			(net "PVDDCR_CPU0_P1_VOS3")
		)
		(pad "2" smd circle
			(at -0.40005 0 270)
			(size 0 0)
			(layers "B.Cu" "B.Mask" "B.Paste")
			(net "PVDDCR_CPU0_P1")
		)
	)
	(footprint ""
		(layer "B.Cu")
		(at 53.378608 -386.766562 90)
		(property "Reference" "C139"
			(at 0 0 90)
			(layer "B.SilkS")
			(hide yes)
			(effects
				(font
					(size 1.27 1.27)
				)
				(justify mirror)
			)
		)
		(property "Value" ""
			(at 0 0 90)
			(layer "B.Fab")
			(effects
				(font
					(size 1.27 1.27)
				)
				(justify mirror)
			)
		)
		(duplicate_pad_numbers_are_jumpers no)
		(fp_line
			(start 0.299974 -0.150114)
			(end -0.299974 -0.150114)
			(stroke
				(width 0.1)
				(type default)
			)
			(layer "B.Fab")
		)
		(fp_line
			(start -0.299974 -0.150114)
			(end -0.299974 0.150114)
			(stroke
				(width 0.1)
				(type default)
			)
			(layer "B.Fab")
		)
		(fp_line
			(start 0.299974 0.150114)
			(end 0.299974 -0.150114)
			(stroke
				(width 0.1)
				(type default)
			)
			(layer "B.Fab")
		)
		(fp_line
			(start -0.299974 0.150114)
			(end 0.299974 0.150114)
			(stroke
				(width 0.1)
				(type default)
			)
			(layer "B.Fab")
		)
		(pad "1" smd rect
			(at 0.2667 0 270)
			(size 0.3048 0.381)
			(layers "B.Cu" "B.Mask" "B.Paste")
			(net "P0V9_CPU1_RT_2D")
		)
		(pad "2" smd rect
			(at -0.2667 0 270)
			(size 0.3048 0.381)
			(layers "B.Cu" "B.Mask" "B.Paste")
			(net "GND")
		)
	)
	(footprint ""
		(layer "B.Cu")
		(at 365.835692 -259.355082)
		(property "Reference" "C2552"
			(at 0 0 0)
			(layer "B.SilkS")
			(hide yes)
			(effects
				(font
					(size 1.27 1.27)
				)
				(justify mirror)
			)
		)
		(property "Value" ""
			(at 0 0 0)
			(layer "B.Fab")
			(effects
				(font
					(size 1.27 1.27)
				)
				(justify mirror)
			)
		)
		(duplicate_pad_numbers_are_jumpers no)
		(fp_line
			(start -0.7874 -0.4064)
			(end -0.7874 0.4064)
			(stroke
				(width 0.1524)
				(type default)
			)
			(layer "B.SilkS")
		)
		(fp_line
			(start -0.7874 0.4064)
			(end 0.7874 0.4064)
			(stroke
				(width 0.1524)
				(type default)
			)
			(layer "B.SilkS")
		)
		(fp_line
			(start 0.7874 -0.4064)
			(end -0.7874 -0.4064)
			(stroke
				(width 0.1524)
				(type default)
			)
			(layer "B.SilkS")
		)
		(fp_line
			(start 0.7874 0.4064)
			(end 0.7874 -0.4064)
			(stroke
				(width 0.1524)
				(type default)
			)
			(layer "B.SilkS")
		)
		(fp_line
			(start -0.67945 -0.3048)
			(end -0.67945 0.3048)
			(stroke
				(width 0.1)
				(type default)
			)
			(layer "B.Fab")
		)
		(fp_line
			(start -0.67945 0.3048)
			(end -0.120396 0.3048)
			(stroke
				(width 0.1)
				(type default)
			)
			(layer "B.Fab")
		)
		(fp_line
			(start -0.12065 -0.3048)
			(end -0.67945 -0.3048)
			(stroke
				(width 0.1)
				(type default)
			)
			(layer "B.Fab")
		)
		(fp_line
			(start -0.12065 -0.2794)
			(end -0.12065 -0.3048)
			(stroke
				(width 0.1)
				(type default)
			)
			(layer "B.Fab")
		)
		(fp_line
			(start -0.120396 0.2794)
			(end 0.12065 0.2794)
			(stroke
				(width 0.1)
				(type default)
			)
			(layer "B.Fab")
		)
		(fp_line
			(start -0.120396 0.3048)
			(end -0.120396 0.2794)
			(stroke
				(width 0.1)
				(type default)
			)
			(layer "B.Fab")
		)
		(fp_line
			(start 0.12065 -0.305054)
			(end 0.12065 -0.2794)
			(stroke
				(width 0.1)
				(type default)
			)
			(layer "B.Fab")
		)
		(fp_line
			(start 0.12065 -0.2794)
			(end -0.12065 -0.2794)
			(stroke
				(width 0.1)
				(type default)
			)
			(layer "B.Fab")
		)
		(fp_line
			(start 0.12065 0.2794)
			(end 0.12065 0.3048)
			(stroke
				(width 0.1)
				(type default)
			)
			(layer "B.Fab")
		)
		(fp_line
			(start 0.12065 0.3048)
			(end 0.67945 0.3048)
			(stroke
				(width 0.1)
				(type default)
			)
			(layer "B.Fab")
		)
		(fp_line
			(start 0.67945 -0.305054)
			(end 0.12065 -0.305054)
			(stroke
				(width 0.1)
				(type default)
			)
			(layer "B.Fab")
		)
		(fp_line
			(start 0.67945 0.3048)
			(end 0.67945 -0.305054)
			(stroke
				(width 0.1)
				(type default)
			)
			(layer "B.Fab")
		)
		(pad "1" smd circle
			(at 0.40005 0 180)
			(size 0 0)
			(layers "B.Cu" "B.Mask" "B.Paste")
			(net "PVDDCR_SOC_P0")
		)
		(pad "2" smd circle
			(at -0.40005 0 180)
			(size 0 0)
			(layers "B.Cu" "B.Mask" "B.Paste")
			(net "GND")
		)
	)
	(footprint ""
		(layer "B.Cu")
		(at 438.344564 -195.859146 180)
		(property "Reference" "R1684"
			(at 0 0 0)
			(layer "B.SilkS")
			(hide yes)
			(effects
				(font
					(size 1.27 1.27)
				)
				(justify mirror)
			)
		)
		(property "Value" ""
			(at 0 0 0)
			(layer "B.Fab")
			(effects
				(font
					(size 1.27 1.27)
				)
				(justify mirror)
			)
		)
		(duplicate_pad_numbers_are_jumpers no)
		(fp_line
			(start 0.7874 0.4064)
			(end 0.7874 -0.4064)
			(stroke
				(width 0.1524)
				(type default)
			)
			(layer "B.SilkS")
		)
		(fp_line
			(start 0.7874 -0.4064)
			(end -0.7874 -0.4064)
			(stroke
				(width 0.1524)
				(type default)
			)
			(layer "B.SilkS")
		)
		(fp_line
			(start -0.7874 0.4064)
			(end 0.7874 0.4064)
			(stroke
				(width 0.1524)
				(type default)
			)
			(layer "B.SilkS")
		)
		(fp_line
			(start -0.7874 -0.4064)
			(end -0.7874 0.4064)
			(stroke
				(width 0.1524)
				(type default)
			)
			(layer "B.SilkS")
		)
		(fp_line
			(start 0.67945 0.3048)
			(end 0.67945 -0.305054)
			(stroke
				(width 0.1)
				(type default)
			)
			(layer "B.Fab")
		)
		(fp_line
			(start 0.67945 -0.305054)
			(end 0.12065 -0.305054)
			(stroke
				(width 0.1)
				(type default)
			)
			(layer "B.Fab")
		)
		(fp_line
			(start 0.12065 0.3048)
			(end 0.67945 0.3048)
			(stroke
				(width 0.1)
				(type default)
			)
			(layer "B.Fab")
		)
		(fp_line
			(start 0.12065 0.2794)
			(end 0.12065 0.3048)
			(stroke
				(width 0.1)
				(type default)
			)
			(layer "B.Fab")
		)
		(fp_line
			(start 0.12065 -0.2794)
			(end -0.12065 -0.2794)
			(stroke
				(width 0.1)
				(type default)
			)
			(layer "B.Fab")
		)
		(fp_line
			(start 0.12065 -0.305054)
			(end 0.12065 -0.2794)
			(stroke
				(width 0.1)
				(type default)
			)
			(layer "B.Fab")
		)
		(fp_line
			(start -0.120396 0.3048)
			(end -0.120396 0.2794)
			(stroke
				(width 0.1)
				(type default)
			)
			(layer "B.Fab")
		)
		(fp_line
			(start -0.120396 0.2794)
			(end 0.12065 0.2794)
			(stroke
				(width 0.1)
				(type default)
			)
			(layer "B.Fab")
		)
		(fp_line
			(start -0.12065 -0.2794)
			(end -0.12065 -0.3048)
			(stroke
				(width 0.1)
				(type default)
			)
			(layer "B.Fab")
		)
		(fp_line
			(start -0.12065 -0.3048)
			(end -0.67945 -0.3048)
			(stroke
				(width 0.1)
				(type default)
			)
			(layer "B.Fab")
		)
		(fp_line
			(start -0.67945 0.3048)
			(end -0.120396 0.3048)
			(stroke
				(width 0.1)
				(type default)
			)
			(layer "B.Fab")
		)
		(fp_line
			(start -0.67945 -0.3048)
			(end -0.67945 0.3048)
			(stroke
				(width 0.1)
				(type default)
			)
			(layer "B.Fab")
		)
		(pad "1" smd circle
			(at 0.40005 0)
			(size 0 0)
			(layers "B.Cu" "B.Mask" "B.Paste")
			(net "I3C_SPD_DDRGL_CPU0_SDA")
		)
		(pad "2" smd circle
			(at -0.40005 0)
			(size 0 0)
			(layers "B.Cu" "B.Mask" "B.Paste")
			(net "I3C_SPD_DDRJ_CPU0_SDA")
		)
	)
	(footprint ""
		(layer "B.Cu")
		(at 231.8512 -327.21169 180)
		(property "Reference" "R1248"
			(at 0 0 0)
			(layer "B.SilkS")
			(hide yes)
			(effects
				(font
					(size 1.27 1.27)
				)
				(justify mirror)
			)
		)
		(property "Value" ""
			(at 0 0 0)
			(layer "B.Fab")
			(effects
				(font
					(size 1.27 1.27)
				)
				(justify mirror)
			)
		)
		(duplicate_pad_numbers_are_jumpers no)
		(fp_line
			(start 0.7874 0.4064)
			(end 0.7874 -0.4064)
			(stroke
				(width 0.1524)
				(type default)
			)
			(layer "B.SilkS")
		)
		(fp_line
			(start 0.7874 -0.4064)
			(end -0.7874 -0.4064)
			(stroke
				(width 0.1524)
				(type default)
			)
			(layer "B.SilkS")
		)
		(fp_line
			(start -0.7874 0.4064)
			(end 0.7874 0.4064)
			(stroke
				(width 0.1524)
				(type default)
			)
			(layer "B.SilkS")
		)
		(fp_line
			(start -0.7874 -0.4064)
			(end -0.7874 0.4064)
			(stroke
				(width 0.1524)
				(type default)
			)
			(layer "B.SilkS")
		)
		(fp_line
			(start 0.67945 0.3048)
			(end 0.67945 -0.305054)
			(stroke
				(width 0.1)
				(type default)
			)
			(layer "B.Fab")
		)
		(fp_line
			(start 0.67945 -0.305054)
			(end 0.12065 -0.305054)
			(stroke
				(width 0.1)
				(type default)
			)
			(layer "B.Fab")
		)
		(fp_line
			(start 0.12065 0.3048)
			(end 0.67945 0.3048)
			(stroke
				(width 0.1)
				(type default)
			)
			(layer "B.Fab")
		)
		(fp_line
			(start 0.12065 0.2794)
			(end 0.12065 0.3048)
			(stroke
				(width 0.1)
				(type default)
			)
			(layer "B.Fab")
		)
		(fp_line
			(start 0.12065 -0.2794)
			(end -0.12065 -0.2794)
			(stroke
				(width 0.1)
				(type default)
			)
			(layer "B.Fab")
		)
		(fp_line
			(start 0.12065 -0.305054)
			(end 0.12065 -0.2794)
			(stroke
				(width 0.1)
				(type default)
			)
			(layer "B.Fab")
		)
		(fp_line
			(start -0.120396 0.3048)
			(end -0.120396 0.2794)
			(stroke
				(width 0.1)
				(type default)
			)
			(layer "B.Fab")
		)
		(fp_line
			(start -0.120396 0.2794)
			(end 0.12065 0.2794)
			(stroke
				(width 0.1)
				(type default)
			)
			(layer "B.Fab")
		)
		(fp_line
			(start -0.12065 -0.2794)
			(end -0.12065 -0.3048)
			(stroke
				(width 0.1)
				(type default)
			)
			(layer "B.Fab")
		)
		(fp_line
			(start -0.12065 -0.3048)
			(end -0.67945 -0.3048)
			(stroke
				(width 0.1)
				(type default)
			)
			(layer "B.Fab")
		)
		(fp_line
			(start -0.67945 0.3048)
			(end -0.120396 0.3048)
			(stroke
				(width 0.1)
				(type default)
			)
			(layer "B.Fab")
		)
		(fp_line
			(start -0.67945 -0.3048)
			(end -0.67945 0.3048)
			(stroke
				(width 0.1)
				(type default)
			)
			(layer "B.Fab")
		)
		(pad "1" smd rect
			(at 0.40005 0 180)
			(size 0.4572 0.508)
			(layers "B.Cu" "B.Mask" "B.Paste")
			(net "PVDD_33_S5_ADC")
		)
		(pad "2" smd rect
			(at -0.40005 0 180)
			(size 0.4572 0.508)
			(layers "B.Cu" "B.Mask" "B.Paste")
			(net "PVDD_33_S5_ADC_MAM")
		)
	)
	(footprint ""
		(layer "B.Cu")
		(at 368.701828 -390.078722)
		(property "Reference" "C7019"
			(at 0 0 0)
			(layer "B.SilkS")
			(hide yes)
			(effects
				(font
					(size 1.27 1.27)
				)
				(justify mirror)
			)
		)
		(property "Value" ""
			(at 0 0 0)
			(layer "B.Fab")
			(effects
				(font
					(size 1.27 1.27)
				)
				(justify mirror)
			)
		)
		(duplicate_pad_numbers_are_jumpers no)
		(fp_line
			(start -1.524 -0.762)
			(end -1.524 0.762)
			(stroke
				(width 0.1524)
				(type default)
			)
			(layer "B.SilkS")
		)
		(fp_line
			(start -1.524 0.762)
			(end 1.524 0.762)
			(stroke
				(width 0.1524)
				(type default)
			)
			(layer "B.SilkS")
		)
		(fp_line
			(start 1.524 -0.762)
			(end -1.524 -0.762)
			(stroke
				(width 0.1524)
				(type default)
			)
			(layer "B.SilkS")
		)
		(fp_line
			(start 1.524 0.762)
			(end 1.524 -0.762)
			(stroke
				(width 0.1524)
				(type default)
			)
			(layer "B.SilkS")
		)
		(fp_line
			(start -1.1049 -0.724916)
			(end 1.1049 -0.724916)
			(stroke
				(width 0.1)
				(type default)
			)
			(layer "B.Fab")
		)
		(fp_line
			(start -1.1049 0.724916)
			(end -1.1049 -0.724916)
			(stroke
				(width 0.1)
				(type default)
			)
			(layer "B.Fab")
		)
		(fp_line
			(start 1.1049 -0.724916)
			(end 1.1049 0.724916)
			(stroke
				(width 0.1)
				(type default)
			)
			(layer "B.Fab")
		)
		(fp_line
			(start 1.1049 0.724916)
			(end -1.1049 0.724916)
			(stroke
				(width 0.1)
				(type default)
			)
			(layer "B.Fab")
		)
		(pad "1" smd rect
			(at 0.889 0)
			(size 1.016 1.27)
			(layers "B.Cu" "B.Mask" "B.Paste")
			(net "P0V9_CPU0_RT3_2A")
		)
		(pad "2" smd rect
			(at -0.889 0)
			(size 1.016 1.27)
			(layers "B.Cu" "B.Mask" "B.Paste")
			(net "GND")
		)
	)
	(footprint ""
		(layer "B.Cu")
		(at 350.818958 -250.89231 180)
		(property "Reference" "C276"
			(at 0 0 0)
			(layer "B.SilkS")
			(hide yes)
			(effects
				(font
					(size 1.27 1.27)
				)
				(justify mirror)
			)
		)
		(property "Value" ""
			(at 0 0 0)
			(layer "B.Fab")
			(effects
				(font
					(size 1.27 1.27)
				)
				(justify mirror)
			)
		)
		(duplicate_pad_numbers_are_jumpers no)
		(fp_line
			(start 0.7874 0.4064)
			(end 0.7874 -0.4064)
			(stroke
				(width 0.1524)
				(type default)
			)
			(layer "B.SilkS")
		)
		(fp_line
			(start 0.7874 -0.4064)
			(end -0.7874 -0.4064)
			(stroke
				(width 0.1524)
				(type default)
			)
			(layer "B.SilkS")
		)
		(fp_line
			(start -0.7874 0.4064)
			(end 0.7874 0.4064)
			(stroke
				(width 0.1524)
				(type default)
			)
			(layer "B.SilkS")
		)
		(fp_line
			(start -0.7874 -0.4064)
			(end -0.7874 0.4064)
			(stroke
				(width 0.1524)
				(type default)
			)
			(layer "B.SilkS")
		)
		(fp_line
			(start 0.67945 0.3048)
			(end 0.67945 -0.305054)
			(stroke
				(width 0.1)
				(type default)
			)
			(layer "B.Fab")
		)
		(fp_line
			(start 0.67945 -0.305054)
			(end 0.12065 -0.305054)
			(stroke
				(width 0.1)
				(type default)
			)
			(layer "B.Fab")
		)
		(fp_line
			(start 0.12065 0.3048)
			(end 0.67945 0.3048)
			(stroke
				(width 0.1)
				(type default)
			)
			(layer "B.Fab")
		)
		(fp_line
			(start 0.12065 0.2794)
			(end 0.12065 0.3048)
			(stroke
				(width 0.1)
				(type default)
			)
			(layer "B.Fab")
		)
		(fp_line
			(start 0.12065 -0.2794)
			(end -0.12065 -0.2794)
			(stroke
				(width 0.1)
				(type default)
			)
			(layer "B.Fab")
		)
		(fp_line
			(start 0.12065 -0.305054)
			(end 0.12065 -0.2794)
			(stroke
				(width 0.1)
				(type default)
			)
			(layer "B.Fab")
		)
		(fp_line
			(start -0.120396 0.3048)
			(end -0.120396 0.2794)
			(stroke
				(width 0.1)
				(type default)
			)
			(layer "B.Fab")
		)
		(fp_line
			(start -0.120396 0.2794)
			(end 0.12065 0.2794)
			(stroke
				(width 0.1)
				(type default)
			)
			(layer "B.Fab")
		)
		(fp_line
			(start -0.12065 -0.2794)
			(end -0.12065 -0.3048)
			(stroke
				(width 0.1)
				(type default)
			)
			(layer "B.Fab")
		)
		(fp_line
			(start -0.12065 -0.3048)
			(end -0.67945 -0.3048)
			(stroke
				(width 0.1)
				(type default)
			)
			(layer "B.Fab")
		)
		(fp_line
			(start -0.67945 0.3048)
			(end -0.120396 0.3048)
			(stroke
				(width 0.1)
				(type default)
			)
			(layer "B.Fab")
		)
		(fp_line
			(start -0.67945 -0.3048)
			(end -0.67945 0.3048)
			(stroke
				(width 0.1)
				(type default)
			)
			(layer "B.Fab")
		)
		(pad "1" smd circle
			(at 0.40005 0)
			(size 0 0)
			(layers "B.Cu" "B.Mask" "B.Paste")
			(net "PVDDCR_CPU0_P0")
		)
		(pad "2" smd circle
			(at -0.40005 0)
			(size 0 0)
			(layers "B.Cu" "B.Mask" "B.Paste")
			(net "GND")
		)
	)
	(footprint ""
		(layer "B.Cu")
		(at 351.506028 -395.148562 90)
		(property "Reference" "C613"
			(at 0 0 90)
			(layer "B.SilkS")
			(hide yes)
			(effects
				(font
					(size 1.27 1.27)
				)
				(justify mirror)
			)
		)
		(property "Value" ""
			(at 0 0 90)
			(layer "B.Fab")
			(effects
				(font
					(size 1.27 1.27)
				)
				(justify mirror)
			)
		)
		(duplicate_pad_numbers_are_jumpers no)
		(fp_line
			(start 0.299974 -0.150114)
			(end -0.299974 -0.150114)
			(stroke
				(width 0.1)
				(type default)
			)
			(layer "B.Fab")
		)
		(fp_line
			(start -0.299974 -0.150114)
			(end -0.299974 0.150114)
			(stroke
				(width 0.1)
				(type default)
			)
			(layer "B.Fab")
		)
		(fp_line
			(start 0.299974 0.150114)
			(end 0.299974 -0.150114)
			(stroke
				(width 0.1)
				(type default)
			)
			(layer "B.Fab")
		)
		(fp_line
			(start -0.299974 0.150114)
			(end 0.299974 0.150114)
			(stroke
				(width 0.1)
				(type default)
			)
			(layer "B.Fab")
		)
		(pad "1" smd rect
			(at 0.2667 0 270)
			(size 0.3048 0.381)
			(layers "B.Cu" "B.Mask" "B.Paste")
			(net "P0V9_CPU0_RT1_2A")
		)
		(pad "2" smd rect
			(at -0.2667 0 270)
			(size 0.3048 0.381)
			(layers "B.Cu" "B.Mask" "B.Paste")
			(net "GND")
		)
	)
	(footprint ""
		(layer "B.Cu")
		(at 26.641298 -388.637272 90)
		(property "Reference" "PC6636_2"
			(at 0 0 90)
			(layer "B.SilkS")
			(hide yes)
			(effects
				(font
					(size 1.27 1.27)
				)
				(justify mirror)
			)
		)
		(property "Value" ""
			(at 0 0 90)
			(layer "B.Fab")
			(effects
				(font
					(size 1.27 1.27)
				)
				(justify mirror)
			)
		)
		(duplicate_pad_numbers_are_jumpers no)
		(fp_line
			(start 1.524 -0.762)
			(end -1.524 -0.762)
			(stroke
				(width 0.1524)
				(type default)
			)
			(layer "B.SilkS")
		)
		(fp_line
			(start -1.524 -0.762)
			(end -1.524 0.762)
			(stroke
				(width 0.1524)
				(type default)
			)
			(layer "B.SilkS")
		)
		(fp_line
			(start 1.524 0.762)
			(end 1.524 -0.762)
			(stroke
				(width 0.1524)
				(type default)
			)
			(layer "B.SilkS")
		)
		(fp_line
			(start -1.524 0.762)
			(end 1.524 0.762)
			(stroke
				(width 0.1524)
				(type default)
			)
			(layer "B.SilkS")
		)
		(fp_line
			(start 1.1049 -0.724916)
			(end 1.1049 0.724916)
			(stroke
				(width 0.1)
				(type default)
			)
			(layer "B.Fab")
		)
		(fp_line
			(start -1.1049 -0.724916)
			(end 1.1049 -0.724916)
			(stroke
				(width 0.1)
				(type default)
			)
			(layer "B.Fab")
		)
		(fp_line
			(start 1.1049 0.724916)
			(end -1.1049 0.724916)
			(stroke
				(width 0.1)
				(type default)
			)
			(layer "B.Fab")
		)
		(fp_line
			(start -1.1049 0.724916)
			(end -1.1049 -0.724916)
			(stroke
				(width 0.1)
				(type default)
			)
			(layer "B.Fab")
		)
		(pad "1" smd rect
			(at 0.889 0 90)
			(size 1.016 1.27)
			(layers "B.Cu" "B.Mask" "B.Paste")
			(net "SW_P12V_AUX_P0V9_RETIMER_CPU1_FLT")
		)
		(pad "2" smd rect
			(at -0.889 0 90)
			(size 1.016 1.27)
			(layers "B.Cu" "B.Mask" "B.Paste")
			(net "GND")
		)
	)
	(footprint ""
		(layer "B.Cu")
		(at 289.697414 -347.77553 -90)
		(property "Reference" "PR99"
			(at 0 0 90)
			(layer "B.SilkS")
			(hide yes)
			(effects
				(font
					(size 1.27 1.27)
				)
				(justify mirror)
			)
		)
		(property "Value" ""
			(at 0 0 90)
			(layer "B.Fab")
			(effects
				(font
					(size 1.27 1.27)
				)
				(justify mirror)
			)
		)
		(duplicate_pad_numbers_are_jumpers no)
		(fp_line
			(start -0.7874 0.4064)
			(end 0.7874 0.4064)
			(stroke
				(width 0.1524)
				(type default)
			)
			(layer "B.SilkS")
		)
		(fp_line
			(start 0.7874 0.4064)
			(end 0.7874 -0.4064)
			(stroke
				(width 0.1524)
				(type default)
			)
			(layer "B.SilkS")
		)
		(fp_line
			(start -0.7874 -0.4064)
			(end -0.7874 0.4064)
			(stroke
				(width 0.1524)
				(type default)
			)
			(layer "B.SilkS")
		)
		(fp_line
			(start 0.7874 -0.4064)
			(end -0.7874 -0.4064)
			(stroke
				(width 0.1524)
				(type default)
			)
			(layer "B.SilkS")
		)
		(fp_line
			(start -0.67945 0.3048)
			(end -0.120396 0.3048)
			(stroke
				(width 0.1)
				(type default)
			)
			(layer "B.Fab")
		)
		(fp_line
			(start -0.120396 0.3048)
			(end -0.120396 0.2794)
			(stroke
				(width 0.1)
				(type default)
			)
			(layer "B.Fab")
		)
		(fp_line
			(start 0.12065 0.3048)
			(end 0.67945 0.3048)
			(stroke
				(width 0.1)
				(type default)
			)
			(layer "B.Fab")
		)
		(fp_line
			(start 0.67945 0.3048)
			(end 0.67945 -0.305054)
			(stroke
				(width 0.1)
				(type default)
			)
			(layer "B.Fab")
		)
		(fp_line
			(start -0.120396 0.2794)
			(end 0.12065 0.2794)
			(stroke
				(width 0.1)
				(type default)
			)
			(layer "B.Fab")
		)
		(fp_line
			(start 0.12065 0.2794)
			(end 0.12065 0.3048)
			(stroke
				(width 0.1)
				(type default)
			)
			(layer "B.Fab")
		)
		(fp_line
			(start -0.12065 -0.2794)
			(end -0.12065 -0.3048)
			(stroke
				(width 0.1)
				(type default)
			)
			(layer "B.Fab")
		)
		(fp_line
			(start 0.12065 -0.2794)
			(end -0.12065 -0.2794)
			(stroke
				(width 0.1)
				(type default)
			)
			(layer "B.Fab")
		)
		(fp_line
			(start -0.67945 -0.3048)
			(end -0.67945 0.3048)
			(stroke
				(width 0.1)
				(type default)
			)
			(layer "B.Fab")
		)
		(fp_line
			(start -0.12065 -0.3048)
			(end -0.67945 -0.3048)
			(stroke
				(width 0.1)
				(type default)
			)
			(layer "B.Fab")
		)
		(fp_line
			(start 0.12065 -0.305054)
			(end 0.12065 -0.2794)
			(stroke
				(width 0.1)
				(type default)
			)
			(layer "B.Fab")
		)
		(fp_line
			(start 0.67945 -0.305054)
			(end 0.12065 -0.305054)
			(stroke
				(width 0.1)
				(type default)
			)
			(layer "B.Fab")
		)
		(pad "1" smd circle
			(at 0.40005 0 90)
			(size 0 0)
			(layers "B.Cu" "B.Mask" "B.Paste")
			(net "PVDDCR_CPU1_P0_PVCC")
		)
		(pad "2" smd circle
			(at -0.40005 0 90)
			(size 0 0)
			(layers "B.Cu" "B.Mask" "B.Paste")
			(net "PVDDIO_P0_VCC2")
		)
	)
	(footprint ""
		(layer "B.Cu")
		(at 144.727676 -388.609078 90)
		(property "Reference" "C393"
			(at 0 0 90)
			(layer "B.SilkS")
			(hide yes)
			(effects
				(font
					(size 1.27 1.27)
				)
				(justify mirror)
			)
		)
		(property "Value" ""
			(at 0 0 90)
			(layer "B.Fab")
			(effects
				(font
					(size 1.27 1.27)
				)
				(justify mirror)
			)
		)
		(duplicate_pad_numbers_are_jumpers no)
		(fp_line
			(start 0.299974 -0.150114)
			(end -0.299974 -0.150114)
			(stroke
				(width 0.1)
				(type default)
			)
			(layer "B.Fab")
		)
		(fp_line
			(start -0.299974 -0.150114)
			(end -0.299974 0.150114)
			(stroke
				(width 0.1)
				(type default)
			)
			(layer "B.Fab")
		)
		(fp_line
			(start 0.299974 0.150114)
			(end 0.299974 -0.150114)
			(stroke
				(width 0.1)
				(type default)
			)
			(layer "B.Fab")
		)
		(fp_line
			(start -0.299974 0.150114)
			(end 0.299974 0.150114)
			(stroke
				(width 0.1)
				(type default)
			)
			(layer "B.Fab")
		)
		(pad "1" smd rect
			(at 0.2667 0 270)
			(size 0.3048 0.381)
			(layers "B.Cu" "B.Mask" "B.Paste")
			(net "P0V9_CPU1_RT2_2A")
		)
		(pad "2" smd rect
			(at -0.2667 0 270)
			(size 0.3048 0.381)
			(layers "B.Cu" "B.Mask" "B.Paste")
			(net "GND")
		)
	)
	(footprint ""
		(layer "B.Cu")
		(at 100.881434 -254.067564 180)
		(property "Reference" "C2292"
			(at 0 0 0)
			(layer "B.SilkS")
			(hide yes)
			(effects
				(font
					(size 1.27 1.27)
				)
				(justify mirror)
			)
		)
		(property "Value" ""
			(at 0 0 0)
			(layer "B.Fab")
			(effects
				(font
					(size 1.27 1.27)
				)
				(justify mirror)
			)
		)
		(duplicate_pad_numbers_are_jumpers no)
		(fp_line
			(start 0.7874 0.4064)
			(end 0.7874 -0.4064)
			(stroke
				(width 0.1524)
				(type default)
			)
			(layer "B.SilkS")
		)
		(fp_line
			(start 0.7874 -0.4064)
			(end -0.7874 -0.4064)
			(stroke
				(width 0.1524)
				(type default)
			)
			(layer "B.SilkS")
		)
		(fp_line
			(start -0.7874 0.4064)
			(end 0.7874 0.4064)
			(stroke
				(width 0.1524)
				(type default)
			)
			(layer "B.SilkS")
		)
		(fp_line
			(start -0.7874 -0.4064)
			(end -0.7874 0.4064)
			(stroke
				(width 0.1524)
				(type default)
			)
			(layer "B.SilkS")
		)
		(fp_line
			(start 0.67945 0.3048)
			(end 0.67945 -0.305054)
			(stroke
				(width 0.1)
				(type default)
			)
			(layer "B.Fab")
		)
		(fp_line
			(start 0.67945 -0.305054)
			(end 0.12065 -0.305054)
			(stroke
				(width 0.1)
				(type default)
			)
			(layer "B.Fab")
		)
		(fp_line
			(start 0.12065 0.3048)
			(end 0.67945 0.3048)
			(stroke
				(width 0.1)
				(type default)
			)
			(layer "B.Fab")
		)
		(fp_line
			(start 0.12065 0.2794)
			(end 0.12065 0.3048)
			(stroke
				(width 0.1)
				(type default)
			)
			(layer "B.Fab")
		)
		(fp_line
			(start 0.12065 -0.2794)
			(end -0.12065 -0.2794)
			(stroke
				(width 0.1)
				(type default)
			)
			(layer "B.Fab")
		)
		(fp_line
			(start 0.12065 -0.305054)
			(end 0.12065 -0.2794)
			(stroke
				(width 0.1)
				(type default)
			)
			(layer "B.Fab")
		)
		(fp_line
			(start -0.120396 0.3048)
			(end -0.120396 0.2794)
			(stroke
				(width 0.1)
				(type default)
			)
			(layer "B.Fab")
		)
		(fp_line
			(start -0.120396 0.2794)
			(end 0.12065 0.2794)
			(stroke
				(width 0.1)
				(type default)
			)
			(layer "B.Fab")
		)
		(fp_line
			(start -0.12065 -0.2794)
			(end -0.12065 -0.3048)
			(stroke
				(width 0.1)
				(type default)
			)
			(layer "B.Fab")
		)
		(fp_line
			(start -0.12065 -0.3048)
			(end -0.67945 -0.3048)
			(stroke
				(width 0.1)
				(type default)
			)
			(layer "B.Fab")
		)
		(fp_line
			(start -0.67945 0.3048)
			(end -0.120396 0.3048)
			(stroke
				(width 0.1)
				(type default)
			)
			(layer "B.Fab")
		)
		(fp_line
			(start -0.67945 -0.3048)
			(end -0.67945 0.3048)
			(stroke
				(width 0.1)
				(type default)
			)
			(layer "B.Fab")
		)
		(pad "1" smd circle
			(at 0.40005 0)
			(size 0 0)
			(layers "B.Cu" "B.Mask" "B.Paste")
			(net "PVDD18_S5_P1")
		)
		(pad "2" smd circle
			(at -0.40005 0)
			(size 0 0)
			(layers "B.Cu" "B.Mask" "B.Paste")
			(net "GND")
		)
	)
	(footprint ""
		(layer "B.Cu")
		(at 305.791108 -398.942052 90)
		(property "Reference" "C557"
			(at 0 0 90)
			(layer "B.SilkS")
			(hide yes)
			(effects
				(font
					(size 1.27 1.27)
				)
				(justify mirror)
			)
		)
		(property "Value" ""
			(at 0 0 90)
			(layer "B.Fab")
			(effects
				(font
					(size 1.27 1.27)
				)
				(justify mirror)
			)
		)
		(duplicate_pad_numbers_are_jumpers no)
		(fp_line
			(start 0.7874 -0.4064)
			(end -0.7874 -0.4064)
			(stroke
				(width 0.1524)
				(type default)
			)
			(layer "B.SilkS")
		)
		(fp_line
			(start -0.7874 -0.4064)
			(end -0.7874 0.4064)
			(stroke
				(width 0.1524)
				(type default)
			)
			(layer "B.SilkS")
		)
		(fp_line
			(start 0.7874 0.4064)
			(end 0.7874 -0.4064)
			(stroke
				(width 0.1524)
				(type default)
			)
			(layer "B.SilkS")
		)
		(fp_line
			(start -0.7874 0.4064)
			(end 0.7874 0.4064)
			(stroke
				(width 0.1524)
				(type default)
			)
			(layer "B.SilkS")
		)
		(fp_line
			(start 0.67945 -0.305054)
			(end 0.12065 -0.305054)
			(stroke
				(width 0.1)
				(type default)
			)
			(layer "B.Fab")
		)
		(fp_line
			(start 0.12065 -0.305054)
			(end 0.12065 -0.2794)
			(stroke
				(width 0.1)
				(type default)
			)
			(layer "B.Fab")
		)
		(fp_line
			(start -0.12065 -0.3048)
			(end -0.67945 -0.3048)
			(stroke
				(width 0.1)
				(type default)
			)
			(layer "B.Fab")
		)
		(fp_line
			(start -0.67945 -0.3048)
			(end -0.67945 0.3048)
			(stroke
				(width 0.1)
				(type default)
			)
			(layer "B.Fab")
		)
		(fp_line
			(start 0.12065 -0.2794)
			(end -0.12065 -0.2794)
			(stroke
				(width 0.1)
				(type default)
			)
			(layer "B.Fab")
		)
		(fp_line
			(start -0.12065 -0.2794)
			(end -0.12065 -0.3048)
			(stroke
				(width 0.1)
				(type default)
			)
			(layer "B.Fab")
		)
		(fp_line
			(start 0.12065 0.2794)
			(end 0.12065 0.3048)
			(stroke
				(width 0.1)
				(type default)
			)
			(layer "B.Fab")
		)
		(fp_line
			(start -0.120396 0.2794)
			(end 0.12065 0.2794)
			(stroke
				(width 0.1)
				(type default)
			)
			(layer "B.Fab")
		)
		(fp_line
			(start 0.67945 0.3048)
			(end 0.67945 -0.305054)
			(stroke
				(width 0.1)
				(type default)
			)
			(layer "B.Fab")
		)
		(fp_line
			(start 0.12065 0.3048)
			(end 0.67945 0.3048)
			(stroke
				(width 0.1)
				(type default)
			)
			(layer "B.Fab")
		)
		(fp_line
			(start -0.120396 0.3048)
			(end -0.120396 0.2794)
			(stroke
				(width 0.1)
				(type default)
			)
			(layer "B.Fab")
		)
		(fp_line
			(start -0.67945 0.3048)
			(end -0.120396 0.3048)
			(stroke
				(width 0.1)
				(type default)
			)
			(layer "B.Fab")
		)
		(pad "1" smd circle
			(at 0.40005 0 270)
			(size 0 0)
			(layers "B.Cu" "B.Mask" "B.Paste")
			(net "P0V9_CPU0_RT0_2A")
		)
		(pad "2" smd circle
			(at -0.40005 0 270)
			(size 0 0)
			(layers "B.Cu" "B.Mask" "B.Paste")
			(net "GND")
		)
	)
	(footprint ""
		(layer "B.Cu")
		(at 307.34127 -195.95211 180)
		(property "Reference" "R1674"
			(at 0 0 0)
			(layer "B.SilkS")
			(hide yes)
			(effects
				(font
					(size 1.27 1.27)
				)
				(justify mirror)
			)
		)
		(property "Value" ""
			(at 0 0 0)
			(layer "B.Fab")
			(effects
				(font
					(size 1.27 1.27)
				)
				(justify mirror)
			)
		)
		(duplicate_pad_numbers_are_jumpers no)
		(fp_line
			(start 0.7874 0.4064)
			(end 0.7874 -0.4064)
			(stroke
				(width 0.1524)
				(type default)
			)
			(layer "B.SilkS")
		)
		(fp_line
			(start 0.7874 -0.4064)
			(end -0.7874 -0.4064)
			(stroke
				(width 0.1524)
				(type default)
			)
			(layer "B.SilkS")
		)
		(fp_line
			(start -0.7874 0.4064)
			(end 0.7874 0.4064)
			(stroke
				(width 0.1524)
				(type default)
			)
			(layer "B.SilkS")
		)
		(fp_line
			(start -0.7874 -0.4064)
			(end -0.7874 0.4064)
			(stroke
				(width 0.1524)
				(type default)
			)
			(layer "B.SilkS")
		)
		(fp_line
			(start 0.67945 0.3048)
			(end 0.67945 -0.305054)
			(stroke
				(width 0.1)
				(type default)
			)
			(layer "B.Fab")
		)
		(fp_line
			(start 0.67945 -0.305054)
			(end 0.12065 -0.305054)
			(stroke
				(width 0.1)
				(type default)
			)
			(layer "B.Fab")
		)
		(fp_line
			(start 0.12065 0.3048)
			(end 0.67945 0.3048)
			(stroke
				(width 0.1)
				(type default)
			)
			(layer "B.Fab")
		)
		(fp_line
			(start 0.12065 0.2794)
			(end 0.12065 0.3048)
			(stroke
				(width 0.1)
				(type default)
			)
			(layer "B.Fab")
		)
		(fp_line
			(start 0.12065 -0.2794)
			(end -0.12065 -0.2794)
			(stroke
				(width 0.1)
				(type default)
			)
			(layer "B.Fab")
		)
		(fp_line
			(start 0.12065 -0.305054)
			(end 0.12065 -0.2794)
			(stroke
				(width 0.1)
				(type default)
			)
			(layer "B.Fab")
		)
		(fp_line
			(start -0.120396 0.3048)
			(end -0.120396 0.2794)
			(stroke
				(width 0.1)
				(type default)
			)
			(layer "B.Fab")
		)
		(fp_line
			(start -0.120396 0.2794)
			(end 0.12065 0.2794)
			(stroke
				(width 0.1)
				(type default)
			)
			(layer "B.Fab")
		)
		(fp_line
			(start -0.12065 -0.2794)
			(end -0.12065 -0.3048)
			(stroke
				(width 0.1)
				(type default)
			)
			(layer "B.Fab")
		)
		(fp_line
			(start -0.12065 -0.3048)
			(end -0.67945 -0.3048)
			(stroke
				(width 0.1)
				(type default)
			)
			(layer "B.Fab")
		)
		(fp_line
			(start -0.67945 0.3048)
			(end -0.120396 0.3048)
			(stroke
				(width 0.1)
				(type default)
			)
			(layer "B.Fab")
		)
		(fp_line
			(start -0.67945 -0.3048)
			(end -0.67945 0.3048)
			(stroke
				(width 0.1)
				(type default)
			)
			(layer "B.Fab")
		)
		(pad "1" smd circle
			(at 0.40005 0)
			(size 0 0)
			(layers "B.Cu" "B.Mask" "B.Paste")
			(net "I3C_SPD_DDRAF_CPU0_SDA")
		)
		(pad "2" smd circle
			(at -0.40005 0)
			(size 0 0)
			(layers "B.Cu" "B.Mask" "B.Paste")
			(net "I3C_SPD_DDRA_CPU0_SDA")
		)
	)
	(footprint ""
		(layer "B.Cu")
		(at 129.305304 -33.654492)
		(property "Reference" "C6080"
			(at 0 0 0)
			(layer "B.SilkS")
			(hide yes)
			(effects
				(font
					(size 1.27 1.27)
				)
				(justify mirror)
			)
		)
		(property "Value" ""
			(at 0 0 0)
			(layer "B.Fab")
			(effects
				(font
					(size 1.27 1.27)
				)
				(justify mirror)
			)
		)
		(duplicate_pad_numbers_are_jumpers no)
		(fp_line
			(start -0.7874 -0.4064)
			(end -0.7874 0.4064)
			(stroke
				(width 0.1524)
				(type default)
			)
			(layer "B.SilkS")
		)
		(fp_line
			(start -0.7874 0.4064)
			(end 0.7874 0.4064)
			(stroke
				(width 0.1524)
				(type default)
			)
			(layer "B.SilkS")
		)
		(fp_line
			(start 0.7874 -0.4064)
			(end -0.7874 -0.4064)
			(stroke
				(width 0.1524)
				(type default)
			)
			(layer "B.SilkS")
		)
		(fp_line
			(start 0.7874 0.4064)
			(end 0.7874 -0.4064)
			(stroke
				(width 0.1524)
				(type default)
			)
			(layer "B.SilkS")
		)
		(fp_line
			(start -0.67945 -0.3048)
			(end -0.67945 0.3048)
			(stroke
				(width 0.1)
				(type default)
			)
			(layer "B.Fab")
		)
		(fp_line
			(start -0.67945 0.3048)
			(end -0.120396 0.3048)
			(stroke
				(width 0.1)
				(type default)
			)
			(layer "B.Fab")
		)
		(fp_line
			(start -0.12065 -0.3048)
			(end -0.67945 -0.3048)
			(stroke
				(width 0.1)
				(type default)
			)
			(layer "B.Fab")
		)
		(fp_line
			(start -0.12065 -0.2794)
			(end -0.12065 -0.3048)
			(stroke
				(width 0.1)
				(type default)
			)
			(layer "B.Fab")
		)
		(fp_line
			(start -0.120396 0.2794)
			(end 0.12065 0.2794)
			(stroke
				(width 0.1)
				(type default)
			)
			(layer "B.Fab")
		)
		(fp_line
			(start -0.120396 0.3048)
			(end -0.120396 0.2794)
			(stroke
				(width 0.1)
				(type default)
			)
			(layer "B.Fab")
		)
		(fp_line
			(start 0.12065 -0.305054)
			(end 0.12065 -0.2794)
			(stroke
				(width 0.1)
				(type default)
			)
			(layer "B.Fab")
		)
		(fp_line
			(start 0.12065 -0.2794)
			(end -0.12065 -0.2794)
			(stroke
				(width 0.1)
				(type default)
			)
			(layer "B.Fab")
		)
		(fp_line
			(start 0.12065 0.2794)
			(end 0.12065 0.3048)
			(stroke
				(width 0.1)
				(type default)
			)
			(layer "B.Fab")
		)
		(fp_line
			(start 0.12065 0.3048)
			(end 0.67945 0.3048)
			(stroke
				(width 0.1)
				(type default)
			)
			(layer "B.Fab")
		)
		(fp_line
			(start 0.67945 -0.305054)
			(end 0.12065 -0.305054)
			(stroke
				(width 0.1)
				(type default)
			)
			(layer "B.Fab")
		)
		(fp_line
			(start 0.67945 0.3048)
			(end 0.67945 -0.305054)
			(stroke
				(width 0.1)
				(type default)
			)
			(layer "B.Fab")
		)
		(pad "1" smd circle
			(at 0.40005 0 180)
			(size 0 0)
			(layers "B.Cu" "B.Mask" "B.Paste")
			(net "P1V2_AUX")
		)
		(pad "2" smd circle
			(at -0.40005 0 180)
			(size 0 0)
			(layers "B.Cu" "B.Mask" "B.Paste")
			(net "GND")
		)
	)
	(footprint ""
		(layer "B.Cu")
		(at 373.337328 -137.008108 -90)
		(property "Reference" "R8308"
			(at 0 0 90)
			(layer "B.SilkS")
			(hide yes)
			(effects
				(font
					(size 1.27 1.27)
				)
				(justify mirror)
			)
		)
		(property "Value" ""
			(at 0 0 90)
			(layer "B.Fab")
			(effects
				(font
					(size 1.27 1.27)
				)
				(justify mirror)
			)
		)
		(duplicate_pad_numbers_are_jumpers no)
		(fp_line
			(start -0.7874 0.4064)
			(end 0.7874 0.4064)
			(stroke
				(width 0.1524)
				(type default)
			)
			(layer "B.SilkS")
		)
		(fp_line
			(start 0.7874 0.4064)
			(end 0.7874 -0.4064)
			(stroke
				(width 0.1524)
				(type default)
			)
			(layer "B.SilkS")
		)
		(fp_line
			(start -0.7874 -0.4064)
			(end -0.7874 0.4064)
			(stroke
				(width 0.1524)
				(type default)
			)
			(layer "B.SilkS")
		)
		(fp_line
			(start 0.7874 -0.4064)
			(end -0.7874 -0.4064)
			(stroke
				(width 0.1524)
				(type default)
			)
			(layer "B.SilkS")
		)
		(fp_line
			(start -0.67945 0.3048)
			(end -0.120396 0.3048)
			(stroke
				(width 0.1)
				(type default)
			)
			(layer "B.Fab")
		)
		(fp_line
			(start -0.120396 0.3048)
			(end -0.120396 0.2794)
			(stroke
				(width 0.1)
				(type default)
			)
			(layer "B.Fab")
		)
		(fp_line
			(start 0.12065 0.3048)
			(end 0.67945 0.3048)
			(stroke
				(width 0.1)
				(type default)
			)
			(layer "B.Fab")
		)
		(fp_line
			(start 0.67945 0.3048)
			(end 0.67945 -0.305054)
			(stroke
				(width 0.1)
				(type default)
			)
			(layer "B.Fab")
		)
		(fp_line
			(start -0.120396 0.2794)
			(end 0.12065 0.2794)
			(stroke
				(width 0.1)
				(type default)
			)
			(layer "B.Fab")
		)
		(fp_line
			(start 0.12065 0.2794)
			(end 0.12065 0.3048)
			(stroke
				(width 0.1)
				(type default)
			)
			(layer "B.Fab")
		)
		(fp_line
			(start -0.12065 -0.2794)
			(end -0.12065 -0.3048)
			(stroke
				(width 0.1)
				(type default)
			)
			(layer "B.Fab")
		)
		(fp_line
			(start 0.12065 -0.2794)
			(end -0.12065 -0.2794)
			(stroke
				(width 0.1)
				(type default)
			)
			(layer "B.Fab")
		)
		(fp_line
			(start -0.67945 -0.3048)
			(end -0.67945 0.3048)
			(stroke
				(width 0.1)
				(type default)
			)
			(layer "B.Fab")
		)
		(fp_line
			(start -0.12065 -0.3048)
			(end -0.67945 -0.3048)
			(stroke
				(width 0.1)
				(type default)
			)
			(layer "B.Fab")
		)
		(fp_line
			(start 0.12065 -0.305054)
			(end 0.12065 -0.2794)
			(stroke
				(width 0.1)
				(type default)
			)
			(layer "B.Fab")
		)
		(fp_line
			(start 0.67945 -0.305054)
			(end 0.12065 -0.305054)
			(stroke
				(width 0.1)
				(type default)
			)
			(layer "B.Fab")
		)
		(pad "1" smd circle
			(at 0.40005 0 90)
			(size 0 0)
			(layers "B.Cu" "B.Mask" "B.Paste")
			(net "SMB_SCM_2_R3_SCL")
		)
		(pad "2" smd circle
			(at -0.40005 0 90)
			(size 0 0)
			(layers "B.Cu" "B.Mask" "B.Paste")
			(net "PVDDCR_CPU0_P0_PMSCL_R")
		)
	)
	(footprint ""
		(layer "B.Cu")
		(at 363.215936 -256.012188 -90)
		(property "Reference" "C2539"
			(at 0 0 90)
			(layer "B.SilkS")
			(hide yes)
			(effects
				(font
					(size 1.27 1.27)
				)
				(justify mirror)
			)
		)
		(property "Value" ""
			(at 0 0 90)
			(layer "B.Fab")
			(effects
				(font
					(size 1.27 1.27)
				)
				(justify mirror)
			)
		)
		(duplicate_pad_numbers_are_jumpers no)
		(fp_line
			(start -0.7874 0.4064)
			(end 0.7874 0.4064)
			(stroke
				(width 0.1524)
				(type default)
			)
			(layer "B.SilkS")
		)
		(fp_line
			(start 0.7874 0.4064)
			(end 0.7874 -0.4064)
			(stroke
				(width 0.1524)
				(type default)
			)
			(layer "B.SilkS")
		)
		(fp_line
			(start -0.7874 -0.4064)
			(end -0.7874 0.4064)
			(stroke
				(width 0.1524)
				(type default)
			)
			(layer "B.SilkS")
		)
		(fp_line
			(start 0.7874 -0.4064)
			(end -0.7874 -0.4064)
			(stroke
				(width 0.1524)
				(type default)
			)
			(layer "B.SilkS")
		)
		(fp_line
			(start -0.67945 0.3048)
			(end -0.120396 0.3048)
			(stroke
				(width 0.1)
				(type default)
			)
			(layer "B.Fab")
		)
		(fp_line
			(start -0.120396 0.3048)
			(end -0.120396 0.2794)
			(stroke
				(width 0.1)
				(type default)
			)
			(layer "B.Fab")
		)
		(fp_line
			(start 0.12065 0.3048)
			(end 0.67945 0.3048)
			(stroke
				(width 0.1)
				(type default)
			)
			(layer "B.Fab")
		)
		(fp_line
			(start 0.67945 0.3048)
			(end 0.67945 -0.305054)
			(stroke
				(width 0.1)
				(type default)
			)
			(layer "B.Fab")
		)
		(fp_line
			(start -0.120396 0.2794)
			(end 0.12065 0.2794)
			(stroke
				(width 0.1)
				(type default)
			)
			(layer "B.Fab")
		)
		(fp_line
			(start 0.12065 0.2794)
			(end 0.12065 0.3048)
			(stroke
				(width 0.1)
				(type default)
			)
			(layer "B.Fab")
		)
		(fp_line
			(start -0.12065 -0.2794)
			(end -0.12065 -0.3048)
			(stroke
				(width 0.1)
				(type default)
			)
			(layer "B.Fab")
		)
		(fp_line
			(start 0.12065 -0.2794)
			(end -0.12065 -0.2794)
			(stroke
				(width 0.1)
				(type default)
			)
			(layer "B.Fab")
		)
		(fp_line
			(start -0.67945 -0.3048)
			(end -0.67945 0.3048)
			(stroke
				(width 0.1)
				(type default)
			)
			(layer "B.Fab")
		)
		(fp_line
			(start -0.12065 -0.3048)
			(end -0.67945 -0.3048)
			(stroke
				(width 0.1)
				(type default)
			)
			(layer "B.Fab")
		)
		(fp_line
			(start 0.12065 -0.305054)
			(end 0.12065 -0.2794)
			(stroke
				(width 0.1)
				(type default)
			)
			(layer "B.Fab")
		)
		(fp_line
			(start 0.67945 -0.305054)
			(end 0.12065 -0.305054)
			(stroke
				(width 0.1)
				(type default)
			)
			(layer "B.Fab")
		)
		(pad "1" smd circle
			(at 0.40005 0 90)
			(size 0 0)
			(layers "B.Cu" "B.Mask" "B.Paste")
			(net "PVDDCR_SOC_P0")
		)
		(pad "2" smd circle
			(at -0.40005 0 90)
			(size 0 0)
			(layers "B.Cu" "B.Mask" "B.Paste")
			(net "GND")
		)
	)
	(footprint ""
		(layer "B.Cu")
		(at 403.315678 -323.892672)
		(property "Reference" "R472"
			(at 0 0 0)
			(layer "B.SilkS")
			(hide yes)
			(effects
				(font
					(size 1.27 1.27)
				)
				(justify mirror)
			)
		)
		(property "Value" ""
			(at 0 0 0)
			(layer "B.Fab")
			(effects
				(font
					(size 1.27 1.27)
				)
				(justify mirror)
			)
		)
		(duplicate_pad_numbers_are_jumpers no)
		(fp_line
			(start -0.7874 -0.4064)
			(end -0.7874 0.4064)
			(stroke
				(width 0.1524)
				(type default)
			)
			(layer "B.SilkS")
		)
		(fp_line
			(start -0.7874 0.4064)
			(end 0.7874 0.4064)
			(stroke
				(width 0.1524)
				(type default)
			)
			(layer "B.SilkS")
		)
		(fp_line
			(start 0.7874 -0.4064)
			(end -0.7874 -0.4064)
			(stroke
				(width 0.1524)
				(type default)
			)
			(layer "B.SilkS")
		)
		(fp_line
			(start 0.7874 0.4064)
			(end 0.7874 -0.4064)
			(stroke
				(width 0.1524)
				(type default)
			)
			(layer "B.SilkS")
		)
		(fp_line
			(start -0.67945 -0.3048)
			(end -0.67945 0.3048)
			(stroke
				(width 0.1)
				(type default)
			)
			(layer "B.Fab")
		)
		(fp_line
			(start -0.67945 0.3048)
			(end -0.120396 0.3048)
			(stroke
				(width 0.1)
				(type default)
			)
			(layer "B.Fab")
		)
		(fp_line
			(start -0.12065 -0.3048)
			(end -0.67945 -0.3048)
			(stroke
				(width 0.1)
				(type default)
			)
			(layer "B.Fab")
		)
		(fp_line
			(start -0.12065 -0.2794)
			(end -0.12065 -0.3048)
			(stroke
				(width 0.1)
				(type default)
			)
			(layer "B.Fab")
		)
		(fp_line
			(start -0.120396 0.2794)
			(end 0.12065 0.2794)
			(stroke
				(width 0.1)
				(type default)
			)
			(layer "B.Fab")
		)
		(fp_line
			(start -0.120396 0.3048)
			(end -0.120396 0.2794)
			(stroke
				(width 0.1)
				(type default)
			)
			(layer "B.Fab")
		)
		(fp_line
			(start 0.12065 -0.305054)
			(end 0.12065 -0.2794)
			(stroke
				(width 0.1)
				(type default)
			)
			(layer "B.Fab")
		)
		(fp_line
			(start 0.12065 -0.2794)
			(end -0.12065 -0.2794)
			(stroke
				(width 0.1)
				(type default)
			)
			(layer "B.Fab")
		)
		(fp_line
			(start 0.12065 0.2794)
			(end 0.12065 0.3048)
			(stroke
				(width 0.1)
				(type default)
			)
			(layer "B.Fab")
		)
		(fp_line
			(start 0.12065 0.3048)
			(end 0.67945 0.3048)
			(stroke
				(width 0.1)
				(type default)
			)
			(layer "B.Fab")
		)
		(fp_line
			(start 0.67945 -0.305054)
			(end 0.12065 -0.305054)
			(stroke
				(width 0.1)
				(type default)
			)
			(layer "B.Fab")
		)
		(fp_line
			(start 0.67945 0.3048)
			(end 0.67945 -0.305054)
			(stroke
				(width 0.1)
				(type default)
			)
			(layer "B.Fab")
		)
		(pad "1" smd rect
			(at 0.40005 0)
			(size 0.4572 0.508)
			(layers "B.Cu" "B.Mask" "B.Paste")
			(net "ESPI_CPU0_ALERT_P0_N")
		)
		(pad "2" smd rect
			(at -0.40005 0)
			(size 0.4572 0.508)
			(layers "B.Cu" "B.Mask" "B.Paste")
			(net "ESPI_CPU0_R_ALERT_N")
		)
	)
	(footprint ""
		(layer "B.Cu")
		(at 104.561386 -267.529564)
		(property "Reference" "C2394"
			(at 0 0 0)
			(layer "B.SilkS")
			(hide yes)
			(effects
				(font
					(size 1.27 1.27)
				)
				(justify mirror)
			)
		)
		(property "Value" ""
			(at 0 0 0)
			(layer "B.Fab")
			(effects
				(font
					(size 1.27 1.27)
				)
				(justify mirror)
			)
		)
		(duplicate_pad_numbers_are_jumpers no)
		(fp_line
			(start -0.7874 -0.4064)
			(end -0.7874 0.4064)
			(stroke
				(width 0.1524)
				(type default)
			)
			(layer "B.SilkS")
		)
		(fp_line
			(start -0.7874 0.4064)
			(end 0.7874 0.4064)
			(stroke
				(width 0.1524)
				(type default)
			)
			(layer "B.SilkS")
		)
		(fp_line
			(start 0.7874 -0.4064)
			(end -0.7874 -0.4064)
			(stroke
				(width 0.1524)
				(type default)
			)
			(layer "B.SilkS")
		)
		(fp_line
			(start 0.7874 0.4064)
			(end 0.7874 -0.4064)
			(stroke
				(width 0.1524)
				(type default)
			)
			(layer "B.SilkS")
		)
		(fp_line
			(start -0.67945 -0.3048)
			(end -0.67945 0.3048)
			(stroke
				(width 0.1)
				(type default)
			)
			(layer "B.Fab")
		)
		(fp_line
			(start -0.67945 0.3048)
			(end -0.120396 0.3048)
			(stroke
				(width 0.1)
				(type default)
			)
			(layer "B.Fab")
		)
		(fp_line
			(start -0.12065 -0.3048)
			(end -0.67945 -0.3048)
			(stroke
				(width 0.1)
				(type default)
			)
			(layer "B.Fab")
		)
		(fp_line
			(start -0.12065 -0.2794)
			(end -0.12065 -0.3048)
			(stroke
				(width 0.1)
				(type default)
			)
			(layer "B.Fab")
		)
		(fp_line
			(start -0.120396 0.2794)
			(end 0.12065 0.2794)
			(stroke
				(width 0.1)
				(type default)
			)
			(layer "B.Fab")
		)
		(fp_line
			(start -0.120396 0.3048)
			(end -0.120396 0.2794)
			(stroke
				(width 0.1)
				(type default)
			)
			(layer "B.Fab")
		)
		(fp_line
			(start 0.12065 -0.305054)
			(end 0.12065 -0.2794)
			(stroke
				(width 0.1)
				(type default)
			)
			(layer "B.Fab")
		)
		(fp_line
			(start 0.12065 -0.2794)
			(end -0.12065 -0.2794)
			(stroke
				(width 0.1)
				(type default)
			)
			(layer "B.Fab")
		)
		(fp_line
			(start 0.12065 0.2794)
			(end 0.12065 0.3048)
			(stroke
				(width 0.1)
				(type default)
			)
			(layer "B.Fab")
		)
		(fp_line
			(start 0.12065 0.3048)
			(end 0.67945 0.3048)
			(stroke
				(width 0.1)
				(type default)
			)
			(layer "B.Fab")
		)
		(fp_line
			(start 0.67945 -0.305054)
			(end 0.12065 -0.305054)
			(stroke
				(width 0.1)
				(type default)
			)
			(layer "B.Fab")
		)
		(fp_line
			(start 0.67945 0.3048)
			(end 0.67945 -0.305054)
			(stroke
				(width 0.1)
				(type default)
			)
			(layer "B.Fab")
		)
		(pad "1" smd circle
			(at 0.40005 0 180)
			(size 0 0)
			(layers "B.Cu" "B.Mask" "B.Paste")
			(net "PVDDCR_CPU1_P1")
		)
		(pad "2" smd circle
			(at -0.40005 0 180)
			(size 0 0)
			(layers "B.Cu" "B.Mask" "B.Paste")
			(net "GND")
		)
	)
	(footprint ""
		(layer "B.Cu")
		(at 338.830158 -309.214012 90)
		(property "Reference" "R392"
			(at 0 0 90)
			(layer "B.SilkS")
			(hide yes)
			(effects
				(font
					(size 1.27 1.27)
				)
				(justify mirror)
			)
		)
		(property "Value" ""
			(at 0 0 90)
			(layer "B.Fab")
			(effects
				(font
					(size 1.27 1.27)
				)
				(justify mirror)
			)
		)
		(duplicate_pad_numbers_are_jumpers no)
		(fp_line
			(start 0.7874 -0.4064)
			(end -0.7874 -0.4064)
			(stroke
				(width 0.1524)
				(type default)
			)
			(layer "B.SilkS")
		)
		(fp_line
			(start -0.7874 -0.4064)
			(end -0.7874 0.4064)
			(stroke
				(width 0.1524)
				(type default)
			)
			(layer "B.SilkS")
		)
		(fp_line
			(start 0.7874 0.4064)
			(end 0.7874 -0.4064)
			(stroke
				(width 0.1524)
				(type default)
			)
			(layer "B.SilkS")
		)
		(fp_line
			(start -0.7874 0.4064)
			(end 0.7874 0.4064)
			(stroke
				(width 0.1524)
				(type default)
			)
			(layer "B.SilkS")
		)
		(fp_line
			(start 0.67945 -0.305054)
			(end 0.12065 -0.305054)
			(stroke
				(width 0.1)
				(type default)
			)
			(layer "B.Fab")
		)
		(fp_line
			(start 0.12065 -0.305054)
			(end 0.12065 -0.2794)
			(stroke
				(width 0.1)
				(type default)
			)
			(layer "B.Fab")
		)
		(fp_line
			(start -0.12065 -0.3048)
			(end -0.67945 -0.3048)
			(stroke
				(width 0.1)
				(type default)
			)
			(layer "B.Fab")
		)
		(fp_line
			(start -0.67945 -0.3048)
			(end -0.67945 0.3048)
			(stroke
				(width 0.1)
				(type default)
			)
			(layer "B.Fab")
		)
		(fp_line
			(start 0.12065 -0.2794)
			(end -0.12065 -0.2794)
			(stroke
				(width 0.1)
				(type default)
			)
			(layer "B.Fab")
		)
		(fp_line
			(start -0.12065 -0.2794)
			(end -0.12065 -0.3048)
			(stroke
				(width 0.1)
				(type default)
			)
			(layer "B.Fab")
		)
		(fp_line
			(start 0.12065 0.2794)
			(end 0.12065 0.3048)
			(stroke
				(width 0.1)
				(type default)
			)
			(layer "B.Fab")
		)
		(fp_line
			(start -0.120396 0.2794)
			(end 0.12065 0.2794)
			(stroke
				(width 0.1)
				(type default)
			)
			(layer "B.Fab")
		)
		(fp_line
			(start 0.67945 0.3048)
			(end 0.67945 -0.305054)
			(stroke
				(width 0.1)
				(type default)
			)
			(layer "B.Fab")
		)
		(fp_line
			(start 0.12065 0.3048)
			(end 0.67945 0.3048)
			(stroke
				(width 0.1)
				(type default)
			)
			(layer "B.Fab")
		)
		(fp_line
			(start -0.120396 0.3048)
			(end -0.120396 0.2794)
			(stroke
				(width 0.1)
				(type default)
			)
			(layer "B.Fab")
		)
		(fp_line
			(start -0.67945 0.3048)
			(end -0.120396 0.3048)
			(stroke
				(width 0.1)
				(type default)
			)
			(layer "B.Fab")
		)
		(pad "1" smd circle
			(at 0.40005 0 270)
			(size 0 0)
			(layers "B.Cu" "B.Mask" "B.Paste")
			(net "PVDD18_S5_P0")
		)
		(pad "2" smd circle
			(at -0.40005 0 270)
			(size 0 0)
			(layers "B.Cu" "B.Mask" "B.Paste")
			(net "CPU0_SA0")
		)
	)
	(footprint ""
		(layer "B.Cu")
		(at 238.379 -234.061 90)
		(property "Reference" "R1161"
			(at 0 0 90)
			(layer "B.SilkS")
			(hide yes)
			(effects
				(font
					(size 1.27 1.27)
				)
				(justify mirror)
			)
		)
		(property "Value" ""
			(at 0 0 90)
			(layer "B.Fab")
			(effects
				(font
					(size 1.27 1.27)
				)
				(justify mirror)
			)
		)
		(duplicate_pad_numbers_are_jumpers no)
		(fp_line
			(start 0.7874 -0.4064)
			(end -0.7874 -0.4064)
			(stroke
				(width 0.1524)
				(type default)
			)
			(layer "B.SilkS")
		)
		(fp_line
			(start -0.7874 -0.4064)
			(end -0.7874 0.4064)
			(stroke
				(width 0.1524)
				(type default)
			)
			(layer "B.SilkS")
		)
		(fp_line
			(start 0.7874 0.4064)
			(end 0.7874 -0.4064)
			(stroke
				(width 0.1524)
				(type default)
			)
			(layer "B.SilkS")
		)
		(fp_line
			(start -0.7874 0.4064)
			(end 0.7874 0.4064)
			(stroke
				(width 0.1524)
				(type default)
			)
			(layer "B.SilkS")
		)
		(fp_line
			(start 0.67945 -0.305054)
			(end 0.12065 -0.305054)
			(stroke
				(width 0.1)
				(type default)
			)
			(layer "B.Fab")
		)
		(fp_line
			(start 0.12065 -0.305054)
			(end 0.12065 -0.2794)
			(stroke
				(width 0.1)
				(type default)
			)
			(layer "B.Fab")
		)
		(fp_line
			(start -0.12065 -0.3048)
			(end -0.67945 -0.3048)
			(stroke
				(width 0.1)
				(type default)
			)
			(layer "B.Fab")
		)
		(fp_line
			(start -0.67945 -0.3048)
			(end -0.67945 0.3048)
			(stroke
				(width 0.1)
				(type default)
			)
			(layer "B.Fab")
		)
		(fp_line
			(start 0.12065 -0.2794)
			(end -0.12065 -0.2794)
			(stroke
				(width 0.1)
				(type default)
			)
			(layer "B.Fab")
		)
		(fp_line
			(start -0.12065 -0.2794)
			(end -0.12065 -0.3048)
			(stroke
				(width 0.1)
				(type default)
			)
			(layer "B.Fab")
		)
		(fp_line
			(start 0.12065 0.2794)
			(end 0.12065 0.3048)
			(stroke
				(width 0.1)
				(type default)
			)
			(layer "B.Fab")
		)
		(fp_line
			(start -0.120396 0.2794)
			(end 0.12065 0.2794)
			(stroke
				(width 0.1)
				(type default)
			)
			(layer "B.Fab")
		)
		(fp_line
			(start 0.67945 0.3048)
			(end 0.67945 -0.305054)
			(stroke
				(width 0.1)
				(type default)
			)
			(layer "B.Fab")
		)
		(fp_line
			(start 0.12065 0.3048)
			(end 0.67945 0.3048)
			(stroke
				(width 0.1)
				(type default)
			)
			(layer "B.Fab")
		)
		(fp_line
			(start -0.120396 0.3048)
			(end -0.120396 0.2794)
			(stroke
				(width 0.1)
				(type default)
			)
			(layer "B.Fab")
		)
		(fp_line
			(start -0.67945 0.3048)
			(end -0.120396 0.3048)
			(stroke
				(width 0.1)
				(type default)
			)
			(layer "B.Fab")
		)
		(pad "1" smd circle
			(at 0.40005 0 270)
			(size 0 0)
			(layers "B.Cu" "B.Mask" "B.Paste")
			(net "SMB_CPU1_SEC_R_SCL")
		)
		(pad "2" smd circle
			(at -0.40005 0 270)
			(size 0 0)
			(layers "B.Cu" "B.Mask" "B.Paste")
			(net "SMB_CPU1_SEC_SCL")
		)
	)
	(footprint ""
		(layer "B.Cu")
		(at 397.820642 -416.899344 90)
		(property "Reference" "C6613"
			(at 0 0 90)
			(layer "B.SilkS")
			(hide yes)
			(effects
				(font
					(size 1.27 1.27)
				)
				(justify mirror)
			)
		)
		(property "Value" ""
			(at 0 0 90)
			(layer "B.Fab")
			(effects
				(font
					(size 1.27 1.27)
				)
				(justify mirror)
			)
		)
		(duplicate_pad_numbers_are_jumpers no)
		(fp_line
			(start 0.299974 -0.150114)
			(end -0.299974 -0.150114)
			(stroke
				(width 0.1)
				(type default)
			)
			(layer "B.Fab")
		)
		(fp_line
			(start -0.299974 -0.150114)
			(end -0.299974 0.150114)
			(stroke
				(width 0.1)
				(type default)
			)
			(layer "B.Fab")
		)
		(fp_line
			(start 0.299974 0.150114)
			(end 0.299974 -0.150114)
			(stroke
				(width 0.1)
				(type default)
			)
			(layer "B.Fab")
		)
		(fp_line
			(start -0.299974 0.150114)
			(end 0.299974 0.150114)
			(stroke
				(width 0.1)
				(type default)
			)
			(layer "B.Fab")
		)
		(pad "1" smd rect
			(at 0.2667 0 270)
			(size 0.3048 0.381)
			(layers "B.Cu" "B.Mask" "B.Paste")
			(net "P5E_CPU0_P3_TX_BUF_C_DP<8>")
		)
		(pad "2" smd rect
			(at -0.2667 0 270)
			(size 0.3048 0.381)
			(layers "B.Cu" "B.Mask" "B.Paste")
			(net "P5E_CPU0_P3_TX_BUF_DP<8>")
		)
	)
	(footprint ""
		(layer "B.Cu")
		(at 231.943148 -322.84035 180)
		(property "Reference" "R1258"
			(at 0 0 0)
			(layer "B.SilkS")
			(hide yes)
			(effects
				(font
					(size 1.27 1.27)
				)
				(justify mirror)
			)
		)
		(property "Value" ""
			(at 0 0 0)
			(layer "B.Fab")
			(effects
				(font
					(size 1.27 1.27)
				)
				(justify mirror)
			)
		)
		(duplicate_pad_numbers_are_jumpers no)
		(fp_line
			(start 0.7874 0.4064)
			(end 0.7874 -0.4064)
			(stroke
				(width 0.1524)
				(type default)
			)
			(layer "B.SilkS")
		)
		(fp_line
			(start 0.7874 -0.4064)
			(end -0.7874 -0.4064)
			(stroke
				(width 0.1524)
				(type default)
			)
			(layer "B.SilkS")
		)
		(fp_line
			(start -0.7874 0.4064)
			(end 0.7874 0.4064)
			(stroke
				(width 0.1524)
				(type default)
			)
			(layer "B.SilkS")
		)
		(fp_line
			(start -0.7874 -0.4064)
			(end -0.7874 0.4064)
			(stroke
				(width 0.1524)
				(type default)
			)
			(layer "B.SilkS")
		)
		(fp_line
			(start 0.67945 0.3048)
			(end 0.67945 -0.305054)
			(stroke
				(width 0.1)
				(type default)
			)
			(layer "B.Fab")
		)
		(fp_line
			(start 0.67945 -0.305054)
			(end 0.12065 -0.305054)
			(stroke
				(width 0.1)
				(type default)
			)
			(layer "B.Fab")
		)
		(fp_line
			(start 0.12065 0.3048)
			(end 0.67945 0.3048)
			(stroke
				(width 0.1)
				(type default)
			)
			(layer "B.Fab")
		)
		(fp_line
			(start 0.12065 0.2794)
			(end 0.12065 0.3048)
			(stroke
				(width 0.1)
				(type default)
			)
			(layer "B.Fab")
		)
		(fp_line
			(start 0.12065 -0.2794)
			(end -0.12065 -0.2794)
			(stroke
				(width 0.1)
				(type default)
			)
			(layer "B.Fab")
		)
		(fp_line
			(start 0.12065 -0.305054)
			(end 0.12065 -0.2794)
			(stroke
				(width 0.1)
				(type default)
			)
			(layer "B.Fab")
		)
		(fp_line
			(start -0.120396 0.3048)
			(end -0.120396 0.2794)
			(stroke
				(width 0.1)
				(type default)
			)
			(layer "B.Fab")
		)
		(fp_line
			(start -0.120396 0.2794)
			(end 0.12065 0.2794)
			(stroke
				(width 0.1)
				(type default)
			)
			(layer "B.Fab")
		)
		(fp_line
			(start -0.12065 -0.2794)
			(end -0.12065 -0.3048)
			(stroke
				(width 0.1)
				(type default)
			)
			(layer "B.Fab")
		)
		(fp_line
			(start -0.12065 -0.3048)
			(end -0.67945 -0.3048)
			(stroke
				(width 0.1)
				(type default)
			)
			(layer "B.Fab")
		)
		(fp_line
			(start -0.67945 0.3048)
			(end -0.120396 0.3048)
			(stroke
				(width 0.1)
				(type default)
			)
			(layer "B.Fab")
		)
		(fp_line
			(start -0.67945 -0.3048)
			(end -0.67945 0.3048)
			(stroke
				(width 0.1)
				(type default)
			)
			(layer "B.Fab")
		)
		(pad "1" smd rect
			(at 0.40005 0 180)
			(size 0.4572 0.508)
			(layers "B.Cu" "B.Mask" "B.Paste")
			(net "P1V8_AUX_ADC")
		)
		(pad "2" smd rect
			(at -0.40005 0 180)
			(size 0.4572 0.508)
			(layers "B.Cu" "B.Mask" "B.Paste")
			(net "P1V8_AUX_ADC_MAM")
		)
	)
	(footprint ""
		(layer "B.Cu")
		(at 186.007502 -351.21342 90)
		(property "Reference" "PC515_1"
			(at 0 0 90)
			(layer "B.SilkS")
			(hide yes)
			(effects
				(font
					(size 1.27 1.27)
				)
				(justify mirror)
			)
		)
		(property "Value" ""
			(at 0 0 90)
			(layer "B.Fab")
			(effects
				(font
					(size 1.27 1.27)
				)
				(justify mirror)
			)
		)
		(duplicate_pad_numbers_are_jumpers no)
		(fp_line
			(start 1.524 -0.762)
			(end -1.524 -0.762)
			(stroke
				(width 0.1524)
				(type default)
			)
			(layer "B.SilkS")
		)
		(fp_line
			(start -1.524 -0.762)
			(end -1.524 0.762)
			(stroke
				(width 0.1524)
				(type default)
			)
			(layer "B.SilkS")
		)
		(fp_line
			(start 1.524 0.762)
			(end 1.524 -0.762)
			(stroke
				(width 0.1524)
				(type default)
			)
			(layer "B.SilkS")
		)
		(fp_line
			(start -1.524 0.762)
			(end 1.524 0.762)
			(stroke
				(width 0.1524)
				(type default)
			)
			(layer "B.SilkS")
		)
		(fp_line
			(start 1.1049 -0.724916)
			(end 1.1049 0.724916)
			(stroke
				(width 0.1)
				(type default)
			)
			(layer "B.Fab")
		)
		(fp_line
			(start -1.1049 -0.724916)
			(end 1.1049 -0.724916)
			(stroke
				(width 0.1)
				(type default)
			)
			(layer "B.Fab")
		)
		(fp_line
			(start 1.1049 0.724916)
			(end -1.1049 0.724916)
			(stroke
				(width 0.1)
				(type default)
			)
			(layer "B.Fab")
		)
		(fp_line
			(start -1.1049 0.724916)
			(end -1.1049 -0.724916)
			(stroke
				(width 0.1)
				(type default)
			)
			(layer "B.Fab")
		)
		(pad "1" smd rect
			(at 0.889 0 90)
			(size 1.016 1.27)
			(layers "B.Cu" "B.Mask" "B.Paste")
			(net "SW_P12V_AUX_PVDD11_S3_P1_FLT")
		)
		(pad "2" smd rect
			(at -0.889 0 90)
			(size 1.016 1.27)
			(layers "B.Cu" "B.Mask" "B.Paste")
			(net "GND")
		)
	)
	(footprint ""
		(layer "B.Cu")
		(at 216.20988 -53.177948)
		(property "Reference" "C2067"
			(at 0 0 0)
			(layer "B.SilkS")
			(hide yes)
			(effects
				(font
					(size 1.27 1.27)
				)
				(justify mirror)
			)
		)
		(property "Value" ""
			(at 0 0 0)
			(layer "B.Fab")
			(effects
				(font
					(size 1.27 1.27)
				)
				(justify mirror)
			)
		)
		(duplicate_pad_numbers_are_jumpers no)
		(fp_line
			(start -0.7874 -0.4064)
			(end -0.7874 0.4064)
			(stroke
				(width 0.1524)
				(type default)
			)
			(layer "B.SilkS")
		)
		(fp_line
			(start -0.7874 0.4064)
			(end 0.7874 0.4064)
			(stroke
				(width 0.1524)
				(type default)
			)
			(layer "B.SilkS")
		)
		(fp_line
			(start 0.7874 -0.4064)
			(end -0.7874 -0.4064)
			(stroke
				(width 0.1524)
				(type default)
			)
			(layer "B.SilkS")
		)
		(fp_line
			(start 0.7874 0.4064)
			(end 0.7874 -0.4064)
			(stroke
				(width 0.1524)
				(type default)
			)
			(layer "B.SilkS")
		)
		(fp_line
			(start -0.67945 -0.3048)
			(end -0.67945 0.3048)
			(stroke
				(width 0.1)
				(type default)
			)
			(layer "B.Fab")
		)
		(fp_line
			(start -0.67945 0.3048)
			(end -0.120396 0.3048)
			(stroke
				(width 0.1)
				(type default)
			)
			(layer "B.Fab")
		)
		(fp_line
			(start -0.12065 -0.3048)
			(end -0.67945 -0.3048)
			(stroke
				(width 0.1)
				(type default)
			)
			(layer "B.Fab")
		)
		(fp_line
			(start -0.12065 -0.2794)
			(end -0.12065 -0.3048)
			(stroke
				(width 0.1)
				(type default)
			)
			(layer "B.Fab")
		)
		(fp_line
			(start -0.120396 0.2794)
			(end 0.12065 0.2794)
			(stroke
				(width 0.1)
				(type default)
			)
			(layer "B.Fab")
		)
		(fp_line
			(start -0.120396 0.3048)
			(end -0.120396 0.2794)
			(stroke
				(width 0.1)
				(type default)
			)
			(layer "B.Fab")
		)
		(fp_line
			(start 0.12065 -0.305054)
			(end 0.12065 -0.2794)
			(stroke
				(width 0.1)
				(type default)
			)
			(layer "B.Fab")
		)
		(fp_line
			(start 0.12065 -0.2794)
			(end -0.12065 -0.2794)
			(stroke
				(width 0.1)
				(type default)
			)
			(layer "B.Fab")
		)
		(fp_line
			(start 0.12065 0.2794)
			(end 0.12065 0.3048)
			(stroke
				(width 0.1)
				(type default)
			)
			(layer "B.Fab")
		)
		(fp_line
			(start 0.12065 0.3048)
			(end 0.67945 0.3048)
			(stroke
				(width 0.1)
				(type default)
			)
			(layer "B.Fab")
		)
		(fp_line
			(start 0.67945 -0.305054)
			(end 0.12065 -0.305054)
			(stroke
				(width 0.1)
				(type default)
			)
			(layer "B.Fab")
		)
		(fp_line
			(start 0.67945 0.3048)
			(end 0.67945 -0.305054)
			(stroke
				(width 0.1)
				(type default)
			)
			(layer "B.Fab")
		)
		(pad "1" smd circle
			(at 0.40005 0 180)
			(size 0 0)
			(layers "B.Cu" "B.Mask" "B.Paste")
			(net "P3V3_AUX")
		)
		(pad "2" smd circle
			(at -0.40005 0 180)
			(size 0 0)
			(layers "B.Cu" "B.Mask" "B.Paste")
			(net "GND")
		)
	)
	(footprint ""
		(layer "B.Cu")
		(at 255.73736 -324.045072 180)
		(property "Reference" "C1084"
			(at 0 0 0)
			(layer "B.SilkS")
			(hide yes)
			(effects
				(font
					(size 1.27 1.27)
				)
				(justify mirror)
			)
		)
		(property "Value" ""
			(at 0 0 0)
			(layer "B.Fab")
			(effects
				(font
					(size 1.27 1.27)
				)
				(justify mirror)
			)
		)
		(duplicate_pad_numbers_are_jumpers no)
		(fp_line
			(start 0.7874 0.4064)
			(end 0.7874 -0.4064)
			(stroke
				(width 0.1524)
				(type default)
			)
			(layer "B.SilkS")
		)
		(fp_line
			(start 0.7874 -0.4064)
			(end -0.7874 -0.4064)
			(stroke
				(width 0.1524)
				(type default)
			)
			(layer "B.SilkS")
		)
		(fp_line
			(start -0.7874 0.4064)
			(end 0.7874 0.4064)
			(stroke
				(width 0.1524)
				(type default)
			)
			(layer "B.SilkS")
		)
		(fp_line
			(start -0.7874 -0.4064)
			(end -0.7874 0.4064)
			(stroke
				(width 0.1524)
				(type default)
			)
			(layer "B.SilkS")
		)
		(fp_line
			(start 0.67945 0.3048)
			(end 0.67945 -0.305054)
			(stroke
				(width 0.1)
				(type default)
			)
			(layer "B.Fab")
		)
		(fp_line
			(start 0.67945 -0.305054)
			(end 0.12065 -0.305054)
			(stroke
				(width 0.1)
				(type default)
			)
			(layer "B.Fab")
		)
		(fp_line
			(start 0.12065 0.3048)
			(end 0.67945 0.3048)
			(stroke
				(width 0.1)
				(type default)
			)
			(layer "B.Fab")
		)
		(fp_line
			(start 0.12065 0.2794)
			(end 0.12065 0.3048)
			(stroke
				(width 0.1)
				(type default)
			)
			(layer "B.Fab")
		)
		(fp_line
			(start 0.12065 -0.2794)
			(end -0.12065 -0.2794)
			(stroke
				(width 0.1)
				(type default)
			)
			(layer "B.Fab")
		)
		(fp_line
			(start 0.12065 -0.305054)
			(end 0.12065 -0.2794)
			(stroke
				(width 0.1)
				(type default)
			)
			(layer "B.Fab")
		)
		(fp_line
			(start -0.120396 0.3048)
			(end -0.120396 0.2794)
			(stroke
				(width 0.1)
				(type default)
			)
			(layer "B.Fab")
		)
		(fp_line
			(start -0.120396 0.2794)
			(end 0.12065 0.2794)
			(stroke
				(width 0.1)
				(type default)
			)
			(layer "B.Fab")
		)
		(fp_line
			(start -0.12065 -0.2794)
			(end -0.12065 -0.3048)
			(stroke
				(width 0.1)
				(type default)
			)
			(layer "B.Fab")
		)
		(fp_line
			(start -0.12065 -0.3048)
			(end -0.67945 -0.3048)
			(stroke
				(width 0.1)
				(type default)
			)
			(layer "B.Fab")
		)
		(fp_line
			(start -0.67945 0.3048)
			(end -0.120396 0.3048)
			(stroke
				(width 0.1)
				(type default)
			)
			(layer "B.Fab")
		)
		(fp_line
			(start -0.67945 -0.3048)
			(end -0.67945 0.3048)
			(stroke
				(width 0.1)
				(type default)
			)
			(layer "B.Fab")
		)
		(pad "1" smd circle
			(at 0.40005 0)
			(size 0 0)
			(layers "B.Cu" "B.Mask" "B.Paste")
			(net "P1V8_AUX_ADC_MAM")
		)
		(pad "2" smd circle
			(at -0.40005 0)
			(size 0 0)
			(layers "B.Cu" "B.Mask" "B.Paste")
			(net "GND")
		)
	)
	(footprint ""
		(layer "B.Cu")
		(at 490.57433 -298.306998 -90)
		(property "Reference" "X12"
			(at 2.985008 3.602736 270)
			(unlocked yes)
			(layer "B.SilkS")
			(effects
				(font
					(size 0.7874 0.5842)
					(thickness 0.1524)
				)
				(justify left mirror)
			)
		)
		(property "Value" ""
			(at 0 0 90)
			(layer "B.Fab")
			(effects
				(font
					(size 1.27 1.27)
				)
				(justify mirror)
			)
		)
		(property "User Part Number" "N_A"
			(at -1.30175 1.27 180)
			(unlocked yes)
			(layer "Cmts.User")
			(hide yes)
			(effects
				(font
					(size 0.635 0.4064)
					(thickness 0.1524)
				)
				(justify mirror)
			)
		)
		(property "Device Type" "TP_TDR_4P_FTS_TH-TP_TDR_4P_DIP,EMPTY,TP15"
			(at -1.30175 1.27 180)
			(unlocked yes)
			(layer "B.Fab")
			(hide yes)
			(effects
				(font
					(size 0.635 0.4064)
					(thickness 0.1524)
				)
				(justify mirror)
			)
		)
		(duplicate_pad_numbers_are_jumpers no)
		(fp_line
			(start -2.54 3.81)
			(end -2.54 3.6703)
			(stroke
				(width 0.1524)
				(type default)
			)
			(layer "B.SilkS")
		)
		(fp_line
			(start 0 3.81)
			(end -2.54 3.81)
			(stroke
				(width 0.1524)
				(type default)
			)
			(layer "B.SilkS")
		)
		(fp_line
			(start 0 3.175)
			(end 0 3.81)
			(stroke
				(width 0.1524)
				(type default)
			)
			(layer "B.SilkS")
		)
		(fp_line
			(start -2.54 1.4097)
			(end -2.54 1.1303)
			(stroke
				(width 0.1524)
				(type default)
			)
			(layer "B.SilkS")
		)
		(fp_line
			(start 0 0.635)
			(end 0 1.905)
			(stroke
				(width 0.1524)
				(type default)
			)
			(layer "B.SilkS")
		)
		(fp_line
			(start -2.54 -1.1303)
			(end -2.54 -1.27)
			(stroke
				(width 0.1524)
				(type default)
			)
			(layer "B.SilkS")
		)
		(fp_line
			(start -2.54 -1.27)
			(end 0 -1.27)
			(stroke
				(width 0.1524)
				(type default)
			)
			(layer "B.SilkS")
		)
		(fp_line
			(start 0 -1.27)
			(end 0 -0.635)
			(stroke
				(width 0.1524)
				(type default)
			)
			(layer "B.SilkS")
		)
		(fp_poly
			(pts
				(xy 2.285746 -0.762) (xy 2.285746 0.762) (xy 0.761746 0)
			)
			(stroke
				(width 0)
				(type default)
			)
			(fill yes)
			(layer "B.SilkS")
		)
		(fp_line
			(start -2.54 3.81)
			(end -2.54 -1.27)
			(stroke
				(width 0.1)
				(type default)
			)
			(layer "B.Fab")
		)
		(fp_line
			(start 0 3.81)
			(end -2.54 3.81)
			(stroke
				(width 0.1)
				(type default)
			)
			(layer "B.Fab")
		)
		(fp_line
			(start -2.54 -1.27)
			(end 0 -1.27)
			(stroke
				(width 0.1)
				(type default)
			)
			(layer "B.Fab")
		)
		(fp_line
			(start 0 -1.27)
			(end 0 3.81)
			(stroke
				(width 0.1)
				(type default)
			)
			(layer "B.Fab")
		)
		(fp_poly
			(pts
				(xy 0.761746 0) (xy 2.285746 -0.762) (xy 2.285746 0.762)
			)
			(stroke
				(width 0)
				(type default)
			)
			(fill yes)
			(layer "B.Fab")
		)
		(pad "1" thru_hole circle
			(at 0 0 90)
			(size 1.0033 1.0033)
			(drill 0.249936)
			(layers "*.Cu" "*.Mask")
			(remove_unused_layers no)
			(net "TDR_DIFF_80_BOT_DN")
			(clearance 0.10795)
			(padstack
				(mode front_inner_back)
				(layer "Inner"
					(shape circle)
					(size 0.8001 0.8001)
					(clearance 0.1524)
				)
				(layer "B.Cu"
					(shape circle)
					(size 1.0033 1.0033)
					(thermal_gap 0.10795)
					(clearance 0.10795)
				)
			)
		)
		(pad "2" thru_hole circle
			(at -2.54 0 90)
			(size 1.9939 1.9939)
			(drill 0.249936)
			(layers "*.Cu" "*.Mask")
			(remove_unused_layers no)
			(net "T1_GND")
			(clearance 0.10795)
			(padstack
				(mode front_inner_back)
				(layer "Inner"
					(shape circle)
					(size 0.8001 0.8001)
					(clearance 0.1524)
				)
				(layer "B.Cu"
					(shape circle)
					(size 1.9939 1.9939)
					(thermal_gap 0.10795)
					(clearance 0.10795)
				)
			)
		)
		(pad "3" thru_hole circle
			(at -2.54 2.54 90)
			(size 1.9939 1.9939)
			(drill 0.249936)
			(layers "*.Cu" "*.Mask")
			(remove_unused_layers no)
			(net "T1_GND")
			(clearance 0.10795)
			(padstack
				(mode front_inner_back)
				(layer "Inner"
					(shape circle)
					(size 0.8001 0.8001)
					(clearance 0.1524)
				)
				(layer "B.Cu"
					(shape circle)
					(size 1.9939 1.9939)
					(thermal_gap 0.10795)
					(clearance 0.10795)
				)
			)
		)
		(pad "4" thru_hole circle
			(at 0 2.54 90)
			(size 1.0033 1.0033)
			(drill 0.249936)
			(layers "*.Cu" "*.Mask")
			(remove_unused_layers no)
			(net "TDR_DIFF_80_BOT_DP")
			(clearance 0.10795)
			(padstack
				(mode front_inner_back)
				(layer "Inner"
					(shape circle)
					(size 0.8001 0.8001)
					(clearance 0.1524)
				)
				(layer "B.Cu"
					(shape circle)
					(size 1.0033 1.0033)
					(thermal_gap 0.10795)
					(clearance 0.10795)
				)
			)
		)
	)
	(footprint ""
		(layer "B.Cu")
		(at 113.841022 -26.03246)
		(property "Reference" "C6106"
			(at 0 0 0)
			(layer "B.SilkS")
			(hide yes)
			(effects
				(font
					(size 1.27 1.27)
				)
				(justify mirror)
			)
		)
		(property "Value" ""
			(at 0 0 0)
			(layer "B.Fab")
			(effects
				(font
					(size 1.27 1.27)
				)
				(justify mirror)
			)
		)
		(duplicate_pad_numbers_are_jumpers no)
		(fp_line
			(start -0.7874 -0.4064)
			(end -0.7874 0.4064)
			(stroke
				(width 0.1524)
				(type default)
			)
			(layer "B.SilkS")
		)
		(fp_line
			(start -0.7874 0.4064)
			(end 0.7874 0.4064)
			(stroke
				(width 0.1524)
				(type default)
			)
			(layer "B.SilkS")
		)
		(fp_line
			(start 0.7874 -0.4064)
			(end -0.7874 -0.4064)
			(stroke
				(width 0.1524)
				(type default)
			)
			(layer "B.SilkS")
		)
		(fp_line
			(start 0.7874 0.4064)
			(end 0.7874 -0.4064)
			(stroke
				(width 0.1524)
				(type default)
			)
			(layer "B.SilkS")
		)
		(fp_line
			(start -0.67945 -0.3048)
			(end -0.67945 0.3048)
			(stroke
				(width 0.1)
				(type default)
			)
			(layer "B.Fab")
		)
		(fp_line
			(start -0.67945 0.3048)
			(end -0.120396 0.3048)
			(stroke
				(width 0.1)
				(type default)
			)
			(layer "B.Fab")
		)
		(fp_line
			(start -0.12065 -0.3048)
			(end -0.67945 -0.3048)
			(stroke
				(width 0.1)
				(type default)
			)
			(layer "B.Fab")
		)
		(fp_line
			(start -0.12065 -0.2794)
			(end -0.12065 -0.3048)
			(stroke
				(width 0.1)
				(type default)
			)
			(layer "B.Fab")
		)
		(fp_line
			(start -0.120396 0.2794)
			(end 0.12065 0.2794)
			(stroke
				(width 0.1)
				(type default)
			)
			(layer "B.Fab")
		)
		(fp_line
			(start -0.120396 0.3048)
			(end -0.120396 0.2794)
			(stroke
				(width 0.1)
				(type default)
			)
			(layer "B.Fab")
		)
		(fp_line
			(start 0.12065 -0.305054)
			(end 0.12065 -0.2794)
			(stroke
				(width 0.1)
				(type default)
			)
			(layer "B.Fab")
		)
		(fp_line
			(start 0.12065 -0.2794)
			(end -0.12065 -0.2794)
			(stroke
				(width 0.1)
				(type default)
			)
			(layer "B.Fab")
		)
		(fp_line
			(start 0.12065 0.2794)
			(end 0.12065 0.3048)
			(stroke
				(width 0.1)
				(type default)
			)
			(layer "B.Fab")
		)
		(fp_line
			(start 0.12065 0.3048)
			(end 0.67945 0.3048)
			(stroke
				(width 0.1)
				(type default)
			)
			(layer "B.Fab")
		)
		(fp_line
			(start 0.67945 -0.305054)
			(end 0.12065 -0.305054)
			(stroke
				(width 0.1)
				(type default)
			)
			(layer "B.Fab")
		)
		(fp_line
			(start 0.67945 0.3048)
			(end 0.67945 -0.305054)
			(stroke
				(width 0.1)
				(type default)
			)
			(layer "B.Fab")
		)
		(pad "1" smd circle
			(at 0.40005 0 180)
			(size 0 0)
			(layers "B.Cu" "B.Mask" "B.Paste")
			(net "P1V2_CPU0_USB2_DVDD12")
		)
		(pad "2" smd circle
			(at -0.40005 0 180)
			(size 0 0)
			(layers "B.Cu" "B.Mask" "B.Paste")
			(net "GND")
		)
	)
	(footprint ""
		(layer "B.Cu")
		(at 376.33656 -180.078634 90)
		(property "Reference" "PR325"
			(at 0 0 90)
			(layer "B.SilkS")
			(hide yes)
			(effects
				(font
					(size 1.27 1.27)
				)
				(justify mirror)
			)
		)
		(property "Value" ""
			(at 0 0 90)
			(layer "B.Fab")
			(effects
				(font
					(size 1.27 1.27)
				)
				(justify mirror)
			)
		)
		(duplicate_pad_numbers_are_jumpers no)
		(fp_line
			(start 0.7874 -0.4064)
			(end -0.7874 -0.4064)
			(stroke
				(width 0.1524)
				(type default)
			)
			(layer "B.SilkS")
		)
		(fp_line
			(start -0.7874 -0.4064)
			(end -0.7874 0.4064)
			(stroke
				(width 0.1524)
				(type default)
			)
			(layer "B.SilkS")
		)
		(fp_line
			(start 0.7874 0.4064)
			(end 0.7874 -0.4064)
			(stroke
				(width 0.1524)
				(type default)
			)
			(layer "B.SilkS")
		)
		(fp_line
			(start -0.7874 0.4064)
			(end 0.7874 0.4064)
			(stroke
				(width 0.1524)
				(type default)
			)
			(layer "B.SilkS")
		)
		(fp_line
			(start 0.67945 -0.305054)
			(end 0.12065 -0.305054)
			(stroke
				(width 0.1)
				(type default)
			)
			(layer "B.Fab")
		)
		(fp_line
			(start 0.12065 -0.305054)
			(end 0.12065 -0.2794)
			(stroke
				(width 0.1)
				(type default)
			)
			(layer "B.Fab")
		)
		(fp_line
			(start -0.12065 -0.3048)
			(end -0.67945 -0.3048)
			(stroke
				(width 0.1)
				(type default)
			)
			(layer "B.Fab")
		)
		(fp_line
			(start -0.67945 -0.3048)
			(end -0.67945 0.3048)
			(stroke
				(width 0.1)
				(type default)
			)
			(layer "B.Fab")
		)
		(fp_line
			(start 0.12065 -0.2794)
			(end -0.12065 -0.2794)
			(stroke
				(width 0.1)
				(type default)
			)
			(layer "B.Fab")
		)
		(fp_line
			(start -0.12065 -0.2794)
			(end -0.12065 -0.3048)
			(stroke
				(width 0.1)
				(type default)
			)
			(layer "B.Fab")
		)
		(fp_line
			(start 0.12065 0.2794)
			(end 0.12065 0.3048)
			(stroke
				(width 0.1)
				(type default)
			)
			(layer "B.Fab")
		)
		(fp_line
			(start -0.120396 0.2794)
			(end 0.12065 0.2794)
			(stroke
				(width 0.1)
				(type default)
			)
			(layer "B.Fab")
		)
		(fp_line
			(start 0.67945 0.3048)
			(end 0.67945 -0.305054)
			(stroke
				(width 0.1)
				(type default)
			)
			(layer "B.Fab")
		)
		(fp_line
			(start 0.12065 0.3048)
			(end 0.67945 0.3048)
			(stroke
				(width 0.1)
				(type default)
			)
			(layer "B.Fab")
		)
		(fp_line
			(start -0.120396 0.3048)
			(end -0.120396 0.2794)
			(stroke
				(width 0.1)
				(type default)
			)
			(layer "B.Fab")
		)
		(fp_line
			(start -0.67945 0.3048)
			(end -0.120396 0.3048)
			(stroke
				(width 0.1)
				(type default)
			)
			(layer "B.Fab")
		)
		(pad "1" smd circle
			(at 0.40005 0 270)
			(size 0 0)
			(layers "B.Cu" "B.Mask" "B.Paste")
			(net "PVDDCR_CPU0_P0_VOS2")
		)
		(pad "2" smd circle
			(at -0.40005 0 270)
			(size 0 0)
			(layers "B.Cu" "B.Mask" "B.Paste")
			(net "PVDDCR_CPU0_P0")
		)
	)
	(footprint ""
		(layer "B.Cu")
		(at 112.521238 -388.296912)
		(property "Reference" "C498"
			(at 0 0 0)
			(layer "B.SilkS")
			(hide yes)
			(effects
				(font
					(size 1.27 1.27)
				)
				(justify mirror)
			)
		)
		(property "Value" ""
			(at 0 0 0)
			(layer "B.Fab")
			(effects
				(font
					(size 1.27 1.27)
				)
				(justify mirror)
			)
		)
		(duplicate_pad_numbers_are_jumpers no)
		(fp_line
			(start -0.299974 -0.150114)
			(end -0.299974 0.150114)
			(stroke
				(width 0.1)
				(type default)
			)
			(layer "B.Fab")
		)
		(fp_line
			(start -0.299974 0.150114)
			(end 0.299974 0.150114)
			(stroke
				(width 0.1)
				(type default)
			)
			(layer "B.Fab")
		)
		(fp_line
			(start 0.299974 -0.150114)
			(end -0.299974 -0.150114)
			(stroke
				(width 0.1)
				(type default)
			)
			(layer "B.Fab")
		)
		(fp_line
			(start 0.299974 0.150114)
			(end 0.299974 -0.150114)
			(stroke
				(width 0.1)
				(type default)
			)
			(layer "B.Fab")
		)
		(pad "1" smd rect
			(at 0.2667 0 180)
			(size 0.3048 0.381)
			(layers "B.Cu" "B.Mask" "B.Paste")
			(net "P0V9_CPU1_RT3_2A")
		)
		(pad "2" smd rect
			(at -0.2667 0 180)
			(size 0.3048 0.381)
			(layers "B.Cu" "B.Mask" "B.Paste")
			(net "GND")
		)
	)
	(footprint ""
		(layer "B.Cu")
		(at 162.746182 -388.011162 -90)
		(property "Reference" "C400"
			(at 0 0 90)
			(layer "B.SilkS")
			(hide yes)
			(effects
				(font
					(size 1.27 1.27)
				)
				(justify mirror)
			)
		)
		(property "Value" ""
			(at 0 0 90)
			(layer "B.Fab")
			(effects
				(font
					(size 1.27 1.27)
				)
				(justify mirror)
			)
		)
		(duplicate_pad_numbers_are_jumpers no)
		(fp_line
			(start -0.299974 0.150114)
			(end 0.299974 0.150114)
			(stroke
				(width 0.1)
				(type default)
			)
			(layer "B.Fab")
		)
		(fp_line
			(start 0.299974 0.150114)
			(end 0.299974 -0.150114)
			(stroke
				(width 0.1)
				(type default)
			)
			(layer "B.Fab")
		)
		(fp_line
			(start -0.299974 -0.150114)
			(end -0.299974 0.150114)
			(stroke
				(width 0.1)
				(type default)
			)
			(layer "B.Fab")
		)
		(fp_line
			(start 0.299974 -0.150114)
			(end -0.299974 -0.150114)
			(stroke
				(width 0.1)
				(type default)
			)
			(layer "B.Fab")
		)
		(pad "1" smd rect
			(at 0.2667 0 90)
			(size 0.3048 0.381)
			(layers "B.Cu" "B.Mask" "B.Paste")
			(net "P0V9_CPU1_RT2_2A")
		)
		(pad "2" smd rect
			(at -0.2667 0 90)
			(size 0.3048 0.381)
			(layers "B.Cu" "B.Mask" "B.Paste")
			(net "GND")
		)
	)
	(footprint ""
		(layer "B.Cu")
		(at 361.046014 -258.795012 180)
		(property "Reference" "C3926"
			(at 0 0 0)
			(layer "B.SilkS")
			(hide yes)
			(effects
				(font
					(size 1.27 1.27)
				)
				(justify mirror)
			)
		)
		(property "Value" ""
			(at 0 0 0)
			(layer "B.Fab")
			(effects
				(font
					(size 1.27 1.27)
				)
				(justify mirror)
			)
		)
		(duplicate_pad_numbers_are_jumpers no)
		(fp_line
			(start 0.7874 0.4064)
			(end 0.7874 -0.4064)
			(stroke
				(width 0.1524)
				(type default)
			)
			(layer "B.SilkS")
		)
		(fp_line
			(start 0.7874 -0.4064)
			(end -0.7874 -0.4064)
			(stroke
				(width 0.1524)
				(type default)
			)
			(layer "B.SilkS")
		)
		(fp_line
			(start -0.7874 0.4064)
			(end 0.7874 0.4064)
			(stroke
				(width 0.1524)
				(type default)
			)
			(layer "B.SilkS")
		)
		(fp_line
			(start -0.7874 -0.4064)
			(end -0.7874 0.4064)
			(stroke
				(width 0.1524)
				(type default)
			)
			(layer "B.SilkS")
		)
		(fp_line
			(start 0.67945 0.3048)
			(end 0.67945 -0.305054)
			(stroke
				(width 0.1)
				(type default)
			)
			(layer "B.Fab")
		)
		(fp_line
			(start 0.67945 -0.305054)
			(end 0.12065 -0.305054)
			(stroke
				(width 0.1)
				(type default)
			)
			(layer "B.Fab")
		)
		(fp_line
			(start 0.12065 0.3048)
			(end 0.67945 0.3048)
			(stroke
				(width 0.1)
				(type default)
			)
			(layer "B.Fab")
		)
		(fp_line
			(start 0.12065 0.2794)
			(end 0.12065 0.3048)
			(stroke
				(width 0.1)
				(type default)
			)
			(layer "B.Fab")
		)
		(fp_line
			(start 0.12065 -0.2794)
			(end -0.12065 -0.2794)
			(stroke
				(width 0.1)
				(type default)
			)
			(layer "B.Fab")
		)
		(fp_line
			(start 0.12065 -0.305054)
			(end 0.12065 -0.2794)
			(stroke
				(width 0.1)
				(type default)
			)
			(layer "B.Fab")
		)
		(fp_line
			(start -0.120396 0.3048)
			(end -0.120396 0.2794)
			(stroke
				(width 0.1)
				(type default)
			)
			(layer "B.Fab")
		)
		(fp_line
			(start -0.120396 0.2794)
			(end 0.12065 0.2794)
			(stroke
				(width 0.1)
				(type default)
			)
			(layer "B.Fab")
		)
		(fp_line
			(start -0.12065 -0.2794)
			(end -0.12065 -0.3048)
			(stroke
				(width 0.1)
				(type default)
			)
			(layer "B.Fab")
		)
		(fp_line
			(start -0.12065 -0.3048)
			(end -0.67945 -0.3048)
			(stroke
				(width 0.1)
				(type default)
			)
			(layer "B.Fab")
		)
		(fp_line
			(start -0.67945 0.3048)
			(end -0.120396 0.3048)
			(stroke
				(width 0.1)
				(type default)
			)
			(layer "B.Fab")
		)
		(fp_line
			(start -0.67945 -0.3048)
			(end -0.67945 0.3048)
			(stroke
				(width 0.1)
				(type default)
			)
			(layer "B.Fab")
		)
		(pad "1" smd circle
			(at 0.40005 0)
			(size 0 0)
			(layers "B.Cu" "B.Mask" "B.Paste")
			(net "PVDDCR_SOC_P0")
		)
		(pad "2" smd circle
			(at -0.40005 0)
			(size 0 0)
			(layers "B.Cu" "B.Mask" "B.Paste")
			(net "GND")
		)
	)
	(footprint ""
		(layer "B.Cu")
		(at 232.537 -335.153 90)
		(property "Reference" "R6768"
			(at 0 0 90)
			(layer "B.SilkS")
			(hide yes)
			(effects
				(font
					(size 1.27 1.27)
				)
				(justify mirror)
			)
		)
		(property "Value" ""
			(at 0 0 90)
			(layer "B.Fab")
			(effects
				(font
					(size 1.27 1.27)
				)
				(justify mirror)
			)
		)
		(duplicate_pad_numbers_are_jumpers no)
		(fp_line
			(start 0.32512 -0.175006)
			(end -0.32512 -0.175006)
			(stroke
				(width 0.1)
				(type default)
			)
			(layer "B.Fab")
		)
		(fp_line
			(start -0.32512 -0.175006)
			(end -0.32512 0.175006)
			(stroke
				(width 0.1)
				(type default)
			)
			(layer "B.Fab")
		)
		(fp_line
			(start 0.32512 0.175006)
			(end 0.32512 -0.175006)
			(stroke
				(width 0.1)
				(type default)
			)
			(layer "B.Fab")
		)
		(fp_line
			(start -0.32512 0.175006)
			(end 0.32512 0.175006)
			(stroke
				(width 0.1)
				(type default)
			)
			(layer "B.Fab")
		)
		(pad "1" smd rect
			(at 0.2667 0 270)
			(size 0.3048 0.381)
			(layers "B.Cu" "B.Mask" "B.Paste")
			(net "P1V8_CPU0_RT_1D")
		)
		(pad "2" smd rect
			(at -0.2667 0 90)
			(size 0.3048 0.381)
			(layers "B.Cu" "B.Mask" "B.Paste")
			(net "SMB_RT_CPU0_P2_R_SDA")
		)
	)
	(footprint ""
		(layer "B.Cu")
		(at 416.84067 -162.70859 90)
		(property "Reference" "PR364"
			(at 0 0 90)
			(layer "B.SilkS")
			(hide yes)
			(effects
				(font
					(size 1.27 1.27)
				)
				(justify mirror)
			)
		)
		(property "Value" ""
			(at 0 0 90)
			(layer "B.Fab")
			(effects
				(font
					(size 1.27 1.27)
				)
				(justify mirror)
			)
		)
		(duplicate_pad_numbers_are_jumpers no)
		(fp_line
			(start 0.7874 -0.4064)
			(end -0.7874 -0.4064)
			(stroke
				(width 0.1524)
				(type default)
			)
			(layer "B.SilkS")
		)
		(fp_line
			(start -0.7874 -0.4064)
			(end -0.7874 0.4064)
			(stroke
				(width 0.1524)
				(type default)
			)
			(layer "B.SilkS")
		)
		(fp_line
			(start 0.7874 0.4064)
			(end 0.7874 -0.4064)
			(stroke
				(width 0.1524)
				(type default)
			)
			(layer "B.SilkS")
		)
		(fp_line
			(start -0.7874 0.4064)
			(end 0.7874 0.4064)
			(stroke
				(width 0.1524)
				(type default)
			)
			(layer "B.SilkS")
		)
		(fp_line
			(start 0.67945 -0.305054)
			(end 0.12065 -0.305054)
			(stroke
				(width 0.1)
				(type default)
			)
			(layer "B.Fab")
		)
		(fp_line
			(start 0.12065 -0.305054)
			(end 0.12065 -0.2794)
			(stroke
				(width 0.1)
				(type default)
			)
			(layer "B.Fab")
		)
		(fp_line
			(start -0.12065 -0.3048)
			(end -0.67945 -0.3048)
			(stroke
				(width 0.1)
				(type default)
			)
			(layer "B.Fab")
		)
		(fp_line
			(start -0.67945 -0.3048)
			(end -0.67945 0.3048)
			(stroke
				(width 0.1)
				(type default)
			)
			(layer "B.Fab")
		)
		(fp_line
			(start 0.12065 -0.2794)
			(end -0.12065 -0.2794)
			(stroke
				(width 0.1)
				(type default)
			)
			(layer "B.Fab")
		)
		(fp_line
			(start -0.12065 -0.2794)
			(end -0.12065 -0.3048)
			(stroke
				(width 0.1)
				(type default)
			)
			(layer "B.Fab")
		)
		(fp_line
			(start 0.12065 0.2794)
			(end 0.12065 0.3048)
			(stroke
				(width 0.1)
				(type default)
			)
			(layer "B.Fab")
		)
		(fp_line
			(start -0.120396 0.2794)
			(end 0.12065 0.2794)
			(stroke
				(width 0.1)
				(type default)
			)
			(layer "B.Fab")
		)
		(fp_line
			(start 0.67945 0.3048)
			(end 0.67945 -0.305054)
			(stroke
				(width 0.1)
				(type default)
			)
			(layer "B.Fab")
		)
		(fp_line
			(start 0.12065 0.3048)
			(end 0.67945 0.3048)
			(stroke
				(width 0.1)
				(type default)
			)
			(layer "B.Fab")
		)
		(fp_line
			(start -0.120396 0.3048)
			(end -0.120396 0.2794)
			(stroke
				(width 0.1)
				(type default)
			)
			(layer "B.Fab")
		)
		(fp_line
			(start -0.67945 0.3048)
			(end -0.120396 0.3048)
			(stroke
				(width 0.1)
				(type default)
			)
			(layer "B.Fab")
		)
		(pad "1" smd circle
			(at 0.40005 0 270)
			(size 0 0)
			(layers "B.Cu" "B.Mask" "B.Paste")
			(net "PVDDCR_CPU0_P0_PVCC")
		)
		(pad "2" smd circle
			(at -0.40005 0 270)
			(size 0 0)
			(layers "B.Cu" "B.Mask" "B.Paste")
			(net "PVDDCR_SOC_P0_VCC3")
		)
	)
	(footprint ""
		(layer "B.Cu")
		(at 338.995766 -416.899344 90)
		(property "Reference" "C6556"
			(at 0 0 90)
			(layer "B.SilkS")
			(hide yes)
			(effects
				(font
					(size 1.27 1.27)
				)
				(justify mirror)
			)
		)
		(property "Value" ""
			(at 0 0 90)
			(layer "B.Fab")
			(effects
				(font
					(size 1.27 1.27)
				)
				(justify mirror)
			)
		)
		(duplicate_pad_numbers_are_jumpers no)
		(fp_line
			(start 0.299974 -0.150114)
			(end -0.299974 -0.150114)
			(stroke
				(width 0.1)
				(type default)
			)
			(layer "B.Fab")
		)
		(fp_line
			(start -0.299974 -0.150114)
			(end -0.299974 0.150114)
			(stroke
				(width 0.1)
				(type default)
			)
			(layer "B.Fab")
		)
		(fp_line
			(start 0.299974 0.150114)
			(end 0.299974 -0.150114)
			(stroke
				(width 0.1)
				(type default)
			)
			(layer "B.Fab")
		)
		(fp_line
			(start -0.299974 0.150114)
			(end 0.299974 0.150114)
			(stroke
				(width 0.1)
				(type default)
			)
			(layer "B.Fab")
		)
		(pad "1" smd rect
			(at 0.2667 0 270)
			(size 0.3048 0.381)
			(layers "B.Cu" "B.Mask" "B.Paste")
			(net "P5E_CPU0_P1_TX_BUF_C_DN<11>")
		)
		(pad "2" smd rect
			(at -0.2667 0 270)
			(size 0.3048 0.381)
			(layers "B.Cu" "B.Mask" "B.Paste")
			(net "P5E_CPU0_P1_TX_BUF_DN<11>")
		)
	)
	(footprint ""
		(layer "B.Cu")
		(at 59.233562 -190.64732 -90)
		(property "Reference" "R520"
			(at 0 0 90)
			(layer "B.SilkS")
			(hide yes)
			(effects
				(font
					(size 1.27 1.27)
				)
				(justify mirror)
			)
		)
		(property "Value" ""
			(at 0 0 90)
			(layer "B.Fab")
			(effects
				(font
					(size 1.27 1.27)
				)
				(justify mirror)
			)
		)
		(duplicate_pad_numbers_are_jumpers no)
		(fp_line
			(start -0.7874 0.4064)
			(end 0.7874 0.4064)
			(stroke
				(width 0.1524)
				(type default)
			)
			(layer "B.SilkS")
		)
		(fp_line
			(start 0.7874 0.4064)
			(end 0.7874 -0.4064)
			(stroke
				(width 0.1524)
				(type default)
			)
			(layer "B.SilkS")
		)
		(fp_line
			(start -0.7874 -0.4064)
			(end -0.7874 0.4064)
			(stroke
				(width 0.1524)
				(type default)
			)
			(layer "B.SilkS")
		)
		(fp_line
			(start 0.7874 -0.4064)
			(end -0.7874 -0.4064)
			(stroke
				(width 0.1524)
				(type default)
			)
			(layer "B.SilkS")
		)
		(fp_line
			(start -0.67945 0.3048)
			(end -0.120396 0.3048)
			(stroke
				(width 0.1)
				(type default)
			)
			(layer "B.Fab")
		)
		(fp_line
			(start -0.120396 0.3048)
			(end -0.120396 0.2794)
			(stroke
				(width 0.1)
				(type default)
			)
			(layer "B.Fab")
		)
		(fp_line
			(start 0.12065 0.3048)
			(end 0.67945 0.3048)
			(stroke
				(width 0.1)
				(type default)
			)
			(layer "B.Fab")
		)
		(fp_line
			(start 0.67945 0.3048)
			(end 0.67945 -0.305054)
			(stroke
				(width 0.1)
				(type default)
			)
			(layer "B.Fab")
		)
		(fp_line
			(start -0.120396 0.2794)
			(end 0.12065 0.2794)
			(stroke
				(width 0.1)
				(type default)
			)
			(layer "B.Fab")
		)
		(fp_line
			(start 0.12065 0.2794)
			(end 0.12065 0.3048)
			(stroke
				(width 0.1)
				(type default)
			)
			(layer "B.Fab")
		)
		(fp_line
			(start -0.12065 -0.2794)
			(end -0.12065 -0.3048)
			(stroke
				(width 0.1)
				(type default)
			)
			(layer "B.Fab")
		)
		(fp_line
			(start 0.12065 -0.2794)
			(end -0.12065 -0.2794)
			(stroke
				(width 0.1)
				(type default)
			)
			(layer "B.Fab")
		)
		(fp_line
			(start -0.67945 -0.3048)
			(end -0.67945 0.3048)
			(stroke
				(width 0.1)
				(type default)
			)
			(layer "B.Fab")
		)
		(fp_line
			(start -0.12065 -0.3048)
			(end -0.67945 -0.3048)
			(stroke
				(width 0.1)
				(type default)
			)
			(layer "B.Fab")
		)
		(fp_line
			(start 0.12065 -0.305054)
			(end 0.12065 -0.2794)
			(stroke
				(width 0.1)
				(type default)
			)
			(layer "B.Fab")
		)
		(fp_line
			(start 0.67945 -0.305054)
			(end 0.12065 -0.305054)
			(stroke
				(width 0.1)
				(type default)
			)
			(layer "B.Fab")
		)
		(pad "1" smd circle
			(at 0.40005 0 90)
			(size 0 0)
			(layers "B.Cu" "B.Mask" "B.Paste")
			(net "CPU1_PROCHOT_N")
		)
		(pad "2" smd circle
			(at -0.40005 0 90)
			(size 0 0)
			(layers "B.Cu" "B.Mask" "B.Paste")
			(net "PVDD18_S5_P1")
		)
	)
	(footprint ""
		(layer "B.Cu")
		(at 167.285162 -347.600016 90)
		(property "Reference" "R8011"
			(at 0 0 90)
			(layer "B.SilkS")
			(hide yes)
			(effects
				(font
					(size 1.27 1.27)
				)
				(justify mirror)
			)
		)
		(property "Value" ""
			(at 0 0 90)
			(layer "B.Fab")
			(effects
				(font
					(size 1.27 1.27)
				)
				(justify mirror)
			)
		)
		(duplicate_pad_numbers_are_jumpers no)
		(fp_line
			(start 0.7874 -0.4064)
			(end -0.7874 -0.4064)
			(stroke
				(width 0.1524)
				(type default)
			)
			(layer "B.SilkS")
		)
		(fp_line
			(start -0.7874 -0.4064)
			(end -0.7874 0.4064)
			(stroke
				(width 0.1524)
				(type default)
			)
			(layer "B.SilkS")
		)
		(fp_line
			(start 0.7874 0.4064)
			(end 0.7874 -0.4064)
			(stroke
				(width 0.1524)
				(type default)
			)
			(layer "B.SilkS")
		)
		(fp_line
			(start -0.7874 0.4064)
			(end 0.7874 0.4064)
			(stroke
				(width 0.1524)
				(type default)
			)
			(layer "B.SilkS")
		)
		(fp_line
			(start 0.67945 -0.305054)
			(end 0.12065 -0.305054)
			(stroke
				(width 0.1)
				(type default)
			)
			(layer "B.Fab")
		)
		(fp_line
			(start 0.12065 -0.305054)
			(end 0.12065 -0.2794)
			(stroke
				(width 0.1)
				(type default)
			)
			(layer "B.Fab")
		)
		(fp_line
			(start -0.12065 -0.3048)
			(end -0.67945 -0.3048)
			(stroke
				(width 0.1)
				(type default)
			)
			(layer "B.Fab")
		)
		(fp_line
			(start -0.67945 -0.3048)
			(end -0.67945 0.3048)
			(stroke
				(width 0.1)
				(type default)
			)
			(layer "B.Fab")
		)
		(fp_line
			(start 0.12065 -0.2794)
			(end -0.12065 -0.2794)
			(stroke
				(width 0.1)
				(type default)
			)
			(layer "B.Fab")
		)
		(fp_line
			(start -0.12065 -0.2794)
			(end -0.12065 -0.3048)
			(stroke
				(width 0.1)
				(type default)
			)
			(layer "B.Fab")
		)
		(fp_line
			(start 0.12065 0.2794)
			(end 0.12065 0.3048)
			(stroke
				(width 0.1)
				(type default)
			)
			(layer "B.Fab")
		)
		(fp_line
			(start -0.120396 0.2794)
			(end 0.12065 0.2794)
			(stroke
				(width 0.1)
				(type default)
			)
			(layer "B.Fab")
		)
		(fp_line
			(start 0.67945 0.3048)
			(end 0.67945 -0.305054)
			(stroke
				(width 0.1)
				(type default)
			)
			(layer "B.Fab")
		)
		(fp_line
			(start 0.12065 0.3048)
			(end 0.67945 0.3048)
			(stroke
				(width 0.1)
				(type default)
			)
			(layer "B.Fab")
		)
		(fp_line
			(start -0.120396 0.3048)
			(end -0.120396 0.2794)
			(stroke
				(width 0.1)
				(type default)
			)
			(layer "B.Fab")
		)
		(fp_line
			(start -0.67945 0.3048)
			(end -0.120396 0.3048)
			(stroke
				(width 0.1)
				(type default)
			)
			(layer "B.Fab")
		)
		(pad "1" smd circle
			(at 0.40005 0 270)
			(size 0 0)
			(layers "B.Cu" "B.Mask" "B.Paste")
			(net "PVDD18_S5_P1")
		)
		(pad "2" smd circle
			(at -0.40005 0 270)
			(size 0 0)
			(layers "B.Cu" "B.Mask" "B.Paste")
			(net "PVDD11_S3_P1_OCP_N_R")
		)
	)
	(footprint ""
		(layer "B.Cu")
		(at 179.7812 -133.111748 -90)
		(property "Reference" "R1422"
			(at 0 0 90)
			(layer "B.SilkS")
			(hide yes)
			(effects
				(font
					(size 1.27 1.27)
				)
				(justify mirror)
			)
		)
		(property "Value" ""
			(at 0 0 90)
			(layer "B.Fab")
			(effects
				(font
					(size 1.27 1.27)
				)
				(justify mirror)
			)
		)
		(duplicate_pad_numbers_are_jumpers no)
		(fp_line
			(start -0.7874 0.4064)
			(end 0.7874 0.4064)
			(stroke
				(width 0.1524)
				(type default)
			)
			(layer "B.SilkS")
		)
		(fp_line
			(start 0.7874 0.4064)
			(end 0.7874 -0.4064)
			(stroke
				(width 0.1524)
				(type default)
			)
			(layer "B.SilkS")
		)
		(fp_line
			(start -0.7874 -0.4064)
			(end -0.7874 0.4064)
			(stroke
				(width 0.1524)
				(type default)
			)
			(layer "B.SilkS")
		)
		(fp_line
			(start 0.7874 -0.4064)
			(end -0.7874 -0.4064)
			(stroke
				(width 0.1524)
				(type default)
			)
			(layer "B.SilkS")
		)
		(fp_line
			(start -0.67945 0.3048)
			(end -0.120396 0.3048)
			(stroke
				(width 0.1)
				(type default)
			)
			(layer "B.Fab")
		)
		(fp_line
			(start -0.120396 0.3048)
			(end -0.120396 0.2794)
			(stroke
				(width 0.1)
				(type default)
			)
			(layer "B.Fab")
		)
		(fp_line
			(start 0.12065 0.3048)
			(end 0.67945 0.3048)
			(stroke
				(width 0.1)
				(type default)
			)
			(layer "B.Fab")
		)
		(fp_line
			(start 0.67945 0.3048)
			(end 0.67945 -0.305054)
			(stroke
				(width 0.1)
				(type default)
			)
			(layer "B.Fab")
		)
		(fp_line
			(start -0.120396 0.2794)
			(end 0.12065 0.2794)
			(stroke
				(width 0.1)
				(type default)
			)
			(layer "B.Fab")
		)
		(fp_line
			(start 0.12065 0.2794)
			(end 0.12065 0.3048)
			(stroke
				(width 0.1)
				(type default)
			)
			(layer "B.Fab")
		)
		(fp_line
			(start -0.12065 -0.2794)
			(end -0.12065 -0.3048)
			(stroke
				(width 0.1)
				(type default)
			)
			(layer "B.Fab")
		)
		(fp_line
			(start 0.12065 -0.2794)
			(end -0.12065 -0.2794)
			(stroke
				(width 0.1)
				(type default)
			)
			(layer "B.Fab")
		)
		(fp_line
			(start -0.67945 -0.3048)
			(end -0.67945 0.3048)
			(stroke
				(width 0.1)
				(type default)
			)
			(layer "B.Fab")
		)
		(fp_line
			(start -0.12065 -0.3048)
			(end -0.67945 -0.3048)
			(stroke
				(width 0.1)
				(type default)
			)
			(layer "B.Fab")
		)
		(fp_line
			(start 0.12065 -0.305054)
			(end 0.12065 -0.2794)
			(stroke
				(width 0.1)
				(type default)
			)
			(layer "B.Fab")
		)
		(fp_line
			(start 0.67945 -0.305054)
			(end 0.12065 -0.305054)
			(stroke
				(width 0.1)
				(type default)
			)
			(layer "B.Fab")
		)
		(pad "1" smd circle
			(at 0.40005 0 90)
			(size 0 0)
			(layers "B.Cu" "B.Mask" "B.Paste")
			(net "PWRGD_CPU0_PWROK")
		)
		(pad "2" smd circle
			(at -0.40005 0 90)
			(size 0 0)
			(layers "B.Cu" "B.Mask" "B.Paste")
			(net "PWRGD_CPU1_PWROK")
		)
	)
	(footprint ""
		(layer "B.Cu")
		(at 138.7729 -9.03859 90)
		(property "Reference" "R6034"
			(at 0 0 90)
			(layer "B.SilkS")
			(hide yes)
			(effects
				(font
					(size 1.27 1.27)
				)
				(justify mirror)
			)
		)
		(property "Value" ""
			(at 0 0 90)
			(layer "B.Fab")
			(effects
				(font
					(size 1.27 1.27)
				)
				(justify mirror)
			)
		)
		(duplicate_pad_numbers_are_jumpers no)
		(fp_line
			(start 0.7874 -0.4064)
			(end -0.7874 -0.4064)
			(stroke
				(width 0.1524)
				(type default)
			)
			(layer "B.SilkS")
		)
		(fp_line
			(start -0.7874 -0.4064)
			(end -0.7874 0.4064)
			(stroke
				(width 0.1524)
				(type default)
			)
			(layer "B.SilkS")
		)
		(fp_line
			(start 0.7874 0.4064)
			(end 0.7874 -0.4064)
			(stroke
				(width 0.1524)
				(type default)
			)
			(layer "B.SilkS")
		)
		(fp_line
			(start -0.7874 0.4064)
			(end 0.7874 0.4064)
			(stroke
				(width 0.1524)
				(type default)
			)
			(layer "B.SilkS")
		)
		(fp_line
			(start 0.67945 -0.305054)
			(end 0.12065 -0.305054)
			(stroke
				(width 0.1)
				(type default)
			)
			(layer "B.Fab")
		)
		(fp_line
			(start 0.12065 -0.305054)
			(end 0.12065 -0.2794)
			(stroke
				(width 0.1)
				(type default)
			)
			(layer "B.Fab")
		)
		(fp_line
			(start -0.12065 -0.3048)
			(end -0.67945 -0.3048)
			(stroke
				(width 0.1)
				(type default)
			)
			(layer "B.Fab")
		)
		(fp_line
			(start -0.67945 -0.3048)
			(end -0.67945 0.3048)
			(stroke
				(width 0.1)
				(type default)
			)
			(layer "B.Fab")
		)
		(fp_line
			(start 0.12065 -0.2794)
			(end -0.12065 -0.2794)
			(stroke
				(width 0.1)
				(type default)
			)
			(layer "B.Fab")
		)
		(fp_line
			(start -0.12065 -0.2794)
			(end -0.12065 -0.3048)
			(stroke
				(width 0.1)
				(type default)
			)
			(layer "B.Fab")
		)
		(fp_line
			(start 0.12065 0.2794)
			(end 0.12065 0.3048)
			(stroke
				(width 0.1)
				(type default)
			)
			(layer "B.Fab")
		)
		(fp_line
			(start -0.120396 0.2794)
			(end 0.12065 0.2794)
			(stroke
				(width 0.1)
				(type default)
			)
			(layer "B.Fab")
		)
		(fp_line
			(start 0.67945 0.3048)
			(end 0.67945 -0.305054)
			(stroke
				(width 0.1)
				(type default)
			)
			(layer "B.Fab")
		)
		(fp_line
			(start 0.12065 0.3048)
			(end 0.67945 0.3048)
			(stroke
				(width 0.1)
				(type default)
			)
			(layer "B.Fab")
		)
		(fp_line
			(start -0.120396 0.3048)
			(end -0.120396 0.2794)
			(stroke
				(width 0.1)
				(type default)
			)
			(layer "B.Fab")
		)
		(fp_line
			(start -0.67945 0.3048)
			(end -0.120396 0.3048)
			(stroke
				(width 0.1)
				(type default)
			)
			(layer "B.Fab")
		)
		(pad "1" smd circle
			(at 0.40005 0 270)
			(size 0 0)
			(layers "B.Cu" "B.Mask" "B.Paste")
			(net "P3V3_AUX")
		)
		(pad "2" smd circle
			(at -0.40005 0 270)
			(size 0 0)
			(layers "B.Cu" "B.Mask" "B.Paste")
			(net "SCM_ROT_CPU_RST_R_N")
		)
	)
	(footprint ""
		(layer "B.Cu")
		(at 342.973406 -416.899344 90)
		(property "Reference" "C6557"
			(at 0 0 90)
			(layer "B.SilkS")
			(hide yes)
			(effects
				(font
					(size 1.27 1.27)
				)
				(justify mirror)
			)
		)
		(property "Value" ""
			(at 0 0 90)
			(layer "B.Fab")
			(effects
				(font
					(size 1.27 1.27)
				)
				(justify mirror)
			)
		)
		(duplicate_pad_numbers_are_jumpers no)
		(fp_line
			(start 0.299974 -0.150114)
			(end -0.299974 -0.150114)
			(stroke
				(width 0.1)
				(type default)
			)
			(layer "B.Fab")
		)
		(fp_line
			(start -0.299974 -0.150114)
			(end -0.299974 0.150114)
			(stroke
				(width 0.1)
				(type default)
			)
			(layer "B.Fab")
		)
		(fp_line
			(start 0.299974 0.150114)
			(end 0.299974 -0.150114)
			(stroke
				(width 0.1)
				(type default)
			)
			(layer "B.Fab")
		)
		(fp_line
			(start -0.299974 0.150114)
			(end 0.299974 0.150114)
			(stroke
				(width 0.1)
				(type default)
			)
			(layer "B.Fab")
		)
		(pad "1" smd rect
			(at 0.2667 0 270)
			(size 0.3048 0.381)
			(layers "B.Cu" "B.Mask" "B.Paste")
			(net "P5E_CPU0_P1_TX_BUF_C_DP<12>")
		)
		(pad "2" smd rect
			(at -0.2667 0 270)
			(size 0.3048 0.381)
			(layers "B.Cu" "B.Mask" "B.Paste")
			(net "P5E_CPU0_P1_TX_BUF_DP<12>")
		)
	)
	(footprint ""
		(layer "B.Cu")
		(at 239.903 -337.312)
		(property "Reference" "R1394"
			(at 0 0 0)
			(layer "B.SilkS")
			(hide yes)
			(effects
				(font
					(size 1.27 1.27)
				)
				(justify mirror)
			)
		)
		(property "Value" ""
			(at 0 0 0)
			(layer "B.Fab")
			(effects
				(font
					(size 1.27 1.27)
				)
				(justify mirror)
			)
		)
		(duplicate_pad_numbers_are_jumpers no)
		(fp_line
			(start -0.32512 -0.175006)
			(end -0.32512 0.175006)
			(stroke
				(width 0.1)
				(type default)
			)
			(layer "B.Fab")
		)
		(fp_line
			(start -0.32512 0.175006)
			(end 0.32512 0.175006)
			(stroke
				(width 0.1)
				(type default)
			)
			(layer "B.Fab")
		)
		(fp_line
			(start 0.32512 -0.175006)
			(end -0.32512 -0.175006)
			(stroke
				(width 0.1)
				(type default)
			)
			(layer "B.Fab")
		)
		(fp_line
			(start 0.32512 0.175006)
			(end 0.32512 -0.175006)
			(stroke
				(width 0.1)
				(type default)
			)
			(layer "B.Fab")
		)
		(pad "1" smd rect
			(at 0.2667 0 180)
			(size 0.3048 0.381)
			(layers "B.Cu" "B.Mask" "B.Paste")
			(net "P1V8_CPU1_RT_1D")
		)
		(pad "2" smd rect
			(at -0.2667 0)
			(size 0.3048 0.381)
			(layers "B.Cu" "B.Mask" "B.Paste")
			(net "SMB_RT_CPU1_P1_ROM_MUX_2D_R_SCL")
		)
	)
	(footprint ""
		(layer "B.Cu")
		(at 174.317914 -13.762228 -90)
		(property "Reference" "R332"
			(at 0 0 90)
			(layer "B.SilkS")
			(hide yes)
			(effects
				(font
					(size 1.27 1.27)
				)
				(justify mirror)
			)
		)
		(property "Value" ""
			(at 0 0 90)
			(layer "B.Fab")
			(effects
				(font
					(size 1.27 1.27)
				)
				(justify mirror)
			)
		)
		(duplicate_pad_numbers_are_jumpers no)
		(fp_line
			(start -0.7874 0.4064)
			(end 0.7874 0.4064)
			(stroke
				(width 0.1524)
				(type default)
			)
			(layer "B.SilkS")
		)
		(fp_line
			(start 0.7874 0.4064)
			(end 0.7874 -0.4064)
			(stroke
				(width 0.1524)
				(type default)
			)
			(layer "B.SilkS")
		)
		(fp_line
			(start -0.7874 -0.4064)
			(end -0.7874 0.4064)
			(stroke
				(width 0.1524)
				(type default)
			)
			(layer "B.SilkS")
		)
		(fp_line
			(start 0.7874 -0.4064)
			(end -0.7874 -0.4064)
			(stroke
				(width 0.1524)
				(type default)
			)
			(layer "B.SilkS")
		)
		(fp_line
			(start -0.67945 0.3048)
			(end -0.120396 0.3048)
			(stroke
				(width 0.1)
				(type default)
			)
			(layer "B.Fab")
		)
		(fp_line
			(start -0.120396 0.3048)
			(end -0.120396 0.2794)
			(stroke
				(width 0.1)
				(type default)
			)
			(layer "B.Fab")
		)
		(fp_line
			(start 0.12065 0.3048)
			(end 0.67945 0.3048)
			(stroke
				(width 0.1)
				(type default)
			)
			(layer "B.Fab")
		)
		(fp_line
			(start 0.67945 0.3048)
			(end 0.67945 -0.305054)
			(stroke
				(width 0.1)
				(type default)
			)
			(layer "B.Fab")
		)
		(fp_line
			(start -0.120396 0.2794)
			(end 0.12065 0.2794)
			(stroke
				(width 0.1)
				(type default)
			)
			(layer "B.Fab")
		)
		(fp_line
			(start 0.12065 0.2794)
			(end 0.12065 0.3048)
			(stroke
				(width 0.1)
				(type default)
			)
			(layer "B.Fab")
		)
		(fp_line
			(start -0.12065 -0.2794)
			(end -0.12065 -0.3048)
			(stroke
				(width 0.1)
				(type default)
			)
			(layer "B.Fab")
		)
		(fp_line
			(start 0.12065 -0.2794)
			(end -0.12065 -0.2794)
			(stroke
				(width 0.1)
				(type default)
			)
			(layer "B.Fab")
		)
		(fp_line
			(start -0.67945 -0.3048)
			(end -0.67945 0.3048)
			(stroke
				(width 0.1)
				(type default)
			)
			(layer "B.Fab")
		)
		(fp_line
			(start -0.12065 -0.3048)
			(end -0.67945 -0.3048)
			(stroke
				(width 0.1)
				(type default)
			)
			(layer "B.Fab")
		)
		(fp_line
			(start 0.12065 -0.305054)
			(end 0.12065 -0.2794)
			(stroke
				(width 0.1)
				(type default)
			)
			(layer "B.Fab")
		)
		(fp_line
			(start 0.67945 -0.305054)
			(end 0.12065 -0.305054)
			(stroke
				(width 0.1)
				(type default)
			)
			(layer "B.Fab")
		)
		(pad "1" smd circle
			(at 0.40005 0 90)
			(size 0 0)
			(layers "B.Cu" "B.Mask" "B.Paste")
			(net "I3C_BMC_SWB_SCL")
		)
		(pad "2" smd circle
			(at -0.40005 0 90)
			(size 0 0)
			(layers "B.Cu" "B.Mask" "B.Paste")
			(net "P3V3_AUX")
		)
	)
	(footprint ""
		(layer "B.Cu")
		(at 231.872536 -326.07885 180)
		(property "Reference" "R1250"
			(at 0 0 0)
			(layer "B.SilkS")
			(hide yes)
			(effects
				(font
					(size 1.27 1.27)
				)
				(justify mirror)
			)
		)
		(property "Value" ""
			(at 0 0 0)
			(layer "B.Fab")
			(effects
				(font
					(size 1.27 1.27)
				)
				(justify mirror)
			)
		)
		(duplicate_pad_numbers_are_jumpers no)
		(fp_line
			(start 0.7874 0.4064)
			(end 0.7874 -0.4064)
			(stroke
				(width 0.1524)
				(type default)
			)
			(layer "B.SilkS")
		)
		(fp_line
			(start 0.7874 -0.4064)
			(end -0.7874 -0.4064)
			(stroke
				(width 0.1524)
				(type default)
			)
			(layer "B.SilkS")
		)
		(fp_line
			(start -0.7874 0.4064)
			(end 0.7874 0.4064)
			(stroke
				(width 0.1524)
				(type default)
			)
			(layer "B.SilkS")
		)
		(fp_line
			(start -0.7874 -0.4064)
			(end -0.7874 0.4064)
			(stroke
				(width 0.1524)
				(type default)
			)
			(layer "B.SilkS")
		)
		(fp_line
			(start 0.67945 0.3048)
			(end 0.67945 -0.305054)
			(stroke
				(width 0.1)
				(type default)
			)
			(layer "B.Fab")
		)
		(fp_line
			(start 0.67945 -0.305054)
			(end 0.12065 -0.305054)
			(stroke
				(width 0.1)
				(type default)
			)
			(layer "B.Fab")
		)
		(fp_line
			(start 0.12065 0.3048)
			(end 0.67945 0.3048)
			(stroke
				(width 0.1)
				(type default)
			)
			(layer "B.Fab")
		)
		(fp_line
			(start 0.12065 0.2794)
			(end 0.12065 0.3048)
			(stroke
				(width 0.1)
				(type default)
			)
			(layer "B.Fab")
		)
		(fp_line
			(start 0.12065 -0.2794)
			(end -0.12065 -0.2794)
			(stroke
				(width 0.1)
				(type default)
			)
			(layer "B.Fab")
		)
		(fp_line
			(start 0.12065 -0.305054)
			(end 0.12065 -0.2794)
			(stroke
				(width 0.1)
				(type default)
			)
			(layer "B.Fab")
		)
		(fp_line
			(start -0.120396 0.3048)
			(end -0.120396 0.2794)
			(stroke
				(width 0.1)
				(type default)
			)
			(layer "B.Fab")
		)
		(fp_line
			(start -0.120396 0.2794)
			(end 0.12065 0.2794)
			(stroke
				(width 0.1)
				(type default)
			)
			(layer "B.Fab")
		)
		(fp_line
			(start -0.12065 -0.2794)
			(end -0.12065 -0.3048)
			(stroke
				(width 0.1)
				(type default)
			)
			(layer "B.Fab")
		)
		(fp_line
			(start -0.12065 -0.3048)
			(end -0.67945 -0.3048)
			(stroke
				(width 0.1)
				(type default)
			)
			(layer "B.Fab")
		)
		(fp_line
			(start -0.67945 0.3048)
			(end -0.120396 0.3048)
			(stroke
				(width 0.1)
				(type default)
			)
			(layer "B.Fab")
		)
		(fp_line
			(start -0.67945 -0.3048)
			(end -0.67945 0.3048)
			(stroke
				(width 0.1)
				(type default)
			)
			(layer "B.Fab")
		)
		(pad "1" smd rect
			(at 0.40005 0 180)
			(size 0.4572 0.508)
			(layers "B.Cu" "B.Mask" "B.Paste")
			(net "P1V8_CPU1_RT_1D_ADC")
		)
		(pad "2" smd rect
			(at -0.40005 0 180)
			(size 0.4572 0.508)
			(layers "B.Cu" "B.Mask" "B.Paste")
			(net "P1V8_CPU1_RT_1D_ADC_MAM")
		)
	)
	(footprint ""
		(layer "B.Cu")
		(at 154.00782 -13.762228 90)
		(property "Reference" "R2415"
			(at 0 0 90)
			(layer "B.SilkS")
			(hide yes)
			(effects
				(font
					(size 1.27 1.27)
				)
				(justify mirror)
			)
		)
		(property "Value" ""
			(at 0 0 90)
			(layer "B.Fab")
			(effects
				(font
					(size 1.27 1.27)
				)
				(justify mirror)
			)
		)
		(duplicate_pad_numbers_are_jumpers no)
		(fp_line
			(start 0.7874 -0.4064)
			(end -0.7874 -0.4064)
			(stroke
				(width 0.1524)
				(type default)
			)
			(layer "B.SilkS")
		)
		(fp_line
			(start -0.7874 -0.4064)
			(end -0.7874 0.4064)
			(stroke
				(width 0.1524)
				(type default)
			)
			(layer "B.SilkS")
		)
		(fp_line
			(start 0.7874 0.4064)
			(end 0.7874 -0.4064)
			(stroke
				(width 0.1524)
				(type default)
			)
			(layer "B.SilkS")
		)
		(fp_line
			(start -0.7874 0.4064)
			(end 0.7874 0.4064)
			(stroke
				(width 0.1524)
				(type default)
			)
			(layer "B.SilkS")
		)
		(fp_line
			(start 0.67945 -0.305054)
			(end 0.12065 -0.305054)
			(stroke
				(width 0.1)
				(type default)
			)
			(layer "B.Fab")
		)
		(fp_line
			(start 0.12065 -0.305054)
			(end 0.12065 -0.2794)
			(stroke
				(width 0.1)
				(type default)
			)
			(layer "B.Fab")
		)
		(fp_line
			(start -0.12065 -0.3048)
			(end -0.67945 -0.3048)
			(stroke
				(width 0.1)
				(type default)
			)
			(layer "B.Fab")
		)
		(fp_line
			(start -0.67945 -0.3048)
			(end -0.67945 0.3048)
			(stroke
				(width 0.1)
				(type default)
			)
			(layer "B.Fab")
		)
		(fp_line
			(start 0.12065 -0.2794)
			(end -0.12065 -0.2794)
			(stroke
				(width 0.1)
				(type default)
			)
			(layer "B.Fab")
		)
		(fp_line
			(start -0.12065 -0.2794)
			(end -0.12065 -0.3048)
			(stroke
				(width 0.1)
				(type default)
			)
			(layer "B.Fab")
		)
		(fp_line
			(start 0.12065 0.2794)
			(end 0.12065 0.3048)
			(stroke
				(width 0.1)
				(type default)
			)
			(layer "B.Fab")
		)
		(fp_line
			(start -0.120396 0.2794)
			(end 0.12065 0.2794)
			(stroke
				(width 0.1)
				(type default)
			)
			(layer "B.Fab")
		)
		(fp_line
			(start 0.67945 0.3048)
			(end 0.67945 -0.305054)
			(stroke
				(width 0.1)
				(type default)
			)
			(layer "B.Fab")
		)
		(fp_line
			(start 0.12065 0.3048)
			(end 0.67945 0.3048)
			(stroke
				(width 0.1)
				(type default)
			)
			(layer "B.Fab")
		)
		(fp_line
			(start -0.120396 0.3048)
			(end -0.120396 0.2794)
			(stroke
				(width 0.1)
				(type default)
			)
			(layer "B.Fab")
		)
		(fp_line
			(start -0.67945 0.3048)
			(end -0.120396 0.3048)
			(stroke
				(width 0.1)
				(type default)
			)
			(layer "B.Fab")
		)
		(pad "1" smd circle
			(at 0.40005 0 270)
			(size 0 0)
			(layers "B.Cu" "B.Mask" "B.Paste")
			(net "SMB_1_BMC_GPU_SCL")
		)
		(pad "2" smd circle
			(at -0.40005 0 270)
			(size 0 0)
			(layers "B.Cu" "B.Mask" "B.Paste")
			(net "SMB_PCIE3_3V3AUX_SCL_R")
		)
	)
	(footprint ""
		(layer "B.Cu")
		(at 111.477044 -261.748016 90)
		(property "Reference" "C2291"
			(at 0 0 90)
			(layer "B.SilkS")
			(hide yes)
			(effects
				(font
					(size 1.27 1.27)
				)
				(justify mirror)
			)
		)
		(property "Value" ""
			(at 0 0 90)
			(layer "B.Fab")
			(effects
				(font
					(size 1.27 1.27)
				)
				(justify mirror)
			)
		)
		(duplicate_pad_numbers_are_jumpers no)
		(fp_line
			(start 0.7874 -0.4064)
			(end -0.7874 -0.4064)
			(stroke
				(width 0.1524)
				(type default)
			)
			(layer "B.SilkS")
		)
		(fp_line
			(start -0.7874 -0.4064)
			(end -0.7874 0.4064)
			(stroke
				(width 0.1524)
				(type default)
			)
			(layer "B.SilkS")
		)
		(fp_line
			(start 0.7874 0.4064)
			(end 0.7874 -0.4064)
			(stroke
				(width 0.1524)
				(type default)
			)
			(layer "B.SilkS")
		)
		(fp_line
			(start -0.7874 0.4064)
			(end 0.7874 0.4064)
			(stroke
				(width 0.1524)
				(type default)
			)
			(layer "B.SilkS")
		)
		(fp_line
			(start 0.67945 -0.305054)
			(end 0.12065 -0.305054)
			(stroke
				(width 0.1)
				(type default)
			)
			(layer "B.Fab")
		)
		(fp_line
			(start 0.12065 -0.305054)
			(end 0.12065 -0.2794)
			(stroke
				(width 0.1)
				(type default)
			)
			(layer "B.Fab")
		)
		(fp_line
			(start -0.12065 -0.3048)
			(end -0.67945 -0.3048)
			(stroke
				(width 0.1)
				(type default)
			)
			(layer "B.Fab")
		)
		(fp_line
			(start -0.67945 -0.3048)
			(end -0.67945 0.3048)
			(stroke
				(width 0.1)
				(type default)
			)
			(layer "B.Fab")
		)
		(fp_line
			(start 0.12065 -0.2794)
			(end -0.12065 -0.2794)
			(stroke
				(width 0.1)
				(type default)
			)
			(layer "B.Fab")
		)
		(fp_line
			(start -0.12065 -0.2794)
			(end -0.12065 -0.3048)
			(stroke
				(width 0.1)
				(type default)
			)
			(layer "B.Fab")
		)
		(fp_line
			(start 0.12065 0.2794)
			(end 0.12065 0.3048)
			(stroke
				(width 0.1)
				(type default)
			)
			(layer "B.Fab")
		)
		(fp_line
			(start -0.120396 0.2794)
			(end 0.12065 0.2794)
			(stroke
				(width 0.1)
				(type default)
			)
			(layer "B.Fab")
		)
		(fp_line
			(start 0.67945 0.3048)
			(end 0.67945 -0.305054)
			(stroke
				(width 0.1)
				(type default)
			)
			(layer "B.Fab")
		)
		(fp_line
			(start 0.12065 0.3048)
			(end 0.67945 0.3048)
			(stroke
				(width 0.1)
				(type default)
			)
			(layer "B.Fab")
		)
		(fp_line
			(start -0.120396 0.3048)
			(end -0.120396 0.2794)
			(stroke
				(width 0.1)
				(type default)
			)
			(layer "B.Fab")
		)
		(fp_line
			(start -0.67945 0.3048)
			(end -0.120396 0.3048)
			(stroke
				(width 0.1)
				(type default)
			)
			(layer "B.Fab")
		)
		(pad "1" smd circle
			(at 0.40005 0 270)
			(size 0 0)
			(layers "B.Cu" "B.Mask" "B.Paste")
			(net "PVDD11_S3_P1")
		)
		(pad "2" smd circle
			(at -0.40005 0 270)
			(size 0 0)
			(layers "B.Cu" "B.Mask" "B.Paste")
			(net "GND")
		)
	)
	(footprint ""
		(layer "B.Cu")
		(at 105.960164 -255.555242 180)
		(property "Reference" "C3909"
			(at 0 0 0)
			(layer "B.SilkS")
			(hide yes)
			(effects
				(font
					(size 1.27 1.27)
				)
				(justify mirror)
			)
		)
		(property "Value" ""
			(at 0 0 0)
			(layer "B.Fab")
			(effects
				(font
					(size 1.27 1.27)
				)
				(justify mirror)
			)
		)
		(duplicate_pad_numbers_are_jumpers no)
		(fp_line
			(start 0.7874 0.4064)
			(end 0.7874 -0.4064)
			(stroke
				(width 0.1524)
				(type default)
			)
			(layer "B.SilkS")
		)
		(fp_line
			(start 0.7874 -0.4064)
			(end -0.7874 -0.4064)
			(stroke
				(width 0.1524)
				(type default)
			)
			(layer "B.SilkS")
		)
		(fp_line
			(start -0.7874 0.4064)
			(end 0.7874 0.4064)
			(stroke
				(width 0.1524)
				(type default)
			)
			(layer "B.SilkS")
		)
		(fp_line
			(start -0.7874 -0.4064)
			(end -0.7874 0.4064)
			(stroke
				(width 0.1524)
				(type default)
			)
			(layer "B.SilkS")
		)
		(fp_line
			(start 0.67945 0.3048)
			(end 0.67945 -0.305054)
			(stroke
				(width 0.1)
				(type default)
			)
			(layer "B.Fab")
		)
		(fp_line
			(start 0.67945 -0.305054)
			(end 0.12065 -0.305054)
			(stroke
				(width 0.1)
				(type default)
			)
			(layer "B.Fab")
		)
		(fp_line
			(start 0.12065 0.3048)
			(end 0.67945 0.3048)
			(stroke
				(width 0.1)
				(type default)
			)
			(layer "B.Fab")
		)
		(fp_line
			(start 0.12065 0.2794)
			(end 0.12065 0.3048)
			(stroke
				(width 0.1)
				(type default)
			)
			(layer "B.Fab")
		)
		(fp_line
			(start 0.12065 -0.2794)
			(end -0.12065 -0.2794)
			(stroke
				(width 0.1)
				(type default)
			)
			(layer "B.Fab")
		)
		(fp_line
			(start 0.12065 -0.305054)
			(end 0.12065 -0.2794)
			(stroke
				(width 0.1)
				(type default)
			)
			(layer "B.Fab")
		)
		(fp_line
			(start -0.120396 0.3048)
			(end -0.120396 0.2794)
			(stroke
				(width 0.1)
				(type default)
			)
			(layer "B.Fab")
		)
		(fp_line
			(start -0.120396 0.2794)
			(end 0.12065 0.2794)
			(stroke
				(width 0.1)
				(type default)
			)
			(layer "B.Fab")
		)
		(fp_line
			(start -0.12065 -0.2794)
			(end -0.12065 -0.3048)
			(stroke
				(width 0.1)
				(type default)
			)
			(layer "B.Fab")
		)
		(fp_line
			(start -0.12065 -0.3048)
			(end -0.67945 -0.3048)
			(stroke
				(width 0.1)
				(type default)
			)
			(layer "B.Fab")
		)
		(fp_line
			(start -0.67945 0.3048)
			(end -0.120396 0.3048)
			(stroke
				(width 0.1)
				(type default)
			)
			(layer "B.Fab")
		)
		(fp_line
			(start -0.67945 -0.3048)
			(end -0.67945 0.3048)
			(stroke
				(width 0.1)
				(type default)
			)
			(layer "B.Fab")
		)
		(pad "1" smd circle
			(at 0.40005 0)
			(size 0 0)
			(layers "B.Cu" "B.Mask" "B.Paste")
			(net "PVDD18_S5_P1")
		)
		(pad "2" smd circle
			(at -0.40005 0)
			(size 0 0)
			(layers "B.Cu" "B.Mask" "B.Paste")
			(net "GND")
		)
	)
	(footprint ""
		(layer "B.Cu")
		(at 350.723454 -266.00531)
		(property "Reference" "C2629"
			(at 0 0 0)
			(layer "B.SilkS")
			(hide yes)
			(effects
				(font
					(size 1.27 1.27)
				)
				(justify mirror)
			)
		)
		(property "Value" ""
			(at 0 0 0)
			(layer "B.Fab")
			(effects
				(font
					(size 1.27 1.27)
				)
				(justify mirror)
			)
		)
		(duplicate_pad_numbers_are_jumpers no)
		(fp_line
			(start -0.7874 -0.4064)
			(end -0.7874 0.4064)
			(stroke
				(width 0.1524)
				(type default)
			)
			(layer "B.SilkS")
		)
		(fp_line
			(start -0.7874 0.4064)
			(end 0.7874 0.4064)
			(stroke
				(width 0.1524)
				(type default)
			)
			(layer "B.SilkS")
		)
		(fp_line
			(start 0.7874 -0.4064)
			(end -0.7874 -0.4064)
			(stroke
				(width 0.1524)
				(type default)
			)
			(layer "B.SilkS")
		)
		(fp_line
			(start 0.7874 0.4064)
			(end 0.7874 -0.4064)
			(stroke
				(width 0.1524)
				(type default)
			)
			(layer "B.SilkS")
		)
		(fp_line
			(start -0.67945 -0.3048)
			(end -0.67945 0.3048)
			(stroke
				(width 0.1)
				(type default)
			)
			(layer "B.Fab")
		)
		(fp_line
			(start -0.67945 0.3048)
			(end -0.120396 0.3048)
			(stroke
				(width 0.1)
				(type default)
			)
			(layer "B.Fab")
		)
		(fp_line
			(start -0.12065 -0.3048)
			(end -0.67945 -0.3048)
			(stroke
				(width 0.1)
				(type default)
			)
			(layer "B.Fab")
		)
		(fp_line
			(start -0.12065 -0.2794)
			(end -0.12065 -0.3048)
			(stroke
				(width 0.1)
				(type default)
			)
			(layer "B.Fab")
		)
		(fp_line
			(start -0.120396 0.2794)
			(end 0.12065 0.2794)
			(stroke
				(width 0.1)
				(type default)
			)
			(layer "B.Fab")
		)
		(fp_line
			(start -0.120396 0.3048)
			(end -0.120396 0.2794)
			(stroke
				(width 0.1)
				(type default)
			)
			(layer "B.Fab")
		)
		(fp_line
			(start 0.12065 -0.305054)
			(end 0.12065 -0.2794)
			(stroke
				(width 0.1)
				(type default)
			)
			(layer "B.Fab")
		)
		(fp_line
			(start 0.12065 -0.2794)
			(end -0.12065 -0.2794)
			(stroke
				(width 0.1)
				(type default)
			)
			(layer "B.Fab")
		)
		(fp_line
			(start 0.12065 0.2794)
			(end 0.12065 0.3048)
			(stroke
				(width 0.1)
				(type default)
			)
			(layer "B.Fab")
		)
		(fp_line
			(start 0.12065 0.3048)
			(end 0.67945 0.3048)
			(stroke
				(width 0.1)
				(type default)
			)
			(layer "B.Fab")
		)
		(fp_line
			(start 0.67945 -0.305054)
			(end 0.12065 -0.305054)
			(stroke
				(width 0.1)
				(type default)
			)
			(layer "B.Fab")
		)
		(fp_line
			(start 0.67945 0.3048)
			(end 0.67945 -0.305054)
			(stroke
				(width 0.1)
				(type default)
			)
			(layer "B.Fab")
		)
		(pad "1" smd circle
			(at 0.40005 0 180)
			(size 0 0)
			(layers "B.Cu" "B.Mask" "B.Paste")
			(net "PVDD11_S3_P0")
		)
		(pad "2" smd circle
			(at -0.40005 0 180)
			(size 0 0)
			(layers "B.Cu" "B.Mask" "B.Paste")
			(net "GND")
		)
	)
	(footprint ""
		(layer "B.Cu")
		(at 398.040606 -397.228568)
		(property "Reference" "C802"
			(at 0 0 0)
			(layer "B.SilkS")
			(hide yes)
			(effects
				(font
					(size 1.27 1.27)
				)
				(justify mirror)
			)
		)
		(property "Value" ""
			(at 0 0 0)
			(layer "B.Fab")
			(effects
				(font
					(size 1.27 1.27)
				)
				(justify mirror)
			)
		)
		(duplicate_pad_numbers_are_jumpers no)
		(fp_line
			(start -1.524 -0.762)
			(end -1.524 0.762)
			(stroke
				(width 0.1524)
				(type default)
			)
			(layer "B.SilkS")
		)
		(fp_line
			(start -1.524 0.762)
			(end 1.524 0.762)
			(stroke
				(width 0.1524)
				(type default)
			)
			(layer "B.SilkS")
		)
		(fp_line
			(start 1.524 -0.762)
			(end -1.524 -0.762)
			(stroke
				(width 0.1524)
				(type default)
			)
			(layer "B.SilkS")
		)
		(fp_line
			(start 1.524 0.762)
			(end 1.524 -0.762)
			(stroke
				(width 0.1524)
				(type default)
			)
			(layer "B.SilkS")
		)
		(fp_line
			(start -1.1049 -0.724916)
			(end 1.1049 -0.724916)
			(stroke
				(width 0.1)
				(type default)
			)
			(layer "B.Fab")
		)
		(fp_line
			(start -1.1049 0.724916)
			(end -1.1049 -0.724916)
			(stroke
				(width 0.1)
				(type default)
			)
			(layer "B.Fab")
		)
		(fp_line
			(start 1.1049 -0.724916)
			(end 1.1049 0.724916)
			(stroke
				(width 0.1)
				(type default)
			)
			(layer "B.Fab")
		)
		(fp_line
			(start 1.1049 0.724916)
			(end -1.1049 0.724916)
			(stroke
				(width 0.1)
				(type default)
			)
			(layer "B.Fab")
		)
		(pad "1" smd rect
			(at 0.889 0)
			(size 1.016 1.27)
			(layers "B.Cu" "B.Mask" "B.Paste")
			(net "P0V9_CPU0_RT2_2A")
		)
		(pad "2" smd rect
			(at -0.889 0)
			(size 1.016 1.27)
			(layers "B.Cu" "B.Mask" "B.Paste")
			(net "GND")
		)
	)
	(footprint ""
		(layer "B.Cu")
		(at 375.604786 -214.523828 90)
		(property "Reference" "R8566"
			(at 0 0 90)
			(layer "B.SilkS")
			(hide yes)
			(effects
				(font
					(size 1.27 1.27)
				)
				(justify mirror)
			)
		)
		(property "Value" ""
			(at 0 0 90)
			(layer "B.Fab")
			(effects
				(font
					(size 1.27 1.27)
				)
				(justify mirror)
			)
		)
		(duplicate_pad_numbers_are_jumpers no)
		(fp_line
			(start 0.7874 -0.4064)
			(end -0.7874 -0.4064)
			(stroke
				(width 0.1524)
				(type default)
			)
			(layer "B.SilkS")
		)
		(fp_line
			(start -0.7874 -0.4064)
			(end -0.7874 0.010414)
			(stroke
				(width 0.1524)
				(type default)
			)
			(layer "B.SilkS")
		)
		(fp_line
			(start 0.7874 -0.014986)
			(end 0.7874 -0.4064)
			(stroke
				(width 0.1524)
				(type default)
			)
			(layer "B.SilkS")
		)
		(fp_line
			(start -0.351028 0.4064)
			(end 0.385572 0.4064)
			(stroke
				(width 0.1524)
				(type default)
			)
			(layer "B.SilkS")
		)
		(fp_line
			(start 0.67945 -0.305054)
			(end 0.12065 -0.305054)
			(stroke
				(width 0.1)
				(type default)
			)
			(layer "B.Fab")
		)
		(fp_line
			(start 0.12065 -0.305054)
			(end 0.12065 -0.2794)
			(stroke
				(width 0.1)
				(type default)
			)
			(layer "B.Fab")
		)
		(fp_line
			(start -0.12065 -0.3048)
			(end -0.67945 -0.3048)
			(stroke
				(width 0.1)
				(type default)
			)
			(layer "B.Fab")
		)
		(fp_line
			(start -0.67945 -0.3048)
			(end -0.67945 0.3048)
			(stroke
				(width 0.1)
				(type default)
			)
			(layer "B.Fab")
		)
		(fp_line
			(start 0.12065 -0.2794)
			(end -0.12065 -0.2794)
			(stroke
				(width 0.1)
				(type default)
			)
			(layer "B.Fab")
		)
		(fp_line
			(start -0.12065 -0.2794)
			(end -0.12065 -0.3048)
			(stroke
				(width 0.1)
				(type default)
			)
			(layer "B.Fab")
		)
		(fp_line
			(start 0.12065 0.2794)
			(end 0.12065 0.3048)
			(stroke
				(width 0.1)
				(type default)
			)
			(layer "B.Fab")
		)
		(fp_line
			(start -0.120396 0.2794)
			(end 0.12065 0.2794)
			(stroke
				(width 0.1)
				(type default)
			)
			(layer "B.Fab")
		)
		(fp_line
			(start 0.67945 0.3048)
			(end 0.67945 -0.305054)
			(stroke
				(width 0.1)
				(type default)
			)
			(layer "B.Fab")
		)
		(fp_line
			(start 0.12065 0.3048)
			(end 0.67945 0.3048)
			(stroke
				(width 0.1)
				(type default)
			)
			(layer "B.Fab")
		)
		(fp_line
			(start -0.120396 0.3048)
			(end -0.120396 0.2794)
			(stroke
				(width 0.1)
				(type default)
			)
			(layer "B.Fab")
		)
		(fp_line
			(start -0.67945 0.3048)
			(end -0.120396 0.3048)
			(stroke
				(width 0.1)
				(type default)
			)
			(layer "B.Fab")
		)
		(pad "1" smd circle
			(at 0.40005 0 270)
			(size 0 0)
			(layers "B.Cu" "B.Mask" "B.Paste")
			(net "CLK_100M_CPU0_CLK03_R_DN")
		)
		(pad "2" smd circle
			(at -0.40005 0 270)
			(size 0 0)
			(layers "B.Cu" "B.Mask" "B.Paste")
			(net "CLK_100M_CPU0_CLK03_DN")
		)
	)
	(footprint ""
		(layer "B.Cu")
		(at 197.269608 -119.721376 180)
		(property "Reference" "R4558"
			(at 0 0 0)
			(layer "B.SilkS")
			(hide yes)
			(effects
				(font
					(size 1.27 1.27)
				)
				(justify mirror)
			)
		)
		(property "Value" ""
			(at 0 0 0)
			(layer "B.Fab")
			(effects
				(font
					(size 1.27 1.27)
				)
				(justify mirror)
			)
		)
		(duplicate_pad_numbers_are_jumpers no)
		(fp_line
			(start 0.7874 0.4064)
			(end 0.7874 -0.4064)
			(stroke
				(width 0.1524)
				(type default)
			)
			(layer "B.SilkS")
		)
		(fp_line
			(start 0.7874 -0.4064)
			(end -0.7874 -0.4064)
			(stroke
				(width 0.1524)
				(type default)
			)
			(layer "B.SilkS")
		)
		(fp_line
			(start -0.7874 0.4064)
			(end 0.7874 0.4064)
			(stroke
				(width 0.1524)
				(type default)
			)
			(layer "B.SilkS")
		)
		(fp_line
			(start -0.7874 -0.4064)
			(end -0.7874 0.4064)
			(stroke
				(width 0.1524)
				(type default)
			)
			(layer "B.SilkS")
		)
		(fp_line
			(start 0.67945 0.3048)
			(end 0.67945 -0.305054)
			(stroke
				(width 0.1)
				(type default)
			)
			(layer "B.Fab")
		)
		(fp_line
			(start 0.67945 -0.305054)
			(end 0.12065 -0.305054)
			(stroke
				(width 0.1)
				(type default)
			)
			(layer "B.Fab")
		)
		(fp_line
			(start 0.12065 0.3048)
			(end 0.67945 0.3048)
			(stroke
				(width 0.1)
				(type default)
			)
			(layer "B.Fab")
		)
		(fp_line
			(start 0.12065 0.2794)
			(end 0.12065 0.3048)
			(stroke
				(width 0.1)
				(type default)
			)
			(layer "B.Fab")
		)
		(fp_line
			(start 0.12065 -0.2794)
			(end -0.12065 -0.2794)
			(stroke
				(width 0.1)
				(type default)
			)
			(layer "B.Fab")
		)
		(fp_line
			(start 0.12065 -0.305054)
			(end 0.12065 -0.2794)
			(stroke
				(width 0.1)
				(type default)
			)
			(layer "B.Fab")
		)
		(fp_line
			(start -0.120396 0.3048)
			(end -0.120396 0.2794)
			(stroke
				(width 0.1)
				(type default)
			)
			(layer "B.Fab")
		)
		(fp_line
			(start -0.120396 0.2794)
			(end 0.12065 0.2794)
			(stroke
				(width 0.1)
				(type default)
			)
			(layer "B.Fab")
		)
		(fp_line
			(start -0.12065 -0.2794)
			(end -0.12065 -0.3048)
			(stroke
				(width 0.1)
				(type default)
			)
			(layer "B.Fab")
		)
		(fp_line
			(start -0.12065 -0.3048)
			(end -0.67945 -0.3048)
			(stroke
				(width 0.1)
				(type default)
			)
			(layer "B.Fab")
		)
		(fp_line
			(start -0.67945 0.3048)
			(end -0.120396 0.3048)
			(stroke
				(width 0.1)
				(type default)
			)
			(layer "B.Fab")
		)
		(fp_line
			(start -0.67945 -0.3048)
			(end -0.67945 0.3048)
			(stroke
				(width 0.1)
				(type default)
			)
			(layer "B.Fab")
		)
		(pad "1" smd circle
			(at 0.40005 0)
			(size 0 0)
			(layers "B.Cu" "B.Mask" "B.Paste")
			(net "SWB_HSC_EN_R")
		)
		(pad "2" smd circle
			(at -0.40005 0)
			(size 0 0)
			(layers "B.Cu" "B.Mask" "B.Paste")
			(net "SWB_HSC_EN")
		)
	)
	(footprint ""
		(layer "B.Cu")
		(at 383.655316 -191.334898 90)
		(property "Reference" "PC562_3"
			(at 0 0 90)
			(layer "B.SilkS")
			(hide yes)
			(effects
				(font
					(size 1.27 1.27)
				)
				(justify mirror)
			)
		)
		(property "Value" ""
			(at 0 0 90)
			(layer "B.Fab")
			(effects
				(font
					(size 1.27 1.27)
				)
				(justify mirror)
			)
		)
		(duplicate_pad_numbers_are_jumpers no)
		(fp_line
			(start 1.524 -0.762)
			(end -1.524 -0.762)
			(stroke
				(width 0.1524)
				(type default)
			)
			(layer "B.SilkS")
		)
		(fp_line
			(start -1.524 -0.762)
			(end -1.524 0.762)
			(stroke
				(width 0.1524)
				(type default)
			)
			(layer "B.SilkS")
		)
		(fp_line
			(start 1.524 0.762)
			(end 1.524 -0.762)
			(stroke
				(width 0.1524)
				(type default)
			)
			(layer "B.SilkS")
		)
		(fp_line
			(start -1.524 0.762)
			(end 1.524 0.762)
			(stroke
				(width 0.1524)
				(type default)
			)
			(layer "B.SilkS")
		)
		(fp_line
			(start 1.1049 -0.724916)
			(end 1.1049 0.724916)
			(stroke
				(width 0.1)
				(type default)
			)
			(layer "B.Fab")
		)
		(fp_line
			(start -1.1049 -0.724916)
			(end 1.1049 -0.724916)
			(stroke
				(width 0.1)
				(type default)
			)
			(layer "B.Fab")
		)
		(fp_line
			(start 1.1049 0.724916)
			(end -1.1049 0.724916)
			(stroke
				(width 0.1)
				(type default)
			)
			(layer "B.Fab")
		)
		(fp_line
			(start -1.1049 0.724916)
			(end -1.1049 -0.724916)
			(stroke
				(width 0.1)
				(type default)
			)
			(layer "B.Fab")
		)
		(pad "1" smd rect
			(at 0.889 0 90)
			(size 1.016 1.27)
			(layers "B.Cu" "B.Mask" "B.Paste")
			(net "PVDDCR_CPU0_P0")
		)
		(pad "2" smd rect
			(at -0.889 0 90)
			(size 1.016 1.27)
			(layers "B.Cu" "B.Mask" "B.Paste")
			(net "GND")
		)
	)
	(footprint ""
		(layer "B.Cu")
		(at 87.432134 -182.607966 -90)
		(property "Reference" "PC269_2"
			(at 0 0 90)
			(layer "B.SilkS")
			(hide yes)
			(effects
				(font
					(size 1.27 1.27)
				)
				(justify mirror)
			)
		)
		(property "Value" ""
			(at 0 0 90)
			(layer "B.Fab")
			(effects
				(font
					(size 1.27 1.27)
				)
				(justify mirror)
			)
		)
		(duplicate_pad_numbers_are_jumpers no)
		(fp_line
			(start -1.524 0.762)
			(end 1.524 0.762)
			(stroke
				(width 0.1524)
				(type default)
			)
			(layer "B.SilkS")
		)
		(fp_line
			(start 1.524 0.762)
			(end 1.524 -0.762)
			(stroke
				(width 0.1524)
				(type default)
			)
			(layer "B.SilkS")
		)
		(fp_line
			(start -1.524 -0.762)
			(end -1.524 0.762)
			(stroke
				(width 0.1524)
				(type default)
			)
			(layer "B.SilkS")
		)
		(fp_line
			(start 1.524 -0.762)
			(end -1.524 -0.762)
			(stroke
				(width 0.1524)
				(type default)
			)
			(layer "B.SilkS")
		)
		(fp_line
			(start -1.1049 0.724916)
			(end -1.1049 -0.724916)
			(stroke
				(width 0.1)
				(type default)
			)
			(layer "B.Fab")
		)
		(fp_line
			(start 1.1049 0.724916)
			(end -1.1049 0.724916)
			(stroke
				(width 0.1)
				(type default)
			)
			(layer "B.Fab")
		)
		(fp_line
			(start -1.1049 -0.724916)
			(end 1.1049 -0.724916)
			(stroke
				(width 0.1)
				(type default)
			)
			(layer "B.Fab")
		)
		(fp_line
			(start 1.1049 -0.724916)
			(end 1.1049 0.724916)
			(stroke
				(width 0.1)
				(type default)
			)
			(layer "B.Fab")
		)
		(pad "1" smd rect
			(at 0.889 0 270)
			(size 1.016 1.27)
			(layers "B.Cu" "B.Mask" "B.Paste")
			(net "SW_P12V_AUX_PVDDCR_CPU0_P1_FLT")
		)
		(pad "2" smd rect
			(at -0.889 0 270)
			(size 1.016 1.27)
			(layers "B.Cu" "B.Mask" "B.Paste")
			(net "GND")
		)
	)
	(footprint ""
		(layer "B.Cu")
		(at 179.162964 -425.394882 90)
		(property "Reference" "U142"
			(at 3.405632 2.674874 0)
			(unlocked yes)
			(layer "B.SilkS")
			(effects
				(font
					(size 0.7874 0.5842)
					(thickness 0.1524)
				)
				(justify left mirror)
			)
		)
		(property "Value" ""
			(at 0 0 90)
			(layer "B.Fab")
			(effects
				(font
					(size 1.27 1.27)
				)
				(justify mirror)
			)
		)
		(duplicate_pad_numbers_are_jumpers no)
		(fp_line
			(start 2.046478 -1.450086)
			(end 2.046478 1.450086)
			(stroke
				(width 0.1524)
				(type default)
			)
			(layer "B.SilkS")
		)
		(fp_line
			(start 0.484886 -1.450086)
			(end 2.046478 -1.450086)
			(stroke
				(width 0.1524)
				(type default)
			)
			(layer "B.SilkS")
		)
		(fp_line
			(start -0.484886 -1.450086)
			(end 0 -0.762)
			(stroke
				(width 0.1524)
				(type default)
			)
			(layer "B.SilkS")
		)
		(fp_line
			(start -2.046478 -1.450086)
			(end -0.484886 -1.450086)
			(stroke
				(width 0.1524)
				(type default)
			)
			(layer "B.SilkS")
		)
		(fp_line
			(start 0 -0.762)
			(end 0.484886 -1.450086)
			(stroke
				(width 0.1524)
				(type default)
			)
			(layer "B.SilkS")
		)
		(fp_line
			(start 2.046478 1.450086)
			(end -2.046478 1.450086)
			(stroke
				(width 0.1524)
				(type default)
			)
			(layer "B.SilkS")
		)
		(fp_line
			(start -2.046478 1.450086)
			(end -2.046478 -1.450086)
			(stroke
				(width 0.1524)
				(type default)
			)
			(layer "B.SilkS")
		)
		(fp_poly
			(pts
				(xy 2.2352 -0.94996) (xy 3.2512 -0.44196) (xy 3.2512 -1.45796)
			)
			(stroke
				(width 0)
				(type default)
			)
			(fill yes)
			(layer "B.SilkS")
		)
		(fp_line
			(start 0.87503 -1.450086)
			(end 0.87503 1.450086)
			(stroke
				(width 0.1)
				(type default)
			)
			(layer "B.Fab")
		)
		(fp_line
			(start -0.87503 -1.450086)
			(end 0.87503 -1.450086)
			(stroke
				(width 0.1)
				(type default)
			)
			(layer "B.Fab")
		)
		(fp_line
			(start 0.87503 1.450086)
			(end -0.87503 1.450086)
			(stroke
				(width 0.1)
				(type default)
			)
			(layer "B.Fab")
		)
		(fp_line
			(start -0.87503 1.450086)
			(end -0.87503 -1.450086)
			(stroke
				(width 0.1)
				(type default)
			)
			(layer "B.Fab")
		)
		(fp_poly
			(pts
				(xy 3.2512 -0.44196) (xy 3.2512 -1.45796) (xy 2.2352 -0.94996)
			)
			(stroke
				(width 0)
				(type default)
			)
			(fill yes)
			(layer "B.Fab")
		)
		(pad "1" smd rect
			(at 1.309878 -0.94996 180)
			(size 0.635 1.2192)
			(layers "B.Cu" "B.Mask" "B.Paste")
			(net "A_HSC_LOW_GATE")
		)
		(pad "2" smd rect
			(at 1.309878 0 180)
			(size 0.635 1.2192)
			(layers "B.Cu" "B.Mask" "B.Paste")
			(net "GND")
		)
		(pad "3" smd rect
			(at 1.309878 0.94996 180)
			(size 0.635 1.2192)
			(layers "B.Cu" "B.Mask" "B.Paste")
			(net "A_HSC_LOW")
		)
		(pad "4" smd rect
			(at -1.309878 0.94996 180)
			(size 0.635 1.2192)
			(layers "B.Cu" "B.Mask" "B.Paste")
			(net "A_HSC_HIGH")
		)
		(pad "5" smd rect
			(at -1.309878 0 180)
			(size 0.635 1.2192)
			(layers "B.Cu" "B.Mask" "B.Paste")
			(net "U142_VS")
		)
		(pad "6" smd rect
			(at -1.309878 -0.94996 180)
			(size 0.635 1.2192)
			(layers "B.Cu" "B.Mask" "B.Paste")
			(net "HSC_D_OC")
		)
	)
	(footprint ""
		(layer "B.Cu")
		(at 29.722318 -350.660716 -90)
		(property "Reference" "PC629_4"
			(at 0 0 90)
			(layer "B.SilkS")
			(hide yes)
			(effects
				(font
					(size 1.27 1.27)
				)
				(justify mirror)
			)
		)
		(property "Value" ""
			(at 0 0 90)
			(layer "B.Fab")
			(effects
				(font
					(size 1.27 1.27)
				)
				(justify mirror)
			)
		)
		(duplicate_pad_numbers_are_jumpers no)
		(fp_line
			(start -1.524 0.762)
			(end 1.524 0.762)
			(stroke
				(width 0.1524)
				(type default)
			)
			(layer "B.SilkS")
		)
		(fp_line
			(start 1.524 0.762)
			(end 1.524 -0.762)
			(stroke
				(width 0.1524)
				(type default)
			)
			(layer "B.SilkS")
		)
		(fp_line
			(start -1.524 -0.762)
			(end -1.524 0.762)
			(stroke
				(width 0.1524)
				(type default)
			)
			(layer "B.SilkS")
		)
		(fp_line
			(start 1.524 -0.762)
			(end -1.524 -0.762)
			(stroke
				(width 0.1524)
				(type default)
			)
			(layer "B.SilkS")
		)
		(fp_line
			(start -1.1049 0.724916)
			(end -1.1049 -0.724916)
			(stroke
				(width 0.1)
				(type default)
			)
			(layer "B.Fab")
		)
		(fp_line
			(start 1.1049 0.724916)
			(end -1.1049 0.724916)
			(stroke
				(width 0.1)
				(type default)
			)
			(layer "B.Fab")
		)
		(fp_line
			(start -1.1049 -0.724916)
			(end 1.1049 -0.724916)
			(stroke
				(width 0.1)
				(type default)
			)
			(layer "B.Fab")
		)
		(fp_line
			(start 1.1049 -0.724916)
			(end 1.1049 0.724916)
			(stroke
				(width 0.1)
				(type default)
			)
			(layer "B.Fab")
		)
		(pad "1" smd rect
			(at 0.889 0 270)
			(size 1.016 1.27)
			(layers "B.Cu" "B.Mask" "B.Paste")
			(net "SW_P12V_AUX_PVDDIO_P1_FLT")
		)
		(pad "2" smd rect
			(at -0.889 0 270)
			(size 1.016 1.27)
			(layers "B.Cu" "B.Mask" "B.Paste")
			(net "GND")
		)
	)
	(footprint ""
		(layer "B.Cu")
		(at 354.025454 -268.41831)
		(property "Reference" "C2229"
			(at 0 0 0)
			(layer "B.SilkS")
			(hide yes)
			(effects
				(font
					(size 1.27 1.27)
				)
				(justify mirror)
			)
		)
		(property "Value" ""
			(at 0 0 0)
			(layer "B.Fab")
			(effects
				(font
					(size 1.27 1.27)
				)
				(justify mirror)
			)
		)
		(duplicate_pad_numbers_are_jumpers no)
		(fp_line
			(start -0.7874 -0.4064)
			(end -0.7874 0.4064)
			(stroke
				(width 0.1524)
				(type default)
			)
			(layer "B.SilkS")
		)
		(fp_line
			(start -0.7874 0.4064)
			(end 0.7874 0.4064)
			(stroke
				(width 0.1524)
				(type default)
			)
			(layer "B.SilkS")
		)
		(fp_line
			(start 0.7874 -0.4064)
			(end -0.7874 -0.4064)
			(stroke
				(width 0.1524)
				(type default)
			)
			(layer "B.SilkS")
		)
		(fp_line
			(start 0.7874 0.4064)
			(end 0.7874 -0.4064)
			(stroke
				(width 0.1524)
				(type default)
			)
			(layer "B.SilkS")
		)
		(fp_line
			(start -0.67945 -0.3048)
			(end -0.67945 0.3048)
			(stroke
				(width 0.1)
				(type default)
			)
			(layer "B.Fab")
		)
		(fp_line
			(start -0.67945 0.3048)
			(end -0.120396 0.3048)
			(stroke
				(width 0.1)
				(type default)
			)
			(layer "B.Fab")
		)
		(fp_line
			(start -0.12065 -0.3048)
			(end -0.67945 -0.3048)
			(stroke
				(width 0.1)
				(type default)
			)
			(layer "B.Fab")
		)
		(fp_line
			(start -0.12065 -0.2794)
			(end -0.12065 -0.3048)
			(stroke
				(width 0.1)
				(type default)
			)
			(layer "B.Fab")
		)
		(fp_line
			(start -0.120396 0.2794)
			(end 0.12065 0.2794)
			(stroke
				(width 0.1)
				(type default)
			)
			(layer "B.Fab")
		)
		(fp_line
			(start -0.120396 0.3048)
			(end -0.120396 0.2794)
			(stroke
				(width 0.1)
				(type default)
			)
			(layer "B.Fab")
		)
		(fp_line
			(start 0.12065 -0.305054)
			(end 0.12065 -0.2794)
			(stroke
				(width 0.1)
				(type default)
			)
			(layer "B.Fab")
		)
		(fp_line
			(start 0.12065 -0.2794)
			(end -0.12065 -0.2794)
			(stroke
				(width 0.1)
				(type default)
			)
			(layer "B.Fab")
		)
		(fp_line
			(start 0.12065 0.2794)
			(end 0.12065 0.3048)
			(stroke
				(width 0.1)
				(type default)
			)
			(layer "B.Fab")
		)
		(fp_line
			(start 0.12065 0.3048)
			(end 0.67945 0.3048)
			(stroke
				(width 0.1)
				(type default)
			)
			(layer "B.Fab")
		)
		(fp_line
			(start 0.67945 -0.305054)
			(end 0.12065 -0.305054)
			(stroke
				(width 0.1)
				(type default)
			)
			(layer "B.Fab")
		)
		(fp_line
			(start 0.67945 0.3048)
			(end 0.67945 -0.305054)
			(stroke
				(width 0.1)
				(type default)
			)
			(layer "B.Fab")
		)
		(pad "1" smd circle
			(at 0.40005 0 180)
			(size 0 0)
			(layers "B.Cu" "B.Mask" "B.Paste")
			(net "PVDDCR_CPU1_P0")
		)
		(pad "2" smd circle
			(at -0.40005 0 180)
			(size 0 0)
			(layers "B.Cu" "B.Mask" "B.Paste")
			(net "GND")
		)
	)
	(footprint ""
		(layer "B.Cu")
		(at 58.19521 -244.085364)
		(property "Reference" "R500"
			(at 0 0 0)
			(layer "B.SilkS")
			(hide yes)
			(effects
				(font
					(size 1.27 1.27)
				)
				(justify mirror)
			)
		)
		(property "Value" ""
			(at 0 0 0)
			(layer "B.Fab")
			(effects
				(font
					(size 1.27 1.27)
				)
				(justify mirror)
			)
		)
		(duplicate_pad_numbers_are_jumpers no)
		(fp_line
			(start -0.7874 -0.4064)
			(end -0.7874 0.4064)
			(stroke
				(width 0.1524)
				(type default)
			)
			(layer "B.SilkS")
		)
		(fp_line
			(start -0.7874 0.4064)
			(end 0.7874 0.4064)
			(stroke
				(width 0.1524)
				(type default)
			)
			(layer "B.SilkS")
		)
		(fp_line
			(start 0.7874 -0.4064)
			(end -0.7874 -0.4064)
			(stroke
				(width 0.1524)
				(type default)
			)
			(layer "B.SilkS")
		)
		(fp_line
			(start 0.7874 0.4064)
			(end 0.7874 -0.4064)
			(stroke
				(width 0.1524)
				(type default)
			)
			(layer "B.SilkS")
		)
		(fp_line
			(start -0.67945 -0.3048)
			(end -0.67945 0.3048)
			(stroke
				(width 0.1)
				(type default)
			)
			(layer "B.Fab")
		)
		(fp_line
			(start -0.67945 0.3048)
			(end -0.120396 0.3048)
			(stroke
				(width 0.1)
				(type default)
			)
			(layer "B.Fab")
		)
		(fp_line
			(start -0.12065 -0.3048)
			(end -0.67945 -0.3048)
			(stroke
				(width 0.1)
				(type default)
			)
			(layer "B.Fab")
		)
		(fp_line
			(start -0.12065 -0.2794)
			(end -0.12065 -0.3048)
			(stroke
				(width 0.1)
				(type default)
			)
			(layer "B.Fab")
		)
		(fp_line
			(start -0.120396 0.2794)
			(end 0.12065 0.2794)
			(stroke
				(width 0.1)
				(type default)
			)
			(layer "B.Fab")
		)
		(fp_line
			(start -0.120396 0.3048)
			(end -0.120396 0.2794)
			(stroke
				(width 0.1)
				(type default)
			)
			(layer "B.Fab")
		)
		(fp_line
			(start 0.12065 -0.305054)
			(end 0.12065 -0.2794)
			(stroke
				(width 0.1)
				(type default)
			)
			(layer "B.Fab")
		)
		(fp_line
			(start 0.12065 -0.2794)
			(end -0.12065 -0.2794)
			(stroke
				(width 0.1)
				(type default)
			)
			(layer "B.Fab")
		)
		(fp_line
			(start 0.12065 0.2794)
			(end 0.12065 0.3048)
			(stroke
				(width 0.1)
				(type default)
			)
			(layer "B.Fab")
		)
		(fp_line
			(start 0.12065 0.3048)
			(end 0.67945 0.3048)
			(stroke
				(width 0.1)
				(type default)
			)
			(layer "B.Fab")
		)
		(fp_line
			(start 0.67945 -0.305054)
			(end 0.12065 -0.305054)
			(stroke
				(width 0.1)
				(type default)
			)
			(layer "B.Fab")
		)
		(fp_line
			(start 0.67945 0.3048)
			(end 0.67945 -0.305054)
			(stroke
				(width 0.1)
				(type default)
			)
			(layer "B.Fab")
		)
		(pad "1" smd circle
			(at 0.40005 0 180)
			(size 0 0)
			(layers "B.Cu" "B.Mask" "B.Paste")
			(net "M_A_CPU1_ALERT_N")
		)
		(pad "2" smd circle
			(at -0.40005 0 180)
			(size 0 0)
			(layers "B.Cu" "B.Mask" "B.Paste")
			(net "M_A_CPU1_ALERT_R_N")
		)
	)
	(footprint ""
		(layer "B.Cu")
		(at 300.304454 -190.82131)
		(property "Reference" "R291"
			(at 0 0 0)
			(layer "B.SilkS")
			(hide yes)
			(effects
				(font
					(size 1.27 1.27)
				)
				(justify mirror)
			)
		)
		(property "Value" ""
			(at 0 0 0)
			(layer "B.Fab")
			(effects
				(font
					(size 1.27 1.27)
				)
				(justify mirror)
			)
		)
		(duplicate_pad_numbers_are_jumpers no)
		(fp_line
			(start -0.7874 -0.4064)
			(end -0.7874 0.4064)
			(stroke
				(width 0.1524)
				(type default)
			)
			(layer "B.SilkS")
		)
		(fp_line
			(start -0.7874 0.4064)
			(end 0.7874 0.4064)
			(stroke
				(width 0.1524)
				(type default)
			)
			(layer "B.SilkS")
		)
		(fp_line
			(start 0.7874 -0.4064)
			(end -0.7874 -0.4064)
			(stroke
				(width 0.1524)
				(type default)
			)
			(layer "B.SilkS")
		)
		(fp_line
			(start 0.7874 0.4064)
			(end 0.7874 -0.4064)
			(stroke
				(width 0.1524)
				(type default)
			)
			(layer "B.SilkS")
		)
		(fp_line
			(start -0.67945 -0.3048)
			(end -0.67945 0.3048)
			(stroke
				(width 0.1)
				(type default)
			)
			(layer "B.Fab")
		)
		(fp_line
			(start -0.67945 0.3048)
			(end -0.120396 0.3048)
			(stroke
				(width 0.1)
				(type default)
			)
			(layer "B.Fab")
		)
		(fp_line
			(start -0.12065 -0.3048)
			(end -0.67945 -0.3048)
			(stroke
				(width 0.1)
				(type default)
			)
			(layer "B.Fab")
		)
		(fp_line
			(start -0.12065 -0.2794)
			(end -0.12065 -0.3048)
			(stroke
				(width 0.1)
				(type default)
			)
			(layer "B.Fab")
		)
		(fp_line
			(start -0.120396 0.2794)
			(end 0.12065 0.2794)
			(stroke
				(width 0.1)
				(type default)
			)
			(layer "B.Fab")
		)
		(fp_line
			(start -0.120396 0.3048)
			(end -0.120396 0.2794)
			(stroke
				(width 0.1)
				(type default)
			)
			(layer "B.Fab")
		)
		(fp_line
			(start 0.12065 -0.305054)
			(end 0.12065 -0.2794)
			(stroke
				(width 0.1)
				(type default)
			)
			(layer "B.Fab")
		)
		(fp_line
			(start 0.12065 -0.2794)
			(end -0.12065 -0.2794)
			(stroke
				(width 0.1)
				(type default)
			)
			(layer "B.Fab")
		)
		(fp_line
			(start 0.12065 0.2794)
			(end 0.12065 0.3048)
			(stroke
				(width 0.1)
				(type default)
			)
			(layer "B.Fab")
		)
		(fp_line
			(start 0.12065 0.3048)
			(end 0.67945 0.3048)
			(stroke
				(width 0.1)
				(type default)
			)
			(layer "B.Fab")
		)
		(fp_line
			(start 0.67945 -0.305054)
			(end 0.12065 -0.305054)
			(stroke
				(width 0.1)
				(type default)
			)
			(layer "B.Fab")
		)
		(fp_line
			(start 0.67945 0.3048)
			(end 0.67945 -0.305054)
			(stroke
				(width 0.1)
				(type default)
			)
			(layer "B.Fab")
		)
		(pad "1" smd circle
			(at 0.40005 0 180)
			(size 0 0)
			(layers "B.Cu" "B.Mask" "B.Paste")
			(net "PWRGD_CHA_CPU0_DIMM0")
		)
		(pad "2" smd circle
			(at -0.40005 0 180)
			(size 0 0)
			(layers "B.Cu" "B.Mask" "B.Paste")
			(net "PWRGD_CHAF_CPU0")
		)
	)
	(footprint ""
		(layer "B.Cu")
		(at 144.102582 -17.313148 90)
		(property "Reference" "R1546"
			(at 0 0 90)
			(layer "B.SilkS")
			(hide yes)
			(effects
				(font
					(size 1.27 1.27)
				)
				(justify mirror)
			)
		)
		(property "Value" ""
			(at 0 0 90)
			(layer "B.Fab")
			(effects
				(font
					(size 1.27 1.27)
				)
				(justify mirror)
			)
		)
		(duplicate_pad_numbers_are_jumpers no)
		(fp_line
			(start 0.7874 -0.4064)
			(end -0.7874 -0.4064)
			(stroke
				(width 0.1524)
				(type default)
			)
			(layer "B.SilkS")
		)
		(fp_line
			(start -0.7874 -0.4064)
			(end -0.7874 0.4064)
			(stroke
				(width 0.1524)
				(type default)
			)
			(layer "B.SilkS")
		)
		(fp_line
			(start 0.7874 0.4064)
			(end 0.7874 -0.4064)
			(stroke
				(width 0.1524)
				(type default)
			)
			(layer "B.SilkS")
		)
		(fp_line
			(start -0.7874 0.4064)
			(end 0.7874 0.4064)
			(stroke
				(width 0.1524)
				(type default)
			)
			(layer "B.SilkS")
		)
		(fp_line
			(start 0.67945 -0.305054)
			(end 0.12065 -0.305054)
			(stroke
				(width 0.1)
				(type default)
			)
			(layer "B.Fab")
		)
		(fp_line
			(start 0.12065 -0.305054)
			(end 0.12065 -0.2794)
			(stroke
				(width 0.1)
				(type default)
			)
			(layer "B.Fab")
		)
		(fp_line
			(start -0.12065 -0.3048)
			(end -0.67945 -0.3048)
			(stroke
				(width 0.1)
				(type default)
			)
			(layer "B.Fab")
		)
		(fp_line
			(start -0.67945 -0.3048)
			(end -0.67945 0.3048)
			(stroke
				(width 0.1)
				(type default)
			)
			(layer "B.Fab")
		)
		(fp_line
			(start 0.12065 -0.2794)
			(end -0.12065 -0.2794)
			(stroke
				(width 0.1)
				(type default)
			)
			(layer "B.Fab")
		)
		(fp_line
			(start -0.12065 -0.2794)
			(end -0.12065 -0.3048)
			(stroke
				(width 0.1)
				(type default)
			)
			(layer "B.Fab")
		)
		(fp_line
			(start 0.12065 0.2794)
			(end 0.12065 0.3048)
			(stroke
				(width 0.1)
				(type default)
			)
			(layer "B.Fab")
		)
		(fp_line
			(start -0.120396 0.2794)
			(end 0.12065 0.2794)
			(stroke
				(width 0.1)
				(type default)
			)
			(layer "B.Fab")
		)
		(fp_line
			(start 0.67945 0.3048)
			(end 0.67945 -0.305054)
			(stroke
				(width 0.1)
				(type default)
			)
			(layer "B.Fab")
		)
		(fp_line
			(start 0.12065 0.3048)
			(end 0.67945 0.3048)
			(stroke
				(width 0.1)
				(type default)
			)
			(layer "B.Fab")
		)
		(fp_line
			(start -0.120396 0.3048)
			(end -0.120396 0.2794)
			(stroke
				(width 0.1)
				(type default)
			)
			(layer "B.Fab")
		)
		(fp_line
			(start -0.67945 0.3048)
			(end -0.120396 0.3048)
			(stroke
				(width 0.1)
				(type default)
			)
			(layer "B.Fab")
		)
		(pad "1" smd circle
			(at 0.40005 0 270)
			(size 0 0)
			(layers "B.Cu" "B.Mask" "B.Paste")
			(net "P3V3_AUX")
		)
		(pad "2" smd circle
			(at -0.40005 0 270)
			(size 0 0)
			(layers "B.Cu" "B.Mask" "B.Paste")
			(net "RST_MB_STBY_N")
		)
	)
	(footprint ""
		(layer "B.Cu")
		(at 184.785 -144.399 180)
		(property "Reference" "U8000"
			(at 0.625602 -2.39903 0)
			(unlocked yes)
			(layer "B.SilkS")
			(effects
				(font
					(size 0.7874 0.5842)
					(thickness 0.1524)
				)
				(justify mirror)
			)
		)
		(property "Value" ""
			(at 0 0 0)
			(layer "B.Fab")
			(effects
				(font
					(size 1.27 1.27)
				)
				(justify mirror)
			)
		)
		(duplicate_pad_numbers_are_jumpers no)
		(fp_line
			(start 1.34493 1.100074)
			(end 1.34493 -1.100074)
			(stroke
				(width 0.1524)
				(type default)
			)
			(layer "B.SilkS")
		)
		(fp_line
			(start 1.34493 -1.100074)
			(end 0.420878 -1.100074)
			(stroke
				(width 0.1524)
				(type default)
			)
			(layer "B.SilkS")
		)
		(fp_line
			(start 0.420878 -1.100074)
			(end -0.039878 -0.592074)
			(stroke
				(width 0.1524)
				(type default)
			)
			(layer "B.SilkS")
		)
		(fp_line
			(start -0.039878 -0.592074)
			(end -0.420878 -1.100074)
			(stroke
				(width 0.1524)
				(type default)
			)
			(layer "B.SilkS")
		)
		(fp_line
			(start -0.420878 -1.100074)
			(end -1.35509 -1.100074)
			(stroke
				(width 0.1524)
				(type default)
			)
			(layer "B.SilkS")
		)
		(fp_line
			(start -1.35509 1.100074)
			(end 1.34493 1.100074)
			(stroke
				(width 0.1524)
				(type default)
			)
			(layer "B.SilkS")
		)
		(fp_line
			(start -1.35509 -1.100074)
			(end -1.35509 1.100074)
			(stroke
				(width 0.1524)
				(type default)
			)
			(layer "B.SilkS")
		)
		(fp_poly
			(pts
				(xy 1.867662 -1.667764) (xy 2.324608 -1.058164) (xy 1.486408 -0.906018)
			)
			(stroke
				(width 0)
				(type default)
			)
			(fill yes)
			(layer "B.SilkS")
		)
		(fp_line
			(start 0.674878 1.100074)
			(end 0.674878 -1.100074)
			(stroke
				(width 0.1)
				(type default)
			)
			(layer "B.Fab")
		)
		(fp_line
			(start 0.674878 -1.100074)
			(end -0.674878 -1.100074)
			(stroke
				(width 0.1)
				(type default)
			)
			(layer "B.Fab")
		)
		(fp_line
			(start -0.674878 1.100074)
			(end 0.674878 1.100074)
			(stroke
				(width 0.1)
				(type default)
			)
			(layer "B.Fab")
		)
		(fp_line
			(start -0.674878 -1.100074)
			(end -0.674878 1.100074)
			(stroke
				(width 0.1)
				(type default)
			)
			(layer "B.Fab")
		)
		(fp_poly
			(pts
				(xy 2.286 -1.030986) (xy 2.286 -0.268986) (xy 1.524 -0.649986)
			)
			(stroke
				(width 0)
				(type default)
			)
			(fill yes)
			(layer "B.Fab")
		)
		(pad "1" smd rect
			(at 0.94996 -0.649986 90)
			(size 0.4064 0.508)
			(layers "B.Cu" "B.Mask" "B.Paste")
			(net "ESPI_CPU0_ALERT_R1_N")
		)
		(pad "2" smd rect
			(at 0.94996 0 90)
			(size 0.4064 0.508)
			(layers "B.Cu" "B.Mask" "B.Paste")
			(net "GND")
		)
		(pad "3" smd rect
			(at 0.94996 0.649986 90)
			(size 0.4064 0.508)
			(layers "B.Cu" "B.Mask" "B.Paste")
			(net "ESPI_CPU0_ALERT_PLD_N")
		)
		(pad "4" smd rect
			(at -0.94996 0.649986 90)
			(size 0.4064 0.508)
			(layers "B.Cu" "B.Mask" "B.Paste")
			(net "ESPI_CPU0_ALERT_P0_N")
		)
		(pad "5" smd rect
			(at -0.94996 0 90)
			(size 0.4064 0.508)
			(layers "B.Cu" "B.Mask" "B.Paste")
			(net "P1V8_AUX")
		)
		(pad "6" smd rect
			(at -0.94996 -0.649986 90)
			(size 0.4064 0.508)
			(layers "B.Cu" "B.Mask" "B.Paste")
			(net "FM_ESPI_CPU0_ALERT_R_SEL")
		)
	)
	(footprint ""
		(layer "B.Cu")
		(at 284.82417 -350.65589 -90)
		(property "Reference" "PC187_3"
			(at 0 0 90)
			(layer "B.SilkS")
			(hide yes)
			(effects
				(font
					(size 1.27 1.27)
				)
				(justify mirror)
			)
		)
		(property "Value" ""
			(at 0 0 90)
			(layer "B.Fab")
			(effects
				(font
					(size 1.27 1.27)
				)
				(justify mirror)
			)
		)
		(duplicate_pad_numbers_are_jumpers no)
		(fp_line
			(start -1.524 0.762)
			(end 1.524 0.762)
			(stroke
				(width 0.1524)
				(type default)
			)
			(layer "B.SilkS")
		)
		(fp_line
			(start 1.524 0.762)
			(end 1.524 -0.762)
			(stroke
				(width 0.1524)
				(type default)
			)
			(layer "B.SilkS")
		)
		(fp_line
			(start -1.524 -0.762)
			(end -1.524 0.762)
			(stroke
				(width 0.1524)
				(type default)
			)
			(layer "B.SilkS")
		)
		(fp_line
			(start 1.524 -0.762)
			(end -1.524 -0.762)
			(stroke
				(width 0.1524)
				(type default)
			)
			(layer "B.SilkS")
		)
		(fp_line
			(start -1.1049 0.724916)
			(end -1.1049 -0.724916)
			(stroke
				(width 0.1)
				(type default)
			)
			(layer "B.Fab")
		)
		(fp_line
			(start 1.1049 0.724916)
			(end -1.1049 0.724916)
			(stroke
				(width 0.1)
				(type default)
			)
			(layer "B.Fab")
		)
		(fp_line
			(start -1.1049 -0.724916)
			(end 1.1049 -0.724916)
			(stroke
				(width 0.1)
				(type default)
			)
			(layer "B.Fab")
		)
		(fp_line
			(start 1.1049 -0.724916)
			(end 1.1049 0.724916)
			(stroke
				(width 0.1)
				(type default)
			)
			(layer "B.Fab")
		)
		(pad "1" smd rect
			(at 0.889 0 270)
			(size 1.016 1.27)
			(layers "B.Cu" "B.Mask" "B.Paste")
			(net "SW_P12V_AUX_PVDDIO_P0_FLT")
		)
		(pad "2" smd rect
			(at -0.889 0 270)
			(size 1.016 1.27)
			(layers "B.Cu" "B.Mask" "B.Paste")
			(net "GND")
		)
	)
	(footprint ""
		(layer "B.Cu")
		(at 309.39105 -398.942052 90)
		(property "Reference" "C569"
			(at 0 0 90)
			(layer "B.SilkS")
			(hide yes)
			(effects
				(font
					(size 1.27 1.27)
				)
				(justify mirror)
			)
		)
		(property "Value" ""
			(at 0 0 90)
			(layer "B.Fab")
			(effects
				(font
					(size 1.27 1.27)
				)
				(justify mirror)
			)
		)
		(duplicate_pad_numbers_are_jumpers no)
		(fp_line
			(start 0.7874 -0.4064)
			(end -0.7874 -0.4064)
			(stroke
				(width 0.1524)
				(type default)
			)
			(layer "B.SilkS")
		)
		(fp_line
			(start -0.7874 -0.4064)
			(end -0.7874 0.4064)
			(stroke
				(width 0.1524)
				(type default)
			)
			(layer "B.SilkS")
		)
		(fp_line
			(start 0.7874 0.4064)
			(end 0.7874 -0.4064)
			(stroke
				(width 0.1524)
				(type default)
			)
			(layer "B.SilkS")
		)
		(fp_line
			(start -0.7874 0.4064)
			(end 0.7874 0.4064)
			(stroke
				(width 0.1524)
				(type default)
			)
			(layer "B.SilkS")
		)
		(fp_line
			(start 0.67945 -0.305054)
			(end 0.12065 -0.305054)
			(stroke
				(width 0.1)
				(type default)
			)
			(layer "B.Fab")
		)
		(fp_line
			(start 0.12065 -0.305054)
			(end 0.12065 -0.2794)
			(stroke
				(width 0.1)
				(type default)
			)
			(layer "B.Fab")
		)
		(fp_line
			(start -0.12065 -0.3048)
			(end -0.67945 -0.3048)
			(stroke
				(width 0.1)
				(type default)
			)
			(layer "B.Fab")
		)
		(fp_line
			(start -0.67945 -0.3048)
			(end -0.67945 0.3048)
			(stroke
				(width 0.1)
				(type default)
			)
			(layer "B.Fab")
		)
		(fp_line
			(start 0.12065 -0.2794)
			(end -0.12065 -0.2794)
			(stroke
				(width 0.1)
				(type default)
			)
			(layer "B.Fab")
		)
		(fp_line
			(start -0.12065 -0.2794)
			(end -0.12065 -0.3048)
			(stroke
				(width 0.1)
				(type default)
			)
			(layer "B.Fab")
		)
		(fp_line
			(start 0.12065 0.2794)
			(end 0.12065 0.3048)
			(stroke
				(width 0.1)
				(type default)
			)
			(layer "B.Fab")
		)
		(fp_line
			(start -0.120396 0.2794)
			(end 0.12065 0.2794)
			(stroke
				(width 0.1)
				(type default)
			)
			(layer "B.Fab")
		)
		(fp_line
			(start 0.67945 0.3048)
			(end 0.67945 -0.305054)
			(stroke
				(width 0.1)
				(type default)
			)
			(layer "B.Fab")
		)
		(fp_line
			(start 0.12065 0.3048)
			(end 0.67945 0.3048)
			(stroke
				(width 0.1)
				(type default)
			)
			(layer "B.Fab")
		)
		(fp_line
			(start -0.120396 0.3048)
			(end -0.120396 0.2794)
			(stroke
				(width 0.1)
				(type default)
			)
			(layer "B.Fab")
		)
		(fp_line
			(start -0.67945 0.3048)
			(end -0.120396 0.3048)
			(stroke
				(width 0.1)
				(type default)
			)
			(layer "B.Fab")
		)
		(pad "1" smd circle
			(at 0.40005 0 270)
			(size 0 0)
			(layers "B.Cu" "B.Mask" "B.Paste")
			(net "P0V9_CPU0_RT_2D")
		)
		(pad "2" smd circle
			(at -0.40005 0 270)
			(size 0 0)
			(layers "B.Cu" "B.Mask" "B.Paste")
			(net "GND")
		)
	)
	(footprint ""
		(layer "B.Cu")
		(at 199.941942 -346.023184)
		(property "Reference" "PC8000"
			(at 0 0 0)
			(layer "B.SilkS")
			(hide yes)
			(effects
				(font
					(size 1.27 1.27)
				)
				(justify mirror)
			)
		)
		(property "Value" ""
			(at 0 0 0)
			(layer "B.Fab")
			(effects
				(font
					(size 1.27 1.27)
				)
				(justify mirror)
			)
		)
		(duplicate_pad_numbers_are_jumpers no)
		(fp_line
			(start -1.524 -0.762)
			(end -1.524 0.762)
			(stroke
				(width 0.1524)
				(type default)
			)
			(layer "B.SilkS")
		)
		(fp_line
			(start -1.524 0.762)
			(end 1.524 0.762)
			(stroke
				(width 0.1524)
				(type default)
			)
			(layer "B.SilkS")
		)
		(fp_line
			(start 1.524 -0.762)
			(end -1.524 -0.762)
			(stroke
				(width 0.1524)
				(type default)
			)
			(layer "B.SilkS")
		)
		(fp_line
			(start 1.524 0.762)
			(end 1.524 -0.762)
			(stroke
				(width 0.1524)
				(type default)
			)
			(layer "B.SilkS")
		)
		(fp_line
			(start -1.1049 -0.724916)
			(end 1.1049 -0.724916)
			(stroke
				(width 0.1)
				(type default)
			)
			(layer "B.Fab")
		)
		(fp_line
			(start -1.1049 0.724916)
			(end -1.1049 -0.724916)
			(stroke
				(width 0.1)
				(type default)
			)
			(layer "B.Fab")
		)
		(fp_line
			(start 1.1049 -0.724916)
			(end 1.1049 0.724916)
			(stroke
				(width 0.1)
				(type default)
			)
			(layer "B.Fab")
		)
		(fp_line
			(start 1.1049 0.724916)
			(end -1.1049 0.724916)
			(stroke
				(width 0.1)
				(type default)
			)
			(layer "B.Fab")
		)
		(pad "1" smd rect
			(at 0.889 0)
			(size 1.016 1.27)
			(layers "B.Cu" "B.Mask" "B.Paste")
			(net "SW_P12V_AUX_PVDD_33_S5_FLT")
		)
		(pad "2" smd rect
			(at -0.889 0)
			(size 1.016 1.27)
			(layers "B.Cu" "B.Mask" "B.Paste")
			(net "GND")
		)
	)
	(footprint ""
		(layer "B.Cu")
		(at 119.103648 -165.079934 -90)
		(property "Reference" "PC335_2"
			(at 0 0 90)
			(layer "B.SilkS")
			(hide yes)
			(effects
				(font
					(size 1.27 1.27)
				)
				(justify mirror)
			)
		)
		(property "Value" ""
			(at 0 0 90)
			(layer "B.Fab")
			(effects
				(font
					(size 1.27 1.27)
				)
				(justify mirror)
			)
		)
		(duplicate_pad_numbers_are_jumpers no)
		(fp_line
			(start -1.524 0.762)
			(end 1.524 0.762)
			(stroke
				(width 0.1524)
				(type default)
			)
			(layer "B.SilkS")
		)
		(fp_line
			(start 1.524 0.762)
			(end 1.524 -0.762)
			(stroke
				(width 0.1524)
				(type default)
			)
			(layer "B.SilkS")
		)
		(fp_line
			(start -1.524 -0.762)
			(end -1.524 0.762)
			(stroke
				(width 0.1524)
				(type default)
			)
			(layer "B.SilkS")
		)
		(fp_line
			(start 1.524 -0.762)
			(end -1.524 -0.762)
			(stroke
				(width 0.1524)
				(type default)
			)
			(layer "B.SilkS")
		)
		(fp_line
			(start -1.1049 0.724916)
			(end -1.1049 -0.724916)
			(stroke
				(width 0.1)
				(type default)
			)
			(layer "B.Fab")
		)
		(fp_line
			(start 1.1049 0.724916)
			(end -1.1049 0.724916)
			(stroke
				(width 0.1)
				(type default)
			)
			(layer "B.Fab")
		)
		(fp_line
			(start -1.1049 -0.724916)
			(end 1.1049 -0.724916)
			(stroke
				(width 0.1)
				(type default)
			)
			(layer "B.Fab")
		)
		(fp_line
			(start 1.1049 -0.724916)
			(end 1.1049 0.724916)
			(stroke
				(width 0.1)
				(type default)
			)
			(layer "B.Fab")
		)
		(pad "1" smd rect
			(at 0.889 0 270)
			(size 1.016 1.27)
			(layers "B.Cu" "B.Mask" "B.Paste")
			(net "SW_P12V_AUX_PVDDCR_SOC_P1_FLT")
		)
		(pad "2" smd rect
			(at -0.889 0 270)
			(size 1.016 1.27)
			(layers "B.Cu" "B.Mask" "B.Paste")
			(net "GND")
		)
	)
	(footprint ""
		(layer "B.Cu")
		(at 218.066112 -67.661028 90)
		(property "Reference" "R83"
			(at 0 0 90)
			(layer "B.SilkS")
			(hide yes)
			(effects
				(font
					(size 1.27 1.27)
				)
				(justify mirror)
			)
		)
		(property "Value" ""
			(at 0 0 90)
			(layer "B.Fab")
			(effects
				(font
					(size 1.27 1.27)
				)
				(justify mirror)
			)
		)
		(duplicate_pad_numbers_are_jumpers no)
		(fp_line
			(start 0.7874 -0.4064)
			(end -0.7874 -0.4064)
			(stroke
				(width 0.1524)
				(type default)
			)
			(layer "B.SilkS")
		)
		(fp_line
			(start -0.7874 -0.4064)
			(end -0.7874 0.4064)
			(stroke
				(width 0.1524)
				(type default)
			)
			(layer "B.SilkS")
		)
		(fp_line
			(start 0.7874 0.4064)
			(end 0.7874 -0.4064)
			(stroke
				(width 0.1524)
				(type default)
			)
			(layer "B.SilkS")
		)
		(fp_line
			(start -0.7874 0.4064)
			(end 0.7874 0.4064)
			(stroke
				(width 0.1524)
				(type default)
			)
			(layer "B.SilkS")
		)
		(fp_line
			(start 0.67945 -0.305054)
			(end 0.12065 -0.305054)
			(stroke
				(width 0.1)
				(type default)
			)
			(layer "B.Fab")
		)
		(fp_line
			(start 0.12065 -0.305054)
			(end 0.12065 -0.2794)
			(stroke
				(width 0.1)
				(type default)
			)
			(layer "B.Fab")
		)
		(fp_line
			(start -0.12065 -0.3048)
			(end -0.67945 -0.3048)
			(stroke
				(width 0.1)
				(type default)
			)
			(layer "B.Fab")
		)
		(fp_line
			(start -0.67945 -0.3048)
			(end -0.67945 0.3048)
			(stroke
				(width 0.1)
				(type default)
			)
			(layer "B.Fab")
		)
		(fp_line
			(start 0.12065 -0.2794)
			(end -0.12065 -0.2794)
			(stroke
				(width 0.1)
				(type default)
			)
			(layer "B.Fab")
		)
		(fp_line
			(start -0.12065 -0.2794)
			(end -0.12065 -0.3048)
			(stroke
				(width 0.1)
				(type default)
			)
			(layer "B.Fab")
		)
		(fp_line
			(start 0.12065 0.2794)
			(end 0.12065 0.3048)
			(stroke
				(width 0.1)
				(type default)
			)
			(layer "B.Fab")
		)
		(fp_line
			(start -0.120396 0.2794)
			(end 0.12065 0.2794)
			(stroke
				(width 0.1)
				(type default)
			)
			(layer "B.Fab")
		)
		(fp_line
			(start 0.67945 0.3048)
			(end 0.67945 -0.305054)
			(stroke
				(width 0.1)
				(type default)
			)
			(layer "B.Fab")
		)
		(fp_line
			(start 0.12065 0.3048)
			(end 0.67945 0.3048)
			(stroke
				(width 0.1)
				(type default)
			)
			(layer "B.Fab")
		)
		(fp_line
			(start -0.120396 0.3048)
			(end -0.120396 0.2794)
			(stroke
				(width 0.1)
				(type default)
			)
			(layer "B.Fab")
		)
		(fp_line
			(start -0.67945 0.3048)
			(end -0.120396 0.3048)
			(stroke
				(width 0.1)
				(type default)
			)
			(layer "B.Fab")
		)
		(pad "1" smd circle
			(at 0.40005 0 270)
			(size 0 0)
			(layers "B.Cu" "B.Mask" "B.Paste")
			(net "RMII_BMC_OCP_TXD_0")
		)
		(pad "2" smd circle
			(at -0.40005 0 270)
			(size 0 0)
			(layers "B.Cu" "B.Mask" "B.Paste")
			(net "GND")
		)
	)
	(footprint ""
		(layer "B.Cu")
		(at 373.202454 -267.498576)
		(property "Reference" "C2223"
			(at 0 0 0)
			(layer "B.SilkS")
			(hide yes)
			(effects
				(font
					(size 1.27 1.27)
				)
				(justify mirror)
			)
		)
		(property "Value" ""
			(at 0 0 0)
			(layer "B.Fab")
			(effects
				(font
					(size 1.27 1.27)
				)
				(justify mirror)
			)
		)
		(duplicate_pad_numbers_are_jumpers no)
		(fp_line
			(start -0.7874 -0.4064)
			(end -0.7874 0.4064)
			(stroke
				(width 0.1524)
				(type default)
			)
			(layer "B.SilkS")
		)
		(fp_line
			(start -0.7874 0.4064)
			(end 0.7874 0.4064)
			(stroke
				(width 0.1524)
				(type default)
			)
			(layer "B.SilkS")
		)
		(fp_line
			(start 0.7874 -0.4064)
			(end -0.7874 -0.4064)
			(stroke
				(width 0.1524)
				(type default)
			)
			(layer "B.SilkS")
		)
		(fp_line
			(start 0.7874 0.4064)
			(end 0.7874 -0.4064)
			(stroke
				(width 0.1524)
				(type default)
			)
			(layer "B.SilkS")
		)
		(fp_line
			(start -0.67945 -0.3048)
			(end -0.67945 0.3048)
			(stroke
				(width 0.1)
				(type default)
			)
			(layer "B.Fab")
		)
		(fp_line
			(start -0.67945 0.3048)
			(end -0.120396 0.3048)
			(stroke
				(width 0.1)
				(type default)
			)
			(layer "B.Fab")
		)
		(fp_line
			(start -0.12065 -0.3048)
			(end -0.67945 -0.3048)
			(stroke
				(width 0.1)
				(type default)
			)
			(layer "B.Fab")
		)
		(fp_line
			(start -0.12065 -0.2794)
			(end -0.12065 -0.3048)
			(stroke
				(width 0.1)
				(type default)
			)
			(layer "B.Fab")
		)
		(fp_line
			(start -0.120396 0.2794)
			(end 0.12065 0.2794)
			(stroke
				(width 0.1)
				(type default)
			)
			(layer "B.Fab")
		)
		(fp_line
			(start -0.120396 0.3048)
			(end -0.120396 0.2794)
			(stroke
				(width 0.1)
				(type default)
			)
			(layer "B.Fab")
		)
		(fp_line
			(start 0.12065 -0.305054)
			(end 0.12065 -0.2794)
			(stroke
				(width 0.1)
				(type default)
			)
			(layer "B.Fab")
		)
		(fp_line
			(start 0.12065 -0.2794)
			(end -0.12065 -0.2794)
			(stroke
				(width 0.1)
				(type default)
			)
			(layer "B.Fab")
		)
		(fp_line
			(start 0.12065 0.2794)
			(end 0.12065 0.3048)
			(stroke
				(width 0.1)
				(type default)
			)
			(layer "B.Fab")
		)
		(fp_line
			(start 0.12065 0.3048)
			(end 0.67945 0.3048)
			(stroke
				(width 0.1)
				(type default)
			)
			(layer "B.Fab")
		)
		(fp_line
			(start 0.67945 -0.305054)
			(end 0.12065 -0.305054)
			(stroke
				(width 0.1)
				(type default)
			)
			(layer "B.Fab")
		)
		(fp_line
			(start 0.67945 0.3048)
			(end 0.67945 -0.305054)
			(stroke
				(width 0.1)
				(type default)
			)
			(layer "B.Fab")
		)
		(pad "1" smd circle
			(at 0.40005 0 180)
			(size 0 0)
			(layers "B.Cu" "B.Mask" "B.Paste")
			(net "PVDDCR_CPU1_P0")
		)
		(pad "2" smd circle
			(at -0.40005 0 180)
			(size 0 0)
			(layers "B.Cu" "B.Mask" "B.Paste")
			(net "GND")
		)
	)
	(footprint ""
		(layer "B.Cu")
		(at 372.251986 -214.523828 90)
		(property "Reference" "R4535"
			(at 0 0 90)
			(layer "B.SilkS")
			(hide yes)
			(effects
				(font
					(size 1.27 1.27)
				)
				(justify mirror)
			)
		)
		(property "Value" ""
			(at 0 0 90)
			(layer "B.Fab")
			(effects
				(font
					(size 1.27 1.27)
				)
				(justify mirror)
			)
		)
		(duplicate_pad_numbers_are_jumpers no)
		(fp_line
			(start 0.512572 -0.4064)
			(end -0.351028 -0.4064)
			(stroke
				(width 0.1524)
				(type default)
			)
			(layer "B.SilkS")
		)
		(fp_line
			(start -0.7874 0.061214)
			(end -0.7874 0.4064)
			(stroke
				(width 0.1524)
				(type default)
			)
			(layer "B.SilkS")
		)
		(fp_line
			(start 0.7874 0.4064)
			(end 0.7874 0.061214)
			(stroke
				(width 0.1524)
				(type default)
			)
			(layer "B.SilkS")
		)
		(fp_line
			(start -0.7874 0.4064)
			(end 0.7874 0.4064)
			(stroke
				(width 0.1524)
				(type default)
			)
			(layer "B.SilkS")
		)
		(fp_line
			(start 0.67945 -0.305054)
			(end 0.12065 -0.305054)
			(stroke
				(width 0.1)
				(type default)
			)
			(layer "B.Fab")
		)
		(fp_line
			(start 0.12065 -0.305054)
			(end 0.12065 -0.2794)
			(stroke
				(width 0.1)
				(type default)
			)
			(layer "B.Fab")
		)
		(fp_line
			(start -0.12065 -0.3048)
			(end -0.67945 -0.3048)
			(stroke
				(width 0.1)
				(type default)
			)
			(layer "B.Fab")
		)
		(fp_line
			(start -0.67945 -0.3048)
			(end -0.67945 0.3048)
			(stroke
				(width 0.1)
				(type default)
			)
			(layer "B.Fab")
		)
		(fp_line
			(start 0.12065 -0.2794)
			(end -0.12065 -0.2794)
			(stroke
				(width 0.1)
				(type default)
			)
			(layer "B.Fab")
		)
		(fp_line
			(start -0.12065 -0.2794)
			(end -0.12065 -0.3048)
			(stroke
				(width 0.1)
				(type default)
			)
			(layer "B.Fab")
		)
		(fp_line
			(start 0.12065 0.2794)
			(end 0.12065 0.3048)
			(stroke
				(width 0.1)
				(type default)
			)
			(layer "B.Fab")
		)
		(fp_line
			(start -0.120396 0.2794)
			(end 0.12065 0.2794)
			(stroke
				(width 0.1)
				(type default)
			)
			(layer "B.Fab")
		)
		(fp_line
			(start 0.67945 0.3048)
			(end 0.67945 -0.305054)
			(stroke
				(width 0.1)
				(type default)
			)
			(layer "B.Fab")
		)
		(fp_line
			(start 0.12065 0.3048)
			(end 0.67945 0.3048)
			(stroke
				(width 0.1)
				(type default)
			)
			(layer "B.Fab")
		)
		(fp_line
			(start -0.120396 0.3048)
			(end -0.120396 0.2794)
			(stroke
				(width 0.1)
				(type default)
			)
			(layer "B.Fab")
		)
		(fp_line
			(start -0.67945 0.3048)
			(end -0.120396 0.3048)
			(stroke
				(width 0.1)
				(type default)
			)
			(layer "B.Fab")
		)
		(pad "1" smd circle
			(at 0.40005 0 270)
			(size 0 0)
			(layers "B.Cu" "B.Mask" "B.Paste")
			(net "CLK_100M_CPU0_CLK01_R_DP")
		)
		(pad "2" smd circle
			(at -0.40005 0 270)
			(size 0 0)
			(layers "B.Cu" "B.Mask" "B.Paste")
			(net "CLK_100M_CPU0_CLK01_DP")
		)
	)
	(footprint ""
		(layer "B.Cu")
		(at 336.279744 -154.256486 180)
		(property "Reference" "PC261"
			(at 0 0 0)
			(layer "B.SilkS")
			(hide yes)
			(effects
				(font
					(size 1.27 1.27)
				)
				(justify mirror)
			)
		)
		(property "Value" ""
			(at 0 0 0)
			(layer "B.Fab")
			(effects
				(font
					(size 1.27 1.27)
				)
				(justify mirror)
			)
		)
		(duplicate_pad_numbers_are_jumpers no)
		(fp_line
			(start 1.524 0.762)
			(end 1.524 -0.762)
			(stroke
				(width 0.1524)
				(type default)
			)
			(layer "B.SilkS")
		)
		(fp_line
			(start 1.524 -0.762)
			(end -1.524 -0.762)
			(stroke
				(width 0.1524)
				(type default)
			)
			(layer "B.SilkS")
		)
		(fp_line
			(start -1.524 0.762)
			(end 1.524 0.762)
			(stroke
				(width 0.1524)
				(type default)
			)
			(layer "B.SilkS")
		)
		(fp_line
			(start -1.524 -0.762)
			(end -1.524 0.762)
			(stroke
				(width 0.1524)
				(type default)
			)
			(layer "B.SilkS")
		)
		(fp_line
			(start 1.1049 0.724916)
			(end -1.1049 0.724916)
			(stroke
				(width 0.1)
				(type default)
			)
			(layer "B.Fab")
		)
		(fp_line
			(start 1.1049 -0.724916)
			(end 1.1049 0.724916)
			(stroke
				(width 0.1)
				(type default)
			)
			(layer "B.Fab")
		)
		(fp_line
			(start -1.1049 0.724916)
			(end -1.1049 -0.724916)
			(stroke
				(width 0.1)
				(type default)
			)
			(layer "B.Fab")
		)
		(fp_line
			(start -1.1049 -0.724916)
			(end 1.1049 -0.724916)
			(stroke
				(width 0.1)
				(type default)
			)
			(layer "B.Fab")
		)
		(pad "1" smd rect
			(at 0.889 0 180)
			(size 1.016 1.27)
			(layers "B.Cu" "B.Mask" "B.Paste")
			(net "PVDD18_S5_P0")
		)
		(pad "2" smd rect
			(at -0.889 0 180)
			(size 1.016 1.27)
			(layers "B.Cu" "B.Mask" "B.Paste")
			(net "GND")
		)
	)
	(footprint ""
		(layer "B.Cu")
		(at 86.04631 -388.011162 -90)
		(property "Reference" "C290"
			(at 0 0 90)
			(layer "B.SilkS")
			(hide yes)
			(effects
				(font
					(size 1.27 1.27)
				)
				(justify mirror)
			)
		)
		(property "Value" ""
			(at 0 0 90)
			(layer "B.Fab")
			(effects
				(font
					(size 1.27 1.27)
				)
				(justify mirror)
			)
		)
		(duplicate_pad_numbers_are_jumpers no)
		(fp_line
			(start -0.299974 0.150114)
			(end 0.299974 0.150114)
			(stroke
				(width 0.1)
				(type default)
			)
			(layer "B.Fab")
		)
		(fp_line
			(start 0.299974 0.150114)
			(end 0.299974 -0.150114)
			(stroke
				(width 0.1)
				(type default)
			)
			(layer "B.Fab")
		)
		(fp_line
			(start -0.299974 -0.150114)
			(end -0.299974 0.150114)
			(stroke
				(width 0.1)
				(type default)
			)
			(layer "B.Fab")
		)
		(fp_line
			(start 0.299974 -0.150114)
			(end -0.299974 -0.150114)
			(stroke
				(width 0.1)
				(type default)
			)
			(layer "B.Fab")
		)
		(pad "1" smd rect
			(at 0.2667 0 90)
			(size 0.3048 0.381)
			(layers "B.Cu" "B.Mask" "B.Paste")
			(net "P0V9_CPU1_RT_2D")
		)
		(pad "2" smd rect
			(at -0.2667 0 90)
			(size 0.3048 0.381)
			(layers "B.Cu" "B.Mask" "B.Paste")
			(net "GND")
		)
	)
	(footprint ""
		(layer "B.Cu")
		(at 283.980636 -194.893946 180)
		(property "Reference" "R1"
			(at 0 0 0)
			(layer "B.SilkS")
			(hide yes)
			(effects
				(font
					(size 1.27 1.27)
				)
				(justify mirror)
			)
		)
		(property "Value" ""
			(at 0 0 0)
			(layer "B.Fab")
			(effects
				(font
					(size 1.27 1.27)
				)
				(justify mirror)
			)
		)
		(duplicate_pad_numbers_are_jumpers no)
		(fp_line
			(start 0.7874 0.4064)
			(end 0.7874 -0.4064)
			(stroke
				(width 0.1524)
				(type default)
			)
			(layer "B.SilkS")
		)
		(fp_line
			(start 0.7874 -0.4064)
			(end -0.7874 -0.4064)
			(stroke
				(width 0.1524)
				(type default)
			)
			(layer "B.SilkS")
		)
		(fp_line
			(start -0.7874 0.4064)
			(end 0.7874 0.4064)
			(stroke
				(width 0.1524)
				(type default)
			)
			(layer "B.SilkS")
		)
		(fp_line
			(start -0.7874 -0.4064)
			(end -0.7874 0.4064)
			(stroke
				(width 0.1524)
				(type default)
			)
			(layer "B.SilkS")
		)
		(fp_line
			(start 0.67945 0.3048)
			(end 0.67945 -0.305054)
			(stroke
				(width 0.1)
				(type default)
			)
			(layer "B.Fab")
		)
		(fp_line
			(start 0.67945 -0.305054)
			(end 0.12065 -0.305054)
			(stroke
				(width 0.1)
				(type default)
			)
			(layer "B.Fab")
		)
		(fp_line
			(start 0.12065 0.3048)
			(end 0.67945 0.3048)
			(stroke
				(width 0.1)
				(type default)
			)
			(layer "B.Fab")
		)
		(fp_line
			(start 0.12065 0.2794)
			(end 0.12065 0.3048)
			(stroke
				(width 0.1)
				(type default)
			)
			(layer "B.Fab")
		)
		(fp_line
			(start 0.12065 -0.2794)
			(end -0.12065 -0.2794)
			(stroke
				(width 0.1)
				(type default)
			)
			(layer "B.Fab")
		)
		(fp_line
			(start 0.12065 -0.305054)
			(end 0.12065 -0.2794)
			(stroke
				(width 0.1)
				(type default)
			)
			(layer "B.Fab")
		)
		(fp_line
			(start -0.120396 0.3048)
			(end -0.120396 0.2794)
			(stroke
				(width 0.1)
				(type default)
			)
			(layer "B.Fab")
		)
		(fp_line
			(start -0.120396 0.2794)
			(end 0.12065 0.2794)
			(stroke
				(width 0.1)
				(type default)
			)
			(layer "B.Fab")
		)
		(fp_line
			(start -0.12065 -0.2794)
			(end -0.12065 -0.3048)
			(stroke
				(width 0.1)
				(type default)
			)
			(layer "B.Fab")
		)
		(fp_line
			(start -0.12065 -0.3048)
			(end -0.67945 -0.3048)
			(stroke
				(width 0.1)
				(type default)
			)
			(layer "B.Fab")
		)
		(fp_line
			(start -0.67945 0.3048)
			(end -0.120396 0.3048)
			(stroke
				(width 0.1)
				(type default)
			)
			(layer "B.Fab")
		)
		(fp_line
			(start -0.67945 -0.3048)
			(end -0.67945 0.3048)
			(stroke
				(width 0.1)
				(type default)
			)
			(layer "B.Fab")
		)
		(pad "1" smd circle
			(at 0.40005 0)
			(size 0 0)
			(layers "B.Cu" "B.Mask" "B.Paste")
			(net "I3C_SPD_DDRAF_CPU0_SCL")
		)
		(pad "2" smd circle
			(at -0.40005 0)
			(size 0 0)
			(layers "B.Cu" "B.Mask" "B.Paste")
			(net "I3C_SPD_DDRD_CPU0_SCL")
		)
	)
	(footprint ""
		(layer "B.Cu")
		(at 358.34447 -168.436798 90)
		(property "Reference" "PR352"
			(at 0 0 90)
			(layer "B.SilkS")
			(hide yes)
			(effects
				(font
					(size 1.27 1.27)
				)
				(justify mirror)
			)
		)
		(property "Value" ""
			(at 0 0 90)
			(layer "B.Fab")
			(effects
				(font
					(size 1.27 1.27)
				)
				(justify mirror)
			)
		)
		(duplicate_pad_numbers_are_jumpers no)
		(fp_line
			(start 0.7874 -0.4064)
			(end -0.7874 -0.4064)
			(stroke
				(width 0.1524)
				(type default)
			)
			(layer "B.SilkS")
		)
		(fp_line
			(start -0.7874 -0.4064)
			(end -0.7874 0.4064)
			(stroke
				(width 0.1524)
				(type default)
			)
			(layer "B.SilkS")
		)
		(fp_line
			(start 0.7874 0.4064)
			(end 0.7874 -0.4064)
			(stroke
				(width 0.1524)
				(type default)
			)
			(layer "B.SilkS")
		)
		(fp_line
			(start -0.7874 0.4064)
			(end 0.7874 0.4064)
			(stroke
				(width 0.1524)
				(type default)
			)
			(layer "B.SilkS")
		)
		(fp_line
			(start 0.67945 -0.305054)
			(end 0.12065 -0.305054)
			(stroke
				(width 0.1)
				(type default)
			)
			(layer "B.Fab")
		)
		(fp_line
			(start 0.12065 -0.305054)
			(end 0.12065 -0.2794)
			(stroke
				(width 0.1)
				(type default)
			)
			(layer "B.Fab")
		)
		(fp_line
			(start -0.12065 -0.3048)
			(end -0.67945 -0.3048)
			(stroke
				(width 0.1)
				(type default)
			)
			(layer "B.Fab")
		)
		(fp_line
			(start -0.67945 -0.3048)
			(end -0.67945 0.3048)
			(stroke
				(width 0.1)
				(type default)
			)
			(layer "B.Fab")
		)
		(fp_line
			(start 0.12065 -0.2794)
			(end -0.12065 -0.2794)
			(stroke
				(width 0.1)
				(type default)
			)
			(layer "B.Fab")
		)
		(fp_line
			(start -0.12065 -0.2794)
			(end -0.12065 -0.3048)
			(stroke
				(width 0.1)
				(type default)
			)
			(layer "B.Fab")
		)
		(fp_line
			(start 0.12065 0.2794)
			(end 0.12065 0.3048)
			(stroke
				(width 0.1)
				(type default)
			)
			(layer "B.Fab")
		)
		(fp_line
			(start -0.120396 0.2794)
			(end 0.12065 0.2794)
			(stroke
				(width 0.1)
				(type default)
			)
			(layer "B.Fab")
		)
		(fp_line
			(start 0.67945 0.3048)
			(end 0.67945 -0.305054)
			(stroke
				(width 0.1)
				(type default)
			)
			(layer "B.Fab")
		)
		(fp_line
			(start 0.12065 0.3048)
			(end 0.67945 0.3048)
			(stroke
				(width 0.1)
				(type default)
			)
			(layer "B.Fab")
		)
		(fp_line
			(start -0.120396 0.3048)
			(end -0.120396 0.2794)
			(stroke
				(width 0.1)
				(type default)
			)
			(layer "B.Fab")
		)
		(fp_line
			(start -0.67945 0.3048)
			(end -0.120396 0.3048)
			(stroke
				(width 0.1)
				(type default)
			)
			(layer "B.Fab")
		)
		(pad "1" smd circle
			(at 0.40005 0 270)
			(size 0 0)
			(layers "B.Cu" "B.Mask" "B.Paste")
			(net "PVDDCR_CPU0_P0_PVCC")
		)
		(pad "2" smd circle
			(at -0.40005 0 270)
			(size 0 0)
			(layers "B.Cu" "B.Mask" "B.Paste")
			(net "PVDDCR_CPU0_P0_VCC5")
		)
	)
	(footprint ""
		(layer "B.Cu")
		(at 164.957506 -16.44523 180)
		(property "Reference" "R2996"
			(at 0 0 0)
			(layer "B.SilkS")
			(hide yes)
			(effects
				(font
					(size 1.27 1.27)
				)
				(justify mirror)
			)
		)
		(property "Value" ""
			(at 0 0 0)
			(layer "B.Fab")
			(effects
				(font
					(size 1.27 1.27)
				)
				(justify mirror)
			)
		)
		(duplicate_pad_numbers_are_jumpers no)
		(fp_line
			(start 0.7874 0.4064)
			(end 0.7874 -0.4064)
			(stroke
				(width 0.1524)
				(type default)
			)
			(layer "B.SilkS")
		)
		(fp_line
			(start 0.7874 -0.4064)
			(end -0.7874 -0.4064)
			(stroke
				(width 0.1524)
				(type default)
			)
			(layer "B.SilkS")
		)
		(fp_line
			(start -0.7874 0.4064)
			(end 0.7874 0.4064)
			(stroke
				(width 0.1524)
				(type default)
			)
			(layer "B.SilkS")
		)
		(fp_line
			(start -0.7874 -0.4064)
			(end -0.7874 0.4064)
			(stroke
				(width 0.1524)
				(type default)
			)
			(layer "B.SilkS")
		)
		(fp_line
			(start 0.67945 0.3048)
			(end 0.67945 -0.305054)
			(stroke
				(width 0.1)
				(type default)
			)
			(layer "B.Fab")
		)
		(fp_line
			(start 0.67945 -0.305054)
			(end 0.12065 -0.305054)
			(stroke
				(width 0.1)
				(type default)
			)
			(layer "B.Fab")
		)
		(fp_line
			(start 0.12065 0.3048)
			(end 0.67945 0.3048)
			(stroke
				(width 0.1)
				(type default)
			)
			(layer "B.Fab")
		)
		(fp_line
			(start 0.12065 0.2794)
			(end 0.12065 0.3048)
			(stroke
				(width 0.1)
				(type default)
			)
			(layer "B.Fab")
		)
		(fp_line
			(start 0.12065 -0.2794)
			(end -0.12065 -0.2794)
			(stroke
				(width 0.1)
				(type default)
			)
			(layer "B.Fab")
		)
		(fp_line
			(start 0.12065 -0.305054)
			(end 0.12065 -0.2794)
			(stroke
				(width 0.1)
				(type default)
			)
			(layer "B.Fab")
		)
		(fp_line
			(start -0.120396 0.3048)
			(end -0.120396 0.2794)
			(stroke
				(width 0.1)
				(type default)
			)
			(layer "B.Fab")
		)
		(fp_line
			(start -0.120396 0.2794)
			(end 0.12065 0.2794)
			(stroke
				(width 0.1)
				(type default)
			)
			(layer "B.Fab")
		)
		(fp_line
			(start -0.12065 -0.2794)
			(end -0.12065 -0.3048)
			(stroke
				(width 0.1)
				(type default)
			)
			(layer "B.Fab")
		)
		(fp_line
			(start -0.12065 -0.3048)
			(end -0.67945 -0.3048)
			(stroke
				(width 0.1)
				(type default)
			)
			(layer "B.Fab")
		)
		(fp_line
			(start -0.67945 0.3048)
			(end -0.120396 0.3048)
			(stroke
				(width 0.1)
				(type default)
			)
			(layer "B.Fab")
		)
		(fp_line
			(start -0.67945 -0.3048)
			(end -0.67945 0.3048)
			(stroke
				(width 0.1)
				(type default)
			)
			(layer "B.Fab")
		)
		(pad "1" smd circle
			(at 0.40005 0)
			(size 0 0)
			(layers "B.Cu" "B.Mask" "B.Paste")
			(net "SMB_PMBUS_3V3AUX_SDA")
		)
		(pad "2" smd circle
			(at -0.40005 0)
			(size 0 0)
			(layers "B.Cu" "B.Mask" "B.Paste")
			(net "SMB_SML1_PMBUS_HSC_SDA")
		)
	)
	(footprint ""
		(layer "B.Cu")
		(at 114.272822 -385.50088 -90)
		(property "Reference" "C459"
			(at 0 0 90)
			(layer "B.SilkS")
			(hide yes)
			(effects
				(font
					(size 1.27 1.27)
				)
				(justify mirror)
			)
		)
		(property "Value" ""
			(at 0 0 90)
			(layer "B.Fab")
			(effects
				(font
					(size 1.27 1.27)
				)
				(justify mirror)
			)
		)
		(duplicate_pad_numbers_are_jumpers no)
		(fp_line
			(start -0.299974 0.150114)
			(end 0.299974 0.150114)
			(stroke
				(width 0.1)
				(type default)
			)
			(layer "B.Fab")
		)
		(fp_line
			(start 0.299974 0.150114)
			(end 0.299974 -0.150114)
			(stroke
				(width 0.1)
				(type default)
			)
			(layer "B.Fab")
		)
		(fp_line
			(start -0.299974 -0.150114)
			(end -0.299974 0.150114)
			(stroke
				(width 0.1)
				(type default)
			)
			(layer "B.Fab")
		)
		(fp_line
			(start 0.299974 -0.150114)
			(end -0.299974 -0.150114)
			(stroke
				(width 0.1)
				(type default)
			)
			(layer "B.Fab")
		)
		(pad "1" smd rect
			(at 0.2667 0 90)
			(size 0.3048 0.381)
			(layers "B.Cu" "B.Mask" "B.Paste")
			(net "P0V9_CPU1_RT3_2A")
		)
		(pad "2" smd rect
			(at -0.2667 0 90)
			(size 0.3048 0.381)
			(layers "B.Cu" "B.Mask" "B.Paste")
			(net "GND")
		)
	)
	(footprint ""
		(layer "B.Cu")
		(at 184.1246 -355.052884 -90)
		(property "Reference" "PC517_1"
			(at 0 0 90)
			(layer "B.SilkS")
			(hide yes)
			(effects
				(font
					(size 1.27 1.27)
				)
				(justify mirror)
			)
		)
		(property "Value" ""
			(at 0 0 90)
			(layer "B.Fab")
			(effects
				(font
					(size 1.27 1.27)
				)
				(justify mirror)
			)
		)
		(duplicate_pad_numbers_are_jumpers no)
		(fp_line
			(start -1.524 0.762)
			(end 1.524 0.762)
			(stroke
				(width 0.1524)
				(type default)
			)
			(layer "B.SilkS")
		)
		(fp_line
			(start 1.524 0.762)
			(end 1.524 -0.762)
			(stroke
				(width 0.1524)
				(type default)
			)
			(layer "B.SilkS")
		)
		(fp_line
			(start -1.524 -0.762)
			(end -1.524 0.762)
			(stroke
				(width 0.1524)
				(type default)
			)
			(layer "B.SilkS")
		)
		(fp_line
			(start 1.524 -0.762)
			(end -1.524 -0.762)
			(stroke
				(width 0.1524)
				(type default)
			)
			(layer "B.SilkS")
		)
		(fp_line
			(start -1.1049 0.724916)
			(end -1.1049 -0.724916)
			(stroke
				(width 0.1)
				(type default)
			)
			(layer "B.Fab")
		)
		(fp_line
			(start 1.1049 0.724916)
			(end -1.1049 0.724916)
			(stroke
				(width 0.1)
				(type default)
			)
			(layer "B.Fab")
		)
		(fp_line
			(start -1.1049 -0.724916)
			(end 1.1049 -0.724916)
			(stroke
				(width 0.1)
				(type default)
			)
			(layer "B.Fab")
		)
		(fp_line
			(start 1.1049 -0.724916)
			(end 1.1049 0.724916)
			(stroke
				(width 0.1)
				(type default)
			)
			(layer "B.Fab")
		)
		(pad "1" smd rect
			(at 0.889 0 270)
			(size 1.016 1.27)
			(layers "B.Cu" "B.Mask" "B.Paste")
			(net "SW_P12V_AUX_PVDD11_S3_P1_FLT")
		)
		(pad "2" smd rect
			(at -0.889 0 270)
			(size 1.016 1.27)
			(layers "B.Cu" "B.Mask" "B.Paste")
			(net "GND")
		)
	)
	(footprint ""
		(layer "B.Cu")
		(at 185.801 -100.294948 -90)
		(property "Reference" "R958"
			(at 0 0 90)
			(layer "B.SilkS")
			(hide yes)
			(effects
				(font
					(size 1.27 1.27)
				)
				(justify mirror)
			)
		)
		(property "Value" ""
			(at 0 0 90)
			(layer "B.Fab")
			(effects
				(font
					(size 1.27 1.27)
				)
				(justify mirror)
			)
		)
		(duplicate_pad_numbers_are_jumpers no)
		(fp_line
			(start -0.7874 0.4064)
			(end 0.7874 0.4064)
			(stroke
				(width 0.1524)
				(type default)
			)
			(layer "B.SilkS")
		)
		(fp_line
			(start 0.7874 0.4064)
			(end 0.7874 -0.4064)
			(stroke
				(width 0.1524)
				(type default)
			)
			(layer "B.SilkS")
		)
		(fp_line
			(start -0.7874 -0.4064)
			(end -0.7874 0.4064)
			(stroke
				(width 0.1524)
				(type default)
			)
			(layer "B.SilkS")
		)
		(fp_line
			(start 0.7874 -0.4064)
			(end -0.7874 -0.4064)
			(stroke
				(width 0.1524)
				(type default)
			)
			(layer "B.SilkS")
		)
		(fp_line
			(start -0.67945 0.3048)
			(end -0.120396 0.3048)
			(stroke
				(width 0.1)
				(type default)
			)
			(layer "B.Fab")
		)
		(fp_line
			(start -0.120396 0.3048)
			(end -0.120396 0.2794)
			(stroke
				(width 0.1)
				(type default)
			)
			(layer "B.Fab")
		)
		(fp_line
			(start 0.12065 0.3048)
			(end 0.67945 0.3048)
			(stroke
				(width 0.1)
				(type default)
			)
			(layer "B.Fab")
		)
		(fp_line
			(start 0.67945 0.3048)
			(end 0.67945 -0.305054)
			(stroke
				(width 0.1)
				(type default)
			)
			(layer "B.Fab")
		)
		(fp_line
			(start -0.120396 0.2794)
			(end 0.12065 0.2794)
			(stroke
				(width 0.1)
				(type default)
			)
			(layer "B.Fab")
		)
		(fp_line
			(start 0.12065 0.2794)
			(end 0.12065 0.3048)
			(stroke
				(width 0.1)
				(type default)
			)
			(layer "B.Fab")
		)
		(fp_line
			(start -0.12065 -0.2794)
			(end -0.12065 -0.3048)
			(stroke
				(width 0.1)
				(type default)
			)
			(layer "B.Fab")
		)
		(fp_line
			(start 0.12065 -0.2794)
			(end -0.12065 -0.2794)
			(stroke
				(width 0.1)
				(type default)
			)
			(layer "B.Fab")
		)
		(fp_line
			(start -0.67945 -0.3048)
			(end -0.67945 0.3048)
			(stroke
				(width 0.1)
				(type default)
			)
			(layer "B.Fab")
		)
		(fp_line
			(start -0.12065 -0.3048)
			(end -0.67945 -0.3048)
			(stroke
				(width 0.1)
				(type default)
			)
			(layer "B.Fab")
		)
		(fp_line
			(start 0.12065 -0.305054)
			(end 0.12065 -0.2794)
			(stroke
				(width 0.1)
				(type default)
			)
			(layer "B.Fab")
		)
		(fp_line
			(start 0.67945 -0.305054)
			(end 0.12065 -0.305054)
			(stroke
				(width 0.1)
				(type default)
			)
			(layer "B.Fab")
		)
		(pad "1" smd circle
			(at 0.40005 0 90)
			(size 0 0)
			(layers "B.Cu" "B.Mask" "B.Paste")
			(net "FM_PLD_OCP_SFF_AUX_PWR_EN")
		)
		(pad "2" smd circle
			(at -0.40005 0 90)
			(size 0 0)
			(layers "B.Cu" "B.Mask" "B.Paste")
			(net "FM_PLD_OCP_SFF_AUX_PWR_R_EN")
		)
	)
	(footprint ""
		(layer "B.Cu")
		(at 339.518752 -398.942052 90)
		(property "Reference" "C626"
			(at 0 0 90)
			(layer "B.SilkS")
			(hide yes)
			(effects
				(font
					(size 1.27 1.27)
				)
				(justify mirror)
			)
		)
		(property "Value" ""
			(at 0 0 90)
			(layer "B.Fab")
			(effects
				(font
					(size 1.27 1.27)
				)
				(justify mirror)
			)
		)
		(duplicate_pad_numbers_are_jumpers no)
		(fp_line
			(start 0.7874 -0.4064)
			(end -0.7874 -0.4064)
			(stroke
				(width 0.1524)
				(type default)
			)
			(layer "B.SilkS")
		)
		(fp_line
			(start -0.7874 -0.4064)
			(end -0.7874 0.4064)
			(stroke
				(width 0.1524)
				(type default)
			)
			(layer "B.SilkS")
		)
		(fp_line
			(start 0.7874 0.4064)
			(end 0.7874 -0.4064)
			(stroke
				(width 0.1524)
				(type default)
			)
			(layer "B.SilkS")
		)
		(fp_line
			(start -0.7874 0.4064)
			(end 0.7874 0.4064)
			(stroke
				(width 0.1524)
				(type default)
			)
			(layer "B.SilkS")
		)
		(fp_line
			(start 0.67945 -0.305054)
			(end 0.12065 -0.305054)
			(stroke
				(width 0.1)
				(type default)
			)
			(layer "B.Fab")
		)
		(fp_line
			(start 0.12065 -0.305054)
			(end 0.12065 -0.2794)
			(stroke
				(width 0.1)
				(type default)
			)
			(layer "B.Fab")
		)
		(fp_line
			(start -0.12065 -0.3048)
			(end -0.67945 -0.3048)
			(stroke
				(width 0.1)
				(type default)
			)
			(layer "B.Fab")
		)
		(fp_line
			(start -0.67945 -0.3048)
			(end -0.67945 0.3048)
			(stroke
				(width 0.1)
				(type default)
			)
			(layer "B.Fab")
		)
		(fp_line
			(start 0.12065 -0.2794)
			(end -0.12065 -0.2794)
			(stroke
				(width 0.1)
				(type default)
			)
			(layer "B.Fab")
		)
		(fp_line
			(start -0.12065 -0.2794)
			(end -0.12065 -0.3048)
			(stroke
				(width 0.1)
				(type default)
			)
			(layer "B.Fab")
		)
		(fp_line
			(start 0.12065 0.2794)
			(end 0.12065 0.3048)
			(stroke
				(width 0.1)
				(type default)
			)
			(layer "B.Fab")
		)
		(fp_line
			(start -0.120396 0.2794)
			(end 0.12065 0.2794)
			(stroke
				(width 0.1)
				(type default)
			)
			(layer "B.Fab")
		)
		(fp_line
			(start 0.67945 0.3048)
			(end 0.67945 -0.305054)
			(stroke
				(width 0.1)
				(type default)
			)
			(layer "B.Fab")
		)
		(fp_line
			(start 0.12065 0.3048)
			(end 0.67945 0.3048)
			(stroke
				(width 0.1)
				(type default)
			)
			(layer "B.Fab")
		)
		(fp_line
			(start -0.120396 0.3048)
			(end -0.120396 0.2794)
			(stroke
				(width 0.1)
				(type default)
			)
			(layer "B.Fab")
		)
		(fp_line
			(start -0.67945 0.3048)
			(end -0.120396 0.3048)
			(stroke
				(width 0.1)
				(type default)
			)
			(layer "B.Fab")
		)
		(pad "1" smd circle
			(at 0.40005 0 270)
			(size 0 0)
			(layers "B.Cu" "B.Mask" "B.Paste")
			(net "P0V9_CPU0_RT1_2A")
		)
		(pad "2" smd circle
			(at -0.40005 0 270)
			(size 0 0)
			(layers "B.Cu" "B.Mask" "B.Paste")
			(net "GND")
		)
	)
	(footprint ""
		(layer "B.Cu")
		(at 202.903582 -194.885564 180)
		(property "Reference" "R778"
			(at 0 0 0)
			(layer "B.SilkS")
			(hide yes)
			(effects
				(font
					(size 1.27 1.27)
				)
				(justify mirror)
			)
		)
		(property "Value" ""
			(at 0 0 0)
			(layer "B.Fab")
			(effects
				(font
					(size 1.27 1.27)
				)
				(justify mirror)
			)
		)
		(duplicate_pad_numbers_are_jumpers no)
		(fp_line
			(start 0.7874 0.4064)
			(end 0.7874 -0.4064)
			(stroke
				(width 0.1524)
				(type default)
			)
			(layer "B.SilkS")
		)
		(fp_line
			(start 0.7874 -0.4064)
			(end -0.7874 -0.4064)
			(stroke
				(width 0.1524)
				(type default)
			)
			(layer "B.SilkS")
		)
		(fp_line
			(start -0.7874 0.4064)
			(end 0.7874 0.4064)
			(stroke
				(width 0.1524)
				(type default)
			)
			(layer "B.SilkS")
		)
		(fp_line
			(start -0.7874 -0.4064)
			(end -0.7874 0.4064)
			(stroke
				(width 0.1524)
				(type default)
			)
			(layer "B.SilkS")
		)
		(fp_line
			(start 0.67945 0.3048)
			(end 0.67945 -0.305054)
			(stroke
				(width 0.1)
				(type default)
			)
			(layer "B.Fab")
		)
		(fp_line
			(start 0.67945 -0.305054)
			(end 0.12065 -0.305054)
			(stroke
				(width 0.1)
				(type default)
			)
			(layer "B.Fab")
		)
		(fp_line
			(start 0.12065 0.3048)
			(end 0.67945 0.3048)
			(stroke
				(width 0.1)
				(type default)
			)
			(layer "B.Fab")
		)
		(fp_line
			(start 0.12065 0.2794)
			(end 0.12065 0.3048)
			(stroke
				(width 0.1)
				(type default)
			)
			(layer "B.Fab")
		)
		(fp_line
			(start 0.12065 -0.2794)
			(end -0.12065 -0.2794)
			(stroke
				(width 0.1)
				(type default)
			)
			(layer "B.Fab")
		)
		(fp_line
			(start 0.12065 -0.305054)
			(end 0.12065 -0.2794)
			(stroke
				(width 0.1)
				(type default)
			)
			(layer "B.Fab")
		)
		(fp_line
			(start -0.120396 0.3048)
			(end -0.120396 0.2794)
			(stroke
				(width 0.1)
				(type default)
			)
			(layer "B.Fab")
		)
		(fp_line
			(start -0.120396 0.2794)
			(end 0.12065 0.2794)
			(stroke
				(width 0.1)
				(type default)
			)
			(layer "B.Fab")
		)
		(fp_line
			(start -0.12065 -0.2794)
			(end -0.12065 -0.3048)
			(stroke
				(width 0.1)
				(type default)
			)
			(layer "B.Fab")
		)
		(fp_line
			(start -0.12065 -0.3048)
			(end -0.67945 -0.3048)
			(stroke
				(width 0.1)
				(type default)
			)
			(layer "B.Fab")
		)
		(fp_line
			(start -0.67945 0.3048)
			(end -0.120396 0.3048)
			(stroke
				(width 0.1)
				(type default)
			)
			(layer "B.Fab")
		)
		(fp_line
			(start -0.67945 -0.3048)
			(end -0.67945 0.3048)
			(stroke
				(width 0.1)
				(type default)
			)
			(layer "B.Fab")
		)
		(pad "1" smd circle
			(at 0.40005 0)
			(size 0 0)
			(layers "B.Cu" "B.Mask" "B.Paste")
			(net "PD_CHL_CPU1_DIMM_SAA")
		)
		(pad "2" smd circle
			(at -0.40005 0)
			(size 0 0)
			(layers "B.Cu" "B.Mask" "B.Paste")
			(net "GND")
		)
	)
	(footprint ""
		(layer "B.Cu")
		(at 216.13368 -329.179174 180)
		(property "Reference" "R1239"
			(at 0 0 0)
			(layer "B.SilkS")
			(hide yes)
			(effects
				(font
					(size 1.27 1.27)
				)
				(justify mirror)
			)
		)
		(property "Value" ""
			(at 0 0 0)
			(layer "B.Fab")
			(effects
				(font
					(size 1.27 1.27)
				)
				(justify mirror)
			)
		)
		(duplicate_pad_numbers_are_jumpers no)
		(fp_line
			(start 0.7874 0.4064)
			(end 0.7874 -0.4064)
			(stroke
				(width 0.1524)
				(type default)
			)
			(layer "B.SilkS")
		)
		(fp_line
			(start 0.7874 -0.4064)
			(end -0.7874 -0.4064)
			(stroke
				(width 0.1524)
				(type default)
			)
			(layer "B.SilkS")
		)
		(fp_line
			(start -0.7874 0.4064)
			(end 0.7874 0.4064)
			(stroke
				(width 0.1524)
				(type default)
			)
			(layer "B.SilkS")
		)
		(fp_line
			(start -0.7874 -0.4064)
			(end -0.7874 0.4064)
			(stroke
				(width 0.1524)
				(type default)
			)
			(layer "B.SilkS")
		)
		(fp_line
			(start 0.67945 0.3048)
			(end 0.67945 -0.305054)
			(stroke
				(width 0.1)
				(type default)
			)
			(layer "B.Fab")
		)
		(fp_line
			(start 0.67945 -0.305054)
			(end 0.12065 -0.305054)
			(stroke
				(width 0.1)
				(type default)
			)
			(layer "B.Fab")
		)
		(fp_line
			(start 0.12065 0.3048)
			(end 0.67945 0.3048)
			(stroke
				(width 0.1)
				(type default)
			)
			(layer "B.Fab")
		)
		(fp_line
			(start 0.12065 0.2794)
			(end 0.12065 0.3048)
			(stroke
				(width 0.1)
				(type default)
			)
			(layer "B.Fab")
		)
		(fp_line
			(start 0.12065 -0.2794)
			(end -0.12065 -0.2794)
			(stroke
				(width 0.1)
				(type default)
			)
			(layer "B.Fab")
		)
		(fp_line
			(start 0.12065 -0.305054)
			(end 0.12065 -0.2794)
			(stroke
				(width 0.1)
				(type default)
			)
			(layer "B.Fab")
		)
		(fp_line
			(start -0.120396 0.3048)
			(end -0.120396 0.2794)
			(stroke
				(width 0.1)
				(type default)
			)
			(layer "B.Fab")
		)
		(fp_line
			(start -0.120396 0.2794)
			(end 0.12065 0.2794)
			(stroke
				(width 0.1)
				(type default)
			)
			(layer "B.Fab")
		)
		(fp_line
			(start -0.12065 -0.2794)
			(end -0.12065 -0.3048)
			(stroke
				(width 0.1)
				(type default)
			)
			(layer "B.Fab")
		)
		(fp_line
			(start -0.12065 -0.3048)
			(end -0.67945 -0.3048)
			(stroke
				(width 0.1)
				(type default)
			)
			(layer "B.Fab")
		)
		(fp_line
			(start -0.67945 0.3048)
			(end -0.120396 0.3048)
			(stroke
				(width 0.1)
				(type default)
			)
			(layer "B.Fab")
		)
		(fp_line
			(start -0.67945 -0.3048)
			(end -0.67945 0.3048)
			(stroke
				(width 0.1)
				(type default)
			)
			(layer "B.Fab")
		)
		(pad "1" smd circle
			(at 0.40005 0)
			(size 0 0)
			(layers "B.Cu" "B.Mask" "B.Paste")
			(net "P3V3_AUX")
		)
		(pad "2" smd circle
			(at -0.40005 0)
			(size 0 0)
			(layers "B.Cu" "B.Mask" "B.Paste")
			(net "ADC128_2_A1")
		)
	)
	(footprint ""
		(layer "B.Cu")
		(at 367.186464 -63.155068)
		(property "Reference" "ME13"
			(at 0 0 0)
			(layer "B.SilkS")
			(hide yes)
			(effects
				(font
					(size 1.27 1.27)
				)
				(justify mirror)
			)
		)
		(property "Value" ""
			(at 0 0 0)
			(layer "B.Fab")
			(effects
				(font
					(size 1.27 1.27)
				)
				(justify mirror)
			)
		)
		(duplicate_pad_numbers_are_jumpers no)
		(zone
			(layer "B.Cu")
			(hatch none 0.5)
			(connect_pads
				(clearance 0)
			)
			(min_thickness 0.25)
			(keepout
				(tracks allowed)
				(vias allowed)
				(pads allowed)
				(copperpour allowed)
				(footprints not_allowed)
			)
			(placement
				(enabled no)
				(sheetname "")
			)
			(fill
				(thermal_gap 0.5)
				(thermal_bridge_width 0.5)
				(island_removal_mode 0)
			)
			(polygon
				(pts
					(arc
						(start 377.186444 -63.155068)
						(mid 357.186484 -63.155068)
						(end 377.186444 -63.155068)
					)
				)
			)
		)
	)
	(footprint ""
		(layer "B.Cu")
		(at 304.055018 -409.560014 90)
		(property "Reference" "PJ09_P0_P"
			(at 0 0 90)
			(layer "B.SilkS")
			(hide yes)
			(effects
				(font
					(size 1.27 1.27)
				)
				(justify mirror)
			)
		)
		(property "Value" ""
			(at 0 0 90)
			(layer "B.Fab")
			(effects
				(font
					(size 1.27 1.27)
				)
				(justify mirror)
			)
		)
		(duplicate_pad_numbers_are_jumpers no)
		(zone
			(layer "In11.Cu")
			(hatch none 0.5)
			(connect_pads
				(clearance 0)
			)
			(min_thickness 0.25)
			(keepout
				(tracks allowed)
				(vias not_allowed)
				(pads allowed)
				(copperpour not_allowed)
				(footprints allowed)
			)
			(placement
				(enabled no)
				(sheetname "")
			)
			(fill
				(thermal_gap 0.5)
				(thermal_bridge_width 0.5)
				(island_removal_mode 0)
			)
			(polygon
				(pts
					(xy 304.245518 -409.775914) (xy 304.245518 -409.344114) (xy 303.864518 -409.344114) (xy 303.864518 -409.775914)
				)
			)
		)
	)
	(footprint ""
		(layer "B.Cu")
		(at 237.90148 -327.698608)
		(property "Reference" "R1233"
			(at 0 0 0)
			(layer "B.SilkS")
			(hide yes)
			(effects
				(font
					(size 1.27 1.27)
				)
				(justify mirror)
			)
		)
		(property "Value" ""
			(at 0 0 0)
			(layer "B.Fab")
			(effects
				(font
					(size 1.27 1.27)
				)
				(justify mirror)
			)
		)
		(duplicate_pad_numbers_are_jumpers no)
		(fp_line
			(start -0.7874 -0.4064)
			(end -0.7874 0.4064)
			(stroke
				(width 0.1524)
				(type default)
			)
			(layer "B.SilkS")
		)
		(fp_line
			(start -0.7874 0.4064)
			(end 0.7874 0.4064)
			(stroke
				(width 0.1524)
				(type default)
			)
			(layer "B.SilkS")
		)
		(fp_line
			(start 0.7874 -0.4064)
			(end -0.7874 -0.4064)
			(stroke
				(width 0.1524)
				(type default)
			)
			(layer "B.SilkS")
		)
		(fp_line
			(start 0.7874 0.4064)
			(end 0.7874 -0.4064)
			(stroke
				(width 0.1524)
				(type default)
			)
			(layer "B.SilkS")
		)
		(fp_line
			(start -0.67945 -0.3048)
			(end -0.67945 0.3048)
			(stroke
				(width 0.1)
				(type default)
			)
			(layer "B.Fab")
		)
		(fp_line
			(start -0.67945 0.3048)
			(end -0.120396 0.3048)
			(stroke
				(width 0.1)
				(type default)
			)
			(layer "B.Fab")
		)
		(fp_line
			(start -0.12065 -0.3048)
			(end -0.67945 -0.3048)
			(stroke
				(width 0.1)
				(type default)
			)
			(layer "B.Fab")
		)
		(fp_line
			(start -0.12065 -0.2794)
			(end -0.12065 -0.3048)
			(stroke
				(width 0.1)
				(type default)
			)
			(layer "B.Fab")
		)
		(fp_line
			(start -0.120396 0.2794)
			(end 0.12065 0.2794)
			(stroke
				(width 0.1)
				(type default)
			)
			(layer "B.Fab")
		)
		(fp_line
			(start -0.120396 0.3048)
			(end -0.120396 0.2794)
			(stroke
				(width 0.1)
				(type default)
			)
			(layer "B.Fab")
		)
		(fp_line
			(start 0.12065 -0.305054)
			(end 0.12065 -0.2794)
			(stroke
				(width 0.1)
				(type default)
			)
			(layer "B.Fab")
		)
		(fp_line
			(start 0.12065 -0.2794)
			(end -0.12065 -0.2794)
			(stroke
				(width 0.1)
				(type default)
			)
			(layer "B.Fab")
		)
		(fp_line
			(start 0.12065 0.2794)
			(end 0.12065 0.3048)
			(stroke
				(width 0.1)
				(type default)
			)
			(layer "B.Fab")
		)
		(fp_line
			(start 0.12065 0.3048)
			(end 0.67945 0.3048)
			(stroke
				(width 0.1)
				(type default)
			)
			(layer "B.Fab")
		)
		(fp_line
			(start 0.67945 -0.305054)
			(end 0.12065 -0.305054)
			(stroke
				(width 0.1)
				(type default)
			)
			(layer "B.Fab")
		)
		(fp_line
			(start 0.67945 0.3048)
			(end 0.67945 -0.305054)
			(stroke
				(width 0.1)
				(type default)
			)
			(layer "B.Fab")
		)
		(pad "1" smd circle
			(at 0.40005 0 180)
			(size 0 0)
			(layers "B.Cu" "B.Mask" "B.Paste")
			(net "PVDD18_S5_P0")
		)
		(pad "2" smd circle
			(at -0.40005 0 180)
			(size 0 0)
			(layers "B.Cu" "B.Mask" "B.Paste")
			(net "PVDD18_S5_P0_ADC")
		)
	)
	(footprint ""
		(layer "B.Cu")
		(at 51.120548 -193.996564)
		(property "Reference" "C140"
			(at 0 0 0)
			(layer "B.SilkS")
			(hide yes)
			(effects
				(font
					(size 1.27 1.27)
				)
				(justify mirror)
			)
		)
		(property "Value" ""
			(at 0 0 0)
			(layer "B.Fab")
			(effects
				(font
					(size 1.27 1.27)
				)
				(justify mirror)
			)
		)
		(duplicate_pad_numbers_are_jumpers no)
		(fp_line
			(start -0.7874 -0.4064)
			(end -0.7874 0.4064)
			(stroke
				(width 0.1524)
				(type default)
			)
			(layer "B.SilkS")
		)
		(fp_line
			(start -0.7874 0.4064)
			(end 0.7874 0.4064)
			(stroke
				(width 0.1524)
				(type default)
			)
			(layer "B.SilkS")
		)
		(fp_line
			(start 0.7874 -0.4064)
			(end -0.7874 -0.4064)
			(stroke
				(width 0.1524)
				(type default)
			)
			(layer "B.SilkS")
		)
		(fp_line
			(start 0.7874 0.4064)
			(end 0.7874 -0.4064)
			(stroke
				(width 0.1524)
				(type default)
			)
			(layer "B.SilkS")
		)
		(fp_line
			(start -0.67945 -0.3048)
			(end -0.67945 0.3048)
			(stroke
				(width 0.1)
				(type default)
			)
			(layer "B.Fab")
		)
		(fp_line
			(start -0.67945 0.3048)
			(end -0.120396 0.3048)
			(stroke
				(width 0.1)
				(type default)
			)
			(layer "B.Fab")
		)
		(fp_line
			(start -0.12065 -0.3048)
			(end -0.67945 -0.3048)
			(stroke
				(width 0.1)
				(type default)
			)
			(layer "B.Fab")
		)
		(fp_line
			(start -0.12065 -0.2794)
			(end -0.12065 -0.3048)
			(stroke
				(width 0.1)
				(type default)
			)
			(layer "B.Fab")
		)
		(fp_line
			(start -0.120396 0.2794)
			(end 0.12065 0.2794)
			(stroke
				(width 0.1)
				(type default)
			)
			(layer "B.Fab")
		)
		(fp_line
			(start -0.120396 0.3048)
			(end -0.120396 0.2794)
			(stroke
				(width 0.1)
				(type default)
			)
			(layer "B.Fab")
		)
		(fp_line
			(start 0.12065 -0.305054)
			(end 0.12065 -0.2794)
			(stroke
				(width 0.1)
				(type default)
			)
			(layer "B.Fab")
		)
		(fp_line
			(start 0.12065 -0.2794)
			(end -0.12065 -0.2794)
			(stroke
				(width 0.1)
				(type default)
			)
			(layer "B.Fab")
		)
		(fp_line
			(start 0.12065 0.2794)
			(end 0.12065 0.3048)
			(stroke
				(width 0.1)
				(type default)
			)
			(layer "B.Fab")
		)
		(fp_line
			(start 0.12065 0.3048)
			(end 0.67945 0.3048)
			(stroke
				(width 0.1)
				(type default)
			)
			(layer "B.Fab")
		)
		(fp_line
			(start 0.67945 -0.305054)
			(end 0.12065 -0.305054)
			(stroke
				(width 0.1)
				(type default)
			)
			(layer "B.Fab")
		)
		(fp_line
			(start 0.67945 0.3048)
			(end 0.67945 -0.305054)
			(stroke
				(width 0.1)
				(type default)
			)
			(layer "B.Fab")
		)
		(pad "1" smd circle
			(at 0.40005 0 180)
			(size 0 0)
			(layers "B.Cu" "B.Mask" "B.Paste")
			(net "P3V3_AUX")
		)
		(pad "2" smd circle
			(at -0.40005 0 180)
			(size 0 0)
			(layers "B.Cu" "B.Mask" "B.Paste")
			(net "GND")
		)
	)
	(footprint ""
		(layer "B.Cu")
		(at 387.716522 -416.899344 90)
		(property "Reference" "C6608"
			(at 0 0 90)
			(layer "B.SilkS")
			(hide yes)
			(effects
				(font
					(size 1.27 1.27)
				)
				(justify mirror)
			)
		)
		(property "Value" ""
			(at 0 0 90)
			(layer "B.Fab")
			(effects
				(font
					(size 1.27 1.27)
				)
				(justify mirror)
			)
		)
		(duplicate_pad_numbers_are_jumpers no)
		(fp_line
			(start 0.299974 -0.150114)
			(end -0.299974 -0.150114)
			(stroke
				(width 0.1)
				(type default)
			)
			(layer "B.Fab")
		)
		(fp_line
			(start -0.299974 -0.150114)
			(end -0.299974 0.150114)
			(stroke
				(width 0.1)
				(type default)
			)
			(layer "B.Fab")
		)
		(fp_line
			(start 0.299974 0.150114)
			(end 0.299974 -0.150114)
			(stroke
				(width 0.1)
				(type default)
			)
			(layer "B.Fab")
		)
		(fp_line
			(start -0.299974 0.150114)
			(end 0.299974 0.150114)
			(stroke
				(width 0.1)
				(type default)
			)
			(layer "B.Fab")
		)
		(pad "1" smd rect
			(at 0.2667 0 270)
			(size 0.3048 0.381)
			(layers "B.Cu" "B.Mask" "B.Paste")
			(net "P5E_CPU0_P3_TX_BUF_C_DN<5>")
		)
		(pad "2" smd rect
			(at -0.2667 0 270)
			(size 0.3048 0.381)
			(layers "B.Cu" "B.Mask" "B.Paste")
			(net "P5E_CPU0_P3_TX_BUF_DN<5>")
		)
	)
	(footprint ""
		(layer "B.Cu")
		(at 337.687158 -309.214012 -90)
		(property "Reference" "R394"
			(at 0 0 90)
			(layer "B.SilkS")
			(hide yes)
			(effects
				(font
					(size 1.27 1.27)
				)
				(justify mirror)
			)
		)
		(property "Value" ""
			(at 0 0 90)
			(layer "B.Fab")
			(effects
				(font
					(size 1.27 1.27)
				)
				(justify mirror)
			)
		)
		(duplicate_pad_numbers_are_jumpers no)
		(fp_line
			(start -0.7874 0.4064)
			(end 0.7874 0.4064)
			(stroke
				(width 0.1524)
				(type default)
			)
			(layer "B.SilkS")
		)
		(fp_line
			(start 0.7874 0.4064)
			(end 0.7874 -0.4064)
			(stroke
				(width 0.1524)
				(type default)
			)
			(layer "B.SilkS")
		)
		(fp_line
			(start -0.7874 -0.4064)
			(end -0.7874 0.4064)
			(stroke
				(width 0.1524)
				(type default)
			)
			(layer "B.SilkS")
		)
		(fp_line
			(start 0.7874 -0.4064)
			(end -0.7874 -0.4064)
			(stroke
				(width 0.1524)
				(type default)
			)
			(layer "B.SilkS")
		)
		(fp_line
			(start -0.67945 0.3048)
			(end -0.120396 0.3048)
			(stroke
				(width 0.1)
				(type default)
			)
			(layer "B.Fab")
		)
		(fp_line
			(start -0.120396 0.3048)
			(end -0.120396 0.2794)
			(stroke
				(width 0.1)
				(type default)
			)
			(layer "B.Fab")
		)
		(fp_line
			(start 0.12065 0.3048)
			(end 0.67945 0.3048)
			(stroke
				(width 0.1)
				(type default)
			)
			(layer "B.Fab")
		)
		(fp_line
			(start 0.67945 0.3048)
			(end 0.67945 -0.305054)
			(stroke
				(width 0.1)
				(type default)
			)
			(layer "B.Fab")
		)
		(fp_line
			(start -0.120396 0.2794)
			(end 0.12065 0.2794)
			(stroke
				(width 0.1)
				(type default)
			)
			(layer "B.Fab")
		)
		(fp_line
			(start 0.12065 0.2794)
			(end 0.12065 0.3048)
			(stroke
				(width 0.1)
				(type default)
			)
			(layer "B.Fab")
		)
		(fp_line
			(start -0.12065 -0.2794)
			(end -0.12065 -0.3048)
			(stroke
				(width 0.1)
				(type default)
			)
			(layer "B.Fab")
		)
		(fp_line
			(start 0.12065 -0.2794)
			(end -0.12065 -0.2794)
			(stroke
				(width 0.1)
				(type default)
			)
			(layer "B.Fab")
		)
		(fp_line
			(start -0.67945 -0.3048)
			(end -0.67945 0.3048)
			(stroke
				(width 0.1)
				(type default)
			)
			(layer "B.Fab")
		)
		(fp_line
			(start -0.12065 -0.3048)
			(end -0.67945 -0.3048)
			(stroke
				(width 0.1)
				(type default)
			)
			(layer "B.Fab")
		)
		(fp_line
			(start 0.12065 -0.305054)
			(end 0.12065 -0.2794)
			(stroke
				(width 0.1)
				(type default)
			)
			(layer "B.Fab")
		)
		(fp_line
			(start 0.67945 -0.305054)
			(end 0.12065 -0.305054)
			(stroke
				(width 0.1)
				(type default)
			)
			(layer "B.Fab")
		)
		(pad "1" smd circle
			(at 0.40005 0 90)
			(size 0 0)
			(layers "B.Cu" "B.Mask" "B.Paste")
			(net "CPU0_SA1")
		)
		(pad "2" smd circle
			(at -0.40005 0 90)
			(size 0 0)
			(layers "B.Cu" "B.Mask" "B.Paste")
			(net "GND")
		)
	)
	(footprint ""
		(layer "B.Cu")
		(at 136.016238 -387.084062 -90)
		(property "Reference" "C433"
			(at 0 0 90)
			(layer "B.SilkS")
			(hide yes)
			(effects
				(font
					(size 1.27 1.27)
				)
				(justify mirror)
			)
		)
		(property "Value" ""
			(at 0 0 90)
			(layer "B.Fab")
			(effects
				(font
					(size 1.27 1.27)
				)
				(justify mirror)
			)
		)
		(duplicate_pad_numbers_are_jumpers no)
		(fp_line
			(start -1.524 0.762)
			(end 1.524 0.762)
			(stroke
				(width 0.1524)
				(type default)
			)
			(layer "B.SilkS")
		)
		(fp_line
			(start 1.524 0.762)
			(end 1.524 -0.762)
			(stroke
				(width 0.1524)
				(type default)
			)
			(layer "B.SilkS")
		)
		(fp_line
			(start -1.524 -0.762)
			(end -1.524 0.762)
			(stroke
				(width 0.1524)
				(type default)
			)
			(layer "B.SilkS")
		)
		(fp_line
			(start 1.524 -0.762)
			(end -1.524 -0.762)
			(stroke
				(width 0.1524)
				(type default)
			)
			(layer "B.SilkS")
		)
		(fp_line
			(start -1.1049 0.724916)
			(end -1.1049 -0.724916)
			(stroke
				(width 0.1)
				(type default)
			)
			(layer "B.Fab")
		)
		(fp_line
			(start 1.1049 0.724916)
			(end -1.1049 0.724916)
			(stroke
				(width 0.1)
				(type default)
			)
			(layer "B.Fab")
		)
		(fp_line
			(start -1.1049 -0.724916)
			(end 1.1049 -0.724916)
			(stroke
				(width 0.1)
				(type default)
			)
			(layer "B.Fab")
		)
		(fp_line
			(start 1.1049 -0.724916)
			(end 1.1049 0.724916)
			(stroke
				(width 0.1)
				(type default)
			)
			(layer "B.Fab")
		)
		(pad "1" smd rect
			(at 0.889 0 270)
			(size 1.016 1.27)
			(layers "B.Cu" "B.Mask" "B.Paste")
			(net "P1V8_CPU1_RT3_1A")
		)
		(pad "2" smd rect
			(at -0.889 0 270)
			(size 1.016 1.27)
			(layers "B.Cu" "B.Mask" "B.Paste")
			(net "GND")
		)
	)
	(footprint ""
		(layer "B.Cu")
		(at 166.955216 -112.902238 180)
		(property "Reference" "R9"
			(at 0 0 0)
			(layer "B.SilkS")
			(hide yes)
			(effects
				(font
					(size 1.27 1.27)
				)
				(justify mirror)
			)
		)
		(property "Value" ""
			(at 0 0 0)
			(layer "B.Fab")
			(effects
				(font
					(size 1.27 1.27)
				)
				(justify mirror)
			)
		)
		(duplicate_pad_numbers_are_jumpers no)
		(fp_line
			(start 0.7874 0.4064)
			(end 0.7874 -0.4064)
			(stroke
				(width 0.1524)
				(type default)
			)
			(layer "B.SilkS")
		)
		(fp_line
			(start 0.7874 -0.4064)
			(end -0.7874 -0.4064)
			(stroke
				(width 0.1524)
				(type default)
			)
			(layer "B.SilkS")
		)
		(fp_line
			(start -0.7874 0.4064)
			(end 0.7874 0.4064)
			(stroke
				(width 0.1524)
				(type default)
			)
			(layer "B.SilkS")
		)
		(fp_line
			(start -0.7874 -0.4064)
			(end -0.7874 0.4064)
			(stroke
				(width 0.1524)
				(type default)
			)
			(layer "B.SilkS")
		)
		(fp_line
			(start 0.67945 0.3048)
			(end 0.67945 -0.305054)
			(stroke
				(width 0.1)
				(type default)
			)
			(layer "B.Fab")
		)
		(fp_line
			(start 0.67945 -0.305054)
			(end 0.12065 -0.305054)
			(stroke
				(width 0.1)
				(type default)
			)
			(layer "B.Fab")
		)
		(fp_line
			(start 0.12065 0.3048)
			(end 0.67945 0.3048)
			(stroke
				(width 0.1)
				(type default)
			)
			(layer "B.Fab")
		)
		(fp_line
			(start 0.12065 0.2794)
			(end 0.12065 0.3048)
			(stroke
				(width 0.1)
				(type default)
			)
			(layer "B.Fab")
		)
		(fp_line
			(start 0.12065 -0.2794)
			(end -0.12065 -0.2794)
			(stroke
				(width 0.1)
				(type default)
			)
			(layer "B.Fab")
		)
		(fp_line
			(start 0.12065 -0.305054)
			(end 0.12065 -0.2794)
			(stroke
				(width 0.1)
				(type default)
			)
			(layer "B.Fab")
		)
		(fp_line
			(start -0.120396 0.3048)
			(end -0.120396 0.2794)
			(stroke
				(width 0.1)
				(type default)
			)
			(layer "B.Fab")
		)
		(fp_line
			(start -0.120396 0.2794)
			(end 0.12065 0.2794)
			(stroke
				(width 0.1)
				(type default)
			)
			(layer "B.Fab")
		)
		(fp_line
			(start -0.12065 -0.2794)
			(end -0.12065 -0.3048)
			(stroke
				(width 0.1)
				(type default)
			)
			(layer "B.Fab")
		)
		(fp_line
			(start -0.12065 -0.3048)
			(end -0.67945 -0.3048)
			(stroke
				(width 0.1)
				(type default)
			)
			(layer "B.Fab")
		)
		(fp_line
			(start -0.67945 0.3048)
			(end -0.120396 0.3048)
			(stroke
				(width 0.1)
				(type default)
			)
			(layer "B.Fab")
		)
		(fp_line
			(start -0.67945 -0.3048)
			(end -0.67945 0.3048)
			(stroke
				(width 0.1)
				(type default)
			)
			(layer "B.Fab")
		)
		(pad "1" smd circle
			(at 0.40005 0)
			(size 0 0)
			(layers "B.Cu" "B.Mask" "B.Paste")
			(net "JTAG_PLD_TDI")
		)
		(pad "2" smd circle
			(at -0.40005 0)
			(size 0 0)
			(layers "B.Cu" "B.Mask" "B.Paste")
			(net "JTAG_SCM_PLD_TDI")
		)
	)
	(footprint ""
		(layer "B.Cu")
		(at 218.059 -337.312 180)
		(property "Reference" "R6737"
			(at 0 0 0)
			(layer "B.SilkS")
			(hide yes)
			(effects
				(font
					(size 1.27 1.27)
				)
				(justify mirror)
			)
		)
		(property "Value" ""
			(at 0 0 0)
			(layer "B.Fab")
			(effects
				(font
					(size 1.27 1.27)
				)
				(justify mirror)
			)
		)
		(duplicate_pad_numbers_are_jumpers no)
		(fp_line
			(start 0.32512 0.175006)
			(end 0.32512 -0.175006)
			(stroke
				(width 0.1)
				(type default)
			)
			(layer "B.Fab")
		)
		(fp_line
			(start 0.32512 -0.175006)
			(end -0.32512 -0.175006)
			(stroke
				(width 0.1)
				(type default)
			)
			(layer "B.Fab")
		)
		(fp_line
			(start -0.32512 0.175006)
			(end 0.32512 0.175006)
			(stroke
				(width 0.1)
				(type default)
			)
			(layer "B.Fab")
		)
		(fp_line
			(start -0.32512 -0.175006)
			(end -0.32512 0.175006)
			(stroke
				(width 0.1)
				(type default)
			)
			(layer "B.Fab")
		)
		(pad "1" smd rect
			(at 0.2667 0)
			(size 0.3048 0.381)
			(layers "B.Cu" "B.Mask" "B.Paste")
			(net "SMB_RT_CPU1_P1_R_SCL")
		)
		(pad "2" smd rect
			(at -0.2667 0 180)
			(size 0.3048 0.381)
			(layers "B.Cu" "B.Mask" "B.Paste")
			(net "SMB_RT_CPU1_P1_SCL")
		)
	)
	(footprint ""
		(layer "B.Cu")
		(at 348.56547 -331.274928 -90)
		(property "Reference" "PC120_6"
			(at 0 0 90)
			(layer "B.SilkS")
			(hide yes)
			(effects
				(font
					(size 1.27 1.27)
				)
				(justify mirror)
			)
		)
		(property "Value" ""
			(at 0 0 90)
			(layer "B.Fab")
			(effects
				(font
					(size 1.27 1.27)
				)
				(justify mirror)
			)
		)
		(duplicate_pad_numbers_are_jumpers no)
		(fp_line
			(start -1.524 0.762)
			(end 1.524 0.762)
			(stroke
				(width 0.1524)
				(type default)
			)
			(layer "B.SilkS")
		)
		(fp_line
			(start 1.524 0.762)
			(end 1.524 -0.762)
			(stroke
				(width 0.1524)
				(type default)
			)
			(layer "B.SilkS")
		)
		(fp_line
			(start -1.524 -0.762)
			(end -1.524 0.762)
			(stroke
				(width 0.1524)
				(type default)
			)
			(layer "B.SilkS")
		)
		(fp_line
			(start 1.524 -0.762)
			(end -1.524 -0.762)
			(stroke
				(width 0.1524)
				(type default)
			)
			(layer "B.SilkS")
		)
		(fp_line
			(start -1.1049 0.724916)
			(end -1.1049 -0.724916)
			(stroke
				(width 0.1)
				(type default)
			)
			(layer "B.Fab")
		)
		(fp_line
			(start 1.1049 0.724916)
			(end -1.1049 0.724916)
			(stroke
				(width 0.1)
				(type default)
			)
			(layer "B.Fab")
		)
		(fp_line
			(start -1.1049 -0.724916)
			(end 1.1049 -0.724916)
			(stroke
				(width 0.1)
				(type default)
			)
			(layer "B.Fab")
		)
		(fp_line
			(start 1.1049 -0.724916)
			(end 1.1049 0.724916)
			(stroke
				(width 0.1)
				(type default)
			)
			(layer "B.Fab")
		)
		(pad "1" smd rect
			(at 0.889 0 270)
			(size 1.016 1.27)
			(layers "B.Cu" "B.Mask" "B.Paste")
			(net "PVDDCR_CPU1_P0")
		)
		(pad "2" smd rect
			(at -0.889 0 270)
			(size 1.016 1.27)
			(layers "B.Cu" "B.Mask" "B.Paste")
			(net "GND")
		)
	)
	(footprint ""
		(layer "B.Cu")
		(at 266.30376 -194.88531 180)
		(property "Reference" "R764"
			(at 0 0 0)
			(layer "B.SilkS")
			(hide yes)
			(effects
				(font
					(size 1.27 1.27)
				)
				(justify mirror)
			)
		)
		(property "Value" ""
			(at 0 0 0)
			(layer "B.Fab")
			(effects
				(font
					(size 1.27 1.27)
				)
				(justify mirror)
			)
		)
		(duplicate_pad_numbers_are_jumpers no)
		(fp_line
			(start 0.7874 0.4064)
			(end 0.7874 -0.4064)
			(stroke
				(width 0.1524)
				(type default)
			)
			(layer "B.SilkS")
		)
		(fp_line
			(start 0.7874 -0.4064)
			(end -0.7874 -0.4064)
			(stroke
				(width 0.1524)
				(type default)
			)
			(layer "B.SilkS")
		)
		(fp_line
			(start -0.7874 0.4064)
			(end 0.7874 0.4064)
			(stroke
				(width 0.1524)
				(type default)
			)
			(layer "B.SilkS")
		)
		(fp_line
			(start -0.7874 -0.4064)
			(end -0.7874 0.4064)
			(stroke
				(width 0.1524)
				(type default)
			)
			(layer "B.SilkS")
		)
		(fp_line
			(start 0.67945 0.3048)
			(end 0.67945 -0.305054)
			(stroke
				(width 0.1)
				(type default)
			)
			(layer "B.Fab")
		)
		(fp_line
			(start 0.67945 -0.305054)
			(end 0.12065 -0.305054)
			(stroke
				(width 0.1)
				(type default)
			)
			(layer "B.Fab")
		)
		(fp_line
			(start 0.12065 0.3048)
			(end 0.67945 0.3048)
			(stroke
				(width 0.1)
				(type default)
			)
			(layer "B.Fab")
		)
		(fp_line
			(start 0.12065 0.2794)
			(end 0.12065 0.3048)
			(stroke
				(width 0.1)
				(type default)
			)
			(layer "B.Fab")
		)
		(fp_line
			(start 0.12065 -0.2794)
			(end -0.12065 -0.2794)
			(stroke
				(width 0.1)
				(type default)
			)
			(layer "B.Fab")
		)
		(fp_line
			(start 0.12065 -0.305054)
			(end 0.12065 -0.2794)
			(stroke
				(width 0.1)
				(type default)
			)
			(layer "B.Fab")
		)
		(fp_line
			(start -0.120396 0.3048)
			(end -0.120396 0.2794)
			(stroke
				(width 0.1)
				(type default)
			)
			(layer "B.Fab")
		)
		(fp_line
			(start -0.120396 0.2794)
			(end 0.12065 0.2794)
			(stroke
				(width 0.1)
				(type default)
			)
			(layer "B.Fab")
		)
		(fp_line
			(start -0.12065 -0.2794)
			(end -0.12065 -0.3048)
			(stroke
				(width 0.1)
				(type default)
			)
			(layer "B.Fab")
		)
		(fp_line
			(start -0.12065 -0.3048)
			(end -0.67945 -0.3048)
			(stroke
				(width 0.1)
				(type default)
			)
			(layer "B.Fab")
		)
		(fp_line
			(start -0.67945 0.3048)
			(end -0.120396 0.3048)
			(stroke
				(width 0.1)
				(type default)
			)
			(layer "B.Fab")
		)
		(fp_line
			(start -0.67945 -0.3048)
			(end -0.67945 0.3048)
			(stroke
				(width 0.1)
				(type default)
			)
			(layer "B.Fab")
		)
		(pad "1" smd circle
			(at 0.40005 0)
			(size 0 0)
			(layers "B.Cu" "B.Mask" "B.Paste")
			(net "PD_CHF_CPU0_DIMM_SAA")
		)
		(pad "2" smd circle
			(at -0.40005 0)
			(size 0 0)
			(layers "B.Cu" "B.Mask" "B.Paste")
			(net "GND")
		)
	)
	(footprint ""
		(layer "B.Cu")
		(at 190.404496 -195.8594 180)
		(property "Reference" "R1709"
			(at 0 0 0)
			(layer "B.SilkS")
			(hide yes)
			(effects
				(font
					(size 1.27 1.27)
				)
				(justify mirror)
			)
		)
		(property "Value" ""
			(at 0 0 0)
			(layer "B.Fab")
			(effects
				(font
					(size 1.27 1.27)
				)
				(justify mirror)
			)
		)
		(duplicate_pad_numbers_are_jumpers no)
		(fp_line
			(start 0.7874 0.4064)
			(end 0.7874 -0.4064)
			(stroke
				(width 0.1524)
				(type default)
			)
			(layer "B.SilkS")
		)
		(fp_line
			(start 0.7874 -0.4064)
			(end -0.7874 -0.4064)
			(stroke
				(width 0.1524)
				(type default)
			)
			(layer "B.SilkS")
		)
		(fp_line
			(start -0.7874 0.4064)
			(end 0.7874 0.4064)
			(stroke
				(width 0.1524)
				(type default)
			)
			(layer "B.SilkS")
		)
		(fp_line
			(start -0.7874 -0.4064)
			(end -0.7874 0.4064)
			(stroke
				(width 0.1524)
				(type default)
			)
			(layer "B.SilkS")
		)
		(fp_line
			(start 0.67945 0.3048)
			(end 0.67945 -0.305054)
			(stroke
				(width 0.1)
				(type default)
			)
			(layer "B.Fab")
		)
		(fp_line
			(start 0.67945 -0.305054)
			(end 0.12065 -0.305054)
			(stroke
				(width 0.1)
				(type default)
			)
			(layer "B.Fab")
		)
		(fp_line
			(start 0.12065 0.3048)
			(end 0.67945 0.3048)
			(stroke
				(width 0.1)
				(type default)
			)
			(layer "B.Fab")
		)
		(fp_line
			(start 0.12065 0.2794)
			(end 0.12065 0.3048)
			(stroke
				(width 0.1)
				(type default)
			)
			(layer "B.Fab")
		)
		(fp_line
			(start 0.12065 -0.2794)
			(end -0.12065 -0.2794)
			(stroke
				(width 0.1)
				(type default)
			)
			(layer "B.Fab")
		)
		(fp_line
			(start 0.12065 -0.305054)
			(end 0.12065 -0.2794)
			(stroke
				(width 0.1)
				(type default)
			)
			(layer "B.Fab")
		)
		(fp_line
			(start -0.120396 0.3048)
			(end -0.120396 0.2794)
			(stroke
				(width 0.1)
				(type default)
			)
			(layer "B.Fab")
		)
		(fp_line
			(start -0.120396 0.2794)
			(end 0.12065 0.2794)
			(stroke
				(width 0.1)
				(type default)
			)
			(layer "B.Fab")
		)
		(fp_line
			(start -0.12065 -0.2794)
			(end -0.12065 -0.3048)
			(stroke
				(width 0.1)
				(type default)
			)
			(layer "B.Fab")
		)
		(fp_line
			(start -0.12065 -0.3048)
			(end -0.67945 -0.3048)
			(stroke
				(width 0.1)
				(type default)
			)
			(layer "B.Fab")
		)
		(fp_line
			(start -0.67945 0.3048)
			(end -0.120396 0.3048)
			(stroke
				(width 0.1)
				(type default)
			)
			(layer "B.Fab")
		)
		(fp_line
			(start -0.67945 -0.3048)
			(end -0.67945 0.3048)
			(stroke
				(width 0.1)
				(type default)
			)
			(layer "B.Fab")
		)
		(pad "1" smd circle
			(at 0.40005 0)
			(size 0 0)
			(layers "B.Cu" "B.Mask" "B.Paste")
			(net "I3C_SPD_DDRGL_CPU1_SDA")
		)
		(pad "2" smd circle
			(at -0.40005 0)
			(size 0 0)
			(layers "B.Cu" "B.Mask" "B.Paste")
			(net "I3C_SPD_DDRJ_CPU1_SDA")
		)
	)
	(footprint ""
		(layer "B.Cu")
		(at 136.040114 -33.834578)
		(property "Reference" "C6038"
			(at 0 0 0)
			(layer "B.SilkS")
			(hide yes)
			(effects
				(font
					(size 1.27 1.27)
				)
				(justify mirror)
			)
		)
		(property "Value" ""
			(at 0 0 0)
			(layer "B.Fab")
			(effects
				(font
					(size 1.27 1.27)
				)
				(justify mirror)
			)
		)
		(duplicate_pad_numbers_are_jumpers no)
		(fp_line
			(start -0.7874 -0.4064)
			(end -0.7874 0.4064)
			(stroke
				(width 0.1524)
				(type default)
			)
			(layer "B.SilkS")
		)
		(fp_line
			(start -0.7874 0.4064)
			(end 0.7874 0.4064)
			(stroke
				(width 0.1524)
				(type default)
			)
			(layer "B.SilkS")
		)
		(fp_line
			(start 0.7874 -0.4064)
			(end -0.7874 -0.4064)
			(stroke
				(width 0.1524)
				(type default)
			)
			(layer "B.SilkS")
		)
		(fp_line
			(start 0.7874 0.4064)
			(end 0.7874 -0.4064)
			(stroke
				(width 0.1524)
				(type default)
			)
			(layer "B.SilkS")
		)
		(fp_line
			(start -0.67945 -0.3048)
			(end -0.67945 0.3048)
			(stroke
				(width 0.1)
				(type default)
			)
			(layer "B.Fab")
		)
		(fp_line
			(start -0.67945 0.3048)
			(end -0.120396 0.3048)
			(stroke
				(width 0.1)
				(type default)
			)
			(layer "B.Fab")
		)
		(fp_line
			(start -0.12065 -0.3048)
			(end -0.67945 -0.3048)
			(stroke
				(width 0.1)
				(type default)
			)
			(layer "B.Fab")
		)
		(fp_line
			(start -0.12065 -0.2794)
			(end -0.12065 -0.3048)
			(stroke
				(width 0.1)
				(type default)
			)
			(layer "B.Fab")
		)
		(fp_line
			(start -0.120396 0.2794)
			(end 0.12065 0.2794)
			(stroke
				(width 0.1)
				(type default)
			)
			(layer "B.Fab")
		)
		(fp_line
			(start -0.120396 0.3048)
			(end -0.120396 0.2794)
			(stroke
				(width 0.1)
				(type default)
			)
			(layer "B.Fab")
		)
		(fp_line
			(start 0.12065 -0.305054)
			(end 0.12065 -0.2794)
			(stroke
				(width 0.1)
				(type default)
			)
			(layer "B.Fab")
		)
		(fp_line
			(start 0.12065 -0.2794)
			(end -0.12065 -0.2794)
			(stroke
				(width 0.1)
				(type default)
			)
			(layer "B.Fab")
		)
		(fp_line
			(start 0.12065 0.2794)
			(end 0.12065 0.3048)
			(stroke
				(width 0.1)
				(type default)
			)
			(layer "B.Fab")
		)
		(fp_line
			(start 0.12065 0.3048)
			(end 0.67945 0.3048)
			(stroke
				(width 0.1)
				(type default)
			)
			(layer "B.Fab")
		)
		(fp_line
			(start 0.67945 -0.305054)
			(end 0.12065 -0.305054)
			(stroke
				(width 0.1)
				(type default)
			)
			(layer "B.Fab")
		)
		(fp_line
			(start 0.67945 0.3048)
			(end 0.67945 -0.305054)
			(stroke
				(width 0.1)
				(type default)
			)
			(layer "B.Fab")
		)
		(pad "1" smd circle
			(at 0.40005 0 180)
			(size 0 0)
			(layers "B.Cu" "B.Mask" "B.Paste")
			(net "P1V2_CPU0_USB_DVDD12")
		)
		(pad "2" smd circle
			(at -0.40005 0 180)
			(size 0 0)
			(layers "B.Cu" "B.Mask" "B.Paste")
			(net "GND")
		)
	)
	(footprint ""
		(layer "B.Cu")
		(at 101.004878 -147.04441 -90)
		(property "Reference" "PC245"
			(at 0 0 90)
			(layer "B.SilkS")
			(hide yes)
			(effects
				(font
					(size 1.27 1.27)
				)
				(justify mirror)
			)
		)
		(property "Value" ""
			(at 0 0 90)
			(layer "B.Fab")
			(effects
				(font
					(size 1.27 1.27)
				)
				(justify mirror)
			)
		)
		(duplicate_pad_numbers_are_jumpers no)
		(fp_line
			(start -0.7874 0.4064)
			(end 0.7874 0.4064)
			(stroke
				(width 0.1524)
				(type default)
			)
			(layer "B.SilkS")
		)
		(fp_line
			(start 0.7874 0.4064)
			(end 0.7874 -0.4064)
			(stroke
				(width 0.1524)
				(type default)
			)
			(layer "B.SilkS")
		)
		(fp_line
			(start -0.7874 -0.4064)
			(end -0.7874 0.4064)
			(stroke
				(width 0.1524)
				(type default)
			)
			(layer "B.SilkS")
		)
		(fp_line
			(start 0.7874 -0.4064)
			(end -0.7874 -0.4064)
			(stroke
				(width 0.1524)
				(type default)
			)
			(layer "B.SilkS")
		)
		(fp_line
			(start -0.67945 0.3048)
			(end -0.120396 0.3048)
			(stroke
				(width 0.1)
				(type default)
			)
			(layer "B.Fab")
		)
		(fp_line
			(start -0.120396 0.3048)
			(end -0.120396 0.2794)
			(stroke
				(width 0.1)
				(type default)
			)
			(layer "B.Fab")
		)
		(fp_line
			(start 0.12065 0.3048)
			(end 0.67945 0.3048)
			(stroke
				(width 0.1)
				(type default)
			)
			(layer "B.Fab")
		)
		(fp_line
			(start 0.67945 0.3048)
			(end 0.67945 -0.305054)
			(stroke
				(width 0.1)
				(type default)
			)
			(layer "B.Fab")
		)
		(fp_line
			(start -0.120396 0.2794)
			(end 0.12065 0.2794)
			(stroke
				(width 0.1)
				(type default)
			)
			(layer "B.Fab")
		)
		(fp_line
			(start 0.12065 0.2794)
			(end 0.12065 0.3048)
			(stroke
				(width 0.1)
				(type default)
			)
			(layer "B.Fab")
		)
		(fp_line
			(start -0.12065 -0.2794)
			(end -0.12065 -0.3048)
			(stroke
				(width 0.1)
				(type default)
			)
			(layer "B.Fab")
		)
		(fp_line
			(start 0.12065 -0.2794)
			(end -0.12065 -0.2794)
			(stroke
				(width 0.1)
				(type default)
			)
			(layer "B.Fab")
		)
		(fp_line
			(start -0.67945 -0.3048)
			(end -0.67945 0.3048)
			(stroke
				(width 0.1)
				(type default)
			)
			(layer "B.Fab")
		)
		(fp_line
			(start -0.12065 -0.3048)
			(end -0.67945 -0.3048)
			(stroke
				(width 0.1)
				(type default)
			)
			(layer "B.Fab")
		)
		(fp_line
			(start 0.12065 -0.305054)
			(end 0.12065 -0.2794)
			(stroke
				(width 0.1)
				(type default)
			)
			(layer "B.Fab")
		)
		(fp_line
			(start 0.67945 -0.305054)
			(end 0.12065 -0.305054)
			(stroke
				(width 0.1)
				(type default)
			)
			(layer "B.Fab")
		)
		(pad "1" smd circle
			(at 0.40005 0 90)
			(size 0 0)
			(layers "B.Cu" "B.Mask" "B.Paste")
			(net "VSENSE_PVDDCR_SOC_P1_VSEN1")
		)
		(pad "2" smd circle
			(at -0.40005 0 90)
			(size 0 0)
			(layers "B.Cu" "B.Mask" "B.Paste")
			(net "VSENSE_VSS_SENSE_A_P1")
		)
	)
	(footprint ""
		(layer "B.Cu")
		(at 167.772588 -194.8942 180)
		(property "Reference" "R1586"
			(at 0 0 0)
			(layer "B.SilkS")
			(hide yes)
			(effects
				(font
					(size 1.27 1.27)
				)
				(justify mirror)
			)
		)
		(property "Value" ""
			(at 0 0 0)
			(layer "B.Fab")
			(effects
				(font
					(size 1.27 1.27)
				)
				(justify mirror)
			)
		)
		(duplicate_pad_numbers_are_jumpers no)
		(fp_line
			(start 0.7874 0.4064)
			(end 0.7874 -0.4064)
			(stroke
				(width 0.1524)
				(type default)
			)
			(layer "B.SilkS")
		)
		(fp_line
			(start 0.7874 -0.4064)
			(end -0.7874 -0.4064)
			(stroke
				(width 0.1524)
				(type default)
			)
			(layer "B.SilkS")
		)
		(fp_line
			(start -0.7874 0.4064)
			(end 0.7874 0.4064)
			(stroke
				(width 0.1524)
				(type default)
			)
			(layer "B.SilkS")
		)
		(fp_line
			(start -0.7874 -0.4064)
			(end -0.7874 0.4064)
			(stroke
				(width 0.1524)
				(type default)
			)
			(layer "B.SilkS")
		)
		(fp_line
			(start 0.67945 0.3048)
			(end 0.67945 -0.305054)
			(stroke
				(width 0.1)
				(type default)
			)
			(layer "B.Fab")
		)
		(fp_line
			(start 0.67945 -0.305054)
			(end 0.12065 -0.305054)
			(stroke
				(width 0.1)
				(type default)
			)
			(layer "B.Fab")
		)
		(fp_line
			(start 0.12065 0.3048)
			(end 0.67945 0.3048)
			(stroke
				(width 0.1)
				(type default)
			)
			(layer "B.Fab")
		)
		(fp_line
			(start 0.12065 0.2794)
			(end 0.12065 0.3048)
			(stroke
				(width 0.1)
				(type default)
			)
			(layer "B.Fab")
		)
		(fp_line
			(start 0.12065 -0.2794)
			(end -0.12065 -0.2794)
			(stroke
				(width 0.1)
				(type default)
			)
			(layer "B.Fab")
		)
		(fp_line
			(start 0.12065 -0.305054)
			(end 0.12065 -0.2794)
			(stroke
				(width 0.1)
				(type default)
			)
			(layer "B.Fab")
		)
		(fp_line
			(start -0.120396 0.3048)
			(end -0.120396 0.2794)
			(stroke
				(width 0.1)
				(type default)
			)
			(layer "B.Fab")
		)
		(fp_line
			(start -0.120396 0.2794)
			(end 0.12065 0.2794)
			(stroke
				(width 0.1)
				(type default)
			)
			(layer "B.Fab")
		)
		(fp_line
			(start -0.12065 -0.2794)
			(end -0.12065 -0.3048)
			(stroke
				(width 0.1)
				(type default)
			)
			(layer "B.Fab")
		)
		(fp_line
			(start -0.12065 -0.3048)
			(end -0.67945 -0.3048)
			(stroke
				(width 0.1)
				(type default)
			)
			(layer "B.Fab")
		)
		(fp_line
			(start -0.67945 0.3048)
			(end -0.120396 0.3048)
			(stroke
				(width 0.1)
				(type default)
			)
			(layer "B.Fab")
		)
		(fp_line
			(start -0.67945 -0.3048)
			(end -0.67945 0.3048)
			(stroke
				(width 0.1)
				(type default)
			)
			(layer "B.Fab")
		)
		(pad "1" smd circle
			(at 0.40005 0)
			(size 0 0)
			(layers "B.Cu" "B.Mask" "B.Paste")
			(net "I3C_SPD_DDRGL_CPU1_SCL")
		)
		(pad "2" smd circle
			(at -0.40005 0)
			(size 0 0)
			(layers "B.Cu" "B.Mask" "B.Paste")
			(net "I3C_SPD_DDRG_CPU1_SCL")
		)
	)
	(footprint ""
		(layer "B.Cu")
		(at 125.389386 -252.543564)
		(property "Reference" "C2471"
			(at 0 0 0)
			(layer "B.SilkS")
			(hide yes)
			(effects
				(font
					(size 1.27 1.27)
				)
				(justify mirror)
			)
		)
		(property "Value" ""
			(at 0 0 0)
			(layer "B.Fab")
			(effects
				(font
					(size 1.27 1.27)
				)
				(justify mirror)
			)
		)
		(duplicate_pad_numbers_are_jumpers no)
		(fp_line
			(start -0.7874 -0.4064)
			(end -0.7874 0.4064)
			(stroke
				(width 0.1524)
				(type default)
			)
			(layer "B.SilkS")
		)
		(fp_line
			(start -0.7874 0.4064)
			(end 0.7874 0.4064)
			(stroke
				(width 0.1524)
				(type default)
			)
			(layer "B.SilkS")
		)
		(fp_line
			(start 0.7874 -0.4064)
			(end -0.7874 -0.4064)
			(stroke
				(width 0.1524)
				(type default)
			)
			(layer "B.SilkS")
		)
		(fp_line
			(start 0.7874 0.4064)
			(end 0.7874 -0.4064)
			(stroke
				(width 0.1524)
				(type default)
			)
			(layer "B.SilkS")
		)
		(fp_line
			(start -0.67945 -0.3048)
			(end -0.67945 0.3048)
			(stroke
				(width 0.1)
				(type default)
			)
			(layer "B.Fab")
		)
		(fp_line
			(start -0.67945 0.3048)
			(end -0.120396 0.3048)
			(stroke
				(width 0.1)
				(type default)
			)
			(layer "B.Fab")
		)
		(fp_line
			(start -0.12065 -0.3048)
			(end -0.67945 -0.3048)
			(stroke
				(width 0.1)
				(type default)
			)
			(layer "B.Fab")
		)
		(fp_line
			(start -0.12065 -0.2794)
			(end -0.12065 -0.3048)
			(stroke
				(width 0.1)
				(type default)
			)
			(layer "B.Fab")
		)
		(fp_line
			(start -0.120396 0.2794)
			(end 0.12065 0.2794)
			(stroke
				(width 0.1)
				(type default)
			)
			(layer "B.Fab")
		)
		(fp_line
			(start -0.120396 0.3048)
			(end -0.120396 0.2794)
			(stroke
				(width 0.1)
				(type default)
			)
			(layer "B.Fab")
		)
		(fp_line
			(start 0.12065 -0.305054)
			(end 0.12065 -0.2794)
			(stroke
				(width 0.1)
				(type default)
			)
			(layer "B.Fab")
		)
		(fp_line
			(start 0.12065 -0.2794)
			(end -0.12065 -0.2794)
			(stroke
				(width 0.1)
				(type default)
			)
			(layer "B.Fab")
		)
		(fp_line
			(start 0.12065 0.2794)
			(end 0.12065 0.3048)
			(stroke
				(width 0.1)
				(type default)
			)
			(layer "B.Fab")
		)
		(fp_line
			(start 0.12065 0.3048)
			(end 0.67945 0.3048)
			(stroke
				(width 0.1)
				(type default)
			)
			(layer "B.Fab")
		)
		(fp_line
			(start 0.67945 -0.305054)
			(end 0.12065 -0.305054)
			(stroke
				(width 0.1)
				(type default)
			)
			(layer "B.Fab")
		)
		(fp_line
			(start 0.67945 0.3048)
			(end 0.67945 -0.305054)
			(stroke
				(width 0.1)
				(type default)
			)
			(layer "B.Fab")
		)
		(pad "1" smd circle
			(at 0.40005 0 180)
			(size 0 0)
			(layers "B.Cu" "B.Mask" "B.Paste")
			(net "PVDDCR_SOC_P1")
		)
		(pad "2" smd circle
			(at -0.40005 0 180)
			(size 0 0)
			(layers "B.Cu" "B.Mask" "B.Paste")
			(net "GND")
		)
	)
	(footprint ""
		(layer "B.Cu")
		(at 421.95877 -422.28897)
		(property "Reference" "R681"
			(at 0 0 0)
			(layer "B.SilkS")
			(hide yes)
			(effects
				(font
					(size 1.27 1.27)
				)
				(justify mirror)
			)
		)
		(property "Value" ""
			(at 0 0 0)
			(layer "B.Fab")
			(effects
				(font
					(size 1.27 1.27)
				)
				(justify mirror)
			)
		)
		(duplicate_pad_numbers_are_jumpers no)
		(fp_line
			(start -0.32512 -0.175006)
			(end -0.32512 0.175006)
			(stroke
				(width 0.1)
				(type default)
			)
			(layer "B.Fab")
		)
		(fp_line
			(start -0.32512 0.175006)
			(end 0.32512 0.175006)
			(stroke
				(width 0.1)
				(type default)
			)
			(layer "B.Fab")
		)
		(fp_line
			(start 0.32512 -0.175006)
			(end -0.32512 -0.175006)
			(stroke
				(width 0.1)
				(type default)
			)
			(layer "B.Fab")
		)
		(fp_line
			(start 0.32512 0.175006)
			(end 0.32512 -0.175006)
			(stroke
				(width 0.1)
				(type default)
			)
			(layer "B.Fab")
		)
		(pad "1" smd rect
			(at 0.2667 0 180)
			(size 0.3048 0.381)
			(layers "B.Cu" "B.Mask" "B.Paste")
			(net "SMB_RT_CPU0_P2_ROM_MUX_1D_SDA")
		)
		(pad "2" smd rect
			(at -0.2667 0)
			(size 0.3048 0.381)
			(layers "B.Cu" "B.Mask" "B.Paste")
			(net "SMB_RT_CPU0_P2_ROM_MUX_1D_R_SDA")
		)
	)
	(footprint ""
		(layer "B.Cu")
		(at 231.874822 -323.913754 180)
		(property "Reference" "R1245"
			(at 0 0 0)
			(layer "B.SilkS")
			(hide yes)
			(effects
				(font
					(size 1.27 1.27)
				)
				(justify mirror)
			)
		)
		(property "Value" ""
			(at 0 0 0)
			(layer "B.Fab")
			(effects
				(font
					(size 1.27 1.27)
				)
				(justify mirror)
			)
		)
		(duplicate_pad_numbers_are_jumpers no)
		(fp_line
			(start 0.7874 0.4064)
			(end 0.7874 -0.4064)
			(stroke
				(width 0.1524)
				(type default)
			)
			(layer "B.SilkS")
		)
		(fp_line
			(start 0.7874 -0.4064)
			(end -0.7874 -0.4064)
			(stroke
				(width 0.1524)
				(type default)
			)
			(layer "B.SilkS")
		)
		(fp_line
			(start -0.7874 0.4064)
			(end 0.7874 0.4064)
			(stroke
				(width 0.1524)
				(type default)
			)
			(layer "B.SilkS")
		)
		(fp_line
			(start -0.7874 -0.4064)
			(end -0.7874 0.4064)
			(stroke
				(width 0.1524)
				(type default)
			)
			(layer "B.SilkS")
		)
		(fp_line
			(start 0.67945 0.3048)
			(end 0.67945 -0.305054)
			(stroke
				(width 0.1)
				(type default)
			)
			(layer "B.Fab")
		)
		(fp_line
			(start 0.67945 -0.305054)
			(end 0.12065 -0.305054)
			(stroke
				(width 0.1)
				(type default)
			)
			(layer "B.Fab")
		)
		(fp_line
			(start 0.12065 0.3048)
			(end 0.67945 0.3048)
			(stroke
				(width 0.1)
				(type default)
			)
			(layer "B.Fab")
		)
		(fp_line
			(start 0.12065 0.2794)
			(end 0.12065 0.3048)
			(stroke
				(width 0.1)
				(type default)
			)
			(layer "B.Fab")
		)
		(fp_line
			(start 0.12065 -0.2794)
			(end -0.12065 -0.2794)
			(stroke
				(width 0.1)
				(type default)
			)
			(layer "B.Fab")
		)
		(fp_line
			(start 0.12065 -0.305054)
			(end 0.12065 -0.2794)
			(stroke
				(width 0.1)
				(type default)
			)
			(layer "B.Fab")
		)
		(fp_line
			(start -0.120396 0.3048)
			(end -0.120396 0.2794)
			(stroke
				(width 0.1)
				(type default)
			)
			(layer "B.Fab")
		)
		(fp_line
			(start -0.120396 0.2794)
			(end 0.12065 0.2794)
			(stroke
				(width 0.1)
				(type default)
			)
			(layer "B.Fab")
		)
		(fp_line
			(start -0.12065 -0.2794)
			(end -0.12065 -0.3048)
			(stroke
				(width 0.1)
				(type default)
			)
			(layer "B.Fab")
		)
		(fp_line
			(start -0.12065 -0.3048)
			(end -0.67945 -0.3048)
			(stroke
				(width 0.1)
				(type default)
			)
			(layer "B.Fab")
		)
		(fp_line
			(start -0.67945 0.3048)
			(end -0.120396 0.3048)
			(stroke
				(width 0.1)
				(type default)
			)
			(layer "B.Fab")
		)
		(fp_line
			(start -0.67945 -0.3048)
			(end -0.67945 0.3048)
			(stroke
				(width 0.1)
				(type default)
			)
			(layer "B.Fab")
		)
		(pad "1" smd rect
			(at 0.40005 0 180)
			(size 0.4572 0.508)
			(layers "B.Cu" "B.Mask" "B.Paste")
			(net "P1V2_AUX_ADC")
		)
		(pad "2" smd rect
			(at -0.40005 0 180)
			(size 0.4572 0.508)
			(layers "B.Cu" "B.Mask" "B.Paste")
			(net "P1V2_AUX_ADC_MAM")
		)
	)
	(footprint ""
		(layer "B.Cu")
		(at 164.325554 -350.762062)
		(property "Reference" "PR604"
			(at 0 0 0)
			(layer "B.SilkS")
			(hide yes)
			(effects
				(font
					(size 1.27 1.27)
				)
				(justify mirror)
			)
		)
		(property "Value" ""
			(at 0 0 0)
			(layer "B.Fab")
			(effects
				(font
					(size 1.27 1.27)
				)
				(justify mirror)
			)
		)
		(duplicate_pad_numbers_are_jumpers no)
		(fp_line
			(start -0.7874 -0.4064)
			(end -0.7874 0.4064)
			(stroke
				(width 0.1524)
				(type default)
			)
			(layer "B.SilkS")
		)
		(fp_line
			(start -0.7874 0.4064)
			(end 0.7874 0.4064)
			(stroke
				(width 0.1524)
				(type default)
			)
			(layer "B.SilkS")
		)
		(fp_line
			(start 0.7874 -0.4064)
			(end -0.7874 -0.4064)
			(stroke
				(width 0.1524)
				(type default)
			)
			(layer "B.SilkS")
		)
		(fp_line
			(start 0.7874 0.4064)
			(end 0.7874 -0.4064)
			(stroke
				(width 0.1524)
				(type default)
			)
			(layer "B.SilkS")
		)
		(fp_line
			(start -0.67945 -0.3048)
			(end -0.67945 0.3048)
			(stroke
				(width 0.1)
				(type default)
			)
			(layer "B.Fab")
		)
		(fp_line
			(start -0.67945 0.3048)
			(end -0.120396 0.3048)
			(stroke
				(width 0.1)
				(type default)
			)
			(layer "B.Fab")
		)
		(fp_line
			(start -0.12065 -0.3048)
			(end -0.67945 -0.3048)
			(stroke
				(width 0.1)
				(type default)
			)
			(layer "B.Fab")
		)
		(fp_line
			(start -0.12065 -0.2794)
			(end -0.12065 -0.3048)
			(stroke
				(width 0.1)
				(type default)
			)
			(layer "B.Fab")
		)
		(fp_line
			(start -0.120396 0.2794)
			(end 0.12065 0.2794)
			(stroke
				(width 0.1)
				(type default)
			)
			(layer "B.Fab")
		)
		(fp_line
			(start -0.120396 0.3048)
			(end -0.120396 0.2794)
			(stroke
				(width 0.1)
				(type default)
			)
			(layer "B.Fab")
		)
		(fp_line
			(start 0.12065 -0.305054)
			(end 0.12065 -0.2794)
			(stroke
				(width 0.1)
				(type default)
			)
			(layer "B.Fab")
		)
		(fp_line
			(start 0.12065 -0.2794)
			(end -0.12065 -0.2794)
			(stroke
				(width 0.1)
				(type default)
			)
			(layer "B.Fab")
		)
		(fp_line
			(start 0.12065 0.2794)
			(end 0.12065 0.3048)
			(stroke
				(width 0.1)
				(type default)
			)
			(layer "B.Fab")
		)
		(fp_line
			(start 0.12065 0.3048)
			(end 0.67945 0.3048)
			(stroke
				(width 0.1)
				(type default)
			)
			(layer "B.Fab")
		)
		(fp_line
			(start 0.67945 -0.305054)
			(end 0.12065 -0.305054)
			(stroke
				(width 0.1)
				(type default)
			)
			(layer "B.Fab")
		)
		(fp_line
			(start 0.67945 0.3048)
			(end 0.67945 -0.305054)
			(stroke
				(width 0.1)
				(type default)
			)
			(layer "B.Fab")
		)
		(pad "1" smd circle
			(at 0.40005 0 180)
			(size 0 0)
			(layers "B.Cu" "B.Mask" "B.Paste")
			(net "PVDD11_S3_P1_VINSEN")
		)
		(pad "2" smd circle
			(at -0.40005 0 180)
			(size 0 0)
			(layers "B.Cu" "B.Mask" "B.Paste")
			(net "GND")
		)
	)
	(footprint ""
		(layer "B.Cu")
		(at 115.70589 -257.74523 180)
		(property "Reference" "C2407"
			(at 0 0 0)
			(layer "B.SilkS")
			(hide yes)
			(effects
				(font
					(size 1.27 1.27)
				)
				(justify mirror)
			)
		)
		(property "Value" ""
			(at 0 0 0)
			(layer "B.Fab")
			(effects
				(font
					(size 1.27 1.27)
				)
				(justify mirror)
			)
		)
		(duplicate_pad_numbers_are_jumpers no)
		(fp_line
			(start 0.7874 0.4064)
			(end 0.7874 -0.4064)
			(stroke
				(width 0.1524)
				(type default)
			)
			(layer "B.SilkS")
		)
		(fp_line
			(start 0.7874 -0.4064)
			(end -0.7874 -0.4064)
			(stroke
				(width 0.1524)
				(type default)
			)
			(layer "B.SilkS")
		)
		(fp_line
			(start -0.7874 0.4064)
			(end 0.7874 0.4064)
			(stroke
				(width 0.1524)
				(type default)
			)
			(layer "B.SilkS")
		)
		(fp_line
			(start -0.7874 -0.4064)
			(end -0.7874 0.4064)
			(stroke
				(width 0.1524)
				(type default)
			)
			(layer "B.SilkS")
		)
		(fp_line
			(start 0.67945 0.3048)
			(end 0.67945 -0.305054)
			(stroke
				(width 0.1)
				(type default)
			)
			(layer "B.Fab")
		)
		(fp_line
			(start 0.67945 -0.305054)
			(end 0.12065 -0.305054)
			(stroke
				(width 0.1)
				(type default)
			)
			(layer "B.Fab")
		)
		(fp_line
			(start 0.12065 0.3048)
			(end 0.67945 0.3048)
			(stroke
				(width 0.1)
				(type default)
			)
			(layer "B.Fab")
		)
		(fp_line
			(start 0.12065 0.2794)
			(end 0.12065 0.3048)
			(stroke
				(width 0.1)
				(type default)
			)
			(layer "B.Fab")
		)
		(fp_line
			(start 0.12065 -0.2794)
			(end -0.12065 -0.2794)
			(stroke
				(width 0.1)
				(type default)
			)
			(layer "B.Fab")
		)
		(fp_line
			(start 0.12065 -0.305054)
			(end 0.12065 -0.2794)
			(stroke
				(width 0.1)
				(type default)
			)
			(layer "B.Fab")
		)
		(fp_line
			(start -0.120396 0.3048)
			(end -0.120396 0.2794)
			(stroke
				(width 0.1)
				(type default)
			)
			(layer "B.Fab")
		)
		(fp_line
			(start -0.120396 0.2794)
			(end 0.12065 0.2794)
			(stroke
				(width 0.1)
				(type default)
			)
			(layer "B.Fab")
		)
		(fp_line
			(start -0.12065 -0.2794)
			(end -0.12065 -0.3048)
			(stroke
				(width 0.1)
				(type default)
			)
			(layer "B.Fab")
		)
		(fp_line
			(start -0.12065 -0.3048)
			(end -0.67945 -0.3048)
			(stroke
				(width 0.1)
				(type default)
			)
			(layer "B.Fab")
		)
		(fp_line
			(start -0.67945 0.3048)
			(end -0.120396 0.3048)
			(stroke
				(width 0.1)
				(type default)
			)
			(layer "B.Fab")
		)
		(fp_line
			(start -0.67945 -0.3048)
			(end -0.67945 0.3048)
			(stroke
				(width 0.1)
				(type default)
			)
			(layer "B.Fab")
		)
		(pad "1" smd circle
			(at 0.40005 0)
			(size 0 0)
			(layers "B.Cu" "B.Mask" "B.Paste")
			(net "PVDDCR_SOC_P1")
		)
		(pad "2" smd circle
			(at -0.40005 0)
			(size 0 0)
			(layers "B.Cu" "B.Mask" "B.Paste")
			(net "GND")
		)
	)
	(footprint ""
		(layer "B.Cu")
		(at 203.897484 -341.853012 180)
		(property "Reference" "PR6000"
			(at 0 0 0)
			(layer "B.SilkS")
			(hide yes)
			(effects
				(font
					(size 1.27 1.27)
				)
				(justify mirror)
			)
		)
		(property "Value" ""
			(at 0 0 0)
			(layer "B.Fab")
			(effects
				(font
					(size 1.27 1.27)
				)
				(justify mirror)
			)
		)
		(duplicate_pad_numbers_are_jumpers no)
		(fp_line
			(start 0.7874 0.4064)
			(end 0.7874 -0.4064)
			(stroke
				(width 0.1524)
				(type default)
			)
			(layer "B.SilkS")
		)
		(fp_line
			(start 0.7874 -0.4064)
			(end -0.7874 -0.4064)
			(stroke
				(width 0.1524)
				(type default)
			)
			(layer "B.SilkS")
		)
		(fp_line
			(start -0.7874 0.4064)
			(end 0.7874 0.4064)
			(stroke
				(width 0.1524)
				(type default)
			)
			(layer "B.SilkS")
		)
		(fp_line
			(start -0.7874 -0.4064)
			(end -0.7874 0.4064)
			(stroke
				(width 0.1524)
				(type default)
			)
			(layer "B.SilkS")
		)
		(fp_line
			(start 0.67945 0.3048)
			(end 0.67945 -0.305054)
			(stroke
				(width 0.1)
				(type default)
			)
			(layer "B.Fab")
		)
		(fp_line
			(start 0.67945 -0.305054)
			(end 0.12065 -0.305054)
			(stroke
				(width 0.1)
				(type default)
			)
			(layer "B.Fab")
		)
		(fp_line
			(start 0.12065 0.3048)
			(end 0.67945 0.3048)
			(stroke
				(width 0.1)
				(type default)
			)
			(layer "B.Fab")
		)
		(fp_line
			(start 0.12065 0.2794)
			(end 0.12065 0.3048)
			(stroke
				(width 0.1)
				(type default)
			)
			(layer "B.Fab")
		)
		(fp_line
			(start 0.12065 -0.2794)
			(end -0.12065 -0.2794)
			(stroke
				(width 0.1)
				(type default)
			)
			(layer "B.Fab")
		)
		(fp_line
			(start 0.12065 -0.305054)
			(end 0.12065 -0.2794)
			(stroke
				(width 0.1)
				(type default)
			)
			(layer "B.Fab")
		)
		(fp_line
			(start -0.120396 0.3048)
			(end -0.120396 0.2794)
			(stroke
				(width 0.1)
				(type default)
			)
			(layer "B.Fab")
		)
		(fp_line
			(start -0.120396 0.2794)
			(end 0.12065 0.2794)
			(stroke
				(width 0.1)
				(type default)
			)
			(layer "B.Fab")
		)
		(fp_line
			(start -0.12065 -0.2794)
			(end -0.12065 -0.3048)
			(stroke
				(width 0.1)
				(type default)
			)
			(layer "B.Fab")
		)
		(fp_line
			(start -0.12065 -0.3048)
			(end -0.67945 -0.3048)
			(stroke
				(width 0.1)
				(type default)
			)
			(layer "B.Fab")
		)
		(fp_line
			(start -0.67945 0.3048)
			(end -0.120396 0.3048)
			(stroke
				(width 0.1)
				(type default)
			)
			(layer "B.Fab")
		)
		(fp_line
			(start -0.67945 -0.3048)
			(end -0.67945 0.3048)
			(stroke
				(width 0.1)
				(type default)
			)
			(layer "B.Fab")
		)
		(pad "1" smd circle
			(at 0.40005 0)
			(size 0 0)
			(layers "B.Cu" "B.Mask" "B.Paste")
			(net "GND")
		)
		(pad "2" smd circle
			(at -0.40005 0)
			(size 0 0)
			(layers "B.Cu" "B.Mask" "B.Paste")
			(net "PVDD_33_S5_MODE")
		)
	)
	(footprint ""
		(layer "B.Cu")
		(at 234.569 -241.2111 90)
		(property "Reference" "R338"
			(at 0 0 90)
			(layer "B.SilkS")
			(hide yes)
			(effects
				(font
					(size 1.27 1.27)
				)
				(justify mirror)
			)
		)
		(property "Value" ""
			(at 0 0 90)
			(layer "B.Fab")
			(effects
				(font
					(size 1.27 1.27)
				)
				(justify mirror)
			)
		)
		(duplicate_pad_numbers_are_jumpers no)
		(fp_line
			(start 0.7874 -0.4064)
			(end -0.7874 -0.4064)
			(stroke
				(width 0.1524)
				(type default)
			)
			(layer "B.SilkS")
		)
		(fp_line
			(start -0.7874 -0.4064)
			(end -0.7874 0.4064)
			(stroke
				(width 0.1524)
				(type default)
			)
			(layer "B.SilkS")
		)
		(fp_line
			(start 0.7874 0.4064)
			(end 0.7874 -0.4064)
			(stroke
				(width 0.1524)
				(type default)
			)
			(layer "B.SilkS")
		)
		(fp_line
			(start -0.7874 0.4064)
			(end 0.7874 0.4064)
			(stroke
				(width 0.1524)
				(type default)
			)
			(layer "B.SilkS")
		)
		(fp_line
			(start 0.67945 -0.305054)
			(end 0.12065 -0.305054)
			(stroke
				(width 0.1)
				(type default)
			)
			(layer "B.Fab")
		)
		(fp_line
			(start 0.12065 -0.305054)
			(end 0.12065 -0.2794)
			(stroke
				(width 0.1)
				(type default)
			)
			(layer "B.Fab")
		)
		(fp_line
			(start -0.12065 -0.3048)
			(end -0.67945 -0.3048)
			(stroke
				(width 0.1)
				(type default)
			)
			(layer "B.Fab")
		)
		(fp_line
			(start -0.67945 -0.3048)
			(end -0.67945 0.3048)
			(stroke
				(width 0.1)
				(type default)
			)
			(layer "B.Fab")
		)
		(fp_line
			(start 0.12065 -0.2794)
			(end -0.12065 -0.2794)
			(stroke
				(width 0.1)
				(type default)
			)
			(layer "B.Fab")
		)
		(fp_line
			(start -0.12065 -0.2794)
			(end -0.12065 -0.3048)
			(stroke
				(width 0.1)
				(type default)
			)
			(layer "B.Fab")
		)
		(fp_line
			(start 0.12065 0.2794)
			(end 0.12065 0.3048)
			(stroke
				(width 0.1)
				(type default)
			)
			(layer "B.Fab")
		)
		(fp_line
			(start -0.120396 0.2794)
			(end 0.12065 0.2794)
			(stroke
				(width 0.1)
				(type default)
			)
			(layer "B.Fab")
		)
		(fp_line
			(start 0.67945 0.3048)
			(end 0.67945 -0.305054)
			(stroke
				(width 0.1)
				(type default)
			)
			(layer "B.Fab")
		)
		(fp_line
			(start 0.12065 0.3048)
			(end 0.67945 0.3048)
			(stroke
				(width 0.1)
				(type default)
			)
			(layer "B.Fab")
		)
		(fp_line
			(start -0.120396 0.3048)
			(end -0.120396 0.2794)
			(stroke
				(width 0.1)
				(type default)
			)
			(layer "B.Fab")
		)
		(fp_line
			(start -0.67945 0.3048)
			(end -0.120396 0.3048)
			(stroke
				(width 0.1)
				(type default)
			)
			(layer "B.Fab")
		)
		(pad "1" smd rect
			(at 0.40005 0 90)
			(size 0.4572 0.508)
			(layers "B.Cu" "B.Mask" "B.Paste")
			(net "SMB_APML_CPU1_MUX2_SDA")
		)
		(pad "2" smd rect
			(at -0.40005 0 90)
			(size 0.4572 0.508)
			(layers "B.Cu" "B.Mask" "B.Paste")
			(net "SMB_APML_CPU1_SDA")
		)
	)
	(footprint ""
		(layer "B.Cu")
		(at 354.628958 -249.36831 180)
		(property "Reference" "C273"
			(at 0 0 0)
			(layer "B.SilkS")
			(hide yes)
			(effects
				(font
					(size 1.27 1.27)
				)
				(justify mirror)
			)
		)
		(property "Value" ""
			(at 0 0 0)
			(layer "B.Fab")
			(effects
				(font
					(size 1.27 1.27)
				)
				(justify mirror)
			)
		)
		(duplicate_pad_numbers_are_jumpers no)
		(fp_line
			(start 0.7874 0.4064)
			(end 0.7874 -0.4064)
			(stroke
				(width 0.1524)
				(type default)
			)
			(layer "B.SilkS")
		)
		(fp_line
			(start 0.7874 -0.4064)
			(end -0.7874 -0.4064)
			(stroke
				(width 0.1524)
				(type default)
			)
			(layer "B.SilkS")
		)
		(fp_line
			(start -0.7874 0.4064)
			(end 0.7874 0.4064)
			(stroke
				(width 0.1524)
				(type default)
			)
			(layer "B.SilkS")
		)
		(fp_line
			(start -0.7874 -0.4064)
			(end -0.7874 0.4064)
			(stroke
				(width 0.1524)
				(type default)
			)
			(layer "B.SilkS")
		)
		(fp_line
			(start 0.67945 0.3048)
			(end 0.67945 -0.305054)
			(stroke
				(width 0.1)
				(type default)
			)
			(layer "B.Fab")
		)
		(fp_line
			(start 0.67945 -0.305054)
			(end 0.12065 -0.305054)
			(stroke
				(width 0.1)
				(type default)
			)
			(layer "B.Fab")
		)
		(fp_line
			(start 0.12065 0.3048)
			(end 0.67945 0.3048)
			(stroke
				(width 0.1)
				(type default)
			)
			(layer "B.Fab")
		)
		(fp_line
			(start 0.12065 0.2794)
			(end 0.12065 0.3048)
			(stroke
				(width 0.1)
				(type default)
			)
			(layer "B.Fab")
		)
		(fp_line
			(start 0.12065 -0.2794)
			(end -0.12065 -0.2794)
			(stroke
				(width 0.1)
				(type default)
			)
			(layer "B.Fab")
		)
		(fp_line
			(start 0.12065 -0.305054)
			(end 0.12065 -0.2794)
			(stroke
				(width 0.1)
				(type default)
			)
			(layer "B.Fab")
		)
		(fp_line
			(start -0.120396 0.3048)
			(end -0.120396 0.2794)
			(stroke
				(width 0.1)
				(type default)
			)
			(layer "B.Fab")
		)
		(fp_line
			(start -0.120396 0.2794)
			(end 0.12065 0.2794)
			(stroke
				(width 0.1)
				(type default)
			)
			(layer "B.Fab")
		)
		(fp_line
			(start -0.12065 -0.2794)
			(end -0.12065 -0.3048)
			(stroke
				(width 0.1)
				(type default)
			)
			(layer "B.Fab")
		)
		(fp_line
			(start -0.12065 -0.3048)
			(end -0.67945 -0.3048)
			(stroke
				(width 0.1)
				(type default)
			)
			(layer "B.Fab")
		)
		(fp_line
			(start -0.67945 0.3048)
			(end -0.120396 0.3048)
			(stroke
				(width 0.1)
				(type default)
			)
			(layer "B.Fab")
		)
		(fp_line
			(start -0.67945 -0.3048)
			(end -0.67945 0.3048)
			(stroke
				(width 0.1)
				(type default)
			)
			(layer "B.Fab")
		)
		(pad "1" smd circle
			(at 0.40005 0)
			(size 0 0)
			(layers "B.Cu" "B.Mask" "B.Paste")
			(net "PVDDCR_CPU0_P0")
		)
		(pad "2" smd circle
			(at -0.40005 0)
			(size 0 0)
			(layers "B.Cu" "B.Mask" "B.Paste")
			(net "GND")
		)
	)
	(footprint ""
		(layer "B.Cu")
		(at 395.179296 -154.065986 180)
		(property "Reference" "U324"
			(at -0.98298 -2.36347 0)
			(unlocked yes)
			(layer "B.SilkS")
			(effects
				(font
					(size 0.7874 0.5842)
					(thickness 0.1524)
				)
				(justify left mirror)
			)
		)
		(property "Value" ""
			(at 0 0 0)
			(layer "B.Fab")
			(effects
				(font
					(size 1.27 1.27)
				)
				(justify mirror)
			)
		)
		(duplicate_pad_numbers_are_jumpers no)
		(fp_line
			(start 1.603248 1.500124)
			(end 1.603248 -1.500124)
			(stroke
				(width 0.1524)
				(type default)
			)
			(layer "B.SilkS")
		)
		(fp_line
			(start 1.603248 -1.500124)
			(end -1.603248 -1.500124)
			(stroke
				(width 0.1524)
				(type default)
			)
			(layer "B.SilkS")
		)
		(fp_line
			(start -1.603248 1.500124)
			(end 1.603248 1.500124)
			(stroke
				(width 0.1524)
				(type default)
			)
			(layer "B.SilkS")
		)
		(fp_line
			(start -1.603248 -1.500124)
			(end -1.603248 1.500124)
			(stroke
				(width 0.1524)
				(type default)
			)
			(layer "B.SilkS")
		)
		(fp_line
			(start 1.249934 1.169924)
			(end 0.700024 1.169924)
			(stroke
				(width 0.1)
				(type default)
			)
			(layer "B.Fab")
		)
		(fp_line
			(start 1.249934 0.729996)
			(end 1.249934 1.169924)
			(stroke
				(width 0.1)
				(type default)
			)
			(layer "B.Fab")
		)
		(fp_line
			(start 1.249934 -0.729996)
			(end 0.6985 -0.729996)
			(stroke
				(width 0.1)
				(type default)
			)
			(layer "B.Fab")
		)
		(fp_line
			(start 1.249934 -1.169924)
			(end 1.249934 -0.729996)
			(stroke
				(width 0.1)
				(type default)
			)
			(layer "B.Fab")
		)
		(fp_line
			(start 0.700024 1.500124)
			(end -0.700024 1.500124)
			(stroke
				(width 0.1)
				(type default)
			)
			(layer "B.Fab")
		)
		(fp_line
			(start 0.700024 1.169924)
			(end 0.700024 1.500124)
			(stroke
				(width 0.1)
				(type default)
			)
			(layer "B.Fab")
		)
		(fp_line
			(start 0.700024 -1.169924)
			(end 1.249934 -1.169924)
			(stroke
				(width 0.1)
				(type default)
			)
			(layer "B.Fab")
		)
		(fp_line
			(start 0.700024 -1.500124)
			(end 0.700024 -1.169924)
			(stroke
				(width 0.1)
				(type default)
			)
			(layer "B.Fab")
		)
		(fp_line
			(start 0.6985 0.729996)
			(end 1.249934 0.729996)
			(stroke
				(width 0.1)
				(type default)
			)
			(layer "B.Fab")
		)
		(fp_line
			(start 0.6985 -0.729996)
			(end 0.6985 0.729996)
			(stroke
				(width 0.1)
				(type default)
			)
			(layer "B.Fab")
		)
		(fp_line
			(start -0.700024 1.500124)
			(end -0.700024 0.219964)
			(stroke
				(width 0.1)
				(type default)
			)
			(layer "B.Fab")
		)
		(fp_line
			(start -0.700024 0.219964)
			(end -1.249934 0.219964)
			(stroke
				(width 0.1)
				(type default)
			)
			(layer "B.Fab")
		)
		(fp_line
			(start -0.700024 -0.219964)
			(end -0.700024 -1.500124)
			(stroke
				(width 0.1)
				(type default)
			)
			(layer "B.Fab")
		)
		(fp_line
			(start -0.700024 -1.500124)
			(end 0.700024 -1.500124)
			(stroke
				(width 0.1)
				(type default)
			)
			(layer "B.Fab")
		)
		(fp_line
			(start -1.249934 0.219964)
			(end -1.249934 -0.219964)
			(stroke
				(width 0.1)
				(type default)
			)
			(layer "B.Fab")
		)
		(fp_line
			(start -1.249934 -0.219964)
			(end -0.700024 -0.219964)
			(stroke
				(width 0.1)
				(type default)
			)
			(layer "B.Fab")
		)
		(fp_rect
			(start -0.700024 1.500124)
			(end 0.700024 -1.500124)
			(stroke
				(width 0)
				(type default)
			)
			(fill no)
			(layer "B.Fab")
		)
		(pad "D" smd rect
			(at -0.999998 0 90)
			(size 0.8128 0.9144)
			(layers "B.Cu" "B.Mask" "B.Paste")
			(net "VR_P5V_EN_D")
		)
		(pad "G" smd rect
			(at 0.999998 -0.94996 90)
			(size 0.8128 0.9144)
			(layers "B.Cu" "B.Mask" "B.Paste")
			(net "VR_P5V_EN_N")
		)
		(pad "S" smd rect
			(at 0.999998 0.94996 90)
			(size 0.8128 0.9144)
			(layers "B.Cu" "B.Mask" "B.Paste")
			(net "GND")
		)
	)
	(footprint ""
		(layer "B.Cu")
		(at 186.711844 -113.462816 90)
		(property "Reference" "C358"
			(at 0 0 90)
			(layer "B.SilkS")
			(hide yes)
			(effects
				(font
					(size 1.27 1.27)
				)
				(justify mirror)
			)
		)
		(property "Value" ""
			(at 0 0 90)
			(layer "B.Fab")
			(effects
				(font
					(size 1.27 1.27)
				)
				(justify mirror)
			)
		)
		(duplicate_pad_numbers_are_jumpers no)
		(fp_line
			(start 0.69215 -0.2921)
			(end -0.69215 -0.2921)
			(stroke
				(width 0.1524)
				(type default)
			)
			(layer "B.SilkS")
		)
		(fp_line
			(start -0.69215 -0.2921)
			(end -0.69215 0.2921)
			(stroke
				(width 0.1524)
				(type default)
			)
			(layer "B.SilkS")
		)
		(fp_line
			(start 0.69215 0.2921)
			(end 0.69215 -0.2921)
			(stroke
				(width 0.1524)
				(type default)
			)
			(layer "B.SilkS")
		)
		(fp_line
			(start -0.69215 0.2921)
			(end 0.69215 0.2921)
			(stroke
				(width 0.1524)
				(type default)
			)
			(layer "B.SilkS")
		)
		(fp_line
			(start 0.51435 -0.2794)
			(end -0.51435 -0.2794)
			(stroke
				(width 0.1)
				(type default)
			)
			(layer "B.Fab")
		)
		(fp_line
			(start -0.51435 -0.2794)
			(end -0.51435 0.2794)
			(stroke
				(width 0.1)
				(type default)
			)
			(layer "B.Fab")
		)
		(fp_line
			(start 0.51435 0.2794)
			(end 0.51435 -0.2794)
			(stroke
				(width 0.1)
				(type default)
			)
			(layer "B.Fab")
		)
		(fp_line
			(start -0.51435 0.2794)
			(end 0.51435 0.2794)
			(stroke
				(width 0.1)
				(type default)
			)
			(layer "B.Fab")
		)
		(pad "1" smd circle
			(at 0.40005 0 270)
			(size 0 0)
			(layers "B.Cu" "B.Mask" "B.Paste")
			(net "P3V3_AUX")
		)
		(pad "2" smd circle
			(at -0.40005 0 270)
			(size 0 0)
			(layers "B.Cu" "B.Mask" "B.Paste")
			(net "GND")
		)
		(zone
			(layer "B.Cu")
			(hatch none 0.5)
			(connect_pads
				(clearance 0)
			)
			(min_thickness 0.25)
			(keepout
				(tracks not_allowed)
				(vias allowed)
				(pads allowed)
				(copperpour not_allowed)
				(footprints allowed)
			)
			(placement
				(enabled no)
				(sheetname "")
			)
			(fill
				(thermal_gap 0.5)
				(thermal_bridge_width 0.5)
				(island_removal_mode 0)
			)
			(polygon
				(pts
					(xy 186.565794 -113.362486) (xy 186.565794 -113.561876) (xy 186.62396 -113.653316) (xy 186.799474 -113.653316)
					(xy 186.85764 -113.561876) (xy 186.85764 -113.362486) (xy 186.799474 -113.272316) (xy 186.624214 -113.272316)
				)
			)
		)
	)
	(footprint ""
		(layer "B.Cu")
		(at 155.01239 -13.762228 90)
		(property "Reference" "R2414"
			(at 0 0 90)
			(layer "B.SilkS")
			(hide yes)
			(effects
				(font
					(size 1.27 1.27)
				)
				(justify mirror)
			)
		)
		(property "Value" ""
			(at 0 0 90)
			(layer "B.Fab")
			(effects
				(font
					(size 1.27 1.27)
				)
				(justify mirror)
			)
		)
		(duplicate_pad_numbers_are_jumpers no)
		(fp_line
			(start 0.7874 -0.4064)
			(end -0.7874 -0.4064)
			(stroke
				(width 0.1524)
				(type default)
			)
			(layer "B.SilkS")
		)
		(fp_line
			(start -0.7874 -0.4064)
			(end -0.7874 0.4064)
			(stroke
				(width 0.1524)
				(type default)
			)
			(layer "B.SilkS")
		)
		(fp_line
			(start 0.7874 0.4064)
			(end 0.7874 -0.4064)
			(stroke
				(width 0.1524)
				(type default)
			)
			(layer "B.SilkS")
		)
		(fp_line
			(start -0.7874 0.4064)
			(end 0.7874 0.4064)
			(stroke
				(width 0.1524)
				(type default)
			)
			(layer "B.SilkS")
		)
		(fp_line
			(start 0.67945 -0.305054)
			(end 0.12065 -0.305054)
			(stroke
				(width 0.1)
				(type default)
			)
			(layer "B.Fab")
		)
		(fp_line
			(start 0.12065 -0.305054)
			(end 0.12065 -0.2794)
			(stroke
				(width 0.1)
				(type default)
			)
			(layer "B.Fab")
		)
		(fp_line
			(start -0.12065 -0.3048)
			(end -0.67945 -0.3048)
			(stroke
				(width 0.1)
				(type default)
			)
			(layer "B.Fab")
		)
		(fp_line
			(start -0.67945 -0.3048)
			(end -0.67945 0.3048)
			(stroke
				(width 0.1)
				(type default)
			)
			(layer "B.Fab")
		)
		(fp_line
			(start 0.12065 -0.2794)
			(end -0.12065 -0.2794)
			(stroke
				(width 0.1)
				(type default)
			)
			(layer "B.Fab")
		)
		(fp_line
			(start -0.12065 -0.2794)
			(end -0.12065 -0.3048)
			(stroke
				(width 0.1)
				(type default)
			)
			(layer "B.Fab")
		)
		(fp_line
			(start 0.12065 0.2794)
			(end 0.12065 0.3048)
			(stroke
				(width 0.1)
				(type default)
			)
			(layer "B.Fab")
		)
		(fp_line
			(start -0.120396 0.2794)
			(end 0.12065 0.2794)
			(stroke
				(width 0.1)
				(type default)
			)
			(layer "B.Fab")
		)
		(fp_line
			(start 0.67945 0.3048)
			(end 0.67945 -0.305054)
			(stroke
				(width 0.1)
				(type default)
			)
			(layer "B.Fab")
		)
		(fp_line
			(start 0.12065 0.3048)
			(end 0.67945 0.3048)
			(stroke
				(width 0.1)
				(type default)
			)
			(layer "B.Fab")
		)
		(fp_line
			(start -0.120396 0.3048)
			(end -0.120396 0.2794)
			(stroke
				(width 0.1)
				(type default)
			)
			(layer "B.Fab")
		)
		(fp_line
			(start -0.67945 0.3048)
			(end -0.120396 0.3048)
			(stroke
				(width 0.1)
				(type default)
			)
			(layer "B.Fab")
		)
		(pad "1" smd circle
			(at 0.40005 0 270)
			(size 0 0)
			(layers "B.Cu" "B.Mask" "B.Paste")
			(net "SMB_2_BMC_GPU_SDA")
		)
		(pad "2" smd circle
			(at -0.40005 0 270)
			(size 0 0)
			(layers "B.Cu" "B.Mask" "B.Paste")
			(net "SMB_PCIE2_3V3AUX_SDA_R0")
		)
	)
	(footprint ""
		(layer "B.Cu")
		(at 320.846958 -198.583296)
		(property "Reference" "R408"
			(at 0 0 0)
			(layer "B.SilkS")
			(hide yes)
			(effects
				(font
					(size 1.27 1.27)
				)
				(justify mirror)
			)
		)
		(property "Value" ""
			(at 0 0 0)
			(layer "B.Fab")
			(effects
				(font
					(size 1.27 1.27)
				)
				(justify mirror)
			)
		)
		(duplicate_pad_numbers_are_jumpers no)
		(fp_line
			(start -0.7874 -0.4064)
			(end -0.7874 0.4064)
			(stroke
				(width 0.1524)
				(type default)
			)
			(layer "B.SilkS")
		)
		(fp_line
			(start -0.7874 0.4064)
			(end 0.7874 0.4064)
			(stroke
				(width 0.1524)
				(type default)
			)
			(layer "B.SilkS")
		)
		(fp_line
			(start 0.7874 -0.4064)
			(end -0.7874 -0.4064)
			(stroke
				(width 0.1524)
				(type default)
			)
			(layer "B.SilkS")
		)
		(fp_line
			(start 0.7874 0.4064)
			(end 0.7874 -0.4064)
			(stroke
				(width 0.1524)
				(type default)
			)
			(layer "B.SilkS")
		)
		(fp_line
			(start -0.67945 -0.3048)
			(end -0.67945 0.3048)
			(stroke
				(width 0.1)
				(type default)
			)
			(layer "B.Fab")
		)
		(fp_line
			(start -0.67945 0.3048)
			(end -0.120396 0.3048)
			(stroke
				(width 0.1)
				(type default)
			)
			(layer "B.Fab")
		)
		(fp_line
			(start -0.12065 -0.3048)
			(end -0.67945 -0.3048)
			(stroke
				(width 0.1)
				(type default)
			)
			(layer "B.Fab")
		)
		(fp_line
			(start -0.12065 -0.2794)
			(end -0.12065 -0.3048)
			(stroke
				(width 0.1)
				(type default)
			)
			(layer "B.Fab")
		)
		(fp_line
			(start -0.120396 0.2794)
			(end 0.12065 0.2794)
			(stroke
				(width 0.1)
				(type default)
			)
			(layer "B.Fab")
		)
		(fp_line
			(start -0.120396 0.3048)
			(end -0.120396 0.2794)
			(stroke
				(width 0.1)
				(type default)
			)
			(layer "B.Fab")
		)
		(fp_line
			(start 0.12065 -0.305054)
			(end 0.12065 -0.2794)
			(stroke
				(width 0.1)
				(type default)
			)
			(layer "B.Fab")
		)
		(fp_line
			(start 0.12065 -0.2794)
			(end -0.12065 -0.2794)
			(stroke
				(width 0.1)
				(type default)
			)
			(layer "B.Fab")
		)
		(fp_line
			(start 0.12065 0.2794)
			(end 0.12065 0.3048)
			(stroke
				(width 0.1)
				(type default)
			)
			(layer "B.Fab")
		)
		(fp_line
			(start 0.12065 0.3048)
			(end 0.67945 0.3048)
			(stroke
				(width 0.1)
				(type default)
			)
			(layer "B.Fab")
		)
		(fp_line
			(start 0.67945 -0.305054)
			(end 0.12065 -0.305054)
			(stroke
				(width 0.1)
				(type default)
			)
			(layer "B.Fab")
		)
		(fp_line
			(start 0.67945 0.3048)
			(end 0.67945 -0.305054)
			(stroke
				(width 0.1)
				(type default)
			)
			(layer "B.Fab")
		)
		(pad "1" smd circle
			(at 0.40005 0 180)
			(size 0 0)
			(layers "B.Cu" "B.Mask" "B.Paste")
			(net "CPU0_BP0")
		)
		(pad "2" smd circle
			(at -0.40005 0 180)
			(size 0 0)
			(layers "B.Cu" "B.Mask" "B.Paste")
			(net "PVDD18_S5_P0")
		)
	)
	(footprint ""
		(layer "B.Cu")
		(at 108.833158 -408.52598)
		(property "Reference" "C58"
			(at 0 0 0)
			(layer "B.SilkS")
			(hide yes)
			(effects
				(font
					(size 1.27 1.27)
				)
				(justify mirror)
			)
		)
		(property "Value" ""
			(at 0 0 0)
			(layer "B.Fab")
			(effects
				(font
					(size 1.27 1.27)
				)
				(justify mirror)
			)
		)
		(duplicate_pad_numbers_are_jumpers no)
		(fp_line
			(start -0.7874 -0.4064)
			(end -0.7874 0.4064)
			(stroke
				(width 0.1524)
				(type default)
			)
			(layer "B.SilkS")
		)
		(fp_line
			(start -0.7874 0.4064)
			(end 0.7874 0.4064)
			(stroke
				(width 0.1524)
				(type default)
			)
			(layer "B.SilkS")
		)
		(fp_line
			(start 0.7874 -0.4064)
			(end -0.7874 -0.4064)
			(stroke
				(width 0.1524)
				(type default)
			)
			(layer "B.SilkS")
		)
		(fp_line
			(start 0.7874 0.4064)
			(end 0.7874 -0.4064)
			(stroke
				(width 0.1524)
				(type default)
			)
			(layer "B.SilkS")
		)
		(fp_line
			(start -0.67945 -0.3048)
			(end -0.67945 0.3048)
			(stroke
				(width 0.1)
				(type default)
			)
			(layer "B.Fab")
		)
		(fp_line
			(start -0.67945 0.3048)
			(end -0.120396 0.3048)
			(stroke
				(width 0.1)
				(type default)
			)
			(layer "B.Fab")
		)
		(fp_line
			(start -0.12065 -0.3048)
			(end -0.67945 -0.3048)
			(stroke
				(width 0.1)
				(type default)
			)
			(layer "B.Fab")
		)
		(fp_line
			(start -0.12065 -0.2794)
			(end -0.12065 -0.3048)
			(stroke
				(width 0.1)
				(type default)
			)
			(layer "B.Fab")
		)
		(fp_line
			(start -0.120396 0.2794)
			(end 0.12065 0.2794)
			(stroke
				(width 0.1)
				(type default)
			)
			(layer "B.Fab")
		)
		(fp_line
			(start -0.120396 0.3048)
			(end -0.120396 0.2794)
			(stroke
				(width 0.1)
				(type default)
			)
			(layer "B.Fab")
		)
		(fp_line
			(start 0.12065 -0.305054)
			(end 0.12065 -0.2794)
			(stroke
				(width 0.1)
				(type default)
			)
			(layer "B.Fab")
		)
		(fp_line
			(start 0.12065 -0.2794)
			(end -0.12065 -0.2794)
			(stroke
				(width 0.1)
				(type default)
			)
			(layer "B.Fab")
		)
		(fp_line
			(start 0.12065 0.2794)
			(end 0.12065 0.3048)
			(stroke
				(width 0.1)
				(type default)
			)
			(layer "B.Fab")
		)
		(fp_line
			(start 0.12065 0.3048)
			(end 0.67945 0.3048)
			(stroke
				(width 0.1)
				(type default)
			)
			(layer "B.Fab")
		)
		(fp_line
			(start 0.67945 -0.305054)
			(end 0.12065 -0.305054)
			(stroke
				(width 0.1)
				(type default)
			)
			(layer "B.Fab")
		)
		(fp_line
			(start 0.67945 0.3048)
			(end 0.67945 -0.305054)
			(stroke
				(width 0.1)
				(type default)
			)
			(layer "B.Fab")
		)
		(pad "1" smd circle
			(at 0.40005 0 180)
			(size 0 0)
			(layers "B.Cu" "B.Mask" "B.Paste")
			(net "P3V3_9ZXL045_P1_VDD")
		)
		(pad "2" smd circle
			(at -0.40005 0 180)
			(size 0 0)
			(layers "B.Cu" "B.Mask" "B.Paste")
			(net "GND")
		)
	)
	(footprint ""
		(layer "B.Cu")
		(at 157.61843 -14.143228 180)
		(property "Reference" "R330"
			(at 0 0 0)
			(layer "B.SilkS")
			(hide yes)
			(effects
				(font
					(size 1.27 1.27)
				)
				(justify mirror)
			)
		)
		(property "Value" ""
			(at 0 0 0)
			(layer "B.Fab")
			(effects
				(font
					(size 1.27 1.27)
				)
				(justify mirror)
			)
		)
		(duplicate_pad_numbers_are_jumpers no)
		(fp_line
			(start 0.7874 0.4064)
			(end 0.7874 -0.4064)
			(stroke
				(width 0.1524)
				(type default)
			)
			(layer "B.SilkS")
		)
		(fp_line
			(start 0.7874 -0.4064)
			(end -0.7874 -0.4064)
			(stroke
				(width 0.1524)
				(type default)
			)
			(layer "B.SilkS")
		)
		(fp_line
			(start -0.7874 0.4064)
			(end 0.7874 0.4064)
			(stroke
				(width 0.1524)
				(type default)
			)
			(layer "B.SilkS")
		)
		(fp_line
			(start -0.7874 -0.4064)
			(end -0.7874 0.4064)
			(stroke
				(width 0.1524)
				(type default)
			)
			(layer "B.SilkS")
		)
		(fp_line
			(start 0.67945 0.3048)
			(end 0.67945 -0.305054)
			(stroke
				(width 0.1)
				(type default)
			)
			(layer "B.Fab")
		)
		(fp_line
			(start 0.67945 -0.305054)
			(end 0.12065 -0.305054)
			(stroke
				(width 0.1)
				(type default)
			)
			(layer "B.Fab")
		)
		(fp_line
			(start 0.12065 0.3048)
			(end 0.67945 0.3048)
			(stroke
				(width 0.1)
				(type default)
			)
			(layer "B.Fab")
		)
		(fp_line
			(start 0.12065 0.2794)
			(end 0.12065 0.3048)
			(stroke
				(width 0.1)
				(type default)
			)
			(layer "B.Fab")
		)
		(fp_line
			(start 0.12065 -0.2794)
			(end -0.12065 -0.2794)
			(stroke
				(width 0.1)
				(type default)
			)
			(layer "B.Fab")
		)
		(fp_line
			(start 0.12065 -0.305054)
			(end 0.12065 -0.2794)
			(stroke
				(width 0.1)
				(type default)
			)
			(layer "B.Fab")
		)
		(fp_line
			(start -0.120396 0.3048)
			(end -0.120396 0.2794)
			(stroke
				(width 0.1)
				(type default)
			)
			(layer "B.Fab")
		)
		(fp_line
			(start -0.120396 0.2794)
			(end 0.12065 0.2794)
			(stroke
				(width 0.1)
				(type default)
			)
			(layer "B.Fab")
		)
		(fp_line
			(start -0.12065 -0.2794)
			(end -0.12065 -0.3048)
			(stroke
				(width 0.1)
				(type default)
			)
			(layer "B.Fab")
		)
		(fp_line
			(start -0.12065 -0.3048)
			(end -0.67945 -0.3048)
			(stroke
				(width 0.1)
				(type default)
			)
			(layer "B.Fab")
		)
		(fp_line
			(start -0.67945 0.3048)
			(end -0.120396 0.3048)
			(stroke
				(width 0.1)
				(type default)
			)
			(layer "B.Fab")
		)
		(fp_line
			(start -0.67945 -0.3048)
			(end -0.67945 0.3048)
			(stroke
				(width 0.1)
				(type default)
			)
			(layer "B.Fab")
		)
		(pad "1" smd circle
			(at 0.40005 0)
			(size 0 0)
			(layers "B.Cu" "B.Mask" "B.Paste")
			(net "SMB_FAN_3V3AUX_SCL")
		)
		(pad "2" smd circle
			(at -0.40005 0)
			(size 0 0)
			(layers "B.Cu" "B.Mask" "B.Paste")
			(net "P3V3_AUX")
		)
	)
	(footprint ""
		(layer "B.Cu")
		(at 242.697 -229.489 180)
		(property "Reference" "R368"
			(at 0 0 0)
			(layer "B.SilkS")
			(hide yes)
			(effects
				(font
					(size 1.27 1.27)
				)
				(justify mirror)
			)
		)
		(property "Value" ""
			(at 0 0 0)
			(layer "B.Fab")
			(effects
				(font
					(size 1.27 1.27)
				)
				(justify mirror)
			)
		)
		(duplicate_pad_numbers_are_jumpers no)
		(fp_line
			(start 0.7874 0.4064)
			(end 0.7874 -0.4064)
			(stroke
				(width 0.1524)
				(type default)
			)
			(layer "B.SilkS")
		)
		(fp_line
			(start 0.7874 -0.4064)
			(end -0.7874 -0.4064)
			(stroke
				(width 0.1524)
				(type default)
			)
			(layer "B.SilkS")
		)
		(fp_line
			(start -0.7874 0.4064)
			(end 0.7874 0.4064)
			(stroke
				(width 0.1524)
				(type default)
			)
			(layer "B.SilkS")
		)
		(fp_line
			(start -0.7874 -0.4064)
			(end -0.7874 0.4064)
			(stroke
				(width 0.1524)
				(type default)
			)
			(layer "B.SilkS")
		)
		(fp_line
			(start 0.67945 0.3048)
			(end 0.67945 -0.305054)
			(stroke
				(width 0.1)
				(type default)
			)
			(layer "B.Fab")
		)
		(fp_line
			(start 0.67945 -0.305054)
			(end 0.12065 -0.305054)
			(stroke
				(width 0.1)
				(type default)
			)
			(layer "B.Fab")
		)
		(fp_line
			(start 0.12065 0.3048)
			(end 0.67945 0.3048)
			(stroke
				(width 0.1)
				(type default)
			)
			(layer "B.Fab")
		)
		(fp_line
			(start 0.12065 0.2794)
			(end 0.12065 0.3048)
			(stroke
				(width 0.1)
				(type default)
			)
			(layer "B.Fab")
		)
		(fp_line
			(start 0.12065 -0.2794)
			(end -0.12065 -0.2794)
			(stroke
				(width 0.1)
				(type default)
			)
			(layer "B.Fab")
		)
		(fp_line
			(start 0.12065 -0.305054)
			(end 0.12065 -0.2794)
			(stroke
				(width 0.1)
				(type default)
			)
			(layer "B.Fab")
		)
		(fp_line
			(start -0.120396 0.3048)
			(end -0.120396 0.2794)
			(stroke
				(width 0.1)
				(type default)
			)
			(layer "B.Fab")
		)
		(fp_line
			(start -0.120396 0.2794)
			(end 0.12065 0.2794)
			(stroke
				(width 0.1)
				(type default)
			)
			(layer "B.Fab")
		)
		(fp_line
			(start -0.12065 -0.2794)
			(end -0.12065 -0.3048)
			(stroke
				(width 0.1)
				(type default)
			)
			(layer "B.Fab")
		)
		(fp_line
			(start -0.12065 -0.3048)
			(end -0.67945 -0.3048)
			(stroke
				(width 0.1)
				(type default)
			)
			(layer "B.Fab")
		)
		(fp_line
			(start -0.67945 0.3048)
			(end -0.120396 0.3048)
			(stroke
				(width 0.1)
				(type default)
			)
			(layer "B.Fab")
		)
		(fp_line
			(start -0.67945 -0.3048)
			(end -0.67945 0.3048)
			(stroke
				(width 0.1)
				(type default)
			)
			(layer "B.Fab")
		)
		(pad "1" smd circle
			(at 0.40005 0)
			(size 0 0)
			(layers "B.Cu" "B.Mask" "B.Paste")
			(net "PVDD18_S5_P0")
		)
		(pad "2" smd circle
			(at -0.40005 0)
			(size 0 0)
			(layers "B.Cu" "B.Mask" "B.Paste")
			(net "SMB_CPU0_CPU1_SEC_SCL_R2")
		)
	)
	(footprint ""
		(layer "B.Cu")
		(at 186.81446 -190.948564 180)
		(property "Reference" "R312"
			(at 0 0 0)
			(layer "B.SilkS")
			(hide yes)
			(effects
				(font
					(size 1.27 1.27)
				)
				(justify mirror)
			)
		)
		(property "Value" ""
			(at 0 0 0)
			(layer "B.Fab")
			(effects
				(font
					(size 1.27 1.27)
				)
				(justify mirror)
			)
		)
		(duplicate_pad_numbers_are_jumpers no)
		(fp_line
			(start 0.7874 0.4064)
			(end 0.7874 -0.4064)
			(stroke
				(width 0.1524)
				(type default)
			)
			(layer "B.SilkS")
		)
		(fp_line
			(start 0.7874 -0.4064)
			(end -0.7874 -0.4064)
			(stroke
				(width 0.1524)
				(type default)
			)
			(layer "B.SilkS")
		)
		(fp_line
			(start -0.7874 0.4064)
			(end 0.7874 0.4064)
			(stroke
				(width 0.1524)
				(type default)
			)
			(layer "B.SilkS")
		)
		(fp_line
			(start -0.7874 -0.4064)
			(end -0.7874 0.4064)
			(stroke
				(width 0.1524)
				(type default)
			)
			(layer "B.SilkS")
		)
		(fp_line
			(start 0.67945 0.3048)
			(end 0.67945 -0.305054)
			(stroke
				(width 0.1)
				(type default)
			)
			(layer "B.Fab")
		)
		(fp_line
			(start 0.67945 -0.305054)
			(end 0.12065 -0.305054)
			(stroke
				(width 0.1)
				(type default)
			)
			(layer "B.Fab")
		)
		(fp_line
			(start 0.12065 0.3048)
			(end 0.67945 0.3048)
			(stroke
				(width 0.1)
				(type default)
			)
			(layer "B.Fab")
		)
		(fp_line
			(start 0.12065 0.2794)
			(end 0.12065 0.3048)
			(stroke
				(width 0.1)
				(type default)
			)
			(layer "B.Fab")
		)
		(fp_line
			(start 0.12065 -0.2794)
			(end -0.12065 -0.2794)
			(stroke
				(width 0.1)
				(type default)
			)
			(layer "B.Fab")
		)
		(fp_line
			(start 0.12065 -0.305054)
			(end 0.12065 -0.2794)
			(stroke
				(width 0.1)
				(type default)
			)
			(layer "B.Fab")
		)
		(fp_line
			(start -0.120396 0.3048)
			(end -0.120396 0.2794)
			(stroke
				(width 0.1)
				(type default)
			)
			(layer "B.Fab")
		)
		(fp_line
			(start -0.120396 0.2794)
			(end 0.12065 0.2794)
			(stroke
				(width 0.1)
				(type default)
			)
			(layer "B.Fab")
		)
		(fp_line
			(start -0.12065 -0.2794)
			(end -0.12065 -0.3048)
			(stroke
				(width 0.1)
				(type default)
			)
			(layer "B.Fab")
		)
		(fp_line
			(start -0.12065 -0.3048)
			(end -0.67945 -0.3048)
			(stroke
				(width 0.1)
				(type default)
			)
			(layer "B.Fab")
		)
		(fp_line
			(start -0.67945 0.3048)
			(end -0.120396 0.3048)
			(stroke
				(width 0.1)
				(type default)
			)
			(layer "B.Fab")
		)
		(fp_line
			(start -0.67945 -0.3048)
			(end -0.67945 0.3048)
			(stroke
				(width 0.1)
				(type default)
			)
			(layer "B.Fab")
		)
		(pad "1" smd circle
			(at 0.40005 0)
			(size 0 0)
			(layers "B.Cu" "B.Mask" "B.Paste")
			(net "PWRGD_CHJ_CPU1_DIMM")
		)
		(pad "2" smd circle
			(at -0.40005 0)
			(size 0 0)
			(layers "B.Cu" "B.Mask" "B.Paste")
			(net "PWRGD_CHGL_CPU1")
		)
	)
	(footprint ""
		(layer "B.Cu")
		(at 185.458608 -116.642896 -90)
		(property "Reference" "C1173"
			(at 0 0 90)
			(layer "B.SilkS")
			(hide yes)
			(effects
				(font
					(size 1.27 1.27)
				)
				(justify mirror)
			)
		)
		(property "Value" ""
			(at 0 0 90)
			(layer "B.Fab")
			(effects
				(font
					(size 1.27 1.27)
				)
				(justify mirror)
			)
		)
		(duplicate_pad_numbers_are_jumpers no)
		(fp_line
			(start -0.69215 0.2921)
			(end 0.69215 0.2921)
			(stroke
				(width 0.1524)
				(type default)
			)
			(layer "B.SilkS")
		)
		(fp_line
			(start 0.69215 0.2921)
			(end 0.69215 -0.2921)
			(stroke
				(width 0.1524)
				(type default)
			)
			(layer "B.SilkS")
		)
		(fp_line
			(start -0.69215 -0.2921)
			(end -0.69215 0.2921)
			(stroke
				(width 0.1524)
				(type default)
			)
			(layer "B.SilkS")
		)
		(fp_line
			(start 0.69215 -0.2921)
			(end -0.69215 -0.2921)
			(stroke
				(width 0.1524)
				(type default)
			)
			(layer "B.SilkS")
		)
		(fp_line
			(start -0.51435 0.2794)
			(end 0.51435 0.2794)
			(stroke
				(width 0.1)
				(type default)
			)
			(layer "B.Fab")
		)
		(fp_line
			(start 0.51435 0.2794)
			(end 0.51435 -0.2794)
			(stroke
				(width 0.1)
				(type default)
			)
			(layer "B.Fab")
		)
		(fp_line
			(start -0.51435 -0.2794)
			(end -0.51435 0.2794)
			(stroke
				(width 0.1)
				(type default)
			)
			(layer "B.Fab")
		)
		(fp_line
			(start 0.51435 -0.2794)
			(end -0.51435 -0.2794)
			(stroke
				(width 0.1)
				(type default)
			)
			(layer "B.Fab")
		)
		(pad "1" smd circle
			(at 0.40005 0 90)
			(size 0 0)
			(layers "B.Cu" "B.Mask" "B.Paste")
			(net "P3V3_AUX")
		)
		(pad "2" smd circle
			(at -0.40005 0 90)
			(size 0 0)
			(layers "B.Cu" "B.Mask" "B.Paste")
			(net "GND")
		)
		(zone
			(layer "B.Cu")
			(hatch none 0.5)
			(connect_pads
				(clearance 0)
			)
			(min_thickness 0.25)
			(keepout
				(tracks not_allowed)
				(vias allowed)
				(pads allowed)
				(copperpour not_allowed)
				(footprints allowed)
			)
			(placement
				(enabled no)
				(sheetname "")
			)
			(fill
				(thermal_gap 0.5)
				(thermal_bridge_width 0.5)
				(island_removal_mode 0)
			)
			(polygon
				(pts
					(xy 185.312812 -116.543836) (xy 185.312812 -116.743226) (xy 185.370978 -116.833396) (xy 185.546238 -116.833396)
					(xy 185.604658 -116.743226) (xy 185.604658 -116.543836) (xy 185.546492 -116.452396) (xy 185.370978 -116.452396)
				)
			)
		)
	)
	(footprint ""
		(layer "B.Cu")
		(at 166.577518 -415.930588 180)
		(property "Reference" "R4575"
			(at 0 0 0)
			(layer "B.SilkS")
			(hide yes)
			(effects
				(font
					(size 1.27 1.27)
				)
				(justify mirror)
			)
		)
		(property "Value" ""
			(at 0 0 0)
			(layer "B.Fab")
			(effects
				(font
					(size 1.27 1.27)
				)
				(justify mirror)
			)
		)
		(duplicate_pad_numbers_are_jumpers no)
		(fp_line
			(start 0.7874 0.4064)
			(end 0.7874 -0.4064)
			(stroke
				(width 0.1524)
				(type default)
			)
			(layer "B.SilkS")
		)
		(fp_line
			(start 0.7874 -0.4064)
			(end -0.7874 -0.4064)
			(stroke
				(width 0.1524)
				(type default)
			)
			(layer "B.SilkS")
		)
		(fp_line
			(start -0.7874 0.4064)
			(end 0.7874 0.4064)
			(stroke
				(width 0.1524)
				(type default)
			)
			(layer "B.SilkS")
		)
		(fp_line
			(start -0.7874 -0.4064)
			(end -0.7874 0.4064)
			(stroke
				(width 0.1524)
				(type default)
			)
			(layer "B.SilkS")
		)
		(fp_line
			(start 0.67945 0.3048)
			(end 0.67945 -0.305054)
			(stroke
				(width 0.1)
				(type default)
			)
			(layer "B.Fab")
		)
		(fp_line
			(start 0.67945 -0.305054)
			(end 0.12065 -0.305054)
			(stroke
				(width 0.1)
				(type default)
			)
			(layer "B.Fab")
		)
		(fp_line
			(start 0.12065 0.3048)
			(end 0.67945 0.3048)
			(stroke
				(width 0.1)
				(type default)
			)
			(layer "B.Fab")
		)
		(fp_line
			(start 0.12065 0.2794)
			(end 0.12065 0.3048)
			(stroke
				(width 0.1)
				(type default)
			)
			(layer "B.Fab")
		)
		(fp_line
			(start 0.12065 -0.2794)
			(end -0.12065 -0.2794)
			(stroke
				(width 0.1)
				(type default)
			)
			(layer "B.Fab")
		)
		(fp_line
			(start 0.12065 -0.305054)
			(end 0.12065 -0.2794)
			(stroke
				(width 0.1)
				(type default)
			)
			(layer "B.Fab")
		)
		(fp_line
			(start -0.120396 0.3048)
			(end -0.120396 0.2794)
			(stroke
				(width 0.1)
				(type default)
			)
			(layer "B.Fab")
		)
		(fp_line
			(start -0.120396 0.2794)
			(end 0.12065 0.2794)
			(stroke
				(width 0.1)
				(type default)
			)
			(layer "B.Fab")
		)
		(fp_line
			(start -0.12065 -0.2794)
			(end -0.12065 -0.3048)
			(stroke
				(width 0.1)
				(type default)
			)
			(layer "B.Fab")
		)
		(fp_line
			(start -0.12065 -0.3048)
			(end -0.67945 -0.3048)
			(stroke
				(width 0.1)
				(type default)
			)
			(layer "B.Fab")
		)
		(fp_line
			(start -0.67945 0.3048)
			(end -0.120396 0.3048)
			(stroke
				(width 0.1)
				(type default)
			)
			(layer "B.Fab")
		)
		(fp_line
			(start -0.67945 -0.3048)
			(end -0.67945 0.3048)
			(stroke
				(width 0.1)
				(type default)
			)
			(layer "B.Fab")
		)
		(pad "1" smd circle
			(at 0.40005 0)
			(size 0 0)
			(layers "B.Cu" "B.Mask" "B.Paste")
			(net "GPU_3V3IO_RSVD0_FFU")
		)
		(pad "2" smd circle
			(at -0.40005 0)
			(size 0 0)
			(layers "B.Cu" "B.Mask" "B.Paste")
			(net "GPU_3V3IO_RSVD0_FFU_ISO")
		)
	)
	(footprint ""
		(layer "B.Cu")
		(at 96.719136 -390.560052 90)
		(property "Reference" "C331"
			(at 0 0 90)
			(layer "B.SilkS")
			(hide yes)
			(effects
				(font
					(size 1.27 1.27)
				)
				(justify mirror)
			)
		)
		(property "Value" ""
			(at 0 0 90)
			(layer "B.Fab")
			(effects
				(font
					(size 1.27 1.27)
				)
				(justify mirror)
			)
		)
		(duplicate_pad_numbers_are_jumpers no)
		(fp_line
			(start 0.7874 -0.4064)
			(end -0.7874 -0.4064)
			(stroke
				(width 0.1524)
				(type default)
			)
			(layer "B.SilkS")
		)
		(fp_line
			(start -0.7874 -0.4064)
			(end -0.7874 0.4064)
			(stroke
				(width 0.1524)
				(type default)
			)
			(layer "B.SilkS")
		)
		(fp_line
			(start 0.7874 0.4064)
			(end 0.7874 -0.4064)
			(stroke
				(width 0.1524)
				(type default)
			)
			(layer "B.SilkS")
		)
		(fp_line
			(start -0.7874 0.4064)
			(end 0.7874 0.4064)
			(stroke
				(width 0.1524)
				(type default)
			)
			(layer "B.SilkS")
		)
		(fp_line
			(start 0.67945 -0.305054)
			(end 0.12065 -0.305054)
			(stroke
				(width 0.1)
				(type default)
			)
			(layer "B.Fab")
		)
		(fp_line
			(start 0.12065 -0.305054)
			(end 0.12065 -0.2794)
			(stroke
				(width 0.1)
				(type default)
			)
			(layer "B.Fab")
		)
		(fp_line
			(start -0.12065 -0.3048)
			(end -0.67945 -0.3048)
			(stroke
				(width 0.1)
				(type default)
			)
			(layer "B.Fab")
		)
		(fp_line
			(start -0.67945 -0.3048)
			(end -0.67945 0.3048)
			(stroke
				(width 0.1)
				(type default)
			)
			(layer "B.Fab")
		)
		(fp_line
			(start 0.12065 -0.2794)
			(end -0.12065 -0.2794)
			(stroke
				(width 0.1)
				(type default)
			)
			(layer "B.Fab")
		)
		(fp_line
			(start -0.12065 -0.2794)
			(end -0.12065 -0.3048)
			(stroke
				(width 0.1)
				(type default)
			)
			(layer "B.Fab")
		)
		(fp_line
			(start 0.12065 0.2794)
			(end 0.12065 0.3048)
			(stroke
				(width 0.1)
				(type default)
			)
			(layer "B.Fab")
		)
		(fp_line
			(start -0.120396 0.2794)
			(end 0.12065 0.2794)
			(stroke
				(width 0.1)
				(type default)
			)
			(layer "B.Fab")
		)
		(fp_line
			(start 0.67945 0.3048)
			(end 0.67945 -0.305054)
			(stroke
				(width 0.1)
				(type default)
			)
			(layer "B.Fab")
		)
		(fp_line
			(start 0.12065 0.3048)
			(end 0.67945 0.3048)
			(stroke
				(width 0.1)
				(type default)
			)
			(layer "B.Fab")
		)
		(fp_line
			(start -0.120396 0.3048)
			(end -0.120396 0.2794)
			(stroke
				(width 0.1)
				(type default)
			)
			(layer "B.Fab")
		)
		(fp_line
			(start -0.67945 0.3048)
			(end -0.120396 0.3048)
			(stroke
				(width 0.1)
				(type default)
			)
			(layer "B.Fab")
		)
		(pad "1" smd circle
			(at 0.40005 0 270)
			(size 0 0)
			(layers "B.Cu" "B.Mask" "B.Paste")
			(net "P0V9_CPU1_RT1_2A")
		)
		(pad "2" smd circle
			(at -0.40005 0 270)
			(size 0 0)
			(layers "B.Cu" "B.Mask" "B.Paste")
			(net "GND")
		)
	)
	(footprint ""
		(layer "B.Cu")
		(at 172.727874 -193.996564)
		(property "Reference" "R111"
			(at 0 0 0)
			(layer "B.SilkS")
			(hide yes)
			(effects
				(font
					(size 1.27 1.27)
				)
				(justify mirror)
			)
		)
		(property "Value" ""
			(at 0 0 0)
			(layer "B.Fab")
			(effects
				(font
					(size 1.27 1.27)
				)
				(justify mirror)
			)
		)
		(duplicate_pad_numbers_are_jumpers no)
		(fp_line
			(start -0.7874 -0.4064)
			(end -0.7874 0.4064)
			(stroke
				(width 0.1524)
				(type default)
			)
			(layer "B.SilkS")
		)
		(fp_line
			(start -0.7874 0.4064)
			(end 0.7874 0.4064)
			(stroke
				(width 0.1524)
				(type default)
			)
			(layer "B.SilkS")
		)
		(fp_line
			(start 0.7874 -0.4064)
			(end -0.7874 -0.4064)
			(stroke
				(width 0.1524)
				(type default)
			)
			(layer "B.SilkS")
		)
		(fp_line
			(start 0.7874 0.4064)
			(end 0.7874 -0.4064)
			(stroke
				(width 0.1524)
				(type default)
			)
			(layer "B.SilkS")
		)
		(fp_line
			(start -0.67945 -0.3048)
			(end -0.67945 0.3048)
			(stroke
				(width 0.1)
				(type default)
			)
			(layer "B.Fab")
		)
		(fp_line
			(start -0.67945 0.3048)
			(end -0.120396 0.3048)
			(stroke
				(width 0.1)
				(type default)
			)
			(layer "B.Fab")
		)
		(fp_line
			(start -0.12065 -0.3048)
			(end -0.67945 -0.3048)
			(stroke
				(width 0.1)
				(type default)
			)
			(layer "B.Fab")
		)
		(fp_line
			(start -0.12065 -0.2794)
			(end -0.12065 -0.3048)
			(stroke
				(width 0.1)
				(type default)
			)
			(layer "B.Fab")
		)
		(fp_line
			(start -0.120396 0.2794)
			(end 0.12065 0.2794)
			(stroke
				(width 0.1)
				(type default)
			)
			(layer "B.Fab")
		)
		(fp_line
			(start -0.120396 0.3048)
			(end -0.120396 0.2794)
			(stroke
				(width 0.1)
				(type default)
			)
			(layer "B.Fab")
		)
		(fp_line
			(start 0.12065 -0.305054)
			(end 0.12065 -0.2794)
			(stroke
				(width 0.1)
				(type default)
			)
			(layer "B.Fab")
		)
		(fp_line
			(start 0.12065 -0.2794)
			(end -0.12065 -0.2794)
			(stroke
				(width 0.1)
				(type default)
			)
			(layer "B.Fab")
		)
		(fp_line
			(start 0.12065 0.2794)
			(end 0.12065 0.3048)
			(stroke
				(width 0.1)
				(type default)
			)
			(layer "B.Fab")
		)
		(fp_line
			(start 0.12065 0.3048)
			(end 0.67945 0.3048)
			(stroke
				(width 0.1)
				(type default)
			)
			(layer "B.Fab")
		)
		(fp_line
			(start 0.67945 -0.305054)
			(end 0.12065 -0.305054)
			(stroke
				(width 0.1)
				(type default)
			)
			(layer "B.Fab")
		)
		(fp_line
			(start 0.67945 0.3048)
			(end 0.67945 -0.305054)
			(stroke
				(width 0.1)
				(type default)
			)
			(layer "B.Fab")
		)
		(pad "1" smd circle
			(at 0.40005 0 180)
			(size 0 0)
			(layers "B.Cu" "B.Mask" "B.Paste")
			(net "P3V3")
		)
		(pad "2" smd circle
			(at -0.40005 0 180)
			(size 0 0)
			(layers "B.Cu" "B.Mask" "B.Paste")
			(net "PWRGD_CHH_CPU1_DIMM")
		)
	)
	(footprint ""
		(layer "B.Cu")
		(at 380.051056 -182.867554 -90)
		(property "Reference" "PC558_3"
			(at 0 0 90)
			(layer "B.SilkS")
			(hide yes)
			(effects
				(font
					(size 1.27 1.27)
				)
				(justify mirror)
			)
		)
		(property "Value" ""
			(at 0 0 90)
			(layer "B.Fab")
			(effects
				(font
					(size 1.27 1.27)
				)
				(justify mirror)
			)
		)
		(duplicate_pad_numbers_are_jumpers no)
		(fp_line
			(start -1.524 0.762)
			(end 1.524 0.762)
			(stroke
				(width 0.1524)
				(type default)
			)
			(layer "B.SilkS")
		)
		(fp_line
			(start 1.524 0.762)
			(end 1.524 -0.762)
			(stroke
				(width 0.1524)
				(type default)
			)
			(layer "B.SilkS")
		)
		(fp_line
			(start -1.524 -0.762)
			(end -1.524 0.762)
			(stroke
				(width 0.1524)
				(type default)
			)
			(layer "B.SilkS")
		)
		(fp_line
			(start 1.524 -0.762)
			(end -1.524 -0.762)
			(stroke
				(width 0.1524)
				(type default)
			)
			(layer "B.SilkS")
		)
		(fp_line
			(start -1.1049 0.724916)
			(end -1.1049 -0.724916)
			(stroke
				(width 0.1)
				(type default)
			)
			(layer "B.Fab")
		)
		(fp_line
			(start 1.1049 0.724916)
			(end -1.1049 0.724916)
			(stroke
				(width 0.1)
				(type default)
			)
			(layer "B.Fab")
		)
		(fp_line
			(start -1.1049 -0.724916)
			(end 1.1049 -0.724916)
			(stroke
				(width 0.1)
				(type default)
			)
			(layer "B.Fab")
		)
		(fp_line
			(start 1.1049 -0.724916)
			(end 1.1049 0.724916)
			(stroke
				(width 0.1)
				(type default)
			)
			(layer "B.Fab")
		)
		(pad "1" smd rect
			(at 0.889 0 270)
			(size 1.016 1.27)
			(layers "B.Cu" "B.Mask" "B.Paste")
			(net "SW_P12V_AUX_PVDDCR_CPU0_P0_FLT")
		)
		(pad "2" smd rect
			(at -0.889 0 270)
			(size 1.016 1.27)
			(layers "B.Cu" "B.Mask" "B.Paste")
			(net "GND")
		)
	)
	(footprint ""
		(layer "B.Cu")
		(at 442.345826 -399.56359 -90)
		(property "Reference" "PR6552"
			(at 0 0 90)
			(layer "B.SilkS")
			(hide yes)
			(effects
				(font
					(size 1.27 1.27)
				)
				(justify mirror)
			)
		)
		(property "Value" ""
			(at 0 0 90)
			(layer "B.Fab")
			(effects
				(font
					(size 1.27 1.27)
				)
				(justify mirror)
			)
		)
		(duplicate_pad_numbers_are_jumpers no)
		(fp_line
			(start -0.7874 0.4064)
			(end 0.7874 0.4064)
			(stroke
				(width 0.1524)
				(type default)
			)
			(layer "B.SilkS")
		)
		(fp_line
			(start 0.7874 0.4064)
			(end 0.7874 -0.4064)
			(stroke
				(width 0.1524)
				(type default)
			)
			(layer "B.SilkS")
		)
		(fp_line
			(start -0.7874 -0.4064)
			(end -0.7874 0.4064)
			(stroke
				(width 0.1524)
				(type default)
			)
			(layer "B.SilkS")
		)
		(fp_line
			(start 0.7874 -0.4064)
			(end -0.7874 -0.4064)
			(stroke
				(width 0.1524)
				(type default)
			)
			(layer "B.SilkS")
		)
		(fp_line
			(start -0.67945 0.3048)
			(end -0.120396 0.3048)
			(stroke
				(width 0.1)
				(type default)
			)
			(layer "B.Fab")
		)
		(fp_line
			(start -0.120396 0.3048)
			(end -0.120396 0.2794)
			(stroke
				(width 0.1)
				(type default)
			)
			(layer "B.Fab")
		)
		(fp_line
			(start 0.12065 0.3048)
			(end 0.67945 0.3048)
			(stroke
				(width 0.1)
				(type default)
			)
			(layer "B.Fab")
		)
		(fp_line
			(start 0.67945 0.3048)
			(end 0.67945 -0.305054)
			(stroke
				(width 0.1)
				(type default)
			)
			(layer "B.Fab")
		)
		(fp_line
			(start -0.120396 0.2794)
			(end 0.12065 0.2794)
			(stroke
				(width 0.1)
				(type default)
			)
			(layer "B.Fab")
		)
		(fp_line
			(start 0.12065 0.2794)
			(end 0.12065 0.3048)
			(stroke
				(width 0.1)
				(type default)
			)
			(layer "B.Fab")
		)
		(fp_line
			(start -0.12065 -0.2794)
			(end -0.12065 -0.3048)
			(stroke
				(width 0.1)
				(type default)
			)
			(layer "B.Fab")
		)
		(fp_line
			(start 0.12065 -0.2794)
			(end -0.12065 -0.2794)
			(stroke
				(width 0.1)
				(type default)
			)
			(layer "B.Fab")
		)
		(fp_line
			(start -0.67945 -0.3048)
			(end -0.67945 0.3048)
			(stroke
				(width 0.1)
				(type default)
			)
			(layer "B.Fab")
		)
		(fp_line
			(start -0.12065 -0.3048)
			(end -0.67945 -0.3048)
			(stroke
				(width 0.1)
				(type default)
			)
			(layer "B.Fab")
		)
		(fp_line
			(start 0.12065 -0.305054)
			(end 0.12065 -0.2794)
			(stroke
				(width 0.1)
				(type default)
			)
			(layer "B.Fab")
		)
		(fp_line
			(start 0.67945 -0.305054)
			(end 0.12065 -0.305054)
			(stroke
				(width 0.1)
				(type default)
			)
			(layer "B.Fab")
		)
		(pad "1" smd circle
			(at 0.40005 0 90)
			(size 0 0)
			(layers "B.Cu" "B.Mask" "B.Paste")
			(net "P0V9_RETIMER_CPU0_PVCC")
		)
		(pad "2" smd circle
			(at -0.40005 0 90)
			(size 0 0)
			(layers "B.Cu" "B.Mask" "B.Paste")
			(net "P0V9_RETIMER_CPU0_VCC1")
		)
	)
	(footprint ""
		(layer "B.Cu")
		(at 30.249114 -244.085364 180)
		(property "Reference" "R504"
			(at 0 0 0)
			(layer "B.SilkS")
			(hide yes)
			(effects
				(font
					(size 1.27 1.27)
				)
				(justify mirror)
			)
		)
		(property "Value" ""
			(at 0 0 0)
			(layer "B.Fab")
			(effects
				(font
					(size 1.27 1.27)
				)
				(justify mirror)
			)
		)
		(duplicate_pad_numbers_are_jumpers no)
		(fp_line
			(start 0.7874 0.4064)
			(end 0.7874 -0.4064)
			(stroke
				(width 0.1524)
				(type default)
			)
			(layer "B.SilkS")
		)
		(fp_line
			(start 0.7874 -0.4064)
			(end -0.7874 -0.4064)
			(stroke
				(width 0.1524)
				(type default)
			)
			(layer "B.SilkS")
		)
		(fp_line
			(start -0.7874 0.4064)
			(end 0.7874 0.4064)
			(stroke
				(width 0.1524)
				(type default)
			)
			(layer "B.SilkS")
		)
		(fp_line
			(start -0.7874 -0.4064)
			(end -0.7874 0.4064)
			(stroke
				(width 0.1524)
				(type default)
			)
			(layer "B.SilkS")
		)
		(fp_line
			(start 0.67945 0.3048)
			(end 0.67945 -0.305054)
			(stroke
				(width 0.1)
				(type default)
			)
			(layer "B.Fab")
		)
		(fp_line
			(start 0.67945 -0.305054)
			(end 0.12065 -0.305054)
			(stroke
				(width 0.1)
				(type default)
			)
			(layer "B.Fab")
		)
		(fp_line
			(start 0.12065 0.3048)
			(end 0.67945 0.3048)
			(stroke
				(width 0.1)
				(type default)
			)
			(layer "B.Fab")
		)
		(fp_line
			(start 0.12065 0.2794)
			(end 0.12065 0.3048)
			(stroke
				(width 0.1)
				(type default)
			)
			(layer "B.Fab")
		)
		(fp_line
			(start 0.12065 -0.2794)
			(end -0.12065 -0.2794)
			(stroke
				(width 0.1)
				(type default)
			)
			(layer "B.Fab")
		)
		(fp_line
			(start 0.12065 -0.305054)
			(end 0.12065 -0.2794)
			(stroke
				(width 0.1)
				(type default)
			)
			(layer "B.Fab")
		)
		(fp_line
			(start -0.120396 0.3048)
			(end -0.120396 0.2794)
			(stroke
				(width 0.1)
				(type default)
			)
			(layer "B.Fab")
		)
		(fp_line
			(start -0.120396 0.2794)
			(end 0.12065 0.2794)
			(stroke
				(width 0.1)
				(type default)
			)
			(layer "B.Fab")
		)
		(fp_line
			(start -0.12065 -0.2794)
			(end -0.12065 -0.3048)
			(stroke
				(width 0.1)
				(type default)
			)
			(layer "B.Fab")
		)
		(fp_line
			(start -0.12065 -0.3048)
			(end -0.67945 -0.3048)
			(stroke
				(width 0.1)
				(type default)
			)
			(layer "B.Fab")
		)
		(fp_line
			(start -0.67945 0.3048)
			(end -0.120396 0.3048)
			(stroke
				(width 0.1)
				(type default)
			)
			(layer "B.Fab")
		)
		(fp_line
			(start -0.67945 -0.3048)
			(end -0.67945 0.3048)
			(stroke
				(width 0.1)
				(type default)
			)
			(layer "B.Fab")
		)
		(pad "1" smd circle
			(at 0.40005 0)
			(size 0 0)
			(layers "B.Cu" "B.Mask" "B.Paste")
			(net "M_E_CPU1_ALERT_N")
		)
		(pad "2" smd circle
			(at -0.40005 0)
			(size 0 0)
			(layers "B.Cu" "B.Mask" "B.Paste")
			(net "M_E_CPU1_ALERT_R_N")
		)
	)
	(footprint ""
		(layer "B.Cu")
		(at 94.948502 -205.14945 90)
		(property "Reference" "R532"
			(at 0 0 90)
			(layer "B.SilkS")
			(hide yes)
			(effects
				(font
					(size 1.27 1.27)
				)
				(justify mirror)
			)
		)
		(property "Value" ""
			(at 0 0 90)
			(layer "B.Fab")
			(effects
				(font
					(size 1.27 1.27)
				)
				(justify mirror)
			)
		)
		(duplicate_pad_numbers_are_jumpers no)
		(fp_line
			(start 0.7874 -0.4064)
			(end -0.7874 -0.4064)
			(stroke
				(width 0.1524)
				(type default)
			)
			(layer "B.SilkS")
		)
		(fp_line
			(start -0.7874 -0.4064)
			(end -0.7874 0.4064)
			(stroke
				(width 0.1524)
				(type default)
			)
			(layer "B.SilkS")
		)
		(fp_line
			(start 0.7874 0.4064)
			(end 0.7874 -0.4064)
			(stroke
				(width 0.1524)
				(type default)
			)
			(layer "B.SilkS")
		)
		(fp_line
			(start -0.7874 0.4064)
			(end 0.7874 0.4064)
			(stroke
				(width 0.1524)
				(type default)
			)
			(layer "B.SilkS")
		)
		(fp_line
			(start 0.67945 -0.305054)
			(end 0.12065 -0.305054)
			(stroke
				(width 0.1)
				(type default)
			)
			(layer "B.Fab")
		)
		(fp_line
			(start 0.12065 -0.305054)
			(end 0.12065 -0.2794)
			(stroke
				(width 0.1)
				(type default)
			)
			(layer "B.Fab")
		)
		(fp_line
			(start -0.12065 -0.3048)
			(end -0.67945 -0.3048)
			(stroke
				(width 0.1)
				(type default)
			)
			(layer "B.Fab")
		)
		(fp_line
			(start -0.67945 -0.3048)
			(end -0.67945 0.3048)
			(stroke
				(width 0.1)
				(type default)
			)
			(layer "B.Fab")
		)
		(fp_line
			(start 0.12065 -0.2794)
			(end -0.12065 -0.2794)
			(stroke
				(width 0.1)
				(type default)
			)
			(layer "B.Fab")
		)
		(fp_line
			(start -0.12065 -0.2794)
			(end -0.12065 -0.3048)
			(stroke
				(width 0.1)
				(type default)
			)
			(layer "B.Fab")
		)
		(fp_line
			(start 0.12065 0.2794)
			(end 0.12065 0.3048)
			(stroke
				(width 0.1)
				(type default)
			)
			(layer "B.Fab")
		)
		(fp_line
			(start -0.120396 0.2794)
			(end 0.12065 0.2794)
			(stroke
				(width 0.1)
				(type default)
			)
			(layer "B.Fab")
		)
		(fp_line
			(start 0.67945 0.3048)
			(end 0.67945 -0.305054)
			(stroke
				(width 0.1)
				(type default)
			)
			(layer "B.Fab")
		)
		(fp_line
			(start 0.12065 0.3048)
			(end 0.67945 0.3048)
			(stroke
				(width 0.1)
				(type default)
			)
			(layer "B.Fab")
		)
		(fp_line
			(start -0.120396 0.3048)
			(end -0.120396 0.2794)
			(stroke
				(width 0.1)
				(type default)
			)
			(layer "B.Fab")
		)
		(fp_line
			(start -0.67945 0.3048)
			(end -0.120396 0.3048)
			(stroke
				(width 0.1)
				(type default)
			)
			(layer "B.Fab")
		)
		(pad "1" smd circle
			(at 0.40005 0 270)
			(size 0 0)
			(layers "B.Cu" "B.Mask" "B.Paste")
			(net "CPU1_BP1")
		)
		(pad "2" smd circle
			(at -0.40005 0 270)
			(size 0 0)
			(layers "B.Cu" "B.Mask" "B.Paste")
			(net "PVDD18_S5_P1")
		)
	)
	(footprint ""
		(layer "B.Cu")
		(at 90.706194 -386.766562 90)
		(property "Reference" "C203"
			(at 0 0 90)
			(layer "B.SilkS")
			(hide yes)
			(effects
				(font
					(size 1.27 1.27)
				)
				(justify mirror)
			)
		)
		(property "Value" ""
			(at 0 0 90)
			(layer "B.Fab")
			(effects
				(font
					(size 1.27 1.27)
				)
				(justify mirror)
			)
		)
		(duplicate_pad_numbers_are_jumpers no)
		(fp_line
			(start 0.299974 -0.150114)
			(end -0.299974 -0.150114)
			(stroke
				(width 0.1)
				(type default)
			)
			(layer "B.Fab")
		)
		(fp_line
			(start -0.299974 -0.150114)
			(end -0.299974 0.150114)
			(stroke
				(width 0.1)
				(type default)
			)
			(layer "B.Fab")
		)
		(fp_line
			(start 0.299974 0.150114)
			(end 0.299974 -0.150114)
			(stroke
				(width 0.1)
				(type default)
			)
			(layer "B.Fab")
		)
		(fp_line
			(start -0.299974 0.150114)
			(end 0.299974 0.150114)
			(stroke
				(width 0.1)
				(type default)
			)
			(layer "B.Fab")
		)
		(pad "1" smd rect
			(at 0.2667 0 270)
			(size 0.3048 0.381)
			(layers "B.Cu" "B.Mask" "B.Paste")
			(net "P1V8_CPU1_RT1_1A_1D")
		)
		(pad "2" smd rect
			(at -0.2667 0 270)
			(size 0.3048 0.381)
			(layers "B.Cu" "B.Mask" "B.Paste")
			(net "GND")
		)
	)
	(footprint ""
		(layer "B.Cu")
		(at 435.755796 -193.99631)
		(property "Reference" "R99"
			(at 0 0 0)
			(layer "B.SilkS")
			(hide yes)
			(effects
				(font
					(size 1.27 1.27)
				)
				(justify mirror)
			)
		)
		(property "Value" ""
			(at 0 0 0)
			(layer "B.Fab")
			(effects
				(font
					(size 1.27 1.27)
				)
				(justify mirror)
			)
		)
		(duplicate_pad_numbers_are_jumpers no)
		(fp_line
			(start -0.7874 -0.4064)
			(end -0.7874 0.4064)
			(stroke
				(width 0.1524)
				(type default)
			)
			(layer "B.SilkS")
		)
		(fp_line
			(start -0.7874 0.4064)
			(end 0.7874 0.4064)
			(stroke
				(width 0.1524)
				(type default)
			)
			(layer "B.SilkS")
		)
		(fp_line
			(start 0.7874 -0.4064)
			(end -0.7874 -0.4064)
			(stroke
				(width 0.1524)
				(type default)
			)
			(layer "B.SilkS")
		)
		(fp_line
			(start 0.7874 0.4064)
			(end 0.7874 -0.4064)
			(stroke
				(width 0.1524)
				(type default)
			)
			(layer "B.SilkS")
		)
		(fp_line
			(start -0.67945 -0.3048)
			(end -0.67945 0.3048)
			(stroke
				(width 0.1)
				(type default)
			)
			(layer "B.Fab")
		)
		(fp_line
			(start -0.67945 0.3048)
			(end -0.120396 0.3048)
			(stroke
				(width 0.1)
				(type default)
			)
			(layer "B.Fab")
		)
		(fp_line
			(start -0.12065 -0.3048)
			(end -0.67945 -0.3048)
			(stroke
				(width 0.1)
				(type default)
			)
			(layer "B.Fab")
		)
		(fp_line
			(start -0.12065 -0.2794)
			(end -0.12065 -0.3048)
			(stroke
				(width 0.1)
				(type default)
			)
			(layer "B.Fab")
		)
		(fp_line
			(start -0.120396 0.2794)
			(end 0.12065 0.2794)
			(stroke
				(width 0.1)
				(type default)
			)
			(layer "B.Fab")
		)
		(fp_line
			(start -0.120396 0.3048)
			(end -0.120396 0.2794)
			(stroke
				(width 0.1)
				(type default)
			)
			(layer "B.Fab")
		)
		(fp_line
			(start 0.12065 -0.305054)
			(end 0.12065 -0.2794)
			(stroke
				(width 0.1)
				(type default)
			)
			(layer "B.Fab")
		)
		(fp_line
			(start 0.12065 -0.2794)
			(end -0.12065 -0.2794)
			(stroke
				(width 0.1)
				(type default)
			)
			(layer "B.Fab")
		)
		(fp_line
			(start 0.12065 0.2794)
			(end 0.12065 0.3048)
			(stroke
				(width 0.1)
				(type default)
			)
			(layer "B.Fab")
		)
		(fp_line
			(start 0.12065 0.3048)
			(end 0.67945 0.3048)
			(stroke
				(width 0.1)
				(type default)
			)
			(layer "B.Fab")
		)
		(fp_line
			(start 0.67945 -0.305054)
			(end 0.12065 -0.305054)
			(stroke
				(width 0.1)
				(type default)
			)
			(layer "B.Fab")
		)
		(fp_line
			(start 0.67945 0.3048)
			(end 0.67945 -0.305054)
			(stroke
				(width 0.1)
				(type default)
			)
			(layer "B.Fab")
		)
		(pad "1" smd circle
			(at 0.40005 0 180)
			(size 0 0)
			(layers "B.Cu" "B.Mask" "B.Paste")
			(net "P3V3")
		)
		(pad "2" smd circle
			(at -0.40005 0 180)
			(size 0 0)
			(layers "B.Cu" "B.Mask" "B.Paste")
			(net "PWRGD_CHJ_CPU0_DIMM")
		)
	)
	(footprint ""
		(layer "B.Cu")
		(at 97.591118 -426.179996 180)
		(property "Reference" "R8003"
			(at 0 0 0)
			(layer "B.SilkS")
			(hide yes)
			(effects
				(font
					(size 1.27 1.27)
				)
				(justify mirror)
			)
		)
		(property "Value" ""
			(at 0 0 0)
			(layer "B.Fab")
			(effects
				(font
					(size 1.27 1.27)
				)
				(justify mirror)
			)
		)
		(duplicate_pad_numbers_are_jumpers no)
		(fp_line
			(start 0.7874 0.4064)
			(end 0.7874 -0.4064)
			(stroke
				(width 0.1524)
				(type default)
			)
			(layer "B.SilkS")
		)
		(fp_line
			(start 0.7874 -0.4064)
			(end -0.7874 -0.4064)
			(stroke
				(width 0.1524)
				(type default)
			)
			(layer "B.SilkS")
		)
		(fp_line
			(start -0.7874 0.4064)
			(end 0.7874 0.4064)
			(stroke
				(width 0.1524)
				(type default)
			)
			(layer "B.SilkS")
		)
		(fp_line
			(start -0.7874 -0.4064)
			(end -0.7874 0.4064)
			(stroke
				(width 0.1524)
				(type default)
			)
			(layer "B.SilkS")
		)
		(fp_line
			(start 0.67945 0.3048)
			(end 0.67945 -0.305054)
			(stroke
				(width 0.1)
				(type default)
			)
			(layer "B.Fab")
		)
		(fp_line
			(start 0.67945 -0.305054)
			(end 0.12065 -0.305054)
			(stroke
				(width 0.1)
				(type default)
			)
			(layer "B.Fab")
		)
		(fp_line
			(start 0.12065 0.3048)
			(end 0.67945 0.3048)
			(stroke
				(width 0.1)
				(type default)
			)
			(layer "B.Fab")
		)
		(fp_line
			(start 0.12065 0.2794)
			(end 0.12065 0.3048)
			(stroke
				(width 0.1)
				(type default)
			)
			(layer "B.Fab")
		)
		(fp_line
			(start 0.12065 -0.2794)
			(end -0.12065 -0.2794)
			(stroke
				(width 0.1)
				(type default)
			)
			(layer "B.Fab")
		)
		(fp_line
			(start 0.12065 -0.305054)
			(end 0.12065 -0.2794)
			(stroke
				(width 0.1)
				(type default)
			)
			(layer "B.Fab")
		)
		(fp_line
			(start -0.120396 0.3048)
			(end -0.120396 0.2794)
			(stroke
				(width 0.1)
				(type default)
			)
			(layer "B.Fab")
		)
		(fp_line
			(start -0.120396 0.2794)
			(end 0.12065 0.2794)
			(stroke
				(width 0.1)
				(type default)
			)
			(layer "B.Fab")
		)
		(fp_line
			(start -0.12065 -0.2794)
			(end -0.12065 -0.3048)
			(stroke
				(width 0.1)
				(type default)
			)
			(layer "B.Fab")
		)
		(fp_line
			(start -0.12065 -0.3048)
			(end -0.67945 -0.3048)
			(stroke
				(width 0.1)
				(type default)
			)
			(layer "B.Fab")
		)
		(fp_line
			(start -0.67945 0.3048)
			(end -0.120396 0.3048)
			(stroke
				(width 0.1)
				(type default)
			)
			(layer "B.Fab")
		)
		(fp_line
			(start -0.67945 -0.3048)
			(end -0.67945 0.3048)
			(stroke
				(width 0.1)
				(type default)
			)
			(layer "B.Fab")
		)
		(pad "1" smd circle
			(at 0.40005 0)
			(size 0 0)
			(layers "B.Cu" "B.Mask" "B.Paste")
			(net "P3V3_AUX")
		)
		(pad "2" smd circle
			(at -0.40005 0)
			(size 0 0)
			(layers "B.Cu" "B.Mask" "B.Paste")
			(net "PRSNT_SWB_ISO_N")
		)
	)
	(footprint ""
		(layer "B.Cu")
		(at 237.905544 -321.471544)
		(property "Reference" "R1238"
			(at 0 0 0)
			(layer "B.SilkS")
			(hide yes)
			(effects
				(font
					(size 1.27 1.27)
				)
				(justify mirror)
			)
		)
		(property "Value" ""
			(at 0 0 0)
			(layer "B.Fab")
			(effects
				(font
					(size 1.27 1.27)
				)
				(justify mirror)
			)
		)
		(duplicate_pad_numbers_are_jumpers no)
		(fp_line
			(start -0.7874 -0.4064)
			(end -0.7874 0.4064)
			(stroke
				(width 0.1524)
				(type default)
			)
			(layer "B.SilkS")
		)
		(fp_line
			(start -0.7874 0.4064)
			(end 0.7874 0.4064)
			(stroke
				(width 0.1524)
				(type default)
			)
			(layer "B.SilkS")
		)
		(fp_line
			(start 0.7874 -0.4064)
			(end -0.7874 -0.4064)
			(stroke
				(width 0.1524)
				(type default)
			)
			(layer "B.SilkS")
		)
		(fp_line
			(start 0.7874 0.4064)
			(end 0.7874 -0.4064)
			(stroke
				(width 0.1524)
				(type default)
			)
			(layer "B.SilkS")
		)
		(fp_line
			(start -0.67945 -0.3048)
			(end -0.67945 0.3048)
			(stroke
				(width 0.1)
				(type default)
			)
			(layer "B.Fab")
		)
		(fp_line
			(start -0.67945 0.3048)
			(end -0.120396 0.3048)
			(stroke
				(width 0.1)
				(type default)
			)
			(layer "B.Fab")
		)
		(fp_line
			(start -0.12065 -0.3048)
			(end -0.67945 -0.3048)
			(stroke
				(width 0.1)
				(type default)
			)
			(layer "B.Fab")
		)
		(fp_line
			(start -0.12065 -0.2794)
			(end -0.12065 -0.3048)
			(stroke
				(width 0.1)
				(type default)
			)
			(layer "B.Fab")
		)
		(fp_line
			(start -0.120396 0.2794)
			(end 0.12065 0.2794)
			(stroke
				(width 0.1)
				(type default)
			)
			(layer "B.Fab")
		)
		(fp_line
			(start -0.120396 0.3048)
			(end -0.120396 0.2794)
			(stroke
				(width 0.1)
				(type default)
			)
			(layer "B.Fab")
		)
		(fp_line
			(start 0.12065 -0.305054)
			(end 0.12065 -0.2794)
			(stroke
				(width 0.1)
				(type default)
			)
			(layer "B.Fab")
		)
		(fp_line
			(start 0.12065 -0.2794)
			(end -0.12065 -0.2794)
			(stroke
				(width 0.1)
				(type default)
			)
			(layer "B.Fab")
		)
		(fp_line
			(start 0.12065 0.2794)
			(end 0.12065 0.3048)
			(stroke
				(width 0.1)
				(type default)
			)
			(layer "B.Fab")
		)
		(fp_line
			(start 0.12065 0.3048)
			(end 0.67945 0.3048)
			(stroke
				(width 0.1)
				(type default)
			)
			(layer "B.Fab")
		)
		(fp_line
			(start 0.67945 -0.305054)
			(end 0.12065 -0.305054)
			(stroke
				(width 0.1)
				(type default)
			)
			(layer "B.Fab")
		)
		(fp_line
			(start 0.67945 0.3048)
			(end 0.67945 -0.305054)
			(stroke
				(width 0.1)
				(type default)
			)
			(layer "B.Fab")
		)
		(pad "1" smd circle
			(at 0.40005 0 180)
			(size 0 0)
			(layers "B.Cu" "B.Mask" "B.Paste")
			(net "P5V_AUX")
		)
		(pad "2" smd circle
			(at -0.40005 0 180)
			(size 0 0)
			(layers "B.Cu" "B.Mask" "B.Paste")
			(net "P5V_AUX_ADC")
		)
	)
	(footprint ""
		(layer "B.Cu")
		(at 317.918338 -396.393162 -90)
		(property "Reference" "C583"
			(at 0 0 90)
			(layer "B.SilkS")
			(hide yes)
			(effects
				(font
					(size 1.27 1.27)
				)
				(justify mirror)
			)
		)
		(property "Value" ""
			(at 0 0 90)
			(layer "B.Fab")
			(effects
				(font
					(size 1.27 1.27)
				)
				(justify mirror)
			)
		)
		(duplicate_pad_numbers_are_jumpers no)
		(fp_line
			(start -0.299974 0.150114)
			(end 0.299974 0.150114)
			(stroke
				(width 0.1)
				(type default)
			)
			(layer "B.Fab")
		)
		(fp_line
			(start 0.299974 0.150114)
			(end 0.299974 -0.150114)
			(stroke
				(width 0.1)
				(type default)
			)
			(layer "B.Fab")
		)
		(fp_line
			(start -0.299974 -0.150114)
			(end -0.299974 0.150114)
			(stroke
				(width 0.1)
				(type default)
			)
			(layer "B.Fab")
		)
		(fp_line
			(start 0.299974 -0.150114)
			(end -0.299974 -0.150114)
			(stroke
				(width 0.1)
				(type default)
			)
			(layer "B.Fab")
		)
		(pad "1" smd rect
			(at 0.2667 0 90)
			(size 0.3048 0.381)
			(layers "B.Cu" "B.Mask" "B.Paste")
			(net "P0V9_CPU0_RT0_2A")
		)
		(pad "2" smd rect
			(at -0.2667 0 90)
			(size 0.3048 0.381)
			(layers "B.Cu" "B.Mask" "B.Paste")
			(net "GND")
		)
	)
	(footprint ""
		(layer "B.Cu")
		(at 356.29596 -257.744976 180)
		(property "Reference" "C2517"
			(at 0 0 0)
			(layer "B.SilkS")
			(hide yes)
			(effects
				(font
					(size 1.27 1.27)
				)
				(justify mirror)
			)
		)
		(property "Value" ""
			(at 0 0 0)
			(layer "B.Fab")
			(effects
				(font
					(size 1.27 1.27)
				)
				(justify mirror)
			)
		)
		(duplicate_pad_numbers_are_jumpers no)
		(fp_line
			(start 0.7874 0.4064)
			(end 0.7874 -0.4064)
			(stroke
				(width 0.1524)
				(type default)
			)
			(layer "B.SilkS")
		)
		(fp_line
			(start 0.7874 -0.4064)
			(end -0.7874 -0.4064)
			(stroke
				(width 0.1524)
				(type default)
			)
			(layer "B.SilkS")
		)
		(fp_line
			(start -0.7874 0.4064)
			(end 0.7874 0.4064)
			(stroke
				(width 0.1524)
				(type default)
			)
			(layer "B.SilkS")
		)
		(fp_line
			(start -0.7874 -0.4064)
			(end -0.7874 0.4064)
			(stroke
				(width 0.1524)
				(type default)
			)
			(layer "B.SilkS")
		)
		(fp_line
			(start 0.67945 0.3048)
			(end 0.67945 -0.305054)
			(stroke
				(width 0.1)
				(type default)
			)
			(layer "B.Fab")
		)
		(fp_line
			(start 0.67945 -0.305054)
			(end 0.12065 -0.305054)
			(stroke
				(width 0.1)
				(type default)
			)
			(layer "B.Fab")
		)
		(fp_line
			(start 0.12065 0.3048)
			(end 0.67945 0.3048)
			(stroke
				(width 0.1)
				(type default)
			)
			(layer "B.Fab")
		)
		(fp_line
			(start 0.12065 0.2794)
			(end 0.12065 0.3048)
			(stroke
				(width 0.1)
				(type default)
			)
			(layer "B.Fab")
		)
		(fp_line
			(start 0.12065 -0.2794)
			(end -0.12065 -0.2794)
			(stroke
				(width 0.1)
				(type default)
			)
			(layer "B.Fab")
		)
		(fp_line
			(start 0.12065 -0.305054)
			(end 0.12065 -0.2794)
			(stroke
				(width 0.1)
				(type default)
			)
			(layer "B.Fab")
		)
		(fp_line
			(start -0.120396 0.3048)
			(end -0.120396 0.2794)
			(stroke
				(width 0.1)
				(type default)
			)
			(layer "B.Fab")
		)
		(fp_line
			(start -0.120396 0.2794)
			(end 0.12065 0.2794)
			(stroke
				(width 0.1)
				(type default)
			)
			(layer "B.Fab")
		)
		(fp_line
			(start -0.12065 -0.2794)
			(end -0.12065 -0.3048)
			(stroke
				(width 0.1)
				(type default)
			)
			(layer "B.Fab")
		)
		(fp_line
			(start -0.12065 -0.3048)
			(end -0.67945 -0.3048)
			(stroke
				(width 0.1)
				(type default)
			)
			(layer "B.Fab")
		)
		(fp_line
			(start -0.67945 0.3048)
			(end -0.120396 0.3048)
			(stroke
				(width 0.1)
				(type default)
			)
			(layer "B.Fab")
		)
		(fp_line
			(start -0.67945 -0.3048)
			(end -0.67945 0.3048)
			(stroke
				(width 0.1)
				(type default)
			)
			(layer "B.Fab")
		)
		(pad "1" smd circle
			(at 0.40005 0)
			(size 0 0)
			(layers "B.Cu" "B.Mask" "B.Paste")
			(net "PVDD18_S5_P0")
		)
		(pad "2" smd circle
			(at -0.40005 0)
			(size 0 0)
			(layers "B.Cu" "B.Mask" "B.Paste")
			(net "GND")
		)
	)
	(footprint ""
		(layer "B.Cu")
		(at 126.478538 -386.766562 90)
		(property "Reference" "C493"
			(at 0 0 90)
			(layer "B.SilkS")
			(hide yes)
			(effects
				(font
					(size 1.27 1.27)
				)
				(justify mirror)
			)
		)
		(property "Value" ""
			(at 0 0 90)
			(layer "B.Fab")
			(effects
				(font
					(size 1.27 1.27)
				)
				(justify mirror)
			)
		)
		(duplicate_pad_numbers_are_jumpers no)
		(fp_line
			(start 0.299974 -0.150114)
			(end -0.299974 -0.150114)
			(stroke
				(width 0.1)
				(type default)
			)
			(layer "B.Fab")
		)
		(fp_line
			(start -0.299974 -0.150114)
			(end -0.299974 0.150114)
			(stroke
				(width 0.1)
				(type default)
			)
			(layer "B.Fab")
		)
		(fp_line
			(start 0.299974 0.150114)
			(end 0.299974 -0.150114)
			(stroke
				(width 0.1)
				(type default)
			)
			(layer "B.Fab")
		)
		(fp_line
			(start -0.299974 0.150114)
			(end 0.299974 0.150114)
			(stroke
				(width 0.1)
				(type default)
			)
			(layer "B.Fab")
		)
		(pad "1" smd rect
			(at 0.2667 0 270)
			(size 0.3048 0.381)
			(layers "B.Cu" "B.Mask" "B.Paste")
			(net "P0V9_CPU1_RT_2D")
		)
		(pad "2" smd rect
			(at -0.2667 0 270)
			(size 0.3048 0.381)
			(layers "B.Cu" "B.Mask" "B.Paste")
			(net "GND")
		)
	)
	(footprint ""
		(layer "B.Cu")
		(at 428.98695 -39.055548)
		(property "Reference" "R1265"
			(at 0 0 0)
			(layer "B.SilkS")
			(hide yes)
			(effects
				(font
					(size 1.27 1.27)
				)
				(justify mirror)
			)
		)
		(property "Value" ""
			(at 0 0 0)
			(layer "B.Fab")
			(effects
				(font
					(size 1.27 1.27)
				)
				(justify mirror)
			)
		)
		(duplicate_pad_numbers_are_jumpers no)
		(fp_line
			(start -0.7874 -0.4064)
			(end -0.7874 0.4064)
			(stroke
				(width 0.1524)
				(type default)
			)
			(layer "B.SilkS")
		)
		(fp_line
			(start -0.7874 0.4064)
			(end 0.7874 0.4064)
			(stroke
				(width 0.1524)
				(type default)
			)
			(layer "B.SilkS")
		)
		(fp_line
			(start 0.7874 -0.4064)
			(end -0.7874 -0.4064)
			(stroke
				(width 0.1524)
				(type default)
			)
			(layer "B.SilkS")
		)
		(fp_line
			(start 0.7874 0.4064)
			(end 0.7874 -0.4064)
			(stroke
				(width 0.1524)
				(type default)
			)
			(layer "B.SilkS")
		)
		(fp_line
			(start -0.67945 -0.3048)
			(end -0.67945 0.3048)
			(stroke
				(width 0.1)
				(type default)
			)
			(layer "B.Fab")
		)
		(fp_line
			(start -0.67945 0.3048)
			(end -0.120396 0.3048)
			(stroke
				(width 0.1)
				(type default)
			)
			(layer "B.Fab")
		)
		(fp_line
			(start -0.12065 -0.3048)
			(end -0.67945 -0.3048)
			(stroke
				(width 0.1)
				(type default)
			)
			(layer "B.Fab")
		)
		(fp_line
			(start -0.12065 -0.2794)
			(end -0.12065 -0.3048)
			(stroke
				(width 0.1)
				(type default)
			)
			(layer "B.Fab")
		)
		(fp_line
			(start -0.120396 0.2794)
			(end 0.12065 0.2794)
			(stroke
				(width 0.1)
				(type default)
			)
			(layer "B.Fab")
		)
		(fp_line
			(start -0.120396 0.3048)
			(end -0.120396 0.2794)
			(stroke
				(width 0.1)
				(type default)
			)
			(layer "B.Fab")
		)
		(fp_line
			(start 0.12065 -0.305054)
			(end 0.12065 -0.2794)
			(stroke
				(width 0.1)
				(type default)
			)
			(layer "B.Fab")
		)
		(fp_line
			(start 0.12065 -0.2794)
			(end -0.12065 -0.2794)
			(stroke
				(width 0.1)
				(type default)
			)
			(layer "B.Fab")
		)
		(fp_line
			(start 0.12065 0.2794)
			(end 0.12065 0.3048)
			(stroke
				(width 0.1)
				(type default)
			)
			(layer "B.Fab")
		)
		(fp_line
			(start 0.12065 0.3048)
			(end 0.67945 0.3048)
			(stroke
				(width 0.1)
				(type default)
			)
			(layer "B.Fab")
		)
		(fp_line
			(start 0.67945 -0.305054)
			(end 0.12065 -0.305054)
			(stroke
				(width 0.1)
				(type default)
			)
			(layer "B.Fab")
		)
		(fp_line
			(start 0.67945 0.3048)
			(end 0.67945 -0.305054)
			(stroke
				(width 0.1)
				(type default)
			)
			(layer "B.Fab")
		)
		(pad "1" smd circle
			(at 0.40005 0 180)
			(size 0 0)
			(layers "B.Cu" "B.Mask" "B.Paste")
			(net "FM_BIOS_USB_RECOVERY")
		)
		(pad "2" smd circle
			(at -0.40005 0 180)
			(size 0 0)
			(layers "B.Cu" "B.Mask" "B.Paste")
			(net "GND")
		)
	)
	(footprint ""
		(layer "B.Cu")
		(at 412.606236 -395.148562 90)
		(property "Reference" "C777"
			(at 0 0 90)
			(layer "B.SilkS")
			(hide yes)
			(effects
				(font
					(size 1.27 1.27)
				)
				(justify mirror)
			)
		)
		(property "Value" ""
			(at 0 0 90)
			(layer "B.Fab")
			(effects
				(font
					(size 1.27 1.27)
				)
				(justify mirror)
			)
		)
		(duplicate_pad_numbers_are_jumpers no)
		(fp_line
			(start 0.299974 -0.150114)
			(end -0.299974 -0.150114)
			(stroke
				(width 0.1)
				(type default)
			)
			(layer "B.Fab")
		)
		(fp_line
			(start -0.299974 -0.150114)
			(end -0.299974 0.150114)
			(stroke
				(width 0.1)
				(type default)
			)
			(layer "B.Fab")
		)
		(fp_line
			(start 0.299974 0.150114)
			(end 0.299974 -0.150114)
			(stroke
				(width 0.1)
				(type default)
			)
			(layer "B.Fab")
		)
		(fp_line
			(start -0.299974 0.150114)
			(end 0.299974 0.150114)
			(stroke
				(width 0.1)
				(type default)
			)
			(layer "B.Fab")
		)
		(pad "1" smd rect
			(at 0.2667 0 270)
			(size 0.3048 0.381)
			(layers "B.Cu" "B.Mask" "B.Paste")
			(net "P1V8_CPU0_RT2_1A")
		)
		(pad "2" smd rect
			(at -0.2667 0 270)
			(size 0.3048 0.381)
			(layers "B.Cu" "B.Mask" "B.Paste")
			(net "GND")
		)
	)
	(footprint ""
		(layer "B.Cu")
		(at 51.118516 -388.011162 -90)
		(property "Reference" "C260"
			(at 0 0 90)
			(layer "B.SilkS")
			(hide yes)
			(effects
				(font
					(size 1.27 1.27)
				)
				(justify mirror)
			)
		)
		(property "Value" ""
			(at 0 0 90)
			(layer "B.Fab")
			(effects
				(font
					(size 1.27 1.27)
				)
				(justify mirror)
			)
		)
		(duplicate_pad_numbers_are_jumpers no)
		(fp_line
			(start -0.299974 0.150114)
			(end 0.299974 0.150114)
			(stroke
				(width 0.1)
				(type default)
			)
			(layer "B.Fab")
		)
		(fp_line
			(start 0.299974 0.150114)
			(end 0.299974 -0.150114)
			(stroke
				(width 0.1)
				(type default)
			)
			(layer "B.Fab")
		)
		(fp_line
			(start -0.299974 -0.150114)
			(end -0.299974 0.150114)
			(stroke
				(width 0.1)
				(type default)
			)
			(layer "B.Fab")
		)
		(fp_line
			(start 0.299974 -0.150114)
			(end -0.299974 -0.150114)
			(stroke
				(width 0.1)
				(type default)
			)
			(layer "B.Fab")
		)
		(pad "1" smd rect
			(at 0.2667 0 90)
			(size 0.3048 0.381)
			(layers "B.Cu" "B.Mask" "B.Paste")
			(net "P0V9_CPU1_RT0_2A")
		)
		(pad "2" smd rect
			(at -0.2667 0 90)
			(size 0.3048 0.381)
			(layers "B.Cu" "B.Mask" "B.Paste")
			(net "GND")
		)
	)
	(footprint ""
		(layer "B.Cu")
		(at 63.118492 -388.011162 -90)
		(property "Reference" "C228"
			(at 0 0 90)
			(layer "B.SilkS")
			(hide yes)
			(effects
				(font
					(size 1.27 1.27)
				)
				(justify mirror)
			)
		)
		(property "Value" ""
			(at 0 0 90)
			(layer "B.Fab")
			(effects
				(font
					(size 1.27 1.27)
				)
				(justify mirror)
			)
		)
		(duplicate_pad_numbers_are_jumpers no)
		(fp_line
			(start -0.299974 0.150114)
			(end 0.299974 0.150114)
			(stroke
				(width 0.1)
				(type default)
			)
			(layer "B.Fab")
		)
		(fp_line
			(start 0.299974 0.150114)
			(end 0.299974 -0.150114)
			(stroke
				(width 0.1)
				(type default)
			)
			(layer "B.Fab")
		)
		(fp_line
			(start -0.299974 -0.150114)
			(end -0.299974 0.150114)
			(stroke
				(width 0.1)
				(type default)
			)
			(layer "B.Fab")
		)
		(fp_line
			(start 0.299974 -0.150114)
			(end -0.299974 -0.150114)
			(stroke
				(width 0.1)
				(type default)
			)
			(layer "B.Fab")
		)
		(pad "1" smd rect
			(at 0.2667 0 90)
			(size 0.3048 0.381)
			(layers "B.Cu" "B.Mask" "B.Paste")
			(net "P0V9_CPU1_RT0_2A")
		)
		(pad "2" smd rect
			(at -0.2667 0 90)
			(size 0.3048 0.381)
			(layers "B.Cu" "B.Mask" "B.Paste")
			(net "GND")
		)
	)
	(footprint ""
		(layer "B.Cu")
		(at 137.492994 -43.37431)
		(property "Reference" "L6001"
			(at 0 0 0)
			(layer "B.SilkS")
			(hide yes)
			(effects
				(font
					(size 1.27 1.27)
				)
				(justify mirror)
			)
		)
		(property "Value" ""
			(at 0 0 0)
			(layer "B.Fab")
			(effects
				(font
					(size 1.27 1.27)
				)
				(justify mirror)
			)
		)
		(duplicate_pad_numbers_are_jumpers no)
		(fp_line
			(start -1.63576 -0.8128)
			(end -1.63576 0.8128)
			(stroke
				(width 0.1524)
				(type default)
			)
			(layer "B.SilkS")
		)
		(fp_line
			(start -1.63576 0.8128)
			(end 1.63576 0.8128)
			(stroke
				(width 0.1524)
				(type default)
			)
			(layer "B.SilkS")
		)
		(fp_line
			(start 1.63576 -0.8128)
			(end -1.63576 -0.8128)
			(stroke
				(width 0.1524)
				(type default)
			)
			(layer "B.SilkS")
		)
		(fp_line
			(start 1.63576 -0.8128)
			(end 1.63576 0.8128)
			(stroke
				(width 0.1524)
				(type default)
			)
			(layer "B.SilkS")
		)
		(fp_line
			(start -1.560576 -0.738632)
			(end 1.56083 -0.738632)
			(stroke
				(width 0.1)
				(type default)
			)
			(layer "B.Fab")
		)
		(fp_line
			(start -1.560576 0.7366)
			(end -1.560576 -0.738632)
			(stroke
				(width 0.1)
				(type default)
			)
			(layer "B.Fab")
		)
		(fp_line
			(start -1.524 0.7366)
			(end -1.560576 0.7366)
			(stroke
				(width 0.1)
				(type default)
			)
			(layer "B.Fab")
		)
		(fp_line
			(start 1.524 0.7366)
			(end -1.524 0.7366)
			(stroke
				(width 0.1)
				(type default)
			)
			(layer "B.Fab")
		)
		(fp_line
			(start 1.56083 -0.738632)
			(end 1.56083 0.7366)
			(stroke
				(width 0.1)
				(type default)
			)
			(layer "B.Fab")
		)
		(fp_line
			(start 1.56083 0.7366)
			(end 1.524 0.7366)
			(stroke
				(width 0.1)
				(type default)
			)
			(layer "B.Fab")
		)
		(pad "1" smd rect
			(at 0.94996 0)
			(size 1.1176 1.3716)
			(layers "B.Cu" "B.Mask" "B.Paste")
			(net "P1V2_AUX")
		)
		(pad "2" smd rect
			(at -0.94996 0)
			(size 1.1176 1.3716)
			(layers "B.Cu" "B.Mask" "B.Paste")
			(net "P1V2_CPU0_USB_DVDD12")
		)
	)
	(footprint ""
		(layer "B.Cu")
		(at 385.129278 -144.266158)
		(property "Reference" "PR307"
			(at 0 0 0)
			(layer "B.SilkS")
			(hide yes)
			(effects
				(font
					(size 1.27 1.27)
				)
				(justify mirror)
			)
		)
		(property "Value" ""
			(at 0 0 0)
			(layer "B.Fab")
			(effects
				(font
					(size 1.27 1.27)
				)
				(justify mirror)
			)
		)
		(duplicate_pad_numbers_are_jumpers no)
		(fp_line
			(start -0.7874 -0.4064)
			(end -0.7874 0.4064)
			(stroke
				(width 0.1524)
				(type default)
			)
			(layer "B.SilkS")
		)
		(fp_line
			(start -0.7874 0.4064)
			(end 0.7874 0.4064)
			(stroke
				(width 0.1524)
				(type default)
			)
			(layer "B.SilkS")
		)
		(fp_line
			(start 0.7874 -0.4064)
			(end -0.7874 -0.4064)
			(stroke
				(width 0.1524)
				(type default)
			)
			(layer "B.SilkS")
		)
		(fp_line
			(start 0.7874 0.4064)
			(end 0.7874 -0.4064)
			(stroke
				(width 0.1524)
				(type default)
			)
			(layer "B.SilkS")
		)
		(fp_line
			(start -0.67945 -0.3048)
			(end -0.67945 0.3048)
			(stroke
				(width 0.1)
				(type default)
			)
			(layer "B.Fab")
		)
		(fp_line
			(start -0.67945 0.3048)
			(end -0.120396 0.3048)
			(stroke
				(width 0.1)
				(type default)
			)
			(layer "B.Fab")
		)
		(fp_line
			(start -0.12065 -0.3048)
			(end -0.67945 -0.3048)
			(stroke
				(width 0.1)
				(type default)
			)
			(layer "B.Fab")
		)
		(fp_line
			(start -0.12065 -0.2794)
			(end -0.12065 -0.3048)
			(stroke
				(width 0.1)
				(type default)
			)
			(layer "B.Fab")
		)
		(fp_line
			(start -0.120396 0.2794)
			(end 0.12065 0.2794)
			(stroke
				(width 0.1)
				(type default)
			)
			(layer "B.Fab")
		)
		(fp_line
			(start -0.120396 0.3048)
			(end -0.120396 0.2794)
			(stroke
				(width 0.1)
				(type default)
			)
			(layer "B.Fab")
		)
		(fp_line
			(start 0.12065 -0.305054)
			(end 0.12065 -0.2794)
			(stroke
				(width 0.1)
				(type default)
			)
			(layer "B.Fab")
		)
		(fp_line
			(start 0.12065 -0.2794)
			(end -0.12065 -0.2794)
			(stroke
				(width 0.1)
				(type default)
			)
			(layer "B.Fab")
		)
		(fp_line
			(start 0.12065 0.2794)
			(end 0.12065 0.3048)
			(stroke
				(width 0.1)
				(type default)
			)
			(layer "B.Fab")
		)
		(fp_line
			(start 0.12065 0.3048)
			(end 0.67945 0.3048)
			(stroke
				(width 0.1)
				(type default)
			)
			(layer "B.Fab")
		)
		(fp_line
			(start 0.67945 -0.305054)
			(end 0.12065 -0.305054)
			(stroke
				(width 0.1)
				(type default)
			)
			(layer "B.Fab")
		)
		(fp_line
			(start 0.67945 0.3048)
			(end 0.67945 -0.305054)
			(stroke
				(width 0.1)
				(type default)
			)
			(layer "B.Fab")
		)
		(pad "1" smd circle
			(at 0.40005 0 180)
			(size 0 0)
			(layers "B.Cu" "B.Mask" "B.Paste")
			(net "VSENSE_PVDDCR_SOC_P0_DP")
		)
		(pad "2" smd circle
			(at -0.40005 0 180)
			(size 0 0)
			(layers "B.Cu" "B.Mask" "B.Paste")
			(net "VSENSE_PVDDCR_SOC_P0_VSEN1")
		)
	)
	(footprint ""
		(layer "B.Cu")
		(at 368.334798 -424.372786 180)
		(property "Reference" "R687"
			(at 0 0 0)
			(layer "B.SilkS")
			(hide yes)
			(effects
				(font
					(size 1.27 1.27)
				)
				(justify mirror)
			)
		)
		(property "Value" ""
			(at 0 0 0)
			(layer "B.Fab")
			(effects
				(font
					(size 1.27 1.27)
				)
				(justify mirror)
			)
		)
		(duplicate_pad_numbers_are_jumpers no)
		(fp_line
			(start 0.32512 0.175006)
			(end 0.32512 -0.175006)
			(stroke
				(width 0.1)
				(type default)
			)
			(layer "B.Fab")
		)
		(fp_line
			(start 0.32512 -0.175006)
			(end -0.32512 -0.175006)
			(stroke
				(width 0.1)
				(type default)
			)
			(layer "B.Fab")
		)
		(fp_line
			(start -0.32512 0.175006)
			(end 0.32512 0.175006)
			(stroke
				(width 0.1)
				(type default)
			)
			(layer "B.Fab")
		)
		(fp_line
			(start -0.32512 -0.175006)
			(end -0.32512 0.175006)
			(stroke
				(width 0.1)
				(type default)
			)
			(layer "B.Fab")
		)
		(pad "1" smd rect
			(at 0.2667 0)
			(size 0.3048 0.381)
			(layers "B.Cu" "B.Mask" "B.Paste")
			(net "SMB_RT_CPU0_P3_ROM_R_SCL")
		)
		(pad "2" smd rect
			(at -0.2667 0 180)
			(size 0.3048 0.381)
			(layers "B.Cu" "B.Mask" "B.Paste")
			(net "SMB_RT_CPU0_P3_ROM_SCL")
		)
	)
	(footprint ""
		(layer "B.Cu")
		(at 363.931454 -250.89231)
		(property "Reference" "C4179"
			(at 0 0 0)
			(layer "B.SilkS")
			(hide yes)
			(effects
				(font
					(size 1.27 1.27)
				)
				(justify mirror)
			)
		)
		(property "Value" ""
			(at 0 0 0)
			(layer "B.Fab")
			(effects
				(font
					(size 1.27 1.27)
				)
				(justify mirror)
			)
		)
		(duplicate_pad_numbers_are_jumpers no)
		(fp_line
			(start -0.7874 -0.4064)
			(end -0.7874 0.4064)
			(stroke
				(width 0.1524)
				(type default)
			)
			(layer "B.SilkS")
		)
		(fp_line
			(start -0.7874 0.4064)
			(end 0.7874 0.4064)
			(stroke
				(width 0.1524)
				(type default)
			)
			(layer "B.SilkS")
		)
		(fp_line
			(start 0.7874 -0.4064)
			(end -0.7874 -0.4064)
			(stroke
				(width 0.1524)
				(type default)
			)
			(layer "B.SilkS")
		)
		(fp_line
			(start 0.7874 0.4064)
			(end 0.7874 -0.4064)
			(stroke
				(width 0.1524)
				(type default)
			)
			(layer "B.SilkS")
		)
		(fp_line
			(start -0.67945 -0.3048)
			(end -0.67945 0.3048)
			(stroke
				(width 0.1)
				(type default)
			)
			(layer "B.Fab")
		)
		(fp_line
			(start -0.67945 0.3048)
			(end -0.120396 0.3048)
			(stroke
				(width 0.1)
				(type default)
			)
			(layer "B.Fab")
		)
		(fp_line
			(start -0.12065 -0.3048)
			(end -0.67945 -0.3048)
			(stroke
				(width 0.1)
				(type default)
			)
			(layer "B.Fab")
		)
		(fp_line
			(start -0.12065 -0.2794)
			(end -0.12065 -0.3048)
			(stroke
				(width 0.1)
				(type default)
			)
			(layer "B.Fab")
		)
		(fp_line
			(start -0.120396 0.2794)
			(end 0.12065 0.2794)
			(stroke
				(width 0.1)
				(type default)
			)
			(layer "B.Fab")
		)
		(fp_line
			(start -0.120396 0.3048)
			(end -0.120396 0.2794)
			(stroke
				(width 0.1)
				(type default)
			)
			(layer "B.Fab")
		)
		(fp_line
			(start 0.12065 -0.305054)
			(end 0.12065 -0.2794)
			(stroke
				(width 0.1)
				(type default)
			)
			(layer "B.Fab")
		)
		(fp_line
			(start 0.12065 -0.2794)
			(end -0.12065 -0.2794)
			(stroke
				(width 0.1)
				(type default)
			)
			(layer "B.Fab")
		)
		(fp_line
			(start 0.12065 0.2794)
			(end 0.12065 0.3048)
			(stroke
				(width 0.1)
				(type default)
			)
			(layer "B.Fab")
		)
		(fp_line
			(start 0.12065 0.3048)
			(end 0.67945 0.3048)
			(stroke
				(width 0.1)
				(type default)
			)
			(layer "B.Fab")
		)
		(fp_line
			(start 0.67945 -0.305054)
			(end 0.12065 -0.305054)
			(stroke
				(width 0.1)
				(type default)
			)
			(layer "B.Fab")
		)
		(fp_line
			(start 0.67945 0.3048)
			(end 0.67945 -0.305054)
			(stroke
				(width 0.1)
				(type default)
			)
			(layer "B.Fab")
		)
		(pad "1" smd circle
			(at 0.40005 0 180)
			(size 0 0)
			(layers "B.Cu" "B.Mask" "B.Paste")
			(net "PVDDCR_CPU0_P0")
		)
		(pad "2" smd circle
			(at -0.40005 0 180)
			(size 0 0)
			(layers "B.Cu" "B.Mask" "B.Paste")
			(net "GND")
		)
	)
	(footprint ""
		(layer "B.Cu")
		(at 398.880076 -169.49547 -90)
		(property "Reference" "PC8009"
			(at 0 0 90)
			(layer "B.SilkS")
			(hide yes)
			(effects
				(font
					(size 1.27 1.27)
				)
				(justify mirror)
			)
		)
		(property "Value" ""
			(at 0 0 90)
			(layer "B.Fab")
			(effects
				(font
					(size 1.27 1.27)
				)
				(justify mirror)
			)
		)
		(duplicate_pad_numbers_are_jumpers no)
		(fp_line
			(start -1.524 0.762)
			(end 1.524 0.762)
			(stroke
				(width 0.1524)
				(type default)
			)
			(layer "B.SilkS")
		)
		(fp_line
			(start 1.524 0.762)
			(end 1.524 -0.762)
			(stroke
				(width 0.1524)
				(type default)
			)
			(layer "B.SilkS")
		)
		(fp_line
			(start -1.524 -0.762)
			(end -1.524 0.762)
			(stroke
				(width 0.1524)
				(type default)
			)
			(layer "B.SilkS")
		)
		(fp_line
			(start 1.524 -0.762)
			(end -1.524 -0.762)
			(stroke
				(width 0.1524)
				(type default)
			)
			(layer "B.SilkS")
		)
		(fp_line
			(start -1.1049 0.724916)
			(end -1.1049 -0.724916)
			(stroke
				(width 0.1)
				(type default)
			)
			(layer "B.Fab")
		)
		(fp_line
			(start 1.1049 0.724916)
			(end -1.1049 0.724916)
			(stroke
				(width 0.1)
				(type default)
			)
			(layer "B.Fab")
		)
		(fp_line
			(start -1.1049 -0.724916)
			(end 1.1049 -0.724916)
			(stroke
				(width 0.1)
				(type default)
			)
			(layer "B.Fab")
		)
		(fp_line
			(start 1.1049 -0.724916)
			(end 1.1049 0.724916)
			(stroke
				(width 0.1)
				(type default)
			)
			(layer "B.Fab")
		)
		(pad "1" smd rect
			(at 0.889 0 270)
			(size 1.016 1.27)
			(layers "B.Cu" "B.Mask" "B.Paste")
			(net "SW_P12V_AUX_PVDDCR_SOC_P0_FLT")
		)
		(pad "2" smd rect
			(at -0.889 0 270)
			(size 1.016 1.27)
			(layers "B.Cu" "B.Mask" "B.Paste")
			(net "GND")
		)
	)
	(footprint ""
		(layer "B.Cu")
		(at 306.991004 -398.942052 90)
		(property "Reference" "C579"
			(at 0 0 90)
			(layer "B.SilkS")
			(hide yes)
			(effects
				(font
					(size 1.27 1.27)
				)
				(justify mirror)
			)
		)
		(property "Value" ""
			(at 0 0 90)
			(layer "B.Fab")
			(effects
				(font
					(size 1.27 1.27)
				)
				(justify mirror)
			)
		)
		(duplicate_pad_numbers_are_jumpers no)
		(fp_line
			(start 0.7874 -0.4064)
			(end -0.7874 -0.4064)
			(stroke
				(width 0.1524)
				(type default)
			)
			(layer "B.SilkS")
		)
		(fp_line
			(start -0.7874 -0.4064)
			(end -0.7874 0.4064)
			(stroke
				(width 0.1524)
				(type default)
			)
			(layer "B.SilkS")
		)
		(fp_line
			(start 0.7874 0.4064)
			(end 0.7874 -0.4064)
			(stroke
				(width 0.1524)
				(type default)
			)
			(layer "B.SilkS")
		)
		(fp_line
			(start -0.7874 0.4064)
			(end 0.7874 0.4064)
			(stroke
				(width 0.1524)
				(type default)
			)
			(layer "B.SilkS")
		)
		(fp_line
			(start 0.67945 -0.305054)
			(end 0.12065 -0.305054)
			(stroke
				(width 0.1)
				(type default)
			)
			(layer "B.Fab")
		)
		(fp_line
			(start 0.12065 -0.305054)
			(end 0.12065 -0.2794)
			(stroke
				(width 0.1)
				(type default)
			)
			(layer "B.Fab")
		)
		(fp_line
			(start -0.12065 -0.3048)
			(end -0.67945 -0.3048)
			(stroke
				(width 0.1)
				(type default)
			)
			(layer "B.Fab")
		)
		(fp_line
			(start -0.67945 -0.3048)
			(end -0.67945 0.3048)
			(stroke
				(width 0.1)
				(type default)
			)
			(layer "B.Fab")
		)
		(fp_line
			(start 0.12065 -0.2794)
			(end -0.12065 -0.2794)
			(stroke
				(width 0.1)
				(type default)
			)
			(layer "B.Fab")
		)
		(fp_line
			(start -0.12065 -0.2794)
			(end -0.12065 -0.3048)
			(stroke
				(width 0.1)
				(type default)
			)
			(layer "B.Fab")
		)
		(fp_line
			(start 0.12065 0.2794)
			(end 0.12065 0.3048)
			(stroke
				(width 0.1)
				(type default)
			)
			(layer "B.Fab")
		)
		(fp_line
			(start -0.120396 0.2794)
			(end 0.12065 0.2794)
			(stroke
				(width 0.1)
				(type default)
			)
			(layer "B.Fab")
		)
		(fp_line
			(start 0.67945 0.3048)
			(end 0.67945 -0.305054)
			(stroke
				(width 0.1)
				(type default)
			)
			(layer "B.Fab")
		)
		(fp_line
			(start 0.12065 0.3048)
			(end 0.67945 0.3048)
			(stroke
				(width 0.1)
				(type default)
			)
			(layer "B.Fab")
		)
		(fp_line
			(start -0.120396 0.3048)
			(end -0.120396 0.2794)
			(stroke
				(width 0.1)
				(type default)
			)
			(layer "B.Fab")
		)
		(fp_line
			(start -0.67945 0.3048)
			(end -0.120396 0.3048)
			(stroke
				(width 0.1)
				(type default)
			)
			(layer "B.Fab")
		)
		(pad "1" smd circle
			(at 0.40005 0 270)
			(size 0 0)
			(layers "B.Cu" "B.Mask" "B.Paste")
			(net "P0V9_CPU0_RT0_2A")
		)
		(pad "2" smd circle
			(at -0.40005 0 270)
			(size 0 0)
			(layers "B.Cu" "B.Mask" "B.Paste")
			(net "GND")
		)
	)
	(footprint ""
		(layer "B.Cu")
		(at 404.346156 -396.393162 -90)
		(property "Reference" "C800"
			(at 0 0 90)
			(layer "B.SilkS")
			(hide yes)
			(effects
				(font
					(size 1.27 1.27)
				)
				(justify mirror)
			)
		)
		(property "Value" ""
			(at 0 0 90)
			(layer "B.Fab")
			(effects
				(font
					(size 1.27 1.27)
				)
				(justify mirror)
			)
		)
		(duplicate_pad_numbers_are_jumpers no)
		(fp_line
			(start -0.299974 0.150114)
			(end 0.299974 0.150114)
			(stroke
				(width 0.1)
				(type default)
			)
			(layer "B.Fab")
		)
		(fp_line
			(start 0.299974 0.150114)
			(end 0.299974 -0.150114)
			(stroke
				(width 0.1)
				(type default)
			)
			(layer "B.Fab")
		)
		(fp_line
			(start -0.299974 -0.150114)
			(end -0.299974 0.150114)
			(stroke
				(width 0.1)
				(type default)
			)
			(layer "B.Fab")
		)
		(fp_line
			(start 0.299974 -0.150114)
			(end -0.299974 -0.150114)
			(stroke
				(width 0.1)
				(type default)
			)
			(layer "B.Fab")
		)
		(pad "1" smd rect
			(at 0.2667 0 90)
			(size 0.3048 0.381)
			(layers "B.Cu" "B.Mask" "B.Paste")
			(net "P0V9_CPU0_RT2_2A")
		)
		(pad "2" smd rect
			(at -0.2667 0 90)
			(size 0.3048 0.381)
			(layers "B.Cu" "B.Mask" "B.Paste")
			(net "GND")
		)
	)
	(footprint ""
		(layer "B.Cu")
		(at 347.906086 -395.148562 90)
		(property "Reference" "C619"
			(at 0 0 90)
			(layer "B.SilkS")
			(hide yes)
			(effects
				(font
					(size 1.27 1.27)
				)
				(justify mirror)
			)
		)
		(property "Value" ""
			(at 0 0 90)
			(layer "B.Fab")
			(effects
				(font
					(size 1.27 1.27)
				)
				(justify mirror)
			)
		)
		(duplicate_pad_numbers_are_jumpers no)
		(fp_line
			(start 0.299974 -0.150114)
			(end -0.299974 -0.150114)
			(stroke
				(width 0.1)
				(type default)
			)
			(layer "B.Fab")
		)
		(fp_line
			(start -0.299974 -0.150114)
			(end -0.299974 0.150114)
			(stroke
				(width 0.1)
				(type default)
			)
			(layer "B.Fab")
		)
		(fp_line
			(start 0.299974 0.150114)
			(end 0.299974 -0.150114)
			(stroke
				(width 0.1)
				(type default)
			)
			(layer "B.Fab")
		)
		(fp_line
			(start -0.299974 0.150114)
			(end 0.299974 0.150114)
			(stroke
				(width 0.1)
				(type default)
			)
			(layer "B.Fab")
		)
		(pad "1" smd rect
			(at 0.2667 0 270)
			(size 0.3048 0.381)
			(layers "B.Cu" "B.Mask" "B.Paste")
			(net "P0V9_CPU0_RT_2D")
		)
		(pad "2" smd rect
			(at -0.2667 0 270)
			(size 0.3048 0.381)
			(layers "B.Cu" "B.Mask" "B.Paste")
			(net "GND")
		)
	)
	(footprint ""
		(layer "B.Cu")
		(at 367.671858 -134.954772 180)
		(property "Reference" "R8282"
			(at 0 0 0)
			(layer "B.SilkS")
			(hide yes)
			(effects
				(font
					(size 1.27 1.27)
				)
				(justify mirror)
			)
		)
		(property "Value" ""
			(at 0 0 0)
			(layer "B.Fab")
			(effects
				(font
					(size 1.27 1.27)
				)
				(justify mirror)
			)
		)
		(duplicate_pad_numbers_are_jumpers no)
		(fp_line
			(start 0.7874 0.4064)
			(end 0.7874 -0.4064)
			(stroke
				(width 0.1524)
				(type default)
			)
			(layer "B.SilkS")
		)
		(fp_line
			(start 0.7874 -0.4064)
			(end -0.7874 -0.4064)
			(stroke
				(width 0.1524)
				(type default)
			)
			(layer "B.SilkS")
		)
		(fp_line
			(start -0.7874 0.4064)
			(end 0.7874 0.4064)
			(stroke
				(width 0.1524)
				(type default)
			)
			(layer "B.SilkS")
		)
		(fp_line
			(start -0.7874 -0.4064)
			(end -0.7874 0.4064)
			(stroke
				(width 0.1524)
				(type default)
			)
			(layer "B.SilkS")
		)
		(fp_line
			(start 0.67945 0.3048)
			(end 0.67945 -0.305054)
			(stroke
				(width 0.1)
				(type default)
			)
			(layer "B.Fab")
		)
		(fp_line
			(start 0.67945 -0.305054)
			(end 0.12065 -0.305054)
			(stroke
				(width 0.1)
				(type default)
			)
			(layer "B.Fab")
		)
		(fp_line
			(start 0.12065 0.3048)
			(end 0.67945 0.3048)
			(stroke
				(width 0.1)
				(type default)
			)
			(layer "B.Fab")
		)
		(fp_line
			(start 0.12065 0.2794)
			(end 0.12065 0.3048)
			(stroke
				(width 0.1)
				(type default)
			)
			(layer "B.Fab")
		)
		(fp_line
			(start 0.12065 -0.2794)
			(end -0.12065 -0.2794)
			(stroke
				(width 0.1)
				(type default)
			)
			(layer "B.Fab")
		)
		(fp_line
			(start 0.12065 -0.305054)
			(end 0.12065 -0.2794)
			(stroke
				(width 0.1)
				(type default)
			)
			(layer "B.Fab")
		)
		(fp_line
			(start -0.120396 0.3048)
			(end -0.120396 0.2794)
			(stroke
				(width 0.1)
				(type default)
			)
			(layer "B.Fab")
		)
		(fp_line
			(start -0.120396 0.2794)
			(end 0.12065 0.2794)
			(stroke
				(width 0.1)
				(type default)
			)
			(layer "B.Fab")
		)
		(fp_line
			(start -0.12065 -0.2794)
			(end -0.12065 -0.3048)
			(stroke
				(width 0.1)
				(type default)
			)
			(layer "B.Fab")
		)
		(fp_line
			(start -0.12065 -0.3048)
			(end -0.67945 -0.3048)
			(stroke
				(width 0.1)
				(type default)
			)
			(layer "B.Fab")
		)
		(fp_line
			(start -0.67945 0.3048)
			(end -0.120396 0.3048)
			(stroke
				(width 0.1)
				(type default)
			)
			(layer "B.Fab")
		)
		(fp_line
			(start -0.67945 -0.3048)
			(end -0.67945 0.3048)
			(stroke
				(width 0.1)
				(type default)
			)
			(layer "B.Fab")
		)
		(pad "1" smd circle
			(at 0.40005 0)
			(size 0 0)
			(layers "B.Cu" "B.Mask" "B.Paste")
			(net "PVDDCR_SOC_P0_EN")
		)
		(pad "2" smd circle
			(at -0.40005 0)
			(size 0 0)
			(layers "B.Cu" "B.Mask" "B.Paste")
			(net "PVDDCR_SOC_P0_EN_RC")
		)
	)
	(footprint ""
		(layer "B.Cu")
		(at 273.847814 -194.88531 180)
		(property "Reference" "R5"
			(at 0 0 0)
			(layer "B.SilkS")
			(hide yes)
			(effects
				(font
					(size 1.27 1.27)
				)
				(justify mirror)
			)
		)
		(property "Value" ""
			(at 0 0 0)
			(layer "B.Fab")
			(effects
				(font
					(size 1.27 1.27)
				)
				(justify mirror)
			)
		)
		(duplicate_pad_numbers_are_jumpers no)
		(fp_line
			(start 0.7874 0.4064)
			(end 0.7874 -0.4064)
			(stroke
				(width 0.1524)
				(type default)
			)
			(layer "B.SilkS")
		)
		(fp_line
			(start 0.7874 -0.4064)
			(end -0.7874 -0.4064)
			(stroke
				(width 0.1524)
				(type default)
			)
			(layer "B.SilkS")
		)
		(fp_line
			(start -0.7874 0.4064)
			(end 0.7874 0.4064)
			(stroke
				(width 0.1524)
				(type default)
			)
			(layer "B.SilkS")
		)
		(fp_line
			(start -0.7874 -0.4064)
			(end -0.7874 0.4064)
			(stroke
				(width 0.1524)
				(type default)
			)
			(layer "B.SilkS")
		)
		(fp_line
			(start 0.67945 0.3048)
			(end 0.67945 -0.305054)
			(stroke
				(width 0.1)
				(type default)
			)
			(layer "B.Fab")
		)
		(fp_line
			(start 0.67945 -0.305054)
			(end 0.12065 -0.305054)
			(stroke
				(width 0.1)
				(type default)
			)
			(layer "B.Fab")
		)
		(fp_line
			(start 0.12065 0.3048)
			(end 0.67945 0.3048)
			(stroke
				(width 0.1)
				(type default)
			)
			(layer "B.Fab")
		)
		(fp_line
			(start 0.12065 0.2794)
			(end 0.12065 0.3048)
			(stroke
				(width 0.1)
				(type default)
			)
			(layer "B.Fab")
		)
		(fp_line
			(start 0.12065 -0.2794)
			(end -0.12065 -0.2794)
			(stroke
				(width 0.1)
				(type default)
			)
			(layer "B.Fab")
		)
		(fp_line
			(start 0.12065 -0.305054)
			(end 0.12065 -0.2794)
			(stroke
				(width 0.1)
				(type default)
			)
			(layer "B.Fab")
		)
		(fp_line
			(start -0.120396 0.3048)
			(end -0.120396 0.2794)
			(stroke
				(width 0.1)
				(type default)
			)
			(layer "B.Fab")
		)
		(fp_line
			(start -0.120396 0.2794)
			(end 0.12065 0.2794)
			(stroke
				(width 0.1)
				(type default)
			)
			(layer "B.Fab")
		)
		(fp_line
			(start -0.12065 -0.2794)
			(end -0.12065 -0.3048)
			(stroke
				(width 0.1)
				(type default)
			)
			(layer "B.Fab")
		)
		(fp_line
			(start -0.12065 -0.3048)
			(end -0.67945 -0.3048)
			(stroke
				(width 0.1)
				(type default)
			)
			(layer "B.Fab")
		)
		(fp_line
			(start -0.67945 0.3048)
			(end -0.120396 0.3048)
			(stroke
				(width 0.1)
				(type default)
			)
			(layer "B.Fab")
		)
		(fp_line
			(start -0.67945 -0.3048)
			(end -0.67945 0.3048)
			(stroke
				(width 0.1)
				(type default)
			)
			(layer "B.Fab")
		)
		(pad "1" smd circle
			(at 0.40005 0)
			(size 0 0)
			(layers "B.Cu" "B.Mask" "B.Paste")
			(net "PD_CHE_CPU0_DIMM_SAA")
		)
		(pad "2" smd circle
			(at -0.40005 0)
			(size 0 0)
			(layers "B.Cu" "B.Mask" "B.Paste")
			(net "GND")
		)
	)
	(footprint ""
		(layer "B.Cu")
		(at 343.105994 -395.148562 90)
		(property "Reference" "C600"
			(at 0 0 90)
			(layer "B.SilkS")
			(hide yes)
			(effects
				(font
					(size 1.27 1.27)
				)
				(justify mirror)
			)
		)
		(property "Value" ""
			(at 0 0 90)
			(layer "B.Fab")
			(effects
				(font
					(size 1.27 1.27)
				)
				(justify mirror)
			)
		)
		(duplicate_pad_numbers_are_jumpers no)
		(fp_line
			(start 0.299974 -0.150114)
			(end -0.299974 -0.150114)
			(stroke
				(width 0.1)
				(type default)
			)
			(layer "B.Fab")
		)
		(fp_line
			(start -0.299974 -0.150114)
			(end -0.299974 0.150114)
			(stroke
				(width 0.1)
				(type default)
			)
			(layer "B.Fab")
		)
		(fp_line
			(start 0.299974 0.150114)
			(end 0.299974 -0.150114)
			(stroke
				(width 0.1)
				(type default)
			)
			(layer "B.Fab")
		)
		(fp_line
			(start -0.299974 0.150114)
			(end 0.299974 0.150114)
			(stroke
				(width 0.1)
				(type default)
			)
			(layer "B.Fab")
		)
		(pad "1" smd rect
			(at 0.2667 0 270)
			(size 0.3048 0.381)
			(layers "B.Cu" "B.Mask" "B.Paste")
			(net "P1V8_CPU0_RT1_1A")
		)
		(pad "2" smd rect
			(at -0.2667 0 270)
			(size 0.3048 0.381)
			(layers "B.Cu" "B.Mask" "B.Paste")
			(net "GND")
		)
	)
	(footprint ""
		(layer "B.Cu")
		(at 406.666954 -175.3489 90)
		(property "Reference" "PC598"
			(at 6.709664 -0.521462 270)
			(unlocked yes)
			(layer "B.SilkS")
			(effects
				(font
					(size 0.7874 0.5842)
					(thickness 0.1524)
				)
				(justify left mirror)
			)
		)
		(property "Value" ""
			(at 0 0 90)
			(layer "B.Fab")
			(effects
				(font
					(size 1.27 1.27)
				)
				(justify mirror)
			)
		)
		(duplicate_pad_numbers_are_jumpers no)
		(fp_line
			(start 4.533392 -2.249932)
			(end -4.533392 -2.249932)
			(stroke
				(width 0.1524)
				(type default)
			)
			(layer "B.SilkS")
		)
		(fp_line
			(start -4.533392 -2.249932)
			(end -4.533392 2.249932)
			(stroke
				(width 0.1524)
				(type default)
			)
			(layer "B.SilkS")
		)
		(fp_line
			(start 4.533392 2.249932)
			(end 4.533392 -2.249932)
			(stroke
				(width 0.1524)
				(type default)
			)
			(layer "B.SilkS")
		)
		(fp_line
			(start -4.533392 2.249932)
			(end 4.533392 2.249932)
			(stroke
				(width 0.1524)
				(type default)
			)
			(layer "B.SilkS")
		)
		(fp_rect
			(start 4.533392 -2.326132)
			(end 5.39242 2.326132)
			(stroke
				(width 0)
				(type default)
			)
			(fill yes)
			(layer "B.SilkS")
		)
		(fp_line
			(start 3.750056 -2.249932)
			(end -3.750056 -2.249932)
			(stroke
				(width 0.1)
				(type default)
			)
			(layer "B.Fab")
		)
		(fp_line
			(start -3.750056 -2.249932)
			(end -3.750056 2.249932)
			(stroke
				(width 0.1)
				(type default)
			)
			(layer "B.Fab")
		)
		(fp_line
			(start 3.750056 2.249932)
			(end 3.750056 -2.249932)
			(stroke
				(width 0.1)
				(type default)
			)
			(layer "B.Fab")
		)
		(fp_line
			(start -3.750056 2.249932)
			(end 3.750056 2.249932)
			(stroke
				(width 0.1)
				(type default)
			)
			(layer "B.Fab")
		)
		(fp_text user "+"
			(at 6.322314 0.786384 0)
			(unlocked yes)
			(layer "B.SilkS")
			(effects
				(font
					(size 1.905 1.4224)
					(thickness 0.1524)
				)
				(justify left mirror)
			)
		)
		(fp_text user "-"
			(at -4.060698 2.725674 90)
			(unlocked yes)
			(layer "B.SilkS")
			(effects
				(font
					(size 1.905 1.4224)
					(thickness 0.1524)
				)
				(justify left mirror)
			)
		)
		(fp_text user "-"
			(at -4.8514 -0.14605 90)
			(unlocked yes)
			(layer "B.Fab")
			(effects
				(font
					(size 1.905 1.4224)
					(thickness 0.1524)
				)
				(justify left mirror)
			)
		)
		(fp_text user "+"
			(at 6.322314 0.786384 0)
			(unlocked yes)
			(layer "B.Fab")
			(effects
				(font
					(size 1.905 1.4224)
					(thickness 0.1524)
				)
				(justify left mirror)
			)
		)
		(pad "1" smd rect
			(at 3.199892 0 270)
			(size 2.413 2.8194)
			(layers "B.Cu" "B.Mask" "B.Paste")
			(net "PVDDCR_SOC_P0")
		)
		(pad "2" smd rect
			(at -3.199892 0 270)
			(size 2.413 2.8194)
			(layers "B.Cu" "B.Mask" "B.Paste")
			(net "GND")
		)
	)
	(footprint ""
		(layer "B.Cu")
		(at 238.310928 -290.844732 180)
		(property "Reference" "R6505"
			(at 0 0 0)
			(layer "B.SilkS")
			(hide yes)
			(effects
				(font
					(size 1.27 1.27)
				)
				(justify mirror)
			)
		)
		(property "Value" ""
			(at 0 0 0)
			(layer "B.Fab")
			(effects
				(font
					(size 1.27 1.27)
				)
				(justify mirror)
			)
		)
		(duplicate_pad_numbers_are_jumpers no)
		(fp_line
			(start 0.7874 0.4064)
			(end 0.7874 -0.4064)
			(stroke
				(width 0.1524)
				(type default)
			)
			(layer "B.SilkS")
		)
		(fp_line
			(start 0.7874 -0.4064)
			(end -0.7874 -0.4064)
			(stroke
				(width 0.1524)
				(type default)
			)
			(layer "B.SilkS")
		)
		(fp_line
			(start -0.7874 0.4064)
			(end 0.7874 0.4064)
			(stroke
				(width 0.1524)
				(type default)
			)
			(layer "B.SilkS")
		)
		(fp_line
			(start -0.7874 -0.4064)
			(end -0.7874 0.4064)
			(stroke
				(width 0.1524)
				(type default)
			)
			(layer "B.SilkS")
		)
		(fp_line
			(start 0.67945 0.3048)
			(end 0.67945 -0.305054)
			(stroke
				(width 0.1)
				(type default)
			)
			(layer "B.Fab")
		)
		(fp_line
			(start 0.67945 -0.305054)
			(end 0.12065 -0.305054)
			(stroke
				(width 0.1)
				(type default)
			)
			(layer "B.Fab")
		)
		(fp_line
			(start 0.12065 0.3048)
			(end 0.67945 0.3048)
			(stroke
				(width 0.1)
				(type default)
			)
			(layer "B.Fab")
		)
		(fp_line
			(start 0.12065 0.2794)
			(end 0.12065 0.3048)
			(stroke
				(width 0.1)
				(type default)
			)
			(layer "B.Fab")
		)
		(fp_line
			(start 0.12065 -0.2794)
			(end -0.12065 -0.2794)
			(stroke
				(width 0.1)
				(type default)
			)
			(layer "B.Fab")
		)
		(fp_line
			(start 0.12065 -0.305054)
			(end 0.12065 -0.2794)
			(stroke
				(width 0.1)
				(type default)
			)
			(layer "B.Fab")
		)
		(fp_line
			(start -0.120396 0.3048)
			(end -0.120396 0.2794)
			(stroke
				(width 0.1)
				(type default)
			)
			(layer "B.Fab")
		)
		(fp_line
			(start -0.120396 0.2794)
			(end 0.12065 0.2794)
			(stroke
				(width 0.1)
				(type default)
			)
			(layer "B.Fab")
		)
		(fp_line
			(start -0.12065 -0.2794)
			(end -0.12065 -0.3048)
			(stroke
				(width 0.1)
				(type default)
			)
			(layer "B.Fab")
		)
		(fp_line
			(start -0.12065 -0.3048)
			(end -0.67945 -0.3048)
			(stroke
				(width 0.1)
				(type default)
			)
			(layer "B.Fab")
		)
		(fp_line
			(start -0.67945 0.3048)
			(end -0.120396 0.3048)
			(stroke
				(width 0.1)
				(type default)
			)
			(layer "B.Fab")
		)
		(fp_line
			(start -0.67945 -0.3048)
			(end -0.67945 0.3048)
			(stroke
				(width 0.1)
				(type default)
			)
			(layer "B.Fab")
		)
		(pad "1" smd circle
			(at 0.40005 0)
			(size 0 0)
			(layers "B.Cu" "B.Mask" "B.Paste")
			(net "P3V3_AUX")
		)
		(pad "2" smd circle
			(at -0.40005 0)
			(size 0 0)
			(layers "B.Cu" "B.Mask" "B.Paste")
			(net "PWRGD_P1V8_RETIMER_CPU0")
		)
	)
	(footprint ""
		(layer "B.Cu")
		(at 137.74547 -387.084062 -90)
		(property "Reference" "C432"
			(at 0 0 90)
			(layer "B.SilkS")
			(hide yes)
			(effects
				(font
					(size 1.27 1.27)
				)
				(justify mirror)
			)
		)
		(property "Value" ""
			(at 0 0 90)
			(layer "B.Fab")
			(effects
				(font
					(size 1.27 1.27)
				)
				(justify mirror)
			)
		)
		(duplicate_pad_numbers_are_jumpers no)
		(fp_line
			(start -1.524 0.762)
			(end 1.524 0.762)
			(stroke
				(width 0.1524)
				(type default)
			)
			(layer "B.SilkS")
		)
		(fp_line
			(start 1.524 0.762)
			(end 1.524 -0.762)
			(stroke
				(width 0.1524)
				(type default)
			)
			(layer "B.SilkS")
		)
		(fp_line
			(start -1.524 -0.762)
			(end -1.524 0.762)
			(stroke
				(width 0.1524)
				(type default)
			)
			(layer "B.SilkS")
		)
		(fp_line
			(start 1.524 -0.762)
			(end -1.524 -0.762)
			(stroke
				(width 0.1524)
				(type default)
			)
			(layer "B.SilkS")
		)
		(fp_line
			(start -1.1049 0.724916)
			(end -1.1049 -0.724916)
			(stroke
				(width 0.1)
				(type default)
			)
			(layer "B.Fab")
		)
		(fp_line
			(start 1.1049 0.724916)
			(end -1.1049 0.724916)
			(stroke
				(width 0.1)
				(type default)
			)
			(layer "B.Fab")
		)
		(fp_line
			(start -1.1049 -0.724916)
			(end 1.1049 -0.724916)
			(stroke
				(width 0.1)
				(type default)
			)
			(layer "B.Fab")
		)
		(fp_line
			(start 1.1049 -0.724916)
			(end 1.1049 0.724916)
			(stroke
				(width 0.1)
				(type default)
			)
			(layer "B.Fab")
		)
		(pad "1" smd rect
			(at 0.889 0 270)
			(size 1.016 1.27)
			(layers "B.Cu" "B.Mask" "B.Paste")
			(net "P1V8_CPU1_RT_1D")
		)
		(pad "2" smd rect
			(at -0.889 0 270)
			(size 1.016 1.27)
			(layers "B.Cu" "B.Mask" "B.Paste")
			(net "GND")
		)
	)
	(footprint ""
		(layer "B.Cu")
		(at 59.391296 -390.909302 90)
		(property "Reference" "C185"
			(at 0 0 90)
			(layer "B.SilkS")
			(hide yes)
			(effects
				(font
					(size 1.27 1.27)
				)
				(justify mirror)
			)
		)
		(property "Value" ""
			(at 0 0 90)
			(layer "B.Fab")
			(effects
				(font
					(size 1.27 1.27)
				)
				(justify mirror)
			)
		)
		(duplicate_pad_numbers_are_jumpers no)
		(fp_line
			(start 0.299974 -0.150114)
			(end -0.299974 -0.150114)
			(stroke
				(width 0.1)
				(type default)
			)
			(layer "B.Fab")
		)
		(fp_line
			(start -0.299974 -0.150114)
			(end -0.299974 0.150114)
			(stroke
				(width 0.1)
				(type default)
			)
			(layer "B.Fab")
		)
		(fp_line
			(start 0.299974 0.150114)
			(end 0.299974 -0.150114)
			(stroke
				(width 0.1)
				(type default)
			)
			(layer "B.Fab")
		)
		(fp_line
			(start -0.299974 0.150114)
			(end 0.299974 0.150114)
			(stroke
				(width 0.1)
				(type default)
			)
			(layer "B.Fab")
		)
		(pad "1" smd rect
			(at 0.2667 0 270)
			(size 0.3048 0.381)
			(layers "B.Cu" "B.Mask" "B.Paste")
			(net "P0V9_CPU1_RT_2D")
		)
		(pad "2" smd rect
			(at -0.2667 0 270)
			(size 0.3048 0.381)
			(layers "B.Cu" "B.Mask" "B.Paste")
			(net "GND")
		)
	)
	(footprint ""
		(layer "B.Cu")
		(at 428.98695 -30.165548 180)
		(property "Reference" "R6041"
			(at 0 0 0)
			(layer "B.SilkS")
			(hide yes)
			(effects
				(font
					(size 1.27 1.27)
				)
				(justify mirror)
			)
		)
		(property "Value" ""
			(at 0 0 0)
			(layer "B.Fab")
			(effects
				(font
					(size 1.27 1.27)
				)
				(justify mirror)
			)
		)
		(duplicate_pad_numbers_are_jumpers no)
		(fp_line
			(start 0.7874 0.4064)
			(end 0.7874 -0.4064)
			(stroke
				(width 0.1524)
				(type default)
			)
			(layer "B.SilkS")
		)
		(fp_line
			(start 0.7874 -0.4064)
			(end -0.7874 -0.4064)
			(stroke
				(width 0.1524)
				(type default)
			)
			(layer "B.SilkS")
		)
		(fp_line
			(start -0.7874 0.4064)
			(end 0.7874 0.4064)
			(stroke
				(width 0.1524)
				(type default)
			)
			(layer "B.SilkS")
		)
		(fp_line
			(start -0.7874 -0.4064)
			(end -0.7874 0.4064)
			(stroke
				(width 0.1524)
				(type default)
			)
			(layer "B.SilkS")
		)
		(fp_line
			(start 0.67945 0.3048)
			(end 0.67945 -0.305054)
			(stroke
				(width 0.1)
				(type default)
			)
			(layer "B.Fab")
		)
		(fp_line
			(start 0.67945 -0.305054)
			(end 0.12065 -0.305054)
			(stroke
				(width 0.1)
				(type default)
			)
			(layer "B.Fab")
		)
		(fp_line
			(start 0.12065 0.3048)
			(end 0.67945 0.3048)
			(stroke
				(width 0.1)
				(type default)
			)
			(layer "B.Fab")
		)
		(fp_line
			(start 0.12065 0.2794)
			(end 0.12065 0.3048)
			(stroke
				(width 0.1)
				(type default)
			)
			(layer "B.Fab")
		)
		(fp_line
			(start 0.12065 -0.2794)
			(end -0.12065 -0.2794)
			(stroke
				(width 0.1)
				(type default)
			)
			(layer "B.Fab")
		)
		(fp_line
			(start 0.12065 -0.305054)
			(end 0.12065 -0.2794)
			(stroke
				(width 0.1)
				(type default)
			)
			(layer "B.Fab")
		)
		(fp_line
			(start -0.120396 0.3048)
			(end -0.120396 0.2794)
			(stroke
				(width 0.1)
				(type default)
			)
			(layer "B.Fab")
		)
		(fp_line
			(start -0.120396 0.2794)
			(end 0.12065 0.2794)
			(stroke
				(width 0.1)
				(type default)
			)
			(layer "B.Fab")
		)
		(fp_line
			(start -0.12065 -0.2794)
			(end -0.12065 -0.3048)
			(stroke
				(width 0.1)
				(type default)
			)
			(layer "B.Fab")
		)
		(fp_line
			(start -0.12065 -0.3048)
			(end -0.67945 -0.3048)
			(stroke
				(width 0.1)
				(type default)
			)
			(layer "B.Fab")
		)
		(fp_line
			(start -0.67945 0.3048)
			(end -0.120396 0.3048)
			(stroke
				(width 0.1)
				(type default)
			)
			(layer "B.Fab")
		)
		(fp_line
			(start -0.67945 -0.3048)
			(end -0.67945 0.3048)
			(stroke
				(width 0.1)
				(type default)
			)
			(layer "B.Fab")
		)
		(pad "1" smd circle
			(at 0.40005 0)
			(size 0 0)
			(layers "B.Cu" "B.Mask" "B.Paste")
			(net "GND")
		)
		(pad "2" smd circle
			(at -0.40005 0)
			(size 0 0)
			(layers "B.Cu" "B.Mask" "B.Paste")
			(net "FPGA_DEBUG_LED_CTRL")
		)
	)
	(footprint ""
		(layer "B.Cu")
		(at 163.359084 -9.013444 -90)
		(property "Reference" "R2205"
			(at 0 0 90)
			(layer "B.SilkS")
			(hide yes)
			(effects
				(font
					(size 1.27 1.27)
				)
				(justify mirror)
			)
		)
		(property "Value" ""
			(at 0 0 90)
			(layer "B.Fab")
			(effects
				(font
					(size 1.27 1.27)
				)
				(justify mirror)
			)
		)
		(duplicate_pad_numbers_are_jumpers no)
		(fp_line
			(start -0.7874 0.4064)
			(end 0.7874 0.4064)
			(stroke
				(width 0.1524)
				(type default)
			)
			(layer "B.SilkS")
		)
		(fp_line
			(start 0.7874 0.4064)
			(end 0.7874 -0.4064)
			(stroke
				(width 0.1524)
				(type default)
			)
			(layer "B.SilkS")
		)
		(fp_line
			(start -0.7874 -0.4064)
			(end -0.7874 0.4064)
			(stroke
				(width 0.1524)
				(type default)
			)
			(layer "B.SilkS")
		)
		(fp_line
			(start 0.7874 -0.4064)
			(end -0.7874 -0.4064)
			(stroke
				(width 0.1524)
				(type default)
			)
			(layer "B.SilkS")
		)
		(fp_line
			(start -0.67945 0.3048)
			(end -0.120396 0.3048)
			(stroke
				(width 0.1)
				(type default)
			)
			(layer "B.Fab")
		)
		(fp_line
			(start -0.120396 0.3048)
			(end -0.120396 0.2794)
			(stroke
				(width 0.1)
				(type default)
			)
			(layer "B.Fab")
		)
		(fp_line
			(start 0.12065 0.3048)
			(end 0.67945 0.3048)
			(stroke
				(width 0.1)
				(type default)
			)
			(layer "B.Fab")
		)
		(fp_line
			(start 0.67945 0.3048)
			(end 0.67945 -0.305054)
			(stroke
				(width 0.1)
				(type default)
			)
			(layer "B.Fab")
		)
		(fp_line
			(start -0.120396 0.2794)
			(end 0.12065 0.2794)
			(stroke
				(width 0.1)
				(type default)
			)
			(layer "B.Fab")
		)
		(fp_line
			(start 0.12065 0.2794)
			(end 0.12065 0.3048)
			(stroke
				(width 0.1)
				(type default)
			)
			(layer "B.Fab")
		)
		(fp_line
			(start -0.12065 -0.2794)
			(end -0.12065 -0.3048)
			(stroke
				(width 0.1)
				(type default)
			)
			(layer "B.Fab")
		)
		(fp_line
			(start 0.12065 -0.2794)
			(end -0.12065 -0.2794)
			(stroke
				(width 0.1)
				(type default)
			)
			(layer "B.Fab")
		)
		(fp_line
			(start -0.67945 -0.3048)
			(end -0.67945 0.3048)
			(stroke
				(width 0.1)
				(type default)
			)
			(layer "B.Fab")
		)
		(fp_line
			(start -0.12065 -0.3048)
			(end -0.67945 -0.3048)
			(stroke
				(width 0.1)
				(type default)
			)
			(layer "B.Fab")
		)
		(fp_line
			(start 0.12065 -0.305054)
			(end 0.12065 -0.2794)
			(stroke
				(width 0.1)
				(type default)
			)
			(layer "B.Fab")
		)
		(fp_line
			(start 0.67945 -0.305054)
			(end 0.12065 -0.305054)
			(stroke
				(width 0.1)
				(type default)
			)
			(layer "B.Fab")
		)
		(pad "1" smd circle
			(at 0.40005 0 90)
			(size 0 0)
			(layers "B.Cu" "B.Mask" "B.Paste")
			(net "P3V3_AUX")
		)
		(pad "2" smd circle
			(at -0.40005 0 90)
			(size 0 0)
			(layers "B.Cu" "B.Mask" "B.Paste")
			(net "SMB_PCIE0_3V3AUX_SDA")
		)
	)
	(footprint ""
		(layer "B.Cu")
		(at 179.27701 -421.374824 90)
		(property "Reference" "C6084"
			(at 0 0 90)
			(layer "B.SilkS")
			(hide yes)
			(effects
				(font
					(size 1.27 1.27)
				)
				(justify mirror)
			)
		)
		(property "Value" ""
			(at 0 0 90)
			(layer "B.Fab")
			(effects
				(font
					(size 1.27 1.27)
				)
				(justify mirror)
			)
		)
		(duplicate_pad_numbers_are_jumpers no)
		(fp_line
			(start 0.7874 -0.4064)
			(end -0.7874 -0.4064)
			(stroke
				(width 0.1524)
				(type default)
			)
			(layer "B.SilkS")
		)
		(fp_line
			(start -0.7874 -0.4064)
			(end -0.7874 0.4064)
			(stroke
				(width 0.1524)
				(type default)
			)
			(layer "B.SilkS")
		)
		(fp_line
			(start 0.7874 0.4064)
			(end 0.7874 -0.4064)
			(stroke
				(width 0.1524)
				(type default)
			)
			(layer "B.SilkS")
		)
		(fp_line
			(start -0.7874 0.4064)
			(end 0.7874 0.4064)
			(stroke
				(width 0.1524)
				(type default)
			)
			(layer "B.SilkS")
		)
		(fp_line
			(start 0.67945 -0.305054)
			(end 0.12065 -0.305054)
			(stroke
				(width 0.1)
				(type default)
			)
			(layer "B.Fab")
		)
		(fp_line
			(start 0.12065 -0.305054)
			(end 0.12065 -0.2794)
			(stroke
				(width 0.1)
				(type default)
			)
			(layer "B.Fab")
		)
		(fp_line
			(start -0.12065 -0.3048)
			(end -0.67945 -0.3048)
			(stroke
				(width 0.1)
				(type default)
			)
			(layer "B.Fab")
		)
		(fp_line
			(start -0.67945 -0.3048)
			(end -0.67945 0.3048)
			(stroke
				(width 0.1)
				(type default)
			)
			(layer "B.Fab")
		)
		(fp_line
			(start 0.12065 -0.2794)
			(end -0.12065 -0.2794)
			(stroke
				(width 0.1)
				(type default)
			)
			(layer "B.Fab")
		)
		(fp_line
			(start -0.12065 -0.2794)
			(end -0.12065 -0.3048)
			(stroke
				(width 0.1)
				(type default)
			)
			(layer "B.Fab")
		)
		(fp_line
			(start 0.12065 0.2794)
			(end 0.12065 0.3048)
			(stroke
				(width 0.1)
				(type default)
			)
			(layer "B.Fab")
		)
		(fp_line
			(start -0.120396 0.2794)
			(end 0.12065 0.2794)
			(stroke
				(width 0.1)
				(type default)
			)
			(layer "B.Fab")
		)
		(fp_line
			(start 0.67945 0.3048)
			(end 0.67945 -0.305054)
			(stroke
				(width 0.1)
				(type default)
			)
			(layer "B.Fab")
		)
		(fp_line
			(start 0.12065 0.3048)
			(end 0.67945 0.3048)
			(stroke
				(width 0.1)
				(type default)
			)
			(layer "B.Fab")
		)
		(fp_line
			(start -0.120396 0.3048)
			(end -0.120396 0.2794)
			(stroke
				(width 0.1)
				(type default)
			)
			(layer "B.Fab")
		)
		(fp_line
			(start -0.67945 0.3048)
			(end -0.120396 0.3048)
			(stroke
				(width 0.1)
				(type default)
			)
			(layer "B.Fab")
		)
		(pad "1" smd circle
			(at 0.40005 0 270)
			(size 0 0)
			(layers "B.Cu" "B.Mask" "B.Paste")
			(net "U142_VS")
		)
		(pad "2" smd circle
			(at -0.40005 0 270)
			(size 0 0)
			(layers "B.Cu" "B.Mask" "B.Paste")
			(net "GND")
		)
	)
	(footprint ""
		(layer "B.Cu")
		(at 80.847184 -408.517344 90)
		(property "Reference" "C6681"
			(at 0 0 90)
			(layer "B.SilkS")
			(hide yes)
			(effects
				(font
					(size 1.27 1.27)
				)
				(justify mirror)
			)
		)
		(property "Value" ""
			(at 0 0 90)
			(layer "B.Fab")
			(effects
				(font
					(size 1.27 1.27)
				)
				(justify mirror)
			)
		)
		(duplicate_pad_numbers_are_jumpers no)
		(fp_line
			(start 0.299974 -0.150114)
			(end -0.299974 -0.150114)
			(stroke
				(width 0.1)
				(type default)
			)
			(layer "B.Fab")
		)
		(fp_line
			(start -0.299974 -0.150114)
			(end -0.299974 0.150114)
			(stroke
				(width 0.1)
				(type default)
			)
			(layer "B.Fab")
		)
		(fp_line
			(start 0.299974 0.150114)
			(end 0.299974 -0.150114)
			(stroke
				(width 0.1)
				(type default)
			)
			(layer "B.Fab")
		)
		(fp_line
			(start -0.299974 0.150114)
			(end 0.299974 0.150114)
			(stroke
				(width 0.1)
				(type default)
			)
			(layer "B.Fab")
		)
		(pad "1" smd rect
			(at 0.2667 0 270)
			(size 0.3048 0.381)
			(layers "B.Cu" "B.Mask" "B.Paste")
			(net "P5E_CPU1_P1_TX_BUF_C_DP<10>")
		)
		(pad "2" smd rect
			(at -0.2667 0 270)
			(size 0.3048 0.381)
			(layers "B.Cu" "B.Mask" "B.Paste")
			(net "P5E_CPU1_P1_TX_BUF_DP<10>")
		)
	)
	(footprint ""
		(layer "B.Cu")
		(at 32.639 -364.871)
		(property "Reference" "PR244"
			(at 0 0 0)
			(layer "B.SilkS")
			(hide yes)
			(effects
				(font
					(size 1.27 1.27)
				)
				(justify mirror)
			)
		)
		(property "Value" ""
			(at 0 0 0)
			(layer "B.Fab")
			(effects
				(font
					(size 1.27 1.27)
				)
				(justify mirror)
			)
		)
		(duplicate_pad_numbers_are_jumpers no)
		(fp_line
			(start -0.7874 -0.4064)
			(end -0.7874 0.4064)
			(stroke
				(width 0.1524)
				(type default)
			)
			(layer "B.SilkS")
		)
		(fp_line
			(start -0.7874 0.4064)
			(end 0.7874 0.4064)
			(stroke
				(width 0.1524)
				(type default)
			)
			(layer "B.SilkS")
		)
		(fp_line
			(start 0.7874 -0.4064)
			(end -0.7874 -0.4064)
			(stroke
				(width 0.1524)
				(type default)
			)
			(layer "B.SilkS")
		)
		(fp_line
			(start 0.7874 0.4064)
			(end 0.7874 -0.4064)
			(stroke
				(width 0.1524)
				(type default)
			)
			(layer "B.SilkS")
		)
		(fp_line
			(start -0.67945 -0.3048)
			(end -0.67945 0.3048)
			(stroke
				(width 0.1)
				(type default)
			)
			(layer "B.Fab")
		)
		(fp_line
			(start -0.67945 0.3048)
			(end -0.120396 0.3048)
			(stroke
				(width 0.1)
				(type default)
			)
			(layer "B.Fab")
		)
		(fp_line
			(start -0.12065 -0.3048)
			(end -0.67945 -0.3048)
			(stroke
				(width 0.1)
				(type default)
			)
			(layer "B.Fab")
		)
		(fp_line
			(start -0.12065 -0.2794)
			(end -0.12065 -0.3048)
			(stroke
				(width 0.1)
				(type default)
			)
			(layer "B.Fab")
		)
		(fp_line
			(start -0.120396 0.2794)
			(end 0.12065 0.2794)
			(stroke
				(width 0.1)
				(type default)
			)
			(layer "B.Fab")
		)
		(fp_line
			(start -0.120396 0.3048)
			(end -0.120396 0.2794)
			(stroke
				(width 0.1)
				(type default)
			)
			(layer "B.Fab")
		)
		(fp_line
			(start 0.12065 -0.305054)
			(end 0.12065 -0.2794)
			(stroke
				(width 0.1)
				(type default)
			)
			(layer "B.Fab")
		)
		(fp_line
			(start 0.12065 -0.2794)
			(end -0.12065 -0.2794)
			(stroke
				(width 0.1)
				(type default)
			)
			(layer "B.Fab")
		)
		(fp_line
			(start 0.12065 0.2794)
			(end 0.12065 0.3048)
			(stroke
				(width 0.1)
				(type default)
			)
			(layer "B.Fab")
		)
		(fp_line
			(start 0.12065 0.3048)
			(end 0.67945 0.3048)
			(stroke
				(width 0.1)
				(type default)
			)
			(layer "B.Fab")
		)
		(fp_line
			(start 0.67945 -0.305054)
			(end 0.12065 -0.305054)
			(stroke
				(width 0.1)
				(type default)
			)
			(layer "B.Fab")
		)
		(fp_line
			(start 0.67945 0.3048)
			(end 0.67945 -0.305054)
			(stroke
				(width 0.1)
				(type default)
			)
			(layer "B.Fab")
		)
		(pad "1" smd circle
			(at 0.40005 0 180)
			(size 0 0)
			(layers "B.Cu" "B.Mask" "B.Paste")
			(net "PVDDCR_CPU1_P1_EN1_ADDR_CFG")
		)
		(pad "2" smd circle
			(at -0.40005 0 180)
			(size 0 0)
			(layers "B.Cu" "B.Mask" "B.Paste")
			(net "GND")
		)
	)
	(footprint ""
		(layer "B.Cu")
		(at 333.561436 -151.069294 90)
		(property "Reference" "PC285"
			(at 0 0 90)
			(layer "B.SilkS")
			(hide yes)
			(effects
				(font
					(size 1.27 1.27)
				)
				(justify mirror)
			)
		)
		(property "Value" ""
			(at 0 0 90)
			(layer "B.Fab")
			(effects
				(font
					(size 1.27 1.27)
				)
				(justify mirror)
			)
		)
		(duplicate_pad_numbers_are_jumpers no)
		(fp_line
			(start 1.524 -0.762)
			(end -1.524 -0.762)
			(stroke
				(width 0.1524)
				(type default)
			)
			(layer "B.SilkS")
		)
		(fp_line
			(start -1.524 -0.762)
			(end -1.524 0.762)
			(stroke
				(width 0.1524)
				(type default)
			)
			(layer "B.SilkS")
		)
		(fp_line
			(start 1.524 0.762)
			(end 1.524 -0.762)
			(stroke
				(width 0.1524)
				(type default)
			)
			(layer "B.SilkS")
		)
		(fp_line
			(start -1.524 0.762)
			(end 1.524 0.762)
			(stroke
				(width 0.1524)
				(type default)
			)
			(layer "B.SilkS")
		)
		(fp_line
			(start 1.1049 -0.724916)
			(end 1.1049 0.724916)
			(stroke
				(width 0.1)
				(type default)
			)
			(layer "B.Fab")
		)
		(fp_line
			(start -1.1049 -0.724916)
			(end 1.1049 -0.724916)
			(stroke
				(width 0.1)
				(type default)
			)
			(layer "B.Fab")
		)
		(fp_line
			(start 1.1049 0.724916)
			(end -1.1049 0.724916)
			(stroke
				(width 0.1)
				(type default)
			)
			(layer "B.Fab")
		)
		(fp_line
			(start -1.1049 0.724916)
			(end -1.1049 -0.724916)
			(stroke
				(width 0.1)
				(type default)
			)
			(layer "B.Fab")
		)
		(pad "1" smd rect
			(at 0.889 0 90)
			(size 1.016 1.27)
			(layers "B.Cu" "B.Mask" "B.Paste")
			(net "PVDD18_S5_P0")
		)
		(pad "2" smd rect
			(at -0.889 0 90)
			(size 1.016 1.27)
			(layers "B.Cu" "B.Mask" "B.Paste")
			(net "GND")
		)
	)
	(footprint ""
		(layer "B.Cu")
		(at 421.974518 -175.029622)
		(property "Reference" "TP1"
			(at -0.72136 -1.224788 0)
			(unlocked yes)
			(layer "B.SilkS")
			(effects
				(font
					(size 0.7874 0.5842)
					(thickness 0.1524)
				)
				(justify left mirror)
			)
		)
		(property "Value" ""
			(at 0 0 0)
			(layer "B.Fab")
			(effects
				(font
					(size 1.27 1.27)
				)
				(justify mirror)
			)
		)
		(duplicate_pad_numbers_are_jumpers no)
		(pad "1" smd circle
			(at 0 0 180)
			(size 0.6604 0.6604)
			(layers "B.Cu" "B.Mask" "B.Paste")
			(net "VSENSE_VSS_SENSE_A_P0")
		)
	)
	(footprint ""
		(layer "B.Cu")
		(at 346.518992 -258.830064 180)
		(property "Reference" "C2654"
			(at 0 0 0)
			(layer "B.SilkS")
			(hide yes)
			(effects
				(font
					(size 1.27 1.27)
				)
				(justify mirror)
			)
		)
		(property "Value" ""
			(at 0 0 0)
			(layer "B.Fab")
			(effects
				(font
					(size 1.27 1.27)
				)
				(justify mirror)
			)
		)
		(duplicate_pad_numbers_are_jumpers no)
		(fp_line
			(start 0.7874 0.4064)
			(end 0.7874 -0.4064)
			(stroke
				(width 0.1524)
				(type default)
			)
			(layer "B.SilkS")
		)
		(fp_line
			(start 0.7874 -0.4064)
			(end -0.7874 -0.4064)
			(stroke
				(width 0.1524)
				(type default)
			)
			(layer "B.SilkS")
		)
		(fp_line
			(start -0.7874 0.4064)
			(end 0.7874 0.4064)
			(stroke
				(width 0.1524)
				(type default)
			)
			(layer "B.SilkS")
		)
		(fp_line
			(start -0.7874 -0.4064)
			(end -0.7874 0.4064)
			(stroke
				(width 0.1524)
				(type default)
			)
			(layer "B.SilkS")
		)
		(fp_line
			(start 0.67945 0.3048)
			(end 0.67945 -0.305054)
			(stroke
				(width 0.1)
				(type default)
			)
			(layer "B.Fab")
		)
		(fp_line
			(start 0.67945 -0.305054)
			(end 0.12065 -0.305054)
			(stroke
				(width 0.1)
				(type default)
			)
			(layer "B.Fab")
		)
		(fp_line
			(start 0.12065 0.3048)
			(end 0.67945 0.3048)
			(stroke
				(width 0.1)
				(type default)
			)
			(layer "B.Fab")
		)
		(fp_line
			(start 0.12065 0.2794)
			(end 0.12065 0.3048)
			(stroke
				(width 0.1)
				(type default)
			)
			(layer "B.Fab")
		)
		(fp_line
			(start 0.12065 -0.2794)
			(end -0.12065 -0.2794)
			(stroke
				(width 0.1)
				(type default)
			)
			(layer "B.Fab")
		)
		(fp_line
			(start 0.12065 -0.305054)
			(end 0.12065 -0.2794)
			(stroke
				(width 0.1)
				(type default)
			)
			(layer "B.Fab")
		)
		(fp_line
			(start -0.120396 0.3048)
			(end -0.120396 0.2794)
			(stroke
				(width 0.1)
				(type default)
			)
			(layer "B.Fab")
		)
		(fp_line
			(start -0.120396 0.2794)
			(end 0.12065 0.2794)
			(stroke
				(width 0.1)
				(type default)
			)
			(layer "B.Fab")
		)
		(fp_line
			(start -0.12065 -0.2794)
			(end -0.12065 -0.3048)
			(stroke
				(width 0.1)
				(type default)
			)
			(layer "B.Fab")
		)
		(fp_line
			(start -0.12065 -0.3048)
			(end -0.67945 -0.3048)
			(stroke
				(width 0.1)
				(type default)
			)
			(layer "B.Fab")
		)
		(fp_line
			(start -0.67945 0.3048)
			(end -0.120396 0.3048)
			(stroke
				(width 0.1)
				(type default)
			)
			(layer "B.Fab")
		)
		(fp_line
			(start -0.67945 -0.3048)
			(end -0.67945 0.3048)
			(stroke
				(width 0.1)
				(type default)
			)
			(layer "B.Fab")
		)
		(pad "1" smd circle
			(at 0.40005 0)
			(size 0 0)
			(layers "B.Cu" "B.Mask" "B.Paste")
			(net "PVDDIO_P0")
		)
		(pad "2" smd circle
			(at -0.40005 0)
			(size 0 0)
			(layers "B.Cu" "B.Mask" "B.Paste")
			(net "GND")
		)
	)
	(footprint ""
		(layer "B.Cu")
		(at 125.262386 -267.49883)
		(property "Reference" "C2399"
			(at 0 0 0)
			(layer "B.SilkS")
			(hide yes)
			(effects
				(font
					(size 1.27 1.27)
				)
				(justify mirror)
			)
		)
		(property "Value" ""
			(at 0 0 0)
			(layer "B.Fab")
			(effects
				(font
					(size 1.27 1.27)
				)
				(justify mirror)
			)
		)
		(duplicate_pad_numbers_are_jumpers no)
		(fp_line
			(start -0.7874 -0.4064)
			(end -0.7874 0.4064)
			(stroke
				(width 0.1524)
				(type default)
			)
			(layer "B.SilkS")
		)
		(fp_line
			(start -0.7874 0.4064)
			(end 0.7874 0.4064)
			(stroke
				(width 0.1524)
				(type default)
			)
			(layer "B.SilkS")
		)
		(fp_line
			(start 0.7874 -0.4064)
			(end -0.7874 -0.4064)
			(stroke
				(width 0.1524)
				(type default)
			)
			(layer "B.SilkS")
		)
		(fp_line
			(start 0.7874 0.4064)
			(end 0.7874 -0.4064)
			(stroke
				(width 0.1524)
				(type default)
			)
			(layer "B.SilkS")
		)
		(fp_line
			(start -0.67945 -0.3048)
			(end -0.67945 0.3048)
			(stroke
				(width 0.1)
				(type default)
			)
			(layer "B.Fab")
		)
		(fp_line
			(start -0.67945 0.3048)
			(end -0.120396 0.3048)
			(stroke
				(width 0.1)
				(type default)
			)
			(layer "B.Fab")
		)
		(fp_line
			(start -0.12065 -0.3048)
			(end -0.67945 -0.3048)
			(stroke
				(width 0.1)
				(type default)
			)
			(layer "B.Fab")
		)
		(fp_line
			(start -0.12065 -0.2794)
			(end -0.12065 -0.3048)
			(stroke
				(width 0.1)
				(type default)
			)
			(layer "B.Fab")
		)
		(fp_line
			(start -0.120396 0.2794)
			(end 0.12065 0.2794)
			(stroke
				(width 0.1)
				(type default)
			)
			(layer "B.Fab")
		)
		(fp_line
			(start -0.120396 0.3048)
			(end -0.120396 0.2794)
			(stroke
				(width 0.1)
				(type default)
			)
			(layer "B.Fab")
		)
		(fp_line
			(start 0.12065 -0.305054)
			(end 0.12065 -0.2794)
			(stroke
				(width 0.1)
				(type default)
			)
			(layer "B.Fab")
		)
		(fp_line
			(start 0.12065 -0.2794)
			(end -0.12065 -0.2794)
			(stroke
				(width 0.1)
				(type default)
			)
			(layer "B.Fab")
		)
		(fp_line
			(start 0.12065 0.2794)
			(end 0.12065 0.3048)
			(stroke
				(width 0.1)
				(type default)
			)
			(layer "B.Fab")
		)
		(fp_line
			(start 0.12065 0.3048)
			(end 0.67945 0.3048)
			(stroke
				(width 0.1)
				(type default)
			)
			(layer "B.Fab")
		)
		(fp_line
			(start 0.67945 -0.305054)
			(end 0.12065 -0.305054)
			(stroke
				(width 0.1)
				(type default)
			)
			(layer "B.Fab")
		)
		(fp_line
			(start 0.67945 0.3048)
			(end 0.67945 -0.305054)
			(stroke
				(width 0.1)
				(type default)
			)
			(layer "B.Fab")
		)
		(pad "1" smd circle
			(at 0.40005 0 180)
			(size 0 0)
			(layers "B.Cu" "B.Mask" "B.Paste")
			(net "PVDDCR_CPU1_P1")
		)
		(pad "2" smd circle
			(at -0.40005 0 180)
			(size 0 0)
			(layers "B.Cu" "B.Mask" "B.Paste")
			(net "GND")
		)
	)
	(footprint ""
		(layer "B.Cu")
		(at 255.905 -332.867 180)
		(property "Reference" "R845"
			(at 0 0 0)
			(layer "B.SilkS")
			(hide yes)
			(effects
				(font
					(size 1.27 1.27)
				)
				(justify mirror)
			)
		)
		(property "Value" ""
			(at 0 0 0)
			(layer "B.Fab")
			(effects
				(font
					(size 1.27 1.27)
				)
				(justify mirror)
			)
		)
		(duplicate_pad_numbers_are_jumpers no)
		(fp_line
			(start 0.32512 0.175006)
			(end 0.32512 -0.175006)
			(stroke
				(width 0.1)
				(type default)
			)
			(layer "B.Fab")
		)
		(fp_line
			(start 0.32512 -0.175006)
			(end -0.32512 -0.175006)
			(stroke
				(width 0.1)
				(type default)
			)
			(layer "B.Fab")
		)
		(fp_line
			(start -0.32512 0.175006)
			(end 0.32512 0.175006)
			(stroke
				(width 0.1)
				(type default)
			)
			(layer "B.Fab")
		)
		(fp_line
			(start -0.32512 -0.175006)
			(end -0.32512 0.175006)
			(stroke
				(width 0.1)
				(type default)
			)
			(layer "B.Fab")
		)
		(pad "1" smd rect
			(at 0.2667 0)
			(size 0.3048 0.381)
			(layers "B.Cu" "B.Mask" "B.Paste")
			(net "RT_ROM_SMB_MUX_ADDR2")
		)
		(pad "2" smd rect
			(at -0.2667 0 180)
			(size 0.3048 0.381)
			(layers "B.Cu" "B.Mask" "B.Paste")
			(net "GND")
		)
	)
	(footprint ""
		(layer "B.Cu")
		(at 12.003532 -99.925632 180)
		(property "Reference" "C2033"
			(at 0 0 0)
			(layer "B.SilkS")
			(hide yes)
			(effects
				(font
					(size 1.27 1.27)
				)
				(justify mirror)
			)
		)
		(property "Value" ""
			(at 0 0 0)
			(layer "B.Fab")
			(effects
				(font
					(size 1.27 1.27)
				)
				(justify mirror)
			)
		)
		(duplicate_pad_numbers_are_jumpers no)
		(fp_line
			(start 0.7874 0.4064)
			(end 0.7874 -0.4064)
			(stroke
				(width 0.1524)
				(type default)
			)
			(layer "B.SilkS")
		)
		(fp_line
			(start 0.7874 -0.4064)
			(end -0.7874 -0.4064)
			(stroke
				(width 0.1524)
				(type default)
			)
			(layer "B.SilkS")
		)
		(fp_line
			(start -0.7874 0.4064)
			(end 0.7874 0.4064)
			(stroke
				(width 0.1524)
				(type default)
			)
			(layer "B.SilkS")
		)
		(fp_line
			(start -0.7874 -0.4064)
			(end -0.7874 0.4064)
			(stroke
				(width 0.1524)
				(type default)
			)
			(layer "B.SilkS")
		)
		(fp_line
			(start 0.67945 0.3048)
			(end 0.67945 -0.305054)
			(stroke
				(width 0.1)
				(type default)
			)
			(layer "B.Fab")
		)
		(fp_line
			(start 0.67945 -0.305054)
			(end 0.12065 -0.305054)
			(stroke
				(width 0.1)
				(type default)
			)
			(layer "B.Fab")
		)
		(fp_line
			(start 0.12065 0.3048)
			(end 0.67945 0.3048)
			(stroke
				(width 0.1)
				(type default)
			)
			(layer "B.Fab")
		)
		(fp_line
			(start 0.12065 0.2794)
			(end 0.12065 0.3048)
			(stroke
				(width 0.1)
				(type default)
			)
			(layer "B.Fab")
		)
		(fp_line
			(start 0.12065 -0.2794)
			(end -0.12065 -0.2794)
			(stroke
				(width 0.1)
				(type default)
			)
			(layer "B.Fab")
		)
		(fp_line
			(start 0.12065 -0.305054)
			(end 0.12065 -0.2794)
			(stroke
				(width 0.1)
				(type default)
			)
			(layer "B.Fab")
		)
		(fp_line
			(start -0.120396 0.3048)
			(end -0.120396 0.2794)
			(stroke
				(width 0.1)
				(type default)
			)
			(layer "B.Fab")
		)
		(fp_line
			(start -0.120396 0.2794)
			(end 0.12065 0.2794)
			(stroke
				(width 0.1)
				(type default)
			)
			(layer "B.Fab")
		)
		(fp_line
			(start -0.12065 -0.2794)
			(end -0.12065 -0.3048)
			(stroke
				(width 0.1)
				(type default)
			)
			(layer "B.Fab")
		)
		(fp_line
			(start -0.12065 -0.3048)
			(end -0.67945 -0.3048)
			(stroke
				(width 0.1)
				(type default)
			)
			(layer "B.Fab")
		)
		(fp_line
			(start -0.67945 0.3048)
			(end -0.120396 0.3048)
			(stroke
				(width 0.1)
				(type default)
			)
			(layer "B.Fab")
		)
		(fp_line
			(start -0.67945 -0.3048)
			(end -0.67945 0.3048)
			(stroke
				(width 0.1)
				(type default)
			)
			(layer "B.Fab")
		)
		(pad "1" smd circle
			(at 0.40005 0)
			(size 0 0)
			(layers "B.Cu" "B.Mask" "B.Paste")
			(net "P3V3_AUX_USB_HUB")
		)
		(pad "2" smd circle
			(at -0.40005 0)
			(size 0 0)
			(layers "B.Cu" "B.Mask" "B.Paste")
			(net "GND")
		)
	)
	(footprint ""
		(layer "B.Cu")
		(at 152.202642 -78.76921)
		(property "Reference" "PC865"
			(at 0 0 0)
			(layer "B.SilkS")
			(hide yes)
			(effects
				(font
					(size 1.27 1.27)
				)
				(justify mirror)
			)
		)
		(property "Value" ""
			(at 0 0 0)
			(layer "B.Fab")
			(effects
				(font
					(size 1.27 1.27)
				)
				(justify mirror)
			)
		)
		(duplicate_pad_numbers_are_jumpers no)
		(fp_line
			(start -1.524 -0.762)
			(end -1.524 0.762)
			(stroke
				(width 0.1524)
				(type default)
			)
			(layer "B.SilkS")
		)
		(fp_line
			(start -1.524 0.762)
			(end 1.524 0.762)
			(stroke
				(width 0.1524)
				(type default)
			)
			(layer "B.SilkS")
		)
		(fp_line
			(start 1.524 -0.762)
			(end -1.524 -0.762)
			(stroke
				(width 0.1524)
				(type default)
			)
			(layer "B.SilkS")
		)
		(fp_line
			(start 1.524 0.762)
			(end 1.524 -0.762)
			(stroke
				(width 0.1524)
				(type default)
			)
			(layer "B.SilkS")
		)
		(fp_line
			(start -1.1049 -0.724916)
			(end 1.1049 -0.724916)
			(stroke
				(width 0.1)
				(type default)
			)
			(layer "B.Fab")
		)
		(fp_line
			(start -1.1049 0.724916)
			(end -1.1049 -0.724916)
			(stroke
				(width 0.1)
				(type default)
			)
			(layer "B.Fab")
		)
		(fp_line
			(start 1.1049 -0.724916)
			(end 1.1049 0.724916)
			(stroke
				(width 0.1)
				(type default)
			)
			(layer "B.Fab")
		)
		(fp_line
			(start 1.1049 0.724916)
			(end -1.1049 0.724916)
			(stroke
				(width 0.1)
				(type default)
			)
			(layer "B.Fab")
		)
		(pad "1" smd rect
			(at 0.889 0)
			(size 1.016 1.27)
			(layers "B.Cu" "B.Mask" "B.Paste")
			(net "P1V8_AUX")
		)
		(pad "2" smd rect
			(at -0.889 0)
			(size 1.016 1.27)
			(layers "B.Cu" "B.Mask" "B.Paste")
			(net "GND")
		)
	)
	(footprint ""
		(layer "B.Cu")
		(at 442.290454 -191.20231 180)
		(property "Reference" "R301"
			(at 0 0 0)
			(layer "B.SilkS")
			(hide yes)
			(effects
				(font
					(size 1.27 1.27)
				)
				(justify mirror)
			)
		)
		(property "Value" ""
			(at 0 0 0)
			(layer "B.Fab")
			(effects
				(font
					(size 1.27 1.27)
				)
				(justify mirror)
			)
		)
		(duplicate_pad_numbers_are_jumpers no)
		(fp_line
			(start 0.7874 0.4064)
			(end 0.7874 -0.4064)
			(stroke
				(width 0.1524)
				(type default)
			)
			(layer "B.SilkS")
		)
		(fp_line
			(start 0.7874 -0.4064)
			(end -0.7874 -0.4064)
			(stroke
				(width 0.1524)
				(type default)
			)
			(layer "B.SilkS")
		)
		(fp_line
			(start -0.7874 0.4064)
			(end 0.7874 0.4064)
			(stroke
				(width 0.1524)
				(type default)
			)
			(layer "B.SilkS")
		)
		(fp_line
			(start -0.7874 -0.4064)
			(end -0.7874 0.4064)
			(stroke
				(width 0.1524)
				(type default)
			)
			(layer "B.SilkS")
		)
		(fp_line
			(start 0.67945 0.3048)
			(end 0.67945 -0.305054)
			(stroke
				(width 0.1)
				(type default)
			)
			(layer "B.Fab")
		)
		(fp_line
			(start 0.67945 -0.305054)
			(end 0.12065 -0.305054)
			(stroke
				(width 0.1)
				(type default)
			)
			(layer "B.Fab")
		)
		(fp_line
			(start 0.12065 0.3048)
			(end 0.67945 0.3048)
			(stroke
				(width 0.1)
				(type default)
			)
			(layer "B.Fab")
		)
		(fp_line
			(start 0.12065 0.2794)
			(end 0.12065 0.3048)
			(stroke
				(width 0.1)
				(type default)
			)
			(layer "B.Fab")
		)
		(fp_line
			(start 0.12065 -0.2794)
			(end -0.12065 -0.2794)
			(stroke
				(width 0.1)
				(type default)
			)
			(layer "B.Fab")
		)
		(fp_line
			(start 0.12065 -0.305054)
			(end 0.12065 -0.2794)
			(stroke
				(width 0.1)
				(type default)
			)
			(layer "B.Fab")
		)
		(fp_line
			(start -0.120396 0.3048)
			(end -0.120396 0.2794)
			(stroke
				(width 0.1)
				(type default)
			)
			(layer "B.Fab")
		)
		(fp_line
			(start -0.120396 0.2794)
			(end 0.12065 0.2794)
			(stroke
				(width 0.1)
				(type default)
			)
			(layer "B.Fab")
		)
		(fp_line
			(start -0.12065 -0.2794)
			(end -0.12065 -0.3048)
			(stroke
				(width 0.1)
				(type default)
			)
			(layer "B.Fab")
		)
		(fp_line
			(start -0.12065 -0.3048)
			(end -0.67945 -0.3048)
			(stroke
				(width 0.1)
				(type default)
			)
			(layer "B.Fab")
		)
		(fp_line
			(start -0.67945 0.3048)
			(end -0.120396 0.3048)
			(stroke
				(width 0.1)
				(type default)
			)
			(layer "B.Fab")
		)
		(fp_line
			(start -0.67945 -0.3048)
			(end -0.67945 0.3048)
			(stroke
				(width 0.1)
				(type default)
			)
			(layer "B.Fab")
		)
		(pad "1" smd circle
			(at 0.40005 0)
			(size 0 0)
			(layers "B.Cu" "B.Mask" "B.Paste")
			(net "PWRGD_CHK_CPU0_DIMM")
		)
		(pad "2" smd circle
			(at -0.40005 0)
			(size 0 0)
			(layers "B.Cu" "B.Mask" "B.Paste")
			(net "PWRGD_CHGL_CPU0")
		)
	)
	(footprint ""
		(layer "B.Cu")
		(at 372.937278 -139.440158)
		(property "Reference" "C467"
			(at 0 0 0)
			(layer "B.SilkS")
			(hide yes)
			(effects
				(font
					(size 1.27 1.27)
				)
				(justify mirror)
			)
		)
		(property "Value" ""
			(at 0 0 0)
			(layer "B.Fab")
			(effects
				(font
					(size 1.27 1.27)
				)
				(justify mirror)
			)
		)
		(duplicate_pad_numbers_are_jumpers no)
		(fp_line
			(start -0.7874 -0.4064)
			(end -0.7874 0.4064)
			(stroke
				(width 0.1524)
				(type default)
			)
			(layer "B.SilkS")
		)
		(fp_line
			(start -0.7874 0.4064)
			(end 0.7874 0.4064)
			(stroke
				(width 0.1524)
				(type default)
			)
			(layer "B.SilkS")
		)
		(fp_line
			(start 0.7874 -0.4064)
			(end -0.7874 -0.4064)
			(stroke
				(width 0.1524)
				(type default)
			)
			(layer "B.SilkS")
		)
		(fp_line
			(start 0.7874 0.4064)
			(end 0.7874 -0.4064)
			(stroke
				(width 0.1524)
				(type default)
			)
			(layer "B.SilkS")
		)
		(fp_line
			(start -0.67945 -0.3048)
			(end -0.67945 0.3048)
			(stroke
				(width 0.1)
				(type default)
			)
			(layer "B.Fab")
		)
		(fp_line
			(start -0.67945 0.3048)
			(end -0.120396 0.3048)
			(stroke
				(width 0.1)
				(type default)
			)
			(layer "B.Fab")
		)
		(fp_line
			(start -0.12065 -0.3048)
			(end -0.67945 -0.3048)
			(stroke
				(width 0.1)
				(type default)
			)
			(layer "B.Fab")
		)
		(fp_line
			(start -0.12065 -0.2794)
			(end -0.12065 -0.3048)
			(stroke
				(width 0.1)
				(type default)
			)
			(layer "B.Fab")
		)
		(fp_line
			(start -0.120396 0.2794)
			(end 0.12065 0.2794)
			(stroke
				(width 0.1)
				(type default)
			)
			(layer "B.Fab")
		)
		(fp_line
			(start -0.120396 0.3048)
			(end -0.120396 0.2794)
			(stroke
				(width 0.1)
				(type default)
			)
			(layer "B.Fab")
		)
		(fp_line
			(start 0.12065 -0.305054)
			(end 0.12065 -0.2794)
			(stroke
				(width 0.1)
				(type default)
			)
			(layer "B.Fab")
		)
		(fp_line
			(start 0.12065 -0.2794)
			(end -0.12065 -0.2794)
			(stroke
				(width 0.1)
				(type default)
			)
			(layer "B.Fab")
		)
		(fp_line
			(start 0.12065 0.2794)
			(end 0.12065 0.3048)
			(stroke
				(width 0.1)
				(type default)
			)
			(layer "B.Fab")
		)
		(fp_line
			(start 0.12065 0.3048)
			(end 0.67945 0.3048)
			(stroke
				(width 0.1)
				(type default)
			)
			(layer "B.Fab")
		)
		(fp_line
			(start 0.67945 -0.305054)
			(end 0.12065 -0.305054)
			(stroke
				(width 0.1)
				(type default)
			)
			(layer "B.Fab")
		)
		(fp_line
			(start 0.67945 0.3048)
			(end 0.67945 -0.305054)
			(stroke
				(width 0.1)
				(type default)
			)
			(layer "B.Fab")
		)
		(pad "1" smd circle
			(at 0.40005 0 180)
			(size 0 0)
			(layers "B.Cu" "B.Mask" "B.Paste")
			(net "PWRGD_PVDDCR_CPU0_P0_R")
		)
		(pad "2" smd circle
			(at -0.40005 0 180)
			(size 0 0)
			(layers "B.Cu" "B.Mask" "B.Paste")
			(net "GND")
		)
	)
	(footprint ""
		(layer "B.Cu")
		(at 152.265634 -201.977752 -90)
		(property "Reference" "C233"
			(at 0 0 90)
			(layer "B.SilkS")
			(hide yes)
			(effects
				(font
					(size 1.27 1.27)
				)
				(justify mirror)
			)
		)
		(property "Value" ""
			(at 0 0 90)
			(layer "B.Fab")
			(effects
				(font
					(size 1.27 1.27)
				)
				(justify mirror)
			)
		)
		(duplicate_pad_numbers_are_jumpers no)
		(fp_line
			(start -0.7874 0.4064)
			(end 0.7874 0.4064)
			(stroke
				(width 0.1524)
				(type default)
			)
			(layer "B.SilkS")
		)
		(fp_line
			(start 0.7874 0.4064)
			(end 0.7874 -0.4064)
			(stroke
				(width 0.1524)
				(type default)
			)
			(layer "B.SilkS")
		)
		(fp_line
			(start -0.7874 -0.4064)
			(end -0.7874 0.4064)
			(stroke
				(width 0.1524)
				(type default)
			)
			(layer "B.SilkS")
		)
		(fp_line
			(start 0.7874 -0.4064)
			(end -0.7874 -0.4064)
			(stroke
				(width 0.1524)
				(type default)
			)
			(layer "B.SilkS")
		)
		(fp_line
			(start -0.67945 0.3048)
			(end -0.120396 0.3048)
			(stroke
				(width 0.1)
				(type default)
			)
			(layer "B.Fab")
		)
		(fp_line
			(start -0.120396 0.3048)
			(end -0.120396 0.2794)
			(stroke
				(width 0.1)
				(type default)
			)
			(layer "B.Fab")
		)
		(fp_line
			(start 0.12065 0.3048)
			(end 0.67945 0.3048)
			(stroke
				(width 0.1)
				(type default)
			)
			(layer "B.Fab")
		)
		(fp_line
			(start 0.67945 0.3048)
			(end 0.67945 -0.305054)
			(stroke
				(width 0.1)
				(type default)
			)
			(layer "B.Fab")
		)
		(fp_line
			(start -0.120396 0.2794)
			(end 0.12065 0.2794)
			(stroke
				(width 0.1)
				(type default)
			)
			(layer "B.Fab")
		)
		(fp_line
			(start 0.12065 0.2794)
			(end 0.12065 0.3048)
			(stroke
				(width 0.1)
				(type default)
			)
			(layer "B.Fab")
		)
		(fp_line
			(start -0.12065 -0.2794)
			(end -0.12065 -0.3048)
			(stroke
				(width 0.1)
				(type default)
			)
			(layer "B.Fab")
		)
		(fp_line
			(start 0.12065 -0.2794)
			(end -0.12065 -0.2794)
			(stroke
				(width 0.1)
				(type default)
			)
			(layer "B.Fab")
		)
		(fp_line
			(start -0.67945 -0.3048)
			(end -0.67945 0.3048)
			(stroke
				(width 0.1)
				(type default)
			)
			(layer "B.Fab")
		)
		(fp_line
			(start -0.12065 -0.3048)
			(end -0.67945 -0.3048)
			(stroke
				(width 0.1)
				(type default)
			)
			(layer "B.Fab")
		)
		(fp_line
			(start 0.12065 -0.305054)
			(end 0.12065 -0.2794)
			(stroke
				(width 0.1)
				(type default)
			)
			(layer "B.Fab")
		)
		(fp_line
			(start 0.67945 -0.305054)
			(end 0.12065 -0.305054)
			(stroke
				(width 0.1)
				(type default)
			)
			(layer "B.Fab")
		)
		(pad "1" smd circle
			(at 0.40005 0 90)
			(size 0 0)
			(layers "B.Cu" "B.Mask" "B.Paste")
			(net "JTAG_CPU1_TCK")
		)
		(pad "2" smd circle
			(at -0.40005 0 90)
			(size 0 0)
			(layers "B.Cu" "B.Mask" "B.Paste")
			(net "GND")
		)
	)
	(footprint ""
		(layer "B.Cu")
		(at 194.604132 -192.66027 180)
		(property "Reference" "C547"
			(at 0 0 0)
			(layer "B.SilkS")
			(hide yes)
			(effects
				(font
					(size 1.27 1.27)
				)
				(justify mirror)
			)
		)
		(property "Value" ""
			(at 0 0 0)
			(layer "B.Fab")
			(effects
				(font
					(size 1.27 1.27)
				)
				(justify mirror)
			)
		)
		(duplicate_pad_numbers_are_jumpers no)
		(fp_line
			(start 1.524 0.762)
			(end 1.524 -0.762)
			(stroke
				(width 0.1524)
				(type default)
			)
			(layer "B.SilkS")
		)
		(fp_line
			(start 1.524 -0.762)
			(end -1.524 -0.762)
			(stroke
				(width 0.1524)
				(type default)
			)
			(layer "B.SilkS")
		)
		(fp_line
			(start -1.524 0.762)
			(end 1.524 0.762)
			(stroke
				(width 0.1524)
				(type default)
			)
			(layer "B.SilkS")
		)
		(fp_line
			(start -1.524 -0.762)
			(end -1.524 0.762)
			(stroke
				(width 0.1524)
				(type default)
			)
			(layer "B.SilkS")
		)
		(fp_line
			(start 1.1049 0.724916)
			(end -1.1049 0.724916)
			(stroke
				(width 0.1)
				(type default)
			)
			(layer "B.Fab")
		)
		(fp_line
			(start 1.1049 -0.724916)
			(end 1.1049 0.724916)
			(stroke
				(width 0.1)
				(type default)
			)
			(layer "B.Fab")
		)
		(fp_line
			(start -1.1049 0.724916)
			(end -1.1049 -0.724916)
			(stroke
				(width 0.1)
				(type default)
			)
			(layer "B.Fab")
		)
		(fp_line
			(start -1.1049 -0.724916)
			(end 1.1049 -0.724916)
			(stroke
				(width 0.1)
				(type default)
			)
			(layer "B.Fab")
		)
		(pad "1" smd rect
			(at 0.889 0 180)
			(size 1.016 1.27)
			(layers "B.Cu" "B.Mask" "B.Paste")
			(net "P12V_MEM_CPU1")
		)
		(pad "2" smd rect
			(at -0.889 0 180)
			(size 1.016 1.27)
			(layers "B.Cu" "B.Mask" "B.Paste")
			(net "GND")
		)
	)
	(footprint ""
		(layer "B.Cu")
		(at 314.475876 -66.708782 90)
		(property "Reference" "R3102"
			(at 0 0 90)
			(layer "B.SilkS")
			(hide yes)
			(effects
				(font
					(size 1.27 1.27)
				)
				(justify mirror)
			)
		)
		(property "Value" ""
			(at 0 0 90)
			(layer "B.Fab")
			(effects
				(font
					(size 1.27 1.27)
				)
				(justify mirror)
			)
		)
		(duplicate_pad_numbers_are_jumpers no)
		(fp_line
			(start 0.7874 -0.4064)
			(end -0.7874 -0.4064)
			(stroke
				(width 0.1524)
				(type default)
			)
			(layer "B.SilkS")
		)
		(fp_line
			(start -0.7874 -0.4064)
			(end -0.7874 0.4064)
			(stroke
				(width 0.1524)
				(type default)
			)
			(layer "B.SilkS")
		)
		(fp_line
			(start 0.7874 0.4064)
			(end 0.7874 -0.4064)
			(stroke
				(width 0.1524)
				(type default)
			)
			(layer "B.SilkS")
		)
		(fp_line
			(start -0.7874 0.4064)
			(end 0.7874 0.4064)
			(stroke
				(width 0.1524)
				(type default)
			)
			(layer "B.SilkS")
		)
		(fp_line
			(start 0.67945 -0.305054)
			(end 0.12065 -0.305054)
			(stroke
				(width 0.1)
				(type default)
			)
			(layer "B.Fab")
		)
		(fp_line
			(start 0.12065 -0.305054)
			(end 0.12065 -0.2794)
			(stroke
				(width 0.1)
				(type default)
			)
			(layer "B.Fab")
		)
		(fp_line
			(start -0.12065 -0.3048)
			(end -0.67945 -0.3048)
			(stroke
				(width 0.1)
				(type default)
			)
			(layer "B.Fab")
		)
		(fp_line
			(start -0.67945 -0.3048)
			(end -0.67945 0.3048)
			(stroke
				(width 0.1)
				(type default)
			)
			(layer "B.Fab")
		)
		(fp_line
			(start 0.12065 -0.2794)
			(end -0.12065 -0.2794)
			(stroke
				(width 0.1)
				(type default)
			)
			(layer "B.Fab")
		)
		(fp_line
			(start -0.12065 -0.2794)
			(end -0.12065 -0.3048)
			(stroke
				(width 0.1)
				(type default)
			)
			(layer "B.Fab")
		)
		(fp_line
			(start 0.12065 0.2794)
			(end 0.12065 0.3048)
			(stroke
				(width 0.1)
				(type default)
			)
			(layer "B.Fab")
		)
		(fp_line
			(start -0.120396 0.2794)
			(end 0.12065 0.2794)
			(stroke
				(width 0.1)
				(type default)
			)
			(layer "B.Fab")
		)
		(fp_line
			(start 0.67945 0.3048)
			(end 0.67945 -0.305054)
			(stroke
				(width 0.1)
				(type default)
			)
			(layer "B.Fab")
		)
		(fp_line
			(start 0.12065 0.3048)
			(end 0.67945 0.3048)
			(stroke
				(width 0.1)
				(type default)
			)
			(layer "B.Fab")
		)
		(fp_line
			(start -0.120396 0.3048)
			(end -0.120396 0.2794)
			(stroke
				(width 0.1)
				(type default)
			)
			(layer "B.Fab")
		)
		(fp_line
			(start -0.67945 0.3048)
			(end -0.120396 0.3048)
			(stroke
				(width 0.1)
				(type default)
			)
			(layer "B.Fab")
		)
		(pad "1" smd circle
			(at 0.40005 0 270)
			(size 0 0)
			(layers "B.Cu" "B.Mask" "B.Paste")
			(net "LED_P5V")
		)
		(pad "2" smd circle
			(at -0.40005 0 270)
			(size 0 0)
			(layers "B.Cu" "B.Mask" "B.Paste")
			(net "P5V")
		)
	)
	(footprint ""
		(layer "B.Cu")
		(at 162.618928 -390.560052 90)
		(property "Reference" "C424"
			(at 0 0 90)
			(layer "B.SilkS")
			(hide yes)
			(effects
				(font
					(size 1.27 1.27)
				)
				(justify mirror)
			)
		)
		(property "Value" ""
			(at 0 0 90)
			(layer "B.Fab")
			(effects
				(font
					(size 1.27 1.27)
				)
				(justify mirror)
			)
		)
		(duplicate_pad_numbers_are_jumpers no)
		(fp_line
			(start 0.7874 -0.4064)
			(end -0.7874 -0.4064)
			(stroke
				(width 0.1524)
				(type default)
			)
			(layer "B.SilkS")
		)
		(fp_line
			(start -0.7874 -0.4064)
			(end -0.7874 0.4064)
			(stroke
				(width 0.1524)
				(type default)
			)
			(layer "B.SilkS")
		)
		(fp_line
			(start 0.7874 0.4064)
			(end 0.7874 -0.4064)
			(stroke
				(width 0.1524)
				(type default)
			)
			(layer "B.SilkS")
		)
		(fp_line
			(start -0.7874 0.4064)
			(end 0.7874 0.4064)
			(stroke
				(width 0.1524)
				(type default)
			)
			(layer "B.SilkS")
		)
		(fp_line
			(start 0.67945 -0.305054)
			(end 0.12065 -0.305054)
			(stroke
				(width 0.1)
				(type default)
			)
			(layer "B.Fab")
		)
		(fp_line
			(start 0.12065 -0.305054)
			(end 0.12065 -0.2794)
			(stroke
				(width 0.1)
				(type default)
			)
			(layer "B.Fab")
		)
		(fp_line
			(start -0.12065 -0.3048)
			(end -0.67945 -0.3048)
			(stroke
				(width 0.1)
				(type default)
			)
			(layer "B.Fab")
		)
		(fp_line
			(start -0.67945 -0.3048)
			(end -0.67945 0.3048)
			(stroke
				(width 0.1)
				(type default)
			)
			(layer "B.Fab")
		)
		(fp_line
			(start 0.12065 -0.2794)
			(end -0.12065 -0.2794)
			(stroke
				(width 0.1)
				(type default)
			)
			(layer "B.Fab")
		)
		(fp_line
			(start -0.12065 -0.2794)
			(end -0.12065 -0.3048)
			(stroke
				(width 0.1)
				(type default)
			)
			(layer "B.Fab")
		)
		(fp_line
			(start 0.12065 0.2794)
			(end 0.12065 0.3048)
			(stroke
				(width 0.1)
				(type default)
			)
			(layer "B.Fab")
		)
		(fp_line
			(start -0.120396 0.2794)
			(end 0.12065 0.2794)
			(stroke
				(width 0.1)
				(type default)
			)
			(layer "B.Fab")
		)
		(fp_line
			(start 0.67945 0.3048)
			(end 0.67945 -0.305054)
			(stroke
				(width 0.1)
				(type default)
			)
			(layer "B.Fab")
		)
		(fp_line
			(start 0.12065 0.3048)
			(end 0.67945 0.3048)
			(stroke
				(width 0.1)
				(type default)
			)
			(layer "B.Fab")
		)
		(fp_line
			(start -0.120396 0.3048)
			(end -0.120396 0.2794)
			(stroke
				(width 0.1)
				(type default)
			)
			(layer "B.Fab")
		)
		(fp_line
			(start -0.67945 0.3048)
			(end -0.120396 0.3048)
			(stroke
				(width 0.1)
				(type default)
			)
			(layer "B.Fab")
		)
		(pad "1" smd circle
			(at 0.40005 0 270)
			(size 0 0)
			(layers "B.Cu" "B.Mask" "B.Paste")
			(net "P0V9_CPU1_RT2_2A")
		)
		(pad "2" smd circle
			(at -0.40005 0 270)
			(size 0 0)
			(layers "B.Cu" "B.Mask" "B.Paste")
			(net "GND")
		)
	)
	(footprint ""
		(layer "B.Cu")
		(at 121.691146 -390.560052 90)
		(property "Reference" "C489"
			(at 0 0 90)
			(layer "B.SilkS")
			(hide yes)
			(effects
				(font
					(size 1.27 1.27)
				)
				(justify mirror)
			)
		)
		(property "Value" ""
			(at 0 0 90)
			(layer "B.Fab")
			(effects
				(font
					(size 1.27 1.27)
				)
				(justify mirror)
			)
		)
		(duplicate_pad_numbers_are_jumpers no)
		(fp_line
			(start 0.7874 -0.4064)
			(end -0.7874 -0.4064)
			(stroke
				(width 0.1524)
				(type default)
			)
			(layer "B.SilkS")
		)
		(fp_line
			(start -0.7874 -0.4064)
			(end -0.7874 0.4064)
			(stroke
				(width 0.1524)
				(type default)
			)
			(layer "B.SilkS")
		)
		(fp_line
			(start 0.7874 0.4064)
			(end 0.7874 -0.4064)
			(stroke
				(width 0.1524)
				(type default)
			)
			(layer "B.SilkS")
		)
		(fp_line
			(start -0.7874 0.4064)
			(end 0.7874 0.4064)
			(stroke
				(width 0.1524)
				(type default)
			)
			(layer "B.SilkS")
		)
		(fp_line
			(start 0.67945 -0.305054)
			(end 0.12065 -0.305054)
			(stroke
				(width 0.1)
				(type default)
			)
			(layer "B.Fab")
		)
		(fp_line
			(start 0.12065 -0.305054)
			(end 0.12065 -0.2794)
			(stroke
				(width 0.1)
				(type default)
			)
			(layer "B.Fab")
		)
		(fp_line
			(start -0.12065 -0.3048)
			(end -0.67945 -0.3048)
			(stroke
				(width 0.1)
				(type default)
			)
			(layer "B.Fab")
		)
		(fp_line
			(start -0.67945 -0.3048)
			(end -0.67945 0.3048)
			(stroke
				(width 0.1)
				(type default)
			)
			(layer "B.Fab")
		)
		(fp_line
			(start 0.12065 -0.2794)
			(end -0.12065 -0.2794)
			(stroke
				(width 0.1)
				(type default)
			)
			(layer "B.Fab")
		)
		(fp_line
			(start -0.12065 -0.2794)
			(end -0.12065 -0.3048)
			(stroke
				(width 0.1)
				(type default)
			)
			(layer "B.Fab")
		)
		(fp_line
			(start 0.12065 0.2794)
			(end 0.12065 0.3048)
			(stroke
				(width 0.1)
				(type default)
			)
			(layer "B.Fab")
		)
		(fp_line
			(start -0.120396 0.2794)
			(end 0.12065 0.2794)
			(stroke
				(width 0.1)
				(type default)
			)
			(layer "B.Fab")
		)
		(fp_line
			(start 0.67945 0.3048)
			(end 0.67945 -0.305054)
			(stroke
				(width 0.1)
				(type default)
			)
			(layer "B.Fab")
		)
		(fp_line
			(start 0.12065 0.3048)
			(end 0.67945 0.3048)
			(stroke
				(width 0.1)
				(type default)
			)
			(layer "B.Fab")
		)
		(fp_line
			(start -0.120396 0.3048)
			(end -0.120396 0.2794)
			(stroke
				(width 0.1)
				(type default)
			)
			(layer "B.Fab")
		)
		(fp_line
			(start -0.67945 0.3048)
			(end -0.120396 0.3048)
			(stroke
				(width 0.1)
				(type default)
			)
			(layer "B.Fab")
		)
		(pad "1" smd circle
			(at 0.40005 0 270)
			(size 0 0)
			(layers "B.Cu" "B.Mask" "B.Paste")
			(net "P0V9_CPU1_RT_2D")
		)
		(pad "2" smd circle
			(at -0.40005 0 270)
			(size 0 0)
			(layers "B.Cu" "B.Mask" "B.Paste")
			(net "GND")
		)
	)
	(footprint ""
		(layer "B.Cu")
		(at 52.318412 -388.011162 -90)
		(property "Reference" "C191"
			(at 0 0 90)
			(layer "B.SilkS")
			(hide yes)
			(effects
				(font
					(size 1.27 1.27)
				)
				(justify mirror)
			)
		)
		(property "Value" ""
			(at 0 0 90)
			(layer "B.Fab")
			(effects
				(font
					(size 1.27 1.27)
				)
				(justify mirror)
			)
		)
		(duplicate_pad_numbers_are_jumpers no)
		(fp_line
			(start -0.299974 0.150114)
			(end 0.299974 0.150114)
			(stroke
				(width 0.1)
				(type default)
			)
			(layer "B.Fab")
		)
		(fp_line
			(start 0.299974 0.150114)
			(end 0.299974 -0.150114)
			(stroke
				(width 0.1)
				(type default)
			)
			(layer "B.Fab")
		)
		(fp_line
			(start -0.299974 -0.150114)
			(end -0.299974 0.150114)
			(stroke
				(width 0.1)
				(type default)
			)
			(layer "B.Fab")
		)
		(fp_line
			(start 0.299974 -0.150114)
			(end -0.299974 -0.150114)
			(stroke
				(width 0.1)
				(type default)
			)
			(layer "B.Fab")
		)
		(pad "1" smd rect
			(at 0.2667 0 90)
			(size 0.3048 0.381)
			(layers "B.Cu" "B.Mask" "B.Paste")
			(net "P0V9_CPU1_RT0_2A_2D")
		)
		(pad "2" smd rect
			(at -0.2667 0 90)
			(size 0.3048 0.381)
			(layers "B.Cu" "B.Mask" "B.Paste")
			(net "GND")
		)
	)
	(footprint ""
		(layer "B.Cu")
		(at 54.665118 -346.788994 90)
		(property "Reference" "PC448_1"
			(at 0 0 90)
			(layer "B.SilkS")
			(hide yes)
			(effects
				(font
					(size 1.27 1.27)
				)
				(justify mirror)
			)
		)
		(property "Value" ""
			(at 0 0 90)
			(layer "B.Fab")
			(effects
				(font
					(size 1.27 1.27)
				)
				(justify mirror)
			)
		)
		(duplicate_pad_numbers_are_jumpers no)
		(fp_line
			(start 1.524 -0.762)
			(end -1.524 -0.762)
			(stroke
				(width 0.1524)
				(type default)
			)
			(layer "B.SilkS")
		)
		(fp_line
			(start -1.524 -0.762)
			(end -1.524 0.762)
			(stroke
				(width 0.1524)
				(type default)
			)
			(layer "B.SilkS")
		)
		(fp_line
			(start 1.524 0.762)
			(end 1.524 -0.762)
			(stroke
				(width 0.1524)
				(type default)
			)
			(layer "B.SilkS")
		)
		(fp_line
			(start -1.524 0.762)
			(end 1.524 0.762)
			(stroke
				(width 0.1524)
				(type default)
			)
			(layer "B.SilkS")
		)
		(fp_line
			(start 1.1049 -0.724916)
			(end 1.1049 0.724916)
			(stroke
				(width 0.1)
				(type default)
			)
			(layer "B.Fab")
		)
		(fp_line
			(start -1.1049 -0.724916)
			(end 1.1049 -0.724916)
			(stroke
				(width 0.1)
				(type default)
			)
			(layer "B.Fab")
		)
		(fp_line
			(start 1.1049 0.724916)
			(end -1.1049 0.724916)
			(stroke
				(width 0.1)
				(type default)
			)
			(layer "B.Fab")
		)
		(fp_line
			(start -1.1049 0.724916)
			(end -1.1049 -0.724916)
			(stroke
				(width 0.1)
				(type default)
			)
			(layer "B.Fab")
		)
		(pad "1" smd rect
			(at 0.889 0 90)
			(size 1.016 1.27)
			(layers "B.Cu" "B.Mask" "B.Paste")
			(net "SW_P12V_AUX_PVDDIO_P1_FLT")
		)
		(pad "2" smd rect
			(at -0.889 0 90)
			(size 1.016 1.27)
			(layers "B.Cu" "B.Mask" "B.Paste")
			(net "GND")
		)
	)
	(footprint ""
		(layer "B.Cu")
		(at 428.98695 -40.071548 180)
		(property "Reference" "R1262"
			(at 0 0 0)
			(layer "B.SilkS")
			(hide yes)
			(effects
				(font
					(size 1.27 1.27)
				)
				(justify mirror)
			)
		)
		(property "Value" ""
			(at 0 0 0)
			(layer "B.Fab")
			(effects
				(font
					(size 1.27 1.27)
				)
				(justify mirror)
			)
		)
		(duplicate_pad_numbers_are_jumpers no)
		(fp_line
			(start 0.7874 0.4064)
			(end 0.7874 -0.4064)
			(stroke
				(width 0.1524)
				(type default)
			)
			(layer "B.SilkS")
		)
		(fp_line
			(start 0.7874 -0.4064)
			(end -0.7874 -0.4064)
			(stroke
				(width 0.1524)
				(type default)
			)
			(layer "B.SilkS")
		)
		(fp_line
			(start -0.7874 0.4064)
			(end 0.7874 0.4064)
			(stroke
				(width 0.1524)
				(type default)
			)
			(layer "B.SilkS")
		)
		(fp_line
			(start -0.7874 -0.4064)
			(end -0.7874 0.4064)
			(stroke
				(width 0.1524)
				(type default)
			)
			(layer "B.SilkS")
		)
		(fp_line
			(start 0.67945 0.3048)
			(end 0.67945 -0.305054)
			(stroke
				(width 0.1)
				(type default)
			)
			(layer "B.Fab")
		)
		(fp_line
			(start 0.67945 -0.305054)
			(end 0.12065 -0.305054)
			(stroke
				(width 0.1)
				(type default)
			)
			(layer "B.Fab")
		)
		(fp_line
			(start 0.12065 0.3048)
			(end 0.67945 0.3048)
			(stroke
				(width 0.1)
				(type default)
			)
			(layer "B.Fab")
		)
		(fp_line
			(start 0.12065 0.2794)
			(end 0.12065 0.3048)
			(stroke
				(width 0.1)
				(type default)
			)
			(layer "B.Fab")
		)
		(fp_line
			(start 0.12065 -0.2794)
			(end -0.12065 -0.2794)
			(stroke
				(width 0.1)
				(type default)
			)
			(layer "B.Fab")
		)
		(fp_line
			(start 0.12065 -0.305054)
			(end 0.12065 -0.2794)
			(stroke
				(width 0.1)
				(type default)
			)
			(layer "B.Fab")
		)
		(fp_line
			(start -0.120396 0.3048)
			(end -0.120396 0.2794)
			(stroke
				(width 0.1)
				(type default)
			)
			(layer "B.Fab")
		)
		(fp_line
			(start -0.120396 0.2794)
			(end 0.12065 0.2794)
			(stroke
				(width 0.1)
				(type default)
			)
			(layer "B.Fab")
		)
		(fp_line
			(start -0.12065 -0.2794)
			(end -0.12065 -0.3048)
			(stroke
				(width 0.1)
				(type default)
			)
			(layer "B.Fab")
		)
		(fp_line
			(start -0.12065 -0.3048)
			(end -0.67945 -0.3048)
			(stroke
				(width 0.1)
				(type default)
			)
			(layer "B.Fab")
		)
		(fp_line
			(start -0.67945 0.3048)
			(end -0.120396 0.3048)
			(stroke
				(width 0.1)
				(type default)
			)
			(layer "B.Fab")
		)
		(fp_line
			(start -0.67945 -0.3048)
			(end -0.67945 0.3048)
			(stroke
				(width 0.1)
				(type default)
			)
			(layer "B.Fab")
		)
		(pad "1" smd circle
			(at 0.40005 0)
			(size 0 0)
			(layers "B.Cu" "B.Mask" "B.Paste")
			(net "P1V8_AUX")
		)
		(pad "2" smd circle
			(at -0.40005 0)
			(size 0 0)
			(layers "B.Cu" "B.Mask" "B.Paste")
			(net "BMC_JTAG_SEL")
		)
	)
	(footprint ""
		(layer "B.Cu")
		(at 302.133 -356.997 180)
		(property "Reference" "R8048"
			(at 0 0 0)
			(layer "B.SilkS")
			(hide yes)
			(effects
				(font
					(size 1.27 1.27)
				)
				(justify mirror)
			)
		)
		(property "Value" ""
			(at 0 0 0)
			(layer "B.Fab")
			(effects
				(font
					(size 1.27 1.27)
				)
				(justify mirror)
			)
		)
		(duplicate_pad_numbers_are_jumpers no)
		(fp_line
			(start 0.7874 0.4064)
			(end 0.7874 -0.4064)
			(stroke
				(width 0.1524)
				(type default)
			)
			(layer "B.SilkS")
		)
		(fp_line
			(start 0.7874 -0.4064)
			(end -0.7874 -0.4064)
			(stroke
				(width 0.1524)
				(type default)
			)
			(layer "B.SilkS")
		)
		(fp_line
			(start -0.7874 0.4064)
			(end 0.7874 0.4064)
			(stroke
				(width 0.1524)
				(type default)
			)
			(layer "B.SilkS")
		)
		(fp_line
			(start -0.7874 -0.4064)
			(end -0.7874 0.4064)
			(stroke
				(width 0.1524)
				(type default)
			)
			(layer "B.SilkS")
		)
		(fp_line
			(start 0.67945 0.3048)
			(end 0.67945 -0.305054)
			(stroke
				(width 0.1)
				(type default)
			)
			(layer "B.Fab")
		)
		(fp_line
			(start 0.67945 -0.305054)
			(end 0.12065 -0.305054)
			(stroke
				(width 0.1)
				(type default)
			)
			(layer "B.Fab")
		)
		(fp_line
			(start 0.12065 0.3048)
			(end 0.67945 0.3048)
			(stroke
				(width 0.1)
				(type default)
			)
			(layer "B.Fab")
		)
		(fp_line
			(start 0.12065 0.2794)
			(end 0.12065 0.3048)
			(stroke
				(width 0.1)
				(type default)
			)
			(layer "B.Fab")
		)
		(fp_line
			(start 0.12065 -0.2794)
			(end -0.12065 -0.2794)
			(stroke
				(width 0.1)
				(type default)
			)
			(layer "B.Fab")
		)
		(fp_line
			(start 0.12065 -0.305054)
			(end 0.12065 -0.2794)
			(stroke
				(width 0.1)
				(type default)
			)
			(layer "B.Fab")
		)
		(fp_line
			(start -0.120396 0.3048)
			(end -0.120396 0.2794)
			(stroke
				(width 0.1)
				(type default)
			)
			(layer "B.Fab")
		)
		(fp_line
			(start -0.120396 0.2794)
			(end 0.12065 0.2794)
			(stroke
				(width 0.1)
				(type default)
			)
			(layer "B.Fab")
		)
		(fp_line
			(start -0.12065 -0.2794)
			(end -0.12065 -0.3048)
			(stroke
				(width 0.1)
				(type default)
			)
			(layer "B.Fab")
		)
		(fp_line
			(start -0.12065 -0.3048)
			(end -0.67945 -0.3048)
			(stroke
				(width 0.1)
				(type default)
			)
			(layer "B.Fab")
		)
		(fp_line
			(start -0.67945 0.3048)
			(end -0.120396 0.3048)
			(stroke
				(width 0.1)
				(type default)
			)
			(layer "B.Fab")
		)
		(fp_line
			(start -0.67945 -0.3048)
			(end -0.67945 0.3048)
			(stroke
				(width 0.1)
				(type default)
			)
			(layer "B.Fab")
		)
		(pad "1" smd circle
			(at 0.40005 0)
			(size 0 0)
			(layers "B.Cu" "B.Mask" "B.Paste")
			(net "PVDD18_S5_P0")
		)
		(pad "2" smd circle
			(at -0.40005 0)
			(size 0 0)
			(layers "B.Cu" "B.Mask" "B.Paste")
			(net "SVID_PVDDCR_CPU1_P0_SVC_R")
		)
	)
	(footprint ""
		(layer "B.Cu")
		(at 395.123162 -200.763632 90)
		(property "Reference" "R6135"
			(at 0 0 90)
			(layer "B.SilkS")
			(hide yes)
			(effects
				(font
					(size 1.27 1.27)
				)
				(justify mirror)
			)
		)
		(property "Value" ""
			(at 0 0 90)
			(layer "B.Fab")
			(effects
				(font
					(size 1.27 1.27)
				)
				(justify mirror)
			)
		)
		(duplicate_pad_numbers_are_jumpers no)
		(fp_line
			(start 0.7874 -0.4064)
			(end -0.7874 -0.4064)
			(stroke
				(width 0.1524)
				(type default)
			)
			(layer "B.SilkS")
		)
		(fp_line
			(start -0.7874 -0.4064)
			(end -0.7874 0.4064)
			(stroke
				(width 0.1524)
				(type default)
			)
			(layer "B.SilkS")
		)
		(fp_line
			(start 0.7874 0.4064)
			(end 0.7874 -0.4064)
			(stroke
				(width 0.1524)
				(type default)
			)
			(layer "B.SilkS")
		)
		(fp_line
			(start -0.7874 0.4064)
			(end 0.7874 0.4064)
			(stroke
				(width 0.1524)
				(type default)
			)
			(layer "B.SilkS")
		)
		(fp_line
			(start 0.67945 -0.305054)
			(end 0.12065 -0.305054)
			(stroke
				(width 0.1)
				(type default)
			)
			(layer "B.Fab")
		)
		(fp_line
			(start 0.12065 -0.305054)
			(end 0.12065 -0.2794)
			(stroke
				(width 0.1)
				(type default)
			)
			(layer "B.Fab")
		)
		(fp_line
			(start -0.12065 -0.3048)
			(end -0.67945 -0.3048)
			(stroke
				(width 0.1)
				(type default)
			)
			(layer "B.Fab")
		)
		(fp_line
			(start -0.67945 -0.3048)
			(end -0.67945 0.3048)
			(stroke
				(width 0.1)
				(type default)
			)
			(layer "B.Fab")
		)
		(fp_line
			(start 0.12065 -0.2794)
			(end -0.12065 -0.2794)
			(stroke
				(width 0.1)
				(type default)
			)
			(layer "B.Fab")
		)
		(fp_line
			(start -0.12065 -0.2794)
			(end -0.12065 -0.3048)
			(stroke
				(width 0.1)
				(type default)
			)
			(layer "B.Fab")
		)
		(fp_line
			(start 0.12065 0.2794)
			(end 0.12065 0.3048)
			(stroke
				(width 0.1)
				(type default)
			)
			(layer "B.Fab")
		)
		(fp_line
			(start -0.120396 0.2794)
			(end 0.12065 0.2794)
			(stroke
				(width 0.1)
				(type default)
			)
			(layer "B.Fab")
		)
		(fp_line
			(start 0.67945 0.3048)
			(end 0.67945 -0.305054)
			(stroke
				(width 0.1)
				(type default)
			)
			(layer "B.Fab")
		)
		(fp_line
			(start 0.12065 0.3048)
			(end 0.67945 0.3048)
			(stroke
				(width 0.1)
				(type default)
			)
			(layer "B.Fab")
		)
		(fp_line
			(start -0.120396 0.3048)
			(end -0.120396 0.2794)
			(stroke
				(width 0.1)
				(type default)
			)
			(layer "B.Fab")
		)
		(fp_line
			(start -0.67945 0.3048)
			(end -0.120396 0.3048)
			(stroke
				(width 0.1)
				(type default)
			)
			(layer "B.Fab")
		)
		(pad "1" smd circle
			(at 0.40005 0 270)
			(size 0 0)
			(layers "B.Cu" "B.Mask" "B.Paste")
			(net "FAB_REV_ID0")
		)
		(pad "2" smd circle
			(at -0.40005 0 270)
			(size 0 0)
			(layers "B.Cu" "B.Mask" "B.Paste")
			(net "GND")
		)
	)
	(footprint ""
		(layer "B.Cu")
		(at 135.919718 -9.02589 -90)
		(property "Reference" "R321"
			(at 0 0 90)
			(layer "B.SilkS")
			(hide yes)
			(effects
				(font
					(size 1.27 1.27)
				)
				(justify mirror)
			)
		)
		(property "Value" ""
			(at 0 0 90)
			(layer "B.Fab")
			(effects
				(font
					(size 1.27 1.27)
				)
				(justify mirror)
			)
		)
		(duplicate_pad_numbers_are_jumpers no)
		(fp_line
			(start -0.7874 0.4064)
			(end 0.7874 0.4064)
			(stroke
				(width 0.1524)
				(type default)
			)
			(layer "B.SilkS")
		)
		(fp_line
			(start 0.7874 0.4064)
			(end 0.7874 -0.4064)
			(stroke
				(width 0.1524)
				(type default)
			)
			(layer "B.SilkS")
		)
		(fp_line
			(start -0.7874 -0.4064)
			(end -0.7874 0.4064)
			(stroke
				(width 0.1524)
				(type default)
			)
			(layer "B.SilkS")
		)
		(fp_line
			(start 0.7874 -0.4064)
			(end -0.7874 -0.4064)
			(stroke
				(width 0.1524)
				(type default)
			)
			(layer "B.SilkS")
		)
		(fp_line
			(start -0.67945 0.3048)
			(end -0.120396 0.3048)
			(stroke
				(width 0.1)
				(type default)
			)
			(layer "B.Fab")
		)
		(fp_line
			(start -0.120396 0.3048)
			(end -0.120396 0.2794)
			(stroke
				(width 0.1)
				(type default)
			)
			(layer "B.Fab")
		)
		(fp_line
			(start 0.12065 0.3048)
			(end 0.67945 0.3048)
			(stroke
				(width 0.1)
				(type default)
			)
			(layer "B.Fab")
		)
		(fp_line
			(start 0.67945 0.3048)
			(end 0.67945 -0.305054)
			(stroke
				(width 0.1)
				(type default)
			)
			(layer "B.Fab")
		)
		(fp_line
			(start -0.120396 0.2794)
			(end 0.12065 0.2794)
			(stroke
				(width 0.1)
				(type default)
			)
			(layer "B.Fab")
		)
		(fp_line
			(start 0.12065 0.2794)
			(end 0.12065 0.3048)
			(stroke
				(width 0.1)
				(type default)
			)
			(layer "B.Fab")
		)
		(fp_line
			(start -0.12065 -0.2794)
			(end -0.12065 -0.3048)
			(stroke
				(width 0.1)
				(type default)
			)
			(layer "B.Fab")
		)
		(fp_line
			(start 0.12065 -0.2794)
			(end -0.12065 -0.2794)
			(stroke
				(width 0.1)
				(type default)
			)
			(layer "B.Fab")
		)
		(fp_line
			(start -0.67945 -0.3048)
			(end -0.67945 0.3048)
			(stroke
				(width 0.1)
				(type default)
			)
			(layer "B.Fab")
		)
		(fp_line
			(start -0.12065 -0.3048)
			(end -0.67945 -0.3048)
			(stroke
				(width 0.1)
				(type default)
			)
			(layer "B.Fab")
		)
		(fp_line
			(start 0.12065 -0.305054)
			(end 0.12065 -0.2794)
			(stroke
				(width 0.1)
				(type default)
			)
			(layer "B.Fab")
		)
		(fp_line
			(start 0.67945 -0.305054)
			(end 0.12065 -0.305054)
			(stroke
				(width 0.1)
				(type default)
			)
			(layer "B.Fab")
		)
		(pad "1" smd circle
			(at 0.40005 0 90)
			(size 0 0)
			(layers "B.Cu" "B.Mask" "B.Paste")
			(net "SCM_IRQ_N")
		)
		(pad "2" smd circle
			(at -0.40005 0 90)
			(size 0 0)
			(layers "B.Cu" "B.Mask" "B.Paste")
			(net "IRQ0_A56")
		)
	)
	(footprint ""
		(layer "B.Cu")
		(at 40.9956 -193.996564)
		(property "Reference" "R105"
			(at 0 0 0)
			(layer "B.SilkS")
			(hide yes)
			(effects
				(font
					(size 1.27 1.27)
				)
				(justify mirror)
			)
		)
		(property "Value" ""
			(at 0 0 0)
			(layer "B.Fab")
			(effects
				(font
					(size 1.27 1.27)
				)
				(justify mirror)
			)
		)
		(duplicate_pad_numbers_are_jumpers no)
		(fp_line
			(start -0.7874 -0.4064)
			(end -0.7874 0.4064)
			(stroke
				(width 0.1524)
				(type default)
			)
			(layer "B.SilkS")
		)
		(fp_line
			(start -0.7874 0.4064)
			(end 0.7874 0.4064)
			(stroke
				(width 0.1524)
				(type default)
			)
			(layer "B.SilkS")
		)
		(fp_line
			(start 0.7874 -0.4064)
			(end -0.7874 -0.4064)
			(stroke
				(width 0.1524)
				(type default)
			)
			(layer "B.SilkS")
		)
		(fp_line
			(start 0.7874 0.4064)
			(end 0.7874 -0.4064)
			(stroke
				(width 0.1524)
				(type default)
			)
			(layer "B.SilkS")
		)
		(fp_line
			(start -0.67945 -0.3048)
			(end -0.67945 0.3048)
			(stroke
				(width 0.1)
				(type default)
			)
			(layer "B.Fab")
		)
		(fp_line
			(start -0.67945 0.3048)
			(end -0.120396 0.3048)
			(stroke
				(width 0.1)
				(type default)
			)
			(layer "B.Fab")
		)
		(fp_line
			(start -0.12065 -0.3048)
			(end -0.67945 -0.3048)
			(stroke
				(width 0.1)
				(type default)
			)
			(layer "B.Fab")
		)
		(fp_line
			(start -0.12065 -0.2794)
			(end -0.12065 -0.3048)
			(stroke
				(width 0.1)
				(type default)
			)
			(layer "B.Fab")
		)
		(fp_line
			(start -0.120396 0.2794)
			(end 0.12065 0.2794)
			(stroke
				(width 0.1)
				(type default)
			)
			(layer "B.Fab")
		)
		(fp_line
			(start -0.120396 0.3048)
			(end -0.120396 0.2794)
			(stroke
				(width 0.1)
				(type default)
			)
			(layer "B.Fab")
		)
		(fp_line
			(start 0.12065 -0.305054)
			(end 0.12065 -0.2794)
			(stroke
				(width 0.1)
				(type default)
			)
			(layer "B.Fab")
		)
		(fp_line
			(start 0.12065 -0.2794)
			(end -0.12065 -0.2794)
			(stroke
				(width 0.1)
				(type default)
			)
			(layer "B.Fab")
		)
		(fp_line
			(start 0.12065 0.2794)
			(end 0.12065 0.3048)
			(stroke
				(width 0.1)
				(type default)
			)
			(layer "B.Fab")
		)
		(fp_line
			(start 0.12065 0.3048)
			(end 0.67945 0.3048)
			(stroke
				(width 0.1)
				(type default)
			)
			(layer "B.Fab")
		)
		(fp_line
			(start 0.67945 -0.305054)
			(end 0.12065 -0.305054)
			(stroke
				(width 0.1)
				(type default)
			)
			(layer "B.Fab")
		)
		(fp_line
			(start 0.67945 0.3048)
			(end 0.67945 -0.305054)
			(stroke
				(width 0.1)
				(type default)
			)
			(layer "B.Fab")
		)
		(pad "1" smd circle
			(at 0.40005 0 180)
			(size 0 0)
			(layers "B.Cu" "B.Mask" "B.Paste")
			(net "P3V3")
		)
		(pad "2" smd circle
			(at -0.40005 0 180)
			(size 0 0)
			(layers "B.Cu" "B.Mask" "B.Paste")
			(net "PWRGD_CHC_CPU1_DIMM")
		)
	)
	(footprint ""
		(layer "B.Cu")
		(at 412.191454 -191.20231 180)
		(property "Reference" "R297"
			(at 0 0 0)
			(layer "B.SilkS")
			(hide yes)
			(effects
				(font
					(size 1.27 1.27)
				)
				(justify mirror)
			)
		)
		(property "Value" ""
			(at 0 0 0)
			(layer "B.Fab")
			(effects
				(font
					(size 1.27 1.27)
				)
				(justify mirror)
			)
		)
		(duplicate_pad_numbers_are_jumpers no)
		(fp_line
			(start 0.7874 0.4064)
			(end 0.7874 -0.4064)
			(stroke
				(width 0.1524)
				(type default)
			)
			(layer "B.SilkS")
		)
		(fp_line
			(start 0.7874 -0.4064)
			(end -0.7874 -0.4064)
			(stroke
				(width 0.1524)
				(type default)
			)
			(layer "B.SilkS")
		)
		(fp_line
			(start -0.7874 0.4064)
			(end 0.7874 0.4064)
			(stroke
				(width 0.1524)
				(type default)
			)
			(layer "B.SilkS")
		)
		(fp_line
			(start -0.7874 -0.4064)
			(end -0.7874 0.4064)
			(stroke
				(width 0.1524)
				(type default)
			)
			(layer "B.SilkS")
		)
		(fp_line
			(start 0.67945 0.3048)
			(end 0.67945 -0.305054)
			(stroke
				(width 0.1)
				(type default)
			)
			(layer "B.Fab")
		)
		(fp_line
			(start 0.67945 -0.305054)
			(end 0.12065 -0.305054)
			(stroke
				(width 0.1)
				(type default)
			)
			(layer "B.Fab")
		)
		(fp_line
			(start 0.12065 0.3048)
			(end 0.67945 0.3048)
			(stroke
				(width 0.1)
				(type default)
			)
			(layer "B.Fab")
		)
		(fp_line
			(start 0.12065 0.2794)
			(end 0.12065 0.3048)
			(stroke
				(width 0.1)
				(type default)
			)
			(layer "B.Fab")
		)
		(fp_line
			(start 0.12065 -0.2794)
			(end -0.12065 -0.2794)
			(stroke
				(width 0.1)
				(type default)
			)
			(layer "B.Fab")
		)
		(fp_line
			(start 0.12065 -0.305054)
			(end 0.12065 -0.2794)
			(stroke
				(width 0.1)
				(type default)
			)
			(layer "B.Fab")
		)
		(fp_line
			(start -0.120396 0.3048)
			(end -0.120396 0.2794)
			(stroke
				(width 0.1)
				(type default)
			)
			(layer "B.Fab")
		)
		(fp_line
			(start -0.120396 0.2794)
			(end 0.12065 0.2794)
			(stroke
				(width 0.1)
				(type default)
			)
			(layer "B.Fab")
		)
		(fp_line
			(start -0.12065 -0.2794)
			(end -0.12065 -0.3048)
			(stroke
				(width 0.1)
				(type default)
			)
			(layer "B.Fab")
		)
		(fp_line
			(start -0.12065 -0.3048)
			(end -0.67945 -0.3048)
			(stroke
				(width 0.1)
				(type default)
			)
			(layer "B.Fab")
		)
		(fp_line
			(start -0.67945 0.3048)
			(end -0.120396 0.3048)
			(stroke
				(width 0.1)
				(type default)
			)
			(layer "B.Fab")
		)
		(fp_line
			(start -0.67945 -0.3048)
			(end -0.67945 0.3048)
			(stroke
				(width 0.1)
				(type default)
			)
			(layer "B.Fab")
		)
		(pad "1" smd circle
			(at 0.40005 0)
			(size 0 0)
			(layers "B.Cu" "B.Mask" "B.Paste")
			(net "PWRGD_CHG_CPU0_DIMM0")
		)
		(pad "2" smd circle
			(at -0.40005 0)
			(size 0 0)
			(layers "B.Cu" "B.Mask" "B.Paste")
			(net "PWRGD_CHGL_CPU0")
		)
	)
	(footprint ""
		(layer "B.Cu")
		(at 125.389386 -258.830318)
		(property "Reference" "C2425"
			(at 0 0 0)
			(layer "B.SilkS")
			(hide yes)
			(effects
				(font
					(size 1.27 1.27)
				)
				(justify mirror)
			)
		)
		(property "Value" ""
			(at 0 0 0)
			(layer "B.Fab")
			(effects
				(font
					(size 1.27 1.27)
				)
				(justify mirror)
			)
		)
		(duplicate_pad_numbers_are_jumpers no)
		(fp_line
			(start -0.7874 -0.4064)
			(end -0.7874 0.4064)
			(stroke
				(width 0.1524)
				(type default)
			)
			(layer "B.SilkS")
		)
		(fp_line
			(start -0.7874 0.4064)
			(end 0.7874 0.4064)
			(stroke
				(width 0.1524)
				(type default)
			)
			(layer "B.SilkS")
		)
		(fp_line
			(start 0.7874 -0.4064)
			(end -0.7874 -0.4064)
			(stroke
				(width 0.1524)
				(type default)
			)
			(layer "B.SilkS")
		)
		(fp_line
			(start 0.7874 0.4064)
			(end 0.7874 -0.4064)
			(stroke
				(width 0.1524)
				(type default)
			)
			(layer "B.SilkS")
		)
		(fp_line
			(start -0.67945 -0.3048)
			(end -0.67945 0.3048)
			(stroke
				(width 0.1)
				(type default)
			)
			(layer "B.Fab")
		)
		(fp_line
			(start -0.67945 0.3048)
			(end -0.120396 0.3048)
			(stroke
				(width 0.1)
				(type default)
			)
			(layer "B.Fab")
		)
		(fp_line
			(start -0.12065 -0.3048)
			(end -0.67945 -0.3048)
			(stroke
				(width 0.1)
				(type default)
			)
			(layer "B.Fab")
		)
		(fp_line
			(start -0.12065 -0.2794)
			(end -0.12065 -0.3048)
			(stroke
				(width 0.1)
				(type default)
			)
			(layer "B.Fab")
		)
		(fp_line
			(start -0.120396 0.2794)
			(end 0.12065 0.2794)
			(stroke
				(width 0.1)
				(type default)
			)
			(layer "B.Fab")
		)
		(fp_line
			(start -0.120396 0.3048)
			(end -0.120396 0.2794)
			(stroke
				(width 0.1)
				(type default)
			)
			(layer "B.Fab")
		)
		(fp_line
			(start 0.12065 -0.305054)
			(end 0.12065 -0.2794)
			(stroke
				(width 0.1)
				(type default)
			)
			(layer "B.Fab")
		)
		(fp_line
			(start 0.12065 -0.2794)
			(end -0.12065 -0.2794)
			(stroke
				(width 0.1)
				(type default)
			)
			(layer "B.Fab")
		)
		(fp_line
			(start 0.12065 0.2794)
			(end 0.12065 0.3048)
			(stroke
				(width 0.1)
				(type default)
			)
			(layer "B.Fab")
		)
		(fp_line
			(start 0.12065 0.3048)
			(end 0.67945 0.3048)
			(stroke
				(width 0.1)
				(type default)
			)
			(layer "B.Fab")
		)
		(fp_line
			(start 0.67945 -0.305054)
			(end 0.12065 -0.305054)
			(stroke
				(width 0.1)
				(type default)
			)
			(layer "B.Fab")
		)
		(fp_line
			(start 0.67945 0.3048)
			(end 0.67945 -0.305054)
			(stroke
				(width 0.1)
				(type default)
			)
			(layer "B.Fab")
		)
		(pad "1" smd circle
			(at 0.40005 0 180)
			(size 0 0)
			(layers "B.Cu" "B.Mask" "B.Paste")
			(net "PVDDCR_SOC_P1")
		)
		(pad "2" smd circle
			(at -0.40005 0 180)
			(size 0 0)
			(layers "B.Cu" "B.Mask" "B.Paste")
			(net "GND")
		)
	)
	(footprint ""
		(layer "B.Cu")
		(at 364.439454 -248.47931)
		(property "Reference" "C2174"
			(at 0 0 0)
			(layer "B.SilkS")
			(hide yes)
			(effects
				(font
					(size 1.27 1.27)
				)
				(justify mirror)
			)
		)
		(property "Value" ""
			(at 0 0 0)
			(layer "B.Fab")
			(effects
				(font
					(size 1.27 1.27)
				)
				(justify mirror)
			)
		)
		(duplicate_pad_numbers_are_jumpers no)
		(fp_line
			(start -0.7874 -0.4064)
			(end -0.7874 0.4064)
			(stroke
				(width 0.1524)
				(type default)
			)
			(layer "B.SilkS")
		)
		(fp_line
			(start -0.7874 0.4064)
			(end 0.7874 0.4064)
			(stroke
				(width 0.1524)
				(type default)
			)
			(layer "B.SilkS")
		)
		(fp_line
			(start 0.7874 -0.4064)
			(end -0.7874 -0.4064)
			(stroke
				(width 0.1524)
				(type default)
			)
			(layer "B.SilkS")
		)
		(fp_line
			(start 0.7874 0.4064)
			(end 0.7874 -0.4064)
			(stroke
				(width 0.1524)
				(type default)
			)
			(layer "B.SilkS")
		)
		(fp_line
			(start -0.67945 -0.3048)
			(end -0.67945 0.3048)
			(stroke
				(width 0.1)
				(type default)
			)
			(layer "B.Fab")
		)
		(fp_line
			(start -0.67945 0.3048)
			(end -0.120396 0.3048)
			(stroke
				(width 0.1)
				(type default)
			)
			(layer "B.Fab")
		)
		(fp_line
			(start -0.12065 -0.3048)
			(end -0.67945 -0.3048)
			(stroke
				(width 0.1)
				(type default)
			)
			(layer "B.Fab")
		)
		(fp_line
			(start -0.12065 -0.2794)
			(end -0.12065 -0.3048)
			(stroke
				(width 0.1)
				(type default)
			)
			(layer "B.Fab")
		)
		(fp_line
			(start -0.120396 0.2794)
			(end 0.12065 0.2794)
			(stroke
				(width 0.1)
				(type default)
			)
			(layer "B.Fab")
		)
		(fp_line
			(start -0.120396 0.3048)
			(end -0.120396 0.2794)
			(stroke
				(width 0.1)
				(type default)
			)
			(layer "B.Fab")
		)
		(fp_line
			(start 0.12065 -0.305054)
			(end 0.12065 -0.2794)
			(stroke
				(width 0.1)
				(type default)
			)
			(layer "B.Fab")
		)
		(fp_line
			(start 0.12065 -0.2794)
			(end -0.12065 -0.2794)
			(stroke
				(width 0.1)
				(type default)
			)
			(layer "B.Fab")
		)
		(fp_line
			(start 0.12065 0.2794)
			(end 0.12065 0.3048)
			(stroke
				(width 0.1)
				(type default)
			)
			(layer "B.Fab")
		)
		(fp_line
			(start 0.12065 0.3048)
			(end 0.67945 0.3048)
			(stroke
				(width 0.1)
				(type default)
			)
			(layer "B.Fab")
		)
		(fp_line
			(start 0.67945 -0.305054)
			(end 0.12065 -0.305054)
			(stroke
				(width 0.1)
				(type default)
			)
			(layer "B.Fab")
		)
		(fp_line
			(start 0.67945 0.3048)
			(end 0.67945 -0.305054)
			(stroke
				(width 0.1)
				(type default)
			)
			(layer "B.Fab")
		)
		(pad "1" smd circle
			(at 0.40005 0 180)
			(size 0 0)
			(layers "B.Cu" "B.Mask" "B.Paste")
			(net "PVDDCR_CPU0_P0")
		)
		(pad "2" smd circle
			(at -0.40005 0 180)
			(size 0 0)
			(layers "B.Cu" "B.Mask" "B.Paste")
			(net "GND")
		)
	)
	(footprint ""
		(layer "B.Cu")
		(at 255.905 -338.51596 180)
		(property "Reference" "R829"
			(at 0 0 0)
			(layer "B.SilkS")
			(hide yes)
			(effects
				(font
					(size 1.27 1.27)
				)
				(justify mirror)
			)
		)
		(property "Value" ""
			(at 0 0 0)
			(layer "B.Fab")
			(effects
				(font
					(size 1.27 1.27)
				)
				(justify mirror)
			)
		)
		(duplicate_pad_numbers_are_jumpers no)
		(fp_line
			(start 0.32512 0.175006)
			(end 0.32512 -0.175006)
			(stroke
				(width 0.1)
				(type default)
			)
			(layer "B.Fab")
		)
		(fp_line
			(start 0.32512 -0.175006)
			(end -0.32512 -0.175006)
			(stroke
				(width 0.1)
				(type default)
			)
			(layer "B.Fab")
		)
		(fp_line
			(start -0.32512 0.175006)
			(end 0.32512 0.175006)
			(stroke
				(width 0.1)
				(type default)
			)
			(layer "B.Fab")
		)
		(fp_line
			(start -0.32512 -0.175006)
			(end -0.32512 0.175006)
			(stroke
				(width 0.1)
				(type default)
			)
			(layer "B.Fab")
		)
		(pad "1" smd rect
			(at 0.2667 0)
			(size 0.3048 0.381)
			(layers "B.Cu" "B.Mask" "B.Paste")
			(net "SMB_RT_CPU0_P1_ROM_MUX_2D_R_SCL")
		)
		(pad "2" smd rect
			(at -0.2667 0 180)
			(size 0.3048 0.381)
			(layers "B.Cu" "B.Mask" "B.Paste")
			(net "SMB_RT_CPU0_P1_ROM_MUX_2D_SCL")
		)
	)
	(footprint ""
		(layer "B.Cu")
		(at 175.507142 -421.216074 180)
		(property "Reference" "R6239"
			(at 0 0 0)
			(layer "B.SilkS")
			(hide yes)
			(effects
				(font
					(size 1.27 1.27)
				)
				(justify mirror)
			)
		)
		(property "Value" ""
			(at 0 0 0)
			(layer "B.Fab")
			(effects
				(font
					(size 1.27 1.27)
				)
				(justify mirror)
			)
		)
		(duplicate_pad_numbers_are_jumpers no)
		(fp_line
			(start 0.7874 0.4064)
			(end 0.7874 -0.4064)
			(stroke
				(width 0.1524)
				(type default)
			)
			(layer "B.SilkS")
		)
		(fp_line
			(start 0.7874 -0.4064)
			(end -0.7874 -0.4064)
			(stroke
				(width 0.1524)
				(type default)
			)
			(layer "B.SilkS")
		)
		(fp_line
			(start -0.7874 0.4064)
			(end 0.7874 0.4064)
			(stroke
				(width 0.1524)
				(type default)
			)
			(layer "B.SilkS")
		)
		(fp_line
			(start -0.7874 -0.4064)
			(end -0.7874 0.4064)
			(stroke
				(width 0.1524)
				(type default)
			)
			(layer "B.SilkS")
		)
		(fp_line
			(start 0.67945 0.3048)
			(end 0.67945 -0.305054)
			(stroke
				(width 0.1)
				(type default)
			)
			(layer "B.Fab")
		)
		(fp_line
			(start 0.67945 -0.305054)
			(end 0.12065 -0.305054)
			(stroke
				(width 0.1)
				(type default)
			)
			(layer "B.Fab")
		)
		(fp_line
			(start 0.12065 0.3048)
			(end 0.67945 0.3048)
			(stroke
				(width 0.1)
				(type default)
			)
			(layer "B.Fab")
		)
		(fp_line
			(start 0.12065 0.2794)
			(end 0.12065 0.3048)
			(stroke
				(width 0.1)
				(type default)
			)
			(layer "B.Fab")
		)
		(fp_line
			(start 0.12065 -0.2794)
			(end -0.12065 -0.2794)
			(stroke
				(width 0.1)
				(type default)
			)
			(layer "B.Fab")
		)
		(fp_line
			(start 0.12065 -0.305054)
			(end 0.12065 -0.2794)
			(stroke
				(width 0.1)
				(type default)
			)
			(layer "B.Fab")
		)
		(fp_line
			(start -0.120396 0.3048)
			(end -0.120396 0.2794)
			(stroke
				(width 0.1)
				(type default)
			)
			(layer "B.Fab")
		)
		(fp_line
			(start -0.120396 0.2794)
			(end 0.12065 0.2794)
			(stroke
				(width 0.1)
				(type default)
			)
			(layer "B.Fab")
		)
		(fp_line
			(start -0.12065 -0.2794)
			(end -0.12065 -0.3048)
			(stroke
				(width 0.1)
				(type default)
			)
			(layer "B.Fab")
		)
		(fp_line
			(start -0.12065 -0.3048)
			(end -0.67945 -0.3048)
			(stroke
				(width 0.1)
				(type default)
			)
			(layer "B.Fab")
		)
		(fp_line
			(start -0.67945 0.3048)
			(end -0.120396 0.3048)
			(stroke
				(width 0.1)
				(type default)
			)
			(layer "B.Fab")
		)
		(fp_line
			(start -0.67945 -0.3048)
			(end -0.67945 0.3048)
			(stroke
				(width 0.1)
				(type default)
			)
			(layer "B.Fab")
		)
		(pad "1" smd circle
			(at 0.40005 0)
			(size 0 0)
			(layers "B.Cu" "B.Mask" "B.Paste")
			(net "P3V3_AUX")
		)
		(pad "2" smd circle
			(at -0.40005 0)
			(size 0 0)
			(layers "B.Cu" "B.Mask" "B.Paste")
			(net "HSC_D_OC")
		)
	)
	(footprint ""
		(layer "B.Cu")
		(at 129.289048 -156.393134 -90)
		(property "Reference" "PC351_3"
			(at 0 0 90)
			(layer "B.SilkS")
			(hide yes)
			(effects
				(font
					(size 1.27 1.27)
				)
				(justify mirror)
			)
		)
		(property "Value" ""
			(at 0 0 90)
			(layer "B.Fab")
			(effects
				(font
					(size 1.27 1.27)
				)
				(justify mirror)
			)
		)
		(duplicate_pad_numbers_are_jumpers no)
		(fp_line
			(start -1.524 0.762)
			(end 1.524 0.762)
			(stroke
				(width 0.1524)
				(type default)
			)
			(layer "B.SilkS")
		)
		(fp_line
			(start 1.524 0.762)
			(end 1.524 -0.762)
			(stroke
				(width 0.1524)
				(type default)
			)
			(layer "B.SilkS")
		)
		(fp_line
			(start -1.524 -0.762)
			(end -1.524 0.762)
			(stroke
				(width 0.1524)
				(type default)
			)
			(layer "B.SilkS")
		)
		(fp_line
			(start 1.524 -0.762)
			(end -1.524 -0.762)
			(stroke
				(width 0.1524)
				(type default)
			)
			(layer "B.SilkS")
		)
		(fp_line
			(start -1.1049 0.724916)
			(end -1.1049 -0.724916)
			(stroke
				(width 0.1)
				(type default)
			)
			(layer "B.Fab")
		)
		(fp_line
			(start 1.1049 0.724916)
			(end -1.1049 0.724916)
			(stroke
				(width 0.1)
				(type default)
			)
			(layer "B.Fab")
		)
		(fp_line
			(start -1.1049 -0.724916)
			(end 1.1049 -0.724916)
			(stroke
				(width 0.1)
				(type default)
			)
			(layer "B.Fab")
		)
		(fp_line
			(start 1.1049 -0.724916)
			(end 1.1049 0.724916)
			(stroke
				(width 0.1)
				(type default)
			)
			(layer "B.Fab")
		)
		(pad "1" smd rect
			(at 0.889 0 270)
			(size 1.016 1.27)
			(layers "B.Cu" "B.Mask" "B.Paste")
			(net "SW_P12V_AUX_PVDDCR_SOC_P1_FLT")
		)
		(pad "2" smd rect
			(at -0.889 0 270)
			(size 1.016 1.27)
			(layers "B.Cu" "B.Mask" "B.Paste")
			(net "GND")
		)
	)
	(footprint ""
		(layer "B.Cu")
		(at 111.781336 -253.432564 180)
		(property "Reference" "C2272"
			(at 0 0 0)
			(layer "B.SilkS")
			(hide yes)
			(effects
				(font
					(size 1.27 1.27)
				)
				(justify mirror)
			)
		)
		(property "Value" ""
			(at 0 0 0)
			(layer "B.Fab")
			(effects
				(font
					(size 1.27 1.27)
				)
				(justify mirror)
			)
		)
		(duplicate_pad_numbers_are_jumpers no)
		(fp_line
			(start 0.7874 0.4064)
			(end 0.7874 -0.4064)
			(stroke
				(width 0.1524)
				(type default)
			)
			(layer "B.SilkS")
		)
		(fp_line
			(start 0.7874 -0.4064)
			(end -0.7874 -0.4064)
			(stroke
				(width 0.1524)
				(type default)
			)
			(layer "B.SilkS")
		)
		(fp_line
			(start -0.7874 0.4064)
			(end 0.7874 0.4064)
			(stroke
				(width 0.1524)
				(type default)
			)
			(layer "B.SilkS")
		)
		(fp_line
			(start -0.7874 -0.4064)
			(end -0.7874 0.4064)
			(stroke
				(width 0.1524)
				(type default)
			)
			(layer "B.SilkS")
		)
		(fp_line
			(start 0.67945 0.3048)
			(end 0.67945 -0.305054)
			(stroke
				(width 0.1)
				(type default)
			)
			(layer "B.Fab")
		)
		(fp_line
			(start 0.67945 -0.305054)
			(end 0.12065 -0.305054)
			(stroke
				(width 0.1)
				(type default)
			)
			(layer "B.Fab")
		)
		(fp_line
			(start 0.12065 0.3048)
			(end 0.67945 0.3048)
			(stroke
				(width 0.1)
				(type default)
			)
			(layer "B.Fab")
		)
		(fp_line
			(start 0.12065 0.2794)
			(end 0.12065 0.3048)
			(stroke
				(width 0.1)
				(type default)
			)
			(layer "B.Fab")
		)
		(fp_line
			(start 0.12065 -0.2794)
			(end -0.12065 -0.2794)
			(stroke
				(width 0.1)
				(type default)
			)
			(layer "B.Fab")
		)
		(fp_line
			(start 0.12065 -0.305054)
			(end 0.12065 -0.2794)
			(stroke
				(width 0.1)
				(type default)
			)
			(layer "B.Fab")
		)
		(fp_line
			(start -0.120396 0.3048)
			(end -0.120396 0.2794)
			(stroke
				(width 0.1)
				(type default)
			)
			(layer "B.Fab")
		)
		(fp_line
			(start -0.120396 0.2794)
			(end 0.12065 0.2794)
			(stroke
				(width 0.1)
				(type default)
			)
			(layer "B.Fab")
		)
		(fp_line
			(start -0.12065 -0.2794)
			(end -0.12065 -0.3048)
			(stroke
				(width 0.1)
				(type default)
			)
			(layer "B.Fab")
		)
		(fp_line
			(start -0.12065 -0.3048)
			(end -0.67945 -0.3048)
			(stroke
				(width 0.1)
				(type default)
			)
			(layer "B.Fab")
		)
		(fp_line
			(start -0.67945 0.3048)
			(end -0.120396 0.3048)
			(stroke
				(width 0.1)
				(type default)
			)
			(layer "B.Fab")
		)
		(fp_line
			(start -0.67945 -0.3048)
			(end -0.67945 0.3048)
			(stroke
				(width 0.1)
				(type default)
			)
			(layer "B.Fab")
		)
		(pad "1" smd circle
			(at 0.40005 0)
			(size 0 0)
			(layers "B.Cu" "B.Mask" "B.Paste")
			(net "PVDDCR_SOC_P1")
		)
		(pad "2" smd circle
			(at -0.40005 0)
			(size 0 0)
			(layers "B.Cu" "B.Mask" "B.Paste")
			(net "GND")
		)
	)
	(footprint ""
		(layer "B.Cu")
		(at 105.960164 -259.355336 180)
		(property "Reference" "C3910"
			(at 0 0 0)
			(layer "B.SilkS")
			(hide yes)
			(effects
				(font
					(size 1.27 1.27)
				)
				(justify mirror)
			)
		)
		(property "Value" ""
			(at 0 0 0)
			(layer "B.Fab")
			(effects
				(font
					(size 1.27 1.27)
				)
				(justify mirror)
			)
		)
		(duplicate_pad_numbers_are_jumpers no)
		(fp_line
			(start 0.7874 0.4064)
			(end 0.7874 -0.4064)
			(stroke
				(width 0.1524)
				(type default)
			)
			(layer "B.SilkS")
		)
		(fp_line
			(start 0.7874 -0.4064)
			(end -0.7874 -0.4064)
			(stroke
				(width 0.1524)
				(type default)
			)
			(layer "B.SilkS")
		)
		(fp_line
			(start -0.7874 0.4064)
			(end 0.7874 0.4064)
			(stroke
				(width 0.1524)
				(type default)
			)
			(layer "B.SilkS")
		)
		(fp_line
			(start -0.7874 -0.4064)
			(end -0.7874 0.4064)
			(stroke
				(width 0.1524)
				(type default)
			)
			(layer "B.SilkS")
		)
		(fp_line
			(start 0.67945 0.3048)
			(end 0.67945 -0.305054)
			(stroke
				(width 0.1)
				(type default)
			)
			(layer "B.Fab")
		)
		(fp_line
			(start 0.67945 -0.305054)
			(end 0.12065 -0.305054)
			(stroke
				(width 0.1)
				(type default)
			)
			(layer "B.Fab")
		)
		(fp_line
			(start 0.12065 0.3048)
			(end 0.67945 0.3048)
			(stroke
				(width 0.1)
				(type default)
			)
			(layer "B.Fab")
		)
		(fp_line
			(start 0.12065 0.2794)
			(end 0.12065 0.3048)
			(stroke
				(width 0.1)
				(type default)
			)
			(layer "B.Fab")
		)
		(fp_line
			(start 0.12065 -0.2794)
			(end -0.12065 -0.2794)
			(stroke
				(width 0.1)
				(type default)
			)
			(layer "B.Fab")
		)
		(fp_line
			(start 0.12065 -0.305054)
			(end 0.12065 -0.2794)
			(stroke
				(width 0.1)
				(type default)
			)
			(layer "B.Fab")
		)
		(fp_line
			(start -0.120396 0.3048)
			(end -0.120396 0.2794)
			(stroke
				(width 0.1)
				(type default)
			)
			(layer "B.Fab")
		)
		(fp_line
			(start -0.120396 0.2794)
			(end 0.12065 0.2794)
			(stroke
				(width 0.1)
				(type default)
			)
			(layer "B.Fab")
		)
		(fp_line
			(start -0.12065 -0.2794)
			(end -0.12065 -0.3048)
			(stroke
				(width 0.1)
				(type default)
			)
			(layer "B.Fab")
		)
		(fp_line
			(start -0.12065 -0.3048)
			(end -0.67945 -0.3048)
			(stroke
				(width 0.1)
				(type default)
			)
			(layer "B.Fab")
		)
		(fp_line
			(start -0.67945 0.3048)
			(end -0.120396 0.3048)
			(stroke
				(width 0.1)
				(type default)
			)
			(layer "B.Fab")
		)
		(fp_line
			(start -0.67945 -0.3048)
			(end -0.67945 0.3048)
			(stroke
				(width 0.1)
				(type default)
			)
			(layer "B.Fab")
		)
		(pad "1" smd circle
			(at 0.40005 0)
			(size 0 0)
			(layers "B.Cu" "B.Mask" "B.Paste")
			(net "PVDDIO_P1")
		)
		(pad "2" smd circle
			(at -0.40005 0)
			(size 0 0)
			(layers "B.Cu" "B.Mask" "B.Paste")
			(net "GND")
		)
	)
	(footprint ""
		(layer "B.Cu")
		(at 25.152096 -192.66027 180)
		(property "Reference" "C509"
			(at 0 0 0)
			(layer "B.SilkS")
			(hide yes)
			(effects
				(font
					(size 1.27 1.27)
				)
				(justify mirror)
			)
		)
		(property "Value" ""
			(at 0 0 0)
			(layer "B.Fab")
			(effects
				(font
					(size 1.27 1.27)
				)
				(justify mirror)
			)
		)
		(duplicate_pad_numbers_are_jumpers no)
		(fp_line
			(start 1.524 0.762)
			(end 1.524 -0.762)
			(stroke
				(width 0.1524)
				(type default)
			)
			(layer "B.SilkS")
		)
		(fp_line
			(start 1.524 -0.762)
			(end -1.524 -0.762)
			(stroke
				(width 0.1524)
				(type default)
			)
			(layer "B.SilkS")
		)
		(fp_line
			(start -1.524 0.762)
			(end 1.524 0.762)
			(stroke
				(width 0.1524)
				(type default)
			)
			(layer "B.SilkS")
		)
		(fp_line
			(start -1.524 -0.762)
			(end -1.524 0.762)
			(stroke
				(width 0.1524)
				(type default)
			)
			(layer "B.SilkS")
		)
		(fp_line
			(start 1.1049 0.724916)
			(end -1.1049 0.724916)
			(stroke
				(width 0.1)
				(type default)
			)
			(layer "B.Fab")
		)
		(fp_line
			(start 1.1049 -0.724916)
			(end 1.1049 0.724916)
			(stroke
				(width 0.1)
				(type default)
			)
			(layer "B.Fab")
		)
		(fp_line
			(start -1.1049 0.724916)
			(end -1.1049 -0.724916)
			(stroke
				(width 0.1)
				(type default)
			)
			(layer "B.Fab")
		)
		(fp_line
			(start -1.1049 -0.724916)
			(end 1.1049 -0.724916)
			(stroke
				(width 0.1)
				(type default)
			)
			(layer "B.Fab")
		)
		(pad "1" smd rect
			(at 0.889 0 180)
			(size 1.016 1.27)
			(layers "B.Cu" "B.Mask" "B.Paste")
			(net "P12V_MEM_CPU1")
		)
		(pad "2" smd rect
			(at -0.889 0 180)
			(size 1.016 1.27)
			(layers "B.Cu" "B.Mask" "B.Paste")
			(net "GND")
		)
	)
	(footprint ""
		(layer "B.Cu")
		(at 41.162732 -337.989672 -90)
		(property "Reference" "PC637_3"
			(at 0 0 90)
			(layer "B.SilkS")
			(hide yes)
			(effects
				(font
					(size 1.27 1.27)
				)
				(justify mirror)
			)
		)
		(property "Value" ""
			(at 0 0 90)
			(layer "B.Fab")
			(effects
				(font
					(size 1.27 1.27)
				)
				(justify mirror)
			)
		)
		(duplicate_pad_numbers_are_jumpers no)
		(fp_line
			(start -1.524 0.762)
			(end 1.524 0.762)
			(stroke
				(width 0.1524)
				(type default)
			)
			(layer "B.SilkS")
		)
		(fp_line
			(start 1.524 0.762)
			(end 1.524 -0.762)
			(stroke
				(width 0.1524)
				(type default)
			)
			(layer "B.SilkS")
		)
		(fp_line
			(start -1.524 -0.762)
			(end -1.524 0.762)
			(stroke
				(width 0.1524)
				(type default)
			)
			(layer "B.SilkS")
		)
		(fp_line
			(start 1.524 -0.762)
			(end -1.524 -0.762)
			(stroke
				(width 0.1524)
				(type default)
			)
			(layer "B.SilkS")
		)
		(fp_line
			(start -1.1049 0.724916)
			(end -1.1049 -0.724916)
			(stroke
				(width 0.1)
				(type default)
			)
			(layer "B.Fab")
		)
		(fp_line
			(start 1.1049 0.724916)
			(end -1.1049 0.724916)
			(stroke
				(width 0.1)
				(type default)
			)
			(layer "B.Fab")
		)
		(fp_line
			(start -1.1049 -0.724916)
			(end 1.1049 -0.724916)
			(stroke
				(width 0.1)
				(type default)
			)
			(layer "B.Fab")
		)
		(fp_line
			(start 1.1049 -0.724916)
			(end 1.1049 0.724916)
			(stroke
				(width 0.1)
				(type default)
			)
			(layer "B.Fab")
		)
		(pad "1" smd rect
			(at 0.889 0 270)
			(size 1.016 1.27)
			(layers "B.Cu" "B.Mask" "B.Paste")
			(net "PVDDIO_P1")
		)
		(pad "2" smd rect
			(at -0.889 0 270)
			(size 1.016 1.27)
			(layers "B.Cu" "B.Mask" "B.Paste")
			(net "GND")
		)
	)
	(footprint ""
		(layer "B.Cu")
		(at 363.217206 -261.747762 90)
		(property "Reference" "C2137"
			(at 0 0 90)
			(layer "B.SilkS")
			(hide yes)
			(effects
				(font
					(size 1.27 1.27)
				)
				(justify mirror)
			)
		)
		(property "Value" ""
			(at 0 0 90)
			(layer "B.Fab")
			(effects
				(font
					(size 1.27 1.27)
				)
				(justify mirror)
			)
		)
		(duplicate_pad_numbers_are_jumpers no)
		(fp_line
			(start 0.7874 -0.4064)
			(end -0.7874 -0.4064)
			(stroke
				(width 0.1524)
				(type default)
			)
			(layer "B.SilkS")
		)
		(fp_line
			(start -0.7874 -0.4064)
			(end -0.7874 0.4064)
			(stroke
				(width 0.1524)
				(type default)
			)
			(layer "B.SilkS")
		)
		(fp_line
			(start 0.7874 0.4064)
			(end 0.7874 -0.4064)
			(stroke
				(width 0.1524)
				(type default)
			)
			(layer "B.SilkS")
		)
		(fp_line
			(start -0.7874 0.4064)
			(end 0.7874 0.4064)
			(stroke
				(width 0.1524)
				(type default)
			)
			(layer "B.SilkS")
		)
		(fp_line
			(start 0.67945 -0.305054)
			(end 0.12065 -0.305054)
			(stroke
				(width 0.1)
				(type default)
			)
			(layer "B.Fab")
		)
		(fp_line
			(start 0.12065 -0.305054)
			(end 0.12065 -0.2794)
			(stroke
				(width 0.1)
				(type default)
			)
			(layer "B.Fab")
		)
		(fp_line
			(start -0.12065 -0.3048)
			(end -0.67945 -0.3048)
			(stroke
				(width 0.1)
				(type default)
			)
			(layer "B.Fab")
		)
		(fp_line
			(start -0.67945 -0.3048)
			(end -0.67945 0.3048)
			(stroke
				(width 0.1)
				(type default)
			)
			(layer "B.Fab")
		)
		(fp_line
			(start 0.12065 -0.2794)
			(end -0.12065 -0.2794)
			(stroke
				(width 0.1)
				(type default)
			)
			(layer "B.Fab")
		)
		(fp_line
			(start -0.12065 -0.2794)
			(end -0.12065 -0.3048)
			(stroke
				(width 0.1)
				(type default)
			)
			(layer "B.Fab")
		)
		(fp_line
			(start 0.12065 0.2794)
			(end 0.12065 0.3048)
			(stroke
				(width 0.1)
				(type default)
			)
			(layer "B.Fab")
		)
		(fp_line
			(start -0.120396 0.2794)
			(end 0.12065 0.2794)
			(stroke
				(width 0.1)
				(type default)
			)
			(layer "B.Fab")
		)
		(fp_line
			(start 0.67945 0.3048)
			(end 0.67945 -0.305054)
			(stroke
				(width 0.1)
				(type default)
			)
			(layer "B.Fab")
		)
		(fp_line
			(start 0.12065 0.3048)
			(end 0.67945 0.3048)
			(stroke
				(width 0.1)
				(type default)
			)
			(layer "B.Fab")
		)
		(fp_line
			(start -0.120396 0.3048)
			(end -0.120396 0.2794)
			(stroke
				(width 0.1)
				(type default)
			)
			(layer "B.Fab")
		)
		(fp_line
			(start -0.67945 0.3048)
			(end -0.120396 0.3048)
			(stroke
				(width 0.1)
				(type default)
			)
			(layer "B.Fab")
		)
		(pad "1" smd circle
			(at 0.40005 0 270)
			(size 0 0)
			(layers "B.Cu" "B.Mask" "B.Paste")
			(net "PVDD11_S3_P0")
		)
		(pad "2" smd circle
			(at -0.40005 0 270)
			(size 0 0)
			(layers "B.Cu" "B.Mask" "B.Paste")
			(net "GND")
		)
	)
	(footprint ""
		(layer "B.Cu")
		(at 216.212674 -76.591668 180)
		(property "Reference" "R3211"
			(at 0 0 0)
			(layer "B.SilkS")
			(hide yes)
			(effects
				(font
					(size 1.27 1.27)
				)
				(justify mirror)
			)
		)
		(property "Value" ""
			(at 0 0 0)
			(layer "B.Fab")
			(effects
				(font
					(size 1.27 1.27)
				)
				(justify mirror)
			)
		)
		(duplicate_pad_numbers_are_jumpers no)
		(fp_line
			(start 0.7874 0.4064)
			(end 0.7874 -0.4064)
			(stroke
				(width 0.1524)
				(type default)
			)
			(layer "B.SilkS")
		)
		(fp_line
			(start 0.7874 -0.4064)
			(end -0.7874 -0.4064)
			(stroke
				(width 0.1524)
				(type default)
			)
			(layer "B.SilkS")
		)
		(fp_line
			(start -0.7874 0.4064)
			(end 0.7874 0.4064)
			(stroke
				(width 0.1524)
				(type default)
			)
			(layer "B.SilkS")
		)
		(fp_line
			(start -0.7874 -0.4064)
			(end -0.7874 0.4064)
			(stroke
				(width 0.1524)
				(type default)
			)
			(layer "B.SilkS")
		)
		(fp_line
			(start 0.67945 0.3048)
			(end 0.67945 -0.305054)
			(stroke
				(width 0.1)
				(type default)
			)
			(layer "B.Fab")
		)
		(fp_line
			(start 0.67945 -0.305054)
			(end 0.12065 -0.305054)
			(stroke
				(width 0.1)
				(type default)
			)
			(layer "B.Fab")
		)
		(fp_line
			(start 0.12065 0.3048)
			(end 0.67945 0.3048)
			(stroke
				(width 0.1)
				(type default)
			)
			(layer "B.Fab")
		)
		(fp_line
			(start 0.12065 0.2794)
			(end 0.12065 0.3048)
			(stroke
				(width 0.1)
				(type default)
			)
			(layer "B.Fab")
		)
		(fp_line
			(start 0.12065 -0.2794)
			(end -0.12065 -0.2794)
			(stroke
				(width 0.1)
				(type default)
			)
			(layer "B.Fab")
		)
		(fp_line
			(start 0.12065 -0.305054)
			(end 0.12065 -0.2794)
			(stroke
				(width 0.1)
				(type default)
			)
			(layer "B.Fab")
		)
		(fp_line
			(start -0.120396 0.3048)
			(end -0.120396 0.2794)
			(stroke
				(width 0.1)
				(type default)
			)
			(layer "B.Fab")
		)
		(fp_line
			(start -0.120396 0.2794)
			(end 0.12065 0.2794)
			(stroke
				(width 0.1)
				(type default)
			)
			(layer "B.Fab")
		)
		(fp_line
			(start -0.12065 -0.2794)
			(end -0.12065 -0.3048)
			(stroke
				(width 0.1)
				(type default)
			)
			(layer "B.Fab")
		)
		(fp_line
			(start -0.12065 -0.3048)
			(end -0.67945 -0.3048)
			(stroke
				(width 0.1)
				(type default)
			)
			(layer "B.Fab")
		)
		(fp_line
			(start -0.67945 0.3048)
			(end -0.120396 0.3048)
			(stroke
				(width 0.1)
				(type default)
			)
			(layer "B.Fab")
		)
		(fp_line
			(start -0.67945 -0.3048)
			(end -0.67945 0.3048)
			(stroke
				(width 0.1)
				(type default)
			)
			(layer "B.Fab")
		)
		(pad "1" smd circle
			(at 0.40005 0)
			(size 0 0)
			(layers "B.Cu" "B.Mask" "B.Paste")
			(net "NCSI_BMC_RXD0_R1")
		)
		(pad "2" smd circle
			(at -0.40005 0)
			(size 0 0)
			(layers "B.Cu" "B.Mask" "B.Paste")
			(net "RMII_OCP_BMC_RXD_0")
		)
	)
	(footprint ""
		(layer "B.Cu")
		(at 149.54631 -388.011162 -90)
		(property "Reference" "C411"
			(at 0 0 90)
			(layer "B.SilkS")
			(hide yes)
			(effects
				(font
					(size 1.27 1.27)
				)
				(justify mirror)
			)
		)
		(property "Value" ""
			(at 0 0 90)
			(layer "B.Fab")
			(effects
				(font
					(size 1.27 1.27)
				)
				(justify mirror)
			)
		)
		(duplicate_pad_numbers_are_jumpers no)
		(fp_line
			(start -0.299974 0.150114)
			(end 0.299974 0.150114)
			(stroke
				(width 0.1)
				(type default)
			)
			(layer "B.Fab")
		)
		(fp_line
			(start 0.299974 0.150114)
			(end 0.299974 -0.150114)
			(stroke
				(width 0.1)
				(type default)
			)
			(layer "B.Fab")
		)
		(fp_line
			(start -0.299974 -0.150114)
			(end -0.299974 0.150114)
			(stroke
				(width 0.1)
				(type default)
			)
			(layer "B.Fab")
		)
		(fp_line
			(start 0.299974 -0.150114)
			(end -0.299974 -0.150114)
			(stroke
				(width 0.1)
				(type default)
			)
			(layer "B.Fab")
		)
		(pad "1" smd rect
			(at 0.2667 0 90)
			(size 0.3048 0.381)
			(layers "B.Cu" "B.Mask" "B.Paste")
			(net "P0V9_CPU1_RT2_2A")
		)
		(pad "2" smd rect
			(at -0.2667 0 90)
			(size 0.3048 0.381)
			(layers "B.Cu" "B.Mask" "B.Paste")
			(net "GND")
		)
	)
	(footprint ""
		(layer "B.Cu")
		(at 58.580782 -148.322792 180)
		(property "Reference" "PR403"
			(at 0 0 0)
			(layer "B.SilkS")
			(hide yes)
			(effects
				(font
					(size 1.27 1.27)
				)
				(justify mirror)
			)
		)
		(property "Value" ""
			(at 0 0 0)
			(layer "B.Fab")
			(effects
				(font
					(size 1.27 1.27)
				)
				(justify mirror)
			)
		)
		(duplicate_pad_numbers_are_jumpers no)
		(fp_line
			(start 0.7874 0.4064)
			(end 0.7874 -0.4064)
			(stroke
				(width 0.1524)
				(type default)
			)
			(layer "B.SilkS")
		)
		(fp_line
			(start 0.7874 -0.4064)
			(end -0.7874 -0.4064)
			(stroke
				(width 0.1524)
				(type default)
			)
			(layer "B.SilkS")
		)
		(fp_line
			(start -0.7874 0.4064)
			(end 0.7874 0.4064)
			(stroke
				(width 0.1524)
				(type default)
			)
			(layer "B.SilkS")
		)
		(fp_line
			(start -0.7874 -0.4064)
			(end -0.7874 0.4064)
			(stroke
				(width 0.1524)
				(type default)
			)
			(layer "B.SilkS")
		)
		(fp_line
			(start 0.67945 0.3048)
			(end 0.67945 -0.305054)
			(stroke
				(width 0.1)
				(type default)
			)
			(layer "B.Fab")
		)
		(fp_line
			(start 0.67945 -0.305054)
			(end 0.12065 -0.305054)
			(stroke
				(width 0.1)
				(type default)
			)
			(layer "B.Fab")
		)
		(fp_line
			(start 0.12065 0.3048)
			(end 0.67945 0.3048)
			(stroke
				(width 0.1)
				(type default)
			)
			(layer "B.Fab")
		)
		(fp_line
			(start 0.12065 0.2794)
			(end 0.12065 0.3048)
			(stroke
				(width 0.1)
				(type default)
			)
			(layer "B.Fab")
		)
		(fp_line
			(start 0.12065 -0.2794)
			(end -0.12065 -0.2794)
			(stroke
				(width 0.1)
				(type default)
			)
			(layer "B.Fab")
		)
		(fp_line
			(start 0.12065 -0.305054)
			(end 0.12065 -0.2794)
			(stroke
				(width 0.1)
				(type default)
			)
			(layer "B.Fab")
		)
		(fp_line
			(start -0.120396 0.3048)
			(end -0.120396 0.2794)
			(stroke
				(width 0.1)
				(type default)
			)
			(layer "B.Fab")
		)
		(fp_line
			(start -0.120396 0.2794)
			(end 0.12065 0.2794)
			(stroke
				(width 0.1)
				(type default)
			)
			(layer "B.Fab")
		)
		(fp_line
			(start -0.12065 -0.2794)
			(end -0.12065 -0.3048)
			(stroke
				(width 0.1)
				(type default)
			)
			(layer "B.Fab")
		)
		(fp_line
			(start -0.12065 -0.3048)
			(end -0.67945 -0.3048)
			(stroke
				(width 0.1)
				(type default)
			)
			(layer "B.Fab")
		)
		(fp_line
			(start -0.67945 0.3048)
			(end -0.120396 0.3048)
			(stroke
				(width 0.1)
				(type default)
			)
			(layer "B.Fab")
		)
		(fp_line
			(start -0.67945 -0.3048)
			(end -0.67945 0.3048)
			(stroke
				(width 0.1)
				(type default)
			)
			(layer "B.Fab")
		)
		(pad "1" smd circle
			(at 0.40005 0)
			(size 0 0)
			(layers "B.Cu" "B.Mask" "B.Paste")
			(net "PVDD18_S5_P1")
		)
		(pad "2" smd circle
			(at -0.40005 0)
			(size 0 0)
			(layers "B.Cu" "B.Mask" "B.Paste")
			(net "GND")
		)
	)
	(footprint ""
		(layer "B.Cu")
		(at 349.355156 -340.99373 -90)
		(property "Reference" "PR416"
			(at 0 0 90)
			(layer "B.SilkS")
			(hide yes)
			(effects
				(font
					(size 1.27 1.27)
				)
				(justify mirror)
			)
		)
		(property "Value" ""
			(at 0 0 90)
			(layer "B.Fab")
			(effects
				(font
					(size 1.27 1.27)
				)
				(justify mirror)
			)
		)
		(duplicate_pad_numbers_are_jumpers no)
		(fp_line
			(start -0.7874 0.4064)
			(end 0.7874 0.4064)
			(stroke
				(width 0.1524)
				(type default)
			)
			(layer "B.SilkS")
		)
		(fp_line
			(start 0.7874 0.4064)
			(end 0.7874 -0.4064)
			(stroke
				(width 0.1524)
				(type default)
			)
			(layer "B.SilkS")
		)
		(fp_line
			(start -0.7874 -0.4064)
			(end -0.7874 0.4064)
			(stroke
				(width 0.1524)
				(type default)
			)
			(layer "B.SilkS")
		)
		(fp_line
			(start 0.7874 -0.4064)
			(end -0.7874 -0.4064)
			(stroke
				(width 0.1524)
				(type default)
			)
			(layer "B.SilkS")
		)
		(fp_line
			(start -0.67945 0.3048)
			(end -0.120396 0.3048)
			(stroke
				(width 0.1)
				(type default)
			)
			(layer "B.Fab")
		)
		(fp_line
			(start -0.120396 0.3048)
			(end -0.120396 0.2794)
			(stroke
				(width 0.1)
				(type default)
			)
			(layer "B.Fab")
		)
		(fp_line
			(start 0.12065 0.3048)
			(end 0.67945 0.3048)
			(stroke
				(width 0.1)
				(type default)
			)
			(layer "B.Fab")
		)
		(fp_line
			(start 0.67945 0.3048)
			(end 0.67945 -0.305054)
			(stroke
				(width 0.1)
				(type default)
			)
			(layer "B.Fab")
		)
		(fp_line
			(start -0.120396 0.2794)
			(end 0.12065 0.2794)
			(stroke
				(width 0.1)
				(type default)
			)
			(layer "B.Fab")
		)
		(fp_line
			(start 0.12065 0.2794)
			(end 0.12065 0.3048)
			(stroke
				(width 0.1)
				(type default)
			)
			(layer "B.Fab")
		)
		(fp_line
			(start -0.12065 -0.2794)
			(end -0.12065 -0.3048)
			(stroke
				(width 0.1)
				(type default)
			)
			(layer "B.Fab")
		)
		(fp_line
			(start 0.12065 -0.2794)
			(end -0.12065 -0.2794)
			(stroke
				(width 0.1)
				(type default)
			)
			(layer "B.Fab")
		)
		(fp_line
			(start -0.67945 -0.3048)
			(end -0.67945 0.3048)
			(stroke
				(width 0.1)
				(type default)
			)
			(layer "B.Fab")
		)
		(fp_line
			(start -0.12065 -0.3048)
			(end -0.67945 -0.3048)
			(stroke
				(width 0.1)
				(type default)
			)
			(layer "B.Fab")
		)
		(fp_line
			(start 0.12065 -0.305054)
			(end 0.12065 -0.2794)
			(stroke
				(width 0.1)
				(type default)
			)
			(layer "B.Fab")
		)
		(fp_line
			(start 0.67945 -0.305054)
			(end 0.12065 -0.305054)
			(stroke
				(width 0.1)
				(type default)
			)
			(layer "B.Fab")
		)
		(pad "1" smd circle
			(at 0.40005 0 90)
			(size 0 0)
			(layers "B.Cu" "B.Mask" "B.Paste")
			(net "PVDDCR_CPU1_P0_PVCC")
		)
		(pad "2" smd circle
			(at -0.40005 0 90)
			(size 0 0)
			(layers "B.Cu" "B.Mask" "B.Paste")
			(net "PVDDCR_CPU1_P0_VCC6")
		)
	)
	(footprint ""
		(layer "B.Cu")
		(at 406.746202 -396.393162 -90)
		(property "Reference" "C985"
			(at 0 0 90)
			(layer "B.SilkS")
			(hide yes)
			(effects
				(font
					(size 1.27 1.27)
				)
				(justify mirror)
			)
		)
		(property "Value" ""
			(at 0 0 90)
			(layer "B.Fab")
			(effects
				(font
					(size 1.27 1.27)
				)
				(justify mirror)
			)
		)
		(duplicate_pad_numbers_are_jumpers no)
		(fp_line
			(start -0.299974 0.150114)
			(end 0.299974 0.150114)
			(stroke
				(width 0.1)
				(type default)
			)
			(layer "B.Fab")
		)
		(fp_line
			(start 0.299974 0.150114)
			(end 0.299974 -0.150114)
			(stroke
				(width 0.1)
				(type default)
			)
			(layer "B.Fab")
		)
		(fp_line
			(start -0.299974 -0.150114)
			(end -0.299974 0.150114)
			(stroke
				(width 0.1)
				(type default)
			)
			(layer "B.Fab")
		)
		(fp_line
			(start 0.299974 -0.150114)
			(end -0.299974 -0.150114)
			(stroke
				(width 0.1)
				(type default)
			)
			(layer "B.Fab")
		)
		(pad "1" smd rect
			(at 0.2667 0 90)
			(size 0.3048 0.381)
			(layers "B.Cu" "B.Mask" "B.Paste")
			(net "P0V9_CPU0_RT2_2A")
		)
		(pad "2" smd rect
			(at -0.2667 0 90)
			(size 0.3048 0.381)
			(layers "B.Cu" "B.Mask" "B.Paste")
			(net "GND")
		)
	)
	(footprint ""
		(layer "B.Cu")
		(at 430.119282 -437.392572 -90)
		(property "Reference" "R4570"
			(at 0 0 90)
			(layer "B.SilkS")
			(hide yes)
			(effects
				(font
					(size 1.27 1.27)
				)
				(justify mirror)
			)
		)
		(property "Value" ""
			(at 0 0 90)
			(layer "B.Fab")
			(effects
				(font
					(size 1.27 1.27)
				)
				(justify mirror)
			)
		)
		(duplicate_pad_numbers_are_jumpers no)
		(fp_line
			(start -0.7874 0.4064)
			(end 0.7874 0.4064)
			(stroke
				(width 0.1524)
				(type default)
			)
			(layer "B.SilkS")
		)
		(fp_line
			(start 0.7874 0.4064)
			(end 0.7874 -0.4064)
			(stroke
				(width 0.1524)
				(type default)
			)
			(layer "B.SilkS")
		)
		(fp_line
			(start -0.7874 -0.4064)
			(end -0.7874 0.4064)
			(stroke
				(width 0.1524)
				(type default)
			)
			(layer "B.SilkS")
		)
		(fp_line
			(start 0.7874 -0.4064)
			(end -0.7874 -0.4064)
			(stroke
				(width 0.1524)
				(type default)
			)
			(layer "B.SilkS")
		)
		(fp_line
			(start -0.67945 0.3048)
			(end -0.120396 0.3048)
			(stroke
				(width 0.1)
				(type default)
			)
			(layer "B.Fab")
		)
		(fp_line
			(start -0.120396 0.3048)
			(end -0.120396 0.2794)
			(stroke
				(width 0.1)
				(type default)
			)
			(layer "B.Fab")
		)
		(fp_line
			(start 0.12065 0.3048)
			(end 0.67945 0.3048)
			(stroke
				(width 0.1)
				(type default)
			)
			(layer "B.Fab")
		)
		(fp_line
			(start 0.67945 0.3048)
			(end 0.67945 -0.305054)
			(stroke
				(width 0.1)
				(type default)
			)
			(layer "B.Fab")
		)
		(fp_line
			(start -0.120396 0.2794)
			(end 0.12065 0.2794)
			(stroke
				(width 0.1)
				(type default)
			)
			(layer "B.Fab")
		)
		(fp_line
			(start 0.12065 0.2794)
			(end 0.12065 0.3048)
			(stroke
				(width 0.1)
				(type default)
			)
			(layer "B.Fab")
		)
		(fp_line
			(start -0.12065 -0.2794)
			(end -0.12065 -0.3048)
			(stroke
				(width 0.1)
				(type default)
			)
			(layer "B.Fab")
		)
		(fp_line
			(start 0.12065 -0.2794)
			(end -0.12065 -0.2794)
			(stroke
				(width 0.1)
				(type default)
			)
			(layer "B.Fab")
		)
		(fp_line
			(start -0.67945 -0.3048)
			(end -0.67945 0.3048)
			(stroke
				(width 0.1)
				(type default)
			)
			(layer "B.Fab")
		)
		(fp_line
			(start -0.12065 -0.3048)
			(end -0.67945 -0.3048)
			(stroke
				(width 0.1)
				(type default)
			)
			(layer "B.Fab")
		)
		(fp_line
			(start 0.12065 -0.305054)
			(end 0.12065 -0.2794)
			(stroke
				(width 0.1)
				(type default)
			)
			(layer "B.Fab")
		)
		(fp_line
			(start 0.67945 -0.305054)
			(end 0.12065 -0.305054)
			(stroke
				(width 0.1)
				(type default)
			)
			(layer "B.Fab")
		)
		(pad "1" smd circle
			(at 0.40005 0 90)
			(size 0 0)
			(layers "B.Cu" "B.Mask" "B.Paste")
			(net "GPU_3V3IO_RSVD3")
		)
		(pad "2" smd circle
			(at -0.40005 0 90)
			(size 0 0)
			(layers "B.Cu" "B.Mask" "B.Paste")
			(net "GPU_3V3IO_RSVD3_ISO")
		)
	)
	(footprint ""
		(layer "B.Cu")
		(at 137.153142 -382.8796 180)
		(property "Reference" "R6903"
			(at 0 0 0)
			(layer "B.SilkS")
			(hide yes)
			(effects
				(font
					(size 1.27 1.27)
				)
				(justify mirror)
			)
		)
		(property "Value" ""
			(at 0 0 0)
			(layer "B.Fab")
			(effects
				(font
					(size 1.27 1.27)
				)
				(justify mirror)
			)
		)
		(duplicate_pad_numbers_are_jumpers no)
		(fp_line
			(start 0.32512 0.175006)
			(end 0.32512 -0.175006)
			(stroke
				(width 0.1)
				(type default)
			)
			(layer "B.Fab")
		)
		(fp_line
			(start 0.32512 -0.175006)
			(end -0.32512 -0.175006)
			(stroke
				(width 0.1)
				(type default)
			)
			(layer "B.Fab")
		)
		(fp_line
			(start -0.32512 0.175006)
			(end 0.32512 0.175006)
			(stroke
				(width 0.1)
				(type default)
			)
			(layer "B.Fab")
		)
		(fp_line
			(start -0.32512 -0.175006)
			(end -0.32512 0.175006)
			(stroke
				(width 0.1)
				(type default)
			)
			(layer "B.Fab")
		)
		(pad "1" smd rect
			(at 0.2667 0)
			(size 0.3048 0.381)
			(layers "B.Cu" "B.Mask" "B.Paste")
			(net "NCF_CPU1_P3_GND")
		)
		(pad "2" smd rect
			(at -0.2667 0 180)
			(size 0.3048 0.381)
			(layers "B.Cu" "B.Mask" "B.Paste")
			(net "GND")
		)
	)
	(footprint ""
		(layer "B.Cu")
		(at 241.173 -224.028 90)
		(property "Reference" "C612"
			(at 0 0 90)
			(layer "B.SilkS")
			(hide yes)
			(effects
				(font
					(size 1.27 1.27)
				)
				(justify mirror)
			)
		)
		(property "Value" ""
			(at 0 0 90)
			(layer "B.Fab")
			(effects
				(font
					(size 1.27 1.27)
				)
				(justify mirror)
			)
		)
		(duplicate_pad_numbers_are_jumpers no)
		(fp_line
			(start 0.7874 -0.4064)
			(end -0.7874 -0.4064)
			(stroke
				(width 0.1524)
				(type default)
			)
			(layer "B.SilkS")
		)
		(fp_line
			(start -0.7874 -0.4064)
			(end -0.7874 0.4064)
			(stroke
				(width 0.1524)
				(type default)
			)
			(layer "B.SilkS")
		)
		(fp_line
			(start 0.7874 0.4064)
			(end 0.7874 -0.4064)
			(stroke
				(width 0.1524)
				(type default)
			)
			(layer "B.SilkS")
		)
		(fp_line
			(start -0.7874 0.4064)
			(end 0.7874 0.4064)
			(stroke
				(width 0.1524)
				(type default)
			)
			(layer "B.SilkS")
		)
		(fp_line
			(start 0.67945 -0.305054)
			(end 0.12065 -0.305054)
			(stroke
				(width 0.1)
				(type default)
			)
			(layer "B.Fab")
		)
		(fp_line
			(start 0.12065 -0.305054)
			(end 0.12065 -0.2794)
			(stroke
				(width 0.1)
				(type default)
			)
			(layer "B.Fab")
		)
		(fp_line
			(start -0.12065 -0.3048)
			(end -0.67945 -0.3048)
			(stroke
				(width 0.1)
				(type default)
			)
			(layer "B.Fab")
		)
		(fp_line
			(start -0.67945 -0.3048)
			(end -0.67945 0.3048)
			(stroke
				(width 0.1)
				(type default)
			)
			(layer "B.Fab")
		)
		(fp_line
			(start 0.12065 -0.2794)
			(end -0.12065 -0.2794)
			(stroke
				(width 0.1)
				(type default)
			)
			(layer "B.Fab")
		)
		(fp_line
			(start -0.12065 -0.2794)
			(end -0.12065 -0.3048)
			(stroke
				(width 0.1)
				(type default)
			)
			(layer "B.Fab")
		)
		(fp_line
			(start 0.12065 0.2794)
			(end 0.12065 0.3048)
			(stroke
				(width 0.1)
				(type default)
			)
			(layer "B.Fab")
		)
		(fp_line
			(start -0.120396 0.2794)
			(end 0.12065 0.2794)
			(stroke
				(width 0.1)
				(type default)
			)
			(layer "B.Fab")
		)
		(fp_line
			(start 0.67945 0.3048)
			(end 0.67945 -0.305054)
			(stroke
				(width 0.1)
				(type default)
			)
			(layer "B.Fab")
		)
		(fp_line
			(start 0.12065 0.3048)
			(end 0.67945 0.3048)
			(stroke
				(width 0.1)
				(type default)
			)
			(layer "B.Fab")
		)
		(fp_line
			(start -0.120396 0.3048)
			(end -0.120396 0.2794)
			(stroke
				(width 0.1)
				(type default)
			)
			(layer "B.Fab")
		)
		(fp_line
			(start -0.67945 0.3048)
			(end -0.120396 0.3048)
			(stroke
				(width 0.1)
				(type default)
			)
			(layer "B.Fab")
		)
		(pad "1" smd circle
			(at 0.40005 0 270)
			(size 0 0)
			(layers "B.Cu" "B.Mask" "B.Paste")
			(net "PVDD18_S5_P0")
		)
		(pad "2" smd circle
			(at -0.40005 0 270)
			(size 0 0)
			(layers "B.Cu" "B.Mask" "B.Paste")
			(net "GND")
		)
	)
	(footprint ""
		(layer "B.Cu")
		(at 140.61948 -9.083548 -90)
		(property "Reference" "R3776"
			(at 0 0 90)
			(layer "B.SilkS")
			(hide yes)
			(effects
				(font
					(size 1.27 1.27)
				)
				(justify mirror)
			)
		)
		(property "Value" ""
			(at 0 0 90)
			(layer "B.Fab")
			(effects
				(font
					(size 1.27 1.27)
				)
				(justify mirror)
			)
		)
		(duplicate_pad_numbers_are_jumpers no)
		(fp_line
			(start -0.7874 0.4064)
			(end 0.7874 0.4064)
			(stroke
				(width 0.1524)
				(type default)
			)
			(layer "B.SilkS")
		)
		(fp_line
			(start 0.7874 0.4064)
			(end 0.7874 -0.4064)
			(stroke
				(width 0.1524)
				(type default)
			)
			(layer "B.SilkS")
		)
		(fp_line
			(start -0.7874 -0.4064)
			(end -0.7874 0.4064)
			(stroke
				(width 0.1524)
				(type default)
			)
			(layer "B.SilkS")
		)
		(fp_line
			(start 0.7874 -0.4064)
			(end -0.7874 -0.4064)
			(stroke
				(width 0.1524)
				(type default)
			)
			(layer "B.SilkS")
		)
		(fp_line
			(start -0.67945 0.3048)
			(end -0.120396 0.3048)
			(stroke
				(width 0.1)
				(type default)
			)
			(layer "B.Fab")
		)
		(fp_line
			(start -0.120396 0.3048)
			(end -0.120396 0.2794)
			(stroke
				(width 0.1)
				(type default)
			)
			(layer "B.Fab")
		)
		(fp_line
			(start 0.12065 0.3048)
			(end 0.67945 0.3048)
			(stroke
				(width 0.1)
				(type default)
			)
			(layer "B.Fab")
		)
		(fp_line
			(start 0.67945 0.3048)
			(end 0.67945 -0.305054)
			(stroke
				(width 0.1)
				(type default)
			)
			(layer "B.Fab")
		)
		(fp_line
			(start -0.120396 0.2794)
			(end 0.12065 0.2794)
			(stroke
				(width 0.1)
				(type default)
			)
			(layer "B.Fab")
		)
		(fp_line
			(start 0.12065 0.2794)
			(end 0.12065 0.3048)
			(stroke
				(width 0.1)
				(type default)
			)
			(layer "B.Fab")
		)
		(fp_line
			(start -0.12065 -0.2794)
			(end -0.12065 -0.3048)
			(stroke
				(width 0.1)
				(type default)
			)
			(layer "B.Fab")
		)
		(fp_line
			(start 0.12065 -0.2794)
			(end -0.12065 -0.2794)
			(stroke
				(width 0.1)
				(type default)
			)
			(layer "B.Fab")
		)
		(fp_line
			(start -0.67945 -0.3048)
			(end -0.67945 0.3048)
			(stroke
				(width 0.1)
				(type default)
			)
			(layer "B.Fab")
		)
		(fp_line
			(start -0.12065 -0.3048)
			(end -0.67945 -0.3048)
			(stroke
				(width 0.1)
				(type default)
			)
			(layer "B.Fab")
		)
		(fp_line
			(start 0.12065 -0.305054)
			(end 0.12065 -0.2794)
			(stroke
				(width 0.1)
				(type default)
			)
			(layer "B.Fab")
		)
		(fp_line
			(start 0.67945 -0.305054)
			(end 0.12065 -0.305054)
			(stroke
				(width 0.1)
				(type default)
			)
			(layer "B.Fab")
		)
		(pad "1" smd circle
			(at 0.40005 0 90)
			(size 0 0)
			(layers "B.Cu" "B.Mask" "B.Paste")
			(net "FM_UARTSW_MSB_N")
		)
		(pad "2" smd circle
			(at -0.40005 0 90)
			(size 0 0)
			(layers "B.Cu" "B.Mask" "B.Paste")
			(net "FM_UARTSW_MSB_R")
		)
	)
	(footprint ""
		(layer "B.Cu")
		(at 255.905 -335.13268 180)
		(property "Reference" "R832"
			(at 0 0 0)
			(layer "B.SilkS")
			(hide yes)
			(effects
				(font
					(size 1.27 1.27)
				)
				(justify mirror)
			)
		)
		(property "Value" ""
			(at 0 0 0)
			(layer "B.Fab")
			(effects
				(font
					(size 1.27 1.27)
				)
				(justify mirror)
			)
		)
		(duplicate_pad_numbers_are_jumpers no)
		(fp_line
			(start 0.32512 0.175006)
			(end 0.32512 -0.175006)
			(stroke
				(width 0.1)
				(type default)
			)
			(layer "B.Fab")
		)
		(fp_line
			(start 0.32512 -0.175006)
			(end -0.32512 -0.175006)
			(stroke
				(width 0.1)
				(type default)
			)
			(layer "B.Fab")
		)
		(fp_line
			(start -0.32512 0.175006)
			(end 0.32512 0.175006)
			(stroke
				(width 0.1)
				(type default)
			)
			(layer "B.Fab")
		)
		(fp_line
			(start -0.32512 -0.175006)
			(end -0.32512 0.175006)
			(stroke
				(width 0.1)
				(type default)
			)
			(layer "B.Fab")
		)
		(pad "1" smd rect
			(at 0.2667 0)
			(size 0.3048 0.381)
			(layers "B.Cu" "B.Mask" "B.Paste")
			(net "SMB_RT_CPU0_P2_ROM_MUX_2D_R_SDA")
		)
		(pad "2" smd rect
			(at -0.2667 0 180)
			(size 0.3048 0.381)
			(layers "B.Cu" "B.Mask" "B.Paste")
			(net "SMB_RT_CPU0_P2_ROM_MUX_2D_SDA")
		)
	)
	(footprint ""
		(layer "B.Cu")
		(at 136.040114 -35.866578)
		(property "Reference" "C6037"
			(at 0 0 0)
			(layer "B.SilkS")
			(hide yes)
			(effects
				(font
					(size 1.27 1.27)
				)
				(justify mirror)
			)
		)
		(property "Value" ""
			(at 0 0 0)
			(layer "B.Fab")
			(effects
				(font
					(size 1.27 1.27)
				)
				(justify mirror)
			)
		)
		(duplicate_pad_numbers_are_jumpers no)
		(fp_line
			(start -0.7874 -0.4064)
			(end -0.7874 0.4064)
			(stroke
				(width 0.1524)
				(type default)
			)
			(layer "B.SilkS")
		)
		(fp_line
			(start -0.7874 0.4064)
			(end 0.7874 0.4064)
			(stroke
				(width 0.1524)
				(type default)
			)
			(layer "B.SilkS")
		)
		(fp_line
			(start 0.7874 -0.4064)
			(end -0.7874 -0.4064)
			(stroke
				(width 0.1524)
				(type default)
			)
			(layer "B.SilkS")
		)
		(fp_line
			(start 0.7874 0.4064)
			(end 0.7874 -0.4064)
			(stroke
				(width 0.1524)
				(type default)
			)
			(layer "B.SilkS")
		)
		(fp_line
			(start -0.67945 -0.3048)
			(end -0.67945 0.3048)
			(stroke
				(width 0.1)
				(type default)
			)
			(layer "B.Fab")
		)
		(fp_line
			(start -0.67945 0.3048)
			(end -0.120396 0.3048)
			(stroke
				(width 0.1)
				(type default)
			)
			(layer "B.Fab")
		)
		(fp_line
			(start -0.12065 -0.3048)
			(end -0.67945 -0.3048)
			(stroke
				(width 0.1)
				(type default)
			)
			(layer "B.Fab")
		)
		(fp_line
			(start -0.12065 -0.2794)
			(end -0.12065 -0.3048)
			(stroke
				(width 0.1)
				(type default)
			)
			(layer "B.Fab")
		)
		(fp_line
			(start -0.120396 0.2794)
			(end 0.12065 0.2794)
			(stroke
				(width 0.1)
				(type default)
			)
			(layer "B.Fab")
		)
		(fp_line
			(start -0.120396 0.3048)
			(end -0.120396 0.2794)
			(stroke
				(width 0.1)
				(type default)
			)
			(layer "B.Fab")
		)
		(fp_line
			(start 0.12065 -0.305054)
			(end 0.12065 -0.2794)
			(stroke
				(width 0.1)
				(type default)
			)
			(layer "B.Fab")
		)
		(fp_line
			(start 0.12065 -0.2794)
			(end -0.12065 -0.2794)
			(stroke
				(width 0.1)
				(type default)
			)
			(layer "B.Fab")
		)
		(fp_line
			(start 0.12065 0.2794)
			(end 0.12065 0.3048)
			(stroke
				(width 0.1)
				(type default)
			)
			(layer "B.Fab")
		)
		(fp_line
			(start 0.12065 0.3048)
			(end 0.67945 0.3048)
			(stroke
				(width 0.1)
				(type default)
			)
			(layer "B.Fab")
		)
		(fp_line
			(start 0.67945 -0.305054)
			(end 0.12065 -0.305054)
			(stroke
				(width 0.1)
				(type default)
			)
			(layer "B.Fab")
		)
		(fp_line
			(start 0.67945 0.3048)
			(end 0.67945 -0.305054)
			(stroke
				(width 0.1)
				(type default)
			)
			(layer "B.Fab")
		)
		(pad "1" smd circle
			(at 0.40005 0 180)
			(size 0 0)
			(layers "B.Cu" "B.Mask" "B.Paste")
			(net "P1V2_CPU0_USB_DVDD12")
		)
		(pad "2" smd circle
			(at -0.40005 0 180)
			(size 0 0)
			(layers "B.Cu" "B.Mask" "B.Paste")
			(net "GND")
		)
	)
	(footprint ""
		(layer "B.Cu")
		(at 367.614454 -267.498576)
		(property "Reference" "C2211"
			(at 0 0 0)
			(layer "B.SilkS")
			(hide yes)
			(effects
				(font
					(size 1.27 1.27)
				)
				(justify mirror)
			)
		)
		(property "Value" ""
			(at 0 0 0)
			(layer "B.Fab")
			(effects
				(font
					(size 1.27 1.27)
				)
				(justify mirror)
			)
		)
		(duplicate_pad_numbers_are_jumpers no)
		(fp_line
			(start -0.7874 -0.4064)
			(end -0.7874 0.4064)
			(stroke
				(width 0.1524)
				(type default)
			)
			(layer "B.SilkS")
		)
		(fp_line
			(start -0.7874 0.4064)
			(end 0.7874 0.4064)
			(stroke
				(width 0.1524)
				(type default)
			)
			(layer "B.SilkS")
		)
		(fp_line
			(start 0.7874 -0.4064)
			(end -0.7874 -0.4064)
			(stroke
				(width 0.1524)
				(type default)
			)
			(layer "B.SilkS")
		)
		(fp_line
			(start 0.7874 0.4064)
			(end 0.7874 -0.4064)
			(stroke
				(width 0.1524)
				(type default)
			)
			(layer "B.SilkS")
		)
		(fp_line
			(start -0.67945 -0.3048)
			(end -0.67945 0.3048)
			(stroke
				(width 0.1)
				(type default)
			)
			(layer "B.Fab")
		)
		(fp_line
			(start -0.67945 0.3048)
			(end -0.120396 0.3048)
			(stroke
				(width 0.1)
				(type default)
			)
			(layer "B.Fab")
		)
		(fp_line
			(start -0.12065 -0.3048)
			(end -0.67945 -0.3048)
			(stroke
				(width 0.1)
				(type default)
			)
			(layer "B.Fab")
		)
		(fp_line
			(start -0.12065 -0.2794)
			(end -0.12065 -0.3048)
			(stroke
				(width 0.1)
				(type default)
			)
			(layer "B.Fab")
		)
		(fp_line
			(start -0.120396 0.2794)
			(end 0.12065 0.2794)
			(stroke
				(width 0.1)
				(type default)
			)
			(layer "B.Fab")
		)
		(fp_line
			(start -0.120396 0.3048)
			(end -0.120396 0.2794)
			(stroke
				(width 0.1)
				(type default)
			)
			(layer "B.Fab")
		)
		(fp_line
			(start 0.12065 -0.305054)
			(end 0.12065 -0.2794)
			(stroke
				(width 0.1)
				(type default)
			)
			(layer "B.Fab")
		)
		(fp_line
			(start 0.12065 -0.2794)
			(end -0.12065 -0.2794)
			(stroke
				(width 0.1)
				(type default)
			)
			(layer "B.Fab")
		)
		(fp_line
			(start 0.12065 0.2794)
			(end 0.12065 0.3048)
			(stroke
				(width 0.1)
				(type default)
			)
			(layer "B.Fab")
		)
		(fp_line
			(start 0.12065 0.3048)
			(end 0.67945 0.3048)
			(stroke
				(width 0.1)
				(type default)
			)
			(layer "B.Fab")
		)
		(fp_line
			(start 0.67945 -0.305054)
			(end 0.12065 -0.305054)
			(stroke
				(width 0.1)
				(type default)
			)
			(layer "B.Fab")
		)
		(fp_line
			(start 0.67945 0.3048)
			(end 0.67945 -0.305054)
			(stroke
				(width 0.1)
				(type default)
			)
			(layer "B.Fab")
		)
		(pad "1" smd circle
			(at 0.40005 0 180)
			(size 0 0)
			(layers "B.Cu" "B.Mask" "B.Paste")
			(net "PVDDCR_CPU1_P0")
		)
		(pad "2" smd circle
			(at -0.40005 0 180)
			(size 0 0)
			(layers "B.Cu" "B.Mask" "B.Paste")
			(net "GND")
		)
	)
	(footprint ""
		(layer "B.Cu")
		(at 331.793342 -393.04468 180)
		(property "Reference" "R1033"
			(at 0 0 0)
			(layer "B.SilkS")
			(hide yes)
			(effects
				(font
					(size 1.27 1.27)
				)
				(justify mirror)
			)
		)
		(property "Value" ""
			(at 0 0 0)
			(layer "B.Fab")
			(effects
				(font
					(size 1.27 1.27)
				)
				(justify mirror)
			)
		)
		(duplicate_pad_numbers_are_jumpers no)
		(fp_line
			(start 0.32512 0.175006)
			(end 0.32512 -0.175006)
			(stroke
				(width 0.1)
				(type default)
			)
			(layer "B.Fab")
		)
		(fp_line
			(start 0.32512 -0.175006)
			(end -0.32512 -0.175006)
			(stroke
				(width 0.1)
				(type default)
			)
			(layer "B.Fab")
		)
		(fp_line
			(start -0.32512 0.175006)
			(end 0.32512 0.175006)
			(stroke
				(width 0.1)
				(type default)
			)
			(layer "B.Fab")
		)
		(fp_line
			(start -0.32512 -0.175006)
			(end -0.32512 0.175006)
			(stroke
				(width 0.1)
				(type default)
			)
			(layer "B.Fab")
		)
		(pad "1" smd rect
			(at 0.2667 0)
			(size 0.3048 0.381)
			(layers "B.Cu" "B.Mask" "B.Paste")
			(net "TEST1_RT_CPU0_P1")
		)
		(pad "2" smd rect
			(at -0.2667 0 180)
			(size 0.3048 0.381)
			(layers "B.Cu" "B.Mask" "B.Paste")
			(net "GND")
		)
	)
	(footprint ""
		(layer "B.Cu")
		(at 124.741432 -261.93623)
		(property "Reference" "C2435"
			(at 0 0 0)
			(layer "B.SilkS")
			(hide yes)
			(effects
				(font
					(size 1.27 1.27)
				)
				(justify mirror)
			)
		)
		(property "Value" ""
			(at 0 0 0)
			(layer "B.Fab")
			(effects
				(font
					(size 1.27 1.27)
				)
				(justify mirror)
			)
		)
		(duplicate_pad_numbers_are_jumpers no)
		(fp_line
			(start -0.7874 -0.4064)
			(end -0.7874 0.4064)
			(stroke
				(width 0.1524)
				(type default)
			)
			(layer "B.SilkS")
		)
		(fp_line
			(start -0.7874 0.4064)
			(end 0.7874 0.4064)
			(stroke
				(width 0.1524)
				(type default)
			)
			(layer "B.SilkS")
		)
		(fp_line
			(start 0.7874 -0.4064)
			(end -0.7874 -0.4064)
			(stroke
				(width 0.1524)
				(type default)
			)
			(layer "B.SilkS")
		)
		(fp_line
			(start 0.7874 0.4064)
			(end 0.7874 -0.4064)
			(stroke
				(width 0.1524)
				(type default)
			)
			(layer "B.SilkS")
		)
		(fp_line
			(start -0.67945 -0.3048)
			(end -0.67945 0.3048)
			(stroke
				(width 0.1)
				(type default)
			)
			(layer "B.Fab")
		)
		(fp_line
			(start -0.67945 0.3048)
			(end -0.120396 0.3048)
			(stroke
				(width 0.1)
				(type default)
			)
			(layer "B.Fab")
		)
		(fp_line
			(start -0.12065 -0.3048)
			(end -0.67945 -0.3048)
			(stroke
				(width 0.1)
				(type default)
			)
			(layer "B.Fab")
		)
		(fp_line
			(start -0.12065 -0.2794)
			(end -0.12065 -0.3048)
			(stroke
				(width 0.1)
				(type default)
			)
			(layer "B.Fab")
		)
		(fp_line
			(start -0.120396 0.2794)
			(end 0.12065 0.2794)
			(stroke
				(width 0.1)
				(type default)
			)
			(layer "B.Fab")
		)
		(fp_line
			(start -0.120396 0.3048)
			(end -0.120396 0.2794)
			(stroke
				(width 0.1)
				(type default)
			)
			(layer "B.Fab")
		)
		(fp_line
			(start 0.12065 -0.305054)
			(end 0.12065 -0.2794)
			(stroke
				(width 0.1)
				(type default)
			)
			(layer "B.Fab")
		)
		(fp_line
			(start 0.12065 -0.2794)
			(end -0.12065 -0.2794)
			(stroke
				(width 0.1)
				(type default)
			)
			(layer "B.Fab")
		)
		(fp_line
			(start 0.12065 0.2794)
			(end 0.12065 0.3048)
			(stroke
				(width 0.1)
				(type default)
			)
			(layer "B.Fab")
		)
		(fp_line
			(start 0.12065 0.3048)
			(end 0.67945 0.3048)
			(stroke
				(width 0.1)
				(type default)
			)
			(layer "B.Fab")
		)
		(fp_line
			(start 0.67945 -0.305054)
			(end 0.12065 -0.305054)
			(stroke
				(width 0.1)
				(type default)
			)
			(layer "B.Fab")
		)
		(fp_line
			(start 0.67945 0.3048)
			(end 0.67945 -0.305054)
			(stroke
				(width 0.1)
				(type default)
			)
			(layer "B.Fab")
		)
		(pad "1" smd circle
			(at 0.40005 0 180)
			(size 0 0)
			(layers "B.Cu" "B.Mask" "B.Paste")
			(net "PVDDCR_SOC_P1")
		)
		(pad "2" smd circle
			(at -0.40005 0 180)
			(size 0 0)
			(layers "B.Cu" "B.Mask" "B.Paste")
			(net "GND")
		)
	)
	(footprint ""
		(layer "B.Cu")
		(at 117.018562 -388.011162 -90)
		(property "Reference" "C450"
			(at 0 0 90)
			(layer "B.SilkS")
			(hide yes)
			(effects
				(font
					(size 1.27 1.27)
				)
				(justify mirror)
			)
		)
		(property "Value" ""
			(at 0 0 90)
			(layer "B.Fab")
			(effects
				(font
					(size 1.27 1.27)
				)
				(justify mirror)
			)
		)
		(duplicate_pad_numbers_are_jumpers no)
		(fp_line
			(start -0.299974 0.150114)
			(end 0.299974 0.150114)
			(stroke
				(width 0.1)
				(type default)
			)
			(layer "B.Fab")
		)
		(fp_line
			(start 0.299974 0.150114)
			(end 0.299974 -0.150114)
			(stroke
				(width 0.1)
				(type default)
			)
			(layer "B.Fab")
		)
		(fp_line
			(start -0.299974 -0.150114)
			(end -0.299974 0.150114)
			(stroke
				(width 0.1)
				(type default)
			)
			(layer "B.Fab")
		)
		(fp_line
			(start 0.299974 -0.150114)
			(end -0.299974 -0.150114)
			(stroke
				(width 0.1)
				(type default)
			)
			(layer "B.Fab")
		)
		(pad "1" smd rect
			(at 0.2667 0 90)
			(size 0.3048 0.381)
			(layers "B.Cu" "B.Mask" "B.Paste")
			(net "P0V9_CPU1_RT3_2A")
		)
		(pad "2" smd rect
			(at -0.2667 0 90)
			(size 0.3048 0.381)
			(layers "B.Cu" "B.Mask" "B.Paste")
			(net "GND")
		)
	)
	(footprint ""
		(layer "B.Cu")
		(at 105.960164 -256.505456 180)
		(property "Reference" "C2660"
			(at 0 0 0)
			(layer "B.SilkS")
			(hide yes)
			(effects
				(font
					(size 1.27 1.27)
				)
				(justify mirror)
			)
		)
		(property "Value" ""
			(at 0 0 0)
			(layer "B.Fab")
			(effects
				(font
					(size 1.27 1.27)
				)
				(justify mirror)
			)
		)
		(duplicate_pad_numbers_are_jumpers no)
		(fp_line
			(start 0.7874 0.4064)
			(end 0.7874 -0.4064)
			(stroke
				(width 0.1524)
				(type default)
			)
			(layer "B.SilkS")
		)
		(fp_line
			(start 0.7874 -0.4064)
			(end -0.7874 -0.4064)
			(stroke
				(width 0.1524)
				(type default)
			)
			(layer "B.SilkS")
		)
		(fp_line
			(start -0.7874 0.4064)
			(end 0.7874 0.4064)
			(stroke
				(width 0.1524)
				(type default)
			)
			(layer "B.SilkS")
		)
		(fp_line
			(start -0.7874 -0.4064)
			(end -0.7874 0.4064)
			(stroke
				(width 0.1524)
				(type default)
			)
			(layer "B.SilkS")
		)
		(fp_line
			(start 0.67945 0.3048)
			(end 0.67945 -0.305054)
			(stroke
				(width 0.1)
				(type default)
			)
			(layer "B.Fab")
		)
		(fp_line
			(start 0.67945 -0.305054)
			(end 0.12065 -0.305054)
			(stroke
				(width 0.1)
				(type default)
			)
			(layer "B.Fab")
		)
		(fp_line
			(start 0.12065 0.3048)
			(end 0.67945 0.3048)
			(stroke
				(width 0.1)
				(type default)
			)
			(layer "B.Fab")
		)
		(fp_line
			(start 0.12065 0.2794)
			(end 0.12065 0.3048)
			(stroke
				(width 0.1)
				(type default)
			)
			(layer "B.Fab")
		)
		(fp_line
			(start 0.12065 -0.2794)
			(end -0.12065 -0.2794)
			(stroke
				(width 0.1)
				(type default)
			)
			(layer "B.Fab")
		)
		(fp_line
			(start 0.12065 -0.305054)
			(end 0.12065 -0.2794)
			(stroke
				(width 0.1)
				(type default)
			)
			(layer "B.Fab")
		)
		(fp_line
			(start -0.120396 0.3048)
			(end -0.120396 0.2794)
			(stroke
				(width 0.1)
				(type default)
			)
			(layer "B.Fab")
		)
		(fp_line
			(start -0.120396 0.2794)
			(end 0.12065 0.2794)
			(stroke
				(width 0.1)
				(type default)
			)
			(layer "B.Fab")
		)
		(fp_line
			(start -0.12065 -0.2794)
			(end -0.12065 -0.3048)
			(stroke
				(width 0.1)
				(type default)
			)
			(layer "B.Fab")
		)
		(fp_line
			(start -0.12065 -0.3048)
			(end -0.67945 -0.3048)
			(stroke
				(width 0.1)
				(type default)
			)
			(layer "B.Fab")
		)
		(fp_line
			(start -0.67945 0.3048)
			(end -0.120396 0.3048)
			(stroke
				(width 0.1)
				(type default)
			)
			(layer "B.Fab")
		)
		(fp_line
			(start -0.67945 -0.3048)
			(end -0.67945 0.3048)
			(stroke
				(width 0.1)
				(type default)
			)
			(layer "B.Fab")
		)
		(pad "1" smd circle
			(at 0.40005 0)
			(size 0 0)
			(layers "B.Cu" "B.Mask" "B.Paste")
			(net "PVDD18_S5_P1")
		)
		(pad "2" smd circle
			(at -0.40005 0)
			(size 0 0)
			(layers "B.Cu" "B.Mask" "B.Paste")
			(net "GND")
		)
	)
	(footprint ""
		(layer "B.Cu")
		(at 146.3548 -13.772388 90)
		(property "Reference" "R4087"
			(at 0 0 90)
			(layer "B.SilkS")
			(hide yes)
			(effects
				(font
					(size 1.27 1.27)
				)
				(justify mirror)
			)
		)
		(property "Value" ""
			(at 0 0 90)
			(layer "B.Fab")
			(effects
				(font
					(size 1.27 1.27)
				)
				(justify mirror)
			)
		)
		(duplicate_pad_numbers_are_jumpers no)
		(fp_line
			(start 0.7874 -0.4064)
			(end -0.7874 -0.4064)
			(stroke
				(width 0.1524)
				(type default)
			)
			(layer "B.SilkS")
		)
		(fp_line
			(start -0.7874 -0.4064)
			(end -0.7874 0.4064)
			(stroke
				(width 0.1524)
				(type default)
			)
			(layer "B.SilkS")
		)
		(fp_line
			(start 0.7874 0.4064)
			(end 0.7874 -0.4064)
			(stroke
				(width 0.1524)
				(type default)
			)
			(layer "B.SilkS")
		)
		(fp_line
			(start -0.7874 0.4064)
			(end 0.7874 0.4064)
			(stroke
				(width 0.1524)
				(type default)
			)
			(layer "B.SilkS")
		)
		(fp_line
			(start 0.67945 -0.305054)
			(end 0.12065 -0.305054)
			(stroke
				(width 0.1)
				(type default)
			)
			(layer "B.Fab")
		)
		(fp_line
			(start 0.12065 -0.305054)
			(end 0.12065 -0.2794)
			(stroke
				(width 0.1)
				(type default)
			)
			(layer "B.Fab")
		)
		(fp_line
			(start -0.12065 -0.3048)
			(end -0.67945 -0.3048)
			(stroke
				(width 0.1)
				(type default)
			)
			(layer "B.Fab")
		)
		(fp_line
			(start -0.67945 -0.3048)
			(end -0.67945 0.3048)
			(stroke
				(width 0.1)
				(type default)
			)
			(layer "B.Fab")
		)
		(fp_line
			(start 0.12065 -0.2794)
			(end -0.12065 -0.2794)
			(stroke
				(width 0.1)
				(type default)
			)
			(layer "B.Fab")
		)
		(fp_line
			(start -0.12065 -0.2794)
			(end -0.12065 -0.3048)
			(stroke
				(width 0.1)
				(type default)
			)
			(layer "B.Fab")
		)
		(fp_line
			(start 0.12065 0.2794)
			(end 0.12065 0.3048)
			(stroke
				(width 0.1)
				(type default)
			)
			(layer "B.Fab")
		)
		(fp_line
			(start -0.120396 0.2794)
			(end 0.12065 0.2794)
			(stroke
				(width 0.1)
				(type default)
			)
			(layer "B.Fab")
		)
		(fp_line
			(start 0.67945 0.3048)
			(end 0.67945 -0.305054)
			(stroke
				(width 0.1)
				(type default)
			)
			(layer "B.Fab")
		)
		(fp_line
			(start 0.12065 0.3048)
			(end 0.67945 0.3048)
			(stroke
				(width 0.1)
				(type default)
			)
			(layer "B.Fab")
		)
		(fp_line
			(start -0.120396 0.3048)
			(end -0.120396 0.2794)
			(stroke
				(width 0.1)
				(type default)
			)
			(layer "B.Fab")
		)
		(fp_line
			(start -0.67945 0.3048)
			(end -0.120396 0.3048)
			(stroke
				(width 0.1)
				(type default)
			)
			(layer "B.Fab")
		)
		(pad "1" smd circle
			(at 0.40005 0 270)
			(size 0 0)
			(layers "B.Cu" "B.Mask" "B.Paste")
			(net "FW_RECOVERY_R")
		)
		(pad "2" smd circle
			(at -0.40005 0 270)
			(size 0 0)
			(layers "B.Cu" "B.Mask" "B.Paste")
			(net "FW_RECOVERY")
		)
	)
	(footprint ""
		(layer "B.Cu")
		(at 369.884706 -263.46531)
		(property "Reference" "C2647"
			(at 0 0 0)
			(layer "B.SilkS")
			(hide yes)
			(effects
				(font
					(size 1.27 1.27)
				)
				(justify mirror)
			)
		)
		(property "Value" ""
			(at 0 0 0)
			(layer "B.Fab")
			(effects
				(font
					(size 1.27 1.27)
				)
				(justify mirror)
			)
		)
		(duplicate_pad_numbers_are_jumpers no)
		(fp_line
			(start -0.7874 -0.4064)
			(end -0.7874 0.4064)
			(stroke
				(width 0.1524)
				(type default)
			)
			(layer "B.SilkS")
		)
		(fp_line
			(start -0.7874 0.4064)
			(end 0.7874 0.4064)
			(stroke
				(width 0.1524)
				(type default)
			)
			(layer "B.SilkS")
		)
		(fp_line
			(start 0.7874 -0.4064)
			(end -0.7874 -0.4064)
			(stroke
				(width 0.1524)
				(type default)
			)
			(layer "B.SilkS")
		)
		(fp_line
			(start 0.7874 0.4064)
			(end 0.7874 -0.4064)
			(stroke
				(width 0.1524)
				(type default)
			)
			(layer "B.SilkS")
		)
		(fp_line
			(start -0.67945 -0.3048)
			(end -0.67945 0.3048)
			(stroke
				(width 0.1)
				(type default)
			)
			(layer "B.Fab")
		)
		(fp_line
			(start -0.67945 0.3048)
			(end -0.120396 0.3048)
			(stroke
				(width 0.1)
				(type default)
			)
			(layer "B.Fab")
		)
		(fp_line
			(start -0.12065 -0.3048)
			(end -0.67945 -0.3048)
			(stroke
				(width 0.1)
				(type default)
			)
			(layer "B.Fab")
		)
		(fp_line
			(start -0.12065 -0.2794)
			(end -0.12065 -0.3048)
			(stroke
				(width 0.1)
				(type default)
			)
			(layer "B.Fab")
		)
		(fp_line
			(start -0.120396 0.2794)
			(end 0.12065 0.2794)
			(stroke
				(width 0.1)
				(type default)
			)
			(layer "B.Fab")
		)
		(fp_line
			(start -0.120396 0.3048)
			(end -0.120396 0.2794)
			(stroke
				(width 0.1)
				(type default)
			)
			(layer "B.Fab")
		)
		(fp_line
			(start 0.12065 -0.305054)
			(end 0.12065 -0.2794)
			(stroke
				(width 0.1)
				(type default)
			)
			(layer "B.Fab")
		)
		(fp_line
			(start 0.12065 -0.2794)
			(end -0.12065 -0.2794)
			(stroke
				(width 0.1)
				(type default)
			)
			(layer "B.Fab")
		)
		(fp_line
			(start 0.12065 0.2794)
			(end 0.12065 0.3048)
			(stroke
				(width 0.1)
				(type default)
			)
			(layer "B.Fab")
		)
		(fp_line
			(start 0.12065 0.3048)
			(end 0.67945 0.3048)
			(stroke
				(width 0.1)
				(type default)
			)
			(layer "B.Fab")
		)
		(fp_line
			(start 0.67945 -0.305054)
			(end 0.12065 -0.305054)
			(stroke
				(width 0.1)
				(type default)
			)
			(layer "B.Fab")
		)
		(fp_line
			(start 0.67945 0.3048)
			(end 0.67945 -0.305054)
			(stroke
				(width 0.1)
				(type default)
			)
			(layer "B.Fab")
		)
		(pad "1" smd circle
			(at 0.40005 0 180)
			(size 0 0)
			(layers "B.Cu" "B.Mask" "B.Paste")
			(net "PVDD11_S3_P0")
		)
		(pad "2" smd circle
			(at -0.40005 0 180)
			(size 0 0)
			(layers "B.Cu" "B.Mask" "B.Paste")
			(net "GND")
		)
	)
	(footprint ""
		(layer "B.Cu")
		(at 320.846958 -197.567296)
		(property "Reference" "R409"
			(at 0 0 0)
			(layer "B.SilkS")
			(hide yes)
			(effects
				(font
					(size 1.27 1.27)
				)
				(justify mirror)
			)
		)
		(property "Value" ""
			(at 0 0 0)
			(layer "B.Fab")
			(effects
				(font
					(size 1.27 1.27)
				)
				(justify mirror)
			)
		)
		(duplicate_pad_numbers_are_jumpers no)
		(fp_line
			(start -0.7874 -0.4064)
			(end -0.7874 0.4064)
			(stroke
				(width 0.1524)
				(type default)
			)
			(layer "B.SilkS")
		)
		(fp_line
			(start -0.7874 0.4064)
			(end 0.7874 0.4064)
			(stroke
				(width 0.1524)
				(type default)
			)
			(layer "B.SilkS")
		)
		(fp_line
			(start 0.7874 -0.4064)
			(end -0.7874 -0.4064)
			(stroke
				(width 0.1524)
				(type default)
			)
			(layer "B.SilkS")
		)
		(fp_line
			(start 0.7874 0.4064)
			(end 0.7874 -0.4064)
			(stroke
				(width 0.1524)
				(type default)
			)
			(layer "B.SilkS")
		)
		(fp_line
			(start -0.67945 -0.3048)
			(end -0.67945 0.3048)
			(stroke
				(width 0.1)
				(type default)
			)
			(layer "B.Fab")
		)
		(fp_line
			(start -0.67945 0.3048)
			(end -0.120396 0.3048)
			(stroke
				(width 0.1)
				(type default)
			)
			(layer "B.Fab")
		)
		(fp_line
			(start -0.12065 -0.3048)
			(end -0.67945 -0.3048)
			(stroke
				(width 0.1)
				(type default)
			)
			(layer "B.Fab")
		)
		(fp_line
			(start -0.12065 -0.2794)
			(end -0.12065 -0.3048)
			(stroke
				(width 0.1)
				(type default)
			)
			(layer "B.Fab")
		)
		(fp_line
			(start -0.120396 0.2794)
			(end 0.12065 0.2794)
			(stroke
				(width 0.1)
				(type default)
			)
			(layer "B.Fab")
		)
		(fp_line
			(start -0.120396 0.3048)
			(end -0.120396 0.2794)
			(stroke
				(width 0.1)
				(type default)
			)
			(layer "B.Fab")
		)
		(fp_line
			(start 0.12065 -0.305054)
			(end 0.12065 -0.2794)
			(stroke
				(width 0.1)
				(type default)
			)
			(layer "B.Fab")
		)
		(fp_line
			(start 0.12065 -0.2794)
			(end -0.12065 -0.2794)
			(stroke
				(width 0.1)
				(type default)
			)
			(layer "B.Fab")
		)
		(fp_line
			(start 0.12065 0.2794)
			(end 0.12065 0.3048)
			(stroke
				(width 0.1)
				(type default)
			)
			(layer "B.Fab")
		)
		(fp_line
			(start 0.12065 0.3048)
			(end 0.67945 0.3048)
			(stroke
				(width 0.1)
				(type default)
			)
			(layer "B.Fab")
		)
		(fp_line
			(start 0.67945 -0.305054)
			(end 0.12065 -0.305054)
			(stroke
				(width 0.1)
				(type default)
			)
			(layer "B.Fab")
		)
		(fp_line
			(start 0.67945 0.3048)
			(end 0.67945 -0.305054)
			(stroke
				(width 0.1)
				(type default)
			)
			(layer "B.Fab")
		)
		(pad "1" smd circle
			(at 0.40005 0 180)
			(size 0 0)
			(layers "B.Cu" "B.Mask" "B.Paste")
			(net "CPU0_BP1")
		)
		(pad "2" smd circle
			(at -0.40005 0 180)
			(size 0 0)
			(layers "B.Cu" "B.Mask" "B.Paste")
			(net "PVDD18_S5_P0")
		)
	)
	(footprint ""
		(layer "B.Cu")
		(at 145.331434 -203.679552 90)
		(property "Reference" "R522"
			(at 0 0 90)
			(layer "B.SilkS")
			(hide yes)
			(effects
				(font
					(size 1.27 1.27)
				)
				(justify mirror)
			)
		)
		(property "Value" ""
			(at 0 0 90)
			(layer "B.Fab")
			(effects
				(font
					(size 1.27 1.27)
				)
				(justify mirror)
			)
		)
		(duplicate_pad_numbers_are_jumpers no)
		(fp_line
			(start 0.7874 -0.4064)
			(end -0.7874 -0.4064)
			(stroke
				(width 0.1524)
				(type default)
			)
			(layer "B.SilkS")
		)
		(fp_line
			(start -0.7874 -0.4064)
			(end -0.7874 0.4064)
			(stroke
				(width 0.1524)
				(type default)
			)
			(layer "B.SilkS")
		)
		(fp_line
			(start 0.7874 0.4064)
			(end 0.7874 -0.4064)
			(stroke
				(width 0.1524)
				(type default)
			)
			(layer "B.SilkS")
		)
		(fp_line
			(start -0.7874 0.4064)
			(end 0.7874 0.4064)
			(stroke
				(width 0.1524)
				(type default)
			)
			(layer "B.SilkS")
		)
		(fp_line
			(start 0.67945 -0.305054)
			(end 0.12065 -0.305054)
			(stroke
				(width 0.1)
				(type default)
			)
			(layer "B.Fab")
		)
		(fp_line
			(start 0.12065 -0.305054)
			(end 0.12065 -0.2794)
			(stroke
				(width 0.1)
				(type default)
			)
			(layer "B.Fab")
		)
		(fp_line
			(start -0.12065 -0.3048)
			(end -0.67945 -0.3048)
			(stroke
				(width 0.1)
				(type default)
			)
			(layer "B.Fab")
		)
		(fp_line
			(start -0.67945 -0.3048)
			(end -0.67945 0.3048)
			(stroke
				(width 0.1)
				(type default)
			)
			(layer "B.Fab")
		)
		(fp_line
			(start 0.12065 -0.2794)
			(end -0.12065 -0.2794)
			(stroke
				(width 0.1)
				(type default)
			)
			(layer "B.Fab")
		)
		(fp_line
			(start -0.12065 -0.2794)
			(end -0.12065 -0.3048)
			(stroke
				(width 0.1)
				(type default)
			)
			(layer "B.Fab")
		)
		(fp_line
			(start 0.12065 0.2794)
			(end 0.12065 0.3048)
			(stroke
				(width 0.1)
				(type default)
			)
			(layer "B.Fab")
		)
		(fp_line
			(start -0.120396 0.2794)
			(end 0.12065 0.2794)
			(stroke
				(width 0.1)
				(type default)
			)
			(layer "B.Fab")
		)
		(fp_line
			(start 0.67945 0.3048)
			(end 0.67945 -0.305054)
			(stroke
				(width 0.1)
				(type default)
			)
			(layer "B.Fab")
		)
		(fp_line
			(start 0.12065 0.3048)
			(end 0.67945 0.3048)
			(stroke
				(width 0.1)
				(type default)
			)
			(layer "B.Fab")
		)
		(fp_line
			(start -0.120396 0.3048)
			(end -0.120396 0.2794)
			(stroke
				(width 0.1)
				(type default)
			)
			(layer "B.Fab")
		)
		(fp_line
			(start -0.67945 0.3048)
			(end -0.120396 0.3048)
			(stroke
				(width 0.1)
				(type default)
			)
			(layer "B.Fab")
		)
		(pad "1" smd circle
			(at 0.40005 0 270)
			(size 0 0)
			(layers "B.Cu" "B.Mask" "B.Paste")
			(net "P3V3_AUX")
		)
		(pad "2" smd circle
			(at -0.40005 0 270)
			(size 0 0)
			(layers "B.Cu" "B.Mask" "B.Paste")
			(net "CPU1_SP5R1")
		)
	)
	(footprint ""
		(layer "B.Cu")
		(at 137.843006 -408.517344 90)
		(property "Reference" "C6740"
			(at 0 0 90)
			(layer "B.SilkS")
			(hide yes)
			(effects
				(font
					(size 1.27 1.27)
				)
				(justify mirror)
			)
		)
		(property "Value" ""
			(at 0 0 90)
			(layer "B.Fab")
			(effects
				(font
					(size 1.27 1.27)
				)
				(justify mirror)
			)
		)
		(duplicate_pad_numbers_are_jumpers no)
		(fp_line
			(start 0.299974 -0.150114)
			(end -0.299974 -0.150114)
			(stroke
				(width 0.1)
				(type default)
			)
			(layer "B.Fab")
		)
		(fp_line
			(start -0.299974 -0.150114)
			(end -0.299974 0.150114)
			(stroke
				(width 0.1)
				(type default)
			)
			(layer "B.Fab")
		)
		(fp_line
			(start 0.299974 0.150114)
			(end 0.299974 -0.150114)
			(stroke
				(width 0.1)
				(type default)
			)
			(layer "B.Fab")
		)
		(fp_line
			(start -0.299974 0.150114)
			(end 0.299974 0.150114)
			(stroke
				(width 0.1)
				(type default)
			)
			(layer "B.Fab")
		)
		(pad "1" smd rect
			(at 0.2667 0 270)
			(size 0.3048 0.381)
			(layers "B.Cu" "B.Mask" "B.Paste")
			(net "P5E_CPU1_P3_TX_BUF_C_DN<7>")
		)
		(pad "2" smd rect
			(at -0.2667 0 270)
			(size 0.3048 0.381)
			(layers "B.Cu" "B.Mask" "B.Paste")
			(net "P5E_CPU1_P3_TX_BUF_DN<7>")
		)
	)
	(footprint ""
		(layer "B.Cu")
		(at 314.191142 -398.942052 90)
		(property "Reference" "C563"
			(at 0 0 90)
			(layer "B.SilkS")
			(hide yes)
			(effects
				(font
					(size 1.27 1.27)
				)
				(justify mirror)
			)
		)
		(property "Value" ""
			(at 0 0 90)
			(layer "B.Fab")
			(effects
				(font
					(size 1.27 1.27)
				)
				(justify mirror)
			)
		)
		(duplicate_pad_numbers_are_jumpers no)
		(fp_line
			(start 0.7874 -0.4064)
			(end -0.7874 -0.4064)
			(stroke
				(width 0.1524)
				(type default)
			)
			(layer "B.SilkS")
		)
		(fp_line
			(start -0.7874 -0.4064)
			(end -0.7874 0.4064)
			(stroke
				(width 0.1524)
				(type default)
			)
			(layer "B.SilkS")
		)
		(fp_line
			(start 0.7874 0.4064)
			(end 0.7874 -0.4064)
			(stroke
				(width 0.1524)
				(type default)
			)
			(layer "B.SilkS")
		)
		(fp_line
			(start -0.7874 0.4064)
			(end 0.7874 0.4064)
			(stroke
				(width 0.1524)
				(type default)
			)
			(layer "B.SilkS")
		)
		(fp_line
			(start 0.67945 -0.305054)
			(end 0.12065 -0.305054)
			(stroke
				(width 0.1)
				(type default)
			)
			(layer "B.Fab")
		)
		(fp_line
			(start 0.12065 -0.305054)
			(end 0.12065 -0.2794)
			(stroke
				(width 0.1)
				(type default)
			)
			(layer "B.Fab")
		)
		(fp_line
			(start -0.12065 -0.3048)
			(end -0.67945 -0.3048)
			(stroke
				(width 0.1)
				(type default)
			)
			(layer "B.Fab")
		)
		(fp_line
			(start -0.67945 -0.3048)
			(end -0.67945 0.3048)
			(stroke
				(width 0.1)
				(type default)
			)
			(layer "B.Fab")
		)
		(fp_line
			(start 0.12065 -0.2794)
			(end -0.12065 -0.2794)
			(stroke
				(width 0.1)
				(type default)
			)
			(layer "B.Fab")
		)
		(fp_line
			(start -0.12065 -0.2794)
			(end -0.12065 -0.3048)
			(stroke
				(width 0.1)
				(type default)
			)
			(layer "B.Fab")
		)
		(fp_line
			(start 0.12065 0.2794)
			(end 0.12065 0.3048)
			(stroke
				(width 0.1)
				(type default)
			)
			(layer "B.Fab")
		)
		(fp_line
			(start -0.120396 0.2794)
			(end 0.12065 0.2794)
			(stroke
				(width 0.1)
				(type default)
			)
			(layer "B.Fab")
		)
		(fp_line
			(start 0.67945 0.3048)
			(end 0.67945 -0.305054)
			(stroke
				(width 0.1)
				(type default)
			)
			(layer "B.Fab")
		)
		(fp_line
			(start 0.12065 0.3048)
			(end 0.67945 0.3048)
			(stroke
				(width 0.1)
				(type default)
			)
			(layer "B.Fab")
		)
		(fp_line
			(start -0.120396 0.3048)
			(end -0.120396 0.2794)
			(stroke
				(width 0.1)
				(type default)
			)
			(layer "B.Fab")
		)
		(fp_line
			(start -0.67945 0.3048)
			(end -0.120396 0.3048)
			(stroke
				(width 0.1)
				(type default)
			)
			(layer "B.Fab")
		)
		(pad "1" smd circle
			(at 0.40005 0 270)
			(size 0 0)
			(layers "B.Cu" "B.Mask" "B.Paste")
			(net "P0V9_CPU0_RT_2D")
		)
		(pad "2" smd circle
			(at -0.40005 0 270)
			(size 0 0)
			(layers "B.Cu" "B.Mask" "B.Paste")
			(net "GND")
		)
	)
	(footprint ""
		(layer "B.Cu")
		(at 173.609 -100.294948 -90)
		(property "Reference" "R6016"
			(at 0 0 90)
			(layer "B.SilkS")
			(hide yes)
			(effects
				(font
					(size 1.27 1.27)
				)
				(justify mirror)
			)
		)
		(property "Value" ""
			(at 0 0 90)
			(layer "B.Fab")
			(effects
				(font
					(size 1.27 1.27)
				)
				(justify mirror)
			)
		)
		(duplicate_pad_numbers_are_jumpers no)
		(fp_line
			(start -0.7874 0.4064)
			(end 0.7874 0.4064)
			(stroke
				(width 0.1524)
				(type default)
			)
			(layer "B.SilkS")
		)
		(fp_line
			(start 0.7874 0.4064)
			(end 0.7874 -0.4064)
			(stroke
				(width 0.1524)
				(type default)
			)
			(layer "B.SilkS")
		)
		(fp_line
			(start -0.7874 -0.4064)
			(end -0.7874 0.4064)
			(stroke
				(width 0.1524)
				(type default)
			)
			(layer "B.SilkS")
		)
		(fp_line
			(start 0.7874 -0.4064)
			(end -0.7874 -0.4064)
			(stroke
				(width 0.1524)
				(type default)
			)
			(layer "B.SilkS")
		)
		(fp_line
			(start -0.67945 0.3048)
			(end -0.120396 0.3048)
			(stroke
				(width 0.1)
				(type default)
			)
			(layer "B.Fab")
		)
		(fp_line
			(start -0.120396 0.3048)
			(end -0.120396 0.2794)
			(stroke
				(width 0.1)
				(type default)
			)
			(layer "B.Fab")
		)
		(fp_line
			(start 0.12065 0.3048)
			(end 0.67945 0.3048)
			(stroke
				(width 0.1)
				(type default)
			)
			(layer "B.Fab")
		)
		(fp_line
			(start 0.67945 0.3048)
			(end 0.67945 -0.305054)
			(stroke
				(width 0.1)
				(type default)
			)
			(layer "B.Fab")
		)
		(fp_line
			(start -0.120396 0.2794)
			(end 0.12065 0.2794)
			(stroke
				(width 0.1)
				(type default)
			)
			(layer "B.Fab")
		)
		(fp_line
			(start 0.12065 0.2794)
			(end 0.12065 0.3048)
			(stroke
				(width 0.1)
				(type default)
			)
			(layer "B.Fab")
		)
		(fp_line
			(start -0.12065 -0.2794)
			(end -0.12065 -0.3048)
			(stroke
				(width 0.1)
				(type default)
			)
			(layer "B.Fab")
		)
		(fp_line
			(start 0.12065 -0.2794)
			(end -0.12065 -0.2794)
			(stroke
				(width 0.1)
				(type default)
			)
			(layer "B.Fab")
		)
		(fp_line
			(start -0.67945 -0.3048)
			(end -0.67945 0.3048)
			(stroke
				(width 0.1)
				(type default)
			)
			(layer "B.Fab")
		)
		(fp_line
			(start -0.12065 -0.3048)
			(end -0.67945 -0.3048)
			(stroke
				(width 0.1)
				(type default)
			)
			(layer "B.Fab")
		)
		(fp_line
			(start 0.12065 -0.305054)
			(end 0.12065 -0.2794)
			(stroke
				(width 0.1)
				(type default)
			)
			(layer "B.Fab")
		)
		(fp_line
			(start 0.67945 -0.305054)
			(end 0.12065 -0.305054)
			(stroke
				(width 0.1)
				(type default)
			)
			(layer "B.Fab")
		)
		(pad "1" smd circle
			(at 0.40005 0 90)
			(size 0 0)
			(layers "B.Cu" "B.Mask" "B.Paste")
			(net "P3V3_AUX")
		)
		(pad "2" smd circle
			(at -0.40005 0 90)
			(size 0 0)
			(layers "B.Cu" "B.Mask" "B.Paste")
			(net "SGPIO_SCM_DO_<0>")
		)
	)
	(footprint ""
		(layer "B.Cu")
		(at 188.710824 -136.658096 90)
		(property "Reference" "R194"
			(at 0 0 90)
			(layer "B.SilkS")
			(hide yes)
			(effects
				(font
					(size 1.27 1.27)
				)
				(justify mirror)
			)
		)
		(property "Value" ""
			(at 0 0 90)
			(layer "B.Fab")
			(effects
				(font
					(size 1.27 1.27)
				)
				(justify mirror)
			)
		)
		(duplicate_pad_numbers_are_jumpers no)
		(fp_line
			(start 0.7874 -0.4064)
			(end -0.7874 -0.4064)
			(stroke
				(width 0.1524)
				(type default)
			)
			(layer "B.SilkS")
		)
		(fp_line
			(start -0.7874 -0.4064)
			(end -0.7874 0.4064)
			(stroke
				(width 0.1524)
				(type default)
			)
			(layer "B.SilkS")
		)
		(fp_line
			(start 0.7874 0.4064)
			(end 0.7874 -0.4064)
			(stroke
				(width 0.1524)
				(type default)
			)
			(layer "B.SilkS")
		)
		(fp_line
			(start -0.7874 0.4064)
			(end 0.7874 0.4064)
			(stroke
				(width 0.1524)
				(type default)
			)
			(layer "B.SilkS")
		)
		(fp_line
			(start 0.67945 -0.305054)
			(end 0.12065 -0.305054)
			(stroke
				(width 0.1)
				(type default)
			)
			(layer "B.Fab")
		)
		(fp_line
			(start 0.12065 -0.305054)
			(end 0.12065 -0.2794)
			(stroke
				(width 0.1)
				(type default)
			)
			(layer "B.Fab")
		)
		(fp_line
			(start -0.12065 -0.3048)
			(end -0.67945 -0.3048)
			(stroke
				(width 0.1)
				(type default)
			)
			(layer "B.Fab")
		)
		(fp_line
			(start -0.67945 -0.3048)
			(end -0.67945 0.3048)
			(stroke
				(width 0.1)
				(type default)
			)
			(layer "B.Fab")
		)
		(fp_line
			(start 0.12065 -0.2794)
			(end -0.12065 -0.2794)
			(stroke
				(width 0.1)
				(type default)
			)
			(layer "B.Fab")
		)
		(fp_line
			(start -0.12065 -0.2794)
			(end -0.12065 -0.3048)
			(stroke
				(width 0.1)
				(type default)
			)
			(layer "B.Fab")
		)
		(fp_line
			(start 0.12065 0.2794)
			(end 0.12065 0.3048)
			(stroke
				(width 0.1)
				(type default)
			)
			(layer "B.Fab")
		)
		(fp_line
			(start -0.120396 0.2794)
			(end 0.12065 0.2794)
			(stroke
				(width 0.1)
				(type default)
			)
			(layer "B.Fab")
		)
		(fp_line
			(start 0.67945 0.3048)
			(end 0.67945 -0.305054)
			(stroke
				(width 0.1)
				(type default)
			)
			(layer "B.Fab")
		)
		(fp_line
			(start 0.12065 0.3048)
			(end 0.67945 0.3048)
			(stroke
				(width 0.1)
				(type default)
			)
			(layer "B.Fab")
		)
		(fp_line
			(start -0.120396 0.3048)
			(end -0.120396 0.2794)
			(stroke
				(width 0.1)
				(type default)
			)
			(layer "B.Fab")
		)
		(fp_line
			(start -0.67945 0.3048)
			(end -0.120396 0.3048)
			(stroke
				(width 0.1)
				(type default)
			)
			(layer "B.Fab")
		)
		(pad "1" smd circle
			(at 0.40005 0 270)
			(size 0 0)
			(layers "B.Cu" "B.Mask" "B.Paste")
			(net "CPU1_SPD_HOST_CTRL_N")
		)
		(pad "2" smd circle
			(at -0.40005 0 270)
			(size 0 0)
			(layers "B.Cu" "B.Mask" "B.Paste")
			(net "CPU1_SPD_HOST_CTRL_R1_N")
		)
	)
	(footprint ""
		(layer "B.Cu")
		(at 90.746834 -308.606952 90)
		(property "Reference" "PR237"
			(at 0 0 90)
			(layer "B.SilkS")
			(hide yes)
			(effects
				(font
					(size 1.27 1.27)
				)
				(justify mirror)
			)
		)
		(property "Value" ""
			(at 0 0 90)
			(layer "B.Fab")
			(effects
				(font
					(size 1.27 1.27)
				)
				(justify mirror)
			)
		)
		(duplicate_pad_numbers_are_jumpers no)
		(fp_line
			(start 0.7874 -0.4064)
			(end -0.7874 -0.4064)
			(stroke
				(width 0.1524)
				(type default)
			)
			(layer "B.SilkS")
		)
		(fp_line
			(start -0.7874 -0.4064)
			(end -0.7874 0.4064)
			(stroke
				(width 0.1524)
				(type default)
			)
			(layer "B.SilkS")
		)
		(fp_line
			(start 0.7874 0.4064)
			(end 0.7874 -0.4064)
			(stroke
				(width 0.1524)
				(type default)
			)
			(layer "B.SilkS")
		)
		(fp_line
			(start -0.7874 0.4064)
			(end 0.7874 0.4064)
			(stroke
				(width 0.1524)
				(type default)
			)
			(layer "B.SilkS")
		)
		(fp_line
			(start 0.67945 -0.305054)
			(end 0.12065 -0.305054)
			(stroke
				(width 0.1)
				(type default)
			)
			(layer "B.Fab")
		)
		(fp_line
			(start 0.12065 -0.305054)
			(end 0.12065 -0.2794)
			(stroke
				(width 0.1)
				(type default)
			)
			(layer "B.Fab")
		)
		(fp_line
			(start -0.12065 -0.3048)
			(end -0.67945 -0.3048)
			(stroke
				(width 0.1)
				(type default)
			)
			(layer "B.Fab")
		)
		(fp_line
			(start -0.67945 -0.3048)
			(end -0.67945 0.3048)
			(stroke
				(width 0.1)
				(type default)
			)
			(layer "B.Fab")
		)
		(fp_line
			(start 0.12065 -0.2794)
			(end -0.12065 -0.2794)
			(stroke
				(width 0.1)
				(type default)
			)
			(layer "B.Fab")
		)
		(fp_line
			(start -0.12065 -0.2794)
			(end -0.12065 -0.3048)
			(stroke
				(width 0.1)
				(type default)
			)
			(layer "B.Fab")
		)
		(fp_line
			(start 0.12065 0.2794)
			(end 0.12065 0.3048)
			(stroke
				(width 0.1)
				(type default)
			)
			(layer "B.Fab")
		)
		(fp_line
			(start -0.120396 0.2794)
			(end 0.12065 0.2794)
			(stroke
				(width 0.1)
				(type default)
			)
			(layer "B.Fab")
		)
		(fp_line
			(start 0.67945 0.3048)
			(end 0.67945 -0.305054)
			(stroke
				(width 0.1)
				(type default)
			)
			(layer "B.Fab")
		)
		(fp_line
			(start 0.12065 0.3048)
			(end 0.67945 0.3048)
			(stroke
				(width 0.1)
				(type default)
			)
			(layer "B.Fab")
		)
		(fp_line
			(start -0.120396 0.3048)
			(end -0.120396 0.2794)
			(stroke
				(width 0.1)
				(type default)
			)
			(layer "B.Fab")
		)
		(fp_line
			(start -0.67945 0.3048)
			(end -0.120396 0.3048)
			(stroke
				(width 0.1)
				(type default)
			)
			(layer "B.Fab")
		)
		(pad "1" smd circle
			(at 0.40005 0 270)
			(size 0 0)
			(layers "B.Cu" "B.Mask" "B.Paste")
			(net "SVID_PVDDCR_CPU1_P1_SVD_R")
		)
		(pad "2" smd circle
			(at -0.40005 0 270)
			(size 0 0)
			(layers "B.Cu" "B.Mask" "B.Paste")
			(net "SVID_PVDDCR_CPU1_P1_SVD")
		)
	)
	(footprint ""
		(layer "B.Cu")
		(at 52.191412 -390.560052 90)
		(property "Reference" "C255"
			(at 0 0 90)
			(layer "B.SilkS")
			(hide yes)
			(effects
				(font
					(size 1.27 1.27)
				)
				(justify mirror)
			)
		)
		(property "Value" ""
			(at 0 0 90)
			(layer "B.Fab")
			(effects
				(font
					(size 1.27 1.27)
				)
				(justify mirror)
			)
		)
		(duplicate_pad_numbers_are_jumpers no)
		(fp_line
			(start 0.7874 -0.4064)
			(end -0.7874 -0.4064)
			(stroke
				(width 0.1524)
				(type default)
			)
			(layer "B.SilkS")
		)
		(fp_line
			(start -0.7874 -0.4064)
			(end -0.7874 0.4064)
			(stroke
				(width 0.1524)
				(type default)
			)
			(layer "B.SilkS")
		)
		(fp_line
			(start 0.7874 0.4064)
			(end 0.7874 -0.4064)
			(stroke
				(width 0.1524)
				(type default)
			)
			(layer "B.SilkS")
		)
		(fp_line
			(start -0.7874 0.4064)
			(end 0.7874 0.4064)
			(stroke
				(width 0.1524)
				(type default)
			)
			(layer "B.SilkS")
		)
		(fp_line
			(start 0.67945 -0.305054)
			(end 0.12065 -0.305054)
			(stroke
				(width 0.1)
				(type default)
			)
			(layer "B.Fab")
		)
		(fp_line
			(start 0.12065 -0.305054)
			(end 0.12065 -0.2794)
			(stroke
				(width 0.1)
				(type default)
			)
			(layer "B.Fab")
		)
		(fp_line
			(start -0.12065 -0.3048)
			(end -0.67945 -0.3048)
			(stroke
				(width 0.1)
				(type default)
			)
			(layer "B.Fab")
		)
		(fp_line
			(start -0.67945 -0.3048)
			(end -0.67945 0.3048)
			(stroke
				(width 0.1)
				(type default)
			)
			(layer "B.Fab")
		)
		(fp_line
			(start 0.12065 -0.2794)
			(end -0.12065 -0.2794)
			(stroke
				(width 0.1)
				(type default)
			)
			(layer "B.Fab")
		)
		(fp_line
			(start -0.12065 -0.2794)
			(end -0.12065 -0.3048)
			(stroke
				(width 0.1)
				(type default)
			)
			(layer "B.Fab")
		)
		(fp_line
			(start 0.12065 0.2794)
			(end 0.12065 0.3048)
			(stroke
				(width 0.1)
				(type default)
			)
			(layer "B.Fab")
		)
		(fp_line
			(start -0.120396 0.2794)
			(end 0.12065 0.2794)
			(stroke
				(width 0.1)
				(type default)
			)
			(layer "B.Fab")
		)
		(fp_line
			(start 0.67945 0.3048)
			(end 0.67945 -0.305054)
			(stroke
				(width 0.1)
				(type default)
			)
			(layer "B.Fab")
		)
		(fp_line
			(start 0.12065 0.3048)
			(end 0.67945 0.3048)
			(stroke
				(width 0.1)
				(type default)
			)
			(layer "B.Fab")
		)
		(fp_line
			(start -0.120396 0.3048)
			(end -0.120396 0.2794)
			(stroke
				(width 0.1)
				(type default)
			)
			(layer "B.Fab")
		)
		(fp_line
			(start -0.67945 0.3048)
			(end -0.120396 0.3048)
			(stroke
				(width 0.1)
				(type default)
			)
			(layer "B.Fab")
		)
		(pad "1" smd circle
			(at 0.40005 0 270)
			(size 0 0)
			(layers "B.Cu" "B.Mask" "B.Paste")
			(net "P0V9_CPU1_RT0_2A")
		)
		(pad "2" smd circle
			(at -0.40005 0 270)
			(size 0 0)
			(layers "B.Cu" "B.Mask" "B.Paste")
			(net "GND")
		)
	)
	(footprint ""
		(layer "B.Cu")
		(at 91.792044 -337.694524 -90)
		(property "Reference" "PR273"
			(at 0 0 90)
			(layer "B.SilkS")
			(hide yes)
			(effects
				(font
					(size 1.27 1.27)
				)
				(justify mirror)
			)
		)
		(property "Value" ""
			(at 0 0 90)
			(layer "B.Fab")
			(effects
				(font
					(size 1.27 1.27)
				)
				(justify mirror)
			)
		)
		(duplicate_pad_numbers_are_jumpers no)
		(fp_line
			(start -0.7874 0.4064)
			(end 0.7874 0.4064)
			(stroke
				(width 0.1524)
				(type default)
			)
			(layer "B.SilkS")
		)
		(fp_line
			(start 0.7874 0.4064)
			(end 0.7874 -0.4064)
			(stroke
				(width 0.1524)
				(type default)
			)
			(layer "B.SilkS")
		)
		(fp_line
			(start -0.7874 -0.4064)
			(end -0.7874 0.4064)
			(stroke
				(width 0.1524)
				(type default)
			)
			(layer "B.SilkS")
		)
		(fp_line
			(start 0.7874 -0.4064)
			(end -0.7874 -0.4064)
			(stroke
				(width 0.1524)
				(type default)
			)
			(layer "B.SilkS")
		)
		(fp_line
			(start -0.67945 0.3048)
			(end -0.120396 0.3048)
			(stroke
				(width 0.1)
				(type default)
			)
			(layer "B.Fab")
		)
		(fp_line
			(start -0.120396 0.3048)
			(end -0.120396 0.2794)
			(stroke
				(width 0.1)
				(type default)
			)
			(layer "B.Fab")
		)
		(fp_line
			(start 0.12065 0.3048)
			(end 0.67945 0.3048)
			(stroke
				(width 0.1)
				(type default)
			)
			(layer "B.Fab")
		)
		(fp_line
			(start 0.67945 0.3048)
			(end 0.67945 -0.305054)
			(stroke
				(width 0.1)
				(type default)
			)
			(layer "B.Fab")
		)
		(fp_line
			(start -0.120396 0.2794)
			(end 0.12065 0.2794)
			(stroke
				(width 0.1)
				(type default)
			)
			(layer "B.Fab")
		)
		(fp_line
			(start 0.12065 0.2794)
			(end 0.12065 0.3048)
			(stroke
				(width 0.1)
				(type default)
			)
			(layer "B.Fab")
		)
		(fp_line
			(start -0.12065 -0.2794)
			(end -0.12065 -0.3048)
			(stroke
				(width 0.1)
				(type default)
			)
			(layer "B.Fab")
		)
		(fp_line
			(start 0.12065 -0.2794)
			(end -0.12065 -0.2794)
			(stroke
				(width 0.1)
				(type default)
			)
			(layer "B.Fab")
		)
		(fp_line
			(start -0.67945 -0.3048)
			(end -0.67945 0.3048)
			(stroke
				(width 0.1)
				(type default)
			)
			(layer "B.Fab")
		)
		(fp_line
			(start -0.12065 -0.3048)
			(end -0.67945 -0.3048)
			(stroke
				(width 0.1)
				(type default)
			)
			(layer "B.Fab")
		)
		(fp_line
			(start 0.12065 -0.305054)
			(end 0.12065 -0.2794)
			(stroke
				(width 0.1)
				(type default)
			)
			(layer "B.Fab")
		)
		(fp_line
			(start 0.67945 -0.305054)
			(end 0.12065 -0.305054)
			(stroke
				(width 0.1)
				(type default)
			)
			(layer "B.Fab")
		)
		(pad "1" smd circle
			(at 0.40005 0 90)
			(size 0 0)
			(layers "B.Cu" "B.Mask" "B.Paste")
			(net "PVDDCR_CPU1_P1_VOS5")
		)
		(pad "2" smd circle
			(at -0.40005 0 90)
			(size 0 0)
			(layers "B.Cu" "B.Mask" "B.Paste")
			(net "PVDDCR_CPU1_P1")
		)
	)
	(footprint ""
		(layer "B.Cu")
		(at 371.551454 -257.930142)
		(property "Reference" "C2530"
			(at 0 0 0)
			(layer "B.SilkS")
			(hide yes)
			(effects
				(font
					(size 1.27 1.27)
				)
				(justify mirror)
			)
		)
		(property "Value" ""
			(at 0 0 0)
			(layer "B.Fab")
			(effects
				(font
					(size 1.27 1.27)
				)
				(justify mirror)
			)
		)
		(duplicate_pad_numbers_are_jumpers no)
		(fp_line
			(start -0.7874 -0.4064)
			(end -0.7874 0.4064)
			(stroke
				(width 0.1524)
				(type default)
			)
			(layer "B.SilkS")
		)
		(fp_line
			(start -0.7874 0.4064)
			(end 0.7874 0.4064)
			(stroke
				(width 0.1524)
				(type default)
			)
			(layer "B.SilkS")
		)
		(fp_line
			(start 0.7874 -0.4064)
			(end -0.7874 -0.4064)
			(stroke
				(width 0.1524)
				(type default)
			)
			(layer "B.SilkS")
		)
		(fp_line
			(start 0.7874 0.4064)
			(end 0.7874 -0.4064)
			(stroke
				(width 0.1524)
				(type default)
			)
			(layer "B.SilkS")
		)
		(fp_line
			(start -0.67945 -0.3048)
			(end -0.67945 0.3048)
			(stroke
				(width 0.1)
				(type default)
			)
			(layer "B.Fab")
		)
		(fp_line
			(start -0.67945 0.3048)
			(end -0.120396 0.3048)
			(stroke
				(width 0.1)
				(type default)
			)
			(layer "B.Fab")
		)
		(fp_line
			(start -0.12065 -0.3048)
			(end -0.67945 -0.3048)
			(stroke
				(width 0.1)
				(type default)
			)
			(layer "B.Fab")
		)
		(fp_line
			(start -0.12065 -0.2794)
			(end -0.12065 -0.3048)
			(stroke
				(width 0.1)
				(type default)
			)
			(layer "B.Fab")
		)
		(fp_line
			(start -0.120396 0.2794)
			(end 0.12065 0.2794)
			(stroke
				(width 0.1)
				(type default)
			)
			(layer "B.Fab")
		)
		(fp_line
			(start -0.120396 0.3048)
			(end -0.120396 0.2794)
			(stroke
				(width 0.1)
				(type default)
			)
			(layer "B.Fab")
		)
		(fp_line
			(start 0.12065 -0.305054)
			(end 0.12065 -0.2794)
			(stroke
				(width 0.1)
				(type default)
			)
			(layer "B.Fab")
		)
		(fp_line
			(start 0.12065 -0.2794)
			(end -0.12065 -0.2794)
			(stroke
				(width 0.1)
				(type default)
			)
			(layer "B.Fab")
		)
		(fp_line
			(start 0.12065 0.2794)
			(end 0.12065 0.3048)
			(stroke
				(width 0.1)
				(type default)
			)
			(layer "B.Fab")
		)
		(fp_line
			(start 0.12065 0.3048)
			(end 0.67945 0.3048)
			(stroke
				(width 0.1)
				(type default)
			)
			(layer "B.Fab")
		)
		(fp_line
			(start 0.67945 -0.305054)
			(end 0.12065 -0.305054)
			(stroke
				(width 0.1)
				(type default)
			)
			(layer "B.Fab")
		)
		(fp_line
			(start 0.67945 0.3048)
			(end 0.67945 -0.305054)
			(stroke
				(width 0.1)
				(type default)
			)
			(layer "B.Fab")
		)
		(pad "1" smd circle
			(at 0.40005 0 180)
			(size 0 0)
			(layers "B.Cu" "B.Mask" "B.Paste")
			(net "PVDDCR_SOC_P0")
		)
		(pad "2" smd circle
			(at -0.40005 0 180)
			(size 0 0)
			(layers "B.Cu" "B.Mask" "B.Paste")
			(net "GND")
		)
	)
	(footprint ""
		(layer "B.Cu")
		(at 206.429356 -380.206504 180)
		(property "Reference" "PR2522"
			(at 0 0 0)
			(layer "B.SilkS")
			(hide yes)
			(effects
				(font
					(size 1.27 1.27)
				)
				(justify mirror)
			)
		)
		(property "Value" ""
			(at 0 0 0)
			(layer "B.Fab")
			(effects
				(font
					(size 1.27 1.27)
				)
				(justify mirror)
			)
		)
		(duplicate_pad_numbers_are_jumpers no)
		(fp_line
			(start 0.7874 0.4064)
			(end 0.7874 -0.4064)
			(stroke
				(width 0.1524)
				(type default)
			)
			(layer "B.SilkS")
		)
		(fp_line
			(start 0.7874 -0.4064)
			(end -0.7874 -0.4064)
			(stroke
				(width 0.1524)
				(type default)
			)
			(layer "B.SilkS")
		)
		(fp_line
			(start -0.7874 0.4064)
			(end 0.7874 0.4064)
			(stroke
				(width 0.1524)
				(type default)
			)
			(layer "B.SilkS")
		)
		(fp_line
			(start -0.7874 -0.4064)
			(end -0.7874 0.4064)
			(stroke
				(width 0.1524)
				(type default)
			)
			(layer "B.SilkS")
		)
		(fp_line
			(start 0.67945 0.3048)
			(end 0.67945 -0.305054)
			(stroke
				(width 0.1)
				(type default)
			)
			(layer "B.Fab")
		)
		(fp_line
			(start 0.67945 -0.305054)
			(end 0.12065 -0.305054)
			(stroke
				(width 0.1)
				(type default)
			)
			(layer "B.Fab")
		)
		(fp_line
			(start 0.12065 0.3048)
			(end 0.67945 0.3048)
			(stroke
				(width 0.1)
				(type default)
			)
			(layer "B.Fab")
		)
		(fp_line
			(start 0.12065 0.2794)
			(end 0.12065 0.3048)
			(stroke
				(width 0.1)
				(type default)
			)
			(layer "B.Fab")
		)
		(fp_line
			(start 0.12065 -0.2794)
			(end -0.12065 -0.2794)
			(stroke
				(width 0.1)
				(type default)
			)
			(layer "B.Fab")
		)
		(fp_line
			(start 0.12065 -0.305054)
			(end 0.12065 -0.2794)
			(stroke
				(width 0.1)
				(type default)
			)
			(layer "B.Fab")
		)
		(fp_line
			(start -0.120396 0.3048)
			(end -0.120396 0.2794)
			(stroke
				(width 0.1)
				(type default)
			)
			(layer "B.Fab")
		)
		(fp_line
			(start -0.120396 0.2794)
			(end 0.12065 0.2794)
			(stroke
				(width 0.1)
				(type default)
			)
			(layer "B.Fab")
		)
		(fp_line
			(start -0.12065 -0.2794)
			(end -0.12065 -0.3048)
			(stroke
				(width 0.1)
				(type default)
			)
			(layer "B.Fab")
		)
		(fp_line
			(start -0.12065 -0.3048)
			(end -0.67945 -0.3048)
			(stroke
				(width 0.1)
				(type default)
			)
			(layer "B.Fab")
		)
		(fp_line
			(start -0.67945 0.3048)
			(end -0.120396 0.3048)
			(stroke
				(width 0.1)
				(type default)
			)
			(layer "B.Fab")
		)
		(fp_line
			(start -0.67945 -0.3048)
			(end -0.67945 0.3048)
			(stroke
				(width 0.1)
				(type default)
			)
			(layer "B.Fab")
		)
		(pad "1" smd circle
			(at 0.40005 0)
			(size 0 0)
			(layers "B.Cu" "B.Mask" "B.Paste")
			(net "P12V_HSC_SENSE2_P")
		)
		(pad "2" smd circle
			(at -0.40005 0)
			(size 0 0)
			(layers "B.Cu" "B.Mask" "B.Paste")
			(net "P12V_HSC_SENSE2_R3_P")
		)
	)
	(footprint ""
		(layer "B.Cu")
		(at 397.935958 -313.477148)
		(property "Reference" "R5102"
			(at 0 0 0)
			(layer "B.SilkS")
			(hide yes)
			(effects
				(font
					(size 1.27 1.27)
				)
				(justify mirror)
			)
		)
		(property "Value" ""
			(at 0 0 0)
			(layer "B.Fab")
			(effects
				(font
					(size 1.27 1.27)
				)
				(justify mirror)
			)
		)
		(duplicate_pad_numbers_are_jumpers no)
		(fp_line
			(start -0.7874 -0.4064)
			(end -0.7874 0.4064)
			(stroke
				(width 0.1524)
				(type default)
			)
			(layer "B.SilkS")
		)
		(fp_line
			(start -0.7874 0.4064)
			(end 0.7874 0.4064)
			(stroke
				(width 0.1524)
				(type default)
			)
			(layer "B.SilkS")
		)
		(fp_line
			(start 0.7874 -0.4064)
			(end -0.7874 -0.4064)
			(stroke
				(width 0.1524)
				(type default)
			)
			(layer "B.SilkS")
		)
		(fp_line
			(start 0.7874 0.4064)
			(end 0.7874 -0.4064)
			(stroke
				(width 0.1524)
				(type default)
			)
			(layer "B.SilkS")
		)
		(fp_line
			(start -0.67945 -0.3048)
			(end -0.67945 0.3048)
			(stroke
				(width 0.1)
				(type default)
			)
			(layer "B.Fab")
		)
		(fp_line
			(start -0.67945 0.3048)
			(end -0.120396 0.3048)
			(stroke
				(width 0.1)
				(type default)
			)
			(layer "B.Fab")
		)
		(fp_line
			(start -0.12065 -0.3048)
			(end -0.67945 -0.3048)
			(stroke
				(width 0.1)
				(type default)
			)
			(layer "B.Fab")
		)
		(fp_line
			(start -0.12065 -0.2794)
			(end -0.12065 -0.3048)
			(stroke
				(width 0.1)
				(type default)
			)
			(layer "B.Fab")
		)
		(fp_line
			(start -0.120396 0.2794)
			(end 0.12065 0.2794)
			(stroke
				(width 0.1)
				(type default)
			)
			(layer "B.Fab")
		)
		(fp_line
			(start -0.120396 0.3048)
			(end -0.120396 0.2794)
			(stroke
				(width 0.1)
				(type default)
			)
			(layer "B.Fab")
		)
		(fp_line
			(start 0.12065 -0.305054)
			(end 0.12065 -0.2794)
			(stroke
				(width 0.1)
				(type default)
			)
			(layer "B.Fab")
		)
		(fp_line
			(start 0.12065 -0.2794)
			(end -0.12065 -0.2794)
			(stroke
				(width 0.1)
				(type default)
			)
			(layer "B.Fab")
		)
		(fp_line
			(start 0.12065 0.2794)
			(end 0.12065 0.3048)
			(stroke
				(width 0.1)
				(type default)
			)
			(layer "B.Fab")
		)
		(fp_line
			(start 0.12065 0.3048)
			(end 0.67945 0.3048)
			(stroke
				(width 0.1)
				(type default)
			)
			(layer "B.Fab")
		)
		(fp_line
			(start 0.67945 -0.305054)
			(end 0.12065 -0.305054)
			(stroke
				(width 0.1)
				(type default)
			)
			(layer "B.Fab")
		)
		(fp_line
			(start 0.67945 0.3048)
			(end 0.67945 -0.305054)
			(stroke
				(width 0.1)
				(type default)
			)
			(layer "B.Fab")
		)
		(pad "1" smd circle
			(at 0.40005 0 180)
			(size 0 0)
			(layers "B.Cu" "B.Mask" "B.Paste")
			(net "XTAL_CPU0_X48M_X2")
		)
		(pad "2" smd circle
			(at -0.40005 0 180)
			(size 0 0)
			(layers "B.Cu" "B.Mask" "B.Paste")
			(net "XTAL_CPU0_X48M_X2_R")
		)
	)
	(footprint ""
		(layer "B.Cu")
		(at 169.2148 -421.277796 -90)
		(property "Reference" "R1463"
			(at 0 0 90)
			(layer "B.SilkS")
			(hide yes)
			(effects
				(font
					(size 1.27 1.27)
				)
				(justify mirror)
			)
		)
		(property "Value" ""
			(at 0 0 90)
			(layer "B.Fab")
			(effects
				(font
					(size 1.27 1.27)
				)
				(justify mirror)
			)
		)
		(duplicate_pad_numbers_are_jumpers no)
		(fp_line
			(start -0.32512 0.175006)
			(end 0.32512 0.175006)
			(stroke
				(width 0.1)
				(type default)
			)
			(layer "B.Fab")
		)
		(fp_line
			(start 0.32512 0.175006)
			(end 0.32512 -0.175006)
			(stroke
				(width 0.1)
				(type default)
			)
			(layer "B.Fab")
		)
		(fp_line
			(start -0.32512 -0.175006)
			(end -0.32512 0.175006)
			(stroke
				(width 0.1)
				(type default)
			)
			(layer "B.Fab")
		)
		(fp_line
			(start 0.32512 -0.175006)
			(end -0.32512 -0.175006)
			(stroke
				(width 0.1)
				(type default)
			)
			(layer "B.Fab")
		)
		(pad "1" smd rect
			(at 0.2667 0 90)
			(size 0.3048 0.381)
			(layers "B.Cu" "B.Mask" "B.Paste")
			(net "P1V8_CPU1_RT_1D")
		)
		(pad "2" smd rect
			(at -0.2667 0 270)
			(size 0.3048 0.381)
			(layers "B.Cu" "B.Mask" "B.Paste")
			(net "SMB_RT_CPU1_P3_ROM_MUX_1D_SCL")
		)
	)
	(footprint ""
		(layer "B.Cu")
		(at 100.478844 -259.73024 180)
		(property "Reference" "C2103"
			(at 0 0 0)
			(layer "B.SilkS")
			(hide yes)
			(effects
				(font
					(size 1.27 1.27)
				)
				(justify mirror)
			)
		)
		(property "Value" ""
			(at 0 0 0)
			(layer "B.Fab")
			(effects
				(font
					(size 1.27 1.27)
				)
				(justify mirror)
			)
		)
		(duplicate_pad_numbers_are_jumpers no)
		(fp_line
			(start 0.7874 0.4064)
			(end 0.7874 -0.4064)
			(stroke
				(width 0.1524)
				(type default)
			)
			(layer "B.SilkS")
		)
		(fp_line
			(start 0.7874 -0.4064)
			(end -0.7874 -0.4064)
			(stroke
				(width 0.1524)
				(type default)
			)
			(layer "B.SilkS")
		)
		(fp_line
			(start -0.7874 0.4064)
			(end 0.7874 0.4064)
			(stroke
				(width 0.1524)
				(type default)
			)
			(layer "B.SilkS")
		)
		(fp_line
			(start -0.7874 -0.4064)
			(end -0.7874 0.4064)
			(stroke
				(width 0.1524)
				(type default)
			)
			(layer "B.SilkS")
		)
		(fp_line
			(start 0.67945 0.3048)
			(end 0.67945 -0.305054)
			(stroke
				(width 0.1)
				(type default)
			)
			(layer "B.Fab")
		)
		(fp_line
			(start 0.67945 -0.305054)
			(end 0.12065 -0.305054)
			(stroke
				(width 0.1)
				(type default)
			)
			(layer "B.Fab")
		)
		(fp_line
			(start 0.12065 0.3048)
			(end 0.67945 0.3048)
			(stroke
				(width 0.1)
				(type default)
			)
			(layer "B.Fab")
		)
		(fp_line
			(start 0.12065 0.2794)
			(end 0.12065 0.3048)
			(stroke
				(width 0.1)
				(type default)
			)
			(layer "B.Fab")
		)
		(fp_line
			(start 0.12065 -0.2794)
			(end -0.12065 -0.2794)
			(stroke
				(width 0.1)
				(type default)
			)
			(layer "B.Fab")
		)
		(fp_line
			(start 0.12065 -0.305054)
			(end 0.12065 -0.2794)
			(stroke
				(width 0.1)
				(type default)
			)
			(layer "B.Fab")
		)
		(fp_line
			(start -0.120396 0.3048)
			(end -0.120396 0.2794)
			(stroke
				(width 0.1)
				(type default)
			)
			(layer "B.Fab")
		)
		(fp_line
			(start -0.120396 0.2794)
			(end 0.12065 0.2794)
			(stroke
				(width 0.1)
				(type default)
			)
			(layer "B.Fab")
		)
		(fp_line
			(start -0.12065 -0.2794)
			(end -0.12065 -0.3048)
			(stroke
				(width 0.1)
				(type default)
			)
			(layer "B.Fab")
		)
		(fp_line
			(start -0.12065 -0.3048)
			(end -0.67945 -0.3048)
			(stroke
				(width 0.1)
				(type default)
			)
			(layer "B.Fab")
		)
		(fp_line
			(start -0.67945 0.3048)
			(end -0.120396 0.3048)
			(stroke
				(width 0.1)
				(type default)
			)
			(layer "B.Fab")
		)
		(fp_line
			(start -0.67945 -0.3048)
			(end -0.67945 0.3048)
			(stroke
				(width 0.1)
				(type default)
			)
			(layer "B.Fab")
		)
		(pad "1" smd circle
			(at 0.40005 0)
			(size 0 0)
			(layers "B.Cu" "B.Mask" "B.Paste")
			(net "PVDDIO_P1")
		)
		(pad "2" smd circle
			(at -0.40005 0)
			(size 0 0)
			(layers "B.Cu" "B.Mask" "B.Paste")
			(net "GND")
		)
	)
	(footprint ""
		(layer "B.Cu")
		(at 361.316016 -256.012188 -90)
		(property "Reference" "C2580"
			(at 0 0 90)
			(layer "B.SilkS")
			(hide yes)
			(effects
				(font
					(size 1.27 1.27)
				)
				(justify mirror)
			)
		)
		(property "Value" ""
			(at 0 0 90)
			(layer "B.Fab")
			(effects
				(font
					(size 1.27 1.27)
				)
				(justify mirror)
			)
		)
		(duplicate_pad_numbers_are_jumpers no)
		(fp_line
			(start -0.7874 0.4064)
			(end 0.7874 0.4064)
			(stroke
				(width 0.1524)
				(type default)
			)
			(layer "B.SilkS")
		)
		(fp_line
			(start 0.7874 0.4064)
			(end 0.7874 -0.4064)
			(stroke
				(width 0.1524)
				(type default)
			)
			(layer "B.SilkS")
		)
		(fp_line
			(start -0.7874 -0.4064)
			(end -0.7874 0.4064)
			(stroke
				(width 0.1524)
				(type default)
			)
			(layer "B.SilkS")
		)
		(fp_line
			(start 0.7874 -0.4064)
			(end -0.7874 -0.4064)
			(stroke
				(width 0.1524)
				(type default)
			)
			(layer "B.SilkS")
		)
		(fp_line
			(start -0.67945 0.3048)
			(end -0.120396 0.3048)
			(stroke
				(width 0.1)
				(type default)
			)
			(layer "B.Fab")
		)
		(fp_line
			(start -0.120396 0.3048)
			(end -0.120396 0.2794)
			(stroke
				(width 0.1)
				(type default)
			)
			(layer "B.Fab")
		)
		(fp_line
			(start 0.12065 0.3048)
			(end 0.67945 0.3048)
			(stroke
				(width 0.1)
				(type default)
			)
			(layer "B.Fab")
		)
		(fp_line
			(start 0.67945 0.3048)
			(end 0.67945 -0.305054)
			(stroke
				(width 0.1)
				(type default)
			)
			(layer "B.Fab")
		)
		(fp_line
			(start -0.120396 0.2794)
			(end 0.12065 0.2794)
			(stroke
				(width 0.1)
				(type default)
			)
			(layer "B.Fab")
		)
		(fp_line
			(start 0.12065 0.2794)
			(end 0.12065 0.3048)
			(stroke
				(width 0.1)
				(type default)
			)
			(layer "B.Fab")
		)
		(fp_line
			(start -0.12065 -0.2794)
			(end -0.12065 -0.3048)
			(stroke
				(width 0.1)
				(type default)
			)
			(layer "B.Fab")
		)
		(fp_line
			(start 0.12065 -0.2794)
			(end -0.12065 -0.2794)
			(stroke
				(width 0.1)
				(type default)
			)
			(layer "B.Fab")
		)
		(fp_line
			(start -0.67945 -0.3048)
			(end -0.67945 0.3048)
			(stroke
				(width 0.1)
				(type default)
			)
			(layer "B.Fab")
		)
		(fp_line
			(start -0.12065 -0.3048)
			(end -0.67945 -0.3048)
			(stroke
				(width 0.1)
				(type default)
			)
			(layer "B.Fab")
		)
		(fp_line
			(start 0.12065 -0.305054)
			(end 0.12065 -0.2794)
			(stroke
				(width 0.1)
				(type default)
			)
			(layer "B.Fab")
		)
		(fp_line
			(start 0.67945 -0.305054)
			(end 0.12065 -0.305054)
			(stroke
				(width 0.1)
				(type default)
			)
			(layer "B.Fab")
		)
		(pad "1" smd circle
			(at 0.40005 0 90)
			(size 0 0)
			(layers "B.Cu" "B.Mask" "B.Paste")
			(net "PVDDCR_SOC_P0")
		)
		(pad "2" smd circle
			(at -0.40005 0 90)
			(size 0 0)
			(layers "B.Cu" "B.Mask" "B.Paste")
			(net "GND")
		)
	)
	(footprint ""
		(layer "B.Cu")
		(at 172.456094 -417.078668)
		(property "Reference" "R2916"
			(at 0 0 0)
			(layer "B.SilkS")
			(hide yes)
			(effects
				(font
					(size 1.27 1.27)
				)
				(justify mirror)
			)
		)
		(property "Value" ""
			(at 0 0 0)
			(layer "B.Fab")
			(effects
				(font
					(size 1.27 1.27)
				)
				(justify mirror)
			)
		)
		(duplicate_pad_numbers_are_jumpers no)
		(fp_line
			(start -0.7874 -0.4064)
			(end -0.7874 0.4064)
			(stroke
				(width 0.1524)
				(type default)
			)
			(layer "B.SilkS")
		)
		(fp_line
			(start -0.7874 0.4064)
			(end 0.7874 0.4064)
			(stroke
				(width 0.1524)
				(type default)
			)
			(layer "B.SilkS")
		)
		(fp_line
			(start 0.7874 -0.4064)
			(end -0.7874 -0.4064)
			(stroke
				(width 0.1524)
				(type default)
			)
			(layer "B.SilkS")
		)
		(fp_line
			(start 0.7874 0.4064)
			(end 0.7874 -0.4064)
			(stroke
				(width 0.1524)
				(type default)
			)
			(layer "B.SilkS")
		)
		(fp_line
			(start -0.67945 -0.3048)
			(end -0.67945 0.3048)
			(stroke
				(width 0.1)
				(type default)
			)
			(layer "B.Fab")
		)
		(fp_line
			(start -0.67945 0.3048)
			(end -0.120396 0.3048)
			(stroke
				(width 0.1)
				(type default)
			)
			(layer "B.Fab")
		)
		(fp_line
			(start -0.12065 -0.3048)
			(end -0.67945 -0.3048)
			(stroke
				(width 0.1)
				(type default)
			)
			(layer "B.Fab")
		)
		(fp_line
			(start -0.12065 -0.2794)
			(end -0.12065 -0.3048)
			(stroke
				(width 0.1)
				(type default)
			)
			(layer "B.Fab")
		)
		(fp_line
			(start -0.120396 0.2794)
			(end 0.12065 0.2794)
			(stroke
				(width 0.1)
				(type default)
			)
			(layer "B.Fab")
		)
		(fp_line
			(start -0.120396 0.3048)
			(end -0.120396 0.2794)
			(stroke
				(width 0.1)
				(type default)
			)
			(layer "B.Fab")
		)
		(fp_line
			(start 0.12065 -0.305054)
			(end 0.12065 -0.2794)
			(stroke
				(width 0.1)
				(type default)
			)
			(layer "B.Fab")
		)
		(fp_line
			(start 0.12065 -0.2794)
			(end -0.12065 -0.2794)
			(stroke
				(width 0.1)
				(type default)
			)
			(layer "B.Fab")
		)
		(fp_line
			(start 0.12065 0.2794)
			(end 0.12065 0.3048)
			(stroke
				(width 0.1)
				(type default)
			)
			(layer "B.Fab")
		)
		(fp_line
			(start 0.12065 0.3048)
			(end 0.67945 0.3048)
			(stroke
				(width 0.1)
				(type default)
			)
			(layer "B.Fab")
		)
		(fp_line
			(start 0.67945 -0.305054)
			(end 0.12065 -0.305054)
			(stroke
				(width 0.1)
				(type default)
			)
			(layer "B.Fab")
		)
		(fp_line
			(start 0.67945 0.3048)
			(end 0.67945 -0.305054)
			(stroke
				(width 0.1)
				(type default)
			)
			(layer "B.Fab")
		)
		(pad "1" smd circle
			(at 0.40005 0 180)
			(size 0 0)
			(layers "B.Cu" "B.Mask" "B.Paste")
			(net "RST_SWB_BIC_R_N")
		)
		(pad "2" smd circle
			(at -0.40005 0 180)
			(size 0 0)
			(layers "B.Cu" "B.Mask" "B.Paste")
			(net "GND")
		)
	)
	(footprint ""
		(layer "B.Cu")
		(at 197.269608 -125.817376 180)
		(property "Reference" "R6113"
			(at 0 0 0)
			(layer "B.SilkS")
			(hide yes)
			(effects
				(font
					(size 1.27 1.27)
				)
				(justify mirror)
			)
		)
		(property "Value" ""
			(at 0 0 0)
			(layer "B.Fab")
			(effects
				(font
					(size 1.27 1.27)
				)
				(justify mirror)
			)
		)
		(duplicate_pad_numbers_are_jumpers no)
		(fp_line
			(start 0.7874 0.4064)
			(end 0.7874 -0.4064)
			(stroke
				(width 0.1524)
				(type default)
			)
			(layer "B.SilkS")
		)
		(fp_line
			(start 0.7874 -0.4064)
			(end -0.7874 -0.4064)
			(stroke
				(width 0.1524)
				(type default)
			)
			(layer "B.SilkS")
		)
		(fp_line
			(start -0.7874 0.4064)
			(end 0.7874 0.4064)
			(stroke
				(width 0.1524)
				(type default)
			)
			(layer "B.SilkS")
		)
		(fp_line
			(start -0.7874 -0.4064)
			(end -0.7874 0.4064)
			(stroke
				(width 0.1524)
				(type default)
			)
			(layer "B.SilkS")
		)
		(fp_line
			(start 0.67945 0.3048)
			(end 0.67945 -0.305054)
			(stroke
				(width 0.1)
				(type default)
			)
			(layer "B.Fab")
		)
		(fp_line
			(start 0.67945 -0.305054)
			(end 0.12065 -0.305054)
			(stroke
				(width 0.1)
				(type default)
			)
			(layer "B.Fab")
		)
		(fp_line
			(start 0.12065 0.3048)
			(end 0.67945 0.3048)
			(stroke
				(width 0.1)
				(type default)
			)
			(layer "B.Fab")
		)
		(fp_line
			(start 0.12065 0.2794)
			(end 0.12065 0.3048)
			(stroke
				(width 0.1)
				(type default)
			)
			(layer "B.Fab")
		)
		(fp_line
			(start 0.12065 -0.2794)
			(end -0.12065 -0.2794)
			(stroke
				(width 0.1)
				(type default)
			)
			(layer "B.Fab")
		)
		(fp_line
			(start 0.12065 -0.305054)
			(end 0.12065 -0.2794)
			(stroke
				(width 0.1)
				(type default)
			)
			(layer "B.Fab")
		)
		(fp_line
			(start -0.120396 0.3048)
			(end -0.120396 0.2794)
			(stroke
				(width 0.1)
				(type default)
			)
			(layer "B.Fab")
		)
		(fp_line
			(start -0.120396 0.2794)
			(end 0.12065 0.2794)
			(stroke
				(width 0.1)
				(type default)
			)
			(layer "B.Fab")
		)
		(fp_line
			(start -0.12065 -0.2794)
			(end -0.12065 -0.3048)
			(stroke
				(width 0.1)
				(type default)
			)
			(layer "B.Fab")
		)
		(fp_line
			(start -0.12065 -0.3048)
			(end -0.67945 -0.3048)
			(stroke
				(width 0.1)
				(type default)
			)
			(layer "B.Fab")
		)
		(fp_line
			(start -0.67945 0.3048)
			(end -0.120396 0.3048)
			(stroke
				(width 0.1)
				(type default)
			)
			(layer "B.Fab")
		)
		(fp_line
			(start -0.67945 -0.3048)
			(end -0.67945 0.3048)
			(stroke
				(width 0.1)
				(type default)
			)
			(layer "B.Fab")
		)
		(pad "1" smd circle
			(at 0.40005 0)
			(size 0 0)
			(layers "B.Cu" "B.Mask" "B.Paste")
			(net "RST_PERST_CPU1_SWB_N")
		)
		(pad "2" smd circle
			(at -0.40005 0)
			(size 0 0)
			(layers "B.Cu" "B.Mask" "B.Paste")
			(net "RST_PERST_CPU1_SWB_R_N")
		)
	)
	(footprint ""
		(layer "B.Cu")
		(at 15.042388 -134.16407)
		(property "Reference" "C97"
			(at 0 0 0)
			(layer "B.SilkS")
			(hide yes)
			(effects
				(font
					(size 1.27 1.27)
				)
				(justify mirror)
			)
		)
		(property "Value" ""
			(at 0 0 0)
			(layer "B.Fab")
			(effects
				(font
					(size 1.27 1.27)
				)
				(justify mirror)
			)
		)
		(duplicate_pad_numbers_are_jumpers no)
		(fp_line
			(start -0.7874 -0.4064)
			(end -0.7874 0.4064)
			(stroke
				(width 0.1524)
				(type default)
			)
			(layer "B.SilkS")
		)
		(fp_line
			(start -0.7874 0.4064)
			(end 0.7874 0.4064)
			(stroke
				(width 0.1524)
				(type default)
			)
			(layer "B.SilkS")
		)
		(fp_line
			(start 0.7874 -0.4064)
			(end -0.7874 -0.4064)
			(stroke
				(width 0.1524)
				(type default)
			)
			(layer "B.SilkS")
		)
		(fp_line
			(start 0.7874 0.4064)
			(end 0.7874 -0.4064)
			(stroke
				(width 0.1524)
				(type default)
			)
			(layer "B.SilkS")
		)
		(fp_line
			(start -0.67945 -0.3048)
			(end -0.67945 0.3048)
			(stroke
				(width 0.1)
				(type default)
			)
			(layer "B.Fab")
		)
		(fp_line
			(start -0.67945 0.3048)
			(end -0.120396 0.3048)
			(stroke
				(width 0.1)
				(type default)
			)
			(layer "B.Fab")
		)
		(fp_line
			(start -0.12065 -0.3048)
			(end -0.67945 -0.3048)
			(stroke
				(width 0.1)
				(type default)
			)
			(layer "B.Fab")
		)
		(fp_line
			(start -0.12065 -0.2794)
			(end -0.12065 -0.3048)
			(stroke
				(width 0.1)
				(type default)
			)
			(layer "B.Fab")
		)
		(fp_line
			(start -0.120396 0.2794)
			(end 0.12065 0.2794)
			(stroke
				(width 0.1)
				(type default)
			)
			(layer "B.Fab")
		)
		(fp_line
			(start -0.120396 0.3048)
			(end -0.120396 0.2794)
			(stroke
				(width 0.1)
				(type default)
			)
			(layer "B.Fab")
		)
		(fp_line
			(start 0.12065 -0.305054)
			(end 0.12065 -0.2794)
			(stroke
				(width 0.1)
				(type default)
			)
			(layer "B.Fab")
		)
		(fp_line
			(start 0.12065 -0.2794)
			(end -0.12065 -0.2794)
			(stroke
				(width 0.1)
				(type default)
			)
			(layer "B.Fab")
		)
		(fp_line
			(start 0.12065 0.2794)
			(end 0.12065 0.3048)
			(stroke
				(width 0.1)
				(type default)
			)
			(layer "B.Fab")
		)
		(fp_line
			(start 0.12065 0.3048)
			(end 0.67945 0.3048)
			(stroke
				(width 0.1)
				(type default)
			)
			(layer "B.Fab")
		)
		(fp_line
			(start 0.67945 -0.305054)
			(end 0.12065 -0.305054)
			(stroke
				(width 0.1)
				(type default)
			)
			(layer "B.Fab")
		)
		(fp_line
			(start 0.67945 0.3048)
			(end 0.67945 -0.305054)
			(stroke
				(width 0.1)
				(type default)
			)
			(layer "B.Fab")
		)
		(pad "1" smd circle
			(at 0.40005 0 180)
			(size 0 0)
			(layers "B.Cu" "B.Mask" "B.Paste")
			(net "VFG_3P3A_CLK_GEN")
		)
		(pad "2" smd circle
			(at -0.40005 0 180)
			(size 0 0)
			(layers "B.Cu" "B.Mask" "B.Paste")
			(net "GND")
		)
	)
	(footprint ""
		(layer "B.Cu")
		(at 365.773208 -267.52931)
		(property "Reference" "C2255"
			(at 0 0 0)
			(layer "B.SilkS")
			(hide yes)
			(effects
				(font
					(size 1.27 1.27)
				)
				(justify mirror)
			)
		)
		(property "Value" ""
			(at 0 0 0)
			(layer "B.Fab")
			(effects
				(font
					(size 1.27 1.27)
				)
				(justify mirror)
			)
		)
		(duplicate_pad_numbers_are_jumpers no)
		(fp_line
			(start -0.7874 -0.4064)
			(end -0.7874 0.4064)
			(stroke
				(width 0.1524)
				(type default)
			)
			(layer "B.SilkS")
		)
		(fp_line
			(start -0.7874 0.4064)
			(end 0.7874 0.4064)
			(stroke
				(width 0.1524)
				(type default)
			)
			(layer "B.SilkS")
		)
		(fp_line
			(start 0.7874 -0.4064)
			(end -0.7874 -0.4064)
			(stroke
				(width 0.1524)
				(type default)
			)
			(layer "B.SilkS")
		)
		(fp_line
			(start 0.7874 0.4064)
			(end 0.7874 -0.4064)
			(stroke
				(width 0.1524)
				(type default)
			)
			(layer "B.SilkS")
		)
		(fp_line
			(start -0.67945 -0.3048)
			(end -0.67945 0.3048)
			(stroke
				(width 0.1)
				(type default)
			)
			(layer "B.Fab")
		)
		(fp_line
			(start -0.67945 0.3048)
			(end -0.120396 0.3048)
			(stroke
				(width 0.1)
				(type default)
			)
			(layer "B.Fab")
		)
		(fp_line
			(start -0.12065 -0.3048)
			(end -0.67945 -0.3048)
			(stroke
				(width 0.1)
				(type default)
			)
			(layer "B.Fab")
		)
		(fp_line
			(start -0.12065 -0.2794)
			(end -0.12065 -0.3048)
			(stroke
				(width 0.1)
				(type default)
			)
			(layer "B.Fab")
		)
		(fp_line
			(start -0.120396 0.2794)
			(end 0.12065 0.2794)
			(stroke
				(width 0.1)
				(type default)
			)
			(layer "B.Fab")
		)
		(fp_line
			(start -0.120396 0.3048)
			(end -0.120396 0.2794)
			(stroke
				(width 0.1)
				(type default)
			)
			(layer "B.Fab")
		)
		(fp_line
			(start 0.12065 -0.305054)
			(end 0.12065 -0.2794)
			(stroke
				(width 0.1)
				(type default)
			)
			(layer "B.Fab")
		)
		(fp_line
			(start 0.12065 -0.2794)
			(end -0.12065 -0.2794)
			(stroke
				(width 0.1)
				(type default)
			)
			(layer "B.Fab")
		)
		(fp_line
			(start 0.12065 0.2794)
			(end 0.12065 0.3048)
			(stroke
				(width 0.1)
				(type default)
			)
			(layer "B.Fab")
		)
		(fp_line
			(start 0.12065 0.3048)
			(end 0.67945 0.3048)
			(stroke
				(width 0.1)
				(type default)
			)
			(layer "B.Fab")
		)
		(fp_line
			(start 0.67945 -0.305054)
			(end 0.12065 -0.305054)
			(stroke
				(width 0.1)
				(type default)
			)
			(layer "B.Fab")
		)
		(fp_line
			(start 0.67945 0.3048)
			(end 0.67945 -0.305054)
			(stroke
				(width 0.1)
				(type default)
			)
			(layer "B.Fab")
		)
		(pad "1" smd circle
			(at 0.40005 0 180)
			(size 0 0)
			(layers "B.Cu" "B.Mask" "B.Paste")
			(net "PVDDCR_CPU1_P0")
		)
		(pad "2" smd circle
			(at -0.40005 0 180)
			(size 0 0)
			(layers "B.Cu" "B.Mask" "B.Paste")
			(net "GND")
		)
	)
	(footprint ""
		(layer "B.Cu")
		(at 318.467486 -416.899344 90)
		(property "Reference" "C6541"
			(at 0 0 90)
			(layer "B.SilkS")
			(hide yes)
			(effects
				(font
					(size 1.27 1.27)
				)
				(justify mirror)
			)
		)
		(property "Value" ""
			(at 0 0 90)
			(layer "B.Fab")
			(effects
				(font
					(size 1.27 1.27)
				)
				(justify mirror)
			)
		)
		(duplicate_pad_numbers_are_jumpers no)
		(fp_line
			(start 0.299974 -0.150114)
			(end -0.299974 -0.150114)
			(stroke
				(width 0.1)
				(type default)
			)
			(layer "B.Fab")
		)
		(fp_line
			(start -0.299974 -0.150114)
			(end -0.299974 0.150114)
			(stroke
				(width 0.1)
				(type default)
			)
			(layer "B.Fab")
		)
		(fp_line
			(start 0.299974 0.150114)
			(end 0.299974 -0.150114)
			(stroke
				(width 0.1)
				(type default)
			)
			(layer "B.Fab")
		)
		(fp_line
			(start -0.299974 0.150114)
			(end 0.299974 0.150114)
			(stroke
				(width 0.1)
				(type default)
			)
			(layer "B.Fab")
		)
		(pad "1" smd rect
			(at 0.2667 0 270)
			(size 0.3048 0.381)
			(layers "B.Cu" "B.Mask" "B.Paste")
			(net "P5E_CPU0_P1_TX_BUF_C_DP<4>")
		)
		(pad "2" smd rect
			(at -0.2667 0 270)
			(size 0.3048 0.381)
			(layers "B.Cu" "B.Mask" "B.Paste")
			(net "P5E_CPU0_P1_TX_BUF_DP<4>")
		)
	)
	(footprint ""
		(layer "B.Cu")
		(at 420.51478 -359.736136)
		(property "Reference" "PR412"
			(at 0 0 0)
			(layer "B.SilkS")
			(hide yes)
			(effects
				(font
					(size 1.27 1.27)
				)
				(justify mirror)
			)
		)
		(property "Value" ""
			(at 0 0 0)
			(layer "B.Fab")
			(effects
				(font
					(size 1.27 1.27)
				)
				(justify mirror)
			)
		)
		(duplicate_pad_numbers_are_jumpers no)
		(fp_line
			(start -0.7874 -0.4064)
			(end -0.7874 0.4064)
			(stroke
				(width 0.1524)
				(type default)
			)
			(layer "B.SilkS")
		)
		(fp_line
			(start -0.7874 0.4064)
			(end 0.7874 0.4064)
			(stroke
				(width 0.1524)
				(type default)
			)
			(layer "B.SilkS")
		)
		(fp_line
			(start 0.7874 -0.4064)
			(end -0.7874 -0.4064)
			(stroke
				(width 0.1524)
				(type default)
			)
			(layer "B.SilkS")
		)
		(fp_line
			(start 0.7874 0.4064)
			(end 0.7874 -0.4064)
			(stroke
				(width 0.1524)
				(type default)
			)
			(layer "B.SilkS")
		)
		(fp_line
			(start -0.67945 -0.3048)
			(end -0.67945 0.3048)
			(stroke
				(width 0.1)
				(type default)
			)
			(layer "B.Fab")
		)
		(fp_line
			(start -0.67945 0.3048)
			(end -0.120396 0.3048)
			(stroke
				(width 0.1)
				(type default)
			)
			(layer "B.Fab")
		)
		(fp_line
			(start -0.12065 -0.3048)
			(end -0.67945 -0.3048)
			(stroke
				(width 0.1)
				(type default)
			)
			(layer "B.Fab")
		)
		(fp_line
			(start -0.12065 -0.2794)
			(end -0.12065 -0.3048)
			(stroke
				(width 0.1)
				(type default)
			)
			(layer "B.Fab")
		)
		(fp_line
			(start -0.120396 0.2794)
			(end 0.12065 0.2794)
			(stroke
				(width 0.1)
				(type default)
			)
			(layer "B.Fab")
		)
		(fp_line
			(start -0.120396 0.3048)
			(end -0.120396 0.2794)
			(stroke
				(width 0.1)
				(type default)
			)
			(layer "B.Fab")
		)
		(fp_line
			(start 0.12065 -0.305054)
			(end 0.12065 -0.2794)
			(stroke
				(width 0.1)
				(type default)
			)
			(layer "B.Fab")
		)
		(fp_line
			(start 0.12065 -0.2794)
			(end -0.12065 -0.2794)
			(stroke
				(width 0.1)
				(type default)
			)
			(layer "B.Fab")
		)
		(fp_line
			(start 0.12065 0.2794)
			(end 0.12065 0.3048)
			(stroke
				(width 0.1)
				(type default)
			)
			(layer "B.Fab")
		)
		(fp_line
			(start 0.12065 0.3048)
			(end 0.67945 0.3048)
			(stroke
				(width 0.1)
				(type default)
			)
			(layer "B.Fab")
		)
		(fp_line
			(start 0.67945 -0.305054)
			(end 0.12065 -0.305054)
			(stroke
				(width 0.1)
				(type default)
			)
			(layer "B.Fab")
		)
		(fp_line
			(start 0.67945 0.3048)
			(end 0.67945 -0.305054)
			(stroke
				(width 0.1)
				(type default)
			)
			(layer "B.Fab")
		)
		(pad "1" smd circle
			(at 0.40005 0 180)
			(size 0 0)
			(layers "B.Cu" "B.Mask" "B.Paste")
			(net "PVDD11_S3_P0_TEMP1")
		)
		(pad "2" smd circle
			(at -0.40005 0 180)
			(size 0 0)
			(layers "B.Cu" "B.Mask" "B.Paste")
			(net "GND")
		)
	)
	(footprint ""
		(layer "B.Cu")
		(at 160.200086 -408.517344 90)
		(property "Reference" "C6753"
			(at 0 0 90)
			(layer "B.SilkS")
			(hide yes)
			(effects
				(font
					(size 1.27 1.27)
				)
				(justify mirror)
			)
		)
		(property "Value" ""
			(at 0 0 90)
			(layer "B.Fab")
			(effects
				(font
					(size 1.27 1.27)
				)
				(justify mirror)
			)
		)
		(duplicate_pad_numbers_are_jumpers no)
		(fp_line
			(start 0.299974 -0.150114)
			(end -0.299974 -0.150114)
			(stroke
				(width 0.1)
				(type default)
			)
			(layer "B.Fab")
		)
		(fp_line
			(start -0.299974 -0.150114)
			(end -0.299974 0.150114)
			(stroke
				(width 0.1)
				(type default)
			)
			(layer "B.Fab")
		)
		(fp_line
			(start 0.299974 0.150114)
			(end 0.299974 -0.150114)
			(stroke
				(width 0.1)
				(type default)
			)
			(layer "B.Fab")
		)
		(fp_line
			(start -0.299974 0.150114)
			(end 0.299974 0.150114)
			(stroke
				(width 0.1)
				(type default)
			)
			(layer "B.Fab")
		)
		(pad "1" smd rect
			(at 0.2667 0 270)
			(size 0.3048 0.381)
			(layers "B.Cu" "B.Mask" "B.Paste")
			(net "P5E_CPU1_P3_TX_BUF_C_DP<14>")
		)
		(pad "2" smd rect
			(at -0.2667 0 270)
			(size 0.3048 0.381)
			(layers "B.Cu" "B.Mask" "B.Paste")
			(net "P5E_CPU1_P3_TX_BUF_DP<14>")
		)
	)
	(footprint ""
		(layer "B.Cu")
		(at 168.44645 -424.117262 -90)
		(property "Reference" "U41"
			(at -3.056128 0.105918 0)
			(unlocked yes)
			(layer "B.SilkS")
			(effects
				(font
					(size 0.7874 0.5842)
					(thickness 0.1524)
				)
				(justify mirror)
			)
		)
		(property "Value" ""
			(at 0 0 90)
			(layer "B.Fab")
			(effects
				(font
					(size 1.27 1.27)
				)
				(justify mirror)
			)
		)
		(duplicate_pad_numbers_are_jumpers no)
		(fp_line
			(start -1.03378 1.284478)
			(end 1.03378 1.284478)
			(stroke
				(width 0.1524)
				(type default)
			)
			(layer "B.SilkS")
		)
		(fp_line
			(start 1.03378 1.284478)
			(end 1.03378 -1.284478)
			(stroke
				(width 0.1524)
				(type default)
			)
			(layer "B.SilkS")
		)
		(fp_line
			(start -1.03378 -1.284478)
			(end -1.03378 1.284478)
			(stroke
				(width 0.1524)
				(type default)
			)
			(layer "B.SilkS")
		)
		(fp_line
			(start 1.03378 -1.284478)
			(end -1.03378 -1.284478)
			(stroke
				(width 0.1524)
				(type default)
			)
			(layer "B.SilkS")
		)
		(fp_poly
			(pts
				(xy 1.258316 -1.470152) (xy 1.86182 -1.775714) (xy 1.375918 -2.13614)
			)
			(stroke
				(width 0)
				(type default)
			)
			(fill yes)
			(layer "B.SilkS")
		)
		(fp_line
			(start -0.774954 1.02489)
			(end 0.774954 1.02489)
			(stroke
				(width 0.1)
				(type default)
			)
			(layer "B.Fab")
		)
		(fp_line
			(start 0.774954 1.02489)
			(end 0.774954 -1.02489)
			(stroke
				(width 0.1)
				(type default)
			)
			(layer "B.Fab")
		)
		(fp_line
			(start -0.774954 -1.02489)
			(end -0.774954 1.02489)
			(stroke
				(width 0.1)
				(type default)
			)
			(layer "B.Fab")
		)
		(fp_line
			(start 0.774954 -1.02489)
			(end -0.774954 -1.02489)
			(stroke
				(width 0.1)
				(type default)
			)
			(layer "B.Fab")
		)
		(fp_poly
			(pts
				(xy 1.201674 -0.750062) (xy 1.806702 -0.447548) (xy 1.806702 -1.052576)
			)
			(stroke
				(width 0)
				(type default)
			)
			(fill yes)
			(layer "B.Fab")
		)
		(pad "1" smd rect
			(at 0.64008 -0.750062)
			(size 0.3048 0.5334)
			(layers "B.Cu" "B.Mask" "B.Paste")
			(net "SMB_RT_CPU1_P3_ROM_MUX_1D_SCL")
		)
		(pad "2" smd rect
			(at 0.64008 -0.249936)
			(size 0.254 0.5334)
			(layers "B.Cu" "B.Mask" "B.Paste")
			(net "SMB_RT_CPU1_P3_ROM_MUX_1D_SDA")
		)
		(pad "3" smd rect
			(at 0.64008 0.249936)
			(size 0.254 0.5334)
			(layers "B.Cu" "B.Mask" "B.Paste")
			(net "SMB_RT_CPU1_P3_ROM_MUX_2D_SCL")
		)
		(pad "4" smd rect
			(at 0.64008 0.750062)
			(size 0.3048 0.5334)
			(layers "B.Cu" "B.Mask" "B.Paste")
			(net "SMB_RT_CPU1_P3_ROM_MUX_2D_SDA")
		)
		(pad "5" smd rect
			(at 0 0.839978 90)
			(size 0.3302 0.635)
			(layers "B.Cu" "B.Mask" "B.Paste")
			(net "GND")
		)
		(pad "6" smd rect
			(at -0.64008 0.750062)
			(size 0.3048 0.5334)
			(layers "B.Cu" "B.Mask" "B.Paste")
			(net "RT_ROM_MUX3_OE_N")
		)
		(pad "7" smd rect
			(at -0.64008 0.249936)
			(size 0.254 0.5334)
			(layers "B.Cu" "B.Mask" "B.Paste")
			(net "SMB_RT_CPU1_P3_ROM_R_SDA")
		)
		(pad "8" smd rect
			(at -0.64008 -0.249936)
			(size 0.254 0.5334)
			(layers "B.Cu" "B.Mask" "B.Paste")
			(net "SMB_RT_CPU1_P3_ROM_R_SCL")
		)
		(pad "9" smd rect
			(at -0.64008 -0.750062)
			(size 0.3048 0.5334)
			(layers "B.Cu" "B.Mask" "B.Paste")
			(net "FM_SMB_RT_ROM_MUX3_SEL")
		)
		(pad "10" smd rect
			(at 0 -0.839978 90)
			(size 0.3302 0.635)
			(layers "B.Cu" "B.Mask" "B.Paste")
			(net "P3V3_AUX")
		)
	)
	(footprint ""
		(layer "B.Cu")
		(at 389.683752 -395.148562 90)
		(property "Reference" "C1046"
			(at 0 0 90)
			(layer "B.SilkS")
			(hide yes)
			(effects
				(font
					(size 1.27 1.27)
				)
				(justify mirror)
			)
		)
		(property "Value" ""
			(at 0 0 90)
			(layer "B.Fab")
			(effects
				(font
					(size 1.27 1.27)
				)
				(justify mirror)
			)
		)
		(duplicate_pad_numbers_are_jumpers no)
		(fp_line
			(start 0.299974 -0.150114)
			(end -0.299974 -0.150114)
			(stroke
				(width 0.1)
				(type default)
			)
			(layer "B.Fab")
		)
		(fp_line
			(start -0.299974 -0.150114)
			(end -0.299974 0.150114)
			(stroke
				(width 0.1)
				(type default)
			)
			(layer "B.Fab")
		)
		(fp_line
			(start 0.299974 0.150114)
			(end 0.299974 -0.150114)
			(stroke
				(width 0.1)
				(type default)
			)
			(layer "B.Fab")
		)
		(fp_line
			(start -0.299974 0.150114)
			(end 0.299974 0.150114)
			(stroke
				(width 0.1)
				(type default)
			)
			(layer "B.Fab")
		)
		(pad "1" smd rect
			(at 0.2667 0 270)
			(size 0.3048 0.381)
			(layers "B.Cu" "B.Mask" "B.Paste")
			(net "P0V9_CPU0_RT3_2A")
		)
		(pad "2" smd rect
			(at -0.2667 0 270)
			(size 0.3048 0.381)
			(layers "B.Cu" "B.Mask" "B.Paste")
			(net "GND")
		)
	)
	(footprint ""
		(layer "B.Cu")
		(at 365.835692 -258.405122)
		(property "Reference" "C2559"
			(at 0 0 0)
			(layer "B.SilkS")
			(hide yes)
			(effects
				(font
					(size 1.27 1.27)
				)
				(justify mirror)
			)
		)
		(property "Value" ""
			(at 0 0 0)
			(layer "B.Fab")
			(effects
				(font
					(size 1.27 1.27)
				)
				(justify mirror)
			)
		)
		(duplicate_pad_numbers_are_jumpers no)
		(fp_line
			(start -0.7874 -0.4064)
			(end -0.7874 0.4064)
			(stroke
				(width 0.1524)
				(type default)
			)
			(layer "B.SilkS")
		)
		(fp_line
			(start -0.7874 0.4064)
			(end 0.7874 0.4064)
			(stroke
				(width 0.1524)
				(type default)
			)
			(layer "B.SilkS")
		)
		(fp_line
			(start 0.7874 -0.4064)
			(end -0.7874 -0.4064)
			(stroke
				(width 0.1524)
				(type default)
			)
			(layer "B.SilkS")
		)
		(fp_line
			(start 0.7874 0.4064)
			(end 0.7874 -0.4064)
			(stroke
				(width 0.1524)
				(type default)
			)
			(layer "B.SilkS")
		)
		(fp_line
			(start -0.67945 -0.3048)
			(end -0.67945 0.3048)
			(stroke
				(width 0.1)
				(type default)
			)
			(layer "B.Fab")
		)
		(fp_line
			(start -0.67945 0.3048)
			(end -0.120396 0.3048)
			(stroke
				(width 0.1)
				(type default)
			)
			(layer "B.Fab")
		)
		(fp_line
			(start -0.12065 -0.3048)
			(end -0.67945 -0.3048)
			(stroke
				(width 0.1)
				(type default)
			)
			(layer "B.Fab")
		)
		(fp_line
			(start -0.12065 -0.2794)
			(end -0.12065 -0.3048)
			(stroke
				(width 0.1)
				(type default)
			)
			(layer "B.Fab")
		)
		(fp_line
			(start -0.120396 0.2794)
			(end 0.12065 0.2794)
			(stroke
				(width 0.1)
				(type default)
			)
			(layer "B.Fab")
		)
		(fp_line
			(start -0.120396 0.3048)
			(end -0.120396 0.2794)
			(stroke
				(width 0.1)
				(type default)
			)
			(layer "B.Fab")
		)
		(fp_line
			(start 0.12065 -0.305054)
			(end 0.12065 -0.2794)
			(stroke
				(width 0.1)
				(type default)
			)
			(layer "B.Fab")
		)
		(fp_line
			(start 0.12065 -0.2794)
			(end -0.12065 -0.2794)
			(stroke
				(width 0.1)
				(type default)
			)
			(layer "B.Fab")
		)
		(fp_line
			(start 0.12065 0.2794)
			(end 0.12065 0.3048)
			(stroke
				(width 0.1)
				(type default)
			)
			(layer "B.Fab")
		)
		(fp_line
			(start 0.12065 0.3048)
			(end 0.67945 0.3048)
			(stroke
				(width 0.1)
				(type default)
			)
			(layer "B.Fab")
		)
		(fp_line
			(start 0.67945 -0.305054)
			(end 0.12065 -0.305054)
			(stroke
				(width 0.1)
				(type default)
			)
			(layer "B.Fab")
		)
		(fp_line
			(start 0.67945 0.3048)
			(end 0.67945 -0.305054)
			(stroke
				(width 0.1)
				(type default)
			)
			(layer "B.Fab")
		)
		(pad "1" smd circle
			(at 0.40005 0 180)
			(size 0 0)
			(layers "B.Cu" "B.Mask" "B.Paste")
			(net "PVDDCR_SOC_P0")
		)
		(pad "2" smd circle
			(at -0.40005 0 180)
			(size 0 0)
			(layers "B.Cu" "B.Mask" "B.Paste")
			(net "GND")
		)
	)
	(footprint ""
		(layer "B.Cu")
		(at 373.329454 -255.84531)
		(property "Reference" "C2578"
			(at 0 0 0)
			(layer "B.SilkS")
			(hide yes)
			(effects
				(font
					(size 1.27 1.27)
				)
				(justify mirror)
			)
		)
		(property "Value" ""
			(at 0 0 0)
			(layer "B.Fab")
			(effects
				(font
					(size 1.27 1.27)
				)
				(justify mirror)
			)
		)
		(duplicate_pad_numbers_are_jumpers no)
		(fp_line
			(start -0.7874 -0.4064)
			(end -0.7874 0.4064)
			(stroke
				(width 0.1524)
				(type default)
			)
			(layer "B.SilkS")
		)
		(fp_line
			(start -0.7874 0.4064)
			(end 0.7874 0.4064)
			(stroke
				(width 0.1524)
				(type default)
			)
			(layer "B.SilkS")
		)
		(fp_line
			(start 0.7874 -0.4064)
			(end -0.7874 -0.4064)
			(stroke
				(width 0.1524)
				(type default)
			)
			(layer "B.SilkS")
		)
		(fp_line
			(start 0.7874 0.4064)
			(end 0.7874 -0.4064)
			(stroke
				(width 0.1524)
				(type default)
			)
			(layer "B.SilkS")
		)
		(fp_line
			(start -0.67945 -0.3048)
			(end -0.67945 0.3048)
			(stroke
				(width 0.1)
				(type default)
			)
			(layer "B.Fab")
		)
		(fp_line
			(start -0.67945 0.3048)
			(end -0.120396 0.3048)
			(stroke
				(width 0.1)
				(type default)
			)
			(layer "B.Fab")
		)
		(fp_line
			(start -0.12065 -0.3048)
			(end -0.67945 -0.3048)
			(stroke
				(width 0.1)
				(type default)
			)
			(layer "B.Fab")
		)
		(fp_line
			(start -0.12065 -0.2794)
			(end -0.12065 -0.3048)
			(stroke
				(width 0.1)
				(type default)
			)
			(layer "B.Fab")
		)
		(fp_line
			(start -0.120396 0.2794)
			(end 0.12065 0.2794)
			(stroke
				(width 0.1)
				(type default)
			)
			(layer "B.Fab")
		)
		(fp_line
			(start -0.120396 0.3048)
			(end -0.120396 0.2794)
			(stroke
				(width 0.1)
				(type default)
			)
			(layer "B.Fab")
		)
		(fp_line
			(start 0.12065 -0.305054)
			(end 0.12065 -0.2794)
			(stroke
				(width 0.1)
				(type default)
			)
			(layer "B.Fab")
		)
		(fp_line
			(start 0.12065 -0.2794)
			(end -0.12065 -0.2794)
			(stroke
				(width 0.1)
				(type default)
			)
			(layer "B.Fab")
		)
		(fp_line
			(start 0.12065 0.2794)
			(end 0.12065 0.3048)
			(stroke
				(width 0.1)
				(type default)
			)
			(layer "B.Fab")
		)
		(fp_line
			(start 0.12065 0.3048)
			(end 0.67945 0.3048)
			(stroke
				(width 0.1)
				(type default)
			)
			(layer "B.Fab")
		)
		(fp_line
			(start 0.67945 -0.305054)
			(end 0.12065 -0.305054)
			(stroke
				(width 0.1)
				(type default)
			)
			(layer "B.Fab")
		)
		(fp_line
			(start 0.67945 0.3048)
			(end 0.67945 -0.305054)
			(stroke
				(width 0.1)
				(type default)
			)
			(layer "B.Fab")
		)
		(pad "1" smd circle
			(at 0.40005 0 180)
			(size 0 0)
			(layers "B.Cu" "B.Mask" "B.Paste")
			(net "PVDDCR_SOC_P0")
		)
		(pad "2" smd circle
			(at -0.40005 0 180)
			(size 0 0)
			(layers "B.Cu" "B.Mask" "B.Paste")
			(net "GND")
		)
	)
	(footprint ""
		(layer "B.Cu")
		(at 88.243918 -335.04632 90)
		(property "Reference" "PC381_1"
			(at 0 0 90)
			(layer "B.SilkS")
			(hide yes)
			(effects
				(font
					(size 1.27 1.27)
				)
				(justify mirror)
			)
		)
		(property "Value" ""
			(at 0 0 90)
			(layer "B.Fab")
			(effects
				(font
					(size 1.27 1.27)
				)
				(justify mirror)
			)
		)
		(duplicate_pad_numbers_are_jumpers no)
		(fp_line
			(start 1.524 -0.762)
			(end -1.524 -0.762)
			(stroke
				(width 0.1524)
				(type default)
			)
			(layer "B.SilkS")
		)
		(fp_line
			(start -1.524 -0.762)
			(end -1.524 0.762)
			(stroke
				(width 0.1524)
				(type default)
			)
			(layer "B.SilkS")
		)
		(fp_line
			(start 1.524 0.762)
			(end 1.524 -0.762)
			(stroke
				(width 0.1524)
				(type default)
			)
			(layer "B.SilkS")
		)
		(fp_line
			(start -1.524 0.762)
			(end 1.524 0.762)
			(stroke
				(width 0.1524)
				(type default)
			)
			(layer "B.SilkS")
		)
		(fp_line
			(start 1.1049 -0.724916)
			(end 1.1049 0.724916)
			(stroke
				(width 0.1)
				(type default)
			)
			(layer "B.Fab")
		)
		(fp_line
			(start -1.1049 -0.724916)
			(end 1.1049 -0.724916)
			(stroke
				(width 0.1)
				(type default)
			)
			(layer "B.Fab")
		)
		(fp_line
			(start 1.1049 0.724916)
			(end -1.1049 0.724916)
			(stroke
				(width 0.1)
				(type default)
			)
			(layer "B.Fab")
		)
		(fp_line
			(start -1.1049 0.724916)
			(end -1.1049 -0.724916)
			(stroke
				(width 0.1)
				(type default)
			)
			(layer "B.Fab")
		)
		(pad "1" smd rect
			(at 0.889 0 90)
			(size 1.016 1.27)
			(layers "B.Cu" "B.Mask" "B.Paste")
			(net "SW_P12V_AUX_PVDDCR_CPU1_P1_FLT")
		)
		(pad "2" smd rect
			(at -0.889 0 90)
			(size 1.016 1.27)
			(layers "B.Cu" "B.Mask" "B.Paste")
			(net "GND")
		)
	)
	(footprint ""
		(layer "B.Cu")
		(at 53.084476 -339.890354 -90)
		(property "Reference" "PC450"
			(at 9.660636 -0.954786 270)
			(unlocked yes)
			(layer "B.SilkS")
			(effects
				(font
					(size 0.7874 0.5842)
					(thickness 0.1524)
				)
				(justify left mirror)
			)
		)
		(property "Value" ""
			(at 0 0 90)
			(layer "B.Fab")
			(effects
				(font
					(size 1.27 1.27)
				)
				(justify mirror)
			)
		)
		(duplicate_pad_numbers_are_jumpers no)
		(fp_line
			(start -4.533392 2.249932)
			(end 4.533392 2.249932)
			(stroke
				(width 0.1524)
				(type default)
			)
			(layer "B.SilkS")
		)
		(fp_line
			(start 4.533392 2.249932)
			(end 4.533392 -2.249932)
			(stroke
				(width 0.1524)
				(type default)
			)
			(layer "B.SilkS")
		)
		(fp_line
			(start -4.533392 -2.249932)
			(end -4.533392 2.249932)
			(stroke
				(width 0.1524)
				(type default)
			)
			(layer "B.SilkS")
		)
		(fp_line
			(start 4.533392 -2.249932)
			(end -4.533392 -2.249932)
			(stroke
				(width 0.1524)
				(type default)
			)
			(layer "B.SilkS")
		)
		(fp_rect
			(start 5.39242 2.326132)
			(end 4.533392 -2.326132)
			(stroke
				(width 0)
				(type default)
			)
			(fill yes)
			(layer "B.SilkS")
		)
		(fp_line
			(start -3.750056 2.249932)
			(end 3.750056 2.249932)
			(stroke
				(width 0.1)
				(type default)
			)
			(layer "B.Fab")
		)
		(fp_line
			(start 3.750056 2.249932)
			(end 3.750056 -2.249932)
			(stroke
				(width 0.1)
				(type default)
			)
			(layer "B.Fab")
		)
		(fp_line
			(start -3.750056 -2.249932)
			(end -3.750056 2.249932)
			(stroke
				(width 0.1)
				(type default)
			)
			(layer "B.Fab")
		)
		(fp_line
			(start 3.750056 -2.249932)
			(end -3.750056 -2.249932)
			(stroke
				(width 0.1)
				(type default)
			)
			(layer "B.Fab")
		)
		(fp_text user "-"
			(at -4.543044 1.90627 270)
			(unlocked yes)
			(layer "B.SilkS")
			(effects
				(font
					(size 1.905 1.4224)
					(thickness 0.1524)
				)
				(justify left mirror)
			)
		)
		(fp_text user "+"
			(at 6.483604 0.760476 180)
			(unlocked yes)
			(layer "B.SilkS")
			(effects
				(font
					(size 1.905 1.4224)
					(thickness 0.1524)
				)
				(justify left mirror)
			)
		)
		(fp_text user "+"
			(at 6.322314 0.786384 180)
			(unlocked yes)
			(layer "B.Fab")
			(effects
				(font
					(size 1.905 1.4224)
					(thickness 0.1524)
				)
				(justify left mirror)
			)
		)
		(fp_text user "-"
			(at -4.8514 -0.14605 270)
			(unlocked yes)
			(layer "B.Fab")
			(effects
				(font
					(size 1.905 1.4224)
					(thickness 0.1524)
				)
				(justify left mirror)
			)
		)
		(pad "1" smd rect
			(at 3.199892 0 90)
			(size 2.413 2.8194)
			(layers "B.Cu" "B.Mask" "B.Paste")
			(net "PVDDIO_P1")
		)
		(pad "2" smd rect
			(at -3.199892 0 90)
			(size 2.413 2.8194)
			(layers "B.Cu" "B.Mask" "B.Paste")
			(net "GND")
		)
	)
	(footprint ""
		(layer "B.Cu")
		(at 365.846868 -423.022776 180)
		(property "Reference" "R838"
			(at 0 0 0)
			(layer "B.SilkS")
			(hide yes)
			(effects
				(font
					(size 1.27 1.27)
				)
				(justify mirror)
			)
		)
		(property "Value" ""
			(at 0 0 0)
			(layer "B.Fab")
			(effects
				(font
					(size 1.27 1.27)
				)
				(justify mirror)
			)
		)
		(duplicate_pad_numbers_are_jumpers no)
		(fp_line
			(start 0.32512 0.175006)
			(end 0.32512 -0.175006)
			(stroke
				(width 0.1)
				(type default)
			)
			(layer "B.Fab")
		)
		(fp_line
			(start 0.32512 -0.175006)
			(end -0.32512 -0.175006)
			(stroke
				(width 0.1)
				(type default)
			)
			(layer "B.Fab")
		)
		(fp_line
			(start -0.32512 0.175006)
			(end 0.32512 0.175006)
			(stroke
				(width 0.1)
				(type default)
			)
			(layer "B.Fab")
		)
		(fp_line
			(start -0.32512 -0.175006)
			(end -0.32512 0.175006)
			(stroke
				(width 0.1)
				(type default)
			)
			(layer "B.Fab")
		)
		(pad "1" smd rect
			(at 0.2667 0)
			(size 0.3048 0.381)
			(layers "B.Cu" "B.Mask" "B.Paste")
			(net "P1V8_CPU0_RT_1D")
		)
		(pad "2" smd rect
			(at -0.2667 0 180)
			(size 0.3048 0.381)
			(layers "B.Cu" "B.Mask" "B.Paste")
			(net "SMB_RT_CPU0_P3_ROM_R_SDA")
		)
	)
	(footprint ""
		(layer "B.Cu")
		(at 357.835454 -250.25731)
		(property "Reference" "C279"
			(at 0 0 0)
			(layer "B.SilkS")
			(hide yes)
			(effects
				(font
					(size 1.27 1.27)
				)
				(justify mirror)
			)
		)
		(property "Value" ""
			(at 0 0 0)
			(layer "B.Fab")
			(effects
				(font
					(size 1.27 1.27)
				)
				(justify mirror)
			)
		)
		(duplicate_pad_numbers_are_jumpers no)
		(fp_line
			(start -0.7874 -0.4064)
			(end -0.7874 0.4064)
			(stroke
				(width 0.1524)
				(type default)
			)
			(layer "B.SilkS")
		)
		(fp_line
			(start -0.7874 0.4064)
			(end 0.7874 0.4064)
			(stroke
				(width 0.1524)
				(type default)
			)
			(layer "B.SilkS")
		)
		(fp_line
			(start 0.7874 -0.4064)
			(end -0.7874 -0.4064)
			(stroke
				(width 0.1524)
				(type default)
			)
			(layer "B.SilkS")
		)
		(fp_line
			(start 0.7874 0.4064)
			(end 0.7874 -0.4064)
			(stroke
				(width 0.1524)
				(type default)
			)
			(layer "B.SilkS")
		)
		(fp_line
			(start -0.67945 -0.3048)
			(end -0.67945 0.3048)
			(stroke
				(width 0.1)
				(type default)
			)
			(layer "B.Fab")
		)
		(fp_line
			(start -0.67945 0.3048)
			(end -0.120396 0.3048)
			(stroke
				(width 0.1)
				(type default)
			)
			(layer "B.Fab")
		)
		(fp_line
			(start -0.12065 -0.3048)
			(end -0.67945 -0.3048)
			(stroke
				(width 0.1)
				(type default)
			)
			(layer "B.Fab")
		)
		(fp_line
			(start -0.12065 -0.2794)
			(end -0.12065 -0.3048)
			(stroke
				(width 0.1)
				(type default)
			)
			(layer "B.Fab")
		)
		(fp_line
			(start -0.120396 0.2794)
			(end 0.12065 0.2794)
			(stroke
				(width 0.1)
				(type default)
			)
			(layer "B.Fab")
		)
		(fp_line
			(start -0.120396 0.3048)
			(end -0.120396 0.2794)
			(stroke
				(width 0.1)
				(type default)
			)
			(layer "B.Fab")
		)
		(fp_line
			(start 0.12065 -0.305054)
			(end 0.12065 -0.2794)
			(stroke
				(width 0.1)
				(type default)
			)
			(layer "B.Fab")
		)
		(fp_line
			(start 0.12065 -0.2794)
			(end -0.12065 -0.2794)
			(stroke
				(width 0.1)
				(type default)
			)
			(layer "B.Fab")
		)
		(fp_line
			(start 0.12065 0.2794)
			(end 0.12065 0.3048)
			(stroke
				(width 0.1)
				(type default)
			)
			(layer "B.Fab")
		)
		(fp_line
			(start 0.12065 0.3048)
			(end 0.67945 0.3048)
			(stroke
				(width 0.1)
				(type default)
			)
			(layer "B.Fab")
		)
		(fp_line
			(start 0.67945 -0.305054)
			(end 0.12065 -0.305054)
			(stroke
				(width 0.1)
				(type default)
			)
			(layer "B.Fab")
		)
		(fp_line
			(start 0.67945 0.3048)
			(end 0.67945 -0.305054)
			(stroke
				(width 0.1)
				(type default)
			)
			(layer "B.Fab")
		)
		(pad "1" smd circle
			(at 0.40005 0 180)
			(size 0 0)
			(layers "B.Cu" "B.Mask" "B.Paste")
			(net "PVDDCR_CPU0_P0")
		)
		(pad "2" smd circle
			(at -0.40005 0 180)
			(size 0 0)
			(layers "B.Cu" "B.Mask" "B.Paste")
			(net "GND")
		)
	)
	(footprint ""
		(layer "B.Cu")
		(at 238.633 -338.455 180)
		(property "Reference" "R806"
			(at 0 0 0)
			(layer "B.SilkS")
			(hide yes)
			(effects
				(font
					(size 1.27 1.27)
				)
				(justify mirror)
			)
		)
		(property "Value" ""
			(at 0 0 0)
			(layer "B.Fab")
			(effects
				(font
					(size 1.27 1.27)
				)
				(justify mirror)
			)
		)
		(duplicate_pad_numbers_are_jumpers no)
		(fp_line
			(start 0.32512 0.175006)
			(end 0.32512 -0.175006)
			(stroke
				(width 0.1)
				(type default)
			)
			(layer "B.Fab")
		)
		(fp_line
			(start 0.32512 -0.175006)
			(end -0.32512 -0.175006)
			(stroke
				(width 0.1)
				(type default)
			)
			(layer "B.Fab")
		)
		(fp_line
			(start -0.32512 0.175006)
			(end 0.32512 0.175006)
			(stroke
				(width 0.1)
				(type default)
			)
			(layer "B.Fab")
		)
		(fp_line
			(start -0.32512 -0.175006)
			(end -0.32512 0.175006)
			(stroke
				(width 0.1)
				(type default)
			)
			(layer "B.Fab")
		)
		(pad "1" smd rect
			(at 0.2667 0)
			(size 0.3048 0.381)
			(layers "B.Cu" "B.Mask" "B.Paste")
			(net "SMB_RT_CPU1_P3_ROM_MUX_2D_SDA")
		)
		(pad "2" smd rect
			(at -0.2667 0 180)
			(size 0.3048 0.381)
			(layers "B.Cu" "B.Mask" "B.Paste")
			(net "SMB_RT_CPU1_P3_ROM_MUX_2D_R_SDA")
		)
	)
	(footprint ""
		(layer "B.Cu")
		(at 344.511884 -338.964016 -90)
		(property "Reference" "PC136_5"
			(at 0 0 90)
			(layer "B.SilkS")
			(hide yes)
			(effects
				(font
					(size 1.27 1.27)
				)
				(justify mirror)
			)
		)
		(property "Value" ""
			(at 0 0 90)
			(layer "B.Fab")
			(effects
				(font
					(size 1.27 1.27)
				)
				(justify mirror)
			)
		)
		(duplicate_pad_numbers_are_jumpers no)
		(fp_line
			(start -1.524 0.762)
			(end 1.524 0.762)
			(stroke
				(width 0.1524)
				(type default)
			)
			(layer "B.SilkS")
		)
		(fp_line
			(start 1.524 0.762)
			(end 1.524 -0.762)
			(stroke
				(width 0.1524)
				(type default)
			)
			(layer "B.SilkS")
		)
		(fp_line
			(start -1.524 -0.762)
			(end -1.524 0.762)
			(stroke
				(width 0.1524)
				(type default)
			)
			(layer "B.SilkS")
		)
		(fp_line
			(start 1.524 -0.762)
			(end -1.524 -0.762)
			(stroke
				(width 0.1524)
				(type default)
			)
			(layer "B.SilkS")
		)
		(fp_line
			(start -1.1049 0.724916)
			(end -1.1049 -0.724916)
			(stroke
				(width 0.1)
				(type default)
			)
			(layer "B.Fab")
		)
		(fp_line
			(start 1.1049 0.724916)
			(end -1.1049 0.724916)
			(stroke
				(width 0.1)
				(type default)
			)
			(layer "B.Fab")
		)
		(fp_line
			(start -1.1049 -0.724916)
			(end 1.1049 -0.724916)
			(stroke
				(width 0.1)
				(type default)
			)
			(layer "B.Fab")
		)
		(fp_line
			(start 1.1049 -0.724916)
			(end 1.1049 0.724916)
			(stroke
				(width 0.1)
				(type default)
			)
			(layer "B.Fab")
		)
		(pad "1" smd rect
			(at 0.889 0 270)
			(size 1.016 1.27)
			(layers "B.Cu" "B.Mask" "B.Paste")
			(net "SW_P12V_AUX_PVDDCR_CPU1_P0_FLT")
		)
		(pad "2" smd rect
			(at -0.889 0 270)
			(size 1.016 1.27)
			(layers "B.Cu" "B.Mask" "B.Paste")
			(net "GND")
		)
	)
	(footprint ""
		(layer "B.Cu")
		(at 172.456094 -414.792668 180)
		(property "Reference" "R2815"
			(at 0 0 0)
			(layer "B.SilkS")
			(hide yes)
			(effects
				(font
					(size 1.27 1.27)
				)
				(justify mirror)
			)
		)
		(property "Value" ""
			(at 0 0 0)
			(layer "B.Fab")
			(effects
				(font
					(size 1.27 1.27)
				)
				(justify mirror)
			)
		)
		(duplicate_pad_numbers_are_jumpers no)
		(fp_line
			(start 0.7874 0.4064)
			(end 0.7874 -0.4064)
			(stroke
				(width 0.1524)
				(type default)
			)
			(layer "B.SilkS")
		)
		(fp_line
			(start 0.7874 -0.4064)
			(end -0.7874 -0.4064)
			(stroke
				(width 0.1524)
				(type default)
			)
			(layer "B.SilkS")
		)
		(fp_line
			(start -0.7874 0.4064)
			(end 0.7874 0.4064)
			(stroke
				(width 0.1524)
				(type default)
			)
			(layer "B.SilkS")
		)
		(fp_line
			(start -0.7874 -0.4064)
			(end -0.7874 0.4064)
			(stroke
				(width 0.1524)
				(type default)
			)
			(layer "B.SilkS")
		)
		(fp_line
			(start 0.67945 0.3048)
			(end 0.67945 -0.305054)
			(stroke
				(width 0.1)
				(type default)
			)
			(layer "B.Fab")
		)
		(fp_line
			(start 0.67945 -0.305054)
			(end 0.12065 -0.305054)
			(stroke
				(width 0.1)
				(type default)
			)
			(layer "B.Fab")
		)
		(fp_line
			(start 0.12065 0.3048)
			(end 0.67945 0.3048)
			(stroke
				(width 0.1)
				(type default)
			)
			(layer "B.Fab")
		)
		(fp_line
			(start 0.12065 0.2794)
			(end 0.12065 0.3048)
			(stroke
				(width 0.1)
				(type default)
			)
			(layer "B.Fab")
		)
		(fp_line
			(start 0.12065 -0.2794)
			(end -0.12065 -0.2794)
			(stroke
				(width 0.1)
				(type default)
			)
			(layer "B.Fab")
		)
		(fp_line
			(start 0.12065 -0.305054)
			(end 0.12065 -0.2794)
			(stroke
				(width 0.1)
				(type default)
			)
			(layer "B.Fab")
		)
		(fp_line
			(start -0.120396 0.3048)
			(end -0.120396 0.2794)
			(stroke
				(width 0.1)
				(type default)
			)
			(layer "B.Fab")
		)
		(fp_line
			(start -0.120396 0.2794)
			(end 0.12065 0.2794)
			(stroke
				(width 0.1)
				(type default)
			)
			(layer "B.Fab")
		)
		(fp_line
			(start -0.12065 -0.2794)
			(end -0.12065 -0.3048)
			(stroke
				(width 0.1)
				(type default)
			)
			(layer "B.Fab")
		)
		(fp_line
			(start -0.12065 -0.3048)
			(end -0.67945 -0.3048)
			(stroke
				(width 0.1)
				(type default)
			)
			(layer "B.Fab")
		)
		(fp_line
			(start -0.67945 0.3048)
			(end -0.120396 0.3048)
			(stroke
				(width 0.1)
				(type default)
			)
			(layer "B.Fab")
		)
		(fp_line
			(start -0.67945 -0.3048)
			(end -0.67945 0.3048)
			(stroke
				(width 0.1)
				(type default)
			)
			(layer "B.Fab")
		)
		(pad "1" smd circle
			(at 0.40005 0)
			(size 0 0)
			(layers "B.Cu" "B.Mask" "B.Paste")
			(net "P3V3_AUX")
		)
		(pad "2" smd circle
			(at -0.40005 0)
			(size 0 0)
			(layers "B.Cu" "B.Mask" "B.Paste")
			(net "BMC_MONITER_R")
		)
	)
	(footprint ""
		(layer "B.Cu")
		(at 405.546306 -396.393162 -90)
		(property "Reference" "C972"
			(at 0 0 90)
			(layer "B.SilkS")
			(hide yes)
			(effects
				(font
					(size 1.27 1.27)
				)
				(justify mirror)
			)
		)
		(property "Value" ""
			(at 0 0 90)
			(layer "B.Fab")
			(effects
				(font
					(size 1.27 1.27)
				)
				(justify mirror)
			)
		)
		(duplicate_pad_numbers_are_jumpers no)
		(fp_line
			(start -0.299974 0.150114)
			(end 0.299974 0.150114)
			(stroke
				(width 0.1)
				(type default)
			)
			(layer "B.Fab")
		)
		(fp_line
			(start 0.299974 0.150114)
			(end 0.299974 -0.150114)
			(stroke
				(width 0.1)
				(type default)
			)
			(layer "B.Fab")
		)
		(fp_line
			(start -0.299974 -0.150114)
			(end -0.299974 0.150114)
			(stroke
				(width 0.1)
				(type default)
			)
			(layer "B.Fab")
		)
		(fp_line
			(start 0.299974 -0.150114)
			(end -0.299974 -0.150114)
			(stroke
				(width 0.1)
				(type default)
			)
			(layer "B.Fab")
		)
		(pad "1" smd rect
			(at 0.2667 0 90)
			(size 0.3048 0.381)
			(layers "B.Cu" "B.Mask" "B.Paste")
			(net "P0V9_CPU0_RT2_2A")
		)
		(pad "2" smd rect
			(at -0.2667 0 90)
			(size 0.3048 0.381)
			(layers "B.Cu" "B.Mask" "B.Paste")
			(net "GND")
		)
	)
	(footprint ""
		(layer "B.Cu")
		(at 254.635 -341.884 180)
		(property "Reference" "R1366"
			(at 0 0 0)
			(layer "B.SilkS")
			(hide yes)
			(effects
				(font
					(size 1.27 1.27)
				)
				(justify mirror)
			)
		)
		(property "Value" ""
			(at 0 0 0)
			(layer "B.Fab")
			(effects
				(font
					(size 1.27 1.27)
				)
				(justify mirror)
			)
		)
		(duplicate_pad_numbers_are_jumpers no)
		(fp_line
			(start 0.32512 0.175006)
			(end 0.32512 -0.175006)
			(stroke
				(width 0.1)
				(type default)
			)
			(layer "B.Fab")
		)
		(fp_line
			(start 0.32512 -0.175006)
			(end -0.32512 -0.175006)
			(stroke
				(width 0.1)
				(type default)
			)
			(layer "B.Fab")
		)
		(fp_line
			(start -0.32512 0.175006)
			(end 0.32512 0.175006)
			(stroke
				(width 0.1)
				(type default)
			)
			(layer "B.Fab")
		)
		(fp_line
			(start -0.32512 -0.175006)
			(end -0.32512 0.175006)
			(stroke
				(width 0.1)
				(type default)
			)
			(layer "B.Fab")
		)
		(pad "1" smd rect
			(at 0.2667 0)
			(size 0.3048 0.381)
			(layers "B.Cu" "B.Mask" "B.Paste")
			(net "P1V8_CPU0_RT_1D")
		)
		(pad "2" smd rect
			(at -0.2667 0 180)
			(size 0.3048 0.381)
			(layers "B.Cu" "B.Mask" "B.Paste")
			(net "SMB_RT_CPU0_P0_ROM_MUX_2D_R_SDA")
		)
	)
	(footprint ""
		(layer "B.Cu")
		(at 85.94598 -180.078634 90)
		(property "Reference" "PR191"
			(at 0 0 90)
			(layer "B.SilkS")
			(hide yes)
			(effects
				(font
					(size 1.27 1.27)
				)
				(justify mirror)
			)
		)
		(property "Value" ""
			(at 0 0 90)
			(layer "B.Fab")
			(effects
				(font
					(size 1.27 1.27)
				)
				(justify mirror)
			)
		)
		(duplicate_pad_numbers_are_jumpers no)
		(fp_line
			(start 0.7874 -0.4064)
			(end -0.7874 -0.4064)
			(stroke
				(width 0.1524)
				(type default)
			)
			(layer "B.SilkS")
		)
		(fp_line
			(start -0.7874 -0.4064)
			(end -0.7874 0.4064)
			(stroke
				(width 0.1524)
				(type default)
			)
			(layer "B.SilkS")
		)
		(fp_line
			(start 0.7874 0.4064)
			(end 0.7874 -0.4064)
			(stroke
				(width 0.1524)
				(type default)
			)
			(layer "B.SilkS")
		)
		(fp_line
			(start -0.7874 0.4064)
			(end 0.7874 0.4064)
			(stroke
				(width 0.1524)
				(type default)
			)
			(layer "B.SilkS")
		)
		(fp_line
			(start 0.67945 -0.305054)
			(end 0.12065 -0.305054)
			(stroke
				(width 0.1)
				(type default)
			)
			(layer "B.Fab")
		)
		(fp_line
			(start 0.12065 -0.305054)
			(end 0.12065 -0.2794)
			(stroke
				(width 0.1)
				(type default)
			)
			(layer "B.Fab")
		)
		(fp_line
			(start -0.12065 -0.3048)
			(end -0.67945 -0.3048)
			(stroke
				(width 0.1)
				(type default)
			)
			(layer "B.Fab")
		)
		(fp_line
			(start -0.67945 -0.3048)
			(end -0.67945 0.3048)
			(stroke
				(width 0.1)
				(type default)
			)
			(layer "B.Fab")
		)
		(fp_line
			(start 0.12065 -0.2794)
			(end -0.12065 -0.2794)
			(stroke
				(width 0.1)
				(type default)
			)
			(layer "B.Fab")
		)
		(fp_line
			(start -0.12065 -0.2794)
			(end -0.12065 -0.3048)
			(stroke
				(width 0.1)
				(type default)
			)
			(layer "B.Fab")
		)
		(fp_line
			(start 0.12065 0.2794)
			(end 0.12065 0.3048)
			(stroke
				(width 0.1)
				(type default)
			)
			(layer "B.Fab")
		)
		(fp_line
			(start -0.120396 0.2794)
			(end 0.12065 0.2794)
			(stroke
				(width 0.1)
				(type default)
			)
			(layer "B.Fab")
		)
		(fp_line
			(start 0.67945 0.3048)
			(end 0.67945 -0.305054)
			(stroke
				(width 0.1)
				(type default)
			)
			(layer "B.Fab")
		)
		(fp_line
			(start 0.12065 0.3048)
			(end 0.67945 0.3048)
			(stroke
				(width 0.1)
				(type default)
			)
			(layer "B.Fab")
		)
		(fp_line
			(start -0.120396 0.3048)
			(end -0.120396 0.2794)
			(stroke
				(width 0.1)
				(type default)
			)
			(layer "B.Fab")
		)
		(fp_line
			(start -0.67945 0.3048)
			(end -0.120396 0.3048)
			(stroke
				(width 0.1)
				(type default)
			)
			(layer "B.Fab")
		)
		(pad "1" smd circle
			(at 0.40005 0 270)
			(size 0 0)
			(layers "B.Cu" "B.Mask" "B.Paste")
			(net "PVDDCR_CPU0_P1_VOS1")
		)
		(pad "2" smd circle
			(at -0.40005 0 270)
			(size 0 0)
			(layers "B.Cu" "B.Mask" "B.Paste")
			(net "PVDDCR_CPU0_P1")
		)
	)
	(footprint ""
		(layer "B.Cu")
		(at 161.09188 -15.35811 90)
		(property "Reference" "R4509"
			(at 0 0 90)
			(layer "B.SilkS")
			(hide yes)
			(effects
				(font
					(size 1.27 1.27)
				)
				(justify mirror)
			)
		)
		(property "Value" ""
			(at 0 0 90)
			(layer "B.Fab")
			(effects
				(font
					(size 1.27 1.27)
				)
				(justify mirror)
			)
		)
		(duplicate_pad_numbers_are_jumpers no)
		(fp_line
			(start 0.7874 -0.4064)
			(end -0.7874 -0.4064)
			(stroke
				(width 0.1524)
				(type default)
			)
			(layer "B.SilkS")
		)
		(fp_line
			(start -0.7874 -0.4064)
			(end -0.7874 0.4064)
			(stroke
				(width 0.1524)
				(type default)
			)
			(layer "B.SilkS")
		)
		(fp_line
			(start 0.7874 0.4064)
			(end 0.7874 -0.4064)
			(stroke
				(width 0.1524)
				(type default)
			)
			(layer "B.SilkS")
		)
		(fp_line
			(start -0.7874 0.4064)
			(end 0.7874 0.4064)
			(stroke
				(width 0.1524)
				(type default)
			)
			(layer "B.SilkS")
		)
		(fp_line
			(start 0.67945 -0.305054)
			(end 0.12065 -0.305054)
			(stroke
				(width 0.1)
				(type default)
			)
			(layer "B.Fab")
		)
		(fp_line
			(start 0.12065 -0.305054)
			(end 0.12065 -0.2794)
			(stroke
				(width 0.1)
				(type default)
			)
			(layer "B.Fab")
		)
		(fp_line
			(start -0.12065 -0.3048)
			(end -0.67945 -0.3048)
			(stroke
				(width 0.1)
				(type default)
			)
			(layer "B.Fab")
		)
		(fp_line
			(start -0.67945 -0.3048)
			(end -0.67945 0.3048)
			(stroke
				(width 0.1)
				(type default)
			)
			(layer "B.Fab")
		)
		(fp_line
			(start 0.12065 -0.2794)
			(end -0.12065 -0.2794)
			(stroke
				(width 0.1)
				(type default)
			)
			(layer "B.Fab")
		)
		(fp_line
			(start -0.12065 -0.2794)
			(end -0.12065 -0.3048)
			(stroke
				(width 0.1)
				(type default)
			)
			(layer "B.Fab")
		)
		(fp_line
			(start 0.12065 0.2794)
			(end 0.12065 0.3048)
			(stroke
				(width 0.1)
				(type default)
			)
			(layer "B.Fab")
		)
		(fp_line
			(start -0.120396 0.2794)
			(end 0.12065 0.2794)
			(stroke
				(width 0.1)
				(type default)
			)
			(layer "B.Fab")
		)
		(fp_line
			(start 0.67945 0.3048)
			(end 0.67945 -0.305054)
			(stroke
				(width 0.1)
				(type default)
			)
			(layer "B.Fab")
		)
		(fp_line
			(start 0.12065 0.3048)
			(end 0.67945 0.3048)
			(stroke
				(width 0.1)
				(type default)
			)
			(layer "B.Fab")
		)
		(fp_line
			(start -0.120396 0.3048)
			(end -0.120396 0.2794)
			(stroke
				(width 0.1)
				(type default)
			)
			(layer "B.Fab")
		)
		(fp_line
			(start -0.67945 0.3048)
			(end -0.120396 0.3048)
			(stroke
				(width 0.1)
				(type default)
			)
			(layer "B.Fab")
		)
		(pad "1" smd circle
			(at 0.40005 0 270)
			(size 0 0)
			(layers "B.Cu" "B.Mask" "B.Paste")
			(net "SMB_1_PLD_3V3AUX_SDA")
		)
		(pad "2" smd circle
			(at -0.40005 0 270)
			(size 0 0)
			(layers "B.Cu" "B.Mask" "B.Paste")
			(net "SMB_1_PLD_3V3AUX_SDA_R3")
		)
	)
	(footprint ""
		(layer "B.Cu")
		(at 71.809864 -11.26871 -90)
		(property "Reference" "R3162"
			(at 0 0 90)
			(layer "B.SilkS")
			(hide yes)
			(effects
				(font
					(size 1.27 1.27)
				)
				(justify mirror)
			)
		)
		(property "Value" ""
			(at 0 0 90)
			(layer "B.Fab")
			(effects
				(font
					(size 1.27 1.27)
				)
				(justify mirror)
			)
		)
		(duplicate_pad_numbers_are_jumpers no)
		(fp_line
			(start -0.7874 0.4064)
			(end 0.7874 0.4064)
			(stroke
				(width 0.1524)
				(type default)
			)
			(layer "B.SilkS")
		)
		(fp_line
			(start 0.7874 0.4064)
			(end 0.7874 -0.4064)
			(stroke
				(width 0.1524)
				(type default)
			)
			(layer "B.SilkS")
		)
		(fp_line
			(start -0.7874 -0.4064)
			(end -0.7874 0.4064)
			(stroke
				(width 0.1524)
				(type default)
			)
			(layer "B.SilkS")
		)
		(fp_line
			(start 0.7874 -0.4064)
			(end -0.7874 -0.4064)
			(stroke
				(width 0.1524)
				(type default)
			)
			(layer "B.SilkS")
		)
		(fp_line
			(start -0.67945 0.3048)
			(end -0.120396 0.3048)
			(stroke
				(width 0.1)
				(type default)
			)
			(layer "B.Fab")
		)
		(fp_line
			(start -0.120396 0.3048)
			(end -0.120396 0.2794)
			(stroke
				(width 0.1)
				(type default)
			)
			(layer "B.Fab")
		)
		(fp_line
			(start 0.12065 0.3048)
			(end 0.67945 0.3048)
			(stroke
				(width 0.1)
				(type default)
			)
			(layer "B.Fab")
		)
		(fp_line
			(start 0.67945 0.3048)
			(end 0.67945 -0.305054)
			(stroke
				(width 0.1)
				(type default)
			)
			(layer "B.Fab")
		)
		(fp_line
			(start -0.120396 0.2794)
			(end 0.12065 0.2794)
			(stroke
				(width 0.1)
				(type default)
			)
			(layer "B.Fab")
		)
		(fp_line
			(start 0.12065 0.2794)
			(end 0.12065 0.3048)
			(stroke
				(width 0.1)
				(type default)
			)
			(layer "B.Fab")
		)
		(fp_line
			(start -0.12065 -0.2794)
			(end -0.12065 -0.3048)
			(stroke
				(width 0.1)
				(type default)
			)
			(layer "B.Fab")
		)
		(fp_line
			(start 0.12065 -0.2794)
			(end -0.12065 -0.2794)
			(stroke
				(width 0.1)
				(type default)
			)
			(layer "B.Fab")
		)
		(fp_line
			(start -0.67945 -0.3048)
			(end -0.67945 0.3048)
			(stroke
				(width 0.1)
				(type default)
			)
			(layer "B.Fab")
		)
		(fp_line
			(start -0.12065 -0.3048)
			(end -0.67945 -0.3048)
			(stroke
				(width 0.1)
				(type default)
			)
			(layer "B.Fab")
		)
		(fp_line
			(start 0.12065 -0.305054)
			(end 0.12065 -0.2794)
			(stroke
				(width 0.1)
				(type default)
			)
			(layer "B.Fab")
		)
		(fp_line
			(start 0.67945 -0.305054)
			(end 0.12065 -0.305054)
			(stroke
				(width 0.1)
				(type default)
			)
			(layer "B.Fab")
		)
		(pad "1" smd circle
			(at 0.40005 0 90)
			(size 0 0)
			(layers "B.Cu" "B.Mask" "B.Paste")
			(net "P3V3_OCP_V3_2")
		)
		(pad "2" smd circle
			(at -0.40005 0 90)
			(size 0 0)
			(layers "B.Cu" "B.Mask" "B.Paste")
			(net "OCP_V3_2_ID0")
		)
	)
	(footprint ""
		(layer "B.Cu")
		(at 194.945 -97.119948 90)
		(property "Reference" "R6062"
			(at 0 0 90)
			(layer "B.SilkS")
			(hide yes)
			(effects
				(font
					(size 1.27 1.27)
				)
				(justify mirror)
			)
		)
		(property "Value" ""
			(at 0 0 90)
			(layer "B.Fab")
			(effects
				(font
					(size 1.27 1.27)
				)
				(justify mirror)
			)
		)
		(duplicate_pad_numbers_are_jumpers no)
		(fp_line
			(start 0.7874 -0.4064)
			(end -0.7874 -0.4064)
			(stroke
				(width 0.1524)
				(type default)
			)
			(layer "B.SilkS")
		)
		(fp_line
			(start -0.7874 -0.4064)
			(end -0.7874 0.4064)
			(stroke
				(width 0.1524)
				(type default)
			)
			(layer "B.SilkS")
		)
		(fp_line
			(start 0.7874 0.4064)
			(end 0.7874 -0.4064)
			(stroke
				(width 0.1524)
				(type default)
			)
			(layer "B.SilkS")
		)
		(fp_line
			(start -0.7874 0.4064)
			(end 0.7874 0.4064)
			(stroke
				(width 0.1524)
				(type default)
			)
			(layer "B.SilkS")
		)
		(fp_line
			(start 0.67945 -0.305054)
			(end 0.12065 -0.305054)
			(stroke
				(width 0.1)
				(type default)
			)
			(layer "B.Fab")
		)
		(fp_line
			(start 0.12065 -0.305054)
			(end 0.12065 -0.2794)
			(stroke
				(width 0.1)
				(type default)
			)
			(layer "B.Fab")
		)
		(fp_line
			(start -0.12065 -0.3048)
			(end -0.67945 -0.3048)
			(stroke
				(width 0.1)
				(type default)
			)
			(layer "B.Fab")
		)
		(fp_line
			(start -0.67945 -0.3048)
			(end -0.67945 0.3048)
			(stroke
				(width 0.1)
				(type default)
			)
			(layer "B.Fab")
		)
		(fp_line
			(start 0.12065 -0.2794)
			(end -0.12065 -0.2794)
			(stroke
				(width 0.1)
				(type default)
			)
			(layer "B.Fab")
		)
		(fp_line
			(start -0.12065 -0.2794)
			(end -0.12065 -0.3048)
			(stroke
				(width 0.1)
				(type default)
			)
			(layer "B.Fab")
		)
		(fp_line
			(start 0.12065 0.2794)
			(end 0.12065 0.3048)
			(stroke
				(width 0.1)
				(type default)
			)
			(layer "B.Fab")
		)
		(fp_line
			(start -0.120396 0.2794)
			(end 0.12065 0.2794)
			(stroke
				(width 0.1)
				(type default)
			)
			(layer "B.Fab")
		)
		(fp_line
			(start 0.67945 0.3048)
			(end 0.67945 -0.305054)
			(stroke
				(width 0.1)
				(type default)
			)
			(layer "B.Fab")
		)
		(fp_line
			(start 0.12065 0.3048)
			(end 0.67945 0.3048)
			(stroke
				(width 0.1)
				(type default)
			)
			(layer "B.Fab")
		)
		(fp_line
			(start -0.120396 0.3048)
			(end -0.120396 0.2794)
			(stroke
				(width 0.1)
				(type default)
			)
			(layer "B.Fab")
		)
		(fp_line
			(start -0.67945 0.3048)
			(end -0.120396 0.3048)
			(stroke
				(width 0.1)
				(type default)
			)
			(layer "B.Fab")
		)
		(pad "1" smd circle
			(at 0.40005 0 270)
			(size 0 0)
			(layers "B.Cu" "B.Mask" "B.Paste")
			(net "P3V3_OCP_V3_2_EN_R")
		)
		(pad "2" smd circle
			(at -0.40005 0 270)
			(size 0 0)
			(layers "B.Cu" "B.Mask" "B.Paste")
			(net "P3V3_AUX")
		)
	)
	(footprint ""
		(layer "B.Cu")
		(at 413.806132 -395.148562 90)
		(property "Reference" "C676"
			(at 0 0 90)
			(layer "B.SilkS")
			(hide yes)
			(effects
				(font
					(size 1.27 1.27)
				)
				(justify mirror)
			)
		)
		(property "Value" ""
			(at 0 0 90)
			(layer "B.Fab")
			(effects
				(font
					(size 1.27 1.27)
				)
				(justify mirror)
			)
		)
		(duplicate_pad_numbers_are_jumpers no)
		(fp_line
			(start 0.299974 -0.150114)
			(end -0.299974 -0.150114)
			(stroke
				(width 0.1)
				(type default)
			)
			(layer "B.Fab")
		)
		(fp_line
			(start -0.299974 -0.150114)
			(end -0.299974 0.150114)
			(stroke
				(width 0.1)
				(type default)
			)
			(layer "B.Fab")
		)
		(fp_line
			(start 0.299974 0.150114)
			(end 0.299974 -0.150114)
			(stroke
				(width 0.1)
				(type default)
			)
			(layer "B.Fab")
		)
		(fp_line
			(start -0.299974 0.150114)
			(end 0.299974 0.150114)
			(stroke
				(width 0.1)
				(type default)
			)
			(layer "B.Fab")
		)
		(pad "1" smd rect
			(at 0.2667 0 270)
			(size 0.3048 0.381)
			(layers "B.Cu" "B.Mask" "B.Paste")
			(net "P1V8_CPU0_RT2_1A_1D")
		)
		(pad "2" smd rect
			(at -0.2667 0 270)
			(size 0.3048 0.381)
			(layers "B.Cu" "B.Mask" "B.Paste")
			(net "GND")
		)
	)
	(footprint ""
		(layer "B.Cu")
		(at 183.946292 -351.21342 90)
		(property "Reference" "PC513_1"
			(at 0 0 90)
			(layer "B.SilkS")
			(hide yes)
			(effects
				(font
					(size 1.27 1.27)
				)
				(justify mirror)
			)
		)
		(property "Value" ""
			(at 0 0 90)
			(layer "B.Fab")
			(effects
				(font
					(size 1.27 1.27)
				)
				(justify mirror)
			)
		)
		(duplicate_pad_numbers_are_jumpers no)
		(fp_line
			(start 1.524 -0.762)
			(end -1.524 -0.762)
			(stroke
				(width 0.1524)
				(type default)
			)
			(layer "B.SilkS")
		)
		(fp_line
			(start -1.524 -0.762)
			(end -1.524 0.762)
			(stroke
				(width 0.1524)
				(type default)
			)
			(layer "B.SilkS")
		)
		(fp_line
			(start 1.524 0.762)
			(end 1.524 -0.762)
			(stroke
				(width 0.1524)
				(type default)
			)
			(layer "B.SilkS")
		)
		(fp_line
			(start -1.524 0.762)
			(end 1.524 0.762)
			(stroke
				(width 0.1524)
				(type default)
			)
			(layer "B.SilkS")
		)
		(fp_line
			(start 1.1049 -0.724916)
			(end 1.1049 0.724916)
			(stroke
				(width 0.1)
				(type default)
			)
			(layer "B.Fab")
		)
		(fp_line
			(start -1.1049 -0.724916)
			(end 1.1049 -0.724916)
			(stroke
				(width 0.1)
				(type default)
			)
			(layer "B.Fab")
		)
		(fp_line
			(start 1.1049 0.724916)
			(end -1.1049 0.724916)
			(stroke
				(width 0.1)
				(type default)
			)
			(layer "B.Fab")
		)
		(fp_line
			(start -1.1049 0.724916)
			(end -1.1049 -0.724916)
			(stroke
				(width 0.1)
				(type default)
			)
			(layer "B.Fab")
		)
		(pad "1" smd rect
			(at 0.889 0 90)
			(size 1.016 1.27)
			(layers "B.Cu" "B.Mask" "B.Paste")
			(net "SW_P12V_AUX_PVDD11_S3_P1_FLT")
		)
		(pad "2" smd rect
			(at -0.889 0 90)
			(size 1.016 1.27)
			(layers "B.Cu" "B.Mask" "B.Paste")
			(net "GND")
		)
	)
	(footprint ""
		(layer "B.Cu")
		(at 428.98695 -37.023548 180)
		(property "Reference" "R6107"
			(at 0 0 0)
			(layer "B.SilkS")
			(hide yes)
			(effects
				(font
					(size 1.27 1.27)
				)
				(justify mirror)
			)
		)
		(property "Value" ""
			(at 0 0 0)
			(layer "B.Fab")
			(effects
				(font
					(size 1.27 1.27)
				)
				(justify mirror)
			)
		)
		(duplicate_pad_numbers_are_jumpers no)
		(fp_line
			(start 0.7874 0.4064)
			(end 0.7874 -0.4064)
			(stroke
				(width 0.1524)
				(type default)
			)
			(layer "B.SilkS")
		)
		(fp_line
			(start 0.7874 -0.4064)
			(end -0.7874 -0.4064)
			(stroke
				(width 0.1524)
				(type default)
			)
			(layer "B.SilkS")
		)
		(fp_line
			(start -0.7874 0.4064)
			(end 0.7874 0.4064)
			(stroke
				(width 0.1524)
				(type default)
			)
			(layer "B.SilkS")
		)
		(fp_line
			(start -0.7874 -0.4064)
			(end -0.7874 0.4064)
			(stroke
				(width 0.1524)
				(type default)
			)
			(layer "B.SilkS")
		)
		(fp_line
			(start 0.67945 0.3048)
			(end 0.67945 -0.305054)
			(stroke
				(width 0.1)
				(type default)
			)
			(layer "B.Fab")
		)
		(fp_line
			(start 0.67945 -0.305054)
			(end 0.12065 -0.305054)
			(stroke
				(width 0.1)
				(type default)
			)
			(layer "B.Fab")
		)
		(fp_line
			(start 0.12065 0.3048)
			(end 0.67945 0.3048)
			(stroke
				(width 0.1)
				(type default)
			)
			(layer "B.Fab")
		)
		(fp_line
			(start 0.12065 0.2794)
			(end 0.12065 0.3048)
			(stroke
				(width 0.1)
				(type default)
			)
			(layer "B.Fab")
		)
		(fp_line
			(start 0.12065 -0.2794)
			(end -0.12065 -0.2794)
			(stroke
				(width 0.1)
				(type default)
			)
			(layer "B.Fab")
		)
		(fp_line
			(start 0.12065 -0.305054)
			(end 0.12065 -0.2794)
			(stroke
				(width 0.1)
				(type default)
			)
			(layer "B.Fab")
		)
		(fp_line
			(start -0.120396 0.3048)
			(end -0.120396 0.2794)
			(stroke
				(width 0.1)
				(type default)
			)
			(layer "B.Fab")
		)
		(fp_line
			(start -0.120396 0.2794)
			(end 0.12065 0.2794)
			(stroke
				(width 0.1)
				(type default)
			)
			(layer "B.Fab")
		)
		(fp_line
			(start -0.12065 -0.2794)
			(end -0.12065 -0.3048)
			(stroke
				(width 0.1)
				(type default)
			)
			(layer "B.Fab")
		)
		(fp_line
			(start -0.12065 -0.3048)
			(end -0.67945 -0.3048)
			(stroke
				(width 0.1)
				(type default)
			)
			(layer "B.Fab")
		)
		(fp_line
			(start -0.67945 0.3048)
			(end -0.120396 0.3048)
			(stroke
				(width 0.1)
				(type default)
			)
			(layer "B.Fab")
		)
		(fp_line
			(start -0.67945 -0.3048)
			(end -0.67945 0.3048)
			(stroke
				(width 0.1)
				(type default)
			)
			(layer "B.Fab")
		)
		(pad "1" smd circle
			(at 0.40005 0)
			(size 0 0)
			(layers "B.Cu" "B.Mask" "B.Paste")
			(net "PVDD18_S5_P0")
		)
		(pad "2" smd circle
			(at -0.40005 0)
			(size 0 0)
			(layers "B.Cu" "B.Mask" "B.Paste")
			(net "BIOS_DEBUG_MODE")
		)
	)
	(footprint ""
		(layer "B.Cu")
		(at 335.918556 -398.942052 90)
		(property "Reference" "C645"
			(at 0 0 90)
			(layer "B.SilkS")
			(hide yes)
			(effects
				(font
					(size 1.27 1.27)
				)
				(justify mirror)
			)
		)
		(property "Value" ""
			(at 0 0 90)
			(layer "B.Fab")
			(effects
				(font
					(size 1.27 1.27)
				)
				(justify mirror)
			)
		)
		(duplicate_pad_numbers_are_jumpers no)
		(fp_line
			(start 0.7874 -0.4064)
			(end -0.7874 -0.4064)
			(stroke
				(width 0.1524)
				(type default)
			)
			(layer "B.SilkS")
		)
		(fp_line
			(start -0.7874 -0.4064)
			(end -0.7874 0.4064)
			(stroke
				(width 0.1524)
				(type default)
			)
			(layer "B.SilkS")
		)
		(fp_line
			(start 0.7874 0.4064)
			(end 0.7874 -0.4064)
			(stroke
				(width 0.1524)
				(type default)
			)
			(layer "B.SilkS")
		)
		(fp_line
			(start -0.7874 0.4064)
			(end 0.7874 0.4064)
			(stroke
				(width 0.1524)
				(type default)
			)
			(layer "B.SilkS")
		)
		(fp_line
			(start 0.67945 -0.305054)
			(end 0.12065 -0.305054)
			(stroke
				(width 0.1)
				(type default)
			)
			(layer "B.Fab")
		)
		(fp_line
			(start 0.12065 -0.305054)
			(end 0.12065 -0.2794)
			(stroke
				(width 0.1)
				(type default)
			)
			(layer "B.Fab")
		)
		(fp_line
			(start -0.12065 -0.3048)
			(end -0.67945 -0.3048)
			(stroke
				(width 0.1)
				(type default)
			)
			(layer "B.Fab")
		)
		(fp_line
			(start -0.67945 -0.3048)
			(end -0.67945 0.3048)
			(stroke
				(width 0.1)
				(type default)
			)
			(layer "B.Fab")
		)
		(fp_line
			(start 0.12065 -0.2794)
			(end -0.12065 -0.2794)
			(stroke
				(width 0.1)
				(type default)
			)
			(layer "B.Fab")
		)
		(fp_line
			(start -0.12065 -0.2794)
			(end -0.12065 -0.3048)
			(stroke
				(width 0.1)
				(type default)
			)
			(layer "B.Fab")
		)
		(fp_line
			(start 0.12065 0.2794)
			(end 0.12065 0.3048)
			(stroke
				(width 0.1)
				(type default)
			)
			(layer "B.Fab")
		)
		(fp_line
			(start -0.120396 0.2794)
			(end 0.12065 0.2794)
			(stroke
				(width 0.1)
				(type default)
			)
			(layer "B.Fab")
		)
		(fp_line
			(start 0.67945 0.3048)
			(end 0.67945 -0.305054)
			(stroke
				(width 0.1)
				(type default)
			)
			(layer "B.Fab")
		)
		(fp_line
			(start 0.12065 0.3048)
			(end 0.67945 0.3048)
			(stroke
				(width 0.1)
				(type default)
			)
			(layer "B.Fab")
		)
		(fp_line
			(start -0.120396 0.3048)
			(end -0.120396 0.2794)
			(stroke
				(width 0.1)
				(type default)
			)
			(layer "B.Fab")
		)
		(fp_line
			(start -0.67945 0.3048)
			(end -0.120396 0.3048)
			(stroke
				(width 0.1)
				(type default)
			)
			(layer "B.Fab")
		)
		(pad "1" smd circle
			(at 0.40005 0 270)
			(size 0 0)
			(layers "B.Cu" "B.Mask" "B.Paste")
			(net "P0V9_CPU0_RT1_2A")
		)
		(pad "2" smd circle
			(at -0.40005 0 270)
			(size 0 0)
			(layers "B.Cu" "B.Mask" "B.Paste")
			(net "GND")
		)
	)
	(footprint ""
		(layer "B.Cu")
		(at 299.265594 -395.10716 180)
		(property "Reference" "R981"
			(at 0 0 0)
			(layer "B.SilkS")
			(hide yes)
			(effects
				(font
					(size 1.27 1.27)
				)
				(justify mirror)
			)
		)
		(property "Value" ""
			(at 0 0 0)
			(layer "B.Fab")
			(effects
				(font
					(size 1.27 1.27)
				)
				(justify mirror)
			)
		)
		(duplicate_pad_numbers_are_jumpers no)
		(fp_line
			(start 0.32512 0.175006)
			(end 0.32512 -0.175006)
			(stroke
				(width 0.1)
				(type default)
			)
			(layer "B.Fab")
		)
		(fp_line
			(start 0.32512 -0.175006)
			(end -0.32512 -0.175006)
			(stroke
				(width 0.1)
				(type default)
			)
			(layer "B.Fab")
		)
		(fp_line
			(start -0.32512 0.175006)
			(end 0.32512 0.175006)
			(stroke
				(width 0.1)
				(type default)
			)
			(layer "B.Fab")
		)
		(fp_line
			(start -0.32512 -0.175006)
			(end -0.32512 0.175006)
			(stroke
				(width 0.1)
				(type default)
			)
			(layer "B.Fab")
		)
		(pad "1" smd rect
			(at 0.2667 0)
			(size 0.3048 0.381)
			(layers "B.Cu" "B.Mask" "B.Paste")
			(net "P1V8_CPU0_RT_1D")
		)
		(pad "2" smd rect
			(at -0.2667 0 180)
			(size 0.3048 0.381)
			(layers "B.Cu" "B.Mask" "B.Paste")
			(net "TEST0_RT_CPU0_P0")
		)
	)
	(footprint ""
		(layer "B.Cu")
		(at 369.392454 -264.35431)
		(property "Reference" "C2630"
			(at 0 0 0)
			(layer "B.SilkS")
			(hide yes)
			(effects
				(font
					(size 1.27 1.27)
				)
				(justify mirror)
			)
		)
		(property "Value" ""
			(at 0 0 0)
			(layer "B.Fab")
			(effects
				(font
					(size 1.27 1.27)
				)
				(justify mirror)
			)
		)
		(duplicate_pad_numbers_are_jumpers no)
		(fp_line
			(start -0.7874 -0.4064)
			(end -0.7874 0.4064)
			(stroke
				(width 0.1524)
				(type default)
			)
			(layer "B.SilkS")
		)
		(fp_line
			(start -0.7874 0.4064)
			(end 0.7874 0.4064)
			(stroke
				(width 0.1524)
				(type default)
			)
			(layer "B.SilkS")
		)
		(fp_line
			(start 0.7874 -0.4064)
			(end -0.7874 -0.4064)
			(stroke
				(width 0.1524)
				(type default)
			)
			(layer "B.SilkS")
		)
		(fp_line
			(start 0.7874 0.4064)
			(end 0.7874 -0.4064)
			(stroke
				(width 0.1524)
				(type default)
			)
			(layer "B.SilkS")
		)
		(fp_line
			(start -0.67945 -0.3048)
			(end -0.67945 0.3048)
			(stroke
				(width 0.1)
				(type default)
			)
			(layer "B.Fab")
		)
		(fp_line
			(start -0.67945 0.3048)
			(end -0.120396 0.3048)
			(stroke
				(width 0.1)
				(type default)
			)
			(layer "B.Fab")
		)
		(fp_line
			(start -0.12065 -0.3048)
			(end -0.67945 -0.3048)
			(stroke
				(width 0.1)
				(type default)
			)
			(layer "B.Fab")
		)
		(fp_line
			(start -0.12065 -0.2794)
			(end -0.12065 -0.3048)
			(stroke
				(width 0.1)
				(type default)
			)
			(layer "B.Fab")
		)
		(fp_line
			(start -0.120396 0.2794)
			(end 0.12065 0.2794)
			(stroke
				(width 0.1)
				(type default)
			)
			(layer "B.Fab")
		)
		(fp_line
			(start -0.120396 0.3048)
			(end -0.120396 0.2794)
			(stroke
				(width 0.1)
				(type default)
			)
			(layer "B.Fab")
		)
		(fp_line
			(start 0.12065 -0.305054)
			(end 0.12065 -0.2794)
			(stroke
				(width 0.1)
				(type default)
			)
			(layer "B.Fab")
		)
		(fp_line
			(start 0.12065 -0.2794)
			(end -0.12065 -0.2794)
			(stroke
				(width 0.1)
				(type default)
			)
			(layer "B.Fab")
		)
		(fp_line
			(start 0.12065 0.2794)
			(end 0.12065 0.3048)
			(stroke
				(width 0.1)
				(type default)
			)
			(layer "B.Fab")
		)
		(fp_line
			(start 0.12065 0.3048)
			(end 0.67945 0.3048)
			(stroke
				(width 0.1)
				(type default)
			)
			(layer "B.Fab")
		)
		(fp_line
			(start 0.67945 -0.305054)
			(end 0.12065 -0.305054)
			(stroke
				(width 0.1)
				(type default)
			)
			(layer "B.Fab")
		)
		(fp_line
			(start 0.67945 0.3048)
			(end 0.67945 -0.305054)
			(stroke
				(width 0.1)
				(type default)
			)
			(layer "B.Fab")
		)
		(pad "1" smd circle
			(at 0.40005 0 180)
			(size 0 0)
			(layers "B.Cu" "B.Mask" "B.Paste")
			(net "PVDD11_S3_P0")
		)
		(pad "2" smd circle
			(at -0.40005 0 180)
			(size 0 0)
			(layers "B.Cu" "B.Mask" "B.Paste")
			(net "GND")
		)
	)
	(footprint ""
		(layer "B.Cu")
		(at 36.040568 -194.9196 180)
		(property "Reference" "R1583"
			(at 0 0 0)
			(layer "B.SilkS")
			(hide yes)
			(effects
				(font
					(size 1.27 1.27)
				)
				(justify mirror)
			)
		)
		(property "Value" ""
			(at 0 0 0)
			(layer "B.Fab")
			(effects
				(font
					(size 1.27 1.27)
				)
				(justify mirror)
			)
		)
		(duplicate_pad_numbers_are_jumpers no)
		(fp_line
			(start 0.7874 0.4064)
			(end 0.7874 -0.4064)
			(stroke
				(width 0.1524)
				(type default)
			)
			(layer "B.SilkS")
		)
		(fp_line
			(start 0.7874 -0.4064)
			(end -0.7874 -0.4064)
			(stroke
				(width 0.1524)
				(type default)
			)
			(layer "B.SilkS")
		)
		(fp_line
			(start -0.7874 0.4064)
			(end 0.7874 0.4064)
			(stroke
				(width 0.1524)
				(type default)
			)
			(layer "B.SilkS")
		)
		(fp_line
			(start -0.7874 -0.4064)
			(end -0.7874 0.4064)
			(stroke
				(width 0.1524)
				(type default)
			)
			(layer "B.SilkS")
		)
		(fp_line
			(start 0.67945 0.3048)
			(end 0.67945 -0.305054)
			(stroke
				(width 0.1)
				(type default)
			)
			(layer "B.Fab")
		)
		(fp_line
			(start 0.67945 -0.305054)
			(end 0.12065 -0.305054)
			(stroke
				(width 0.1)
				(type default)
			)
			(layer "B.Fab")
		)
		(fp_line
			(start 0.12065 0.3048)
			(end 0.67945 0.3048)
			(stroke
				(width 0.1)
				(type default)
			)
			(layer "B.Fab")
		)
		(fp_line
			(start 0.12065 0.2794)
			(end 0.12065 0.3048)
			(stroke
				(width 0.1)
				(type default)
			)
			(layer "B.Fab")
		)
		(fp_line
			(start 0.12065 -0.2794)
			(end -0.12065 -0.2794)
			(stroke
				(width 0.1)
				(type default)
			)
			(layer "B.Fab")
		)
		(fp_line
			(start 0.12065 -0.305054)
			(end 0.12065 -0.2794)
			(stroke
				(width 0.1)
				(type default)
			)
			(layer "B.Fab")
		)
		(fp_line
			(start -0.120396 0.3048)
			(end -0.120396 0.2794)
			(stroke
				(width 0.1)
				(type default)
			)
			(layer "B.Fab")
		)
		(fp_line
			(start -0.120396 0.2794)
			(end 0.12065 0.2794)
			(stroke
				(width 0.1)
				(type default)
			)
			(layer "B.Fab")
		)
		(fp_line
			(start -0.12065 -0.2794)
			(end -0.12065 -0.3048)
			(stroke
				(width 0.1)
				(type default)
			)
			(layer "B.Fab")
		)
		(fp_line
			(start -0.12065 -0.3048)
			(end -0.67945 -0.3048)
			(stroke
				(width 0.1)
				(type default)
			)
			(layer "B.Fab")
		)
		(fp_line
			(start -0.67945 0.3048)
			(end -0.120396 0.3048)
			(stroke
				(width 0.1)
				(type default)
			)
			(layer "B.Fab")
		)
		(fp_line
			(start -0.67945 -0.3048)
			(end -0.67945 0.3048)
			(stroke
				(width 0.1)
				(type default)
			)
			(layer "B.Fab")
		)
		(pad "1" smd circle
			(at 0.40005 0)
			(size 0 0)
			(layers "B.Cu" "B.Mask" "B.Paste")
			(net "I3C_SPD_DDRAF_CPU1_SCL")
		)
		(pad "2" smd circle
			(at -0.40005 0)
			(size 0 0)
			(layers "B.Cu" "B.Mask" "B.Paste")
			(net "I3C_SPD_DDRD_CPU1_SCL")
		)
	)
	(footprint ""
		(layer "B.Cu")
		(at 175.133 -126.238 180)
		(property "Reference" "R6852"
			(at 0 0 0)
			(layer "B.SilkS")
			(hide yes)
			(effects
				(font
					(size 1.27 1.27)
				)
				(justify mirror)
			)
		)
		(property "Value" ""
			(at 0 0 0)
			(layer "B.Fab")
			(effects
				(font
					(size 1.27 1.27)
				)
				(justify mirror)
			)
		)
		(duplicate_pad_numbers_are_jumpers no)
		(fp_line
			(start 0.7874 0.4064)
			(end 0.7874 -0.4064)
			(stroke
				(width 0.1524)
				(type default)
			)
			(layer "B.SilkS")
		)
		(fp_line
			(start 0.7874 -0.4064)
			(end -0.7874 -0.4064)
			(stroke
				(width 0.1524)
				(type default)
			)
			(layer "B.SilkS")
		)
		(fp_line
			(start -0.7874 0.4064)
			(end 0.7874 0.4064)
			(stroke
				(width 0.1524)
				(type default)
			)
			(layer "B.SilkS")
		)
		(fp_line
			(start -0.7874 -0.4064)
			(end -0.7874 0.4064)
			(stroke
				(width 0.1524)
				(type default)
			)
			(layer "B.SilkS")
		)
		(fp_line
			(start 0.67945 0.3048)
			(end 0.67945 -0.305054)
			(stroke
				(width 0.1)
				(type default)
			)
			(layer "B.Fab")
		)
		(fp_line
			(start 0.67945 -0.305054)
			(end 0.12065 -0.305054)
			(stroke
				(width 0.1)
				(type default)
			)
			(layer "B.Fab")
		)
		(fp_line
			(start 0.12065 0.3048)
			(end 0.67945 0.3048)
			(stroke
				(width 0.1)
				(type default)
			)
			(layer "B.Fab")
		)
		(fp_line
			(start 0.12065 0.2794)
			(end 0.12065 0.3048)
			(stroke
				(width 0.1)
				(type default)
			)
			(layer "B.Fab")
		)
		(fp_line
			(start 0.12065 -0.2794)
			(end -0.12065 -0.2794)
			(stroke
				(width 0.1)
				(type default)
			)
			(layer "B.Fab")
		)
		(fp_line
			(start 0.12065 -0.305054)
			(end 0.12065 -0.2794)
			(stroke
				(width 0.1)
				(type default)
			)
			(layer "B.Fab")
		)
		(fp_line
			(start -0.120396 0.3048)
			(end -0.120396 0.2794)
			(stroke
				(width 0.1)
				(type default)
			)
			(layer "B.Fab")
		)
		(fp_line
			(start -0.120396 0.2794)
			(end 0.12065 0.2794)
			(stroke
				(width 0.1)
				(type default)
			)
			(layer "B.Fab")
		)
		(fp_line
			(start -0.12065 -0.2794)
			(end -0.12065 -0.3048)
			(stroke
				(width 0.1)
				(type default)
			)
			(layer "B.Fab")
		)
		(fp_line
			(start -0.12065 -0.3048)
			(end -0.67945 -0.3048)
			(stroke
				(width 0.1)
				(type default)
			)
			(layer "B.Fab")
		)
		(fp_line
			(start -0.67945 0.3048)
			(end -0.120396 0.3048)
			(stroke
				(width 0.1)
				(type default)
			)
			(layer "B.Fab")
		)
		(fp_line
			(start -0.67945 -0.3048)
			(end -0.67945 0.3048)
			(stroke
				(width 0.1)
				(type default)
			)
			(layer "B.Fab")
		)
		(pad "1" smd circle
			(at 0.40005 0)
			(size 0 0)
			(layers "B.Cu" "B.Mask" "B.Paste")
			(net "PWRGD_P0V9_RETIMER_CPU0")
		)
		(pad "2" smd circle
			(at -0.40005 0)
			(size 0 0)
			(layers "B.Cu" "B.Mask" "B.Paste")
			(net "PWRGD_P0V9_RETIMER_CPU0_R2")
		)
	)
	(footprint ""
		(layer "B.Cu")
		(at 14.407388 -111.004604 90)
		(property "Reference" "C5229"
			(at 0 0 90)
			(layer "B.SilkS")
			(hide yes)
			(effects
				(font
					(size 1.27 1.27)
				)
				(justify mirror)
			)
		)
		(property "Value" ""
			(at 0 0 90)
			(layer "B.Fab")
			(effects
				(font
					(size 1.27 1.27)
				)
				(justify mirror)
			)
		)
		(duplicate_pad_numbers_are_jumpers no)
		(fp_line
			(start 0.7874 -0.4064)
			(end -0.7874 -0.4064)
			(stroke
				(width 0.1524)
				(type default)
			)
			(layer "B.SilkS")
		)
		(fp_line
			(start -0.7874 -0.4064)
			(end -0.7874 0.4064)
			(stroke
				(width 0.1524)
				(type default)
			)
			(layer "B.SilkS")
		)
		(fp_line
			(start 0.7874 0.4064)
			(end 0.7874 -0.4064)
			(stroke
				(width 0.1524)
				(type default)
			)
			(layer "B.SilkS")
		)
		(fp_line
			(start -0.7874 0.4064)
			(end 0.7874 0.4064)
			(stroke
				(width 0.1524)
				(type default)
			)
			(layer "B.SilkS")
		)
		(fp_line
			(start 0.67945 -0.305054)
			(end 0.12065 -0.305054)
			(stroke
				(width 0.1)
				(type default)
			)
			(layer "B.Fab")
		)
		(fp_line
			(start 0.12065 -0.305054)
			(end 0.12065 -0.2794)
			(stroke
				(width 0.1)
				(type default)
			)
			(layer "B.Fab")
		)
		(fp_line
			(start -0.12065 -0.3048)
			(end -0.67945 -0.3048)
			(stroke
				(width 0.1)
				(type default)
			)
			(layer "B.Fab")
		)
		(fp_line
			(start -0.67945 -0.3048)
			(end -0.67945 0.3048)
			(stroke
				(width 0.1)
				(type default)
			)
			(layer "B.Fab")
		)
		(fp_line
			(start 0.12065 -0.2794)
			(end -0.12065 -0.2794)
			(stroke
				(width 0.1)
				(type default)
			)
			(layer "B.Fab")
		)
		(fp_line
			(start -0.12065 -0.2794)
			(end -0.12065 -0.3048)
			(stroke
				(width 0.1)
				(type default)
			)
			(layer "B.Fab")
		)
		(fp_line
			(start 0.12065 0.2794)
			(end 0.12065 0.3048)
			(stroke
				(width 0.1)
				(type default)
			)
			(layer "B.Fab")
		)
		(fp_line
			(start -0.120396 0.2794)
			(end 0.12065 0.2794)
			(stroke
				(width 0.1)
				(type default)
			)
			(layer "B.Fab")
		)
		(fp_line
			(start 0.67945 0.3048)
			(end 0.67945 -0.305054)
			(stroke
				(width 0.1)
				(type default)
			)
			(layer "B.Fab")
		)
		(fp_line
			(start 0.12065 0.3048)
			(end 0.67945 0.3048)
			(stroke
				(width 0.1)
				(type default)
			)
			(layer "B.Fab")
		)
		(fp_line
			(start -0.120396 0.3048)
			(end -0.120396 0.2794)
			(stroke
				(width 0.1)
				(type default)
			)
			(layer "B.Fab")
		)
		(fp_line
			(start -0.67945 0.3048)
			(end -0.120396 0.3048)
			(stroke
				(width 0.1)
				(type default)
			)
			(layer "B.Fab")
		)
		(pad "1" smd circle
			(at 0.40005 0 270)
			(size 0 0)
			(layers "B.Cu" "B.Mask" "B.Paste")
			(net "P3V3_AUX")
		)
		(pad "2" smd circle
			(at -0.40005 0 270)
			(size 0 0)
			(layers "B.Cu" "B.Mask" "B.Paste")
			(net "GND")
		)
	)
	(footprint ""
		(layer "B.Cu")
		(at 180.0352 -106.71048 90)
		(property "Reference" "C352"
			(at 0 0 90)
			(layer "B.SilkS")
			(hide yes)
			(effects
				(font
					(size 1.27 1.27)
				)
				(justify mirror)
			)
		)
		(property "Value" ""
			(at 0 0 90)
			(layer "B.Fab")
			(effects
				(font
					(size 1.27 1.27)
				)
				(justify mirror)
			)
		)
		(duplicate_pad_numbers_are_jumpers no)
		(fp_line
			(start 0.7874 -0.4064)
			(end -0.7874 -0.4064)
			(stroke
				(width 0.1524)
				(type default)
			)
			(layer "B.SilkS")
		)
		(fp_line
			(start -0.7874 -0.4064)
			(end -0.7874 0.4064)
			(stroke
				(width 0.1524)
				(type default)
			)
			(layer "B.SilkS")
		)
		(fp_line
			(start 0.7874 0.4064)
			(end 0.7874 -0.4064)
			(stroke
				(width 0.1524)
				(type default)
			)
			(layer "B.SilkS")
		)
		(fp_line
			(start -0.7874 0.4064)
			(end 0.7874 0.4064)
			(stroke
				(width 0.1524)
				(type default)
			)
			(layer "B.SilkS")
		)
		(fp_line
			(start 0.67945 -0.305054)
			(end 0.12065 -0.305054)
			(stroke
				(width 0.1)
				(type default)
			)
			(layer "B.Fab")
		)
		(fp_line
			(start 0.12065 -0.305054)
			(end 0.12065 -0.2794)
			(stroke
				(width 0.1)
				(type default)
			)
			(layer "B.Fab")
		)
		(fp_line
			(start -0.12065 -0.3048)
			(end -0.67945 -0.3048)
			(stroke
				(width 0.1)
				(type default)
			)
			(layer "B.Fab")
		)
		(fp_line
			(start -0.67945 -0.3048)
			(end -0.67945 0.3048)
			(stroke
				(width 0.1)
				(type default)
			)
			(layer "B.Fab")
		)
		(fp_line
			(start 0.12065 -0.2794)
			(end -0.12065 -0.2794)
			(stroke
				(width 0.1)
				(type default)
			)
			(layer "B.Fab")
		)
		(fp_line
			(start -0.12065 -0.2794)
			(end -0.12065 -0.3048)
			(stroke
				(width 0.1)
				(type default)
			)
			(layer "B.Fab")
		)
		(fp_line
			(start 0.12065 0.2794)
			(end 0.12065 0.3048)
			(stroke
				(width 0.1)
				(type default)
			)
			(layer "B.Fab")
		)
		(fp_line
			(start -0.120396 0.2794)
			(end 0.12065 0.2794)
			(stroke
				(width 0.1)
				(type default)
			)
			(layer "B.Fab")
		)
		(fp_line
			(start 0.67945 0.3048)
			(end 0.67945 -0.305054)
			(stroke
				(width 0.1)
				(type default)
			)
			(layer "B.Fab")
		)
		(fp_line
			(start 0.12065 0.3048)
			(end 0.67945 0.3048)
			(stroke
				(width 0.1)
				(type default)
			)
			(layer "B.Fab")
		)
		(fp_line
			(start -0.120396 0.3048)
			(end -0.120396 0.2794)
			(stroke
				(width 0.1)
				(type default)
			)
			(layer "B.Fab")
		)
		(fp_line
			(start -0.67945 0.3048)
			(end -0.120396 0.3048)
			(stroke
				(width 0.1)
				(type default)
			)
			(layer "B.Fab")
		)
		(pad "1" smd circle
			(at 0.40005 0 270)
			(size 0 0)
			(layers "B.Cu" "B.Mask" "B.Paste")
			(net "P1V8_AUX")
		)
		(pad "2" smd circle
			(at -0.40005 0 270)
			(size 0 0)
			(layers "B.Cu" "B.Mask" "B.Paste")
			(net "GND")
		)
	)
	(footprint ""
		(layer "B.Cu")
		(at 18.01749 -400.953732)
		(property "Reference" "PC6819"
			(at 0 0 0)
			(layer "B.SilkS")
			(hide yes)
			(effects
				(font
					(size 1.27 1.27)
				)
				(justify mirror)
			)
		)
		(property "Value" ""
			(at 0 0 0)
			(layer "B.Fab")
			(effects
				(font
					(size 1.27 1.27)
				)
				(justify mirror)
			)
		)
		(duplicate_pad_numbers_are_jumpers no)
		(fp_line
			(start -1.524 -0.762)
			(end -1.524 0.762)
			(stroke
				(width 0.1524)
				(type default)
			)
			(layer "B.SilkS")
		)
		(fp_line
			(start -1.524 0.762)
			(end 1.524 0.762)
			(stroke
				(width 0.1524)
				(type default)
			)
			(layer "B.SilkS")
		)
		(fp_line
			(start 1.524 -0.762)
			(end -1.524 -0.762)
			(stroke
				(width 0.1524)
				(type default)
			)
			(layer "B.SilkS")
		)
		(fp_line
			(start 1.524 0.762)
			(end 1.524 -0.762)
			(stroke
				(width 0.1524)
				(type default)
			)
			(layer "B.SilkS")
		)
		(fp_line
			(start -1.1049 -0.724916)
			(end 1.1049 -0.724916)
			(stroke
				(width 0.1)
				(type default)
			)
			(layer "B.Fab")
		)
		(fp_line
			(start -1.1049 0.724916)
			(end -1.1049 -0.724916)
			(stroke
				(width 0.1)
				(type default)
			)
			(layer "B.Fab")
		)
		(fp_line
			(start 1.1049 -0.724916)
			(end 1.1049 0.724916)
			(stroke
				(width 0.1)
				(type default)
			)
			(layer "B.Fab")
		)
		(fp_line
			(start 1.1049 0.724916)
			(end -1.1049 0.724916)
			(stroke
				(width 0.1)
				(type default)
			)
			(layer "B.Fab")
		)
		(pad "1" smd rect
			(at 0.889 0)
			(size 1.016 1.27)
			(layers "B.Cu" "B.Mask" "B.Paste")
			(net "SW_P12V_AUX_P0V9_RETIMER_CPU1_FLT")
		)
		(pad "2" smd rect
			(at -0.889 0)
			(size 1.016 1.27)
			(layers "B.Cu" "B.Mask" "B.Paste")
			(net "GND")
		)
	)
	(footprint ""
		(layer "B.Cu")
		(at 111.379 -418.211 180)
		(property "Reference" "R3503"
			(at 0 0 0)
			(layer "B.SilkS")
			(hide yes)
			(effects
				(font
					(size 1.27 1.27)
				)
				(justify mirror)
			)
		)
		(property "Value" ""
			(at 0 0 0)
			(layer "B.Fab")
			(effects
				(font
					(size 1.27 1.27)
				)
				(justify mirror)
			)
		)
		(duplicate_pad_numbers_are_jumpers no)
		(fp_line
			(start 0.7874 0.4064)
			(end 0.7874 -0.4064)
			(stroke
				(width 0.1524)
				(type default)
			)
			(layer "B.SilkS")
		)
		(fp_line
			(start 0.7874 -0.4064)
			(end -0.7874 -0.4064)
			(stroke
				(width 0.1524)
				(type default)
			)
			(layer "B.SilkS")
		)
		(fp_line
			(start -0.7874 0.4064)
			(end 0.7874 0.4064)
			(stroke
				(width 0.1524)
				(type default)
			)
			(layer "B.SilkS")
		)
		(fp_line
			(start -0.7874 -0.4064)
			(end -0.7874 0.4064)
			(stroke
				(width 0.1524)
				(type default)
			)
			(layer "B.SilkS")
		)
		(fp_line
			(start 0.67945 0.3048)
			(end 0.67945 -0.305054)
			(stroke
				(width 0.1)
				(type default)
			)
			(layer "B.Fab")
		)
		(fp_line
			(start 0.67945 -0.305054)
			(end 0.12065 -0.305054)
			(stroke
				(width 0.1)
				(type default)
			)
			(layer "B.Fab")
		)
		(fp_line
			(start 0.12065 0.3048)
			(end 0.67945 0.3048)
			(stroke
				(width 0.1)
				(type default)
			)
			(layer "B.Fab")
		)
		(fp_line
			(start 0.12065 0.2794)
			(end 0.12065 0.3048)
			(stroke
				(width 0.1)
				(type default)
			)
			(layer "B.Fab")
		)
		(fp_line
			(start 0.12065 -0.2794)
			(end -0.12065 -0.2794)
			(stroke
				(width 0.1)
				(type default)
			)
			(layer "B.Fab")
		)
		(fp_line
			(start 0.12065 -0.305054)
			(end 0.12065 -0.2794)
			(stroke
				(width 0.1)
				(type default)
			)
			(layer "B.Fab")
		)
		(fp_line
			(start -0.120396 0.3048)
			(end -0.120396 0.2794)
			(stroke
				(width 0.1)
				(type default)
			)
			(layer "B.Fab")
		)
		(fp_line
			(start -0.120396 0.2794)
			(end 0.12065 0.2794)
			(stroke
				(width 0.1)
				(type default)
			)
			(layer "B.Fab")
		)
		(fp_line
			(start -0.12065 -0.2794)
			(end -0.12065 -0.3048)
			(stroke
				(width 0.1)
				(type default)
			)
			(layer "B.Fab")
		)
		(fp_line
			(start -0.12065 -0.3048)
			(end -0.67945 -0.3048)
			(stroke
				(width 0.1)
				(type default)
			)
			(layer "B.Fab")
		)
		(fp_line
			(start -0.67945 0.3048)
			(end -0.120396 0.3048)
			(stroke
				(width 0.1)
				(type default)
			)
			(layer "B.Fab")
		)
		(fp_line
			(start -0.67945 -0.3048)
			(end -0.67945 0.3048)
			(stroke
				(width 0.1)
				(type default)
			)
			(layer "B.Fab")
		)
		(pad "1" smd circle
			(at 0.40005 0)
			(size 0 0)
			(layers "B.Cu" "B.Mask" "B.Paste")
			(net "P3V3_AUX")
		)
		(pad "2" smd circle
			(at -0.40005 0)
			(size 0 0)
			(layers "B.Cu" "B.Mask" "B.Paste")
			(net "GPU_FPGA_EROT_FATALERR")
		)
	)
	(footprint ""
		(layer "B.Cu")
		(at 230.505 -242.443 90)
		(property "Reference" "R323"
			(at 0 0 90)
			(layer "B.SilkS")
			(hide yes)
			(effects
				(font
					(size 1.27 1.27)
				)
				(justify mirror)
			)
		)
		(property "Value" ""
			(at 0 0 90)
			(layer "B.Fab")
			(effects
				(font
					(size 1.27 1.27)
				)
				(justify mirror)
			)
		)
		(duplicate_pad_numbers_are_jumpers no)
		(fp_line
			(start 0.7874 -0.4064)
			(end -0.7874 -0.4064)
			(stroke
				(width 0.1524)
				(type default)
			)
			(layer "B.SilkS")
		)
		(fp_line
			(start -0.7874 -0.4064)
			(end -0.7874 0.4064)
			(stroke
				(width 0.1524)
				(type default)
			)
			(layer "B.SilkS")
		)
		(fp_line
			(start 0.7874 0.4064)
			(end 0.7874 -0.4064)
			(stroke
				(width 0.1524)
				(type default)
			)
			(layer "B.SilkS")
		)
		(fp_line
			(start -0.7874 0.4064)
			(end 0.7874 0.4064)
			(stroke
				(width 0.1524)
				(type default)
			)
			(layer "B.SilkS")
		)
		(fp_line
			(start 0.67945 -0.305054)
			(end 0.12065 -0.305054)
			(stroke
				(width 0.1)
				(type default)
			)
			(layer "B.Fab")
		)
		(fp_line
			(start 0.12065 -0.305054)
			(end 0.12065 -0.2794)
			(stroke
				(width 0.1)
				(type default)
			)
			(layer "B.Fab")
		)
		(fp_line
			(start -0.12065 -0.3048)
			(end -0.67945 -0.3048)
			(stroke
				(width 0.1)
				(type default)
			)
			(layer "B.Fab")
		)
		(fp_line
			(start -0.67945 -0.3048)
			(end -0.67945 0.3048)
			(stroke
				(width 0.1)
				(type default)
			)
			(layer "B.Fab")
		)
		(fp_line
			(start 0.12065 -0.2794)
			(end -0.12065 -0.2794)
			(stroke
				(width 0.1)
				(type default)
			)
			(layer "B.Fab")
		)
		(fp_line
			(start -0.12065 -0.2794)
			(end -0.12065 -0.3048)
			(stroke
				(width 0.1)
				(type default)
			)
			(layer "B.Fab")
		)
		(fp_line
			(start 0.12065 0.2794)
			(end 0.12065 0.3048)
			(stroke
				(width 0.1)
				(type default)
			)
			(layer "B.Fab")
		)
		(fp_line
			(start -0.120396 0.2794)
			(end 0.12065 0.2794)
			(stroke
				(width 0.1)
				(type default)
			)
			(layer "B.Fab")
		)
		(fp_line
			(start 0.67945 0.3048)
			(end 0.67945 -0.305054)
			(stroke
				(width 0.1)
				(type default)
			)
			(layer "B.Fab")
		)
		(fp_line
			(start 0.12065 0.3048)
			(end 0.67945 0.3048)
			(stroke
				(width 0.1)
				(type default)
			)
			(layer "B.Fab")
		)
		(fp_line
			(start -0.120396 0.3048)
			(end -0.120396 0.2794)
			(stroke
				(width 0.1)
				(type default)
			)
			(layer "B.Fab")
		)
		(fp_line
			(start -0.67945 0.3048)
			(end -0.120396 0.3048)
			(stroke
				(width 0.1)
				(type default)
			)
			(layer "B.Fab")
		)
		(pad "1" smd rect
			(at 0.40005 0 90)
			(size 0.4572 0.508)
			(layers "B.Cu" "B.Mask" "B.Paste")
			(net "SMB_CPU0_CPU1_APML_SDA_R2")
		)
		(pad "2" smd rect
			(at -0.40005 0 90)
			(size 0.4572 0.508)
			(layers "B.Cu" "B.Mask" "B.Paste")
			(net "SMB_CPU0_CPU1_APML_MUX1_SDA")
		)
	)
	(footprint ""
		(layer "B.Cu")
		(at 402.322538 -321.179952 180)
		(property "Reference" "R446"
			(at 0 0 0)
			(layer "B.SilkS")
			(hide yes)
			(effects
				(font
					(size 1.27 1.27)
				)
				(justify mirror)
			)
		)
		(property "Value" ""
			(at 0 0 0)
			(layer "B.Fab")
			(effects
				(font
					(size 1.27 1.27)
				)
				(justify mirror)
			)
		)
		(duplicate_pad_numbers_are_jumpers no)
		(fp_line
			(start 0.7874 0.4064)
			(end 0.7874 -0.4064)
			(stroke
				(width 0.1524)
				(type default)
			)
			(layer "B.SilkS")
		)
		(fp_line
			(start 0.7874 -0.4064)
			(end -0.7874 -0.4064)
			(stroke
				(width 0.1524)
				(type default)
			)
			(layer "B.SilkS")
		)
		(fp_line
			(start -0.7874 0.4064)
			(end 0.7874 0.4064)
			(stroke
				(width 0.1524)
				(type default)
			)
			(layer "B.SilkS")
		)
		(fp_line
			(start -0.7874 -0.4064)
			(end -0.7874 0.4064)
			(stroke
				(width 0.1524)
				(type default)
			)
			(layer "B.SilkS")
		)
		(fp_line
			(start 0.67945 0.3048)
			(end 0.67945 -0.305054)
			(stroke
				(width 0.1)
				(type default)
			)
			(layer "B.Fab")
		)
		(fp_line
			(start 0.67945 -0.305054)
			(end 0.12065 -0.305054)
			(stroke
				(width 0.1)
				(type default)
			)
			(layer "B.Fab")
		)
		(fp_line
			(start 0.12065 0.3048)
			(end 0.67945 0.3048)
			(stroke
				(width 0.1)
				(type default)
			)
			(layer "B.Fab")
		)
		(fp_line
			(start 0.12065 0.2794)
			(end 0.12065 0.3048)
			(stroke
				(width 0.1)
				(type default)
			)
			(layer "B.Fab")
		)
		(fp_line
			(start 0.12065 -0.2794)
			(end -0.12065 -0.2794)
			(stroke
				(width 0.1)
				(type default)
			)
			(layer "B.Fab")
		)
		(fp_line
			(start 0.12065 -0.305054)
			(end 0.12065 -0.2794)
			(stroke
				(width 0.1)
				(type default)
			)
			(layer "B.Fab")
		)
		(fp_line
			(start -0.120396 0.3048)
			(end -0.120396 0.2794)
			(stroke
				(width 0.1)
				(type default)
			)
			(layer "B.Fab")
		)
		(fp_line
			(start -0.120396 0.2794)
			(end 0.12065 0.2794)
			(stroke
				(width 0.1)
				(type default)
			)
			(layer "B.Fab")
		)
		(fp_line
			(start -0.12065 -0.2794)
			(end -0.12065 -0.3048)
			(stroke
				(width 0.1)
				(type default)
			)
			(layer "B.Fab")
		)
		(fp_line
			(start -0.12065 -0.3048)
			(end -0.67945 -0.3048)
			(stroke
				(width 0.1)
				(type default)
			)
			(layer "B.Fab")
		)
		(fp_line
			(start -0.67945 0.3048)
			(end -0.120396 0.3048)
			(stroke
				(width 0.1)
				(type default)
			)
			(layer "B.Fab")
		)
		(fp_line
			(start -0.67945 -0.3048)
			(end -0.67945 0.3048)
			(stroke
				(width 0.1)
				(type default)
			)
			(layer "B.Fab")
		)
		(pad "1" smd circle
			(at 0.40005 0)
			(size 0 0)
			(layers "B.Cu" "B.Mask" "B.Paste")
			(net "IRQ_SMI_ACTIVE_N")
		)
		(pad "2" smd circle
			(at -0.40005 0)
			(size 0 0)
			(layers "B.Cu" "B.Mask" "B.Paste")
			(net "PVDD18_S5_P0")
		)
	)
	(footprint ""
		(layer "B.Cu")
		(at 243.713 -322.834)
		(property "Reference" "C1082"
			(at 0 0 0)
			(layer "B.SilkS")
			(hide yes)
			(effects
				(font
					(size 1.27 1.27)
				)
				(justify mirror)
			)
		)
		(property "Value" ""
			(at 0 0 0)
			(layer "B.Fab")
			(effects
				(font
					(size 1.27 1.27)
				)
				(justify mirror)
			)
		)
		(duplicate_pad_numbers_are_jumpers no)
		(fp_line
			(start -0.7874 -0.4064)
			(end -0.7874 0.4064)
			(stroke
				(width 0.1524)
				(type default)
			)
			(layer "B.SilkS")
		)
		(fp_line
			(start -0.7874 0.4064)
			(end 0.7874 0.4064)
			(stroke
				(width 0.1524)
				(type default)
			)
			(layer "B.SilkS")
		)
		(fp_line
			(start 0.7874 -0.4064)
			(end -0.7874 -0.4064)
			(stroke
				(width 0.1524)
				(type default)
			)
			(layer "B.SilkS")
		)
		(fp_line
			(start 0.7874 0.4064)
			(end 0.7874 -0.4064)
			(stroke
				(width 0.1524)
				(type default)
			)
			(layer "B.SilkS")
		)
		(fp_line
			(start -0.67945 -0.3048)
			(end -0.67945 0.3048)
			(stroke
				(width 0.1)
				(type default)
			)
			(layer "B.Fab")
		)
		(fp_line
			(start -0.67945 0.3048)
			(end -0.120396 0.3048)
			(stroke
				(width 0.1)
				(type default)
			)
			(layer "B.Fab")
		)
		(fp_line
			(start -0.12065 -0.3048)
			(end -0.67945 -0.3048)
			(stroke
				(width 0.1)
				(type default)
			)
			(layer "B.Fab")
		)
		(fp_line
			(start -0.12065 -0.2794)
			(end -0.12065 -0.3048)
			(stroke
				(width 0.1)
				(type default)
			)
			(layer "B.Fab")
		)
		(fp_line
			(start -0.120396 0.2794)
			(end 0.12065 0.2794)
			(stroke
				(width 0.1)
				(type default)
			)
			(layer "B.Fab")
		)
		(fp_line
			(start -0.120396 0.3048)
			(end -0.120396 0.2794)
			(stroke
				(width 0.1)
				(type default)
			)
			(layer "B.Fab")
		)
		(fp_line
			(start 0.12065 -0.305054)
			(end 0.12065 -0.2794)
			(stroke
				(width 0.1)
				(type default)
			)
			(layer "B.Fab")
		)
		(fp_line
			(start 0.12065 -0.2794)
			(end -0.12065 -0.2794)
			(stroke
				(width 0.1)
				(type default)
			)
			(layer "B.Fab")
		)
		(fp_line
			(start 0.12065 0.2794)
			(end 0.12065 0.3048)
			(stroke
				(width 0.1)
				(type default)
			)
			(layer "B.Fab")
		)
		(fp_line
			(start 0.12065 0.3048)
			(end 0.67945 0.3048)
			(stroke
				(width 0.1)
				(type default)
			)
			(layer "B.Fab")
		)
		(fp_line
			(start 0.67945 -0.305054)
			(end 0.12065 -0.305054)
			(stroke
				(width 0.1)
				(type default)
			)
			(layer "B.Fab")
		)
		(fp_line
			(start 0.67945 0.3048)
			(end 0.67945 -0.305054)
			(stroke
				(width 0.1)
				(type default)
			)
			(layer "B.Fab")
		)
		(pad "1" smd circle
			(at 0.40005 0 180)
			(size 0 0)
			(layers "B.Cu" "B.Mask" "B.Paste")
			(net "PVDD_33_S5_ADC_MAM")
		)
		(pad "2" smd circle
			(at -0.40005 0 180)
			(size 0 0)
			(layers "B.Cu" "B.Mask" "B.Paste")
			(net "GND")
		)
	)
	(footprint ""
		(layer "B.Cu")
		(at 308.318154 -396.393162 -90)
		(property "Reference" "C538"
			(at 0 0 90)
			(layer "B.SilkS")
			(hide yes)
			(effects
				(font
					(size 1.27 1.27)
				)
				(justify mirror)
			)
		)
		(property "Value" ""
			(at 0 0 90)
			(layer "B.Fab")
			(effects
				(font
					(size 1.27 1.27)
				)
				(justify mirror)
			)
		)
		(duplicate_pad_numbers_are_jumpers no)
		(fp_line
			(start -0.299974 0.150114)
			(end 0.299974 0.150114)
			(stroke
				(width 0.1)
				(type default)
			)
			(layer "B.Fab")
		)
		(fp_line
			(start 0.299974 0.150114)
			(end 0.299974 -0.150114)
			(stroke
				(width 0.1)
				(type default)
			)
			(layer "B.Fab")
		)
		(fp_line
			(start -0.299974 -0.150114)
			(end -0.299974 0.150114)
			(stroke
				(width 0.1)
				(type default)
			)
			(layer "B.Fab")
		)
		(fp_line
			(start 0.299974 -0.150114)
			(end -0.299974 -0.150114)
			(stroke
				(width 0.1)
				(type default)
			)
			(layer "B.Fab")
		)
		(pad "1" smd rect
			(at 0.2667 0 90)
			(size 0.3048 0.381)
			(layers "B.Cu" "B.Mask" "B.Paste")
			(net "P0V9_CPU0_RT0_2A_2D")
		)
		(pad "2" smd rect
			(at -0.2667 0 90)
			(size 0.3048 0.381)
			(layers "B.Cu" "B.Mask" "B.Paste")
			(net "GND")
		)
	)
	(footprint ""
		(layer "B.Cu")
		(at 83.51901 -390.560052 90)
		(property "Reference" "C321"
			(at 0 0 90)
			(layer "B.SilkS")
			(hide yes)
			(effects
				(font
					(size 1.27 1.27)
				)
				(justify mirror)
			)
		)
		(property "Value" ""
			(at 0 0 90)
			(layer "B.Fab")
			(effects
				(font
					(size 1.27 1.27)
				)
				(justify mirror)
			)
		)
		(duplicate_pad_numbers_are_jumpers no)
		(fp_line
			(start 0.7874 -0.4064)
			(end -0.7874 -0.4064)
			(stroke
				(width 0.1524)
				(type default)
			)
			(layer "B.SilkS")
		)
		(fp_line
			(start -0.7874 -0.4064)
			(end -0.7874 0.4064)
			(stroke
				(width 0.1524)
				(type default)
			)
			(layer "B.SilkS")
		)
		(fp_line
			(start 0.7874 0.4064)
			(end 0.7874 -0.4064)
			(stroke
				(width 0.1524)
				(type default)
			)
			(layer "B.SilkS")
		)
		(fp_line
			(start -0.7874 0.4064)
			(end 0.7874 0.4064)
			(stroke
				(width 0.1524)
				(type default)
			)
			(layer "B.SilkS")
		)
		(fp_line
			(start 0.67945 -0.305054)
			(end 0.12065 -0.305054)
			(stroke
				(width 0.1)
				(type default)
			)
			(layer "B.Fab")
		)
		(fp_line
			(start 0.12065 -0.305054)
			(end 0.12065 -0.2794)
			(stroke
				(width 0.1)
				(type default)
			)
			(layer "B.Fab")
		)
		(fp_line
			(start -0.12065 -0.3048)
			(end -0.67945 -0.3048)
			(stroke
				(width 0.1)
				(type default)
			)
			(layer "B.Fab")
		)
		(fp_line
			(start -0.67945 -0.3048)
			(end -0.67945 0.3048)
			(stroke
				(width 0.1)
				(type default)
			)
			(layer "B.Fab")
		)
		(fp_line
			(start 0.12065 -0.2794)
			(end -0.12065 -0.2794)
			(stroke
				(width 0.1)
				(type default)
			)
			(layer "B.Fab")
		)
		(fp_line
			(start -0.12065 -0.2794)
			(end -0.12065 -0.3048)
			(stroke
				(width 0.1)
				(type default)
			)
			(layer "B.Fab")
		)
		(fp_line
			(start 0.12065 0.2794)
			(end 0.12065 0.3048)
			(stroke
				(width 0.1)
				(type default)
			)
			(layer "B.Fab")
		)
		(fp_line
			(start -0.120396 0.2794)
			(end 0.12065 0.2794)
			(stroke
				(width 0.1)
				(type default)
			)
			(layer "B.Fab")
		)
		(fp_line
			(start 0.67945 0.3048)
			(end 0.67945 -0.305054)
			(stroke
				(width 0.1)
				(type default)
			)
			(layer "B.Fab")
		)
		(fp_line
			(start 0.12065 0.3048)
			(end 0.67945 0.3048)
			(stroke
				(width 0.1)
				(type default)
			)
			(layer "B.Fab")
		)
		(fp_line
			(start -0.120396 0.3048)
			(end -0.120396 0.2794)
			(stroke
				(width 0.1)
				(type default)
			)
			(layer "B.Fab")
		)
		(fp_line
			(start -0.67945 0.3048)
			(end -0.120396 0.3048)
			(stroke
				(width 0.1)
				(type default)
			)
			(layer "B.Fab")
		)
		(pad "1" smd circle
			(at 0.40005 0 270)
			(size 0 0)
			(layers "B.Cu" "B.Mask" "B.Paste")
			(net "P0V9_CPU1_RT1_2A")
		)
		(pad "2" smd circle
			(at -0.40005 0 270)
			(size 0 0)
			(layers "B.Cu" "B.Mask" "B.Paste")
			(net "GND")
		)
	)
	(footprint ""
		(layer "B.Cu")
		(at 129.067814 -381.11303)
		(property "Reference" "C7030"
			(at 2.21742 3.131312 0)
			(unlocked yes)
			(layer "B.SilkS")
			(effects
				(font
					(size 0.7874 0.5842)
					(thickness 0.1524)
				)
				(justify left mirror)
			)
		)
		(property "Value" ""
			(at 0 0 0)
			(layer "B.Fab")
			(effects
				(font
					(size 1.27 1.27)
				)
				(justify mirror)
			)
		)
		(duplicate_pad_numbers_are_jumpers no)
		(fp_line
			(start -4.53898 -2.15011)
			(end -4.53898 2.15011)
			(stroke
				(width 0.1524)
				(type default)
			)
			(layer "B.SilkS")
		)
		(fp_line
			(start -4.53898 2.15011)
			(end 4.53898 2.15011)
			(stroke
				(width 0.1524)
				(type default)
			)
			(layer "B.SilkS")
		)
		(fp_line
			(start 4.53898 -2.150618)
			(end 4.539742 2.152142)
			(stroke
				(width 0.1524)
				(type default)
			)
			(layer "B.SilkS")
		)
		(fp_line
			(start 4.53898 -2.15011)
			(end -4.53898 -2.15011)
			(stroke
				(width 0.1524)
				(type default)
			)
			(layer "B.SilkS")
		)
		(fp_line
			(start 4.53898 2.15011)
			(end 4.53898 -2.15011)
			(stroke
				(width 0.1524)
				(type default)
			)
			(layer "B.SilkS")
		)
		(fp_line
			(start 4.69138 -2.150618)
			(end 4.692396 2.161032)
			(stroke
				(width 0.1524)
				(type default)
			)
			(layer "B.SilkS")
		)
		(fp_line
			(start 4.83108 2.150364)
			(end 4.447794 2.149348)
			(stroke
				(width 0.1524)
				(type default)
			)
			(layer "B.SilkS")
		)
		(fp_line
			(start 4.84378 -2.150618)
			(end 4.53898 -2.150618)
			(stroke
				(width 0.1524)
				(type default)
			)
			(layer "B.SilkS")
		)
		(fp_line
			(start 4.84378 -2.150618)
			(end 4.842256 2.163064)
			(stroke
				(width 0.1524)
				(type default)
			)
			(layer "B.SilkS")
		)
		(fp_line
			(start -3.64998 -2.15011)
			(end -3.64998 2.15011)
			(stroke
				(width 0.1)
				(type default)
			)
			(layer "B.Fab")
		)
		(fp_line
			(start -3.64998 2.15011)
			(end 3.64998 2.15011)
			(stroke
				(width 0.1)
				(type default)
			)
			(layer "B.Fab")
		)
		(fp_line
			(start 3.64998 -2.15011)
			(end -3.64998 -2.15011)
			(stroke
				(width 0.1)
				(type default)
			)
			(layer "B.Fab")
		)
		(fp_line
			(start 3.64998 2.15011)
			(end 3.64998 -2.15011)
			(stroke
				(width 0.1)
				(type default)
			)
			(layer "B.Fab")
		)
		(fp_text user "-"
			(at -2.804414 2.313432 0)
			(unlocked yes)
			(layer "B.SilkS")
			(effects
				(font
					(size 1.905 1.4224)
					(thickness 0.1524)
				)
				(justify left mirror)
			)
		)
		(fp_text user "+"
			(at 6.214872 -0.337058 0)
			(unlocked yes)
			(layer "B.SilkS")
			(effects
				(font
					(size 1.905 1.4224)
					(thickness 0.1524)
				)
				(justify left mirror)
			)
		)
		(fp_text user "-"
			(at -4.313174 -0.094488 0)
			(unlocked yes)
			(layer "B.Fab")
			(effects
				(font
					(size 1.905 1.4224)
					(thickness 0.1524)
				)
				(justify left mirror)
			)
		)
		(fp_text user "+"
			(at 6.214872 -0.337058 0)
			(unlocked yes)
			(layer "B.Fab")
			(effects
				(font
					(size 1.905 1.4224)
					(thickness 0.1524)
				)
				(justify left mirror)
			)
		)
		(pad "1" smd rect
			(at 3.199892 0 180)
			(size 2.413 2.8194)
			(layers "B.Cu" "B.Mask" "B.Paste")
			(net "P0V9_CPU1_RT3_2A")
		)
		(pad "2" smd rect
			(at -3.199892 0 180)
			(size 2.413 2.8194)
			(layers "B.Cu" "B.Mask" "B.Paste")
			(net "GND")
		)
	)
	(footprint ""
		(layer "B.Cu")
		(at 301.418244 -395.43228)
		(property "Reference" "C555"
			(at 0 0 0)
			(layer "B.SilkS")
			(hide yes)
			(effects
				(font
					(size 1.27 1.27)
				)
				(justify mirror)
			)
		)
		(property "Value" ""
			(at 0 0 0)
			(layer "B.Fab")
			(effects
				(font
					(size 1.27 1.27)
				)
				(justify mirror)
			)
		)
		(duplicate_pad_numbers_are_jumpers no)
		(fp_line
			(start -0.299974 -0.150114)
			(end -0.299974 0.150114)
			(stroke
				(width 0.1)
				(type default)
			)
			(layer "B.Fab")
		)
		(fp_line
			(start -0.299974 0.150114)
			(end 0.299974 0.150114)
			(stroke
				(width 0.1)
				(type default)
			)
			(layer "B.Fab")
		)
		(fp_line
			(start 0.299974 -0.150114)
			(end -0.299974 -0.150114)
			(stroke
				(width 0.1)
				(type default)
			)
			(layer "B.Fab")
		)
		(fp_line
			(start 0.299974 0.150114)
			(end 0.299974 -0.150114)
			(stroke
				(width 0.1)
				(type default)
			)
			(layer "B.Fab")
		)
		(pad "1" smd rect
			(at 0.2667 0 180)
			(size 0.3048 0.381)
			(layers "B.Cu" "B.Mask" "B.Paste")
			(net "P0V9_CPU0_RT0_2A")
		)
		(pad "2" smd rect
			(at -0.2667 0 180)
			(size 0.3048 0.381)
			(layers "B.Cu" "B.Mask" "B.Paste")
			(net "GND")
		)
	)
	(footprint ""
		(layer "B.Cu")
		(at 63.55588 -8.981948 90)
		(property "Reference" "C1838"
			(at 0 0 90)
			(layer "B.SilkS")
			(hide yes)
			(effects
				(font
					(size 1.27 1.27)
				)
				(justify mirror)
			)
		)
		(property "Value" ""
			(at 0 0 90)
			(layer "B.Fab")
			(effects
				(font
					(size 1.27 1.27)
				)
				(justify mirror)
			)
		)
		(duplicate_pad_numbers_are_jumpers no)
		(fp_line
			(start 0.7874 -0.4064)
			(end -0.7874 -0.4064)
			(stroke
				(width 0.1524)
				(type default)
			)
			(layer "B.SilkS")
		)
		(fp_line
			(start -0.7874 -0.4064)
			(end -0.7874 0.4064)
			(stroke
				(width 0.1524)
				(type default)
			)
			(layer "B.SilkS")
		)
		(fp_line
			(start 0.7874 0.4064)
			(end 0.7874 -0.4064)
			(stroke
				(width 0.1524)
				(type default)
			)
			(layer "B.SilkS")
		)
		(fp_line
			(start -0.7874 0.4064)
			(end 0.7874 0.4064)
			(stroke
				(width 0.1524)
				(type default)
			)
			(layer "B.SilkS")
		)
		(fp_line
			(start 0.67945 -0.305054)
			(end 0.12065 -0.305054)
			(stroke
				(width 0.1)
				(type default)
			)
			(layer "B.Fab")
		)
		(fp_line
			(start 0.12065 -0.305054)
			(end 0.12065 -0.2794)
			(stroke
				(width 0.1)
				(type default)
			)
			(layer "B.Fab")
		)
		(fp_line
			(start -0.12065 -0.3048)
			(end -0.67945 -0.3048)
			(stroke
				(width 0.1)
				(type default)
			)
			(layer "B.Fab")
		)
		(fp_line
			(start -0.67945 -0.3048)
			(end -0.67945 0.3048)
			(stroke
				(width 0.1)
				(type default)
			)
			(layer "B.Fab")
		)
		(fp_line
			(start 0.12065 -0.2794)
			(end -0.12065 -0.2794)
			(stroke
				(width 0.1)
				(type default)
			)
			(layer "B.Fab")
		)
		(fp_line
			(start -0.12065 -0.2794)
			(end -0.12065 -0.3048)
			(stroke
				(width 0.1)
				(type default)
			)
			(layer "B.Fab")
		)
		(fp_line
			(start 0.12065 0.2794)
			(end 0.12065 0.3048)
			(stroke
				(width 0.1)
				(type default)
			)
			(layer "B.Fab")
		)
		(fp_line
			(start -0.120396 0.2794)
			(end 0.12065 0.2794)
			(stroke
				(width 0.1)
				(type default)
			)
			(layer "B.Fab")
		)
		(fp_line
			(start 0.67945 0.3048)
			(end 0.67945 -0.305054)
			(stroke
				(width 0.1)
				(type default)
			)
			(layer "B.Fab")
		)
		(fp_line
			(start 0.12065 0.3048)
			(end 0.67945 0.3048)
			(stroke
				(width 0.1)
				(type default)
			)
			(layer "B.Fab")
		)
		(fp_line
			(start -0.120396 0.3048)
			(end -0.120396 0.2794)
			(stroke
				(width 0.1)
				(type default)
			)
			(layer "B.Fab")
		)
		(fp_line
			(start -0.67945 0.3048)
			(end -0.120396 0.3048)
			(stroke
				(width 0.1)
				(type default)
			)
			(layer "B.Fab")
		)
		(pad "1" smd circle
			(at 0.40005 0 270)
			(size 0 0)
			(layers "B.Cu" "B.Mask" "B.Paste")
			(net "P3V3_OCP_V3_2")
		)
		(pad "2" smd circle
			(at -0.40005 0 270)
			(size 0 0)
			(layers "B.Cu" "B.Mask" "B.Paste")
			(net "GND")
		)
	)
	(footprint ""
		(layer "B.Cu")
		(at 415.712402 -193.99631)
		(property "Reference" "C116"
			(at 0 0 0)
			(layer "B.SilkS")
			(hide yes)
			(effects
				(font
					(size 1.27 1.27)
				)
				(justify mirror)
			)
		)
		(property "Value" ""
			(at 0 0 0)
			(layer "B.Fab")
			(effects
				(font
					(size 1.27 1.27)
				)
				(justify mirror)
			)
		)
		(duplicate_pad_numbers_are_jumpers no)
		(fp_line
			(start -0.7874 -0.4064)
			(end -0.7874 0.4064)
			(stroke
				(width 0.1524)
				(type default)
			)
			(layer "B.SilkS")
		)
		(fp_line
			(start -0.7874 0.4064)
			(end 0.7874 0.4064)
			(stroke
				(width 0.1524)
				(type default)
			)
			(layer "B.SilkS")
		)
		(fp_line
			(start 0.7874 -0.4064)
			(end -0.7874 -0.4064)
			(stroke
				(width 0.1524)
				(type default)
			)
			(layer "B.SilkS")
		)
		(fp_line
			(start 0.7874 0.4064)
			(end 0.7874 -0.4064)
			(stroke
				(width 0.1524)
				(type default)
			)
			(layer "B.SilkS")
		)
		(fp_line
			(start -0.67945 -0.3048)
			(end -0.67945 0.3048)
			(stroke
				(width 0.1)
				(type default)
			)
			(layer "B.Fab")
		)
		(fp_line
			(start -0.67945 0.3048)
			(end -0.120396 0.3048)
			(stroke
				(width 0.1)
				(type default)
			)
			(layer "B.Fab")
		)
		(fp_line
			(start -0.12065 -0.3048)
			(end -0.67945 -0.3048)
			(stroke
				(width 0.1)
				(type default)
			)
			(layer "B.Fab")
		)
		(fp_line
			(start -0.12065 -0.2794)
			(end -0.12065 -0.3048)
			(stroke
				(width 0.1)
				(type default)
			)
			(layer "B.Fab")
		)
		(fp_line
			(start -0.120396 0.2794)
			(end 0.12065 0.2794)
			(stroke
				(width 0.1)
				(type default)
			)
			(layer "B.Fab")
		)
		(fp_line
			(start -0.120396 0.3048)
			(end -0.120396 0.2794)
			(stroke
				(width 0.1)
				(type default)
			)
			(layer "B.Fab")
		)
		(fp_line
			(start 0.12065 -0.305054)
			(end 0.12065 -0.2794)
			(stroke
				(width 0.1)
				(type default)
			)
			(layer "B.Fab")
		)
		(fp_line
			(start 0.12065 -0.2794)
			(end -0.12065 -0.2794)
			(stroke
				(width 0.1)
				(type default)
			)
			(layer "B.Fab")
		)
		(fp_line
			(start 0.12065 0.2794)
			(end 0.12065 0.3048)
			(stroke
				(width 0.1)
				(type default)
			)
			(layer "B.Fab")
		)
		(fp_line
			(start 0.12065 0.3048)
			(end 0.67945 0.3048)
			(stroke
				(width 0.1)
				(type default)
			)
			(layer "B.Fab")
		)
		(fp_line
			(start 0.67945 -0.305054)
			(end 0.12065 -0.305054)
			(stroke
				(width 0.1)
				(type default)
			)
			(layer "B.Fab")
		)
		(fp_line
			(start 0.67945 0.3048)
			(end 0.67945 -0.305054)
			(stroke
				(width 0.1)
				(type default)
			)
			(layer "B.Fab")
		)
		(pad "1" smd circle
			(at 0.40005 0 180)
			(size 0 0)
			(layers "B.Cu" "B.Mask" "B.Paste")
			(net "P3V3_AUX")
		)
		(pad "2" smd circle
			(at -0.40005 0 180)
			(size 0 0)
			(layers "B.Cu" "B.Mask" "B.Paste")
			(net "GND")
		)
	)
	(footprint ""
		(layer "B.Cu")
		(at 126.375668 -35.203892)
		(property "Reference" "C6055"
			(at 0 0 0)
			(layer "B.SilkS")
			(hide yes)
			(effects
				(font
					(size 1.27 1.27)
				)
				(justify mirror)
			)
		)
		(property "Value" ""
			(at 0 0 0)
			(layer "B.Fab")
			(effects
				(font
					(size 1.27 1.27)
				)
				(justify mirror)
			)
		)
		(duplicate_pad_numbers_are_jumpers no)
		(fp_line
			(start -0.7874 -0.4064)
			(end -0.7874 0.4064)
			(stroke
				(width 0.1524)
				(type default)
			)
			(layer "B.SilkS")
		)
		(fp_line
			(start -0.7874 0.4064)
			(end 0.7874 0.4064)
			(stroke
				(width 0.1524)
				(type default)
			)
			(layer "B.SilkS")
		)
		(fp_line
			(start 0.7874 -0.4064)
			(end -0.7874 -0.4064)
			(stroke
				(width 0.1524)
				(type default)
			)
			(layer "B.SilkS")
		)
		(fp_line
			(start 0.7874 0.4064)
			(end 0.7874 -0.4064)
			(stroke
				(width 0.1524)
				(type default)
			)
			(layer "B.SilkS")
		)
		(fp_line
			(start -0.67945 -0.3048)
			(end -0.67945 0.3048)
			(stroke
				(width 0.1)
				(type default)
			)
			(layer "B.Fab")
		)
		(fp_line
			(start -0.67945 0.3048)
			(end -0.120396 0.3048)
			(stroke
				(width 0.1)
				(type default)
			)
			(layer "B.Fab")
		)
		(fp_line
			(start -0.12065 -0.3048)
			(end -0.67945 -0.3048)
			(stroke
				(width 0.1)
				(type default)
			)
			(layer "B.Fab")
		)
		(fp_line
			(start -0.12065 -0.2794)
			(end -0.12065 -0.3048)
			(stroke
				(width 0.1)
				(type default)
			)
			(layer "B.Fab")
		)
		(fp_line
			(start -0.120396 0.2794)
			(end 0.12065 0.2794)
			(stroke
				(width 0.1)
				(type default)
			)
			(layer "B.Fab")
		)
		(fp_line
			(start -0.120396 0.3048)
			(end -0.120396 0.2794)
			(stroke
				(width 0.1)
				(type default)
			)
			(layer "B.Fab")
		)
		(fp_line
			(start 0.12065 -0.305054)
			(end 0.12065 -0.2794)
			(stroke
				(width 0.1)
				(type default)
			)
			(layer "B.Fab")
		)
		(fp_line
			(start 0.12065 -0.2794)
			(end -0.12065 -0.2794)
			(stroke
				(width 0.1)
				(type default)
			)
			(layer "B.Fab")
		)
		(fp_line
			(start 0.12065 0.2794)
			(end 0.12065 0.3048)
			(stroke
				(width 0.1)
				(type default)
			)
			(layer "B.Fab")
		)
		(fp_line
			(start 0.12065 0.3048)
			(end 0.67945 0.3048)
			(stroke
				(width 0.1)
				(type default)
			)
			(layer "B.Fab")
		)
		(fp_line
			(start 0.67945 -0.305054)
			(end 0.12065 -0.305054)
			(stroke
				(width 0.1)
				(type default)
			)
			(layer "B.Fab")
		)
		(fp_line
			(start 0.67945 0.3048)
			(end 0.67945 -0.305054)
			(stroke
				(width 0.1)
				(type default)
			)
			(layer "B.Fab")
		)
		(pad "1" smd circle
			(at 0.40005 0 180)
			(size 0 0)
			(layers "B.Cu" "B.Mask" "B.Paste")
			(net "P1V2_AUX")
		)
		(pad "2" smd circle
			(at -0.40005 0 180)
			(size 0 0)
			(layers "B.Cu" "B.Mask" "B.Paste")
			(net "GND")
		)
	)
	(footprint ""
		(layer "B.Cu")
		(at 112.427004 -261.748016 90)
		(property "Reference" "C2510"
			(at 0 0 90)
			(layer "B.SilkS")
			(hide yes)
			(effects
				(font
					(size 1.27 1.27)
				)
				(justify mirror)
			)
		)
		(property "Value" ""
			(at 0 0 90)
			(layer "B.Fab")
			(effects
				(font
					(size 1.27 1.27)
				)
				(justify mirror)
			)
		)
		(duplicate_pad_numbers_are_jumpers no)
		(fp_line
			(start 0.7874 -0.4064)
			(end -0.7874 -0.4064)
			(stroke
				(width 0.1524)
				(type default)
			)
			(layer "B.SilkS")
		)
		(fp_line
			(start -0.7874 -0.4064)
			(end -0.7874 0.4064)
			(stroke
				(width 0.1524)
				(type default)
			)
			(layer "B.SilkS")
		)
		(fp_line
			(start 0.7874 0.4064)
			(end 0.7874 -0.4064)
			(stroke
				(width 0.1524)
				(type default)
			)
			(layer "B.SilkS")
		)
		(fp_line
			(start -0.7874 0.4064)
			(end 0.7874 0.4064)
			(stroke
				(width 0.1524)
				(type default)
			)
			(layer "B.SilkS")
		)
		(fp_line
			(start 0.67945 -0.305054)
			(end 0.12065 -0.305054)
			(stroke
				(width 0.1)
				(type default)
			)
			(layer "B.Fab")
		)
		(fp_line
			(start 0.12065 -0.305054)
			(end 0.12065 -0.2794)
			(stroke
				(width 0.1)
				(type default)
			)
			(layer "B.Fab")
		)
		(fp_line
			(start -0.12065 -0.3048)
			(end -0.67945 -0.3048)
			(stroke
				(width 0.1)
				(type default)
			)
			(layer "B.Fab")
		)
		(fp_line
			(start -0.67945 -0.3048)
			(end -0.67945 0.3048)
			(stroke
				(width 0.1)
				(type default)
			)
			(layer "B.Fab")
		)
		(fp_line
			(start 0.12065 -0.2794)
			(end -0.12065 -0.2794)
			(stroke
				(width 0.1)
				(type default)
			)
			(layer "B.Fab")
		)
		(fp_line
			(start -0.12065 -0.2794)
			(end -0.12065 -0.3048)
			(stroke
				(width 0.1)
				(type default)
			)
			(layer "B.Fab")
		)
		(fp_line
			(start 0.12065 0.2794)
			(end 0.12065 0.3048)
			(stroke
				(width 0.1)
				(type default)
			)
			(layer "B.Fab")
		)
		(fp_line
			(start -0.120396 0.2794)
			(end 0.12065 0.2794)
			(stroke
				(width 0.1)
				(type default)
			)
			(layer "B.Fab")
		)
		(fp_line
			(start 0.67945 0.3048)
			(end 0.67945 -0.305054)
			(stroke
				(width 0.1)
				(type default)
			)
			(layer "B.Fab")
		)
		(fp_line
			(start 0.12065 0.3048)
			(end 0.67945 0.3048)
			(stroke
				(width 0.1)
				(type default)
			)
			(layer "B.Fab")
		)
		(fp_line
			(start -0.120396 0.3048)
			(end -0.120396 0.2794)
			(stroke
				(width 0.1)
				(type default)
			)
			(layer "B.Fab")
		)
		(fp_line
			(start -0.67945 0.3048)
			(end -0.120396 0.3048)
			(stroke
				(width 0.1)
				(type default)
			)
			(layer "B.Fab")
		)
		(pad "1" smd circle
			(at 0.40005 0 270)
			(size 0 0)
			(layers "B.Cu" "B.Mask" "B.Paste")
			(net "PVDD11_S3_P1")
		)
		(pad "2" smd circle
			(at -0.40005 0 270)
			(size 0 0)
			(layers "B.Cu" "B.Mask" "B.Paste")
			(net "GND")
		)
	)
	(footprint ""
		(layer "B.Cu")
		(at 171.2341 -113.589308)
		(property "Reference" "R58"
			(at 0 0 0)
			(layer "B.SilkS")
			(hide yes)
			(effects
				(font
					(size 1.27 1.27)
				)
				(justify mirror)
			)
		)
		(property "Value" ""
			(at 0 0 0)
			(layer "B.Fab")
			(effects
				(font
					(size 1.27 1.27)
				)
				(justify mirror)
			)
		)
		(duplicate_pad_numbers_are_jumpers no)
		(fp_line
			(start -0.7874 -0.4064)
			(end -0.7874 0.4064)
			(stroke
				(width 0.1524)
				(type default)
			)
			(layer "B.SilkS")
		)
		(fp_line
			(start -0.7874 0.4064)
			(end 0.7874 0.4064)
			(stroke
				(width 0.1524)
				(type default)
			)
			(layer "B.SilkS")
		)
		(fp_line
			(start 0.7874 -0.4064)
			(end -0.7874 -0.4064)
			(stroke
				(width 0.1524)
				(type default)
			)
			(layer "B.SilkS")
		)
		(fp_line
			(start 0.7874 0.4064)
			(end 0.7874 -0.4064)
			(stroke
				(width 0.1524)
				(type default)
			)
			(layer "B.SilkS")
		)
		(fp_line
			(start -0.67945 -0.3048)
			(end -0.67945 0.3048)
			(stroke
				(width 0.1)
				(type default)
			)
			(layer "B.Fab")
		)
		(fp_line
			(start -0.67945 0.3048)
			(end -0.120396 0.3048)
			(stroke
				(width 0.1)
				(type default)
			)
			(layer "B.Fab")
		)
		(fp_line
			(start -0.12065 -0.3048)
			(end -0.67945 -0.3048)
			(stroke
				(width 0.1)
				(type default)
			)
			(layer "B.Fab")
		)
		(fp_line
			(start -0.12065 -0.2794)
			(end -0.12065 -0.3048)
			(stroke
				(width 0.1)
				(type default)
			)
			(layer "B.Fab")
		)
		(fp_line
			(start -0.120396 0.2794)
			(end 0.12065 0.2794)
			(stroke
				(width 0.1)
				(type default)
			)
			(layer "B.Fab")
		)
		(fp_line
			(start -0.120396 0.3048)
			(end -0.120396 0.2794)
			(stroke
				(width 0.1)
				(type default)
			)
			(layer "B.Fab")
		)
		(fp_line
			(start 0.12065 -0.305054)
			(end 0.12065 -0.2794)
			(stroke
				(width 0.1)
				(type default)
			)
			(layer "B.Fab")
		)
		(fp_line
			(start 0.12065 -0.2794)
			(end -0.12065 -0.2794)
			(stroke
				(width 0.1)
				(type default)
			)
			(layer "B.Fab")
		)
		(fp_line
			(start 0.12065 0.2794)
			(end 0.12065 0.3048)
			(stroke
				(width 0.1)
				(type default)
			)
			(layer "B.Fab")
		)
		(fp_line
			(start 0.12065 0.3048)
			(end 0.67945 0.3048)
			(stroke
				(width 0.1)
				(type default)
			)
			(layer "B.Fab")
		)
		(fp_line
			(start 0.67945 -0.305054)
			(end 0.12065 -0.305054)
			(stroke
				(width 0.1)
				(type default)
			)
			(layer "B.Fab")
		)
		(fp_line
			(start 0.67945 0.3048)
			(end 0.67945 -0.305054)
			(stroke
				(width 0.1)
				(type default)
			)
			(layer "B.Fab")
		)
		(pad "1" smd circle
			(at 0.40005 0 180)
			(size 0 0)
			(layers "B.Cu" "B.Mask" "B.Paste")
			(net "SGPIO_SCM_INTR_R_N")
		)
		(pad "2" smd circle
			(at -0.40005 0 180)
			(size 0 0)
			(layers "B.Cu" "B.Mask" "B.Paste")
			(net "SGPIO_SCM_INTR_N")
		)
	)
	(footprint ""
		(layer "B.Cu")
		(at 401.554696 -341.172292 90)
		(property "Reference" "C218"
			(at 0 0 90)
			(layer "B.SilkS")
			(hide yes)
			(effects
				(font
					(size 1.27 1.27)
				)
				(justify mirror)
			)
		)
		(property "Value" ""
			(at 0 0 90)
			(layer "B.Fab")
			(effects
				(font
					(size 1.27 1.27)
				)
				(justify mirror)
			)
		)
		(duplicate_pad_numbers_are_jumpers no)
		(fp_line
			(start 0.7874 -0.4064)
			(end -0.7874 -0.4064)
			(stroke
				(width 0.1524)
				(type default)
			)
			(layer "B.SilkS")
		)
		(fp_line
			(start -0.7874 -0.4064)
			(end -0.7874 0.4064)
			(stroke
				(width 0.1524)
				(type default)
			)
			(layer "B.SilkS")
		)
		(fp_line
			(start 0.7874 0.4064)
			(end 0.7874 -0.4064)
			(stroke
				(width 0.1524)
				(type default)
			)
			(layer "B.SilkS")
		)
		(fp_line
			(start -0.7874 0.4064)
			(end 0.7874 0.4064)
			(stroke
				(width 0.1524)
				(type default)
			)
			(layer "B.SilkS")
		)
		(fp_line
			(start 0.67945 -0.305054)
			(end 0.12065 -0.305054)
			(stroke
				(width 0.1)
				(type default)
			)
			(layer "B.Fab")
		)
		(fp_line
			(start 0.12065 -0.305054)
			(end 0.12065 -0.2794)
			(stroke
				(width 0.1)
				(type default)
			)
			(layer "B.Fab")
		)
		(fp_line
			(start -0.12065 -0.3048)
			(end -0.67945 -0.3048)
			(stroke
				(width 0.1)
				(type default)
			)
			(layer "B.Fab")
		)
		(fp_line
			(start -0.67945 -0.3048)
			(end -0.67945 0.3048)
			(stroke
				(width 0.1)
				(type default)
			)
			(layer "B.Fab")
		)
		(fp_line
			(start 0.12065 -0.2794)
			(end -0.12065 -0.2794)
			(stroke
				(width 0.1)
				(type default)
			)
			(layer "B.Fab")
		)
		(fp_line
			(start -0.12065 -0.2794)
			(end -0.12065 -0.3048)
			(stroke
				(width 0.1)
				(type default)
			)
			(layer "B.Fab")
		)
		(fp_line
			(start 0.12065 0.2794)
			(end 0.12065 0.3048)
			(stroke
				(width 0.1)
				(type default)
			)
			(layer "B.Fab")
		)
		(fp_line
			(start -0.120396 0.2794)
			(end 0.12065 0.2794)
			(stroke
				(width 0.1)
				(type default)
			)
			(layer "B.Fab")
		)
		(fp_line
			(start 0.67945 0.3048)
			(end 0.67945 -0.305054)
			(stroke
				(width 0.1)
				(type default)
			)
			(layer "B.Fab")
		)
		(fp_line
			(start 0.12065 0.3048)
			(end 0.67945 0.3048)
			(stroke
				(width 0.1)
				(type default)
			)
			(layer "B.Fab")
		)
		(fp_line
			(start -0.120396 0.3048)
			(end -0.120396 0.2794)
			(stroke
				(width 0.1)
				(type default)
			)
			(layer "B.Fab")
		)
		(fp_line
			(start -0.67945 0.3048)
			(end -0.120396 0.3048)
			(stroke
				(width 0.1)
				(type default)
			)
			(layer "B.Fab")
		)
		(pad "1" smd circle
			(at 0.40005 0 270)
			(size 0 0)
			(layers "B.Cu" "B.Mask" "B.Paste")
			(net "P1V8_AUX")
		)
		(pad "2" smd circle
			(at -0.40005 0 270)
			(size 0 0)
			(layers "B.Cu" "B.Mask" "B.Paste")
			(net "GND")
		)
	)
	(footprint ""
		(layer "B.Cu")
		(at 527.561048 -24.162512)
		(property "Reference" "DB16"
			(at 2.586228 -5.512308 270)
			(unlocked yes)
			(layer "B.SilkS")
			(effects
				(font
					(size 0.7874 0.5842)
					(thickness 0.1524)
				)
				(justify left mirror)
			)
		)
		(property "Value" ""
			(at 0 0 0)
			(layer "B.Fab")
			(effects
				(font
					(size 1.27 1.27)
				)
				(justify mirror)
			)
		)
		(duplicate_pad_numbers_are_jumpers no)
		(fp_line
			(start -3.330702 -4.771136)
			(end 0 4.011168)
			(stroke
				(width 0.1524)
				(type default)
			)
			(layer "B.SilkS")
		)
		(fp_line
			(start 0 4.011168)
			(end 3.330702 -4.771136)
			(stroke
				(width 0.1524)
				(type default)
			)
			(layer "B.SilkS")
		)
		(fp_line
			(start 3.330702 -4.771136)
			(end -3.330702 -4.771136)
			(stroke
				(width 0.1524)
				(type default)
			)
			(layer "B.SilkS")
		)
		(fp_line
			(start -3.330702 -4.771136)
			(end 0 4.011168)
			(stroke
				(width 0.1)
				(type default)
			)
			(layer "B.Fab")
		)
		(fp_line
			(start 0 4.011168)
			(end 3.330702 -4.771136)
			(stroke
				(width 0.1)
				(type default)
			)
			(layer "B.Fab")
		)
		(fp_line
			(start 3.330702 -4.771136)
			(end -3.330702 -4.771136)
			(stroke
				(width 0.1)
				(type default)
			)
			(layer "B.Fab")
		)
		(pad "1" thru_hole circle
			(at 0 0 180)
			(size 2.159 2.159)
			(drill 1.7018)
			(layers "*.Cu" "*.Mask")
			(remove_unused_layers no)
			(net "T1_GND")
			(clearance 0.0254)
			(thermal_gap 0.0254)
		)
		(pad "2" thru_hole circle
			(at 1.27 -3.348736 180)
			(size 2.159 2.159)
			(drill 1.7018)
			(layers "*.Cu" "*.Mask")
			(remove_unused_layers no)
			(net "TDR_SE_50_OHM_IN6")
			(clearance 0.0254)
			(thermal_gap 0.0254)
		)
		(pad "3" thru_hole circle
			(at -1.27 -3.348736 180)
			(size 2.159 2.159)
			(drill 1.7018)
			(layers "*.Cu" "*.Mask")
			(remove_unused_layers no)
			(net "TDR_SE_50_OHM_IN6")
			(clearance 0.0254)
			(thermal_gap 0.0254)
		)
	)
	(footprint ""
		(layer "B.Cu")
		(at 400.13509 -176.111916 90)
		(property "Reference" "PR356"
			(at 0 0 90)
			(layer "B.SilkS")
			(hide yes)
			(effects
				(font
					(size 1.27 1.27)
				)
				(justify mirror)
			)
		)
		(property "Value" ""
			(at 0 0 90)
			(layer "B.Fab")
			(effects
				(font
					(size 1.27 1.27)
				)
				(justify mirror)
			)
		)
		(duplicate_pad_numbers_are_jumpers no)
		(fp_line
			(start 0.7874 -0.4064)
			(end -0.7874 -0.4064)
			(stroke
				(width 0.1524)
				(type default)
			)
			(layer "B.SilkS")
		)
		(fp_line
			(start -0.7874 -0.4064)
			(end -0.7874 0.4064)
			(stroke
				(width 0.1524)
				(type default)
			)
			(layer "B.SilkS")
		)
		(fp_line
			(start 0.7874 0.4064)
			(end 0.7874 -0.4064)
			(stroke
				(width 0.1524)
				(type default)
			)
			(layer "B.SilkS")
		)
		(fp_line
			(start -0.7874 0.4064)
			(end 0.7874 0.4064)
			(stroke
				(width 0.1524)
				(type default)
			)
			(layer "B.SilkS")
		)
		(fp_line
			(start 0.67945 -0.305054)
			(end 0.12065 -0.305054)
			(stroke
				(width 0.1)
				(type default)
			)
			(layer "B.Fab")
		)
		(fp_line
			(start 0.12065 -0.305054)
			(end 0.12065 -0.2794)
			(stroke
				(width 0.1)
				(type default)
			)
			(layer "B.Fab")
		)
		(fp_line
			(start -0.12065 -0.3048)
			(end -0.67945 -0.3048)
			(stroke
				(width 0.1)
				(type default)
			)
			(layer "B.Fab")
		)
		(fp_line
			(start -0.67945 -0.3048)
			(end -0.67945 0.3048)
			(stroke
				(width 0.1)
				(type default)
			)
			(layer "B.Fab")
		)
		(fp_line
			(start 0.12065 -0.2794)
			(end -0.12065 -0.2794)
			(stroke
				(width 0.1)
				(type default)
			)
			(layer "B.Fab")
		)
		(fp_line
			(start -0.12065 -0.2794)
			(end -0.12065 -0.3048)
			(stroke
				(width 0.1)
				(type default)
			)
			(layer "B.Fab")
		)
		(fp_line
			(start 0.12065 0.2794)
			(end 0.12065 0.3048)
			(stroke
				(width 0.1)
				(type default)
			)
			(layer "B.Fab")
		)
		(fp_line
			(start -0.120396 0.2794)
			(end 0.12065 0.2794)
			(stroke
				(width 0.1)
				(type default)
			)
			(layer "B.Fab")
		)
		(fp_line
			(start 0.67945 0.3048)
			(end 0.67945 -0.305054)
			(stroke
				(width 0.1)
				(type default)
			)
			(layer "B.Fab")
		)
		(fp_line
			(start 0.12065 0.3048)
			(end 0.67945 0.3048)
			(stroke
				(width 0.1)
				(type default)
			)
			(layer "B.Fab")
		)
		(fp_line
			(start -0.120396 0.3048)
			(end -0.120396 0.2794)
			(stroke
				(width 0.1)
				(type default)
			)
			(layer "B.Fab")
		)
		(fp_line
			(start -0.67945 0.3048)
			(end -0.120396 0.3048)
			(stroke
				(width 0.1)
				(type default)
			)
			(layer "B.Fab")
		)
		(pad "1" smd circle
			(at 0.40005 0 270)
			(size 0 0)
			(layers "B.Cu" "B.Mask" "B.Paste")
			(net "PVDDCR_CPU0_P0_PVCC")
		)
		(pad "2" smd circle
			(at -0.40005 0 270)
			(size 0 0)
			(layers "B.Cu" "B.Mask" "B.Paste")
			(net "PVDDCR_SOC_P0_VCC1")
		)
	)
	(footprint ""
		(layer "B.Cu")
		(at 428.98695 -33.467548 180)
		(property "Reference" "R1357"
			(at 0 0 0)
			(layer "B.SilkS")
			(hide yes)
			(effects
				(font
					(size 1.27 1.27)
				)
				(justify mirror)
			)
		)
		(property "Value" ""
			(at 0 0 0)
			(layer "B.Fab")
			(effects
				(font
					(size 1.27 1.27)
				)
				(justify mirror)
			)
		)
		(duplicate_pad_numbers_are_jumpers no)
		(fp_line
			(start 0.7874 0.4064)
			(end 0.7874 -0.4064)
			(stroke
				(width 0.1524)
				(type default)
			)
			(layer "B.SilkS")
		)
		(fp_line
			(start 0.7874 -0.4064)
			(end -0.7874 -0.4064)
			(stroke
				(width 0.1524)
				(type default)
			)
			(layer "B.SilkS")
		)
		(fp_line
			(start -0.7874 0.4064)
			(end 0.7874 0.4064)
			(stroke
				(width 0.1524)
				(type default)
			)
			(layer "B.SilkS")
		)
		(fp_line
			(start -0.7874 -0.4064)
			(end -0.7874 0.4064)
			(stroke
				(width 0.1524)
				(type default)
			)
			(layer "B.SilkS")
		)
		(fp_line
			(start 0.67945 0.3048)
			(end 0.67945 -0.305054)
			(stroke
				(width 0.1)
				(type default)
			)
			(layer "B.Fab")
		)
		(fp_line
			(start 0.67945 -0.305054)
			(end 0.12065 -0.305054)
			(stroke
				(width 0.1)
				(type default)
			)
			(layer "B.Fab")
		)
		(fp_line
			(start 0.12065 0.3048)
			(end 0.67945 0.3048)
			(stroke
				(width 0.1)
				(type default)
			)
			(layer "B.Fab")
		)
		(fp_line
			(start 0.12065 0.2794)
			(end 0.12065 0.3048)
			(stroke
				(width 0.1)
				(type default)
			)
			(layer "B.Fab")
		)
		(fp_line
			(start 0.12065 -0.2794)
			(end -0.12065 -0.2794)
			(stroke
				(width 0.1)
				(type default)
			)
			(layer "B.Fab")
		)
		(fp_line
			(start 0.12065 -0.305054)
			(end 0.12065 -0.2794)
			(stroke
				(width 0.1)
				(type default)
			)
			(layer "B.Fab")
		)
		(fp_line
			(start -0.120396 0.3048)
			(end -0.120396 0.2794)
			(stroke
				(width 0.1)
				(type default)
			)
			(layer "B.Fab")
		)
		(fp_line
			(start -0.120396 0.2794)
			(end 0.12065 0.2794)
			(stroke
				(width 0.1)
				(type default)
			)
			(layer "B.Fab")
		)
		(fp_line
			(start -0.12065 -0.2794)
			(end -0.12065 -0.3048)
			(stroke
				(width 0.1)
				(type default)
			)
			(layer "B.Fab")
		)
		(fp_line
			(start -0.12065 -0.3048)
			(end -0.67945 -0.3048)
			(stroke
				(width 0.1)
				(type default)
			)
			(layer "B.Fab")
		)
		(fp_line
			(start -0.67945 0.3048)
			(end -0.120396 0.3048)
			(stroke
				(width 0.1)
				(type default)
			)
			(layer "B.Fab")
		)
		(fp_line
			(start -0.67945 -0.3048)
			(end -0.67945 0.3048)
			(stroke
				(width 0.1)
				(type default)
			)
			(layer "B.Fab")
		)
		(pad "1" smd circle
			(at 0.40005 0)
			(size 0 0)
			(layers "B.Cu" "B.Mask" "B.Paste")
			(net "P3V3_AUX")
		)
		(pad "2" smd circle
			(at -0.40005 0)
			(size 0 0)
			(layers "B.Cu" "B.Mask" "B.Paste")
			(net "FM_PRSNT_CPU1_N")
		)
	)
	(footprint ""
		(layer "B.Cu")
		(at 308.080664 -73.534778)
		(property "Reference" "Q6000"
			(at 1.4224 -1.768348 0)
			(unlocked yes)
			(layer "B.SilkS")
			(effects
				(font
					(size 0.7874 0.5842)
					(thickness 0.1524)
				)
				(justify left mirror)
			)
		)
		(property "Value" ""
			(at 0 0 0)
			(layer "B.Fab")
			(effects
				(font
					(size 1.27 1.27)
				)
				(justify mirror)
			)
		)
		(duplicate_pad_numbers_are_jumpers no)
		(fp_line
			(start -1.332738 -1.100074)
			(end -1.332738 1.100074)
			(stroke
				(width 0.1524)
				(type default)
			)
			(layer "B.SilkS")
		)
		(fp_line
			(start -1.332738 1.100074)
			(end 1.332738 1.100074)
			(stroke
				(width 0.1524)
				(type default)
			)
			(layer "B.SilkS")
		)
		(fp_line
			(start -0.4826 -1.100074)
			(end -1.332738 -1.100074)
			(stroke
				(width 0.1524)
				(type default)
			)
			(layer "B.SilkS")
		)
		(fp_line
			(start 0 -0.541274)
			(end -0.4826 -1.100074)
			(stroke
				(width 0.1524)
				(type default)
			)
			(layer "B.SilkS")
		)
		(fp_line
			(start 0.4826 -1.100074)
			(end 0 -0.541274)
			(stroke
				(width 0.1524)
				(type default)
			)
			(layer "B.SilkS")
		)
		(fp_line
			(start 1.332738 -1.100074)
			(end 0.4826 -1.100074)
			(stroke
				(width 0.1524)
				(type default)
			)
			(layer "B.SilkS")
		)
		(fp_line
			(start 1.332738 1.100074)
			(end 1.332738 -1.100074)
			(stroke
				(width 0.1524)
				(type default)
			)
			(layer "B.SilkS")
		)
		(fp_poly
			(pts
				(xy 1.334516 -0.672084) (xy 2.036572 -1.023112) (xy 2.036572 -0.321056)
			)
			(stroke
				(width 0)
				(type default)
			)
			(fill yes)
			(layer "B.SilkS")
		)
		(fp_line
			(start -0.674878 -1.100074)
			(end -0.674878 1.100074)
			(stroke
				(width 0.1)
				(type default)
			)
			(layer "B.Fab")
		)
		(fp_line
			(start -0.674878 1.100074)
			(end 0.674878 1.100074)
			(stroke
				(width 0.1)
				(type default)
			)
			(layer "B.Fab")
		)
		(fp_line
			(start 0.674878 -1.100074)
			(end -0.674878 -1.100074)
			(stroke
				(width 0.1)
				(type default)
			)
			(layer "B.Fab")
		)
		(fp_line
			(start 0.674878 1.100074)
			(end 0.674878 -1.100074)
			(stroke
				(width 0.1)
				(type default)
			)
			(layer "B.Fab")
		)
		(fp_poly
			(pts
				(xy 2.2352 -0.298958) (xy 2.2352 -1.001014) (xy 1.533144 -0.649986)
			)
			(stroke
				(width 0)
				(type default)
			)
			(fill yes)
			(layer "B.Fab")
		)
		(pad "1" smd rect
			(at 0.94996 -0.649986 90)
			(size 0.4318 0.508)
			(layers "B.Cu" "B.Mask" "B.Paste")
			(net "GND")
		)
		(pad "2" smd rect
			(at 0.94996 0 90)
			(size 0.4318 0.508)
			(layers "B.Cu" "B.Mask" "B.Paste")
			(net "PWRGD_P1V2_AUX_R")
		)
		(pad "3" smd rect
			(at 0.94996 0.649986 90)
			(size 0.4318 0.508)
			(layers "B.Cu" "B.Mask" "B.Paste")
			(net "Net_10797")
		)
		(pad "4" smd rect
			(at -0.94996 0.649986 90)
			(size 0.4318 0.508)
			(layers "B.Cu" "B.Mask" "B.Paste")
			(net "Net_10795")
		)
		(pad "5" smd rect
			(at -0.94996 0 90)
			(size 0.4318 0.508)
			(layers "B.Cu" "B.Mask" "B.Paste")
			(net "Net_10796")
		)
		(pad "6" smd rect
			(at -0.94996 -0.649986 90)
			(size 0.4318 0.508)
			(layers "B.Cu" "B.Mask" "B.Paste")
			(net "LED_PWRGD_P1V2_AUX_D")
		)
	)
	(footprint ""
		(layer "B.Cu")
		(at 21.70811 -192.66027)
		(property "Reference" "C527"
			(at 0 0 0)
			(layer "B.SilkS")
			(hide yes)
			(effects
				(font
					(size 1.27 1.27)
				)
				(justify mirror)
			)
		)
		(property "Value" ""
			(at 0 0 0)
			(layer "B.Fab")
			(effects
				(font
					(size 1.27 1.27)
				)
				(justify mirror)
			)
		)
		(duplicate_pad_numbers_are_jumpers no)
		(fp_line
			(start -1.524 -0.762)
			(end -1.524 0.762)
			(stroke
				(width 0.1524)
				(type default)
			)
			(layer "B.SilkS")
		)
		(fp_line
			(start -1.524 0.762)
			(end 1.524 0.762)
			(stroke
				(width 0.1524)
				(type default)
			)
			(layer "B.SilkS")
		)
		(fp_line
			(start 1.524 -0.762)
			(end -1.524 -0.762)
			(stroke
				(width 0.1524)
				(type default)
			)
			(layer "B.SilkS")
		)
		(fp_line
			(start 1.524 0.762)
			(end 1.524 -0.762)
			(stroke
				(width 0.1524)
				(type default)
			)
			(layer "B.SilkS")
		)
		(fp_line
			(start -1.1049 -0.724916)
			(end 1.1049 -0.724916)
			(stroke
				(width 0.1)
				(type default)
			)
			(layer "B.Fab")
		)
		(fp_line
			(start -1.1049 0.724916)
			(end -1.1049 -0.724916)
			(stroke
				(width 0.1)
				(type default)
			)
			(layer "B.Fab")
		)
		(fp_line
			(start 1.1049 -0.724916)
			(end 1.1049 0.724916)
			(stroke
				(width 0.1)
				(type default)
			)
			(layer "B.Fab")
		)
		(fp_line
			(start 1.1049 0.724916)
			(end -1.1049 0.724916)
			(stroke
				(width 0.1)
				(type default)
			)
			(layer "B.Fab")
		)
		(pad "1" smd rect
			(at 0.889 0)
			(size 1.016 1.27)
			(layers "B.Cu" "B.Mask" "B.Paste")
			(net "P12V_MEM_CPU1")
		)
		(pad "2" smd rect
			(at -0.889 0)
			(size 1.016 1.27)
			(layers "B.Cu" "B.Mask" "B.Paste")
			(net "GND")
		)
	)
	(footprint ""
		(layer "B.Cu")
		(at 150.618952 -390.560052 90)
		(property "Reference" "C429"
			(at 0 0 90)
			(layer "B.SilkS")
			(hide yes)
			(effects
				(font
					(size 1.27 1.27)
				)
				(justify mirror)
			)
		)
		(property "Value" ""
			(at 0 0 90)
			(layer "B.Fab")
			(effects
				(font
					(size 1.27 1.27)
				)
				(justify mirror)
			)
		)
		(duplicate_pad_numbers_are_jumpers no)
		(fp_line
			(start 0.7874 -0.4064)
			(end -0.7874 -0.4064)
			(stroke
				(width 0.1524)
				(type default)
			)
			(layer "B.SilkS")
		)
		(fp_line
			(start -0.7874 -0.4064)
			(end -0.7874 0.4064)
			(stroke
				(width 0.1524)
				(type default)
			)
			(layer "B.SilkS")
		)
		(fp_line
			(start 0.7874 0.4064)
			(end 0.7874 -0.4064)
			(stroke
				(width 0.1524)
				(type default)
			)
			(layer "B.SilkS")
		)
		(fp_line
			(start -0.7874 0.4064)
			(end 0.7874 0.4064)
			(stroke
				(width 0.1524)
				(type default)
			)
			(layer "B.SilkS")
		)
		(fp_line
			(start 0.67945 -0.305054)
			(end 0.12065 -0.305054)
			(stroke
				(width 0.1)
				(type default)
			)
			(layer "B.Fab")
		)
		(fp_line
			(start 0.12065 -0.305054)
			(end 0.12065 -0.2794)
			(stroke
				(width 0.1)
				(type default)
			)
			(layer "B.Fab")
		)
		(fp_line
			(start -0.12065 -0.3048)
			(end -0.67945 -0.3048)
			(stroke
				(width 0.1)
				(type default)
			)
			(layer "B.Fab")
		)
		(fp_line
			(start -0.67945 -0.3048)
			(end -0.67945 0.3048)
			(stroke
				(width 0.1)
				(type default)
			)
			(layer "B.Fab")
		)
		(fp_line
			(start 0.12065 -0.2794)
			(end -0.12065 -0.2794)
			(stroke
				(width 0.1)
				(type default)
			)
			(layer "B.Fab")
		)
		(fp_line
			(start -0.12065 -0.2794)
			(end -0.12065 -0.3048)
			(stroke
				(width 0.1)
				(type default)
			)
			(layer "B.Fab")
		)
		(fp_line
			(start 0.12065 0.2794)
			(end 0.12065 0.3048)
			(stroke
				(width 0.1)
				(type default)
			)
			(layer "B.Fab")
		)
		(fp_line
			(start -0.120396 0.2794)
			(end 0.12065 0.2794)
			(stroke
				(width 0.1)
				(type default)
			)
			(layer "B.Fab")
		)
		(fp_line
			(start 0.67945 0.3048)
			(end 0.67945 -0.305054)
			(stroke
				(width 0.1)
				(type default)
			)
			(layer "B.Fab")
		)
		(fp_line
			(start 0.12065 0.3048)
			(end 0.67945 0.3048)
			(stroke
				(width 0.1)
				(type default)
			)
			(layer "B.Fab")
		)
		(fp_line
			(start -0.120396 0.3048)
			(end -0.120396 0.2794)
			(stroke
				(width 0.1)
				(type default)
			)
			(layer "B.Fab")
		)
		(fp_line
			(start -0.67945 0.3048)
			(end -0.120396 0.3048)
			(stroke
				(width 0.1)
				(type default)
			)
			(layer "B.Fab")
		)
		(pad "1" smd circle
			(at 0.40005 0 270)
			(size 0 0)
			(layers "B.Cu" "B.Mask" "B.Paste")
			(net "P0V9_CPU1_RT2_2A")
		)
		(pad "2" smd circle
			(at -0.40005 0 270)
			(size 0 0)
			(layers "B.Cu" "B.Mask" "B.Paste")
			(net "GND")
		)
	)
	(footprint ""
		(layer "B.Cu")
		(at 126.375668 -36.46043)
		(property "Reference" "C6073"
			(at 0 0 0)
			(layer "B.SilkS")
			(hide yes)
			(effects
				(font
					(size 1.27 1.27)
				)
				(justify mirror)
			)
		)
		(property "Value" ""
			(at 0 0 0)
			(layer "B.Fab")
			(effects
				(font
					(size 1.27 1.27)
				)
				(justify mirror)
			)
		)
		(duplicate_pad_numbers_are_jumpers no)
		(fp_line
			(start -0.7874 -0.4064)
			(end -0.7874 0.4064)
			(stroke
				(width 0.1524)
				(type default)
			)
			(layer "B.SilkS")
		)
		(fp_line
			(start -0.7874 0.4064)
			(end 0.7874 0.4064)
			(stroke
				(width 0.1524)
				(type default)
			)
			(layer "B.SilkS")
		)
		(fp_line
			(start 0.7874 -0.4064)
			(end -0.7874 -0.4064)
			(stroke
				(width 0.1524)
				(type default)
			)
			(layer "B.SilkS")
		)
		(fp_line
			(start 0.7874 0.4064)
			(end 0.7874 -0.4064)
			(stroke
				(width 0.1524)
				(type default)
			)
			(layer "B.SilkS")
		)
		(fp_line
			(start -0.67945 -0.3048)
			(end -0.67945 0.3048)
			(stroke
				(width 0.1)
				(type default)
			)
			(layer "B.Fab")
		)
		(fp_line
			(start -0.67945 0.3048)
			(end -0.120396 0.3048)
			(stroke
				(width 0.1)
				(type default)
			)
			(layer "B.Fab")
		)
		(fp_line
			(start -0.12065 -0.3048)
			(end -0.67945 -0.3048)
			(stroke
				(width 0.1)
				(type default)
			)
			(layer "B.Fab")
		)
		(fp_line
			(start -0.12065 -0.2794)
			(end -0.12065 -0.3048)
			(stroke
				(width 0.1)
				(type default)
			)
			(layer "B.Fab")
		)
		(fp_line
			(start -0.120396 0.2794)
			(end 0.12065 0.2794)
			(stroke
				(width 0.1)
				(type default)
			)
			(layer "B.Fab")
		)
		(fp_line
			(start -0.120396 0.3048)
			(end -0.120396 0.2794)
			(stroke
				(width 0.1)
				(type default)
			)
			(layer "B.Fab")
		)
		(fp_line
			(start 0.12065 -0.305054)
			(end 0.12065 -0.2794)
			(stroke
				(width 0.1)
				(type default)
			)
			(layer "B.Fab")
		)
		(fp_line
			(start 0.12065 -0.2794)
			(end -0.12065 -0.2794)
			(stroke
				(width 0.1)
				(type default)
			)
			(layer "B.Fab")
		)
		(fp_line
			(start 0.12065 0.2794)
			(end 0.12065 0.3048)
			(stroke
				(width 0.1)
				(type default)
			)
			(layer "B.Fab")
		)
		(fp_line
			(start 0.12065 0.3048)
			(end 0.67945 0.3048)
			(stroke
				(width 0.1)
				(type default)
			)
			(layer "B.Fab")
		)
		(fp_line
			(start 0.67945 -0.305054)
			(end 0.12065 -0.305054)
			(stroke
				(width 0.1)
				(type default)
			)
			(layer "B.Fab")
		)
		(fp_line
			(start 0.67945 0.3048)
			(end 0.67945 -0.305054)
			(stroke
				(width 0.1)
				(type default)
			)
			(layer "B.Fab")
		)
		(pad "1" smd circle
			(at 0.40005 0 180)
			(size 0 0)
			(layers "B.Cu" "B.Mask" "B.Paste")
			(net "P1V2_AUX")
		)
		(pad "2" smd circle
			(at -0.40005 0 180)
			(size 0 0)
			(layers "B.Cu" "B.Mask" "B.Paste")
			(net "GND")
		)
	)
	(footprint ""
		(layer "B.Cu")
		(at 313.734958 -201.926952 90)
		(property "Reference" "R28"
			(at 0 0 90)
			(layer "B.SilkS")
			(hide yes)
			(effects
				(font
					(size 1.27 1.27)
				)
				(justify mirror)
			)
		)
		(property "Value" ""
			(at 0 0 90)
			(layer "B.Fab")
			(effects
				(font
					(size 1.27 1.27)
				)
				(justify mirror)
			)
		)
		(duplicate_pad_numbers_are_jumpers no)
		(fp_line
			(start 0.7874 -0.4064)
			(end -0.7874 -0.4064)
			(stroke
				(width 0.1524)
				(type default)
			)
			(layer "B.SilkS")
		)
		(fp_line
			(start -0.7874 -0.4064)
			(end -0.7874 0.4064)
			(stroke
				(width 0.1524)
				(type default)
			)
			(layer "B.SilkS")
		)
		(fp_line
			(start 0.7874 0.4064)
			(end 0.7874 -0.4064)
			(stroke
				(width 0.1524)
				(type default)
			)
			(layer "B.SilkS")
		)
		(fp_line
			(start -0.7874 0.4064)
			(end 0.7874 0.4064)
			(stroke
				(width 0.1524)
				(type default)
			)
			(layer "B.SilkS")
		)
		(fp_line
			(start 0.67945 -0.305054)
			(end 0.12065 -0.305054)
			(stroke
				(width 0.1)
				(type default)
			)
			(layer "B.Fab")
		)
		(fp_line
			(start 0.12065 -0.305054)
			(end 0.12065 -0.2794)
			(stroke
				(width 0.1)
				(type default)
			)
			(layer "B.Fab")
		)
		(fp_line
			(start -0.12065 -0.3048)
			(end -0.67945 -0.3048)
			(stroke
				(width 0.1)
				(type default)
			)
			(layer "B.Fab")
		)
		(fp_line
			(start -0.67945 -0.3048)
			(end -0.67945 0.3048)
			(stroke
				(width 0.1)
				(type default)
			)
			(layer "B.Fab")
		)
		(fp_line
			(start 0.12065 -0.2794)
			(end -0.12065 -0.2794)
			(stroke
				(width 0.1)
				(type default)
			)
			(layer "B.Fab")
		)
		(fp_line
			(start -0.12065 -0.2794)
			(end -0.12065 -0.3048)
			(stroke
				(width 0.1)
				(type default)
			)
			(layer "B.Fab")
		)
		(fp_line
			(start 0.12065 0.2794)
			(end 0.12065 0.3048)
			(stroke
				(width 0.1)
				(type default)
			)
			(layer "B.Fab")
		)
		(fp_line
			(start -0.120396 0.2794)
			(end 0.12065 0.2794)
			(stroke
				(width 0.1)
				(type default)
			)
			(layer "B.Fab")
		)
		(fp_line
			(start 0.67945 0.3048)
			(end 0.67945 -0.305054)
			(stroke
				(width 0.1)
				(type default)
			)
			(layer "B.Fab")
		)
		(fp_line
			(start 0.12065 0.3048)
			(end 0.67945 0.3048)
			(stroke
				(width 0.1)
				(type default)
			)
			(layer "B.Fab")
		)
		(fp_line
			(start -0.120396 0.3048)
			(end -0.120396 0.2794)
			(stroke
				(width 0.1)
				(type default)
			)
			(layer "B.Fab")
		)
		(fp_line
			(start -0.67945 0.3048)
			(end -0.120396 0.3048)
			(stroke
				(width 0.1)
				(type default)
			)
			(layer "B.Fab")
		)
		(pad "1" smd circle
			(at 0.40005 0 270)
			(size 0 0)
			(layers "B.Cu" "B.Mask" "B.Paste")
			(net "SMB_CPU0_2_R_SDA")
		)
		(pad "2" smd circle
			(at -0.40005 0 270)
			(size 0 0)
			(layers "B.Cu" "B.Mask" "B.Paste")
			(net "SMB_CPU0_2_SDA")
		)
	)
	(footprint ""
		(layer "B.Cu")
		(at 234.286298 -213.258654 180)
		(property "Reference" "R281"
			(at 0 0 0)
			(layer "B.SilkS")
			(hide yes)
			(effects
				(font
					(size 1.27 1.27)
				)
				(justify mirror)
			)
		)
		(property "Value" ""
			(at 0 0 0)
			(layer "B.Fab")
			(effects
				(font
					(size 1.27 1.27)
				)
				(justify mirror)
			)
		)
		(duplicate_pad_numbers_are_jumpers no)
		(fp_line
			(start 0.7874 0.4064)
			(end 0.7874 -0.4064)
			(stroke
				(width 0.1524)
				(type default)
			)
			(layer "B.SilkS")
		)
		(fp_line
			(start 0.7874 -0.4064)
			(end -0.7874 -0.4064)
			(stroke
				(width 0.1524)
				(type default)
			)
			(layer "B.SilkS")
		)
		(fp_line
			(start -0.7874 0.4064)
			(end 0.7874 0.4064)
			(stroke
				(width 0.1524)
				(type default)
			)
			(layer "B.SilkS")
		)
		(fp_line
			(start -0.7874 -0.4064)
			(end -0.7874 0.4064)
			(stroke
				(width 0.1524)
				(type default)
			)
			(layer "B.SilkS")
		)
		(fp_line
			(start 0.67945 0.3048)
			(end 0.67945 -0.305054)
			(stroke
				(width 0.1)
				(type default)
			)
			(layer "B.Fab")
		)
		(fp_line
			(start 0.67945 -0.305054)
			(end 0.12065 -0.305054)
			(stroke
				(width 0.1)
				(type default)
			)
			(layer "B.Fab")
		)
		(fp_line
			(start 0.12065 0.3048)
			(end 0.67945 0.3048)
			(stroke
				(width 0.1)
				(type default)
			)
			(layer "B.Fab")
		)
		(fp_line
			(start 0.12065 0.2794)
			(end 0.12065 0.3048)
			(stroke
				(width 0.1)
				(type default)
			)
			(layer "B.Fab")
		)
		(fp_line
			(start 0.12065 -0.2794)
			(end -0.12065 -0.2794)
			(stroke
				(width 0.1)
				(type default)
			)
			(layer "B.Fab")
		)
		(fp_line
			(start 0.12065 -0.305054)
			(end 0.12065 -0.2794)
			(stroke
				(width 0.1)
				(type default)
			)
			(layer "B.Fab")
		)
		(fp_line
			(start -0.120396 0.3048)
			(end -0.120396 0.2794)
			(stroke
				(width 0.1)
				(type default)
			)
			(layer "B.Fab")
		)
		(fp_line
			(start -0.120396 0.2794)
			(end 0.12065 0.2794)
			(stroke
				(width 0.1)
				(type default)
			)
			(layer "B.Fab")
		)
		(fp_line
			(start -0.12065 -0.2794)
			(end -0.12065 -0.3048)
			(stroke
				(width 0.1)
				(type default)
			)
			(layer "B.Fab")
		)
		(fp_line
			(start -0.12065 -0.3048)
			(end -0.67945 -0.3048)
			(stroke
				(width 0.1)
				(type default)
			)
			(layer "B.Fab")
		)
		(fp_line
			(start -0.67945 0.3048)
			(end -0.120396 0.3048)
			(stroke
				(width 0.1)
				(type default)
			)
			(layer "B.Fab")
		)
		(fp_line
			(start -0.67945 -0.3048)
			(end -0.67945 0.3048)
			(stroke
				(width 0.1)
				(type default)
			)
			(layer "B.Fab")
		)
		(pad "1" smd rect
			(at 0.40005 0 180)
			(size 0.4572 0.508)
			(layers "B.Cu" "B.Mask" "B.Paste")
			(net "SMB_CPU0_CPU1_APML_BUF2_SDA_R2")
		)
		(pad "2" smd rect
			(at -0.40005 0 180)
			(size 0.4572 0.508)
			(layers "B.Cu" "B.Mask" "B.Paste")
			(net "SMB_CPU0_CPU1_APML_SDA_R2")
		)
	)
	(footprint ""
		(layer "B.Cu")
		(at 118.218458 -388.011162 -90)
		(property "Reference" "C477"
			(at 0 0 90)
			(layer "B.SilkS")
			(hide yes)
			(effects
				(font
					(size 1.27 1.27)
				)
				(justify mirror)
			)
		)
		(property "Value" ""
			(at 0 0 90)
			(layer "B.Fab")
			(effects
				(font
					(size 1.27 1.27)
				)
				(justify mirror)
			)
		)
		(duplicate_pad_numbers_are_jumpers no)
		(fp_line
			(start -0.299974 0.150114)
			(end 0.299974 0.150114)
			(stroke
				(width 0.1)
				(type default)
			)
			(layer "B.Fab")
		)
		(fp_line
			(start 0.299974 0.150114)
			(end 0.299974 -0.150114)
			(stroke
				(width 0.1)
				(type default)
			)
			(layer "B.Fab")
		)
		(fp_line
			(start -0.299974 -0.150114)
			(end -0.299974 0.150114)
			(stroke
				(width 0.1)
				(type default)
			)
			(layer "B.Fab")
		)
		(fp_line
			(start 0.299974 -0.150114)
			(end -0.299974 -0.150114)
			(stroke
				(width 0.1)
				(type default)
			)
			(layer "B.Fab")
		)
		(pad "1" smd rect
			(at 0.2667 0 90)
			(size 0.3048 0.381)
			(layers "B.Cu" "B.Mask" "B.Paste")
			(net "P0V9_CPU1_RT3_2A")
		)
		(pad "2" smd rect
			(at -0.2667 0 90)
			(size 0.3048 0.381)
			(layers "B.Cu" "B.Mask" "B.Paste")
			(net "GND")
		)
	)
	(footprint ""
		(layer "B.Cu")
		(at 345.51874 -398.942052 90)
		(property "Reference" "C595"
			(at 0 0 90)
			(layer "B.SilkS")
			(hide yes)
			(effects
				(font
					(size 1.27 1.27)
				)
				(justify mirror)
			)
		)
		(property "Value" ""
			(at 0 0 90)
			(layer "B.Fab")
			(effects
				(font
					(size 1.27 1.27)
				)
				(justify mirror)
			)
		)
		(duplicate_pad_numbers_are_jumpers no)
		(fp_line
			(start 0.7874 -0.4064)
			(end -0.7874 -0.4064)
			(stroke
				(width 0.1524)
				(type default)
			)
			(layer "B.SilkS")
		)
		(fp_line
			(start -0.7874 -0.4064)
			(end -0.7874 0.4064)
			(stroke
				(width 0.1524)
				(type default)
			)
			(layer "B.SilkS")
		)
		(fp_line
			(start 0.7874 0.4064)
			(end 0.7874 -0.4064)
			(stroke
				(width 0.1524)
				(type default)
			)
			(layer "B.SilkS")
		)
		(fp_line
			(start -0.7874 0.4064)
			(end 0.7874 0.4064)
			(stroke
				(width 0.1524)
				(type default)
			)
			(layer "B.SilkS")
		)
		(fp_line
			(start 0.67945 -0.305054)
			(end 0.12065 -0.305054)
			(stroke
				(width 0.1)
				(type default)
			)
			(layer "B.Fab")
		)
		(fp_line
			(start 0.12065 -0.305054)
			(end 0.12065 -0.2794)
			(stroke
				(width 0.1)
				(type default)
			)
			(layer "B.Fab")
		)
		(fp_line
			(start -0.12065 -0.3048)
			(end -0.67945 -0.3048)
			(stroke
				(width 0.1)
				(type default)
			)
			(layer "B.Fab")
		)
		(fp_line
			(start -0.67945 -0.3048)
			(end -0.67945 0.3048)
			(stroke
				(width 0.1)
				(type default)
			)
			(layer "B.Fab")
		)
		(fp_line
			(start 0.12065 -0.2794)
			(end -0.12065 -0.2794)
			(stroke
				(width 0.1)
				(type default)
			)
			(layer "B.Fab")
		)
		(fp_line
			(start -0.12065 -0.2794)
			(end -0.12065 -0.3048)
			(stroke
				(width 0.1)
				(type default)
			)
			(layer "B.Fab")
		)
		(fp_line
			(start 0.12065 0.2794)
			(end 0.12065 0.3048)
			(stroke
				(width 0.1)
				(type default)
			)
			(layer "B.Fab")
		)
		(fp_line
			(start -0.120396 0.2794)
			(end 0.12065 0.2794)
			(stroke
				(width 0.1)
				(type default)
			)
			(layer "B.Fab")
		)
		(fp_line
			(start 0.67945 0.3048)
			(end 0.67945 -0.305054)
			(stroke
				(width 0.1)
				(type default)
			)
			(layer "B.Fab")
		)
		(fp_line
			(start 0.12065 0.3048)
			(end 0.67945 0.3048)
			(stroke
				(width 0.1)
				(type default)
			)
			(layer "B.Fab")
		)
		(fp_line
			(start -0.120396 0.3048)
			(end -0.120396 0.2794)
			(stroke
				(width 0.1)
				(type default)
			)
			(layer "B.Fab")
		)
		(fp_line
			(start -0.67945 0.3048)
			(end -0.120396 0.3048)
			(stroke
				(width 0.1)
				(type default)
			)
			(layer "B.Fab")
		)
		(pad "1" smd circle
			(at 0.40005 0 270)
			(size 0 0)
			(layers "B.Cu" "B.Mask" "B.Paste")
			(net "P1V8_CPU0_RT1_1A")
		)
		(pad "2" smd circle
			(at -0.40005 0 270)
			(size 0 0)
			(layers "B.Cu" "B.Mask" "B.Paste")
			(net "GND")
		)
	)
	(footprint ""
		(layer "B.Cu")
		(at 243.713 -325.882 180)
		(property "Reference" "R1228"
			(at 0 0 0)
			(layer "B.SilkS")
			(hide yes)
			(effects
				(font
					(size 1.27 1.27)
				)
				(justify mirror)
			)
		)
		(property "Value" ""
			(at 0 0 0)
			(layer "B.Fab")
			(effects
				(font
					(size 1.27 1.27)
				)
				(justify mirror)
			)
		)
		(duplicate_pad_numbers_are_jumpers no)
		(fp_line
			(start 0.7874 0.4064)
			(end 0.7874 -0.4064)
			(stroke
				(width 0.1524)
				(type default)
			)
			(layer "B.SilkS")
		)
		(fp_line
			(start 0.7874 -0.4064)
			(end -0.7874 -0.4064)
			(stroke
				(width 0.1524)
				(type default)
			)
			(layer "B.SilkS")
		)
		(fp_line
			(start -0.7874 0.4064)
			(end 0.7874 0.4064)
			(stroke
				(width 0.1524)
				(type default)
			)
			(layer "B.SilkS")
		)
		(fp_line
			(start -0.7874 -0.4064)
			(end -0.7874 0.4064)
			(stroke
				(width 0.1524)
				(type default)
			)
			(layer "B.SilkS")
		)
		(fp_line
			(start 0.67945 0.3048)
			(end 0.67945 -0.305054)
			(stroke
				(width 0.1)
				(type default)
			)
			(layer "B.Fab")
		)
		(fp_line
			(start 0.67945 -0.305054)
			(end 0.12065 -0.305054)
			(stroke
				(width 0.1)
				(type default)
			)
			(layer "B.Fab")
		)
		(fp_line
			(start 0.12065 0.3048)
			(end 0.67945 0.3048)
			(stroke
				(width 0.1)
				(type default)
			)
			(layer "B.Fab")
		)
		(fp_line
			(start 0.12065 0.2794)
			(end 0.12065 0.3048)
			(stroke
				(width 0.1)
				(type default)
			)
			(layer "B.Fab")
		)
		(fp_line
			(start 0.12065 -0.2794)
			(end -0.12065 -0.2794)
			(stroke
				(width 0.1)
				(type default)
			)
			(layer "B.Fab")
		)
		(fp_line
			(start 0.12065 -0.305054)
			(end 0.12065 -0.2794)
			(stroke
				(width 0.1)
				(type default)
			)
			(layer "B.Fab")
		)
		(fp_line
			(start -0.120396 0.3048)
			(end -0.120396 0.2794)
			(stroke
				(width 0.1)
				(type default)
			)
			(layer "B.Fab")
		)
		(fp_line
			(start -0.120396 0.2794)
			(end 0.12065 0.2794)
			(stroke
				(width 0.1)
				(type default)
			)
			(layer "B.Fab")
		)
		(fp_line
			(start -0.12065 -0.2794)
			(end -0.12065 -0.3048)
			(stroke
				(width 0.1)
				(type default)
			)
			(layer "B.Fab")
		)
		(fp_line
			(start -0.12065 -0.3048)
			(end -0.67945 -0.3048)
			(stroke
				(width 0.1)
				(type default)
			)
			(layer "B.Fab")
		)
		(fp_line
			(start -0.67945 0.3048)
			(end -0.120396 0.3048)
			(stroke
				(width 0.1)
				(type default)
			)
			(layer "B.Fab")
		)
		(fp_line
			(start -0.67945 -0.3048)
			(end -0.67945 0.3048)
			(stroke
				(width 0.1)
				(type default)
			)
			(layer "B.Fab")
		)
		(pad "1" smd circle
			(at 0.40005 0)
			(size 0 0)
			(layers "B.Cu" "B.Mask" "B.Paste")
			(net "SMB_ADC_SCL_R")
		)
		(pad "2" smd circle
			(at -0.40005 0)
			(size 0 0)
			(layers "B.Cu" "B.Mask" "B.Paste")
			(net "SMB_SEN_MAM_2_3V3AUX_SCL")
		)
	)
	(footprint ""
		(layer "B.Cu")
		(at 380.536958 -208.530952 90)
		(property "Reference" "C208"
			(at 0 0 90)
			(layer "B.SilkS")
			(hide yes)
			(effects
				(font
					(size 1.27 1.27)
				)
				(justify mirror)
			)
		)
		(property "Value" ""
			(at 0 0 90)
			(layer "B.Fab")
			(effects
				(font
					(size 1.27 1.27)
				)
				(justify mirror)
			)
		)
		(duplicate_pad_numbers_are_jumpers no)
		(fp_line
			(start 0.7874 -0.4064)
			(end -0.7874 -0.4064)
			(stroke
				(width 0.1524)
				(type default)
			)
			(layer "B.SilkS")
		)
		(fp_line
			(start -0.7874 -0.4064)
			(end -0.7874 0.4064)
			(stroke
				(width 0.1524)
				(type default)
			)
			(layer "B.SilkS")
		)
		(fp_line
			(start 0.7874 0.4064)
			(end 0.7874 -0.4064)
			(stroke
				(width 0.1524)
				(type default)
			)
			(layer "B.SilkS")
		)
		(fp_line
			(start -0.7874 0.4064)
			(end 0.7874 0.4064)
			(stroke
				(width 0.1524)
				(type default)
			)
			(layer "B.SilkS")
		)
		(fp_line
			(start 0.67945 -0.305054)
			(end 0.12065 -0.305054)
			(stroke
				(width 0.1)
				(type default)
			)
			(layer "B.Fab")
		)
		(fp_line
			(start 0.12065 -0.305054)
			(end 0.12065 -0.2794)
			(stroke
				(width 0.1)
				(type default)
			)
			(layer "B.Fab")
		)
		(fp_line
			(start -0.12065 -0.3048)
			(end -0.67945 -0.3048)
			(stroke
				(width 0.1)
				(type default)
			)
			(layer "B.Fab")
		)
		(fp_line
			(start -0.67945 -0.3048)
			(end -0.67945 0.3048)
			(stroke
				(width 0.1)
				(type default)
			)
			(layer "B.Fab")
		)
		(fp_line
			(start 0.12065 -0.2794)
			(end -0.12065 -0.2794)
			(stroke
				(width 0.1)
				(type default)
			)
			(layer "B.Fab")
		)
		(fp_line
			(start -0.12065 -0.2794)
			(end -0.12065 -0.3048)
			(stroke
				(width 0.1)
				(type default)
			)
			(layer "B.Fab")
		)
		(fp_line
			(start 0.12065 0.2794)
			(end 0.12065 0.3048)
			(stroke
				(width 0.1)
				(type default)
			)
			(layer "B.Fab")
		)
		(fp_line
			(start -0.120396 0.2794)
			(end 0.12065 0.2794)
			(stroke
				(width 0.1)
				(type default)
			)
			(layer "B.Fab")
		)
		(fp_line
			(start 0.67945 0.3048)
			(end 0.67945 -0.305054)
			(stroke
				(width 0.1)
				(type default)
			)
			(layer "B.Fab")
		)
		(fp_line
			(start 0.12065 0.3048)
			(end 0.67945 0.3048)
			(stroke
				(width 0.1)
				(type default)
			)
			(layer "B.Fab")
		)
		(fp_line
			(start -0.120396 0.3048)
			(end -0.120396 0.2794)
			(stroke
				(width 0.1)
				(type default)
			)
			(layer "B.Fab")
		)
		(fp_line
			(start -0.67945 0.3048)
			(end -0.120396 0.3048)
			(stroke
				(width 0.1)
				(type default)
			)
			(layer "B.Fab")
		)
		(pad "1" smd circle
			(at 0.40005 0 270)
			(size 0 0)
			(layers "B.Cu" "B.Mask" "B.Paste")
			(net "JTAG_CPU0_TDI")
		)
		(pad "2" smd circle
			(at -0.40005 0 270)
			(size 0 0)
			(layers "B.Cu" "B.Mask" "B.Paste")
			(net "GND")
		)
	)
	(footprint ""
		(layer "B.Cu")
		(at 175.836834 -343.785952 -90)
		(property "Reference" "PC802"
			(at 7.354316 -3.474466 270)
			(unlocked yes)
			(layer "B.SilkS")
			(effects
				(font
					(size 0.7874 0.5842)
					(thickness 0.1524)
				)
				(justify left mirror)
			)
		)
		(property "Value" ""
			(at 0 0 90)
			(layer "B.Fab")
			(effects
				(font
					(size 1.27 1.27)
				)
				(justify mirror)
			)
		)
		(duplicate_pad_numbers_are_jumpers no)
		(fp_line
			(start -4.533392 2.249932)
			(end 4.533392 2.249932)
			(stroke
				(width 0.1524)
				(type default)
			)
			(layer "B.SilkS")
		)
		(fp_line
			(start 4.533392 2.249932)
			(end 4.533392 -2.249932)
			(stroke
				(width 0.1524)
				(type default)
			)
			(layer "B.SilkS")
		)
		(fp_line
			(start -4.533392 -2.249932)
			(end -4.533392 2.249932)
			(stroke
				(width 0.1524)
				(type default)
			)
			(layer "B.SilkS")
		)
		(fp_line
			(start 4.533392 -2.249932)
			(end -4.533392 -2.249932)
			(stroke
				(width 0.1524)
				(type default)
			)
			(layer "B.SilkS")
		)
		(fp_rect
			(start 5.39242 2.326132)
			(end 4.533392 -2.326132)
			(stroke
				(width 0)
				(type default)
			)
			(fill yes)
			(layer "B.SilkS")
		)
		(fp_line
			(start -3.750056 2.249932)
			(end 3.750056 2.249932)
			(stroke
				(width 0.1)
				(type default)
			)
			(layer "B.Fab")
		)
		(fp_line
			(start 3.750056 2.249932)
			(end 3.750056 -2.249932)
			(stroke
				(width 0.1)
				(type default)
			)
			(layer "B.Fab")
		)
		(fp_line
			(start -3.750056 -2.249932)
			(end -3.750056 2.249932)
			(stroke
				(width 0.1)
				(type default)
			)
			(layer "B.Fab")
		)
		(fp_line
			(start 3.750056 -2.249932)
			(end -3.750056 -2.249932)
			(stroke
				(width 0.1)
				(type default)
			)
			(layer "B.Fab")
		)
		(fp_text user "+"
			(at 6.322314 0.786384 180)
			(unlocked yes)
			(layer "B.SilkS")
			(effects
				(font
					(size 1.905 1.4224)
					(thickness 0.1524)
				)
				(justify left mirror)
			)
		)
		(fp_text user "-"
			(at -4.8514 -0.14605 270)
			(unlocked yes)
			(layer "B.SilkS")
			(effects
				(font
					(size 1.905 1.4224)
					(thickness 0.1524)
				)
				(justify left mirror)
			)
		)
		(fp_text user "+"
			(at 6.322314 0.786384 180)
			(unlocked yes)
			(layer "B.Fab")
			(effects
				(font
					(size 1.905 1.4224)
					(thickness 0.1524)
				)
				(justify left mirror)
			)
		)
		(fp_text user "-"
			(at -4.8514 -0.14605 270)
			(unlocked yes)
			(layer "B.Fab")
			(effects
				(font
					(size 1.905 1.4224)
					(thickness 0.1524)
				)
				(justify left mirror)
			)
		)
		(pad "1" smd rect
			(at 3.199892 0 90)
			(size 2.413 2.8194)
			(layers "B.Cu" "B.Mask" "B.Paste")
			(net "PVDD11_S3_P1")
		)
		(pad "2" smd rect
			(at -3.199892 0 90)
			(size 2.413 2.8194)
			(layers "B.Cu" "B.Mask" "B.Paste")
			(net "GND")
		)
	)
	(footprint ""
		(layer "B.Cu")
		(at 360.367072 -261.747762 90)
		(property "Reference" "C2636"
			(at 0 0 90)
			(layer "B.SilkS")
			(hide yes)
			(effects
				(font
					(size 1.27 1.27)
				)
				(justify mirror)
			)
		)
		(property "Value" ""
			(at 0 0 90)
			(layer "B.Fab")
			(effects
				(font
					(size 1.27 1.27)
				)
				(justify mirror)
			)
		)
		(duplicate_pad_numbers_are_jumpers no)
		(fp_line
			(start 0.7874 -0.4064)
			(end -0.7874 -0.4064)
			(stroke
				(width 0.1524)
				(type default)
			)
			(layer "B.SilkS")
		)
		(fp_line
			(start -0.7874 -0.4064)
			(end -0.7874 0.4064)
			(stroke
				(width 0.1524)
				(type default)
			)
			(layer "B.SilkS")
		)
		(fp_line
			(start 0.7874 0.4064)
			(end 0.7874 -0.4064)
			(stroke
				(width 0.1524)
				(type default)
			)
			(layer "B.SilkS")
		)
		(fp_line
			(start -0.7874 0.4064)
			(end 0.7874 0.4064)
			(stroke
				(width 0.1524)
				(type default)
			)
			(layer "B.SilkS")
		)
		(fp_line
			(start 0.67945 -0.305054)
			(end 0.12065 -0.305054)
			(stroke
				(width 0.1)
				(type default)
			)
			(layer "B.Fab")
		)
		(fp_line
			(start 0.12065 -0.305054)
			(end 0.12065 -0.2794)
			(stroke
				(width 0.1)
				(type default)
			)
			(layer "B.Fab")
		)
		(fp_line
			(start -0.12065 -0.3048)
			(end -0.67945 -0.3048)
			(stroke
				(width 0.1)
				(type default)
			)
			(layer "B.Fab")
		)
		(fp_line
			(start -0.67945 -0.3048)
			(end -0.67945 0.3048)
			(stroke
				(width 0.1)
				(type default)
			)
			(layer "B.Fab")
		)
		(fp_line
			(start 0.12065 -0.2794)
			(end -0.12065 -0.2794)
			(stroke
				(width 0.1)
				(type default)
			)
			(layer "B.Fab")
		)
		(fp_line
			(start -0.12065 -0.2794)
			(end -0.12065 -0.3048)
			(stroke
				(width 0.1)
				(type default)
			)
			(layer "B.Fab")
		)
		(fp_line
			(start 0.12065 0.2794)
			(end 0.12065 0.3048)
			(stroke
				(width 0.1)
				(type default)
			)
			(layer "B.Fab")
		)
		(fp_line
			(start -0.120396 0.2794)
			(end 0.12065 0.2794)
			(stroke
				(width 0.1)
				(type default)
			)
			(layer "B.Fab")
		)
		(fp_line
			(start 0.67945 0.3048)
			(end 0.67945 -0.305054)
			(stroke
				(width 0.1)
				(type default)
			)
			(layer "B.Fab")
		)
		(fp_line
			(start 0.12065 0.3048)
			(end 0.67945 0.3048)
			(stroke
				(width 0.1)
				(type default)
			)
			(layer "B.Fab")
		)
		(fp_line
			(start -0.120396 0.3048)
			(end -0.120396 0.2794)
			(stroke
				(width 0.1)
				(type default)
			)
			(layer "B.Fab")
		)
		(fp_line
			(start -0.67945 0.3048)
			(end -0.120396 0.3048)
			(stroke
				(width 0.1)
				(type default)
			)
			(layer "B.Fab")
		)
		(pad "1" smd circle
			(at 0.40005 0 270)
			(size 0 0)
			(layers "B.Cu" "B.Mask" "B.Paste")
			(net "PVDD11_S3_P0")
		)
		(pad "2" smd circle
			(at -0.40005 0 270)
			(size 0 0)
			(layers "B.Cu" "B.Mask" "B.Paste")
			(net "GND")
		)
	)
	(footprint ""
		(layer "B.Cu")
		(at 373.329454 -257.930142)
		(property "Reference" "C2583"
			(at 0 0 0)
			(layer "B.SilkS")
			(hide yes)
			(effects
				(font
					(size 1.27 1.27)
				)
				(justify mirror)
			)
		)
		(property "Value" ""
			(at 0 0 0)
			(layer "B.Fab")
			(effects
				(font
					(size 1.27 1.27)
				)
				(justify mirror)
			)
		)
		(duplicate_pad_numbers_are_jumpers no)
		(fp_line
			(start -0.7874 -0.4064)
			(end -0.7874 0.4064)
			(stroke
				(width 0.1524)
				(type default)
			)
			(layer "B.SilkS")
		)
		(fp_line
			(start -0.7874 0.4064)
			(end 0.7874 0.4064)
			(stroke
				(width 0.1524)
				(type default)
			)
			(layer "B.SilkS")
		)
		(fp_line
			(start 0.7874 -0.4064)
			(end -0.7874 -0.4064)
			(stroke
				(width 0.1524)
				(type default)
			)
			(layer "B.SilkS")
		)
		(fp_line
			(start 0.7874 0.4064)
			(end 0.7874 -0.4064)
			(stroke
				(width 0.1524)
				(type default)
			)
			(layer "B.SilkS")
		)
		(fp_line
			(start -0.67945 -0.3048)
			(end -0.67945 0.3048)
			(stroke
				(width 0.1)
				(type default)
			)
			(layer "B.Fab")
		)
		(fp_line
			(start -0.67945 0.3048)
			(end -0.120396 0.3048)
			(stroke
				(width 0.1)
				(type default)
			)
			(layer "B.Fab")
		)
		(fp_line
			(start -0.12065 -0.3048)
			(end -0.67945 -0.3048)
			(stroke
				(width 0.1)
				(type default)
			)
			(layer "B.Fab")
		)
		(fp_line
			(start -0.12065 -0.2794)
			(end -0.12065 -0.3048)
			(stroke
				(width 0.1)
				(type default)
			)
			(layer "B.Fab")
		)
		(fp_line
			(start -0.120396 0.2794)
			(end 0.12065 0.2794)
			(stroke
				(width 0.1)
				(type default)
			)
			(layer "B.Fab")
		)
		(fp_line
			(start -0.120396 0.3048)
			(end -0.120396 0.2794)
			(stroke
				(width 0.1)
				(type default)
			)
			(layer "B.Fab")
		)
		(fp_line
			(start 0.12065 -0.305054)
			(end 0.12065 -0.2794)
			(stroke
				(width 0.1)
				(type default)
			)
			(layer "B.Fab")
		)
		(fp_line
			(start 0.12065 -0.2794)
			(end -0.12065 -0.2794)
			(stroke
				(width 0.1)
				(type default)
			)
			(layer "B.Fab")
		)
		(fp_line
			(start 0.12065 0.2794)
			(end 0.12065 0.3048)
			(stroke
				(width 0.1)
				(type default)
			)
			(layer "B.Fab")
		)
		(fp_line
			(start 0.12065 0.3048)
			(end 0.67945 0.3048)
			(stroke
				(width 0.1)
				(type default)
			)
			(layer "B.Fab")
		)
		(fp_line
			(start 0.67945 -0.305054)
			(end 0.12065 -0.305054)
			(stroke
				(width 0.1)
				(type default)
			)
			(layer "B.Fab")
		)
		(fp_line
			(start 0.67945 0.3048)
			(end 0.67945 -0.305054)
			(stroke
				(width 0.1)
				(type default)
			)
			(layer "B.Fab")
		)
		(pad "1" smd circle
			(at 0.40005 0 180)
			(size 0 0)
			(layers "B.Cu" "B.Mask" "B.Paste")
			(net "PVDDCR_SOC_P0")
		)
		(pad "2" smd circle
			(at -0.40005 0 180)
			(size 0 0)
			(layers "B.Cu" "B.Mask" "B.Paste")
			(net "GND")
		)
	)
	(footprint ""
		(layer "B.Cu")
		(at 500.851424 -457.29398 -90)
		(property "Reference" "X9027"
			(at 4.7244 -1.61163 270)
			(unlocked yes)
			(layer "B.SilkS")
			(effects
				(font
					(size 0.7874 0.5842)
					(thickness 0.1524)
				)
				(justify left mirror)
			)
		)
		(property "Value" ""
			(at 0 0 90)
			(layer "B.Fab")
			(effects
				(font
					(size 1.27 1.27)
				)
				(justify mirror)
			)
		)
		(property "User Part Number" "N_A"
			(at -1.30175 1.27 180)
			(unlocked yes)
			(layer "Cmts.User")
			(hide yes)
			(effects
				(font
					(size 0.635 0.4064)
					(thickness 0.1524)
				)
				(justify mirror)
			)
		)
		(property "Device Type" "TP_TDR_4P_FTS_TH-TP_TDR_4P_DIP,EMPTY,TP15"
			(at -1.30175 1.27 180)
			(unlocked yes)
			(layer "B.Fab")
			(hide yes)
			(effects
				(font
					(size 0.635 0.4064)
					(thickness 0.1524)
				)
				(justify mirror)
			)
		)
		(duplicate_pad_numbers_are_jumpers no)
		(fp_line
			(start -2.54 3.81)
			(end -2.54 3.6703)
			(stroke
				(width 0.1524)
				(type default)
			)
			(layer "B.SilkS")
		)
		(fp_line
			(start 0 3.81)
			(end -2.54 3.81)
			(stroke
				(width 0.1524)
				(type default)
			)
			(layer "B.SilkS")
		)
		(fp_line
			(start 0 3.175)
			(end 0 3.81)
			(stroke
				(width 0.1524)
				(type default)
			)
			(layer "B.SilkS")
		)
		(fp_line
			(start -2.54 1.4097)
			(end -2.54 1.1303)
			(stroke
				(width 0.1524)
				(type default)
			)
			(layer "B.SilkS")
		)
		(fp_line
			(start 0 0.635)
			(end 0 1.905)
			(stroke
				(width 0.1524)
				(type default)
			)
			(layer "B.SilkS")
		)
		(fp_line
			(start -2.54 -1.1303)
			(end -2.54 -1.27)
			(stroke
				(width 0.1524)
				(type default)
			)
			(layer "B.SilkS")
		)
		(fp_line
			(start -2.54 -1.27)
			(end 0 -1.27)
			(stroke
				(width 0.1524)
				(type default)
			)
			(layer "B.SilkS")
		)
		(fp_line
			(start 0 -1.27)
			(end 0 -0.635)
			(stroke
				(width 0.1524)
				(type default)
			)
			(layer "B.SilkS")
		)
		(fp_poly
			(pts
				(xy 0.761746 0) (xy 2.285746 -0.762) (xy 2.285746 0.762)
			)
			(stroke
				(width 0)
				(type default)
			)
			(fill yes)
			(layer "B.SilkS")
		)
		(fp_line
			(start -2.54 3.81)
			(end -2.54 -1.27)
			(stroke
				(width 0.1)
				(type default)
			)
			(layer "B.Fab")
		)
		(fp_line
			(start 0 3.81)
			(end -2.54 3.81)
			(stroke
				(width 0.1)
				(type default)
			)
			(layer "B.Fab")
		)
		(fp_line
			(start -2.54 -1.27)
			(end 0 -1.27)
			(stroke
				(width 0.1)
				(type default)
			)
			(layer "B.Fab")
		)
		(fp_line
			(start 0 -1.27)
			(end 0 3.81)
			(stroke
				(width 0.1)
				(type default)
			)
			(layer "B.Fab")
		)
		(fp_poly
			(pts
				(xy 0.761746 0) (xy 2.285746 -0.762) (xy 2.285746 0.762)
			)
			(stroke
				(width 0)
				(type default)
			)
			(fill yes)
			(layer "B.Fab")
		)
		(pad "1" thru_hole circle
			(at 0 0 90)
			(size 1.0033 1.0033)
			(drill 0.249936)
			(layers "*.Cu" "*.Mask")
			(remove_unused_layers no)
			(net "TDR_DIFF_85_NECK_IN5_DN")
			(clearance 0.10795)
			(padstack
				(mode front_inner_back)
				(layer "Inner"
					(shape circle)
					(size 0.8001 0.8001)
					(clearance 0.1524)
				)
				(layer "B.Cu"
					(shape circle)
					(size 1.0033 1.0033)
					(thermal_gap 0.10795)
					(clearance 0.10795)
				)
			)
		)
		(pad "2" thru_hole circle
			(at -2.54 0 90)
			(size 1.9939 1.9939)
			(drill 0.249936)
			(layers "*.Cu" "*.Mask")
			(remove_unused_layers no)
			(net "T1_GND")
			(clearance 0.10795)
			(padstack
				(mode front_inner_back)
				(layer "Inner"
					(shape circle)
					(size 0.8001 0.8001)
					(clearance 0.1524)
				)
				(layer "B.Cu"
					(shape circle)
					(size 1.9939 1.9939)
					(thermal_gap 0.10795)
					(clearance 0.10795)
				)
			)
		)
		(pad "3" thru_hole circle
			(at -2.54 2.54 90)
			(size 1.9939 1.9939)
			(drill 0.249936)
			(layers "*.Cu" "*.Mask")
			(remove_unused_layers no)
			(net "T1_GND")
			(clearance 0.10795)
			(padstack
				(mode front_inner_back)
				(layer "Inner"
					(shape circle)
					(size 0.8001 0.8001)
					(clearance 0.1524)
				)
				(layer "B.Cu"
					(shape circle)
					(size 1.9939 1.9939)
					(thermal_gap 0.10795)
					(clearance 0.10795)
				)
			)
		)
		(pad "4" thru_hole circle
			(at 0 2.54 90)
			(size 1.0033 1.0033)
			(drill 0.249936)
			(layers "*.Cu" "*.Mask")
			(remove_unused_layers no)
			(net "TDR_DIFF_85_NECK_IN5_DP")
			(clearance 0.10795)
			(padstack
				(mode front_inner_back)
				(layer "Inner"
					(shape circle)
					(size 0.8001 0.8001)
					(clearance 0.1524)
				)
				(layer "B.Cu"
					(shape circle)
					(size 1.0033 1.0033)
					(thermal_gap 0.10795)
					(clearance 0.10795)
				)
			)
		)
	)
	(footprint ""
		(layer "B.Cu")
		(at 197.345808 -124.877576 180)
		(property "Reference" "R6115"
			(at 0 0 0)
			(layer "B.SilkS")
			(hide yes)
			(effects
				(font
					(size 1.27 1.27)
				)
				(justify mirror)
			)
		)
		(property "Value" ""
			(at 0 0 0)
			(layer "B.Fab")
			(effects
				(font
					(size 1.27 1.27)
				)
				(justify mirror)
			)
		)
		(duplicate_pad_numbers_are_jumpers no)
		(fp_line
			(start 0.7874 0.4064)
			(end 0.7874 -0.4064)
			(stroke
				(width 0.1524)
				(type default)
			)
			(layer "B.SilkS")
		)
		(fp_line
			(start 0.7874 -0.4064)
			(end -0.7874 -0.4064)
			(stroke
				(width 0.1524)
				(type default)
			)
			(layer "B.SilkS")
		)
		(fp_line
			(start -0.7874 0.4064)
			(end 0.7874 0.4064)
			(stroke
				(width 0.1524)
				(type default)
			)
			(layer "B.SilkS")
		)
		(fp_line
			(start -0.7874 -0.4064)
			(end -0.7874 0.4064)
			(stroke
				(width 0.1524)
				(type default)
			)
			(layer "B.SilkS")
		)
		(fp_line
			(start 0.67945 0.3048)
			(end 0.67945 -0.305054)
			(stroke
				(width 0.1)
				(type default)
			)
			(layer "B.Fab")
		)
		(fp_line
			(start 0.67945 -0.305054)
			(end 0.12065 -0.305054)
			(stroke
				(width 0.1)
				(type default)
			)
			(layer "B.Fab")
		)
		(fp_line
			(start 0.12065 0.3048)
			(end 0.67945 0.3048)
			(stroke
				(width 0.1)
				(type default)
			)
			(layer "B.Fab")
		)
		(fp_line
			(start 0.12065 0.2794)
			(end 0.12065 0.3048)
			(stroke
				(width 0.1)
				(type default)
			)
			(layer "B.Fab")
		)
		(fp_line
			(start 0.12065 -0.2794)
			(end -0.12065 -0.2794)
			(stroke
				(width 0.1)
				(type default)
			)
			(layer "B.Fab")
		)
		(fp_line
			(start 0.12065 -0.305054)
			(end 0.12065 -0.2794)
			(stroke
				(width 0.1)
				(type default)
			)
			(layer "B.Fab")
		)
		(fp_line
			(start -0.120396 0.3048)
			(end -0.120396 0.2794)
			(stroke
				(width 0.1)
				(type default)
			)
			(layer "B.Fab")
		)
		(fp_line
			(start -0.120396 0.2794)
			(end 0.12065 0.2794)
			(stroke
				(width 0.1)
				(type default)
			)
			(layer "B.Fab")
		)
		(fp_line
			(start -0.12065 -0.2794)
			(end -0.12065 -0.3048)
			(stroke
				(width 0.1)
				(type default)
			)
			(layer "B.Fab")
		)
		(fp_line
			(start -0.12065 -0.3048)
			(end -0.67945 -0.3048)
			(stroke
				(width 0.1)
				(type default)
			)
			(layer "B.Fab")
		)
		(fp_line
			(start -0.67945 0.3048)
			(end -0.120396 0.3048)
			(stroke
				(width 0.1)
				(type default)
			)
			(layer "B.Fab")
		)
		(fp_line
			(start -0.67945 -0.3048)
			(end -0.67945 0.3048)
			(stroke
				(width 0.1)
				(type default)
			)
			(layer "B.Fab")
		)
		(pad "1" smd circle
			(at 0.40005 0)
			(size 0 0)
			(layers "B.Cu" "B.Mask" "B.Paste")
			(net "RST_PERST_CPU1_SWB_N")
		)
		(pad "2" smd circle
			(at -0.40005 0)
			(size 0 0)
			(layers "B.Cu" "B.Mask" "B.Paste")
			(net "GND")
		)
	)
	(footprint ""
		(layer "B.Cu")
		(at 188.849 -100.294948 -90)
		(property "Reference" "R232"
			(at 0 0 90)
			(layer "B.SilkS")
			(hide yes)
			(effects
				(font
					(size 1.27 1.27)
				)
				(justify mirror)
			)
		)
		(property "Value" ""
			(at 0 0 90)
			(layer "B.Fab")
			(effects
				(font
					(size 1.27 1.27)
				)
				(justify mirror)
			)
		)
		(duplicate_pad_numbers_are_jumpers no)
		(fp_line
			(start -0.7874 0.4064)
			(end 0.7874 0.4064)
			(stroke
				(width 0.1524)
				(type default)
			)
			(layer "B.SilkS")
		)
		(fp_line
			(start 0.7874 0.4064)
			(end 0.7874 -0.4064)
			(stroke
				(width 0.1524)
				(type default)
			)
			(layer "B.SilkS")
		)
		(fp_line
			(start -0.7874 -0.4064)
			(end -0.7874 0.4064)
			(stroke
				(width 0.1524)
				(type default)
			)
			(layer "B.SilkS")
		)
		(fp_line
			(start 0.7874 -0.4064)
			(end -0.7874 -0.4064)
			(stroke
				(width 0.1524)
				(type default)
			)
			(layer "B.SilkS")
		)
		(fp_line
			(start -0.67945 0.3048)
			(end -0.120396 0.3048)
			(stroke
				(width 0.1)
				(type default)
			)
			(layer "B.Fab")
		)
		(fp_line
			(start -0.120396 0.3048)
			(end -0.120396 0.2794)
			(stroke
				(width 0.1)
				(type default)
			)
			(layer "B.Fab")
		)
		(fp_line
			(start 0.12065 0.3048)
			(end 0.67945 0.3048)
			(stroke
				(width 0.1)
				(type default)
			)
			(layer "B.Fab")
		)
		(fp_line
			(start 0.67945 0.3048)
			(end 0.67945 -0.305054)
			(stroke
				(width 0.1)
				(type default)
			)
			(layer "B.Fab")
		)
		(fp_line
			(start -0.120396 0.2794)
			(end 0.12065 0.2794)
			(stroke
				(width 0.1)
				(type default)
			)
			(layer "B.Fab")
		)
		(fp_line
			(start 0.12065 0.2794)
			(end 0.12065 0.3048)
			(stroke
				(width 0.1)
				(type default)
			)
			(layer "B.Fab")
		)
		(fp_line
			(start -0.12065 -0.2794)
			(end -0.12065 -0.3048)
			(stroke
				(width 0.1)
				(type default)
			)
			(layer "B.Fab")
		)
		(fp_line
			(start 0.12065 -0.2794)
			(end -0.12065 -0.2794)
			(stroke
				(width 0.1)
				(type default)
			)
			(layer "B.Fab")
		)
		(fp_line
			(start -0.67945 -0.3048)
			(end -0.67945 0.3048)
			(stroke
				(width 0.1)
				(type default)
			)
			(layer "B.Fab")
		)
		(fp_line
			(start -0.12065 -0.3048)
			(end -0.67945 -0.3048)
			(stroke
				(width 0.1)
				(type default)
			)
			(layer "B.Fab")
		)
		(fp_line
			(start 0.12065 -0.305054)
			(end 0.12065 -0.2794)
			(stroke
				(width 0.1)
				(type default)
			)
			(layer "B.Fab")
		)
		(fp_line
			(start 0.67945 -0.305054)
			(end 0.12065 -0.305054)
			(stroke
				(width 0.1)
				(type default)
			)
			(layer "B.Fab")
		)
		(pad "1" smd circle
			(at 0.40005 0 90)
			(size 0 0)
			(layers "B.Cu" "B.Mask" "B.Paste")
			(net "FM_PVDDCR_CPU1_P0_EN")
		)
		(pad "2" smd circle
			(at -0.40005 0 90)
			(size 0 0)
			(layers "B.Cu" "B.Mask" "B.Paste")
			(net "FM_PVDDCR_CPU1_P0_R_EN")
		)
	)
	(footprint ""
		(layer "B.Cu")
		(at 278.713184 -337.984846 -90)
		(property "Reference" "PC189_4"
			(at 0 0 90)
			(layer "B.SilkS")
			(hide yes)
			(effects
				(font
					(size 1.27 1.27)
				)
				(justify mirror)
			)
		)
		(property "Value" ""
			(at 0 0 90)
			(layer "B.Fab")
			(effects
				(font
					(size 1.27 1.27)
				)
				(justify mirror)
			)
		)
		(duplicate_pad_numbers_are_jumpers no)
		(fp_line
			(start -1.524 0.762)
			(end 1.524 0.762)
			(stroke
				(width 0.1524)
				(type default)
			)
			(layer "B.SilkS")
		)
		(fp_line
			(start 1.524 0.762)
			(end 1.524 -0.762)
			(stroke
				(width 0.1524)
				(type default)
			)
			(layer "B.SilkS")
		)
		(fp_line
			(start -1.524 -0.762)
			(end -1.524 0.762)
			(stroke
				(width 0.1524)
				(type default)
			)
			(layer "B.SilkS")
		)
		(fp_line
			(start 1.524 -0.762)
			(end -1.524 -0.762)
			(stroke
				(width 0.1524)
				(type default)
			)
			(layer "B.SilkS")
		)
		(fp_line
			(start -1.1049 0.724916)
			(end -1.1049 -0.724916)
			(stroke
				(width 0.1)
				(type default)
			)
			(layer "B.Fab")
		)
		(fp_line
			(start 1.1049 0.724916)
			(end -1.1049 0.724916)
			(stroke
				(width 0.1)
				(type default)
			)
			(layer "B.Fab")
		)
		(fp_line
			(start -1.1049 -0.724916)
			(end 1.1049 -0.724916)
			(stroke
				(width 0.1)
				(type default)
			)
			(layer "B.Fab")
		)
		(fp_line
			(start 1.1049 -0.724916)
			(end 1.1049 0.724916)
			(stroke
				(width 0.1)
				(type default)
			)
			(layer "B.Fab")
		)
		(pad "1" smd rect
			(at 0.889 0 270)
			(size 1.016 1.27)
			(layers "B.Cu" "B.Mask" "B.Paste")
			(net "PVDDIO_P0")
		)
		(pad "2" smd rect
			(at -0.889 0 270)
			(size 1.016 1.27)
			(layers "B.Cu" "B.Mask" "B.Paste")
			(net "GND")
		)
	)
	(footprint ""
		(layer "B.Cu")
		(at 105.577386 -269.307564)
		(property "Reference" "C2351"
			(at 0 0 0)
			(layer "B.SilkS")
			(hide yes)
			(effects
				(font
					(size 1.27 1.27)
				)
				(justify mirror)
			)
		)
		(property "Value" ""
			(at 0 0 0)
			(layer "B.Fab")
			(effects
				(font
					(size 1.27 1.27)
				)
				(justify mirror)
			)
		)
		(duplicate_pad_numbers_are_jumpers no)
		(fp_line
			(start -0.7874 -0.4064)
			(end -0.7874 0.4064)
			(stroke
				(width 0.1524)
				(type default)
			)
			(layer "B.SilkS")
		)
		(fp_line
			(start -0.7874 0.4064)
			(end 0.7874 0.4064)
			(stroke
				(width 0.1524)
				(type default)
			)
			(layer "B.SilkS")
		)
		(fp_line
			(start 0.7874 -0.4064)
			(end -0.7874 -0.4064)
			(stroke
				(width 0.1524)
				(type default)
			)
			(layer "B.SilkS")
		)
		(fp_line
			(start 0.7874 0.4064)
			(end 0.7874 -0.4064)
			(stroke
				(width 0.1524)
				(type default)
			)
			(layer "B.SilkS")
		)
		(fp_line
			(start -0.67945 -0.3048)
			(end -0.67945 0.3048)
			(stroke
				(width 0.1)
				(type default)
			)
			(layer "B.Fab")
		)
		(fp_line
			(start -0.67945 0.3048)
			(end -0.120396 0.3048)
			(stroke
				(width 0.1)
				(type default)
			)
			(layer "B.Fab")
		)
		(fp_line
			(start -0.12065 -0.3048)
			(end -0.67945 -0.3048)
			(stroke
				(width 0.1)
				(type default)
			)
			(layer "B.Fab")
		)
		(fp_line
			(start -0.12065 -0.2794)
			(end -0.12065 -0.3048)
			(stroke
				(width 0.1)
				(type default)
			)
			(layer "B.Fab")
		)
		(fp_line
			(start -0.120396 0.2794)
			(end 0.12065 0.2794)
			(stroke
				(width 0.1)
				(type default)
			)
			(layer "B.Fab")
		)
		(fp_line
			(start -0.120396 0.3048)
			(end -0.120396 0.2794)
			(stroke
				(width 0.1)
				(type default)
			)
			(layer "B.Fab")
		)
		(fp_line
			(start 0.12065 -0.305054)
			(end 0.12065 -0.2794)
			(stroke
				(width 0.1)
				(type default)
			)
			(layer "B.Fab")
		)
		(fp_line
			(start 0.12065 -0.2794)
			(end -0.12065 -0.2794)
			(stroke
				(width 0.1)
				(type default)
			)
			(layer "B.Fab")
		)
		(fp_line
			(start 0.12065 0.2794)
			(end 0.12065 0.3048)
			(stroke
				(width 0.1)
				(type default)
			)
			(layer "B.Fab")
		)
		(fp_line
			(start 0.12065 0.3048)
			(end 0.67945 0.3048)
			(stroke
				(width 0.1)
				(type default)
			)
			(layer "B.Fab")
		)
		(fp_line
			(start 0.67945 -0.305054)
			(end 0.12065 -0.305054)
			(stroke
				(width 0.1)
				(type default)
			)
			(layer "B.Fab")
		)
		(fp_line
			(start 0.67945 0.3048)
			(end 0.67945 -0.305054)
			(stroke
				(width 0.1)
				(type default)
			)
			(layer "B.Fab")
		)
		(pad "1" smd circle
			(at 0.40005 0 180)
			(size 0 0)
			(layers "B.Cu" "B.Mask" "B.Paste")
			(net "PVDDCR_CPU1_P1")
		)
		(pad "2" smd circle
			(at -0.40005 0 180)
			(size 0 0)
			(layers "B.Cu" "B.Mask" "B.Paste")
			(net "GND")
		)
	)
	(footprint ""
		(layer "B.Cu")
		(at 109.095794 -384.66268 180)
		(property "Reference" "R920"
			(at 0 0 0)
			(layer "B.SilkS")
			(hide yes)
			(effects
				(font
					(size 1.27 1.27)
				)
				(justify mirror)
			)
		)
		(property "Value" ""
			(at 0 0 0)
			(layer "B.Fab")
			(effects
				(font
					(size 1.27 1.27)
				)
				(justify mirror)
			)
		)
		(duplicate_pad_numbers_are_jumpers no)
		(fp_line
			(start 0.32512 0.175006)
			(end 0.32512 -0.175006)
			(stroke
				(width 0.1)
				(type default)
			)
			(layer "B.Fab")
		)
		(fp_line
			(start 0.32512 -0.175006)
			(end -0.32512 -0.175006)
			(stroke
				(width 0.1)
				(type default)
			)
			(layer "B.Fab")
		)
		(fp_line
			(start -0.32512 0.175006)
			(end 0.32512 0.175006)
			(stroke
				(width 0.1)
				(type default)
			)
			(layer "B.Fab")
		)
		(fp_line
			(start -0.32512 -0.175006)
			(end -0.32512 0.175006)
			(stroke
				(width 0.1)
				(type default)
			)
			(layer "B.Fab")
		)
		(pad "1" smd rect
			(at 0.2667 0)
			(size 0.3048 0.381)
			(layers "B.Cu" "B.Mask" "B.Paste")
			(net "P1V8_CPU1_RT_1D")
		)
		(pad "2" smd rect
			(at -0.2667 0 180)
			(size 0.3048 0.381)
			(layers "B.Cu" "B.Mask" "B.Paste")
			(net "TEST1_RT_CPU1_P3")
		)
	)
	(footprint ""
		(layer "B.Cu")
		(at 235.077 -234.061 90)
		(property "Reference" "R1162"
			(at 0 0 90)
			(layer "B.SilkS")
			(hide yes)
			(effects
				(font
					(size 1.27 1.27)
				)
				(justify mirror)
			)
		)
		(property "Value" ""
			(at 0 0 90)
			(layer "B.Fab")
			(effects
				(font
					(size 1.27 1.27)
				)
				(justify mirror)
			)
		)
		(duplicate_pad_numbers_are_jumpers no)
		(fp_line
			(start 0.7874 -0.4064)
			(end -0.7874 -0.4064)
			(stroke
				(width 0.1524)
				(type default)
			)
			(layer "B.SilkS")
		)
		(fp_line
			(start -0.7874 -0.4064)
			(end -0.7874 0.4064)
			(stroke
				(width 0.1524)
				(type default)
			)
			(layer "B.SilkS")
		)
		(fp_line
			(start 0.7874 0.4064)
			(end 0.7874 -0.4064)
			(stroke
				(width 0.1524)
				(type default)
			)
			(layer "B.SilkS")
		)
		(fp_line
			(start -0.7874 0.4064)
			(end 0.7874 0.4064)
			(stroke
				(width 0.1524)
				(type default)
			)
			(layer "B.SilkS")
		)
		(fp_line
			(start 0.67945 -0.305054)
			(end 0.12065 -0.305054)
			(stroke
				(width 0.1)
				(type default)
			)
			(layer "B.Fab")
		)
		(fp_line
			(start 0.12065 -0.305054)
			(end 0.12065 -0.2794)
			(stroke
				(width 0.1)
				(type default)
			)
			(layer "B.Fab")
		)
		(fp_line
			(start -0.12065 -0.3048)
			(end -0.67945 -0.3048)
			(stroke
				(width 0.1)
				(type default)
			)
			(layer "B.Fab")
		)
		(fp_line
			(start -0.67945 -0.3048)
			(end -0.67945 0.3048)
			(stroke
				(width 0.1)
				(type default)
			)
			(layer "B.Fab")
		)
		(fp_line
			(start 0.12065 -0.2794)
			(end -0.12065 -0.2794)
			(stroke
				(width 0.1)
				(type default)
			)
			(layer "B.Fab")
		)
		(fp_line
			(start -0.12065 -0.2794)
			(end -0.12065 -0.3048)
			(stroke
				(width 0.1)
				(type default)
			)
			(layer "B.Fab")
		)
		(fp_line
			(start 0.12065 0.2794)
			(end 0.12065 0.3048)
			(stroke
				(width 0.1)
				(type default)
			)
			(layer "B.Fab")
		)
		(fp_line
			(start -0.120396 0.2794)
			(end 0.12065 0.2794)
			(stroke
				(width 0.1)
				(type default)
			)
			(layer "B.Fab")
		)
		(fp_line
			(start 0.67945 0.3048)
			(end 0.67945 -0.305054)
			(stroke
				(width 0.1)
				(type default)
			)
			(layer "B.Fab")
		)
		(fp_line
			(start 0.12065 0.3048)
			(end 0.67945 0.3048)
			(stroke
				(width 0.1)
				(type default)
			)
			(layer "B.Fab")
		)
		(fp_line
			(start -0.120396 0.3048)
			(end -0.120396 0.2794)
			(stroke
				(width 0.1)
				(type default)
			)
			(layer "B.Fab")
		)
		(fp_line
			(start -0.67945 0.3048)
			(end -0.120396 0.3048)
			(stroke
				(width 0.1)
				(type default)
			)
			(layer "B.Fab")
		)
		(pad "1" smd circle
			(at 0.40005 0 270)
			(size 0 0)
			(layers "B.Cu" "B.Mask" "B.Paste")
			(net "SMB_CPU1_SEC_R_SDA")
		)
		(pad "2" smd circle
			(at -0.40005 0 270)
			(size 0 0)
			(layers "B.Cu" "B.Mask" "B.Paste")
			(net "SMB_CPU1_SEC_SDA")
		)
	)
	(footprint ""
		(layer "B.Cu")
		(at 347.918786 -399.291302 90)
		(property "Reference" "C655"
			(at 0 0 90)
			(layer "B.SilkS")
			(hide yes)
			(effects
				(font
					(size 1.27 1.27)
				)
				(justify mirror)
			)
		)
		(property "Value" ""
			(at 0 0 90)
			(layer "B.Fab")
			(effects
				(font
					(size 1.27 1.27)
				)
				(justify mirror)
			)
		)
		(duplicate_pad_numbers_are_jumpers no)
		(fp_line
			(start 0.299974 -0.150114)
			(end -0.299974 -0.150114)
			(stroke
				(width 0.1)
				(type default)
			)
			(layer "B.Fab")
		)
		(fp_line
			(start -0.299974 -0.150114)
			(end -0.299974 0.150114)
			(stroke
				(width 0.1)
				(type default)
			)
			(layer "B.Fab")
		)
		(fp_line
			(start 0.299974 0.150114)
			(end 0.299974 -0.150114)
			(stroke
				(width 0.1)
				(type default)
			)
			(layer "B.Fab")
		)
		(fp_line
			(start -0.299974 0.150114)
			(end 0.299974 0.150114)
			(stroke
				(width 0.1)
				(type default)
			)
			(layer "B.Fab")
		)
		(pad "1" smd rect
			(at 0.2667 0 270)
			(size 0.3048 0.381)
			(layers "B.Cu" "B.Mask" "B.Paste")
			(net "P0V9_CPU0_RT_2D")
		)
		(pad "2" smd rect
			(at -0.2667 0 270)
			(size 0.3048 0.381)
			(layers "B.Cu" "B.Mask" "B.Paste")
			(net "GND")
		)
	)
	(footprint ""
		(layer "B.Cu")
		(at 170.12158 -50.107088 180)
		(property "Reference" "C9922"
			(at 0 0 0)
			(layer "B.SilkS")
			(hide yes)
			(effects
				(font
					(size 1.27 1.27)
				)
				(justify mirror)
			)
		)
		(property "Value" ""
			(at 0 0 0)
			(layer "B.Fab")
			(effects
				(font
					(size 1.27 1.27)
				)
				(justify mirror)
			)
		)
		(duplicate_pad_numbers_are_jumpers no)
		(fp_line
			(start 1.2954 0.5842)
			(end 1.2954 -0.5842)
			(stroke
				(width 0.1524)
				(type default)
			)
			(layer "B.SilkS")
		)
		(fp_line
			(start 1.2954 -0.5842)
			(end -1.2954 -0.5842)
			(stroke
				(width 0.1524)
				(type default)
			)
			(layer "B.SilkS")
		)
		(fp_line
			(start -1.2954 0.5842)
			(end 1.2954 0.5842)
			(stroke
				(width 0.1524)
				(type default)
			)
			(layer "B.SilkS")
		)
		(fp_line
			(start -1.2954 -0.5842)
			(end -1.2954 0.5842)
			(stroke
				(width 0.1524)
				(type default)
			)
			(layer "B.SilkS")
		)
		(fp_line
			(start 1.1938 0.4064)
			(end 1.1938 -0.4064)
			(stroke
				(width 0.1)
				(type default)
			)
			(layer "B.Fab")
		)
		(fp_line
			(start 1.1938 -0.4064)
			(end 0.8636 -0.4064)
			(stroke
				(width 0.1)
				(type default)
			)
			(layer "B.Fab")
		)
		(fp_line
			(start 0.8636 0.4572)
			(end 0.8636 0.4064)
			(stroke
				(width 0.1)
				(type default)
			)
			(layer "B.Fab")
		)
		(fp_line
			(start 0.8636 0.4064)
			(end 1.1938 0.4064)
			(stroke
				(width 0.1)
				(type default)
			)
			(layer "B.Fab")
		)
		(fp_line
			(start 0.8636 -0.4064)
			(end 0.8636 -0.4572)
			(stroke
				(width 0.1)
				(type default)
			)
			(layer "B.Fab")
		)
		(fp_line
			(start 0.8636 -0.4572)
			(end -0.8636 -0.4572)
			(stroke
				(width 0.1)
				(type default)
			)
			(layer "B.Fab")
		)
		(fp_line
			(start -0.8636 0.4572)
			(end 0.8636 0.4572)
			(stroke
				(width 0.1)
				(type default)
			)
			(layer "B.Fab")
		)
		(fp_line
			(start -0.8636 0.4064)
			(end -0.8636 0.4572)
			(stroke
				(width 0.1)
				(type default)
			)
			(layer "B.Fab")
		)
		(fp_line
			(start -0.8636 -0.4064)
			(end -1.1938 -0.4064)
			(stroke
				(width 0.1)
				(type default)
			)
			(layer "B.Fab")
		)
		(fp_line
			(start -0.8636 -0.4572)
			(end -0.8636 -0.4064)
			(stroke
				(width 0.1)
				(type default)
			)
			(layer "B.Fab")
		)
		(fp_line
			(start -1.1938 0.4064)
			(end -0.8636 0.4064)
			(stroke
				(width 0.1)
				(type default)
			)
			(layer "B.Fab")
		)
		(fp_line
			(start -1.1938 -0.4064)
			(end -1.1938 0.4064)
			(stroke
				(width 0.1)
				(type default)
			)
			(layer "B.Fab")
		)
		(pad "1" smd rect
			(at 0.7366 0 90)
			(size 0.7112 0.8128)
			(layers "B.Cu" "B.Mask" "B.Paste")
			(net "P3V3_M2_0")
		)
		(pad "2" smd rect
			(at -0.7366 0 90)
			(size 0.7112 0.8128)
			(layers "B.Cu" "B.Mask" "B.Paste")
			(net "GND")
		)
	)
	(footprint ""
		(layer "B.Cu")
		(at 13.650468 -135.44931 90)
		(property "Reference" "C95"
			(at 0 0 90)
			(layer "B.SilkS")
			(hide yes)
			(effects
				(font
					(size 1.27 1.27)
				)
				(justify mirror)
			)
		)
		(property "Value" ""
			(at 0 0 90)
			(layer "B.Fab")
			(effects
				(font
					(size 1.27 1.27)
				)
				(justify mirror)
			)
		)
		(duplicate_pad_numbers_are_jumpers no)
		(fp_line
			(start 0.7874 -0.4064)
			(end -0.7874 -0.4064)
			(stroke
				(width 0.1524)
				(type default)
			)
			(layer "B.SilkS")
		)
		(fp_line
			(start -0.7874 -0.4064)
			(end -0.7874 0.4064)
			(stroke
				(width 0.1524)
				(type default)
			)
			(layer "B.SilkS")
		)
		(fp_line
			(start 0.7874 0.4064)
			(end 0.7874 -0.4064)
			(stroke
				(width 0.1524)
				(type default)
			)
			(layer "B.SilkS")
		)
		(fp_line
			(start -0.7874 0.4064)
			(end 0.7874 0.4064)
			(stroke
				(width 0.1524)
				(type default)
			)
			(layer "B.SilkS")
		)
		(fp_line
			(start 0.67945 -0.305054)
			(end 0.12065 -0.305054)
			(stroke
				(width 0.1)
				(type default)
			)
			(layer "B.Fab")
		)
		(fp_line
			(start 0.12065 -0.305054)
			(end 0.12065 -0.2794)
			(stroke
				(width 0.1)
				(type default)
			)
			(layer "B.Fab")
		)
		(fp_line
			(start -0.12065 -0.3048)
			(end -0.67945 -0.3048)
			(stroke
				(width 0.1)
				(type default)
			)
			(layer "B.Fab")
		)
		(fp_line
			(start -0.67945 -0.3048)
			(end -0.67945 0.3048)
			(stroke
				(width 0.1)
				(type default)
			)
			(layer "B.Fab")
		)
		(fp_line
			(start 0.12065 -0.2794)
			(end -0.12065 -0.2794)
			(stroke
				(width 0.1)
				(type default)
			)
			(layer "B.Fab")
		)
		(fp_line
			(start -0.12065 -0.2794)
			(end -0.12065 -0.3048)
			(stroke
				(width 0.1)
				(type default)
			)
			(layer "B.Fab")
		)
		(fp_line
			(start 0.12065 0.2794)
			(end 0.12065 0.3048)
			(stroke
				(width 0.1)
				(type default)
			)
			(layer "B.Fab")
		)
		(fp_line
			(start -0.120396 0.2794)
			(end 0.12065 0.2794)
			(stroke
				(width 0.1)
				(type default)
			)
			(layer "B.Fab")
		)
		(fp_line
			(start 0.67945 0.3048)
			(end 0.67945 -0.305054)
			(stroke
				(width 0.1)
				(type default)
			)
			(layer "B.Fab")
		)
		(fp_line
			(start 0.12065 0.3048)
			(end 0.67945 0.3048)
			(stroke
				(width 0.1)
				(type default)
			)
			(layer "B.Fab")
		)
		(fp_line
			(start -0.120396 0.3048)
			(end -0.120396 0.2794)
			(stroke
				(width 0.1)
				(type default)
			)
			(layer "B.Fab")
		)
		(fp_line
			(start -0.67945 0.3048)
			(end -0.120396 0.3048)
			(stroke
				(width 0.1)
				(type default)
			)
			(layer "B.Fab")
		)
		(pad "1" smd circle
			(at 0.40005 0 270)
			(size 0 0)
			(layers "B.Cu" "B.Mask" "B.Paste")
			(net "VFG3P3_CLK_GEN")
		)
		(pad "2" smd circle
			(at -0.40005 0 270)
			(size 0 0)
			(layers "B.Cu" "B.Mask" "B.Paste")
			(net "GND")
		)
	)
	(footprint ""
		(layer "B.Cu")
		(at 312.403236 -197.836028 -90)
		(property "Reference" "R6081"
			(at 0 0 90)
			(layer "B.SilkS")
			(hide yes)
			(effects
				(font
					(size 1.27 1.27)
				)
				(justify mirror)
			)
		)
		(property "Value" ""
			(at 0 0 90)
			(layer "B.Fab")
			(effects
				(font
					(size 1.27 1.27)
				)
				(justify mirror)
			)
		)
		(duplicate_pad_numbers_are_jumpers no)
		(fp_line
			(start -0.7874 0.4064)
			(end 0.7874 0.4064)
			(stroke
				(width 0.1524)
				(type default)
			)
			(layer "B.SilkS")
		)
		(fp_line
			(start 0.7874 0.4064)
			(end 0.7874 -0.4064)
			(stroke
				(width 0.1524)
				(type default)
			)
			(layer "B.SilkS")
		)
		(fp_line
			(start -0.7874 -0.4064)
			(end -0.7874 0.4064)
			(stroke
				(width 0.1524)
				(type default)
			)
			(layer "B.SilkS")
		)
		(fp_line
			(start 0.7874 -0.4064)
			(end -0.7874 -0.4064)
			(stroke
				(width 0.1524)
				(type default)
			)
			(layer "B.SilkS")
		)
		(fp_line
			(start -0.67945 0.3048)
			(end -0.120396 0.3048)
			(stroke
				(width 0.1)
				(type default)
			)
			(layer "B.Fab")
		)
		(fp_line
			(start -0.120396 0.3048)
			(end -0.120396 0.2794)
			(stroke
				(width 0.1)
				(type default)
			)
			(layer "B.Fab")
		)
		(fp_line
			(start 0.12065 0.3048)
			(end 0.67945 0.3048)
			(stroke
				(width 0.1)
				(type default)
			)
			(layer "B.Fab")
		)
		(fp_line
			(start 0.67945 0.3048)
			(end 0.67945 -0.305054)
			(stroke
				(width 0.1)
				(type default)
			)
			(layer "B.Fab")
		)
		(fp_line
			(start -0.120396 0.2794)
			(end 0.12065 0.2794)
			(stroke
				(width 0.1)
				(type default)
			)
			(layer "B.Fab")
		)
		(fp_line
			(start 0.12065 0.2794)
			(end 0.12065 0.3048)
			(stroke
				(width 0.1)
				(type default)
			)
			(layer "B.Fab")
		)
		(fp_line
			(start -0.12065 -0.2794)
			(end -0.12065 -0.3048)
			(stroke
				(width 0.1)
				(type default)
			)
			(layer "B.Fab")
		)
		(fp_line
			(start 0.12065 -0.2794)
			(end -0.12065 -0.2794)
			(stroke
				(width 0.1)
				(type default)
			)
			(layer "B.Fab")
		)
		(fp_line
			(start -0.67945 -0.3048)
			(end -0.67945 0.3048)
			(stroke
				(width 0.1)
				(type default)
			)
			(layer "B.Fab")
		)
		(fp_line
			(start -0.12065 -0.3048)
			(end -0.67945 -0.3048)
			(stroke
				(width 0.1)
				(type default)
			)
			(layer "B.Fab")
		)
		(fp_line
			(start 0.12065 -0.305054)
			(end 0.12065 -0.2794)
			(stroke
				(width 0.1)
				(type default)
			)
			(layer "B.Fab")
		)
		(fp_line
			(start 0.67945 -0.305054)
			(end 0.12065 -0.305054)
			(stroke
				(width 0.1)
				(type default)
			)
			(layer "B.Fab")
		)
		(pad "1" smd circle
			(at 0.40005 0 90)
			(size 0 0)
			(layers "B.Cu" "B.Mask" "B.Paste")
			(net "PVDD11_S3_P0")
		)
		(pad "2" smd circle
			(at -0.40005 0 90)
			(size 0 0)
			(layers "B.Cu" "B.Mask" "B.Paste")
			(net "SMB_CPU0_2_SCL")
		)
	)
	(footprint ""
		(layer "B.Cu")
		(at 50.214784 -408.517344 90)
		(property "Reference" "C6661"
			(at 0 0 90)
			(layer "B.SilkS")
			(hide yes)
			(effects
				(font
					(size 1.27 1.27)
				)
				(justify mirror)
			)
		)
		(property "Value" ""
			(at 0 0 90)
			(layer "B.Fab")
			(effects
				(font
					(size 1.27 1.27)
				)
				(justify mirror)
			)
		)
		(duplicate_pad_numbers_are_jumpers no)
		(fp_line
			(start 0.299974 -0.150114)
			(end -0.299974 -0.150114)
			(stroke
				(width 0.1)
				(type default)
			)
			(layer "B.Fab")
		)
		(fp_line
			(start -0.299974 -0.150114)
			(end -0.299974 0.150114)
			(stroke
				(width 0.1)
				(type default)
			)
			(layer "B.Fab")
		)
		(fp_line
			(start 0.299974 0.150114)
			(end 0.299974 -0.150114)
			(stroke
				(width 0.1)
				(type default)
			)
			(layer "B.Fab")
		)
		(fp_line
			(start -0.299974 0.150114)
			(end 0.299974 0.150114)
			(stroke
				(width 0.1)
				(type default)
			)
			(layer "B.Fab")
		)
		(pad "1" smd rect
			(at 0.2667 0 270)
			(size 0.3048 0.381)
			(layers "B.Cu" "B.Mask" "B.Paste")
			(net "P5E_CPU1_P1_TX_BUF_C_DP<0>")
		)
		(pad "2" smd rect
			(at -0.2667 0 270)
			(size 0.3048 0.381)
			(layers "B.Cu" "B.Mask" "B.Paste")
			(net "P5E_CPU1_P1_TX_BUF_DP<0>")
		)
	)
	(footprint ""
		(layer "B.Cu")
		(at 384.653282 -416.899344 90)
		(property "Reference" "C6606"
			(at 0 0 90)
			(layer "B.SilkS")
			(hide yes)
			(effects
				(font
					(size 1.27 1.27)
				)
				(justify mirror)
			)
		)
		(property "Value" ""
			(at 0 0 90)
			(layer "B.Fab")
			(effects
				(font
					(size 1.27 1.27)
				)
				(justify mirror)
			)
		)
		(duplicate_pad_numbers_are_jumpers no)
		(fp_line
			(start 0.299974 -0.150114)
			(end -0.299974 -0.150114)
			(stroke
				(width 0.1)
				(type default)
			)
			(layer "B.Fab")
		)
		(fp_line
			(start -0.299974 -0.150114)
			(end -0.299974 0.150114)
			(stroke
				(width 0.1)
				(type default)
			)
			(layer "B.Fab")
		)
		(fp_line
			(start 0.299974 0.150114)
			(end 0.299974 -0.150114)
			(stroke
				(width 0.1)
				(type default)
			)
			(layer "B.Fab")
		)
		(fp_line
			(start -0.299974 0.150114)
			(end 0.299974 0.150114)
			(stroke
				(width 0.1)
				(type default)
			)
			(layer "B.Fab")
		)
		(pad "1" smd rect
			(at 0.2667 0 270)
			(size 0.3048 0.381)
			(layers "B.Cu" "B.Mask" "B.Paste")
			(net "P5E_CPU0_P3_TX_BUF_C_DN<4>")
		)
		(pad "2" smd rect
			(at -0.2667 0 270)
			(size 0.3048 0.381)
			(layers "B.Cu" "B.Mask" "B.Paste")
			(net "P5E_CPU0_P3_TX_BUF_DN<4>")
		)
	)
	(footprint ""
		(layer "B.Cu")
		(at 191.000888 -126.861824 -90)
		(property "Reference" "R251"
			(at 0 0 90)
			(layer "B.SilkS")
			(hide yes)
			(effects
				(font
					(size 1.27 1.27)
				)
				(justify mirror)
			)
		)
		(property "Value" ""
			(at 0 0 90)
			(layer "B.Fab")
			(effects
				(font
					(size 1.27 1.27)
				)
				(justify mirror)
			)
		)
		(duplicate_pad_numbers_are_jumpers no)
		(fp_line
			(start -0.7874 0.4064)
			(end 0.7874 0.4064)
			(stroke
				(width 0.1524)
				(type default)
			)
			(layer "B.SilkS")
		)
		(fp_line
			(start 0.7874 0.4064)
			(end 0.7874 -0.4064)
			(stroke
				(width 0.1524)
				(type default)
			)
			(layer "B.SilkS")
		)
		(fp_line
			(start -0.7874 -0.4064)
			(end -0.7874 0.4064)
			(stroke
				(width 0.1524)
				(type default)
			)
			(layer "B.SilkS")
		)
		(fp_line
			(start 0.7874 -0.4064)
			(end -0.7874 -0.4064)
			(stroke
				(width 0.1524)
				(type default)
			)
			(layer "B.SilkS")
		)
		(fp_line
			(start -0.67945 0.3048)
			(end -0.120396 0.3048)
			(stroke
				(width 0.1)
				(type default)
			)
			(layer "B.Fab")
		)
		(fp_line
			(start -0.120396 0.3048)
			(end -0.120396 0.2794)
			(stroke
				(width 0.1)
				(type default)
			)
			(layer "B.Fab")
		)
		(fp_line
			(start 0.12065 0.3048)
			(end 0.67945 0.3048)
			(stroke
				(width 0.1)
				(type default)
			)
			(layer "B.Fab")
		)
		(fp_line
			(start 0.67945 0.3048)
			(end 0.67945 -0.305054)
			(stroke
				(width 0.1)
				(type default)
			)
			(layer "B.Fab")
		)
		(fp_line
			(start -0.120396 0.2794)
			(end 0.12065 0.2794)
			(stroke
				(width 0.1)
				(type default)
			)
			(layer "B.Fab")
		)
		(fp_line
			(start 0.12065 0.2794)
			(end 0.12065 0.3048)
			(stroke
				(width 0.1)
				(type default)
			)
			(layer "B.Fab")
		)
		(fp_line
			(start -0.12065 -0.2794)
			(end -0.12065 -0.3048)
			(stroke
				(width 0.1)
				(type default)
			)
			(layer "B.Fab")
		)
		(fp_line
			(start 0.12065 -0.2794)
			(end -0.12065 -0.2794)
			(stroke
				(width 0.1)
				(type default)
			)
			(layer "B.Fab")
		)
		(fp_line
			(start -0.67945 -0.3048)
			(end -0.67945 0.3048)
			(stroke
				(width 0.1)
				(type default)
			)
			(layer "B.Fab")
		)
		(fp_line
			(start -0.12065 -0.3048)
			(end -0.67945 -0.3048)
			(stroke
				(width 0.1)
				(type default)
			)
			(layer "B.Fab")
		)
		(fp_line
			(start 0.12065 -0.305054)
			(end 0.12065 -0.2794)
			(stroke
				(width 0.1)
				(type default)
			)
			(layer "B.Fab")
		)
		(fp_line
			(start 0.67945 -0.305054)
			(end 0.12065 -0.305054)
			(stroke
				(width 0.1)
				(type default)
			)
			(layer "B.Fab")
		)
		(pad "1" smd circle
			(at 0.40005 0 90)
			(size 0 0)
			(layers "B.Cu" "B.Mask" "B.Paste")
			(net "CPU0_SPD_HOST_CTRL_R1_N")
		)
		(pad "2" smd circle
			(at -0.40005 0 90)
			(size 0 0)
			(layers "B.Cu" "B.Mask" "B.Paste")
			(net "CPU0_SPD_HOST_CTRL_N")
		)
	)
	(footprint ""
		(layer "B.Cu")
		(at 522.584426 -298.381674 -90)
		(property "Reference" "X11"
			(at 3.303524 3.168396 270)
			(unlocked yes)
			(layer "B.SilkS")
			(effects
				(font
					(size 0.7874 0.5842)
					(thickness 0.1524)
				)
				(justify left mirror)
			)
		)
		(property "Value" ""
			(at 0 0 90)
			(layer "B.Fab")
			(effects
				(font
					(size 1.27 1.27)
				)
				(justify mirror)
			)
		)
		(property "User Part Number" "N_A"
			(at -1.30175 1.27 180)
			(unlocked yes)
			(layer "Cmts.User")
			(hide yes)
			(effects
				(font
					(size 0.635 0.4064)
					(thickness 0.1524)
				)
				(justify mirror)
			)
		)
		(property "Device Type" "TP_TDR_4P_FTS_TH-TP_TDR_4P_DIP,EMPTY,TP15"
			(at -1.30175 1.27 180)
			(unlocked yes)
			(layer "B.Fab")
			(hide yes)
			(effects
				(font
					(size 0.635 0.4064)
					(thickness 0.1524)
				)
				(justify mirror)
			)
		)
		(duplicate_pad_numbers_are_jumpers no)
		(fp_line
			(start -2.54 3.81)
			(end -2.54 3.6703)
			(stroke
				(width 0.1524)
				(type default)
			)
			(layer "B.SilkS")
		)
		(fp_line
			(start 0 3.81)
			(end -2.54 3.81)
			(stroke
				(width 0.1524)
				(type default)
			)
			(layer "B.SilkS")
		)
		(fp_line
			(start 0 3.175)
			(end 0 3.81)
			(stroke
				(width 0.1524)
				(type default)
			)
			(layer "B.SilkS")
		)
		(fp_line
			(start -2.54 1.4097)
			(end -2.54 1.1303)
			(stroke
				(width 0.1524)
				(type default)
			)
			(layer "B.SilkS")
		)
		(fp_line
			(start 0 0.635)
			(end 0 1.905)
			(stroke
				(width 0.1524)
				(type default)
			)
			(layer "B.SilkS")
		)
		(fp_line
			(start -2.54 -1.1303)
			(end -2.54 -1.27)
			(stroke
				(width 0.1524)
				(type default)
			)
			(layer "B.SilkS")
		)
		(fp_line
			(start -2.54 -1.27)
			(end 0 -1.27)
			(stroke
				(width 0.1524)
				(type default)
			)
			(layer "B.SilkS")
		)
		(fp_line
			(start 0 -1.27)
			(end 0 -0.635)
			(stroke
				(width 0.1524)
				(type default)
			)
			(layer "B.SilkS")
		)
		(fp_poly
			(pts
				(xy 2.285746 -0.762) (xy 2.285746 0.762) (xy 0.761746 0)
			)
			(stroke
				(width 0)
				(type default)
			)
			(fill yes)
			(layer "B.SilkS")
		)
		(fp_line
			(start -2.54 3.81)
			(end -2.54 -1.27)
			(stroke
				(width 0.1)
				(type default)
			)
			(layer "B.Fab")
		)
		(fp_line
			(start 0 3.81)
			(end -2.54 3.81)
			(stroke
				(width 0.1)
				(type default)
			)
			(layer "B.Fab")
		)
		(fp_line
			(start -2.54 -1.27)
			(end 0 -1.27)
			(stroke
				(width 0.1)
				(type default)
			)
			(layer "B.Fab")
		)
		(fp_line
			(start 0 -1.27)
			(end 0 3.81)
			(stroke
				(width 0.1)
				(type default)
			)
			(layer "B.Fab")
		)
		(fp_poly
			(pts
				(xy 0.761746 0) (xy 2.285746 -0.762) (xy 2.285746 0.762)
			)
			(stroke
				(width 0)
				(type default)
			)
			(fill yes)
			(layer "B.Fab")
		)
		(pad "1" thru_hole circle
			(at 0 0 90)
			(size 1.0033 1.0033)
			(drill 0.249936)
			(layers "*.Cu" "*.Mask")
			(remove_unused_layers no)
			(net "TDR_DIFF_80_IN4_DN")
			(clearance 0.10795)
			(padstack
				(mode front_inner_back)
				(layer "Inner"
					(shape circle)
					(size 0.8001 0.8001)
					(clearance 0.1524)
				)
				(layer "B.Cu"
					(shape circle)
					(size 1.0033 1.0033)
					(thermal_gap 0.10795)
					(clearance 0.10795)
				)
			)
		)
		(pad "2" thru_hole circle
			(at -2.54 0 90)
			(size 1.9939 1.9939)
			(drill 0.249936)
			(layers "*.Cu" "*.Mask")
			(remove_unused_layers no)
			(net "T1_GND")
			(clearance 0.10795)
			(padstack
				(mode front_inner_back)
				(layer "Inner"
					(shape circle)
					(size 0.8001 0.8001)
					(clearance 0.1524)
				)
				(layer "B.Cu"
					(shape circle)
					(size 1.9939 1.9939)
					(thermal_gap 0.10795)
					(clearance 0.10795)
				)
			)
		)
		(pad "3" thru_hole circle
			(at -2.54 2.54 90)
			(size 1.9939 1.9939)
			(drill 0.249936)
			(layers "*.Cu" "*.Mask")
			(remove_unused_layers no)
			(net "T1_GND")
			(clearance 0.10795)
			(padstack
				(mode front_inner_back)
				(layer "Inner"
					(shape circle)
					(size 0.8001 0.8001)
					(clearance 0.1524)
				)
				(layer "B.Cu"
					(shape circle)
					(size 1.9939 1.9939)
					(thermal_gap 0.10795)
					(clearance 0.10795)
				)
			)
		)
		(pad "4" thru_hole circle
			(at 0 2.54 90)
			(size 1.0033 1.0033)
			(drill 0.249936)
			(layers "*.Cu" "*.Mask")
			(remove_unused_layers no)
			(net "TDR_DIFF_80_IN4_DP")
			(clearance 0.10795)
			(padstack
				(mode front_inner_back)
				(layer "Inner"
					(shape circle)
					(size 0.8001 0.8001)
					(clearance 0.1524)
				)
				(layer "B.Cu"
					(shape circle)
					(size 1.0033 1.0033)
					(thermal_gap 0.10795)
					(clearance 0.10795)
				)
			)
		)
	)
	(footprint ""
		(layer "B.Cu")
		(at 115.70589 -258.795266 180)
		(property "Reference" "C2441"
			(at 0 0 0)
			(layer "B.SilkS")
			(hide yes)
			(effects
				(font
					(size 1.27 1.27)
				)
				(justify mirror)
			)
		)
		(property "Value" ""
			(at 0 0 0)
			(layer "B.Fab")
			(effects
				(font
					(size 1.27 1.27)
				)
				(justify mirror)
			)
		)
		(duplicate_pad_numbers_are_jumpers no)
		(fp_line
			(start 0.7874 0.4064)
			(end 0.7874 -0.4064)
			(stroke
				(width 0.1524)
				(type default)
			)
			(layer "B.SilkS")
		)
		(fp_line
			(start 0.7874 -0.4064)
			(end -0.7874 -0.4064)
			(stroke
				(width 0.1524)
				(type default)
			)
			(layer "B.SilkS")
		)
		(fp_line
			(start -0.7874 0.4064)
			(end 0.7874 0.4064)
			(stroke
				(width 0.1524)
				(type default)
			)
			(layer "B.SilkS")
		)
		(fp_line
			(start -0.7874 -0.4064)
			(end -0.7874 0.4064)
			(stroke
				(width 0.1524)
				(type default)
			)
			(layer "B.SilkS")
		)
		(fp_line
			(start 0.67945 0.3048)
			(end 0.67945 -0.305054)
			(stroke
				(width 0.1)
				(type default)
			)
			(layer "B.Fab")
		)
		(fp_line
			(start 0.67945 -0.305054)
			(end 0.12065 -0.305054)
			(stroke
				(width 0.1)
				(type default)
			)
			(layer "B.Fab")
		)
		(fp_line
			(start 0.12065 0.3048)
			(end 0.67945 0.3048)
			(stroke
				(width 0.1)
				(type default)
			)
			(layer "B.Fab")
		)
		(fp_line
			(start 0.12065 0.2794)
			(end 0.12065 0.3048)
			(stroke
				(width 0.1)
				(type default)
			)
			(layer "B.Fab")
		)
		(fp_line
			(start 0.12065 -0.2794)
			(end -0.12065 -0.2794)
			(stroke
				(width 0.1)
				(type default)
			)
			(layer "B.Fab")
		)
		(fp_line
			(start 0.12065 -0.305054)
			(end 0.12065 -0.2794)
			(stroke
				(width 0.1)
				(type default)
			)
			(layer "B.Fab")
		)
		(fp_line
			(start -0.120396 0.3048)
			(end -0.120396 0.2794)
			(stroke
				(width 0.1)
				(type default)
			)
			(layer "B.Fab")
		)
		(fp_line
			(start -0.120396 0.2794)
			(end 0.12065 0.2794)
			(stroke
				(width 0.1)
				(type default)
			)
			(layer "B.Fab")
		)
		(fp_line
			(start -0.12065 -0.2794)
			(end -0.12065 -0.3048)
			(stroke
				(width 0.1)
				(type default)
			)
			(layer "B.Fab")
		)
		(fp_line
			(start -0.12065 -0.3048)
			(end -0.67945 -0.3048)
			(stroke
				(width 0.1)
				(type default)
			)
			(layer "B.Fab")
		)
		(fp_line
			(start -0.67945 0.3048)
			(end -0.120396 0.3048)
			(stroke
				(width 0.1)
				(type default)
			)
			(layer "B.Fab")
		)
		(fp_line
			(start -0.67945 -0.3048)
			(end -0.67945 0.3048)
			(stroke
				(width 0.1)
				(type default)
			)
			(layer "B.Fab")
		)
		(pad "1" smd circle
			(at 0.40005 0)
			(size 0 0)
			(layers "B.Cu" "B.Mask" "B.Paste")
			(net "PVDDCR_SOC_P1")
		)
		(pad "2" smd circle
			(at -0.40005 0)
			(size 0 0)
			(layers "B.Cu" "B.Mask" "B.Paste")
			(net "GND")
		)
	)
	(footprint ""
		(layer "B.Cu")
		(at 187.96 -418.846 90)
		(property "Reference" "U8005"
			(at -2.277364 2.563622 270)
			(unlocked yes)
			(layer "B.SilkS")
			(effects
				(font
					(size 0.7874 0.5842)
					(thickness 0.1524)
				)
				(justify left mirror)
			)
		)
		(property "Value" ""
			(at 0 0 90)
			(layer "B.Fab")
			(effects
				(font
					(size 1.27 1.27)
				)
				(justify mirror)
			)
		)
		(duplicate_pad_numbers_are_jumpers no)
		(fp_line
			(start 1.868424 -1.519936)
			(end 1.868424 1.519936)
			(stroke
				(width 0.1524)
				(type default)
			)
			(layer "B.SilkS")
		)
		(fp_line
			(start -1.868424 -1.519936)
			(end 1.868424 -1.519936)
			(stroke
				(width 0.1524)
				(type default)
			)
			(layer "B.SilkS")
		)
		(fp_line
			(start 1.868424 1.519936)
			(end -1.868424 1.519936)
			(stroke
				(width 0.1524)
				(type default)
			)
			(layer "B.SilkS")
		)
		(fp_line
			(start -1.868424 1.519936)
			(end -1.868424 -1.519936)
			(stroke
				(width 0.1524)
				(type default)
			)
			(layer "B.SilkS")
		)
		(fp_line
			(start 0.700024 -1.519936)
			(end 0.700024 1.519936)
			(stroke
				(width 0.1)
				(type default)
			)
			(layer "B.Fab")
		)
		(fp_line
			(start -0.700024 -1.519936)
			(end 0.700024 -1.519936)
			(stroke
				(width 0.1)
				(type default)
			)
			(layer "B.Fab")
		)
		(fp_line
			(start 0.700024 1.519936)
			(end -0.700024 1.519936)
			(stroke
				(width 0.1)
				(type default)
			)
			(layer "B.Fab")
		)
		(fp_line
			(start -0.700024 1.519936)
			(end -0.700024 -1.519936)
			(stroke
				(width 0.1)
				(type default)
			)
			(layer "B.Fab")
		)
		(pad "1" smd rect
			(at 1.18491 -0.94996)
			(size 0.6096 1.0668)
			(layers "B.Cu" "B.Mask" "B.Paste")
			(net "OC_P2V5_COMP")
		)
		(pad "2" smd rect
			(at 1.18491 0.94996)
			(size 0.6096 1.0668)
			(layers "B.Cu" "B.Mask" "B.Paste")
			(net "GND")
		)
		(pad "3" smd rect
			(at -1.18491 0)
			(size 0.6096 1.0668)
			(layers "B.Cu" "B.Mask" "B.Paste")
			(net "Net_10848")
		)
	)
	(footprint ""
		(layer "B.Cu")
		(at 121.8184 -388.011162 -90)
		(property "Reference" "C440"
			(at 0 0 90)
			(layer "B.SilkS")
			(hide yes)
			(effects
				(font
					(size 1.27 1.27)
				)
				(justify mirror)
			)
		)
		(property "Value" ""
			(at 0 0 90)
			(layer "B.Fab")
			(effects
				(font
					(size 1.27 1.27)
				)
				(justify mirror)
			)
		)
		(duplicate_pad_numbers_are_jumpers no)
		(fp_line
			(start -0.299974 0.150114)
			(end 0.299974 0.150114)
			(stroke
				(width 0.1)
				(type default)
			)
			(layer "B.Fab")
		)
		(fp_line
			(start 0.299974 0.150114)
			(end 0.299974 -0.150114)
			(stroke
				(width 0.1)
				(type default)
			)
			(layer "B.Fab")
		)
		(fp_line
			(start -0.299974 -0.150114)
			(end -0.299974 0.150114)
			(stroke
				(width 0.1)
				(type default)
			)
			(layer "B.Fab")
		)
		(fp_line
			(start 0.299974 -0.150114)
			(end -0.299974 -0.150114)
			(stroke
				(width 0.1)
				(type default)
			)
			(layer "B.Fab")
		)
		(pad "1" smd rect
			(at 0.2667 0 90)
			(size 0.3048 0.381)
			(layers "B.Cu" "B.Mask" "B.Paste")
			(net "P1V8_CPU1_RT3_1A")
		)
		(pad "2" smd rect
			(at -0.2667 0 90)
			(size 0.3048 0.381)
			(layers "B.Cu" "B.Mask" "B.Paste")
			(net "GND")
		)
	)
	(footprint ""
		(layer "B.Cu")
		(at 125.291342 -390.560052 90)
		(property "Reference" "C478"
			(at 0 0 90)
			(layer "B.SilkS")
			(hide yes)
			(effects
				(font
					(size 1.27 1.27)
				)
				(justify mirror)
			)
		)
		(property "Value" ""
			(at 0 0 90)
			(layer "B.Fab")
			(effects
				(font
					(size 1.27 1.27)
				)
				(justify mirror)
			)
		)
		(duplicate_pad_numbers_are_jumpers no)
		(fp_line
			(start 0.7874 -0.4064)
			(end -0.7874 -0.4064)
			(stroke
				(width 0.1524)
				(type default)
			)
			(layer "B.SilkS")
		)
		(fp_line
			(start -0.7874 -0.4064)
			(end -0.7874 0.4064)
			(stroke
				(width 0.1524)
				(type default)
			)
			(layer "B.SilkS")
		)
		(fp_line
			(start 0.7874 0.4064)
			(end 0.7874 -0.4064)
			(stroke
				(width 0.1524)
				(type default)
			)
			(layer "B.SilkS")
		)
		(fp_line
			(start -0.7874 0.4064)
			(end 0.7874 0.4064)
			(stroke
				(width 0.1524)
				(type default)
			)
			(layer "B.SilkS")
		)
		(fp_line
			(start 0.67945 -0.305054)
			(end 0.12065 -0.305054)
			(stroke
				(width 0.1)
				(type default)
			)
			(layer "B.Fab")
		)
		(fp_line
			(start 0.12065 -0.305054)
			(end 0.12065 -0.2794)
			(stroke
				(width 0.1)
				(type default)
			)
			(layer "B.Fab")
		)
		(fp_line
			(start -0.12065 -0.3048)
			(end -0.67945 -0.3048)
			(stroke
				(width 0.1)
				(type default)
			)
			(layer "B.Fab")
		)
		(fp_line
			(start -0.67945 -0.3048)
			(end -0.67945 0.3048)
			(stroke
				(width 0.1)
				(type default)
			)
			(layer "B.Fab")
		)
		(fp_line
			(start 0.12065 -0.2794)
			(end -0.12065 -0.2794)
			(stroke
				(width 0.1)
				(type default)
			)
			(layer "B.Fab")
		)
		(fp_line
			(start -0.12065 -0.2794)
			(end -0.12065 -0.3048)
			(stroke
				(width 0.1)
				(type default)
			)
			(layer "B.Fab")
		)
		(fp_line
			(start 0.12065 0.2794)
			(end 0.12065 0.3048)
			(stroke
				(width 0.1)
				(type default)
			)
			(layer "B.Fab")
		)
		(fp_line
			(start -0.120396 0.2794)
			(end 0.12065 0.2794)
			(stroke
				(width 0.1)
				(type default)
			)
			(layer "B.Fab")
		)
		(fp_line
			(start 0.67945 0.3048)
			(end 0.67945 -0.305054)
			(stroke
				(width 0.1)
				(type default)
			)
			(layer "B.Fab")
		)
		(fp_line
			(start 0.12065 0.3048)
			(end 0.67945 0.3048)
			(stroke
				(width 0.1)
				(type default)
			)
			(layer "B.Fab")
		)
		(fp_line
			(start -0.120396 0.3048)
			(end -0.120396 0.2794)
			(stroke
				(width 0.1)
				(type default)
			)
			(layer "B.Fab")
		)
		(fp_line
			(start -0.67945 0.3048)
			(end -0.120396 0.3048)
			(stroke
				(width 0.1)
				(type default)
			)
			(layer "B.Fab")
		)
		(pad "1" smd circle
			(at 0.40005 0 270)
			(size 0 0)
			(layers "B.Cu" "B.Mask" "B.Paste")
			(net "P0V9_CPU1_RT_2D")
		)
		(pad "2" smd circle
			(at -0.40005 0 270)
			(size 0 0)
			(layers "B.Cu" "B.Mask" "B.Paste")
			(net "GND")
		)
	)
	(footprint ""
		(layer "B.Cu")
		(at 65.3796 -15.8496)
		(property "Reference" "C1834"
			(at 0 0 0)
			(layer "B.SilkS")
			(hide yes)
			(effects
				(font
					(size 1.27 1.27)
				)
				(justify mirror)
			)
		)
		(property "Value" ""
			(at 0 0 0)
			(layer "B.Fab")
			(effects
				(font
					(size 1.27 1.27)
				)
				(justify mirror)
			)
		)
		(duplicate_pad_numbers_are_jumpers no)
		(fp_line
			(start -0.7874 -0.4064)
			(end -0.7874 0.4064)
			(stroke
				(width 0.1524)
				(type default)
			)
			(layer "B.SilkS")
		)
		(fp_line
			(start -0.7874 0.4064)
			(end 0.7874 0.4064)
			(stroke
				(width 0.1524)
				(type default)
			)
			(layer "B.SilkS")
		)
		(fp_line
			(start 0.7874 -0.4064)
			(end -0.7874 -0.4064)
			(stroke
				(width 0.1524)
				(type default)
			)
			(layer "B.SilkS")
		)
		(fp_line
			(start 0.7874 0.4064)
			(end 0.7874 -0.4064)
			(stroke
				(width 0.1524)
				(type default)
			)
			(layer "B.SilkS")
		)
		(fp_line
			(start -0.67945 -0.3048)
			(end -0.67945 0.3048)
			(stroke
				(width 0.1)
				(type default)
			)
			(layer "B.Fab")
		)
		(fp_line
			(start -0.67945 0.3048)
			(end -0.120396 0.3048)
			(stroke
				(width 0.1)
				(type default)
			)
			(layer "B.Fab")
		)
		(fp_line
			(start -0.12065 -0.3048)
			(end -0.67945 -0.3048)
			(stroke
				(width 0.1)
				(type default)
			)
			(layer "B.Fab")
		)
		(fp_line
			(start -0.12065 -0.2794)
			(end -0.12065 -0.3048)
			(stroke
				(width 0.1)
				(type default)
			)
			(layer "B.Fab")
		)
		(fp_line
			(start -0.120396 0.2794)
			(end 0.12065 0.2794)
			(stroke
				(width 0.1)
				(type default)
			)
			(layer "B.Fab")
		)
		(fp_line
			(start -0.120396 0.3048)
			(end -0.120396 0.2794)
			(stroke
				(width 0.1)
				(type default)
			)
			(layer "B.Fab")
		)
		(fp_line
			(start 0.12065 -0.305054)
			(end 0.12065 -0.2794)
			(stroke
				(width 0.1)
				(type default)
			)
			(layer "B.Fab")
		)
		(fp_line
			(start 0.12065 -0.2794)
			(end -0.12065 -0.2794)
			(stroke
				(width 0.1)
				(type default)
			)
			(layer "B.Fab")
		)
		(fp_line
			(start 0.12065 0.2794)
			(end 0.12065 0.3048)
			(stroke
				(width 0.1)
				(type default)
			)
			(layer "B.Fab")
		)
		(fp_line
			(start 0.12065 0.3048)
			(end 0.67945 0.3048)
			(stroke
				(width 0.1)
				(type default)
			)
			(layer "B.Fab")
		)
		(fp_line
			(start 0.67945 -0.305054)
			(end 0.12065 -0.305054)
			(stroke
				(width 0.1)
				(type default)
			)
			(layer "B.Fab")
		)
		(fp_line
			(start 0.67945 0.3048)
			(end 0.67945 -0.305054)
			(stroke
				(width 0.1)
				(type default)
			)
			(layer "B.Fab")
		)
		(pad "1" smd circle
			(at 0.40005 0 180)
			(size 0 0)
			(layers "B.Cu" "B.Mask" "B.Paste")
			(net "P12V_OCP_V3_2_R")
		)
		(pad "2" smd circle
			(at -0.40005 0 180)
			(size 0 0)
			(layers "B.Cu" "B.Mask" "B.Paste")
			(net "GND")
		)
	)
	(footprint ""
		(layer "B.Cu")
		(at 213.02091 -324.262242 180)
		(property "Reference" "L25"
			(at 0 0 0)
			(layer "B.SilkS")
			(hide yes)
			(effects
				(font
					(size 1.27 1.27)
				)
				(justify mirror)
			)
		)
		(property "Value" ""
			(at 0 0 0)
			(layer "B.Fab")
			(effects
				(font
					(size 1.27 1.27)
				)
				(justify mirror)
			)
		)
		(duplicate_pad_numbers_are_jumpers no)
		(fp_line
			(start 1.27 0.5842)
			(end 1.27 -0.5842)
			(stroke
				(width 0.1524)
				(type default)
			)
			(layer "B.SilkS")
		)
		(fp_line
			(start 1.27 -0.5588)
			(end 1.27 -0.5842)
			(stroke
				(width 0.1524)
				(type default)
			)
			(layer "B.SilkS")
		)
		(fp_line
			(start 1.27 -0.5842)
			(end -1.27 -0.5842)
			(stroke
				(width 0.1524)
				(type default)
			)
			(layer "B.SilkS")
		)
		(fp_line
			(start -1.27 0.5842)
			(end 1.27 0.5842)
			(stroke
				(width 0.1524)
				(type default)
			)
			(layer "B.SilkS")
		)
		(fp_line
			(start -1.27 0.5842)
			(end -1.27 -0.5842)
			(stroke
				(width 0.1524)
				(type default)
			)
			(layer "B.SilkS")
		)
		(fp_line
			(start 1.194308 0.406654)
			(end 1.194308 -0.406654)
			(stroke
				(width 0.1)
				(type default)
			)
			(layer "B.Fab")
		)
		(fp_line
			(start 1.194308 -0.406654)
			(end 0.9144 -0.406654)
			(stroke
				(width 0.1)
				(type default)
			)
			(layer "B.Fab")
		)
		(fp_line
			(start 0.9144 0.508)
			(end 0.9144 0.406654)
			(stroke
				(width 0.1)
				(type default)
			)
			(layer "B.Fab")
		)
		(fp_line
			(start 0.9144 0.406654)
			(end 1.194308 0.406654)
			(stroke
				(width 0.1)
				(type default)
			)
			(layer "B.Fab")
		)
		(fp_line
			(start 0.9144 -0.406654)
			(end 0.9144 -0.508)
			(stroke
				(width 0.1)
				(type default)
			)
			(layer "B.Fab")
		)
		(fp_line
			(start 0.9144 -0.508)
			(end -0.9144 -0.508)
			(stroke
				(width 0.1)
				(type default)
			)
			(layer "B.Fab")
		)
		(fp_line
			(start -0.9144 0.508)
			(end 0.9144 0.508)
			(stroke
				(width 0.1)
				(type default)
			)
			(layer "B.Fab")
		)
		(fp_line
			(start -0.9144 0.4064)
			(end -0.9144 0.508)
			(stroke
				(width 0.1)
				(type default)
			)
			(layer "B.Fab")
		)
		(fp_line
			(start -0.9144 -0.406654)
			(end -1.1938 -0.406654)
			(stroke
				(width 0.1)
				(type default)
			)
			(layer "B.Fab")
		)
		(fp_line
			(start -0.9144 -0.508)
			(end -0.9144 -0.406654)
			(stroke
				(width 0.1)
				(type default)
			)
			(layer "B.Fab")
		)
		(fp_line
			(start -1.1938 0.4064)
			(end -0.9144 0.4064)
			(stroke
				(width 0.1)
				(type default)
			)
			(layer "B.Fab")
		)
		(fp_line
			(start -1.1938 -0.406654)
			(end -1.1938 0.4064)
			(stroke
				(width 0.1)
				(type default)
			)
			(layer "B.Fab")
		)
		(pad "1" smd rect
			(at 0.7366 0 90)
			(size 0.7112 0.8128)
			(layers "B.Cu" "B.Mask" "B.Paste")
			(net "P3V3_AUX")
		)
		(pad "2" smd rect
			(at -0.7366 0 90)
			(size 0.7112 0.8128)
			(layers "B.Cu" "B.Mask" "B.Paste")
			(net "P3V3_ADC128_2_VCC")
		)
	)
	(footprint ""
		(layer "B.Cu")
		(at 383.818384 -396.393162 -90)
		(property "Reference" "C1014"
			(at 0 0 90)
			(layer "B.SilkS")
			(hide yes)
			(effects
				(font
					(size 1.27 1.27)
				)
				(justify mirror)
			)
		)
		(property "Value" ""
			(at 0 0 90)
			(layer "B.Fab")
			(effects
				(font
					(size 1.27 1.27)
				)
				(justify mirror)
			)
		)
		(duplicate_pad_numbers_are_jumpers no)
		(fp_line
			(start -0.299974 0.150114)
			(end 0.299974 0.150114)
			(stroke
				(width 0.1)
				(type default)
			)
			(layer "B.Fab")
		)
		(fp_line
			(start 0.299974 0.150114)
			(end 0.299974 -0.150114)
			(stroke
				(width 0.1)
				(type default)
			)
			(layer "B.Fab")
		)
		(fp_line
			(start -0.299974 -0.150114)
			(end -0.299974 0.150114)
			(stroke
				(width 0.1)
				(type default)
			)
			(layer "B.Fab")
		)
		(fp_line
			(start 0.299974 -0.150114)
			(end -0.299974 -0.150114)
			(stroke
				(width 0.1)
				(type default)
			)
			(layer "B.Fab")
		)
		(pad "1" smd rect
			(at 0.2667 0 90)
			(size 0.3048 0.381)
			(layers "B.Cu" "B.Mask" "B.Paste")
			(net "P0V9_CPU0_RT3_2A_2D")
		)
		(pad "2" smd rect
			(at -0.2667 0 90)
			(size 0.3048 0.381)
			(layers "B.Cu" "B.Mask" "B.Paste")
			(net "GND")
		)
	)
	(footprint ""
		(layer "B.Cu")
		(at 222.408242 -326.534272 180)
		(property "Reference" "U51"
			(at 0.015494 -3.693922 0)
			(unlocked yes)
			(layer "B.SilkS")
			(effects
				(font
					(size 0.7874 0.5842)
					(thickness 0.1524)
				)
				(justify left mirror)
			)
		)
		(property "Value" ""
			(at 0 0 0)
			(layer "B.Fab")
			(effects
				(font
					(size 1.27 1.27)
				)
				(justify mirror)
			)
		)
		(duplicate_pad_numbers_are_jumpers no)
		(fp_line
			(start 1.868932 2.549906)
			(end -1.868932 2.549906)
			(stroke
				(width 0.1524)
				(type default)
			)
			(layer "B.SilkS")
		)
		(fp_line
			(start 1.868932 -2.549906)
			(end 1.868932 2.549906)
			(stroke
				(width 0.1524)
				(type default)
			)
			(layer "B.SilkS")
		)
		(fp_line
			(start 1.025906 -2.549906)
			(end 1.868932 -2.549906)
			(stroke
				(width 0.1524)
				(type default)
			)
			(layer "B.SilkS")
		)
		(fp_line
			(start 0 -1.524)
			(end 1.025906 -2.549906)
			(stroke
				(width 0.1524)
				(type default)
			)
			(layer "B.SilkS")
		)
		(fp_line
			(start -1.025906 -2.549906)
			(end 0 -1.524)
			(stroke
				(width 0.1524)
				(type default)
			)
			(layer "B.SilkS")
		)
		(fp_line
			(start -1.868932 2.549906)
			(end -1.868932 -2.549906)
			(stroke
				(width 0.1524)
				(type default)
			)
			(layer "B.SilkS")
		)
		(fp_line
			(start -1.868932 -2.549906)
			(end -1.025906 -2.549906)
			(stroke
				(width 0.1524)
				(type default)
			)
			(layer "B.SilkS")
		)
		(fp_poly
			(pts
				(xy 4.948682 -3.169666) (xy 4.290822 -3.943858) (xy 3.84556 -2.898902)
			)
			(stroke
				(width 0)
				(type default)
			)
			(fill yes)
			(layer "B.SilkS")
		)
		(fp_line
			(start 2.249932 2.549906)
			(end -2.249932 2.549906)
			(stroke
				(width 0.1)
				(type default)
			)
			(layer "B.Fab")
		)
		(fp_line
			(start 2.249932 -2.549906)
			(end 2.249932 2.549906)
			(stroke
				(width 0.1)
				(type default)
			)
			(layer "B.Fab")
		)
		(fp_line
			(start -2.249932 2.549906)
			(end -2.249932 -2.549906)
			(stroke
				(width 0.1)
				(type default)
			)
			(layer "B.Fab")
		)
		(fp_line
			(start -2.249932 -2.549906)
			(end 2.249932 -2.549906)
			(stroke
				(width 0.1)
				(type default)
			)
			(layer "B.Fab")
		)
		(fp_poly
			(pts
				(xy 4.7752 -1.787398) (xy 4.7752 -2.803398) (xy 3.7592 -2.295398)
			)
			(stroke
				(width 0)
				(type default)
			)
			(fill yes)
			(layer "B.Fab")
		)
		(pad "1" smd rect
			(at 2.800096 -2.275078 90)
			(size 0.3556 1.6002)
			(layers "B.Cu" "B.Mask" "B.Paste")
			(net "ADC128_2_VREF")
		)
		(pad "2" smd rect
			(at 2.800096 -1.625092 90)
			(size 0.3556 1.6002)
			(layers "B.Cu" "B.Mask" "B.Paste")
			(net "SMB_SEN_TIC_2_3V3AUX_SDA")
		)
		(pad "3" smd rect
			(at 2.800096 -0.975106 90)
			(size 0.3556 1.6002)
			(layers "B.Cu" "B.Mask" "B.Paste")
			(net "SMB_SEN_TIC_2_3V3AUX_SCL")
		)
		(pad "4" smd rect
			(at 2.800096 -0.32512 90)
			(size 0.3556 1.6002)
			(layers "B.Cu" "B.Mask" "B.Paste")
			(net "GND")
		)
		(pad "5" smd rect
			(at 2.800096 0.32512 90)
			(size 0.3556 1.6002)
			(layers "B.Cu" "B.Mask" "B.Paste")
			(net "P3V3_ADC128_2_VCC")
		)
		(pad "6" smd rect
			(at 2.800096 0.975106 90)
			(size 0.3556 1.6002)
			(layers "B.Cu" "B.Mask" "B.Paste")
			(net "TP_ADC128_2_INT")
		)
		(pad "7" smd rect
			(at 2.800096 1.625092 90)
			(size 0.3556 1.6002)
			(layers "B.Cu" "B.Mask" "B.Paste")
			(net "ADC128_2_A0")
		)
		(pad "8" smd rect
			(at 2.800096 2.275078 90)
			(size 0.3556 1.6002)
			(layers "B.Cu" "B.Mask" "B.Paste")
			(net "ADC128_2_A1")
		)
		(pad "9" smd rect
			(at -2.800096 2.275078 90)
			(size 0.3556 1.6002)
			(layers "B.Cu" "B.Mask" "B.Paste")
			(net "PVDD18_S5_P1_ADC_TIC")
		)
		(pad "10" smd rect
			(at -2.800096 1.625092 90)
			(size 0.3556 1.6002)
			(layers "B.Cu" "B.Mask" "B.Paste")
			(net "PVDD18_S5_P0_ADC_TIC")
		)
		(pad "11" smd rect
			(at -2.800096 0.975106 90)
			(size 0.3556 1.6002)
			(layers "B.Cu" "B.Mask" "B.Paste")
			(net "PVDD_33_S5_ADC_TIC")
		)
		(pad "12" smd rect
			(at -2.800096 0.32512 90)
			(size 0.3556 1.6002)
			(layers "B.Cu" "B.Mask" "B.Paste")
			(net "P1V8_CPU1_RT_1D_ADC_TIC")
		)
		(pad "13" smd rect
			(at -2.800096 -0.32512 90)
			(size 0.3556 1.6002)
			(layers "B.Cu" "B.Mask" "B.Paste")
			(net "P1V8_CPU0_RT_1D_ADC_TIC")
		)
		(pad "14" smd rect
			(at -2.800096 -0.975106 90)
			(size 0.3556 1.6002)
			(layers "B.Cu" "B.Mask" "B.Paste")
			(net "P1V2_AUX_ADC_TIC")
		)
		(pad "15" smd rect
			(at -2.800096 -1.625092 90)
			(size 0.3556 1.6002)
			(layers "B.Cu" "B.Mask" "B.Paste")
			(net "P1V8_AUX_ADC_TIC")
		)
		(pad "16" smd rect
			(at -2.800096 -2.275078 90)
			(size 0.3556 1.6002)
			(layers "B.Cu" "B.Mask" "B.Paste")
			(net "P5V_AUX_ADC_TIC")
		)
	)
	(footprint ""
		(layer "B.Cu")
		(at 231.029002 -329.365102)
		(property "Reference" "R1256"
			(at 0 0 0)
			(layer "B.SilkS")
			(hide yes)
			(effects
				(font
					(size 1.27 1.27)
				)
				(justify mirror)
			)
		)
		(property "Value" ""
			(at 0 0 0)
			(layer "B.Fab")
			(effects
				(font
					(size 1.27 1.27)
				)
				(justify mirror)
			)
		)
		(duplicate_pad_numbers_are_jumpers no)
		(fp_line
			(start -0.7874 -0.4064)
			(end -0.7874 0.4064)
			(stroke
				(width 0.1524)
				(type default)
			)
			(layer "B.SilkS")
		)
		(fp_line
			(start -0.7874 0.4064)
			(end 0.7874 0.4064)
			(stroke
				(width 0.1524)
				(type default)
			)
			(layer "B.SilkS")
		)
		(fp_line
			(start 0.7874 -0.4064)
			(end -0.7874 -0.4064)
			(stroke
				(width 0.1524)
				(type default)
			)
			(layer "B.SilkS")
		)
		(fp_line
			(start 0.7874 0.4064)
			(end 0.7874 -0.4064)
			(stroke
				(width 0.1524)
				(type default)
			)
			(layer "B.SilkS")
		)
		(fp_line
			(start -0.67945 -0.3048)
			(end -0.67945 0.3048)
			(stroke
				(width 0.1)
				(type default)
			)
			(layer "B.Fab")
		)
		(fp_line
			(start -0.67945 0.3048)
			(end -0.120396 0.3048)
			(stroke
				(width 0.1)
				(type default)
			)
			(layer "B.Fab")
		)
		(fp_line
			(start -0.12065 -0.3048)
			(end -0.67945 -0.3048)
			(stroke
				(width 0.1)
				(type default)
			)
			(layer "B.Fab")
		)
		(fp_line
			(start -0.12065 -0.2794)
			(end -0.12065 -0.3048)
			(stroke
				(width 0.1)
				(type default)
			)
			(layer "B.Fab")
		)
		(fp_line
			(start -0.120396 0.2794)
			(end 0.12065 0.2794)
			(stroke
				(width 0.1)
				(type default)
			)
			(layer "B.Fab")
		)
		(fp_line
			(start -0.120396 0.3048)
			(end -0.120396 0.2794)
			(stroke
				(width 0.1)
				(type default)
			)
			(layer "B.Fab")
		)
		(fp_line
			(start 0.12065 -0.305054)
			(end 0.12065 -0.2794)
			(stroke
				(width 0.1)
				(type default)
			)
			(layer "B.Fab")
		)
		(fp_line
			(start 0.12065 -0.2794)
			(end -0.12065 -0.2794)
			(stroke
				(width 0.1)
				(type default)
			)
			(layer "B.Fab")
		)
		(fp_line
			(start 0.12065 0.2794)
			(end 0.12065 0.3048)
			(stroke
				(width 0.1)
				(type default)
			)
			(layer "B.Fab")
		)
		(fp_line
			(start 0.12065 0.3048)
			(end 0.67945 0.3048)
			(stroke
				(width 0.1)
				(type default)
			)
			(layer "B.Fab")
		)
		(fp_line
			(start 0.67945 -0.305054)
			(end 0.12065 -0.305054)
			(stroke
				(width 0.1)
				(type default)
			)
			(layer "B.Fab")
		)
		(fp_line
			(start 0.67945 0.3048)
			(end 0.67945 -0.305054)
			(stroke
				(width 0.1)
				(type default)
			)
			(layer "B.Fab")
		)
		(pad "1" smd rect
			(at 0.40005 0)
			(size 0.4572 0.508)
			(layers "B.Cu" "B.Mask" "B.Paste")
			(net "PVDD18_S5_P1_ADC")
		)
		(pad "2" smd rect
			(at -0.40005 0)
			(size 0.4572 0.508)
			(layers "B.Cu" "B.Mask" "B.Paste")
			(net "PVDD18_S5_P1_ADC_TIC")
		)
	)
	(footprint ""
		(layer "B.Cu")
		(at 50.718974 -418.707316 180)
		(property "Reference" "R5234"
			(at 0 0 0)
			(layer "B.SilkS")
			(hide yes)
			(effects
				(font
					(size 1.27 1.27)
				)
				(justify mirror)
			)
		)
		(property "Value" ""
			(at 0 0 0)
			(layer "B.Fab")
			(effects
				(font
					(size 1.27 1.27)
				)
				(justify mirror)
			)
		)
		(duplicate_pad_numbers_are_jumpers no)
		(fp_line
			(start 0.7874 0.4064)
			(end 0.7874 -0.4064)
			(stroke
				(width 0.1524)
				(type default)
			)
			(layer "B.SilkS")
		)
		(fp_line
			(start 0.7874 -0.4064)
			(end -0.7874 -0.4064)
			(stroke
				(width 0.1524)
				(type default)
			)
			(layer "B.SilkS")
		)
		(fp_line
			(start -0.7874 0.4064)
			(end 0.7874 0.4064)
			(stroke
				(width 0.1524)
				(type default)
			)
			(layer "B.SilkS")
		)
		(fp_line
			(start -0.7874 -0.4064)
			(end -0.7874 0.4064)
			(stroke
				(width 0.1524)
				(type default)
			)
			(layer "B.SilkS")
		)
		(fp_line
			(start 0.67945 0.3048)
			(end 0.67945 -0.305054)
			(stroke
				(width 0.1)
				(type default)
			)
			(layer "B.Fab")
		)
		(fp_line
			(start 0.67945 -0.305054)
			(end 0.12065 -0.305054)
			(stroke
				(width 0.1)
				(type default)
			)
			(layer "B.Fab")
		)
		(fp_line
			(start 0.12065 0.3048)
			(end 0.67945 0.3048)
			(stroke
				(width 0.1)
				(type default)
			)
			(layer "B.Fab")
		)
		(fp_line
			(start 0.12065 0.2794)
			(end 0.12065 0.3048)
			(stroke
				(width 0.1)
				(type default)
			)
			(layer "B.Fab")
		)
		(fp_line
			(start 0.12065 -0.2794)
			(end -0.12065 -0.2794)
			(stroke
				(width 0.1)
				(type default)
			)
			(layer "B.Fab")
		)
		(fp_line
			(start 0.12065 -0.305054)
			(end 0.12065 -0.2794)
			(stroke
				(width 0.1)
				(type default)
			)
			(layer "B.Fab")
		)
		(fp_line
			(start -0.120396 0.3048)
			(end -0.120396 0.2794)
			(stroke
				(width 0.1)
				(type default)
			)
			(layer "B.Fab")
		)
		(fp_line
			(start -0.120396 0.2794)
			(end 0.12065 0.2794)
			(stroke
				(width 0.1)
				(type default)
			)
			(layer "B.Fab")
		)
		(fp_line
			(start -0.12065 -0.2794)
			(end -0.12065 -0.3048)
			(stroke
				(width 0.1)
				(type default)
			)
			(layer "B.Fab")
		)
		(fp_line
			(start -0.12065 -0.3048)
			(end -0.67945 -0.3048)
			(stroke
				(width 0.1)
				(type default)
			)
			(layer "B.Fab")
		)
		(fp_line
			(start -0.67945 0.3048)
			(end -0.120396 0.3048)
			(stroke
				(width 0.1)
				(type default)
			)
			(layer "B.Fab")
		)
		(fp_line
			(start -0.67945 -0.3048)
			(end -0.67945 0.3048)
			(stroke
				(width 0.1)
				(type default)
			)
			(layer "B.Fab")
		)
		(pad "1" smd circle
			(at 0.40005 0)
			(size 0 0)
			(layers "B.Cu" "B.Mask" "B.Paste")
			(net "USB2_HUB_BUF_SWB_R_DP")
		)
		(pad "2" smd circle
			(at -0.40005 0)
			(size 0 0)
			(layers "B.Cu" "B.Mask" "B.Paste")
			(net "USB2_HUB_BUF_SWB_DP")
		)
	)
	(footprint ""
		(layer "B.Cu")
		(at 357.515922 -256.012188 -90)
		(property "Reference" "C2546"
			(at 0 0 90)
			(layer "B.SilkS")
			(hide yes)
			(effects
				(font
					(size 1.27 1.27)
				)
				(justify mirror)
			)
		)
		(property "Value" ""
			(at 0 0 90)
			(layer "B.Fab")
			(effects
				(font
					(size 1.27 1.27)
				)
				(justify mirror)
			)
		)
		(duplicate_pad_numbers_are_jumpers no)
		(fp_line
			(start -0.7874 0.4064)
			(end 0.7874 0.4064)
			(stroke
				(width 0.1524)
				(type default)
			)
			(layer "B.SilkS")
		)
		(fp_line
			(start 0.7874 0.4064)
			(end 0.7874 -0.4064)
			(stroke
				(width 0.1524)
				(type default)
			)
			(layer "B.SilkS")
		)
		(fp_line
			(start -0.7874 -0.4064)
			(end -0.7874 0.4064)
			(stroke
				(width 0.1524)
				(type default)
			)
			(layer "B.SilkS")
		)
		(fp_line
			(start 0.7874 -0.4064)
			(end -0.7874 -0.4064)
			(stroke
				(width 0.1524)
				(type default)
			)
			(layer "B.SilkS")
		)
		(fp_line
			(start -0.67945 0.3048)
			(end -0.120396 0.3048)
			(stroke
				(width 0.1)
				(type default)
			)
			(layer "B.Fab")
		)
		(fp_line
			(start -0.120396 0.3048)
			(end -0.120396 0.2794)
			(stroke
				(width 0.1)
				(type default)
			)
			(layer "B.Fab")
		)
		(fp_line
			(start 0.12065 0.3048)
			(end 0.67945 0.3048)
			(stroke
				(width 0.1)
				(type default)
			)
			(layer "B.Fab")
		)
		(fp_line
			(start 0.67945 0.3048)
			(end 0.67945 -0.305054)
			(stroke
				(width 0.1)
				(type default)
			)
			(layer "B.Fab")
		)
		(fp_line
			(start -0.120396 0.2794)
			(end 0.12065 0.2794)
			(stroke
				(width 0.1)
				(type default)
			)
			(layer "B.Fab")
		)
		(fp_line
			(start 0.12065 0.2794)
			(end 0.12065 0.3048)
			(stroke
				(width 0.1)
				(type default)
			)
			(layer "B.Fab")
		)
		(fp_line
			(start -0.12065 -0.2794)
			(end -0.12065 -0.3048)
			(stroke
				(width 0.1)
				(type default)
			)
			(layer "B.Fab")
		)
		(fp_line
			(start 0.12065 -0.2794)
			(end -0.12065 -0.2794)
			(stroke
				(width 0.1)
				(type default)
			)
			(layer "B.Fab")
		)
		(fp_line
			(start -0.67945 -0.3048)
			(end -0.67945 0.3048)
			(stroke
				(width 0.1)
				(type default)
			)
			(layer "B.Fab")
		)
		(fp_line
			(start -0.12065 -0.3048)
			(end -0.67945 -0.3048)
			(stroke
				(width 0.1)
				(type default)
			)
			(layer "B.Fab")
		)
		(fp_line
			(start 0.12065 -0.305054)
			(end 0.12065 -0.2794)
			(stroke
				(width 0.1)
				(type default)
			)
			(layer "B.Fab")
		)
		(fp_line
			(start 0.67945 -0.305054)
			(end 0.12065 -0.305054)
			(stroke
				(width 0.1)
				(type default)
			)
			(layer "B.Fab")
		)
		(pad "1" smd circle
			(at 0.40005 0 90)
			(size 0 0)
			(layers "B.Cu" "B.Mask" "B.Paste")
			(net "PVDDCR_SOC_P0")
		)
		(pad "2" smd circle
			(at -0.40005 0 90)
			(size 0 0)
			(layers "B.Cu" "B.Mask" "B.Paste")
			(net "GND")
		)
	)
	(footprint ""
		(layer "B.Cu")
		(at 128.811528 -39.090092 180)
		(property "Reference" "C6072"
			(at 0 0 0)
			(layer "B.SilkS")
			(hide yes)
			(effects
				(font
					(size 1.27 1.27)
				)
				(justify mirror)
			)
		)
		(property "Value" ""
			(at 0 0 0)
			(layer "B.Fab")
			(effects
				(font
					(size 1.27 1.27)
				)
				(justify mirror)
			)
		)
		(duplicate_pad_numbers_are_jumpers no)
		(fp_line
			(start 0.7874 0.4064)
			(end 0.7874 -0.4064)
			(stroke
				(width 0.1524)
				(type default)
			)
			(layer "B.SilkS")
		)
		(fp_line
			(start 0.7874 -0.4064)
			(end -0.7874 -0.4064)
			(stroke
				(width 0.1524)
				(type default)
			)
			(layer "B.SilkS")
		)
		(fp_line
			(start -0.7874 0.4064)
			(end 0.7874 0.4064)
			(stroke
				(width 0.1524)
				(type default)
			)
			(layer "B.SilkS")
		)
		(fp_line
			(start -0.7874 -0.4064)
			(end -0.7874 0.4064)
			(stroke
				(width 0.1524)
				(type default)
			)
			(layer "B.SilkS")
		)
		(fp_line
			(start 0.67945 0.3048)
			(end 0.67945 -0.305054)
			(stroke
				(width 0.1)
				(type default)
			)
			(layer "B.Fab")
		)
		(fp_line
			(start 0.67945 -0.305054)
			(end 0.12065 -0.305054)
			(stroke
				(width 0.1)
				(type default)
			)
			(layer "B.Fab")
		)
		(fp_line
			(start 0.12065 0.3048)
			(end 0.67945 0.3048)
			(stroke
				(width 0.1)
				(type default)
			)
			(layer "B.Fab")
		)
		(fp_line
			(start 0.12065 0.2794)
			(end 0.12065 0.3048)
			(stroke
				(width 0.1)
				(type default)
			)
			(layer "B.Fab")
		)
		(fp_line
			(start 0.12065 -0.2794)
			(end -0.12065 -0.2794)
			(stroke
				(width 0.1)
				(type default)
			)
			(layer "B.Fab")
		)
		(fp_line
			(start 0.12065 -0.305054)
			(end 0.12065 -0.2794)
			(stroke
				(width 0.1)
				(type default)
			)
			(layer "B.Fab")
		)
		(fp_line
			(start -0.120396 0.3048)
			(end -0.120396 0.2794)
			(stroke
				(width 0.1)
				(type default)
			)
			(layer "B.Fab")
		)
		(fp_line
			(start -0.120396 0.2794)
			(end 0.12065 0.2794)
			(stroke
				(width 0.1)
				(type default)
			)
			(layer "B.Fab")
		)
		(fp_line
			(start -0.12065 -0.2794)
			(end -0.12065 -0.3048)
			(stroke
				(width 0.1)
				(type default)
			)
			(layer "B.Fab")
		)
		(fp_line
			(start -0.12065 -0.3048)
			(end -0.67945 -0.3048)
			(stroke
				(width 0.1)
				(type default)
			)
			(layer "B.Fab")
		)
		(fp_line
			(start -0.67945 0.3048)
			(end -0.120396 0.3048)
			(stroke
				(width 0.1)
				(type default)
			)
			(layer "B.Fab")
		)
		(fp_line
			(start -0.67945 -0.3048)
			(end -0.67945 0.3048)
			(stroke
				(width 0.1)
				(type default)
			)
			(layer "B.Fab")
		)
		(pad "1" smd circle
			(at 0.40005 0)
			(size 0 0)
			(layers "B.Cu" "B.Mask" "B.Paste")
			(net "P1V2_AUX")
		)
		(pad "2" smd circle
			(at -0.40005 0)
			(size 0 0)
			(layers "B.Cu" "B.Mask" "B.Paste")
			(net "GND")
		)
	)
	(footprint ""
		(layer "B.Cu")
		(at 95.64624 -388.011162 -90)
		(property "Reference" "C344"
			(at 0 0 90)
			(layer "B.SilkS")
			(hide yes)
			(effects
				(font
					(size 1.27 1.27)
				)
				(justify mirror)
			)
		)
		(property "Value" ""
			(at 0 0 90)
			(layer "B.Fab")
			(effects
				(font
					(size 1.27 1.27)
				)
				(justify mirror)
			)
		)
		(duplicate_pad_numbers_are_jumpers no)
		(fp_line
			(start -0.299974 0.150114)
			(end 0.299974 0.150114)
			(stroke
				(width 0.1)
				(type default)
			)
			(layer "B.Fab")
		)
		(fp_line
			(start 0.299974 0.150114)
			(end 0.299974 -0.150114)
			(stroke
				(width 0.1)
				(type default)
			)
			(layer "B.Fab")
		)
		(fp_line
			(start -0.299974 -0.150114)
			(end -0.299974 0.150114)
			(stroke
				(width 0.1)
				(type default)
			)
			(layer "B.Fab")
		)
		(fp_line
			(start 0.299974 -0.150114)
			(end -0.299974 -0.150114)
			(stroke
				(width 0.1)
				(type default)
			)
			(layer "B.Fab")
		)
		(pad "1" smd rect
			(at 0.2667 0 90)
			(size 0.3048 0.381)
			(layers "B.Cu" "B.Mask" "B.Paste")
			(net "P0V9_CPU1_RT1_2A")
		)
		(pad "2" smd rect
			(at -0.2667 0 90)
			(size 0.3048 0.381)
			(layers "B.Cu" "B.Mask" "B.Paste")
			(net "GND")
		)
	)
	(footprint ""
		(layer "B.Cu")
		(at 32.69615 -192.66027 180)
		(property "Reference" "C182"
			(at 0 0 0)
			(layer "B.SilkS")
			(hide yes)
			(effects
				(font
					(size 1.27 1.27)
				)
				(justify mirror)
			)
		)
		(property "Value" ""
			(at 0 0 0)
			(layer "B.Fab")
			(effects
				(font
					(size 1.27 1.27)
				)
				(justify mirror)
			)
		)
		(duplicate_pad_numbers_are_jumpers no)
		(fp_line
			(start 1.524 0.762)
			(end 1.524 -0.762)
			(stroke
				(width 0.1524)
				(type default)
			)
			(layer "B.SilkS")
		)
		(fp_line
			(start 1.524 -0.762)
			(end -1.524 -0.762)
			(stroke
				(width 0.1524)
				(type default)
			)
			(layer "B.SilkS")
		)
		(fp_line
			(start -1.524 0.762)
			(end 1.524 0.762)
			(stroke
				(width 0.1524)
				(type default)
			)
			(layer "B.SilkS")
		)
		(fp_line
			(start -1.524 -0.762)
			(end -1.524 0.762)
			(stroke
				(width 0.1524)
				(type default)
			)
			(layer "B.SilkS")
		)
		(fp_line
			(start 1.1049 0.724916)
			(end -1.1049 0.724916)
			(stroke
				(width 0.1)
				(type default)
			)
			(layer "B.Fab")
		)
		(fp_line
			(start 1.1049 -0.724916)
			(end 1.1049 0.724916)
			(stroke
				(width 0.1)
				(type default)
			)
			(layer "B.Fab")
		)
		(fp_line
			(start -1.1049 0.724916)
			(end -1.1049 -0.724916)
			(stroke
				(width 0.1)
				(type default)
			)
			(layer "B.Fab")
		)
		(fp_line
			(start -1.1049 -0.724916)
			(end 1.1049 -0.724916)
			(stroke
				(width 0.1)
				(type default)
			)
			(layer "B.Fab")
		)
		(pad "1" smd rect
			(at 0.889 0 180)
			(size 1.016 1.27)
			(layers "B.Cu" "B.Mask" "B.Paste")
			(net "P12V_MEM_CPU1")
		)
		(pad "2" smd rect
			(at -0.889 0 180)
			(size 1.016 1.27)
			(layers "B.Cu" "B.Mask" "B.Paste")
			(net "GND")
		)
	)
	(footprint ""
		(layer "B.Cu")
		(at 408.671776 -141.40942)
		(property "Reference" "PR3337"
			(at 0 0 0)
			(layer "B.SilkS")
			(hide yes)
			(effects
				(font
					(size 1.27 1.27)
				)
				(justify mirror)
			)
		)
		(property "Value" ""
			(at 0 0 0)
			(layer "B.Fab")
			(effects
				(font
					(size 1.27 1.27)
				)
				(justify mirror)
			)
		)
		(duplicate_pad_numbers_are_jumpers no)
		(fp_line
			(start -0.7874 -0.4064)
			(end -0.7874 0.4064)
			(stroke
				(width 0.1524)
				(type default)
			)
			(layer "B.SilkS")
		)
		(fp_line
			(start -0.7874 0.4064)
			(end 0.7874 0.4064)
			(stroke
				(width 0.1524)
				(type default)
			)
			(layer "B.SilkS")
		)
		(fp_line
			(start 0.7874 -0.4064)
			(end -0.7874 -0.4064)
			(stroke
				(width 0.1524)
				(type default)
			)
			(layer "B.SilkS")
		)
		(fp_line
			(start 0.7874 0.4064)
			(end 0.7874 -0.4064)
			(stroke
				(width 0.1524)
				(type default)
			)
			(layer "B.SilkS")
		)
		(fp_line
			(start -0.67945 -0.3048)
			(end -0.67945 0.3048)
			(stroke
				(width 0.1)
				(type default)
			)
			(layer "B.Fab")
		)
		(fp_line
			(start -0.67945 0.3048)
			(end -0.120396 0.3048)
			(stroke
				(width 0.1)
				(type default)
			)
			(layer "B.Fab")
		)
		(fp_line
			(start -0.12065 -0.3048)
			(end -0.67945 -0.3048)
			(stroke
				(width 0.1)
				(type default)
			)
			(layer "B.Fab")
		)
		(fp_line
			(start -0.12065 -0.2794)
			(end -0.12065 -0.3048)
			(stroke
				(width 0.1)
				(type default)
			)
			(layer "B.Fab")
		)
		(fp_line
			(start -0.120396 0.2794)
			(end 0.12065 0.2794)
			(stroke
				(width 0.1)
				(type default)
			)
			(layer "B.Fab")
		)
		(fp_line
			(start -0.120396 0.3048)
			(end -0.120396 0.2794)
			(stroke
				(width 0.1)
				(type default)
			)
			(layer "B.Fab")
		)
		(fp_line
			(start 0.12065 -0.305054)
			(end 0.12065 -0.2794)
			(stroke
				(width 0.1)
				(type default)
			)
			(layer "B.Fab")
		)
		(fp_line
			(start 0.12065 -0.2794)
			(end -0.12065 -0.2794)
			(stroke
				(width 0.1)
				(type default)
			)
			(layer "B.Fab")
		)
		(fp_line
			(start 0.12065 0.2794)
			(end 0.12065 0.3048)
			(stroke
				(width 0.1)
				(type default)
			)
			(layer "B.Fab")
		)
		(fp_line
			(start 0.12065 0.3048)
			(end 0.67945 0.3048)
			(stroke
				(width 0.1)
				(type default)
			)
			(layer "B.Fab")
		)
		(fp_line
			(start 0.67945 -0.305054)
			(end 0.12065 -0.305054)
			(stroke
				(width 0.1)
				(type default)
			)
			(layer "B.Fab")
		)
		(fp_line
			(start 0.67945 0.3048)
			(end 0.67945 -0.305054)
			(stroke
				(width 0.1)
				(type default)
			)
			(layer "B.Fab")
		)
		(pad "1" smd circle
			(at 0.40005 0 180)
			(size 0 0)
			(layers "B.Cu" "B.Mask" "B.Paste")
			(net "P5V_AUX_MODE")
		)
		(pad "2" smd circle
			(at -0.40005 0 180)
			(size 0 0)
			(layers "B.Cu" "B.Mask" "B.Paste")
			(net "GND")
		)
	)
	(footprint ""
		(layer "B.Cu")
		(at 428.211742 -194.88531 180)
		(property "Reference" "R766"
			(at 0 0 0)
			(layer "B.SilkS")
			(hide yes)
			(effects
				(font
					(size 1.27 1.27)
				)
				(justify mirror)
			)
		)
		(property "Value" ""
			(at 0 0 0)
			(layer "B.Fab")
			(effects
				(font
					(size 1.27 1.27)
				)
				(justify mirror)
			)
		)
		(duplicate_pad_numbers_are_jumpers no)
		(fp_line
			(start 0.7874 0.4064)
			(end 0.7874 -0.4064)
			(stroke
				(width 0.1524)
				(type default)
			)
			(layer "B.SilkS")
		)
		(fp_line
			(start 0.7874 -0.4064)
			(end -0.7874 -0.4064)
			(stroke
				(width 0.1524)
				(type default)
			)
			(layer "B.SilkS")
		)
		(fp_line
			(start -0.7874 0.4064)
			(end 0.7874 0.4064)
			(stroke
				(width 0.1524)
				(type default)
			)
			(layer "B.SilkS")
		)
		(fp_line
			(start -0.7874 -0.4064)
			(end -0.7874 0.4064)
			(stroke
				(width 0.1524)
				(type default)
			)
			(layer "B.SilkS")
		)
		(fp_line
			(start 0.67945 0.3048)
			(end 0.67945 -0.305054)
			(stroke
				(width 0.1)
				(type default)
			)
			(layer "B.Fab")
		)
		(fp_line
			(start 0.67945 -0.305054)
			(end 0.12065 -0.305054)
			(stroke
				(width 0.1)
				(type default)
			)
			(layer "B.Fab")
		)
		(fp_line
			(start 0.12065 0.3048)
			(end 0.67945 0.3048)
			(stroke
				(width 0.1)
				(type default)
			)
			(layer "B.Fab")
		)
		(fp_line
			(start 0.12065 0.2794)
			(end 0.12065 0.3048)
			(stroke
				(width 0.1)
				(type default)
			)
			(layer "B.Fab")
		)
		(fp_line
			(start 0.12065 -0.2794)
			(end -0.12065 -0.2794)
			(stroke
				(width 0.1)
				(type default)
			)
			(layer "B.Fab")
		)
		(fp_line
			(start 0.12065 -0.305054)
			(end 0.12065 -0.2794)
			(stroke
				(width 0.1)
				(type default)
			)
			(layer "B.Fab")
		)
		(fp_line
			(start -0.120396 0.3048)
			(end -0.120396 0.2794)
			(stroke
				(width 0.1)
				(type default)
			)
			(layer "B.Fab")
		)
		(fp_line
			(start -0.120396 0.2794)
			(end 0.12065 0.2794)
			(stroke
				(width 0.1)
				(type default)
			)
			(layer "B.Fab")
		)
		(fp_line
			(start -0.12065 -0.2794)
			(end -0.12065 -0.3048)
			(stroke
				(width 0.1)
				(type default)
			)
			(layer "B.Fab")
		)
		(fp_line
			(start -0.12065 -0.3048)
			(end -0.67945 -0.3048)
			(stroke
				(width 0.1)
				(type default)
			)
			(layer "B.Fab")
		)
		(fp_line
			(start -0.67945 0.3048)
			(end -0.120396 0.3048)
			(stroke
				(width 0.1)
				(type default)
			)
			(layer "B.Fab")
		)
		(fp_line
			(start -0.67945 -0.3048)
			(end -0.67945 0.3048)
			(stroke
				(width 0.1)
				(type default)
			)
			(layer "B.Fab")
		)
		(pad "1" smd circle
			(at 0.40005 0)
			(size 0 0)
			(layers "B.Cu" "B.Mask" "B.Paste")
			(net "PD_CHI_CPU0_DIMM_SAA")
		)
		(pad "2" smd circle
			(at -0.40005 0)
			(size 0 0)
			(layers "B.Cu" "B.Mask" "B.Paste")
			(net "GND")
		)
	)
	(footprint ""
		(layer "B.Cu")
		(at 232.857802 -251.042678 -90)
		(property "Reference" "C11"
			(at 0 0 90)
			(layer "B.SilkS")
			(hide yes)
			(effects
				(font
					(size 1.27 1.27)
				)
				(justify mirror)
			)
		)
		(property "Value" ""
			(at 0 0 90)
			(layer "B.Fab")
			(effects
				(font
					(size 1.27 1.27)
				)
				(justify mirror)
			)
		)
		(duplicate_pad_numbers_are_jumpers no)
		(fp_line
			(start -0.7874 0.4064)
			(end 0.7874 0.4064)
			(stroke
				(width 0.1524)
				(type default)
			)
			(layer "B.SilkS")
		)
		(fp_line
			(start 0.7874 0.4064)
			(end 0.7874 -0.4064)
			(stroke
				(width 0.1524)
				(type default)
			)
			(layer "B.SilkS")
		)
		(fp_line
			(start -0.7874 -0.4064)
			(end -0.7874 0.4064)
			(stroke
				(width 0.1524)
				(type default)
			)
			(layer "B.SilkS")
		)
		(fp_line
			(start 0.7874 -0.4064)
			(end -0.7874 -0.4064)
			(stroke
				(width 0.1524)
				(type default)
			)
			(layer "B.SilkS")
		)
		(fp_line
			(start -0.67945 0.3048)
			(end -0.120396 0.3048)
			(stroke
				(width 0.1)
				(type default)
			)
			(layer "B.Fab")
		)
		(fp_line
			(start -0.120396 0.3048)
			(end -0.120396 0.2794)
			(stroke
				(width 0.1)
				(type default)
			)
			(layer "B.Fab")
		)
		(fp_line
			(start 0.12065 0.3048)
			(end 0.67945 0.3048)
			(stroke
				(width 0.1)
				(type default)
			)
			(layer "B.Fab")
		)
		(fp_line
			(start 0.67945 0.3048)
			(end 0.67945 -0.305054)
			(stroke
				(width 0.1)
				(type default)
			)
			(layer "B.Fab")
		)
		(fp_line
			(start -0.120396 0.2794)
			(end 0.12065 0.2794)
			(stroke
				(width 0.1)
				(type default)
			)
			(layer "B.Fab")
		)
		(fp_line
			(start 0.12065 0.2794)
			(end 0.12065 0.3048)
			(stroke
				(width 0.1)
				(type default)
			)
			(layer "B.Fab")
		)
		(fp_line
			(start -0.12065 -0.2794)
			(end -0.12065 -0.3048)
			(stroke
				(width 0.1)
				(type default)
			)
			(layer "B.Fab")
		)
		(fp_line
			(start 0.12065 -0.2794)
			(end -0.12065 -0.2794)
			(stroke
				(width 0.1)
				(type default)
			)
			(layer "B.Fab")
		)
		(fp_line
			(start -0.67945 -0.3048)
			(end -0.67945 0.3048)
			(stroke
				(width 0.1)
				(type default)
			)
			(layer "B.Fab")
		)
		(fp_line
			(start -0.12065 -0.3048)
			(end -0.67945 -0.3048)
			(stroke
				(width 0.1)
				(type default)
			)
			(layer "B.Fab")
		)
		(fp_line
			(start 0.12065 -0.305054)
			(end 0.12065 -0.2794)
			(stroke
				(width 0.1)
				(type default)
			)
			(layer "B.Fab")
		)
		(fp_line
			(start 0.67945 -0.305054)
			(end 0.12065 -0.305054)
			(stroke
				(width 0.1)
				(type default)
			)
			(layer "B.Fab")
		)
		(pad "1" smd circle
			(at 0.40005 0 90)
			(size 0 0)
			(layers "B.Cu" "B.Mask" "B.Paste")
			(net "P3V3_AUX")
		)
		(pad "2" smd circle
			(at -0.40005 0 90)
			(size 0 0)
			(layers "B.Cu" "B.Mask" "B.Paste")
			(net "GND")
		)
	)
	(footprint ""
		(layer "B.Cu")
		(at 233.553 -240.411 -90)
		(property "Reference" "R359"
			(at 0 0 90)
			(layer "B.SilkS")
			(hide yes)
			(effects
				(font
					(size 1.27 1.27)
				)
				(justify mirror)
			)
		)
		(property "Value" ""
			(at 0 0 90)
			(layer "B.Fab")
			(effects
				(font
					(size 1.27 1.27)
				)
				(justify mirror)
			)
		)
		(duplicate_pad_numbers_are_jumpers no)
		(fp_line
			(start -0.7874 0.4064)
			(end 0.7874 0.4064)
			(stroke
				(width 0.1524)
				(type default)
			)
			(layer "B.SilkS")
		)
		(fp_line
			(start 0.7874 0.4064)
			(end 0.7874 -0.4064)
			(stroke
				(width 0.1524)
				(type default)
			)
			(layer "B.SilkS")
		)
		(fp_line
			(start -0.7874 -0.4064)
			(end -0.7874 0.4064)
			(stroke
				(width 0.1524)
				(type default)
			)
			(layer "B.SilkS")
		)
		(fp_line
			(start 0.7874 -0.4064)
			(end -0.7874 -0.4064)
			(stroke
				(width 0.1524)
				(type default)
			)
			(layer "B.SilkS")
		)
		(fp_line
			(start -0.67945 0.3048)
			(end -0.120396 0.3048)
			(stroke
				(width 0.1)
				(type default)
			)
			(layer "B.Fab")
		)
		(fp_line
			(start -0.120396 0.3048)
			(end -0.120396 0.2794)
			(stroke
				(width 0.1)
				(type default)
			)
			(layer "B.Fab")
		)
		(fp_line
			(start 0.12065 0.3048)
			(end 0.67945 0.3048)
			(stroke
				(width 0.1)
				(type default)
			)
			(layer "B.Fab")
		)
		(fp_line
			(start 0.67945 0.3048)
			(end 0.67945 -0.305054)
			(stroke
				(width 0.1)
				(type default)
			)
			(layer "B.Fab")
		)
		(fp_line
			(start -0.120396 0.2794)
			(end 0.12065 0.2794)
			(stroke
				(width 0.1)
				(type default)
			)
			(layer "B.Fab")
		)
		(fp_line
			(start 0.12065 0.2794)
			(end 0.12065 0.3048)
			(stroke
				(width 0.1)
				(type default)
			)
			(layer "B.Fab")
		)
		(fp_line
			(start -0.12065 -0.2794)
			(end -0.12065 -0.3048)
			(stroke
				(width 0.1)
				(type default)
			)
			(layer "B.Fab")
		)
		(fp_line
			(start 0.12065 -0.2794)
			(end -0.12065 -0.2794)
			(stroke
				(width 0.1)
				(type default)
			)
			(layer "B.Fab")
		)
		(fp_line
			(start -0.67945 -0.3048)
			(end -0.67945 0.3048)
			(stroke
				(width 0.1)
				(type default)
			)
			(layer "B.Fab")
		)
		(fp_line
			(start -0.12065 -0.3048)
			(end -0.67945 -0.3048)
			(stroke
				(width 0.1)
				(type default)
			)
			(layer "B.Fab")
		)
		(fp_line
			(start 0.12065 -0.305054)
			(end 0.12065 -0.2794)
			(stroke
				(width 0.1)
				(type default)
			)
			(layer "B.Fab")
		)
		(fp_line
			(start 0.67945 -0.305054)
			(end 0.12065 -0.305054)
			(stroke
				(width 0.1)
				(type default)
			)
			(layer "B.Fab")
		)
		(pad "1" smd circle
			(at 0.40005 0 90)
			(size 0 0)
			(layers "B.Cu" "B.Mask" "B.Paste")
			(net "PVDD11_S3_P1")
		)
		(pad "2" smd circle
			(at -0.40005 0 90)
			(size 0 0)
			(layers "B.Cu" "B.Mask" "B.Paste")
			(net "SMB_APML_CPU1_SDA")
		)
	)
	(footprint ""
		(layer "B.Cu")
		(at 173.609 -98.135948 90)
		(property "Reference" "R6017"
			(at 0 0 90)
			(layer "B.SilkS")
			(hide yes)
			(effects
				(font
					(size 1.27 1.27)
				)
				(justify mirror)
			)
		)
		(property "Value" ""
			(at 0 0 90)
			(layer "B.Fab")
			(effects
				(font
					(size 1.27 1.27)
				)
				(justify mirror)
			)
		)
		(duplicate_pad_numbers_are_jumpers no)
		(fp_line
			(start 0.7874 -0.4064)
			(end -0.7874 -0.4064)
			(stroke
				(width 0.1524)
				(type default)
			)
			(layer "B.SilkS")
		)
		(fp_line
			(start -0.7874 -0.4064)
			(end -0.7874 0.4064)
			(stroke
				(width 0.1524)
				(type default)
			)
			(layer "B.SilkS")
		)
		(fp_line
			(start 0.7874 0.4064)
			(end 0.7874 -0.4064)
			(stroke
				(width 0.1524)
				(type default)
			)
			(layer "B.SilkS")
		)
		(fp_line
			(start -0.7874 0.4064)
			(end 0.7874 0.4064)
			(stroke
				(width 0.1524)
				(type default)
			)
			(layer "B.SilkS")
		)
		(fp_line
			(start 0.67945 -0.305054)
			(end 0.12065 -0.305054)
			(stroke
				(width 0.1)
				(type default)
			)
			(layer "B.Fab")
		)
		(fp_line
			(start 0.12065 -0.305054)
			(end 0.12065 -0.2794)
			(stroke
				(width 0.1)
				(type default)
			)
			(layer "B.Fab")
		)
		(fp_line
			(start -0.12065 -0.3048)
			(end -0.67945 -0.3048)
			(stroke
				(width 0.1)
				(type default)
			)
			(layer "B.Fab")
		)
		(fp_line
			(start -0.67945 -0.3048)
			(end -0.67945 0.3048)
			(stroke
				(width 0.1)
				(type default)
			)
			(layer "B.Fab")
		)
		(fp_line
			(start 0.12065 -0.2794)
			(end -0.12065 -0.2794)
			(stroke
				(width 0.1)
				(type default)
			)
			(layer "B.Fab")
		)
		(fp_line
			(start -0.12065 -0.2794)
			(end -0.12065 -0.3048)
			(stroke
				(width 0.1)
				(type default)
			)
			(layer "B.Fab")
		)
		(fp_line
			(start 0.12065 0.2794)
			(end 0.12065 0.3048)
			(stroke
				(width 0.1)
				(type default)
			)
			(layer "B.Fab")
		)
		(fp_line
			(start -0.120396 0.2794)
			(end 0.12065 0.2794)
			(stroke
				(width 0.1)
				(type default)
			)
			(layer "B.Fab")
		)
		(fp_line
			(start 0.67945 0.3048)
			(end 0.67945 -0.305054)
			(stroke
				(width 0.1)
				(type default)
			)
			(layer "B.Fab")
		)
		(fp_line
			(start 0.12065 0.3048)
			(end 0.67945 0.3048)
			(stroke
				(width 0.1)
				(type default)
			)
			(layer "B.Fab")
		)
		(fp_line
			(start -0.120396 0.3048)
			(end -0.120396 0.2794)
			(stroke
				(width 0.1)
				(type default)
			)
			(layer "B.Fab")
		)
		(fp_line
			(start -0.67945 0.3048)
			(end -0.120396 0.3048)
			(stroke
				(width 0.1)
				(type default)
			)
			(layer "B.Fab")
		)
		(pad "1" smd circle
			(at 0.40005 0 270)
			(size 0 0)
			(layers "B.Cu" "B.Mask" "B.Paste")
			(net "P3V3_AUX")
		)
		(pad "2" smd circle
			(at -0.40005 0 270)
			(size 0 0)
			(layers "B.Cu" "B.Mask" "B.Paste")
			(net "SGPIO_SCM_CLK_<0>")
		)
	)
	(footprint ""
		(layer "B.Cu")
		(at 91.987878 -138.40841 -90)
		(property "Reference" "R175"
			(at 0 0 90)
			(layer "B.SilkS")
			(hide yes)
			(effects
				(font
					(size 1.27 1.27)
				)
				(justify mirror)
			)
		)
		(property "Value" ""
			(at 0 0 90)
			(layer "B.Fab")
			(effects
				(font
					(size 1.27 1.27)
				)
				(justify mirror)
			)
		)
		(duplicate_pad_numbers_are_jumpers no)
		(fp_line
			(start -0.7874 0.4064)
			(end 0.7874 0.4064)
			(stroke
				(width 0.1524)
				(type default)
			)
			(layer "B.SilkS")
		)
		(fp_line
			(start 0.7874 0.4064)
			(end 0.7874 -0.4064)
			(stroke
				(width 0.1524)
				(type default)
			)
			(layer "B.SilkS")
		)
		(fp_line
			(start -0.7874 -0.4064)
			(end -0.7874 0.4064)
			(stroke
				(width 0.1524)
				(type default)
			)
			(layer "B.SilkS")
		)
		(fp_line
			(start 0.7874 -0.4064)
			(end -0.7874 -0.4064)
			(stroke
				(width 0.1524)
				(type default)
			)
			(layer "B.SilkS")
		)
		(fp_line
			(start -0.67945 0.3048)
			(end -0.120396 0.3048)
			(stroke
				(width 0.1)
				(type default)
			)
			(layer "B.Fab")
		)
		(fp_line
			(start -0.120396 0.3048)
			(end -0.120396 0.2794)
			(stroke
				(width 0.1)
				(type default)
			)
			(layer "B.Fab")
		)
		(fp_line
			(start 0.12065 0.3048)
			(end 0.67945 0.3048)
			(stroke
				(width 0.1)
				(type default)
			)
			(layer "B.Fab")
		)
		(fp_line
			(start 0.67945 0.3048)
			(end 0.67945 -0.305054)
			(stroke
				(width 0.1)
				(type default)
			)
			(layer "B.Fab")
		)
		(fp_line
			(start -0.120396 0.2794)
			(end 0.12065 0.2794)
			(stroke
				(width 0.1)
				(type default)
			)
			(layer "B.Fab")
		)
		(fp_line
			(start 0.12065 0.2794)
			(end 0.12065 0.3048)
			(stroke
				(width 0.1)
				(type default)
			)
			(layer "B.Fab")
		)
		(fp_line
			(start -0.12065 -0.2794)
			(end -0.12065 -0.3048)
			(stroke
				(width 0.1)
				(type default)
			)
			(layer "B.Fab")
		)
		(fp_line
			(start 0.12065 -0.2794)
			(end -0.12065 -0.2794)
			(stroke
				(width 0.1)
				(type default)
			)
			(layer "B.Fab")
		)
		(fp_line
			(start -0.67945 -0.3048)
			(end -0.67945 0.3048)
			(stroke
				(width 0.1)
				(type default)
			)
			(layer "B.Fab")
		)
		(fp_line
			(start -0.12065 -0.3048)
			(end -0.67945 -0.3048)
			(stroke
				(width 0.1)
				(type default)
			)
			(layer "B.Fab")
		)
		(fp_line
			(start 0.12065 -0.305054)
			(end 0.12065 -0.2794)
			(stroke
				(width 0.1)
				(type default)
			)
			(layer "B.Fab")
		)
		(fp_line
			(start 0.67945 -0.305054)
			(end 0.12065 -0.305054)
			(stroke
				(width 0.1)
				(type default)
			)
			(layer "B.Fab")
		)
		(pad "1" smd circle
			(at 0.40005 0 90)
			(size 0 0)
			(layers "B.Cu" "B.Mask" "B.Paste")
			(net "SMB_VR_3V3STBY_SCL")
		)
		(pad "2" smd circle
			(at -0.40005 0 90)
			(size 0 0)
			(layers "B.Cu" "B.Mask" "B.Paste")
			(net "PVDDCR_CPU0_P1_PMSCL_R")
		)
	)
	(footprint ""
		(layer "B.Cu")
		(at 453.191118 -244.08511)
		(property "Reference" "R386"
			(at 0 0 0)
			(layer "B.SilkS")
			(hide yes)
			(effects
				(font
					(size 1.27 1.27)
				)
				(justify mirror)
			)
		)
		(property "Value" ""
			(at 0 0 0)
			(layer "B.Fab")
			(effects
				(font
					(size 1.27 1.27)
				)
				(justify mirror)
			)
		)
		(duplicate_pad_numbers_are_jumpers no)
		(fp_line
			(start -0.7874 -0.4064)
			(end -0.7874 0.4064)
			(stroke
				(width 0.1524)
				(type default)
			)
			(layer "B.SilkS")
		)
		(fp_line
			(start -0.7874 0.4064)
			(end 0.7874 0.4064)
			(stroke
				(width 0.1524)
				(type default)
			)
			(layer "B.SilkS")
		)
		(fp_line
			(start 0.7874 -0.4064)
			(end -0.7874 -0.4064)
			(stroke
				(width 0.1524)
				(type default)
			)
			(layer "B.SilkS")
		)
		(fp_line
			(start 0.7874 0.4064)
			(end 0.7874 -0.4064)
			(stroke
				(width 0.1524)
				(type default)
			)
			(layer "B.SilkS")
		)
		(fp_line
			(start -0.67945 -0.3048)
			(end -0.67945 0.3048)
			(stroke
				(width 0.1)
				(type default)
			)
			(layer "B.Fab")
		)
		(fp_line
			(start -0.67945 0.3048)
			(end -0.120396 0.3048)
			(stroke
				(width 0.1)
				(type default)
			)
			(layer "B.Fab")
		)
		(fp_line
			(start -0.12065 -0.3048)
			(end -0.67945 -0.3048)
			(stroke
				(width 0.1)
				(type default)
			)
			(layer "B.Fab")
		)
		(fp_line
			(start -0.12065 -0.2794)
			(end -0.12065 -0.3048)
			(stroke
				(width 0.1)
				(type default)
			)
			(layer "B.Fab")
		)
		(fp_line
			(start -0.120396 0.2794)
			(end 0.12065 0.2794)
			(stroke
				(width 0.1)
				(type default)
			)
			(layer "B.Fab")
		)
		(fp_line
			(start -0.120396 0.3048)
			(end -0.120396 0.2794)
			(stroke
				(width 0.1)
				(type default)
			)
			(layer "B.Fab")
		)
		(fp_line
			(start 0.12065 -0.305054)
			(end 0.12065 -0.2794)
			(stroke
				(width 0.1)
				(type default)
			)
			(layer "B.Fab")
		)
		(fp_line
			(start 0.12065 -0.2794)
			(end -0.12065 -0.2794)
			(stroke
				(width 0.1)
				(type default)
			)
			(layer "B.Fab")
		)
		(fp_line
			(start 0.12065 0.2794)
			(end 0.12065 0.3048)
			(stroke
				(width 0.1)
				(type default)
			)
			(layer "B.Fab")
		)
		(fp_line
			(start 0.12065 0.3048)
			(end 0.67945 0.3048)
			(stroke
				(width 0.1)
				(type default)
			)
			(layer "B.Fab")
		)
		(fp_line
			(start 0.67945 -0.305054)
			(end 0.12065 -0.305054)
			(stroke
				(width 0.1)
				(type default)
			)
			(layer "B.Fab")
		)
		(fp_line
			(start 0.67945 0.3048)
			(end 0.67945 -0.305054)
			(stroke
				(width 0.1)
				(type default)
			)
			(layer "B.Fab")
		)
		(pad "1" smd circle
			(at 0.40005 0 180)
			(size 0 0)
			(layers "B.Cu" "B.Mask" "B.Paste")
			(net "M_L_CPU0_ALERT_N")
		)
		(pad "2" smd circle
			(at -0.40005 0 180)
			(size 0 0)
			(layers "B.Cu" "B.Mask" "B.Paste")
			(net "M_L_CPU0_ALERT_R_N")
		)
	)
	(footprint ""
		(layer "B.Cu")
		(at 349.675958 -272.284952 180)
		(property "Reference" "C2234"
			(at 0 0 0)
			(layer "B.SilkS")
			(hide yes)
			(effects
				(font
					(size 1.27 1.27)
				)
				(justify mirror)
			)
		)
		(property "Value" ""
			(at 0 0 0)
			(layer "B.Fab")
			(effects
				(font
					(size 1.27 1.27)
				)
				(justify mirror)
			)
		)
		(duplicate_pad_numbers_are_jumpers no)
		(fp_line
			(start 0.7874 0.4064)
			(end 0.7874 -0.4064)
			(stroke
				(width 0.1524)
				(type default)
			)
			(layer "B.SilkS")
		)
		(fp_line
			(start 0.7874 -0.4064)
			(end -0.7874 -0.4064)
			(stroke
				(width 0.1524)
				(type default)
			)
			(layer "B.SilkS")
		)
		(fp_line
			(start -0.7874 0.4064)
			(end 0.7874 0.4064)
			(stroke
				(width 0.1524)
				(type default)
			)
			(layer "B.SilkS")
		)
		(fp_line
			(start -0.7874 -0.4064)
			(end -0.7874 0.4064)
			(stroke
				(width 0.1524)
				(type default)
			)
			(layer "B.SilkS")
		)
		(fp_line
			(start 0.67945 0.3048)
			(end 0.67945 -0.305054)
			(stroke
				(width 0.1)
				(type default)
			)
			(layer "B.Fab")
		)
		(fp_line
			(start 0.67945 -0.305054)
			(end 0.12065 -0.305054)
			(stroke
				(width 0.1)
				(type default)
			)
			(layer "B.Fab")
		)
		(fp_line
			(start 0.12065 0.3048)
			(end 0.67945 0.3048)
			(stroke
				(width 0.1)
				(type default)
			)
			(layer "B.Fab")
		)
		(fp_line
			(start 0.12065 0.2794)
			(end 0.12065 0.3048)
			(stroke
				(width 0.1)
				(type default)
			)
			(layer "B.Fab")
		)
		(fp_line
			(start 0.12065 -0.2794)
			(end -0.12065 -0.2794)
			(stroke
				(width 0.1)
				(type default)
			)
			(layer "B.Fab")
		)
		(fp_line
			(start 0.12065 -0.305054)
			(end 0.12065 -0.2794)
			(stroke
				(width 0.1)
				(type default)
			)
			(layer "B.Fab")
		)
		(fp_line
			(start -0.120396 0.3048)
			(end -0.120396 0.2794)
			(stroke
				(width 0.1)
				(type default)
			)
			(layer "B.Fab")
		)
		(fp_line
			(start -0.120396 0.2794)
			(end 0.12065 0.2794)
			(stroke
				(width 0.1)
				(type default)
			)
			(layer "B.Fab")
		)
		(fp_line
			(start -0.12065 -0.2794)
			(end -0.12065 -0.3048)
			(stroke
				(width 0.1)
				(type default)
			)
			(layer "B.Fab")
		)
		(fp_line
			(start -0.12065 -0.3048)
			(end -0.67945 -0.3048)
			(stroke
				(width 0.1)
				(type default)
			)
			(layer "B.Fab")
		)
		(fp_line
			(start -0.67945 0.3048)
			(end -0.120396 0.3048)
			(stroke
				(width 0.1)
				(type default)
			)
			(layer "B.Fab")
		)
		(fp_line
			(start -0.67945 -0.3048)
			(end -0.67945 0.3048)
			(stroke
				(width 0.1)
				(type default)
			)
			(layer "B.Fab")
		)
		(pad "1" smd circle
			(at 0.40005 0)
			(size 0 0)
			(layers "B.Cu" "B.Mask" "B.Paste")
			(net "PVDDCR_CPU1_P0")
		)
		(pad "2" smd circle
			(at -0.40005 0)
			(size 0 0)
			(layers "B.Cu" "B.Mask" "B.Paste")
			(net "GND")
		)
	)
	(footprint ""
		(layer "B.Cu")
		(at 184.681114 -419.861238)
		(property "Reference" "R2796"
			(at 0 0 0)
			(layer "B.SilkS")
			(hide yes)
			(effects
				(font
					(size 1.27 1.27)
				)
				(justify mirror)
			)
		)
		(property "Value" ""
			(at 0 0 0)
			(layer "B.Fab")
			(effects
				(font
					(size 1.27 1.27)
				)
				(justify mirror)
			)
		)
		(duplicate_pad_numbers_are_jumpers no)
		(fp_line
			(start -0.7874 -0.4064)
			(end -0.7874 0.4064)
			(stroke
				(width 0.1524)
				(type default)
			)
			(layer "B.SilkS")
		)
		(fp_line
			(start -0.7874 0.4064)
			(end 0.7874 0.4064)
			(stroke
				(width 0.1524)
				(type default)
			)
			(layer "B.SilkS")
		)
		(fp_line
			(start 0.7874 -0.4064)
			(end -0.7874 -0.4064)
			(stroke
				(width 0.1524)
				(type default)
			)
			(layer "B.SilkS")
		)
		(fp_line
			(start 0.7874 0.4064)
			(end 0.7874 -0.4064)
			(stroke
				(width 0.1524)
				(type default)
			)
			(layer "B.SilkS")
		)
		(fp_line
			(start -0.67945 -0.3048)
			(end -0.67945 0.3048)
			(stroke
				(width 0.1)
				(type default)
			)
			(layer "B.Fab")
		)
		(fp_line
			(start -0.67945 0.3048)
			(end -0.120396 0.3048)
			(stroke
				(width 0.1)
				(type default)
			)
			(layer "B.Fab")
		)
		(fp_line
			(start -0.12065 -0.3048)
			(end -0.67945 -0.3048)
			(stroke
				(width 0.1)
				(type default)
			)
			(layer "B.Fab")
		)
		(fp_line
			(start -0.12065 -0.2794)
			(end -0.12065 -0.3048)
			(stroke
				(width 0.1)
				(type default)
			)
			(layer "B.Fab")
		)
		(fp_line
			(start -0.120396 0.2794)
			(end 0.12065 0.2794)
			(stroke
				(width 0.1)
				(type default)
			)
			(layer "B.Fab")
		)
		(fp_line
			(start -0.120396 0.3048)
			(end -0.120396 0.2794)
			(stroke
				(width 0.1)
				(type default)
			)
			(layer "B.Fab")
		)
		(fp_line
			(start 0.12065 -0.305054)
			(end 0.12065 -0.2794)
			(stroke
				(width 0.1)
				(type default)
			)
			(layer "B.Fab")
		)
		(fp_line
			(start 0.12065 -0.2794)
			(end -0.12065 -0.2794)
			(stroke
				(width 0.1)
				(type default)
			)
			(layer "B.Fab")
		)
		(fp_line
			(start 0.12065 0.2794)
			(end 0.12065 0.3048)
			(stroke
				(width 0.1)
				(type default)
			)
			(layer "B.Fab")
		)
		(fp_line
			(start 0.12065 0.3048)
			(end 0.67945 0.3048)
			(stroke
				(width 0.1)
				(type default)
			)
			(layer "B.Fab")
		)
		(fp_line
			(start 0.67945 -0.305054)
			(end 0.12065 -0.305054)
			(stroke
				(width 0.1)
				(type default)
			)
			(layer "B.Fab")
		)
		(fp_line
			(start 0.67945 0.3048)
			(end 0.67945 -0.305054)
			(stroke
				(width 0.1)
				(type default)
			)
			(layer "B.Fab")
		)
		(pad "1" smd circle
			(at 0.40005 0 180)
			(size 0 0)
			(layers "B.Cu" "B.Mask" "B.Paste")
			(net "FM_PDB_BUF_EN_R1")
		)
		(pad "2" smd circle
			(at -0.40005 0 180)
			(size 0 0)
			(layers "B.Cu" "B.Mask" "B.Paste")
			(net "MB_PDB_SMB9_R_EN")
		)
	)
	(footprint ""
		(layer "B.Cu")
		(at 118.277386 -248.479564 180)
		(property "Reference" "C2337"
			(at 0 0 0)
			(layer "B.SilkS")
			(hide yes)
			(effects
				(font
					(size 1.27 1.27)
				)
				(justify mirror)
			)
		)
		(property "Value" ""
			(at 0 0 0)
			(layer "B.Fab")
			(effects
				(font
					(size 1.27 1.27)
				)
				(justify mirror)
			)
		)
		(duplicate_pad_numbers_are_jumpers no)
		(fp_line
			(start 0.7874 0.4064)
			(end 0.7874 -0.4064)
			(stroke
				(width 0.1524)
				(type default)
			)
			(layer "B.SilkS")
		)
		(fp_line
			(start 0.7874 -0.4064)
			(end -0.7874 -0.4064)
			(stroke
				(width 0.1524)
				(type default)
			)
			(layer "B.SilkS")
		)
		(fp_line
			(start -0.7874 0.4064)
			(end 0.7874 0.4064)
			(stroke
				(width 0.1524)
				(type default)
			)
			(layer "B.SilkS")
		)
		(fp_line
			(start -0.7874 -0.4064)
			(end -0.7874 0.4064)
			(stroke
				(width 0.1524)
				(type default)
			)
			(layer "B.SilkS")
		)
		(fp_line
			(start 0.67945 0.3048)
			(end 0.67945 -0.305054)
			(stroke
				(width 0.1)
				(type default)
			)
			(layer "B.Fab")
		)
		(fp_line
			(start 0.67945 -0.305054)
			(end 0.12065 -0.305054)
			(stroke
				(width 0.1)
				(type default)
			)
			(layer "B.Fab")
		)
		(fp_line
			(start 0.12065 0.3048)
			(end 0.67945 0.3048)
			(stroke
				(width 0.1)
				(type default)
			)
			(layer "B.Fab")
		)
		(fp_line
			(start 0.12065 0.2794)
			(end 0.12065 0.3048)
			(stroke
				(width 0.1)
				(type default)
			)
			(layer "B.Fab")
		)
		(fp_line
			(start 0.12065 -0.2794)
			(end -0.12065 -0.2794)
			(stroke
				(width 0.1)
				(type default)
			)
			(layer "B.Fab")
		)
		(fp_line
			(start 0.12065 -0.305054)
			(end 0.12065 -0.2794)
			(stroke
				(width 0.1)
				(type default)
			)
			(layer "B.Fab")
		)
		(fp_line
			(start -0.120396 0.3048)
			(end -0.120396 0.2794)
			(stroke
				(width 0.1)
				(type default)
			)
			(layer "B.Fab")
		)
		(fp_line
			(start -0.120396 0.2794)
			(end 0.12065 0.2794)
			(stroke
				(width 0.1)
				(type default)
			)
			(layer "B.Fab")
		)
		(fp_line
			(start -0.12065 -0.2794)
			(end -0.12065 -0.3048)
			(stroke
				(width 0.1)
				(type default)
			)
			(layer "B.Fab")
		)
		(fp_line
			(start -0.12065 -0.3048)
			(end -0.67945 -0.3048)
			(stroke
				(width 0.1)
				(type default)
			)
			(layer "B.Fab")
		)
		(fp_line
			(start -0.67945 0.3048)
			(end -0.120396 0.3048)
			(stroke
				(width 0.1)
				(type default)
			)
			(layer "B.Fab")
		)
		(fp_line
			(start -0.67945 -0.3048)
			(end -0.67945 0.3048)
			(stroke
				(width 0.1)
				(type default)
			)
			(layer "B.Fab")
		)
		(pad "1" smd circle
			(at 0.40005 0)
			(size 0 0)
			(layers "B.Cu" "B.Mask" "B.Paste")
			(net "PVDDCR_CPU0_P1")
		)
		(pad "2" smd circle
			(at -0.40005 0)
			(size 0 0)
			(layers "B.Cu" "B.Mask" "B.Paste")
			(net "GND")
		)
	)
	(footprint ""
		(layer "B.Cu")
		(at 160.103312 -417.50488 180)
		(property "Reference" "U43"
			(at -0.04318 -3.007106 0)
			(unlocked yes)
			(layer "B.SilkS")
			(effects
				(font
					(size 0.7874 0.5842)
					(thickness 0.1524)
				)
				(justify mirror)
			)
		)
		(property "Value" ""
			(at 0 0 0)
			(layer "B.Fab")
			(effects
				(font
					(size 1.27 1.27)
				)
				(justify mirror)
			)
		)
		(duplicate_pad_numbers_are_jumpers no)
		(fp_line
			(start 1.03378 1.284478)
			(end 1.03378 -1.284478)
			(stroke
				(width 0.1524)
				(type default)
			)
			(layer "B.SilkS")
		)
		(fp_line
			(start 1.03378 -1.284478)
			(end -1.03378 -1.284478)
			(stroke
				(width 0.1524)
				(type default)
			)
			(layer "B.SilkS")
		)
		(fp_line
			(start -1.03378 1.284478)
			(end 1.03378 1.284478)
			(stroke
				(width 0.1524)
				(type default)
			)
			(layer "B.SilkS")
		)
		(fp_line
			(start -1.03378 -1.284478)
			(end -1.03378 1.284478)
			(stroke
				(width 0.1524)
				(type default)
			)
			(layer "B.SilkS")
		)
		(fp_poly
			(pts
				(xy 1.183132 -0.700532) (xy 1.6129 -0.178308) (xy 1.858772 -0.731012)
			)
			(stroke
				(width 0)
				(type default)
			)
			(fill yes)
			(layer "B.SilkS")
		)
		(fp_line
			(start 0.774954 1.02489)
			(end 0.774954 -1.02489)
			(stroke
				(width 0.1)
				(type default)
			)
			(layer "B.Fab")
		)
		(fp_line
			(start 0.774954 -1.02489)
			(end -0.774954 -1.02489)
			(stroke
				(width 0.1)
				(type default)
			)
			(layer "B.Fab")
		)
		(fp_line
			(start -0.774954 1.02489)
			(end 0.774954 1.02489)
			(stroke
				(width 0.1)
				(type default)
			)
			(layer "B.Fab")
		)
		(fp_line
			(start -0.774954 -1.02489)
			(end -0.774954 1.02489)
			(stroke
				(width 0.1)
				(type default)
			)
			(layer "B.Fab")
		)
		(fp_poly
			(pts
				(xy 1.201674 -0.750062) (xy 1.806702 -0.447548) (xy 1.806702 -1.052576)
			)
			(stroke
				(width 0)
				(type default)
			)
			(fill yes)
			(layer "B.Fab")
		)
		(pad "1" smd rect
			(at 0.64008 -0.750062 270)
			(size 0.3048 0.5334)
			(layers "B.Cu" "B.Mask" "B.Paste")
			(net "SMB_RT_CPU1_P2_ROM_MUX_1D_SCL")
		)
		(pad "2" smd rect
			(at 0.64008 -0.249936 270)
			(size 0.254 0.5334)
			(layers "B.Cu" "B.Mask" "B.Paste")
			(net "SMB_RT_CPU1_P2_ROM_MUX_1D_SDA")
		)
		(pad "3" smd rect
			(at 0.64008 0.249936 270)
			(size 0.254 0.5334)
			(layers "B.Cu" "B.Mask" "B.Paste")
			(net "SMB_RT_CPU1_P2_ROM_MUX_2D_SCL")
		)
		(pad "4" smd rect
			(at 0.64008 0.750062 270)
			(size 0.3048 0.5334)
			(layers "B.Cu" "B.Mask" "B.Paste")
			(net "SMB_RT_CPU1_P2_ROM_MUX_2D_SDA")
		)
		(pad "5" smd rect
			(at 0 0.839978)
			(size 0.3302 0.635)
			(layers "B.Cu" "B.Mask" "B.Paste")
			(net "GND")
		)
		(pad "6" smd rect
			(at -0.64008 0.750062 270)
			(size 0.3048 0.5334)
			(layers "B.Cu" "B.Mask" "B.Paste")
			(net "RT_ROM_MUX4_OE_N")
		)
		(pad "7" smd rect
			(at -0.64008 0.249936 270)
			(size 0.254 0.5334)
			(layers "B.Cu" "B.Mask" "B.Paste")
			(net "SMB_RT_CPU1_P2_ROM_R_SDA")
		)
		(pad "8" smd rect
			(at -0.64008 -0.249936 270)
			(size 0.254 0.5334)
			(layers "B.Cu" "B.Mask" "B.Paste")
			(net "SMB_RT_CPU1_P2_ROM_R_SCL")
		)
		(pad "9" smd rect
			(at -0.64008 -0.750062 270)
			(size 0.3048 0.5334)
			(layers "B.Cu" "B.Mask" "B.Paste")
			(net "FM_SMB_RT_ROM_MUX4_SEL")
		)
		(pad "10" smd rect
			(at 0 -0.839978)
			(size 0.3302 0.635)
			(layers "B.Cu" "B.Mask" "B.Paste")
			(net "P3V3_AUX")
		)
	)
	(footprint ""
		(layer "B.Cu")
		(at 258.208018 -53.118512 90)
		(property "Reference" "PR4541"
			(at 0 0 90)
			(layer "B.SilkS")
			(hide yes)
			(effects
				(font
					(size 1.27 1.27)
				)
				(justify mirror)
			)
		)
		(property "Value" ""
			(at 0 0 90)
			(layer "B.Fab")
			(effects
				(font
					(size 1.27 1.27)
				)
				(justify mirror)
			)
		)
		(duplicate_pad_numbers_are_jumpers no)
		(fp_line
			(start 0.7874 -0.4064)
			(end -0.7874 -0.4064)
			(stroke
				(width 0.1524)
				(type default)
			)
			(layer "B.SilkS")
		)
		(fp_line
			(start -0.7874 -0.4064)
			(end -0.7874 0.4064)
			(stroke
				(width 0.1524)
				(type default)
			)
			(layer "B.SilkS")
		)
		(fp_line
			(start 0.7874 0.4064)
			(end 0.7874 -0.4064)
			(stroke
				(width 0.1524)
				(type default)
			)
			(layer "B.SilkS")
		)
		(fp_line
			(start -0.7874 0.4064)
			(end 0.7874 0.4064)
			(stroke
				(width 0.1524)
				(type default)
			)
			(layer "B.SilkS")
		)
		(fp_line
			(start 0.67945 -0.305054)
			(end 0.12065 -0.305054)
			(stroke
				(width 0.1)
				(type default)
			)
			(layer "B.Fab")
		)
		(fp_line
			(start 0.12065 -0.305054)
			(end 0.12065 -0.2794)
			(stroke
				(width 0.1)
				(type default)
			)
			(layer "B.Fab")
		)
		(fp_line
			(start -0.12065 -0.3048)
			(end -0.67945 -0.3048)
			(stroke
				(width 0.1)
				(type default)
			)
			(layer "B.Fab")
		)
		(fp_line
			(start -0.67945 -0.3048)
			(end -0.67945 0.3048)
			(stroke
				(width 0.1)
				(type default)
			)
			(layer "B.Fab")
		)
		(fp_line
			(start 0.12065 -0.2794)
			(end -0.12065 -0.2794)
			(stroke
				(width 0.1)
				(type default)
			)
			(layer "B.Fab")
		)
		(fp_line
			(start -0.12065 -0.2794)
			(end -0.12065 -0.3048)
			(stroke
				(width 0.1)
				(type default)
			)
			(layer "B.Fab")
		)
		(fp_line
			(start 0.12065 0.2794)
			(end 0.12065 0.3048)
			(stroke
				(width 0.1)
				(type default)
			)
			(layer "B.Fab")
		)
		(fp_line
			(start -0.120396 0.2794)
			(end 0.12065 0.2794)
			(stroke
				(width 0.1)
				(type default)
			)
			(layer "B.Fab")
		)
		(fp_line
			(start 0.67945 0.3048)
			(end 0.67945 -0.305054)
			(stroke
				(width 0.1)
				(type default)
			)
			(layer "B.Fab")
		)
		(fp_line
			(start 0.12065 0.3048)
			(end 0.67945 0.3048)
			(stroke
				(width 0.1)
				(type default)
			)
			(layer "B.Fab")
		)
		(fp_line
			(start -0.120396 0.3048)
			(end -0.120396 0.2794)
			(stroke
				(width 0.1)
				(type default)
			)
			(layer "B.Fab")
		)
		(fp_line
			(start -0.67945 0.3048)
			(end -0.120396 0.3048)
			(stroke
				(width 0.1)
				(type default)
			)
			(layer "B.Fab")
		)
		(pad "1" smd circle
			(at 0.40005 0 270)
			(size 0 0)
			(layers "B.Cu" "B.Mask" "B.Paste")
			(net "P12V_E1S_ISET_0")
		)
		(pad "2" smd circle
			(at -0.40005 0 270)
			(size 0 0)
			(layers "B.Cu" "B.Mask" "B.Paste")
			(net "P12V_E1S_ISET_0_R")
		)
	)
	(footprint ""
		(layer "B.Cu")
		(at 347.008958 -250.89231 180)
		(property "Reference" "C2521"
			(at 0 0 0)
			(layer "B.SilkS")
			(hide yes)
			(effects
				(font
					(size 1.27 1.27)
				)
				(justify mirror)
			)
		)
		(property "Value" ""
			(at 0 0 0)
			(layer "B.Fab")
			(effects
				(font
					(size 1.27 1.27)
				)
				(justify mirror)
			)
		)
		(duplicate_pad_numbers_are_jumpers no)
		(fp_line
			(start 0.7874 0.4064)
			(end 0.7874 -0.4064)
			(stroke
				(width 0.1524)
				(type default)
			)
			(layer "B.SilkS")
		)
		(fp_line
			(start 0.7874 -0.4064)
			(end -0.7874 -0.4064)
			(stroke
				(width 0.1524)
				(type default)
			)
			(layer "B.SilkS")
		)
		(fp_line
			(start -0.7874 0.4064)
			(end 0.7874 0.4064)
			(stroke
				(width 0.1524)
				(type default)
			)
			(layer "B.SilkS")
		)
		(fp_line
			(start -0.7874 -0.4064)
			(end -0.7874 0.4064)
			(stroke
				(width 0.1524)
				(type default)
			)
			(layer "B.SilkS")
		)
		(fp_line
			(start 0.67945 0.3048)
			(end 0.67945 -0.305054)
			(stroke
				(width 0.1)
				(type default)
			)
			(layer "B.Fab")
		)
		(fp_line
			(start 0.67945 -0.305054)
			(end 0.12065 -0.305054)
			(stroke
				(width 0.1)
				(type default)
			)
			(layer "B.Fab")
		)
		(fp_line
			(start 0.12065 0.3048)
			(end 0.67945 0.3048)
			(stroke
				(width 0.1)
				(type default)
			)
			(layer "B.Fab")
		)
		(fp_line
			(start 0.12065 0.2794)
			(end 0.12065 0.3048)
			(stroke
				(width 0.1)
				(type default)
			)
			(layer "B.Fab")
		)
		(fp_line
			(start 0.12065 -0.2794)
			(end -0.12065 -0.2794)
			(stroke
				(width 0.1)
				(type default)
			)
			(layer "B.Fab")
		)
		(fp_line
			(start 0.12065 -0.305054)
			(end 0.12065 -0.2794)
			(stroke
				(width 0.1)
				(type default)
			)
			(layer "B.Fab")
		)
		(fp_line
			(start -0.120396 0.3048)
			(end -0.120396 0.2794)
			(stroke
				(width 0.1)
				(type default)
			)
			(layer "B.Fab")
		)
		(fp_line
			(start -0.120396 0.2794)
			(end 0.12065 0.2794)
			(stroke
				(width 0.1)
				(type default)
			)
			(layer "B.Fab")
		)
		(fp_line
			(start -0.12065 -0.2794)
			(end -0.12065 -0.3048)
			(stroke
				(width 0.1)
				(type default)
			)
			(layer "B.Fab")
		)
		(fp_line
			(start -0.12065 -0.3048)
			(end -0.67945 -0.3048)
			(stroke
				(width 0.1)
				(type default)
			)
			(layer "B.Fab")
		)
		(fp_line
			(start -0.67945 0.3048)
			(end -0.120396 0.3048)
			(stroke
				(width 0.1)
				(type default)
			)
			(layer "B.Fab")
		)
		(fp_line
			(start -0.67945 -0.3048)
			(end -0.67945 0.3048)
			(stroke
				(width 0.1)
				(type default)
			)
			(layer "B.Fab")
		)
		(pad "1" smd circle
			(at 0.40005 0)
			(size 0 0)
			(layers "B.Cu" "B.Mask" "B.Paste")
			(net "PVDD18_S5_P0")
		)
		(pad "2" smd circle
			(at -0.40005 0)
			(size 0 0)
			(layers "B.Cu" "B.Mask" "B.Paste")
			(net "GND")
		)
	)
	(footprint ""
		(layer "B.Cu")
		(at 419.129464 -426.799248 180)
		(property "Reference" "R840"
			(at 0 0 0)
			(layer "B.SilkS")
			(hide yes)
			(effects
				(font
					(size 1.27 1.27)
				)
				(justify mirror)
			)
		)
		(property "Value" ""
			(at 0 0 0)
			(layer "B.Fab")
			(effects
				(font
					(size 1.27 1.27)
				)
				(justify mirror)
			)
		)
		(duplicate_pad_numbers_are_jumpers no)
		(fp_line
			(start 0.32512 0.175006)
			(end 0.32512 -0.175006)
			(stroke
				(width 0.1)
				(type default)
			)
			(layer "B.Fab")
		)
		(fp_line
			(start 0.32512 -0.175006)
			(end -0.32512 -0.175006)
			(stroke
				(width 0.1)
				(type default)
			)
			(layer "B.Fab")
		)
		(fp_line
			(start -0.32512 0.175006)
			(end 0.32512 0.175006)
			(stroke
				(width 0.1)
				(type default)
			)
			(layer "B.Fab")
		)
		(fp_line
			(start -0.32512 -0.175006)
			(end -0.32512 0.175006)
			(stroke
				(width 0.1)
				(type default)
			)
			(layer "B.Fab")
		)
		(pad "1" smd rect
			(at 0.2667 0)
			(size 0.3048 0.381)
			(layers "B.Cu" "B.Mask" "B.Paste")
			(net "P1V8_CPU0_RT_1D")
		)
		(pad "2" smd rect
			(at -0.2667 0 180)
			(size 0.3048 0.381)
			(layers "B.Cu" "B.Mask" "B.Paste")
			(net "SMB_RT_CPU0_P2_ROM_R_SDA")
		)
	)
	(footprint ""
		(layer "B.Cu")
		(at 350.342454 -256.73431 180)
		(property "Reference" "C2554"
			(at 0 0 0)
			(layer "B.SilkS")
			(hide yes)
			(effects
				(font
					(size 1.27 1.27)
				)
				(justify mirror)
			)
		)
		(property "Value" ""
			(at 0 0 0)
			(layer "B.Fab")
			(effects
				(font
					(size 1.27 1.27)
				)
				(justify mirror)
			)
		)
		(duplicate_pad_numbers_are_jumpers no)
		(fp_line
			(start 0.7874 0.4064)
			(end 0.7874 -0.4064)
			(stroke
				(width 0.1524)
				(type default)
			)
			(layer "B.SilkS")
		)
		(fp_line
			(start 0.7874 -0.4064)
			(end -0.7874 -0.4064)
			(stroke
				(width 0.1524)
				(type default)
			)
			(layer "B.SilkS")
		)
		(fp_line
			(start -0.7874 0.4064)
			(end 0.7874 0.4064)
			(stroke
				(width 0.1524)
				(type default)
			)
			(layer "B.SilkS")
		)
		(fp_line
			(start -0.7874 -0.4064)
			(end -0.7874 0.4064)
			(stroke
				(width 0.1524)
				(type default)
			)
			(layer "B.SilkS")
		)
		(fp_line
			(start 0.67945 0.3048)
			(end 0.67945 -0.305054)
			(stroke
				(width 0.1)
				(type default)
			)
			(layer "B.Fab")
		)
		(fp_line
			(start 0.67945 -0.305054)
			(end 0.12065 -0.305054)
			(stroke
				(width 0.1)
				(type default)
			)
			(layer "B.Fab")
		)
		(fp_line
			(start 0.12065 0.3048)
			(end 0.67945 0.3048)
			(stroke
				(width 0.1)
				(type default)
			)
			(layer "B.Fab")
		)
		(fp_line
			(start 0.12065 0.2794)
			(end 0.12065 0.3048)
			(stroke
				(width 0.1)
				(type default)
			)
			(layer "B.Fab")
		)
		(fp_line
			(start 0.12065 -0.2794)
			(end -0.12065 -0.2794)
			(stroke
				(width 0.1)
				(type default)
			)
			(layer "B.Fab")
		)
		(fp_line
			(start 0.12065 -0.305054)
			(end 0.12065 -0.2794)
			(stroke
				(width 0.1)
				(type default)
			)
			(layer "B.Fab")
		)
		(fp_line
			(start -0.120396 0.3048)
			(end -0.120396 0.2794)
			(stroke
				(width 0.1)
				(type default)
			)
			(layer "B.Fab")
		)
		(fp_line
			(start -0.120396 0.2794)
			(end 0.12065 0.2794)
			(stroke
				(width 0.1)
				(type default)
			)
			(layer "B.Fab")
		)
		(fp_line
			(start -0.12065 -0.2794)
			(end -0.12065 -0.3048)
			(stroke
				(width 0.1)
				(type default)
			)
			(layer "B.Fab")
		)
		(fp_line
			(start -0.12065 -0.3048)
			(end -0.67945 -0.3048)
			(stroke
				(width 0.1)
				(type default)
			)
			(layer "B.Fab")
		)
		(fp_line
			(start -0.67945 0.3048)
			(end -0.120396 0.3048)
			(stroke
				(width 0.1)
				(type default)
			)
			(layer "B.Fab")
		)
		(fp_line
			(start -0.67945 -0.3048)
			(end -0.67945 0.3048)
			(stroke
				(width 0.1)
				(type default)
			)
			(layer "B.Fab")
		)
		(pad "1" smd circle
			(at 0.40005 0)
			(size 0 0)
			(layers "B.Cu" "B.Mask" "B.Paste")
			(net "PVDDCR_SOC_P0")
		)
		(pad "2" smd circle
			(at -0.40005 0)
			(size 0 0)
			(layers "B.Cu" "B.Mask" "B.Paste")
			(net "GND")
		)
	)
	(footprint ""
		(layer "B.Cu")
		(at 24.765 -358.775 180)
		(property "Reference" "R8219"
			(at 0 0 0)
			(layer "B.SilkS")
			(hide yes)
			(effects
				(font
					(size 1.27 1.27)
				)
				(justify mirror)
			)
		)
		(property "Value" ""
			(at 0 0 0)
			(layer "B.Fab")
			(effects
				(font
					(size 1.27 1.27)
				)
				(justify mirror)
			)
		)
		(duplicate_pad_numbers_are_jumpers no)
		(fp_line
			(start 0.7874 0.4064)
			(end 0.7874 -0.4064)
			(stroke
				(width 0.1524)
				(type default)
			)
			(layer "B.SilkS")
		)
		(fp_line
			(start 0.7874 -0.4064)
			(end -0.7874 -0.4064)
			(stroke
				(width 0.1524)
				(type default)
			)
			(layer "B.SilkS")
		)
		(fp_line
			(start -0.7874 0.4064)
			(end 0.7874 0.4064)
			(stroke
				(width 0.1524)
				(type default)
			)
			(layer "B.SilkS")
		)
		(fp_line
			(start -0.7874 -0.4064)
			(end -0.7874 0.4064)
			(stroke
				(width 0.1524)
				(type default)
			)
			(layer "B.SilkS")
		)
		(fp_line
			(start 0.67945 0.3048)
			(end 0.67945 -0.305054)
			(stroke
				(width 0.1)
				(type default)
			)
			(layer "B.Fab")
		)
		(fp_line
			(start 0.67945 -0.305054)
			(end 0.12065 -0.305054)
			(stroke
				(width 0.1)
				(type default)
			)
			(layer "B.Fab")
		)
		(fp_line
			(start 0.12065 0.3048)
			(end 0.67945 0.3048)
			(stroke
				(width 0.1)
				(type default)
			)
			(layer "B.Fab")
		)
		(fp_line
			(start 0.12065 0.2794)
			(end 0.12065 0.3048)
			(stroke
				(width 0.1)
				(type default)
			)
			(layer "B.Fab")
		)
		(fp_line
			(start 0.12065 -0.2794)
			(end -0.12065 -0.2794)
			(stroke
				(width 0.1)
				(type default)
			)
			(layer "B.Fab")
		)
		(fp_line
			(start 0.12065 -0.305054)
			(end 0.12065 -0.2794)
			(stroke
				(width 0.1)
				(type default)
			)
			(layer "B.Fab")
		)
		(fp_line
			(start -0.120396 0.3048)
			(end -0.120396 0.2794)
			(stroke
				(width 0.1)
				(type default)
			)
			(layer "B.Fab")
		)
		(fp_line
			(start -0.120396 0.2794)
			(end 0.12065 0.2794)
			(stroke
				(width 0.1)
				(type default)
			)
			(layer "B.Fab")
		)
		(fp_line
			(start -0.12065 -0.2794)
			(end -0.12065 -0.3048)
			(stroke
				(width 0.1)
				(type default)
			)
			(layer "B.Fab")
		)
		(fp_line
			(start -0.12065 -0.3048)
			(end -0.67945 -0.3048)
			(stroke
				(width 0.1)
				(type default)
			)
			(layer "B.Fab")
		)
		(fp_line
			(start -0.67945 0.3048)
			(end -0.120396 0.3048)
			(stroke
				(width 0.1)
				(type default)
			)
			(layer "B.Fab")
		)
		(fp_line
			(start -0.67945 -0.3048)
			(end -0.67945 0.3048)
			(stroke
				(width 0.1)
				(type default)
			)
			(layer "B.Fab")
		)
		(pad "1" smd circle
			(at 0.40005 0)
			(size 0 0)
			(layers "B.Cu" "B.Mask" "B.Paste")
			(net "SVID_PVDDCR_CPU1_P1_SVTO")
		)
		(pad "2" smd circle
			(at -0.40005 0)
			(size 0 0)
			(layers "B.Cu" "B.Mask" "B.Paste")
			(net "GND")
		)
	)
	(footprint ""
		(layer "B.Cu")
		(at 156.17063 -13.762228 90)
		(property "Reference" "R2413"
			(at 0 0 90)
			(layer "B.SilkS")
			(hide yes)
			(effects
				(font
					(size 1.27 1.27)
				)
				(justify mirror)
			)
		)
		(property "Value" ""
			(at 0 0 90)
			(layer "B.Fab")
			(effects
				(font
					(size 1.27 1.27)
				)
				(justify mirror)
			)
		)
		(duplicate_pad_numbers_are_jumpers no)
		(fp_line
			(start 0.7874 -0.4064)
			(end -0.7874 -0.4064)
			(stroke
				(width 0.1524)
				(type default)
			)
			(layer "B.SilkS")
		)
		(fp_line
			(start -0.7874 -0.4064)
			(end -0.7874 0.4064)
			(stroke
				(width 0.1524)
				(type default)
			)
			(layer "B.SilkS")
		)
		(fp_line
			(start 0.7874 0.4064)
			(end 0.7874 -0.4064)
			(stroke
				(width 0.1524)
				(type default)
			)
			(layer "B.SilkS")
		)
		(fp_line
			(start -0.7874 0.4064)
			(end 0.7874 0.4064)
			(stroke
				(width 0.1524)
				(type default)
			)
			(layer "B.SilkS")
		)
		(fp_line
			(start 0.67945 -0.305054)
			(end 0.12065 -0.305054)
			(stroke
				(width 0.1)
				(type default)
			)
			(layer "B.Fab")
		)
		(fp_line
			(start 0.12065 -0.305054)
			(end 0.12065 -0.2794)
			(stroke
				(width 0.1)
				(type default)
			)
			(layer "B.Fab")
		)
		(fp_line
			(start -0.12065 -0.3048)
			(end -0.67945 -0.3048)
			(stroke
				(width 0.1)
				(type default)
			)
			(layer "B.Fab")
		)
		(fp_line
			(start -0.67945 -0.3048)
			(end -0.67945 0.3048)
			(stroke
				(width 0.1)
				(type default)
			)
			(layer "B.Fab")
		)
		(fp_line
			(start 0.12065 -0.2794)
			(end -0.12065 -0.2794)
			(stroke
				(width 0.1)
				(type default)
			)
			(layer "B.Fab")
		)
		(fp_line
			(start -0.12065 -0.2794)
			(end -0.12065 -0.3048)
			(stroke
				(width 0.1)
				(type default)
			)
			(layer "B.Fab")
		)
		(fp_line
			(start 0.12065 0.2794)
			(end 0.12065 0.3048)
			(stroke
				(width 0.1)
				(type default)
			)
			(layer "B.Fab")
		)
		(fp_line
			(start -0.120396 0.2794)
			(end 0.12065 0.2794)
			(stroke
				(width 0.1)
				(type default)
			)
			(layer "B.Fab")
		)
		(fp_line
			(start 0.67945 0.3048)
			(end 0.67945 -0.305054)
			(stroke
				(width 0.1)
				(type default)
			)
			(layer "B.Fab")
		)
		(fp_line
			(start 0.12065 0.3048)
			(end 0.67945 0.3048)
			(stroke
				(width 0.1)
				(type default)
			)
			(layer "B.Fab")
		)
		(fp_line
			(start -0.120396 0.3048)
			(end -0.120396 0.2794)
			(stroke
				(width 0.1)
				(type default)
			)
			(layer "B.Fab")
		)
		(fp_line
			(start -0.67945 0.3048)
			(end -0.120396 0.3048)
			(stroke
				(width 0.1)
				(type default)
			)
			(layer "B.Fab")
		)
		(pad "1" smd circle
			(at 0.40005 0 270)
			(size 0 0)
			(layers "B.Cu" "B.Mask" "B.Paste")
			(net "SMB_2_BMC_GPU_SCL")
		)
		(pad "2" smd circle
			(at -0.40005 0 270)
			(size 0 0)
			(layers "B.Cu" "B.Mask" "B.Paste")
			(net "SMB_PCIE2_3V3AUX_SCL_R0")
		)
	)
	(footprint ""
		(layer "B.Cu")
		(at 182.860442 -193.996564)
		(property "Reference" "C168"
			(at 0 0 0)
			(layer "B.SilkS")
			(hide yes)
			(effects
				(font
					(size 1.27 1.27)
				)
				(justify mirror)
			)
		)
		(property "Value" ""
			(at 0 0 0)
			(layer "B.Fab")
			(effects
				(font
					(size 1.27 1.27)
				)
				(justify mirror)
			)
		)
		(duplicate_pad_numbers_are_jumpers no)
		(fp_line
			(start -0.7874 -0.4064)
			(end -0.7874 0.4064)
			(stroke
				(width 0.1524)
				(type default)
			)
			(layer "B.SilkS")
		)
		(fp_line
			(start -0.7874 0.4064)
			(end 0.7874 0.4064)
			(stroke
				(width 0.1524)
				(type default)
			)
			(layer "B.SilkS")
		)
		(fp_line
			(start 0.7874 -0.4064)
			(end -0.7874 -0.4064)
			(stroke
				(width 0.1524)
				(type default)
			)
			(layer "B.SilkS")
		)
		(fp_line
			(start 0.7874 0.4064)
			(end 0.7874 -0.4064)
			(stroke
				(width 0.1524)
				(type default)
			)
			(layer "B.SilkS")
		)
		(fp_line
			(start -0.67945 -0.3048)
			(end -0.67945 0.3048)
			(stroke
				(width 0.1)
				(type default)
			)
			(layer "B.Fab")
		)
		(fp_line
			(start -0.67945 0.3048)
			(end -0.120396 0.3048)
			(stroke
				(width 0.1)
				(type default)
			)
			(layer "B.Fab")
		)
		(fp_line
			(start -0.12065 -0.3048)
			(end -0.67945 -0.3048)
			(stroke
				(width 0.1)
				(type default)
			)
			(layer "B.Fab")
		)
		(fp_line
			(start -0.12065 -0.2794)
			(end -0.12065 -0.3048)
			(stroke
				(width 0.1)
				(type default)
			)
			(layer "B.Fab")
		)
		(fp_line
			(start -0.120396 0.2794)
			(end 0.12065 0.2794)
			(stroke
				(width 0.1)
				(type default)
			)
			(layer "B.Fab")
		)
		(fp_line
			(start -0.120396 0.3048)
			(end -0.120396 0.2794)
			(stroke
				(width 0.1)
				(type default)
			)
			(layer "B.Fab")
		)
		(fp_line
			(start 0.12065 -0.305054)
			(end 0.12065 -0.2794)
			(stroke
				(width 0.1)
				(type default)
			)
			(layer "B.Fab")
		)
		(fp_line
			(start 0.12065 -0.2794)
			(end -0.12065 -0.2794)
			(stroke
				(width 0.1)
				(type default)
			)
			(layer "B.Fab")
		)
		(fp_line
			(start 0.12065 0.2794)
			(end 0.12065 0.3048)
			(stroke
				(width 0.1)
				(type default)
			)
			(layer "B.Fab")
		)
		(fp_line
			(start 0.12065 0.3048)
			(end 0.67945 0.3048)
			(stroke
				(width 0.1)
				(type default)
			)
			(layer "B.Fab")
		)
		(fp_line
			(start 0.67945 -0.305054)
			(end 0.12065 -0.305054)
			(stroke
				(width 0.1)
				(type default)
			)
			(layer "B.Fab")
		)
		(fp_line
			(start 0.67945 0.3048)
			(end 0.67945 -0.305054)
			(stroke
				(width 0.1)
				(type default)
			)
			(layer "B.Fab")
		)
		(pad "1" smd circle
			(at 0.40005 0 180)
			(size 0 0)
			(layers "B.Cu" "B.Mask" "B.Paste")
			(net "P3V3_AUX")
		)
		(pad "2" smd circle
			(at -0.40005 0 180)
			(size 0 0)
			(layers "B.Cu" "B.Mask" "B.Paste")
			(net "GND")
		)
	)
	(footprint ""
		(layer "B.Cu")
		(at 242.443 -234.061 90)
		(property "Reference" "R1159"
			(at 0 0 90)
			(layer "B.SilkS")
			(hide yes)
			(effects
				(font
					(size 1.27 1.27)
				)
				(justify mirror)
			)
		)
		(property "Value" ""
			(at 0 0 90)
			(layer "B.Fab")
			(effects
				(font
					(size 1.27 1.27)
				)
				(justify mirror)
			)
		)
		(duplicate_pad_numbers_are_jumpers no)
		(fp_line
			(start 0.7874 -0.4064)
			(end -0.7874 -0.4064)
			(stroke
				(width 0.1524)
				(type default)
			)
			(layer "B.SilkS")
		)
		(fp_line
			(start -0.7874 -0.4064)
			(end -0.7874 0.4064)
			(stroke
				(width 0.1524)
				(type default)
			)
			(layer "B.SilkS")
		)
		(fp_line
			(start 0.7874 0.4064)
			(end 0.7874 -0.4064)
			(stroke
				(width 0.1524)
				(type default)
			)
			(layer "B.SilkS")
		)
		(fp_line
			(start -0.7874 0.4064)
			(end 0.7874 0.4064)
			(stroke
				(width 0.1524)
				(type default)
			)
			(layer "B.SilkS")
		)
		(fp_line
			(start 0.67945 -0.305054)
			(end 0.12065 -0.305054)
			(stroke
				(width 0.1)
				(type default)
			)
			(layer "B.Fab")
		)
		(fp_line
			(start 0.12065 -0.305054)
			(end 0.12065 -0.2794)
			(stroke
				(width 0.1)
				(type default)
			)
			(layer "B.Fab")
		)
		(fp_line
			(start -0.12065 -0.3048)
			(end -0.67945 -0.3048)
			(stroke
				(width 0.1)
				(type default)
			)
			(layer "B.Fab")
		)
		(fp_line
			(start -0.67945 -0.3048)
			(end -0.67945 0.3048)
			(stroke
				(width 0.1)
				(type default)
			)
			(layer "B.Fab")
		)
		(fp_line
			(start 0.12065 -0.2794)
			(end -0.12065 -0.2794)
			(stroke
				(width 0.1)
				(type default)
			)
			(layer "B.Fab")
		)
		(fp_line
			(start -0.12065 -0.2794)
			(end -0.12065 -0.3048)
			(stroke
				(width 0.1)
				(type default)
			)
			(layer "B.Fab")
		)
		(fp_line
			(start 0.12065 0.2794)
			(end 0.12065 0.3048)
			(stroke
				(width 0.1)
				(type default)
			)
			(layer "B.Fab")
		)
		(fp_line
			(start -0.120396 0.2794)
			(end 0.12065 0.2794)
			(stroke
				(width 0.1)
				(type default)
			)
			(layer "B.Fab")
		)
		(fp_line
			(start 0.67945 0.3048)
			(end 0.67945 -0.305054)
			(stroke
				(width 0.1)
				(type default)
			)
			(layer "B.Fab")
		)
		(fp_line
			(start 0.12065 0.3048)
			(end 0.67945 0.3048)
			(stroke
				(width 0.1)
				(type default)
			)
			(layer "B.Fab")
		)
		(fp_line
			(start -0.120396 0.3048)
			(end -0.120396 0.2794)
			(stroke
				(width 0.1)
				(type default)
			)
			(layer "B.Fab")
		)
		(fp_line
			(start -0.67945 0.3048)
			(end -0.120396 0.3048)
			(stroke
				(width 0.1)
				(type default)
			)
			(layer "B.Fab")
		)
		(pad "1" smd circle
			(at 0.40005 0 270)
			(size 0 0)
			(layers "B.Cu" "B.Mask" "B.Paste")
			(net "SMB_CPU0_SEC_R_SCL")
		)
		(pad "2" smd circle
			(at -0.40005 0 270)
			(size 0 0)
			(layers "B.Cu" "B.Mask" "B.Paste")
			(net "SMB_CPU0_SEC_SCL")
		)
	)
	(footprint ""
		(layer "B.Cu")
		(at 117.996462 -170.864276 90)
		(property "Reference" "PR205"
			(at 0 0 90)
			(layer "B.SilkS")
			(hide yes)
			(effects
				(font
					(size 1.27 1.27)
				)
				(justify mirror)
			)
		)
		(property "Value" ""
			(at 0 0 90)
			(layer "B.Fab")
			(effects
				(font
					(size 1.27 1.27)
				)
				(justify mirror)
			)
		)
		(duplicate_pad_numbers_are_jumpers no)
		(fp_line
			(start 0.7874 -0.4064)
			(end -0.7874 -0.4064)
			(stroke
				(width 0.1524)
				(type default)
			)
			(layer "B.SilkS")
		)
		(fp_line
			(start -0.7874 -0.4064)
			(end -0.7874 0.4064)
			(stroke
				(width 0.1524)
				(type default)
			)
			(layer "B.SilkS")
		)
		(fp_line
			(start 0.7874 0.4064)
			(end 0.7874 -0.4064)
			(stroke
				(width 0.1524)
				(type default)
			)
			(layer "B.SilkS")
		)
		(fp_line
			(start -0.7874 0.4064)
			(end 0.7874 0.4064)
			(stroke
				(width 0.1524)
				(type default)
			)
			(layer "B.SilkS")
		)
		(fp_line
			(start 0.67945 -0.305054)
			(end 0.12065 -0.305054)
			(stroke
				(width 0.1)
				(type default)
			)
			(layer "B.Fab")
		)
		(fp_line
			(start 0.12065 -0.305054)
			(end 0.12065 -0.2794)
			(stroke
				(width 0.1)
				(type default)
			)
			(layer "B.Fab")
		)
		(fp_line
			(start -0.12065 -0.3048)
			(end -0.67945 -0.3048)
			(stroke
				(width 0.1)
				(type default)
			)
			(layer "B.Fab")
		)
		(fp_line
			(start -0.67945 -0.3048)
			(end -0.67945 0.3048)
			(stroke
				(width 0.1)
				(type default)
			)
			(layer "B.Fab")
		)
		(fp_line
			(start 0.12065 -0.2794)
			(end -0.12065 -0.2794)
			(stroke
				(width 0.1)
				(type default)
			)
			(layer "B.Fab")
		)
		(fp_line
			(start -0.12065 -0.2794)
			(end -0.12065 -0.3048)
			(stroke
				(width 0.1)
				(type default)
			)
			(layer "B.Fab")
		)
		(fp_line
			(start 0.12065 0.2794)
			(end 0.12065 0.3048)
			(stroke
				(width 0.1)
				(type default)
			)
			(layer "B.Fab")
		)
		(fp_line
			(start -0.120396 0.2794)
			(end 0.12065 0.2794)
			(stroke
				(width 0.1)
				(type default)
			)
			(layer "B.Fab")
		)
		(fp_line
			(start 0.67945 0.3048)
			(end 0.67945 -0.305054)
			(stroke
				(width 0.1)
				(type default)
			)
			(layer "B.Fab")
		)
		(fp_line
			(start 0.12065 0.3048)
			(end 0.67945 0.3048)
			(stroke
				(width 0.1)
				(type default)
			)
			(layer "B.Fab")
		)
		(fp_line
			(start -0.120396 0.3048)
			(end -0.120396 0.2794)
			(stroke
				(width 0.1)
				(type default)
			)
			(layer "B.Fab")
		)
		(fp_line
			(start -0.67945 0.3048)
			(end -0.120396 0.3048)
			(stroke
				(width 0.1)
				(type default)
			)
			(layer "B.Fab")
		)
		(pad "1" smd circle
			(at 0.40005 0 270)
			(size 0 0)
			(layers "B.Cu" "B.Mask" "B.Paste")
			(net "PVDDCR_CPU0_P1_PVCC")
		)
		(pad "2" smd circle
			(at -0.40005 0 270)
			(size 0 0)
			(layers "B.Cu" "B.Mask" "B.Paste")
			(net "PVDDCR_SOC_P1_VCC1")
		)
	)
	(footprint ""
		(layer "B.Cu")
		(at 47.538386 -190.948564 180)
		(property "Reference" "R304"
			(at 0 0 0)
			(layer "B.SilkS")
			(hide yes)
			(effects
				(font
					(size 1.27 1.27)
				)
				(justify mirror)
			)
		)
		(property "Value" ""
			(at 0 0 0)
			(layer "B.Fab")
			(effects
				(font
					(size 1.27 1.27)
				)
				(justify mirror)
			)
		)
		(duplicate_pad_numbers_are_jumpers no)
		(fp_line
			(start 0.7874 0.4064)
			(end 0.7874 -0.4064)
			(stroke
				(width 0.1524)
				(type default)
			)
			(layer "B.SilkS")
		)
		(fp_line
			(start 0.7874 -0.4064)
			(end -0.7874 -0.4064)
			(stroke
				(width 0.1524)
				(type default)
			)
			(layer "B.SilkS")
		)
		(fp_line
			(start -0.7874 0.4064)
			(end 0.7874 0.4064)
			(stroke
				(width 0.1524)
				(type default)
			)
			(layer "B.SilkS")
		)
		(fp_line
			(start -0.7874 -0.4064)
			(end -0.7874 0.4064)
			(stroke
				(width 0.1524)
				(type default)
			)
			(layer "B.SilkS")
		)
		(fp_line
			(start 0.67945 0.3048)
			(end 0.67945 -0.305054)
			(stroke
				(width 0.1)
				(type default)
			)
			(layer "B.Fab")
		)
		(fp_line
			(start 0.67945 -0.305054)
			(end 0.12065 -0.305054)
			(stroke
				(width 0.1)
				(type default)
			)
			(layer "B.Fab")
		)
		(fp_line
			(start 0.12065 0.3048)
			(end 0.67945 0.3048)
			(stroke
				(width 0.1)
				(type default)
			)
			(layer "B.Fab")
		)
		(fp_line
			(start 0.12065 0.2794)
			(end 0.12065 0.3048)
			(stroke
				(width 0.1)
				(type default)
			)
			(layer "B.Fab")
		)
		(fp_line
			(start 0.12065 -0.2794)
			(end -0.12065 -0.2794)
			(stroke
				(width 0.1)
				(type default)
			)
			(layer "B.Fab")
		)
		(fp_line
			(start 0.12065 -0.305054)
			(end 0.12065 -0.2794)
			(stroke
				(width 0.1)
				(type default)
			)
			(layer "B.Fab")
		)
		(fp_line
			(start -0.120396 0.3048)
			(end -0.120396 0.2794)
			(stroke
				(width 0.1)
				(type default)
			)
			(layer "B.Fab")
		)
		(fp_line
			(start -0.120396 0.2794)
			(end 0.12065 0.2794)
			(stroke
				(width 0.1)
				(type default)
			)
			(layer "B.Fab")
		)
		(fp_line
			(start -0.12065 -0.2794)
			(end -0.12065 -0.3048)
			(stroke
				(width 0.1)
				(type default)
			)
			(layer "B.Fab")
		)
		(fp_line
			(start -0.12065 -0.3048)
			(end -0.67945 -0.3048)
			(stroke
				(width 0.1)
				(type default)
			)
			(layer "B.Fab")
		)
		(fp_line
			(start -0.67945 0.3048)
			(end -0.120396 0.3048)
			(stroke
				(width 0.1)
				(type default)
			)
			(layer "B.Fab")
		)
		(fp_line
			(start -0.67945 -0.3048)
			(end -0.67945 0.3048)
			(stroke
				(width 0.1)
				(type default)
			)
			(layer "B.Fab")
		)
		(pad "1" smd circle
			(at 0.40005 0)
			(size 0 0)
			(layers "B.Cu" "B.Mask" "B.Paste")
			(net "PWRGD_CHB_CPU1_DIMM")
		)
		(pad "2" smd circle
			(at -0.40005 0)
			(size 0 0)
			(layers "B.Cu" "B.Mask" "B.Paste")
			(net "PWRGD_CHAF_CPU1")
		)
	)
	(footprint ""
		(layer "B.Cu")
		(at 305.778408 -395.148562 90)
		(property "Reference" "C526"
			(at 0 0 90)
			(layer "B.SilkS")
			(hide yes)
			(effects
				(font
					(size 1.27 1.27)
				)
				(justify mirror)
			)
		)
		(property "Value" ""
			(at 0 0 90)
			(layer "B.Fab")
			(effects
				(font
					(size 1.27 1.27)
				)
				(justify mirror)
			)
		)
		(duplicate_pad_numbers_are_jumpers no)
		(fp_line
			(start 0.299974 -0.150114)
			(end -0.299974 -0.150114)
			(stroke
				(width 0.1)
				(type default)
			)
			(layer "B.Fab")
		)
		(fp_line
			(start -0.299974 -0.150114)
			(end -0.299974 0.150114)
			(stroke
				(width 0.1)
				(type default)
			)
			(layer "B.Fab")
		)
		(fp_line
			(start 0.299974 0.150114)
			(end 0.299974 -0.150114)
			(stroke
				(width 0.1)
				(type default)
			)
			(layer "B.Fab")
		)
		(fp_line
			(start -0.299974 0.150114)
			(end 0.299974 0.150114)
			(stroke
				(width 0.1)
				(type default)
			)
			(layer "B.Fab")
		)
		(pad "1" smd rect
			(at 0.2667 0 270)
			(size 0.3048 0.381)
			(layers "B.Cu" "B.Mask" "B.Paste")
			(net "P0V9_CPU0_RT0_2A")
		)
		(pad "2" smd rect
			(at -0.2667 0 270)
			(size 0.3048 0.381)
			(layers "B.Cu" "B.Mask" "B.Paste")
			(net "GND")
		)
	)
	(footprint ""
		(layer "B.Cu")
		(at 199.517 -134.874 -90)
		(property "Reference" "R8106"
			(at 0 0 90)
			(layer "B.SilkS")
			(hide yes)
			(effects
				(font
					(size 1.27 1.27)
				)
				(justify mirror)
			)
		)
		(property "Value" ""
			(at 0 0 90)
			(layer "B.Fab")
			(effects
				(font
					(size 1.27 1.27)
				)
				(justify mirror)
			)
		)
		(duplicate_pad_numbers_are_jumpers no)
		(fp_line
			(start -0.7874 0.4064)
			(end 0.7874 0.4064)
			(stroke
				(width 0.1524)
				(type default)
			)
			(layer "B.SilkS")
		)
		(fp_line
			(start 0.7874 0.4064)
			(end 0.7874 -0.4064)
			(stroke
				(width 0.1524)
				(type default)
			)
			(layer "B.SilkS")
		)
		(fp_line
			(start -0.7874 -0.4064)
			(end -0.7874 0.4064)
			(stroke
				(width 0.1524)
				(type default)
			)
			(layer "B.SilkS")
		)
		(fp_line
			(start 0.7874 -0.4064)
			(end -0.7874 -0.4064)
			(stroke
				(width 0.1524)
				(type default)
			)
			(layer "B.SilkS")
		)
		(fp_line
			(start -0.67945 0.3048)
			(end -0.120396 0.3048)
			(stroke
				(width 0.1)
				(type default)
			)
			(layer "B.Fab")
		)
		(fp_line
			(start -0.120396 0.3048)
			(end -0.120396 0.2794)
			(stroke
				(width 0.1)
				(type default)
			)
			(layer "B.Fab")
		)
		(fp_line
			(start 0.12065 0.3048)
			(end 0.67945 0.3048)
			(stroke
				(width 0.1)
				(type default)
			)
			(layer "B.Fab")
		)
		(fp_line
			(start 0.67945 0.3048)
			(end 0.67945 -0.305054)
			(stroke
				(width 0.1)
				(type default)
			)
			(layer "B.Fab")
		)
		(fp_line
			(start -0.120396 0.2794)
			(end 0.12065 0.2794)
			(stroke
				(width 0.1)
				(type default)
			)
			(layer "B.Fab")
		)
		(fp_line
			(start 0.12065 0.2794)
			(end 0.12065 0.3048)
			(stroke
				(width 0.1)
				(type default)
			)
			(layer "B.Fab")
		)
		(fp_line
			(start -0.12065 -0.2794)
			(end -0.12065 -0.3048)
			(stroke
				(width 0.1)
				(type default)
			)
			(layer "B.Fab")
		)
		(fp_line
			(start 0.12065 -0.2794)
			(end -0.12065 -0.2794)
			(stroke
				(width 0.1)
				(type default)
			)
			(layer "B.Fab")
		)
		(fp_line
			(start -0.67945 -0.3048)
			(end -0.67945 0.3048)
			(stroke
				(width 0.1)
				(type default)
			)
			(layer "B.Fab")
		)
		(fp_line
			(start -0.12065 -0.3048)
			(end -0.67945 -0.3048)
			(stroke
				(width 0.1)
				(type default)
			)
			(layer "B.Fab")
		)
		(fp_line
			(start 0.12065 -0.305054)
			(end 0.12065 -0.2794)
			(stroke
				(width 0.1)
				(type default)
			)
			(layer "B.Fab")
		)
		(fp_line
			(start 0.67945 -0.305054)
			(end 0.12065 -0.305054)
			(stroke
				(width 0.1)
				(type default)
			)
			(layer "B.Fab")
		)
		(pad "1" smd circle
			(at 0.40005 0 90)
			(size 0 0)
			(layers "B.Cu" "B.Mask" "B.Paste")
			(net "P3V3_AUX")
		)
		(pad "2" smd circle
			(at -0.40005 0 90)
			(size 0 0)
			(layers "B.Cu" "B.Mask" "B.Paste")
			(net "FM_AC_PWR_BTN_PLD_ISO_N")
		)
	)
	(footprint ""
		(layer "B.Cu")
		(at 231.648 -342.011 90)
		(property "Reference" "R6762"
			(at 0 0 90)
			(layer "B.SilkS")
			(hide yes)
			(effects
				(font
					(size 1.27 1.27)
				)
				(justify mirror)
			)
		)
		(property "Value" ""
			(at 0 0 90)
			(layer "B.Fab")
			(effects
				(font
					(size 1.27 1.27)
				)
				(justify mirror)
			)
		)
		(duplicate_pad_numbers_are_jumpers no)
		(fp_line
			(start 0.32512 -0.175006)
			(end -0.32512 -0.175006)
			(stroke
				(width 0.1)
				(type default)
			)
			(layer "B.Fab")
		)
		(fp_line
			(start -0.32512 -0.175006)
			(end -0.32512 0.175006)
			(stroke
				(width 0.1)
				(type default)
			)
			(layer "B.Fab")
		)
		(fp_line
			(start 0.32512 0.175006)
			(end 0.32512 -0.175006)
			(stroke
				(width 0.1)
				(type default)
			)
			(layer "B.Fab")
		)
		(fp_line
			(start -0.32512 0.175006)
			(end 0.32512 0.175006)
			(stroke
				(width 0.1)
				(type default)
			)
			(layer "B.Fab")
		)
		(pad "1" smd rect
			(at 0.2667 0 270)
			(size 0.3048 0.381)
			(layers "B.Cu" "B.Mask" "B.Paste")
			(net "P1V8_CPU0_RT_1D")
		)
		(pad "2" smd rect
			(at -0.2667 0 90)
			(size 0.3048 0.381)
			(layers "B.Cu" "B.Mask" "B.Paste")
			(net "SMB_RT_CPU0_P0_R_SDA")
		)
	)
	(footprint ""
		(layer "B.Cu")
		(at 110.965996 -26.952448 90)
		(property "Reference" "C6098"
			(at 0 0 90)
			(layer "B.SilkS")
			(hide yes)
			(effects
				(font
					(size 1.27 1.27)
				)
				(justify mirror)
			)
		)
		(property "Value" ""
			(at 0 0 90)
			(layer "B.Fab")
			(effects
				(font
					(size 1.27 1.27)
				)
				(justify mirror)
			)
		)
		(duplicate_pad_numbers_are_jumpers no)
		(fp_line
			(start 0.7874 -0.4064)
			(end -0.7874 -0.4064)
			(stroke
				(width 0.1524)
				(type default)
			)
			(layer "B.SilkS")
		)
		(fp_line
			(start -0.7874 -0.4064)
			(end -0.7874 0.4064)
			(stroke
				(width 0.1524)
				(type default)
			)
			(layer "B.SilkS")
		)
		(fp_line
			(start 0.7874 0.4064)
			(end 0.7874 -0.4064)
			(stroke
				(width 0.1524)
				(type default)
			)
			(layer "B.SilkS")
		)
		(fp_line
			(start -0.7874 0.4064)
			(end 0.7874 0.4064)
			(stroke
				(width 0.1524)
				(type default)
			)
			(layer "B.SilkS")
		)
		(fp_line
			(start 0.67945 -0.305054)
			(end 0.12065 -0.305054)
			(stroke
				(width 0.1)
				(type default)
			)
			(layer "B.Fab")
		)
		(fp_line
			(start 0.12065 -0.305054)
			(end 0.12065 -0.2794)
			(stroke
				(width 0.1)
				(type default)
			)
			(layer "B.Fab")
		)
		(fp_line
			(start -0.12065 -0.3048)
			(end -0.67945 -0.3048)
			(stroke
				(width 0.1)
				(type default)
			)
			(layer "B.Fab")
		)
		(fp_line
			(start -0.67945 -0.3048)
			(end -0.67945 0.3048)
			(stroke
				(width 0.1)
				(type default)
			)
			(layer "B.Fab")
		)
		(fp_line
			(start 0.12065 -0.2794)
			(end -0.12065 -0.2794)
			(stroke
				(width 0.1)
				(type default)
			)
			(layer "B.Fab")
		)
		(fp_line
			(start -0.12065 -0.2794)
			(end -0.12065 -0.3048)
			(stroke
				(width 0.1)
				(type default)
			)
			(layer "B.Fab")
		)
		(fp_line
			(start 0.12065 0.2794)
			(end 0.12065 0.3048)
			(stroke
				(width 0.1)
				(type default)
			)
			(layer "B.Fab")
		)
		(fp_line
			(start -0.120396 0.2794)
			(end 0.12065 0.2794)
			(stroke
				(width 0.1)
				(type default)
			)
			(layer "B.Fab")
		)
		(fp_line
			(start 0.67945 0.3048)
			(end 0.67945 -0.305054)
			(stroke
				(width 0.1)
				(type default)
			)
			(layer "B.Fab")
		)
		(fp_line
			(start 0.12065 0.3048)
			(end 0.67945 0.3048)
			(stroke
				(width 0.1)
				(type default)
			)
			(layer "B.Fab")
		)
		(fp_line
			(start -0.120396 0.3048)
			(end -0.120396 0.2794)
			(stroke
				(width 0.1)
				(type default)
			)
			(layer "B.Fab")
		)
		(fp_line
			(start -0.67945 0.3048)
			(end -0.120396 0.3048)
			(stroke
				(width 0.1)
				(type default)
			)
			(layer "B.Fab")
		)
		(pad "1" smd circle
			(at 0.40005 0 270)
			(size 0 0)
			(layers "B.Cu" "B.Mask" "B.Paste")
			(net "P3V3_AUX_CPU0_USB2_AVDD33")
		)
		(pad "2" smd circle
			(at -0.40005 0 270)
			(size 0 0)
			(layers "B.Cu" "B.Mask" "B.Paste")
			(net "GND")
		)
	)
	(footprint ""
		(layer "B.Cu")
		(at 102.275386 -268.418564)
		(property "Reference" "C2366"
			(at 0 0 0)
			(layer "B.SilkS")
			(hide yes)
			(effects
				(font
					(size 1.27 1.27)
				)
				(justify mirror)
			)
		)
		(property "Value" ""
			(at 0 0 0)
			(layer "B.Fab")
			(effects
				(font
					(size 1.27 1.27)
				)
				(justify mirror)
			)
		)
		(duplicate_pad_numbers_are_jumpers no)
		(fp_line
			(start -0.7874 -0.4064)
			(end -0.7874 0.4064)
			(stroke
				(width 0.1524)
				(type default)
			)
			(layer "B.SilkS")
		)
		(fp_line
			(start -0.7874 0.4064)
			(end 0.7874 0.4064)
			(stroke
				(width 0.1524)
				(type default)
			)
			(layer "B.SilkS")
		)
		(fp_line
			(start 0.7874 -0.4064)
			(end -0.7874 -0.4064)
			(stroke
				(width 0.1524)
				(type default)
			)
			(layer "B.SilkS")
		)
		(fp_line
			(start 0.7874 0.4064)
			(end 0.7874 -0.4064)
			(stroke
				(width 0.1524)
				(type default)
			)
			(layer "B.SilkS")
		)
		(fp_line
			(start -0.67945 -0.3048)
			(end -0.67945 0.3048)
			(stroke
				(width 0.1)
				(type default)
			)
			(layer "B.Fab")
		)
		(fp_line
			(start -0.67945 0.3048)
			(end -0.120396 0.3048)
			(stroke
				(width 0.1)
				(type default)
			)
			(layer "B.Fab")
		)
		(fp_line
			(start -0.12065 -0.3048)
			(end -0.67945 -0.3048)
			(stroke
				(width 0.1)
				(type default)
			)
			(layer "B.Fab")
		)
		(fp_line
			(start -0.12065 -0.2794)
			(end -0.12065 -0.3048)
			(stroke
				(width 0.1)
				(type default)
			)
			(layer "B.Fab")
		)
		(fp_line
			(start -0.120396 0.2794)
			(end 0.12065 0.2794)
			(stroke
				(width 0.1)
				(type default)
			)
			(layer "B.Fab")
		)
		(fp_line
			(start -0.120396 0.3048)
			(end -0.120396 0.2794)
			(stroke
				(width 0.1)
				(type default)
			)
			(layer "B.Fab")
		)
		(fp_line
			(start 0.12065 -0.305054)
			(end 0.12065 -0.2794)
			(stroke
				(width 0.1)
				(type default)
			)
			(layer "B.Fab")
		)
		(fp_line
			(start 0.12065 -0.2794)
			(end -0.12065 -0.2794)
			(stroke
				(width 0.1)
				(type default)
			)
			(layer "B.Fab")
		)
		(fp_line
			(start 0.12065 0.2794)
			(end 0.12065 0.3048)
			(stroke
				(width 0.1)
				(type default)
			)
			(layer "B.Fab")
		)
		(fp_line
			(start 0.12065 0.3048)
			(end 0.67945 0.3048)
			(stroke
				(width 0.1)
				(type default)
			)
			(layer "B.Fab")
		)
		(fp_line
			(start 0.67945 -0.305054)
			(end 0.12065 -0.305054)
			(stroke
				(width 0.1)
				(type default)
			)
			(layer "B.Fab")
		)
		(fp_line
			(start 0.67945 0.3048)
			(end 0.67945 -0.305054)
			(stroke
				(width 0.1)
				(type default)
			)
			(layer "B.Fab")
		)
		(pad "1" smd circle
			(at 0.40005 0 180)
			(size 0 0)
			(layers "B.Cu" "B.Mask" "B.Paste")
			(net "PVDDCR_CPU1_P1")
		)
		(pad "2" smd circle
			(at -0.40005 0 180)
			(size 0 0)
			(layers "B.Cu" "B.Mask" "B.Paste")
			(net "GND")
		)
	)
	(footprint ""
		(layer "B.Cu")
		(at 197.70725 -244.085364)
		(property "Reference" "R510"
			(at 0 0 0)
			(layer "B.SilkS")
			(hide yes)
			(effects
				(font
					(size 1.27 1.27)
				)
				(justify mirror)
			)
		)
		(property "Value" ""
			(at 0 0 0)
			(layer "B.Fab")
			(effects
				(font
					(size 1.27 1.27)
				)
				(justify mirror)
			)
		)
		(duplicate_pad_numbers_are_jumpers no)
		(fp_line
			(start -0.7874 -0.4064)
			(end -0.7874 0.4064)
			(stroke
				(width 0.1524)
				(type default)
			)
			(layer "B.SilkS")
		)
		(fp_line
			(start -0.7874 0.4064)
			(end 0.7874 0.4064)
			(stroke
				(width 0.1524)
				(type default)
			)
			(layer "B.SilkS")
		)
		(fp_line
			(start 0.7874 -0.4064)
			(end -0.7874 -0.4064)
			(stroke
				(width 0.1524)
				(type default)
			)
			(layer "B.SilkS")
		)
		(fp_line
			(start 0.7874 0.4064)
			(end 0.7874 -0.4064)
			(stroke
				(width 0.1524)
				(type default)
			)
			(layer "B.SilkS")
		)
		(fp_line
			(start -0.67945 -0.3048)
			(end -0.67945 0.3048)
			(stroke
				(width 0.1)
				(type default)
			)
			(layer "B.Fab")
		)
		(fp_line
			(start -0.67945 0.3048)
			(end -0.120396 0.3048)
			(stroke
				(width 0.1)
				(type default)
			)
			(layer "B.Fab")
		)
		(fp_line
			(start -0.12065 -0.3048)
			(end -0.67945 -0.3048)
			(stroke
				(width 0.1)
				(type default)
			)
			(layer "B.Fab")
		)
		(fp_line
			(start -0.12065 -0.2794)
			(end -0.12065 -0.3048)
			(stroke
				(width 0.1)
				(type default)
			)
			(layer "B.Fab")
		)
		(fp_line
			(start -0.120396 0.2794)
			(end 0.12065 0.2794)
			(stroke
				(width 0.1)
				(type default)
			)
			(layer "B.Fab")
		)
		(fp_line
			(start -0.120396 0.3048)
			(end -0.120396 0.2794)
			(stroke
				(width 0.1)
				(type default)
			)
			(layer "B.Fab")
		)
		(fp_line
			(start 0.12065 -0.305054)
			(end 0.12065 -0.2794)
			(stroke
				(width 0.1)
				(type default)
			)
			(layer "B.Fab")
		)
		(fp_line
			(start 0.12065 -0.2794)
			(end -0.12065 -0.2794)
			(stroke
				(width 0.1)
				(type default)
			)
			(layer "B.Fab")
		)
		(fp_line
			(start 0.12065 0.2794)
			(end 0.12065 0.3048)
			(stroke
				(width 0.1)
				(type default)
			)
			(layer "B.Fab")
		)
		(fp_line
			(start 0.12065 0.3048)
			(end 0.67945 0.3048)
			(stroke
				(width 0.1)
				(type default)
			)
			(layer "B.Fab")
		)
		(fp_line
			(start 0.67945 -0.305054)
			(end 0.12065 -0.305054)
			(stroke
				(width 0.1)
				(type default)
			)
			(layer "B.Fab")
		)
		(fp_line
			(start 0.67945 0.3048)
			(end 0.67945 -0.305054)
			(stroke
				(width 0.1)
				(type default)
			)
			(layer "B.Fab")
		)
		(pad "1" smd circle
			(at 0.40005 0 180)
			(size 0 0)
			(layers "B.Cu" "B.Mask" "B.Paste")
			(net "M_K_CPU1_ALERT_N")
		)
		(pad "2" smd circle
			(at -0.40005 0 180)
			(size 0 0)
			(layers "B.Cu" "B.Mask" "B.Paste")
			(net "M_K_CPU1_ALERT_R_N")
		)
	)
	(footprint ""
		(layer "B.Cu")
		(at 59.563762 -347.780356 -90)
		(property "Reference" "PR264"
			(at 0 0 90)
			(layer "B.SilkS")
			(hide yes)
			(effects
				(font
					(size 1.27 1.27)
				)
				(justify mirror)
			)
		)
		(property "Value" ""
			(at 0 0 90)
			(layer "B.Fab")
			(effects
				(font
					(size 1.27 1.27)
				)
				(justify mirror)
			)
		)
		(duplicate_pad_numbers_are_jumpers no)
		(fp_line
			(start -0.7874 0.4064)
			(end 0.7874 0.4064)
			(stroke
				(width 0.1524)
				(type default)
			)
			(layer "B.SilkS")
		)
		(fp_line
			(start 0.7874 0.4064)
			(end 0.7874 -0.4064)
			(stroke
				(width 0.1524)
				(type default)
			)
			(layer "B.SilkS")
		)
		(fp_line
			(start -0.7874 -0.4064)
			(end -0.7874 0.4064)
			(stroke
				(width 0.1524)
				(type default)
			)
			(layer "B.SilkS")
		)
		(fp_line
			(start 0.7874 -0.4064)
			(end -0.7874 -0.4064)
			(stroke
				(width 0.1524)
				(type default)
			)
			(layer "B.SilkS")
		)
		(fp_line
			(start -0.67945 0.3048)
			(end -0.120396 0.3048)
			(stroke
				(width 0.1)
				(type default)
			)
			(layer "B.Fab")
		)
		(fp_line
			(start -0.120396 0.3048)
			(end -0.120396 0.2794)
			(stroke
				(width 0.1)
				(type default)
			)
			(layer "B.Fab")
		)
		(fp_line
			(start 0.12065 0.3048)
			(end 0.67945 0.3048)
			(stroke
				(width 0.1)
				(type default)
			)
			(layer "B.Fab")
		)
		(fp_line
			(start 0.67945 0.3048)
			(end 0.67945 -0.305054)
			(stroke
				(width 0.1)
				(type default)
			)
			(layer "B.Fab")
		)
		(fp_line
			(start -0.120396 0.2794)
			(end 0.12065 0.2794)
			(stroke
				(width 0.1)
				(type default)
			)
			(layer "B.Fab")
		)
		(fp_line
			(start 0.12065 0.2794)
			(end 0.12065 0.3048)
			(stroke
				(width 0.1)
				(type default)
			)
			(layer "B.Fab")
		)
		(fp_line
			(start -0.12065 -0.2794)
			(end -0.12065 -0.3048)
			(stroke
				(width 0.1)
				(type default)
			)
			(layer "B.Fab")
		)
		(fp_line
			(start 0.12065 -0.2794)
			(end -0.12065 -0.2794)
			(stroke
				(width 0.1)
				(type default)
			)
			(layer "B.Fab")
		)
		(fp_line
			(start -0.67945 -0.3048)
			(end -0.67945 0.3048)
			(stroke
				(width 0.1)
				(type default)
			)
			(layer "B.Fab")
		)
		(fp_line
			(start -0.12065 -0.3048)
			(end -0.67945 -0.3048)
			(stroke
				(width 0.1)
				(type default)
			)
			(layer "B.Fab")
		)
		(fp_line
			(start 0.12065 -0.305054)
			(end 0.12065 -0.2794)
			(stroke
				(width 0.1)
				(type default)
			)
			(layer "B.Fab")
		)
		(fp_line
			(start 0.67945 -0.305054)
			(end 0.12065 -0.305054)
			(stroke
				(width 0.1)
				(type default)
			)
			(layer "B.Fab")
		)
		(pad "1" smd circle
			(at 0.40005 0 90)
			(size 0 0)
			(layers "B.Cu" "B.Mask" "B.Paste")
			(net "PVDDCR_CPU1_P1_PVCC")
		)
		(pad "2" smd circle
			(at -0.40005 0 90)
			(size 0 0)
			(layers "B.Cu" "B.Mask" "B.Paste")
			(net "PVDDCR_CPU1_P1_VCC4")
		)
	)
	(footprint ""
		(layer "B.Cu")
		(at 363.034834 -398.055084 90)
		(property "Reference" "C1028"
			(at 0 0 90)
			(layer "B.SilkS")
			(hide yes)
			(effects
				(font
					(size 1.27 1.27)
				)
				(justify mirror)
			)
		)
		(property "Value" ""
			(at 0 0 90)
			(layer "B.Fab")
			(effects
				(font
					(size 1.27 1.27)
				)
				(justify mirror)
			)
		)
		(duplicate_pad_numbers_are_jumpers no)
		(fp_line
			(start 1.524 -0.762)
			(end -1.524 -0.762)
			(stroke
				(width 0.1524)
				(type default)
			)
			(layer "B.SilkS")
		)
		(fp_line
			(start -1.524 -0.762)
			(end -1.524 0.762)
			(stroke
				(width 0.1524)
				(type default)
			)
			(layer "B.SilkS")
		)
		(fp_line
			(start 1.524 0.762)
			(end 1.524 -0.762)
			(stroke
				(width 0.1524)
				(type default)
			)
			(layer "B.SilkS")
		)
		(fp_line
			(start -1.524 0.762)
			(end 1.524 0.762)
			(stroke
				(width 0.1524)
				(type default)
			)
			(layer "B.SilkS")
		)
		(fp_line
			(start 1.1049 -0.724916)
			(end 1.1049 0.724916)
			(stroke
				(width 0.1)
				(type default)
			)
			(layer "B.Fab")
		)
		(fp_line
			(start -1.1049 -0.724916)
			(end 1.1049 -0.724916)
			(stroke
				(width 0.1)
				(type default)
			)
			(layer "B.Fab")
		)
		(fp_line
			(start 1.1049 0.724916)
			(end -1.1049 0.724916)
			(stroke
				(width 0.1)
				(type default)
			)
			(layer "B.Fab")
		)
		(fp_line
			(start -1.1049 0.724916)
			(end -1.1049 -0.724916)
			(stroke
				(width 0.1)
				(type default)
			)
			(layer "B.Fab")
		)
		(pad "1" smd rect
			(at 0.889 0 90)
			(size 1.016 1.27)
			(layers "B.Cu" "B.Mask" "B.Paste")
			(net "P0V9_CPU0_RT_2D")
		)
		(pad "2" smd rect
			(at -0.889 0 90)
			(size 1.016 1.27)
			(layers "B.Cu" "B.Mask" "B.Paste")
			(net "GND")
		)
	)
	(footprint ""
		(layer "B.Cu")
		(at 331.793342 -393.96416 180)
		(property "Reference" "R1031"
			(at 0 0 0)
			(layer "B.SilkS")
			(hide yes)
			(effects
				(font
					(size 1.27 1.27)
				)
				(justify mirror)
			)
		)
		(property "Value" ""
			(at 0 0 0)
			(layer "B.Fab")
			(effects
				(font
					(size 1.27 1.27)
				)
				(justify mirror)
			)
		)
		(duplicate_pad_numbers_are_jumpers no)
		(fp_line
			(start 0.32512 0.175006)
			(end 0.32512 -0.175006)
			(stroke
				(width 0.1)
				(type default)
			)
			(layer "B.Fab")
		)
		(fp_line
			(start 0.32512 -0.175006)
			(end -0.32512 -0.175006)
			(stroke
				(width 0.1)
				(type default)
			)
			(layer "B.Fab")
		)
		(fp_line
			(start -0.32512 0.175006)
			(end 0.32512 0.175006)
			(stroke
				(width 0.1)
				(type default)
			)
			(layer "B.Fab")
		)
		(fp_line
			(start -0.32512 -0.175006)
			(end -0.32512 0.175006)
			(stroke
				(width 0.1)
				(type default)
			)
			(layer "B.Fab")
		)
		(pad "1" smd rect
			(at 0.2667 0)
			(size 0.3048 0.381)
			(layers "B.Cu" "B.Mask" "B.Paste")
			(net "TEST0_RT_CPU0_P1")
		)
		(pad "2" smd rect
			(at -0.2667 0 180)
			(size 0.3048 0.381)
			(layers "B.Cu" "B.Mask" "B.Paste")
			(net "GND")
		)
	)
	(footprint ""
		(layer "B.Cu")
		(at 206.22133 -194.98691)
		(property "Reference" "R1591"
			(at 0 0 0)
			(layer "B.SilkS")
			(hide yes)
			(effects
				(font
					(size 1.27 1.27)
				)
				(justify mirror)
			)
		)
		(property "Value" ""
			(at 0 0 0)
			(layer "B.Fab")
			(effects
				(font
					(size 1.27 1.27)
				)
				(justify mirror)
			)
		)
		(duplicate_pad_numbers_are_jumpers no)
		(fp_line
			(start -0.7874 -0.4064)
			(end -0.7874 0.4064)
			(stroke
				(width 0.1524)
				(type default)
			)
			(layer "B.SilkS")
		)
		(fp_line
			(start -0.7874 0.4064)
			(end 0.7874 0.4064)
			(stroke
				(width 0.1524)
				(type default)
			)
			(layer "B.SilkS")
		)
		(fp_line
			(start 0.7874 -0.4064)
			(end -0.7874 -0.4064)
			(stroke
				(width 0.1524)
				(type default)
			)
			(layer "B.SilkS")
		)
		(fp_line
			(start 0.7874 0.4064)
			(end 0.7874 -0.4064)
			(stroke
				(width 0.1524)
				(type default)
			)
			(layer "B.SilkS")
		)
		(fp_line
			(start -0.67945 -0.3048)
			(end -0.67945 0.3048)
			(stroke
				(width 0.1)
				(type default)
			)
			(layer "B.Fab")
		)
		(fp_line
			(start -0.67945 0.3048)
			(end -0.120396 0.3048)
			(stroke
				(width 0.1)
				(type default)
			)
			(layer "B.Fab")
		)
		(fp_line
			(start -0.12065 -0.3048)
			(end -0.67945 -0.3048)
			(stroke
				(width 0.1)
				(type default)
			)
			(layer "B.Fab")
		)
		(fp_line
			(start -0.12065 -0.2794)
			(end -0.12065 -0.3048)
			(stroke
				(width 0.1)
				(type default)
			)
			(layer "B.Fab")
		)
		(fp_line
			(start -0.120396 0.2794)
			(end 0.12065 0.2794)
			(stroke
				(width 0.1)
				(type default)
			)
			(layer "B.Fab")
		)
		(fp_line
			(start -0.120396 0.3048)
			(end -0.120396 0.2794)
			(stroke
				(width 0.1)
				(type default)
			)
			(layer "B.Fab")
		)
		(fp_line
			(start 0.12065 -0.305054)
			(end 0.12065 -0.2794)
			(stroke
				(width 0.1)
				(type default)
			)
			(layer "B.Fab")
		)
		(fp_line
			(start 0.12065 -0.2794)
			(end -0.12065 -0.2794)
			(stroke
				(width 0.1)
				(type default)
			)
			(layer "B.Fab")
		)
		(fp_line
			(start 0.12065 0.2794)
			(end 0.12065 0.3048)
			(stroke
				(width 0.1)
				(type default)
			)
			(layer "B.Fab")
		)
		(fp_line
			(start 0.12065 0.3048)
			(end 0.67945 0.3048)
			(stroke
				(width 0.1)
				(type default)
			)
			(layer "B.Fab")
		)
		(fp_line
			(start 0.67945 -0.305054)
			(end 0.12065 -0.305054)
			(stroke
				(width 0.1)
				(type default)
			)
			(layer "B.Fab")
		)
		(fp_line
			(start 0.67945 0.3048)
			(end 0.67945 -0.305054)
			(stroke
				(width 0.1)
				(type default)
			)
			(layer "B.Fab")
		)
		(pad "1" smd circle
			(at 0.40005 0 180)
			(size 0 0)
			(layers "B.Cu" "B.Mask" "B.Paste")
			(net "I3C_SPD_DDRGL_CPU1_SCL")
		)
		(pad "2" smd circle
			(at -0.40005 0 180)
			(size 0 0)
			(layers "B.Cu" "B.Mask" "B.Paste")
			(net "I3C_SPD_DDRL_CPU1_SCL")
		)
	)
	(footprint ""
		(layer "B.Cu")
		(at 113.959386 -266.005564)
		(property "Reference" "C2275"
			(at 0 0 0)
			(layer "B.SilkS")
			(hide yes)
			(effects
				(font
					(size 1.27 1.27)
				)
				(justify mirror)
			)
		)
		(property "Value" ""
			(at 0 0 0)
			(layer "B.Fab")
			(effects
				(font
					(size 1.27 1.27)
				)
				(justify mirror)
			)
		)
		(duplicate_pad_numbers_are_jumpers no)
		(fp_line
			(start -0.7874 -0.4064)
			(end -0.7874 0.4064)
			(stroke
				(width 0.1524)
				(type default)
			)
			(layer "B.SilkS")
		)
		(fp_line
			(start -0.7874 0.4064)
			(end 0.7874 0.4064)
			(stroke
				(width 0.1524)
				(type default)
			)
			(layer "B.SilkS")
		)
		(fp_line
			(start 0.7874 -0.4064)
			(end -0.7874 -0.4064)
			(stroke
				(width 0.1524)
				(type default)
			)
			(layer "B.SilkS")
		)
		(fp_line
			(start 0.7874 0.4064)
			(end 0.7874 -0.4064)
			(stroke
				(width 0.1524)
				(type default)
			)
			(layer "B.SilkS")
		)
		(fp_line
			(start -0.67945 -0.3048)
			(end -0.67945 0.3048)
			(stroke
				(width 0.1)
				(type default)
			)
			(layer "B.Fab")
		)
		(fp_line
			(start -0.67945 0.3048)
			(end -0.120396 0.3048)
			(stroke
				(width 0.1)
				(type default)
			)
			(layer "B.Fab")
		)
		(fp_line
			(start -0.12065 -0.3048)
			(end -0.67945 -0.3048)
			(stroke
				(width 0.1)
				(type default)
			)
			(layer "B.Fab")
		)
		(fp_line
			(start -0.12065 -0.2794)
			(end -0.12065 -0.3048)
			(stroke
				(width 0.1)
				(type default)
			)
			(layer "B.Fab")
		)
		(fp_line
			(start -0.120396 0.2794)
			(end 0.12065 0.2794)
			(stroke
				(width 0.1)
				(type default)
			)
			(layer "B.Fab")
		)
		(fp_line
			(start -0.120396 0.3048)
			(end -0.120396 0.2794)
			(stroke
				(width 0.1)
				(type default)
			)
			(layer "B.Fab")
		)
		(fp_line
			(start 0.12065 -0.305054)
			(end 0.12065 -0.2794)
			(stroke
				(width 0.1)
				(type default)
			)
			(layer "B.Fab")
		)
		(fp_line
			(start 0.12065 -0.2794)
			(end -0.12065 -0.2794)
			(stroke
				(width 0.1)
				(type default)
			)
			(layer "B.Fab")
		)
		(fp_line
			(start 0.12065 0.2794)
			(end 0.12065 0.3048)
			(stroke
				(width 0.1)
				(type default)
			)
			(layer "B.Fab")
		)
		(fp_line
			(start 0.12065 0.3048)
			(end 0.67945 0.3048)
			(stroke
				(width 0.1)
				(type default)
			)
			(layer "B.Fab")
		)
		(fp_line
			(start 0.67945 -0.305054)
			(end 0.12065 -0.305054)
			(stroke
				(width 0.1)
				(type default)
			)
			(layer "B.Fab")
		)
		(fp_line
			(start 0.67945 0.3048)
			(end 0.67945 -0.305054)
			(stroke
				(width 0.1)
				(type default)
			)
			(layer "B.Fab")
		)
		(pad "1" smd circle
			(at 0.40005 0 180)
			(size 0 0)
			(layers "B.Cu" "B.Mask" "B.Paste")
			(net "PVDD11_S3_P1")
		)
		(pad "2" smd circle
			(at -0.40005 0 180)
			(size 0 0)
			(layers "B.Cu" "B.Mask" "B.Paste")
			(net "GND")
		)
	)
	(footprint ""
		(layer "B.Cu")
		(at 127.319024 -31.259272)
		(property "Reference" "C6066"
			(at 0 0 0)
			(layer "B.SilkS")
			(hide yes)
			(effects
				(font
					(size 1.27 1.27)
				)
				(justify mirror)
			)
		)
		(property "Value" ""
			(at 0 0 0)
			(layer "B.Fab")
			(effects
				(font
					(size 1.27 1.27)
				)
				(justify mirror)
			)
		)
		(duplicate_pad_numbers_are_jumpers no)
		(fp_line
			(start -1.2954 -0.5842)
			(end -1.2954 0.5842)
			(stroke
				(width 0.1524)
				(type default)
			)
			(layer "B.SilkS")
		)
		(fp_line
			(start -1.2954 0.5842)
			(end 1.2954 0.5842)
			(stroke
				(width 0.1524)
				(type default)
			)
			(layer "B.SilkS")
		)
		(fp_line
			(start 1.2954 -0.5842)
			(end -1.2954 -0.5842)
			(stroke
				(width 0.1524)
				(type default)
			)
			(layer "B.SilkS")
		)
		(fp_line
			(start 1.2954 0.5842)
			(end 1.2954 -0.5842)
			(stroke
				(width 0.1524)
				(type default)
			)
			(layer "B.SilkS")
		)
		(fp_line
			(start -1.1938 -0.4064)
			(end -1.1938 0.4064)
			(stroke
				(width 0.1)
				(type default)
			)
			(layer "B.Fab")
		)
		(fp_line
			(start -1.1938 0.4064)
			(end -0.8636 0.4064)
			(stroke
				(width 0.1)
				(type default)
			)
			(layer "B.Fab")
		)
		(fp_line
			(start -0.8636 -0.4572)
			(end -0.8636 -0.4064)
			(stroke
				(width 0.1)
				(type default)
			)
			(layer "B.Fab")
		)
		(fp_line
			(start -0.8636 -0.4064)
			(end -1.1938 -0.4064)
			(stroke
				(width 0.1)
				(type default)
			)
			(layer "B.Fab")
		)
		(fp_line
			(start -0.8636 0.4064)
			(end -0.8636 0.4572)
			(stroke
				(width 0.1)
				(type default)
			)
			(layer "B.Fab")
		)
		(fp_line
			(start -0.8636 0.4572)
			(end 0.8636 0.4572)
			(stroke
				(width 0.1)
				(type default)
			)
			(layer "B.Fab")
		)
		(fp_line
			(start 0.8636 -0.4572)
			(end -0.8636 -0.4572)
			(stroke
				(width 0.1)
				(type default)
			)
			(layer "B.Fab")
		)
		(fp_line
			(start 0.8636 -0.4064)
			(end 0.8636 -0.4572)
			(stroke
				(width 0.1)
				(type default)
			)
			(layer "B.Fab")
		)
		(fp_line
			(start 0.8636 0.4064)
			(end 1.1938 0.4064)
			(stroke
				(width 0.1)
				(type default)
			)
			(layer "B.Fab")
		)
		(fp_line
			(start 0.8636 0.4572)
			(end 0.8636 0.4064)
			(stroke
				(width 0.1)
				(type default)
			)
			(layer "B.Fab")
		)
		(fp_line
			(start 1.1938 -0.4064)
			(end 0.8636 -0.4064)
			(stroke
				(width 0.1)
				(type default)
			)
			(layer "B.Fab")
		)
		(fp_line
			(start 1.1938 0.4064)
			(end 1.1938 -0.4064)
			(stroke
				(width 0.1)
				(type default)
			)
			(layer "B.Fab")
		)
		(pad "1" smd rect
			(at 0.7366 0 270)
			(size 0.7112 0.8128)
			(layers "B.Cu" "B.Mask" "B.Paste")
			(net "P1V2_AUX")
		)
		(pad "2" smd rect
			(at -0.7366 0 270)
			(size 0.7112 0.8128)
			(layers "B.Cu" "B.Mask" "B.Paste")
			(net "GND")
		)
	)
	(footprint ""
		(layer "B.Cu")
		(at 128.811528 -40.106092 180)
		(property "Reference" "C6071"
			(at 0 0 0)
			(layer "B.SilkS")
			(hide yes)
			(effects
				(font
					(size 1.27 1.27)
				)
				(justify mirror)
			)
		)
		(property "Value" ""
			(at 0 0 0)
			(layer "B.Fab")
			(effects
				(font
					(size 1.27 1.27)
				)
				(justify mirror)
			)
		)
		(duplicate_pad_numbers_are_jumpers no)
		(fp_line
			(start 0.7874 0.4064)
			(end 0.7874 -0.4064)
			(stroke
				(width 0.1524)
				(type default)
			)
			(layer "B.SilkS")
		)
		(fp_line
			(start 0.7874 -0.4064)
			(end -0.7874 -0.4064)
			(stroke
				(width 0.1524)
				(type default)
			)
			(layer "B.SilkS")
		)
		(fp_line
			(start -0.7874 0.4064)
			(end 0.7874 0.4064)
			(stroke
				(width 0.1524)
				(type default)
			)
			(layer "B.SilkS")
		)
		(fp_line
			(start -0.7874 -0.4064)
			(end -0.7874 0.4064)
			(stroke
				(width 0.1524)
				(type default)
			)
			(layer "B.SilkS")
		)
		(fp_line
			(start 0.67945 0.3048)
			(end 0.67945 -0.305054)
			(stroke
				(width 0.1)
				(type default)
			)
			(layer "B.Fab")
		)
		(fp_line
			(start 0.67945 -0.305054)
			(end 0.12065 -0.305054)
			(stroke
				(width 0.1)
				(type default)
			)
			(layer "B.Fab")
		)
		(fp_line
			(start 0.12065 0.3048)
			(end 0.67945 0.3048)
			(stroke
				(width 0.1)
				(type default)
			)
			(layer "B.Fab")
		)
		(fp_line
			(start 0.12065 0.2794)
			(end 0.12065 0.3048)
			(stroke
				(width 0.1)
				(type default)
			)
			(layer "B.Fab")
		)
		(fp_line
			(start 0.12065 -0.2794)
			(end -0.12065 -0.2794)
			(stroke
				(width 0.1)
				(type default)
			)
			(layer "B.Fab")
		)
		(fp_line
			(start 0.12065 -0.305054)
			(end 0.12065 -0.2794)
			(stroke
				(width 0.1)
				(type default)
			)
			(layer "B.Fab")
		)
		(fp_line
			(start -0.120396 0.3048)
			(end -0.120396 0.2794)
			(stroke
				(width 0.1)
				(type default)
			)
			(layer "B.Fab")
		)
		(fp_line
			(start -0.120396 0.2794)
			(end 0.12065 0.2794)
			(stroke
				(width 0.1)
				(type default)
			)
			(layer "B.Fab")
		)
		(fp_line
			(start -0.12065 -0.2794)
			(end -0.12065 -0.3048)
			(stroke
				(width 0.1)
				(type default)
			)
			(layer "B.Fab")
		)
		(fp_line
			(start -0.12065 -0.3048)
			(end -0.67945 -0.3048)
			(stroke
				(width 0.1)
				(type default)
			)
			(layer "B.Fab")
		)
		(fp_line
			(start -0.67945 0.3048)
			(end -0.120396 0.3048)
			(stroke
				(width 0.1)
				(type default)
			)
			(layer "B.Fab")
		)
		(fp_line
			(start -0.67945 -0.3048)
			(end -0.67945 0.3048)
			(stroke
				(width 0.1)
				(type default)
			)
			(layer "B.Fab")
		)
		(pad "1" smd circle
			(at 0.40005 0)
			(size 0 0)
			(layers "B.Cu" "B.Mask" "B.Paste")
			(net "P1V2_AUX")
		)
		(pad "2" smd circle
			(at -0.40005 0)
			(size 0 0)
			(layers "B.Cu" "B.Mask" "B.Paste")
			(net "GND")
		)
	)
	(footprint ""
		(layer "B.Cu")
		(at 81.106264 -386.766562 90)
		(property "Reference" "C330"
			(at 0 0 90)
			(layer "B.SilkS")
			(hide yes)
			(effects
				(font
					(size 1.27 1.27)
				)
				(justify mirror)
			)
		)
		(property "Value" ""
			(at 0 0 90)
			(layer "B.Fab")
			(effects
				(font
					(size 1.27 1.27)
				)
				(justify mirror)
			)
		)
		(duplicate_pad_numbers_are_jumpers no)
		(fp_line
			(start 0.299974 -0.150114)
			(end -0.299974 -0.150114)
			(stroke
				(width 0.1)
				(type default)
			)
			(layer "B.Fab")
		)
		(fp_line
			(start -0.299974 -0.150114)
			(end -0.299974 0.150114)
			(stroke
				(width 0.1)
				(type default)
			)
			(layer "B.Fab")
		)
		(fp_line
			(start 0.299974 0.150114)
			(end 0.299974 -0.150114)
			(stroke
				(width 0.1)
				(type default)
			)
			(layer "B.Fab")
		)
		(fp_line
			(start -0.299974 0.150114)
			(end 0.299974 0.150114)
			(stroke
				(width 0.1)
				(type default)
			)
			(layer "B.Fab")
		)
		(pad "1" smd rect
			(at 0.2667 0 270)
			(size 0.3048 0.381)
			(layers "B.Cu" "B.Mask" "B.Paste")
			(net "P0V9_CPU1_RT1_2A")
		)
		(pad "2" smd rect
			(at -0.2667 0 270)
			(size 0.3048 0.381)
			(layers "B.Cu" "B.Mask" "B.Paste")
			(net "GND")
		)
	)
	(footprint ""
		(layer "B.Cu")
		(at 406.618948 -398.942052 90)
		(property "Reference" "C796"
			(at 0 0 90)
			(layer "B.SilkS")
			(hide yes)
			(effects
				(font
					(size 1.27 1.27)
				)
				(justify mirror)
			)
		)
		(property "Value" ""
			(at 0 0 90)
			(layer "B.Fab")
			(effects
				(font
					(size 1.27 1.27)
				)
				(justify mirror)
			)
		)
		(duplicate_pad_numbers_are_jumpers no)
		(fp_line
			(start 0.7874 -0.4064)
			(end -0.7874 -0.4064)
			(stroke
				(width 0.1524)
				(type default)
			)
			(layer "B.SilkS")
		)
		(fp_line
			(start -0.7874 -0.4064)
			(end -0.7874 0.4064)
			(stroke
				(width 0.1524)
				(type default)
			)
			(layer "B.SilkS")
		)
		(fp_line
			(start 0.7874 0.4064)
			(end 0.7874 -0.4064)
			(stroke
				(width 0.1524)
				(type default)
			)
			(layer "B.SilkS")
		)
		(fp_line
			(start -0.7874 0.4064)
			(end 0.7874 0.4064)
			(stroke
				(width 0.1524)
				(type default)
			)
			(layer "B.SilkS")
		)
		(fp_line
			(start 0.67945 -0.305054)
			(end 0.12065 -0.305054)
			(stroke
				(width 0.1)
				(type default)
			)
			(layer "B.Fab")
		)
		(fp_line
			(start 0.12065 -0.305054)
			(end 0.12065 -0.2794)
			(stroke
				(width 0.1)
				(type default)
			)
			(layer "B.Fab")
		)
		(fp_line
			(start -0.12065 -0.3048)
			(end -0.67945 -0.3048)
			(stroke
				(width 0.1)
				(type default)
			)
			(layer "B.Fab")
		)
		(fp_line
			(start -0.67945 -0.3048)
			(end -0.67945 0.3048)
			(stroke
				(width 0.1)
				(type default)
			)
			(layer "B.Fab")
		)
		(fp_line
			(start 0.12065 -0.2794)
			(end -0.12065 -0.2794)
			(stroke
				(width 0.1)
				(type default)
			)
			(layer "B.Fab")
		)
		(fp_line
			(start -0.12065 -0.2794)
			(end -0.12065 -0.3048)
			(stroke
				(width 0.1)
				(type default)
			)
			(layer "B.Fab")
		)
		(fp_line
			(start 0.12065 0.2794)
			(end 0.12065 0.3048)
			(stroke
				(width 0.1)
				(type default)
			)
			(layer "B.Fab")
		)
		(fp_line
			(start -0.120396 0.2794)
			(end 0.12065 0.2794)
			(stroke
				(width 0.1)
				(type default)
			)
			(layer "B.Fab")
		)
		(fp_line
			(start 0.67945 0.3048)
			(end 0.67945 -0.305054)
			(stroke
				(width 0.1)
				(type default)
			)
			(layer "B.Fab")
		)
		(fp_line
			(start 0.12065 0.3048)
			(end 0.67945 0.3048)
			(stroke
				(width 0.1)
				(type default)
			)
			(layer "B.Fab")
		)
		(fp_line
			(start -0.120396 0.3048)
			(end -0.120396 0.2794)
			(stroke
				(width 0.1)
				(type default)
			)
			(layer "B.Fab")
		)
		(fp_line
			(start -0.67945 0.3048)
			(end -0.120396 0.3048)
			(stroke
				(width 0.1)
				(type default)
			)
			(layer "B.Fab")
		)
		(pad "1" smd circle
			(at 0.40005 0 270)
			(size 0 0)
			(layers "B.Cu" "B.Mask" "B.Paste")
			(net "P0V9_CPU0_RT2_2A")
		)
		(pad "2" smd circle
			(at -0.40005 0 270)
			(size 0 0)
			(layers "B.Cu" "B.Mask" "B.Paste")
			(net "GND")
		)
	)
	(footprint ""
		(layer "B.Cu")
		(at 78.159864 -11.26871 -90)
		(property "Reference" "R3165"
			(at 0 0 90)
			(layer "B.SilkS")
			(hide yes)
			(effects
				(font
					(size 1.27 1.27)
				)
				(justify mirror)
			)
		)
		(property "Value" ""
			(at 0 0 90)
			(layer "B.Fab")
			(effects
				(font
					(size 1.27 1.27)
				)
				(justify mirror)
			)
		)
		(duplicate_pad_numbers_are_jumpers no)
		(fp_line
			(start -0.7874 0.4064)
			(end 0.7874 0.4064)
			(stroke
				(width 0.1524)
				(type default)
			)
			(layer "B.SilkS")
		)
		(fp_line
			(start 0.7874 0.4064)
			(end 0.7874 -0.4064)
			(stroke
				(width 0.1524)
				(type default)
			)
			(layer "B.SilkS")
		)
		(fp_line
			(start -0.7874 -0.4064)
			(end -0.7874 0.4064)
			(stroke
				(width 0.1524)
				(type default)
			)
			(layer "B.SilkS")
		)
		(fp_line
			(start 0.7874 -0.4064)
			(end -0.7874 -0.4064)
			(stroke
				(width 0.1524)
				(type default)
			)
			(layer "B.SilkS")
		)
		(fp_line
			(start -0.67945 0.3048)
			(end -0.120396 0.3048)
			(stroke
				(width 0.1)
				(type default)
			)
			(layer "B.Fab")
		)
		(fp_line
			(start -0.120396 0.3048)
			(end -0.120396 0.2794)
			(stroke
				(width 0.1)
				(type default)
			)
			(layer "B.Fab")
		)
		(fp_line
			(start 0.12065 0.3048)
			(end 0.67945 0.3048)
			(stroke
				(width 0.1)
				(type default)
			)
			(layer "B.Fab")
		)
		(fp_line
			(start 0.67945 0.3048)
			(end 0.67945 -0.305054)
			(stroke
				(width 0.1)
				(type default)
			)
			(layer "B.Fab")
		)
		(fp_line
			(start -0.120396 0.2794)
			(end 0.12065 0.2794)
			(stroke
				(width 0.1)
				(type default)
			)
			(layer "B.Fab")
		)
		(fp_line
			(start 0.12065 0.2794)
			(end 0.12065 0.3048)
			(stroke
				(width 0.1)
				(type default)
			)
			(layer "B.Fab")
		)
		(fp_line
			(start -0.12065 -0.2794)
			(end -0.12065 -0.3048)
			(stroke
				(width 0.1)
				(type default)
			)
			(layer "B.Fab")
		)
		(fp_line
			(start 0.12065 -0.2794)
			(end -0.12065 -0.2794)
			(stroke
				(width 0.1)
				(type default)
			)
			(layer "B.Fab")
		)
		(fp_line
			(start -0.67945 -0.3048)
			(end -0.67945 0.3048)
			(stroke
				(width 0.1)
				(type default)
			)
			(layer "B.Fab")
		)
		(fp_line
			(start -0.12065 -0.3048)
			(end -0.67945 -0.3048)
			(stroke
				(width 0.1)
				(type default)
			)
			(layer "B.Fab")
		)
		(fp_line
			(start 0.12065 -0.305054)
			(end 0.12065 -0.2794)
			(stroke
				(width 0.1)
				(type default)
			)
			(layer "B.Fab")
		)
		(fp_line
			(start 0.67945 -0.305054)
			(end 0.12065 -0.305054)
			(stroke
				(width 0.1)
				(type default)
			)
			(layer "B.Fab")
		)
		(pad "1" smd circle
			(at 0.40005 0 90)
			(size 0 0)
			(layers "B.Cu" "B.Mask" "B.Paste")
			(net "GND")
		)
		(pad "2" smd circle
			(at -0.40005 0 90)
			(size 0 0)
			(layers "B.Cu" "B.Mask" "B.Paste")
			(net "OCP_V3_2_MAIN_PWR_EN")
		)
	)
	(footprint ""
		(layer "B.Cu")
		(at 244.221 -228.092 -90)
		(property "Reference" "R1154"
			(at 0 0 90)
			(layer "B.SilkS")
			(hide yes)
			(effects
				(font
					(size 1.27 1.27)
				)
				(justify mirror)
			)
		)
		(property "Value" ""
			(at 0 0 90)
			(layer "B.Fab")
			(effects
				(font
					(size 1.27 1.27)
				)
				(justify mirror)
			)
		)
		(duplicate_pad_numbers_are_jumpers no)
		(fp_line
			(start -0.7874 0.4064)
			(end 0.7874 0.4064)
			(stroke
				(width 0.1524)
				(type default)
			)
			(layer "B.SilkS")
		)
		(fp_line
			(start 0.7874 0.4064)
			(end 0.7874 -0.4064)
			(stroke
				(width 0.1524)
				(type default)
			)
			(layer "B.SilkS")
		)
		(fp_line
			(start -0.7874 -0.4064)
			(end -0.7874 0.4064)
			(stroke
				(width 0.1524)
				(type default)
			)
			(layer "B.SilkS")
		)
		(fp_line
			(start 0.7874 -0.4064)
			(end -0.7874 -0.4064)
			(stroke
				(width 0.1524)
				(type default)
			)
			(layer "B.SilkS")
		)
		(fp_line
			(start -0.67945 0.3048)
			(end -0.120396 0.3048)
			(stroke
				(width 0.1)
				(type default)
			)
			(layer "B.Fab")
		)
		(fp_line
			(start -0.120396 0.3048)
			(end -0.120396 0.2794)
			(stroke
				(width 0.1)
				(type default)
			)
			(layer "B.Fab")
		)
		(fp_line
			(start 0.12065 0.3048)
			(end 0.67945 0.3048)
			(stroke
				(width 0.1)
				(type default)
			)
			(layer "B.Fab")
		)
		(fp_line
			(start 0.67945 0.3048)
			(end 0.67945 -0.305054)
			(stroke
				(width 0.1)
				(type default)
			)
			(layer "B.Fab")
		)
		(fp_line
			(start -0.120396 0.2794)
			(end 0.12065 0.2794)
			(stroke
				(width 0.1)
				(type default)
			)
			(layer "B.Fab")
		)
		(fp_line
			(start 0.12065 0.2794)
			(end 0.12065 0.3048)
			(stroke
				(width 0.1)
				(type default)
			)
			(layer "B.Fab")
		)
		(fp_line
			(start -0.12065 -0.2794)
			(end -0.12065 -0.3048)
			(stroke
				(width 0.1)
				(type default)
			)
			(layer "B.Fab")
		)
		(fp_line
			(start 0.12065 -0.2794)
			(end -0.12065 -0.2794)
			(stroke
				(width 0.1)
				(type default)
			)
			(layer "B.Fab")
		)
		(fp_line
			(start -0.67945 -0.3048)
			(end -0.67945 0.3048)
			(stroke
				(width 0.1)
				(type default)
			)
			(layer "B.Fab")
		)
		(fp_line
			(start -0.12065 -0.3048)
			(end -0.67945 -0.3048)
			(stroke
				(width 0.1)
				(type default)
			)
			(layer "B.Fab")
		)
		(fp_line
			(start 0.12065 -0.305054)
			(end 0.12065 -0.2794)
			(stroke
				(width 0.1)
				(type default)
			)
			(layer "B.Fab")
		)
		(fp_line
			(start 0.67945 -0.305054)
			(end 0.12065 -0.305054)
			(stroke
				(width 0.1)
				(type default)
			)
			(layer "B.Fab")
		)
		(pad "1" smd circle
			(at 0.40005 0 90)
			(size 0 0)
			(layers "B.Cu" "B.Mask" "B.Paste")
			(net "SMB_CPU0_CPU1_SEC_SDA_R1")
		)
		(pad "2" smd circle
			(at -0.40005 0 90)
			(size 0 0)
			(layers "B.Cu" "B.Mask" "B.Paste")
			(net "SMB_CPU0_CPU1_SEC_SDA_R2")
		)
	)
	(footprint ""
		(layer "B.Cu")
		(at 323.386958 -198.964296)
		(property "Reference" "R438"
			(at 0 0 0)
			(layer "B.SilkS")
			(hide yes)
			(effects
				(font
					(size 1.27 1.27)
				)
				(justify mirror)
			)
		)
		(property "Value" ""
			(at 0 0 0)
			(layer "B.Fab")
			(effects
				(font
					(size 1.27 1.27)
				)
				(justify mirror)
			)
		)
		(duplicate_pad_numbers_are_jumpers no)
		(fp_line
			(start -0.7874 -0.4064)
			(end -0.7874 0.4064)
			(stroke
				(width 0.1524)
				(type default)
			)
			(layer "B.SilkS")
		)
		(fp_line
			(start -0.7874 0.4064)
			(end 0.7874 0.4064)
			(stroke
				(width 0.1524)
				(type default)
			)
			(layer "B.SilkS")
		)
		(fp_line
			(start 0.7874 -0.4064)
			(end -0.7874 -0.4064)
			(stroke
				(width 0.1524)
				(type default)
			)
			(layer "B.SilkS")
		)
		(fp_line
			(start 0.7874 0.4064)
			(end 0.7874 -0.4064)
			(stroke
				(width 0.1524)
				(type default)
			)
			(layer "B.SilkS")
		)
		(fp_line
			(start -0.67945 -0.3048)
			(end -0.67945 0.3048)
			(stroke
				(width 0.1)
				(type default)
			)
			(layer "B.Fab")
		)
		(fp_line
			(start -0.67945 0.3048)
			(end -0.120396 0.3048)
			(stroke
				(width 0.1)
				(type default)
			)
			(layer "B.Fab")
		)
		(fp_line
			(start -0.12065 -0.3048)
			(end -0.67945 -0.3048)
			(stroke
				(width 0.1)
				(type default)
			)
			(layer "B.Fab")
		)
		(fp_line
			(start -0.12065 -0.2794)
			(end -0.12065 -0.3048)
			(stroke
				(width 0.1)
				(type default)
			)
			(layer "B.Fab")
		)
		(fp_line
			(start -0.120396 0.2794)
			(end 0.12065 0.2794)
			(stroke
				(width 0.1)
				(type default)
			)
			(layer "B.Fab")
		)
		(fp_line
			(start -0.120396 0.3048)
			(end -0.120396 0.2794)
			(stroke
				(width 0.1)
				(type default)
			)
			(layer "B.Fab")
		)
		(fp_line
			(start 0.12065 -0.305054)
			(end 0.12065 -0.2794)
			(stroke
				(width 0.1)
				(type default)
			)
			(layer "B.Fab")
		)
		(fp_line
			(start 0.12065 -0.2794)
			(end -0.12065 -0.2794)
			(stroke
				(width 0.1)
				(type default)
			)
			(layer "B.Fab")
		)
		(fp_line
			(start 0.12065 0.2794)
			(end 0.12065 0.3048)
			(stroke
				(width 0.1)
				(type default)
			)
			(layer "B.Fab")
		)
		(fp_line
			(start 0.12065 0.3048)
			(end 0.67945 0.3048)
			(stroke
				(width 0.1)
				(type default)
			)
			(layer "B.Fab")
		)
		(fp_line
			(start 0.67945 -0.305054)
			(end 0.12065 -0.305054)
			(stroke
				(width 0.1)
				(type default)
			)
			(layer "B.Fab")
		)
		(fp_line
			(start 0.67945 0.3048)
			(end 0.67945 -0.305054)
			(stroke
				(width 0.1)
				(type default)
			)
			(layer "B.Fab")
		)
		(pad "1" smd circle
			(at 0.40005 0 180)
			(size 0 0)
			(layers "B.Cu" "B.Mask" "B.Paste")
			(net "CPU0_FORCE_SELFREFRESH")
		)
		(pad "2" smd circle
			(at -0.40005 0 180)
			(size 0 0)
			(layers "B.Cu" "B.Mask" "B.Paste")
			(net "PVDD18_S5_P0")
		)
	)
	(footprint ""
		(layer "B.Cu")
		(at 436.839614 -351.095818 90)
		(property "Reference" "PC218_2"
			(at 0 0 90)
			(layer "B.SilkS")
			(hide yes)
			(effects
				(font
					(size 1.27 1.27)
				)
				(justify mirror)
			)
		)
		(property "Value" ""
			(at 0 0 90)
			(layer "B.Fab")
			(effects
				(font
					(size 1.27 1.27)
				)
				(justify mirror)
			)
		)
		(duplicate_pad_numbers_are_jumpers no)
		(fp_line
			(start 1.524 -0.762)
			(end -1.524 -0.762)
			(stroke
				(width 0.1524)
				(type default)
			)
			(layer "B.SilkS")
		)
		(fp_line
			(start -1.524 -0.762)
			(end -1.524 0.762)
			(stroke
				(width 0.1524)
				(type default)
			)
			(layer "B.SilkS")
		)
		(fp_line
			(start 1.524 0.762)
			(end 1.524 -0.762)
			(stroke
				(width 0.1524)
				(type default)
			)
			(layer "B.SilkS")
		)
		(fp_line
			(start -1.524 0.762)
			(end 1.524 0.762)
			(stroke
				(width 0.1524)
				(type default)
			)
			(layer "B.SilkS")
		)
		(fp_line
			(start 1.1049 -0.724916)
			(end 1.1049 0.724916)
			(stroke
				(width 0.1)
				(type default)
			)
			(layer "B.Fab")
		)
		(fp_line
			(start -1.1049 -0.724916)
			(end 1.1049 -0.724916)
			(stroke
				(width 0.1)
				(type default)
			)
			(layer "B.Fab")
		)
		(fp_line
			(start 1.1049 0.724916)
			(end -1.1049 0.724916)
			(stroke
				(width 0.1)
				(type default)
			)
			(layer "B.Fab")
		)
		(fp_line
			(start -1.1049 0.724916)
			(end -1.1049 -0.724916)
			(stroke
				(width 0.1)
				(type default)
			)
			(layer "B.Fab")
		)
		(pad "1" smd rect
			(at 0.889 0 90)
			(size 1.016 1.27)
			(layers "B.Cu" "B.Mask" "B.Paste")
			(net "SW_P12V_AUX_PVDD11_S3_P0_FLT")
		)
		(pad "2" smd rect
			(at -0.889 0 90)
			(size 1.016 1.27)
			(layers "B.Cu" "B.Mask" "B.Paste")
			(net "GND")
		)
	)
	(footprint ""
		(layer "B.Cu")
		(at 269.648178 -192.660016)
		(property "Reference" "C154"
			(at 0 0 0)
			(layer "B.SilkS")
			(hide yes)
			(effects
				(font
					(size 1.27 1.27)
				)
				(justify mirror)
			)
		)
		(property "Value" ""
			(at 0 0 0)
			(layer "B.Fab")
			(effects
				(font
					(size 1.27 1.27)
				)
				(justify mirror)
			)
		)
		(duplicate_pad_numbers_are_jumpers no)
		(fp_line
			(start -1.524 -0.762)
			(end -1.524 0.762)
			(stroke
				(width 0.1524)
				(type default)
			)
			(layer "B.SilkS")
		)
		(fp_line
			(start -1.524 0.762)
			(end 1.524 0.762)
			(stroke
				(width 0.1524)
				(type default)
			)
			(layer "B.SilkS")
		)
		(fp_line
			(start 1.524 -0.762)
			(end -1.524 -0.762)
			(stroke
				(width 0.1524)
				(type default)
			)
			(layer "B.SilkS")
		)
		(fp_line
			(start 1.524 0.762)
			(end 1.524 -0.762)
			(stroke
				(width 0.1524)
				(type default)
			)
			(layer "B.SilkS")
		)
		(fp_line
			(start -1.1049 -0.724916)
			(end 1.1049 -0.724916)
			(stroke
				(width 0.1)
				(type default)
			)
			(layer "B.Fab")
		)
		(fp_line
			(start -1.1049 0.724916)
			(end -1.1049 -0.724916)
			(stroke
				(width 0.1)
				(type default)
			)
			(layer "B.Fab")
		)
		(fp_line
			(start 1.1049 -0.724916)
			(end 1.1049 0.724916)
			(stroke
				(width 0.1)
				(type default)
			)
			(layer "B.Fab")
		)
		(fp_line
			(start 1.1049 0.724916)
			(end -1.1049 0.724916)
			(stroke
				(width 0.1)
				(type default)
			)
			(layer "B.Fab")
		)
		(pad "1" smd rect
			(at 0.889 0)
			(size 1.016 1.27)
			(layers "B.Cu" "B.Mask" "B.Paste")
			(net "P12V_MEM_CPU0")
		)
		(pad "2" smd rect
			(at -0.889 0)
			(size 1.016 1.27)
			(layers "B.Cu" "B.Mask" "B.Paste")
			(net "GND")
		)
	)
	(footprint ""
		(layer "B.Cu")
		(at 407.819098 -398.942052 90)
		(property "Reference" "C799"
			(at 0 0 90)
			(layer "B.SilkS")
			(hide yes)
			(effects
				(font
					(size 1.27 1.27)
				)
				(justify mirror)
			)
		)
		(property "Value" ""
			(at 0 0 90)
			(layer "B.Fab")
			(effects
				(font
					(size 1.27 1.27)
				)
				(justify mirror)
			)
		)
		(duplicate_pad_numbers_are_jumpers no)
		(fp_line
			(start 0.7874 -0.4064)
			(end -0.7874 -0.4064)
			(stroke
				(width 0.1524)
				(type default)
			)
			(layer "B.SilkS")
		)
		(fp_line
			(start -0.7874 -0.4064)
			(end -0.7874 0.4064)
			(stroke
				(width 0.1524)
				(type default)
			)
			(layer "B.SilkS")
		)
		(fp_line
			(start 0.7874 0.4064)
			(end 0.7874 -0.4064)
			(stroke
				(width 0.1524)
				(type default)
			)
			(layer "B.SilkS")
		)
		(fp_line
			(start -0.7874 0.4064)
			(end 0.7874 0.4064)
			(stroke
				(width 0.1524)
				(type default)
			)
			(layer "B.SilkS")
		)
		(fp_line
			(start 0.67945 -0.305054)
			(end 0.12065 -0.305054)
			(stroke
				(width 0.1)
				(type default)
			)
			(layer "B.Fab")
		)
		(fp_line
			(start 0.12065 -0.305054)
			(end 0.12065 -0.2794)
			(stroke
				(width 0.1)
				(type default)
			)
			(layer "B.Fab")
		)
		(fp_line
			(start -0.12065 -0.3048)
			(end -0.67945 -0.3048)
			(stroke
				(width 0.1)
				(type default)
			)
			(layer "B.Fab")
		)
		(fp_line
			(start -0.67945 -0.3048)
			(end -0.67945 0.3048)
			(stroke
				(width 0.1)
				(type default)
			)
			(layer "B.Fab")
		)
		(fp_line
			(start 0.12065 -0.2794)
			(end -0.12065 -0.2794)
			(stroke
				(width 0.1)
				(type default)
			)
			(layer "B.Fab")
		)
		(fp_line
			(start -0.12065 -0.2794)
			(end -0.12065 -0.3048)
			(stroke
				(width 0.1)
				(type default)
			)
			(layer "B.Fab")
		)
		(fp_line
			(start 0.12065 0.2794)
			(end 0.12065 0.3048)
			(stroke
				(width 0.1)
				(type default)
			)
			(layer "B.Fab")
		)
		(fp_line
			(start -0.120396 0.2794)
			(end 0.12065 0.2794)
			(stroke
				(width 0.1)
				(type default)
			)
			(layer "B.Fab")
		)
		(fp_line
			(start 0.67945 0.3048)
			(end 0.67945 -0.305054)
			(stroke
				(width 0.1)
				(type default)
			)
			(layer "B.Fab")
		)
		(fp_line
			(start 0.12065 0.3048)
			(end 0.67945 0.3048)
			(stroke
				(width 0.1)
				(type default)
			)
			(layer "B.Fab")
		)
		(fp_line
			(start -0.120396 0.3048)
			(end -0.120396 0.2794)
			(stroke
				(width 0.1)
				(type default)
			)
			(layer "B.Fab")
		)
		(fp_line
			(start -0.67945 0.3048)
			(end -0.120396 0.3048)
			(stroke
				(width 0.1)
				(type default)
			)
			(layer "B.Fab")
		)
		(pad "1" smd circle
			(at 0.40005 0 270)
			(size 0 0)
			(layers "B.Cu" "B.Mask" "B.Paste")
			(net "P0V9_CPU0_RT2_2A")
		)
		(pad "2" smd circle
			(at -0.40005 0 270)
			(size 0 0)
			(layers "B.Cu" "B.Mask" "B.Paste")
			(net "GND")
		)
	)
	(footprint ""
		(layer "B.Cu")
		(at 482.66985 7.613142 90)
		(property "Reference" "X8006"
			(at 0.93726 -1.53035 270)
			(unlocked yes)
			(layer "B.SilkS")
			(effects
				(font
					(size 0.7874 0.5842)
					(thickness 0.1524)
				)
				(justify left mirror)
			)
		)
		(property "Value" ""
			(at 0 0 90)
			(layer "B.Fab")
			(effects
				(font
					(size 1.27 1.27)
				)
				(justify mirror)
			)
		)
		(property "Device Type" "TP_TDR_4P_FTS_TH-TP_TDR_4P_DIP,EMPTY,TP15"
			(at -1.30175 1.27 0)
			(unlocked yes)
			(layer "B.Fab")
			(hide yes)
			(effects
				(font
					(size 0.635 0.4064)
					(thickness 0.1524)
				)
				(justify mirror)
			)
		)
		(property "User Part Number" "N_A"
			(at -1.30175 1.27 0)
			(unlocked yes)
			(layer "Cmts.User")
			(hide yes)
			(effects
				(font
					(size 0.635 0.4064)
					(thickness 0.1524)
				)
				(justify mirror)
			)
		)
		(duplicate_pad_numbers_are_jumpers no)
		(fp_line
			(start 0 -1.27)
			(end 0 -0.635)
			(stroke
				(width 0.1524)
				(type default)
			)
			(layer "B.SilkS")
		)
		(fp_line
			(start -2.54 -1.27)
			(end 0 -1.27)
			(stroke
				(width 0.1524)
				(type default)
			)
			(layer "B.SilkS")
		)
		(fp_line
			(start -2.54 -1.1303)
			(end -2.54 -1.27)
			(stroke
				(width 0.1524)
				(type default)
			)
			(layer "B.SilkS")
		)
		(fp_line
			(start 0 0.635)
			(end 0 1.905)
			(stroke
				(width 0.1524)
				(type default)
			)
			(layer "B.SilkS")
		)
		(fp_line
			(start -2.54 1.4097)
			(end -2.54 1.1303)
			(stroke
				(width 0.1524)
				(type default)
			)
			(layer "B.SilkS")
		)
		(fp_line
			(start 0 3.175)
			(end 0 3.81)
			(stroke
				(width 0.1524)
				(type default)
			)
			(layer "B.SilkS")
		)
		(fp_line
			(start 0 3.81)
			(end -2.54 3.81)
			(stroke
				(width 0.1524)
				(type default)
			)
			(layer "B.SilkS")
		)
		(fp_line
			(start -2.54 3.81)
			(end -2.54 3.6703)
			(stroke
				(width 0.1524)
				(type default)
			)
			(layer "B.SilkS")
		)
		(fp_poly
			(pts
				(xy 0.761746 0) (xy 2.285746 -0.762) (xy 2.285746 0.762)
			)
			(stroke
				(width 0)
				(type default)
			)
			(fill yes)
			(layer "B.SilkS")
		)
		(fp_line
			(start 0 -1.27)
			(end 0 3.81)
			(stroke
				(width 0.1)
				(type default)
			)
			(layer "B.Fab")
		)
		(fp_line
			(start -2.54 -1.27)
			(end 0 -1.27)
			(stroke
				(width 0.1)
				(type default)
			)
			(layer "B.Fab")
		)
		(fp_line
			(start 0 3.81)
			(end -2.54 3.81)
			(stroke
				(width 0.1)
				(type default)
			)
			(layer "B.Fab")
		)
		(fp_line
			(start -2.54 3.81)
			(end -2.54 -1.27)
			(stroke
				(width 0.1)
				(type default)
			)
			(layer "B.Fab")
		)
		(fp_poly
			(pts
				(xy 0.761746 0) (xy 2.285746 -0.762) (xy 2.285746 0.762)
			)
			(stroke
				(width 0)
				(type default)
			)
			(fill yes)
			(layer "B.Fab")
		)
		(pad "1" thru_hole circle
			(at 0 0 270)
			(size 1.0033 1.0033)
			(drill 0.249936)
			(layers "*.Cu" "*.Mask")
			(remove_unused_layers no)
			(net "TDR_DIFF_85_BOT_DP")
			(clearance 0.10795)
			(padstack
				(mode front_inner_back)
				(layer "Inner"
					(shape circle)
					(size 0.8001 0.8001)
					(clearance 0.1524)
				)
				(layer "B.Cu"
					(shape circle)
					(size 1.0033 1.0033)
					(thermal_gap 0.10795)
					(clearance 0.10795)
				)
			)
		)
		(pad "2" thru_hole circle
			(at -2.54 0 270)
			(size 1.9939 1.9939)
			(drill 0.249936)
			(layers "*.Cu" "*.Mask")
			(remove_unused_layers no)
			(net "T1_GND")
			(clearance 0.10795)
			(padstack
				(mode front_inner_back)
				(layer "Inner"
					(shape circle)
					(size 0.8001 0.8001)
					(clearance 0.1524)
				)
				(layer "B.Cu"
					(shape circle)
					(size 1.9939 1.9939)
					(thermal_gap 0.10795)
					(clearance 0.10795)
				)
			)
		)
		(pad "3" thru_hole circle
			(at -2.54 2.54 270)
			(size 1.9939 1.9939)
			(drill 0.249936)
			(layers "*.Cu" "*.Mask")
			(remove_unused_layers no)
			(net "T1_GND")
			(clearance 0.10795)
			(padstack
				(mode front_inner_back)
				(layer "Inner"
					(shape circle)
					(size 0.8001 0.8001)
					(clearance 0.1524)
				)
				(layer "B.Cu"
					(shape circle)
					(size 1.9939 1.9939)
					(thermal_gap 0.10795)
					(clearance 0.10795)
				)
			)
		)
		(pad "4" thru_hole circle
			(at 0 2.54 270)
			(size 1.0033 1.0033)
			(drill 0.249936)
			(layers "*.Cu" "*.Mask")
			(remove_unused_layers no)
			(net "TDR_DIFF_85_BOT_DN")
			(clearance 0.10795)
			(padstack
				(mode front_inner_back)
				(layer "Inner"
					(shape circle)
					(size 0.8001 0.8001)
					(clearance 0.1524)
				)
				(layer "B.Cu"
					(shape circle)
					(size 1.0033 1.0033)
					(thermal_gap 0.10795)
					(clearance 0.10795)
				)
			)
		)
	)
	(footprint ""
		(layer "B.Cu")
		(at 130.104642 -76.48321)
		(property "Reference" "PC6024"
			(at 0 0 0)
			(layer "B.SilkS")
			(hide yes)
			(effects
				(font
					(size 1.27 1.27)
				)
				(justify mirror)
			)
		)
		(property "Value" ""
			(at 0 0 0)
			(layer "B.Fab")
			(effects
				(font
					(size 1.27 1.27)
				)
				(justify mirror)
			)
		)
		(duplicate_pad_numbers_are_jumpers no)
		(fp_line
			(start -1.524 -0.762)
			(end -1.524 0.762)
			(stroke
				(width 0.1524)
				(type default)
			)
			(layer "B.SilkS")
		)
		(fp_line
			(start -1.524 0.762)
			(end 1.524 0.762)
			(stroke
				(width 0.1524)
				(type default)
			)
			(layer "B.SilkS")
		)
		(fp_line
			(start 1.524 -0.762)
			(end -1.524 -0.762)
			(stroke
				(width 0.1524)
				(type default)
			)
			(layer "B.SilkS")
		)
		(fp_line
			(start 1.524 0.762)
			(end 1.524 -0.762)
			(stroke
				(width 0.1524)
				(type default)
			)
			(layer "B.SilkS")
		)
		(fp_line
			(start -1.1049 -0.724916)
			(end 1.1049 -0.724916)
			(stroke
				(width 0.1)
				(type default)
			)
			(layer "B.Fab")
		)
		(fp_line
			(start -1.1049 0.724916)
			(end -1.1049 -0.724916)
			(stroke
				(width 0.1)
				(type default)
			)
			(layer "B.Fab")
		)
		(fp_line
			(start 1.1049 -0.724916)
			(end 1.1049 0.724916)
			(stroke
				(width 0.1)
				(type default)
			)
			(layer "B.Fab")
		)
		(fp_line
			(start 1.1049 0.724916)
			(end -1.1049 0.724916)
			(stroke
				(width 0.1)
				(type default)
			)
			(layer "B.Fab")
		)
		(pad "1" smd rect
			(at 0.889 0)
			(size 1.016 1.27)
			(layers "B.Cu" "B.Mask" "B.Paste")
			(net "P1V2_AUX")
		)
		(pad "2" smd rect
			(at -0.889 0)
			(size 1.016 1.27)
			(layers "B.Cu" "B.Mask" "B.Paste")
			(net "GND")
		)
	)
	(footprint ""
		(layer "B.Cu")
		(at 111.800386 -249.876564 90)
		(property "Reference" "C2332"
			(at 0 0 90)
			(layer "B.SilkS")
			(hide yes)
			(effects
				(font
					(size 1.27 1.27)
				)
				(justify mirror)
			)
		)
		(property "Value" ""
			(at 0 0 90)
			(layer "B.Fab")
			(effects
				(font
					(size 1.27 1.27)
				)
				(justify mirror)
			)
		)
		(duplicate_pad_numbers_are_jumpers no)
		(fp_line
			(start 0.7874 -0.4064)
			(end -0.7874 -0.4064)
			(stroke
				(width 0.1524)
				(type default)
			)
			(layer "B.SilkS")
		)
		(fp_line
			(start -0.7874 -0.4064)
			(end -0.7874 0.4064)
			(stroke
				(width 0.1524)
				(type default)
			)
			(layer "B.SilkS")
		)
		(fp_line
			(start 0.7874 0.4064)
			(end 0.7874 -0.4064)
			(stroke
				(width 0.1524)
				(type default)
			)
			(layer "B.SilkS")
		)
		(fp_line
			(start -0.7874 0.4064)
			(end 0.7874 0.4064)
			(stroke
				(width 0.1524)
				(type default)
			)
			(layer "B.SilkS")
		)
		(fp_line
			(start 0.67945 -0.305054)
			(end 0.12065 -0.305054)
			(stroke
				(width 0.1)
				(type default)
			)
			(layer "B.Fab")
		)
		(fp_line
			(start 0.12065 -0.305054)
			(end 0.12065 -0.2794)
			(stroke
				(width 0.1)
				(type default)
			)
			(layer "B.Fab")
		)
		(fp_line
			(start -0.12065 -0.3048)
			(end -0.67945 -0.3048)
			(stroke
				(width 0.1)
				(type default)
			)
			(layer "B.Fab")
		)
		(fp_line
			(start -0.67945 -0.3048)
			(end -0.67945 0.3048)
			(stroke
				(width 0.1)
				(type default)
			)
			(layer "B.Fab")
		)
		(fp_line
			(start 0.12065 -0.2794)
			(end -0.12065 -0.2794)
			(stroke
				(width 0.1)
				(type default)
			)
			(layer "B.Fab")
		)
		(fp_line
			(start -0.12065 -0.2794)
			(end -0.12065 -0.3048)
			(stroke
				(width 0.1)
				(type default)
			)
			(layer "B.Fab")
		)
		(fp_line
			(start 0.12065 0.2794)
			(end 0.12065 0.3048)
			(stroke
				(width 0.1)
				(type default)
			)
			(layer "B.Fab")
		)
		(fp_line
			(start -0.120396 0.2794)
			(end 0.12065 0.2794)
			(stroke
				(width 0.1)
				(type default)
			)
			(layer "B.Fab")
		)
		(fp_line
			(start 0.67945 0.3048)
			(end 0.67945 -0.305054)
			(stroke
				(width 0.1)
				(type default)
			)
			(layer "B.Fab")
		)
		(fp_line
			(start 0.12065 0.3048)
			(end 0.67945 0.3048)
			(stroke
				(width 0.1)
				(type default)
			)
			(layer "B.Fab")
		)
		(fp_line
			(start -0.120396 0.3048)
			(end -0.120396 0.2794)
			(stroke
				(width 0.1)
				(type default)
			)
			(layer "B.Fab")
		)
		(fp_line
			(start -0.67945 0.3048)
			(end -0.120396 0.3048)
			(stroke
				(width 0.1)
				(type default)
			)
			(layer "B.Fab")
		)
		(pad "1" smd circle
			(at 0.40005 0 270)
			(size 0 0)
			(layers "B.Cu" "B.Mask" "B.Paste")
			(net "PVDDCR_CPU0_P1")
		)
		(pad "2" smd circle
			(at -0.40005 0 270)
			(size 0 0)
			(layers "B.Cu" "B.Mask" "B.Paste")
			(net "GND")
		)
	)
	(footprint ""
		(layer "B.Cu")
		(at 62.53988 -8.981948 90)
		(property "Reference" "C1837"
			(at 0 0 90)
			(layer "B.SilkS")
			(hide yes)
			(effects
				(font
					(size 1.27 1.27)
				)
				(justify mirror)
			)
		)
		(property "Value" ""
			(at 0 0 90)
			(layer "B.Fab")
			(effects
				(font
					(size 1.27 1.27)
				)
				(justify mirror)
			)
		)
		(duplicate_pad_numbers_are_jumpers no)
		(fp_line
			(start 0.7874 -0.4064)
			(end -0.7874 -0.4064)
			(stroke
				(width 0.1524)
				(type default)
			)
			(layer "B.SilkS")
		)
		(fp_line
			(start -0.7874 -0.4064)
			(end -0.7874 0.4064)
			(stroke
				(width 0.1524)
				(type default)
			)
			(layer "B.SilkS")
		)
		(fp_line
			(start 0.7874 0.4064)
			(end 0.7874 -0.4064)
			(stroke
				(width 0.1524)
				(type default)
			)
			(layer "B.SilkS")
		)
		(fp_line
			(start -0.7874 0.4064)
			(end 0.7874 0.4064)
			(stroke
				(width 0.1524)
				(type default)
			)
			(layer "B.SilkS")
		)
		(fp_line
			(start 0.67945 -0.305054)
			(end 0.12065 -0.305054)
			(stroke
				(width 0.1)
				(type default)
			)
			(layer "B.Fab")
		)
		(fp_line
			(start 0.12065 -0.305054)
			(end 0.12065 -0.2794)
			(stroke
				(width 0.1)
				(type default)
			)
			(layer "B.Fab")
		)
		(fp_line
			(start -0.12065 -0.3048)
			(end -0.67945 -0.3048)
			(stroke
				(width 0.1)
				(type default)
			)
			(layer "B.Fab")
		)
		(fp_line
			(start -0.67945 -0.3048)
			(end -0.67945 0.3048)
			(stroke
				(width 0.1)
				(type default)
			)
			(layer "B.Fab")
		)
		(fp_line
			(start 0.12065 -0.2794)
			(end -0.12065 -0.2794)
			(stroke
				(width 0.1)
				(type default)
			)
			(layer "B.Fab")
		)
		(fp_line
			(start -0.12065 -0.2794)
			(end -0.12065 -0.3048)
			(stroke
				(width 0.1)
				(type default)
			)
			(layer "B.Fab")
		)
		(fp_line
			(start 0.12065 0.2794)
			(end 0.12065 0.3048)
			(stroke
				(width 0.1)
				(type default)
			)
			(layer "B.Fab")
		)
		(fp_line
			(start -0.120396 0.2794)
			(end 0.12065 0.2794)
			(stroke
				(width 0.1)
				(type default)
			)
			(layer "B.Fab")
		)
		(fp_line
			(start 0.67945 0.3048)
			(end 0.67945 -0.305054)
			(stroke
				(width 0.1)
				(type default)
			)
			(layer "B.Fab")
		)
		(fp_line
			(start 0.12065 0.3048)
			(end 0.67945 0.3048)
			(stroke
				(width 0.1)
				(type default)
			)
			(layer "B.Fab")
		)
		(fp_line
			(start -0.120396 0.3048)
			(end -0.120396 0.2794)
			(stroke
				(width 0.1)
				(type default)
			)
			(layer "B.Fab")
		)
		(fp_line
			(start -0.67945 0.3048)
			(end -0.120396 0.3048)
			(stroke
				(width 0.1)
				(type default)
			)
			(layer "B.Fab")
		)
		(pad "1" smd circle
			(at 0.40005 0 270)
			(size 0 0)
			(layers "B.Cu" "B.Mask" "B.Paste")
			(net "P3V3_OCP_V3_2")
		)
		(pad "2" smd circle
			(at -0.40005 0 270)
			(size 0 0)
			(layers "B.Cu" "B.Mask" "B.Paste")
			(net "GND")
		)
	)
	(footprint ""
		(layer "B.Cu")
		(at 311.945782 -346.784168 90)
		(property "Reference" "PC119_4"
			(at 0 0 90)
			(layer "B.SilkS")
			(hide yes)
			(effects
				(font
					(size 1.27 1.27)
				)
				(justify mirror)
			)
		)
		(property "Value" ""
			(at 0 0 90)
			(layer "B.Fab")
			(effects
				(font
					(size 1.27 1.27)
				)
				(justify mirror)
			)
		)
		(duplicate_pad_numbers_are_jumpers no)
		(fp_line
			(start 1.524 -0.762)
			(end -1.524 -0.762)
			(stroke
				(width 0.1524)
				(type default)
			)
			(layer "B.SilkS")
		)
		(fp_line
			(start -1.524 -0.762)
			(end -1.524 0.762)
			(stroke
				(width 0.1524)
				(type default)
			)
			(layer "B.SilkS")
		)
		(fp_line
			(start 1.524 0.762)
			(end 1.524 -0.762)
			(stroke
				(width 0.1524)
				(type default)
			)
			(layer "B.SilkS")
		)
		(fp_line
			(start -1.524 0.762)
			(end 1.524 0.762)
			(stroke
				(width 0.1524)
				(type default)
			)
			(layer "B.SilkS")
		)
		(fp_line
			(start 1.1049 -0.724916)
			(end 1.1049 0.724916)
			(stroke
				(width 0.1)
				(type default)
			)
			(layer "B.Fab")
		)
		(fp_line
			(start -1.1049 -0.724916)
			(end 1.1049 -0.724916)
			(stroke
				(width 0.1)
				(type default)
			)
			(layer "B.Fab")
		)
		(fp_line
			(start 1.1049 0.724916)
			(end -1.1049 0.724916)
			(stroke
				(width 0.1)
				(type default)
			)
			(layer "B.Fab")
		)
		(fp_line
			(start -1.1049 0.724916)
			(end -1.1049 -0.724916)
			(stroke
				(width 0.1)
				(type default)
			)
			(layer "B.Fab")
		)
		(pad "1" smd rect
			(at 0.889 0 90)
			(size 1.016 1.27)
			(layers "B.Cu" "B.Mask" "B.Paste")
			(net "SW_P12V_AUX_PVDDCR_CPU1_P0_FLT")
		)
		(pad "2" smd rect
			(at -0.889 0 90)
			(size 1.016 1.27)
			(layers "B.Cu" "B.Mask" "B.Paste")
			(net "GND")
		)
	)
	(footprint ""
		(layer "B.Cu")
		(at 205.388972 -72.214994 180)
		(property "Reference" "R3215"
			(at 0 0 0)
			(layer "B.SilkS")
			(hide yes)
			(effects
				(font
					(size 1.27 1.27)
				)
				(justify mirror)
			)
		)
		(property "Value" ""
			(at 0 0 0)
			(layer "B.Fab")
			(effects
				(font
					(size 1.27 1.27)
				)
				(justify mirror)
			)
		)
		(duplicate_pad_numbers_are_jumpers no)
		(fp_line
			(start 0.7874 0.4064)
			(end 0.7874 -0.4064)
			(stroke
				(width 0.1524)
				(type default)
			)
			(layer "B.SilkS")
		)
		(fp_line
			(start 0.7874 -0.4064)
			(end -0.7874 -0.4064)
			(stroke
				(width 0.1524)
				(type default)
			)
			(layer "B.SilkS")
		)
		(fp_line
			(start -0.7874 0.4064)
			(end 0.7874 0.4064)
			(stroke
				(width 0.1524)
				(type default)
			)
			(layer "B.SilkS")
		)
		(fp_line
			(start -0.7874 -0.4064)
			(end -0.7874 0.4064)
			(stroke
				(width 0.1524)
				(type default)
			)
			(layer "B.SilkS")
		)
		(fp_line
			(start 0.67945 0.3048)
			(end 0.67945 -0.305054)
			(stroke
				(width 0.1)
				(type default)
			)
			(layer "B.Fab")
		)
		(fp_line
			(start 0.67945 -0.305054)
			(end 0.12065 -0.305054)
			(stroke
				(width 0.1)
				(type default)
			)
			(layer "B.Fab")
		)
		(fp_line
			(start 0.12065 0.3048)
			(end 0.67945 0.3048)
			(stroke
				(width 0.1)
				(type default)
			)
			(layer "B.Fab")
		)
		(fp_line
			(start 0.12065 0.2794)
			(end 0.12065 0.3048)
			(stroke
				(width 0.1)
				(type default)
			)
			(layer "B.Fab")
		)
		(fp_line
			(start 0.12065 -0.2794)
			(end -0.12065 -0.2794)
			(stroke
				(width 0.1)
				(type default)
			)
			(layer "B.Fab")
		)
		(fp_line
			(start 0.12065 -0.305054)
			(end 0.12065 -0.2794)
			(stroke
				(width 0.1)
				(type default)
			)
			(layer "B.Fab")
		)
		(fp_line
			(start -0.120396 0.3048)
			(end -0.120396 0.2794)
			(stroke
				(width 0.1)
				(type default)
			)
			(layer "B.Fab")
		)
		(fp_line
			(start -0.120396 0.2794)
			(end 0.12065 0.2794)
			(stroke
				(width 0.1)
				(type default)
			)
			(layer "B.Fab")
		)
		(fp_line
			(start -0.12065 -0.2794)
			(end -0.12065 -0.3048)
			(stroke
				(width 0.1)
				(type default)
			)
			(layer "B.Fab")
		)
		(fp_line
			(start -0.12065 -0.3048)
			(end -0.67945 -0.3048)
			(stroke
				(width 0.1)
				(type default)
			)
			(layer "B.Fab")
		)
		(fp_line
			(start -0.67945 0.3048)
			(end -0.120396 0.3048)
			(stroke
				(width 0.1)
				(type default)
			)
			(layer "B.Fab")
		)
		(fp_line
			(start -0.67945 -0.3048)
			(end -0.67945 0.3048)
			(stroke
				(width 0.1)
				(type default)
			)
			(layer "B.Fab")
		)
		(pad "1" smd circle
			(at 0.40005 0)
			(size 0 0)
			(layers "B.Cu" "B.Mask" "B.Paste")
			(net "NCSI_BMC_TXD1_R1")
		)
		(pad "2" smd circle
			(at -0.40005 0)
			(size 0 0)
			(layers "B.Cu" "B.Mask" "B.Paste")
			(net "RMII_BMC_OCP_TXD_1")
		)
	)
	(footprint ""
		(layer "B.Cu")
		(at 402.800566 -393.88288 -90)
		(property "Reference" "C779"
			(at 0 0 90)
			(layer "B.SilkS")
			(hide yes)
			(effects
				(font
					(size 1.27 1.27)
				)
				(justify mirror)
			)
		)
		(property "Value" ""
			(at 0 0 90)
			(layer "B.Fab")
			(effects
				(font
					(size 1.27 1.27)
				)
				(justify mirror)
			)
		)
		(duplicate_pad_numbers_are_jumpers no)
		(fp_line
			(start -0.299974 0.150114)
			(end 0.299974 0.150114)
			(stroke
				(width 0.1)
				(type default)
			)
			(layer "B.Fab")
		)
		(fp_line
			(start 0.299974 0.150114)
			(end 0.299974 -0.150114)
			(stroke
				(width 0.1)
				(type default)
			)
			(layer "B.Fab")
		)
		(fp_line
			(start -0.299974 -0.150114)
			(end -0.299974 0.150114)
			(stroke
				(width 0.1)
				(type default)
			)
			(layer "B.Fab")
		)
		(fp_line
			(start 0.299974 -0.150114)
			(end -0.299974 -0.150114)
			(stroke
				(width 0.1)
				(type default)
			)
			(layer "B.Fab")
		)
		(pad "1" smd rect
			(at 0.2667 0 90)
			(size 0.3048 0.381)
			(layers "B.Cu" "B.Mask" "B.Paste")
			(net "P0V9_CPU0_RT2_2A")
		)
		(pad "2" smd rect
			(at -0.2667 0 90)
			(size 0.3048 0.381)
			(layers "B.Cu" "B.Mask" "B.Paste")
			(net "GND")
		)
	)
	(footprint ""
		(layer "B.Cu")
		(at 171.20235 -120.233948 180)
		(property "Reference" "R6117"
			(at 0 0 0)
			(layer "B.SilkS")
			(hide yes)
			(effects
				(font
					(size 1.27 1.27)
				)
				(justify mirror)
			)
		)
		(property "Value" ""
			(at 0 0 0)
			(layer "B.Fab")
			(effects
				(font
					(size 1.27 1.27)
				)
				(justify mirror)
			)
		)
		(duplicate_pad_numbers_are_jumpers no)
		(fp_line
			(start 0.7874 0.4064)
			(end 0.7874 -0.4064)
			(stroke
				(width 0.1524)
				(type default)
			)
			(layer "B.SilkS")
		)
		(fp_line
			(start 0.7874 -0.4064)
			(end -0.7874 -0.4064)
			(stroke
				(width 0.1524)
				(type default)
			)
			(layer "B.SilkS")
		)
		(fp_line
			(start -0.7874 0.4064)
			(end 0.7874 0.4064)
			(stroke
				(width 0.1524)
				(type default)
			)
			(layer "B.SilkS")
		)
		(fp_line
			(start -0.7874 -0.4064)
			(end -0.7874 0.4064)
			(stroke
				(width 0.1524)
				(type default)
			)
			(layer "B.SilkS")
		)
		(fp_line
			(start 0.67945 0.3048)
			(end 0.67945 -0.305054)
			(stroke
				(width 0.1)
				(type default)
			)
			(layer "B.Fab")
		)
		(fp_line
			(start 0.67945 -0.305054)
			(end 0.12065 -0.305054)
			(stroke
				(width 0.1)
				(type default)
			)
			(layer "B.Fab")
		)
		(fp_line
			(start 0.12065 0.3048)
			(end 0.67945 0.3048)
			(stroke
				(width 0.1)
				(type default)
			)
			(layer "B.Fab")
		)
		(fp_line
			(start 0.12065 0.2794)
			(end 0.12065 0.3048)
			(stroke
				(width 0.1)
				(type default)
			)
			(layer "B.Fab")
		)
		(fp_line
			(start 0.12065 -0.2794)
			(end -0.12065 -0.2794)
			(stroke
				(width 0.1)
				(type default)
			)
			(layer "B.Fab")
		)
		(fp_line
			(start 0.12065 -0.305054)
			(end 0.12065 -0.2794)
			(stroke
				(width 0.1)
				(type default)
			)
			(layer "B.Fab")
		)
		(fp_line
			(start -0.120396 0.3048)
			(end -0.120396 0.2794)
			(stroke
				(width 0.1)
				(type default)
			)
			(layer "B.Fab")
		)
		(fp_line
			(start -0.120396 0.2794)
			(end 0.12065 0.2794)
			(stroke
				(width 0.1)
				(type default)
			)
			(layer "B.Fab")
		)
		(fp_line
			(start -0.12065 -0.2794)
			(end -0.12065 -0.3048)
			(stroke
				(width 0.1)
				(type default)
			)
			(layer "B.Fab")
		)
		(fp_line
			(start -0.12065 -0.3048)
			(end -0.67945 -0.3048)
			(stroke
				(width 0.1)
				(type default)
			)
			(layer "B.Fab")
		)
		(fp_line
			(start -0.67945 0.3048)
			(end -0.120396 0.3048)
			(stroke
				(width 0.1)
				(type default)
			)
			(layer "B.Fab")
		)
		(fp_line
			(start -0.67945 -0.3048)
			(end -0.67945 0.3048)
			(stroke
				(width 0.1)
				(type default)
			)
			(layer "B.Fab")
		)
		(pad "1" smd circle
			(at 0.40005 0)
			(size 0 0)
			(layers "B.Cu" "B.Mask" "B.Paste")
			(net "HP_LVC3_OCP_V3_2_PRSNT2_PLD_N")
		)
		(pad "2" smd circle
			(at -0.40005 0)
			(size 0 0)
			(layers "B.Cu" "B.Mask" "B.Paste")
			(net "PRSNT_OCP_V3_2_N")
		)
	)
	(footprint ""
		(layer "B.Cu")
		(at 286.004 -425.958 -90)
		(property "Reference" "R2670"
			(at 0 0 90)
			(layer "B.SilkS")
			(hide yes)
			(effects
				(font
					(size 1.27 1.27)
				)
				(justify mirror)
			)
		)
		(property "Value" ""
			(at 0 0 90)
			(layer "B.Fab")
			(effects
				(font
					(size 1.27 1.27)
				)
				(justify mirror)
			)
		)
		(duplicate_pad_numbers_are_jumpers no)
		(fp_line
			(start -0.7874 0.4064)
			(end 0.7874 0.4064)
			(stroke
				(width 0.1524)
				(type default)
			)
			(layer "B.SilkS")
		)
		(fp_line
			(start 0.7874 0.4064)
			(end 0.7874 -0.4064)
			(stroke
				(width 0.1524)
				(type default)
			)
			(layer "B.SilkS")
		)
		(fp_line
			(start -0.7874 -0.4064)
			(end -0.7874 0.4064)
			(stroke
				(width 0.1524)
				(type default)
			)
			(layer "B.SilkS")
		)
		(fp_line
			(start 0.7874 -0.4064)
			(end -0.7874 -0.4064)
			(stroke
				(width 0.1524)
				(type default)
			)
			(layer "B.SilkS")
		)
		(fp_line
			(start -0.67945 0.3048)
			(end -0.120396 0.3048)
			(stroke
				(width 0.1)
				(type default)
			)
			(layer "B.Fab")
		)
		(fp_line
			(start -0.120396 0.3048)
			(end -0.120396 0.2794)
			(stroke
				(width 0.1)
				(type default)
			)
			(layer "B.Fab")
		)
		(fp_line
			(start 0.12065 0.3048)
			(end 0.67945 0.3048)
			(stroke
				(width 0.1)
				(type default)
			)
			(layer "B.Fab")
		)
		(fp_line
			(start 0.67945 0.3048)
			(end 0.67945 -0.305054)
			(stroke
				(width 0.1)
				(type default)
			)
			(layer "B.Fab")
		)
		(fp_line
			(start -0.120396 0.2794)
			(end 0.12065 0.2794)
			(stroke
				(width 0.1)
				(type default)
			)
			(layer "B.Fab")
		)
		(fp_line
			(start 0.12065 0.2794)
			(end 0.12065 0.3048)
			(stroke
				(width 0.1)
				(type default)
			)
			(layer "B.Fab")
		)
		(fp_line
			(start -0.12065 -0.2794)
			(end -0.12065 -0.3048)
			(stroke
				(width 0.1)
				(type default)
			)
			(layer "B.Fab")
		)
		(fp_line
			(start 0.12065 -0.2794)
			(end -0.12065 -0.2794)
			(stroke
				(width 0.1)
				(type default)
			)
			(layer "B.Fab")
		)
		(fp_line
			(start -0.67945 -0.3048)
			(end -0.67945 0.3048)
			(stroke
				(width 0.1)
				(type default)
			)
			(layer "B.Fab")
		)
		(fp_line
			(start -0.12065 -0.3048)
			(end -0.67945 -0.3048)
			(stroke
				(width 0.1)
				(type default)
			)
			(layer "B.Fab")
		)
		(fp_line
			(start 0.12065 -0.305054)
			(end 0.12065 -0.2794)
			(stroke
				(width 0.1)
				(type default)
			)
			(layer "B.Fab")
		)
		(fp_line
			(start 0.67945 -0.305054)
			(end 0.12065 -0.305054)
			(stroke
				(width 0.1)
				(type default)
			)
			(layer "B.Fab")
		)
		(pad "1" smd circle
			(at 0.40005 0 90)
			(size 0 0)
			(layers "B.Cu" "B.Mask" "B.Paste")
			(net "P3V3_AUX")
		)
		(pad "2" smd circle
			(at -0.40005 0 90)
			(size 0 0)
			(layers "B.Cu" "B.Mask" "B.Paste")
			(net "I3C_BMC_SWB_BUF_R_SCL")
		)
	)
	(footprint ""
		(layer "B.Cu")
		(at 165.1508 -424.60037 -90)
		(property "Reference" "R1510"
			(at 0 0 90)
			(layer "B.SilkS")
			(hide yes)
			(effects
				(font
					(size 1.27 1.27)
				)
				(justify mirror)
			)
		)
		(property "Value" ""
			(at 0 0 90)
			(layer "B.Fab")
			(effects
				(font
					(size 1.27 1.27)
				)
				(justify mirror)
			)
		)
		(duplicate_pad_numbers_are_jumpers no)
		(fp_line
			(start -0.32512 0.175006)
			(end 0.32512 0.175006)
			(stroke
				(width 0.1)
				(type default)
			)
			(layer "B.Fab")
		)
		(fp_line
			(start 0.32512 0.175006)
			(end 0.32512 -0.175006)
			(stroke
				(width 0.1)
				(type default)
			)
			(layer "B.Fab")
		)
		(fp_line
			(start -0.32512 -0.175006)
			(end -0.32512 0.175006)
			(stroke
				(width 0.1)
				(type default)
			)
			(layer "B.Fab")
		)
		(fp_line
			(start 0.32512 -0.175006)
			(end -0.32512 -0.175006)
			(stroke
				(width 0.1)
				(type default)
			)
			(layer "B.Fab")
		)
		(pad "1" smd rect
			(at 0.2667 0 90)
			(size 0.3048 0.381)
			(layers "B.Cu" "B.Mask" "B.Paste")
			(net "P1V8_CPU1_RT_1D")
		)
		(pad "2" smd rect
			(at -0.2667 0 270)
			(size 0.3048 0.381)
			(layers "B.Cu" "B.Mask" "B.Paste")
			(net "JTAG_TDI_RT_CPU1_P3")
		)
	)
	(footprint ""
		(layer "B.Cu")
		(at 64.595248 -168.86682 -90)
		(property "Reference" "PC130_6"
			(at 0 0 90)
			(layer "B.SilkS")
			(hide yes)
			(effects
				(font
					(size 1.27 1.27)
				)
				(justify mirror)
			)
		)
		(property "Value" ""
			(at 0 0 90)
			(layer "B.Fab")
			(effects
				(font
					(size 1.27 1.27)
				)
				(justify mirror)
			)
		)
		(duplicate_pad_numbers_are_jumpers no)
		(fp_line
			(start -1.524 0.762)
			(end 1.524 0.762)
			(stroke
				(width 0.1524)
				(type default)
			)
			(layer "B.SilkS")
		)
		(fp_line
			(start 1.524 0.762)
			(end 1.524 -0.762)
			(stroke
				(width 0.1524)
				(type default)
			)
			(layer "B.SilkS")
		)
		(fp_line
			(start -1.524 -0.762)
			(end -1.524 0.762)
			(stroke
				(width 0.1524)
				(type default)
			)
			(layer "B.SilkS")
		)
		(fp_line
			(start 1.524 -0.762)
			(end -1.524 -0.762)
			(stroke
				(width 0.1524)
				(type default)
			)
			(layer "B.SilkS")
		)
		(fp_line
			(start -1.1049 0.724916)
			(end -1.1049 -0.724916)
			(stroke
				(width 0.1)
				(type default)
			)
			(layer "B.Fab")
		)
		(fp_line
			(start 1.1049 0.724916)
			(end -1.1049 0.724916)
			(stroke
				(width 0.1)
				(type default)
			)
			(layer "B.Fab")
		)
		(fp_line
			(start -1.1049 -0.724916)
			(end 1.1049 -0.724916)
			(stroke
				(width 0.1)
				(type default)
			)
			(layer "B.Fab")
		)
		(fp_line
			(start 1.1049 -0.724916)
			(end 1.1049 0.724916)
			(stroke
				(width 0.1)
				(type default)
			)
			(layer "B.Fab")
		)
		(pad "1" smd rect
			(at 0.889 0 270)
			(size 1.016 1.27)
			(layers "B.Cu" "B.Mask" "B.Paste")
			(net "SW_P12V_AUX_PVDDCR_CPU0_P1_FLT")
		)
		(pad "2" smd rect
			(at -0.889 0 270)
			(size 1.016 1.27)
			(layers "B.Cu" "B.Mask" "B.Paste")
			(net "GND")
		)
	)
	(footprint ""
		(layer "B.Cu")
		(at 219.082112 -67.661028 -90)
		(property "Reference" "R3959"
			(at 0 0 90)
			(layer "B.SilkS")
			(hide yes)
			(effects
				(font
					(size 1.27 1.27)
				)
				(justify mirror)
			)
		)
		(property "Value" ""
			(at 0 0 90)
			(layer "B.Fab")
			(effects
				(font
					(size 1.27 1.27)
				)
				(justify mirror)
			)
		)
		(duplicate_pad_numbers_are_jumpers no)
		(fp_line
			(start -0.7874 0.4064)
			(end 0.7874 0.4064)
			(stroke
				(width 0.1524)
				(type default)
			)
			(layer "B.SilkS")
		)
		(fp_line
			(start 0.7874 0.4064)
			(end 0.7874 -0.4064)
			(stroke
				(width 0.1524)
				(type default)
			)
			(layer "B.SilkS")
		)
		(fp_line
			(start -0.7874 -0.4064)
			(end -0.7874 0.4064)
			(stroke
				(width 0.1524)
				(type default)
			)
			(layer "B.SilkS")
		)
		(fp_line
			(start 0.7874 -0.4064)
			(end -0.7874 -0.4064)
			(stroke
				(width 0.1524)
				(type default)
			)
			(layer "B.SilkS")
		)
		(fp_line
			(start -0.67945 0.3048)
			(end -0.120396 0.3048)
			(stroke
				(width 0.1)
				(type default)
			)
			(layer "B.Fab")
		)
		(fp_line
			(start -0.120396 0.3048)
			(end -0.120396 0.2794)
			(stroke
				(width 0.1)
				(type default)
			)
			(layer "B.Fab")
		)
		(fp_line
			(start 0.12065 0.3048)
			(end 0.67945 0.3048)
			(stroke
				(width 0.1)
				(type default)
			)
			(layer "B.Fab")
		)
		(fp_line
			(start 0.67945 0.3048)
			(end 0.67945 -0.305054)
			(stroke
				(width 0.1)
				(type default)
			)
			(layer "B.Fab")
		)
		(fp_line
			(start -0.120396 0.2794)
			(end 0.12065 0.2794)
			(stroke
				(width 0.1)
				(type default)
			)
			(layer "B.Fab")
		)
		(fp_line
			(start 0.12065 0.2794)
			(end 0.12065 0.3048)
			(stroke
				(width 0.1)
				(type default)
			)
			(layer "B.Fab")
		)
		(fp_line
			(start -0.12065 -0.2794)
			(end -0.12065 -0.3048)
			(stroke
				(width 0.1)
				(type default)
			)
			(layer "B.Fab")
		)
		(fp_line
			(start 0.12065 -0.2794)
			(end -0.12065 -0.2794)
			(stroke
				(width 0.1)
				(type default)
			)
			(layer "B.Fab")
		)
		(fp_line
			(start -0.67945 -0.3048)
			(end -0.67945 0.3048)
			(stroke
				(width 0.1)
				(type default)
			)
			(layer "B.Fab")
		)
		(fp_line
			(start -0.12065 -0.3048)
			(end -0.67945 -0.3048)
			(stroke
				(width 0.1)
				(type default)
			)
			(layer "B.Fab")
		)
		(fp_line
			(start 0.12065 -0.305054)
			(end 0.12065 -0.2794)
			(stroke
				(width 0.1)
				(type default)
			)
			(layer "B.Fab")
		)
		(fp_line
			(start 0.67945 -0.305054)
			(end 0.12065 -0.305054)
			(stroke
				(width 0.1)
				(type default)
			)
			(layer "B.Fab")
		)
		(pad "1" smd circle
			(at 0.40005 0 90)
			(size 0 0)
			(layers "B.Cu" "B.Mask" "B.Paste")
			(net "P3V3_E1S_UV_0_R")
		)
		(pad "2" smd circle
			(at -0.40005 0 90)
			(size 0 0)
			(layers "B.Cu" "B.Mask" "B.Paste")
			(net "P3V3_E1S_UV_0")
		)
	)
	(footprint ""
		(layer "B.Cu")
		(at 105.596182 -386.745988 -90)
		(property "Reference" "C200"
			(at 0 0 90)
			(layer "B.SilkS")
			(hide yes)
			(effects
				(font
					(size 1.27 1.27)
				)
				(justify mirror)
			)
		)
		(property "Value" ""
			(at 0 0 90)
			(layer "B.Fab")
			(effects
				(font
					(size 1.27 1.27)
				)
				(justify mirror)
			)
		)
		(duplicate_pad_numbers_are_jumpers no)
		(fp_line
			(start -0.7874 0.4064)
			(end 0.7874 0.4064)
			(stroke
				(width 0.1524)
				(type default)
			)
			(layer "B.SilkS")
		)
		(fp_line
			(start 0.7874 0.4064)
			(end 0.7874 -0.4064)
			(stroke
				(width 0.1524)
				(type default)
			)
			(layer "B.SilkS")
		)
		(fp_line
			(start -0.7874 -0.4064)
			(end -0.7874 0.4064)
			(stroke
				(width 0.1524)
				(type default)
			)
			(layer "B.SilkS")
		)
		(fp_line
			(start 0.7874 -0.4064)
			(end -0.7874 -0.4064)
			(stroke
				(width 0.1524)
				(type default)
			)
			(layer "B.SilkS")
		)
		(fp_line
			(start -0.67945 0.3048)
			(end -0.120396 0.3048)
			(stroke
				(width 0.1)
				(type default)
			)
			(layer "B.Fab")
		)
		(fp_line
			(start -0.120396 0.3048)
			(end -0.120396 0.2794)
			(stroke
				(width 0.1)
				(type default)
			)
			(layer "B.Fab")
		)
		(fp_line
			(start 0.12065 0.3048)
			(end 0.67945 0.3048)
			(stroke
				(width 0.1)
				(type default)
			)
			(layer "B.Fab")
		)
		(fp_line
			(start 0.67945 0.3048)
			(end 0.67945 -0.305054)
			(stroke
				(width 0.1)
				(type default)
			)
			(layer "B.Fab")
		)
		(fp_line
			(start -0.120396 0.2794)
			(end 0.12065 0.2794)
			(stroke
				(width 0.1)
				(type default)
			)
			(layer "B.Fab")
		)
		(fp_line
			(start 0.12065 0.2794)
			(end 0.12065 0.3048)
			(stroke
				(width 0.1)
				(type default)
			)
			(layer "B.Fab")
		)
		(fp_line
			(start -0.12065 -0.2794)
			(end -0.12065 -0.3048)
			(stroke
				(width 0.1)
				(type default)
			)
			(layer "B.Fab")
		)
		(fp_line
			(start 0.12065 -0.2794)
			(end -0.12065 -0.2794)
			(stroke
				(width 0.1)
				(type default)
			)
			(layer "B.Fab")
		)
		(fp_line
			(start -0.67945 -0.3048)
			(end -0.67945 0.3048)
			(stroke
				(width 0.1)
				(type default)
			)
			(layer "B.Fab")
		)
		(fp_line
			(start -0.12065 -0.3048)
			(end -0.67945 -0.3048)
			(stroke
				(width 0.1)
				(type default)
			)
			(layer "B.Fab")
		)
		(fp_line
			(start 0.12065 -0.305054)
			(end 0.12065 -0.2794)
			(stroke
				(width 0.1)
				(type default)
			)
			(layer "B.Fab")
		)
		(fp_line
			(start 0.67945 -0.305054)
			(end 0.12065 -0.305054)
			(stroke
				(width 0.1)
				(type default)
			)
			(layer "B.Fab")
		)
		(pad "1" smd circle
			(at 0.40005 0 90)
			(size 0 0)
			(layers "B.Cu" "B.Mask" "B.Paste")
			(net "P1V8_CPU1_RT_1D")
		)
		(pad "2" smd circle
			(at -0.40005 0 90)
			(size 0 0)
			(layers "B.Cu" "B.Mask" "B.Paste")
			(net "GND")
		)
	)
	(footprint ""
		(layer "B.Cu")
		(at 237.617 -250.571)
		(property "Reference" "R363"
			(at 0 0 0)
			(layer "B.SilkS")
			(hide yes)
			(effects
				(font
					(size 1.27 1.27)
				)
				(justify mirror)
			)
		)
		(property "Value" ""
			(at 0 0 0)
			(layer "B.Fab")
			(effects
				(font
					(size 1.27 1.27)
				)
				(justify mirror)
			)
		)
		(duplicate_pad_numbers_are_jumpers no)
		(fp_line
			(start -0.7874 -0.4064)
			(end -0.7874 0.4064)
			(stroke
				(width 0.1524)
				(type default)
			)
			(layer "B.SilkS")
		)
		(fp_line
			(start -0.7874 0.4064)
			(end 0.7874 0.4064)
			(stroke
				(width 0.1524)
				(type default)
			)
			(layer "B.SilkS")
		)
		(fp_line
			(start 0.7874 -0.4064)
			(end -0.7874 -0.4064)
			(stroke
				(width 0.1524)
				(type default)
			)
			(layer "B.SilkS")
		)
		(fp_line
			(start 0.7874 0.4064)
			(end 0.7874 -0.4064)
			(stroke
				(width 0.1524)
				(type default)
			)
			(layer "B.SilkS")
		)
		(fp_line
			(start -0.67945 -0.3048)
			(end -0.67945 0.3048)
			(stroke
				(width 0.1)
				(type default)
			)
			(layer "B.Fab")
		)
		(fp_line
			(start -0.67945 0.3048)
			(end -0.120396 0.3048)
			(stroke
				(width 0.1)
				(type default)
			)
			(layer "B.Fab")
		)
		(fp_line
			(start -0.12065 -0.3048)
			(end -0.67945 -0.3048)
			(stroke
				(width 0.1)
				(type default)
			)
			(layer "B.Fab")
		)
		(fp_line
			(start -0.12065 -0.2794)
			(end -0.12065 -0.3048)
			(stroke
				(width 0.1)
				(type default)
			)
			(layer "B.Fab")
		)
		(fp_line
			(start -0.120396 0.2794)
			(end 0.12065 0.2794)
			(stroke
				(width 0.1)
				(type default)
			)
			(layer "B.Fab")
		)
		(fp_line
			(start -0.120396 0.3048)
			(end -0.120396 0.2794)
			(stroke
				(width 0.1)
				(type default)
			)
			(layer "B.Fab")
		)
		(fp_line
			(start 0.12065 -0.305054)
			(end 0.12065 -0.2794)
			(stroke
				(width 0.1)
				(type default)
			)
			(layer "B.Fab")
		)
		(fp_line
			(start 0.12065 -0.2794)
			(end -0.12065 -0.2794)
			(stroke
				(width 0.1)
				(type default)
			)
			(layer "B.Fab")
		)
		(fp_line
			(start 0.12065 0.2794)
			(end 0.12065 0.3048)
			(stroke
				(width 0.1)
				(type default)
			)
			(layer "B.Fab")
		)
		(fp_line
			(start 0.12065 0.3048)
			(end 0.67945 0.3048)
			(stroke
				(width 0.1)
				(type default)
			)
			(layer "B.Fab")
		)
		(fp_line
			(start 0.67945 -0.305054)
			(end 0.12065 -0.305054)
			(stroke
				(width 0.1)
				(type default)
			)
			(layer "B.Fab")
		)
		(fp_line
			(start 0.67945 0.3048)
			(end 0.67945 -0.305054)
			(stroke
				(width 0.1)
				(type default)
			)
			(layer "B.Fab")
		)
		(pad "1" smd circle
			(at 0.40005 0 180)
			(size 0 0)
			(layers "B.Cu" "B.Mask" "B.Paste")
			(net "PVDD11_S3_P0")
		)
		(pad "2" smd circle
			(at -0.40005 0 180)
			(size 0 0)
			(layers "B.Cu" "B.Mask" "B.Paste")
			(net "SMB_APML_CPU0_SCL")
		)
	)
	(footprint ""
		(layer "B.Cu")
		(at 182.948834 -344.199972 -90)
		(property "Reference" "PC525"
			(at 7.610856 -3.388106 270)
			(unlocked yes)
			(layer "B.SilkS")
			(effects
				(font
					(size 0.7874 0.5842)
					(thickness 0.1524)
				)
				(justify left mirror)
			)
		)
		(property "Value" ""
			(at 0 0 90)
			(layer "B.Fab")
			(effects
				(font
					(size 1.27 1.27)
				)
				(justify mirror)
			)
		)
		(duplicate_pad_numbers_are_jumpers no)
		(fp_line
			(start -4.533392 2.249932)
			(end 4.533392 2.249932)
			(stroke
				(width 0.1524)
				(type default)
			)
			(layer "B.SilkS")
		)
		(fp_line
			(start 4.533392 2.249932)
			(end 4.533392 -2.249932)
			(stroke
				(width 0.1524)
				(type default)
			)
			(layer "B.SilkS")
		)
		(fp_line
			(start -4.533392 -2.249932)
			(end -4.533392 2.249932)
			(stroke
				(width 0.1524)
				(type default)
			)
			(layer "B.SilkS")
		)
		(fp_line
			(start 4.533392 -2.249932)
			(end -4.533392 -2.249932)
			(stroke
				(width 0.1524)
				(type default)
			)
			(layer "B.SilkS")
		)
		(fp_rect
			(start 5.39242 2.326132)
			(end 4.533392 -2.326132)
			(stroke
				(width 0)
				(type default)
			)
			(fill yes)
			(layer "B.SilkS")
		)
		(fp_line
			(start -3.750056 2.249932)
			(end 3.750056 2.249932)
			(stroke
				(width 0.1)
				(type default)
			)
			(layer "B.Fab")
		)
		(fp_line
			(start 3.750056 2.249932)
			(end 3.750056 -2.249932)
			(stroke
				(width 0.1)
				(type default)
			)
			(layer "B.Fab")
		)
		(fp_line
			(start -3.750056 -2.249932)
			(end -3.750056 2.249932)
			(stroke
				(width 0.1)
				(type default)
			)
			(layer "B.Fab")
		)
		(fp_line
			(start 3.750056 -2.249932)
			(end -3.750056 -2.249932)
			(stroke
				(width 0.1)
				(type default)
			)
			(layer "B.Fab")
		)
		(fp_text user "-"
			(at -4.658868 2.486914 270)
			(unlocked yes)
			(layer "B.SilkS")
			(effects
				(font
					(size 1.905 1.4224)
					(thickness 0.1524)
				)
				(justify left mirror)
			)
		)
		(fp_text user "+"
			(at 6.322314 0.786384 180)
			(unlocked yes)
			(layer "B.SilkS")
			(effects
				(font
					(size 1.905 1.4224)
					(thickness 0.1524)
				)
				(justify left mirror)
			)
		)
		(fp_text user "+"
			(at 6.322314 0.786384 180)
			(unlocked yes)
			(layer "B.Fab")
			(effects
				(font
					(size 1.905 1.4224)
					(thickness 0.1524)
				)
				(justify left mirror)
			)
		)
		(fp_text user "-"
			(at -4.8514 -0.14605 270)
			(unlocked yes)
			(layer "B.Fab")
			(effects
				(font
					(size 1.905 1.4224)
					(thickness 0.1524)
				)
				(justify left mirror)
			)
		)
		(pad "1" smd rect
			(at 3.199892 0 90)
			(size 2.413 2.8194)
			(layers "B.Cu" "B.Mask" "B.Paste")
			(net "PVDD11_S3_P1")
		)
		(pad "2" smd rect
			(at -3.199892 0 90)
			(size 2.413 2.8194)
			(layers "B.Cu" "B.Mask" "B.Paste")
			(net "GND")
		)
	)
	(footprint ""
		(layer "B.Cu")
		(at 408.45867 -167.53459 90)
		(property "Reference" "PR357"
			(at 0 0 90)
			(layer "B.SilkS")
			(hide yes)
			(effects
				(font
					(size 1.27 1.27)
				)
				(justify mirror)
			)
		)
		(property "Value" ""
			(at 0 0 90)
			(layer "B.Fab")
			(effects
				(font
					(size 1.27 1.27)
				)
				(justify mirror)
			)
		)
		(duplicate_pad_numbers_are_jumpers no)
		(fp_line
			(start 0.7874 -0.4064)
			(end -0.7874 -0.4064)
			(stroke
				(width 0.1524)
				(type default)
			)
			(layer "B.SilkS")
		)
		(fp_line
			(start -0.7874 -0.4064)
			(end -0.7874 0.4064)
			(stroke
				(width 0.1524)
				(type default)
			)
			(layer "B.SilkS")
		)
		(fp_line
			(start 0.7874 0.4064)
			(end 0.7874 -0.4064)
			(stroke
				(width 0.1524)
				(type default)
			)
			(layer "B.SilkS")
		)
		(fp_line
			(start -0.7874 0.4064)
			(end 0.7874 0.4064)
			(stroke
				(width 0.1524)
				(type default)
			)
			(layer "B.SilkS")
		)
		(fp_line
			(start 0.67945 -0.305054)
			(end 0.12065 -0.305054)
			(stroke
				(width 0.1)
				(type default)
			)
			(layer "B.Fab")
		)
		(fp_line
			(start 0.12065 -0.305054)
			(end 0.12065 -0.2794)
			(stroke
				(width 0.1)
				(type default)
			)
			(layer "B.Fab")
		)
		(fp_line
			(start -0.12065 -0.3048)
			(end -0.67945 -0.3048)
			(stroke
				(width 0.1)
				(type default)
			)
			(layer "B.Fab")
		)
		(fp_line
			(start -0.67945 -0.3048)
			(end -0.67945 0.3048)
			(stroke
				(width 0.1)
				(type default)
			)
			(layer "B.Fab")
		)
		(fp_line
			(start 0.12065 -0.2794)
			(end -0.12065 -0.2794)
			(stroke
				(width 0.1)
				(type default)
			)
			(layer "B.Fab")
		)
		(fp_line
			(start -0.12065 -0.2794)
			(end -0.12065 -0.3048)
			(stroke
				(width 0.1)
				(type default)
			)
			(layer "B.Fab")
		)
		(fp_line
			(start 0.12065 0.2794)
			(end 0.12065 0.3048)
			(stroke
				(width 0.1)
				(type default)
			)
			(layer "B.Fab")
		)
		(fp_line
			(start -0.120396 0.2794)
			(end 0.12065 0.2794)
			(stroke
				(width 0.1)
				(type default)
			)
			(layer "B.Fab")
		)
		(fp_line
			(start 0.67945 0.3048)
			(end 0.67945 -0.305054)
			(stroke
				(width 0.1)
				(type default)
			)
			(layer "B.Fab")
		)
		(fp_line
			(start 0.12065 0.3048)
			(end 0.67945 0.3048)
			(stroke
				(width 0.1)
				(type default)
			)
			(layer "B.Fab")
		)
		(fp_line
			(start -0.120396 0.3048)
			(end -0.120396 0.2794)
			(stroke
				(width 0.1)
				(type default)
			)
			(layer "B.Fab")
		)
		(fp_line
			(start -0.67945 0.3048)
			(end -0.120396 0.3048)
			(stroke
				(width 0.1)
				(type default)
			)
			(layer "B.Fab")
		)
		(pad "1" smd circle
			(at 0.40005 0 270)
			(size 0 0)
			(layers "B.Cu" "B.Mask" "B.Paste")
			(net "PVDDCR_CPU0_P0_PVCC")
		)
		(pad "2" smd circle
			(at -0.40005 0 270)
			(size 0 0)
			(layers "B.Cu" "B.Mask" "B.Paste")
			(net "PVDDCR_SOC_P0_VCC2")
		)
	)
	(footprint ""
		(layer "B.Cu")
		(at 71.530718 -338.939632 -90)
		(property "Reference" "PC410_3"
			(at 0 0 90)
			(layer "B.SilkS")
			(hide yes)
			(effects
				(font
					(size 1.27 1.27)
				)
				(justify mirror)
			)
		)
		(property "Value" ""
			(at 0 0 90)
			(layer "B.Fab")
			(effects
				(font
					(size 1.27 1.27)
				)
				(justify mirror)
			)
		)
		(duplicate_pad_numbers_are_jumpers no)
		(fp_line
			(start -1.524 0.762)
			(end 1.524 0.762)
			(stroke
				(width 0.1524)
				(type default)
			)
			(layer "B.SilkS")
		)
		(fp_line
			(start 1.524 0.762)
			(end 1.524 -0.762)
			(stroke
				(width 0.1524)
				(type default)
			)
			(layer "B.SilkS")
		)
		(fp_line
			(start -1.524 -0.762)
			(end -1.524 0.762)
			(stroke
				(width 0.1524)
				(type default)
			)
			(layer "B.SilkS")
		)
		(fp_line
			(start 1.524 -0.762)
			(end -1.524 -0.762)
			(stroke
				(width 0.1524)
				(type default)
			)
			(layer "B.SilkS")
		)
		(fp_line
			(start -1.1049 0.724916)
			(end -1.1049 -0.724916)
			(stroke
				(width 0.1)
				(type default)
			)
			(layer "B.Fab")
		)
		(fp_line
			(start 1.1049 0.724916)
			(end -1.1049 0.724916)
			(stroke
				(width 0.1)
				(type default)
			)
			(layer "B.Fab")
		)
		(fp_line
			(start -1.1049 -0.724916)
			(end 1.1049 -0.724916)
			(stroke
				(width 0.1)
				(type default)
			)
			(layer "B.Fab")
		)
		(fp_line
			(start 1.1049 -0.724916)
			(end 1.1049 0.724916)
			(stroke
				(width 0.1)
				(type default)
			)
			(layer "B.Fab")
		)
		(pad "1" smd rect
			(at 0.889 0 270)
			(size 1.016 1.27)
			(layers "B.Cu" "B.Mask" "B.Paste")
			(net "SW_P12V_AUX_PVDDCR_CPU1_P1_FLT")
		)
		(pad "2" smd rect
			(at -0.889 0 270)
			(size 1.016 1.27)
			(layers "B.Cu" "B.Mask" "B.Paste")
			(net "GND")
		)
	)
	(footprint ""
		(layer "B.Cu")
		(at 111.17834 -62.01791 -90)
		(property "Reference" "R6224"
			(at 0 0 90)
			(layer "B.SilkS")
			(hide yes)
			(effects
				(font
					(size 1.27 1.27)
				)
				(justify mirror)
			)
		)
		(property "Value" ""
			(at 0 0 90)
			(layer "B.Fab")
			(effects
				(font
					(size 1.27 1.27)
				)
				(justify mirror)
			)
		)
		(duplicate_pad_numbers_are_jumpers no)
		(fp_line
			(start -0.7874 0.4064)
			(end 0.7874 0.4064)
			(stroke
				(width 0.1524)
				(type default)
			)
			(layer "B.SilkS")
		)
		(fp_line
			(start 0.7874 0.4064)
			(end 0.7874 -0.4064)
			(stroke
				(width 0.1524)
				(type default)
			)
			(layer "B.SilkS")
		)
		(fp_line
			(start -0.7874 -0.4064)
			(end -0.7874 0.4064)
			(stroke
				(width 0.1524)
				(type default)
			)
			(layer "B.SilkS")
		)
		(fp_line
			(start 0.7874 -0.4064)
			(end -0.7874 -0.4064)
			(stroke
				(width 0.1524)
				(type default)
			)
			(layer "B.SilkS")
		)
		(fp_line
			(start -0.67945 0.3048)
			(end -0.120396 0.3048)
			(stroke
				(width 0.1)
				(type default)
			)
			(layer "B.Fab")
		)
		(fp_line
			(start -0.120396 0.3048)
			(end -0.120396 0.2794)
			(stroke
				(width 0.1)
				(type default)
			)
			(layer "B.Fab")
		)
		(fp_line
			(start 0.12065 0.3048)
			(end 0.67945 0.3048)
			(stroke
				(width 0.1)
				(type default)
			)
			(layer "B.Fab")
		)
		(fp_line
			(start 0.67945 0.3048)
			(end 0.67945 -0.305054)
			(stroke
				(width 0.1)
				(type default)
			)
			(layer "B.Fab")
		)
		(fp_line
			(start -0.120396 0.2794)
			(end 0.12065 0.2794)
			(stroke
				(width 0.1)
				(type default)
			)
			(layer "B.Fab")
		)
		(fp_line
			(start 0.12065 0.2794)
			(end 0.12065 0.3048)
			(stroke
				(width 0.1)
				(type default)
			)
			(layer "B.Fab")
		)
		(fp_line
			(start -0.12065 -0.2794)
			(end -0.12065 -0.3048)
			(stroke
				(width 0.1)
				(type default)
			)
			(layer "B.Fab")
		)
		(fp_line
			(start 0.12065 -0.2794)
			(end -0.12065 -0.2794)
			(stroke
				(width 0.1)
				(type default)
			)
			(layer "B.Fab")
		)
		(fp_line
			(start -0.67945 -0.3048)
			(end -0.67945 0.3048)
			(stroke
				(width 0.1)
				(type default)
			)
			(layer "B.Fab")
		)
		(fp_line
			(start -0.12065 -0.3048)
			(end -0.67945 -0.3048)
			(stroke
				(width 0.1)
				(type default)
			)
			(layer "B.Fab")
		)
		(fp_line
			(start 0.12065 -0.305054)
			(end 0.12065 -0.2794)
			(stroke
				(width 0.1)
				(type default)
			)
			(layer "B.Fab")
		)
		(fp_line
			(start 0.67945 -0.305054)
			(end 0.12065 -0.305054)
			(stroke
				(width 0.1)
				(type default)
			)
			(layer "B.Fab")
		)
		(pad "1" smd circle
			(at 0.40005 0 90)
			(size 0 0)
			(layers "B.Cu" "B.Mask" "B.Paste")
			(net "SMB_USB_CPU0_HUB1_SCL")
		)
		(pad "2" smd circle
			(at -0.40005 0 90)
			(size 0 0)
			(layers "B.Cu" "B.Mask" "B.Paste")
			(net "SMB_USB_CPU0_HUB1_SCL_R2")
		)
	)
	(footprint ""
		(layer "B.Cu")
		(at 201.041 -140.462 90)
		(property "Reference" "U8004"
			(at -2.036826 -2.62509 270)
			(unlocked yes)
			(layer "B.SilkS")
			(effects
				(font
					(size 0.7874 0.5842)
					(thickness 0.1524)
				)
				(justify left mirror)
			)
		)
		(property "Value" ""
			(at 0 0 90)
			(layer "B.Fab")
			(effects
				(font
					(size 1.27 1.27)
				)
				(justify mirror)
			)
		)
		(duplicate_pad_numbers_are_jumpers no)
		(fp_line
			(start 1.38176 -1.100074)
			(end 1.38176 1.100074)
			(stroke
				(width 0.1524)
				(type default)
			)
			(layer "B.SilkS")
		)
		(fp_line
			(start 0.592074 -1.100074)
			(end 1.38176 -1.100074)
			(stroke
				(width 0.1524)
				(type default)
			)
			(layer "B.SilkS")
		)
		(fp_line
			(start -0.592074 -1.100074)
			(end 0 -0.508)
			(stroke
				(width 0.1524)
				(type default)
			)
			(layer "B.SilkS")
		)
		(fp_line
			(start -1.38176 -1.100074)
			(end -0.592074 -1.100074)
			(stroke
				(width 0.1524)
				(type default)
			)
			(layer "B.SilkS")
		)
		(fp_line
			(start 0 -0.508)
			(end 0.592074 -1.100074)
			(stroke
				(width 0.1524)
				(type default)
			)
			(layer "B.SilkS")
		)
		(fp_line
			(start 1.38176 1.100074)
			(end -1.38176 1.100074)
			(stroke
				(width 0.1524)
				(type default)
			)
			(layer "B.SilkS")
		)
		(fp_line
			(start -1.38176 1.100074)
			(end -1.38176 -1.100074)
			(stroke
				(width 0.1524)
				(type default)
			)
			(layer "B.SilkS")
		)
		(fp_poly
			(pts
				(xy 1.9431 -0.870204) (xy 1.50241 -0.649986) (xy 1.9431 -0.429768)
			)
			(stroke
				(width 0)
				(type default)
			)
			(fill yes)
			(layer "B.SilkS")
		)
		(fp_line
			(start 0.674878 -1.100074)
			(end 0.674878 1.100074)
			(stroke
				(width 0.1)
				(type default)
			)
			(layer "B.Fab")
		)
		(fp_line
			(start -0.674878 -1.100074)
			(end 0.674878 -1.100074)
			(stroke
				(width 0.1)
				(type default)
			)
			(layer "B.Fab")
		)
		(fp_line
			(start 0.674878 1.100074)
			(end -0.674878 1.100074)
			(stroke
				(width 0.1)
				(type default)
			)
			(layer "B.Fab")
		)
		(fp_line
			(start -0.674878 1.100074)
			(end -0.674878 -1.100074)
			(stroke
				(width 0.1)
				(type default)
			)
			(layer "B.Fab")
		)
		(fp_poly
			(pts
				(xy 1.9431 -0.870204) (xy 1.50241 -0.649986) (xy 1.9431 -0.429768)
			)
			(stroke
				(width 0)
				(type default)
			)
			(fill yes)
			(layer "B.Fab")
		)
		(pad "1" smd rect
			(at 0.94996 -0.649986)
			(size 0.4318 0.6096)
			(layers "B.Cu" "B.Mask" "B.Paste")
			(net "FM_AC_PWR_BTN_PLD_N")
		)
		(pad "2" smd rect
			(at 0.94996 0)
			(size 0.4318 0.6096)
			(layers "B.Cu" "B.Mask" "B.Paste")
			(net "GND")
		)
		(pad "3" smd rect
			(at 0.94996 0.649986)
			(size 0.4318 0.6096)
			(layers "B.Cu" "B.Mask" "B.Paste")
			(net "GND")
		)
		(pad "4" smd rect
			(at -0.94996 0.649986)
			(size 0.4318 0.6096)
			(layers "B.Cu" "B.Mask" "B.Paste")
			(net "NC_U8004_2Y")
		)
		(pad "5" smd rect
			(at -0.94996 0)
			(size 0.4318 0.6096)
			(layers "B.Cu" "B.Mask" "B.Paste")
			(net "P3V3_AUX")
		)
		(pad "6" smd rect
			(at -0.94996 -0.649986)
			(size 0.4318 0.6096)
			(layers "B.Cu" "B.Mask" "B.Paste")
			(net "FM_AC_PWR_BTN_PLD_ISO_R_N")
		)
	)
	(footprint ""
		(layer "B.Cu")
		(at 428.98695 -41.087548)
		(property "Reference" "R6044"
			(at 0 0 0)
			(layer "B.SilkS")
			(hide yes)
			(effects
				(font
					(size 1.27 1.27)
				)
				(justify mirror)
			)
		)
		(property "Value" ""
			(at 0 0 0)
			(layer "B.Fab")
			(effects
				(font
					(size 1.27 1.27)
				)
				(justify mirror)
			)
		)
		(duplicate_pad_numbers_are_jumpers no)
		(fp_line
			(start -0.7874 -0.4064)
			(end -0.7874 0.4064)
			(stroke
				(width 0.1524)
				(type default)
			)
			(layer "B.SilkS")
		)
		(fp_line
			(start -0.7874 0.4064)
			(end 0.7874 0.4064)
			(stroke
				(width 0.1524)
				(type default)
			)
			(layer "B.SilkS")
		)
		(fp_line
			(start 0.7874 -0.4064)
			(end -0.7874 -0.4064)
			(stroke
				(width 0.1524)
				(type default)
			)
			(layer "B.SilkS")
		)
		(fp_line
			(start 0.7874 0.4064)
			(end 0.7874 -0.4064)
			(stroke
				(width 0.1524)
				(type default)
			)
			(layer "B.SilkS")
		)
		(fp_line
			(start -0.67945 -0.3048)
			(end -0.67945 0.3048)
			(stroke
				(width 0.1)
				(type default)
			)
			(layer "B.Fab")
		)
		(fp_line
			(start -0.67945 0.3048)
			(end -0.120396 0.3048)
			(stroke
				(width 0.1)
				(type default)
			)
			(layer "B.Fab")
		)
		(fp_line
			(start -0.12065 -0.3048)
			(end -0.67945 -0.3048)
			(stroke
				(width 0.1)
				(type default)
			)
			(layer "B.Fab")
		)
		(fp_line
			(start -0.12065 -0.2794)
			(end -0.12065 -0.3048)
			(stroke
				(width 0.1)
				(type default)
			)
			(layer "B.Fab")
		)
		(fp_line
			(start -0.120396 0.2794)
			(end 0.12065 0.2794)
			(stroke
				(width 0.1)
				(type default)
			)
			(layer "B.Fab")
		)
		(fp_line
			(start -0.120396 0.3048)
			(end -0.120396 0.2794)
			(stroke
				(width 0.1)
				(type default)
			)
			(layer "B.Fab")
		)
		(fp_line
			(start 0.12065 -0.305054)
			(end 0.12065 -0.2794)
			(stroke
				(width 0.1)
				(type default)
			)
			(layer "B.Fab")
		)
		(fp_line
			(start 0.12065 -0.2794)
			(end -0.12065 -0.2794)
			(stroke
				(width 0.1)
				(type default)
			)
			(layer "B.Fab")
		)
		(fp_line
			(start 0.12065 0.2794)
			(end 0.12065 0.3048)
			(stroke
				(width 0.1)
				(type default)
			)
			(layer "B.Fab")
		)
		(fp_line
			(start 0.12065 0.3048)
			(end 0.67945 0.3048)
			(stroke
				(width 0.1)
				(type default)
			)
			(layer "B.Fab")
		)
		(fp_line
			(start 0.67945 -0.305054)
			(end 0.12065 -0.305054)
			(stroke
				(width 0.1)
				(type default)
			)
			(layer "B.Fab")
		)
		(fp_line
			(start 0.67945 0.3048)
			(end 0.67945 -0.305054)
			(stroke
				(width 0.1)
				(type default)
			)
			(layer "B.Fab")
		)
		(pad "1" smd circle
			(at 0.40005 0 180)
			(size 0 0)
			(layers "B.Cu" "B.Mask" "B.Paste")
			(net "FM_FORCE_ALL_PWRON")
		)
		(pad "2" smd circle
			(at -0.40005 0 180)
			(size 0 0)
			(layers "B.Cu" "B.Mask" "B.Paste")
			(net "GND")
		)
	)
	(footprint ""
		(layer "B.Cu")
		(at 291.849048 -337.984846 -90)
		(property "Reference" "PC168_2"
			(at 0 0 90)
			(layer "B.SilkS")
			(hide yes)
			(effects
				(font
					(size 1.27 1.27)
				)
				(justify mirror)
			)
		)
		(property "Value" ""
			(at 0 0 90)
			(layer "B.Fab")
			(effects
				(font
					(size 1.27 1.27)
				)
				(justify mirror)
			)
		)
		(duplicate_pad_numbers_are_jumpers no)
		(fp_line
			(start -1.524 0.762)
			(end 1.524 0.762)
			(stroke
				(width 0.1524)
				(type default)
			)
			(layer "B.SilkS")
		)
		(fp_line
			(start 1.524 0.762)
			(end 1.524 -0.762)
			(stroke
				(width 0.1524)
				(type default)
			)
			(layer "B.SilkS")
		)
		(fp_line
			(start -1.524 -0.762)
			(end -1.524 0.762)
			(stroke
				(width 0.1524)
				(type default)
			)
			(layer "B.SilkS")
		)
		(fp_line
			(start 1.524 -0.762)
			(end -1.524 -0.762)
			(stroke
				(width 0.1524)
				(type default)
			)
			(layer "B.SilkS")
		)
		(fp_line
			(start -1.1049 0.724916)
			(end -1.1049 -0.724916)
			(stroke
				(width 0.1)
				(type default)
			)
			(layer "B.Fab")
		)
		(fp_line
			(start 1.1049 0.724916)
			(end -1.1049 0.724916)
			(stroke
				(width 0.1)
				(type default)
			)
			(layer "B.Fab")
		)
		(fp_line
			(start -1.1049 -0.724916)
			(end 1.1049 -0.724916)
			(stroke
				(width 0.1)
				(type default)
			)
			(layer "B.Fab")
		)
		(fp_line
			(start 1.1049 -0.724916)
			(end 1.1049 0.724916)
			(stroke
				(width 0.1)
				(type default)
			)
			(layer "B.Fab")
		)
		(pad "1" smd rect
			(at 0.889 0 270)
			(size 1.016 1.27)
			(layers "B.Cu" "B.Mask" "B.Paste")
			(net "PVDDIO_P0")
		)
		(pad "2" smd rect
			(at -0.889 0 270)
			(size 1.016 1.27)
			(layers "B.Cu" "B.Mask" "B.Paste")
			(net "GND")
		)
	)
	(footprint ""
		(layer "B.Cu")
		(at 100.144834 -271.903952 90)
		(property "Reference" "C2382"
			(at 0 0 90)
			(layer "B.SilkS")
			(hide yes)
			(effects
				(font
					(size 1.27 1.27)
				)
				(justify mirror)
			)
		)
		(property "Value" ""
			(at 0 0 90)
			(layer "B.Fab")
			(effects
				(font
					(size 1.27 1.27)
				)
				(justify mirror)
			)
		)
		(duplicate_pad_numbers_are_jumpers no)
		(fp_line
			(start 0.7874 -0.4064)
			(end -0.7874 -0.4064)
			(stroke
				(width 0.1524)
				(type default)
			)
			(layer "B.SilkS")
		)
		(fp_line
			(start -0.7874 -0.4064)
			(end -0.7874 0.4064)
			(stroke
				(width 0.1524)
				(type default)
			)
			(layer "B.SilkS")
		)
		(fp_line
			(start 0.7874 0.4064)
			(end 0.7874 -0.4064)
			(stroke
				(width 0.1524)
				(type default)
			)
			(layer "B.SilkS")
		)
		(fp_line
			(start -0.7874 0.4064)
			(end 0.7874 0.4064)
			(stroke
				(width 0.1524)
				(type default)
			)
			(layer "B.SilkS")
		)
		(fp_line
			(start 0.67945 -0.305054)
			(end 0.12065 -0.305054)
			(stroke
				(width 0.1)
				(type default)
			)
			(layer "B.Fab")
		)
		(fp_line
			(start 0.12065 -0.305054)
			(end 0.12065 -0.2794)
			(stroke
				(width 0.1)
				(type default)
			)
			(layer "B.Fab")
		)
		(fp_line
			(start -0.12065 -0.3048)
			(end -0.67945 -0.3048)
			(stroke
				(width 0.1)
				(type default)
			)
			(layer "B.Fab")
		)
		(fp_line
			(start -0.67945 -0.3048)
			(end -0.67945 0.3048)
			(stroke
				(width 0.1)
				(type default)
			)
			(layer "B.Fab")
		)
		(fp_line
			(start 0.12065 -0.2794)
			(end -0.12065 -0.2794)
			(stroke
				(width 0.1)
				(type default)
			)
			(layer "B.Fab")
		)
		(fp_line
			(start -0.12065 -0.2794)
			(end -0.12065 -0.3048)
			(stroke
				(width 0.1)
				(type default)
			)
			(layer "B.Fab")
		)
		(fp_line
			(start 0.12065 0.2794)
			(end 0.12065 0.3048)
			(stroke
				(width 0.1)
				(type default)
			)
			(layer "B.Fab")
		)
		(fp_line
			(start -0.120396 0.2794)
			(end 0.12065 0.2794)
			(stroke
				(width 0.1)
				(type default)
			)
			(layer "B.Fab")
		)
		(fp_line
			(start 0.67945 0.3048)
			(end 0.67945 -0.305054)
			(stroke
				(width 0.1)
				(type default)
			)
			(layer "B.Fab")
		)
		(fp_line
			(start 0.12065 0.3048)
			(end 0.67945 0.3048)
			(stroke
				(width 0.1)
				(type default)
			)
			(layer "B.Fab")
		)
		(fp_line
			(start -0.120396 0.3048)
			(end -0.120396 0.2794)
			(stroke
				(width 0.1)
				(type default)
			)
			(layer "B.Fab")
		)
		(fp_line
			(start -0.67945 0.3048)
			(end -0.120396 0.3048)
			(stroke
				(width 0.1)
				(type default)
			)
			(layer "B.Fab")
		)
		(pad "1" smd circle
			(at 0.40005 0 270)
			(size 0 0)
			(layers "B.Cu" "B.Mask" "B.Paste")
			(net "PVDDCR_CPU1_P1")
		)
		(pad "2" smd circle
			(at -0.40005 0 270)
			(size 0 0)
			(layers "B.Cu" "B.Mask" "B.Paste")
			(net "GND")
		)
	)
	(footprint ""
		(layer "B.Cu")
		(at 457.702666 -389.23087 -90)
		(property "Reference" "PC6806"
			(at 0 0 90)
			(layer "B.SilkS")
			(hide yes)
			(effects
				(font
					(size 1.27 1.27)
				)
				(justify mirror)
			)
		)
		(property "Value" ""
			(at 0 0 90)
			(layer "B.Fab")
			(effects
				(font
					(size 1.27 1.27)
				)
				(justify mirror)
			)
		)
		(duplicate_pad_numbers_are_jumpers no)
		(fp_line
			(start -0.7874 0.4064)
			(end 0.7874 0.4064)
			(stroke
				(width 0.1524)
				(type default)
			)
			(layer "B.SilkS")
		)
		(fp_line
			(start 0.7874 0.4064)
			(end 0.7874 -0.4064)
			(stroke
				(width 0.1524)
				(type default)
			)
			(layer "B.SilkS")
		)
		(fp_line
			(start -0.7874 -0.4064)
			(end -0.7874 0.4064)
			(stroke
				(width 0.1524)
				(type default)
			)
			(layer "B.SilkS")
		)
		(fp_line
			(start 0.7874 -0.4064)
			(end -0.7874 -0.4064)
			(stroke
				(width 0.1524)
				(type default)
			)
			(layer "B.SilkS")
		)
		(fp_line
			(start -0.67945 0.3048)
			(end -0.120396 0.3048)
			(stroke
				(width 0.1)
				(type default)
			)
			(layer "B.Fab")
		)
		(fp_line
			(start -0.120396 0.3048)
			(end -0.120396 0.2794)
			(stroke
				(width 0.1)
				(type default)
			)
			(layer "B.Fab")
		)
		(fp_line
			(start 0.12065 0.3048)
			(end 0.67945 0.3048)
			(stroke
				(width 0.1)
				(type default)
			)
			(layer "B.Fab")
		)
		(fp_line
			(start 0.67945 0.3048)
			(end 0.67945 -0.305054)
			(stroke
				(width 0.1)
				(type default)
			)
			(layer "B.Fab")
		)
		(fp_line
			(start -0.120396 0.2794)
			(end 0.12065 0.2794)
			(stroke
				(width 0.1)
				(type default)
			)
			(layer "B.Fab")
		)
		(fp_line
			(start 0.12065 0.2794)
			(end 0.12065 0.3048)
			(stroke
				(width 0.1)
				(type default)
			)
			(layer "B.Fab")
		)
		(fp_line
			(start -0.12065 -0.2794)
			(end -0.12065 -0.3048)
			(stroke
				(width 0.1)
				(type default)
			)
			(layer "B.Fab")
		)
		(fp_line
			(start 0.12065 -0.2794)
			(end -0.12065 -0.2794)
			(stroke
				(width 0.1)
				(type default)
			)
			(layer "B.Fab")
		)
		(fp_line
			(start -0.67945 -0.3048)
			(end -0.67945 0.3048)
			(stroke
				(width 0.1)
				(type default)
			)
			(layer "B.Fab")
		)
		(fp_line
			(start -0.12065 -0.3048)
			(end -0.67945 -0.3048)
			(stroke
				(width 0.1)
				(type default)
			)
			(layer "B.Fab")
		)
		(fp_line
			(start 0.12065 -0.305054)
			(end 0.12065 -0.2794)
			(stroke
				(width 0.1)
				(type default)
			)
			(layer "B.Fab")
		)
		(fp_line
			(start 0.67945 -0.305054)
			(end 0.12065 -0.305054)
			(stroke
				(width 0.1)
				(type default)
			)
			(layer "B.Fab")
		)
		(pad "1" smd circle
			(at 0.40005 0 90)
			(size 0 0)
			(layers "B.Cu" "B.Mask" "B.Paste")
			(net "P0V9_CPU0_RT_2D")
		)
		(pad "2" smd circle
			(at -0.40005 0 90)
			(size 0 0)
			(layers "B.Cu" "B.Mask" "B.Paste")
			(net "GND")
		)
	)
	(footprint ""
		(layer "B.Cu")
		(at 62.978538 -386.766562 90)
		(property "Reference" "C222"
			(at 0 0 90)
			(layer "B.SilkS")
			(hide yes)
			(effects
				(font
					(size 1.27 1.27)
				)
				(justify mirror)
			)
		)
		(property "Value" ""
			(at 0 0 90)
			(layer "B.Fab")
			(effects
				(font
					(size 1.27 1.27)
				)
				(justify mirror)
			)
		)
		(duplicate_pad_numbers_are_jumpers no)
		(fp_line
			(start 0.299974 -0.150114)
			(end -0.299974 -0.150114)
			(stroke
				(width 0.1)
				(type default)
			)
			(layer "B.Fab")
		)
		(fp_line
			(start -0.299974 -0.150114)
			(end -0.299974 0.150114)
			(stroke
				(width 0.1)
				(type default)
			)
			(layer "B.Fab")
		)
		(fp_line
			(start 0.299974 0.150114)
			(end 0.299974 -0.150114)
			(stroke
				(width 0.1)
				(type default)
			)
			(layer "B.Fab")
		)
		(fp_line
			(start -0.299974 0.150114)
			(end 0.299974 0.150114)
			(stroke
				(width 0.1)
				(type default)
			)
			(layer "B.Fab")
		)
		(pad "1" smd rect
			(at 0.2667 0 270)
			(size 0.3048 0.381)
			(layers "B.Cu" "B.Mask" "B.Paste")
			(net "P0V9_CPU1_RT0_2A")
		)
		(pad "2" smd rect
			(at -0.2667 0 270)
			(size 0.3048 0.381)
			(layers "B.Cu" "B.Mask" "B.Paste")
			(net "GND")
		)
	)
	(footprint ""
		(layer "B.Cu")
		(at 61.52388 -8.981948 90)
		(property "Reference" "C1836"
			(at 0 0 90)
			(layer "B.SilkS")
			(hide yes)
			(effects
				(font
					(size 1.27 1.27)
				)
				(justify mirror)
			)
		)
		(property "Value" ""
			(at 0 0 90)
			(layer "B.Fab")
			(effects
				(font
					(size 1.27 1.27)
				)
				(justify mirror)
			)
		)
		(duplicate_pad_numbers_are_jumpers no)
		(fp_line
			(start 0.7874 -0.4064)
			(end -0.7874 -0.4064)
			(stroke
				(width 0.1524)
				(type default)
			)
			(layer "B.SilkS")
		)
		(fp_line
			(start -0.7874 -0.4064)
			(end -0.7874 0.4064)
			(stroke
				(width 0.1524)
				(type default)
			)
			(layer "B.SilkS")
		)
		(fp_line
			(start 0.7874 0.4064)
			(end 0.7874 -0.4064)
			(stroke
				(width 0.1524)
				(type default)
			)
			(layer "B.SilkS")
		)
		(fp_line
			(start -0.7874 0.4064)
			(end 0.7874 0.4064)
			(stroke
				(width 0.1524)
				(type default)
			)
			(layer "B.SilkS")
		)
		(fp_line
			(start 0.67945 -0.305054)
			(end 0.12065 -0.305054)
			(stroke
				(width 0.1)
				(type default)
			)
			(layer "B.Fab")
		)
		(fp_line
			(start 0.12065 -0.305054)
			(end 0.12065 -0.2794)
			(stroke
				(width 0.1)
				(type default)
			)
			(layer "B.Fab")
		)
		(fp_line
			(start -0.12065 -0.3048)
			(end -0.67945 -0.3048)
			(stroke
				(width 0.1)
				(type default)
			)
			(layer "B.Fab")
		)
		(fp_line
			(start -0.67945 -0.3048)
			(end -0.67945 0.3048)
			(stroke
				(width 0.1)
				(type default)
			)
			(layer "B.Fab")
		)
		(fp_line
			(start 0.12065 -0.2794)
			(end -0.12065 -0.2794)
			(stroke
				(width 0.1)
				(type default)
			)
			(layer "B.Fab")
		)
		(fp_line
			(start -0.12065 -0.2794)
			(end -0.12065 -0.3048)
			(stroke
				(width 0.1)
				(type default)
			)
			(layer "B.Fab")
		)
		(fp_line
			(start 0.12065 0.2794)
			(end 0.12065 0.3048)
			(stroke
				(width 0.1)
				(type default)
			)
			(layer "B.Fab")
		)
		(fp_line
			(start -0.120396 0.2794)
			(end 0.12065 0.2794)
			(stroke
				(width 0.1)
				(type default)
			)
			(layer "B.Fab")
		)
		(fp_line
			(start 0.67945 0.3048)
			(end 0.67945 -0.305054)
			(stroke
				(width 0.1)
				(type default)
			)
			(layer "B.Fab")
		)
		(fp_line
			(start 0.12065 0.3048)
			(end 0.67945 0.3048)
			(stroke
				(width 0.1)
				(type default)
			)
			(layer "B.Fab")
		)
		(fp_line
			(start -0.120396 0.3048)
			(end -0.120396 0.2794)
			(stroke
				(width 0.1)
				(type default)
			)
			(layer "B.Fab")
		)
		(fp_line
			(start -0.67945 0.3048)
			(end -0.120396 0.3048)
			(stroke
				(width 0.1)
				(type default)
			)
			(layer "B.Fab")
		)
		(pad "1" smd circle
			(at 0.40005 0 270)
			(size 0 0)
			(layers "B.Cu" "B.Mask" "B.Paste")
			(net "P3V3_OCP_V3_2")
		)
		(pad "2" smd circle
			(at -0.40005 0 270)
			(size 0 0)
			(layers "B.Cu" "B.Mask" "B.Paste")
			(net "GND")
		)
	)
	(footprint ""
		(layer "B.Cu")
		(at 199.96912 -331.027786 -90)
		(property "Reference" "PC129"
			(at 0 0 90)
			(layer "B.SilkS")
			(hide yes)
			(effects
				(font
					(size 1.27 1.27)
				)
				(justify mirror)
			)
		)
		(property "Value" ""
			(at 0 0 90)
			(layer "B.Fab")
			(effects
				(font
					(size 1.27 1.27)
				)
				(justify mirror)
			)
		)
		(duplicate_pad_numbers_are_jumpers no)
		(fp_line
			(start -1.524 0.762)
			(end 1.524 0.762)
			(stroke
				(width 0.1524)
				(type default)
			)
			(layer "B.SilkS")
		)
		(fp_line
			(start 1.524 0.762)
			(end 1.524 -0.762)
			(stroke
				(width 0.1524)
				(type default)
			)
			(layer "B.SilkS")
		)
		(fp_line
			(start -1.524 -0.762)
			(end -1.524 0.762)
			(stroke
				(width 0.1524)
				(type default)
			)
			(layer "B.SilkS")
		)
		(fp_line
			(start 1.524 -0.762)
			(end -1.524 -0.762)
			(stroke
				(width 0.1524)
				(type default)
			)
			(layer "B.SilkS")
		)
		(fp_line
			(start -1.1049 0.724916)
			(end -1.1049 -0.724916)
			(stroke
				(width 0.1)
				(type default)
			)
			(layer "B.Fab")
		)
		(fp_line
			(start 1.1049 0.724916)
			(end -1.1049 0.724916)
			(stroke
				(width 0.1)
				(type default)
			)
			(layer "B.Fab")
		)
		(fp_line
			(start -1.1049 -0.724916)
			(end 1.1049 -0.724916)
			(stroke
				(width 0.1)
				(type default)
			)
			(layer "B.Fab")
		)
		(fp_line
			(start 1.1049 -0.724916)
			(end 1.1049 0.724916)
			(stroke
				(width 0.1)
				(type default)
			)
			(layer "B.Fab")
		)
		(pad "1" smd rect
			(at 0.889 0 270)
			(size 1.016 1.27)
			(layers "B.Cu" "B.Mask" "B.Paste")
			(net "PVDD_33_S5")
		)
		(pad "2" smd rect
			(at -0.889 0 270)
			(size 1.016 1.27)
			(layers "B.Cu" "B.Mask" "B.Paste")
			(net "GND")
		)
	)
	(footprint ""
		(layer "B.Cu")
		(at 359.740454 -251.40031 180)
		(property "Reference" "C2595"
			(at 0 0 0)
			(layer "B.SilkS")
			(hide yes)
			(effects
				(font
					(size 1.27 1.27)
				)
				(justify mirror)
			)
		)
		(property "Value" ""
			(at 0 0 0)
			(layer "B.Fab")
			(effects
				(font
					(size 1.27 1.27)
				)
				(justify mirror)
			)
		)
		(duplicate_pad_numbers_are_jumpers no)
		(fp_line
			(start 0.7874 0.4064)
			(end 0.7874 -0.4064)
			(stroke
				(width 0.1524)
				(type default)
			)
			(layer "B.SilkS")
		)
		(fp_line
			(start 0.7874 -0.4064)
			(end -0.7874 -0.4064)
			(stroke
				(width 0.1524)
				(type default)
			)
			(layer "B.SilkS")
		)
		(fp_line
			(start -0.7874 0.4064)
			(end 0.7874 0.4064)
			(stroke
				(width 0.1524)
				(type default)
			)
			(layer "B.SilkS")
		)
		(fp_line
			(start -0.7874 -0.4064)
			(end -0.7874 0.4064)
			(stroke
				(width 0.1524)
				(type default)
			)
			(layer "B.SilkS")
		)
		(fp_line
			(start 0.67945 0.3048)
			(end 0.67945 -0.305054)
			(stroke
				(width 0.1)
				(type default)
			)
			(layer "B.Fab")
		)
		(fp_line
			(start 0.67945 -0.305054)
			(end 0.12065 -0.305054)
			(stroke
				(width 0.1)
				(type default)
			)
			(layer "B.Fab")
		)
		(fp_line
			(start 0.12065 0.3048)
			(end 0.67945 0.3048)
			(stroke
				(width 0.1)
				(type default)
			)
			(layer "B.Fab")
		)
		(fp_line
			(start 0.12065 0.2794)
			(end 0.12065 0.3048)
			(stroke
				(width 0.1)
				(type default)
			)
			(layer "B.Fab")
		)
		(fp_line
			(start 0.12065 -0.2794)
			(end -0.12065 -0.2794)
			(stroke
				(width 0.1)
				(type default)
			)
			(layer "B.Fab")
		)
		(fp_line
			(start 0.12065 -0.305054)
			(end 0.12065 -0.2794)
			(stroke
				(width 0.1)
				(type default)
			)
			(layer "B.Fab")
		)
		(fp_line
			(start -0.120396 0.3048)
			(end -0.120396 0.2794)
			(stroke
				(width 0.1)
				(type default)
			)
			(layer "B.Fab")
		)
		(fp_line
			(start -0.120396 0.2794)
			(end 0.12065 0.2794)
			(stroke
				(width 0.1)
				(type default)
			)
			(layer "B.Fab")
		)
		(fp_line
			(start -0.12065 -0.2794)
			(end -0.12065 -0.3048)
			(stroke
				(width 0.1)
				(type default)
			)
			(layer "B.Fab")
		)
		(fp_line
			(start -0.12065 -0.3048)
			(end -0.67945 -0.3048)
			(stroke
				(width 0.1)
				(type default)
			)
			(layer "B.Fab")
		)
		(fp_line
			(start -0.67945 0.3048)
			(end -0.120396 0.3048)
			(stroke
				(width 0.1)
				(type default)
			)
			(layer "B.Fab")
		)
		(fp_line
			(start -0.67945 -0.3048)
			(end -0.67945 0.3048)
			(stroke
				(width 0.1)
				(type default)
			)
			(layer "B.Fab")
		)
		(pad "1" smd circle
			(at 0.40005 0)
			(size 0 0)
			(layers "B.Cu" "B.Mask" "B.Paste")
			(net "PVDDCR_SOC_P0")
		)
		(pad "2" smd circle
			(at -0.40005 0)
			(size 0 0)
			(layers "B.Cu" "B.Mask" "B.Paste")
			(net "GND")
		)
	)
	(footprint ""
		(layer "B.Cu")
		(at 238.633 -340.741 180)
		(property "Reference" "R808"
			(at 0 0 0)
			(layer "B.SilkS")
			(hide yes)
			(effects
				(font
					(size 1.27 1.27)
				)
				(justify mirror)
			)
		)
		(property "Value" ""
			(at 0 0 0)
			(layer "B.Fab")
			(effects
				(font
					(size 1.27 1.27)
				)
				(justify mirror)
			)
		)
		(duplicate_pad_numbers_are_jumpers no)
		(fp_line
			(start 0.32512 0.175006)
			(end 0.32512 -0.175006)
			(stroke
				(width 0.1)
				(type default)
			)
			(layer "B.Fab")
		)
		(fp_line
			(start 0.32512 -0.175006)
			(end -0.32512 -0.175006)
			(stroke
				(width 0.1)
				(type default)
			)
			(layer "B.Fab")
		)
		(fp_line
			(start -0.32512 0.175006)
			(end 0.32512 0.175006)
			(stroke
				(width 0.1)
				(type default)
			)
			(layer "B.Fab")
		)
		(fp_line
			(start -0.32512 -0.175006)
			(end -0.32512 0.175006)
			(stroke
				(width 0.1)
				(type default)
			)
			(layer "B.Fab")
		)
		(pad "1" smd rect
			(at 0.2667 0)
			(size 0.3048 0.381)
			(layers "B.Cu" "B.Mask" "B.Paste")
			(net "SMB_RT_CPU1_P2_ROM_MUX_2D_SDA")
		)
		(pad "2" smd rect
			(at -0.2667 0 180)
			(size 0.3048 0.381)
			(layers "B.Cu" "B.Mask" "B.Paste")
			(net "SMB_RT_CPU1_P2_ROM_MUX_2D_R_SDA")
		)
	)
	(footprint ""
		(layer "B.Cu")
		(at 384.240278 -137.535158 90)
		(property "Reference" "PC471"
			(at 0 0 90)
			(layer "B.SilkS")
			(hide yes)
			(effects
				(font
					(size 1.27 1.27)
				)
				(justify mirror)
			)
		)
		(property "Value" ""
			(at 0 0 90)
			(layer "B.Fab")
			(effects
				(font
					(size 1.27 1.27)
				)
				(justify mirror)
			)
		)
		(duplicate_pad_numbers_are_jumpers no)
		(fp_line
			(start 0.7874 -0.4064)
			(end -0.7874 -0.4064)
			(stroke
				(width 0.1524)
				(type default)
			)
			(layer "B.SilkS")
		)
		(fp_line
			(start -0.7874 -0.4064)
			(end -0.7874 0.4064)
			(stroke
				(width 0.1524)
				(type default)
			)
			(layer "B.SilkS")
		)
		(fp_line
			(start 0.7874 0.4064)
			(end 0.7874 -0.4064)
			(stroke
				(width 0.1524)
				(type default)
			)
			(layer "B.SilkS")
		)
		(fp_line
			(start -0.7874 0.4064)
			(end 0.7874 0.4064)
			(stroke
				(width 0.1524)
				(type default)
			)
			(layer "B.SilkS")
		)
		(fp_line
			(start 0.67945 -0.305054)
			(end 0.12065 -0.305054)
			(stroke
				(width 0.1)
				(type default)
			)
			(layer "B.Fab")
		)
		(fp_line
			(start 0.12065 -0.305054)
			(end 0.12065 -0.2794)
			(stroke
				(width 0.1)
				(type default)
			)
			(layer "B.Fab")
		)
		(fp_line
			(start -0.12065 -0.3048)
			(end -0.67945 -0.3048)
			(stroke
				(width 0.1)
				(type default)
			)
			(layer "B.Fab")
		)
		(fp_line
			(start -0.67945 -0.3048)
			(end -0.67945 0.3048)
			(stroke
				(width 0.1)
				(type default)
			)
			(layer "B.Fab")
		)
		(fp_line
			(start 0.12065 -0.2794)
			(end -0.12065 -0.2794)
			(stroke
				(width 0.1)
				(type default)
			)
			(layer "B.Fab")
		)
		(fp_line
			(start -0.12065 -0.2794)
			(end -0.12065 -0.3048)
			(stroke
				(width 0.1)
				(type default)
			)
			(layer "B.Fab")
		)
		(fp_line
			(start 0.12065 0.2794)
			(end 0.12065 0.3048)
			(stroke
				(width 0.1)
				(type default)
			)
			(layer "B.Fab")
		)
		(fp_line
			(start -0.120396 0.2794)
			(end 0.12065 0.2794)
			(stroke
				(width 0.1)
				(type default)
			)
			(layer "B.Fab")
		)
		(fp_line
			(start 0.67945 0.3048)
			(end 0.67945 -0.305054)
			(stroke
				(width 0.1)
				(type default)
			)
			(layer "B.Fab")
		)
		(fp_line
			(start 0.12065 0.3048)
			(end 0.67945 0.3048)
			(stroke
				(width 0.1)
				(type default)
			)
			(layer "B.Fab")
		)
		(fp_line
			(start -0.120396 0.3048)
			(end -0.120396 0.2794)
			(stroke
				(width 0.1)
				(type default)
			)
			(layer "B.Fab")
		)
		(fp_line
			(start -0.67945 0.3048)
			(end -0.120396 0.3048)
			(stroke
				(width 0.1)
				(type default)
			)
			(layer "B.Fab")
		)
		(pad "1" smd circle
			(at 0.40005 0 270)
			(size 0 0)
			(layers "B.Cu" "B.Mask" "B.Paste")
			(net "PVDDCR_CPU0_P0_VCC")
		)
		(pad "2" smd circle
			(at -0.40005 0 270)
			(size 0 0)
			(layers "B.Cu" "B.Mask" "B.Paste")
			(net "GND")
		)
	)
	(footprint ""
		(layer "B.Cu")
		(at 93.142562 -336.088482 -90)
		(property "Reference" "PR271"
			(at 0 0 90)
			(layer "B.SilkS")
			(hide yes)
			(effects
				(font
					(size 1.27 1.27)
				)
				(justify mirror)
			)
		)
		(property "Value" ""
			(at 0 0 90)
			(layer "B.Fab")
			(effects
				(font
					(size 1.27 1.27)
				)
				(justify mirror)
			)
		)
		(duplicate_pad_numbers_are_jumpers no)
		(fp_line
			(start -0.7874 0.4064)
			(end 0.7874 0.4064)
			(stroke
				(width 0.1524)
				(type default)
			)
			(layer "B.SilkS")
		)
		(fp_line
			(start 0.7874 0.4064)
			(end 0.7874 -0.4064)
			(stroke
				(width 0.1524)
				(type default)
			)
			(layer "B.SilkS")
		)
		(fp_line
			(start -0.7874 -0.4064)
			(end -0.7874 0.4064)
			(stroke
				(width 0.1524)
				(type default)
			)
			(layer "B.SilkS")
		)
		(fp_line
			(start 0.7874 -0.4064)
			(end -0.7874 -0.4064)
			(stroke
				(width 0.1524)
				(type default)
			)
			(layer "B.SilkS")
		)
		(fp_line
			(start -0.67945 0.3048)
			(end -0.120396 0.3048)
			(stroke
				(width 0.1)
				(type default)
			)
			(layer "B.Fab")
		)
		(fp_line
			(start -0.120396 0.3048)
			(end -0.120396 0.2794)
			(stroke
				(width 0.1)
				(type default)
			)
			(layer "B.Fab")
		)
		(fp_line
			(start 0.12065 0.3048)
			(end 0.67945 0.3048)
			(stroke
				(width 0.1)
				(type default)
			)
			(layer "B.Fab")
		)
		(fp_line
			(start 0.67945 0.3048)
			(end 0.67945 -0.305054)
			(stroke
				(width 0.1)
				(type default)
			)
			(layer "B.Fab")
		)
		(fp_line
			(start -0.120396 0.2794)
			(end 0.12065 0.2794)
			(stroke
				(width 0.1)
				(type default)
			)
			(layer "B.Fab")
		)
		(fp_line
			(start 0.12065 0.2794)
			(end 0.12065 0.3048)
			(stroke
				(width 0.1)
				(type default)
			)
			(layer "B.Fab")
		)
		(fp_line
			(start -0.12065 -0.2794)
			(end -0.12065 -0.3048)
			(stroke
				(width 0.1)
				(type default)
			)
			(layer "B.Fab")
		)
		(fp_line
			(start 0.12065 -0.2794)
			(end -0.12065 -0.2794)
			(stroke
				(width 0.1)
				(type default)
			)
			(layer "B.Fab")
		)
		(fp_line
			(start -0.67945 -0.3048)
			(end -0.67945 0.3048)
			(stroke
				(width 0.1)
				(type default)
			)
			(layer "B.Fab")
		)
		(fp_line
			(start -0.12065 -0.3048)
			(end -0.67945 -0.3048)
			(stroke
				(width 0.1)
				(type default)
			)
			(layer "B.Fab")
		)
		(fp_line
			(start 0.12065 -0.305054)
			(end 0.12065 -0.2794)
			(stroke
				(width 0.1)
				(type default)
			)
			(layer "B.Fab")
		)
		(fp_line
			(start 0.67945 -0.305054)
			(end 0.12065 -0.305054)
			(stroke
				(width 0.1)
				(type default)
			)
			(layer "B.Fab")
		)
		(pad "1" smd circle
			(at 0.40005 0 90)
			(size 0 0)
			(layers "B.Cu" "B.Mask" "B.Paste")
			(net "PVDDCR_CPU1_P1_PVCC")
		)
		(pad "2" smd circle
			(at -0.40005 0 90)
			(size 0 0)
			(layers "B.Cu" "B.Mask" "B.Paste")
			(net "PVDDCR_CPU1_P1_VCC5")
		)
	)
	(footprint ""
		(layer "B.Cu")
		(at 275.217128 -339.860128 -90)
		(property "Reference" "PC160"
			(at 9.447276 -0.827786 270)
			(unlocked yes)
			(layer "B.SilkS")
			(effects
				(font
					(size 0.7874 0.5842)
					(thickness 0.1524)
				)
				(justify left mirror)
			)
		)
		(property "Value" ""
			(at 0 0 90)
			(layer "B.Fab")
			(effects
				(font
					(size 1.27 1.27)
				)
				(justify mirror)
			)
		)
		(duplicate_pad_numbers_are_jumpers no)
		(fp_line
			(start -4.533392 2.249932)
			(end 4.533392 2.249932)
			(stroke
				(width 0.1524)
				(type default)
			)
			(layer "B.SilkS")
		)
		(fp_line
			(start 4.533392 2.249932)
			(end 4.533392 -2.249932)
			(stroke
				(width 0.1524)
				(type default)
			)
			(layer "B.SilkS")
		)
		(fp_line
			(start -4.533392 -2.249932)
			(end -4.533392 2.249932)
			(stroke
				(width 0.1524)
				(type default)
			)
			(layer "B.SilkS")
		)
		(fp_line
			(start 4.533392 -2.249932)
			(end -4.533392 -2.249932)
			(stroke
				(width 0.1524)
				(type default)
			)
			(layer "B.SilkS")
		)
		(fp_rect
			(start 5.39242 2.326132)
			(end 4.533392 -2.326132)
			(stroke
				(width 0)
				(type default)
			)
			(fill yes)
			(layer "B.SilkS")
		)
		(fp_line
			(start -3.750056 2.249932)
			(end 3.750056 2.249932)
			(stroke
				(width 0.1)
				(type default)
			)
			(layer "B.Fab")
		)
		(fp_line
			(start 3.750056 2.249932)
			(end 3.750056 -2.249932)
			(stroke
				(width 0.1)
				(type default)
			)
			(layer "B.Fab")
		)
		(fp_line
			(start -3.750056 -2.249932)
			(end -3.750056 2.249932)
			(stroke
				(width 0.1)
				(type default)
			)
			(layer "B.Fab")
		)
		(fp_line
			(start 3.750056 -2.249932)
			(end -3.750056 -2.249932)
			(stroke
				(width 0.1)
				(type default)
			)
			(layer "B.Fab")
		)
		(fp_text user "+"
			(at 6.322314 0.786384 180)
			(unlocked yes)
			(layer "B.SilkS")
			(effects
				(font
					(size 1.905 1.4224)
					(thickness 0.1524)
				)
				(justify left mirror)
			)
		)
		(fp_text user "-"
			(at -4.8514 -0.14605 270)
			(unlocked yes)
			(layer "B.SilkS")
			(effects
				(font
					(size 1.905 1.4224)
					(thickness 0.1524)
				)
				(justify left mirror)
			)
		)
		(fp_text user "+"
			(at 6.322314 0.786384 180)
			(unlocked yes)
			(layer "B.Fab")
			(effects
				(font
					(size 1.905 1.4224)
					(thickness 0.1524)
				)
				(justify left mirror)
			)
		)
		(fp_text user "-"
			(at -4.8514 -0.14605 270)
			(unlocked yes)
			(layer "B.Fab")
			(effects
				(font
					(size 1.905 1.4224)
					(thickness 0.1524)
				)
				(justify left mirror)
			)
		)
		(pad "1" smd rect
			(at 3.199892 0 90)
			(size 2.413 2.8194)
			(layers "B.Cu" "B.Mask" "B.Paste")
			(net "PVDDIO_P0")
		)
		(pad "2" smd rect
			(at -3.199892 0 90)
			(size 2.413 2.8194)
			(layers "B.Cu" "B.Mask" "B.Paste")
			(net "GND")
		)
	)
	(footprint ""
		(layer "B.Cu")
		(at 233.172 -337.312 180)
		(property "Reference" "R1110"
			(at 0 0 0)
			(layer "B.SilkS")
			(hide yes)
			(effects
				(font
					(size 1.27 1.27)
				)
				(justify mirror)
			)
		)
		(property "Value" ""
			(at 0 0 0)
			(layer "B.Fab")
			(effects
				(font
					(size 1.27 1.27)
				)
				(justify mirror)
			)
		)
		(duplicate_pad_numbers_are_jumpers no)
		(fp_line
			(start 0.32512 0.175006)
			(end 0.32512 -0.175006)
			(stroke
				(width 0.1)
				(type default)
			)
			(layer "B.Fab")
		)
		(fp_line
			(start 0.32512 -0.175006)
			(end -0.32512 -0.175006)
			(stroke
				(width 0.1)
				(type default)
			)
			(layer "B.Fab")
		)
		(fp_line
			(start -0.32512 0.175006)
			(end 0.32512 0.175006)
			(stroke
				(width 0.1)
				(type default)
			)
			(layer "B.Fab")
		)
		(fp_line
			(start -0.32512 -0.175006)
			(end -0.32512 0.175006)
			(stroke
				(width 0.1)
				(type default)
			)
			(layer "B.Fab")
		)
		(pad "1" smd rect
			(at 0.2667 0)
			(size 0.3048 0.381)
			(layers "B.Cu" "B.Mask" "B.Paste")
			(net "SMB_RT_CPU0_P3_R_SDA")
		)
		(pad "2" smd rect
			(at -0.2667 0 180)
			(size 0.3048 0.381)
			(layers "B.Cu" "B.Mask" "B.Paste")
			(net "SMB_RT_CPU0_P3_R2_SDA")
		)
	)
	(footprint ""
		(layer "B.Cu")
		(at 151.946102 -388.011162 -90)
		(property "Reference" "C396"
			(at 0 0 90)
			(layer "B.SilkS")
			(hide yes)
			(effects
				(font
					(size 1.27 1.27)
				)
				(justify mirror)
			)
		)
		(property "Value" ""
			(at 0 0 90)
			(layer "B.Fab")
			(effects
				(font
					(size 1.27 1.27)
				)
				(justify mirror)
			)
		)
		(duplicate_pad_numbers_are_jumpers no)
		(fp_line
			(start -0.299974 0.150114)
			(end 0.299974 0.150114)
			(stroke
				(width 0.1)
				(type default)
			)
			(layer "B.Fab")
		)
		(fp_line
			(start 0.299974 0.150114)
			(end 0.299974 -0.150114)
			(stroke
				(width 0.1)
				(type default)
			)
			(layer "B.Fab")
		)
		(fp_line
			(start -0.299974 -0.150114)
			(end -0.299974 0.150114)
			(stroke
				(width 0.1)
				(type default)
			)
			(layer "B.Fab")
		)
		(fp_line
			(start 0.299974 -0.150114)
			(end -0.299974 -0.150114)
			(stroke
				(width 0.1)
				(type default)
			)
			(layer "B.Fab")
		)
		(pad "1" smd rect
			(at 0.2667 0 90)
			(size 0.3048 0.381)
			(layers "B.Cu" "B.Mask" "B.Paste")
			(net "P0V9_CPU1_RT2_2A_2D")
		)
		(pad "2" smd rect
			(at -0.2667 0 90)
			(size 0.3048 0.381)
			(layers "B.Cu" "B.Mask" "B.Paste")
			(net "GND")
		)
	)
	(footprint ""
		(layer "B.Cu")
		(at 135.115554 -165.145212 90)
		(property "Reference" "PC355_3"
			(at 0 0 90)
			(layer "B.SilkS")
			(hide yes)
			(effects
				(font
					(size 1.27 1.27)
				)
				(justify mirror)
			)
		)
		(property "Value" ""
			(at 0 0 90)
			(layer "B.Fab")
			(effects
				(font
					(size 1.27 1.27)
				)
				(justify mirror)
			)
		)
		(duplicate_pad_numbers_are_jumpers no)
		(fp_line
			(start 1.524 -0.762)
			(end -1.524 -0.762)
			(stroke
				(width 0.1524)
				(type default)
			)
			(layer "B.SilkS")
		)
		(fp_line
			(start -1.524 -0.762)
			(end -1.524 0.762)
			(stroke
				(width 0.1524)
				(type default)
			)
			(layer "B.SilkS")
		)
		(fp_line
			(start 1.524 0.762)
			(end 1.524 -0.762)
			(stroke
				(width 0.1524)
				(type default)
			)
			(layer "B.SilkS")
		)
		(fp_line
			(start -1.524 0.762)
			(end 1.524 0.762)
			(stroke
				(width 0.1524)
				(type default)
			)
			(layer "B.SilkS")
		)
		(fp_line
			(start 1.1049 -0.724916)
			(end 1.1049 0.724916)
			(stroke
				(width 0.1)
				(type default)
			)
			(layer "B.Fab")
		)
		(fp_line
			(start -1.1049 -0.724916)
			(end 1.1049 -0.724916)
			(stroke
				(width 0.1)
				(type default)
			)
			(layer "B.Fab")
		)
		(fp_line
			(start 1.1049 0.724916)
			(end -1.1049 0.724916)
			(stroke
				(width 0.1)
				(type default)
			)
			(layer "B.Fab")
		)
		(fp_line
			(start -1.1049 0.724916)
			(end -1.1049 -0.724916)
			(stroke
				(width 0.1)
				(type default)
			)
			(layer "B.Fab")
		)
		(pad "1" smd rect
			(at 0.889 0 90)
			(size 1.016 1.27)
			(layers "B.Cu" "B.Mask" "B.Paste")
			(net "PVDDCR_SOC_P1")
		)
		(pad "2" smd rect
			(at -0.889 0 90)
			(size 1.016 1.27)
			(layers "B.Cu" "B.Mask" "B.Paste")
			(net "GND")
		)
	)
	(footprint ""
		(layer "B.Cu")
		(at 212.725 -57.061608 90)
		(property "Reference" "R4093"
			(at 0 0 90)
			(layer "B.SilkS")
			(hide yes)
			(effects
				(font
					(size 1.27 1.27)
				)
				(justify mirror)
			)
		)
		(property "Value" ""
			(at 0 0 90)
			(layer "B.Fab")
			(effects
				(font
					(size 1.27 1.27)
				)
				(justify mirror)
			)
		)
		(duplicate_pad_numbers_are_jumpers no)
		(fp_line
			(start 0.7874 -0.4064)
			(end -0.7874 -0.4064)
			(stroke
				(width 0.1524)
				(type default)
			)
			(layer "B.SilkS")
		)
		(fp_line
			(start -0.7874 -0.4064)
			(end -0.7874 0.4064)
			(stroke
				(width 0.1524)
				(type default)
			)
			(layer "B.SilkS")
		)
		(fp_line
			(start 0.7874 0.4064)
			(end 0.7874 -0.4064)
			(stroke
				(width 0.1524)
				(type default)
			)
			(layer "B.SilkS")
		)
		(fp_line
			(start -0.7874 0.4064)
			(end 0.7874 0.4064)
			(stroke
				(width 0.1524)
				(type default)
			)
			(layer "B.SilkS")
		)
		(fp_line
			(start 0.67945 -0.305054)
			(end 0.12065 -0.305054)
			(stroke
				(width 0.1)
				(type default)
			)
			(layer "B.Fab")
		)
		(fp_line
			(start 0.12065 -0.305054)
			(end 0.12065 -0.2794)
			(stroke
				(width 0.1)
				(type default)
			)
			(layer "B.Fab")
		)
		(fp_line
			(start -0.12065 -0.3048)
			(end -0.67945 -0.3048)
			(stroke
				(width 0.1)
				(type default)
			)
			(layer "B.Fab")
		)
		(fp_line
			(start -0.67945 -0.3048)
			(end -0.67945 0.3048)
			(stroke
				(width 0.1)
				(type default)
			)
			(layer "B.Fab")
		)
		(fp_line
			(start 0.12065 -0.2794)
			(end -0.12065 -0.2794)
			(stroke
				(width 0.1)
				(type default)
			)
			(layer "B.Fab")
		)
		(fp_line
			(start -0.12065 -0.2794)
			(end -0.12065 -0.3048)
			(stroke
				(width 0.1)
				(type default)
			)
			(layer "B.Fab")
		)
		(fp_line
			(start 0.12065 0.2794)
			(end 0.12065 0.3048)
			(stroke
				(width 0.1)
				(type default)
			)
			(layer "B.Fab")
		)
		(fp_line
			(start -0.120396 0.2794)
			(end 0.12065 0.2794)
			(stroke
				(width 0.1)
				(type default)
			)
			(layer "B.Fab")
		)
		(fp_line
			(start 0.67945 0.3048)
			(end 0.67945 -0.305054)
			(stroke
				(width 0.1)
				(type default)
			)
			(layer "B.Fab")
		)
		(fp_line
			(start 0.12065 0.3048)
			(end 0.67945 0.3048)
			(stroke
				(width 0.1)
				(type default)
			)
			(layer "B.Fab")
		)
		(fp_line
			(start -0.120396 0.3048)
			(end -0.120396 0.2794)
			(stroke
				(width 0.1)
				(type default)
			)
			(layer "B.Fab")
		)
		(fp_line
			(start -0.67945 0.3048)
			(end -0.120396 0.3048)
			(stroke
				(width 0.1)
				(type default)
			)
			(layer "B.Fab")
		)
		(pad "1" smd circle
			(at 0.40005 0 270)
			(size 0 0)
			(layers "B.Cu" "B.Mask" "B.Paste")
			(net "P3V3_AUX")
		)
		(pad "2" smd circle
			(at -0.40005 0 270)
			(size 0 0)
			(layers "B.Cu" "B.Mask" "B.Paste")
			(net "E1S_0_P3V3_ADC_ALERT_R")
		)
	)
	(footprint ""
		(layer "B.Cu")
		(at 24.765 -364.617 180)
		(property "Reference" "R8235"
			(at 0 0 0)
			(layer "B.SilkS")
			(hide yes)
			(effects
				(font
					(size 1.27 1.27)
				)
				(justify mirror)
			)
		)
		(property "Value" ""
			(at 0 0 0)
			(layer "B.Fab")
			(effects
				(font
					(size 1.27 1.27)
				)
				(justify mirror)
			)
		)
		(duplicate_pad_numbers_are_jumpers no)
		(fp_line
			(start 0.7874 0.4064)
			(end 0.7874 -0.4064)
			(stroke
				(width 0.1524)
				(type default)
			)
			(layer "B.SilkS")
		)
		(fp_line
			(start 0.7874 -0.4064)
			(end -0.7874 -0.4064)
			(stroke
				(width 0.1524)
				(type default)
			)
			(layer "B.SilkS")
		)
		(fp_line
			(start -0.7874 0.4064)
			(end 0.7874 0.4064)
			(stroke
				(width 0.1524)
				(type default)
			)
			(layer "B.SilkS")
		)
		(fp_line
			(start -0.7874 -0.4064)
			(end -0.7874 0.4064)
			(stroke
				(width 0.1524)
				(type default)
			)
			(layer "B.SilkS")
		)
		(fp_line
			(start 0.67945 0.3048)
			(end 0.67945 -0.305054)
			(stroke
				(width 0.1)
				(type default)
			)
			(layer "B.Fab")
		)
		(fp_line
			(start 0.67945 -0.305054)
			(end 0.12065 -0.305054)
			(stroke
				(width 0.1)
				(type default)
			)
			(layer "B.Fab")
		)
		(fp_line
			(start 0.12065 0.3048)
			(end 0.67945 0.3048)
			(stroke
				(width 0.1)
				(type default)
			)
			(layer "B.Fab")
		)
		(fp_line
			(start 0.12065 0.2794)
			(end 0.12065 0.3048)
			(stroke
				(width 0.1)
				(type default)
			)
			(layer "B.Fab")
		)
		(fp_line
			(start 0.12065 -0.2794)
			(end -0.12065 -0.2794)
			(stroke
				(width 0.1)
				(type default)
			)
			(layer "B.Fab")
		)
		(fp_line
			(start 0.12065 -0.305054)
			(end 0.12065 -0.2794)
			(stroke
				(width 0.1)
				(type default)
			)
			(layer "B.Fab")
		)
		(fp_line
			(start -0.120396 0.3048)
			(end -0.120396 0.2794)
			(stroke
				(width 0.1)
				(type default)
			)
			(layer "B.Fab")
		)
		(fp_line
			(start -0.120396 0.2794)
			(end 0.12065 0.2794)
			(stroke
				(width 0.1)
				(type default)
			)
			(layer "B.Fab")
		)
		(fp_line
			(start -0.12065 -0.2794)
			(end -0.12065 -0.3048)
			(stroke
				(width 0.1)
				(type default)
			)
			(layer "B.Fab")
		)
		(fp_line
			(start -0.12065 -0.3048)
			(end -0.67945 -0.3048)
			(stroke
				(width 0.1)
				(type default)
			)
			(layer "B.Fab")
		)
		(fp_line
			(start -0.67945 0.3048)
			(end -0.120396 0.3048)
			(stroke
				(width 0.1)
				(type default)
			)
			(layer "B.Fab")
		)
		(fp_line
			(start -0.67945 -0.3048)
			(end -0.67945 0.3048)
			(stroke
				(width 0.1)
				(type default)
			)
			(layer "B.Fab")
		)
		(pad "1" smd circle
			(at 0.40005 0)
			(size 0 0)
			(layers "B.Cu" "B.Mask" "B.Paste")
			(net "FM_PVDDCR_CPU1_P1_EN")
		)
		(pad "2" smd circle
			(at -0.40005 0)
			(size 0 0)
			(layers "B.Cu" "B.Mask" "B.Paste")
			(net "PVDDCR_CPU1_P1_EN_R")
		)
	)
	(footprint ""
		(layer "B.Cu")
		(at 53.278024 -408.517344 90)
		(property "Reference" "C6663"
			(at 0 0 90)
			(layer "B.SilkS")
			(hide yes)
			(effects
				(font
					(size 1.27 1.27)
				)
				(justify mirror)
			)
		)
		(property "Value" ""
			(at 0 0 90)
			(layer "B.Fab")
			(effects
				(font
					(size 1.27 1.27)
				)
				(justify mirror)
			)
		)
		(duplicate_pad_numbers_are_jumpers no)
		(fp_line
			(start 0.299974 -0.150114)
			(end -0.299974 -0.150114)
			(stroke
				(width 0.1)
				(type default)
			)
			(layer "B.Fab")
		)
		(fp_line
			(start -0.299974 -0.150114)
			(end -0.299974 0.150114)
			(stroke
				(width 0.1)
				(type default)
			)
			(layer "B.Fab")
		)
		(fp_line
			(start 0.299974 0.150114)
			(end 0.299974 -0.150114)
			(stroke
				(width 0.1)
				(type default)
			)
			(layer "B.Fab")
		)
		(fp_line
			(start -0.299974 0.150114)
			(end 0.299974 0.150114)
			(stroke
				(width 0.1)
				(type default)
			)
			(layer "B.Fab")
		)
		(pad "1" smd rect
			(at 0.2667 0 270)
			(size 0.3048 0.381)
			(layers "B.Cu" "B.Mask" "B.Paste")
			(net "P5E_CPU1_P1_TX_BUF_C_DP<1>")
		)
		(pad "2" smd rect
			(at -0.2667 0 270)
			(size 0.3048 0.381)
			(layers "B.Cu" "B.Mask" "B.Paste")
			(net "P5E_CPU1_P1_TX_BUF_DP<1>")
		)
	)
	(footprint ""
		(layer "B.Cu")
		(at 305.423316 -427.2788 180)
		(property "Reference" "R1438"
			(at 0 0 0)
			(layer "B.SilkS")
			(hide yes)
			(effects
				(font
					(size 1.27 1.27)
				)
				(justify mirror)
			)
		)
		(property "Value" ""
			(at 0 0 0)
			(layer "B.Fab")
			(effects
				(font
					(size 1.27 1.27)
				)
				(justify mirror)
			)
		)
		(duplicate_pad_numbers_are_jumpers no)
		(fp_line
			(start 0.32512 0.175006)
			(end 0.32512 -0.175006)
			(stroke
				(width 0.1)
				(type default)
			)
			(layer "B.Fab")
		)
		(fp_line
			(start 0.32512 -0.175006)
			(end -0.32512 -0.175006)
			(stroke
				(width 0.1)
				(type default)
			)
			(layer "B.Fab")
		)
		(fp_line
			(start -0.32512 0.175006)
			(end 0.32512 0.175006)
			(stroke
				(width 0.1)
				(type default)
			)
			(layer "B.Fab")
		)
		(fp_line
			(start -0.32512 -0.175006)
			(end -0.32512 0.175006)
			(stroke
				(width 0.1)
				(type default)
			)
			(layer "B.Fab")
		)
		(pad "1" smd rect
			(at 0.2667 0)
			(size 0.3048 0.381)
			(layers "B.Cu" "B.Mask" "B.Paste")
			(net "P1V8_CPU0_RT_1D")
		)
		(pad "2" smd rect
			(at -0.2667 0 180)
			(size 0.3048 0.381)
			(layers "B.Cu" "B.Mask" "B.Paste")
			(net "JTAG_TDI_RT_CPU0_P0")
		)
	)
	(footprint ""
		(layer "B.Cu")
		(at 146.010884 -320.525902 180)
		(property "Reference" "R1502"
			(at 0 0 0)
			(layer "B.SilkS")
			(hide yes)
			(effects
				(font
					(size 1.27 1.27)
				)
				(justify mirror)
			)
		)
		(property "Value" ""
			(at 0 0 0)
			(layer "B.Fab")
			(effects
				(font
					(size 1.27 1.27)
				)
				(justify mirror)
			)
		)
		(duplicate_pad_numbers_are_jumpers no)
		(fp_line
			(start 0.7874 0.4064)
			(end 0.7874 -0.4064)
			(stroke
				(width 0.1524)
				(type default)
			)
			(layer "B.SilkS")
		)
		(fp_line
			(start 0.7874 -0.4064)
			(end -0.7874 -0.4064)
			(stroke
				(width 0.1524)
				(type default)
			)
			(layer "B.SilkS")
		)
		(fp_line
			(start -0.7874 0.4064)
			(end 0.7874 0.4064)
			(stroke
				(width 0.1524)
				(type default)
			)
			(layer "B.SilkS")
		)
		(fp_line
			(start -0.7874 -0.4064)
			(end -0.7874 0.4064)
			(stroke
				(width 0.1524)
				(type default)
			)
			(layer "B.SilkS")
		)
		(fp_line
			(start 0.67945 0.3048)
			(end 0.67945 -0.305054)
			(stroke
				(width 0.1)
				(type default)
			)
			(layer "B.Fab")
		)
		(fp_line
			(start 0.67945 -0.305054)
			(end 0.12065 -0.305054)
			(stroke
				(width 0.1)
				(type default)
			)
			(layer "B.Fab")
		)
		(fp_line
			(start 0.12065 0.3048)
			(end 0.67945 0.3048)
			(stroke
				(width 0.1)
				(type default)
			)
			(layer "B.Fab")
		)
		(fp_line
			(start 0.12065 0.2794)
			(end 0.12065 0.3048)
			(stroke
				(width 0.1)
				(type default)
			)
			(layer "B.Fab")
		)
		(fp_line
			(start 0.12065 -0.2794)
			(end -0.12065 -0.2794)
			(stroke
				(width 0.1)
				(type default)
			)
			(layer "B.Fab")
		)
		(fp_line
			(start 0.12065 -0.305054)
			(end 0.12065 -0.2794)
			(stroke
				(width 0.1)
				(type default)
			)
			(layer "B.Fab")
		)
		(fp_line
			(start -0.120396 0.3048)
			(end -0.120396 0.2794)
			(stroke
				(width 0.1)
				(type default)
			)
			(layer "B.Fab")
		)
		(fp_line
			(start -0.120396 0.2794)
			(end 0.12065 0.2794)
			(stroke
				(width 0.1)
				(type default)
			)
			(layer "B.Fab")
		)
		(fp_line
			(start -0.12065 -0.2794)
			(end -0.12065 -0.3048)
			(stroke
				(width 0.1)
				(type default)
			)
			(layer "B.Fab")
		)
		(fp_line
			(start -0.12065 -0.3048)
			(end -0.67945 -0.3048)
			(stroke
				(width 0.1)
				(type default)
			)
			(layer "B.Fab")
		)
		(fp_line
			(start -0.67945 0.3048)
			(end -0.120396 0.3048)
			(stroke
				(width 0.1)
				(type default)
			)
			(layer "B.Fab")
		)
		(fp_line
			(start -0.67945 -0.3048)
			(end -0.67945 0.3048)
			(stroke
				(width 0.1)
				(type default)
			)
			(layer "B.Fab")
		)
		(pad "1" smd circle
			(at 0.40005 0)
			(size 0 0)
			(layers "B.Cu" "B.Mask" "B.Paste")
			(net "GND")
		)
		(pad "2" smd circle
			(at -0.40005 0)
			(size 0 0)
			(layers "B.Cu" "B.Mask" "B.Paste")
			(net "CLK_CPU1_RTCCLK")
		)
	)
	(footprint ""
		(layer "B.Cu")
		(at 191.192912 -70.459346)
		(property "Reference" "R82"
			(at 0 0 0)
			(layer "B.SilkS")
			(hide yes)
			(effects
				(font
					(size 1.27 1.27)
				)
				(justify mirror)
			)
		)
		(property "Value" ""
			(at 0 0 0)
			(layer "B.Fab")
			(effects
				(font
					(size 1.27 1.27)
				)
				(justify mirror)
			)
		)
		(duplicate_pad_numbers_are_jumpers no)
		(fp_line
			(start -0.7874 -0.4064)
			(end -0.7874 0.4064)
			(stroke
				(width 0.1524)
				(type default)
			)
			(layer "B.SilkS")
		)
		(fp_line
			(start -0.7874 0.4064)
			(end 0.7874 0.4064)
			(stroke
				(width 0.1524)
				(type default)
			)
			(layer "B.SilkS")
		)
		(fp_line
			(start 0.7874 -0.4064)
			(end -0.7874 -0.4064)
			(stroke
				(width 0.1524)
				(type default)
			)
			(layer "B.SilkS")
		)
		(fp_line
			(start 0.7874 0.4064)
			(end 0.7874 -0.4064)
			(stroke
				(width 0.1524)
				(type default)
			)
			(layer "B.SilkS")
		)
		(fp_line
			(start -0.67945 -0.3048)
			(end -0.67945 0.3048)
			(stroke
				(width 0.1)
				(type default)
			)
			(layer "B.Fab")
		)
		(fp_line
			(start -0.67945 0.3048)
			(end -0.120396 0.3048)
			(stroke
				(width 0.1)
				(type default)
			)
			(layer "B.Fab")
		)
		(fp_line
			(start -0.12065 -0.3048)
			(end -0.67945 -0.3048)
			(stroke
				(width 0.1)
				(type default)
			)
			(layer "B.Fab")
		)
		(fp_line
			(start -0.12065 -0.2794)
			(end -0.12065 -0.3048)
			(stroke
				(width 0.1)
				(type default)
			)
			(layer "B.Fab")
		)
		(fp_line
			(start -0.120396 0.2794)
			(end 0.12065 0.2794)
			(stroke
				(width 0.1)
				(type default)
			)
			(layer "B.Fab")
		)
		(fp_line
			(start -0.120396 0.3048)
			(end -0.120396 0.2794)
			(stroke
				(width 0.1)
				(type default)
			)
			(layer "B.Fab")
		)
		(fp_line
			(start 0.12065 -0.305054)
			(end 0.12065 -0.2794)
			(stroke
				(width 0.1)
				(type default)
			)
			(layer "B.Fab")
		)
		(fp_line
			(start 0.12065 -0.2794)
			(end -0.12065 -0.2794)
			(stroke
				(width 0.1)
				(type default)
			)
			(layer "B.Fab")
		)
		(fp_line
			(start 0.12065 0.2794)
			(end 0.12065 0.3048)
			(stroke
				(width 0.1)
				(type default)
			)
			(layer "B.Fab")
		)
		(fp_line
			(start 0.12065 0.3048)
			(end 0.67945 0.3048)
			(stroke
				(width 0.1)
				(type default)
			)
			(layer "B.Fab")
		)
		(fp_line
			(start 0.67945 -0.305054)
			(end 0.12065 -0.305054)
			(stroke
				(width 0.1)
				(type default)
			)
			(layer "B.Fab")
		)
		(fp_line
			(start 0.67945 0.3048)
			(end 0.67945 -0.305054)
			(stroke
				(width 0.1)
				(type default)
			)
			(layer "B.Fab")
		)
		(pad "1" smd circle
			(at 0.40005 0 180)
			(size 0 0)
			(layers "B.Cu" "B.Mask" "B.Paste")
			(net "RMII_BMC_OCP_TX_EN")
		)
		(pad "2" smd circle
			(at -0.40005 0 180)
			(size 0 0)
			(layers "B.Cu" "B.Mask" "B.Paste")
			(net "GND")
		)
	)
	(footprint ""
		(layer "B.Cu")
		(at 289.941 -426.466)
		(property "Reference" "R2674"
			(at 0 0 0)
			(layer "B.SilkS")
			(hide yes)
			(effects
				(font
					(size 1.27 1.27)
				)
				(justify mirror)
			)
		)
		(property "Value" ""
			(at 0 0 0)
			(layer "B.Fab")
			(effects
				(font
					(size 1.27 1.27)
				)
				(justify mirror)
			)
		)
		(duplicate_pad_numbers_are_jumpers no)
		(fp_line
			(start -0.7874 -0.4064)
			(end -0.7874 0.4064)
			(stroke
				(width 0.1524)
				(type default)
			)
			(layer "B.SilkS")
		)
		(fp_line
			(start -0.7874 0.4064)
			(end 0.7874 0.4064)
			(stroke
				(width 0.1524)
				(type default)
			)
			(layer "B.SilkS")
		)
		(fp_line
			(start 0.7874 -0.4064)
			(end -0.7874 -0.4064)
			(stroke
				(width 0.1524)
				(type default)
			)
			(layer "B.SilkS")
		)
		(fp_line
			(start 0.7874 0.4064)
			(end 0.7874 -0.4064)
			(stroke
				(width 0.1524)
				(type default)
			)
			(layer "B.SilkS")
		)
		(fp_line
			(start -0.67945 -0.3048)
			(end -0.67945 0.3048)
			(stroke
				(width 0.1)
				(type default)
			)
			(layer "B.Fab")
		)
		(fp_line
			(start -0.67945 0.3048)
			(end -0.120396 0.3048)
			(stroke
				(width 0.1)
				(type default)
			)
			(layer "B.Fab")
		)
		(fp_line
			(start -0.12065 -0.3048)
			(end -0.67945 -0.3048)
			(stroke
				(width 0.1)
				(type default)
			)
			(layer "B.Fab")
		)
		(fp_line
			(start -0.12065 -0.2794)
			(end -0.12065 -0.3048)
			(stroke
				(width 0.1)
				(type default)
			)
			(layer "B.Fab")
		)
		(fp_line
			(start -0.120396 0.2794)
			(end 0.12065 0.2794)
			(stroke
				(width 0.1)
				(type default)
			)
			(layer "B.Fab")
		)
		(fp_line
			(start -0.120396 0.3048)
			(end -0.120396 0.2794)
			(stroke
				(width 0.1)
				(type default)
			)
			(layer "B.Fab")
		)
		(fp_line
			(start 0.12065 -0.305054)
			(end 0.12065 -0.2794)
			(stroke
				(width 0.1)
				(type default)
			)
			(layer "B.Fab")
		)
		(fp_line
			(start 0.12065 -0.2794)
			(end -0.12065 -0.2794)
			(stroke
				(width 0.1)
				(type default)
			)
			(layer "B.Fab")
		)
		(fp_line
			(start 0.12065 0.2794)
			(end 0.12065 0.3048)
			(stroke
				(width 0.1)
				(type default)
			)
			(layer "B.Fab")
		)
		(fp_line
			(start 0.12065 0.3048)
			(end 0.67945 0.3048)
			(stroke
				(width 0.1)
				(type default)
			)
			(layer "B.Fab")
		)
		(fp_line
			(start 0.67945 -0.305054)
			(end 0.12065 -0.305054)
			(stroke
				(width 0.1)
				(type default)
			)
			(layer "B.Fab")
		)
		(fp_line
			(start 0.67945 0.3048)
			(end 0.67945 -0.305054)
			(stroke
				(width 0.1)
				(type default)
			)
			(layer "B.Fab")
		)
		(pad "1" smd circle
			(at 0.40005 0 180)
			(size 0 0)
			(layers "B.Cu" "B.Mask" "B.Paste")
			(net "I3C_BMC_SWB_BUF_R_SDA")
		)
		(pad "2" smd circle
			(at -0.40005 0 180)
			(size 0 0)
			(layers "B.Cu" "B.Mask" "B.Paste")
			(net "I3C_BMC_SWB_BUF_SDA")
		)
	)
	(footprint ""
		(layer "B.Cu")
		(at 216.027 -338.455 -90)
		(property "Reference" "R6750"
			(at 0 0 90)
			(layer "B.SilkS")
			(hide yes)
			(effects
				(font
					(size 1.27 1.27)
				)
				(justify mirror)
			)
		)
		(property "Value" ""
			(at 0 0 90)
			(layer "B.Fab")
			(effects
				(font
					(size 1.27 1.27)
				)
				(justify mirror)
			)
		)
		(duplicate_pad_numbers_are_jumpers no)
		(fp_line
			(start -0.32512 0.175006)
			(end 0.32512 0.175006)
			(stroke
				(width 0.1)
				(type default)
			)
			(layer "B.Fab")
		)
		(fp_line
			(start 0.32512 0.175006)
			(end 0.32512 -0.175006)
			(stroke
				(width 0.1)
				(type default)
			)
			(layer "B.Fab")
		)
		(fp_line
			(start -0.32512 -0.175006)
			(end -0.32512 0.175006)
			(stroke
				(width 0.1)
				(type default)
			)
			(layer "B.Fab")
		)
		(fp_line
			(start 0.32512 -0.175006)
			(end -0.32512 -0.175006)
			(stroke
				(width 0.1)
				(type default)
			)
			(layer "B.Fab")
		)
		(pad "1" smd rect
			(at 0.2667 0 90)
			(size 0.3048 0.381)
			(layers "B.Cu" "B.Mask" "B.Paste")
			(net "P1V8_CPU1_RT_1D")
		)
		(pad "2" smd rect
			(at -0.2667 0 270)
			(size 0.3048 0.381)
			(layers "B.Cu" "B.Mask" "B.Paste")
			(net "SMB_RT_CPU1_P3_R_SDA")
		)
	)
	(footprint ""
		(layer "B.Cu")
		(at 349.105982 -395.148562 90)
		(property "Reference" "C624"
			(at 0 0 90)
			(layer "B.SilkS")
			(hide yes)
			(effects
				(font
					(size 1.27 1.27)
				)
				(justify mirror)
			)
		)
		(property "Value" ""
			(at 0 0 90)
			(layer "B.Fab")
			(effects
				(font
					(size 1.27 1.27)
				)
				(justify mirror)
			)
		)
		(duplicate_pad_numbers_are_jumpers no)
		(fp_line
			(start 0.299974 -0.150114)
			(end -0.299974 -0.150114)
			(stroke
				(width 0.1)
				(type default)
			)
			(layer "B.Fab")
		)
		(fp_line
			(start -0.299974 -0.150114)
			(end -0.299974 0.150114)
			(stroke
				(width 0.1)
				(type default)
			)
			(layer "B.Fab")
		)
		(fp_line
			(start 0.299974 0.150114)
			(end 0.299974 -0.150114)
			(stroke
				(width 0.1)
				(type default)
			)
			(layer "B.Fab")
		)
		(fp_line
			(start -0.299974 0.150114)
			(end 0.299974 0.150114)
			(stroke
				(width 0.1)
				(type default)
			)
			(layer "B.Fab")
		)
		(pad "1" smd rect
			(at 0.2667 0 270)
			(size 0.3048 0.381)
			(layers "B.Cu" "B.Mask" "B.Paste")
			(net "P0V9_CPU0_RT1_2A_2D")
		)
		(pad "2" smd rect
			(at -0.2667 0 270)
			(size 0.3048 0.381)
			(layers "B.Cu" "B.Mask" "B.Paste")
			(net "GND")
		)
	)
	(footprint ""
		(layer "B.Cu")
		(at 188.838078 -97.085912 -90)
		(property "Reference" "R261"
			(at 0 0 90)
			(layer "B.SilkS")
			(hide yes)
			(effects
				(font
					(size 1.27 1.27)
				)
				(justify mirror)
			)
		)
		(property "Value" ""
			(at 0 0 90)
			(layer "B.Fab")
			(effects
				(font
					(size 1.27 1.27)
				)
				(justify mirror)
			)
		)
		(duplicate_pad_numbers_are_jumpers no)
		(fp_line
			(start -0.7874 0.4064)
			(end 0.7874 0.4064)
			(stroke
				(width 0.1524)
				(type default)
			)
			(layer "B.SilkS")
		)
		(fp_line
			(start 0.7874 0.4064)
			(end 0.7874 -0.4064)
			(stroke
				(width 0.1524)
				(type default)
			)
			(layer "B.SilkS")
		)
		(fp_line
			(start -0.7874 -0.4064)
			(end -0.7874 0.4064)
			(stroke
				(width 0.1524)
				(type default)
			)
			(layer "B.SilkS")
		)
		(fp_line
			(start 0.7874 -0.4064)
			(end -0.7874 -0.4064)
			(stroke
				(width 0.1524)
				(type default)
			)
			(layer "B.SilkS")
		)
		(fp_line
			(start -0.67945 0.3048)
			(end -0.120396 0.3048)
			(stroke
				(width 0.1)
				(type default)
			)
			(layer "B.Fab")
		)
		(fp_line
			(start -0.120396 0.3048)
			(end -0.120396 0.2794)
			(stroke
				(width 0.1)
				(type default)
			)
			(layer "B.Fab")
		)
		(fp_line
			(start 0.12065 0.3048)
			(end 0.67945 0.3048)
			(stroke
				(width 0.1)
				(type default)
			)
			(layer "B.Fab")
		)
		(fp_line
			(start 0.67945 0.3048)
			(end 0.67945 -0.305054)
			(stroke
				(width 0.1)
				(type default)
			)
			(layer "B.Fab")
		)
		(fp_line
			(start -0.120396 0.2794)
			(end 0.12065 0.2794)
			(stroke
				(width 0.1)
				(type default)
			)
			(layer "B.Fab")
		)
		(fp_line
			(start 0.12065 0.2794)
			(end 0.12065 0.3048)
			(stroke
				(width 0.1)
				(type default)
			)
			(layer "B.Fab")
		)
		(fp_line
			(start -0.12065 -0.2794)
			(end -0.12065 -0.3048)
			(stroke
				(width 0.1)
				(type default)
			)
			(layer "B.Fab")
		)
		(fp_line
			(start 0.12065 -0.2794)
			(end -0.12065 -0.2794)
			(stroke
				(width 0.1)
				(type default)
			)
			(layer "B.Fab")
		)
		(fp_line
			(start -0.67945 -0.3048)
			(end -0.67945 0.3048)
			(stroke
				(width 0.1)
				(type default)
			)
			(layer "B.Fab")
		)
		(fp_line
			(start -0.12065 -0.3048)
			(end -0.67945 -0.3048)
			(stroke
				(width 0.1)
				(type default)
			)
			(layer "B.Fab")
		)
		(fp_line
			(start 0.12065 -0.305054)
			(end 0.12065 -0.2794)
			(stroke
				(width 0.1)
				(type default)
			)
			(layer "B.Fab")
		)
		(fp_line
			(start 0.67945 -0.305054)
			(end 0.12065 -0.305054)
			(stroke
				(width 0.1)
				(type default)
			)
			(layer "B.Fab")
		)
		(pad "1" smd circle
			(at 0.40005 0 90)
			(size 0 0)
			(layers "B.Cu" "B.Mask" "B.Paste")
			(net "CPU1_SP5R2")
		)
		(pad "2" smd circle
			(at -0.40005 0 90)
			(size 0 0)
			(layers "B.Cu" "B.Mask" "B.Paste")
			(net "FM_CPU1_SP5R2")
		)
	)
	(footprint ""
		(layer "B.Cu")
		(at 348.786958 -252.54331 180)
		(property "Reference" "C2518"
			(at 0 0 0)
			(layer "B.SilkS")
			(hide yes)
			(effects
				(font
					(size 1.27 1.27)
				)
				(justify mirror)
			)
		)
		(property "Value" ""
			(at 0 0 0)
			(layer "B.Fab")
			(effects
				(font
					(size 1.27 1.27)
				)
				(justify mirror)
			)
		)
		(duplicate_pad_numbers_are_jumpers no)
		(fp_line
			(start 0.7874 0.4064)
			(end 0.7874 -0.4064)
			(stroke
				(width 0.1524)
				(type default)
			)
			(layer "B.SilkS")
		)
		(fp_line
			(start 0.7874 -0.4064)
			(end -0.7874 -0.4064)
			(stroke
				(width 0.1524)
				(type default)
			)
			(layer "B.SilkS")
		)
		(fp_line
			(start -0.7874 0.4064)
			(end 0.7874 0.4064)
			(stroke
				(width 0.1524)
				(type default)
			)
			(layer "B.SilkS")
		)
		(fp_line
			(start -0.7874 -0.4064)
			(end -0.7874 0.4064)
			(stroke
				(width 0.1524)
				(type default)
			)
			(layer "B.SilkS")
		)
		(fp_line
			(start 0.67945 0.3048)
			(end 0.67945 -0.305054)
			(stroke
				(width 0.1)
				(type default)
			)
			(layer "B.Fab")
		)
		(fp_line
			(start 0.67945 -0.305054)
			(end 0.12065 -0.305054)
			(stroke
				(width 0.1)
				(type default)
			)
			(layer "B.Fab")
		)
		(fp_line
			(start 0.12065 0.3048)
			(end 0.67945 0.3048)
			(stroke
				(width 0.1)
				(type default)
			)
			(layer "B.Fab")
		)
		(fp_line
			(start 0.12065 0.2794)
			(end 0.12065 0.3048)
			(stroke
				(width 0.1)
				(type default)
			)
			(layer "B.Fab")
		)
		(fp_line
			(start 0.12065 -0.2794)
			(end -0.12065 -0.2794)
			(stroke
				(width 0.1)
				(type default)
			)
			(layer "B.Fab")
		)
		(fp_line
			(start 0.12065 -0.305054)
			(end 0.12065 -0.2794)
			(stroke
				(width 0.1)
				(type default)
			)
			(layer "B.Fab")
		)
		(fp_line
			(start -0.120396 0.3048)
			(end -0.120396 0.2794)
			(stroke
				(width 0.1)
				(type default)
			)
			(layer "B.Fab")
		)
		(fp_line
			(start -0.120396 0.2794)
			(end 0.12065 0.2794)
			(stroke
				(width 0.1)
				(type default)
			)
			(layer "B.Fab")
		)
		(fp_line
			(start -0.12065 -0.2794)
			(end -0.12065 -0.3048)
			(stroke
				(width 0.1)
				(type default)
			)
			(layer "B.Fab")
		)
		(fp_line
			(start -0.12065 -0.3048)
			(end -0.67945 -0.3048)
			(stroke
				(width 0.1)
				(type default)
			)
			(layer "B.Fab")
		)
		(fp_line
			(start -0.67945 0.3048)
			(end -0.120396 0.3048)
			(stroke
				(width 0.1)
				(type default)
			)
			(layer "B.Fab")
		)
		(fp_line
			(start -0.67945 -0.3048)
			(end -0.67945 0.3048)
			(stroke
				(width 0.1)
				(type default)
			)
			(layer "B.Fab")
		)
		(pad "1" smd circle
			(at 0.40005 0)
			(size 0 0)
			(layers "B.Cu" "B.Mask" "B.Paste")
			(net "PVDD18_S5_P0")
		)
		(pad "2" smd circle
			(at -0.40005 0)
			(size 0 0)
			(layers "B.Cu" "B.Mask" "B.Paste")
			(net "GND")
		)
	)
	(footprint ""
		(layer "B.Cu")
		(at 344.446098 -396.393162 -90)
		(property "Reference" "C599"
			(at 0 0 90)
			(layer "B.SilkS")
			(hide yes)
			(effects
				(font
					(size 1.27 1.27)
				)
				(justify mirror)
			)
		)
		(property "Value" ""
			(at 0 0 90)
			(layer "B.Fab")
			(effects
				(font
					(size 1.27 1.27)
				)
				(justify mirror)
			)
		)
		(duplicate_pad_numbers_are_jumpers no)
		(fp_line
			(start -0.299974 0.150114)
			(end 0.299974 0.150114)
			(stroke
				(width 0.1)
				(type default)
			)
			(layer "B.Fab")
		)
		(fp_line
			(start 0.299974 0.150114)
			(end 0.299974 -0.150114)
			(stroke
				(width 0.1)
				(type default)
			)
			(layer "B.Fab")
		)
		(fp_line
			(start -0.299974 -0.150114)
			(end -0.299974 0.150114)
			(stroke
				(width 0.1)
				(type default)
			)
			(layer "B.Fab")
		)
		(fp_line
			(start 0.299974 -0.150114)
			(end -0.299974 -0.150114)
			(stroke
				(width 0.1)
				(type default)
			)
			(layer "B.Fab")
		)
		(pad "1" smd rect
			(at 0.2667 0 90)
			(size 0.3048 0.381)
			(layers "B.Cu" "B.Mask" "B.Paste")
			(net "P1V8_CPU0_RT1_1A")
		)
		(pad "2" smd rect
			(at -0.2667 0 90)
			(size 0.3048 0.381)
			(layers "B.Cu" "B.Mask" "B.Paste")
			(net "GND")
		)
	)
	(footprint ""
		(layer "B.Cu")
		(at 76.453746 -336.05216 -90)
		(property "Reference" "PR257"
			(at 0 0 90)
			(layer "B.SilkS")
			(hide yes)
			(effects
				(font
					(size 1.27 1.27)
				)
				(justify mirror)
			)
		)
		(property "Value" ""
			(at 0 0 90)
			(layer "B.Fab")
			(effects
				(font
					(size 1.27 1.27)
				)
				(justify mirror)
			)
		)
		(duplicate_pad_numbers_are_jumpers no)
		(fp_line
			(start -0.7874 0.4064)
			(end 0.7874 0.4064)
			(stroke
				(width 0.1524)
				(type default)
			)
			(layer "B.SilkS")
		)
		(fp_line
			(start 0.7874 0.4064)
			(end 0.7874 -0.4064)
			(stroke
				(width 0.1524)
				(type default)
			)
			(layer "B.SilkS")
		)
		(fp_line
			(start -0.7874 -0.4064)
			(end -0.7874 0.4064)
			(stroke
				(width 0.1524)
				(type default)
			)
			(layer "B.SilkS")
		)
		(fp_line
			(start 0.7874 -0.4064)
			(end -0.7874 -0.4064)
			(stroke
				(width 0.1524)
				(type default)
			)
			(layer "B.SilkS")
		)
		(fp_line
			(start -0.67945 0.3048)
			(end -0.120396 0.3048)
			(stroke
				(width 0.1)
				(type default)
			)
			(layer "B.Fab")
		)
		(fp_line
			(start -0.120396 0.3048)
			(end -0.120396 0.2794)
			(stroke
				(width 0.1)
				(type default)
			)
			(layer "B.Fab")
		)
		(fp_line
			(start 0.12065 0.3048)
			(end 0.67945 0.3048)
			(stroke
				(width 0.1)
				(type default)
			)
			(layer "B.Fab")
		)
		(fp_line
			(start 0.67945 0.3048)
			(end 0.67945 -0.305054)
			(stroke
				(width 0.1)
				(type default)
			)
			(layer "B.Fab")
		)
		(fp_line
			(start -0.120396 0.2794)
			(end 0.12065 0.2794)
			(stroke
				(width 0.1)
				(type default)
			)
			(layer "B.Fab")
		)
		(fp_line
			(start 0.12065 0.2794)
			(end 0.12065 0.3048)
			(stroke
				(width 0.1)
				(type default)
			)
			(layer "B.Fab")
		)
		(fp_line
			(start -0.12065 -0.2794)
			(end -0.12065 -0.3048)
			(stroke
				(width 0.1)
				(type default)
			)
			(layer "B.Fab")
		)
		(fp_line
			(start 0.12065 -0.2794)
			(end -0.12065 -0.2794)
			(stroke
				(width 0.1)
				(type default)
			)
			(layer "B.Fab")
		)
		(fp_line
			(start -0.67945 -0.3048)
			(end -0.67945 0.3048)
			(stroke
				(width 0.1)
				(type default)
			)
			(layer "B.Fab")
		)
		(fp_line
			(start -0.12065 -0.3048)
			(end -0.67945 -0.3048)
			(stroke
				(width 0.1)
				(type default)
			)
			(layer "B.Fab")
		)
		(fp_line
			(start 0.12065 -0.305054)
			(end 0.12065 -0.2794)
			(stroke
				(width 0.1)
				(type default)
			)
			(layer "B.Fab")
		)
		(fp_line
			(start 0.67945 -0.305054)
			(end 0.12065 -0.305054)
			(stroke
				(width 0.1)
				(type default)
			)
			(layer "B.Fab")
		)
		(pad "1" smd circle
			(at 0.40005 0 90)
			(size 0 0)
			(layers "B.Cu" "B.Mask" "B.Paste")
			(net "PVDDCR_CPU1_P1_PVCC")
		)
		(pad "2" smd circle
			(at -0.40005 0 90)
			(size 0 0)
			(layers "B.Cu" "B.Mask" "B.Paste")
			(net "PVDDCR_CPU1_P1_VCC2")
		)
	)
	(footprint ""
		(layer "B.Cu")
		(at 90.503502 -207.41005 90)
		(property "Reference" "R862"
			(at 0 0 90)
			(layer "B.SilkS")
			(hide yes)
			(effects
				(font
					(size 1.27 1.27)
				)
				(justify mirror)
			)
		)
		(property "Value" ""
			(at 0 0 90)
			(layer "B.Fab")
			(effects
				(font
					(size 1.27 1.27)
				)
				(justify mirror)
			)
		)
		(duplicate_pad_numbers_are_jumpers no)
		(fp_line
			(start 0.7874 -0.4064)
			(end -0.7874 -0.4064)
			(stroke
				(width 0.1524)
				(type default)
			)
			(layer "B.SilkS")
		)
		(fp_line
			(start -0.7874 -0.4064)
			(end -0.7874 0.4064)
			(stroke
				(width 0.1524)
				(type default)
			)
			(layer "B.SilkS")
		)
		(fp_line
			(start 0.7874 0.4064)
			(end 0.7874 -0.4064)
			(stroke
				(width 0.1524)
				(type default)
			)
			(layer "B.SilkS")
		)
		(fp_line
			(start -0.7874 0.4064)
			(end 0.7874 0.4064)
			(stroke
				(width 0.1524)
				(type default)
			)
			(layer "B.SilkS")
		)
		(fp_line
			(start 0.67945 -0.305054)
			(end 0.12065 -0.305054)
			(stroke
				(width 0.1)
				(type default)
			)
			(layer "B.Fab")
		)
		(fp_line
			(start 0.12065 -0.305054)
			(end 0.12065 -0.2794)
			(stroke
				(width 0.1)
				(type default)
			)
			(layer "B.Fab")
		)
		(fp_line
			(start -0.12065 -0.3048)
			(end -0.67945 -0.3048)
			(stroke
				(width 0.1)
				(type default)
			)
			(layer "B.Fab")
		)
		(fp_line
			(start -0.67945 -0.3048)
			(end -0.67945 0.3048)
			(stroke
				(width 0.1)
				(type default)
			)
			(layer "B.Fab")
		)
		(fp_line
			(start 0.12065 -0.2794)
			(end -0.12065 -0.2794)
			(stroke
				(width 0.1)
				(type default)
			)
			(layer "B.Fab")
		)
		(fp_line
			(start -0.12065 -0.2794)
			(end -0.12065 -0.3048)
			(stroke
				(width 0.1)
				(type default)
			)
			(layer "B.Fab")
		)
		(fp_line
			(start 0.12065 0.2794)
			(end 0.12065 0.3048)
			(stroke
				(width 0.1)
				(type default)
			)
			(layer "B.Fab")
		)
		(fp_line
			(start -0.120396 0.2794)
			(end 0.12065 0.2794)
			(stroke
				(width 0.1)
				(type default)
			)
			(layer "B.Fab")
		)
		(fp_line
			(start 0.67945 0.3048)
			(end 0.67945 -0.305054)
			(stroke
				(width 0.1)
				(type default)
			)
			(layer "B.Fab")
		)
		(fp_line
			(start 0.12065 0.3048)
			(end 0.67945 0.3048)
			(stroke
				(width 0.1)
				(type default)
			)
			(layer "B.Fab")
		)
		(fp_line
			(start -0.120396 0.3048)
			(end -0.120396 0.2794)
			(stroke
				(width 0.1)
				(type default)
			)
			(layer "B.Fab")
		)
		(fp_line
			(start -0.67945 0.3048)
			(end -0.120396 0.3048)
			(stroke
				(width 0.1)
				(type default)
			)
			(layer "B.Fab")
		)
		(pad "1" smd circle
			(at 0.40005 0 270)
			(size 0 0)
			(layers "B.Cu" "B.Mask" "B.Paste")
			(net "CPU1_XTRIG_R2_L6")
		)
		(pad "2" smd circle
			(at -0.40005 0 270)
			(size 0 0)
			(layers "B.Cu" "B.Mask" "B.Paste")
			(net "CPU1_XTRIG_L6")
		)
	)
	(footprint ""
		(layer "B.Cu")
		(at 406.698958 -327.910952 180)
		(property "Reference" "R288"
			(at 0 0 0)
			(layer "B.SilkS")
			(hide yes)
			(effects
				(font
					(size 1.27 1.27)
				)
				(justify mirror)
			)
		)
		(property "Value" ""
			(at 0 0 0)
			(layer "B.Fab")
			(effects
				(font
					(size 1.27 1.27)
				)
				(justify mirror)
			)
		)
		(duplicate_pad_numbers_are_jumpers no)
		(fp_line
			(start 0.7874 0.4064)
			(end 0.7874 -0.4064)
			(stroke
				(width 0.1524)
				(type default)
			)
			(layer "B.SilkS")
		)
		(fp_line
			(start 0.7874 -0.4064)
			(end -0.7874 -0.4064)
			(stroke
				(width 0.1524)
				(type default)
			)
			(layer "B.SilkS")
		)
		(fp_line
			(start -0.7874 0.4064)
			(end 0.7874 0.4064)
			(stroke
				(width 0.1524)
				(type default)
			)
			(layer "B.SilkS")
		)
		(fp_line
			(start -0.7874 -0.4064)
			(end -0.7874 0.4064)
			(stroke
				(width 0.1524)
				(type default)
			)
			(layer "B.SilkS")
		)
		(fp_line
			(start 0.67945 0.3048)
			(end 0.67945 -0.305054)
			(stroke
				(width 0.1)
				(type default)
			)
			(layer "B.Fab")
		)
		(fp_line
			(start 0.67945 -0.305054)
			(end 0.12065 -0.305054)
			(stroke
				(width 0.1)
				(type default)
			)
			(layer "B.Fab")
		)
		(fp_line
			(start 0.12065 0.3048)
			(end 0.67945 0.3048)
			(stroke
				(width 0.1)
				(type default)
			)
			(layer "B.Fab")
		)
		(fp_line
			(start 0.12065 0.2794)
			(end 0.12065 0.3048)
			(stroke
				(width 0.1)
				(type default)
			)
			(layer "B.Fab")
		)
		(fp_line
			(start 0.12065 -0.2794)
			(end -0.12065 -0.2794)
			(stroke
				(width 0.1)
				(type default)
			)
			(layer "B.Fab")
		)
		(fp_line
			(start 0.12065 -0.305054)
			(end 0.12065 -0.2794)
			(stroke
				(width 0.1)
				(type default)
			)
			(layer "B.Fab")
		)
		(fp_line
			(start -0.120396 0.3048)
			(end -0.120396 0.2794)
			(stroke
				(width 0.1)
				(type default)
			)
			(layer "B.Fab")
		)
		(fp_line
			(start -0.120396 0.2794)
			(end 0.12065 0.2794)
			(stroke
				(width 0.1)
				(type default)
			)
			(layer "B.Fab")
		)
		(fp_line
			(start -0.12065 -0.2794)
			(end -0.12065 -0.3048)
			(stroke
				(width 0.1)
				(type default)
			)
			(layer "B.Fab")
		)
		(fp_line
			(start -0.12065 -0.3048)
			(end -0.67945 -0.3048)
			(stroke
				(width 0.1)
				(type default)
			)
			(layer "B.Fab")
		)
		(fp_line
			(start -0.67945 0.3048)
			(end -0.120396 0.3048)
			(stroke
				(width 0.1)
				(type default)
			)
			(layer "B.Fab")
		)
		(fp_line
			(start -0.67945 -0.3048)
			(end -0.67945 0.3048)
			(stroke
				(width 0.1)
				(type default)
			)
			(layer "B.Fab")
		)
		(pad "1" smd circle
			(at 0.40005 0)
			(size 0 0)
			(layers "B.Cu" "B.Mask" "B.Paste")
			(net "CPU0_PWR_GD_OUT")
		)
		(pad "2" smd circle
			(at -0.40005 0)
			(size 0 0)
			(layers "B.Cu" "B.Mask" "B.Paste")
			(net "PVDD18_S5_P0")
		)
	)
	(footprint ""
		(layer "B.Cu")
		(at 175.46701 -427.92269)
		(property "Reference" "R8111"
			(at 0 0 0)
			(layer "B.SilkS")
			(hide yes)
			(effects
				(font
					(size 1.27 1.27)
				)
				(justify mirror)
			)
		)
		(property "Value" ""
			(at 0 0 0)
			(layer "B.Fab")
			(effects
				(font
					(size 1.27 1.27)
				)
				(justify mirror)
			)
		)
		(duplicate_pad_numbers_are_jumpers no)
		(fp_line
			(start -0.7874 -0.4064)
			(end -0.7874 0.4064)
			(stroke
				(width 0.1524)
				(type default)
			)
			(layer "B.SilkS")
		)
		(fp_line
			(start -0.7874 0.4064)
			(end 0.7874 0.4064)
			(stroke
				(width 0.1524)
				(type default)
			)
			(layer "B.SilkS")
		)
		(fp_line
			(start 0.7874 -0.4064)
			(end -0.7874 -0.4064)
			(stroke
				(width 0.1524)
				(type default)
			)
			(layer "B.SilkS")
		)
		(fp_line
			(start 0.7874 0.4064)
			(end 0.7874 -0.4064)
			(stroke
				(width 0.1524)
				(type default)
			)
			(layer "B.SilkS")
		)
		(fp_line
			(start -0.67945 -0.3048)
			(end -0.67945 0.3048)
			(stroke
				(width 0.1)
				(type default)
			)
			(layer "B.Fab")
		)
		(fp_line
			(start -0.67945 0.3048)
			(end -0.120396 0.3048)
			(stroke
				(width 0.1)
				(type default)
			)
			(layer "B.Fab")
		)
		(fp_line
			(start -0.12065 -0.3048)
			(end -0.67945 -0.3048)
			(stroke
				(width 0.1)
				(type default)
			)
			(layer "B.Fab")
		)
		(fp_line
			(start -0.12065 -0.2794)
			(end -0.12065 -0.3048)
			(stroke
				(width 0.1)
				(type default)
			)
			(layer "B.Fab")
		)
		(fp_line
			(start -0.120396 0.2794)
			(end 0.12065 0.2794)
			(stroke
				(width 0.1)
				(type default)
			)
			(layer "B.Fab")
		)
		(fp_line
			(start -0.120396 0.3048)
			(end -0.120396 0.2794)
			(stroke
				(width 0.1)
				(type default)
			)
			(layer "B.Fab")
		)
		(fp_line
			(start 0.12065 -0.305054)
			(end 0.12065 -0.2794)
			(stroke
				(width 0.1)
				(type default)
			)
			(layer "B.Fab")
		)
		(fp_line
			(start 0.12065 -0.2794)
			(end -0.12065 -0.2794)
			(stroke
				(width 0.1)
				(type default)
			)
			(layer "B.Fab")
		)
		(fp_line
			(start 0.12065 0.2794)
			(end 0.12065 0.3048)
			(stroke
				(width 0.1)
				(type default)
			)
			(layer "B.Fab")
		)
		(fp_line
			(start 0.12065 0.3048)
			(end 0.67945 0.3048)
			(stroke
				(width 0.1)
				(type default)
			)
			(layer "B.Fab")
		)
		(fp_line
			(start 0.67945 -0.305054)
			(end 0.12065 -0.305054)
			(stroke
				(width 0.1)
				(type default)
			)
			(layer "B.Fab")
		)
		(fp_line
			(start 0.67945 0.3048)
			(end 0.67945 -0.305054)
			(stroke
				(width 0.1)
				(type default)
			)
			(layer "B.Fab")
		)
		(pad "1" smd circle
			(at 0.40005 0 180)
			(size 0 0)
			(layers "B.Cu" "B.Mask" "B.Paste")
			(net "P3V3_AUX")
		)
		(pad "2" smd circle
			(at -0.40005 0 180)
			(size 0 0)
			(layers "B.Cu" "B.Mask" "B.Paste")
			(net "A_HSC_LOW_GATE")
		)
	)
	(footprint ""
		(layer "B.Cu")
		(at 108.50626 -35.088068 90)
		(property "Reference" "C6109"
			(at 0 0 90)
			(layer "B.SilkS")
			(hide yes)
			(effects
				(font
					(size 1.27 1.27)
				)
				(justify mirror)
			)
		)
		(property "Value" ""
			(at 0 0 90)
			(layer "B.Fab")
			(effects
				(font
					(size 1.27 1.27)
				)
				(justify mirror)
			)
		)
		(duplicate_pad_numbers_are_jumpers no)
		(fp_line
			(start 0.7874 -0.4064)
			(end -0.7874 -0.4064)
			(stroke
				(width 0.1524)
				(type default)
			)
			(layer "B.SilkS")
		)
		(fp_line
			(start -0.7874 -0.4064)
			(end -0.7874 0.4064)
			(stroke
				(width 0.1524)
				(type default)
			)
			(layer "B.SilkS")
		)
		(fp_line
			(start 0.7874 0.4064)
			(end 0.7874 -0.4064)
			(stroke
				(width 0.1524)
				(type default)
			)
			(layer "B.SilkS")
		)
		(fp_line
			(start -0.7874 0.4064)
			(end 0.7874 0.4064)
			(stroke
				(width 0.1524)
				(type default)
			)
			(layer "B.SilkS")
		)
		(fp_line
			(start 0.67945 -0.305054)
			(end 0.12065 -0.305054)
			(stroke
				(width 0.1)
				(type default)
			)
			(layer "B.Fab")
		)
		(fp_line
			(start 0.12065 -0.305054)
			(end 0.12065 -0.2794)
			(stroke
				(width 0.1)
				(type default)
			)
			(layer "B.Fab")
		)
		(fp_line
			(start -0.12065 -0.3048)
			(end -0.67945 -0.3048)
			(stroke
				(width 0.1)
				(type default)
			)
			(layer "B.Fab")
		)
		(fp_line
			(start -0.67945 -0.3048)
			(end -0.67945 0.3048)
			(stroke
				(width 0.1)
				(type default)
			)
			(layer "B.Fab")
		)
		(fp_line
			(start 0.12065 -0.2794)
			(end -0.12065 -0.2794)
			(stroke
				(width 0.1)
				(type default)
			)
			(layer "B.Fab")
		)
		(fp_line
			(start -0.12065 -0.2794)
			(end -0.12065 -0.3048)
			(stroke
				(width 0.1)
				(type default)
			)
			(layer "B.Fab")
		)
		(fp_line
			(start 0.12065 0.2794)
			(end 0.12065 0.3048)
			(stroke
				(width 0.1)
				(type default)
			)
			(layer "B.Fab")
		)
		(fp_line
			(start -0.120396 0.2794)
			(end 0.12065 0.2794)
			(stroke
				(width 0.1)
				(type default)
			)
			(layer "B.Fab")
		)
		(fp_line
			(start 0.67945 0.3048)
			(end 0.67945 -0.305054)
			(stroke
				(width 0.1)
				(type default)
			)
			(layer "B.Fab")
		)
		(fp_line
			(start 0.12065 0.3048)
			(end 0.67945 0.3048)
			(stroke
				(width 0.1)
				(type default)
			)
			(layer "B.Fab")
		)
		(fp_line
			(start -0.120396 0.3048)
			(end -0.120396 0.2794)
			(stroke
				(width 0.1)
				(type default)
			)
			(layer "B.Fab")
		)
		(fp_line
			(start -0.67945 0.3048)
			(end -0.120396 0.3048)
			(stroke
				(width 0.1)
				(type default)
			)
			(layer "B.Fab")
		)
		(pad "1" smd circle
			(at 0.40005 0 270)
			(size 0 0)
			(layers "B.Cu" "B.Mask" "B.Paste")
			(net "P1V2_CPU0_USB2_DVDD12")
		)
		(pad "2" smd circle
			(at -0.40005 0 270)
			(size 0 0)
			(layers "B.Cu" "B.Mask" "B.Paste")
			(net "GND")
		)
	)
	(footprint ""
		(layer "B.Cu")
		(at 145.046192 -387.05028)
		(property "Reference" "C384"
			(at 0 0 0)
			(layer "B.SilkS")
			(hide yes)
			(effects
				(font
					(size 1.27 1.27)
				)
				(justify mirror)
			)
		)
		(property "Value" ""
			(at 0 0 0)
			(layer "B.Fab")
			(effects
				(font
					(size 1.27 1.27)
				)
				(justify mirror)
			)
		)
		(duplicate_pad_numbers_are_jumpers no)
		(fp_line
			(start -0.299974 -0.150114)
			(end -0.299974 0.150114)
			(stroke
				(width 0.1)
				(type default)
			)
			(layer "B.Fab")
		)
		(fp_line
			(start -0.299974 0.150114)
			(end 0.299974 0.150114)
			(stroke
				(width 0.1)
				(type default)
			)
			(layer "B.Fab")
		)
		(fp_line
			(start 0.299974 -0.150114)
			(end -0.299974 -0.150114)
			(stroke
				(width 0.1)
				(type default)
			)
			(layer "B.Fab")
		)
		(fp_line
			(start 0.299974 0.150114)
			(end 0.299974 -0.150114)
			(stroke
				(width 0.1)
				(type default)
			)
			(layer "B.Fab")
		)
		(pad "1" smd rect
			(at 0.2667 0 180)
			(size 0.3048 0.381)
			(layers "B.Cu" "B.Mask" "B.Paste")
			(net "P0V9_CPU1_RT2_2A")
		)
		(pad "2" smd rect
			(at -0.2667 0 180)
			(size 0.3048 0.381)
			(layers "B.Cu" "B.Mask" "B.Paste")
			(net "GND")
		)
	)
	(footprint ""
		(layer "B.Cu")
		(at 108.145834 -250.257564)
		(property "Reference" "C2301"
			(at 0 0 0)
			(layer "B.SilkS")
			(hide yes)
			(effects
				(font
					(size 1.27 1.27)
				)
				(justify mirror)
			)
		)
		(property "Value" ""
			(at 0 0 0)
			(layer "B.Fab")
			(effects
				(font
					(size 1.27 1.27)
				)
				(justify mirror)
			)
		)
		(duplicate_pad_numbers_are_jumpers no)
		(fp_line
			(start -0.7874 -0.4064)
			(end -0.7874 0.4064)
			(stroke
				(width 0.1524)
				(type default)
			)
			(layer "B.SilkS")
		)
		(fp_line
			(start -0.7874 0.4064)
			(end 0.7874 0.4064)
			(stroke
				(width 0.1524)
				(type default)
			)
			(layer "B.SilkS")
		)
		(fp_line
			(start 0.7874 -0.4064)
			(end -0.7874 -0.4064)
			(stroke
				(width 0.1524)
				(type default)
			)
			(layer "B.SilkS")
		)
		(fp_line
			(start 0.7874 0.4064)
			(end 0.7874 -0.4064)
			(stroke
				(width 0.1524)
				(type default)
			)
			(layer "B.SilkS")
		)
		(fp_line
			(start -0.67945 -0.3048)
			(end -0.67945 0.3048)
			(stroke
				(width 0.1)
				(type default)
			)
			(layer "B.Fab")
		)
		(fp_line
			(start -0.67945 0.3048)
			(end -0.120396 0.3048)
			(stroke
				(width 0.1)
				(type default)
			)
			(layer "B.Fab")
		)
		(fp_line
			(start -0.12065 -0.3048)
			(end -0.67945 -0.3048)
			(stroke
				(width 0.1)
				(type default)
			)
			(layer "B.Fab")
		)
		(fp_line
			(start -0.12065 -0.2794)
			(end -0.12065 -0.3048)
			(stroke
				(width 0.1)
				(type default)
			)
			(layer "B.Fab")
		)
		(fp_line
			(start -0.120396 0.2794)
			(end 0.12065 0.2794)
			(stroke
				(width 0.1)
				(type default)
			)
			(layer "B.Fab")
		)
		(fp_line
			(start -0.120396 0.3048)
			(end -0.120396 0.2794)
			(stroke
				(width 0.1)
				(type default)
			)
			(layer "B.Fab")
		)
		(fp_line
			(start 0.12065 -0.305054)
			(end 0.12065 -0.2794)
			(stroke
				(width 0.1)
				(type default)
			)
			(layer "B.Fab")
		)
		(fp_line
			(start 0.12065 -0.2794)
			(end -0.12065 -0.2794)
			(stroke
				(width 0.1)
				(type default)
			)
			(layer "B.Fab")
		)
		(fp_line
			(start 0.12065 0.2794)
			(end 0.12065 0.3048)
			(stroke
				(width 0.1)
				(type default)
			)
			(layer "B.Fab")
		)
		(fp_line
			(start 0.12065 0.3048)
			(end 0.67945 0.3048)
			(stroke
				(width 0.1)
				(type default)
			)
			(layer "B.Fab")
		)
		(fp_line
			(start 0.67945 -0.305054)
			(end 0.12065 -0.305054)
			(stroke
				(width 0.1)
				(type default)
			)
			(layer "B.Fab")
		)
		(fp_line
			(start 0.67945 0.3048)
			(end 0.67945 -0.305054)
			(stroke
				(width 0.1)
				(type default)
			)
			(layer "B.Fab")
		)
		(pad "1" smd circle
			(at 0.40005 0 180)
			(size 0 0)
			(layers "B.Cu" "B.Mask" "B.Paste")
			(net "PVDDCR_CPU0_P1")
		)
		(pad "2" smd circle
			(at -0.40005 0 180)
			(size 0 0)
			(layers "B.Cu" "B.Mask" "B.Paste")
			(net "GND")
		)
	)
	(footprint ""
		(layer "B.Cu")
		(at 202.903836 -193.99631)
		(property "Reference" "R115"
			(at 0 0 0)
			(layer "B.SilkS")
			(hide yes)
			(effects
				(font
					(size 1.27 1.27)
				)
				(justify mirror)
			)
		)
		(property "Value" ""
			(at 0 0 0)
			(layer "B.Fab")
			(effects
				(font
					(size 1.27 1.27)
				)
				(justify mirror)
			)
		)
		(duplicate_pad_numbers_are_jumpers no)
		(fp_line
			(start -0.7874 -0.4064)
			(end -0.7874 0.4064)
			(stroke
				(width 0.1524)
				(type default)
			)
			(layer "B.SilkS")
		)
		(fp_line
			(start -0.7874 0.4064)
			(end 0.7874 0.4064)
			(stroke
				(width 0.1524)
				(type default)
			)
			(layer "B.SilkS")
		)
		(fp_line
			(start 0.7874 -0.4064)
			(end -0.7874 -0.4064)
			(stroke
				(width 0.1524)
				(type default)
			)
			(layer "B.SilkS")
		)
		(fp_line
			(start 0.7874 0.4064)
			(end 0.7874 -0.4064)
			(stroke
				(width 0.1524)
				(type default)
			)
			(layer "B.SilkS")
		)
		(fp_line
			(start -0.67945 -0.3048)
			(end -0.67945 0.3048)
			(stroke
				(width 0.1)
				(type default)
			)
			(layer "B.Fab")
		)
		(fp_line
			(start -0.67945 0.3048)
			(end -0.120396 0.3048)
			(stroke
				(width 0.1)
				(type default)
			)
			(layer "B.Fab")
		)
		(fp_line
			(start -0.12065 -0.3048)
			(end -0.67945 -0.3048)
			(stroke
				(width 0.1)
				(type default)
			)
			(layer "B.Fab")
		)
		(fp_line
			(start -0.12065 -0.2794)
			(end -0.12065 -0.3048)
			(stroke
				(width 0.1)
				(type default)
			)
			(layer "B.Fab")
		)
		(fp_line
			(start -0.120396 0.2794)
			(end 0.12065 0.2794)
			(stroke
				(width 0.1)
				(type default)
			)
			(layer "B.Fab")
		)
		(fp_line
			(start -0.120396 0.3048)
			(end -0.120396 0.2794)
			(stroke
				(width 0.1)
				(type default)
			)
			(layer "B.Fab")
		)
		(fp_line
			(start 0.12065 -0.305054)
			(end 0.12065 -0.2794)
			(stroke
				(width 0.1)
				(type default)
			)
			(layer "B.Fab")
		)
		(fp_line
			(start 0.12065 -0.2794)
			(end -0.12065 -0.2794)
			(stroke
				(width 0.1)
				(type default)
			)
			(layer "B.Fab")
		)
		(fp_line
			(start 0.12065 0.2794)
			(end 0.12065 0.3048)
			(stroke
				(width 0.1)
				(type default)
			)
			(layer "B.Fab")
		)
		(fp_line
			(start 0.12065 0.3048)
			(end 0.67945 0.3048)
			(stroke
				(width 0.1)
				(type default)
			)
			(layer "B.Fab")
		)
		(fp_line
			(start 0.67945 -0.305054)
			(end 0.12065 -0.305054)
			(stroke
				(width 0.1)
				(type default)
			)
			(layer "B.Fab")
		)
		(fp_line
			(start 0.67945 0.3048)
			(end 0.67945 -0.305054)
			(stroke
				(width 0.1)
				(type default)
			)
			(layer "B.Fab")
		)
		(pad "1" smd circle
			(at 0.40005 0 180)
			(size 0 0)
			(layers "B.Cu" "B.Mask" "B.Paste")
			(net "P3V3")
		)
		(pad "2" smd circle
			(at -0.40005 0 180)
			(size 0 0)
			(layers "B.Cu" "B.Mask" "B.Paste")
			(net "PWRGD_CHL_CPU1_DIMM")
		)
	)
	(footprint ""
		(layer "B.Cu")
		(at 96.84639 -388.011162 -90)
		(property "Reference" "C340"
			(at 0 0 90)
			(layer "B.SilkS")
			(hide yes)
			(effects
				(font
					(size 1.27 1.27)
				)
				(justify mirror)
			)
		)
		(property "Value" ""
			(at 0 0 90)
			(layer "B.Fab")
			(effects
				(font
					(size 1.27 1.27)
				)
				(justify mirror)
			)
		)
		(duplicate_pad_numbers_are_jumpers no)
		(fp_line
			(start -0.299974 0.150114)
			(end 0.299974 0.150114)
			(stroke
				(width 0.1)
				(type default)
			)
			(layer "B.Fab")
		)
		(fp_line
			(start 0.299974 0.150114)
			(end 0.299974 -0.150114)
			(stroke
				(width 0.1)
				(type default)
			)
			(layer "B.Fab")
		)
		(fp_line
			(start -0.299974 -0.150114)
			(end -0.299974 0.150114)
			(stroke
				(width 0.1)
				(type default)
			)
			(layer "B.Fab")
		)
		(fp_line
			(start 0.299974 -0.150114)
			(end -0.299974 -0.150114)
			(stroke
				(width 0.1)
				(type default)
			)
			(layer "B.Fab")
		)
		(pad "1" smd rect
			(at 0.2667 0 90)
			(size 0.3048 0.381)
			(layers "B.Cu" "B.Mask" "B.Paste")
			(net "P0V9_CPU1_RT1_2A")
		)
		(pad "2" smd rect
			(at -0.2667 0 90)
			(size 0.3048 0.381)
			(layers "B.Cu" "B.Mask" "B.Paste")
			(net "GND")
		)
	)
	(footprint ""
		(layer "B.Cu")
		(at 125.389386 -259.73024)
		(property "Reference" "C2462"
			(at 0 0 0)
			(layer "B.SilkS")
			(hide yes)
			(effects
				(font
					(size 1.27 1.27)
				)
				(justify mirror)
			)
		)
		(property "Value" ""
			(at 0 0 0)
			(layer "B.Fab")
			(effects
				(font
					(size 1.27 1.27)
				)
				(justify mirror)
			)
		)
		(duplicate_pad_numbers_are_jumpers no)
		(fp_line
			(start -0.7874 -0.4064)
			(end -0.7874 0.4064)
			(stroke
				(width 0.1524)
				(type default)
			)
			(layer "B.SilkS")
		)
		(fp_line
			(start -0.7874 0.4064)
			(end 0.7874 0.4064)
			(stroke
				(width 0.1524)
				(type default)
			)
			(layer "B.SilkS")
		)
		(fp_line
			(start 0.7874 -0.4064)
			(end -0.7874 -0.4064)
			(stroke
				(width 0.1524)
				(type default)
			)
			(layer "B.SilkS")
		)
		(fp_line
			(start 0.7874 0.4064)
			(end 0.7874 -0.4064)
			(stroke
				(width 0.1524)
				(type default)
			)
			(layer "B.SilkS")
		)
		(fp_line
			(start -0.67945 -0.3048)
			(end -0.67945 0.3048)
			(stroke
				(width 0.1)
				(type default)
			)
			(layer "B.Fab")
		)
		(fp_line
			(start -0.67945 0.3048)
			(end -0.120396 0.3048)
			(stroke
				(width 0.1)
				(type default)
			)
			(layer "B.Fab")
		)
		(fp_line
			(start -0.12065 -0.3048)
			(end -0.67945 -0.3048)
			(stroke
				(width 0.1)
				(type default)
			)
			(layer "B.Fab")
		)
		(fp_line
			(start -0.12065 -0.2794)
			(end -0.12065 -0.3048)
			(stroke
				(width 0.1)
				(type default)
			)
			(layer "B.Fab")
		)
		(fp_line
			(start -0.120396 0.2794)
			(end 0.12065 0.2794)
			(stroke
				(width 0.1)
				(type default)
			)
			(layer "B.Fab")
		)
		(fp_line
			(start -0.120396 0.3048)
			(end -0.120396 0.2794)
			(stroke
				(width 0.1)
				(type default)
			)
			(layer "B.Fab")
		)
		(fp_line
			(start 0.12065 -0.305054)
			(end 0.12065 -0.2794)
			(stroke
				(width 0.1)
				(type default)
			)
			(layer "B.Fab")
		)
		(fp_line
			(start 0.12065 -0.2794)
			(end -0.12065 -0.2794)
			(stroke
				(width 0.1)
				(type default)
			)
			(layer "B.Fab")
		)
		(fp_line
			(start 0.12065 0.2794)
			(end 0.12065 0.3048)
			(stroke
				(width 0.1)
				(type default)
			)
			(layer "B.Fab")
		)
		(fp_line
			(start 0.12065 0.3048)
			(end 0.67945 0.3048)
			(stroke
				(width 0.1)
				(type default)
			)
			(layer "B.Fab")
		)
		(fp_line
			(start 0.67945 -0.305054)
			(end 0.12065 -0.305054)
			(stroke
				(width 0.1)
				(type default)
			)
			(layer "B.Fab")
		)
		(fp_line
			(start 0.67945 0.3048)
			(end 0.67945 -0.305054)
			(stroke
				(width 0.1)
				(type default)
			)
			(layer "B.Fab")
		)
		(pad "1" smd circle
			(at 0.40005 0 180)
			(size 0 0)
			(layers "B.Cu" "B.Mask" "B.Paste")
			(net "PVDDCR_SOC_P1")
		)
		(pad "2" smd circle
			(at -0.40005 0 180)
			(size 0 0)
			(layers "B.Cu" "B.Mask" "B.Paste")
			(net "GND")
		)
	)
	(footprint ""
		(layer "B.Cu")
		(at 415.285682 -416.899344 90)
		(property "Reference" "C6626"
			(at 0 0 90)
			(layer "B.SilkS")
			(hide yes)
			(effects
				(font
					(size 1.27 1.27)
				)
				(justify mirror)
			)
		)
		(property "Value" ""
			(at 0 0 90)
			(layer "B.Fab")
			(effects
				(font
					(size 1.27 1.27)
				)
				(justify mirror)
			)
		)
		(duplicate_pad_numbers_are_jumpers no)
		(fp_line
			(start 0.299974 -0.150114)
			(end -0.299974 -0.150114)
			(stroke
				(width 0.1)
				(type default)
			)
			(layer "B.Fab")
		)
		(fp_line
			(start -0.299974 -0.150114)
			(end -0.299974 0.150114)
			(stroke
				(width 0.1)
				(type default)
			)
			(layer "B.Fab")
		)
		(fp_line
			(start 0.299974 0.150114)
			(end 0.299974 -0.150114)
			(stroke
				(width 0.1)
				(type default)
			)
			(layer "B.Fab")
		)
		(fp_line
			(start -0.299974 0.150114)
			(end 0.299974 0.150114)
			(stroke
				(width 0.1)
				(type default)
			)
			(layer "B.Fab")
		)
		(pad "1" smd rect
			(at 0.2667 0 270)
			(size 0.3048 0.381)
			(layers "B.Cu" "B.Mask" "B.Paste")
			(net "P5E_CPU0_P3_TX_BUF_C_DN<14>")
		)
		(pad "2" smd rect
			(at -0.2667 0 270)
			(size 0.3048 0.381)
			(layers "B.Cu" "B.Mask" "B.Paste")
			(net "P5E_CPU0_P3_TX_BUF_DN<14>")
		)
	)
	(footprint ""
		(layer "B.Cu")
		(at 102.780084 -384.575558)
		(property "Reference" "L5"
			(at 0 0 0)
			(layer "B.SilkS")
			(hide yes)
			(effects
				(font
					(size 1.27 1.27)
				)
				(justify mirror)
			)
		)
		(property "Value" ""
			(at 0 0 0)
			(layer "B.Fab")
			(effects
				(font
					(size 1.27 1.27)
				)
				(justify mirror)
			)
		)
		(duplicate_pad_numbers_are_jumpers no)
		(fp_line
			(start -1.63576 -0.8128)
			(end -1.63576 0.8128)
			(stroke
				(width 0.1524)
				(type default)
			)
			(layer "B.SilkS")
		)
		(fp_line
			(start -1.63576 0.8128)
			(end 1.63576 0.8128)
			(stroke
				(width 0.1524)
				(type default)
			)
			(layer "B.SilkS")
		)
		(fp_line
			(start 1.63576 -0.8128)
			(end -1.63576 -0.8128)
			(stroke
				(width 0.1524)
				(type default)
			)
			(layer "B.SilkS")
		)
		(fp_line
			(start 1.63576 -0.8128)
			(end 1.63576 0.8128)
			(stroke
				(width 0.1524)
				(type default)
			)
			(layer "B.SilkS")
		)
		(fp_line
			(start -1.560576 -0.738632)
			(end 1.56083 -0.738632)
			(stroke
				(width 0.1)
				(type default)
			)
			(layer "B.Fab")
		)
		(fp_line
			(start -1.560576 0.7366)
			(end -1.560576 -0.738632)
			(stroke
				(width 0.1)
				(type default)
			)
			(layer "B.Fab")
		)
		(fp_line
			(start -1.524 0.7366)
			(end -1.560576 0.7366)
			(stroke
				(width 0.1)
				(type default)
			)
			(layer "B.Fab")
		)
		(fp_line
			(start 1.524 0.7366)
			(end -1.524 0.7366)
			(stroke
				(width 0.1)
				(type default)
			)
			(layer "B.Fab")
		)
		(fp_line
			(start 1.56083 -0.738632)
			(end 1.56083 0.7366)
			(stroke
				(width 0.1)
				(type default)
			)
			(layer "B.Fab")
		)
		(fp_line
			(start 1.56083 0.7366)
			(end 1.524 0.7366)
			(stroke
				(width 0.1)
				(type default)
			)
			(layer "B.Fab")
		)
		(pad "1" smd rect
			(at 0.94996 0)
			(size 1.1176 1.3716)
			(layers "B.Cu" "B.Mask" "B.Paste")
			(net "P1V8_CPU1_RT_1D")
		)
		(pad "2" smd rect
			(at -0.94996 0)
			(size 1.1176 1.3716)
			(layers "B.Cu" "B.Mask" "B.Paste")
			(net "P1V8_CPU1_RT1_1A")
		)
	)
	(footprint ""
		(layer "B.Cu")
		(at 80.046322 -388.011162 -90)
		(property "Reference" "C341"
			(at 0 0 90)
			(layer "B.SilkS")
			(hide yes)
			(effects
				(font
					(size 1.27 1.27)
				)
				(justify mirror)
			)
		)
		(property "Value" ""
			(at 0 0 90)
			(layer "B.Fab")
			(effects
				(font
					(size 1.27 1.27)
				)
				(justify mirror)
			)
		)
		(duplicate_pad_numbers_are_jumpers no)
		(fp_line
			(start -0.299974 0.150114)
			(end 0.299974 0.150114)
			(stroke
				(width 0.1)
				(type default)
			)
			(layer "B.Fab")
		)
		(fp_line
			(start 0.299974 0.150114)
			(end 0.299974 -0.150114)
			(stroke
				(width 0.1)
				(type default)
			)
			(layer "B.Fab")
		)
		(fp_line
			(start -0.299974 -0.150114)
			(end -0.299974 0.150114)
			(stroke
				(width 0.1)
				(type default)
			)
			(layer "B.Fab")
		)
		(fp_line
			(start 0.299974 -0.150114)
			(end -0.299974 -0.150114)
			(stroke
				(width 0.1)
				(type default)
			)
			(layer "B.Fab")
		)
		(pad "1" smd rect
			(at 0.2667 0 90)
			(size 0.3048 0.381)
			(layers "B.Cu" "B.Mask" "B.Paste")
			(net "P0V9_CPU1_RT1_2A")
		)
		(pad "2" smd rect
			(at -0.2667 0 90)
			(size 0.3048 0.381)
			(layers "B.Cu" "B.Mask" "B.Paste")
			(net "GND")
		)
	)
	(footprint ""
		(layer "B.Cu")
		(at 117.895624 -262.205216)
		(property "Reference" "C2492"
			(at 0 0 0)
			(layer "B.SilkS")
			(hide yes)
			(effects
				(font
					(size 1.27 1.27)
				)
				(justify mirror)
			)
		)
		(property "Value" ""
			(at 0 0 0)
			(layer "B.Fab")
			(effects
				(font
					(size 1.27 1.27)
				)
				(justify mirror)
			)
		)
		(duplicate_pad_numbers_are_jumpers no)
		(fp_line
			(start -0.7874 -0.4064)
			(end -0.7874 0.4064)
			(stroke
				(width 0.1524)
				(type default)
			)
			(layer "B.SilkS")
		)
		(fp_line
			(start -0.7874 0.4064)
			(end 0.7874 0.4064)
			(stroke
				(width 0.1524)
				(type default)
			)
			(layer "B.SilkS")
		)
		(fp_line
			(start 0.7874 -0.4064)
			(end -0.7874 -0.4064)
			(stroke
				(width 0.1524)
				(type default)
			)
			(layer "B.SilkS")
		)
		(fp_line
			(start 0.7874 0.4064)
			(end 0.7874 -0.4064)
			(stroke
				(width 0.1524)
				(type default)
			)
			(layer "B.SilkS")
		)
		(fp_line
			(start -0.67945 -0.3048)
			(end -0.67945 0.3048)
			(stroke
				(width 0.1)
				(type default)
			)
			(layer "B.Fab")
		)
		(fp_line
			(start -0.67945 0.3048)
			(end -0.120396 0.3048)
			(stroke
				(width 0.1)
				(type default)
			)
			(layer "B.Fab")
		)
		(fp_line
			(start -0.12065 -0.3048)
			(end -0.67945 -0.3048)
			(stroke
				(width 0.1)
				(type default)
			)
			(layer "B.Fab")
		)
		(fp_line
			(start -0.12065 -0.2794)
			(end -0.12065 -0.3048)
			(stroke
				(width 0.1)
				(type default)
			)
			(layer "B.Fab")
		)
		(fp_line
			(start -0.120396 0.2794)
			(end 0.12065 0.2794)
			(stroke
				(width 0.1)
				(type default)
			)
			(layer "B.Fab")
		)
		(fp_line
			(start -0.120396 0.3048)
			(end -0.120396 0.2794)
			(stroke
				(width 0.1)
				(type default)
			)
			(layer "B.Fab")
		)
		(fp_line
			(start 0.12065 -0.305054)
			(end 0.12065 -0.2794)
			(stroke
				(width 0.1)
				(type default)
			)
			(layer "B.Fab")
		)
		(fp_line
			(start 0.12065 -0.2794)
			(end -0.12065 -0.2794)
			(stroke
				(width 0.1)
				(type default)
			)
			(layer "B.Fab")
		)
		(fp_line
			(start 0.12065 0.2794)
			(end 0.12065 0.3048)
			(stroke
				(width 0.1)
				(type default)
			)
			(layer "B.Fab")
		)
		(fp_line
			(start 0.12065 0.3048)
			(end 0.67945 0.3048)
			(stroke
				(width 0.1)
				(type default)
			)
			(layer "B.Fab")
		)
		(fp_line
			(start 0.67945 -0.305054)
			(end 0.12065 -0.305054)
			(stroke
				(width 0.1)
				(type default)
			)
			(layer "B.Fab")
		)
		(fp_line
			(start 0.67945 0.3048)
			(end 0.67945 -0.305054)
			(stroke
				(width 0.1)
				(type default)
			)
			(layer "B.Fab")
		)
		(pad "1" smd circle
			(at 0.40005 0 180)
			(size 0 0)
			(layers "B.Cu" "B.Mask" "B.Paste")
			(net "PVDD11_S3_P1")
		)
		(pad "2" smd circle
			(at -0.40005 0 180)
			(size 0 0)
			(layers "B.Cu" "B.Mask" "B.Paste")
			(net "GND")
		)
	)
	(footprint ""
		(layer "B.Cu")
		(at 97.853754 -178.886612 90)
		(property "Reference" "PC294_3"
			(at 0 0 90)
			(layer "B.SilkS")
			(hide yes)
			(effects
				(font
					(size 1.27 1.27)
				)
				(justify mirror)
			)
		)
		(property "Value" ""
			(at 0 0 90)
			(layer "B.Fab")
			(effects
				(font
					(size 1.27 1.27)
				)
				(justify mirror)
			)
		)
		(duplicate_pad_numbers_are_jumpers no)
		(fp_line
			(start 1.524 -0.762)
			(end -1.524 -0.762)
			(stroke
				(width 0.1524)
				(type default)
			)
			(layer "B.SilkS")
		)
		(fp_line
			(start -1.524 -0.762)
			(end -1.524 0.762)
			(stroke
				(width 0.1524)
				(type default)
			)
			(layer "B.SilkS")
		)
		(fp_line
			(start 1.524 0.762)
			(end 1.524 -0.762)
			(stroke
				(width 0.1524)
				(type default)
			)
			(layer "B.SilkS")
		)
		(fp_line
			(start -1.524 0.762)
			(end 1.524 0.762)
			(stroke
				(width 0.1524)
				(type default)
			)
			(layer "B.SilkS")
		)
		(fp_line
			(start 1.1049 -0.724916)
			(end 1.1049 0.724916)
			(stroke
				(width 0.1)
				(type default)
			)
			(layer "B.Fab")
		)
		(fp_line
			(start -1.1049 -0.724916)
			(end 1.1049 -0.724916)
			(stroke
				(width 0.1)
				(type default)
			)
			(layer "B.Fab")
		)
		(fp_line
			(start 1.1049 0.724916)
			(end -1.1049 0.724916)
			(stroke
				(width 0.1)
				(type default)
			)
			(layer "B.Fab")
		)
		(fp_line
			(start -1.1049 0.724916)
			(end -1.1049 -0.724916)
			(stroke
				(width 0.1)
				(type default)
			)
			(layer "B.Fab")
		)
		(pad "1" smd rect
			(at 0.889 0 90)
			(size 1.016 1.27)
			(layers "B.Cu" "B.Mask" "B.Paste")
			(net "SW_P12V_AUX_PVDDCR_CPU0_P1_FLT")
		)
		(pad "2" smd rect
			(at -0.889 0 90)
			(size 1.016 1.27)
			(layers "B.Cu" "B.Mask" "B.Paste")
			(net "GND")
		)
	)
	(footprint ""
		(layer "B.Cu")
		(at 102.656386 -264.354564)
		(property "Reference" "C2495"
			(at 0 0 0)
			(layer "B.SilkS")
			(hide yes)
			(effects
				(font
					(size 1.27 1.27)
				)
				(justify mirror)
			)
		)
		(property "Value" ""
			(at 0 0 0)
			(layer "B.Fab")
			(effects
				(font
					(size 1.27 1.27)
				)
				(justify mirror)
			)
		)
		(duplicate_pad_numbers_are_jumpers no)
		(fp_line
			(start -0.7874 -0.4064)
			(end -0.7874 0.4064)
			(stroke
				(width 0.1524)
				(type default)
			)
			(layer "B.SilkS")
		)
		(fp_line
			(start -0.7874 0.4064)
			(end 0.7874 0.4064)
			(stroke
				(width 0.1524)
				(type default)
			)
			(layer "B.SilkS")
		)
		(fp_line
			(start 0.7874 -0.4064)
			(end -0.7874 -0.4064)
			(stroke
				(width 0.1524)
				(type default)
			)
			(layer "B.SilkS")
		)
		(fp_line
			(start 0.7874 0.4064)
			(end 0.7874 -0.4064)
			(stroke
				(width 0.1524)
				(type default)
			)
			(layer "B.SilkS")
		)
		(fp_line
			(start -0.67945 -0.3048)
			(end -0.67945 0.3048)
			(stroke
				(width 0.1)
				(type default)
			)
			(layer "B.Fab")
		)
		(fp_line
			(start -0.67945 0.3048)
			(end -0.120396 0.3048)
			(stroke
				(width 0.1)
				(type default)
			)
			(layer "B.Fab")
		)
		(fp_line
			(start -0.12065 -0.3048)
			(end -0.67945 -0.3048)
			(stroke
				(width 0.1)
				(type default)
			)
			(layer "B.Fab")
		)
		(fp_line
			(start -0.12065 -0.2794)
			(end -0.12065 -0.3048)
			(stroke
				(width 0.1)
				(type default)
			)
			(layer "B.Fab")
		)
		(fp_line
			(start -0.120396 0.2794)
			(end 0.12065 0.2794)
			(stroke
				(width 0.1)
				(type default)
			)
			(layer "B.Fab")
		)
		(fp_line
			(start -0.120396 0.3048)
			(end -0.120396 0.2794)
			(stroke
				(width 0.1)
				(type default)
			)
			(layer "B.Fab")
		)
		(fp_line
			(start 0.12065 -0.305054)
			(end 0.12065 -0.2794)
			(stroke
				(width 0.1)
				(type default)
			)
			(layer "B.Fab")
		)
		(fp_line
			(start 0.12065 -0.2794)
			(end -0.12065 -0.2794)
			(stroke
				(width 0.1)
				(type default)
			)
			(layer "B.Fab")
		)
		(fp_line
			(start 0.12065 0.2794)
			(end 0.12065 0.3048)
			(stroke
				(width 0.1)
				(type default)
			)
			(layer "B.Fab")
		)
		(fp_line
			(start 0.12065 0.3048)
			(end 0.67945 0.3048)
			(stroke
				(width 0.1)
				(type default)
			)
			(layer "B.Fab")
		)
		(fp_line
			(start 0.67945 -0.305054)
			(end 0.12065 -0.305054)
			(stroke
				(width 0.1)
				(type default)
			)
			(layer "B.Fab")
		)
		(fp_line
			(start 0.67945 0.3048)
			(end 0.67945 -0.305054)
			(stroke
				(width 0.1)
				(type default)
			)
			(layer "B.Fab")
		)
		(pad "1" smd circle
			(at 0.40005 0 180)
			(size 0 0)
			(layers "B.Cu" "B.Mask" "B.Paste")
			(net "PVDD11_S3_P1")
		)
		(pad "2" smd circle
			(at -0.40005 0 180)
			(size 0 0)
			(layers "B.Cu" "B.Mask" "B.Paste")
			(net "GND")
		)
	)
	(footprint ""
		(layer "B.Cu")
		(at 350.204278 -254.507492 -60)
		(property "Reference" "C2561"
			(at 0 0 120)
			(layer "B.SilkS")
			(hide yes)
			(effects
				(font
					(size 1.27 1.27)
				)
				(justify mirror)
			)
		)
		(property "Value" ""
			(at 0 0 120)
			(layer "B.Fab")
			(effects
				(font
					(size 1.27 1.27)
				)
				(justify mirror)
			)
		)
		(duplicate_pad_numbers_are_jumpers no)
		(fp_line
			(start -0.787516 0.406438)
			(end 0.787425 0.40652)
			(stroke
				(width 0.1524)
				(type default)
			)
			(layer "B.SilkS")
		)
		(fp_line
			(start -0.787425 -0.40652)
			(end -0.787516 0.406438)
			(stroke
				(width 0.1524)
				(type default)
			)
			(layer "B.SilkS")
		)
		(fp_line
			(start 0.787425 0.40652)
			(end 0.787516 -0.406438)
			(stroke
				(width 0.1524)
				(type default)
			)
			(layer "B.SilkS")
		)
		(fp_line
			(start 0.787516 -0.406438)
			(end -0.787425 -0.40652)
			(stroke
				(width 0.1524)
				(type default)
			)
			(layer "B.SilkS")
		)
		(fp_line
			(start -0.679568 0.304811)
			(end -0.120258 0.304812)
			(stroke
				(width 0.1)
				(type default)
			)
			(layer "B.Fab")
		)
		(fp_line
			(start -0.120258 0.304812)
			(end -0.120334 0.279545)
			(stroke
				(width 0.1)
				(type default)
			)
			(layer "B.Fab")
		)
		(fp_line
			(start -0.120334 0.279545)
			(end 0.120587 0.279326)
			(stroke
				(width 0.1)
				(type default)
			)
			(layer "B.Fab")
		)
		(fp_line
			(start 0.120536 0.304813)
			(end 0.6795 0.304908)
			(stroke
				(width 0.1)
				(type default)
			)
			(layer "B.Fab")
		)
		(fp_line
			(start 0.120587 0.279326)
			(end 0.120536 0.304813)
			(stroke
				(width 0.1)
				(type default)
			)
			(layer "B.Fab")
		)
		(fp_line
			(start -0.6795 -0.304908)
			(end -0.679568 0.304811)
			(stroke
				(width 0.1)
				(type default)
			)
			(layer "B.Fab")
		)
		(fp_line
			(start 0.6795 0.304908)
			(end 0.679475 -0.305158)
			(stroke
				(width 0.1)
				(type default)
			)
			(layer "B.Fab")
		)
		(fp_line
			(start -0.120587 -0.279326)
			(end -0.120536 -0.304813)
			(stroke
				(width 0.1)
				(type default)
			)
			(layer "B.Fab")
		)
		(fp_line
			(start -0.120536 -0.304813)
			(end -0.6795 -0.304908)
			(stroke
				(width 0.1)
				(type default)
			)
			(layer "B.Fab")
		)
		(fp_line
			(start 0.120554 -0.279418)
			(end -0.120587 -0.279326)
			(stroke
				(width 0.1)
				(type default)
			)
			(layer "B.Fab")
		)
		(fp_line
			(start 0.120732 -0.305125)
			(end 0.120554 -0.279418)
			(stroke
				(width 0.1)
				(type default)
			)
			(layer "B.Fab")
		)
		(fp_line
			(start 0.679475 -0.305158)
			(end 0.120732 -0.305125)
			(stroke
				(width 0.1)
				(type default)
			)
			(layer "B.Fab")
		)
		(pad "1" smd circle
			(at 0.40005 0 120)
			(size 0 0)
			(layers "B.Cu" "B.Mask" "B.Paste")
			(net "PVDDCR_SOC_P0")
		)
		(pad "2" smd circle
			(at -0.40005 0 120)
			(size 0 0)
			(layers "B.Cu" "B.Mask" "B.Paste")
			(net "GND")
		)
	)
	(footprint ""
		(layer "B.Cu")
		(at 142.893542 -383.7432 180)
		(property "Reference" "R869"
			(at 0 0 0)
			(layer "B.SilkS")
			(hide yes)
			(effects
				(font
					(size 1.27 1.27)
				)
				(justify mirror)
			)
		)
		(property "Value" ""
			(at 0 0 0)
			(layer "B.Fab")
			(effects
				(font
					(size 1.27 1.27)
				)
				(justify mirror)
			)
		)
		(duplicate_pad_numbers_are_jumpers no)
		(fp_line
			(start 0.32512 0.175006)
			(end 0.32512 -0.175006)
			(stroke
				(width 0.1)
				(type default)
			)
			(layer "B.Fab")
		)
		(fp_line
			(start 0.32512 -0.175006)
			(end -0.32512 -0.175006)
			(stroke
				(width 0.1)
				(type default)
			)
			(layer "B.Fab")
		)
		(fp_line
			(start -0.32512 0.175006)
			(end 0.32512 0.175006)
			(stroke
				(width 0.1)
				(type default)
			)
			(layer "B.Fab")
		)
		(fp_line
			(start -0.32512 -0.175006)
			(end -0.32512 0.175006)
			(stroke
				(width 0.1)
				(type default)
			)
			(layer "B.Fab")
		)
		(pad "1" smd rect
			(at 0.2667 0)
			(size 0.3048 0.381)
			(layers "B.Cu" "B.Mask" "B.Paste")
			(net "RT_CPU1_P2_SCAN_MODE")
		)
		(pad "2" smd rect
			(at -0.2667 0 180)
			(size 0.3048 0.381)
			(layers "B.Cu" "B.Mask" "B.Paste")
			(net "GND")
		)
	)
	(footprint ""
		(layer "B.Cu")
		(at 197.269608 -107.529376 180)
		(property "Reference" "R285"
			(at 0 0 0)
			(layer "B.SilkS")
			(hide yes)
			(effects
				(font
					(size 1.27 1.27)
				)
				(justify mirror)
			)
		)
		(property "Value" ""
			(at 0 0 0)
			(layer "B.Fab")
			(effects
				(font
					(size 1.27 1.27)
				)
				(justify mirror)
			)
		)
		(duplicate_pad_numbers_are_jumpers no)
		(fp_line
			(start 0.7874 0.4064)
			(end 0.7874 -0.4064)
			(stroke
				(width 0.1524)
				(type default)
			)
			(layer "B.SilkS")
		)
		(fp_line
			(start 0.7874 -0.4064)
			(end -0.7874 -0.4064)
			(stroke
				(width 0.1524)
				(type default)
			)
			(layer "B.SilkS")
		)
		(fp_line
			(start -0.7874 0.4064)
			(end 0.7874 0.4064)
			(stroke
				(width 0.1524)
				(type default)
			)
			(layer "B.SilkS")
		)
		(fp_line
			(start -0.7874 -0.4064)
			(end -0.7874 0.4064)
			(stroke
				(width 0.1524)
				(type default)
			)
			(layer "B.SilkS")
		)
		(fp_line
			(start 0.67945 0.3048)
			(end 0.67945 -0.305054)
			(stroke
				(width 0.1)
				(type default)
			)
			(layer "B.Fab")
		)
		(fp_line
			(start 0.67945 -0.305054)
			(end 0.12065 -0.305054)
			(stroke
				(width 0.1)
				(type default)
			)
			(layer "B.Fab")
		)
		(fp_line
			(start 0.12065 0.3048)
			(end 0.67945 0.3048)
			(stroke
				(width 0.1)
				(type default)
			)
			(layer "B.Fab")
		)
		(fp_line
			(start 0.12065 0.2794)
			(end 0.12065 0.3048)
			(stroke
				(width 0.1)
				(type default)
			)
			(layer "B.Fab")
		)
		(fp_line
			(start 0.12065 -0.2794)
			(end -0.12065 -0.2794)
			(stroke
				(width 0.1)
				(type default)
			)
			(layer "B.Fab")
		)
		(fp_line
			(start 0.12065 -0.305054)
			(end 0.12065 -0.2794)
			(stroke
				(width 0.1)
				(type default)
			)
			(layer "B.Fab")
		)
		(fp_line
			(start -0.120396 0.3048)
			(end -0.120396 0.2794)
			(stroke
				(width 0.1)
				(type default)
			)
			(layer "B.Fab")
		)
		(fp_line
			(start -0.120396 0.2794)
			(end 0.12065 0.2794)
			(stroke
				(width 0.1)
				(type default)
			)
			(layer "B.Fab")
		)
		(fp_line
			(start -0.12065 -0.2794)
			(end -0.12065 -0.3048)
			(stroke
				(width 0.1)
				(type default)
			)
			(layer "B.Fab")
		)
		(fp_line
			(start -0.12065 -0.3048)
			(end -0.67945 -0.3048)
			(stroke
				(width 0.1)
				(type default)
			)
			(layer "B.Fab")
		)
		(fp_line
			(start -0.67945 0.3048)
			(end -0.120396 0.3048)
			(stroke
				(width 0.1)
				(type default)
			)
			(layer "B.Fab")
		)
		(fp_line
			(start -0.67945 -0.3048)
			(end -0.67945 0.3048)
			(stroke
				(width 0.1)
				(type default)
			)
			(layer "B.Fab")
		)
		(pad "1" smd circle
			(at 0.40005 0)
			(size 0 0)
			(layers "B.Cu" "B.Mask" "B.Paste")
			(net "FM_PVDDCR_CPU1_P1_R_EN")
		)
		(pad "2" smd circle
			(at -0.40005 0)
			(size 0 0)
			(layers "B.Cu" "B.Mask" "B.Paste")
			(net "FM_PVDDCR_CPU1_P1_EN")
		)
	)
	(footprint ""
		(layer "B.Cu")
		(at 197.955408 -122.769376 180)
		(property "Reference" "R3485"
			(at 0 0 0)
			(layer "B.SilkS")
			(hide yes)
			(effects
				(font
					(size 1.27 1.27)
				)
				(justify mirror)
			)
		)
		(property "Value" ""
			(at 0 0 0)
			(layer "B.Fab")
			(effects
				(font
					(size 1.27 1.27)
				)
				(justify mirror)
			)
		)
		(duplicate_pad_numbers_are_jumpers no)
		(fp_line
			(start 0.7874 0.4064)
			(end 0.7874 -0.4064)
			(stroke
				(width 0.1524)
				(type default)
			)
			(layer "B.SilkS")
		)
		(fp_line
			(start 0.7874 -0.4064)
			(end -0.7874 -0.4064)
			(stroke
				(width 0.1524)
				(type default)
			)
			(layer "B.SilkS")
		)
		(fp_line
			(start -0.7874 0.4064)
			(end 0.7874 0.4064)
			(stroke
				(width 0.1524)
				(type default)
			)
			(layer "B.SilkS")
		)
		(fp_line
			(start -0.7874 -0.4064)
			(end -0.7874 0.4064)
			(stroke
				(width 0.1524)
				(type default)
			)
			(layer "B.SilkS")
		)
		(fp_line
			(start 0.67945 0.3048)
			(end 0.67945 -0.305054)
			(stroke
				(width 0.1)
				(type default)
			)
			(layer "B.Fab")
		)
		(fp_line
			(start 0.67945 -0.305054)
			(end 0.12065 -0.305054)
			(stroke
				(width 0.1)
				(type default)
			)
			(layer "B.Fab")
		)
		(fp_line
			(start 0.12065 0.3048)
			(end 0.67945 0.3048)
			(stroke
				(width 0.1)
				(type default)
			)
			(layer "B.Fab")
		)
		(fp_line
			(start 0.12065 0.2794)
			(end 0.12065 0.3048)
			(stroke
				(width 0.1)
				(type default)
			)
			(layer "B.Fab")
		)
		(fp_line
			(start 0.12065 -0.2794)
			(end -0.12065 -0.2794)
			(stroke
				(width 0.1)
				(type default)
			)
			(layer "B.Fab")
		)
		(fp_line
			(start 0.12065 -0.305054)
			(end 0.12065 -0.2794)
			(stroke
				(width 0.1)
				(type default)
			)
			(layer "B.Fab")
		)
		(fp_line
			(start -0.120396 0.3048)
			(end -0.120396 0.2794)
			(stroke
				(width 0.1)
				(type default)
			)
			(layer "B.Fab")
		)
		(fp_line
			(start -0.120396 0.2794)
			(end 0.12065 0.2794)
			(stroke
				(width 0.1)
				(type default)
			)
			(layer "B.Fab")
		)
		(fp_line
			(start -0.12065 -0.2794)
			(end -0.12065 -0.3048)
			(stroke
				(width 0.1)
				(type default)
			)
			(layer "B.Fab")
		)
		(fp_line
			(start -0.12065 -0.3048)
			(end -0.67945 -0.3048)
			(stroke
				(width 0.1)
				(type default)
			)
			(layer "B.Fab")
		)
		(fp_line
			(start -0.67945 0.3048)
			(end -0.120396 0.3048)
			(stroke
				(width 0.1)
				(type default)
			)
			(layer "B.Fab")
		)
		(fp_line
			(start -0.67945 -0.3048)
			(end -0.67945 0.3048)
			(stroke
				(width 0.1)
				(type default)
			)
			(layer "B.Fab")
		)
		(pad "1" smd circle
			(at 0.40005 0)
			(size 0 0)
			(layers "B.Cu" "B.Mask" "B.Paste")
			(net "GPU_WP_HW_CTRL_R_N")
		)
		(pad "2" smd circle
			(at -0.40005 0)
			(size 0 0)
			(layers "B.Cu" "B.Mask" "B.Paste")
			(net "GPU_WP_HW_CTRL_N")
		)
	)
	(footprint ""
		(layer "B.Cu")
		(at 168.528238 -192.66027)
		(property "Reference" "C530"
			(at 0 0 0)
			(layer "B.SilkS")
			(hide yes)
			(effects
				(font
					(size 1.27 1.27)
				)
				(justify mirror)
			)
		)
		(property "Value" ""
			(at 0 0 0)
			(layer "B.Fab")
			(effects
				(font
					(size 1.27 1.27)
				)
				(justify mirror)
			)
		)
		(duplicate_pad_numbers_are_jumpers no)
		(fp_line
			(start -1.524 -0.762)
			(end -1.524 0.762)
			(stroke
				(width 0.1524)
				(type default)
			)
			(layer "B.SilkS")
		)
		(fp_line
			(start -1.524 0.762)
			(end 1.524 0.762)
			(stroke
				(width 0.1524)
				(type default)
			)
			(layer "B.SilkS")
		)
		(fp_line
			(start 1.524 -0.762)
			(end -1.524 -0.762)
			(stroke
				(width 0.1524)
				(type default)
			)
			(layer "B.SilkS")
		)
		(fp_line
			(start 1.524 0.762)
			(end 1.524 -0.762)
			(stroke
				(width 0.1524)
				(type default)
			)
			(layer "B.SilkS")
		)
		(fp_line
			(start -1.1049 -0.724916)
			(end 1.1049 -0.724916)
			(stroke
				(width 0.1)
				(type default)
			)
			(layer "B.Fab")
		)
		(fp_line
			(start -1.1049 0.724916)
			(end -1.1049 -0.724916)
			(stroke
				(width 0.1)
				(type default)
			)
			(layer "B.Fab")
		)
		(fp_line
			(start 1.1049 -0.724916)
			(end 1.1049 0.724916)
			(stroke
				(width 0.1)
				(type default)
			)
			(layer "B.Fab")
		)
		(fp_line
			(start 1.1049 0.724916)
			(end -1.1049 0.724916)
			(stroke
				(width 0.1)
				(type default)
			)
			(layer "B.Fab")
		)
		(pad "1" smd rect
			(at 0.889 0)
			(size 1.016 1.27)
			(layers "B.Cu" "B.Mask" "B.Paste")
			(net "P12V_MEM_CPU1")
		)
		(pad "2" smd rect
			(at -0.889 0)
			(size 1.016 1.27)
			(layers "B.Cu" "B.Mask" "B.Paste")
			(net "GND")
		)
	)
	(footprint ""
		(layer "B.Cu")
		(at 187.060078 -192.66027 180)
		(property "Reference" "C537"
			(at 0 0 0)
			(layer "B.SilkS")
			(hide yes)
			(effects
				(font
					(size 1.27 1.27)
				)
				(justify mirror)
			)
		)
		(property "Value" ""
			(at 0 0 0)
			(layer "B.Fab")
			(effects
				(font
					(size 1.27 1.27)
				)
				(justify mirror)
			)
		)
		(duplicate_pad_numbers_are_jumpers no)
		(fp_line
			(start 1.524 0.762)
			(end 1.524 -0.762)
			(stroke
				(width 0.1524)
				(type default)
			)
			(layer "B.SilkS")
		)
		(fp_line
			(start 1.524 -0.762)
			(end -1.524 -0.762)
			(stroke
				(width 0.1524)
				(type default)
			)
			(layer "B.SilkS")
		)
		(fp_line
			(start -1.524 0.762)
			(end 1.524 0.762)
			(stroke
				(width 0.1524)
				(type default)
			)
			(layer "B.SilkS")
		)
		(fp_line
			(start -1.524 -0.762)
			(end -1.524 0.762)
			(stroke
				(width 0.1524)
				(type default)
			)
			(layer "B.SilkS")
		)
		(fp_line
			(start 1.1049 0.724916)
			(end -1.1049 0.724916)
			(stroke
				(width 0.1)
				(type default)
			)
			(layer "B.Fab")
		)
		(fp_line
			(start 1.1049 -0.724916)
			(end 1.1049 0.724916)
			(stroke
				(width 0.1)
				(type default)
			)
			(layer "B.Fab")
		)
		(fp_line
			(start -1.1049 0.724916)
			(end -1.1049 -0.724916)
			(stroke
				(width 0.1)
				(type default)
			)
			(layer "B.Fab")
		)
		(fp_line
			(start -1.1049 -0.724916)
			(end 1.1049 -0.724916)
			(stroke
				(width 0.1)
				(type default)
			)
			(layer "B.Fab")
		)
		(pad "1" smd rect
			(at 0.889 0 180)
			(size 1.016 1.27)
			(layers "B.Cu" "B.Mask" "B.Paste")
			(net "P12V_MEM_CPU1")
		)
		(pad "2" smd rect
			(at -0.889 0 180)
			(size 1.016 1.27)
			(layers "B.Cu" "B.Mask" "B.Paste")
			(net "GND")
		)
	)
	(footprint ""
		(layer "B.Cu")
		(at 132.865114 -33.199578 -90)
		(property "Reference" "C6049"
			(at 0 0 90)
			(layer "B.SilkS")
			(hide yes)
			(effects
				(font
					(size 1.27 1.27)
				)
				(justify mirror)
			)
		)
		(property "Value" ""
			(at 0 0 90)
			(layer "B.Fab")
			(effects
				(font
					(size 1.27 1.27)
				)
				(justify mirror)
			)
		)
		(duplicate_pad_numbers_are_jumpers no)
		(fp_line
			(start -0.7874 0.4064)
			(end 0.7874 0.4064)
			(stroke
				(width 0.1524)
				(type default)
			)
			(layer "B.SilkS")
		)
		(fp_line
			(start 0.7874 0.4064)
			(end 0.7874 -0.4064)
			(stroke
				(width 0.1524)
				(type default)
			)
			(layer "B.SilkS")
		)
		(fp_line
			(start -0.7874 -0.4064)
			(end -0.7874 0.4064)
			(stroke
				(width 0.1524)
				(type default)
			)
			(layer "B.SilkS")
		)
		(fp_line
			(start 0.7874 -0.4064)
			(end -0.7874 -0.4064)
			(stroke
				(width 0.1524)
				(type default)
			)
			(layer "B.SilkS")
		)
		(fp_line
			(start -0.67945 0.3048)
			(end -0.120396 0.3048)
			(stroke
				(width 0.1)
				(type default)
			)
			(layer "B.Fab")
		)
		(fp_line
			(start -0.120396 0.3048)
			(end -0.120396 0.2794)
			(stroke
				(width 0.1)
				(type default)
			)
			(layer "B.Fab")
		)
		(fp_line
			(start 0.12065 0.3048)
			(end 0.67945 0.3048)
			(stroke
				(width 0.1)
				(type default)
			)
			(layer "B.Fab")
		)
		(fp_line
			(start 0.67945 0.3048)
			(end 0.67945 -0.305054)
			(stroke
				(width 0.1)
				(type default)
			)
			(layer "B.Fab")
		)
		(fp_line
			(start -0.120396 0.2794)
			(end 0.12065 0.2794)
			(stroke
				(width 0.1)
				(type default)
			)
			(layer "B.Fab")
		)
		(fp_line
			(start 0.12065 0.2794)
			(end 0.12065 0.3048)
			(stroke
				(width 0.1)
				(type default)
			)
			(layer "B.Fab")
		)
		(fp_line
			(start -0.12065 -0.2794)
			(end -0.12065 -0.3048)
			(stroke
				(width 0.1)
				(type default)
			)
			(layer "B.Fab")
		)
		(fp_line
			(start 0.12065 -0.2794)
			(end -0.12065 -0.2794)
			(stroke
				(width 0.1)
				(type default)
			)
			(layer "B.Fab")
		)
		(fp_line
			(start -0.67945 -0.3048)
			(end -0.67945 0.3048)
			(stroke
				(width 0.1)
				(type default)
			)
			(layer "B.Fab")
		)
		(fp_line
			(start -0.12065 -0.3048)
			(end -0.67945 -0.3048)
			(stroke
				(width 0.1)
				(type default)
			)
			(layer "B.Fab")
		)
		(fp_line
			(start 0.12065 -0.305054)
			(end 0.12065 -0.2794)
			(stroke
				(width 0.1)
				(type default)
			)
			(layer "B.Fab")
		)
		(fp_line
			(start 0.67945 -0.305054)
			(end 0.12065 -0.305054)
			(stroke
				(width 0.1)
				(type default)
			)
			(layer "B.Fab")
		)
		(pad "1" smd circle
			(at 0.40005 0 90)
			(size 0 0)
			(layers "B.Cu" "B.Mask" "B.Paste")
			(net "P3V3_AUX")
		)
		(pad "2" smd circle
			(at -0.40005 0 90)
			(size 0 0)
			(layers "B.Cu" "B.Mask" "B.Paste")
			(net "GND")
		)
	)
	(footprint ""
		(layer "B.Cu")
		(at 233.68 -228.092)
		(property "Reference" "R162"
			(at 0 0 0)
			(layer "B.SilkS")
			(hide yes)
			(effects
				(font
					(size 1.27 1.27)
				)
				(justify mirror)
			)
		)
		(property "Value" ""
			(at 0 0 0)
			(layer "B.Fab")
			(effects
				(font
					(size 1.27 1.27)
				)
				(justify mirror)
			)
		)
		(duplicate_pad_numbers_are_jumpers no)
		(fp_line
			(start -0.7874 -0.4064)
			(end -0.7874 0.4064)
			(stroke
				(width 0.1524)
				(type default)
			)
			(layer "B.SilkS")
		)
		(fp_line
			(start -0.7874 0.4064)
			(end 0.7874 0.4064)
			(stroke
				(width 0.1524)
				(type default)
			)
			(layer "B.SilkS")
		)
		(fp_line
			(start 0.7874 -0.4064)
			(end -0.7874 -0.4064)
			(stroke
				(width 0.1524)
				(type default)
			)
			(layer "B.SilkS")
		)
		(fp_line
			(start 0.7874 0.4064)
			(end 0.7874 -0.4064)
			(stroke
				(width 0.1524)
				(type default)
			)
			(layer "B.SilkS")
		)
		(fp_line
			(start -0.67945 -0.3048)
			(end -0.67945 0.3048)
			(stroke
				(width 0.1)
				(type default)
			)
			(layer "B.Fab")
		)
		(fp_line
			(start -0.67945 0.3048)
			(end -0.120396 0.3048)
			(stroke
				(width 0.1)
				(type default)
			)
			(layer "B.Fab")
		)
		(fp_line
			(start -0.12065 -0.3048)
			(end -0.67945 -0.3048)
			(stroke
				(width 0.1)
				(type default)
			)
			(layer "B.Fab")
		)
		(fp_line
			(start -0.12065 -0.2794)
			(end -0.12065 -0.3048)
			(stroke
				(width 0.1)
				(type default)
			)
			(layer "B.Fab")
		)
		(fp_line
			(start -0.120396 0.2794)
			(end 0.12065 0.2794)
			(stroke
				(width 0.1)
				(type default)
			)
			(layer "B.Fab")
		)
		(fp_line
			(start -0.120396 0.3048)
			(end -0.120396 0.2794)
			(stroke
				(width 0.1)
				(type default)
			)
			(layer "B.Fab")
		)
		(fp_line
			(start 0.12065 -0.305054)
			(end 0.12065 -0.2794)
			(stroke
				(width 0.1)
				(type default)
			)
			(layer "B.Fab")
		)
		(fp_line
			(start 0.12065 -0.2794)
			(end -0.12065 -0.2794)
			(stroke
				(width 0.1)
				(type default)
			)
			(layer "B.Fab")
		)
		(fp_line
			(start 0.12065 0.2794)
			(end 0.12065 0.3048)
			(stroke
				(width 0.1)
				(type default)
			)
			(layer "B.Fab")
		)
		(fp_line
			(start 0.12065 0.3048)
			(end 0.67945 0.3048)
			(stroke
				(width 0.1)
				(type default)
			)
			(layer "B.Fab")
		)
		(fp_line
			(start 0.67945 -0.305054)
			(end 0.12065 -0.305054)
			(stroke
				(width 0.1)
				(type default)
			)
			(layer "B.Fab")
		)
		(fp_line
			(start 0.67945 0.3048)
			(end 0.67945 -0.305054)
			(stroke
				(width 0.1)
				(type default)
			)
			(layer "B.Fab")
		)
		(pad "1" smd rect
			(at 0.40005 0)
			(size 0.4572 0.508)
			(layers "B.Cu" "B.Mask" "B.Paste")
			(net "SMB_CPU0_CPU1_APML_SDA")
		)
		(pad "2" smd rect
			(at -0.40005 0)
			(size 0.4572 0.508)
			(layers "B.Cu" "B.Mask" "B.Paste")
			(net "SMB_CPU0_CPU1_APML_BUF2_SDA")
		)
	)
	(footprint ""
		(layer "B.Cu")
		(at 276.436582 -195.859146 180)
		(property "Reference" "R1678"
			(at 0 0 0)
			(layer "B.SilkS")
			(hide yes)
			(effects
				(font
					(size 1.27 1.27)
				)
				(justify mirror)
			)
		)
		(property "Value" ""
			(at 0 0 0)
			(layer "B.Fab")
			(effects
				(font
					(size 1.27 1.27)
				)
				(justify mirror)
			)
		)
		(duplicate_pad_numbers_are_jumpers no)
		(fp_line
			(start 0.7874 0.4064)
			(end 0.7874 -0.4064)
			(stroke
				(width 0.1524)
				(type default)
			)
			(layer "B.SilkS")
		)
		(fp_line
			(start 0.7874 -0.4064)
			(end -0.7874 -0.4064)
			(stroke
				(width 0.1524)
				(type default)
			)
			(layer "B.SilkS")
		)
		(fp_line
			(start -0.7874 0.4064)
			(end 0.7874 0.4064)
			(stroke
				(width 0.1524)
				(type default)
			)
			(layer "B.SilkS")
		)
		(fp_line
			(start -0.7874 -0.4064)
			(end -0.7874 0.4064)
			(stroke
				(width 0.1524)
				(type default)
			)
			(layer "B.SilkS")
		)
		(fp_line
			(start 0.67945 0.3048)
			(end 0.67945 -0.305054)
			(stroke
				(width 0.1)
				(type default)
			)
			(layer "B.Fab")
		)
		(fp_line
			(start 0.67945 -0.305054)
			(end 0.12065 -0.305054)
			(stroke
				(width 0.1)
				(type default)
			)
			(layer "B.Fab")
		)
		(fp_line
			(start 0.12065 0.3048)
			(end 0.67945 0.3048)
			(stroke
				(width 0.1)
				(type default)
			)
			(layer "B.Fab")
		)
		(fp_line
			(start 0.12065 0.2794)
			(end 0.12065 0.3048)
			(stroke
				(width 0.1)
				(type default)
			)
			(layer "B.Fab")
		)
		(fp_line
			(start 0.12065 -0.2794)
			(end -0.12065 -0.2794)
			(stroke
				(width 0.1)
				(type default)
			)
			(layer "B.Fab")
		)
		(fp_line
			(start 0.12065 -0.305054)
			(end 0.12065 -0.2794)
			(stroke
				(width 0.1)
				(type default)
			)
			(layer "B.Fab")
		)
		(fp_line
			(start -0.120396 0.3048)
			(end -0.120396 0.2794)
			(stroke
				(width 0.1)
				(type default)
			)
			(layer "B.Fab")
		)
		(fp_line
			(start -0.120396 0.2794)
			(end 0.12065 0.2794)
			(stroke
				(width 0.1)
				(type default)
			)
			(layer "B.Fab")
		)
		(fp_line
			(start -0.12065 -0.2794)
			(end -0.12065 -0.3048)
			(stroke
				(width 0.1)
				(type default)
			)
			(layer "B.Fab")
		)
		(fp_line
			(start -0.12065 -0.3048)
			(end -0.67945 -0.3048)
			(stroke
				(width 0.1)
				(type default)
			)
			(layer "B.Fab")
		)
		(fp_line
			(start -0.67945 0.3048)
			(end -0.120396 0.3048)
			(stroke
				(width 0.1)
				(type default)
			)
			(layer "B.Fab")
		)
		(fp_line
			(start -0.67945 -0.3048)
			(end -0.67945 0.3048)
			(stroke
				(width 0.1)
				(type default)
			)
			(layer "B.Fab")
		)
		(pad "1" smd circle
			(at 0.40005 0)
			(size 0 0)
			(layers "B.Cu" "B.Mask" "B.Paste")
			(net "I3C_SPD_DDRAF_CPU0_SDA")
		)
		(pad "2" smd circle
			(at -0.40005 0)
			(size 0 0)
			(layers "B.Cu" "B.Mask" "B.Paste")
			(net "I3C_SPD_DDRE_CPU0_SDA")
		)
	)
	(footprint ""
		(layer "B.Cu")
		(at 218.059 -340.868 180)
		(property "Reference" "R6748"
			(at 0 0 0)
			(layer "B.SilkS")
			(hide yes)
			(effects
				(font
					(size 1.27 1.27)
				)
				(justify mirror)
			)
		)
		(property "Value" ""
			(at 0 0 0)
			(layer "B.Fab")
			(effects
				(font
					(size 1.27 1.27)
				)
				(justify mirror)
			)
		)
		(duplicate_pad_numbers_are_jumpers no)
		(fp_line
			(start 0.32512 0.175006)
			(end 0.32512 -0.175006)
			(stroke
				(width 0.1)
				(type default)
			)
			(layer "B.Fab")
		)
		(fp_line
			(start 0.32512 -0.175006)
			(end -0.32512 -0.175006)
			(stroke
				(width 0.1)
				(type default)
			)
			(layer "B.Fab")
		)
		(fp_line
			(start -0.32512 0.175006)
			(end 0.32512 0.175006)
			(stroke
				(width 0.1)
				(type default)
			)
			(layer "B.Fab")
		)
		(fp_line
			(start -0.32512 -0.175006)
			(end -0.32512 0.175006)
			(stroke
				(width 0.1)
				(type default)
			)
			(layer "B.Fab")
		)
		(pad "1" smd rect
			(at 0.2667 0)
			(size 0.3048 0.381)
			(layers "B.Cu" "B.Mask" "B.Paste")
			(net "SMB_RT_CPU1_P2_R_SDA")
		)
		(pad "2" smd rect
			(at -0.2667 0 180)
			(size 0.3048 0.381)
			(layers "B.Cu" "B.Mask" "B.Paste")
			(net "SMB_RT_CPU1_P2_SDA")
		)
	)
	(footprint ""
		(layer "B.Cu")
		(at 107.429554 -184.906412 90)
		(property "Reference" "PC105"
			(at 5.990336 1.013714 270)
			(unlocked yes)
			(layer "B.SilkS")
			(effects
				(font
					(size 0.7874 0.5842)
					(thickness 0.1524)
				)
				(justify left mirror)
			)
		)
		(property "Value" ""
			(at 0 0 90)
			(layer "B.Fab")
			(effects
				(font
					(size 1.27 1.27)
				)
				(justify mirror)
			)
		)
		(duplicate_pad_numbers_are_jumpers no)
		(fp_line
			(start 4.533392 -2.249932)
			(end -4.533392 -2.249932)
			(stroke
				(width 0.1524)
				(type default)
			)
			(layer "B.SilkS")
		)
		(fp_line
			(start -4.533392 -2.249932)
			(end -4.533392 2.249932)
			(stroke
				(width 0.1524)
				(type default)
			)
			(layer "B.SilkS")
		)
		(fp_line
			(start 4.533392 2.249932)
			(end 4.533392 -2.249932)
			(stroke
				(width 0.1524)
				(type default)
			)
			(layer "B.SilkS")
		)
		(fp_line
			(start -4.533392 2.249932)
			(end 4.533392 2.249932)
			(stroke
				(width 0.1524)
				(type default)
			)
			(layer "B.SilkS")
		)
		(fp_rect
			(start 4.533392 -2.326132)
			(end 5.39242 2.326132)
			(stroke
				(width 0)
				(type default)
			)
			(fill yes)
			(layer "B.SilkS")
		)
		(fp_line
			(start 3.750056 -2.249932)
			(end -3.750056 -2.249932)
			(stroke
				(width 0.1)
				(type default)
			)
			(layer "B.Fab")
		)
		(fp_line
			(start -3.750056 -2.249932)
			(end -3.750056 2.249932)
			(stroke
				(width 0.1)
				(type default)
			)
			(layer "B.Fab")
		)
		(fp_line
			(start 3.750056 2.249932)
			(end 3.750056 -2.249932)
			(stroke
				(width 0.1)
				(type default)
			)
			(layer "B.Fab")
		)
		(fp_line
			(start -3.750056 2.249932)
			(end 3.750056 2.249932)
			(stroke
				(width 0.1)
				(type default)
			)
			(layer "B.Fab")
		)
		(fp_text user "-"
			(at -4.8514 -0.14605 90)
			(unlocked yes)
			(layer "B.SilkS")
			(effects
				(font
					(size 1.905 1.4224)
					(thickness 0.1524)
				)
				(justify left mirror)
			)
		)
		(fp_text user "+"
			(at 6.322314 0.786384 0)
			(unlocked yes)
			(layer "B.SilkS")
			(effects
				(font
					(size 1.905 1.4224)
					(thickness 0.1524)
				)
				(justify left mirror)
			)
		)
		(fp_text user "-"
			(at -4.8514 -0.14605 90)
			(unlocked yes)
			(layer "B.Fab")
			(effects
				(font
					(size 1.905 1.4224)
					(thickness 0.1524)
				)
				(justify left mirror)
			)
		)
		(fp_text user "+"
			(at 6.322314 0.786384 0)
			(unlocked yes)
			(layer "B.Fab")
			(effects
				(font
					(size 1.905 1.4224)
					(thickness 0.1524)
				)
				(justify left mirror)
			)
		)
		(pad "1" smd rect
			(at 3.199892 0 270)
			(size 2.413 2.8194)
			(layers "B.Cu" "B.Mask" "B.Paste")
			(net "PVDDCR_CPU0_P1")
		)
		(pad "2" smd rect
			(at -3.199892 0 270)
			(size 2.413 2.8194)
			(layers "B.Cu" "B.Mask" "B.Paste")
			(net "GND")
		)
	)
	(footprint ""
		(layer "B.Cu")
		(at 355.009958 -245.487952 180)
		(property "Reference" "C252"
			(at 0 0 0)
			(layer "B.SilkS")
			(hide yes)
			(effects
				(font
					(size 1.27 1.27)
				)
				(justify mirror)
			)
		)
		(property "Value" ""
			(at 0 0 0)
			(layer "B.Fab")
			(effects
				(font
					(size 1.27 1.27)
				)
				(justify mirror)
			)
		)
		(duplicate_pad_numbers_are_jumpers no)
		(fp_line
			(start 0.7874 0.4064)
			(end 0.7874 -0.4064)
			(stroke
				(width 0.1524)
				(type default)
			)
			(layer "B.SilkS")
		)
		(fp_line
			(start 0.7874 -0.4064)
			(end -0.7874 -0.4064)
			(stroke
				(width 0.1524)
				(type default)
			)
			(layer "B.SilkS")
		)
		(fp_line
			(start -0.7874 0.4064)
			(end 0.7874 0.4064)
			(stroke
				(width 0.1524)
				(type default)
			)
			(layer "B.SilkS")
		)
		(fp_line
			(start -0.7874 -0.4064)
			(end -0.7874 0.4064)
			(stroke
				(width 0.1524)
				(type default)
			)
			(layer "B.SilkS")
		)
		(fp_line
			(start 0.67945 0.3048)
			(end 0.67945 -0.305054)
			(stroke
				(width 0.1)
				(type default)
			)
			(layer "B.Fab")
		)
		(fp_line
			(start 0.67945 -0.305054)
			(end 0.12065 -0.305054)
			(stroke
				(width 0.1)
				(type default)
			)
			(layer "B.Fab")
		)
		(fp_line
			(start 0.12065 0.3048)
			(end 0.67945 0.3048)
			(stroke
				(width 0.1)
				(type default)
			)
			(layer "B.Fab")
		)
		(fp_line
			(start 0.12065 0.2794)
			(end 0.12065 0.3048)
			(stroke
				(width 0.1)
				(type default)
			)
			(layer "B.Fab")
		)
		(fp_line
			(start 0.12065 -0.2794)
			(end -0.12065 -0.2794)
			(stroke
				(width 0.1)
				(type default)
			)
			(layer "B.Fab")
		)
		(fp_line
			(start 0.12065 -0.305054)
			(end 0.12065 -0.2794)
			(stroke
				(width 0.1)
				(type default)
			)
			(layer "B.Fab")
		)
		(fp_line
			(start -0.120396 0.3048)
			(end -0.120396 0.2794)
			(stroke
				(width 0.1)
				(type default)
			)
			(layer "B.Fab")
		)
		(fp_line
			(start -0.120396 0.2794)
			(end 0.12065 0.2794)
			(stroke
				(width 0.1)
				(type default)
			)
			(layer "B.Fab")
		)
		(fp_line
			(start -0.12065 -0.2794)
			(end -0.12065 -0.3048)
			(stroke
				(width 0.1)
				(type default)
			)
			(layer "B.Fab")
		)
		(fp_line
			(start -0.12065 -0.3048)
			(end -0.67945 -0.3048)
			(stroke
				(width 0.1)
				(type default)
			)
			(layer "B.Fab")
		)
		(fp_line
			(start -0.67945 0.3048)
			(end -0.120396 0.3048)
			(stroke
				(width 0.1)
				(type default)
			)
			(layer "B.Fab")
		)
		(fp_line
			(start -0.67945 -0.3048)
			(end -0.67945 0.3048)
			(stroke
				(width 0.1)
				(type default)
			)
			(layer "B.Fab")
		)
		(pad "1" smd circle
			(at 0.40005 0)
			(size 0 0)
			(layers "B.Cu" "B.Mask" "B.Paste")
			(net "PVDDCR_CPU0_P0")
		)
		(pad "2" smd circle
			(at -0.40005 0)
			(size 0 0)
			(layers "B.Cu" "B.Mask" "B.Paste")
			(net "GND")
		)
	)
	(footprint ""
		(layer "B.Cu")
		(at 428.211742 -193.99631)
		(property "Reference" "R98"
			(at 0 0 0)
			(layer "B.SilkS")
			(hide yes)
			(effects
				(font
					(size 1.27 1.27)
				)
				(justify mirror)
			)
		)
		(property "Value" ""
			(at 0 0 0)
			(layer "B.Fab")
			(effects
				(font
					(size 1.27 1.27)
				)
				(justify mirror)
			)
		)
		(duplicate_pad_numbers_are_jumpers no)
		(fp_line
			(start -0.7874 -0.4064)
			(end -0.7874 0.4064)
			(stroke
				(width 0.1524)
				(type default)
			)
			(layer "B.SilkS")
		)
		(fp_line
			(start -0.7874 0.4064)
			(end 0.7874 0.4064)
			(stroke
				(width 0.1524)
				(type default)
			)
			(layer "B.SilkS")
		)
		(fp_line
			(start 0.7874 -0.4064)
			(end -0.7874 -0.4064)
			(stroke
				(width 0.1524)
				(type default)
			)
			(layer "B.SilkS")
		)
		(fp_line
			(start 0.7874 0.4064)
			(end 0.7874 -0.4064)
			(stroke
				(width 0.1524)
				(type default)
			)
			(layer "B.SilkS")
		)
		(fp_line
			(start -0.67945 -0.3048)
			(end -0.67945 0.3048)
			(stroke
				(width 0.1)
				(type default)
			)
			(layer "B.Fab")
		)
		(fp_line
			(start -0.67945 0.3048)
			(end -0.120396 0.3048)
			(stroke
				(width 0.1)
				(type default)
			)
			(layer "B.Fab")
		)
		(fp_line
			(start -0.12065 -0.3048)
			(end -0.67945 -0.3048)
			(stroke
				(width 0.1)
				(type default)
			)
			(layer "B.Fab")
		)
		(fp_line
			(start -0.12065 -0.2794)
			(end -0.12065 -0.3048)
			(stroke
				(width 0.1)
				(type default)
			)
			(layer "B.Fab")
		)
		(fp_line
			(start -0.120396 0.2794)
			(end 0.12065 0.2794)
			(stroke
				(width 0.1)
				(type default)
			)
			(layer "B.Fab")
		)
		(fp_line
			(start -0.120396 0.3048)
			(end -0.120396 0.2794)
			(stroke
				(width 0.1)
				(type default)
			)
			(layer "B.Fab")
		)
		(fp_line
			(start 0.12065 -0.305054)
			(end 0.12065 -0.2794)
			(stroke
				(width 0.1)
				(type default)
			)
			(layer "B.Fab")
		)
		(fp_line
			(start 0.12065 -0.2794)
			(end -0.12065 -0.2794)
			(stroke
				(width 0.1)
				(type default)
			)
			(layer "B.Fab")
		)
		(fp_line
			(start 0.12065 0.2794)
			(end 0.12065 0.3048)
			(stroke
				(width 0.1)
				(type default)
			)
			(layer "B.Fab")
		)
		(fp_line
			(start 0.12065 0.3048)
			(end 0.67945 0.3048)
			(stroke
				(width 0.1)
				(type default)
			)
			(layer "B.Fab")
		)
		(fp_line
			(start 0.67945 -0.305054)
			(end 0.12065 -0.305054)
			(stroke
				(width 0.1)
				(type default)
			)
			(layer "B.Fab")
		)
		(fp_line
			(start 0.67945 0.3048)
			(end 0.67945 -0.305054)
			(stroke
				(width 0.1)
				(type default)
			)
			(layer "B.Fab")
		)
		(pad "1" smd circle
			(at 0.40005 0 180)
			(size 0 0)
			(layers "B.Cu" "B.Mask" "B.Paste")
			(net "P3V3")
		)
		(pad "2" smd circle
			(at -0.40005 0 180)
			(size 0 0)
			(layers "B.Cu" "B.Mask" "B.Paste")
			(net "PWRGD_CHI_CPU0_DIMM")
		)
	)
	(footprint ""
		(layer "B.Cu")
		(at 369.519454 -266.00531)
		(property "Reference" "C2600"
			(at 0 0 0)
			(layer "B.SilkS")
			(hide yes)
			(effects
				(font
					(size 1.27 1.27)
				)
				(justify mirror)
			)
		)
		(property "Value" ""
			(at 0 0 0)
			(layer "B.Fab")
			(effects
				(font
					(size 1.27 1.27)
				)
				(justify mirror)
			)
		)
		(duplicate_pad_numbers_are_jumpers no)
		(fp_line
			(start -0.7874 -0.4064)
			(end -0.7874 0.4064)
			(stroke
				(width 0.1524)
				(type default)
			)
			(layer "B.SilkS")
		)
		(fp_line
			(start -0.7874 0.4064)
			(end 0.7874 0.4064)
			(stroke
				(width 0.1524)
				(type default)
			)
			(layer "B.SilkS")
		)
		(fp_line
			(start 0.7874 -0.4064)
			(end -0.7874 -0.4064)
			(stroke
				(width 0.1524)
				(type default)
			)
			(layer "B.SilkS")
		)
		(fp_line
			(start 0.7874 0.4064)
			(end 0.7874 -0.4064)
			(stroke
				(width 0.1524)
				(type default)
			)
			(layer "B.SilkS")
		)
		(fp_line
			(start -0.67945 -0.3048)
			(end -0.67945 0.3048)
			(stroke
				(width 0.1)
				(type default)
			)
			(layer "B.Fab")
		)
		(fp_line
			(start -0.67945 0.3048)
			(end -0.120396 0.3048)
			(stroke
				(width 0.1)
				(type default)
			)
			(layer "B.Fab")
		)
		(fp_line
			(start -0.12065 -0.3048)
			(end -0.67945 -0.3048)
			(stroke
				(width 0.1)
				(type default)
			)
			(layer "B.Fab")
		)
		(fp_line
			(start -0.12065 -0.2794)
			(end -0.12065 -0.3048)
			(stroke
				(width 0.1)
				(type default)
			)
			(layer "B.Fab")
		)
		(fp_line
			(start -0.120396 0.2794)
			(end 0.12065 0.2794)
			(stroke
				(width 0.1)
				(type default)
			)
			(layer "B.Fab")
		)
		(fp_line
			(start -0.120396 0.3048)
			(end -0.120396 0.2794)
			(stroke
				(width 0.1)
				(type default)
			)
			(layer "B.Fab")
		)
		(fp_line
			(start 0.12065 -0.305054)
			(end 0.12065 -0.2794)
			(stroke
				(width 0.1)
				(type default)
			)
			(layer "B.Fab")
		)
		(fp_line
			(start 0.12065 -0.2794)
			(end -0.12065 -0.2794)
			(stroke
				(width 0.1)
				(type default)
			)
			(layer "B.Fab")
		)
		(fp_line
			(start 0.12065 0.2794)
			(end 0.12065 0.3048)
			(stroke
				(width 0.1)
				(type default)
			)
			(layer "B.Fab")
		)
		(fp_line
			(start 0.12065 0.3048)
			(end 0.67945 0.3048)
			(stroke
				(width 0.1)
				(type default)
			)
			(layer "B.Fab")
		)
		(fp_line
			(start 0.67945 -0.305054)
			(end 0.12065 -0.305054)
			(stroke
				(width 0.1)
				(type default)
			)
			(layer "B.Fab")
		)
		(fp_line
			(start 0.67945 0.3048)
			(end 0.67945 -0.305054)
			(stroke
				(width 0.1)
				(type default)
			)
			(layer "B.Fab")
		)
		(pad "1" smd circle
			(at 0.40005 0 180)
			(size 0 0)
			(layers "B.Cu" "B.Mask" "B.Paste")
			(net "PVDD11_S3_P0")
		)
		(pad "2" smd circle
			(at -0.40005 0 180)
			(size 0 0)
			(layers "B.Cu" "B.Mask" "B.Paste")
			(net "GND")
		)
	)
	(footprint ""
		(layer "B.Cu")
		(at 101.385878 -145.64741)
		(property "Reference" "R8168"
			(at 0 0 0)
			(layer "B.SilkS")
			(hide yes)
			(effects
				(font
					(size 1.27 1.27)
				)
				(justify mirror)
			)
		)
		(property "Value" ""
			(at 0 0 0)
			(layer "B.Fab")
			(effects
				(font
					(size 1.27 1.27)
				)
				(justify mirror)
			)
		)
		(duplicate_pad_numbers_are_jumpers no)
		(fp_line
			(start -0.7874 -0.4064)
			(end -0.7874 0.4064)
			(stroke
				(width 0.1524)
				(type default)
			)
			(layer "B.SilkS")
		)
		(fp_line
			(start -0.7874 0.4064)
			(end 0.7874 0.4064)
			(stroke
				(width 0.1524)
				(type default)
			)
			(layer "B.SilkS")
		)
		(fp_line
			(start 0.7874 -0.4064)
			(end -0.7874 -0.4064)
			(stroke
				(width 0.1524)
				(type default)
			)
			(layer "B.SilkS")
		)
		(fp_line
			(start 0.7874 0.4064)
			(end 0.7874 -0.4064)
			(stroke
				(width 0.1524)
				(type default)
			)
			(layer "B.SilkS")
		)
		(fp_line
			(start -0.67945 -0.3048)
			(end -0.67945 0.3048)
			(stroke
				(width 0.1)
				(type default)
			)
			(layer "B.Fab")
		)
		(fp_line
			(start -0.67945 0.3048)
			(end -0.120396 0.3048)
			(stroke
				(width 0.1)
				(type default)
			)
			(layer "B.Fab")
		)
		(fp_line
			(start -0.12065 -0.3048)
			(end -0.67945 -0.3048)
			(stroke
				(width 0.1)
				(type default)
			)
			(layer "B.Fab")
		)
		(fp_line
			(start -0.12065 -0.2794)
			(end -0.12065 -0.3048)
			(stroke
				(width 0.1)
				(type default)
			)
			(layer "B.Fab")
		)
		(fp_line
			(start -0.120396 0.2794)
			(end 0.12065 0.2794)
			(stroke
				(width 0.1)
				(type default)
			)
			(layer "B.Fab")
		)
		(fp_line
			(start -0.120396 0.3048)
			(end -0.120396 0.2794)
			(stroke
				(width 0.1)
				(type default)
			)
			(layer "B.Fab")
		)
		(fp_line
			(start 0.12065 -0.305054)
			(end 0.12065 -0.2794)
			(stroke
				(width 0.1)
				(type default)
			)
			(layer "B.Fab")
		)
		(fp_line
			(start 0.12065 -0.2794)
			(end -0.12065 -0.2794)
			(stroke
				(width 0.1)
				(type default)
			)
			(layer "B.Fab")
		)
		(fp_line
			(start 0.12065 0.2794)
			(end 0.12065 0.3048)
			(stroke
				(width 0.1)
				(type default)
			)
			(layer "B.Fab")
		)
		(fp_line
			(start 0.12065 0.3048)
			(end 0.67945 0.3048)
			(stroke
				(width 0.1)
				(type default)
			)
			(layer "B.Fab")
		)
		(fp_line
			(start 0.67945 -0.305054)
			(end 0.12065 -0.305054)
			(stroke
				(width 0.1)
				(type default)
			)
			(layer "B.Fab")
		)
		(fp_line
			(start 0.67945 0.3048)
			(end 0.67945 -0.305054)
			(stroke
				(width 0.1)
				(type default)
			)
			(layer "B.Fab")
		)
		(pad "1" smd circle
			(at 0.40005 0 180)
			(size 0 0)
			(layers "B.Cu" "B.Mask" "B.Paste")
			(net "PVDDCR_CPU0_P1_OCP_N")
		)
		(pad "2" smd circle
			(at -0.40005 0 180)
			(size 0 0)
			(layers "B.Cu" "B.Mask" "B.Paste")
			(net "PVDDCR_CPU0_P1_OCP_N_R")
		)
	)
	(footprint ""
		(layer "B.Cu")
		(at 351.389188 -158.474156 90)
		(property "Reference" "PR433"
			(at 0 0 90)
			(layer "B.SilkS")
			(hide yes)
			(effects
				(font
					(size 1.27 1.27)
				)
				(justify mirror)
			)
		)
		(property "Value" ""
			(at 0 0 90)
			(layer "B.Fab")
			(effects
				(font
					(size 1.27 1.27)
				)
				(justify mirror)
			)
		)
		(duplicate_pad_numbers_are_jumpers no)
		(fp_line
			(start 0.7874 -0.4064)
			(end -0.7874 -0.4064)
			(stroke
				(width 0.1524)
				(type default)
			)
			(layer "B.SilkS")
		)
		(fp_line
			(start -0.7874 -0.4064)
			(end -0.7874 0.4064)
			(stroke
				(width 0.1524)
				(type default)
			)
			(layer "B.SilkS")
		)
		(fp_line
			(start 0.7874 0.4064)
			(end 0.7874 -0.4064)
			(stroke
				(width 0.1524)
				(type default)
			)
			(layer "B.SilkS")
		)
		(fp_line
			(start -0.7874 0.4064)
			(end 0.7874 0.4064)
			(stroke
				(width 0.1524)
				(type default)
			)
			(layer "B.SilkS")
		)
		(fp_line
			(start 0.67945 -0.305054)
			(end 0.12065 -0.305054)
			(stroke
				(width 0.1)
				(type default)
			)
			(layer "B.Fab")
		)
		(fp_line
			(start 0.12065 -0.305054)
			(end 0.12065 -0.2794)
			(stroke
				(width 0.1)
				(type default)
			)
			(layer "B.Fab")
		)
		(fp_line
			(start -0.12065 -0.3048)
			(end -0.67945 -0.3048)
			(stroke
				(width 0.1)
				(type default)
			)
			(layer "B.Fab")
		)
		(fp_line
			(start -0.67945 -0.3048)
			(end -0.67945 0.3048)
			(stroke
				(width 0.1)
				(type default)
			)
			(layer "B.Fab")
		)
		(fp_line
			(start 0.12065 -0.2794)
			(end -0.12065 -0.2794)
			(stroke
				(width 0.1)
				(type default)
			)
			(layer "B.Fab")
		)
		(fp_line
			(start -0.12065 -0.2794)
			(end -0.12065 -0.3048)
			(stroke
				(width 0.1)
				(type default)
			)
			(layer "B.Fab")
		)
		(fp_line
			(start 0.12065 0.2794)
			(end 0.12065 0.3048)
			(stroke
				(width 0.1)
				(type default)
			)
			(layer "B.Fab")
		)
		(fp_line
			(start -0.120396 0.2794)
			(end 0.12065 0.2794)
			(stroke
				(width 0.1)
				(type default)
			)
			(layer "B.Fab")
		)
		(fp_line
			(start 0.67945 0.3048)
			(end 0.67945 -0.305054)
			(stroke
				(width 0.1)
				(type default)
			)
			(layer "B.Fab")
		)
		(fp_line
			(start 0.12065 0.3048)
			(end 0.67945 0.3048)
			(stroke
				(width 0.1)
				(type default)
			)
			(layer "B.Fab")
		)
		(fp_line
			(start -0.120396 0.3048)
			(end -0.120396 0.2794)
			(stroke
				(width 0.1)
				(type default)
			)
			(layer "B.Fab")
		)
		(fp_line
			(start -0.67945 0.3048)
			(end -0.120396 0.3048)
			(stroke
				(width 0.1)
				(type default)
			)
			(layer "B.Fab")
		)
		(pad "1" smd circle
			(at 0.40005 0 270)
			(size 0 0)
			(layers "B.Cu" "B.Mask" "B.Paste")
			(net "PVDDCR_CPU0_P0_VOS6")
		)
		(pad "2" smd circle
			(at -0.40005 0 270)
			(size 0 0)
			(layers "B.Cu" "B.Mask" "B.Paste")
			(net "PVDDCR_CPU0_P0")
		)
	)
	(footprint ""
		(layer "B.Cu")
		(at 31.891732 -337.989672 -90)
		(property "Reference" "PC636_4"
			(at 0 0 90)
			(layer "B.SilkS")
			(hide yes)
			(effects
				(font
					(size 1.27 1.27)
				)
				(justify mirror)
			)
		)
		(property "Value" ""
			(at 0 0 90)
			(layer "B.Fab")
			(effects
				(font
					(size 1.27 1.27)
				)
				(justify mirror)
			)
		)
		(duplicate_pad_numbers_are_jumpers no)
		(fp_line
			(start -1.524 0.762)
			(end 1.524 0.762)
			(stroke
				(width 0.1524)
				(type default)
			)
			(layer "B.SilkS")
		)
		(fp_line
			(start 1.524 0.762)
			(end 1.524 -0.762)
			(stroke
				(width 0.1524)
				(type default)
			)
			(layer "B.SilkS")
		)
		(fp_line
			(start -1.524 -0.762)
			(end -1.524 0.762)
			(stroke
				(width 0.1524)
				(type default)
			)
			(layer "B.SilkS")
		)
		(fp_line
			(start 1.524 -0.762)
			(end -1.524 -0.762)
			(stroke
				(width 0.1524)
				(type default)
			)
			(layer "B.SilkS")
		)
		(fp_line
			(start -1.1049 0.724916)
			(end -1.1049 -0.724916)
			(stroke
				(width 0.1)
				(type default)
			)
			(layer "B.Fab")
		)
		(fp_line
			(start 1.1049 0.724916)
			(end -1.1049 0.724916)
			(stroke
				(width 0.1)
				(type default)
			)
			(layer "B.Fab")
		)
		(fp_line
			(start -1.1049 -0.724916)
			(end 1.1049 -0.724916)
			(stroke
				(width 0.1)
				(type default)
			)
			(layer "B.Fab")
		)
		(fp_line
			(start 1.1049 -0.724916)
			(end 1.1049 0.724916)
			(stroke
				(width 0.1)
				(type default)
			)
			(layer "B.Fab")
		)
		(pad "1" smd rect
			(at 0.889 0 270)
			(size 1.016 1.27)
			(layers "B.Cu" "B.Mask" "B.Paste")
			(net "PVDDIO_P1")
		)
		(pad "2" smd rect
			(at -0.889 0 270)
			(size 1.016 1.27)
			(layers "B.Cu" "B.Mask" "B.Paste")
			(net "GND")
		)
	)
	(footprint ""
		(layer "B.Cu")
		(at 167.772334 -193.996564)
		(property "Reference" "C160"
			(at 0 0 0)
			(layer "B.SilkS")
			(hide yes)
			(effects
				(font
					(size 1.27 1.27)
				)
				(justify mirror)
			)
		)
		(property "Value" ""
			(at 0 0 0)
			(layer "B.Fab")
			(effects
				(font
					(size 1.27 1.27)
				)
				(justify mirror)
			)
		)
		(duplicate_pad_numbers_are_jumpers no)
		(fp_line
			(start -0.7874 -0.4064)
			(end -0.7874 0.4064)
			(stroke
				(width 0.1524)
				(type default)
			)
			(layer "B.SilkS")
		)
		(fp_line
			(start -0.7874 0.4064)
			(end 0.7874 0.4064)
			(stroke
				(width 0.1524)
				(type default)
			)
			(layer "B.SilkS")
		)
		(fp_line
			(start 0.7874 -0.4064)
			(end -0.7874 -0.4064)
			(stroke
				(width 0.1524)
				(type default)
			)
			(layer "B.SilkS")
		)
		(fp_line
			(start 0.7874 0.4064)
			(end 0.7874 -0.4064)
			(stroke
				(width 0.1524)
				(type default)
			)
			(layer "B.SilkS")
		)
		(fp_line
			(start -0.67945 -0.3048)
			(end -0.67945 0.3048)
			(stroke
				(width 0.1)
				(type default)
			)
			(layer "B.Fab")
		)
		(fp_line
			(start -0.67945 0.3048)
			(end -0.120396 0.3048)
			(stroke
				(width 0.1)
				(type default)
			)
			(layer "B.Fab")
		)
		(fp_line
			(start -0.12065 -0.3048)
			(end -0.67945 -0.3048)
			(stroke
				(width 0.1)
				(type default)
			)
			(layer "B.Fab")
		)
		(fp_line
			(start -0.12065 -0.2794)
			(end -0.12065 -0.3048)
			(stroke
				(width 0.1)
				(type default)
			)
			(layer "B.Fab")
		)
		(fp_line
			(start -0.120396 0.2794)
			(end 0.12065 0.2794)
			(stroke
				(width 0.1)
				(type default)
			)
			(layer "B.Fab")
		)
		(fp_line
			(start -0.120396 0.3048)
			(end -0.120396 0.2794)
			(stroke
				(width 0.1)
				(type default)
			)
			(layer "B.Fab")
		)
		(fp_line
			(start 0.12065 -0.305054)
			(end 0.12065 -0.2794)
			(stroke
				(width 0.1)
				(type default)
			)
			(layer "B.Fab")
		)
		(fp_line
			(start 0.12065 -0.2794)
			(end -0.12065 -0.2794)
			(stroke
				(width 0.1)
				(type default)
			)
			(layer "B.Fab")
		)
		(fp_line
			(start 0.12065 0.2794)
			(end 0.12065 0.3048)
			(stroke
				(width 0.1)
				(type default)
			)
			(layer "B.Fab")
		)
		(fp_line
			(start 0.12065 0.3048)
			(end 0.67945 0.3048)
			(stroke
				(width 0.1)
				(type default)
			)
			(layer "B.Fab")
		)
		(fp_line
			(start 0.67945 -0.305054)
			(end 0.12065 -0.305054)
			(stroke
				(width 0.1)
				(type default)
			)
			(layer "B.Fab")
		)
		(fp_line
			(start 0.67945 0.3048)
			(end 0.67945 -0.305054)
			(stroke
				(width 0.1)
				(type default)
			)
			(layer "B.Fab")
		)
		(pad "1" smd circle
			(at 0.40005 0 180)
			(size 0 0)
			(layers "B.Cu" "B.Mask" "B.Paste")
			(net "P3V3_AUX")
		)
		(pad "2" smd circle
			(at -0.40005 0 180)
			(size 0 0)
			(layers "B.Cu" "B.Mask" "B.Paste")
			(net "GND")
		)
	)
	(footprint ""
		(layer "B.Cu")
		(at 80.937354 -178.962812 90)
		(property "Reference" "PC264_1"
			(at 0 0 90)
			(layer "B.SilkS")
			(hide yes)
			(effects
				(font
					(size 1.27 1.27)
				)
				(justify mirror)
			)
		)
		(property "Value" ""
			(at 0 0 90)
			(layer "B.Fab")
			(effects
				(font
					(size 1.27 1.27)
				)
				(justify mirror)
			)
		)
		(duplicate_pad_numbers_are_jumpers no)
		(fp_line
			(start 1.524 -0.762)
			(end -1.524 -0.762)
			(stroke
				(width 0.1524)
				(type default)
			)
			(layer "B.SilkS")
		)
		(fp_line
			(start -1.524 -0.762)
			(end -1.524 0.762)
			(stroke
				(width 0.1524)
				(type default)
			)
			(layer "B.SilkS")
		)
		(fp_line
			(start 1.524 0.762)
			(end 1.524 -0.762)
			(stroke
				(width 0.1524)
				(type default)
			)
			(layer "B.SilkS")
		)
		(fp_line
			(start -1.524 0.762)
			(end 1.524 0.762)
			(stroke
				(width 0.1524)
				(type default)
			)
			(layer "B.SilkS")
		)
		(fp_line
			(start 1.1049 -0.724916)
			(end 1.1049 0.724916)
			(stroke
				(width 0.1)
				(type default)
			)
			(layer "B.Fab")
		)
		(fp_line
			(start -1.1049 -0.724916)
			(end 1.1049 -0.724916)
			(stroke
				(width 0.1)
				(type default)
			)
			(layer "B.Fab")
		)
		(fp_line
			(start 1.1049 0.724916)
			(end -1.1049 0.724916)
			(stroke
				(width 0.1)
				(type default)
			)
			(layer "B.Fab")
		)
		(fp_line
			(start -1.1049 0.724916)
			(end -1.1049 -0.724916)
			(stroke
				(width 0.1)
				(type default)
			)
			(layer "B.Fab")
		)
		(pad "1" smd rect
			(at 0.889 0 90)
			(size 1.016 1.27)
			(layers "B.Cu" "B.Mask" "B.Paste")
			(net "SW_P12V_AUX_PVDDCR_CPU0_P1_FLT")
		)
		(pad "2" smd rect
			(at -0.889 0 90)
			(size 1.016 1.27)
			(layers "B.Cu" "B.Mask" "B.Paste")
			(net "GND")
		)
	)
	(footprint ""
		(layer "B.Cu")
		(at 125.590046 -408.517344 90)
		(property "Reference" "C6732"
			(at 0 0 90)
			(layer "B.SilkS")
			(hide yes)
			(effects
				(font
					(size 1.27 1.27)
				)
				(justify mirror)
			)
		)
		(property "Value" ""
			(at 0 0 90)
			(layer "B.Fab")
			(effects
				(font
					(size 1.27 1.27)
				)
				(justify mirror)
			)
		)
		(duplicate_pad_numbers_are_jumpers no)
		(fp_line
			(start 0.299974 -0.150114)
			(end -0.299974 -0.150114)
			(stroke
				(width 0.1)
				(type default)
			)
			(layer "B.Fab")
		)
		(fp_line
			(start -0.299974 -0.150114)
			(end -0.299974 0.150114)
			(stroke
				(width 0.1)
				(type default)
			)
			(layer "B.Fab")
		)
		(fp_line
			(start 0.299974 0.150114)
			(end 0.299974 -0.150114)
			(stroke
				(width 0.1)
				(type default)
			)
			(layer "B.Fab")
		)
		(fp_line
			(start -0.299974 0.150114)
			(end 0.299974 0.150114)
			(stroke
				(width 0.1)
				(type default)
			)
			(layer "B.Fab")
		)
		(pad "1" smd rect
			(at 0.2667 0 270)
			(size 0.3048 0.381)
			(layers "B.Cu" "B.Mask" "B.Paste")
			(net "P5E_CPU1_P3_TX_BUF_C_DN<3>")
		)
		(pad "2" smd rect
			(at -0.2667 0 270)
			(size 0.3048 0.381)
			(layers "B.Cu" "B.Mask" "B.Paste")
			(net "P5E_CPU1_P3_TX_BUF_DN<3>")
		)
	)
	(footprint ""
		(layer "B.Cu")
		(at 369.57 -426.466)
		(property "Reference" "C1057"
			(at 0 0 0)
			(layer "B.SilkS")
			(hide yes)
			(effects
				(font
					(size 1.27 1.27)
				)
				(justify mirror)
			)
		)
		(property "Value" ""
			(at 0 0 0)
			(layer "B.Fab")
			(effects
				(font
					(size 1.27 1.27)
				)
				(justify mirror)
			)
		)
		(duplicate_pad_numbers_are_jumpers no)
		(fp_line
			(start -0.299974 -0.150114)
			(end -0.299974 0.150114)
			(stroke
				(width 0.1)
				(type default)
			)
			(layer "B.Fab")
		)
		(fp_line
			(start -0.299974 0.150114)
			(end 0.299974 0.150114)
			(stroke
				(width 0.1)
				(type default)
			)
			(layer "B.Fab")
		)
		(fp_line
			(start 0.299974 -0.150114)
			(end -0.299974 -0.150114)
			(stroke
				(width 0.1)
				(type default)
			)
			(layer "B.Fab")
		)
		(fp_line
			(start 0.299974 0.150114)
			(end 0.299974 -0.150114)
			(stroke
				(width 0.1)
				(type default)
			)
			(layer "B.Fab")
		)
		(pad "1" smd rect
			(at 0.2667 0 180)
			(size 0.3048 0.381)
			(layers "B.Cu" "B.Mask" "B.Paste")
			(net "P1V8_CPU0_RT_1D")
		)
		(pad "2" smd rect
			(at -0.2667 0 180)
			(size 0.3048 0.381)
			(layers "B.Cu" "B.Mask" "B.Paste")
			(net "GND")
		)
	)
	(footprint ""
		(layer "B.Cu")
		(at 331.39761 -337.638898 -90)
		(property "Reference" "PR84"
			(at 0 0 90)
			(layer "B.SilkS")
			(hide yes)
			(effects
				(font
					(size 1.27 1.27)
				)
				(justify mirror)
			)
		)
		(property "Value" ""
			(at 0 0 90)
			(layer "B.Fab")
			(effects
				(font
					(size 1.27 1.27)
				)
				(justify mirror)
			)
		)
		(duplicate_pad_numbers_are_jumpers no)
		(fp_line
			(start -0.7874 0.4064)
			(end 0.7874 0.4064)
			(stroke
				(width 0.1524)
				(type default)
			)
			(layer "B.SilkS")
		)
		(fp_line
			(start 0.7874 0.4064)
			(end 0.7874 -0.4064)
			(stroke
				(width 0.1524)
				(type default)
			)
			(layer "B.SilkS")
		)
		(fp_line
			(start -0.7874 -0.4064)
			(end -0.7874 0.4064)
			(stroke
				(width 0.1524)
				(type default)
			)
			(layer "B.SilkS")
		)
		(fp_line
			(start 0.7874 -0.4064)
			(end -0.7874 -0.4064)
			(stroke
				(width 0.1524)
				(type default)
			)
			(layer "B.SilkS")
		)
		(fp_line
			(start -0.67945 0.3048)
			(end -0.120396 0.3048)
			(stroke
				(width 0.1)
				(type default)
			)
			(layer "B.Fab")
		)
		(fp_line
			(start -0.120396 0.3048)
			(end -0.120396 0.2794)
			(stroke
				(width 0.1)
				(type default)
			)
			(layer "B.Fab")
		)
		(fp_line
			(start 0.12065 0.3048)
			(end 0.67945 0.3048)
			(stroke
				(width 0.1)
				(type default)
			)
			(layer "B.Fab")
		)
		(fp_line
			(start 0.67945 0.3048)
			(end 0.67945 -0.305054)
			(stroke
				(width 0.1)
				(type default)
			)
			(layer "B.Fab")
		)
		(fp_line
			(start -0.120396 0.2794)
			(end 0.12065 0.2794)
			(stroke
				(width 0.1)
				(type default)
			)
			(layer "B.Fab")
		)
		(fp_line
			(start 0.12065 0.2794)
			(end 0.12065 0.3048)
			(stroke
				(width 0.1)
				(type default)
			)
			(layer "B.Fab")
		)
		(fp_line
			(start -0.12065 -0.2794)
			(end -0.12065 -0.3048)
			(stroke
				(width 0.1)
				(type default)
			)
			(layer "B.Fab")
		)
		(fp_line
			(start 0.12065 -0.2794)
			(end -0.12065 -0.2794)
			(stroke
				(width 0.1)
				(type default)
			)
			(layer "B.Fab")
		)
		(fp_line
			(start -0.67945 -0.3048)
			(end -0.67945 0.3048)
			(stroke
				(width 0.1)
				(type default)
			)
			(layer "B.Fab")
		)
		(fp_line
			(start -0.12065 -0.3048)
			(end -0.67945 -0.3048)
			(stroke
				(width 0.1)
				(type default)
			)
			(layer "B.Fab")
		)
		(fp_line
			(start 0.12065 -0.305054)
			(end 0.12065 -0.2794)
			(stroke
				(width 0.1)
				(type default)
			)
			(layer "B.Fab")
		)
		(fp_line
			(start 0.67945 -0.305054)
			(end 0.12065 -0.305054)
			(stroke
				(width 0.1)
				(type default)
			)
			(layer "B.Fab")
		)
		(pad "1" smd circle
			(at 0.40005 0 90)
			(size 0 0)
			(layers "B.Cu" "B.Mask" "B.Paste")
			(net "PVDDCR_CPU1_P0_VOS1")
		)
		(pad "2" smd circle
			(at -0.40005 0 90)
			(size 0 0)
			(layers "B.Cu" "B.Mask" "B.Paste")
			(net "PVDDCR_CPU1_P0")
		)
	)
	(footprint ""
		(layer "B.Cu")
		(at 115.277138 -261.748016 90)
		(property "Reference" "C2497"
			(at 0 0 90)
			(layer "B.SilkS")
			(hide yes)
			(effects
				(font
					(size 1.27 1.27)
				)
				(justify mirror)
			)
		)
		(property "Value" ""
			(at 0 0 90)
			(layer "B.Fab")
			(effects
				(font
					(size 1.27 1.27)
				)
				(justify mirror)
			)
		)
		(duplicate_pad_numbers_are_jumpers no)
		(fp_line
			(start 0.7874 -0.4064)
			(end -0.7874 -0.4064)
			(stroke
				(width 0.1524)
				(type default)
			)
			(layer "B.SilkS")
		)
		(fp_line
			(start -0.7874 -0.4064)
			(end -0.7874 0.4064)
			(stroke
				(width 0.1524)
				(type default)
			)
			(layer "B.SilkS")
		)
		(fp_line
			(start 0.7874 0.4064)
			(end 0.7874 -0.4064)
			(stroke
				(width 0.1524)
				(type default)
			)
			(layer "B.SilkS")
		)
		(fp_line
			(start -0.7874 0.4064)
			(end 0.7874 0.4064)
			(stroke
				(width 0.1524)
				(type default)
			)
			(layer "B.SilkS")
		)
		(fp_line
			(start 0.67945 -0.305054)
			(end 0.12065 -0.305054)
			(stroke
				(width 0.1)
				(type default)
			)
			(layer "B.Fab")
		)
		(fp_line
			(start 0.12065 -0.305054)
			(end 0.12065 -0.2794)
			(stroke
				(width 0.1)
				(type default)
			)
			(layer "B.Fab")
		)
		(fp_line
			(start -0.12065 -0.3048)
			(end -0.67945 -0.3048)
			(stroke
				(width 0.1)
				(type default)
			)
			(layer "B.Fab")
		)
		(fp_line
			(start -0.67945 -0.3048)
			(end -0.67945 0.3048)
			(stroke
				(width 0.1)
				(type default)
			)
			(layer "B.Fab")
		)
		(fp_line
			(start 0.12065 -0.2794)
			(end -0.12065 -0.2794)
			(stroke
				(width 0.1)
				(type default)
			)
			(layer "B.Fab")
		)
		(fp_line
			(start -0.12065 -0.2794)
			(end -0.12065 -0.3048)
			(stroke
				(width 0.1)
				(type default)
			)
			(layer "B.Fab")
		)
		(fp_line
			(start 0.12065 0.2794)
			(end 0.12065 0.3048)
			(stroke
				(width 0.1)
				(type default)
			)
			(layer "B.Fab")
		)
		(fp_line
			(start -0.120396 0.2794)
			(end 0.12065 0.2794)
			(stroke
				(width 0.1)
				(type default)
			)
			(layer "B.Fab")
		)
		(fp_line
			(start 0.67945 0.3048)
			(end 0.67945 -0.305054)
			(stroke
				(width 0.1)
				(type default)
			)
			(layer "B.Fab")
		)
		(fp_line
			(start 0.12065 0.3048)
			(end 0.67945 0.3048)
			(stroke
				(width 0.1)
				(type default)
			)
			(layer "B.Fab")
		)
		(fp_line
			(start -0.120396 0.3048)
			(end -0.120396 0.2794)
			(stroke
				(width 0.1)
				(type default)
			)
			(layer "B.Fab")
		)
		(fp_line
			(start -0.67945 0.3048)
			(end -0.120396 0.3048)
			(stroke
				(width 0.1)
				(type default)
			)
			(layer "B.Fab")
		)
		(pad "1" smd circle
			(at 0.40005 0 270)
			(size 0 0)
			(layers "B.Cu" "B.Mask" "B.Paste")
			(net "PVDD11_S3_P1")
		)
		(pad "2" smd circle
			(at -0.40005 0 270)
			(size 0 0)
			(layers "B.Cu" "B.Mask" "B.Paste")
			(net "GND")
		)
	)
	(footprint ""
		(layer "B.Cu")
		(at 156.154374 -324.781672 180)
		(property "Reference" "R549"
			(at 0 0 0)
			(layer "B.SilkS")
			(hide yes)
			(effects
				(font
					(size 1.27 1.27)
				)
				(justify mirror)
			)
		)
		(property "Value" ""
			(at 0 0 0)
			(layer "B.Fab")
			(effects
				(font
					(size 1.27 1.27)
				)
				(justify mirror)
			)
		)
		(duplicate_pad_numbers_are_jumpers no)
		(fp_line
			(start 0.7874 0.4064)
			(end 0.7874 -0.4064)
			(stroke
				(width 0.1524)
				(type default)
			)
			(layer "B.SilkS")
		)
		(fp_line
			(start 0.7874 -0.4064)
			(end -0.7874 -0.4064)
			(stroke
				(width 0.1524)
				(type default)
			)
			(layer "B.SilkS")
		)
		(fp_line
			(start -0.7874 0.4064)
			(end 0.7874 0.4064)
			(stroke
				(width 0.1524)
				(type default)
			)
			(layer "B.SilkS")
		)
		(fp_line
			(start -0.7874 -0.4064)
			(end -0.7874 0.4064)
			(stroke
				(width 0.1524)
				(type default)
			)
			(layer "B.SilkS")
		)
		(fp_line
			(start 0.67945 0.3048)
			(end 0.67945 -0.305054)
			(stroke
				(width 0.1)
				(type default)
			)
			(layer "B.Fab")
		)
		(fp_line
			(start 0.67945 -0.305054)
			(end 0.12065 -0.305054)
			(stroke
				(width 0.1)
				(type default)
			)
			(layer "B.Fab")
		)
		(fp_line
			(start 0.12065 0.3048)
			(end 0.67945 0.3048)
			(stroke
				(width 0.1)
				(type default)
			)
			(layer "B.Fab")
		)
		(fp_line
			(start 0.12065 0.2794)
			(end 0.12065 0.3048)
			(stroke
				(width 0.1)
				(type default)
			)
			(layer "B.Fab")
		)
		(fp_line
			(start 0.12065 -0.2794)
			(end -0.12065 -0.2794)
			(stroke
				(width 0.1)
				(type default)
			)
			(layer "B.Fab")
		)
		(fp_line
			(start 0.12065 -0.305054)
			(end 0.12065 -0.2794)
			(stroke
				(width 0.1)
				(type default)
			)
			(layer "B.Fab")
		)
		(fp_line
			(start -0.120396 0.3048)
			(end -0.120396 0.2794)
			(stroke
				(width 0.1)
				(type default)
			)
			(layer "B.Fab")
		)
		(fp_line
			(start -0.120396 0.2794)
			(end 0.12065 0.2794)
			(stroke
				(width 0.1)
				(type default)
			)
			(layer "B.Fab")
		)
		(fp_line
			(start -0.12065 -0.2794)
			(end -0.12065 -0.3048)
			(stroke
				(width 0.1)
				(type default)
			)
			(layer "B.Fab")
		)
		(fp_line
			(start -0.12065 -0.3048)
			(end -0.67945 -0.3048)
			(stroke
				(width 0.1)
				(type default)
			)
			(layer "B.Fab")
		)
		(fp_line
			(start -0.67945 0.3048)
			(end -0.120396 0.3048)
			(stroke
				(width 0.1)
				(type default)
			)
			(layer "B.Fab")
		)
		(fp_line
			(start -0.67945 -0.3048)
			(end -0.67945 0.3048)
			(stroke
				(width 0.1)
				(type default)
			)
			(layer "B.Fab")
		)
		(pad "1" smd circle
			(at 0.40005 0)
			(size 0 0)
			(layers "B.Cu" "B.Mask" "B.Paste")
			(net "CPU1_SLP_S3_N")
		)
		(pad "2" smd circle
			(at -0.40005 0)
			(size 0 0)
			(layers "B.Cu" "B.Mask" "B.Paste")
			(net "PVDD18_S5_P1")
		)
	)
	(footprint ""
		(layer "B.Cu")
		(at 164.044376 -111.637572 180)
		(property "Reference" "R6140"
			(at 0 0 0)
			(layer "B.SilkS")
			(hide yes)
			(effects
				(font
					(size 1.27 1.27)
				)
				(justify mirror)
			)
		)
		(property "Value" ""
			(at 0 0 0)
			(layer "B.Fab")
			(effects
				(font
					(size 1.27 1.27)
				)
				(justify mirror)
			)
		)
		(duplicate_pad_numbers_are_jumpers no)
		(fp_line
			(start 0.7874 0.4064)
			(end 0.7874 -0.4064)
			(stroke
				(width 0.1524)
				(type default)
			)
			(layer "B.SilkS")
		)
		(fp_line
			(start 0.7874 -0.4064)
			(end -0.7874 -0.4064)
			(stroke
				(width 0.1524)
				(type default)
			)
			(layer "B.SilkS")
		)
		(fp_line
			(start -0.7874 0.4064)
			(end 0.7874 0.4064)
			(stroke
				(width 0.1524)
				(type default)
			)
			(layer "B.SilkS")
		)
		(fp_line
			(start -0.7874 -0.4064)
			(end -0.7874 0.4064)
			(stroke
				(width 0.1524)
				(type default)
			)
			(layer "B.SilkS")
		)
		(fp_line
			(start 0.67945 0.3048)
			(end 0.67945 -0.305054)
			(stroke
				(width 0.1)
				(type default)
			)
			(layer "B.Fab")
		)
		(fp_line
			(start 0.67945 -0.305054)
			(end 0.12065 -0.305054)
			(stroke
				(width 0.1)
				(type default)
			)
			(layer "B.Fab")
		)
		(fp_line
			(start 0.12065 0.3048)
			(end 0.67945 0.3048)
			(stroke
				(width 0.1)
				(type default)
			)
			(layer "B.Fab")
		)
		(fp_line
			(start 0.12065 0.2794)
			(end 0.12065 0.3048)
			(stroke
				(width 0.1)
				(type default)
			)
			(layer "B.Fab")
		)
		(fp_line
			(start 0.12065 -0.2794)
			(end -0.12065 -0.2794)
			(stroke
				(width 0.1)
				(type default)
			)
			(layer "B.Fab")
		)
		(fp_line
			(start 0.12065 -0.305054)
			(end 0.12065 -0.2794)
			(stroke
				(width 0.1)
				(type default)
			)
			(layer "B.Fab")
		)
		(fp_line
			(start -0.120396 0.3048)
			(end -0.120396 0.2794)
			(stroke
				(width 0.1)
				(type default)
			)
			(layer "B.Fab")
		)
		(fp_line
			(start -0.120396 0.2794)
			(end 0.12065 0.2794)
			(stroke
				(width 0.1)
				(type default)
			)
			(layer "B.Fab")
		)
		(fp_line
			(start -0.12065 -0.2794)
			(end -0.12065 -0.3048)
			(stroke
				(width 0.1)
				(type default)
			)
			(layer "B.Fab")
		)
		(fp_line
			(start -0.12065 -0.3048)
			(end -0.67945 -0.3048)
			(stroke
				(width 0.1)
				(type default)
			)
			(layer "B.Fab")
		)
		(fp_line
			(start -0.67945 0.3048)
			(end -0.120396 0.3048)
			(stroke
				(width 0.1)
				(type default)
			)
			(layer "B.Fab")
		)
		(fp_line
			(start -0.67945 -0.3048)
			(end -0.67945 0.3048)
			(stroke
				(width 0.1)
				(type default)
			)
			(layer "B.Fab")
		)
		(pad "1" smd circle
			(at 0.40005 0)
			(size 0 0)
			(layers "B.Cu" "B.Mask" "B.Paste")
			(net "P3V3_AUX")
		)
		(pad "2" smd circle
			(at -0.40005 0)
			(size 0 0)
			(layers "B.Cu" "B.Mask" "B.Paste")
			(net "FM_BOARD_BMC_SKU_ID0")
		)
	)
	(footprint ""
		(layer "B.Cu")
		(at 112.46866 -35.088068 90)
		(property "Reference" "C6110"
			(at 0 0 90)
			(layer "B.SilkS")
			(hide yes)
			(effects
				(font
					(size 1.27 1.27)
				)
				(justify mirror)
			)
		)
		(property "Value" ""
			(at 0 0 90)
			(layer "B.Fab")
			(effects
				(font
					(size 1.27 1.27)
				)
				(justify mirror)
			)
		)
		(duplicate_pad_numbers_are_jumpers no)
		(fp_line
			(start 0.7874 -0.4064)
			(end -0.7874 -0.4064)
			(stroke
				(width 0.1524)
				(type default)
			)
			(layer "B.SilkS")
		)
		(fp_line
			(start -0.7874 -0.4064)
			(end -0.7874 0.4064)
			(stroke
				(width 0.1524)
				(type default)
			)
			(layer "B.SilkS")
		)
		(fp_line
			(start 0.7874 0.4064)
			(end 0.7874 -0.4064)
			(stroke
				(width 0.1524)
				(type default)
			)
			(layer "B.SilkS")
		)
		(fp_line
			(start -0.7874 0.4064)
			(end 0.7874 0.4064)
			(stroke
				(width 0.1524)
				(type default)
			)
			(layer "B.SilkS")
		)
		(fp_line
			(start 0.67945 -0.305054)
			(end 0.12065 -0.305054)
			(stroke
				(width 0.1)
				(type default)
			)
			(layer "B.Fab")
		)
		(fp_line
			(start 0.12065 -0.305054)
			(end 0.12065 -0.2794)
			(stroke
				(width 0.1)
				(type default)
			)
			(layer "B.Fab")
		)
		(fp_line
			(start -0.12065 -0.3048)
			(end -0.67945 -0.3048)
			(stroke
				(width 0.1)
				(type default)
			)
			(layer "B.Fab")
		)
		(fp_line
			(start -0.67945 -0.3048)
			(end -0.67945 0.3048)
			(stroke
				(width 0.1)
				(type default)
			)
			(layer "B.Fab")
		)
		(fp_line
			(start 0.12065 -0.2794)
			(end -0.12065 -0.2794)
			(stroke
				(width 0.1)
				(type default)
			)
			(layer "B.Fab")
		)
		(fp_line
			(start -0.12065 -0.2794)
			(end -0.12065 -0.3048)
			(stroke
				(width 0.1)
				(type default)
			)
			(layer "B.Fab")
		)
		(fp_line
			(start 0.12065 0.2794)
			(end 0.12065 0.3048)
			(stroke
				(width 0.1)
				(type default)
			)
			(layer "B.Fab")
		)
		(fp_line
			(start -0.120396 0.2794)
			(end 0.12065 0.2794)
			(stroke
				(width 0.1)
				(type default)
			)
			(layer "B.Fab")
		)
		(fp_line
			(start 0.67945 0.3048)
			(end 0.67945 -0.305054)
			(stroke
				(width 0.1)
				(type default)
			)
			(layer "B.Fab")
		)
		(fp_line
			(start 0.12065 0.3048)
			(end 0.67945 0.3048)
			(stroke
				(width 0.1)
				(type default)
			)
			(layer "B.Fab")
		)
		(fp_line
			(start -0.120396 0.3048)
			(end -0.120396 0.2794)
			(stroke
				(width 0.1)
				(type default)
			)
			(layer "B.Fab")
		)
		(fp_line
			(start -0.67945 0.3048)
			(end -0.120396 0.3048)
			(stroke
				(width 0.1)
				(type default)
			)
			(layer "B.Fab")
		)
		(pad "1" smd circle
			(at 0.40005 0 270)
			(size 0 0)
			(layers "B.Cu" "B.Mask" "B.Paste")
			(net "P1V2_CPU0_USB2_DVDD12")
		)
		(pad "2" smd circle
			(at -0.40005 0 270)
			(size 0 0)
			(layers "B.Cu" "B.Mask" "B.Paste")
			(net "GND")
		)
	)
	(footprint ""
		(layer "B.Cu")
		(at 97.795842 3.523234 180)
		(property "Reference" "J118"
			(at 4.737608 -1.817624 270)
			(unlocked yes)
			(layer "B.SilkS")
			(effects
				(font
					(size 0.7874 0.5842)
					(thickness 0.1524)
				)
				(justify left mirror)
			)
		)
		(property "Value" ""
			(at 0 0 0)
			(layer "B.Fab")
			(effects
				(font
					(size 1.27 1.27)
				)
				(justify mirror)
			)
		)
		(duplicate_pad_numbers_are_jumpers no)
		(fp_line
			(start 1.2192 2.06756)
			(end 1.2192 -2.06756)
			(stroke
				(width 0.1524)
				(type default)
			)
			(layer "B.SilkS")
		)
		(fp_line
			(start 1.2192 -2.06756)
			(end -1.2192 -2.06756)
			(stroke
				(width 0.1524)
				(type default)
			)
			(layer "B.SilkS")
		)
		(fp_line
			(start -1.2192 2.06756)
			(end 1.2192 2.06756)
			(stroke
				(width 0.1524)
				(type default)
			)
			(layer "B.SilkS")
		)
		(fp_line
			(start -1.2192 -2.06756)
			(end -1.2192 2.06756)
			(stroke
				(width 0.1524)
				(type default)
			)
			(layer "B.SilkS")
		)
		(pad "" np_thru_hole circle
			(at -3.4671 -1.27 90)
			(size 1.0414 1.0414)
			(drill 1.0414)
			(layers "*.Cu" "*.Mask")
			(clearance 0.381)
			(thermal_gap 0.381)
		)
		(pad "" np_thru_hole circle
			(at -3.4671 1.27 90)
			(size 1.0414 1.0414)
			(drill 1.0414)
			(layers "*.Cu" "*.Mask")
			(clearance 0.381)
			(thermal_gap 0.381)
		)
		(pad "" np_thru_hole circle
			(at 2.8829 -1.27 90)
			(size 1.0414 1.0414)
			(drill 1.0414)
			(layers "*.Cu" "*.Mask")
			(clearance 0.381)
			(thermal_gap 0.381)
		)
		(pad "" np_thru_hole circle
			(at 2.8829 1.27 90)
			(size 1.0414 1.0414)
			(drill 1.0414)
			(layers "*.Cu" "*.Mask")
			(clearance 0.381)
			(thermal_gap 0.381)
		)
		(pad "1" smd rect
			(at -0.8255 -0.249936 90)
			(size 0.3048 0.508)
			(layers "B.Cu" "B.Mask" "B.Paste")
			(net "DELTA_L_85_10INCH_IN5_DP")
		)
		(pad "2" smd rect
			(at -0.8255 0.249936 90)
			(size 0.3048 0.508)
			(layers "B.Cu" "B.Mask" "B.Paste")
			(net "DELTA_L_85_10INCH_IN5_DN")
		)
		(pad "3" smd circle
			(at 0 0)
			(size 0 0)
			(layers "B.Cu" "B.Mask" "B.Paste")
			(net "DELTA_L_GND_1")
		)
		(zone
			(layers "F.Cu" "B.Cu" "In1.Cu" "In2.Cu" "In3.Cu" "In4.Cu" "In5.Cu" "In6.Cu"
				"In7.Cu" "In8.Cu" "In9.Cu" "In10.Cu" "In11.Cu" "In12.Cu" "In13.Cu" "In14.Cu"
				"In15.Cu" "In16.Cu"
			)
			(hatch none 0.5)
			(connect_pads
				(clearance 0)
			)
			(min_thickness 0.25)
			(keepout
				(tracks not_allowed)
				(vias allowed)
				(pads allowed)
				(copperpour not_allowed)
				(footprints allowed)
			)
			(placement
				(enabled no)
				(sheetname "")
			)
			(fill
				(thermal_gap 0.5)
				(thermal_bridge_width 0.5)
				(island_removal_mode 0)
			)
			(polygon
				(pts
					(arc
						(start 95.840042 2.253234)
						(mid 93.985842 2.253234)
						(end 95.840042 2.253234)
					)
				)
			)
		)
		(zone
			(layers "F.Cu" "B.Cu" "In1.Cu" "In2.Cu" "In3.Cu" "In4.Cu" "In5.Cu" "In6.Cu"
				"In7.Cu" "In8.Cu" "In9.Cu" "In10.Cu" "In11.Cu" "In12.Cu" "In13.Cu" "In14.Cu"
				"In15.Cu" "In16.Cu"
			)
			(hatch none 0.5)
			(connect_pads
				(clearance 0)
			)
			(min_thickness 0.25)
			(keepout
				(tracks not_allowed)
				(vias allowed)
				(pads allowed)
				(copperpour not_allowed)
				(footprints allowed)
			)
			(placement
				(enabled no)
				(sheetname "")
			)
			(fill
				(thermal_gap 0.5)
				(thermal_bridge_width 0.5)
				(island_removal_mode 0)
			)
			(polygon
				(pts
					(arc
						(start 95.840042 4.793234)
						(mid 93.985842 4.793234)
						(end 95.840042 4.793234)
					)
				)
			)
		)
		(zone
			(layers "F.Cu" "B.Cu" "In1.Cu" "In2.Cu" "In3.Cu" "In4.Cu" "In5.Cu" "In6.Cu"
				"In7.Cu" "In8.Cu" "In9.Cu" "In10.Cu" "In11.Cu" "In12.Cu" "In13.Cu" "In14.Cu"
				"In15.Cu" "In16.Cu"
			)
			(hatch none 0.5)
			(connect_pads
				(clearance 0)
			)
			(min_thickness 0.25)
			(keepout
				(tracks not_allowed)
				(vias allowed)
				(pads allowed)
				(copperpour not_allowed)
				(footprints allowed)
			)
			(placement
				(enabled no)
				(sheetname "")
			)
			(fill
				(thermal_gap 0.5)
				(thermal_bridge_width 0.5)
				(island_removal_mode 0)
			)
			(polygon
				(pts
					(arc
						(start 102.190042 2.253234)
						(mid 100.335842 2.253234)
						(end 102.190042 2.253234)
					)
				)
			)
		)
		(zone
			(layers "F.Cu" "B.Cu" "In1.Cu" "In2.Cu" "In3.Cu" "In4.Cu" "In5.Cu" "In6.Cu"
				"In7.Cu" "In8.Cu" "In9.Cu" "In10.Cu" "In11.Cu" "In12.Cu" "In13.Cu" "In14.Cu"
				"In15.Cu" "In16.Cu"
			)
			(hatch none 0.5)
			(connect_pads
				(clearance 0)
			)
			(min_thickness 0.25)
			(keepout
				(tracks not_allowed)
				(vias allowed)
				(pads allowed)
				(copperpour not_allowed)
				(footprints allowed)
			)
			(placement
				(enabled no)
				(sheetname "")
			)
			(fill
				(thermal_gap 0.5)
				(thermal_bridge_width 0.5)
				(island_removal_mode 0)
			)
			(polygon
				(pts
					(arc
						(start 102.190042 4.793234)
						(mid 100.335842 4.793234)
						(end 102.190042 4.793234)
					)
				)
			)
		)
		(zone
			(layer "B.Cu")
			(hatch none 0.5)
			(connect_pads
				(clearance 0)
			)
			(min_thickness 0.25)
			(keepout
				(tracks not_allowed)
				(vias allowed)
				(pads allowed)
				(copperpour not_allowed)
				(footprints allowed)
			)
			(placement
				(enabled no)
				(sheetname "")
			)
			(fill
				(thermal_gap 0.5)
				(thermal_bridge_width 0.5)
				(island_removal_mode 0)
			)
			(polygon
				(pts
					(xy 98.913442 4.071874) (xy 98.913442 3.97637) (xy 98.316542 3.97637) (xy 98.316542 3.56997) (xy 98.913442 3.56997)
					(xy 98.913442 3.476498) (xy 98.316542 3.476498) (xy 98.316542 3.070098) (xy 98.913442 3.070098)
					(xy 98.913442 2.974594) (xy 98.214942 2.974594) (xy 98.214942 4.071874)
				)
			)
		)
	)
	(footprint ""
		(layer "B.Cu")
		(at 124.078492 -386.766562 90)
		(property "Reference" "C445"
			(at 0 0 90)
			(layer "B.SilkS")
			(hide yes)
			(effects
				(font
					(size 1.27 1.27)
				)
				(justify mirror)
			)
		)
		(property "Value" ""
			(at 0 0 90)
			(layer "B.Fab")
			(effects
				(font
					(size 1.27 1.27)
				)
				(justify mirror)
			)
		)
		(duplicate_pad_numbers_are_jumpers no)
		(fp_line
			(start 0.299974 -0.150114)
			(end -0.299974 -0.150114)
			(stroke
				(width 0.1)
				(type default)
			)
			(layer "B.Fab")
		)
		(fp_line
			(start -0.299974 -0.150114)
			(end -0.299974 0.150114)
			(stroke
				(width 0.1)
				(type default)
			)
			(layer "B.Fab")
		)
		(fp_line
			(start 0.299974 0.150114)
			(end 0.299974 -0.150114)
			(stroke
				(width 0.1)
				(type default)
			)
			(layer "B.Fab")
		)
		(fp_line
			(start -0.299974 0.150114)
			(end 0.299974 0.150114)
			(stroke
				(width 0.1)
				(type default)
			)
			(layer "B.Fab")
		)
		(pad "1" smd rect
			(at 0.2667 0 270)
			(size 0.3048 0.381)
			(layers "B.Cu" "B.Mask" "B.Paste")
			(net "P1V8_CPU1_RT3_1A")
		)
		(pad "2" smd rect
			(at -0.2667 0 270)
			(size 0.3048 0.381)
			(layers "B.Cu" "B.Mask" "B.Paste")
			(net "GND")
		)
	)
	(footprint ""
		(layer "B.Cu")
		(at 377.234958 -205.101952 -90)
		(property "Reference" "R403"
			(at 0 0 90)
			(layer "B.SilkS")
			(hide yes)
			(effects
				(font
					(size 1.27 1.27)
				)
				(justify mirror)
			)
		)
		(property "Value" ""
			(at 0 0 90)
			(layer "B.Fab")
			(effects
				(font
					(size 1.27 1.27)
				)
				(justify mirror)
			)
		)
		(duplicate_pad_numbers_are_jumpers no)
		(fp_line
			(start -0.7874 0.4064)
			(end 0.7874 0.4064)
			(stroke
				(width 0.1524)
				(type default)
			)
			(layer "B.SilkS")
		)
		(fp_line
			(start 0.7874 0.4064)
			(end 0.7874 -0.4064)
			(stroke
				(width 0.1524)
				(type default)
			)
			(layer "B.SilkS")
		)
		(fp_line
			(start -0.7874 -0.4064)
			(end -0.7874 0.4064)
			(stroke
				(width 0.1524)
				(type default)
			)
			(layer "B.SilkS")
		)
		(fp_line
			(start 0.7874 -0.4064)
			(end -0.7874 -0.4064)
			(stroke
				(width 0.1524)
				(type default)
			)
			(layer "B.SilkS")
		)
		(fp_line
			(start -0.67945 0.3048)
			(end -0.120396 0.3048)
			(stroke
				(width 0.1)
				(type default)
			)
			(layer "B.Fab")
		)
		(fp_line
			(start -0.120396 0.3048)
			(end -0.120396 0.2794)
			(stroke
				(width 0.1)
				(type default)
			)
			(layer "B.Fab")
		)
		(fp_line
			(start 0.12065 0.3048)
			(end 0.67945 0.3048)
			(stroke
				(width 0.1)
				(type default)
			)
			(layer "B.Fab")
		)
		(fp_line
			(start 0.67945 0.3048)
			(end 0.67945 -0.305054)
			(stroke
				(width 0.1)
				(type default)
			)
			(layer "B.Fab")
		)
		(fp_line
			(start -0.120396 0.2794)
			(end 0.12065 0.2794)
			(stroke
				(width 0.1)
				(type default)
			)
			(layer "B.Fab")
		)
		(fp_line
			(start 0.12065 0.2794)
			(end 0.12065 0.3048)
			(stroke
				(width 0.1)
				(type default)
			)
			(layer "B.Fab")
		)
		(fp_line
			(start -0.12065 -0.2794)
			(end -0.12065 -0.3048)
			(stroke
				(width 0.1)
				(type default)
			)
			(layer "B.Fab")
		)
		(fp_line
			(start 0.12065 -0.2794)
			(end -0.12065 -0.2794)
			(stroke
				(width 0.1)
				(type default)
			)
			(layer "B.Fab")
		)
		(fp_line
			(start -0.67945 -0.3048)
			(end -0.67945 0.3048)
			(stroke
				(width 0.1)
				(type default)
			)
			(layer "B.Fab")
		)
		(fp_line
			(start -0.12065 -0.3048)
			(end -0.67945 -0.3048)
			(stroke
				(width 0.1)
				(type default)
			)
			(layer "B.Fab")
		)
		(fp_line
			(start 0.12065 -0.305054)
			(end 0.12065 -0.2794)
			(stroke
				(width 0.1)
				(type default)
			)
			(layer "B.Fab")
		)
		(fp_line
			(start 0.67945 -0.305054)
			(end 0.12065 -0.305054)
			(stroke
				(width 0.1)
				(type default)
			)
			(layer "B.Fab")
		)
		(pad "1" smd circle
			(at 0.40005 0 90)
			(size 0 0)
			(layers "B.Cu" "B.Mask" "B.Paste")
			(net "PVDD18_S5_P0")
		)
		(pad "2" smd circle
			(at -0.40005 0 90)
			(size 0 0)
			(layers "B.Cu" "B.Mask" "B.Paste")
			(net "JTAG_CPU0_DBREQ_N")
		)
	)
	(footprint ""
		(layer "B.Cu")
		(at 104.850946 -340.007194 90)
		(property "Reference" "PC144_6"
			(at 0 0 90)
			(layer "B.SilkS")
			(hide yes)
			(effects
				(font
					(size 1.27 1.27)
				)
				(justify mirror)
			)
		)
		(property "Value" ""
			(at 0 0 90)
			(layer "B.Fab")
			(effects
				(font
					(size 1.27 1.27)
				)
				(justify mirror)
			)
		)
		(duplicate_pad_numbers_are_jumpers no)
		(fp_line
			(start 1.524 -0.762)
			(end -1.524 -0.762)
			(stroke
				(width 0.1524)
				(type default)
			)
			(layer "B.SilkS")
		)
		(fp_line
			(start -1.524 -0.762)
			(end -1.524 0.762)
			(stroke
				(width 0.1524)
				(type default)
			)
			(layer "B.SilkS")
		)
		(fp_line
			(start 1.524 0.762)
			(end 1.524 -0.762)
			(stroke
				(width 0.1524)
				(type default)
			)
			(layer "B.SilkS")
		)
		(fp_line
			(start -1.524 0.762)
			(end 1.524 0.762)
			(stroke
				(width 0.1524)
				(type default)
			)
			(layer "B.SilkS")
		)
		(fp_line
			(start 1.1049 -0.724916)
			(end 1.1049 0.724916)
			(stroke
				(width 0.1)
				(type default)
			)
			(layer "B.Fab")
		)
		(fp_line
			(start -1.1049 -0.724916)
			(end 1.1049 -0.724916)
			(stroke
				(width 0.1)
				(type default)
			)
			(layer "B.Fab")
		)
		(fp_line
			(start 1.1049 0.724916)
			(end -1.1049 0.724916)
			(stroke
				(width 0.1)
				(type default)
			)
			(layer "B.Fab")
		)
		(fp_line
			(start -1.1049 0.724916)
			(end -1.1049 -0.724916)
			(stroke
				(width 0.1)
				(type default)
			)
			(layer "B.Fab")
		)
		(pad "1" smd rect
			(at 0.889 0 90)
			(size 1.016 1.27)
			(layers "B.Cu" "B.Mask" "B.Paste")
			(net "SW_P12V_AUX_PVDDCR_CPU1_P1_FLT")
		)
		(pad "2" smd rect
			(at -0.889 0 90)
			(size 1.016 1.27)
			(layers "B.Cu" "B.Mask" "B.Paste")
			(net "GND")
		)
	)
	(footprint ""
		(layer "B.Cu")
		(at 298.054014 -347.77553 -90)
		(property "Reference" "PR100"
			(at 0 0 90)
			(layer "B.SilkS")
			(hide yes)
			(effects
				(font
					(size 1.27 1.27)
				)
				(justify mirror)
			)
		)
		(property "Value" ""
			(at 0 0 90)
			(layer "B.Fab")
			(effects
				(font
					(size 1.27 1.27)
				)
				(justify mirror)
			)
		)
		(duplicate_pad_numbers_are_jumpers no)
		(fp_line
			(start -0.7874 0.4064)
			(end 0.7874 0.4064)
			(stroke
				(width 0.1524)
				(type default)
			)
			(layer "B.SilkS")
		)
		(fp_line
			(start 0.7874 0.4064)
			(end 0.7874 -0.4064)
			(stroke
				(width 0.1524)
				(type default)
			)
			(layer "B.SilkS")
		)
		(fp_line
			(start -0.7874 -0.4064)
			(end -0.7874 0.4064)
			(stroke
				(width 0.1524)
				(type default)
			)
			(layer "B.SilkS")
		)
		(fp_line
			(start 0.7874 -0.4064)
			(end -0.7874 -0.4064)
			(stroke
				(width 0.1524)
				(type default)
			)
			(layer "B.SilkS")
		)
		(fp_line
			(start -0.67945 0.3048)
			(end -0.120396 0.3048)
			(stroke
				(width 0.1)
				(type default)
			)
			(layer "B.Fab")
		)
		(fp_line
			(start -0.120396 0.3048)
			(end -0.120396 0.2794)
			(stroke
				(width 0.1)
				(type default)
			)
			(layer "B.Fab")
		)
		(fp_line
			(start 0.12065 0.3048)
			(end 0.67945 0.3048)
			(stroke
				(width 0.1)
				(type default)
			)
			(layer "B.Fab")
		)
		(fp_line
			(start 0.67945 0.3048)
			(end 0.67945 -0.305054)
			(stroke
				(width 0.1)
				(type default)
			)
			(layer "B.Fab")
		)
		(fp_line
			(start -0.120396 0.2794)
			(end 0.12065 0.2794)
			(stroke
				(width 0.1)
				(type default)
			)
			(layer "B.Fab")
		)
		(fp_line
			(start 0.12065 0.2794)
			(end 0.12065 0.3048)
			(stroke
				(width 0.1)
				(type default)
			)
			(layer "B.Fab")
		)
		(fp_line
			(start -0.12065 -0.2794)
			(end -0.12065 -0.3048)
			(stroke
				(width 0.1)
				(type default)
			)
			(layer "B.Fab")
		)
		(fp_line
			(start 0.12065 -0.2794)
			(end -0.12065 -0.2794)
			(stroke
				(width 0.1)
				(type default)
			)
			(layer "B.Fab")
		)
		(fp_line
			(start -0.67945 -0.3048)
			(end -0.67945 0.3048)
			(stroke
				(width 0.1)
				(type default)
			)
			(layer "B.Fab")
		)
		(fp_line
			(start -0.12065 -0.3048)
			(end -0.67945 -0.3048)
			(stroke
				(width 0.1)
				(type default)
			)
			(layer "B.Fab")
		)
		(fp_line
			(start 0.12065 -0.305054)
			(end 0.12065 -0.2794)
			(stroke
				(width 0.1)
				(type default)
			)
			(layer "B.Fab")
		)
		(fp_line
			(start 0.67945 -0.305054)
			(end 0.12065 -0.305054)
			(stroke
				(width 0.1)
				(type default)
			)
			(layer "B.Fab")
		)
		(pad "1" smd circle
			(at 0.40005 0 90)
			(size 0 0)
			(layers "B.Cu" "B.Mask" "B.Paste")
			(net "PVDDCR_CPU1_P0_PVCC")
		)
		(pad "2" smd circle
			(at -0.40005 0 90)
			(size 0 0)
			(layers "B.Cu" "B.Mask" "B.Paste")
			(net "PVDDIO_P0_VCC1")
		)
	)
	(footprint ""
		(layer "B.Cu")
		(at 231.914192 -321.775582 180)
		(property "Reference" "R1260"
			(at 0 0 0)
			(layer "B.SilkS")
			(hide yes)
			(effects
				(font
					(size 1.27 1.27)
				)
				(justify mirror)
			)
		)
		(property "Value" ""
			(at 0 0 0)
			(layer "B.Fab")
			(effects
				(font
					(size 1.27 1.27)
				)
				(justify mirror)
			)
		)
		(duplicate_pad_numbers_are_jumpers no)
		(fp_line
			(start 0.7874 0.4064)
			(end 0.7874 -0.4064)
			(stroke
				(width 0.1524)
				(type default)
			)
			(layer "B.SilkS")
		)
		(fp_line
			(start 0.7874 -0.4064)
			(end -0.7874 -0.4064)
			(stroke
				(width 0.1524)
				(type default)
			)
			(layer "B.SilkS")
		)
		(fp_line
			(start -0.7874 0.4064)
			(end 0.7874 0.4064)
			(stroke
				(width 0.1524)
				(type default)
			)
			(layer "B.SilkS")
		)
		(fp_line
			(start -0.7874 -0.4064)
			(end -0.7874 0.4064)
			(stroke
				(width 0.1524)
				(type default)
			)
			(layer "B.SilkS")
		)
		(fp_line
			(start 0.67945 0.3048)
			(end 0.67945 -0.305054)
			(stroke
				(width 0.1)
				(type default)
			)
			(layer "B.Fab")
		)
		(fp_line
			(start 0.67945 -0.305054)
			(end 0.12065 -0.305054)
			(stroke
				(width 0.1)
				(type default)
			)
			(layer "B.Fab")
		)
		(fp_line
			(start 0.12065 0.3048)
			(end 0.67945 0.3048)
			(stroke
				(width 0.1)
				(type default)
			)
			(layer "B.Fab")
		)
		(fp_line
			(start 0.12065 0.2794)
			(end 0.12065 0.3048)
			(stroke
				(width 0.1)
				(type default)
			)
			(layer "B.Fab")
		)
		(fp_line
			(start 0.12065 -0.2794)
			(end -0.12065 -0.2794)
			(stroke
				(width 0.1)
				(type default)
			)
			(layer "B.Fab")
		)
		(fp_line
			(start 0.12065 -0.305054)
			(end 0.12065 -0.2794)
			(stroke
				(width 0.1)
				(type default)
			)
			(layer "B.Fab")
		)
		(fp_line
			(start -0.120396 0.3048)
			(end -0.120396 0.2794)
			(stroke
				(width 0.1)
				(type default)
			)
			(layer "B.Fab")
		)
		(fp_line
			(start -0.120396 0.2794)
			(end 0.12065 0.2794)
			(stroke
				(width 0.1)
				(type default)
			)
			(layer "B.Fab")
		)
		(fp_line
			(start -0.12065 -0.2794)
			(end -0.12065 -0.3048)
			(stroke
				(width 0.1)
				(type default)
			)
			(layer "B.Fab")
		)
		(fp_line
			(start -0.12065 -0.3048)
			(end -0.67945 -0.3048)
			(stroke
				(width 0.1)
				(type default)
			)
			(layer "B.Fab")
		)
		(fp_line
			(start -0.67945 0.3048)
			(end -0.120396 0.3048)
			(stroke
				(width 0.1)
				(type default)
			)
			(layer "B.Fab")
		)
		(fp_line
			(start -0.67945 -0.3048)
			(end -0.67945 0.3048)
			(stroke
				(width 0.1)
				(type default)
			)
			(layer "B.Fab")
		)
		(pad "1" smd rect
			(at 0.40005 0 180)
			(size 0.4572 0.508)
			(layers "B.Cu" "B.Mask" "B.Paste")
			(net "P5V_AUX_ADC")
		)
		(pad "2" smd rect
			(at -0.40005 0 180)
			(size 0.4572 0.508)
			(layers "B.Cu" "B.Mask" "B.Paste")
			(net "P5V_AUX_ADC_MAM")
		)
	)
	(footprint ""
		(layer "B.Cu")
		(at 77.14488 -11.267948 90)
		(property "Reference" "R3168"
			(at 0 0 90)
			(layer "B.SilkS")
			(hide yes)
			(effects
				(font
					(size 1.27 1.27)
				)
				(justify mirror)
			)
		)
		(property "Value" ""
			(at 0 0 90)
			(layer "B.Fab")
			(effects
				(font
					(size 1.27 1.27)
				)
				(justify mirror)
			)
		)
		(duplicate_pad_numbers_are_jumpers no)
		(fp_line
			(start 0.7874 -0.4064)
			(end -0.7874 -0.4064)
			(stroke
				(width 0.1524)
				(type default)
			)
			(layer "B.SilkS")
		)
		(fp_line
			(start -0.7874 -0.4064)
			(end -0.7874 0.4064)
			(stroke
				(width 0.1524)
				(type default)
			)
			(layer "B.SilkS")
		)
		(fp_line
			(start 0.7874 0.4064)
			(end 0.7874 -0.4064)
			(stroke
				(width 0.1524)
				(type default)
			)
			(layer "B.SilkS")
		)
		(fp_line
			(start -0.7874 0.4064)
			(end 0.7874 0.4064)
			(stroke
				(width 0.1524)
				(type default)
			)
			(layer "B.SilkS")
		)
		(fp_line
			(start 0.67945 -0.305054)
			(end 0.12065 -0.305054)
			(stroke
				(width 0.1)
				(type default)
			)
			(layer "B.Fab")
		)
		(fp_line
			(start 0.12065 -0.305054)
			(end 0.12065 -0.2794)
			(stroke
				(width 0.1)
				(type default)
			)
			(layer "B.Fab")
		)
		(fp_line
			(start -0.12065 -0.3048)
			(end -0.67945 -0.3048)
			(stroke
				(width 0.1)
				(type default)
			)
			(layer "B.Fab")
		)
		(fp_line
			(start -0.67945 -0.3048)
			(end -0.67945 0.3048)
			(stroke
				(width 0.1)
				(type default)
			)
			(layer "B.Fab")
		)
		(fp_line
			(start 0.12065 -0.2794)
			(end -0.12065 -0.2794)
			(stroke
				(width 0.1)
				(type default)
			)
			(layer "B.Fab")
		)
		(fp_line
			(start -0.12065 -0.2794)
			(end -0.12065 -0.3048)
			(stroke
				(width 0.1)
				(type default)
			)
			(layer "B.Fab")
		)
		(fp_line
			(start 0.12065 0.2794)
			(end 0.12065 0.3048)
			(stroke
				(width 0.1)
				(type default)
			)
			(layer "B.Fab")
		)
		(fp_line
			(start -0.120396 0.2794)
			(end 0.12065 0.2794)
			(stroke
				(width 0.1)
				(type default)
			)
			(layer "B.Fab")
		)
		(fp_line
			(start 0.67945 0.3048)
			(end 0.67945 -0.305054)
			(stroke
				(width 0.1)
				(type default)
			)
			(layer "B.Fab")
		)
		(fp_line
			(start 0.12065 0.3048)
			(end 0.67945 0.3048)
			(stroke
				(width 0.1)
				(type default)
			)
			(layer "B.Fab")
		)
		(fp_line
			(start -0.120396 0.3048)
			(end -0.120396 0.2794)
			(stroke
				(width 0.1)
				(type default)
			)
			(layer "B.Fab")
		)
		(fp_line
			(start -0.67945 0.3048)
			(end -0.120396 0.3048)
			(stroke
				(width 0.1)
				(type default)
			)
			(layer "B.Fab")
		)
		(pad "1" smd circle
			(at 0.40005 0 270)
			(size 0 0)
			(layers "B.Cu" "B.Mask" "B.Paste")
			(net "OCP_V3_2_MAIN_PWR_EN")
		)
		(pad "2" smd circle
			(at -0.40005 0 270)
			(size 0 0)
			(layers "B.Cu" "B.Mask" "B.Paste")
			(net "OCP_V3_2_MAIN_PWR_EN_R")
		)
	)
	(footprint ""
		(layer "B.Cu")
		(at 171.196 -110.200948)
		(property "Reference" "R168"
			(at 0 0 0)
			(layer "B.SilkS")
			(hide yes)
			(effects
				(font
					(size 1.27 1.27)
				)
				(justify mirror)
			)
		)
		(property "Value" ""
			(at 0 0 0)
			(layer "B.Fab")
			(effects
				(font
					(size 1.27 1.27)
				)
				(justify mirror)
			)
		)
		(duplicate_pad_numbers_are_jumpers no)
		(fp_line
			(start -0.7874 -0.4064)
			(end -0.7874 0.4064)
			(stroke
				(width 0.1524)
				(type default)
			)
			(layer "B.SilkS")
		)
		(fp_line
			(start -0.7874 0.4064)
			(end 0.7874 0.4064)
			(stroke
				(width 0.1524)
				(type default)
			)
			(layer "B.SilkS")
		)
		(fp_line
			(start 0.7874 -0.4064)
			(end -0.7874 -0.4064)
			(stroke
				(width 0.1524)
				(type default)
			)
			(layer "B.SilkS")
		)
		(fp_line
			(start 0.7874 0.4064)
			(end 0.7874 -0.4064)
			(stroke
				(width 0.1524)
				(type default)
			)
			(layer "B.SilkS")
		)
		(fp_line
			(start -0.67945 -0.3048)
			(end -0.67945 0.3048)
			(stroke
				(width 0.1)
				(type default)
			)
			(layer "B.Fab")
		)
		(fp_line
			(start -0.67945 0.3048)
			(end -0.120396 0.3048)
			(stroke
				(width 0.1)
				(type default)
			)
			(layer "B.Fab")
		)
		(fp_line
			(start -0.12065 -0.3048)
			(end -0.67945 -0.3048)
			(stroke
				(width 0.1)
				(type default)
			)
			(layer "B.Fab")
		)
		(fp_line
			(start -0.12065 -0.2794)
			(end -0.12065 -0.3048)
			(stroke
				(width 0.1)
				(type default)
			)
			(layer "B.Fab")
		)
		(fp_line
			(start -0.120396 0.2794)
			(end 0.12065 0.2794)
			(stroke
				(width 0.1)
				(type default)
			)
			(layer "B.Fab")
		)
		(fp_line
			(start -0.120396 0.3048)
			(end -0.120396 0.2794)
			(stroke
				(width 0.1)
				(type default)
			)
			(layer "B.Fab")
		)
		(fp_line
			(start 0.12065 -0.305054)
			(end 0.12065 -0.2794)
			(stroke
				(width 0.1)
				(type default)
			)
			(layer "B.Fab")
		)
		(fp_line
			(start 0.12065 -0.2794)
			(end -0.12065 -0.2794)
			(stroke
				(width 0.1)
				(type default)
			)
			(layer "B.Fab")
		)
		(fp_line
			(start 0.12065 0.2794)
			(end 0.12065 0.3048)
			(stroke
				(width 0.1)
				(type default)
			)
			(layer "B.Fab")
		)
		(fp_line
			(start 0.12065 0.3048)
			(end 0.67945 0.3048)
			(stroke
				(width 0.1)
				(type default)
			)
			(layer "B.Fab")
		)
		(fp_line
			(start 0.67945 -0.305054)
			(end 0.12065 -0.305054)
			(stroke
				(width 0.1)
				(type default)
			)
			(layer "B.Fab")
		)
		(fp_line
			(start 0.67945 0.3048)
			(end 0.67945 -0.305054)
			(stroke
				(width 0.1)
				(type default)
			)
			(layer "B.Fab")
		)
		(pad "1" smd circle
			(at 0.40005 0 180)
			(size 0 0)
			(layers "B.Cu" "B.Mask" "B.Paste")
			(net "SGPIO_SCM_DI_R<1>")
		)
		(pad "2" smd circle
			(at -0.40005 0 180)
			(size 0 0)
			(layers "B.Cu" "B.Mask" "B.Paste")
			(net "SGPIO_SCM_DI_<1>")
		)
	)
	(footprint ""
		(layer "B.Cu")
		(at 182.801768 -414.772094 180)
		(property "Reference" "R2924"
			(at 0 0 0)
			(layer "B.SilkS")
			(hide yes)
			(effects
				(font
					(size 1.27 1.27)
				)
				(justify mirror)
			)
		)
		(property "Value" ""
			(at 0 0 0)
			(layer "B.Fab")
			(effects
				(font
					(size 1.27 1.27)
				)
				(justify mirror)
			)
		)
		(duplicate_pad_numbers_are_jumpers no)
		(fp_line
			(start 0.7874 0.4064)
			(end 0.7874 -0.4064)
			(stroke
				(width 0.1524)
				(type default)
			)
			(layer "B.SilkS")
		)
		(fp_line
			(start 0.7874 -0.4064)
			(end -0.7874 -0.4064)
			(stroke
				(width 0.1524)
				(type default)
			)
			(layer "B.SilkS")
		)
		(fp_line
			(start -0.7874 0.4064)
			(end 0.7874 0.4064)
			(stroke
				(width 0.1524)
				(type default)
			)
			(layer "B.SilkS")
		)
		(fp_line
			(start -0.7874 -0.4064)
			(end -0.7874 0.4064)
			(stroke
				(width 0.1524)
				(type default)
			)
			(layer "B.SilkS")
		)
		(fp_line
			(start 0.67945 0.3048)
			(end 0.67945 -0.305054)
			(stroke
				(width 0.1)
				(type default)
			)
			(layer "B.Fab")
		)
		(fp_line
			(start 0.67945 -0.305054)
			(end 0.12065 -0.305054)
			(stroke
				(width 0.1)
				(type default)
			)
			(layer "B.Fab")
		)
		(fp_line
			(start 0.12065 0.3048)
			(end 0.67945 0.3048)
			(stroke
				(width 0.1)
				(type default)
			)
			(layer "B.Fab")
		)
		(fp_line
			(start 0.12065 0.2794)
			(end 0.12065 0.3048)
			(stroke
				(width 0.1)
				(type default)
			)
			(layer "B.Fab")
		)
		(fp_line
			(start 0.12065 -0.2794)
			(end -0.12065 -0.2794)
			(stroke
				(width 0.1)
				(type default)
			)
			(layer "B.Fab")
		)
		(fp_line
			(start 0.12065 -0.305054)
			(end 0.12065 -0.2794)
			(stroke
				(width 0.1)
				(type default)
			)
			(layer "B.Fab")
		)
		(fp_line
			(start -0.120396 0.3048)
			(end -0.120396 0.2794)
			(stroke
				(width 0.1)
				(type default)
			)
			(layer "B.Fab")
		)
		(fp_line
			(start -0.120396 0.2794)
			(end 0.12065 0.2794)
			(stroke
				(width 0.1)
				(type default)
			)
			(layer "B.Fab")
		)
		(fp_line
			(start -0.12065 -0.2794)
			(end -0.12065 -0.3048)
			(stroke
				(width 0.1)
				(type default)
			)
			(layer "B.Fab")
		)
		(fp_line
			(start -0.12065 -0.3048)
			(end -0.67945 -0.3048)
			(stroke
				(width 0.1)
				(type default)
			)
			(layer "B.Fab")
		)
		(fp_line
			(start -0.67945 0.3048)
			(end -0.120396 0.3048)
			(stroke
				(width 0.1)
				(type default)
			)
			(layer "B.Fab")
		)
		(fp_line
			(start -0.67945 -0.3048)
			(end -0.67945 0.3048)
			(stroke
				(width 0.1)
				(type default)
			)
			(layer "B.Fab")
		)
		(pad "1" smd circle
			(at 0.40005 0)
			(size 0 0)
			(layers "B.Cu" "B.Mask" "B.Paste")
			(net "RST_SWB_BIC_BUF_R_N")
		)
		(pad "2" smd circle
			(at -0.40005 0)
			(size 0 0)
			(layers "B.Cu" "B.Mask" "B.Paste")
			(net "RST_SWB_BIC_BUF_N")
		)
	)
	(footprint ""
		(layer "B.Cu")
		(at 188.935614 -352.380042 -90)
		(property "Reference" "PR327"
			(at 0 0 90)
			(layer "B.SilkS")
			(hide yes)
			(effects
				(font
					(size 1.27 1.27)
				)
				(justify mirror)
			)
		)
		(property "Value" ""
			(at 0 0 90)
			(layer "B.Fab")
			(effects
				(font
					(size 1.27 1.27)
				)
				(justify mirror)
			)
		)
		(duplicate_pad_numbers_are_jumpers no)
		(fp_line
			(start -0.7874 0.4064)
			(end 0.7874 0.4064)
			(stroke
				(width 0.1524)
				(type default)
			)
			(layer "B.SilkS")
		)
		(fp_line
			(start 0.7874 0.4064)
			(end 0.7874 -0.4064)
			(stroke
				(width 0.1524)
				(type default)
			)
			(layer "B.SilkS")
		)
		(fp_line
			(start -0.7874 -0.4064)
			(end -0.7874 0.4064)
			(stroke
				(width 0.1524)
				(type default)
			)
			(layer "B.SilkS")
		)
		(fp_line
			(start 0.7874 -0.4064)
			(end -0.7874 -0.4064)
			(stroke
				(width 0.1524)
				(type default)
			)
			(layer "B.SilkS")
		)
		(fp_line
			(start -0.67945 0.3048)
			(end -0.120396 0.3048)
			(stroke
				(width 0.1)
				(type default)
			)
			(layer "B.Fab")
		)
		(fp_line
			(start -0.120396 0.3048)
			(end -0.120396 0.2794)
			(stroke
				(width 0.1)
				(type default)
			)
			(layer "B.Fab")
		)
		(fp_line
			(start 0.12065 0.3048)
			(end 0.67945 0.3048)
			(stroke
				(width 0.1)
				(type default)
			)
			(layer "B.Fab")
		)
		(fp_line
			(start 0.67945 0.3048)
			(end 0.67945 -0.305054)
			(stroke
				(width 0.1)
				(type default)
			)
			(layer "B.Fab")
		)
		(fp_line
			(start -0.120396 0.2794)
			(end 0.12065 0.2794)
			(stroke
				(width 0.1)
				(type default)
			)
			(layer "B.Fab")
		)
		(fp_line
			(start 0.12065 0.2794)
			(end 0.12065 0.3048)
			(stroke
				(width 0.1)
				(type default)
			)
			(layer "B.Fab")
		)
		(fp_line
			(start -0.12065 -0.2794)
			(end -0.12065 -0.3048)
			(stroke
				(width 0.1)
				(type default)
			)
			(layer "B.Fab")
		)
		(fp_line
			(start 0.12065 -0.2794)
			(end -0.12065 -0.2794)
			(stroke
				(width 0.1)
				(type default)
			)
			(layer "B.Fab")
		)
		(fp_line
			(start -0.67945 -0.3048)
			(end -0.67945 0.3048)
			(stroke
				(width 0.1)
				(type default)
			)
			(layer "B.Fab")
		)
		(fp_line
			(start -0.12065 -0.3048)
			(end -0.67945 -0.3048)
			(stroke
				(width 0.1)
				(type default)
			)
			(layer "B.Fab")
		)
		(fp_line
			(start 0.12065 -0.305054)
			(end 0.12065 -0.2794)
			(stroke
				(width 0.1)
				(type default)
			)
			(layer "B.Fab")
		)
		(fp_line
			(start 0.67945 -0.305054)
			(end 0.12065 -0.305054)
			(stroke
				(width 0.1)
				(type default)
			)
			(layer "B.Fab")
		)
		(pad "1" smd circle
			(at 0.40005 0 90)
			(size 0 0)
			(layers "B.Cu" "B.Mask" "B.Paste")
			(net "PVDD11_S3_P1_PVCC")
		)
		(pad "2" smd circle
			(at -0.40005 0 90)
			(size 0 0)
			(layers "B.Cu" "B.Mask" "B.Paste")
			(net "PVDD11_S3_P1_VCC2")
		)
	)
	(footprint ""
		(layer "B.Cu")
		(at 88.177878 -150.19909)
		(property "Reference" "PR150"
			(at 0 0 0)
			(layer "B.SilkS")
			(hide yes)
			(effects
				(font
					(size 1.27 1.27)
				)
				(justify mirror)
			)
		)
		(property "Value" ""
			(at 0 0 0)
			(layer "B.Fab")
			(effects
				(font
					(size 1.27 1.27)
				)
				(justify mirror)
			)
		)
		(duplicate_pad_numbers_are_jumpers no)
		(fp_line
			(start -0.7874 -0.4064)
			(end -0.7874 0.4064)
			(stroke
				(width 0.1524)
				(type default)
			)
			(layer "B.SilkS")
		)
		(fp_line
			(start -0.7874 0.4064)
			(end 0.7874 0.4064)
			(stroke
				(width 0.1524)
				(type default)
			)
			(layer "B.SilkS")
		)
		(fp_line
			(start 0.7874 -0.4064)
			(end -0.7874 -0.4064)
			(stroke
				(width 0.1524)
				(type default)
			)
			(layer "B.SilkS")
		)
		(fp_line
			(start 0.7874 0.4064)
			(end 0.7874 -0.4064)
			(stroke
				(width 0.1524)
				(type default)
			)
			(layer "B.SilkS")
		)
		(fp_line
			(start -0.67945 -0.3048)
			(end -0.67945 0.3048)
			(stroke
				(width 0.1)
				(type default)
			)
			(layer "B.Fab")
		)
		(fp_line
			(start -0.67945 0.3048)
			(end -0.120396 0.3048)
			(stroke
				(width 0.1)
				(type default)
			)
			(layer "B.Fab")
		)
		(fp_line
			(start -0.12065 -0.3048)
			(end -0.67945 -0.3048)
			(stroke
				(width 0.1)
				(type default)
			)
			(layer "B.Fab")
		)
		(fp_line
			(start -0.12065 -0.2794)
			(end -0.12065 -0.3048)
			(stroke
				(width 0.1)
				(type default)
			)
			(layer "B.Fab")
		)
		(fp_line
			(start -0.120396 0.2794)
			(end 0.12065 0.2794)
			(stroke
				(width 0.1)
				(type default)
			)
			(layer "B.Fab")
		)
		(fp_line
			(start -0.120396 0.3048)
			(end -0.120396 0.2794)
			(stroke
				(width 0.1)
				(type default)
			)
			(layer "B.Fab")
		)
		(fp_line
			(start 0.12065 -0.305054)
			(end 0.12065 -0.2794)
			(stroke
				(width 0.1)
				(type default)
			)
			(layer "B.Fab")
		)
		(fp_line
			(start 0.12065 -0.2794)
			(end -0.12065 -0.2794)
			(stroke
				(width 0.1)
				(type default)
			)
			(layer "B.Fab")
		)
		(fp_line
			(start 0.12065 0.2794)
			(end 0.12065 0.3048)
			(stroke
				(width 0.1)
				(type default)
			)
			(layer "B.Fab")
		)
		(fp_line
			(start 0.12065 0.3048)
			(end 0.67945 0.3048)
			(stroke
				(width 0.1)
				(type default)
			)
			(layer "B.Fab")
		)
		(fp_line
			(start 0.67945 -0.305054)
			(end 0.12065 -0.305054)
			(stroke
				(width 0.1)
				(type default)
			)
			(layer "B.Fab")
		)
		(fp_line
			(start 0.67945 0.3048)
			(end 0.67945 -0.305054)
			(stroke
				(width 0.1)
				(type default)
			)
			(layer "B.Fab")
		)
		(pad "1" smd circle
			(at 0.40005 0 180)
			(size 0 0)
			(layers "B.Cu" "B.Mask" "B.Paste")
			(net "SVID_PVDDCR_CPU0_P1_SVTI")
		)
		(pad "2" smd circle
			(at -0.40005 0 180)
			(size 0 0)
			(layers "B.Cu" "B.Mask" "B.Paste")
			(net "GND")
		)
	)
	(footprint ""
		(layer "B.Cu")
		(at 237.923578 -323.585332)
		(property "Reference" "R1232"
			(at 0 0 0)
			(layer "B.SilkS")
			(hide yes)
			(effects
				(font
					(size 1.27 1.27)
				)
				(justify mirror)
			)
		)
		(property "Value" ""
			(at 0 0 0)
			(layer "B.Fab")
			(effects
				(font
					(size 1.27 1.27)
				)
				(justify mirror)
			)
		)
		(duplicate_pad_numbers_are_jumpers no)
		(fp_line
			(start -0.7874 -0.4064)
			(end -0.7874 0.4064)
			(stroke
				(width 0.1524)
				(type default)
			)
			(layer "B.SilkS")
		)
		(fp_line
			(start -0.7874 0.4064)
			(end 0.7874 0.4064)
			(stroke
				(width 0.1524)
				(type default)
			)
			(layer "B.SilkS")
		)
		(fp_line
			(start 0.7874 -0.4064)
			(end -0.7874 -0.4064)
			(stroke
				(width 0.1524)
				(type default)
			)
			(layer "B.SilkS")
		)
		(fp_line
			(start 0.7874 0.4064)
			(end 0.7874 -0.4064)
			(stroke
				(width 0.1524)
				(type default)
			)
			(layer "B.SilkS")
		)
		(fp_line
			(start -0.67945 -0.3048)
			(end -0.67945 0.3048)
			(stroke
				(width 0.1)
				(type default)
			)
			(layer "B.Fab")
		)
		(fp_line
			(start -0.67945 0.3048)
			(end -0.120396 0.3048)
			(stroke
				(width 0.1)
				(type default)
			)
			(layer "B.Fab")
		)
		(fp_line
			(start -0.12065 -0.3048)
			(end -0.67945 -0.3048)
			(stroke
				(width 0.1)
				(type default)
			)
			(layer "B.Fab")
		)
		(fp_line
			(start -0.12065 -0.2794)
			(end -0.12065 -0.3048)
			(stroke
				(width 0.1)
				(type default)
			)
			(layer "B.Fab")
		)
		(fp_line
			(start -0.120396 0.2794)
			(end 0.12065 0.2794)
			(stroke
				(width 0.1)
				(type default)
			)
			(layer "B.Fab")
		)
		(fp_line
			(start -0.120396 0.3048)
			(end -0.120396 0.2794)
			(stroke
				(width 0.1)
				(type default)
			)
			(layer "B.Fab")
		)
		(fp_line
			(start 0.12065 -0.305054)
			(end 0.12065 -0.2794)
			(stroke
				(width 0.1)
				(type default)
			)
			(layer "B.Fab")
		)
		(fp_line
			(start 0.12065 -0.2794)
			(end -0.12065 -0.2794)
			(stroke
				(width 0.1)
				(type default)
			)
			(layer "B.Fab")
		)
		(fp_line
			(start 0.12065 0.2794)
			(end 0.12065 0.3048)
			(stroke
				(width 0.1)
				(type default)
			)
			(layer "B.Fab")
		)
		(fp_line
			(start 0.12065 0.3048)
			(end 0.67945 0.3048)
			(stroke
				(width 0.1)
				(type default)
			)
			(layer "B.Fab")
		)
		(fp_line
			(start 0.67945 -0.305054)
			(end 0.12065 -0.305054)
			(stroke
				(width 0.1)
				(type default)
			)
			(layer "B.Fab")
		)
		(fp_line
			(start 0.67945 0.3048)
			(end 0.67945 -0.305054)
			(stroke
				(width 0.1)
				(type default)
			)
			(layer "B.Fab")
		)
		(pad "1" smd circle
			(at 0.40005 0 180)
			(size 0 0)
			(layers "B.Cu" "B.Mask" "B.Paste")
			(net "P1V2_AUX")
		)
		(pad "2" smd circle
			(at -0.40005 0 180)
			(size 0 0)
			(layers "B.Cu" "B.Mask" "B.Paste")
			(net "P1V2_AUX_ADC")
		)
	)
	(footprint ""
		(layer "B.Cu")
		(at 183.557164 -23.655782 -90)
		(property "Reference" "R3240"
			(at 0 0 90)
			(layer "B.SilkS")
			(hide yes)
			(effects
				(font
					(size 1.27 1.27)
				)
				(justify mirror)
			)
		)
		(property "Value" ""
			(at 0 0 90)
			(layer "B.Fab")
			(effects
				(font
					(size 1.27 1.27)
				)
				(justify mirror)
			)
		)
		(duplicate_pad_numbers_are_jumpers no)
		(fp_line
			(start -0.7874 0.4064)
			(end 0.7874 0.4064)
			(stroke
				(width 0.1524)
				(type default)
			)
			(layer "B.SilkS")
		)
		(fp_line
			(start 0.7874 0.4064)
			(end 0.7874 -0.4064)
			(stroke
				(width 0.1524)
				(type default)
			)
			(layer "B.SilkS")
		)
		(fp_line
			(start -0.7874 -0.4064)
			(end -0.7874 0.4064)
			(stroke
				(width 0.1524)
				(type default)
			)
			(layer "B.SilkS")
		)
		(fp_line
			(start 0.7874 -0.4064)
			(end -0.7874 -0.4064)
			(stroke
				(width 0.1524)
				(type default)
			)
			(layer "B.SilkS")
		)
		(fp_line
			(start -0.67945 0.3048)
			(end -0.120396 0.3048)
			(stroke
				(width 0.1)
				(type default)
			)
			(layer "B.Fab")
		)
		(fp_line
			(start -0.120396 0.3048)
			(end -0.120396 0.2794)
			(stroke
				(width 0.1)
				(type default)
			)
			(layer "B.Fab")
		)
		(fp_line
			(start 0.12065 0.3048)
			(end 0.67945 0.3048)
			(stroke
				(width 0.1)
				(type default)
			)
			(layer "B.Fab")
		)
		(fp_line
			(start 0.67945 0.3048)
			(end 0.67945 -0.305054)
			(stroke
				(width 0.1)
				(type default)
			)
			(layer "B.Fab")
		)
		(fp_line
			(start -0.120396 0.2794)
			(end 0.12065 0.2794)
			(stroke
				(width 0.1)
				(type default)
			)
			(layer "B.Fab")
		)
		(fp_line
			(start 0.12065 0.2794)
			(end 0.12065 0.3048)
			(stroke
				(width 0.1)
				(type default)
			)
			(layer "B.Fab")
		)
		(fp_line
			(start -0.12065 -0.2794)
			(end -0.12065 -0.3048)
			(stroke
				(width 0.1)
				(type default)
			)
			(layer "B.Fab")
		)
		(fp_line
			(start 0.12065 -0.2794)
			(end -0.12065 -0.2794)
			(stroke
				(width 0.1)
				(type default)
			)
			(layer "B.Fab")
		)
		(fp_line
			(start -0.67945 -0.3048)
			(end -0.67945 0.3048)
			(stroke
				(width 0.1)
				(type default)
			)
			(layer "B.Fab")
		)
		(fp_line
			(start -0.12065 -0.3048)
			(end -0.67945 -0.3048)
			(stroke
				(width 0.1)
				(type default)
			)
			(layer "B.Fab")
		)
		(fp_line
			(start 0.12065 -0.305054)
			(end 0.12065 -0.2794)
			(stroke
				(width 0.1)
				(type default)
			)
			(layer "B.Fab")
		)
		(fp_line
			(start 0.67945 -0.305054)
			(end 0.12065 -0.305054)
			(stroke
				(width 0.1)
				(type default)
			)
			(layer "B.Fab")
		)
		(pad "1" smd circle
			(at 0.40005 0 90)
			(size 0 0)
			(layers "B.Cu" "B.Mask" "B.Paste")
			(net "SMB_OCP_SFF_3V3AUX_SCL")
		)
		(pad "2" smd circle
			(at -0.40005 0 90)
			(size 0 0)
			(layers "B.Cu" "B.Mask" "B.Paste")
			(net "P3V3_AUX")
		)
	)
	(footprint ""
		(layer "B.Cu")
		(at 439.100214 -192.660016)
		(property "Reference" "C166"
			(at 0 0 0)
			(layer "B.SilkS")
			(hide yes)
			(effects
				(font
					(size 1.27 1.27)
				)
				(justify mirror)
			)
		)
		(property "Value" ""
			(at 0 0 0)
			(layer "B.Fab")
			(effects
				(font
					(size 1.27 1.27)
				)
				(justify mirror)
			)
		)
		(duplicate_pad_numbers_are_jumpers no)
		(fp_line
			(start -1.524 -0.762)
			(end -1.524 0.762)
			(stroke
				(width 0.1524)
				(type default)
			)
			(layer "B.SilkS")
		)
		(fp_line
			(start -1.524 0.762)
			(end 1.524 0.762)
			(stroke
				(width 0.1524)
				(type default)
			)
			(layer "B.SilkS")
		)
		(fp_line
			(start 1.524 -0.762)
			(end -1.524 -0.762)
			(stroke
				(width 0.1524)
				(type default)
			)
			(layer "B.SilkS")
		)
		(fp_line
			(start 1.524 0.762)
			(end 1.524 -0.762)
			(stroke
				(width 0.1524)
				(type default)
			)
			(layer "B.SilkS")
		)
		(fp_line
			(start -1.1049 -0.724916)
			(end 1.1049 -0.724916)
			(stroke
				(width 0.1)
				(type default)
			)
			(layer "B.Fab")
		)
		(fp_line
			(start -1.1049 0.724916)
			(end -1.1049 -0.724916)
			(stroke
				(width 0.1)
				(type default)
			)
			(layer "B.Fab")
		)
		(fp_line
			(start 1.1049 -0.724916)
			(end 1.1049 0.724916)
			(stroke
				(width 0.1)
				(type default)
			)
			(layer "B.Fab")
		)
		(fp_line
			(start 1.1049 0.724916)
			(end -1.1049 0.724916)
			(stroke
				(width 0.1)
				(type default)
			)
			(layer "B.Fab")
		)
		(pad "1" smd rect
			(at 0.889 0)
			(size 1.016 1.27)
			(layers "B.Cu" "B.Mask" "B.Paste")
			(net "P12V_MEM_CPU0")
		)
		(pad "2" smd rect
			(at -0.889 0)
			(size 1.016 1.27)
			(layers "B.Cu" "B.Mask" "B.Paste")
			(net "GND")
		)
	)
	(footprint ""
		(layer "B.Cu")
		(at 391.104628 -314.180474 90)
		(property "Reference" "R751"
			(at 0 0 90)
			(layer "B.SilkS")
			(hide yes)
			(effects
				(font
					(size 1.27 1.27)
				)
				(justify mirror)
			)
		)
		(property "Value" ""
			(at 0 0 90)
			(layer "B.Fab")
			(effects
				(font
					(size 1.27 1.27)
				)
				(justify mirror)
			)
		)
		(duplicate_pad_numbers_are_jumpers no)
		(fp_line
			(start 0.7874 -0.4064)
			(end -0.7874 -0.4064)
			(stroke
				(width 0.1524)
				(type default)
			)
			(layer "B.SilkS")
		)
		(fp_line
			(start -0.7874 -0.4064)
			(end -0.7874 0.4064)
			(stroke
				(width 0.1524)
				(type default)
			)
			(layer "B.SilkS")
		)
		(fp_line
			(start 0.7874 0.4064)
			(end 0.7874 -0.4064)
			(stroke
				(width 0.1524)
				(type default)
			)
			(layer "B.SilkS")
		)
		(fp_line
			(start -0.7874 0.4064)
			(end 0.7874 0.4064)
			(stroke
				(width 0.1524)
				(type default)
			)
			(layer "B.SilkS")
		)
		(fp_line
			(start 0.67945 -0.305054)
			(end 0.12065 -0.305054)
			(stroke
				(width 0.1)
				(type default)
			)
			(layer "B.Fab")
		)
		(fp_line
			(start 0.12065 -0.305054)
			(end 0.12065 -0.2794)
			(stroke
				(width 0.1)
				(type default)
			)
			(layer "B.Fab")
		)
		(fp_line
			(start -0.12065 -0.3048)
			(end -0.67945 -0.3048)
			(stroke
				(width 0.1)
				(type default)
			)
			(layer "B.Fab")
		)
		(fp_line
			(start -0.67945 -0.3048)
			(end -0.67945 0.3048)
			(stroke
				(width 0.1)
				(type default)
			)
			(layer "B.Fab")
		)
		(fp_line
			(start 0.12065 -0.2794)
			(end -0.12065 -0.2794)
			(stroke
				(width 0.1)
				(type default)
			)
			(layer "B.Fab")
		)
		(fp_line
			(start -0.12065 -0.2794)
			(end -0.12065 -0.3048)
			(stroke
				(width 0.1)
				(type default)
			)
			(layer "B.Fab")
		)
		(fp_line
			(start 0.12065 0.2794)
			(end 0.12065 0.3048)
			(stroke
				(width 0.1)
				(type default)
			)
			(layer "B.Fab")
		)
		(fp_line
			(start -0.120396 0.2794)
			(end 0.12065 0.2794)
			(stroke
				(width 0.1)
				(type default)
			)
			(layer "B.Fab")
		)
		(fp_line
			(start 0.67945 0.3048)
			(end 0.67945 -0.305054)
			(stroke
				(width 0.1)
				(type default)
			)
			(layer "B.Fab")
		)
		(fp_line
			(start 0.12065 0.3048)
			(end 0.67945 0.3048)
			(stroke
				(width 0.1)
				(type default)
			)
			(layer "B.Fab")
		)
		(fp_line
			(start -0.120396 0.3048)
			(end -0.120396 0.2794)
			(stroke
				(width 0.1)
				(type default)
			)
			(layer "B.Fab")
		)
		(fp_line
			(start -0.67945 0.3048)
			(end -0.120396 0.3048)
			(stroke
				(width 0.1)
				(type default)
			)
			(layer "B.Fab")
		)
		(pad "1" smd circle
			(at 0.40005 0 270)
			(size 0 0)
			(layers "B.Cu" "B.Mask" "B.Paste")
			(net "GND")
		)
		(pad "2" smd circle
			(at -0.40005 0 270)
			(size 0 0)
			(layers "B.Cu" "B.Mask" "B.Paste")
			(net "CLK_CPU0_RTCCLK")
		)
	)
	(footprint ""
		(layer "B.Cu")
		(at 106.901996 -26.952448 90)
		(property "Reference" "C6101"
			(at 0 0 90)
			(layer "B.SilkS")
			(hide yes)
			(effects
				(font
					(size 1.27 1.27)
				)
				(justify mirror)
			)
		)
		(property "Value" ""
			(at 0 0 90)
			(layer "B.Fab")
			(effects
				(font
					(size 1.27 1.27)
				)
				(justify mirror)
			)
		)
		(duplicate_pad_numbers_are_jumpers no)
		(fp_line
			(start 0.7874 -0.4064)
			(end -0.7874 -0.4064)
			(stroke
				(width 0.1524)
				(type default)
			)
			(layer "B.SilkS")
		)
		(fp_line
			(start -0.7874 -0.4064)
			(end -0.7874 0.4064)
			(stroke
				(width 0.1524)
				(type default)
			)
			(layer "B.SilkS")
		)
		(fp_line
			(start 0.7874 0.4064)
			(end 0.7874 -0.4064)
			(stroke
				(width 0.1524)
				(type default)
			)
			(layer "B.SilkS")
		)
		(fp_line
			(start -0.7874 0.4064)
			(end 0.7874 0.4064)
			(stroke
				(width 0.1524)
				(type default)
			)
			(layer "B.SilkS")
		)
		(fp_line
			(start 0.67945 -0.305054)
			(end 0.12065 -0.305054)
			(stroke
				(width 0.1)
				(type default)
			)
			(layer "B.Fab")
		)
		(fp_line
			(start 0.12065 -0.305054)
			(end 0.12065 -0.2794)
			(stroke
				(width 0.1)
				(type default)
			)
			(layer "B.Fab")
		)
		(fp_line
			(start -0.12065 -0.3048)
			(end -0.67945 -0.3048)
			(stroke
				(width 0.1)
				(type default)
			)
			(layer "B.Fab")
		)
		(fp_line
			(start -0.67945 -0.3048)
			(end -0.67945 0.3048)
			(stroke
				(width 0.1)
				(type default)
			)
			(layer "B.Fab")
		)
		(fp_line
			(start 0.12065 -0.2794)
			(end -0.12065 -0.2794)
			(stroke
				(width 0.1)
				(type default)
			)
			(layer "B.Fab")
		)
		(fp_line
			(start -0.12065 -0.2794)
			(end -0.12065 -0.3048)
			(stroke
				(width 0.1)
				(type default)
			)
			(layer "B.Fab")
		)
		(fp_line
			(start 0.12065 0.2794)
			(end 0.12065 0.3048)
			(stroke
				(width 0.1)
				(type default)
			)
			(layer "B.Fab")
		)
		(fp_line
			(start -0.120396 0.2794)
			(end 0.12065 0.2794)
			(stroke
				(width 0.1)
				(type default)
			)
			(layer "B.Fab")
		)
		(fp_line
			(start 0.67945 0.3048)
			(end 0.67945 -0.305054)
			(stroke
				(width 0.1)
				(type default)
			)
			(layer "B.Fab")
		)
		(fp_line
			(start 0.12065 0.3048)
			(end 0.67945 0.3048)
			(stroke
				(width 0.1)
				(type default)
			)
			(layer "B.Fab")
		)
		(fp_line
			(start -0.120396 0.3048)
			(end -0.120396 0.2794)
			(stroke
				(width 0.1)
				(type default)
			)
			(layer "B.Fab")
		)
		(fp_line
			(start -0.67945 0.3048)
			(end -0.120396 0.3048)
			(stroke
				(width 0.1)
				(type default)
			)
			(layer "B.Fab")
		)
		(pad "1" smd circle
			(at 0.40005 0 270)
			(size 0 0)
			(layers "B.Cu" "B.Mask" "B.Paste")
			(net "P3V3_AUX_CPU0_USB2_AVDD33")
		)
		(pad "2" smd circle
			(at -0.40005 0 270)
			(size 0 0)
			(layers "B.Cu" "B.Mask" "B.Paste")
			(net "GND")
		)
	)
	(footprint ""
		(layer "B.Cu")
		(at 226.366578 -289.828732)
		(property "Reference" "C109"
			(at 0 0 0)
			(layer "B.SilkS")
			(hide yes)
			(effects
				(font
					(size 1.27 1.27)
				)
				(justify mirror)
			)
		)
		(property "Value" ""
			(at 0 0 0)
			(layer "B.Fab")
			(effects
				(font
					(size 1.27 1.27)
				)
				(justify mirror)
			)
		)
		(duplicate_pad_numbers_are_jumpers no)
		(fp_line
			(start -0.7874 -0.4064)
			(end -0.7874 0.4064)
			(stroke
				(width 0.1524)
				(type default)
			)
			(layer "B.SilkS")
		)
		(fp_line
			(start -0.7874 0.4064)
			(end 0.7874 0.4064)
			(stroke
				(width 0.1524)
				(type default)
			)
			(layer "B.SilkS")
		)
		(fp_line
			(start 0.7874 -0.4064)
			(end -0.7874 -0.4064)
			(stroke
				(width 0.1524)
				(type default)
			)
			(layer "B.SilkS")
		)
		(fp_line
			(start 0.7874 0.4064)
			(end 0.7874 -0.4064)
			(stroke
				(width 0.1524)
				(type default)
			)
			(layer "B.SilkS")
		)
		(fp_line
			(start -0.67945 -0.3048)
			(end -0.67945 0.3048)
			(stroke
				(width 0.1)
				(type default)
			)
			(layer "B.Fab")
		)
		(fp_line
			(start -0.67945 0.3048)
			(end -0.120396 0.3048)
			(stroke
				(width 0.1)
				(type default)
			)
			(layer "B.Fab")
		)
		(fp_line
			(start -0.12065 -0.3048)
			(end -0.67945 -0.3048)
			(stroke
				(width 0.1)
				(type default)
			)
			(layer "B.Fab")
		)
		(fp_line
			(start -0.12065 -0.2794)
			(end -0.12065 -0.3048)
			(stroke
				(width 0.1)
				(type default)
			)
			(layer "B.Fab")
		)
		(fp_line
			(start -0.120396 0.2794)
			(end 0.12065 0.2794)
			(stroke
				(width 0.1)
				(type default)
			)
			(layer "B.Fab")
		)
		(fp_line
			(start -0.120396 0.3048)
			(end -0.120396 0.2794)
			(stroke
				(width 0.1)
				(type default)
			)
			(layer "B.Fab")
		)
		(fp_line
			(start 0.12065 -0.305054)
			(end 0.12065 -0.2794)
			(stroke
				(width 0.1)
				(type default)
			)
			(layer "B.Fab")
		)
		(fp_line
			(start 0.12065 -0.2794)
			(end -0.12065 -0.2794)
			(stroke
				(width 0.1)
				(type default)
			)
			(layer "B.Fab")
		)
		(fp_line
			(start 0.12065 0.2794)
			(end 0.12065 0.3048)
			(stroke
				(width 0.1)
				(type default)
			)
			(layer "B.Fab")
		)
		(fp_line
			(start 0.12065 0.3048)
			(end 0.67945 0.3048)
			(stroke
				(width 0.1)
				(type default)
			)
			(layer "B.Fab")
		)
		(fp_line
			(start 0.67945 -0.305054)
			(end 0.12065 -0.305054)
			(stroke
				(width 0.1)
				(type default)
			)
			(layer "B.Fab")
		)
		(fp_line
			(start 0.67945 0.3048)
			(end 0.67945 -0.305054)
			(stroke
				(width 0.1)
				(type default)
			)
			(layer "B.Fab")
		)
		(pad "1" smd circle
			(at 0.40005 0 180)
			(size 0 0)
			(layers "B.Cu" "B.Mask" "B.Paste")
			(net "FM_PWRGD_P1V8_RETIMER_CPU1")
		)
		(pad "2" smd circle
			(at -0.40005 0 180)
			(size 0 0)
			(layers "B.Cu" "B.Mask" "B.Paste")
			(net "GND")
		)
	)
	(footprint ""
		(layer "B.Cu")
		(at 161.595562 -381.11303)
		(property "Reference" "C7026"
			(at 2.78384 3.128772 0)
			(unlocked yes)
			(layer "B.SilkS")
			(effects
				(font
					(size 0.7874 0.5842)
					(thickness 0.1524)
				)
				(justify left mirror)
			)
		)
		(property "Value" ""
			(at 0 0 0)
			(layer "B.Fab")
			(effects
				(font
					(size 1.27 1.27)
				)
				(justify mirror)
			)
		)
		(duplicate_pad_numbers_are_jumpers no)
		(fp_line
			(start -4.53898 -2.15011)
			(end -4.53898 2.15011)
			(stroke
				(width 0.1524)
				(type default)
			)
			(layer "B.SilkS")
		)
		(fp_line
			(start -4.53898 2.15011)
			(end 4.53898 2.15011)
			(stroke
				(width 0.1524)
				(type default)
			)
			(layer "B.SilkS")
		)
		(fp_line
			(start 4.53898 -2.150618)
			(end 4.539742 2.152142)
			(stroke
				(width 0.1524)
				(type default)
			)
			(layer "B.SilkS")
		)
		(fp_line
			(start 4.53898 -2.15011)
			(end -4.53898 -2.15011)
			(stroke
				(width 0.1524)
				(type default)
			)
			(layer "B.SilkS")
		)
		(fp_line
			(start 4.53898 2.15011)
			(end 4.53898 -2.15011)
			(stroke
				(width 0.1524)
				(type default)
			)
			(layer "B.SilkS")
		)
		(fp_line
			(start 4.69138 -2.150618)
			(end 4.692396 2.161032)
			(stroke
				(width 0.1524)
				(type default)
			)
			(layer "B.SilkS")
		)
		(fp_line
			(start 4.83108 2.150364)
			(end 4.447794 2.149348)
			(stroke
				(width 0.1524)
				(type default)
			)
			(layer "B.SilkS")
		)
		(fp_line
			(start 4.84378 -2.150618)
			(end 4.53898 -2.150618)
			(stroke
				(width 0.1524)
				(type default)
			)
			(layer "B.SilkS")
		)
		(fp_line
			(start 4.84378 -2.150618)
			(end 4.842256 2.163064)
			(stroke
				(width 0.1524)
				(type default)
			)
			(layer "B.SilkS")
		)
		(fp_line
			(start -3.64998 -2.15011)
			(end -3.64998 2.15011)
			(stroke
				(width 0.1)
				(type default)
			)
			(layer "B.Fab")
		)
		(fp_line
			(start -3.64998 2.15011)
			(end 3.64998 2.15011)
			(stroke
				(width 0.1)
				(type default)
			)
			(layer "B.Fab")
		)
		(fp_line
			(start 3.64998 -2.15011)
			(end -3.64998 -2.15011)
			(stroke
				(width 0.1)
				(type default)
			)
			(layer "B.Fab")
		)
		(fp_line
			(start 3.64998 2.15011)
			(end 3.64998 -2.15011)
			(stroke
				(width 0.1)
				(type default)
			)
			(layer "B.Fab")
		)
		(fp_text user "-"
			(at -2.568194 2.356612 0)
			(unlocked yes)
			(layer "B.SilkS")
			(effects
				(font
					(size 1.905 1.4224)
					(thickness 0.1524)
				)
				(justify left mirror)
			)
		)
		(fp_text user "+"
			(at 6.214872 -0.337058 0)
			(unlocked yes)
			(layer "B.SilkS")
			(effects
				(font
					(size 1.905 1.4224)
					(thickness 0.1524)
				)
				(justify left mirror)
			)
		)
		(fp_text user "-"
			(at -4.313174 -0.094488 0)
			(unlocked yes)
			(layer "B.Fab")
			(effects
				(font
					(size 1.905 1.4224)
					(thickness 0.1524)
				)
				(justify left mirror)
			)
		)
		(fp_text user "+"
			(at 6.214872 -0.337058 0)
			(unlocked yes)
			(layer "B.Fab")
			(effects
				(font
					(size 1.905 1.4224)
					(thickness 0.1524)
				)
				(justify left mirror)
			)
		)
		(pad "1" smd rect
			(at 3.199892 0 180)
			(size 2.413 2.8194)
			(layers "B.Cu" "B.Mask" "B.Paste")
			(net "P0V9_CPU1_RT2_2A")
		)
		(pad "2" smd rect
			(at -3.199892 0 180)
			(size 2.413 2.8194)
			(layers "B.Cu" "B.Mask" "B.Paste")
			(net "GND")
		)
	)
	(footprint ""
		(layer "B.Cu")
		(at 91.271852 -304.325274)
		(property "Reference" "R518"
			(at 0 0 0)
			(layer "B.SilkS")
			(hide yes)
			(effects
				(font
					(size 1.27 1.27)
				)
				(justify mirror)
			)
		)
		(property "Value" ""
			(at 0 0 0)
			(layer "B.Fab")
			(effects
				(font
					(size 1.27 1.27)
				)
				(justify mirror)
			)
		)
		(duplicate_pad_numbers_are_jumpers no)
		(fp_line
			(start -0.7874 -0.4064)
			(end -0.7874 0.4064)
			(stroke
				(width 0.1524)
				(type default)
			)
			(layer "B.SilkS")
		)
		(fp_line
			(start -0.7874 0.4064)
			(end 0.7874 0.4064)
			(stroke
				(width 0.1524)
				(type default)
			)
			(layer "B.SilkS")
		)
		(fp_line
			(start 0.7874 -0.4064)
			(end -0.7874 -0.4064)
			(stroke
				(width 0.1524)
				(type default)
			)
			(layer "B.SilkS")
		)
		(fp_line
			(start 0.7874 0.4064)
			(end 0.7874 -0.4064)
			(stroke
				(width 0.1524)
				(type default)
			)
			(layer "B.SilkS")
		)
		(fp_line
			(start -0.67945 -0.3048)
			(end -0.67945 0.3048)
			(stroke
				(width 0.1)
				(type default)
			)
			(layer "B.Fab")
		)
		(fp_line
			(start -0.67945 0.3048)
			(end -0.120396 0.3048)
			(stroke
				(width 0.1)
				(type default)
			)
			(layer "B.Fab")
		)
		(fp_line
			(start -0.12065 -0.3048)
			(end -0.67945 -0.3048)
			(stroke
				(width 0.1)
				(type default)
			)
			(layer "B.Fab")
		)
		(fp_line
			(start -0.12065 -0.2794)
			(end -0.12065 -0.3048)
			(stroke
				(width 0.1)
				(type default)
			)
			(layer "B.Fab")
		)
		(fp_line
			(start -0.120396 0.2794)
			(end 0.12065 0.2794)
			(stroke
				(width 0.1)
				(type default)
			)
			(layer "B.Fab")
		)
		(fp_line
			(start -0.120396 0.3048)
			(end -0.120396 0.2794)
			(stroke
				(width 0.1)
				(type default)
			)
			(layer "B.Fab")
		)
		(fp_line
			(start 0.12065 -0.305054)
			(end 0.12065 -0.2794)
			(stroke
				(width 0.1)
				(type default)
			)
			(layer "B.Fab")
		)
		(fp_line
			(start 0.12065 -0.2794)
			(end -0.12065 -0.2794)
			(stroke
				(width 0.1)
				(type default)
			)
			(layer "B.Fab")
		)
		(fp_line
			(start 0.12065 0.2794)
			(end 0.12065 0.3048)
			(stroke
				(width 0.1)
				(type default)
			)
			(layer "B.Fab")
		)
		(fp_line
			(start 0.12065 0.3048)
			(end 0.67945 0.3048)
			(stroke
				(width 0.1)
				(type default)
			)
			(layer "B.Fab")
		)
		(fp_line
			(start 0.67945 -0.305054)
			(end 0.12065 -0.305054)
			(stroke
				(width 0.1)
				(type default)
			)
			(layer "B.Fab")
		)
		(fp_line
			(start 0.67945 0.3048)
			(end 0.67945 -0.305054)
			(stroke
				(width 0.1)
				(type default)
			)
			(layer "B.Fab")
		)
		(pad "1" smd circle
			(at 0.40005 0 180)
			(size 0 0)
			(layers "B.Cu" "B.Mask" "B.Paste")
			(net "PVDD18_S5_P1")
		)
		(pad "2" smd circle
			(at -0.40005 0 180)
			(size 0 0)
			(layers "B.Cu" "B.Mask" "B.Paste")
			(net "CPU1_SA0")
		)
	)
	(footprint ""
		(layer "B.Cu")
		(at 60.679076 -338.086954 -90)
		(property "Reference" "PC417_3"
			(at 0 0 90)
			(layer "B.SilkS")
			(hide yes)
			(effects
				(font
					(size 1.27 1.27)
				)
				(justify mirror)
			)
		)
		(property "Value" ""
			(at 0 0 90)
			(layer "B.Fab")
			(effects
				(font
					(size 1.27 1.27)
				)
				(justify mirror)
			)
		)
		(duplicate_pad_numbers_are_jumpers no)
		(fp_line
			(start -1.524 0.762)
			(end 1.524 0.762)
			(stroke
				(width 0.1524)
				(type default)
			)
			(layer "B.SilkS")
		)
		(fp_line
			(start 1.524 0.762)
			(end 1.524 -0.762)
			(stroke
				(width 0.1524)
				(type default)
			)
			(layer "B.SilkS")
		)
		(fp_line
			(start -1.524 -0.762)
			(end -1.524 0.762)
			(stroke
				(width 0.1524)
				(type default)
			)
			(layer "B.SilkS")
		)
		(fp_line
			(start 1.524 -0.762)
			(end -1.524 -0.762)
			(stroke
				(width 0.1524)
				(type default)
			)
			(layer "B.SilkS")
		)
		(fp_line
			(start -1.1049 0.724916)
			(end -1.1049 -0.724916)
			(stroke
				(width 0.1)
				(type default)
			)
			(layer "B.Fab")
		)
		(fp_line
			(start 1.1049 0.724916)
			(end -1.1049 0.724916)
			(stroke
				(width 0.1)
				(type default)
			)
			(layer "B.Fab")
		)
		(fp_line
			(start -1.1049 -0.724916)
			(end 1.1049 -0.724916)
			(stroke
				(width 0.1)
				(type default)
			)
			(layer "B.Fab")
		)
		(fp_line
			(start 1.1049 -0.724916)
			(end 1.1049 0.724916)
			(stroke
				(width 0.1)
				(type default)
			)
			(layer "B.Fab")
		)
		(pad "1" smd rect
			(at 0.889 0 270)
			(size 1.016 1.27)
			(layers "B.Cu" "B.Mask" "B.Paste")
			(net "PVDDCR_CPU1_P1")
		)
		(pad "2" smd rect
			(at -0.889 0 270)
			(size 1.016 1.27)
			(layers "B.Cu" "B.Mask" "B.Paste")
			(net "GND")
		)
	)
	(footprint ""
		(layer "B.Cu")
		(at 96.575118 -335.09712 90)
		(property "Reference" "PC427_5"
			(at 0 0 90)
			(layer "B.SilkS")
			(hide yes)
			(effects
				(font
					(size 1.27 1.27)
				)
				(justify mirror)
			)
		)
		(property "Value" ""
			(at 0 0 90)
			(layer "B.Fab")
			(effects
				(font
					(size 1.27 1.27)
				)
				(justify mirror)
			)
		)
		(duplicate_pad_numbers_are_jumpers no)
		(fp_line
			(start 1.524 -0.762)
			(end -1.524 -0.762)
			(stroke
				(width 0.1524)
				(type default)
			)
			(layer "B.SilkS")
		)
		(fp_line
			(start -1.524 -0.762)
			(end -1.524 0.762)
			(stroke
				(width 0.1524)
				(type default)
			)
			(layer "B.SilkS")
		)
		(fp_line
			(start 1.524 0.762)
			(end 1.524 -0.762)
			(stroke
				(width 0.1524)
				(type default)
			)
			(layer "B.SilkS")
		)
		(fp_line
			(start -1.524 0.762)
			(end 1.524 0.762)
			(stroke
				(width 0.1524)
				(type default)
			)
			(layer "B.SilkS")
		)
		(fp_line
			(start 1.1049 -0.724916)
			(end 1.1049 0.724916)
			(stroke
				(width 0.1)
				(type default)
			)
			(layer "B.Fab")
		)
		(fp_line
			(start -1.1049 -0.724916)
			(end 1.1049 -0.724916)
			(stroke
				(width 0.1)
				(type default)
			)
			(layer "B.Fab")
		)
		(fp_line
			(start 1.1049 0.724916)
			(end -1.1049 0.724916)
			(stroke
				(width 0.1)
				(type default)
			)
			(layer "B.Fab")
		)
		(fp_line
			(start -1.1049 0.724916)
			(end -1.1049 -0.724916)
			(stroke
				(width 0.1)
				(type default)
			)
			(layer "B.Fab")
		)
		(pad "1" smd rect
			(at 0.889 0 90)
			(size 1.016 1.27)
			(layers "B.Cu" "B.Mask" "B.Paste")
			(net "SW_P12V_AUX_PVDDCR_CPU1_P1_FLT")
		)
		(pad "2" smd rect
			(at -0.889 0 90)
			(size 1.016 1.27)
			(layers "B.Cu" "B.Mask" "B.Paste")
			(net "GND")
		)
	)
	(footprint ""
		(layer "B.Cu")
		(at 353.231958 -245.487952)
		(property "Reference" "C245"
			(at 0 0 0)
			(layer "B.SilkS")
			(hide yes)
			(effects
				(font
					(size 1.27 1.27)
				)
				(justify mirror)
			)
		)
		(property "Value" ""
			(at 0 0 0)
			(layer "B.Fab")
			(effects
				(font
					(size 1.27 1.27)
				)
				(justify mirror)
			)
		)
		(duplicate_pad_numbers_are_jumpers no)
		(fp_line
			(start -0.7874 -0.4064)
			(end -0.7874 0.4064)
			(stroke
				(width 0.1524)
				(type default)
			)
			(layer "B.SilkS")
		)
		(fp_line
			(start -0.7874 0.4064)
			(end 0.7874 0.4064)
			(stroke
				(width 0.1524)
				(type default)
			)
			(layer "B.SilkS")
		)
		(fp_line
			(start 0.7874 -0.4064)
			(end -0.7874 -0.4064)
			(stroke
				(width 0.1524)
				(type default)
			)
			(layer "B.SilkS")
		)
		(fp_line
			(start 0.7874 0.4064)
			(end 0.7874 -0.4064)
			(stroke
				(width 0.1524)
				(type default)
			)
			(layer "B.SilkS")
		)
		(fp_line
			(start -0.67945 -0.3048)
			(end -0.67945 0.3048)
			(stroke
				(width 0.1)
				(type default)
			)
			(layer "B.Fab")
		)
		(fp_line
			(start -0.67945 0.3048)
			(end -0.120396 0.3048)
			(stroke
				(width 0.1)
				(type default)
			)
			(layer "B.Fab")
		)
		(fp_line
			(start -0.12065 -0.3048)
			(end -0.67945 -0.3048)
			(stroke
				(width 0.1)
				(type default)
			)
			(layer "B.Fab")
		)
		(fp_line
			(start -0.12065 -0.2794)
			(end -0.12065 -0.3048)
			(stroke
				(width 0.1)
				(type default)
			)
			(layer "B.Fab")
		)
		(fp_line
			(start -0.120396 0.2794)
			(end 0.12065 0.2794)
			(stroke
				(width 0.1)
				(type default)
			)
			(layer "B.Fab")
		)
		(fp_line
			(start -0.120396 0.3048)
			(end -0.120396 0.2794)
			(stroke
				(width 0.1)
				(type default)
			)
			(layer "B.Fab")
		)
		(fp_line
			(start 0.12065 -0.305054)
			(end 0.12065 -0.2794)
			(stroke
				(width 0.1)
				(type default)
			)
			(layer "B.Fab")
		)
		(fp_line
			(start 0.12065 -0.2794)
			(end -0.12065 -0.2794)
			(stroke
				(width 0.1)
				(type default)
			)
			(layer "B.Fab")
		)
		(fp_line
			(start 0.12065 0.2794)
			(end 0.12065 0.3048)
			(stroke
				(width 0.1)
				(type default)
			)
			(layer "B.Fab")
		)
		(fp_line
			(start 0.12065 0.3048)
			(end 0.67945 0.3048)
			(stroke
				(width 0.1)
				(type default)
			)
			(layer "B.Fab")
		)
		(fp_line
			(start 0.67945 -0.305054)
			(end 0.12065 -0.305054)
			(stroke
				(width 0.1)
				(type default)
			)
			(layer "B.Fab")
		)
		(fp_line
			(start 0.67945 0.3048)
			(end 0.67945 -0.305054)
			(stroke
				(width 0.1)
				(type default)
			)
			(layer "B.Fab")
		)
		(pad "1" smd circle
			(at 0.40005 0 180)
			(size 0 0)
			(layers "B.Cu" "B.Mask" "B.Paste")
			(net "PVDDCR_CPU0_P0")
		)
		(pad "2" smd circle
			(at -0.40005 0 180)
			(size 0 0)
			(layers "B.Cu" "B.Mask" "B.Paste")
			(net "GND")
		)
	)
	(footprint ""
		(layer "B.Cu")
		(at 321.391026 -398.942052 90)
		(property "Reference" "C567"
			(at 0 0 90)
			(layer "B.SilkS")
			(hide yes)
			(effects
				(font
					(size 1.27 1.27)
				)
				(justify mirror)
			)
		)
		(property "Value" ""
			(at 0 0 90)
			(layer "B.Fab")
			(effects
				(font
					(size 1.27 1.27)
				)
				(justify mirror)
			)
		)
		(duplicate_pad_numbers_are_jumpers no)
		(fp_line
			(start 0.7874 -0.4064)
			(end -0.7874 -0.4064)
			(stroke
				(width 0.1524)
				(type default)
			)
			(layer "B.SilkS")
		)
		(fp_line
			(start -0.7874 -0.4064)
			(end -0.7874 0.4064)
			(stroke
				(width 0.1524)
				(type default)
			)
			(layer "B.SilkS")
		)
		(fp_line
			(start 0.7874 0.4064)
			(end 0.7874 -0.4064)
			(stroke
				(width 0.1524)
				(type default)
			)
			(layer "B.SilkS")
		)
		(fp_line
			(start -0.7874 0.4064)
			(end 0.7874 0.4064)
			(stroke
				(width 0.1524)
				(type default)
			)
			(layer "B.SilkS")
		)
		(fp_line
			(start 0.67945 -0.305054)
			(end 0.12065 -0.305054)
			(stroke
				(width 0.1)
				(type default)
			)
			(layer "B.Fab")
		)
		(fp_line
			(start 0.12065 -0.305054)
			(end 0.12065 -0.2794)
			(stroke
				(width 0.1)
				(type default)
			)
			(layer "B.Fab")
		)
		(fp_line
			(start -0.12065 -0.3048)
			(end -0.67945 -0.3048)
			(stroke
				(width 0.1)
				(type default)
			)
			(layer "B.Fab")
		)
		(fp_line
			(start -0.67945 -0.3048)
			(end -0.67945 0.3048)
			(stroke
				(width 0.1)
				(type default)
			)
			(layer "B.Fab")
		)
		(fp_line
			(start 0.12065 -0.2794)
			(end -0.12065 -0.2794)
			(stroke
				(width 0.1)
				(type default)
			)
			(layer "B.Fab")
		)
		(fp_line
			(start -0.12065 -0.2794)
			(end -0.12065 -0.3048)
			(stroke
				(width 0.1)
				(type default)
			)
			(layer "B.Fab")
		)
		(fp_line
			(start 0.12065 0.2794)
			(end 0.12065 0.3048)
			(stroke
				(width 0.1)
				(type default)
			)
			(layer "B.Fab")
		)
		(fp_line
			(start -0.120396 0.2794)
			(end 0.12065 0.2794)
			(stroke
				(width 0.1)
				(type default)
			)
			(layer "B.Fab")
		)
		(fp_line
			(start 0.67945 0.3048)
			(end 0.67945 -0.305054)
			(stroke
				(width 0.1)
				(type default)
			)
			(layer "B.Fab")
		)
		(fp_line
			(start 0.12065 0.3048)
			(end 0.67945 0.3048)
			(stroke
				(width 0.1)
				(type default)
			)
			(layer "B.Fab")
		)
		(fp_line
			(start -0.120396 0.3048)
			(end -0.120396 0.2794)
			(stroke
				(width 0.1)
				(type default)
			)
			(layer "B.Fab")
		)
		(fp_line
			(start -0.67945 0.3048)
			(end -0.120396 0.3048)
			(stroke
				(width 0.1)
				(type default)
			)
			(layer "B.Fab")
		)
		(pad "1" smd circle
			(at 0.40005 0 270)
			(size 0 0)
			(layers "B.Cu" "B.Mask" "B.Paste")
			(net "P0V9_CPU0_RT0_2A")
		)
		(pad "2" smd circle
			(at -0.40005 0 270)
			(size 0 0)
			(layers "B.Cu" "B.Mask" "B.Paste")
			(net "GND")
		)
	)
	(footprint ""
		(layer "B.Cu")
		(at 348.418912 -258.830064 180)
		(property "Reference" "C2632"
			(at 0 0 0)
			(layer "B.SilkS")
			(hide yes)
			(effects
				(font
					(size 1.27 1.27)
				)
				(justify mirror)
			)
		)
		(property "Value" ""
			(at 0 0 0)
			(layer "B.Fab")
			(effects
				(font
					(size 1.27 1.27)
				)
				(justify mirror)
			)
		)
		(duplicate_pad_numbers_are_jumpers no)
		(fp_line
			(start 0.7874 0.4064)
			(end 0.7874 -0.4064)
			(stroke
				(width 0.1524)
				(type default)
			)
			(layer "B.SilkS")
		)
		(fp_line
			(start 0.7874 -0.4064)
			(end -0.7874 -0.4064)
			(stroke
				(width 0.1524)
				(type default)
			)
			(layer "B.SilkS")
		)
		(fp_line
			(start -0.7874 0.4064)
			(end 0.7874 0.4064)
			(stroke
				(width 0.1524)
				(type default)
			)
			(layer "B.SilkS")
		)
		(fp_line
			(start -0.7874 -0.4064)
			(end -0.7874 0.4064)
			(stroke
				(width 0.1524)
				(type default)
			)
			(layer "B.SilkS")
		)
		(fp_line
			(start 0.67945 0.3048)
			(end 0.67945 -0.305054)
			(stroke
				(width 0.1)
				(type default)
			)
			(layer "B.Fab")
		)
		(fp_line
			(start 0.67945 -0.305054)
			(end 0.12065 -0.305054)
			(stroke
				(width 0.1)
				(type default)
			)
			(layer "B.Fab")
		)
		(fp_line
			(start 0.12065 0.3048)
			(end 0.67945 0.3048)
			(stroke
				(width 0.1)
				(type default)
			)
			(layer "B.Fab")
		)
		(fp_line
			(start 0.12065 0.2794)
			(end 0.12065 0.3048)
			(stroke
				(width 0.1)
				(type default)
			)
			(layer "B.Fab")
		)
		(fp_line
			(start 0.12065 -0.2794)
			(end -0.12065 -0.2794)
			(stroke
				(width 0.1)
				(type default)
			)
			(layer "B.Fab")
		)
		(fp_line
			(start 0.12065 -0.305054)
			(end 0.12065 -0.2794)
			(stroke
				(width 0.1)
				(type default)
			)
			(layer "B.Fab")
		)
		(fp_line
			(start -0.120396 0.3048)
			(end -0.120396 0.2794)
			(stroke
				(width 0.1)
				(type default)
			)
			(layer "B.Fab")
		)
		(fp_line
			(start -0.120396 0.2794)
			(end 0.12065 0.2794)
			(stroke
				(width 0.1)
				(type default)
			)
			(layer "B.Fab")
		)
		(fp_line
			(start -0.12065 -0.2794)
			(end -0.12065 -0.3048)
			(stroke
				(width 0.1)
				(type default)
			)
			(layer "B.Fab")
		)
		(fp_line
			(start -0.12065 -0.3048)
			(end -0.67945 -0.3048)
			(stroke
				(width 0.1)
				(type default)
			)
			(layer "B.Fab")
		)
		(fp_line
			(start -0.67945 0.3048)
			(end -0.120396 0.3048)
			(stroke
				(width 0.1)
				(type default)
			)
			(layer "B.Fab")
		)
		(fp_line
			(start -0.67945 -0.3048)
			(end -0.67945 0.3048)
			(stroke
				(width 0.1)
				(type default)
			)
			(layer "B.Fab")
		)
		(pad "1" smd circle
			(at 0.40005 0)
			(size 0 0)
			(layers "B.Cu" "B.Mask" "B.Paste")
			(net "PVDDIO_P0")
		)
		(pad "2" smd circle
			(at -0.40005 0)
			(size 0 0)
			(layers "B.Cu" "B.Mask" "B.Paste")
			(net "GND")
		)
	)
	(footprint ""
		(layer "B.Cu")
		(at 189.993778 -126.93396 -90)
		(property "Reference" "R6824"
			(at 0 0 90)
			(layer "B.SilkS")
			(hide yes)
			(effects
				(font
					(size 1.27 1.27)
				)
				(justify mirror)
			)
		)
		(property "Value" ""
			(at 0 0 90)
			(layer "B.Fab")
			(effects
				(font
					(size 1.27 1.27)
				)
				(justify mirror)
			)
		)
		(duplicate_pad_numbers_are_jumpers no)
		(fp_line
			(start -0.7874 0.4064)
			(end 0.7874 0.4064)
			(stroke
				(width 0.1524)
				(type default)
			)
			(layer "B.SilkS")
		)
		(fp_line
			(start 0.7874 0.4064)
			(end 0.7874 -0.4064)
			(stroke
				(width 0.1524)
				(type default)
			)
			(layer "B.SilkS")
		)
		(fp_line
			(start -0.7874 -0.4064)
			(end -0.7874 0.4064)
			(stroke
				(width 0.1524)
				(type default)
			)
			(layer "B.SilkS")
		)
		(fp_line
			(start 0.7874 -0.4064)
			(end -0.7874 -0.4064)
			(stroke
				(width 0.1524)
				(type default)
			)
			(layer "B.SilkS")
		)
		(fp_line
			(start -0.67945 0.3048)
			(end -0.120396 0.3048)
			(stroke
				(width 0.1)
				(type default)
			)
			(layer "B.Fab")
		)
		(fp_line
			(start -0.120396 0.3048)
			(end -0.120396 0.2794)
			(stroke
				(width 0.1)
				(type default)
			)
			(layer "B.Fab")
		)
		(fp_line
			(start 0.12065 0.3048)
			(end 0.67945 0.3048)
			(stroke
				(width 0.1)
				(type default)
			)
			(layer "B.Fab")
		)
		(fp_line
			(start 0.67945 0.3048)
			(end 0.67945 -0.305054)
			(stroke
				(width 0.1)
				(type default)
			)
			(layer "B.Fab")
		)
		(fp_line
			(start -0.120396 0.2794)
			(end 0.12065 0.2794)
			(stroke
				(width 0.1)
				(type default)
			)
			(layer "B.Fab")
		)
		(fp_line
			(start 0.12065 0.2794)
			(end 0.12065 0.3048)
			(stroke
				(width 0.1)
				(type default)
			)
			(layer "B.Fab")
		)
		(fp_line
			(start -0.12065 -0.2794)
			(end -0.12065 -0.3048)
			(stroke
				(width 0.1)
				(type default)
			)
			(layer "B.Fab")
		)
		(fp_line
			(start 0.12065 -0.2794)
			(end -0.12065 -0.2794)
			(stroke
				(width 0.1)
				(type default)
			)
			(layer "B.Fab")
		)
		(fp_line
			(start -0.67945 -0.3048)
			(end -0.67945 0.3048)
			(stroke
				(width 0.1)
				(type default)
			)
			(layer "B.Fab")
		)
		(fp_line
			(start -0.12065 -0.3048)
			(end -0.67945 -0.3048)
			(stroke
				(width 0.1)
				(type default)
			)
			(layer "B.Fab")
		)
		(fp_line
			(start 0.12065 -0.305054)
			(end 0.12065 -0.2794)
			(stroke
				(width 0.1)
				(type default)
			)
			(layer "B.Fab")
		)
		(fp_line
			(start 0.67945 -0.305054)
			(end 0.12065 -0.305054)
			(stroke
				(width 0.1)
				(type default)
			)
			(layer "B.Fab")
		)
		(pad "1" smd circle
			(at 0.40005 0 90)
			(size 0 0)
			(layers "B.Cu" "B.Mask" "B.Paste")
			(net "RST_RT_CPU0_P2_RESET_R2_N")
		)
		(pad "2" smd circle
			(at -0.40005 0 90)
			(size 0 0)
			(layers "B.Cu" "B.Mask" "B.Paste")
			(net "RST_RT_CPU0_P2_RESET_R_N")
		)
	)
	(footprint ""
		(layer "B.Cu")
		(at 229.8446 -337.312 180)
		(property "Reference" "R6758"
			(at 0 0 0)
			(layer "B.SilkS")
			(hide yes)
			(effects
				(font
					(size 1.27 1.27)
				)
				(justify mirror)
			)
		)
		(property "Value" ""
			(at 0 0 0)
			(layer "B.Fab")
			(effects
				(font
					(size 1.27 1.27)
				)
				(justify mirror)
			)
		)
		(duplicate_pad_numbers_are_jumpers no)
		(fp_line
			(start 0.32512 0.175006)
			(end 0.32512 -0.175006)
			(stroke
				(width 0.1)
				(type default)
			)
			(layer "B.Fab")
		)
		(fp_line
			(start 0.32512 -0.175006)
			(end -0.32512 -0.175006)
			(stroke
				(width 0.1)
				(type default)
			)
			(layer "B.Fab")
		)
		(fp_line
			(start -0.32512 0.175006)
			(end 0.32512 0.175006)
			(stroke
				(width 0.1)
				(type default)
			)
			(layer "B.Fab")
		)
		(fp_line
			(start -0.32512 -0.175006)
			(end -0.32512 0.175006)
			(stroke
				(width 0.1)
				(type default)
			)
			(layer "B.Fab")
		)
		(pad "1" smd rect
			(at 0.2667 0)
			(size 0.3048 0.381)
			(layers "B.Cu" "B.Mask" "B.Paste")
			(net "SMB_RT_CPU0_P3_SDA")
		)
		(pad "2" smd rect
			(at -0.2667 0 180)
			(size 0.3048 0.381)
			(layers "B.Cu" "B.Mask" "B.Paste")
			(net "SMB_RT_CPU0_P3_R_SDA")
		)
	)
	(footprint ""
		(layer "B.Cu")
		(at 356.565962 -256.012188 -90)
		(property "Reference" "C2547"
			(at 0 0 90)
			(layer "B.SilkS")
			(hide yes)
			(effects
				(font
					(size 1.27 1.27)
				)
				(justify mirror)
			)
		)
		(property "Value" ""
			(at 0 0 90)
			(layer "B.Fab")
			(effects
				(font
					(size 1.27 1.27)
				)
				(justify mirror)
			)
		)
		(duplicate_pad_numbers_are_jumpers no)
		(fp_line
			(start -0.7874 0.4064)
			(end 0.7874 0.4064)
			(stroke
				(width 0.1524)
				(type default)
			)
			(layer "B.SilkS")
		)
		(fp_line
			(start 0.7874 0.4064)
			(end 0.7874 -0.4064)
			(stroke
				(width 0.1524)
				(type default)
			)
			(layer "B.SilkS")
		)
		(fp_line
			(start -0.7874 -0.4064)
			(end -0.7874 0.4064)
			(stroke
				(width 0.1524)
				(type default)
			)
			(layer "B.SilkS")
		)
		(fp_line
			(start 0.7874 -0.4064)
			(end -0.7874 -0.4064)
			(stroke
				(width 0.1524)
				(type default)
			)
			(layer "B.SilkS")
		)
		(fp_line
			(start -0.67945 0.3048)
			(end -0.120396 0.3048)
			(stroke
				(width 0.1)
				(type default)
			)
			(layer "B.Fab")
		)
		(fp_line
			(start -0.120396 0.3048)
			(end -0.120396 0.2794)
			(stroke
				(width 0.1)
				(type default)
			)
			(layer "B.Fab")
		)
		(fp_line
			(start 0.12065 0.3048)
			(end 0.67945 0.3048)
			(stroke
				(width 0.1)
				(type default)
			)
			(layer "B.Fab")
		)
		(fp_line
			(start 0.67945 0.3048)
			(end 0.67945 -0.305054)
			(stroke
				(width 0.1)
				(type default)
			)
			(layer "B.Fab")
		)
		(fp_line
			(start -0.120396 0.2794)
			(end 0.12065 0.2794)
			(stroke
				(width 0.1)
				(type default)
			)
			(layer "B.Fab")
		)
		(fp_line
			(start 0.12065 0.2794)
			(end 0.12065 0.3048)
			(stroke
				(width 0.1)
				(type default)
			)
			(layer "B.Fab")
		)
		(fp_line
			(start -0.12065 -0.2794)
			(end -0.12065 -0.3048)
			(stroke
				(width 0.1)
				(type default)
			)
			(layer "B.Fab")
		)
		(fp_line
			(start 0.12065 -0.2794)
			(end -0.12065 -0.2794)
			(stroke
				(width 0.1)
				(type default)
			)
			(layer "B.Fab")
		)
		(fp_line
			(start -0.67945 -0.3048)
			(end -0.67945 0.3048)
			(stroke
				(width 0.1)
				(type default)
			)
			(layer "B.Fab")
		)
		(fp_line
			(start -0.12065 -0.3048)
			(end -0.67945 -0.3048)
			(stroke
				(width 0.1)
				(type default)
			)
			(layer "B.Fab")
		)
		(fp_line
			(start 0.12065 -0.305054)
			(end 0.12065 -0.2794)
			(stroke
				(width 0.1)
				(type default)
			)
			(layer "B.Fab")
		)
		(fp_line
			(start 0.67945 -0.305054)
			(end 0.12065 -0.305054)
			(stroke
				(width 0.1)
				(type default)
			)
			(layer "B.Fab")
		)
		(pad "1" smd circle
			(at 0.40005 0 90)
			(size 0 0)
			(layers "B.Cu" "B.Mask" "B.Paste")
			(net "PVDDCR_SOC_P0")
		)
		(pad "2" smd circle
			(at -0.40005 0 90)
			(size 0 0)
			(layers "B.Cu" "B.Mask" "B.Paste")
			(net "GND")
		)
	)
	(footprint ""
		(layer "B.Cu")
		(at 68.318634 -203.501752 -90)
		(property "Reference" "R512"
			(at 0 0 90)
			(layer "B.SilkS")
			(hide yes)
			(effects
				(font
					(size 1.27 1.27)
				)
				(justify mirror)
			)
		)
		(property "Value" ""
			(at 0 0 90)
			(layer "B.Fab")
			(effects
				(font
					(size 1.27 1.27)
				)
				(justify mirror)
			)
		)
		(duplicate_pad_numbers_are_jumpers no)
		(fp_line
			(start -0.7874 0.4064)
			(end 0.7874 0.4064)
			(stroke
				(width 0.1524)
				(type default)
			)
			(layer "B.SilkS")
		)
		(fp_line
			(start 0.7874 0.4064)
			(end 0.7874 -0.4064)
			(stroke
				(width 0.1524)
				(type default)
			)
			(layer "B.SilkS")
		)
		(fp_line
			(start -0.7874 -0.4064)
			(end -0.7874 0.4064)
			(stroke
				(width 0.1524)
				(type default)
			)
			(layer "B.SilkS")
		)
		(fp_line
			(start 0.7874 -0.4064)
			(end -0.7874 -0.4064)
			(stroke
				(width 0.1524)
				(type default)
			)
			(layer "B.SilkS")
		)
		(fp_line
			(start -0.67945 0.3048)
			(end -0.120396 0.3048)
			(stroke
				(width 0.1)
				(type default)
			)
			(layer "B.Fab")
		)
		(fp_line
			(start -0.120396 0.3048)
			(end -0.120396 0.2794)
			(stroke
				(width 0.1)
				(type default)
			)
			(layer "B.Fab")
		)
		(fp_line
			(start 0.12065 0.3048)
			(end 0.67945 0.3048)
			(stroke
				(width 0.1)
				(type default)
			)
			(layer "B.Fab")
		)
		(fp_line
			(start 0.67945 0.3048)
			(end 0.67945 -0.305054)
			(stroke
				(width 0.1)
				(type default)
			)
			(layer "B.Fab")
		)
		(fp_line
			(start -0.120396 0.2794)
			(end 0.12065 0.2794)
			(stroke
				(width 0.1)
				(type default)
			)
			(layer "B.Fab")
		)
		(fp_line
			(start 0.12065 0.2794)
			(end 0.12065 0.3048)
			(stroke
				(width 0.1)
				(type default)
			)
			(layer "B.Fab")
		)
		(fp_line
			(start -0.12065 -0.2794)
			(end -0.12065 -0.3048)
			(stroke
				(width 0.1)
				(type default)
			)
			(layer "B.Fab")
		)
		(fp_line
			(start 0.12065 -0.2794)
			(end -0.12065 -0.2794)
			(stroke
				(width 0.1)
				(type default)
			)
			(layer "B.Fab")
		)
		(fp_line
			(start -0.67945 -0.3048)
			(end -0.67945 0.3048)
			(stroke
				(width 0.1)
				(type default)
			)
			(layer "B.Fab")
		)
		(fp_line
			(start -0.12065 -0.3048)
			(end -0.67945 -0.3048)
			(stroke
				(width 0.1)
				(type default)
			)
			(layer "B.Fab")
		)
		(fp_line
			(start 0.12065 -0.305054)
			(end 0.12065 -0.2794)
			(stroke
				(width 0.1)
				(type default)
			)
			(layer "B.Fab")
		)
		(fp_line
			(start 0.67945 -0.305054)
			(end 0.12065 -0.305054)
			(stroke
				(width 0.1)
				(type default)
			)
			(layer "B.Fab")
		)
		(pad "1" smd circle
			(at 0.40005 0 90)
			(size 0 0)
			(layers "B.Cu" "B.Mask" "B.Paste")
			(net "P3V3_AUX")
		)
		(pad "2" smd circle
			(at -0.40005 0 90)
			(size 0 0)
			(layers "B.Cu" "B.Mask" "B.Paste")
			(net "CPU1_CORETYPE2")
		)
	)
	(footprint ""
		(layer "B.Cu")
		(at 340.845902 -396.393162 -90)
		(property "Reference" "C617"
			(at 0 0 90)
			(layer "B.SilkS")
			(hide yes)
			(effects
				(font
					(size 1.27 1.27)
				)
				(justify mirror)
			)
		)
		(property "Value" ""
			(at 0 0 90)
			(layer "B.Fab")
			(effects
				(font
					(size 1.27 1.27)
				)
				(justify mirror)
			)
		)
		(duplicate_pad_numbers_are_jumpers no)
		(fp_line
			(start -0.299974 0.150114)
			(end 0.299974 0.150114)
			(stroke
				(width 0.1)
				(type default)
			)
			(layer "B.Fab")
		)
		(fp_line
			(start 0.299974 0.150114)
			(end 0.299974 -0.150114)
			(stroke
				(width 0.1)
				(type default)
			)
			(layer "B.Fab")
		)
		(fp_line
			(start -0.299974 -0.150114)
			(end -0.299974 0.150114)
			(stroke
				(width 0.1)
				(type default)
			)
			(layer "B.Fab")
		)
		(fp_line
			(start 0.299974 -0.150114)
			(end -0.299974 -0.150114)
			(stroke
				(width 0.1)
				(type default)
			)
			(layer "B.Fab")
		)
		(pad "1" smd rect
			(at 0.2667 0 90)
			(size 0.3048 0.381)
			(layers "B.Cu" "B.Mask" "B.Paste")
			(net "P0V9_CPU0_RT1_2A_2D")
		)
		(pad "2" smd rect
			(at -0.2667 0 90)
			(size 0.3048 0.381)
			(layers "B.Cu" "B.Mask" "B.Paste")
			(net "GND")
		)
	)
	(footprint ""
		(layer "B.Cu")
		(at 70.172834 -201.672952)
		(property "Reference" "R530"
			(at 0 0 0)
			(layer "B.SilkS")
			(hide yes)
			(effects
				(font
					(size 1.27 1.27)
				)
				(justify mirror)
			)
		)
		(property "Value" ""
			(at 0 0 0)
			(layer "B.Fab")
			(effects
				(font
					(size 1.27 1.27)
				)
				(justify mirror)
			)
		)
		(duplicate_pad_numbers_are_jumpers no)
		(fp_line
			(start -0.7874 -0.4064)
			(end -0.7874 0.4064)
			(stroke
				(width 0.1524)
				(type default)
			)
			(layer "B.SilkS")
		)
		(fp_line
			(start -0.7874 0.4064)
			(end 0.7874 0.4064)
			(stroke
				(width 0.1524)
				(type default)
			)
			(layer "B.SilkS")
		)
		(fp_line
			(start 0.7874 -0.4064)
			(end -0.7874 -0.4064)
			(stroke
				(width 0.1524)
				(type default)
			)
			(layer "B.SilkS")
		)
		(fp_line
			(start 0.7874 0.4064)
			(end 0.7874 -0.4064)
			(stroke
				(width 0.1524)
				(type default)
			)
			(layer "B.SilkS")
		)
		(fp_line
			(start -0.67945 -0.3048)
			(end -0.67945 0.3048)
			(stroke
				(width 0.1)
				(type default)
			)
			(layer "B.Fab")
		)
		(fp_line
			(start -0.67945 0.3048)
			(end -0.120396 0.3048)
			(stroke
				(width 0.1)
				(type default)
			)
			(layer "B.Fab")
		)
		(fp_line
			(start -0.12065 -0.3048)
			(end -0.67945 -0.3048)
			(stroke
				(width 0.1)
				(type default)
			)
			(layer "B.Fab")
		)
		(fp_line
			(start -0.12065 -0.2794)
			(end -0.12065 -0.3048)
			(stroke
				(width 0.1)
				(type default)
			)
			(layer "B.Fab")
		)
		(fp_line
			(start -0.120396 0.2794)
			(end 0.12065 0.2794)
			(stroke
				(width 0.1)
				(type default)
			)
			(layer "B.Fab")
		)
		(fp_line
			(start -0.120396 0.3048)
			(end -0.120396 0.2794)
			(stroke
				(width 0.1)
				(type default)
			)
			(layer "B.Fab")
		)
		(fp_line
			(start 0.12065 -0.305054)
			(end 0.12065 -0.2794)
			(stroke
				(width 0.1)
				(type default)
			)
			(layer "B.Fab")
		)
		(fp_line
			(start 0.12065 -0.2794)
			(end -0.12065 -0.2794)
			(stroke
				(width 0.1)
				(type default)
			)
			(layer "B.Fab")
		)
		(fp_line
			(start 0.12065 0.2794)
			(end 0.12065 0.3048)
			(stroke
				(width 0.1)
				(type default)
			)
			(layer "B.Fab")
		)
		(fp_line
			(start 0.12065 0.3048)
			(end 0.67945 0.3048)
			(stroke
				(width 0.1)
				(type default)
			)
			(layer "B.Fab")
		)
		(fp_line
			(start 0.67945 -0.305054)
			(end 0.12065 -0.305054)
			(stroke
				(width 0.1)
				(type default)
			)
			(layer "B.Fab")
		)
		(fp_line
			(start 0.67945 0.3048)
			(end 0.67945 -0.305054)
			(stroke
				(width 0.1)
				(type default)
			)
			(layer "B.Fab")
		)
		(pad "1" smd circle
			(at 0.40005 0 180)
			(size 0 0)
			(layers "B.Cu" "B.Mask" "B.Paste")
			(net "RST_CPU0_RESETL_N")
		)
		(pad "2" smd circle
			(at -0.40005 0 180)
			(size 0 0)
			(layers "B.Cu" "B.Mask" "B.Paste")
			(net "RST_CPU1_RESETL_N")
		)
	)
	(footprint ""
		(layer "B.Cu")
		(at 148.34616 -388.011162 -90)
		(property "Reference" "C428"
			(at 0 0 90)
			(layer "B.SilkS")
			(hide yes)
			(effects
				(font
					(size 1.27 1.27)
				)
				(justify mirror)
			)
		)
		(property "Value" ""
			(at 0 0 90)
			(layer "B.Fab")
			(effects
				(font
					(size 1.27 1.27)
				)
				(justify mirror)
			)
		)
		(duplicate_pad_numbers_are_jumpers no)
		(fp_line
			(start -0.299974 0.150114)
			(end 0.299974 0.150114)
			(stroke
				(width 0.1)
				(type default)
			)
			(layer "B.Fab")
		)
		(fp_line
			(start 0.299974 0.150114)
			(end 0.299974 -0.150114)
			(stroke
				(width 0.1)
				(type default)
			)
			(layer "B.Fab")
		)
		(fp_line
			(start -0.299974 -0.150114)
			(end -0.299974 0.150114)
			(stroke
				(width 0.1)
				(type default)
			)
			(layer "B.Fab")
		)
		(fp_line
			(start 0.299974 -0.150114)
			(end -0.299974 -0.150114)
			(stroke
				(width 0.1)
				(type default)
			)
			(layer "B.Fab")
		)
		(pad "1" smd rect
			(at 0.2667 0 90)
			(size 0.3048 0.381)
			(layers "B.Cu" "B.Mask" "B.Paste")
			(net "P0V9_CPU1_RT2_2A")
		)
		(pad "2" smd rect
			(at -0.2667 0 90)
			(size 0.3048 0.381)
			(layers "B.Cu" "B.Mask" "B.Paste")
			(net "GND")
		)
	)
	(footprint ""
		(layer "B.Cu")
		(at 406.698958 -326.894952)
		(property "Reference" "R440"
			(at 0 0 0)
			(layer "B.SilkS")
			(hide yes)
			(effects
				(font
					(size 1.27 1.27)
				)
				(justify mirror)
			)
		)
		(property "Value" ""
			(at 0 0 0)
			(layer "B.Fab")
			(effects
				(font
					(size 1.27 1.27)
				)
				(justify mirror)
			)
		)
		(duplicate_pad_numbers_are_jumpers no)
		(fp_line
			(start -0.7874 -0.4064)
			(end -0.7874 0.4064)
			(stroke
				(width 0.1524)
				(type default)
			)
			(layer "B.SilkS")
		)
		(fp_line
			(start -0.7874 0.4064)
			(end 0.7874 0.4064)
			(stroke
				(width 0.1524)
				(type default)
			)
			(layer "B.SilkS")
		)
		(fp_line
			(start 0.7874 -0.4064)
			(end -0.7874 -0.4064)
			(stroke
				(width 0.1524)
				(type default)
			)
			(layer "B.SilkS")
		)
		(fp_line
			(start 0.7874 0.4064)
			(end 0.7874 -0.4064)
			(stroke
				(width 0.1524)
				(type default)
			)
			(layer "B.SilkS")
		)
		(fp_line
			(start -0.67945 -0.3048)
			(end -0.67945 0.3048)
			(stroke
				(width 0.1)
				(type default)
			)
			(layer "B.Fab")
		)
		(fp_line
			(start -0.67945 0.3048)
			(end -0.120396 0.3048)
			(stroke
				(width 0.1)
				(type default)
			)
			(layer "B.Fab")
		)
		(fp_line
			(start -0.12065 -0.3048)
			(end -0.67945 -0.3048)
			(stroke
				(width 0.1)
				(type default)
			)
			(layer "B.Fab")
		)
		(fp_line
			(start -0.12065 -0.2794)
			(end -0.12065 -0.3048)
			(stroke
				(width 0.1)
				(type default)
			)
			(layer "B.Fab")
		)
		(fp_line
			(start -0.120396 0.2794)
			(end 0.12065 0.2794)
			(stroke
				(width 0.1)
				(type default)
			)
			(layer "B.Fab")
		)
		(fp_line
			(start -0.120396 0.3048)
			(end -0.120396 0.2794)
			(stroke
				(width 0.1)
				(type default)
			)
			(layer "B.Fab")
		)
		(fp_line
			(start 0.12065 -0.305054)
			(end 0.12065 -0.2794)
			(stroke
				(width 0.1)
				(type default)
			)
			(layer "B.Fab")
		)
		(fp_line
			(start 0.12065 -0.2794)
			(end -0.12065 -0.2794)
			(stroke
				(width 0.1)
				(type default)
			)
			(layer "B.Fab")
		)
		(fp_line
			(start 0.12065 0.2794)
			(end 0.12065 0.3048)
			(stroke
				(width 0.1)
				(type default)
			)
			(layer "B.Fab")
		)
		(fp_line
			(start 0.12065 0.3048)
			(end 0.67945 0.3048)
			(stroke
				(width 0.1)
				(type default)
			)
			(layer "B.Fab")
		)
		(fp_line
			(start 0.67945 -0.305054)
			(end 0.12065 -0.305054)
			(stroke
				(width 0.1)
				(type default)
			)
			(layer "B.Fab")
		)
		(fp_line
			(start 0.67945 0.3048)
			(end 0.67945 -0.305054)
			(stroke
				(width 0.1)
				(type default)
			)
			(layer "B.Fab")
		)
		(pad "1" smd circle
			(at 0.40005 0 180)
			(size 0 0)
			(layers "B.Cu" "B.Mask" "B.Paste")
			(net "GND")
		)
		(pad "2" smd circle
			(at -0.40005 0 180)
			(size 0 0)
			(layers "B.Cu" "B.Mask" "B.Paste")
			(net "CPU0_PWR_GD_OUT")
		)
	)
	(footprint ""
		(layer "B.Cu")
		(at 157.136846 -408.517344 90)
		(property "Reference" "C6751"
			(at 0 0 90)
			(layer "B.SilkS")
			(hide yes)
			(effects
				(font
					(size 1.27 1.27)
				)
				(justify mirror)
			)
		)
		(property "Value" ""
			(at 0 0 90)
			(layer "B.Fab")
			(effects
				(font
					(size 1.27 1.27)
				)
				(justify mirror)
			)
		)
		(duplicate_pad_numbers_are_jumpers no)
		(fp_line
			(start 0.299974 -0.150114)
			(end -0.299974 -0.150114)
			(stroke
				(width 0.1)
				(type default)
			)
			(layer "B.Fab")
		)
		(fp_line
			(start -0.299974 -0.150114)
			(end -0.299974 0.150114)
			(stroke
				(width 0.1)
				(type default)
			)
			(layer "B.Fab")
		)
		(fp_line
			(start 0.299974 0.150114)
			(end 0.299974 -0.150114)
			(stroke
				(width 0.1)
				(type default)
			)
			(layer "B.Fab")
		)
		(fp_line
			(start -0.299974 0.150114)
			(end 0.299974 0.150114)
			(stroke
				(width 0.1)
				(type default)
			)
			(layer "B.Fab")
		)
		(pad "1" smd rect
			(at 0.2667 0 270)
			(size 0.3048 0.381)
			(layers "B.Cu" "B.Mask" "B.Paste")
			(net "P5E_CPU1_P3_TX_BUF_C_DP<13>")
		)
		(pad "2" smd rect
			(at -0.2667 0 270)
			(size 0.3048 0.381)
			(layers "B.Cu" "B.Mask" "B.Paste")
			(net "P5E_CPU1_P3_TX_BUF_DP<13>")
		)
	)
	(footprint ""
		(layer "B.Cu")
		(at 233.68 -331.724 180)
		(property "Reference" "R6784"
			(at 0 0 0)
			(layer "B.SilkS")
			(hide yes)
			(effects
				(font
					(size 1.27 1.27)
				)
				(justify mirror)
			)
		)
		(property "Value" ""
			(at 0 0 0)
			(layer "B.Fab")
			(effects
				(font
					(size 1.27 1.27)
				)
				(justify mirror)
			)
		)
		(duplicate_pad_numbers_are_jumpers no)
		(fp_line
			(start 0.7874 0.4064)
			(end 0.7874 -0.4064)
			(stroke
				(width 0.1524)
				(type default)
			)
			(layer "B.SilkS")
		)
		(fp_line
			(start 0.7874 -0.4064)
			(end -0.7874 -0.4064)
			(stroke
				(width 0.1524)
				(type default)
			)
			(layer "B.SilkS")
		)
		(fp_line
			(start -0.7874 0.4064)
			(end 0.7874 0.4064)
			(stroke
				(width 0.1524)
				(type default)
			)
			(layer "B.SilkS")
		)
		(fp_line
			(start -0.7874 -0.4064)
			(end -0.7874 0.4064)
			(stroke
				(width 0.1524)
				(type default)
			)
			(layer "B.SilkS")
		)
		(fp_line
			(start 0.67945 0.3048)
			(end 0.67945 -0.305054)
			(stroke
				(width 0.1)
				(type default)
			)
			(layer "B.Fab")
		)
		(fp_line
			(start 0.67945 -0.305054)
			(end 0.12065 -0.305054)
			(stroke
				(width 0.1)
				(type default)
			)
			(layer "B.Fab")
		)
		(fp_line
			(start 0.12065 0.3048)
			(end 0.67945 0.3048)
			(stroke
				(width 0.1)
				(type default)
			)
			(layer "B.Fab")
		)
		(fp_line
			(start 0.12065 0.2794)
			(end 0.12065 0.3048)
			(stroke
				(width 0.1)
				(type default)
			)
			(layer "B.Fab")
		)
		(fp_line
			(start 0.12065 -0.2794)
			(end -0.12065 -0.2794)
			(stroke
				(width 0.1)
				(type default)
			)
			(layer "B.Fab")
		)
		(fp_line
			(start 0.12065 -0.305054)
			(end 0.12065 -0.2794)
			(stroke
				(width 0.1)
				(type default)
			)
			(layer "B.Fab")
		)
		(fp_line
			(start -0.120396 0.3048)
			(end -0.120396 0.2794)
			(stroke
				(width 0.1)
				(type default)
			)
			(layer "B.Fab")
		)
		(fp_line
			(start -0.120396 0.2794)
			(end 0.12065 0.2794)
			(stroke
				(width 0.1)
				(type default)
			)
			(layer "B.Fab")
		)
		(fp_line
			(start -0.12065 -0.2794)
			(end -0.12065 -0.3048)
			(stroke
				(width 0.1)
				(type default)
			)
			(layer "B.Fab")
		)
		(fp_line
			(start -0.12065 -0.3048)
			(end -0.67945 -0.3048)
			(stroke
				(width 0.1)
				(type default)
			)
			(layer "B.Fab")
		)
		(fp_line
			(start -0.67945 0.3048)
			(end -0.120396 0.3048)
			(stroke
				(width 0.1)
				(type default)
			)
			(layer "B.Fab")
		)
		(fp_line
			(start -0.67945 -0.3048)
			(end -0.67945 0.3048)
			(stroke
				(width 0.1)
				(type default)
			)
			(layer "B.Fab")
		)
		(pad "1" smd circle
			(at 0.40005 0)
			(size 0 0)
			(layers "B.Cu" "B.Mask" "B.Paste")
			(net "SMB_MUX_RT_R1_SCL")
		)
		(pad "2" smd circle
			(at -0.40005 0)
			(size 0 0)
			(layers "B.Cu" "B.Mask" "B.Paste")
			(net "SMB_SML1_PMBUS_HSC_SCL")
		)
	)
	(footprint ""
		(layer "B.Cu")
		(at 102.401878 -146.66341)
		(property "Reference" "PR174"
			(at 0 0 0)
			(layer "B.SilkS")
			(hide yes)
			(effects
				(font
					(size 1.27 1.27)
				)
				(justify mirror)
			)
		)
		(property "Value" ""
			(at 0 0 0)
			(layer "B.Fab")
			(effects
				(font
					(size 1.27 1.27)
				)
				(justify mirror)
			)
		)
		(duplicate_pad_numbers_are_jumpers no)
		(fp_line
			(start -0.7874 -0.4064)
			(end -0.7874 0.4064)
			(stroke
				(width 0.1524)
				(type default)
			)
			(layer "B.SilkS")
		)
		(fp_line
			(start -0.7874 0.4064)
			(end 0.7874 0.4064)
			(stroke
				(width 0.1524)
				(type default)
			)
			(layer "B.SilkS")
		)
		(fp_line
			(start 0.7874 -0.4064)
			(end -0.7874 -0.4064)
			(stroke
				(width 0.1524)
				(type default)
			)
			(layer "B.SilkS")
		)
		(fp_line
			(start 0.7874 0.4064)
			(end 0.7874 -0.4064)
			(stroke
				(width 0.1524)
				(type default)
			)
			(layer "B.SilkS")
		)
		(fp_line
			(start -0.67945 -0.3048)
			(end -0.67945 0.3048)
			(stroke
				(width 0.1)
				(type default)
			)
			(layer "B.Fab")
		)
		(fp_line
			(start -0.67945 0.3048)
			(end -0.120396 0.3048)
			(stroke
				(width 0.1)
				(type default)
			)
			(layer "B.Fab")
		)
		(fp_line
			(start -0.12065 -0.3048)
			(end -0.67945 -0.3048)
			(stroke
				(width 0.1)
				(type default)
			)
			(layer "B.Fab")
		)
		(fp_line
			(start -0.12065 -0.2794)
			(end -0.12065 -0.3048)
			(stroke
				(width 0.1)
				(type default)
			)
			(layer "B.Fab")
		)
		(fp_line
			(start -0.120396 0.2794)
			(end 0.12065 0.2794)
			(stroke
				(width 0.1)
				(type default)
			)
			(layer "B.Fab")
		)
		(fp_line
			(start -0.120396 0.3048)
			(end -0.120396 0.2794)
			(stroke
				(width 0.1)
				(type default)
			)
			(layer "B.Fab")
		)
		(fp_line
			(start 0.12065 -0.305054)
			(end 0.12065 -0.2794)
			(stroke
				(width 0.1)
				(type default)
			)
			(layer "B.Fab")
		)
		(fp_line
			(start 0.12065 -0.2794)
			(end -0.12065 -0.2794)
			(stroke
				(width 0.1)
				(type default)
			)
			(layer "B.Fab")
		)
		(fp_line
			(start 0.12065 0.2794)
			(end 0.12065 0.3048)
			(stroke
				(width 0.1)
				(type default)
			)
			(layer "B.Fab")
		)
		(fp_line
			(start 0.12065 0.3048)
			(end 0.67945 0.3048)
			(stroke
				(width 0.1)
				(type default)
			)
			(layer "B.Fab")
		)
		(fp_line
			(start 0.67945 -0.305054)
			(end 0.12065 -0.305054)
			(stroke
				(width 0.1)
				(type default)
			)
			(layer "B.Fab")
		)
		(fp_line
			(start 0.67945 0.3048)
			(end 0.67945 -0.305054)
			(stroke
				(width 0.1)
				(type default)
			)
			(layer "B.Fab")
		)
		(pad "1" smd circle
			(at 0.40005 0 180)
			(size 0 0)
			(layers "B.Cu" "B.Mask" "B.Paste")
			(net "VSENSE_PVDDCR_SOC_P1_DP")
		)
		(pad "2" smd circle
			(at -0.40005 0 180)
			(size 0 0)
			(layers "B.Cu" "B.Mask" "B.Paste")
			(net "VSENSE_PVDDCR_SOC_P1_VSEN1")
		)
	)
	(footprint ""
		(layer "B.Cu")
		(at 323.386958 -199.980296)
		(property "Reference" "R452"
			(at 0 0 0)
			(layer "B.SilkS")
			(hide yes)
			(effects
				(font
					(size 1.27 1.27)
				)
				(justify mirror)
			)
		)
		(property "Value" ""
			(at 0 0 0)
			(layer "B.Fab")
			(effects
				(font
					(size 1.27 1.27)
				)
				(justify mirror)
			)
		)
		(duplicate_pad_numbers_are_jumpers no)
		(fp_line
			(start -0.7874 -0.4064)
			(end -0.7874 0.4064)
			(stroke
				(width 0.1524)
				(type default)
			)
			(layer "B.SilkS")
		)
		(fp_line
			(start -0.7874 0.4064)
			(end 0.7874 0.4064)
			(stroke
				(width 0.1524)
				(type default)
			)
			(layer "B.SilkS")
		)
		(fp_line
			(start 0.7874 -0.4064)
			(end -0.7874 -0.4064)
			(stroke
				(width 0.1524)
				(type default)
			)
			(layer "B.SilkS")
		)
		(fp_line
			(start 0.7874 0.4064)
			(end 0.7874 -0.4064)
			(stroke
				(width 0.1524)
				(type default)
			)
			(layer "B.SilkS")
		)
		(fp_line
			(start -0.67945 -0.3048)
			(end -0.67945 0.3048)
			(stroke
				(width 0.1)
				(type default)
			)
			(layer "B.Fab")
		)
		(fp_line
			(start -0.67945 0.3048)
			(end -0.120396 0.3048)
			(stroke
				(width 0.1)
				(type default)
			)
			(layer "B.Fab")
		)
		(fp_line
			(start -0.12065 -0.3048)
			(end -0.67945 -0.3048)
			(stroke
				(width 0.1)
				(type default)
			)
			(layer "B.Fab")
		)
		(fp_line
			(start -0.12065 -0.2794)
			(end -0.12065 -0.3048)
			(stroke
				(width 0.1)
				(type default)
			)
			(layer "B.Fab")
		)
		(fp_line
			(start -0.120396 0.2794)
			(end 0.12065 0.2794)
			(stroke
				(width 0.1)
				(type default)
			)
			(layer "B.Fab")
		)
		(fp_line
			(start -0.120396 0.3048)
			(end -0.120396 0.2794)
			(stroke
				(width 0.1)
				(type default)
			)
			(layer "B.Fab")
		)
		(fp_line
			(start 0.12065 -0.305054)
			(end 0.12065 -0.2794)
			(stroke
				(width 0.1)
				(type default)
			)
			(layer "B.Fab")
		)
		(fp_line
			(start 0.12065 -0.2794)
			(end -0.12065 -0.2794)
			(stroke
				(width 0.1)
				(type default)
			)
			(layer "B.Fab")
		)
		(fp_line
			(start 0.12065 0.2794)
			(end 0.12065 0.3048)
			(stroke
				(width 0.1)
				(type default)
			)
			(layer "B.Fab")
		)
		(fp_line
			(start 0.12065 0.3048)
			(end 0.67945 0.3048)
			(stroke
				(width 0.1)
				(type default)
			)
			(layer "B.Fab")
		)
		(fp_line
			(start 0.67945 -0.305054)
			(end 0.12065 -0.305054)
			(stroke
				(width 0.1)
				(type default)
			)
			(layer "B.Fab")
		)
		(fp_line
			(start 0.67945 0.3048)
			(end 0.67945 -0.305054)
			(stroke
				(width 0.1)
				(type default)
			)
			(layer "B.Fab")
		)
		(pad "1" smd circle
			(at 0.40005 0 180)
			(size 0 0)
			(layers "B.Cu" "B.Mask" "B.Paste")
			(net "CPU0_NV_SAVE_N")
		)
		(pad "2" smd circle
			(at -0.40005 0 180)
			(size 0 0)
			(layers "B.Cu" "B.Mask" "B.Paste")
			(net "PVDD18_S5_P0")
		)
	)
	(footprint ""
		(layer "B.Cu")
		(at 421.486076 -362.44403)
		(property "Reference" "PR3"
			(at 0 0 0)
			(layer "B.SilkS")
			(hide yes)
			(effects
				(font
					(size 1.27 1.27)
				)
				(justify mirror)
			)
		)
		(property "Value" ""
			(at 0 0 0)
			(layer "B.Fab")
			(effects
				(font
					(size 1.27 1.27)
				)
				(justify mirror)
			)
		)
		(duplicate_pad_numbers_are_jumpers no)
		(fp_line
			(start -0.7874 -0.4064)
			(end -0.7874 0.4064)
			(stroke
				(width 0.1524)
				(type default)
			)
			(layer "B.SilkS")
		)
		(fp_line
			(start -0.7874 0.4064)
			(end 0.7874 0.4064)
			(stroke
				(width 0.1524)
				(type default)
			)
			(layer "B.SilkS")
		)
		(fp_line
			(start 0.7874 -0.4064)
			(end -0.7874 -0.4064)
			(stroke
				(width 0.1524)
				(type default)
			)
			(layer "B.SilkS")
		)
		(fp_line
			(start 0.7874 0.4064)
			(end 0.7874 -0.4064)
			(stroke
				(width 0.1524)
				(type default)
			)
			(layer "B.SilkS")
		)
		(fp_line
			(start -0.67945 -0.3048)
			(end -0.67945 0.3048)
			(stroke
				(width 0.1)
				(type default)
			)
			(layer "B.Fab")
		)
		(fp_line
			(start -0.67945 0.3048)
			(end -0.120396 0.3048)
			(stroke
				(width 0.1)
				(type default)
			)
			(layer "B.Fab")
		)
		(fp_line
			(start -0.12065 -0.3048)
			(end -0.67945 -0.3048)
			(stroke
				(width 0.1)
				(type default)
			)
			(layer "B.Fab")
		)
		(fp_line
			(start -0.12065 -0.2794)
			(end -0.12065 -0.3048)
			(stroke
				(width 0.1)
				(type default)
			)
			(layer "B.Fab")
		)
		(fp_line
			(start -0.120396 0.2794)
			(end 0.12065 0.2794)
			(stroke
				(width 0.1)
				(type default)
			)
			(layer "B.Fab")
		)
		(fp_line
			(start -0.120396 0.3048)
			(end -0.120396 0.2794)
			(stroke
				(width 0.1)
				(type default)
			)
			(layer "B.Fab")
		)
		(fp_line
			(start 0.12065 -0.305054)
			(end 0.12065 -0.2794)
			(stroke
				(width 0.1)
				(type default)
			)
			(layer "B.Fab")
		)
		(fp_line
			(start 0.12065 -0.2794)
			(end -0.12065 -0.2794)
			(stroke
				(width 0.1)
				(type default)
			)
			(layer "B.Fab")
		)
		(fp_line
			(start 0.12065 0.2794)
			(end 0.12065 0.3048)
			(stroke
				(width 0.1)
				(type default)
			)
			(layer "B.Fab")
		)
		(fp_line
			(start 0.12065 0.3048)
			(end 0.67945 0.3048)
			(stroke
				(width 0.1)
				(type default)
			)
			(layer "B.Fab")
		)
		(fp_line
			(start 0.67945 -0.305054)
			(end 0.12065 -0.305054)
			(stroke
				(width 0.1)
				(type default)
			)
			(layer "B.Fab")
		)
		(fp_line
			(start 0.67945 0.3048)
			(end 0.67945 -0.305054)
			(stroke
				(width 0.1)
				(type default)
			)
			(layer "B.Fab")
		)
		(pad "1" smd circle
			(at 0.40005 0 180)
			(size 0 0)
			(layers "B.Cu" "B.Mask" "B.Paste")
			(net "PVDD11_S3_P0_VMON")
		)
		(pad "2" smd circle
			(at -0.40005 0 180)
			(size 0 0)
			(layers "B.Cu" "B.Mask" "B.Paste")
			(net "GND")
		)
	)
	(footprint ""
		(layer "B.Cu")
		(at 404.584408 -330.849732 90)
		(property "Reference" "R451"
			(at 0 0 90)
			(layer "B.SilkS")
			(hide yes)
			(effects
				(font
					(size 1.27 1.27)
				)
				(justify mirror)
			)
		)
		(property "Value" ""
			(at 0 0 90)
			(layer "B.Fab")
			(effects
				(font
					(size 1.27 1.27)
				)
				(justify mirror)
			)
		)
		(duplicate_pad_numbers_are_jumpers no)
		(fp_line
			(start 0.7874 -0.4064)
			(end -0.7874 -0.4064)
			(stroke
				(width 0.1524)
				(type default)
			)
			(layer "B.SilkS")
		)
		(fp_line
			(start -0.7874 -0.4064)
			(end -0.7874 0.4064)
			(stroke
				(width 0.1524)
				(type default)
			)
			(layer "B.SilkS")
		)
		(fp_line
			(start 0.7874 0.4064)
			(end 0.7874 -0.4064)
			(stroke
				(width 0.1524)
				(type default)
			)
			(layer "B.SilkS")
		)
		(fp_line
			(start -0.7874 0.4064)
			(end 0.7874 0.4064)
			(stroke
				(width 0.1524)
				(type default)
			)
			(layer "B.SilkS")
		)
		(fp_line
			(start 0.67945 -0.305054)
			(end 0.12065 -0.305054)
			(stroke
				(width 0.1)
				(type default)
			)
			(layer "B.Fab")
		)
		(fp_line
			(start 0.12065 -0.305054)
			(end 0.12065 -0.2794)
			(stroke
				(width 0.1)
				(type default)
			)
			(layer "B.Fab")
		)
		(fp_line
			(start -0.12065 -0.3048)
			(end -0.67945 -0.3048)
			(stroke
				(width 0.1)
				(type default)
			)
			(layer "B.Fab")
		)
		(fp_line
			(start -0.67945 -0.3048)
			(end -0.67945 0.3048)
			(stroke
				(width 0.1)
				(type default)
			)
			(layer "B.Fab")
		)
		(fp_line
			(start 0.12065 -0.2794)
			(end -0.12065 -0.2794)
			(stroke
				(width 0.1)
				(type default)
			)
			(layer "B.Fab")
		)
		(fp_line
			(start -0.12065 -0.2794)
			(end -0.12065 -0.3048)
			(stroke
				(width 0.1)
				(type default)
			)
			(layer "B.Fab")
		)
		(fp_line
			(start 0.12065 0.2794)
			(end 0.12065 0.3048)
			(stroke
				(width 0.1)
				(type default)
			)
			(layer "B.Fab")
		)
		(fp_line
			(start -0.120396 0.2794)
			(end 0.12065 0.2794)
			(stroke
				(width 0.1)
				(type default)
			)
			(layer "B.Fab")
		)
		(fp_line
			(start 0.67945 0.3048)
			(end 0.67945 -0.305054)
			(stroke
				(width 0.1)
				(type default)
			)
			(layer "B.Fab")
		)
		(fp_line
			(start 0.12065 0.3048)
			(end 0.67945 0.3048)
			(stroke
				(width 0.1)
				(type default)
			)
			(layer "B.Fab")
		)
		(fp_line
			(start -0.120396 0.3048)
			(end -0.120396 0.2794)
			(stroke
				(width 0.1)
				(type default)
			)
			(layer "B.Fab")
		)
		(fp_line
			(start -0.67945 0.3048)
			(end -0.120396 0.3048)
			(stroke
				(width 0.1)
				(type default)
			)
			(layer "B.Fab")
		)
		(pad "1" smd circle
			(at 0.40005 0 270)
			(size 0 0)
			(layers "B.Cu" "B.Mask" "B.Paste")
			(net "CPU0_SPD_HOST_CTRL_N")
		)
		(pad "2" smd circle
			(at -0.40005 0 270)
			(size 0 0)
			(layers "B.Cu" "B.Mask" "B.Paste")
			(net "PVDD18_S5_P0")
		)
	)
	(footprint ""
		(layer "B.Cu")
		(at 109.395514 -331.404976 -90)
		(property "Reference" "PR342"
			(at 0 0 90)
			(layer "B.SilkS")
			(hide yes)
			(effects
				(font
					(size 1.27 1.27)
				)
				(justify mirror)
			)
		)
		(property "Value" ""
			(at 0 0 90)
			(layer "B.Fab")
			(effects
				(font
					(size 1.27 1.27)
				)
				(justify mirror)
			)
		)
		(duplicate_pad_numbers_are_jumpers no)
		(fp_line
			(start -0.7874 0.4064)
			(end 0.7874 0.4064)
			(stroke
				(width 0.1524)
				(type default)
			)
			(layer "B.SilkS")
		)
		(fp_line
			(start 0.7874 0.4064)
			(end 0.7874 -0.4064)
			(stroke
				(width 0.1524)
				(type default)
			)
			(layer "B.SilkS")
		)
		(fp_line
			(start -0.7874 -0.4064)
			(end -0.7874 0.4064)
			(stroke
				(width 0.1524)
				(type default)
			)
			(layer "B.SilkS")
		)
		(fp_line
			(start 0.7874 -0.4064)
			(end -0.7874 -0.4064)
			(stroke
				(width 0.1524)
				(type default)
			)
			(layer "B.SilkS")
		)
		(fp_line
			(start -0.67945 0.3048)
			(end -0.120396 0.3048)
			(stroke
				(width 0.1)
				(type default)
			)
			(layer "B.Fab")
		)
		(fp_line
			(start -0.120396 0.3048)
			(end -0.120396 0.2794)
			(stroke
				(width 0.1)
				(type default)
			)
			(layer "B.Fab")
		)
		(fp_line
			(start 0.12065 0.3048)
			(end 0.67945 0.3048)
			(stroke
				(width 0.1)
				(type default)
			)
			(layer "B.Fab")
		)
		(fp_line
			(start 0.67945 0.3048)
			(end 0.67945 -0.305054)
			(stroke
				(width 0.1)
				(type default)
			)
			(layer "B.Fab")
		)
		(fp_line
			(start -0.120396 0.2794)
			(end 0.12065 0.2794)
			(stroke
				(width 0.1)
				(type default)
			)
			(layer "B.Fab")
		)
		(fp_line
			(start 0.12065 0.2794)
			(end 0.12065 0.3048)
			(stroke
				(width 0.1)
				(type default)
			)
			(layer "B.Fab")
		)
		(fp_line
			(start -0.12065 -0.2794)
			(end -0.12065 -0.3048)
			(stroke
				(width 0.1)
				(type default)
			)
			(layer "B.Fab")
		)
		(fp_line
			(start 0.12065 -0.2794)
			(end -0.12065 -0.2794)
			(stroke
				(width 0.1)
				(type default)
			)
			(layer "B.Fab")
		)
		(fp_line
			(start -0.67945 -0.3048)
			(end -0.67945 0.3048)
			(stroke
				(width 0.1)
				(type default)
			)
			(layer "B.Fab")
		)
		(fp_line
			(start -0.12065 -0.3048)
			(end -0.67945 -0.3048)
			(stroke
				(width 0.1)
				(type default)
			)
			(layer "B.Fab")
		)
		(fp_line
			(start 0.12065 -0.305054)
			(end 0.12065 -0.2794)
			(stroke
				(width 0.1)
				(type default)
			)
			(layer "B.Fab")
		)
		(fp_line
			(start 0.67945 -0.305054)
			(end 0.12065 -0.305054)
			(stroke
				(width 0.1)
				(type default)
			)
			(layer "B.Fab")
		)
		(pad "1" smd circle
			(at 0.40005 0 90)
			(size 0 0)
			(layers "B.Cu" "B.Mask" "B.Paste")
			(net "PVDDCR_CPU1_P1")
		)
		(pad "2" smd circle
			(at -0.40005 0 90)
			(size 0 0)
			(layers "B.Cu" "B.Mask" "B.Paste")
			(net "GND")
		)
	)
	(footprint ""
		(layer "B.Cu")
		(at 202.15733 -190.94831 180)
		(property "Reference" "R314"
			(at 0 0 0)
			(layer "B.SilkS")
			(hide yes)
			(effects
				(font
					(size 1.27 1.27)
				)
				(justify mirror)
			)
		)
		(property "Value" ""
			(at 0 0 0)
			(layer "B.Fab")
			(effects
				(font
					(size 1.27 1.27)
				)
				(justify mirror)
			)
		)
		(duplicate_pad_numbers_are_jumpers no)
		(fp_line
			(start 0.7874 0.4064)
			(end 0.7874 -0.4064)
			(stroke
				(width 0.1524)
				(type default)
			)
			(layer "B.SilkS")
		)
		(fp_line
			(start 0.7874 -0.4064)
			(end -0.7874 -0.4064)
			(stroke
				(width 0.1524)
				(type default)
			)
			(layer "B.SilkS")
		)
		(fp_line
			(start -0.7874 0.4064)
			(end 0.7874 0.4064)
			(stroke
				(width 0.1524)
				(type default)
			)
			(layer "B.SilkS")
		)
		(fp_line
			(start -0.7874 -0.4064)
			(end -0.7874 0.4064)
			(stroke
				(width 0.1524)
				(type default)
			)
			(layer "B.SilkS")
		)
		(fp_line
			(start 0.67945 0.3048)
			(end 0.67945 -0.305054)
			(stroke
				(width 0.1)
				(type default)
			)
			(layer "B.Fab")
		)
		(fp_line
			(start 0.67945 -0.305054)
			(end 0.12065 -0.305054)
			(stroke
				(width 0.1)
				(type default)
			)
			(layer "B.Fab")
		)
		(fp_line
			(start 0.12065 0.3048)
			(end 0.67945 0.3048)
			(stroke
				(width 0.1)
				(type default)
			)
			(layer "B.Fab")
		)
		(fp_line
			(start 0.12065 0.2794)
			(end 0.12065 0.3048)
			(stroke
				(width 0.1)
				(type default)
			)
			(layer "B.Fab")
		)
		(fp_line
			(start 0.12065 -0.2794)
			(end -0.12065 -0.2794)
			(stroke
				(width 0.1)
				(type default)
			)
			(layer "B.Fab")
		)
		(fp_line
			(start 0.12065 -0.305054)
			(end 0.12065 -0.2794)
			(stroke
				(width 0.1)
				(type default)
			)
			(layer "B.Fab")
		)
		(fp_line
			(start -0.120396 0.3048)
			(end -0.120396 0.2794)
			(stroke
				(width 0.1)
				(type default)
			)
			(layer "B.Fab")
		)
		(fp_line
			(start -0.120396 0.2794)
			(end 0.12065 0.2794)
			(stroke
				(width 0.1)
				(type default)
			)
			(layer "B.Fab")
		)
		(fp_line
			(start -0.12065 -0.2794)
			(end -0.12065 -0.3048)
			(stroke
				(width 0.1)
				(type default)
			)
			(layer "B.Fab")
		)
		(fp_line
			(start -0.12065 -0.3048)
			(end -0.67945 -0.3048)
			(stroke
				(width 0.1)
				(type default)
			)
			(layer "B.Fab")
		)
		(fp_line
			(start -0.67945 0.3048)
			(end -0.120396 0.3048)
			(stroke
				(width 0.1)
				(type default)
			)
			(layer "B.Fab")
		)
		(fp_line
			(start -0.67945 -0.3048)
			(end -0.67945 0.3048)
			(stroke
				(width 0.1)
				(type default)
			)
			(layer "B.Fab")
		)
		(pad "1" smd circle
			(at 0.40005 0)
			(size 0 0)
			(layers "B.Cu" "B.Mask" "B.Paste")
			(net "PWRGD_CHL_CPU1_DIMM")
		)
		(pad "2" smd circle
			(at -0.40005 0)
			(size 0 0)
			(layers "B.Cu" "B.Mask" "B.Paste")
			(net "PWRGD_CHGL_CPU1")
		)
	)
	(footprint ""
		(layer "B.Cu")
		(at 97.591118 -425.19219)
		(property "Reference" "C8000"
			(at 0 0 0)
			(layer "B.SilkS")
			(hide yes)
			(effects
				(font
					(size 1.27 1.27)
				)
				(justify mirror)
			)
		)
		(property "Value" ""
			(at 0 0 0)
			(layer "B.Fab")
			(effects
				(font
					(size 1.27 1.27)
				)
				(justify mirror)
			)
		)
		(duplicate_pad_numbers_are_jumpers no)
		(fp_line
			(start -0.7874 -0.4064)
			(end -0.7874 0.4064)
			(stroke
				(width 0.1524)
				(type default)
			)
			(layer "B.SilkS")
		)
		(fp_line
			(start -0.7874 0.4064)
			(end 0.7874 0.4064)
			(stroke
				(width 0.1524)
				(type default)
			)
			(layer "B.SilkS")
		)
		(fp_line
			(start 0.7874 -0.4064)
			(end -0.7874 -0.4064)
			(stroke
				(width 0.1524)
				(type default)
			)
			(layer "B.SilkS")
		)
		(fp_line
			(start 0.7874 0.4064)
			(end 0.7874 -0.4064)
			(stroke
				(width 0.1524)
				(type default)
			)
			(layer "B.SilkS")
		)
		(fp_line
			(start -0.67945 -0.3048)
			(end -0.67945 0.3048)
			(stroke
				(width 0.1)
				(type default)
			)
			(layer "B.Fab")
		)
		(fp_line
			(start -0.67945 0.3048)
			(end -0.120396 0.3048)
			(stroke
				(width 0.1)
				(type default)
			)
			(layer "B.Fab")
		)
		(fp_line
			(start -0.12065 -0.3048)
			(end -0.67945 -0.3048)
			(stroke
				(width 0.1)
				(type default)
			)
			(layer "B.Fab")
		)
		(fp_line
			(start -0.12065 -0.2794)
			(end -0.12065 -0.3048)
			(stroke
				(width 0.1)
				(type default)
			)
			(layer "B.Fab")
		)
		(fp_line
			(start -0.120396 0.2794)
			(end 0.12065 0.2794)
			(stroke
				(width 0.1)
				(type default)
			)
			(layer "B.Fab")
		)
		(fp_line
			(start -0.120396 0.3048)
			(end -0.120396 0.2794)
			(stroke
				(width 0.1)
				(type default)
			)
			(layer "B.Fab")
		)
		(fp_line
			(start 0.12065 -0.305054)
			(end 0.12065 -0.2794)
			(stroke
				(width 0.1)
				(type default)
			)
			(layer "B.Fab")
		)
		(fp_line
			(start 0.12065 -0.2794)
			(end -0.12065 -0.2794)
			(stroke
				(width 0.1)
				(type default)
			)
			(layer "B.Fab")
		)
		(fp_line
			(start 0.12065 0.2794)
			(end 0.12065 0.3048)
			(stroke
				(width 0.1)
				(type default)
			)
			(layer "B.Fab")
		)
		(fp_line
			(start 0.12065 0.3048)
			(end 0.67945 0.3048)
			(stroke
				(width 0.1)
				(type default)
			)
			(layer "B.Fab")
		)
		(fp_line
			(start 0.67945 -0.305054)
			(end 0.12065 -0.305054)
			(stroke
				(width 0.1)
				(type default)
			)
			(layer "B.Fab")
		)
		(fp_line
			(start 0.67945 0.3048)
			(end 0.67945 -0.305054)
			(stroke
				(width 0.1)
				(type default)
			)
			(layer "B.Fab")
		)
		(pad "1" smd circle
			(at 0.40005 0 180)
			(size 0 0)
			(layers "B.Cu" "B.Mask" "B.Paste")
			(net "PRSNT_SWB_ISO_N")
		)
		(pad "2" smd circle
			(at -0.40005 0 180)
			(size 0 0)
			(layers "B.Cu" "B.Mask" "B.Paste")
			(net "GND")
		)
	)
	(footprint ""
		(layer "B.Cu")
		(at 123.357386 -267.49883)
		(property "Reference" "C2405"
			(at 0 0 0)
			(layer "B.SilkS")
			(hide yes)
			(effects
				(font
					(size 1.27 1.27)
				)
				(justify mirror)
			)
		)
		(property "Value" ""
			(at 0 0 0)
			(layer "B.Fab")
			(effects
				(font
					(size 1.27 1.27)
				)
				(justify mirror)
			)
		)
		(duplicate_pad_numbers_are_jumpers no)
		(fp_line
			(start -0.7874 -0.4064)
			(end -0.7874 0.4064)
			(stroke
				(width 0.1524)
				(type default)
			)
			(layer "B.SilkS")
		)
		(fp_line
			(start -0.7874 0.4064)
			(end 0.7874 0.4064)
			(stroke
				(width 0.1524)
				(type default)
			)
			(layer "B.SilkS")
		)
		(fp_line
			(start 0.7874 -0.4064)
			(end -0.7874 -0.4064)
			(stroke
				(width 0.1524)
				(type default)
			)
			(layer "B.SilkS")
		)
		(fp_line
			(start 0.7874 0.4064)
			(end 0.7874 -0.4064)
			(stroke
				(width 0.1524)
				(type default)
			)
			(layer "B.SilkS")
		)
		(fp_line
			(start -0.67945 -0.3048)
			(end -0.67945 0.3048)
			(stroke
				(width 0.1)
				(type default)
			)
			(layer "B.Fab")
		)
		(fp_line
			(start -0.67945 0.3048)
			(end -0.120396 0.3048)
			(stroke
				(width 0.1)
				(type default)
			)
			(layer "B.Fab")
		)
		(fp_line
			(start -0.12065 -0.3048)
			(end -0.67945 -0.3048)
			(stroke
				(width 0.1)
				(type default)
			)
			(layer "B.Fab")
		)
		(fp_line
			(start -0.12065 -0.2794)
			(end -0.12065 -0.3048)
			(stroke
				(width 0.1)
				(type default)
			)
			(layer "B.Fab")
		)
		(fp_line
			(start -0.120396 0.2794)
			(end 0.12065 0.2794)
			(stroke
				(width 0.1)
				(type default)
			)
			(layer "B.Fab")
		)
		(fp_line
			(start -0.120396 0.3048)
			(end -0.120396 0.2794)
			(stroke
				(width 0.1)
				(type default)
			)
			(layer "B.Fab")
		)
		(fp_line
			(start 0.12065 -0.305054)
			(end 0.12065 -0.2794)
			(stroke
				(width 0.1)
				(type default)
			)
			(layer "B.Fab")
		)
		(fp_line
			(start 0.12065 -0.2794)
			(end -0.12065 -0.2794)
			(stroke
				(width 0.1)
				(type default)
			)
			(layer "B.Fab")
		)
		(fp_line
			(start 0.12065 0.2794)
			(end 0.12065 0.3048)
			(stroke
				(width 0.1)
				(type default)
			)
			(layer "B.Fab")
		)
		(fp_line
			(start 0.12065 0.3048)
			(end 0.67945 0.3048)
			(stroke
				(width 0.1)
				(type default)
			)
			(layer "B.Fab")
		)
		(fp_line
			(start 0.67945 -0.305054)
			(end 0.12065 -0.305054)
			(stroke
				(width 0.1)
				(type default)
			)
			(layer "B.Fab")
		)
		(fp_line
			(start 0.67945 0.3048)
			(end 0.67945 -0.305054)
			(stroke
				(width 0.1)
				(type default)
			)
			(layer "B.Fab")
		)
		(pad "1" smd circle
			(at 0.40005 0 180)
			(size 0 0)
			(layers "B.Cu" "B.Mask" "B.Paste")
			(net "PVDDCR_CPU1_P1")
		)
		(pad "2" smd circle
			(at -0.40005 0 180)
			(size 0 0)
			(layers "B.Cu" "B.Mask" "B.Paste")
			(net "GND")
		)
	)
	(footprint ""
		(layer "B.Cu")
		(at 174.202852 -8.05688 -90)
		(property "Reference" "R2425"
			(at 0 0 90)
			(layer "B.SilkS")
			(hide yes)
			(effects
				(font
					(size 1.27 1.27)
				)
				(justify mirror)
			)
		)
		(property "Value" ""
			(at 0 0 90)
			(layer "B.Fab")
			(effects
				(font
					(size 1.27 1.27)
				)
				(justify mirror)
			)
		)
		(duplicate_pad_numbers_are_jumpers no)
		(fp_line
			(start -0.7874 0.4064)
			(end 0.7874 0.4064)
			(stroke
				(width 0.1524)
				(type default)
			)
			(layer "B.SilkS")
		)
		(fp_line
			(start 0.7874 0.4064)
			(end 0.7874 -0.4064)
			(stroke
				(width 0.1524)
				(type default)
			)
			(layer "B.SilkS")
		)
		(fp_line
			(start -0.7874 -0.4064)
			(end -0.7874 0.4064)
			(stroke
				(width 0.1524)
				(type default)
			)
			(layer "B.SilkS")
		)
		(fp_line
			(start 0.7874 -0.4064)
			(end -0.7874 -0.4064)
			(stroke
				(width 0.1524)
				(type default)
			)
			(layer "B.SilkS")
		)
		(fp_line
			(start -0.67945 0.3048)
			(end -0.120396 0.3048)
			(stroke
				(width 0.1)
				(type default)
			)
			(layer "B.Fab")
		)
		(fp_line
			(start -0.120396 0.3048)
			(end -0.120396 0.2794)
			(stroke
				(width 0.1)
				(type default)
			)
			(layer "B.Fab")
		)
		(fp_line
			(start 0.12065 0.3048)
			(end 0.67945 0.3048)
			(stroke
				(width 0.1)
				(type default)
			)
			(layer "B.Fab")
		)
		(fp_line
			(start 0.67945 0.3048)
			(end 0.67945 -0.305054)
			(stroke
				(width 0.1)
				(type default)
			)
			(layer "B.Fab")
		)
		(fp_line
			(start -0.120396 0.2794)
			(end 0.12065 0.2794)
			(stroke
				(width 0.1)
				(type default)
			)
			(layer "B.Fab")
		)
		(fp_line
			(start 0.12065 0.2794)
			(end 0.12065 0.3048)
			(stroke
				(width 0.1)
				(type default)
			)
			(layer "B.Fab")
		)
		(fp_line
			(start -0.12065 -0.2794)
			(end -0.12065 -0.3048)
			(stroke
				(width 0.1)
				(type default)
			)
			(layer "B.Fab")
		)
		(fp_line
			(start 0.12065 -0.2794)
			(end -0.12065 -0.2794)
			(stroke
				(width 0.1)
				(type default)
			)
			(layer "B.Fab")
		)
		(fp_line
			(start -0.67945 -0.3048)
			(end -0.67945 0.3048)
			(stroke
				(width 0.1)
				(type default)
			)
			(layer "B.Fab")
		)
		(fp_line
			(start -0.12065 -0.3048)
			(end -0.67945 -0.3048)
			(stroke
				(width 0.1)
				(type default)
			)
			(layer "B.Fab")
		)
		(fp_line
			(start 0.12065 -0.305054)
			(end 0.12065 -0.2794)
			(stroke
				(width 0.1)
				(type default)
			)
			(layer "B.Fab")
		)
		(fp_line
			(start 0.67945 -0.305054)
			(end 0.12065 -0.305054)
			(stroke
				(width 0.1)
				(type default)
			)
			(layer "B.Fab")
		)
		(pad "1" smd circle
			(at 0.40005 0 90)
			(size 0 0)
			(layers "B.Cu" "B.Mask" "B.Paste")
			(net "SMB_OCP_V3_2_3V3AUX_SCL")
		)
		(pad "2" smd circle
			(at -0.40005 0 90)
			(size 0 0)
			(layers "B.Cu" "B.Mask" "B.Paste")
			(net "SMB_OCP_V3_2_3V3AUX_SCL_R0")
		)
	)
	(footprint ""
		(layer "B.Cu")
		(at 120.856248 -165.079934 -90)
		(property "Reference" "PC332_2"
			(at 0 0 90)
			(layer "B.SilkS")
			(hide yes)
			(effects
				(font
					(size 1.27 1.27)
				)
				(justify mirror)
			)
		)
		(property "Value" ""
			(at 0 0 90)
			(layer "B.Fab")
			(effects
				(font
					(size 1.27 1.27)
				)
				(justify mirror)
			)
		)
		(duplicate_pad_numbers_are_jumpers no)
		(fp_line
			(start -1.524 0.762)
			(end 1.524 0.762)
			(stroke
				(width 0.1524)
				(type default)
			)
			(layer "B.SilkS")
		)
		(fp_line
			(start 1.524 0.762)
			(end 1.524 -0.762)
			(stroke
				(width 0.1524)
				(type default)
			)
			(layer "B.SilkS")
		)
		(fp_line
			(start -1.524 -0.762)
			(end -1.524 0.762)
			(stroke
				(width 0.1524)
				(type default)
			)
			(layer "B.SilkS")
		)
		(fp_line
			(start 1.524 -0.762)
			(end -1.524 -0.762)
			(stroke
				(width 0.1524)
				(type default)
			)
			(layer "B.SilkS")
		)
		(fp_line
			(start -1.1049 0.724916)
			(end -1.1049 -0.724916)
			(stroke
				(width 0.1)
				(type default)
			)
			(layer "B.Fab")
		)
		(fp_line
			(start 1.1049 0.724916)
			(end -1.1049 0.724916)
			(stroke
				(width 0.1)
				(type default)
			)
			(layer "B.Fab")
		)
		(fp_line
			(start -1.1049 -0.724916)
			(end 1.1049 -0.724916)
			(stroke
				(width 0.1)
				(type default)
			)
			(layer "B.Fab")
		)
		(fp_line
			(start 1.1049 -0.724916)
			(end 1.1049 0.724916)
			(stroke
				(width 0.1)
				(type default)
			)
			(layer "B.Fab")
		)
		(pad "1" smd rect
			(at 0.889 0 270)
			(size 1.016 1.27)
			(layers "B.Cu" "B.Mask" "B.Paste")
			(net "SW_P12V_AUX_PVDDCR_SOC_P1_FLT")
		)
		(pad "2" smd rect
			(at -0.889 0 270)
			(size 1.016 1.27)
			(layers "B.Cu" "B.Mask" "B.Paste")
			(net "GND")
		)
	)
	(footprint ""
		(layer "B.Cu")
		(at 387.41858 -396.393162 -90)
		(property "Reference" "C1010"
			(at 0 0 90)
			(layer "B.SilkS")
			(hide yes)
			(effects
				(font
					(size 1.27 1.27)
				)
				(justify mirror)
			)
		)
		(property "Value" ""
			(at 0 0 90)
			(layer "B.Fab")
			(effects
				(font
					(size 1.27 1.27)
				)
				(justify mirror)
			)
		)
		(duplicate_pad_numbers_are_jumpers no)
		(fp_line
			(start -0.299974 0.150114)
			(end 0.299974 0.150114)
			(stroke
				(width 0.1)
				(type default)
			)
			(layer "B.Fab")
		)
		(fp_line
			(start 0.299974 0.150114)
			(end 0.299974 -0.150114)
			(stroke
				(width 0.1)
				(type default)
			)
			(layer "B.Fab")
		)
		(fp_line
			(start -0.299974 -0.150114)
			(end -0.299974 0.150114)
			(stroke
				(width 0.1)
				(type default)
			)
			(layer "B.Fab")
		)
		(fp_line
			(start 0.299974 -0.150114)
			(end -0.299974 -0.150114)
			(stroke
				(width 0.1)
				(type default)
			)
			(layer "B.Fab")
		)
		(pad "1" smd rect
			(at 0.2667 0 90)
			(size 0.3048 0.381)
			(layers "B.Cu" "B.Mask" "B.Paste")
			(net "P0V9_CPU0_RT3_2A")
		)
		(pad "2" smd rect
			(at -0.2667 0 90)
			(size 0.3048 0.381)
			(layers "B.Cu" "B.Mask" "B.Paste")
			(net "GND")
		)
	)
	(footprint ""
		(layer "B.Cu")
		(at 154.346148 -388.011162 -90)
		(property "Reference" "C374"
			(at 0 0 90)
			(layer "B.SilkS")
			(hide yes)
			(effects
				(font
					(size 1.27 1.27)
				)
				(justify mirror)
			)
		)
		(property "Value" ""
			(at 0 0 90)
			(layer "B.Fab")
			(effects
				(font
					(size 1.27 1.27)
				)
				(justify mirror)
			)
		)
		(duplicate_pad_numbers_are_jumpers no)
		(fp_line
			(start -0.299974 0.150114)
			(end 0.299974 0.150114)
			(stroke
				(width 0.1)
				(type default)
			)
			(layer "B.Fab")
		)
		(fp_line
			(start 0.299974 0.150114)
			(end 0.299974 -0.150114)
			(stroke
				(width 0.1)
				(type default)
			)
			(layer "B.Fab")
		)
		(fp_line
			(start -0.299974 -0.150114)
			(end -0.299974 0.150114)
			(stroke
				(width 0.1)
				(type default)
			)
			(layer "B.Fab")
		)
		(fp_line
			(start 0.299974 -0.150114)
			(end -0.299974 -0.150114)
			(stroke
				(width 0.1)
				(type default)
			)
			(layer "B.Fab")
		)
		(pad "1" smd rect
			(at 0.2667 0 90)
			(size 0.3048 0.381)
			(layers "B.Cu" "B.Mask" "B.Paste")
			(net "P1V8_CPU1_RT2_1A")
		)
		(pad "2" smd rect
			(at -0.2667 0 90)
			(size 0.3048 0.381)
			(layers "B.Cu" "B.Mask" "B.Paste")
			(net "GND")
		)
	)
	(footprint ""
		(layer "B.Cu")
		(at 176.657 -100.294948 -90)
		(property "Reference" "R188"
			(at 0 0 90)
			(layer "B.SilkS")
			(hide yes)
			(effects
				(font
					(size 1.27 1.27)
				)
				(justify mirror)
			)
		)
		(property "Value" ""
			(at 0 0 90)
			(layer "B.Fab")
			(effects
				(font
					(size 1.27 1.27)
				)
				(justify mirror)
			)
		)
		(duplicate_pad_numbers_are_jumpers no)
		(fp_line
			(start -0.7874 0.4064)
			(end 0.7874 0.4064)
			(stroke
				(width 0.1524)
				(type default)
			)
			(layer "B.SilkS")
		)
		(fp_line
			(start 0.7874 0.4064)
			(end 0.7874 -0.4064)
			(stroke
				(width 0.1524)
				(type default)
			)
			(layer "B.SilkS")
		)
		(fp_line
			(start -0.7874 -0.4064)
			(end -0.7874 0.4064)
			(stroke
				(width 0.1524)
				(type default)
			)
			(layer "B.SilkS")
		)
		(fp_line
			(start 0.7874 -0.4064)
			(end -0.7874 -0.4064)
			(stroke
				(width 0.1524)
				(type default)
			)
			(layer "B.SilkS")
		)
		(fp_line
			(start -0.67945 0.3048)
			(end -0.120396 0.3048)
			(stroke
				(width 0.1)
				(type default)
			)
			(layer "B.Fab")
		)
		(fp_line
			(start -0.120396 0.3048)
			(end -0.120396 0.2794)
			(stroke
				(width 0.1)
				(type default)
			)
			(layer "B.Fab")
		)
		(fp_line
			(start 0.12065 0.3048)
			(end 0.67945 0.3048)
			(stroke
				(width 0.1)
				(type default)
			)
			(layer "B.Fab")
		)
		(fp_line
			(start 0.67945 0.3048)
			(end 0.67945 -0.305054)
			(stroke
				(width 0.1)
				(type default)
			)
			(layer "B.Fab")
		)
		(fp_line
			(start -0.120396 0.2794)
			(end 0.12065 0.2794)
			(stroke
				(width 0.1)
				(type default)
			)
			(layer "B.Fab")
		)
		(fp_line
			(start 0.12065 0.2794)
			(end 0.12065 0.3048)
			(stroke
				(width 0.1)
				(type default)
			)
			(layer "B.Fab")
		)
		(fp_line
			(start -0.12065 -0.2794)
			(end -0.12065 -0.3048)
			(stroke
				(width 0.1)
				(type default)
			)
			(layer "B.Fab")
		)
		(fp_line
			(start 0.12065 -0.2794)
			(end -0.12065 -0.2794)
			(stroke
				(width 0.1)
				(type default)
			)
			(layer "B.Fab")
		)
		(fp_line
			(start -0.67945 -0.3048)
			(end -0.67945 0.3048)
			(stroke
				(width 0.1)
				(type default)
			)
			(layer "B.Fab")
		)
		(fp_line
			(start -0.12065 -0.3048)
			(end -0.67945 -0.3048)
			(stroke
				(width 0.1)
				(type default)
			)
			(layer "B.Fab")
		)
		(fp_line
			(start 0.12065 -0.305054)
			(end 0.12065 -0.2794)
			(stroke
				(width 0.1)
				(type default)
			)
			(layer "B.Fab")
		)
		(fp_line
			(start 0.67945 -0.305054)
			(end 0.12065 -0.305054)
			(stroke
				(width 0.1)
				(type default)
			)
			(layer "B.Fab")
		)
		(pad "1" smd circle
			(at 0.40005 0 90)
			(size 0 0)
			(layers "B.Cu" "B.Mask" "B.Paste")
			(net "FM_BMC_READY_N")
		)
		(pad "2" smd circle
			(at -0.40005 0 90)
			(size 0 0)
			(layers "B.Cu" "B.Mask" "B.Paste")
			(net "FM_BMC_READY_R_N")
		)
	)
	(footprint ""
		(layer "B.Cu")
		(at 146.115024 -391.340848 -90)
		(property "Reference" "C413"
			(at 0 0 90)
			(layer "B.SilkS")
			(hide yes)
			(effects
				(font
					(size 1.27 1.27)
				)
				(justify mirror)
			)
		)
		(property "Value" ""
			(at 0 0 90)
			(layer "B.Fab")
			(effects
				(font
					(size 1.27 1.27)
				)
				(justify mirror)
			)
		)
		(duplicate_pad_numbers_are_jumpers no)
		(fp_line
			(start -0.7874 0.4064)
			(end 0.7874 0.4064)
			(stroke
				(width 0.1524)
				(type default)
			)
			(layer "B.SilkS")
		)
		(fp_line
			(start 0.7874 0.4064)
			(end 0.7874 -0.4064)
			(stroke
				(width 0.1524)
				(type default)
			)
			(layer "B.SilkS")
		)
		(fp_line
			(start -0.7874 -0.4064)
			(end -0.7874 0.4064)
			(stroke
				(width 0.1524)
				(type default)
			)
			(layer "B.SilkS")
		)
		(fp_line
			(start 0.7874 -0.4064)
			(end -0.7874 -0.4064)
			(stroke
				(width 0.1524)
				(type default)
			)
			(layer "B.SilkS")
		)
		(fp_line
			(start -0.67945 0.3048)
			(end -0.120396 0.3048)
			(stroke
				(width 0.1)
				(type default)
			)
			(layer "B.Fab")
		)
		(fp_line
			(start -0.120396 0.3048)
			(end -0.120396 0.2794)
			(stroke
				(width 0.1)
				(type default)
			)
			(layer "B.Fab")
		)
		(fp_line
			(start 0.12065 0.3048)
			(end 0.67945 0.3048)
			(stroke
				(width 0.1)
				(type default)
			)
			(layer "B.Fab")
		)
		(fp_line
			(start 0.67945 0.3048)
			(end 0.67945 -0.305054)
			(stroke
				(width 0.1)
				(type default)
			)
			(layer "B.Fab")
		)
		(fp_line
			(start -0.120396 0.2794)
			(end 0.12065 0.2794)
			(stroke
				(width 0.1)
				(type default)
			)
			(layer "B.Fab")
		)
		(fp_line
			(start 0.12065 0.2794)
			(end 0.12065 0.3048)
			(stroke
				(width 0.1)
				(type default)
			)
			(layer "B.Fab")
		)
		(fp_line
			(start -0.12065 -0.2794)
			(end -0.12065 -0.3048)
			(stroke
				(width 0.1)
				(type default)
			)
			(layer "B.Fab")
		)
		(fp_line
			(start 0.12065 -0.2794)
			(end -0.12065 -0.2794)
			(stroke
				(width 0.1)
				(type default)
			)
			(layer "B.Fab")
		)
		(fp_line
			(start -0.67945 -0.3048)
			(end -0.67945 0.3048)
			(stroke
				(width 0.1)
				(type default)
			)
			(layer "B.Fab")
		)
		(fp_line
			(start -0.12065 -0.3048)
			(end -0.67945 -0.3048)
			(stroke
				(width 0.1)
				(type default)
			)
			(layer "B.Fab")
		)
		(fp_line
			(start 0.12065 -0.305054)
			(end 0.12065 -0.2794)
			(stroke
				(width 0.1)
				(type default)
			)
			(layer "B.Fab")
		)
		(fp_line
			(start 0.67945 -0.305054)
			(end 0.12065 -0.305054)
			(stroke
				(width 0.1)
				(type default)
			)
			(layer "B.Fab")
		)
		(pad "1" smd circle
			(at 0.40005 0 90)
			(size 0 0)
			(layers "B.Cu" "B.Mask" "B.Paste")
			(net "P0V9_CPU1_RT2_2A")
		)
		(pad "2" smd circle
			(at -0.40005 0 90)
			(size 0 0)
			(layers "B.Cu" "B.Mask" "B.Paste")
			(net "GND")
		)
	)
	(footprint ""
		(layer "B.Cu")
		(at 165.419532 -431.57648 -90)
		(property "Reference" "R4572"
			(at 0 0 90)
			(layer "B.SilkS")
			(hide yes)
			(effects
				(font
					(size 1.27 1.27)
				)
				(justify mirror)
			)
		)
		(property "Value" ""
			(at 0 0 90)
			(layer "B.Fab")
			(effects
				(font
					(size 1.27 1.27)
				)
				(justify mirror)
			)
		)
		(duplicate_pad_numbers_are_jumpers no)
		(fp_line
			(start -0.7874 0.4064)
			(end 0.7874 0.4064)
			(stroke
				(width 0.1524)
				(type default)
			)
			(layer "B.SilkS")
		)
		(fp_line
			(start 0.7874 0.4064)
			(end 0.7874 -0.4064)
			(stroke
				(width 0.1524)
				(type default)
			)
			(layer "B.SilkS")
		)
		(fp_line
			(start -0.7874 -0.4064)
			(end -0.7874 0.4064)
			(stroke
				(width 0.1524)
				(type default)
			)
			(layer "B.SilkS")
		)
		(fp_line
			(start 0.7874 -0.4064)
			(end -0.7874 -0.4064)
			(stroke
				(width 0.1524)
				(type default)
			)
			(layer "B.SilkS")
		)
		(fp_line
			(start -0.67945 0.3048)
			(end -0.120396 0.3048)
			(stroke
				(width 0.1)
				(type default)
			)
			(layer "B.Fab")
		)
		(fp_line
			(start -0.120396 0.3048)
			(end -0.120396 0.2794)
			(stroke
				(width 0.1)
				(type default)
			)
			(layer "B.Fab")
		)
		(fp_line
			(start 0.12065 0.3048)
			(end 0.67945 0.3048)
			(stroke
				(width 0.1)
				(type default)
			)
			(layer "B.Fab")
		)
		(fp_line
			(start 0.67945 0.3048)
			(end 0.67945 -0.305054)
			(stroke
				(width 0.1)
				(type default)
			)
			(layer "B.Fab")
		)
		(fp_line
			(start -0.120396 0.2794)
			(end 0.12065 0.2794)
			(stroke
				(width 0.1)
				(type default)
			)
			(layer "B.Fab")
		)
		(fp_line
			(start 0.12065 0.2794)
			(end 0.12065 0.3048)
			(stroke
				(width 0.1)
				(type default)
			)
			(layer "B.Fab")
		)
		(fp_line
			(start -0.12065 -0.2794)
			(end -0.12065 -0.3048)
			(stroke
				(width 0.1)
				(type default)
			)
			(layer "B.Fab")
		)
		(fp_line
			(start 0.12065 -0.2794)
			(end -0.12065 -0.2794)
			(stroke
				(width 0.1)
				(type default)
			)
			(layer "B.Fab")
		)
		(fp_line
			(start -0.67945 -0.3048)
			(end -0.67945 0.3048)
			(stroke
				(width 0.1)
				(type default)
			)
			(layer "B.Fab")
		)
		(fp_line
			(start -0.12065 -0.3048)
			(end -0.67945 -0.3048)
			(stroke
				(width 0.1)
				(type default)
			)
			(layer "B.Fab")
		)
		(fp_line
			(start 0.12065 -0.305054)
			(end 0.12065 -0.2794)
			(stroke
				(width 0.1)
				(type default)
			)
			(layer "B.Fab")
		)
		(fp_line
			(start 0.67945 -0.305054)
			(end 0.12065 -0.305054)
			(stroke
				(width 0.1)
				(type default)
			)
			(layer "B.Fab")
		)
		(pad "1" smd circle
			(at 0.40005 0 90)
			(size 0 0)
			(layers "B.Cu" "B.Mask" "B.Paste")
			(net "GPU_3V3IO_RSVD1_FFU")
		)
		(pad "2" smd circle
			(at -0.40005 0 90)
			(size 0 0)
			(layers "B.Cu" "B.Mask" "B.Paste")
			(net "GPU_3V3IO_RSVD1_FFU_ISO")
		)
	)
	(footprint ""
		(layer "B.Cu")
		(at 182.8673 -13.60043 -90)
		(property "Reference" "R6007"
			(at 0 0 90)
			(layer "B.SilkS")
			(hide yes)
			(effects
				(font
					(size 1.27 1.27)
				)
				(justify mirror)
			)
		)
		(property "Value" ""
			(at 0 0 90)
			(layer "B.Fab")
			(effects
				(font
					(size 1.27 1.27)
				)
				(justify mirror)
			)
		)
		(duplicate_pad_numbers_are_jumpers no)
		(fp_line
			(start -0.7874 0.4064)
			(end 0.7874 0.4064)
			(stroke
				(width 0.1524)
				(type default)
			)
			(layer "B.SilkS")
		)
		(fp_line
			(start 0.7874 0.4064)
			(end 0.7874 -0.4064)
			(stroke
				(width 0.1524)
				(type default)
			)
			(layer "B.SilkS")
		)
		(fp_line
			(start -0.7874 -0.4064)
			(end -0.7874 0.4064)
			(stroke
				(width 0.1524)
				(type default)
			)
			(layer "B.SilkS")
		)
		(fp_line
			(start 0.7874 -0.4064)
			(end -0.7874 -0.4064)
			(stroke
				(width 0.1524)
				(type default)
			)
			(layer "B.SilkS")
		)
		(fp_line
			(start -0.67945 0.3048)
			(end -0.120396 0.3048)
			(stroke
				(width 0.1)
				(type default)
			)
			(layer "B.Fab")
		)
		(fp_line
			(start -0.120396 0.3048)
			(end -0.120396 0.2794)
			(stroke
				(width 0.1)
				(type default)
			)
			(layer "B.Fab")
		)
		(fp_line
			(start 0.12065 0.3048)
			(end 0.67945 0.3048)
			(stroke
				(width 0.1)
				(type default)
			)
			(layer "B.Fab")
		)
		(fp_line
			(start 0.67945 0.3048)
			(end 0.67945 -0.305054)
			(stroke
				(width 0.1)
				(type default)
			)
			(layer "B.Fab")
		)
		(fp_line
			(start -0.120396 0.2794)
			(end 0.12065 0.2794)
			(stroke
				(width 0.1)
				(type default)
			)
			(layer "B.Fab")
		)
		(fp_line
			(start 0.12065 0.2794)
			(end 0.12065 0.3048)
			(stroke
				(width 0.1)
				(type default)
			)
			(layer "B.Fab")
		)
		(fp_line
			(start -0.12065 -0.2794)
			(end -0.12065 -0.3048)
			(stroke
				(width 0.1)
				(type default)
			)
			(layer "B.Fab")
		)
		(fp_line
			(start 0.12065 -0.2794)
			(end -0.12065 -0.2794)
			(stroke
				(width 0.1)
				(type default)
			)
			(layer "B.Fab")
		)
		(fp_line
			(start -0.67945 -0.3048)
			(end -0.67945 0.3048)
			(stroke
				(width 0.1)
				(type default)
			)
			(layer "B.Fab")
		)
		(fp_line
			(start -0.12065 -0.3048)
			(end -0.67945 -0.3048)
			(stroke
				(width 0.1)
				(type default)
			)
			(layer "B.Fab")
		)
		(fp_line
			(start 0.12065 -0.305054)
			(end 0.12065 -0.2794)
			(stroke
				(width 0.1)
				(type default)
			)
			(layer "B.Fab")
		)
		(fp_line
			(start 0.67945 -0.305054)
			(end 0.12065 -0.305054)
			(stroke
				(width 0.1)
				(type default)
			)
			(layer "B.Fab")
		)
		(pad "1" smd circle
			(at 0.40005 0 90)
			(size 0 0)
			(layers "B.Cu" "B.Mask" "B.Paste")
			(net "I3C_SCM_3_SDA")
		)
		(pad "2" smd circle
			(at -0.40005 0 90)
			(size 0 0)
			(layers "B.Cu" "B.Mask" "B.Paste")
			(net "I3C_SCM_3_R_SDA")
		)
	)
	(footprint ""
		(layer "B.Cu")
		(at 276.54377 -346.784168 90)
		(property "Reference" "PC182_4"
			(at 0 0 90)
			(layer "B.SilkS")
			(hide yes)
			(effects
				(font
					(size 1.27 1.27)
				)
				(justify mirror)
			)
		)
		(property "Value" ""
			(at 0 0 90)
			(layer "B.Fab")
			(effects
				(font
					(size 1.27 1.27)
				)
				(justify mirror)
			)
		)
		(duplicate_pad_numbers_are_jumpers no)
		(fp_line
			(start 1.524 -0.762)
			(end -1.524 -0.762)
			(stroke
				(width 0.1524)
				(type default)
			)
			(layer "B.SilkS")
		)
		(fp_line
			(start -1.524 -0.762)
			(end -1.524 0.762)
			(stroke
				(width 0.1524)
				(type default)
			)
			(layer "B.SilkS")
		)
		(fp_line
			(start 1.524 0.762)
			(end 1.524 -0.762)
			(stroke
				(width 0.1524)
				(type default)
			)
			(layer "B.SilkS")
		)
		(fp_line
			(start -1.524 0.762)
			(end 1.524 0.762)
			(stroke
				(width 0.1524)
				(type default)
			)
			(layer "B.SilkS")
		)
		(fp_line
			(start 1.1049 -0.724916)
			(end 1.1049 0.724916)
			(stroke
				(width 0.1)
				(type default)
			)
			(layer "B.Fab")
		)
		(fp_line
			(start -1.1049 -0.724916)
			(end 1.1049 -0.724916)
			(stroke
				(width 0.1)
				(type default)
			)
			(layer "B.Fab")
		)
		(fp_line
			(start 1.1049 0.724916)
			(end -1.1049 0.724916)
			(stroke
				(width 0.1)
				(type default)
			)
			(layer "B.Fab")
		)
		(fp_line
			(start -1.1049 0.724916)
			(end -1.1049 -0.724916)
			(stroke
				(width 0.1)
				(type default)
			)
			(layer "B.Fab")
		)
		(pad "1" smd rect
			(at 0.889 0 90)
			(size 1.016 1.27)
			(layers "B.Cu" "B.Mask" "B.Paste")
			(net "SW_P12V_AUX_PVDDIO_P0_FLT")
		)
		(pad "2" smd rect
			(at -0.889 0 90)
			(size 1.016 1.27)
			(layers "B.Cu" "B.Mask" "B.Paste")
			(net "GND")
		)
	)
	(footprint ""
		(layer "B.Cu")
		(at 336.279744 -156.059886 180)
		(property "Reference" "PC114"
			(at 0 0 0)
			(layer "B.SilkS")
			(hide yes)
			(effects
				(font
					(size 1.27 1.27)
				)
				(justify mirror)
			)
		)
		(property "Value" ""
			(at 0 0 0)
			(layer "B.Fab")
			(effects
				(font
					(size 1.27 1.27)
				)
				(justify mirror)
			)
		)
		(duplicate_pad_numbers_are_jumpers no)
		(fp_line
			(start 1.524 0.762)
			(end 1.524 -0.762)
			(stroke
				(width 0.1524)
				(type default)
			)
			(layer "B.SilkS")
		)
		(fp_line
			(start 1.524 -0.762)
			(end -1.524 -0.762)
			(stroke
				(width 0.1524)
				(type default)
			)
			(layer "B.SilkS")
		)
		(fp_line
			(start -1.524 0.762)
			(end 1.524 0.762)
			(stroke
				(width 0.1524)
				(type default)
			)
			(layer "B.SilkS")
		)
		(fp_line
			(start -1.524 -0.762)
			(end -1.524 0.762)
			(stroke
				(width 0.1524)
				(type default)
			)
			(layer "B.SilkS")
		)
		(fp_line
			(start 1.1049 0.724916)
			(end -1.1049 0.724916)
			(stroke
				(width 0.1)
				(type default)
			)
			(layer "B.Fab")
		)
		(fp_line
			(start 1.1049 -0.724916)
			(end 1.1049 0.724916)
			(stroke
				(width 0.1)
				(type default)
			)
			(layer "B.Fab")
		)
		(fp_line
			(start -1.1049 0.724916)
			(end -1.1049 -0.724916)
			(stroke
				(width 0.1)
				(type default)
			)
			(layer "B.Fab")
		)
		(fp_line
			(start -1.1049 -0.724916)
			(end 1.1049 -0.724916)
			(stroke
				(width 0.1)
				(type default)
			)
			(layer "B.Fab")
		)
		(pad "1" smd rect
			(at 0.889 0 180)
			(size 1.016 1.27)
			(layers "B.Cu" "B.Mask" "B.Paste")
			(net "PVDD18_S5_P0")
		)
		(pad "2" smd rect
			(at -0.889 0 180)
			(size 1.016 1.27)
			(layers "B.Cu" "B.Mask" "B.Paste")
			(net "GND")
		)
	)
	(footprint ""
		(layer "B.Cu")
		(at 75.473814 -9.50468 180)
		(property "Reference" "R3174"
			(at 0 0 0)
			(layer "B.SilkS")
			(hide yes)
			(effects
				(font
					(size 1.27 1.27)
				)
				(justify mirror)
			)
		)
		(property "Value" ""
			(at 0 0 0)
			(layer "B.Fab")
			(effects
				(font
					(size 1.27 1.27)
				)
				(justify mirror)
			)
		)
		(duplicate_pad_numbers_are_jumpers no)
		(fp_line
			(start 0.7874 0.4064)
			(end 0.7874 -0.4064)
			(stroke
				(width 0.1524)
				(type default)
			)
			(layer "B.SilkS")
		)
		(fp_line
			(start 0.7874 -0.4064)
			(end -0.7874 -0.4064)
			(stroke
				(width 0.1524)
				(type default)
			)
			(layer "B.SilkS")
		)
		(fp_line
			(start -0.7874 0.4064)
			(end 0.7874 0.4064)
			(stroke
				(width 0.1524)
				(type default)
			)
			(layer "B.SilkS")
		)
		(fp_line
			(start -0.7874 -0.4064)
			(end -0.7874 0.4064)
			(stroke
				(width 0.1524)
				(type default)
			)
			(layer "B.SilkS")
		)
		(fp_line
			(start 0.67945 0.3048)
			(end 0.67945 -0.305054)
			(stroke
				(width 0.1)
				(type default)
			)
			(layer "B.Fab")
		)
		(fp_line
			(start 0.67945 -0.305054)
			(end 0.12065 -0.305054)
			(stroke
				(width 0.1)
				(type default)
			)
			(layer "B.Fab")
		)
		(fp_line
			(start 0.12065 0.3048)
			(end 0.67945 0.3048)
			(stroke
				(width 0.1)
				(type default)
			)
			(layer "B.Fab")
		)
		(fp_line
			(start 0.12065 0.2794)
			(end 0.12065 0.3048)
			(stroke
				(width 0.1)
				(type default)
			)
			(layer "B.Fab")
		)
		(fp_line
			(start 0.12065 -0.2794)
			(end -0.12065 -0.2794)
			(stroke
				(width 0.1)
				(type default)
			)
			(layer "B.Fab")
		)
		(fp_line
			(start 0.12065 -0.305054)
			(end 0.12065 -0.2794)
			(stroke
				(width 0.1)
				(type default)
			)
			(layer "B.Fab")
		)
		(fp_line
			(start -0.120396 0.3048)
			(end -0.120396 0.2794)
			(stroke
				(width 0.1)
				(type default)
			)
			(layer "B.Fab")
		)
		(fp_line
			(start -0.120396 0.2794)
			(end 0.12065 0.2794)
			(stroke
				(width 0.1)
				(type default)
			)
			(layer "B.Fab")
		)
		(fp_line
			(start -0.12065 -0.2794)
			(end -0.12065 -0.3048)
			(stroke
				(width 0.1)
				(type default)
			)
			(layer "B.Fab")
		)
		(fp_line
			(start -0.12065 -0.3048)
			(end -0.67945 -0.3048)
			(stroke
				(width 0.1)
				(type default)
			)
			(layer "B.Fab")
		)
		(fp_line
			(start -0.67945 0.3048)
			(end -0.120396 0.3048)
			(stroke
				(width 0.1)
				(type default)
			)
			(layer "B.Fab")
		)
		(fp_line
			(start -0.67945 -0.3048)
			(end -0.67945 0.3048)
			(stroke
				(width 0.1)
				(type default)
			)
			(layer "B.Fab")
		)
		(pad "1" smd circle
			(at 0.40005 0)
			(size 0 0)
			(layers "B.Cu" "B.Mask" "B.Paste")
			(net "SGPIO_OCP_V3_2_DATAIN")
		)
		(pad "2" smd circle
			(at -0.40005 0)
			(size 0 0)
			(layers "B.Cu" "B.Mask" "B.Paste")
			(net "P3V3_OCP_V3_2")
		)
	)
	(footprint ""
		(layer "B.Cu")
		(at 286.893 -425.958 -90)
		(property "Reference" "R2725"
			(at 0 0 90)
			(layer "B.SilkS")
			(hide yes)
			(effects
				(font
					(size 1.27 1.27)
				)
				(justify mirror)
			)
		)
		(property "Value" ""
			(at 0 0 90)
			(layer "B.Fab")
			(effects
				(font
					(size 1.27 1.27)
				)
				(justify mirror)
			)
		)
		(duplicate_pad_numbers_are_jumpers no)
		(fp_line
			(start -0.7874 0.4064)
			(end 0.7874 0.4064)
			(stroke
				(width 0.1524)
				(type default)
			)
			(layer "B.SilkS")
		)
		(fp_line
			(start 0.7874 0.4064)
			(end 0.7874 -0.4064)
			(stroke
				(width 0.1524)
				(type default)
			)
			(layer "B.SilkS")
		)
		(fp_line
			(start -0.7874 -0.4064)
			(end -0.7874 0.4064)
			(stroke
				(width 0.1524)
				(type default)
			)
			(layer "B.SilkS")
		)
		(fp_line
			(start 0.7874 -0.4064)
			(end -0.7874 -0.4064)
			(stroke
				(width 0.1524)
				(type default)
			)
			(layer "B.SilkS")
		)
		(fp_line
			(start -0.67945 0.3048)
			(end -0.120396 0.3048)
			(stroke
				(width 0.1)
				(type default)
			)
			(layer "B.Fab")
		)
		(fp_line
			(start -0.120396 0.3048)
			(end -0.120396 0.2794)
			(stroke
				(width 0.1)
				(type default)
			)
			(layer "B.Fab")
		)
		(fp_line
			(start 0.12065 0.3048)
			(end 0.67945 0.3048)
			(stroke
				(width 0.1)
				(type default)
			)
			(layer "B.Fab")
		)
		(fp_line
			(start 0.67945 0.3048)
			(end 0.67945 -0.305054)
			(stroke
				(width 0.1)
				(type default)
			)
			(layer "B.Fab")
		)
		(fp_line
			(start -0.120396 0.2794)
			(end 0.12065 0.2794)
			(stroke
				(width 0.1)
				(type default)
			)
			(layer "B.Fab")
		)
		(fp_line
			(start 0.12065 0.2794)
			(end 0.12065 0.3048)
			(stroke
				(width 0.1)
				(type default)
			)
			(layer "B.Fab")
		)
		(fp_line
			(start -0.12065 -0.2794)
			(end -0.12065 -0.3048)
			(stroke
				(width 0.1)
				(type default)
			)
			(layer "B.Fab")
		)
		(fp_line
			(start 0.12065 -0.2794)
			(end -0.12065 -0.2794)
			(stroke
				(width 0.1)
				(type default)
			)
			(layer "B.Fab")
		)
		(fp_line
			(start -0.67945 -0.3048)
			(end -0.67945 0.3048)
			(stroke
				(width 0.1)
				(type default)
			)
			(layer "B.Fab")
		)
		(fp_line
			(start -0.12065 -0.3048)
			(end -0.67945 -0.3048)
			(stroke
				(width 0.1)
				(type default)
			)
			(layer "B.Fab")
		)
		(fp_line
			(start 0.12065 -0.305054)
			(end 0.12065 -0.2794)
			(stroke
				(width 0.1)
				(type default)
			)
			(layer "B.Fab")
		)
		(fp_line
			(start 0.67945 -0.305054)
			(end 0.12065 -0.305054)
			(stroke
				(width 0.1)
				(type default)
			)
			(layer "B.Fab")
		)
		(pad "1" smd circle
			(at 0.40005 0 90)
			(size 0 0)
			(layers "B.Cu" "B.Mask" "B.Paste")
			(net "I3C_BMC_SWB_R_SCL")
		)
		(pad "2" smd circle
			(at -0.40005 0 90)
			(size 0 0)
			(layers "B.Cu" "B.Mask" "B.Paste")
			(net "I3C_BMC_SWB_BUF_R_SCL")
		)
	)
	(footprint ""
		(layer "B.Cu")
		(at 299.905928 -339.885528 -90)
		(property "Reference" "PC162"
			(at 9.619996 -0.997966 270)
			(unlocked yes)
			(layer "B.SilkS")
			(effects
				(font
					(size 0.7874 0.5842)
					(thickness 0.1524)
				)
				(justify left mirror)
			)
		)
		(property "Value" ""
			(at 0 0 90)
			(layer "B.Fab")
			(effects
				(font
					(size 1.27 1.27)
				)
				(justify mirror)
			)
		)
		(duplicate_pad_numbers_are_jumpers no)
		(fp_line
			(start -4.533392 2.249932)
			(end 4.533392 2.249932)
			(stroke
				(width 0.1524)
				(type default)
			)
			(layer "B.SilkS")
		)
		(fp_line
			(start 4.533392 2.249932)
			(end 4.533392 -2.249932)
			(stroke
				(width 0.1524)
				(type default)
			)
			(layer "B.SilkS")
		)
		(fp_line
			(start -4.533392 -2.249932)
			(end -4.533392 2.249932)
			(stroke
				(width 0.1524)
				(type default)
			)
			(layer "B.SilkS")
		)
		(fp_line
			(start 4.533392 -2.249932)
			(end -4.533392 -2.249932)
			(stroke
				(width 0.1524)
				(type default)
			)
			(layer "B.SilkS")
		)
		(fp_rect
			(start 5.39242 2.326132)
			(end 4.533392 -2.326132)
			(stroke
				(width 0)
				(type default)
			)
			(fill yes)
			(layer "B.SilkS")
		)
		(fp_line
			(start -3.750056 2.249932)
			(end 3.750056 2.249932)
			(stroke
				(width 0.1)
				(type default)
			)
			(layer "B.Fab")
		)
		(fp_line
			(start 3.750056 2.249932)
			(end 3.750056 -2.249932)
			(stroke
				(width 0.1)
				(type default)
			)
			(layer "B.Fab")
		)
		(fp_line
			(start -3.750056 -2.249932)
			(end -3.750056 2.249932)
			(stroke
				(width 0.1)
				(type default)
			)
			(layer "B.Fab")
		)
		(fp_line
			(start 3.750056 -2.249932)
			(end -3.750056 -2.249932)
			(stroke
				(width 0.1)
				(type default)
			)
			(layer "B.Fab")
		)
		(fp_text user "-"
			(at -4.607814 2.00787 270)
			(unlocked yes)
			(layer "B.SilkS")
			(effects
				(font
					(size 1.905 1.4224)
					(thickness 0.1524)
				)
				(justify left mirror)
			)
		)
		(fp_text user "+"
			(at 6.322314 0.786384 180)
			(unlocked yes)
			(layer "B.SilkS")
			(effects
				(font
					(size 1.905 1.4224)
					(thickness 0.1524)
				)
				(justify left mirror)
			)
		)
		(fp_text user "+"
			(at 6.322314 0.786384 180)
			(unlocked yes)
			(layer "B.Fab")
			(effects
				(font
					(size 1.905 1.4224)
					(thickness 0.1524)
				)
				(justify left mirror)
			)
		)
		(fp_text user "-"
			(at -4.8514 -0.14605 270)
			(unlocked yes)
			(layer "B.Fab")
			(effects
				(font
					(size 1.905 1.4224)
					(thickness 0.1524)
				)
				(justify left mirror)
			)
		)
		(pad "1" smd rect
			(at 3.199892 0 90)
			(size 2.413 2.8194)
			(layers "B.Cu" "B.Mask" "B.Paste")
			(net "PVDDIO_P0")
		)
		(pad "2" smd rect
			(at -3.199892 0 90)
			(size 2.413 2.8194)
			(layers "B.Cu" "B.Mask" "B.Paste")
			(net "GND")
		)
	)
	(footprint ""
		(layer "B.Cu")
		(at 308.379876 -66.708782 90)
		(property "Reference" "R6246"
			(at 0 0 90)
			(layer "B.SilkS")
			(hide yes)
			(effects
				(font
					(size 1.27 1.27)
				)
				(justify mirror)
			)
		)
		(property "Value" ""
			(at 0 0 90)
			(layer "B.Fab")
			(effects
				(font
					(size 1.27 1.27)
				)
				(justify mirror)
			)
		)
		(duplicate_pad_numbers_are_jumpers no)
		(fp_line
			(start 0.7874 -0.4064)
			(end -0.7874 -0.4064)
			(stroke
				(width 0.1524)
				(type default)
			)
			(layer "B.SilkS")
		)
		(fp_line
			(start -0.7874 -0.4064)
			(end -0.7874 0.4064)
			(stroke
				(width 0.1524)
				(type default)
			)
			(layer "B.SilkS")
		)
		(fp_line
			(start 0.7874 0.4064)
			(end 0.7874 -0.4064)
			(stroke
				(width 0.1524)
				(type default)
			)
			(layer "B.SilkS")
		)
		(fp_line
			(start -0.7874 0.4064)
			(end 0.7874 0.4064)
			(stroke
				(width 0.1524)
				(type default)
			)
			(layer "B.SilkS")
		)
		(fp_line
			(start 0.67945 -0.305054)
			(end 0.12065 -0.305054)
			(stroke
				(width 0.1)
				(type default)
			)
			(layer "B.Fab")
		)
		(fp_line
			(start 0.12065 -0.305054)
			(end 0.12065 -0.2794)
			(stroke
				(width 0.1)
				(type default)
			)
			(layer "B.Fab")
		)
		(fp_line
			(start -0.12065 -0.3048)
			(end -0.67945 -0.3048)
			(stroke
				(width 0.1)
				(type default)
			)
			(layer "B.Fab")
		)
		(fp_line
			(start -0.67945 -0.3048)
			(end -0.67945 0.3048)
			(stroke
				(width 0.1)
				(type default)
			)
			(layer "B.Fab")
		)
		(fp_line
			(start 0.12065 -0.2794)
			(end -0.12065 -0.2794)
			(stroke
				(width 0.1)
				(type default)
			)
			(layer "B.Fab")
		)
		(fp_line
			(start -0.12065 -0.2794)
			(end -0.12065 -0.3048)
			(stroke
				(width 0.1)
				(type default)
			)
			(layer "B.Fab")
		)
		(fp_line
			(start 0.12065 0.2794)
			(end 0.12065 0.3048)
			(stroke
				(width 0.1)
				(type default)
			)
			(layer "B.Fab")
		)
		(fp_line
			(start -0.120396 0.2794)
			(end 0.12065 0.2794)
			(stroke
				(width 0.1)
				(type default)
			)
			(layer "B.Fab")
		)
		(fp_line
			(start 0.67945 0.3048)
			(end 0.67945 -0.305054)
			(stroke
				(width 0.1)
				(type default)
			)
			(layer "B.Fab")
		)
		(fp_line
			(start 0.12065 0.3048)
			(end 0.67945 0.3048)
			(stroke
				(width 0.1)
				(type default)
			)
			(layer "B.Fab")
		)
		(fp_line
			(start -0.120396 0.3048)
			(end -0.120396 0.2794)
			(stroke
				(width 0.1)
				(type default)
			)
			(layer "B.Fab")
		)
		(fp_line
			(start -0.67945 0.3048)
			(end -0.120396 0.3048)
			(stroke
				(width 0.1)
				(type default)
			)
			(layer "B.Fab")
		)
		(pad "1" smd circle
			(at 0.40005 0 270)
			(size 0 0)
			(layers "B.Cu" "B.Mask" "B.Paste")
			(net "LED_PWRGD_P1V2_AUX")
		)
		(pad "2" smd circle
			(at -0.40005 0 270)
			(size 0 0)
			(layers "B.Cu" "B.Mask" "B.Paste")
			(net "P3V3_AUX")
		)
	)
	(footprint ""
		(layer "B.Cu")
		(at 163.423092 -417.295584)
		(property "Reference" "R1200"
			(at 0 0 0)
			(layer "B.SilkS")
			(hide yes)
			(effects
				(font
					(size 1.27 1.27)
				)
				(justify mirror)
			)
		)
		(property "Value" ""
			(at 0 0 0)
			(layer "B.Fab")
			(effects
				(font
					(size 1.27 1.27)
				)
				(justify mirror)
			)
		)
		(duplicate_pad_numbers_are_jumpers no)
		(fp_line
			(start -0.32512 -0.175006)
			(end -0.32512 0.175006)
			(stroke
				(width 0.1)
				(type default)
			)
			(layer "B.Fab")
		)
		(fp_line
			(start -0.32512 0.175006)
			(end 0.32512 0.175006)
			(stroke
				(width 0.1)
				(type default)
			)
			(layer "B.Fab")
		)
		(fp_line
			(start 0.32512 -0.175006)
			(end -0.32512 -0.175006)
			(stroke
				(width 0.1)
				(type default)
			)
			(layer "B.Fab")
		)
		(fp_line
			(start 0.32512 0.175006)
			(end 0.32512 -0.175006)
			(stroke
				(width 0.1)
				(type default)
			)
			(layer "B.Fab")
		)
		(pad "1" smd rect
			(at 0.2667 0 180)
			(size 0.3048 0.381)
			(layers "B.Cu" "B.Mask" "B.Paste")
			(net "RST_SMB_RT_ROM_R1_N")
		)
		(pad "2" smd rect
			(at -0.2667 0)
			(size 0.3048 0.381)
			(layers "B.Cu" "B.Mask" "B.Paste")
			(net "FM_SMB_RT_ROM_MUX4_SEL")
		)
	)
	(footprint ""
		(layer "B.Cu")
		(at 187.585096 -353.986084 -90)
		(property "Reference" "PR333"
			(at 0 0 90)
			(layer "B.SilkS")
			(hide yes)
			(effects
				(font
					(size 1.27 1.27)
				)
				(justify mirror)
			)
		)
		(property "Value" ""
			(at 0 0 90)
			(layer "B.Fab")
			(effects
				(font
					(size 1.27 1.27)
				)
				(justify mirror)
			)
		)
		(duplicate_pad_numbers_are_jumpers no)
		(fp_line
			(start -0.7874 0.4064)
			(end 0.7874 0.4064)
			(stroke
				(width 0.1524)
				(type default)
			)
			(layer "B.SilkS")
		)
		(fp_line
			(start 0.7874 0.4064)
			(end 0.7874 -0.4064)
			(stroke
				(width 0.1524)
				(type default)
			)
			(layer "B.SilkS")
		)
		(fp_line
			(start -0.7874 -0.4064)
			(end -0.7874 0.4064)
			(stroke
				(width 0.1524)
				(type default)
			)
			(layer "B.SilkS")
		)
		(fp_line
			(start 0.7874 -0.4064)
			(end -0.7874 -0.4064)
			(stroke
				(width 0.1524)
				(type default)
			)
			(layer "B.SilkS")
		)
		(fp_line
			(start -0.67945 0.3048)
			(end -0.120396 0.3048)
			(stroke
				(width 0.1)
				(type default)
			)
			(layer "B.Fab")
		)
		(fp_line
			(start -0.120396 0.3048)
			(end -0.120396 0.2794)
			(stroke
				(width 0.1)
				(type default)
			)
			(layer "B.Fab")
		)
		(fp_line
			(start 0.12065 0.3048)
			(end 0.67945 0.3048)
			(stroke
				(width 0.1)
				(type default)
			)
			(layer "B.Fab")
		)
		(fp_line
			(start 0.67945 0.3048)
			(end 0.67945 -0.305054)
			(stroke
				(width 0.1)
				(type default)
			)
			(layer "B.Fab")
		)
		(fp_line
			(start -0.120396 0.2794)
			(end 0.12065 0.2794)
			(stroke
				(width 0.1)
				(type default)
			)
			(layer "B.Fab")
		)
		(fp_line
			(start 0.12065 0.2794)
			(end 0.12065 0.3048)
			(stroke
				(width 0.1)
				(type default)
			)
			(layer "B.Fab")
		)
		(fp_line
			(start -0.12065 -0.2794)
			(end -0.12065 -0.3048)
			(stroke
				(width 0.1)
				(type default)
			)
			(layer "B.Fab")
		)
		(fp_line
			(start 0.12065 -0.2794)
			(end -0.12065 -0.2794)
			(stroke
				(width 0.1)
				(type default)
			)
			(layer "B.Fab")
		)
		(fp_line
			(start -0.67945 -0.3048)
			(end -0.67945 0.3048)
			(stroke
				(width 0.1)
				(type default)
			)
			(layer "B.Fab")
		)
		(fp_line
			(start -0.12065 -0.3048)
			(end -0.67945 -0.3048)
			(stroke
				(width 0.1)
				(type default)
			)
			(layer "B.Fab")
		)
		(fp_line
			(start 0.12065 -0.305054)
			(end 0.12065 -0.2794)
			(stroke
				(width 0.1)
				(type default)
			)
			(layer "B.Fab")
		)
		(fp_line
			(start 0.67945 -0.305054)
			(end 0.12065 -0.305054)
			(stroke
				(width 0.1)
				(type default)
			)
			(layer "B.Fab")
		)
		(pad "1" smd circle
			(at 0.40005 0 90)
			(size 0 0)
			(layers "B.Cu" "B.Mask" "B.Paste")
			(net "PVDD11_S3_P1_VOS2")
		)
		(pad "2" smd circle
			(at -0.40005 0 90)
			(size 0 0)
			(layers "B.Cu" "B.Mask" "B.Paste")
			(net "PVDD11_S3_P1")
		)
	)
	(footprint ""
		(layer "B.Cu")
		(at 378.957586 -214.523828 90)
		(property "Reference" "R9275"
			(at 0 0 90)
			(layer "B.SilkS")
			(hide yes)
			(effects
				(font
					(size 1.27 1.27)
				)
				(justify mirror)
			)
		)
		(property "Value" ""
			(at 0 0 90)
			(layer "B.Fab")
			(effects
				(font
					(size 1.27 1.27)
				)
				(justify mirror)
			)
		)
		(duplicate_pad_numbers_are_jumpers no)
		(fp_line
			(start 0.360172 -0.4064)
			(end -0.376428 -0.4064)
			(stroke
				(width 0.1524)
				(type default)
			)
			(layer "B.SilkS")
		)
		(fp_line
			(start -0.7874 0.086614)
			(end -0.7874 0.4064)
			(stroke
				(width 0.1524)
				(type default)
			)
			(layer "B.SilkS")
		)
		(fp_line
			(start 0.7874 0.4064)
			(end 0.7874 0.010414)
			(stroke
				(width 0.1524)
				(type default)
			)
			(layer "B.SilkS")
		)
		(fp_line
			(start -0.7874 0.4064)
			(end 0.7874 0.4064)
			(stroke
				(width 0.1524)
				(type default)
			)
			(layer "B.SilkS")
		)
		(fp_line
			(start 0.67945 -0.305054)
			(end 0.12065 -0.305054)
			(stroke
				(width 0.1)
				(type default)
			)
			(layer "B.Fab")
		)
		(fp_line
			(start 0.12065 -0.305054)
			(end 0.12065 -0.2794)
			(stroke
				(width 0.1)
				(type default)
			)
			(layer "B.Fab")
		)
		(fp_line
			(start -0.12065 -0.3048)
			(end -0.67945 -0.3048)
			(stroke
				(width 0.1)
				(type default)
			)
			(layer "B.Fab")
		)
		(fp_line
			(start -0.67945 -0.3048)
			(end -0.67945 0.3048)
			(stroke
				(width 0.1)
				(type default)
			)
			(layer "B.Fab")
		)
		(fp_line
			(start 0.12065 -0.2794)
			(end -0.12065 -0.2794)
			(stroke
				(width 0.1)
				(type default)
			)
			(layer "B.Fab")
		)
		(fp_line
			(start -0.12065 -0.2794)
			(end -0.12065 -0.3048)
			(stroke
				(width 0.1)
				(type default)
			)
			(layer "B.Fab")
		)
		(fp_line
			(start 0.12065 0.2794)
			(end 0.12065 0.3048)
			(stroke
				(width 0.1)
				(type default)
			)
			(layer "B.Fab")
		)
		(fp_line
			(start -0.120396 0.2794)
			(end 0.12065 0.2794)
			(stroke
				(width 0.1)
				(type default)
			)
			(layer "B.Fab")
		)
		(fp_line
			(start 0.67945 0.3048)
			(end 0.67945 -0.305054)
			(stroke
				(width 0.1)
				(type default)
			)
			(layer "B.Fab")
		)
		(fp_line
			(start 0.12065 0.3048)
			(end 0.67945 0.3048)
			(stroke
				(width 0.1)
				(type default)
			)
			(layer "B.Fab")
		)
		(fp_line
			(start -0.120396 0.3048)
			(end -0.120396 0.2794)
			(stroke
				(width 0.1)
				(type default)
			)
			(layer "B.Fab")
		)
		(fp_line
			(start -0.67945 0.3048)
			(end -0.120396 0.3048)
			(stroke
				(width 0.1)
				(type default)
			)
			(layer "B.Fab")
		)
		(pad "1" smd circle
			(at 0.40005 0 270)
			(size 0 0)
			(layers "B.Cu" "B.Mask" "B.Paste")
			(net "CLK_100M_CPU0_CLK05_R_DP")
		)
		(pad "2" smd circle
			(at -0.40005 0 270)
			(size 0 0)
			(layers "B.Cu" "B.Mask" "B.Paste")
			(net "CLK_100M_CPU0_CLK05_DP")
		)
	)
	(footprint ""
		(layer "B.Cu")
		(at 392.695938 -195.830952 90)
		(property "Reference" "PC563_4"
			(at 0 0 90)
			(layer "B.SilkS")
			(hide yes)
			(effects
				(font
					(size 1.27 1.27)
				)
				(justify mirror)
			)
		)
		(property "Value" ""
			(at 0 0 90)
			(layer "B.Fab")
			(effects
				(font
					(size 1.27 1.27)
				)
				(justify mirror)
			)
		)
		(duplicate_pad_numbers_are_jumpers no)
		(fp_line
			(start 1.524 -0.762)
			(end -1.524 -0.762)
			(stroke
				(width 0.1524)
				(type default)
			)
			(layer "B.SilkS")
		)
		(fp_line
			(start -1.524 -0.762)
			(end -1.524 0.762)
			(stroke
				(width 0.1524)
				(type default)
			)
			(layer "B.SilkS")
		)
		(fp_line
			(start 1.524 0.762)
			(end 1.524 -0.762)
			(stroke
				(width 0.1524)
				(type default)
			)
			(layer "B.SilkS")
		)
		(fp_line
			(start -1.524 0.762)
			(end 1.524 0.762)
			(stroke
				(width 0.1524)
				(type default)
			)
			(layer "B.SilkS")
		)
		(fp_line
			(start 1.1049 -0.724916)
			(end 1.1049 0.724916)
			(stroke
				(width 0.1)
				(type default)
			)
			(layer "B.Fab")
		)
		(fp_line
			(start -1.1049 -0.724916)
			(end 1.1049 -0.724916)
			(stroke
				(width 0.1)
				(type default)
			)
			(layer "B.Fab")
		)
		(fp_line
			(start 1.1049 0.724916)
			(end -1.1049 0.724916)
			(stroke
				(width 0.1)
				(type default)
			)
			(layer "B.Fab")
		)
		(fp_line
			(start -1.1049 0.724916)
			(end -1.1049 -0.724916)
			(stroke
				(width 0.1)
				(type default)
			)
			(layer "B.Fab")
		)
		(pad "1" smd rect
			(at 0.889 0 90)
			(size 1.016 1.27)
			(layers "B.Cu" "B.Mask" "B.Paste")
			(net "PVDDCR_CPU0_P0")
		)
		(pad "2" smd rect
			(at -0.889 0 90)
			(size 1.016 1.27)
			(layers "B.Cu" "B.Mask" "B.Paste")
			(net "GND")
		)
	)
	(footprint ""
		(layer "B.Cu")
		(at 369.570254 -249.36831)
		(property "Reference" "C2177"
			(at 0 0 0)
			(layer "B.SilkS")
			(hide yes)
			(effects
				(font
					(size 1.27 1.27)
				)
				(justify mirror)
			)
		)
		(property "Value" ""
			(at 0 0 0)
			(layer "B.Fab")
			(effects
				(font
					(size 1.27 1.27)
				)
				(justify mirror)
			)
		)
		(duplicate_pad_numbers_are_jumpers no)
		(fp_line
			(start -0.7874 -0.4064)
			(end -0.7874 0.4064)
			(stroke
				(width 0.1524)
				(type default)
			)
			(layer "B.SilkS")
		)
		(fp_line
			(start -0.7874 0.4064)
			(end 0.7874 0.4064)
			(stroke
				(width 0.1524)
				(type default)
			)
			(layer "B.SilkS")
		)
		(fp_line
			(start 0.7874 -0.4064)
			(end -0.7874 -0.4064)
			(stroke
				(width 0.1524)
				(type default)
			)
			(layer "B.SilkS")
		)
		(fp_line
			(start 0.7874 0.4064)
			(end 0.7874 -0.4064)
			(stroke
				(width 0.1524)
				(type default)
			)
			(layer "B.SilkS")
		)
		(fp_line
			(start -0.67945 -0.3048)
			(end -0.67945 0.3048)
			(stroke
				(width 0.1)
				(type default)
			)
			(layer "B.Fab")
		)
		(fp_line
			(start -0.67945 0.3048)
			(end -0.120396 0.3048)
			(stroke
				(width 0.1)
				(type default)
			)
			(layer "B.Fab")
		)
		(fp_line
			(start -0.12065 -0.3048)
			(end -0.67945 -0.3048)
			(stroke
				(width 0.1)
				(type default)
			)
			(layer "B.Fab")
		)
		(fp_line
			(start -0.12065 -0.2794)
			(end -0.12065 -0.3048)
			(stroke
				(width 0.1)
				(type default)
			)
			(layer "B.Fab")
		)
		(fp_line
			(start -0.120396 0.2794)
			(end 0.12065 0.2794)
			(stroke
				(width 0.1)
				(type default)
			)
			(layer "B.Fab")
		)
		(fp_line
			(start -0.120396 0.3048)
			(end -0.120396 0.2794)
			(stroke
				(width 0.1)
				(type default)
			)
			(layer "B.Fab")
		)
		(fp_line
			(start 0.12065 -0.305054)
			(end 0.12065 -0.2794)
			(stroke
				(width 0.1)
				(type default)
			)
			(layer "B.Fab")
		)
		(fp_line
			(start 0.12065 -0.2794)
			(end -0.12065 -0.2794)
			(stroke
				(width 0.1)
				(type default)
			)
			(layer "B.Fab")
		)
		(fp_line
			(start 0.12065 0.2794)
			(end 0.12065 0.3048)
			(stroke
				(width 0.1)
				(type default)
			)
			(layer "B.Fab")
		)
		(fp_line
			(start 0.12065 0.3048)
			(end 0.67945 0.3048)
			(stroke
				(width 0.1)
				(type default)
			)
			(layer "B.Fab")
		)
		(fp_line
			(start 0.67945 -0.305054)
			(end 0.12065 -0.305054)
			(stroke
				(width 0.1)
				(type default)
			)
			(layer "B.Fab")
		)
		(fp_line
			(start 0.67945 0.3048)
			(end 0.67945 -0.305054)
			(stroke
				(width 0.1)
				(type default)
			)
			(layer "B.Fab")
		)
		(pad "1" smd circle
			(at 0.40005 0 180)
			(size 0 0)
			(layers "B.Cu" "B.Mask" "B.Paste")
			(net "PVDDCR_CPU0_P0")
		)
		(pad "2" smd circle
			(at -0.40005 0 180)
			(size 0 0)
			(layers "B.Cu" "B.Mask" "B.Paste")
			(net "GND")
		)
	)
	(footprint ""
		(layer "B.Cu")
		(at 421.00627 -395.148562 90)
		(property "Reference" "C786"
			(at 0 0 90)
			(layer "B.SilkS")
			(hide yes)
			(effects
				(font
					(size 1.27 1.27)
				)
				(justify mirror)
			)
		)
		(property "Value" ""
			(at 0 0 90)
			(layer "B.Fab")
			(effects
				(font
					(size 1.27 1.27)
				)
				(justify mirror)
			)
		)
		(duplicate_pad_numbers_are_jumpers no)
		(fp_line
			(start 0.299974 -0.150114)
			(end -0.299974 -0.150114)
			(stroke
				(width 0.1)
				(type default)
			)
			(layer "B.Fab")
		)
		(fp_line
			(start -0.299974 -0.150114)
			(end -0.299974 0.150114)
			(stroke
				(width 0.1)
				(type default)
			)
			(layer "B.Fab")
		)
		(fp_line
			(start 0.299974 0.150114)
			(end 0.299974 -0.150114)
			(stroke
				(width 0.1)
				(type default)
			)
			(layer "B.Fab")
		)
		(fp_line
			(start -0.299974 0.150114)
			(end 0.299974 0.150114)
			(stroke
				(width 0.1)
				(type default)
			)
			(layer "B.Fab")
		)
		(pad "1" smd rect
			(at 0.2667 0 270)
			(size 0.3048 0.381)
			(layers "B.Cu" "B.Mask" "B.Paste")
			(net "P0V9_CPU0_RT2_2A")
		)
		(pad "2" smd rect
			(at -0.2667 0 270)
			(size 0.3048 0.381)
			(layers "B.Cu" "B.Mask" "B.Paste")
			(net "GND")
		)
	)
	(footprint ""
		(layer "B.Cu")
		(at 83.460844 -337.643724 -90)
		(property "Reference" "PR261"
			(at 0 0 90)
			(layer "B.SilkS")
			(hide yes)
			(effects
				(font
					(size 1.27 1.27)
				)
				(justify mirror)
			)
		)
		(property "Value" ""
			(at 0 0 90)
			(layer "B.Fab")
			(effects
				(font
					(size 1.27 1.27)
				)
				(justify mirror)
			)
		)
		(duplicate_pad_numbers_are_jumpers no)
		(fp_line
			(start -0.7874 0.4064)
			(end 0.7874 0.4064)
			(stroke
				(width 0.1524)
				(type default)
			)
			(layer "B.SilkS")
		)
		(fp_line
			(start 0.7874 0.4064)
			(end 0.7874 -0.4064)
			(stroke
				(width 0.1524)
				(type default)
			)
			(layer "B.SilkS")
		)
		(fp_line
			(start -0.7874 -0.4064)
			(end -0.7874 0.4064)
			(stroke
				(width 0.1524)
				(type default)
			)
			(layer "B.SilkS")
		)
		(fp_line
			(start 0.7874 -0.4064)
			(end -0.7874 -0.4064)
			(stroke
				(width 0.1524)
				(type default)
			)
			(layer "B.SilkS")
		)
		(fp_line
			(start -0.67945 0.3048)
			(end -0.120396 0.3048)
			(stroke
				(width 0.1)
				(type default)
			)
			(layer "B.Fab")
		)
		(fp_line
			(start -0.120396 0.3048)
			(end -0.120396 0.2794)
			(stroke
				(width 0.1)
				(type default)
			)
			(layer "B.Fab")
		)
		(fp_line
			(start 0.12065 0.3048)
			(end 0.67945 0.3048)
			(stroke
				(width 0.1)
				(type default)
			)
			(layer "B.Fab")
		)
		(fp_line
			(start 0.67945 0.3048)
			(end 0.67945 -0.305054)
			(stroke
				(width 0.1)
				(type default)
			)
			(layer "B.Fab")
		)
		(fp_line
			(start -0.120396 0.2794)
			(end 0.12065 0.2794)
			(stroke
				(width 0.1)
				(type default)
			)
			(layer "B.Fab")
		)
		(fp_line
			(start 0.12065 0.2794)
			(end 0.12065 0.3048)
			(stroke
				(width 0.1)
				(type default)
			)
			(layer "B.Fab")
		)
		(fp_line
			(start -0.12065 -0.2794)
			(end -0.12065 -0.3048)
			(stroke
				(width 0.1)
				(type default)
			)
			(layer "B.Fab")
		)
		(fp_line
			(start 0.12065 -0.2794)
			(end -0.12065 -0.2794)
			(stroke
				(width 0.1)
				(type default)
			)
			(layer "B.Fab")
		)
		(fp_line
			(start -0.67945 -0.3048)
			(end -0.67945 0.3048)
			(stroke
				(width 0.1)
				(type default)
			)
			(layer "B.Fab")
		)
		(fp_line
			(start -0.12065 -0.3048)
			(end -0.67945 -0.3048)
			(stroke
				(width 0.1)
				(type default)
			)
			(layer "B.Fab")
		)
		(fp_line
			(start 0.12065 -0.305054)
			(end 0.12065 -0.2794)
			(stroke
				(width 0.1)
				(type default)
			)
			(layer "B.Fab")
		)
		(fp_line
			(start 0.67945 -0.305054)
			(end 0.12065 -0.305054)
			(stroke
				(width 0.1)
				(type default)
			)
			(layer "B.Fab")
		)
		(pad "1" smd circle
			(at 0.40005 0 90)
			(size 0 0)
			(layers "B.Cu" "B.Mask" "B.Paste")
			(net "PVDDCR_CPU1_P1_VOS1")
		)
		(pad "2" smd circle
			(at -0.40005 0 90)
			(size 0 0)
			(layers "B.Cu" "B.Mask" "B.Paste")
			(net "PVDDCR_CPU1_P1")
		)
	)
	(footprint ""
		(layer "B.Cu")
		(at 130.657092 -49.502822 -90)
		(property "Reference" "R6066"
			(at 0 0 90)
			(layer "B.SilkS")
			(hide yes)
			(effects
				(font
					(size 1.27 1.27)
				)
				(justify mirror)
			)
		)
		(property "Value" ""
			(at 0 0 90)
			(layer "B.Fab")
			(effects
				(font
					(size 1.27 1.27)
				)
				(justify mirror)
			)
		)
		(duplicate_pad_numbers_are_jumpers no)
		(fp_line
			(start -0.7874 0.4064)
			(end 0.7874 0.4064)
			(stroke
				(width 0.1524)
				(type default)
			)
			(layer "B.SilkS")
		)
		(fp_line
			(start 0.7874 0.4064)
			(end 0.7874 -0.4064)
			(stroke
				(width 0.1524)
				(type default)
			)
			(layer "B.SilkS")
		)
		(fp_line
			(start -0.7874 -0.4064)
			(end -0.7874 0.4064)
			(stroke
				(width 0.1524)
				(type default)
			)
			(layer "B.SilkS")
		)
		(fp_line
			(start 0.7874 -0.4064)
			(end -0.7874 -0.4064)
			(stroke
				(width 0.1524)
				(type default)
			)
			(layer "B.SilkS")
		)
		(fp_line
			(start -0.67945 0.3048)
			(end -0.120396 0.3048)
			(stroke
				(width 0.1)
				(type default)
			)
			(layer "B.Fab")
		)
		(fp_line
			(start -0.120396 0.3048)
			(end -0.120396 0.2794)
			(stroke
				(width 0.1)
				(type default)
			)
			(layer "B.Fab")
		)
		(fp_line
			(start 0.12065 0.3048)
			(end 0.67945 0.3048)
			(stroke
				(width 0.1)
				(type default)
			)
			(layer "B.Fab")
		)
		(fp_line
			(start 0.67945 0.3048)
			(end 0.67945 -0.305054)
			(stroke
				(width 0.1)
				(type default)
			)
			(layer "B.Fab")
		)
		(fp_line
			(start -0.120396 0.2794)
			(end 0.12065 0.2794)
			(stroke
				(width 0.1)
				(type default)
			)
			(layer "B.Fab")
		)
		(fp_line
			(start 0.12065 0.2794)
			(end 0.12065 0.3048)
			(stroke
				(width 0.1)
				(type default)
			)
			(layer "B.Fab")
		)
		(fp_line
			(start -0.12065 -0.2794)
			(end -0.12065 -0.3048)
			(stroke
				(width 0.1)
				(type default)
			)
			(layer "B.Fab")
		)
		(fp_line
			(start 0.12065 -0.2794)
			(end -0.12065 -0.2794)
			(stroke
				(width 0.1)
				(type default)
			)
			(layer "B.Fab")
		)
		(fp_line
			(start -0.67945 -0.3048)
			(end -0.67945 0.3048)
			(stroke
				(width 0.1)
				(type default)
			)
			(layer "B.Fab")
		)
		(fp_line
			(start -0.12065 -0.3048)
			(end -0.67945 -0.3048)
			(stroke
				(width 0.1)
				(type default)
			)
			(layer "B.Fab")
		)
		(fp_line
			(start 0.12065 -0.305054)
			(end 0.12065 -0.2794)
			(stroke
				(width 0.1)
				(type default)
			)
			(layer "B.Fab")
		)
		(fp_line
			(start 0.67945 -0.305054)
			(end 0.12065 -0.305054)
			(stroke
				(width 0.1)
				(type default)
			)
			(layer "B.Fab")
		)
		(pad "1" smd rect
			(at 0.40005 0 270)
			(size 0.4572 0.508)
			(layers "B.Cu" "B.Mask" "B.Paste")
			(net "JTAG_SCM_TDI_R")
		)
		(pad "2" smd rect
			(at -0.40005 0 270)
			(size 0.4572 0.508)
			(layers "B.Cu" "B.Mask" "B.Paste")
			(net "JTAG_SCM_TDI")
		)
	)
	(footprint ""
		(layer "B.Cu")
		(at 238.633 -336.169 180)
		(property "Reference" "R803"
			(at 0 0 0)
			(layer "B.SilkS")
			(hide yes)
			(effects
				(font
					(size 1.27 1.27)
				)
				(justify mirror)
			)
		)
		(property "Value" ""
			(at 0 0 0)
			(layer "B.Fab")
			(effects
				(font
					(size 1.27 1.27)
				)
				(justify mirror)
			)
		)
		(duplicate_pad_numbers_are_jumpers no)
		(fp_line
			(start 0.32512 0.175006)
			(end 0.32512 -0.175006)
			(stroke
				(width 0.1)
				(type default)
			)
			(layer "B.Fab")
		)
		(fp_line
			(start 0.32512 -0.175006)
			(end -0.32512 -0.175006)
			(stroke
				(width 0.1)
				(type default)
			)
			(layer "B.Fab")
		)
		(fp_line
			(start -0.32512 0.175006)
			(end 0.32512 0.175006)
			(stroke
				(width 0.1)
				(type default)
			)
			(layer "B.Fab")
		)
		(fp_line
			(start -0.32512 -0.175006)
			(end -0.32512 0.175006)
			(stroke
				(width 0.1)
				(type default)
			)
			(layer "B.Fab")
		)
		(pad "1" smd rect
			(at 0.2667 0)
			(size 0.3048 0.381)
			(layers "B.Cu" "B.Mask" "B.Paste")
			(net "SMB_RT_CPU1_P1_ROM_MUX_2D_SDA")
		)
		(pad "2" smd rect
			(at -0.2667 0 180)
			(size 0.3048 0.381)
			(layers "B.Cu" "B.Mask" "B.Paste")
			(net "SMB_RT_CPU1_P1_ROM_MUX_2D_R_SDA")
		)
	)
	(footprint ""
		(layer "B.Cu")
		(at 428.309278 -353.80549 -90)
		(property "Reference" "PR138"
			(at 0 0 90)
			(layer "B.SilkS")
			(hide yes)
			(effects
				(font
					(size 1.27 1.27)
				)
				(justify mirror)
			)
		)
		(property "Value" ""
			(at 0 0 90)
			(layer "B.Fab")
			(effects
				(font
					(size 1.27 1.27)
				)
				(justify mirror)
			)
		)
		(duplicate_pad_numbers_are_jumpers no)
		(fp_line
			(start -0.7874 0.4064)
			(end 0.7874 0.4064)
			(stroke
				(width 0.1524)
				(type default)
			)
			(layer "B.SilkS")
		)
		(fp_line
			(start 0.7874 0.4064)
			(end 0.7874 -0.4064)
			(stroke
				(width 0.1524)
				(type default)
			)
			(layer "B.SilkS")
		)
		(fp_line
			(start -0.7874 -0.4064)
			(end -0.7874 0.4064)
			(stroke
				(width 0.1524)
				(type default)
			)
			(layer "B.SilkS")
		)
		(fp_line
			(start 0.7874 -0.4064)
			(end -0.7874 -0.4064)
			(stroke
				(width 0.1524)
				(type default)
			)
			(layer "B.SilkS")
		)
		(fp_line
			(start -0.67945 0.3048)
			(end -0.120396 0.3048)
			(stroke
				(width 0.1)
				(type default)
			)
			(layer "B.Fab")
		)
		(fp_line
			(start -0.120396 0.3048)
			(end -0.120396 0.2794)
			(stroke
				(width 0.1)
				(type default)
			)
			(layer "B.Fab")
		)
		(fp_line
			(start 0.12065 0.3048)
			(end 0.67945 0.3048)
			(stroke
				(width 0.1)
				(type default)
			)
			(layer "B.Fab")
		)
		(fp_line
			(start 0.67945 0.3048)
			(end 0.67945 -0.305054)
			(stroke
				(width 0.1)
				(type default)
			)
			(layer "B.Fab")
		)
		(fp_line
			(start -0.120396 0.2794)
			(end 0.12065 0.2794)
			(stroke
				(width 0.1)
				(type default)
			)
			(layer "B.Fab")
		)
		(fp_line
			(start 0.12065 0.2794)
			(end 0.12065 0.3048)
			(stroke
				(width 0.1)
				(type default)
			)
			(layer "B.Fab")
		)
		(fp_line
			(start -0.12065 -0.2794)
			(end -0.12065 -0.3048)
			(stroke
				(width 0.1)
				(type default)
			)
			(layer "B.Fab")
		)
		(fp_line
			(start 0.12065 -0.2794)
			(end -0.12065 -0.2794)
			(stroke
				(width 0.1)
				(type default)
			)
			(layer "B.Fab")
		)
		(fp_line
			(start -0.67945 -0.3048)
			(end -0.67945 0.3048)
			(stroke
				(width 0.1)
				(type default)
			)
			(layer "B.Fab")
		)
		(fp_line
			(start -0.12065 -0.3048)
			(end -0.67945 -0.3048)
			(stroke
				(width 0.1)
				(type default)
			)
			(layer "B.Fab")
		)
		(fp_line
			(start 0.12065 -0.305054)
			(end 0.12065 -0.2794)
			(stroke
				(width 0.1)
				(type default)
			)
			(layer "B.Fab")
		)
		(fp_line
			(start 0.67945 -0.305054)
			(end 0.12065 -0.305054)
			(stroke
				(width 0.1)
				(type default)
			)
			(layer "B.Fab")
		)
		(pad "1" smd circle
			(at 0.40005 0 90)
			(size 0 0)
			(layers "B.Cu" "B.Mask" "B.Paste")
			(net "PVDD11_S3_P0_VOS2")
		)
		(pad "2" smd circle
			(at -0.40005 0 90)
			(size 0 0)
			(layers "B.Cu" "B.Mask" "B.Paste")
			(net "PVDD11_S3_P0")
		)
	)
	(footprint ""
		(layer "B.Cu")
		(at 200.952608 -122.769376 180)
		(property "Reference" "R3484"
			(at 0 0 0)
			(layer "B.SilkS")
			(hide yes)
			(effects
				(font
					(size 1.27 1.27)
				)
				(justify mirror)
			)
		)
		(property "Value" ""
			(at 0 0 0)
			(layer "B.Fab")
			(effects
				(font
					(size 1.27 1.27)
				)
				(justify mirror)
			)
		)
		(duplicate_pad_numbers_are_jumpers no)
		(fp_line
			(start 0.7874 0.4064)
			(end 0.7874 -0.4064)
			(stroke
				(width 0.1524)
				(type default)
			)
			(layer "B.SilkS")
		)
		(fp_line
			(start 0.7874 -0.4064)
			(end -0.7874 -0.4064)
			(stroke
				(width 0.1524)
				(type default)
			)
			(layer "B.SilkS")
		)
		(fp_line
			(start -0.7874 0.4064)
			(end 0.7874 0.4064)
			(stroke
				(width 0.1524)
				(type default)
			)
			(layer "B.SilkS")
		)
		(fp_line
			(start -0.7874 -0.4064)
			(end -0.7874 0.4064)
			(stroke
				(width 0.1524)
				(type default)
			)
			(layer "B.SilkS")
		)
		(fp_line
			(start 0.67945 0.3048)
			(end 0.67945 -0.305054)
			(stroke
				(width 0.1)
				(type default)
			)
			(layer "B.Fab")
		)
		(fp_line
			(start 0.67945 -0.305054)
			(end 0.12065 -0.305054)
			(stroke
				(width 0.1)
				(type default)
			)
			(layer "B.Fab")
		)
		(fp_line
			(start 0.12065 0.3048)
			(end 0.67945 0.3048)
			(stroke
				(width 0.1)
				(type default)
			)
			(layer "B.Fab")
		)
		(fp_line
			(start 0.12065 0.2794)
			(end 0.12065 0.3048)
			(stroke
				(width 0.1)
				(type default)
			)
			(layer "B.Fab")
		)
		(fp_line
			(start 0.12065 -0.2794)
			(end -0.12065 -0.2794)
			(stroke
				(width 0.1)
				(type default)
			)
			(layer "B.Fab")
		)
		(fp_line
			(start 0.12065 -0.305054)
			(end 0.12065 -0.2794)
			(stroke
				(width 0.1)
				(type default)
			)
			(layer "B.Fab")
		)
		(fp_line
			(start -0.120396 0.3048)
			(end -0.120396 0.2794)
			(stroke
				(width 0.1)
				(type default)
			)
			(layer "B.Fab")
		)
		(fp_line
			(start -0.120396 0.2794)
			(end 0.12065 0.2794)
			(stroke
				(width 0.1)
				(type default)
			)
			(layer "B.Fab")
		)
		(fp_line
			(start -0.12065 -0.2794)
			(end -0.12065 -0.3048)
			(stroke
				(width 0.1)
				(type default)
			)
			(layer "B.Fab")
		)
		(fp_line
			(start -0.12065 -0.3048)
			(end -0.67945 -0.3048)
			(stroke
				(width 0.1)
				(type default)
			)
			(layer "B.Fab")
		)
		(fp_line
			(start -0.67945 0.3048)
			(end -0.120396 0.3048)
			(stroke
				(width 0.1)
				(type default)
			)
			(layer "B.Fab")
		)
		(fp_line
			(start -0.67945 -0.3048)
			(end -0.67945 0.3048)
			(stroke
				(width 0.1)
				(type default)
			)
			(layer "B.Fab")
		)
		(pad "1" smd circle
			(at 0.40005 0)
			(size 0 0)
			(layers "B.Cu" "B.Mask" "B.Paste")
			(net "GPU_FPGA_OVERT_ISO_R_N")
		)
		(pad "2" smd circle
			(at -0.40005 0)
			(size 0 0)
			(layers "B.Cu" "B.Mask" "B.Paste")
			(net "GPU_FPGA_OVERT_ISO_N")
		)
	)
	(footprint ""
		(layer "B.Cu")
		(at 239.903 -336.169)
		(property "Reference" "R1393"
			(at 0 0 0)
			(layer "B.SilkS")
			(hide yes)
			(effects
				(font
					(size 1.27 1.27)
				)
				(justify mirror)
			)
		)
		(property "Value" ""
			(at 0 0 0)
			(layer "B.Fab")
			(effects
				(font
					(size 1.27 1.27)
				)
				(justify mirror)
			)
		)
		(duplicate_pad_numbers_are_jumpers no)
		(fp_line
			(start -0.32512 -0.175006)
			(end -0.32512 0.175006)
			(stroke
				(width 0.1)
				(type default)
			)
			(layer "B.Fab")
		)
		(fp_line
			(start -0.32512 0.175006)
			(end 0.32512 0.175006)
			(stroke
				(width 0.1)
				(type default)
			)
			(layer "B.Fab")
		)
		(fp_line
			(start 0.32512 -0.175006)
			(end -0.32512 -0.175006)
			(stroke
				(width 0.1)
				(type default)
			)
			(layer "B.Fab")
		)
		(fp_line
			(start 0.32512 0.175006)
			(end 0.32512 -0.175006)
			(stroke
				(width 0.1)
				(type default)
			)
			(layer "B.Fab")
		)
		(pad "1" smd rect
			(at 0.2667 0 180)
			(size 0.3048 0.381)
			(layers "B.Cu" "B.Mask" "B.Paste")
			(net "P1V8_CPU1_RT_1D")
		)
		(pad "2" smd rect
			(at -0.2667 0)
			(size 0.3048 0.381)
			(layers "B.Cu" "B.Mask" "B.Paste")
			(net "SMB_RT_CPU1_P1_ROM_MUX_2D_R_SDA")
		)
	)
	(footprint ""
		(layer "B.Cu")
		(at 284.386528 -339.910928 -90)
		(property "Reference" "PC165"
			(at 9.490456 0.924814 270)
			(unlocked yes)
			(layer "B.SilkS")
			(effects
				(font
					(size 0.7874 0.5842)
					(thickness 0.1524)
				)
				(justify left mirror)
			)
		)
		(property "Value" ""
			(at 0 0 90)
			(layer "B.Fab")
			(effects
				(font
					(size 1.27 1.27)
				)
				(justify mirror)
			)
		)
		(duplicate_pad_numbers_are_jumpers no)
		(fp_line
			(start -4.533392 2.249932)
			(end 4.533392 2.249932)
			(stroke
				(width 0.1524)
				(type default)
			)
			(layer "B.SilkS")
		)
		(fp_line
			(start 4.533392 2.249932)
			(end 4.533392 -2.249932)
			(stroke
				(width 0.1524)
				(type default)
			)
			(layer "B.SilkS")
		)
		(fp_line
			(start -4.533392 -2.249932)
			(end -4.533392 2.249932)
			(stroke
				(width 0.1524)
				(type default)
			)
			(layer "B.SilkS")
		)
		(fp_line
			(start 4.533392 -2.249932)
			(end -4.533392 -2.249932)
			(stroke
				(width 0.1524)
				(type default)
			)
			(layer "B.SilkS")
		)
		(fp_rect
			(start 5.39242 2.326132)
			(end 4.533392 -2.326132)
			(stroke
				(width 0)
				(type default)
			)
			(fill yes)
			(layer "B.SilkS")
		)
		(fp_line
			(start -3.750056 2.249932)
			(end 3.750056 2.249932)
			(stroke
				(width 0.1)
				(type default)
			)
			(layer "B.Fab")
		)
		(fp_line
			(start 3.750056 2.249932)
			(end 3.750056 -2.249932)
			(stroke
				(width 0.1)
				(type default)
			)
			(layer "B.Fab")
		)
		(fp_line
			(start -3.750056 -2.249932)
			(end -3.750056 2.249932)
			(stroke
				(width 0.1)
				(type default)
			)
			(layer "B.Fab")
		)
		(fp_line
			(start 3.750056 -2.249932)
			(end -3.750056 -2.249932)
			(stroke
				(width 0.1)
				(type default)
			)
			(layer "B.Fab")
		)
		(fp_text user "-"
			(at -4.699254 0.960374 270)
			(unlocked yes)
			(layer "B.SilkS")
			(effects
				(font
					(size 1.905 1.4224)
					(thickness 0.1524)
				)
				(justify left mirror)
			)
		)
		(fp_text user "+"
			(at 6.322314 0.786384 180)
			(unlocked yes)
			(layer "B.SilkS")
			(effects
				(font
					(size 1.905 1.4224)
					(thickness 0.1524)
				)
				(justify left mirror)
			)
		)
		(fp_text user "+"
			(at 6.322314 0.786384 180)
			(unlocked yes)
			(layer "B.Fab")
			(effects
				(font
					(size 1.905 1.4224)
					(thickness 0.1524)
				)
				(justify left mirror)
			)
		)
		(fp_text user "-"
			(at -4.8514 -0.14605 270)
			(unlocked yes)
			(layer "B.Fab")
			(effects
				(font
					(size 1.905 1.4224)
					(thickness 0.1524)
				)
				(justify left mirror)
			)
		)
		(pad "1" smd rect
			(at 3.199892 0 90)
			(size 2.413 2.8194)
			(layers "B.Cu" "B.Mask" "B.Paste")
			(net "PVDDIO_P0")
		)
		(pad "2" smd rect
			(at -3.199892 0 90)
			(size 2.413 2.8194)
			(layers "B.Cu" "B.Mask" "B.Paste")
			(net "GND")
		)
	)
	(footprint ""
		(layer "B.Cu")
		(at 380.078488 -395.148562 90)
		(property "Reference" "C1003"
			(at 0 0 90)
			(layer "B.SilkS")
			(hide yes)
			(effects
				(font
					(size 1.27 1.27)
				)
				(justify mirror)
			)
		)
		(property "Value" ""
			(at 0 0 90)
			(layer "B.Fab")
			(effects
				(font
					(size 1.27 1.27)
				)
				(justify mirror)
			)
		)
		(duplicate_pad_numbers_are_jumpers no)
		(fp_line
			(start 0.299974 -0.150114)
			(end -0.299974 -0.150114)
			(stroke
				(width 0.1)
				(type default)
			)
			(layer "B.Fab")
		)
		(fp_line
			(start -0.299974 -0.150114)
			(end -0.299974 0.150114)
			(stroke
				(width 0.1)
				(type default)
			)
			(layer "B.Fab")
		)
		(fp_line
			(start 0.299974 0.150114)
			(end 0.299974 -0.150114)
			(stroke
				(width 0.1)
				(type default)
			)
			(layer "B.Fab")
		)
		(fp_line
			(start -0.299974 0.150114)
			(end 0.299974 0.150114)
			(stroke
				(width 0.1)
				(type default)
			)
			(layer "B.Fab")
		)
		(pad "1" smd rect
			(at 0.2667 0 270)
			(size 0.3048 0.381)
			(layers "B.Cu" "B.Mask" "B.Paste")
			(net "P1V8_CPU0_RT3_1A")
		)
		(pad "2" smd rect
			(at -0.2667 0 270)
			(size 0.3048 0.381)
			(layers "B.Cu" "B.Mask" "B.Paste")
			(net "GND")
		)
	)
	(footprint ""
		(layer "B.Cu")
		(at 74.5236 -384.66268 180)
		(property "Reference" "R786"
			(at 0 0 0)
			(layer "B.SilkS")
			(hide yes)
			(effects
				(font
					(size 1.27 1.27)
				)
				(justify mirror)
			)
		)
		(property "Value" ""
			(at 0 0 0)
			(layer "B.Fab")
			(effects
				(font
					(size 1.27 1.27)
				)
				(justify mirror)
			)
		)
		(duplicate_pad_numbers_are_jumpers no)
		(fp_line
			(start 0.32512 0.175006)
			(end 0.32512 -0.175006)
			(stroke
				(width 0.1)
				(type default)
			)
			(layer "B.Fab")
		)
		(fp_line
			(start 0.32512 -0.175006)
			(end -0.32512 -0.175006)
			(stroke
				(width 0.1)
				(type default)
			)
			(layer "B.Fab")
		)
		(fp_line
			(start -0.32512 0.175006)
			(end 0.32512 0.175006)
			(stroke
				(width 0.1)
				(type default)
			)
			(layer "B.Fab")
		)
		(fp_line
			(start -0.32512 -0.175006)
			(end -0.32512 0.175006)
			(stroke
				(width 0.1)
				(type default)
			)
			(layer "B.Fab")
		)
		(pad "1" smd rect
			(at 0.2667 0)
			(size 0.3048 0.381)
			(layers "B.Cu" "B.Mask" "B.Paste")
			(net "P1V8_CPU1_RT_1D")
		)
		(pad "2" smd rect
			(at -0.2667 0 180)
			(size 0.3048 0.381)
			(layers "B.Cu" "B.Mask" "B.Paste")
			(net "TEST1_RT_CPU1_P1")
		)
	)
	(footprint ""
		(layer "B.Cu")
		(at 363.341158 -271.395952 180)
		(property "Reference" "C2225"
			(at 0 0 0)
			(layer "B.SilkS")
			(hide yes)
			(effects
				(font
					(size 1.27 1.27)
				)
				(justify mirror)
			)
		)
		(property "Value" ""
			(at 0 0 0)
			(layer "B.Fab")
			(effects
				(font
					(size 1.27 1.27)
				)
				(justify mirror)
			)
		)
		(duplicate_pad_numbers_are_jumpers no)
		(fp_line
			(start 0.7874 0.4064)
			(end 0.7874 -0.4064)
			(stroke
				(width 0.1524)
				(type default)
			)
			(layer "B.SilkS")
		)
		(fp_line
			(start 0.7874 -0.4064)
			(end -0.7874 -0.4064)
			(stroke
				(width 0.1524)
				(type default)
			)
			(layer "B.SilkS")
		)
		(fp_line
			(start -0.7874 0.4064)
			(end 0.7874 0.4064)
			(stroke
				(width 0.1524)
				(type default)
			)
			(layer "B.SilkS")
		)
		(fp_line
			(start -0.7874 -0.4064)
			(end -0.7874 0.4064)
			(stroke
				(width 0.1524)
				(type default)
			)
			(layer "B.SilkS")
		)
		(fp_line
			(start 0.67945 0.3048)
			(end 0.67945 -0.305054)
			(stroke
				(width 0.1)
				(type default)
			)
			(layer "B.Fab")
		)
		(fp_line
			(start 0.67945 -0.305054)
			(end 0.12065 -0.305054)
			(stroke
				(width 0.1)
				(type default)
			)
			(layer "B.Fab")
		)
		(fp_line
			(start 0.12065 0.3048)
			(end 0.67945 0.3048)
			(stroke
				(width 0.1)
				(type default)
			)
			(layer "B.Fab")
		)
		(fp_line
			(start 0.12065 0.2794)
			(end 0.12065 0.3048)
			(stroke
				(width 0.1)
				(type default)
			)
			(layer "B.Fab")
		)
		(fp_line
			(start 0.12065 -0.2794)
			(end -0.12065 -0.2794)
			(stroke
				(width 0.1)
				(type default)
			)
			(layer "B.Fab")
		)
		(fp_line
			(start 0.12065 -0.305054)
			(end 0.12065 -0.2794)
			(stroke
				(width 0.1)
				(type default)
			)
			(layer "B.Fab")
		)
		(fp_line
			(start -0.120396 0.3048)
			(end -0.120396 0.2794)
			(stroke
				(width 0.1)
				(type default)
			)
			(layer "B.Fab")
		)
		(fp_line
			(start -0.120396 0.2794)
			(end 0.12065 0.2794)
			(stroke
				(width 0.1)
				(type default)
			)
			(layer "B.Fab")
		)
		(fp_line
			(start -0.12065 -0.2794)
			(end -0.12065 -0.3048)
			(stroke
				(width 0.1)
				(type default)
			)
			(layer "B.Fab")
		)
		(fp_line
			(start -0.12065 -0.3048)
			(end -0.67945 -0.3048)
			(stroke
				(width 0.1)
				(type default)
			)
			(layer "B.Fab")
		)
		(fp_line
			(start -0.67945 0.3048)
			(end -0.120396 0.3048)
			(stroke
				(width 0.1)
				(type default)
			)
			(layer "B.Fab")
		)
		(fp_line
			(start -0.67945 -0.3048)
			(end -0.67945 0.3048)
			(stroke
				(width 0.1)
				(type default)
			)
			(layer "B.Fab")
		)
		(pad "1" smd circle
			(at 0.40005 0)
			(size 0 0)
			(layers "B.Cu" "B.Mask" "B.Paste")
			(net "PVDDCR_CPU1_P0")
		)
		(pad "2" smd circle
			(at -0.40005 0)
			(size 0 0)
			(layers "B.Cu" "B.Mask" "B.Paste")
			(net "GND")
		)
	)
	(footprint ""
		(layer "B.Cu")
		(at 160.7312 -191.1604 -90)
		(property "Reference" "R541"
			(at 0 0 90)
			(layer "B.SilkS")
			(hide yes)
			(effects
				(font
					(size 1.27 1.27)
				)
				(justify mirror)
			)
		)
		(property "Value" ""
			(at 0 0 90)
			(layer "B.Fab")
			(effects
				(font
					(size 1.27 1.27)
				)
				(justify mirror)
			)
		)
		(duplicate_pad_numbers_are_jumpers no)
		(fp_line
			(start -0.7874 0.4064)
			(end 0.7874 0.4064)
			(stroke
				(width 0.1524)
				(type default)
			)
			(layer "B.SilkS")
		)
		(fp_line
			(start 0.7874 0.4064)
			(end 0.7874 -0.4064)
			(stroke
				(width 0.1524)
				(type default)
			)
			(layer "B.SilkS")
		)
		(fp_line
			(start -0.7874 -0.4064)
			(end -0.7874 0.4064)
			(stroke
				(width 0.1524)
				(type default)
			)
			(layer "B.SilkS")
		)
		(fp_line
			(start 0.7874 -0.4064)
			(end -0.7874 -0.4064)
			(stroke
				(width 0.1524)
				(type default)
			)
			(layer "B.SilkS")
		)
		(fp_line
			(start -0.67945 0.3048)
			(end -0.120396 0.3048)
			(stroke
				(width 0.1)
				(type default)
			)
			(layer "B.Fab")
		)
		(fp_line
			(start -0.120396 0.3048)
			(end -0.120396 0.2794)
			(stroke
				(width 0.1)
				(type default)
			)
			(layer "B.Fab")
		)
		(fp_line
			(start 0.12065 0.3048)
			(end 0.67945 0.3048)
			(stroke
				(width 0.1)
				(type default)
			)
			(layer "B.Fab")
		)
		(fp_line
			(start 0.67945 0.3048)
			(end 0.67945 -0.305054)
			(stroke
				(width 0.1)
				(type default)
			)
			(layer "B.Fab")
		)
		(fp_line
			(start -0.120396 0.2794)
			(end 0.12065 0.2794)
			(stroke
				(width 0.1)
				(type default)
			)
			(layer "B.Fab")
		)
		(fp_line
			(start 0.12065 0.2794)
			(end 0.12065 0.3048)
			(stroke
				(width 0.1)
				(type default)
			)
			(layer "B.Fab")
		)
		(fp_line
			(start -0.12065 -0.2794)
			(end -0.12065 -0.3048)
			(stroke
				(width 0.1)
				(type default)
			)
			(layer "B.Fab")
		)
		(fp_line
			(start 0.12065 -0.2794)
			(end -0.12065 -0.2794)
			(stroke
				(width 0.1)
				(type default)
			)
			(layer "B.Fab")
		)
		(fp_line
			(start -0.67945 -0.3048)
			(end -0.67945 0.3048)
			(stroke
				(width 0.1)
				(type default)
			)
			(layer "B.Fab")
		)
		(fp_line
			(start -0.12065 -0.3048)
			(end -0.67945 -0.3048)
			(stroke
				(width 0.1)
				(type default)
			)
			(layer "B.Fab")
		)
		(fp_line
			(start 0.12065 -0.305054)
			(end 0.12065 -0.2794)
			(stroke
				(width 0.1)
				(type default)
			)
			(layer "B.Fab")
		)
		(fp_line
			(start 0.67945 -0.305054)
			(end 0.12065 -0.305054)
			(stroke
				(width 0.1)
				(type default)
			)
			(layer "B.Fab")
		)
		(pad "1" smd circle
			(at 0.40005 0 90)
			(size 0 0)
			(layers "B.Cu" "B.Mask" "B.Paste")
			(net "PVDD11_S3_P1")
		)
		(pad "2" smd circle
			(at -0.40005 0 90)
			(size 0 0)
			(layers "B.Cu" "B.Mask" "B.Paste")
			(net "I3C_1_SPD_DDRGL_CPU1_R_SDA")
		)
	)
	(footprint ""
		(layer "B.Cu")
		(at 426.702474 -351.032826 90)
		(property "Reference" "PC211_1"
			(at 0 0 90)
			(layer "B.SilkS")
			(hide yes)
			(effects
				(font
					(size 1.27 1.27)
				)
				(justify mirror)
			)
		)
		(property "Value" ""
			(at 0 0 90)
			(layer "B.Fab")
			(effects
				(font
					(size 1.27 1.27)
				)
				(justify mirror)
			)
		)
		(duplicate_pad_numbers_are_jumpers no)
		(fp_line
			(start 1.524 -0.762)
			(end -1.524 -0.762)
			(stroke
				(width 0.1524)
				(type default)
			)
			(layer "B.SilkS")
		)
		(fp_line
			(start -1.524 -0.762)
			(end -1.524 0.762)
			(stroke
				(width 0.1524)
				(type default)
			)
			(layer "B.SilkS")
		)
		(fp_line
			(start 1.524 0.762)
			(end 1.524 -0.762)
			(stroke
				(width 0.1524)
				(type default)
			)
			(layer "B.SilkS")
		)
		(fp_line
			(start -1.524 0.762)
			(end 1.524 0.762)
			(stroke
				(width 0.1524)
				(type default)
			)
			(layer "B.SilkS")
		)
		(fp_line
			(start 1.1049 -0.724916)
			(end 1.1049 0.724916)
			(stroke
				(width 0.1)
				(type default)
			)
			(layer "B.Fab")
		)
		(fp_line
			(start -1.1049 -0.724916)
			(end 1.1049 -0.724916)
			(stroke
				(width 0.1)
				(type default)
			)
			(layer "B.Fab")
		)
		(fp_line
			(start 1.1049 0.724916)
			(end -1.1049 0.724916)
			(stroke
				(width 0.1)
				(type default)
			)
			(layer "B.Fab")
		)
		(fp_line
			(start -1.1049 0.724916)
			(end -1.1049 -0.724916)
			(stroke
				(width 0.1)
				(type default)
			)
			(layer "B.Fab")
		)
		(pad "1" smd rect
			(at 0.889 0 90)
			(size 1.016 1.27)
			(layers "B.Cu" "B.Mask" "B.Paste")
			(net "SW_P12V_AUX_PVDD11_S3_P0_FLT")
		)
		(pad "2" smd rect
			(at -0.889 0 90)
			(size 1.016 1.27)
			(layers "B.Cu" "B.Mask" "B.Paste")
			(net "GND")
		)
	)
	(footprint ""
		(layer "B.Cu")
		(at 404.475696 -340.622382)
		(property "Reference" "U82"
			(at 5.969 -0.980948 0)
			(unlocked yes)
			(layer "B.SilkS")
			(effects
				(font
					(size 0.7874 0.5842)
					(thickness 0.1524)
				)
				(justify left mirror)
			)
		)
		(property "Value" ""
			(at 0 0 0)
			(layer "B.Fab")
			(effects
				(font
					(size 1.27 1.27)
				)
				(justify mirror)
			)
		)
		(duplicate_pad_numbers_are_jumpers no)
		(fp_line
			(start -2.0574 -1.651)
			(end -2.0574 1.651)
			(stroke
				(width 0.1524)
				(type default)
			)
			(layer "B.SilkS")
		)
		(fp_line
			(start -2.0574 1.651)
			(end 2.0574 1.651)
			(stroke
				(width 0.1524)
				(type default)
			)
			(layer "B.SilkS")
		)
		(fp_line
			(start -0.381 -1.651)
			(end -2.0574 -1.651)
			(stroke
				(width 0.1524)
				(type default)
			)
			(layer "B.SilkS")
		)
		(fp_line
			(start 0 -1.016)
			(end -0.381 -1.651)
			(stroke
				(width 0.1524)
				(type default)
			)
			(layer "B.SilkS")
		)
		(fp_line
			(start 0.381 -1.651)
			(end 0 -1.016)
			(stroke
				(width 0.1524)
				(type default)
			)
			(layer "B.SilkS")
		)
		(fp_line
			(start 2.0574 -1.651)
			(end 0.381 -1.651)
			(stroke
				(width 0.1524)
				(type default)
			)
			(layer "B.SilkS")
		)
		(fp_line
			(start 2.0574 1.651)
			(end 2.0574 -1.651)
			(stroke
				(width 0.1524)
				(type default)
			)
			(layer "B.SilkS")
		)
		(fp_poly
			(pts
				(xy 2.159 -1.016) (xy 2.71272 -0.719328) (xy 2.71272 -1.344168)
			)
			(stroke
				(width 0)
				(type default)
			)
			(fill yes)
			(layer "B.SilkS")
		)
		(fp_line
			(start -1.599946 -1.199896)
			(end -1.599946 1.199896)
			(stroke
				(width 0.1)
				(type default)
			)
			(layer "B.Fab")
		)
		(fp_line
			(start -1.599946 1.199896)
			(end -0.899922 1.199896)
			(stroke
				(width 0.1)
				(type default)
			)
			(layer "B.Fab")
		)
		(fp_line
			(start -0.899922 -1.549908)
			(end -0.899922 -1.199896)
			(stroke
				(width 0.1)
				(type default)
			)
			(layer "B.Fab")
		)
		(fp_line
			(start -0.899922 -1.199896)
			(end -1.599946 -1.199896)
			(stroke
				(width 0.1)
				(type default)
			)
			(layer "B.Fab")
		)
		(fp_line
			(start -0.899922 1.199896)
			(end -0.899922 1.549908)
			(stroke
				(width 0.1)
				(type default)
			)
			(layer "B.Fab")
		)
		(fp_line
			(start -0.899922 1.549908)
			(end 0.899922 1.549908)
			(stroke
				(width 0.1)
				(type default)
			)
			(layer "B.Fab")
		)
		(fp_line
			(start 0.899922 -1.549908)
			(end -0.899922 -1.549908)
			(stroke
				(width 0.1)
				(type default)
			)
			(layer "B.Fab")
		)
		(fp_line
			(start 0.899922 -1.199896)
			(end 0.899922 -1.549908)
			(stroke
				(width 0.1)
				(type default)
			)
			(layer "B.Fab")
		)
		(fp_line
			(start 0.899922 1.199896)
			(end 1.599946 1.199896)
			(stroke
				(width 0.1)
				(type default)
			)
			(layer "B.Fab")
		)
		(fp_line
			(start 0.899922 1.549908)
			(end 0.899922 1.199896)
			(stroke
				(width 0.1)
				(type default)
			)
			(layer "B.Fab")
		)
		(fp_line
			(start 1.599946 -1.199896)
			(end 0.899922 -1.199896)
			(stroke
				(width 0.1)
				(type default)
			)
			(layer "B.Fab")
		)
		(fp_line
			(start 1.599946 1.199896)
			(end 1.599946 -1.199896)
			(stroke
				(width 0.1)
				(type default)
			)
			(layer "B.Fab")
		)
		(fp_poly
			(pts
				(xy 2.71272 -0.719328) (xy 2.71272 -1.344168) (xy 2.159 -1.016)
			)
			(stroke
				(width 0)
				(type default)
			)
			(fill yes)
			(layer "B.Fab")
		)
		(pad "1" smd rect
			(at 1.225042 -0.94996 270)
			(size 0.5588 1.3462)
			(layers "B.Cu" "B.Mask" "B.Paste")
			(net "Net_10732")
		)
		(pad "2" smd rect
			(at 1.225042 0 270)
			(size 0.5588 1.3462)
			(layers "B.Cu" "B.Mask" "B.Paste")
			(net "BOOT_RDY_R1_N")
		)
		(pad "3" smd rect
			(at 1.225042 0.94996 270)
			(size 0.5588 1.3462)
			(layers "B.Cu" "B.Mask" "B.Paste")
			(net "GND")
		)
		(pad "4" smd rect
			(at -1.225042 0.94996 270)
			(size 0.5588 1.3462)
			(layers "B.Cu" "B.Mask" "B.Paste")
			(net "BOOT_RDY_BUF_R_LED")
		)
		(pad "5" smd rect
			(at -1.225042 -0.94996 270)
			(size 0.5588 1.3462)
			(layers "B.Cu" "B.Mask" "B.Paste")
			(net "P1V8_AUX")
		)
	)
	(footprint ""
		(layer "B.Cu")
		(at 231.074722 -323.913754)
		(property "Reference" "R1251"
			(at 0 0 0)
			(layer "B.SilkS")
			(hide yes)
			(effects
				(font
					(size 1.27 1.27)
				)
				(justify mirror)
			)
		)
		(property "Value" ""
			(at 0 0 0)
			(layer "B.Fab")
			(effects
				(font
					(size 1.27 1.27)
				)
				(justify mirror)
			)
		)
		(duplicate_pad_numbers_are_jumpers no)
		(fp_line
			(start -0.7874 -0.4064)
			(end -0.7874 0.4064)
			(stroke
				(width 0.1524)
				(type default)
			)
			(layer "B.SilkS")
		)
		(fp_line
			(start -0.7874 0.4064)
			(end 0.7874 0.4064)
			(stroke
				(width 0.1524)
				(type default)
			)
			(layer "B.SilkS")
		)
		(fp_line
			(start 0.7874 -0.4064)
			(end -0.7874 -0.4064)
			(stroke
				(width 0.1524)
				(type default)
			)
			(layer "B.SilkS")
		)
		(fp_line
			(start 0.7874 0.4064)
			(end 0.7874 -0.4064)
			(stroke
				(width 0.1524)
				(type default)
			)
			(layer "B.SilkS")
		)
		(fp_line
			(start -0.67945 -0.3048)
			(end -0.67945 0.3048)
			(stroke
				(width 0.1)
				(type default)
			)
			(layer "B.Fab")
		)
		(fp_line
			(start -0.67945 0.3048)
			(end -0.120396 0.3048)
			(stroke
				(width 0.1)
				(type default)
			)
			(layer "B.Fab")
		)
		(fp_line
			(start -0.12065 -0.3048)
			(end -0.67945 -0.3048)
			(stroke
				(width 0.1)
				(type default)
			)
			(layer "B.Fab")
		)
		(fp_line
			(start -0.12065 -0.2794)
			(end -0.12065 -0.3048)
			(stroke
				(width 0.1)
				(type default)
			)
			(layer "B.Fab")
		)
		(fp_line
			(start -0.120396 0.2794)
			(end 0.12065 0.2794)
			(stroke
				(width 0.1)
				(type default)
			)
			(layer "B.Fab")
		)
		(fp_line
			(start -0.120396 0.3048)
			(end -0.120396 0.2794)
			(stroke
				(width 0.1)
				(type default)
			)
			(layer "B.Fab")
		)
		(fp_line
			(start 0.12065 -0.305054)
			(end 0.12065 -0.2794)
			(stroke
				(width 0.1)
				(type default)
			)
			(layer "B.Fab")
		)
		(fp_line
			(start 0.12065 -0.2794)
			(end -0.12065 -0.2794)
			(stroke
				(width 0.1)
				(type default)
			)
			(layer "B.Fab")
		)
		(fp_line
			(start 0.12065 0.2794)
			(end 0.12065 0.3048)
			(stroke
				(width 0.1)
				(type default)
			)
			(layer "B.Fab")
		)
		(fp_line
			(start 0.12065 0.3048)
			(end 0.67945 0.3048)
			(stroke
				(width 0.1)
				(type default)
			)
			(layer "B.Fab")
		)
		(fp_line
			(start 0.67945 -0.305054)
			(end 0.12065 -0.305054)
			(stroke
				(width 0.1)
				(type default)
			)
			(layer "B.Fab")
		)
		(fp_line
			(start 0.67945 0.3048)
			(end 0.67945 -0.305054)
			(stroke
				(width 0.1)
				(type default)
			)
			(layer "B.Fab")
		)
		(pad "1" smd rect
			(at 0.40005 0)
			(size 0.4572 0.508)
			(layers "B.Cu" "B.Mask" "B.Paste")
			(net "P1V2_AUX_ADC")
		)
		(pad "2" smd rect
			(at -0.40005 0)
			(size 0.4572 0.508)
			(layers "B.Cu" "B.Mask" "B.Paste")
			(net "P1V2_AUX_ADC_TIC")
		)
	)
	(footprint ""
		(layer "B.Cu")
		(at 341.906098 -395.148562 90)
		(property "Reference" "C610"
			(at 0 0 90)
			(layer "B.SilkS")
			(hide yes)
			(effects
				(font
					(size 1.27 1.27)
				)
				(justify mirror)
			)
		)
		(property "Value" ""
			(at 0 0 90)
			(layer "B.Fab")
			(effects
				(font
					(size 1.27 1.27)
				)
				(justify mirror)
			)
		)
		(duplicate_pad_numbers_are_jumpers no)
		(fp_line
			(start 0.299974 -0.150114)
			(end -0.299974 -0.150114)
			(stroke
				(width 0.1)
				(type default)
			)
			(layer "B.Fab")
		)
		(fp_line
			(start -0.299974 -0.150114)
			(end -0.299974 0.150114)
			(stroke
				(width 0.1)
				(type default)
			)
			(layer "B.Fab")
		)
		(fp_line
			(start 0.299974 0.150114)
			(end 0.299974 -0.150114)
			(stroke
				(width 0.1)
				(type default)
			)
			(layer "B.Fab")
		)
		(fp_line
			(start -0.299974 0.150114)
			(end 0.299974 0.150114)
			(stroke
				(width 0.1)
				(type default)
			)
			(layer "B.Fab")
		)
		(pad "1" smd rect
			(at 0.2667 0 270)
			(size 0.3048 0.381)
			(layers "B.Cu" "B.Mask" "B.Paste")
			(net "P0V9_CPU0_RT_2D")
		)
		(pad "2" smd rect
			(at -0.2667 0 270)
			(size 0.3048 0.381)
			(layers "B.Cu" "B.Mask" "B.Paste")
			(net "GND")
		)
	)
	(footprint ""
		(layer "B.Cu")
		(at 167.502332 -434.882544 180)
		(property "Reference" "Q132"
			(at -5.782056 0.352552 0)
			(unlocked yes)
			(layer "B.SilkS")
			(effects
				(font
					(size 0.7874 0.5842)
					(thickness 0.1524)
				)
				(justify left mirror)
			)
		)
		(property "Value" ""
			(at 0 0 0)
			(layer "B.Fab")
			(effects
				(font
					(size 1.27 1.27)
				)
				(justify mirror)
			)
		)
		(duplicate_pad_numbers_are_jumpers no)
		(fp_line
			(start 1.332738 1.100074)
			(end 1.332738 -1.100074)
			(stroke
				(width 0.1524)
				(type default)
			)
			(layer "B.SilkS")
		)
		(fp_line
			(start 1.332738 -1.100074)
			(end 0.4826 -1.100074)
			(stroke
				(width 0.1524)
				(type default)
			)
			(layer "B.SilkS")
		)
		(fp_line
			(start 0.4826 -1.100074)
			(end 0 -0.541274)
			(stroke
				(width 0.1524)
				(type default)
			)
			(layer "B.SilkS")
		)
		(fp_line
			(start 0 -0.541274)
			(end -0.4826 -1.100074)
			(stroke
				(width 0.1524)
				(type default)
			)
			(layer "B.SilkS")
		)
		(fp_line
			(start -0.4826 -1.100074)
			(end -1.332738 -1.100074)
			(stroke
				(width 0.1524)
				(type default)
			)
			(layer "B.SilkS")
		)
		(fp_line
			(start -1.332738 1.100074)
			(end 1.332738 1.100074)
			(stroke
				(width 0.1524)
				(type default)
			)
			(layer "B.SilkS")
		)
		(fp_line
			(start -1.332738 -1.100074)
			(end -1.332738 1.100074)
			(stroke
				(width 0.1524)
				(type default)
			)
			(layer "B.SilkS")
		)
		(fp_poly
			(pts
				(xy 1.020064 -1.309624) (xy 1.371092 -2.011426) (xy 0.669036 -2.011426)
			)
			(stroke
				(width 0)
				(type default)
			)
			(fill yes)
			(layer "B.SilkS")
		)
		(fp_line
			(start 0.674878 1.100074)
			(end 0.674878 -1.100074)
			(stroke
				(width 0.1)
				(type default)
			)
			(layer "B.Fab")
		)
		(fp_line
			(start 0.674878 -1.100074)
			(end -0.674878 -1.100074)
			(stroke
				(width 0.1)
				(type default)
			)
			(layer "B.Fab")
		)
		(fp_line
			(start -0.674878 1.100074)
			(end 0.674878 1.100074)
			(stroke
				(width 0.1)
				(type default)
			)
			(layer "B.Fab")
		)
		(fp_line
			(start -0.674878 -1.100074)
			(end -0.674878 1.100074)
			(stroke
				(width 0.1)
				(type default)
			)
			(layer "B.Fab")
		)
		(fp_poly
			(pts
				(xy 2.2352 -0.298958) (xy 2.2352 -1.001014) (xy 1.533144 -0.649986)
			)
			(stroke
				(width 0)
				(type default)
			)
			(fill yes)
			(layer "B.Fab")
		)
		(pad "1" smd rect
			(at 0.94996 -0.649986 270)
			(size 0.4318 0.508)
			(layers "B.Cu" "B.Mask" "B.Paste")
			(net "GND")
		)
		(pad "2" smd rect
			(at 0.94996 0 270)
			(size 0.4318 0.508)
			(layers "B.Cu" "B.Mask" "B.Paste")
			(net "PRSNT_CABLE_GPU_B3_N")
		)
		(pad "3" smd rect
			(at 0.94996 0.649986 270)
			(size 0.4318 0.508)
			(layers "B.Cu" "B.Mask" "B.Paste")
			(net "PRSNT_CABLE_GPU_B3_ISO_N")
		)
		(pad "4" smd rect
			(at -0.94996 0.649986 270)
			(size 0.4318 0.508)
			(layers "B.Cu" "B.Mask" "B.Paste")
			(net "GND")
		)
		(pad "5" smd rect
			(at -0.94996 0 270)
			(size 0.4318 0.508)
			(layers "B.Cu" "B.Mask" "B.Paste")
			(net "PRSNT_CABLE_GPU_B3")
		)
		(pad "6" smd rect
			(at -0.94996 -0.649986 270)
			(size 0.4318 0.508)
			(layers "B.Cu" "B.Mask" "B.Paste")
			(net "PRSNT_CABLE_GPU_B3")
		)
	)
	(footprint ""
		(layer "B.Cu")
		(at 25.92324 -193.996564)
		(property "Reference" "R107"
			(at 0 0 0)
			(layer "B.SilkS")
			(hide yes)
			(effects
				(font
					(size 1.27 1.27)
				)
				(justify mirror)
			)
		)
		(property "Value" ""
			(at 0 0 0)
			(layer "B.Fab")
			(effects
				(font
					(size 1.27 1.27)
				)
				(justify mirror)
			)
		)
		(duplicate_pad_numbers_are_jumpers no)
		(fp_line
			(start -0.7874 -0.4064)
			(end -0.7874 0.4064)
			(stroke
				(width 0.1524)
				(type default)
			)
			(layer "B.SilkS")
		)
		(fp_line
			(start -0.7874 0.4064)
			(end 0.7874 0.4064)
			(stroke
				(width 0.1524)
				(type default)
			)
			(layer "B.SilkS")
		)
		(fp_line
			(start 0.7874 -0.4064)
			(end -0.7874 -0.4064)
			(stroke
				(width 0.1524)
				(type default)
			)
			(layer "B.SilkS")
		)
		(fp_line
			(start 0.7874 0.4064)
			(end 0.7874 -0.4064)
			(stroke
				(width 0.1524)
				(type default)
			)
			(layer "B.SilkS")
		)
		(fp_line
			(start -0.67945 -0.3048)
			(end -0.67945 0.3048)
			(stroke
				(width 0.1)
				(type default)
			)
			(layer "B.Fab")
		)
		(fp_line
			(start -0.67945 0.3048)
			(end -0.120396 0.3048)
			(stroke
				(width 0.1)
				(type default)
			)
			(layer "B.Fab")
		)
		(fp_line
			(start -0.12065 -0.3048)
			(end -0.67945 -0.3048)
			(stroke
				(width 0.1)
				(type default)
			)
			(layer "B.Fab")
		)
		(fp_line
			(start -0.12065 -0.2794)
			(end -0.12065 -0.3048)
			(stroke
				(width 0.1)
				(type default)
			)
			(layer "B.Fab")
		)
		(fp_line
			(start -0.120396 0.2794)
			(end 0.12065 0.2794)
			(stroke
				(width 0.1)
				(type default)
			)
			(layer "B.Fab")
		)
		(fp_line
			(start -0.120396 0.3048)
			(end -0.120396 0.2794)
			(stroke
				(width 0.1)
				(type default)
			)
			(layer "B.Fab")
		)
		(fp_line
			(start 0.12065 -0.305054)
			(end 0.12065 -0.2794)
			(stroke
				(width 0.1)
				(type default)
			)
			(layer "B.Fab")
		)
		(fp_line
			(start 0.12065 -0.2794)
			(end -0.12065 -0.2794)
			(stroke
				(width 0.1)
				(type default)
			)
			(layer "B.Fab")
		)
		(fp_line
			(start 0.12065 0.2794)
			(end 0.12065 0.3048)
			(stroke
				(width 0.1)
				(type default)
			)
			(layer "B.Fab")
		)
		(fp_line
			(start 0.12065 0.3048)
			(end 0.67945 0.3048)
			(stroke
				(width 0.1)
				(type default)
			)
			(layer "B.Fab")
		)
		(fp_line
			(start 0.67945 -0.305054)
			(end 0.12065 -0.305054)
			(stroke
				(width 0.1)
				(type default)
			)
			(layer "B.Fab")
		)
		(fp_line
			(start 0.67945 0.3048)
			(end 0.67945 -0.305054)
			(stroke
				(width 0.1)
				(type default)
			)
			(layer "B.Fab")
		)
		(pad "1" smd circle
			(at 0.40005 0 180)
			(size 0 0)
			(layers "B.Cu" "B.Mask" "B.Paste")
			(net "P3V3")
		)
		(pad "2" smd circle
			(at -0.40005 0 180)
			(size 0 0)
			(layers "B.Cu" "B.Mask" "B.Paste")
			(net "PWRGD_CHE_CPU1_DIMM")
		)
	)
	(footprint ""
		(layer "B.Cu")
		(at 24.765 -361.061 180)
		(property "Reference" "R8243"
			(at 0 0 0)
			(layer "B.SilkS")
			(hide yes)
			(effects
				(font
					(size 1.27 1.27)
				)
				(justify mirror)
			)
		)
		(property "Value" ""
			(at 0 0 0)
			(layer "B.Fab")
			(effects
				(font
					(size 1.27 1.27)
				)
				(justify mirror)
			)
		)
		(duplicate_pad_numbers_are_jumpers no)
		(fp_line
			(start 0.7874 0.4064)
			(end 0.7874 -0.4064)
			(stroke
				(width 0.1524)
				(type default)
			)
			(layer "B.SilkS")
		)
		(fp_line
			(start 0.7874 -0.4064)
			(end -0.7874 -0.4064)
			(stroke
				(width 0.1524)
				(type default)
			)
			(layer "B.SilkS")
		)
		(fp_line
			(start -0.7874 0.4064)
			(end 0.7874 0.4064)
			(stroke
				(width 0.1524)
				(type default)
			)
			(layer "B.SilkS")
		)
		(fp_line
			(start -0.7874 -0.4064)
			(end -0.7874 0.4064)
			(stroke
				(width 0.1524)
				(type default)
			)
			(layer "B.SilkS")
		)
		(fp_line
			(start 0.67945 0.3048)
			(end 0.67945 -0.305054)
			(stroke
				(width 0.1)
				(type default)
			)
			(layer "B.Fab")
		)
		(fp_line
			(start 0.67945 -0.305054)
			(end 0.12065 -0.305054)
			(stroke
				(width 0.1)
				(type default)
			)
			(layer "B.Fab")
		)
		(fp_line
			(start 0.12065 0.3048)
			(end 0.67945 0.3048)
			(stroke
				(width 0.1)
				(type default)
			)
			(layer "B.Fab")
		)
		(fp_line
			(start 0.12065 0.2794)
			(end 0.12065 0.3048)
			(stroke
				(width 0.1)
				(type default)
			)
			(layer "B.Fab")
		)
		(fp_line
			(start 0.12065 -0.2794)
			(end -0.12065 -0.2794)
			(stroke
				(width 0.1)
				(type default)
			)
			(layer "B.Fab")
		)
		(fp_line
			(start 0.12065 -0.305054)
			(end 0.12065 -0.2794)
			(stroke
				(width 0.1)
				(type default)
			)
			(layer "B.Fab")
		)
		(fp_line
			(start -0.120396 0.3048)
			(end -0.120396 0.2794)
			(stroke
				(width 0.1)
				(type default)
			)
			(layer "B.Fab")
		)
		(fp_line
			(start -0.120396 0.2794)
			(end 0.12065 0.2794)
			(stroke
				(width 0.1)
				(type default)
			)
			(layer "B.Fab")
		)
		(fp_line
			(start -0.12065 -0.2794)
			(end -0.12065 -0.3048)
			(stroke
				(width 0.1)
				(type default)
			)
			(layer "B.Fab")
		)
		(fp_line
			(start -0.12065 -0.3048)
			(end -0.67945 -0.3048)
			(stroke
				(width 0.1)
				(type default)
			)
			(layer "B.Fab")
		)
		(fp_line
			(start -0.67945 0.3048)
			(end -0.120396 0.3048)
			(stroke
				(width 0.1)
				(type default)
			)
			(layer "B.Fab")
		)
		(fp_line
			(start -0.67945 -0.3048)
			(end -0.67945 0.3048)
			(stroke
				(width 0.1)
				(type default)
			)
			(layer "B.Fab")
		)
		(pad "1" smd circle
			(at 0.40005 0)
			(size 0 0)
			(layers "B.Cu" "B.Mask" "B.Paste")
			(net "PWRGD_PVDDIO_P1")
		)
		(pad "2" smd circle
			(at -0.40005 0)
			(size 0 0)
			(layers "B.Cu" "B.Mask" "B.Paste")
			(net "PWRGD_PVDDIO_P1_R")
		)
	)
	(footprint ""
		(layer "B.Cu")
		(at 428.98695 -38.039548 180)
		(property "Reference" "R6043"
			(at 0 0 0)
			(layer "B.SilkS")
			(hide yes)
			(effects
				(font
					(size 1.27 1.27)
				)
				(justify mirror)
			)
		)
		(property "Value" ""
			(at 0 0 0)
			(layer "B.Fab")
			(effects
				(font
					(size 1.27 1.27)
				)
				(justify mirror)
			)
		)
		(duplicate_pad_numbers_are_jumpers no)
		(fp_line
			(start 0.7874 0.4064)
			(end 0.7874 -0.4064)
			(stroke
				(width 0.1524)
				(type default)
			)
			(layer "B.SilkS")
		)
		(fp_line
			(start 0.7874 -0.4064)
			(end -0.7874 -0.4064)
			(stroke
				(width 0.1524)
				(type default)
			)
			(layer "B.SilkS")
		)
		(fp_line
			(start -0.7874 0.4064)
			(end 0.7874 0.4064)
			(stroke
				(width 0.1524)
				(type default)
			)
			(layer "B.SilkS")
		)
		(fp_line
			(start -0.7874 -0.4064)
			(end -0.7874 0.4064)
			(stroke
				(width 0.1524)
				(type default)
			)
			(layer "B.SilkS")
		)
		(fp_line
			(start 0.67945 0.3048)
			(end 0.67945 -0.305054)
			(stroke
				(width 0.1)
				(type default)
			)
			(layer "B.Fab")
		)
		(fp_line
			(start 0.67945 -0.305054)
			(end 0.12065 -0.305054)
			(stroke
				(width 0.1)
				(type default)
			)
			(layer "B.Fab")
		)
		(fp_line
			(start 0.12065 0.3048)
			(end 0.67945 0.3048)
			(stroke
				(width 0.1)
				(type default)
			)
			(layer "B.Fab")
		)
		(fp_line
			(start 0.12065 0.2794)
			(end 0.12065 0.3048)
			(stroke
				(width 0.1)
				(type default)
			)
			(layer "B.Fab")
		)
		(fp_line
			(start 0.12065 -0.2794)
			(end -0.12065 -0.2794)
			(stroke
				(width 0.1)
				(type default)
			)
			(layer "B.Fab")
		)
		(fp_line
			(start 0.12065 -0.305054)
			(end 0.12065 -0.2794)
			(stroke
				(width 0.1)
				(type default)
			)
			(layer "B.Fab")
		)
		(fp_line
			(start -0.120396 0.3048)
			(end -0.120396 0.2794)
			(stroke
				(width 0.1)
				(type default)
			)
			(layer "B.Fab")
		)
		(fp_line
			(start -0.120396 0.2794)
			(end 0.12065 0.2794)
			(stroke
				(width 0.1)
				(type default)
			)
			(layer "B.Fab")
		)
		(fp_line
			(start -0.12065 -0.2794)
			(end -0.12065 -0.3048)
			(stroke
				(width 0.1)
				(type default)
			)
			(layer "B.Fab")
		)
		(fp_line
			(start -0.12065 -0.3048)
			(end -0.67945 -0.3048)
			(stroke
				(width 0.1)
				(type default)
			)
			(layer "B.Fab")
		)
		(fp_line
			(start -0.67945 0.3048)
			(end -0.120396 0.3048)
			(stroke
				(width 0.1)
				(type default)
			)
			(layer "B.Fab")
		)
		(fp_line
			(start -0.67945 -0.3048)
			(end -0.67945 0.3048)
			(stroke
				(width 0.1)
				(type default)
			)
			(layer "B.Fab")
		)
		(pad "1" smd circle
			(at 0.40005 0)
			(size 0 0)
			(layers "B.Cu" "B.Mask" "B.Paste")
			(net "GND")
		)
		(pad "2" smd circle
			(at -0.40005 0)
			(size 0 0)
			(layers "B.Cu" "B.Mask" "B.Paste")
			(net "FPGA_DEBUG_SW_SPARE")
		)
	)
	(footprint ""
		(layer "B.Cu")
		(at 232.537 -338.455 -90)
		(property "Reference" "R6765"
			(at 0 0 90)
			(layer "B.SilkS")
			(hide yes)
			(effects
				(font
					(size 1.27 1.27)
				)
				(justify mirror)
			)
		)
		(property "Value" ""
			(at 0 0 90)
			(layer "B.Fab")
			(effects
				(font
					(size 1.27 1.27)
				)
				(justify mirror)
			)
		)
		(duplicate_pad_numbers_are_jumpers no)
		(fp_line
			(start -0.32512 0.175006)
			(end 0.32512 0.175006)
			(stroke
				(width 0.1)
				(type default)
			)
			(layer "B.Fab")
		)
		(fp_line
			(start 0.32512 0.175006)
			(end 0.32512 -0.175006)
			(stroke
				(width 0.1)
				(type default)
			)
			(layer "B.Fab")
		)
		(fp_line
			(start -0.32512 -0.175006)
			(end -0.32512 0.175006)
			(stroke
				(width 0.1)
				(type default)
			)
			(layer "B.Fab")
		)
		(fp_line
			(start 0.32512 -0.175006)
			(end -0.32512 -0.175006)
			(stroke
				(width 0.1)
				(type default)
			)
			(layer "B.Fab")
		)
		(pad "1" smd rect
			(at 0.2667 0 90)
			(size 0.3048 0.381)
			(layers "B.Cu" "B.Mask" "B.Paste")
			(net "P1V8_CPU0_RT_1D")
		)
		(pad "2" smd rect
			(at -0.2667 0 270)
			(size 0.3048 0.381)
			(layers "B.Cu" "B.Mask" "B.Paste")
			(net "SMB_RT_CPU0_P1_R_SCL")
		)
	)
	(footprint ""
		(layer "B.Cu")
		(at 61.967872 -381.11303)
		(property "Reference" "C7020"
			(at 2.02692 3.319272 0)
			(unlocked yes)
			(layer "B.SilkS")
			(effects
				(font
					(size 0.7874 0.5842)
					(thickness 0.1524)
				)
				(justify left mirror)
			)
		)
		(property "Value" ""
			(at 0 0 0)
			(layer "B.Fab")
			(effects
				(font
					(size 1.27 1.27)
				)
				(justify mirror)
			)
		)
		(duplicate_pad_numbers_are_jumpers no)
		(fp_line
			(start -4.53898 -2.15011)
			(end -4.53898 2.15011)
			(stroke
				(width 0.1524)
				(type default)
			)
			(layer "B.SilkS")
		)
		(fp_line
			(start -4.53898 2.15011)
			(end 4.53898 2.15011)
			(stroke
				(width 0.1524)
				(type default)
			)
			(layer "B.SilkS")
		)
		(fp_line
			(start 4.53898 -2.150618)
			(end 4.539742 2.152142)
			(stroke
				(width 0.1524)
				(type default)
			)
			(layer "B.SilkS")
		)
		(fp_line
			(start 4.53898 -2.15011)
			(end -4.53898 -2.15011)
			(stroke
				(width 0.1524)
				(type default)
			)
			(layer "B.SilkS")
		)
		(fp_line
			(start 4.53898 2.15011)
			(end 4.53898 -2.15011)
			(stroke
				(width 0.1524)
				(type default)
			)
			(layer "B.SilkS")
		)
		(fp_line
			(start 4.69138 -2.150618)
			(end 4.692396 2.161032)
			(stroke
				(width 0.1524)
				(type default)
			)
			(layer "B.SilkS")
		)
		(fp_line
			(start 4.83108 2.150364)
			(end 4.447794 2.149348)
			(stroke
				(width 0.1524)
				(type default)
			)
			(layer "B.SilkS")
		)
		(fp_line
			(start 4.84378 -2.150618)
			(end 4.53898 -2.150618)
			(stroke
				(width 0.1524)
				(type default)
			)
			(layer "B.SilkS")
		)
		(fp_line
			(start 4.84378 -2.150618)
			(end 4.842256 2.163064)
			(stroke
				(width 0.1524)
				(type default)
			)
			(layer "B.SilkS")
		)
		(fp_line
			(start -3.64998 -2.15011)
			(end -3.64998 2.15011)
			(stroke
				(width 0.1)
				(type default)
			)
			(layer "B.Fab")
		)
		(fp_line
			(start -3.64998 2.15011)
			(end 3.64998 2.15011)
			(stroke
				(width 0.1)
				(type default)
			)
			(layer "B.Fab")
		)
		(fp_line
			(start 3.64998 -2.15011)
			(end -3.64998 -2.15011)
			(stroke
				(width 0.1)
				(type default)
			)
			(layer "B.Fab")
		)
		(fp_line
			(start 3.64998 2.15011)
			(end 3.64998 -2.15011)
			(stroke
				(width 0.1)
				(type default)
			)
			(layer "B.Fab")
		)
		(fp_text user "-"
			(at -5.075174 2.326132 0)
			(unlocked yes)
			(layer "B.SilkS")
			(effects
				(font
					(size 1.905 1.4224)
					(thickness 0.1524)
				)
				(justify left mirror)
			)
		)
		(fp_text user "+"
			(at 4.302252 2.545842 0)
			(unlocked yes)
			(layer "B.SilkS")
			(effects
				(font
					(size 1.905 1.4224)
					(thickness 0.1524)
				)
				(justify left mirror)
			)
		)
		(fp_text user "-"
			(at -4.313174 -0.094488 0)
			(unlocked yes)
			(layer "B.Fab")
			(effects
				(font
					(size 1.905 1.4224)
					(thickness 0.1524)
				)
				(justify left mirror)
			)
		)
		(fp_text user "+"
			(at 6.214872 -0.337058 0)
			(unlocked yes)
			(layer "B.Fab")
			(effects
				(font
					(size 1.905 1.4224)
					(thickness 0.1524)
				)
				(justify left mirror)
			)
		)
		(pad "1" smd rect
			(at 3.199892 0 180)
			(size 2.413 2.8194)
			(layers "B.Cu" "B.Mask" "B.Paste")
			(net "P0V9_CPU1_RT0_2A")
		)
		(pad "2" smd rect
			(at -3.199892 0 180)
			(size 2.413 2.8194)
			(layers "B.Cu" "B.Mask" "B.Paste")
			(net "GND")
		)
	)
	(footprint ""
		(layer "B.Cu")
		(at 371.297454 -267.498576)
		(property "Reference" "C2207"
			(at 0 0 0)
			(layer "B.SilkS")
			(hide yes)
			(effects
				(font
					(size 1.27 1.27)
				)
				(justify mirror)
			)
		)
		(property "Value" ""
			(at 0 0 0)
			(layer "B.Fab")
			(effects
				(font
					(size 1.27 1.27)
				)
				(justify mirror)
			)
		)
		(duplicate_pad_numbers_are_jumpers no)
		(fp_line
			(start -0.7874 -0.4064)
			(end -0.7874 0.4064)
			(stroke
				(width 0.1524)
				(type default)
			)
			(layer "B.SilkS")
		)
		(fp_line
			(start -0.7874 0.4064)
			(end 0.7874 0.4064)
			(stroke
				(width 0.1524)
				(type default)
			)
			(layer "B.SilkS")
		)
		(fp_line
			(start 0.7874 -0.4064)
			(end -0.7874 -0.4064)
			(stroke
				(width 0.1524)
				(type default)
			)
			(layer "B.SilkS")
		)
		(fp_line
			(start 0.7874 0.4064)
			(end 0.7874 -0.4064)
			(stroke
				(width 0.1524)
				(type default)
			)
			(layer "B.SilkS")
		)
		(fp_line
			(start -0.67945 -0.3048)
			(end -0.67945 0.3048)
			(stroke
				(width 0.1)
				(type default)
			)
			(layer "B.Fab")
		)
		(fp_line
			(start -0.67945 0.3048)
			(end -0.120396 0.3048)
			(stroke
				(width 0.1)
				(type default)
			)
			(layer "B.Fab")
		)
		(fp_line
			(start -0.12065 -0.3048)
			(end -0.67945 -0.3048)
			(stroke
				(width 0.1)
				(type default)
			)
			(layer "B.Fab")
		)
		(fp_line
			(start -0.12065 -0.2794)
			(end -0.12065 -0.3048)
			(stroke
				(width 0.1)
				(type default)
			)
			(layer "B.Fab")
		)
		(fp_line
			(start -0.120396 0.2794)
			(end 0.12065 0.2794)
			(stroke
				(width 0.1)
				(type default)
			)
			(layer "B.Fab")
		)
		(fp_line
			(start -0.120396 0.3048)
			(end -0.120396 0.2794)
			(stroke
				(width 0.1)
				(type default)
			)
			(layer "B.Fab")
		)
		(fp_line
			(start 0.12065 -0.305054)
			(end 0.12065 -0.2794)
			(stroke
				(width 0.1)
				(type default)
			)
			(layer "B.Fab")
		)
		(fp_line
			(start 0.12065 -0.2794)
			(end -0.12065 -0.2794)
			(stroke
				(width 0.1)
				(type default)
			)
			(layer "B.Fab")
		)
		(fp_line
			(start 0.12065 0.2794)
			(end 0.12065 0.3048)
			(stroke
				(width 0.1)
				(type default)
			)
			(layer "B.Fab")
		)
		(fp_line
			(start 0.12065 0.3048)
			(end 0.67945 0.3048)
			(stroke
				(width 0.1)
				(type default)
			)
			(layer "B.Fab")
		)
		(fp_line
			(start 0.67945 -0.305054)
			(end 0.12065 -0.305054)
			(stroke
				(width 0.1)
				(type default)
			)
			(layer "B.Fab")
		)
		(fp_line
			(start 0.67945 0.3048)
			(end 0.67945 -0.305054)
			(stroke
				(width 0.1)
				(type default)
			)
			(layer "B.Fab")
		)
		(pad "1" smd circle
			(at 0.40005 0 180)
			(size 0 0)
			(layers "B.Cu" "B.Mask" "B.Paste")
			(net "PVDDCR_CPU1_P0")
		)
		(pad "2" smd circle
			(at -0.40005 0 180)
			(size 0 0)
			(layers "B.Cu" "B.Mask" "B.Paste")
			(net "GND")
		)
	)
	(footprint ""
		(layer "B.Cu")
		(at 415.146236 -396.393162 -90)
		(property "Reference" "C785"
			(at 0 0 90)
			(layer "B.SilkS")
			(hide yes)
			(effects
				(font
					(size 1.27 1.27)
				)
				(justify mirror)
			)
		)
		(property "Value" ""
			(at 0 0 90)
			(layer "B.Fab")
			(effects
				(font
					(size 1.27 1.27)
				)
				(justify mirror)
			)
		)
		(duplicate_pad_numbers_are_jumpers no)
		(fp_line
			(start -0.299974 0.150114)
			(end 0.299974 0.150114)
			(stroke
				(width 0.1)
				(type default)
			)
			(layer "B.Fab")
		)
		(fp_line
			(start 0.299974 0.150114)
			(end 0.299974 -0.150114)
			(stroke
				(width 0.1)
				(type default)
			)
			(layer "B.Fab")
		)
		(fp_line
			(start -0.299974 -0.150114)
			(end -0.299974 0.150114)
			(stroke
				(width 0.1)
				(type default)
			)
			(layer "B.Fab")
		)
		(fp_line
			(start 0.299974 -0.150114)
			(end -0.299974 -0.150114)
			(stroke
				(width 0.1)
				(type default)
			)
			(layer "B.Fab")
		)
		(pad "1" smd rect
			(at 0.2667 0 90)
			(size 0.3048 0.381)
			(layers "B.Cu" "B.Mask" "B.Paste")
			(net "P0V9_CPU0_RT_2D")
		)
		(pad "2" smd rect
			(at -0.2667 0 90)
			(size 0.3048 0.381)
			(layers "B.Cu" "B.Mask" "B.Paste")
			(net "GND")
		)
	)
	(footprint ""
		(layer "B.Cu")
		(at 314.318142 -396.393162 -90)
		(property "Reference" "C516"
			(at 0 0 90)
			(layer "B.SilkS")
			(hide yes)
			(effects
				(font
					(size 1.27 1.27)
				)
				(justify mirror)
			)
		)
		(property "Value" ""
			(at 0 0 90)
			(layer "B.Fab")
			(effects
				(font
					(size 1.27 1.27)
				)
				(justify mirror)
			)
		)
		(duplicate_pad_numbers_are_jumpers no)
		(fp_line
			(start -0.299974 0.150114)
			(end 0.299974 0.150114)
			(stroke
				(width 0.1)
				(type default)
			)
			(layer "B.Fab")
		)
		(fp_line
			(start 0.299974 0.150114)
			(end 0.299974 -0.150114)
			(stroke
				(width 0.1)
				(type default)
			)
			(layer "B.Fab")
		)
		(fp_line
			(start -0.299974 -0.150114)
			(end -0.299974 0.150114)
			(stroke
				(width 0.1)
				(type default)
			)
			(layer "B.Fab")
		)
		(fp_line
			(start 0.299974 -0.150114)
			(end -0.299974 -0.150114)
			(stroke
				(width 0.1)
				(type default)
			)
			(layer "B.Fab")
		)
		(pad "1" smd rect
			(at 0.2667 0 90)
			(size 0.3048 0.381)
			(layers "B.Cu" "B.Mask" "B.Paste")
			(net "P1V8_CPU0_RT0_1A_1D")
		)
		(pad "2" smd rect
			(at -0.2667 0 90)
			(size 0.3048 0.381)
			(layers "B.Cu" "B.Mask" "B.Paste")
			(net "GND")
		)
	)
	(footprint ""
		(layer "B.Cu")
		(at 111.800386 -251.400564 180)
		(property "Reference" "C2277"
			(at 0 0 0)
			(layer "B.SilkS")
			(hide yes)
			(effects
				(font
					(size 1.27 1.27)
				)
				(justify mirror)
			)
		)
		(property "Value" ""
			(at 0 0 0)
			(layer "B.Fab")
			(effects
				(font
					(size 1.27 1.27)
				)
				(justify mirror)
			)
		)
		(duplicate_pad_numbers_are_jumpers no)
		(fp_line
			(start 0.7874 0.4064)
			(end 0.7874 -0.4064)
			(stroke
				(width 0.1524)
				(type default)
			)
			(layer "B.SilkS")
		)
		(fp_line
			(start 0.7874 -0.4064)
			(end -0.7874 -0.4064)
			(stroke
				(width 0.1524)
				(type default)
			)
			(layer "B.SilkS")
		)
		(fp_line
			(start -0.7874 0.4064)
			(end 0.7874 0.4064)
			(stroke
				(width 0.1524)
				(type default)
			)
			(layer "B.SilkS")
		)
		(fp_line
			(start -0.7874 -0.4064)
			(end -0.7874 0.4064)
			(stroke
				(width 0.1524)
				(type default)
			)
			(layer "B.SilkS")
		)
		(fp_line
			(start 0.67945 0.3048)
			(end 0.67945 -0.305054)
			(stroke
				(width 0.1)
				(type default)
			)
			(layer "B.Fab")
		)
		(fp_line
			(start 0.67945 -0.305054)
			(end 0.12065 -0.305054)
			(stroke
				(width 0.1)
				(type default)
			)
			(layer "B.Fab")
		)
		(fp_line
			(start 0.12065 0.3048)
			(end 0.67945 0.3048)
			(stroke
				(width 0.1)
				(type default)
			)
			(layer "B.Fab")
		)
		(fp_line
			(start 0.12065 0.2794)
			(end 0.12065 0.3048)
			(stroke
				(width 0.1)
				(type default)
			)
			(layer "B.Fab")
		)
		(fp_line
			(start 0.12065 -0.2794)
			(end -0.12065 -0.2794)
			(stroke
				(width 0.1)
				(type default)
			)
			(layer "B.Fab")
		)
		(fp_line
			(start 0.12065 -0.305054)
			(end 0.12065 -0.2794)
			(stroke
				(width 0.1)
				(type default)
			)
			(layer "B.Fab")
		)
		(fp_line
			(start -0.120396 0.3048)
			(end -0.120396 0.2794)
			(stroke
				(width 0.1)
				(type default)
			)
			(layer "B.Fab")
		)
		(fp_line
			(start -0.120396 0.2794)
			(end 0.12065 0.2794)
			(stroke
				(width 0.1)
				(type default)
			)
			(layer "B.Fab")
		)
		(fp_line
			(start -0.12065 -0.2794)
			(end -0.12065 -0.3048)
			(stroke
				(width 0.1)
				(type default)
			)
			(layer "B.Fab")
		)
		(fp_line
			(start -0.12065 -0.3048)
			(end -0.67945 -0.3048)
			(stroke
				(width 0.1)
				(type default)
			)
			(layer "B.Fab")
		)
		(fp_line
			(start -0.67945 0.3048)
			(end -0.120396 0.3048)
			(stroke
				(width 0.1)
				(type default)
			)
			(layer "B.Fab")
		)
		(fp_line
			(start -0.67945 -0.3048)
			(end -0.67945 0.3048)
			(stroke
				(width 0.1)
				(type default)
			)
			(layer "B.Fab")
		)
		(pad "1" smd circle
			(at 0.40005 0)
			(size 0 0)
			(layers "B.Cu" "B.Mask" "B.Paste")
			(net "PVDDCR_SOC_P1")
		)
		(pad "2" smd circle
			(at -0.40005 0)
			(size 0 0)
			(layers "B.Cu" "B.Mask" "B.Paste")
			(net "GND")
		)
	)
	(footprint ""
		(layer "B.Cu")
		(at 104.580182 -386.745988 -90)
		(property "Reference" "C127"
			(at 0 0 90)
			(layer "B.SilkS")
			(hide yes)
			(effects
				(font
					(size 1.27 1.27)
				)
				(justify mirror)
			)
		)
		(property "Value" ""
			(at 0 0 90)
			(layer "B.Fab")
			(effects
				(font
					(size 1.27 1.27)
				)
				(justify mirror)
			)
		)
		(duplicate_pad_numbers_are_jumpers no)
		(fp_line
			(start -0.7874 0.4064)
			(end 0.7874 0.4064)
			(stroke
				(width 0.1524)
				(type default)
			)
			(layer "B.SilkS")
		)
		(fp_line
			(start 0.7874 0.4064)
			(end 0.7874 -0.4064)
			(stroke
				(width 0.1524)
				(type default)
			)
			(layer "B.SilkS")
		)
		(fp_line
			(start -0.7874 -0.4064)
			(end -0.7874 0.4064)
			(stroke
				(width 0.1524)
				(type default)
			)
			(layer "B.SilkS")
		)
		(fp_line
			(start 0.7874 -0.4064)
			(end -0.7874 -0.4064)
			(stroke
				(width 0.1524)
				(type default)
			)
			(layer "B.SilkS")
		)
		(fp_line
			(start -0.67945 0.3048)
			(end -0.120396 0.3048)
			(stroke
				(width 0.1)
				(type default)
			)
			(layer "B.Fab")
		)
		(fp_line
			(start -0.120396 0.3048)
			(end -0.120396 0.2794)
			(stroke
				(width 0.1)
				(type default)
			)
			(layer "B.Fab")
		)
		(fp_line
			(start 0.12065 0.3048)
			(end 0.67945 0.3048)
			(stroke
				(width 0.1)
				(type default)
			)
			(layer "B.Fab")
		)
		(fp_line
			(start 0.67945 0.3048)
			(end 0.67945 -0.305054)
			(stroke
				(width 0.1)
				(type default)
			)
			(layer "B.Fab")
		)
		(fp_line
			(start -0.120396 0.2794)
			(end 0.12065 0.2794)
			(stroke
				(width 0.1)
				(type default)
			)
			(layer "B.Fab")
		)
		(fp_line
			(start 0.12065 0.2794)
			(end 0.12065 0.3048)
			(stroke
				(width 0.1)
				(type default)
			)
			(layer "B.Fab")
		)
		(fp_line
			(start -0.12065 -0.2794)
			(end -0.12065 -0.3048)
			(stroke
				(width 0.1)
				(type default)
			)
			(layer "B.Fab")
		)
		(fp_line
			(start 0.12065 -0.2794)
			(end -0.12065 -0.2794)
			(stroke
				(width 0.1)
				(type default)
			)
			(layer "B.Fab")
		)
		(fp_line
			(start -0.67945 -0.3048)
			(end -0.67945 0.3048)
			(stroke
				(width 0.1)
				(type default)
			)
			(layer "B.Fab")
		)
		(fp_line
			(start -0.12065 -0.3048)
			(end -0.67945 -0.3048)
			(stroke
				(width 0.1)
				(type default)
			)
			(layer "B.Fab")
		)
		(fp_line
			(start 0.12065 -0.305054)
			(end 0.12065 -0.2794)
			(stroke
				(width 0.1)
				(type default)
			)
			(layer "B.Fab")
		)
		(fp_line
			(start 0.67945 -0.305054)
			(end 0.12065 -0.305054)
			(stroke
				(width 0.1)
				(type default)
			)
			(layer "B.Fab")
		)
		(pad "1" smd circle
			(at 0.40005 0 90)
			(size 0 0)
			(layers "B.Cu" "B.Mask" "B.Paste")
			(net "P1V8_CPU1_RT_1D")
		)
		(pad "2" smd circle
			(at -0.40005 0 90)
			(size 0 0)
			(layers "B.Cu" "B.Mask" "B.Paste")
			(net "GND")
		)
	)
	(footprint ""
		(layer "B.Cu")
		(at 393.617958 -325.878952)
		(property "Reference" "R471"
			(at 0 0 0)
			(layer "B.SilkS")
			(hide yes)
			(effects
				(font
					(size 1.27 1.27)
				)
				(justify mirror)
			)
		)
		(property "Value" ""
			(at 0 0 0)
			(layer "B.Fab")
			(effects
				(font
					(size 1.27 1.27)
				)
				(justify mirror)
			)
		)
		(duplicate_pad_numbers_are_jumpers no)
		(fp_line
			(start -0.7874 -0.4064)
			(end -0.7874 0.4064)
			(stroke
				(width 0.1524)
				(type default)
			)
			(layer "B.SilkS")
		)
		(fp_line
			(start -0.7874 0.4064)
			(end 0.7874 0.4064)
			(stroke
				(width 0.1524)
				(type default)
			)
			(layer "B.SilkS")
		)
		(fp_line
			(start 0.7874 -0.4064)
			(end -0.7874 -0.4064)
			(stroke
				(width 0.1524)
				(type default)
			)
			(layer "B.SilkS")
		)
		(fp_line
			(start 0.7874 0.4064)
			(end 0.7874 -0.4064)
			(stroke
				(width 0.1524)
				(type default)
			)
			(layer "B.SilkS")
		)
		(fp_line
			(start -0.67945 -0.3048)
			(end -0.67945 0.3048)
			(stroke
				(width 0.1)
				(type default)
			)
			(layer "B.Fab")
		)
		(fp_line
			(start -0.67945 0.3048)
			(end -0.120396 0.3048)
			(stroke
				(width 0.1)
				(type default)
			)
			(layer "B.Fab")
		)
		(fp_line
			(start -0.12065 -0.3048)
			(end -0.67945 -0.3048)
			(stroke
				(width 0.1)
				(type default)
			)
			(layer "B.Fab")
		)
		(fp_line
			(start -0.12065 -0.2794)
			(end -0.12065 -0.3048)
			(stroke
				(width 0.1)
				(type default)
			)
			(layer "B.Fab")
		)
		(fp_line
			(start -0.120396 0.2794)
			(end 0.12065 0.2794)
			(stroke
				(width 0.1)
				(type default)
			)
			(layer "B.Fab")
		)
		(fp_line
			(start -0.120396 0.3048)
			(end -0.120396 0.2794)
			(stroke
				(width 0.1)
				(type default)
			)
			(layer "B.Fab")
		)
		(fp_line
			(start 0.12065 -0.305054)
			(end 0.12065 -0.2794)
			(stroke
				(width 0.1)
				(type default)
			)
			(layer "B.Fab")
		)
		(fp_line
			(start 0.12065 -0.2794)
			(end -0.12065 -0.2794)
			(stroke
				(width 0.1)
				(type default)
			)
			(layer "B.Fab")
		)
		(fp_line
			(start 0.12065 0.2794)
			(end 0.12065 0.3048)
			(stroke
				(width 0.1)
				(type default)
			)
			(layer "B.Fab")
		)
		(fp_line
			(start 0.12065 0.3048)
			(end 0.67945 0.3048)
			(stroke
				(width 0.1)
				(type default)
			)
			(layer "B.Fab")
		)
		(fp_line
			(start 0.67945 -0.305054)
			(end 0.12065 -0.305054)
			(stroke
				(width 0.1)
				(type default)
			)
			(layer "B.Fab")
		)
		(fp_line
			(start 0.67945 0.3048)
			(end 0.67945 -0.305054)
			(stroke
				(width 0.1)
				(type default)
			)
			(layer "B.Fab")
		)
		(pad "1" smd circle
			(at 0.40005 0 180)
			(size 0 0)
			(layers "B.Cu" "B.Mask" "B.Paste")
			(net "ESPI_CPU0_D3")
		)
		(pad "2" smd circle
			(at -0.40005 0 180)
			(size 0 0)
			(layers "B.Cu" "B.Mask" "B.Paste")
			(net "ESPI_CPU0_R_D3")
		)
	)
	(footprint ""
		(layer "B.Cu")
		(at 283.980636 -193.99631)
		(property "Reference" "C100"
			(at 0 0 0)
			(layer "B.SilkS")
			(hide yes)
			(effects
				(font
					(size 1.27 1.27)
				)
				(justify mirror)
			)
		)
		(property "Value" ""
			(at 0 0 0)
			(layer "B.Fab")
			(effects
				(font
					(size 1.27 1.27)
				)
				(justify mirror)
			)
		)
		(duplicate_pad_numbers_are_jumpers no)
		(fp_line
			(start -0.7874 -0.4064)
			(end -0.7874 0.4064)
			(stroke
				(width 0.1524)
				(type default)
			)
			(layer "B.SilkS")
		)
		(fp_line
			(start -0.7874 0.4064)
			(end 0.7874 0.4064)
			(stroke
				(width 0.1524)
				(type default)
			)
			(layer "B.SilkS")
		)
		(fp_line
			(start 0.7874 -0.4064)
			(end -0.7874 -0.4064)
			(stroke
				(width 0.1524)
				(type default)
			)
			(layer "B.SilkS")
		)
		(fp_line
			(start 0.7874 0.4064)
			(end 0.7874 -0.4064)
			(stroke
				(width 0.1524)
				(type default)
			)
			(layer "B.SilkS")
		)
		(fp_line
			(start -0.67945 -0.3048)
			(end -0.67945 0.3048)
			(stroke
				(width 0.1)
				(type default)
			)
			(layer "B.Fab")
		)
		(fp_line
			(start -0.67945 0.3048)
			(end -0.120396 0.3048)
			(stroke
				(width 0.1)
				(type default)
			)
			(layer "B.Fab")
		)
		(fp_line
			(start -0.12065 -0.3048)
			(end -0.67945 -0.3048)
			(stroke
				(width 0.1)
				(type default)
			)
			(layer "B.Fab")
		)
		(fp_line
			(start -0.12065 -0.2794)
			(end -0.12065 -0.3048)
			(stroke
				(width 0.1)
				(type default)
			)
			(layer "B.Fab")
		)
		(fp_line
			(start -0.120396 0.2794)
			(end 0.12065 0.2794)
			(stroke
				(width 0.1)
				(type default)
			)
			(layer "B.Fab")
		)
		(fp_line
			(start -0.120396 0.3048)
			(end -0.120396 0.2794)
			(stroke
				(width 0.1)
				(type default)
			)
			(layer "B.Fab")
		)
		(fp_line
			(start 0.12065 -0.305054)
			(end 0.12065 -0.2794)
			(stroke
				(width 0.1)
				(type default)
			)
			(layer "B.Fab")
		)
		(fp_line
			(start 0.12065 -0.2794)
			(end -0.12065 -0.2794)
			(stroke
				(width 0.1)
				(type default)
			)
			(layer "B.Fab")
		)
		(fp_line
			(start 0.12065 0.2794)
			(end 0.12065 0.3048)
			(stroke
				(width 0.1)
				(type default)
			)
			(layer "B.Fab")
		)
		(fp_line
			(start 0.12065 0.3048)
			(end 0.67945 0.3048)
			(stroke
				(width 0.1)
				(type default)
			)
			(layer "B.Fab")
		)
		(fp_line
			(start 0.67945 -0.305054)
			(end 0.12065 -0.305054)
			(stroke
				(width 0.1)
				(type default)
			)
			(layer "B.Fab")
		)
		(fp_line
			(start 0.67945 0.3048)
			(end 0.67945 -0.305054)
			(stroke
				(width 0.1)
				(type default)
			)
			(layer "B.Fab")
		)
		(pad "1" smd circle
			(at 0.40005 0 180)
			(size 0 0)
			(layers "B.Cu" "B.Mask" "B.Paste")
			(net "P3V3_AUX")
		)
		(pad "2" smd circle
			(at -0.40005 0 180)
			(size 0 0)
			(layers "B.Cu" "B.Mask" "B.Paste")
			(net "GND")
		)
	)
	(footprint ""
		(layer "B.Cu")
		(at 238.633 -339.598 180)
		(property "Reference" "R807"
			(at 0 0 0)
			(layer "B.SilkS")
			(hide yes)
			(effects
				(font
					(size 1.27 1.27)
				)
				(justify mirror)
			)
		)
		(property "Value" ""
			(at 0 0 0)
			(layer "B.Fab")
			(effects
				(font
					(size 1.27 1.27)
				)
				(justify mirror)
			)
		)
		(duplicate_pad_numbers_are_jumpers no)
		(fp_line
			(start 0.32512 0.175006)
			(end 0.32512 -0.175006)
			(stroke
				(width 0.1)
				(type default)
			)
			(layer "B.Fab")
		)
		(fp_line
			(start 0.32512 -0.175006)
			(end -0.32512 -0.175006)
			(stroke
				(width 0.1)
				(type default)
			)
			(layer "B.Fab")
		)
		(fp_line
			(start -0.32512 0.175006)
			(end 0.32512 0.175006)
			(stroke
				(width 0.1)
				(type default)
			)
			(layer "B.Fab")
		)
		(fp_line
			(start -0.32512 -0.175006)
			(end -0.32512 0.175006)
			(stroke
				(width 0.1)
				(type default)
			)
			(layer "B.Fab")
		)
		(pad "1" smd rect
			(at 0.2667 0)
			(size 0.3048 0.381)
			(layers "B.Cu" "B.Mask" "B.Paste")
			(net "SMB_RT_CPU1_P3_ROM_MUX_2D_SCL")
		)
		(pad "2" smd rect
			(at -0.2667 0 180)
			(size 0.3048 0.381)
			(layers "B.Cu" "B.Mask" "B.Paste")
			(net "SMB_RT_CPU1_P3_ROM_MUX_2D_R_SCL")
		)
	)
	(footprint ""
		(layer "B.Cu")
		(at 108.933996 -26.952448 90)
		(property "Reference" "C6097"
			(at 0 0 90)
			(layer "B.SilkS")
			(hide yes)
			(effects
				(font
					(size 1.27 1.27)
				)
				(justify mirror)
			)
		)
		(property "Value" ""
			(at 0 0 90)
			(layer "B.Fab")
			(effects
				(font
					(size 1.27 1.27)
				)
				(justify mirror)
			)
		)
		(duplicate_pad_numbers_are_jumpers no)
		(fp_line
			(start 0.7874 -0.4064)
			(end -0.7874 -0.4064)
			(stroke
				(width 0.1524)
				(type default)
			)
			(layer "B.SilkS")
		)
		(fp_line
			(start -0.7874 -0.4064)
			(end -0.7874 0.4064)
			(stroke
				(width 0.1524)
				(type default)
			)
			(layer "B.SilkS")
		)
		(fp_line
			(start 0.7874 0.4064)
			(end 0.7874 -0.4064)
			(stroke
				(width 0.1524)
				(type default)
			)
			(layer "B.SilkS")
		)
		(fp_line
			(start -0.7874 0.4064)
			(end 0.7874 0.4064)
			(stroke
				(width 0.1524)
				(type default)
			)
			(layer "B.SilkS")
		)
		(fp_line
			(start 0.67945 -0.305054)
			(end 0.12065 -0.305054)
			(stroke
				(width 0.1)
				(type default)
			)
			(layer "B.Fab")
		)
		(fp_line
			(start 0.12065 -0.305054)
			(end 0.12065 -0.2794)
			(stroke
				(width 0.1)
				(type default)
			)
			(layer "B.Fab")
		)
		(fp_line
			(start -0.12065 -0.3048)
			(end -0.67945 -0.3048)
			(stroke
				(width 0.1)
				(type default)
			)
			(layer "B.Fab")
		)
		(fp_line
			(start -0.67945 -0.3048)
			(end -0.67945 0.3048)
			(stroke
				(width 0.1)
				(type default)
			)
			(layer "B.Fab")
		)
		(fp_line
			(start 0.12065 -0.2794)
			(end -0.12065 -0.2794)
			(stroke
				(width 0.1)
				(type default)
			)
			(layer "B.Fab")
		)
		(fp_line
			(start -0.12065 -0.2794)
			(end -0.12065 -0.3048)
			(stroke
				(width 0.1)
				(type default)
			)
			(layer "B.Fab")
		)
		(fp_line
			(start 0.12065 0.2794)
			(end 0.12065 0.3048)
			(stroke
				(width 0.1)
				(type default)
			)
			(layer "B.Fab")
		)
		(fp_line
			(start -0.120396 0.2794)
			(end 0.12065 0.2794)
			(stroke
				(width 0.1)
				(type default)
			)
			(layer "B.Fab")
		)
		(fp_line
			(start 0.67945 0.3048)
			(end 0.67945 -0.305054)
			(stroke
				(width 0.1)
				(type default)
			)
			(layer "B.Fab")
		)
		(fp_line
			(start 0.12065 0.3048)
			(end 0.67945 0.3048)
			(stroke
				(width 0.1)
				(type default)
			)
			(layer "B.Fab")
		)
		(fp_line
			(start -0.120396 0.3048)
			(end -0.120396 0.2794)
			(stroke
				(width 0.1)
				(type default)
			)
			(layer "B.Fab")
		)
		(fp_line
			(start -0.67945 0.3048)
			(end -0.120396 0.3048)
			(stroke
				(width 0.1)
				(type default)
			)
			(layer "B.Fab")
		)
		(pad "1" smd circle
			(at 0.40005 0 270)
			(size 0 0)
			(layers "B.Cu" "B.Mask" "B.Paste")
			(net "P3V3_AUX_CPU0_USB2_AVDD33")
		)
		(pad "2" smd circle
			(at -0.40005 0 270)
			(size 0 0)
			(layers "B.Cu" "B.Mask" "B.Paste")
			(net "GND")
		)
	)
	(footprint ""
		(layer "B.Cu")
		(at 429.103282 -438.192672 -90)
		(property "Reference" "C7"
			(at 0 0 90)
			(layer "B.SilkS")
			(hide yes)
			(effects
				(font
					(size 1.27 1.27)
				)
				(justify mirror)
			)
		)
		(property "Value" ""
			(at 0 0 90)
			(layer "B.Fab")
			(effects
				(font
					(size 1.27 1.27)
				)
				(justify mirror)
			)
		)
		(duplicate_pad_numbers_are_jumpers no)
		(fp_line
			(start -0.7874 0.4064)
			(end 0.7874 0.4064)
			(stroke
				(width 0.1524)
				(type default)
			)
			(layer "B.SilkS")
		)
		(fp_line
			(start 0.7874 0.4064)
			(end 0.7874 -0.4064)
			(stroke
				(width 0.1524)
				(type default)
			)
			(layer "B.SilkS")
		)
		(fp_line
			(start -0.7874 -0.4064)
			(end -0.7874 0.4064)
			(stroke
				(width 0.1524)
				(type default)
			)
			(layer "B.SilkS")
		)
		(fp_line
			(start 0.7874 -0.4064)
			(end -0.7874 -0.4064)
			(stroke
				(width 0.1524)
				(type default)
			)
			(layer "B.SilkS")
		)
		(fp_line
			(start -0.67945 0.3048)
			(end -0.120396 0.3048)
			(stroke
				(width 0.1)
				(type default)
			)
			(layer "B.Fab")
		)
		(fp_line
			(start -0.120396 0.3048)
			(end -0.120396 0.2794)
			(stroke
				(width 0.1)
				(type default)
			)
			(layer "B.Fab")
		)
		(fp_line
			(start 0.12065 0.3048)
			(end 0.67945 0.3048)
			(stroke
				(width 0.1)
				(type default)
			)
			(layer "B.Fab")
		)
		(fp_line
			(start 0.67945 0.3048)
			(end 0.67945 -0.305054)
			(stroke
				(width 0.1)
				(type default)
			)
			(layer "B.Fab")
		)
		(fp_line
			(start -0.120396 0.2794)
			(end 0.12065 0.2794)
			(stroke
				(width 0.1)
				(type default)
			)
			(layer "B.Fab")
		)
		(fp_line
			(start 0.12065 0.2794)
			(end 0.12065 0.3048)
			(stroke
				(width 0.1)
				(type default)
			)
			(layer "B.Fab")
		)
		(fp_line
			(start -0.12065 -0.2794)
			(end -0.12065 -0.3048)
			(stroke
				(width 0.1)
				(type default)
			)
			(layer "B.Fab")
		)
		(fp_line
			(start 0.12065 -0.2794)
			(end -0.12065 -0.2794)
			(stroke
				(width 0.1)
				(type default)
			)
			(layer "B.Fab")
		)
		(fp_line
			(start -0.67945 -0.3048)
			(end -0.67945 0.3048)
			(stroke
				(width 0.1)
				(type default)
			)
			(layer "B.Fab")
		)
		(fp_line
			(start -0.12065 -0.3048)
			(end -0.67945 -0.3048)
			(stroke
				(width 0.1)
				(type default)
			)
			(layer "B.Fab")
		)
		(fp_line
			(start 0.12065 -0.305054)
			(end 0.12065 -0.2794)
			(stroke
				(width 0.1)
				(type default)
			)
			(layer "B.Fab")
		)
		(fp_line
			(start 0.67945 -0.305054)
			(end 0.12065 -0.305054)
			(stroke
				(width 0.1)
				(type default)
			)
			(layer "B.Fab")
		)
		(pad "1" smd circle
			(at 0.40005 0 90)
			(size 0 0)
			(layers "B.Cu" "B.Mask" "B.Paste")
			(net "GPU_3V3IO_RSVD3_ISO")
		)
		(pad "2" smd circle
			(at -0.40005 0 90)
			(size 0 0)
			(layers "B.Cu" "B.Mask" "B.Paste")
			(net "GND")
		)
	)
	(footprint ""
		(layer "B.Cu")
		(at 129.567686 -408.517344 90)
		(property "Reference" "C6733"
			(at 0 0 90)
			(layer "B.SilkS")
			(hide yes)
			(effects
				(font
					(size 1.27 1.27)
				)
				(justify mirror)
			)
		)
		(property "Value" ""
			(at 0 0 90)
			(layer "B.Fab")
			(effects
				(font
					(size 1.27 1.27)
				)
				(justify mirror)
			)
		)
		(duplicate_pad_numbers_are_jumpers no)
		(fp_line
			(start 0.299974 -0.150114)
			(end -0.299974 -0.150114)
			(stroke
				(width 0.1)
				(type default)
			)
			(layer "B.Fab")
		)
		(fp_line
			(start -0.299974 -0.150114)
			(end -0.299974 0.150114)
			(stroke
				(width 0.1)
				(type default)
			)
			(layer "B.Fab")
		)
		(fp_line
			(start 0.299974 0.150114)
			(end 0.299974 -0.150114)
			(stroke
				(width 0.1)
				(type default)
			)
			(layer "B.Fab")
		)
		(fp_line
			(start -0.299974 0.150114)
			(end 0.299974 0.150114)
			(stroke
				(width 0.1)
				(type default)
			)
			(layer "B.Fab")
		)
		(pad "1" smd rect
			(at 0.2667 0 270)
			(size 0.3048 0.381)
			(layers "B.Cu" "B.Mask" "B.Paste")
			(net "P5E_CPU1_P3_TX_BUF_C_DP<4>")
		)
		(pad "2" smd rect
			(at -0.2667 0 270)
			(size 0.3048 0.381)
			(layers "B.Cu" "B.Mask" "B.Paste")
			(net "P5E_CPU1_P3_TX_BUF_DP<4>")
		)
	)
	(footprint ""
		(layer "B.Cu")
		(at 397.788892 -201.308208)
		(property "Reference" "R589"
			(at 0 0 0)
			(layer "B.SilkS")
			(hide yes)
			(effects
				(font
					(size 1.27 1.27)
				)
				(justify mirror)
			)
		)
		(property "Value" ""
			(at 0 0 0)
			(layer "B.Fab")
			(effects
				(font
					(size 1.27 1.27)
				)
				(justify mirror)
			)
		)
		(duplicate_pad_numbers_are_jumpers no)
		(fp_line
			(start -0.7874 -0.4064)
			(end -0.7874 0.4064)
			(stroke
				(width 0.1524)
				(type default)
			)
			(layer "B.SilkS")
		)
		(fp_line
			(start -0.7874 0.4064)
			(end 0.7874 0.4064)
			(stroke
				(width 0.1524)
				(type default)
			)
			(layer "B.SilkS")
		)
		(fp_line
			(start 0.7874 -0.4064)
			(end -0.7874 -0.4064)
			(stroke
				(width 0.1524)
				(type default)
			)
			(layer "B.SilkS")
		)
		(fp_line
			(start 0.7874 0.4064)
			(end 0.7874 -0.4064)
			(stroke
				(width 0.1524)
				(type default)
			)
			(layer "B.SilkS")
		)
		(fp_line
			(start -0.67945 -0.3048)
			(end -0.67945 0.3048)
			(stroke
				(width 0.1)
				(type default)
			)
			(layer "B.Fab")
		)
		(fp_line
			(start -0.67945 0.3048)
			(end -0.120396 0.3048)
			(stroke
				(width 0.1)
				(type default)
			)
			(layer "B.Fab")
		)
		(fp_line
			(start -0.12065 -0.3048)
			(end -0.67945 -0.3048)
			(stroke
				(width 0.1)
				(type default)
			)
			(layer "B.Fab")
		)
		(fp_line
			(start -0.12065 -0.2794)
			(end -0.12065 -0.3048)
			(stroke
				(width 0.1)
				(type default)
			)
			(layer "B.Fab")
		)
		(fp_line
			(start -0.120396 0.2794)
			(end 0.12065 0.2794)
			(stroke
				(width 0.1)
				(type default)
			)
			(layer "B.Fab")
		)
		(fp_line
			(start -0.120396 0.3048)
			(end -0.120396 0.2794)
			(stroke
				(width 0.1)
				(type default)
			)
			(layer "B.Fab")
		)
		(fp_line
			(start 0.12065 -0.305054)
			(end 0.12065 -0.2794)
			(stroke
				(width 0.1)
				(type default)
			)
			(layer "B.Fab")
		)
		(fp_line
			(start 0.12065 -0.2794)
			(end -0.12065 -0.2794)
			(stroke
				(width 0.1)
				(type default)
			)
			(layer "B.Fab")
		)
		(fp_line
			(start 0.12065 0.2794)
			(end 0.12065 0.3048)
			(stroke
				(width 0.1)
				(type default)
			)
			(layer "B.Fab")
		)
		(fp_line
			(start 0.12065 0.3048)
			(end 0.67945 0.3048)
			(stroke
				(width 0.1)
				(type default)
			)
			(layer "B.Fab")
		)
		(fp_line
			(start 0.67945 -0.305054)
			(end 0.12065 -0.305054)
			(stroke
				(width 0.1)
				(type default)
			)
			(layer "B.Fab")
		)
		(fp_line
			(start 0.67945 0.3048)
			(end 0.67945 -0.305054)
			(stroke
				(width 0.1)
				(type default)
			)
			(layer "B.Fab")
		)
		(pad "1" smd circle
			(at 0.40005 0 180)
			(size 0 0)
			(layers "B.Cu" "B.Mask" "B.Paste")
			(net "SCM_USB_OC_BU_R_N")
		)
		(pad "2" smd circle
			(at -0.40005 0 180)
			(size 0 0)
			(layers "B.Cu" "B.Mask" "B.Paste")
			(net "SCM_USB_OC_BUF_N")
		)
	)
	(footprint ""
		(layer "B.Cu")
		(at 350.446086 -396.393162 -90)
		(property "Reference" "C627"
			(at 0 0 90)
			(layer "B.SilkS")
			(hide yes)
			(effects
				(font
					(size 1.27 1.27)
				)
				(justify mirror)
			)
		)
		(property "Value" ""
			(at 0 0 90)
			(layer "B.Fab")
			(effects
				(font
					(size 1.27 1.27)
				)
				(justify mirror)
			)
		)
		(duplicate_pad_numbers_are_jumpers no)
		(fp_line
			(start -0.299974 0.150114)
			(end 0.299974 0.150114)
			(stroke
				(width 0.1)
				(type default)
			)
			(layer "B.Fab")
		)
		(fp_line
			(start 0.299974 0.150114)
			(end 0.299974 -0.150114)
			(stroke
				(width 0.1)
				(type default)
			)
			(layer "B.Fab")
		)
		(fp_line
			(start -0.299974 -0.150114)
			(end -0.299974 0.150114)
			(stroke
				(width 0.1)
				(type default)
			)
			(layer "B.Fab")
		)
		(fp_line
			(start 0.299974 -0.150114)
			(end -0.299974 -0.150114)
			(stroke
				(width 0.1)
				(type default)
			)
			(layer "B.Fab")
		)
		(pad "1" smd rect
			(at 0.2667 0 90)
			(size 0.3048 0.381)
			(layers "B.Cu" "B.Mask" "B.Paste")
			(net "P0V9_CPU0_RT1_2A")
		)
		(pad "2" smd rect
			(at -0.2667 0 90)
			(size 0.3048 0.381)
			(layers "B.Cu" "B.Mask" "B.Paste")
			(net "GND")
		)
	)
	(footprint ""
		(layer "B.Cu")
		(at 298.565316 -425.288964)
		(property "Reference" "U49"
			(at 0.087884 -4.071366 0)
			(unlocked yes)
			(layer "B.SilkS")
			(effects
				(font
					(size 0.7874 0.5842)
					(thickness 0.1524)
				)
				(justify mirror)
			)
		)
		(property "Value" ""
			(at 0 0 0)
			(layer "B.Fab")
			(effects
				(font
					(size 1.27 1.27)
				)
				(justify mirror)
			)
		)
		(duplicate_pad_numbers_are_jumpers no)
		(fp_line
			(start -1.03378 -1.284478)
			(end -1.03378 1.284478)
			(stroke
				(width 0.1524)
				(type default)
			)
			(layer "B.SilkS")
		)
		(fp_line
			(start -1.03378 1.284478)
			(end 1.03378 1.284478)
			(stroke
				(width 0.1524)
				(type default)
			)
			(layer "B.SilkS")
		)
		(fp_line
			(start 1.03378 -1.284478)
			(end -1.03378 -1.284478)
			(stroke
				(width 0.1524)
				(type default)
			)
			(layer "B.SilkS")
		)
		(fp_line
			(start 1.03378 1.284478)
			(end 1.03378 -1.284478)
			(stroke
				(width 0.1524)
				(type default)
			)
			(layer "B.SilkS")
		)
		(fp_poly
			(pts
				(xy 1.201674 -0.750062) (xy 1.806702 -0.447548) (xy 1.806702 -1.052576)
			)
			(stroke
				(width 0)
				(type default)
			)
			(fill yes)
			(layer "B.SilkS")
		)
		(fp_line
			(start -0.774954 -1.02489)
			(end -0.774954 1.02489)
			(stroke
				(width 0.1)
				(type default)
			)
			(layer "B.Fab")
		)
		(fp_line
			(start -0.774954 1.02489)
			(end 0.774954 1.02489)
			(stroke
				(width 0.1)
				(type default)
			)
			(layer "B.Fab")
		)
		(fp_line
			(start 0.774954 -1.02489)
			(end -0.774954 -1.02489)
			(stroke
				(width 0.1)
				(type default)
			)
			(layer "B.Fab")
		)
		(fp_line
			(start 0.774954 1.02489)
			(end 0.774954 -1.02489)
			(stroke
				(width 0.1)
				(type default)
			)
			(layer "B.Fab")
		)
		(fp_poly
			(pts
				(xy 1.201674 -0.750062) (xy 1.806702 -0.447548) (xy 1.806702 -1.052576)
			)
			(stroke
				(width 0)
				(type default)
			)
			(fill yes)
			(layer "B.Fab")
		)
		(pad "1" smd rect
			(at 0.64008 -0.750062 90)
			(size 0.3048 0.5334)
			(layers "B.Cu" "B.Mask" "B.Paste")
			(net "SMB_RT_CPU0_P0_ROM_MUX_1D_SCL")
		)
		(pad "2" smd rect
			(at 0.64008 -0.249936 90)
			(size 0.254 0.5334)
			(layers "B.Cu" "B.Mask" "B.Paste")
			(net "SMB_RT_CPU0_P0_ROM_MUX_1D_SDA")
		)
		(pad "3" smd rect
			(at 0.64008 0.249936 90)
			(size 0.254 0.5334)
			(layers "B.Cu" "B.Mask" "B.Paste")
			(net "SMB_RT_CPU0_P0_ROM_MUX_2D_SCL")
		)
		(pad "4" smd rect
			(at 0.64008 0.750062 90)
			(size 0.3048 0.5334)
			(layers "B.Cu" "B.Mask" "B.Paste")
			(net "SMB_RT_CPU0_P0_ROM_MUX_2D_SDA")
		)
		(pad "5" smd rect
			(at 0 0.839978 180)
			(size 0.3302 0.635)
			(layers "B.Cu" "B.Mask" "B.Paste")
			(net "GND")
		)
		(pad "6" smd rect
			(at -0.64008 0.750062 90)
			(size 0.3048 0.5334)
			(layers "B.Cu" "B.Mask" "B.Paste")
			(net "RT_ROM_MUX5_OE_N")
		)
		(pad "7" smd rect
			(at -0.64008 0.249936 90)
			(size 0.254 0.5334)
			(layers "B.Cu" "B.Mask" "B.Paste")
			(net "SMB_RT_CPU0_P0_ROM_R_SDA")
		)
		(pad "8" smd rect
			(at -0.64008 -0.249936 90)
			(size 0.254 0.5334)
			(layers "B.Cu" "B.Mask" "B.Paste")
			(net "SMB_RT_CPU0_P0_ROM_R_SCL")
		)
		(pad "9" smd rect
			(at -0.64008 -0.750062 90)
			(size 0.3048 0.5334)
			(layers "B.Cu" "B.Mask" "B.Paste")
			(net "FM_SMB_RT_ROM_MUX5_SEL")
		)
		(pad "10" smd rect
			(at 0 -0.839978 180)
			(size 0.3302 0.635)
			(layers "B.Cu" "B.Mask" "B.Paste")
			(net "P3V3_AUX")
		)
	)
	(footprint ""
		(layer "B.Cu")
		(at 216.0905 -322.52539)
		(property "Reference" "R1268"
			(at 0 0 0)
			(layer "B.SilkS")
			(hide yes)
			(effects
				(font
					(size 1.27 1.27)
				)
				(justify mirror)
			)
		)
		(property "Value" ""
			(at 0 0 0)
			(layer "B.Fab")
			(effects
				(font
					(size 1.27 1.27)
				)
				(justify mirror)
			)
		)
		(duplicate_pad_numbers_are_jumpers no)
		(fp_line
			(start -0.7874 -0.4064)
			(end -0.7874 0.4064)
			(stroke
				(width 0.1524)
				(type default)
			)
			(layer "B.SilkS")
		)
		(fp_line
			(start -0.7874 0.4064)
			(end 0.7874 0.4064)
			(stroke
				(width 0.1524)
				(type default)
			)
			(layer "B.SilkS")
		)
		(fp_line
			(start 0.7874 -0.4064)
			(end -0.7874 -0.4064)
			(stroke
				(width 0.1524)
				(type default)
			)
			(layer "B.SilkS")
		)
		(fp_line
			(start 0.7874 0.4064)
			(end 0.7874 -0.4064)
			(stroke
				(width 0.1524)
				(type default)
			)
			(layer "B.SilkS")
		)
		(fp_line
			(start -0.67945 -0.3048)
			(end -0.67945 0.3048)
			(stroke
				(width 0.1)
				(type default)
			)
			(layer "B.Fab")
		)
		(fp_line
			(start -0.67945 0.3048)
			(end -0.120396 0.3048)
			(stroke
				(width 0.1)
				(type default)
			)
			(layer "B.Fab")
		)
		(fp_line
			(start -0.12065 -0.3048)
			(end -0.67945 -0.3048)
			(stroke
				(width 0.1)
				(type default)
			)
			(layer "B.Fab")
		)
		(fp_line
			(start -0.12065 -0.2794)
			(end -0.12065 -0.3048)
			(stroke
				(width 0.1)
				(type default)
			)
			(layer "B.Fab")
		)
		(fp_line
			(start -0.120396 0.2794)
			(end 0.12065 0.2794)
			(stroke
				(width 0.1)
				(type default)
			)
			(layer "B.Fab")
		)
		(fp_line
			(start -0.120396 0.3048)
			(end -0.120396 0.2794)
			(stroke
				(width 0.1)
				(type default)
			)
			(layer "B.Fab")
		)
		(fp_line
			(start 0.12065 -0.305054)
			(end 0.12065 -0.2794)
			(stroke
				(width 0.1)
				(type default)
			)
			(layer "B.Fab")
		)
		(fp_line
			(start 0.12065 -0.2794)
			(end -0.12065 -0.2794)
			(stroke
				(width 0.1)
				(type default)
			)
			(layer "B.Fab")
		)
		(fp_line
			(start 0.12065 0.2794)
			(end 0.12065 0.3048)
			(stroke
				(width 0.1)
				(type default)
			)
			(layer "B.Fab")
		)
		(fp_line
			(start 0.12065 0.3048)
			(end 0.67945 0.3048)
			(stroke
				(width 0.1)
				(type default)
			)
			(layer "B.Fab")
		)
		(fp_line
			(start 0.67945 -0.305054)
			(end 0.12065 -0.305054)
			(stroke
				(width 0.1)
				(type default)
			)
			(layer "B.Fab")
		)
		(fp_line
			(start 0.67945 0.3048)
			(end 0.67945 -0.305054)
			(stroke
				(width 0.1)
				(type default)
			)
			(layer "B.Fab")
		)
		(pad "1" smd circle
			(at 0.40005 0 180)
			(size 0 0)
			(layers "B.Cu" "B.Mask" "B.Paste")
			(net "ADC128_2_VREF")
		)
		(pad "2" smd circle
			(at -0.40005 0 180)
			(size 0 0)
			(layers "B.Cu" "B.Mask" "B.Paste")
			(net "GND")
		)
	)
	(footprint ""
		(layer "B.Cu")
		(at 131.321048 -156.393134 -90)
		(property "Reference" "PC350_3"
			(at 0 0 90)
			(layer "B.SilkS")
			(hide yes)
			(effects
				(font
					(size 1.27 1.27)
				)
				(justify mirror)
			)
		)
		(property "Value" ""
			(at 0 0 90)
			(layer "B.Fab")
			(effects
				(font
					(size 1.27 1.27)
				)
				(justify mirror)
			)
		)
		(duplicate_pad_numbers_are_jumpers no)
		(fp_line
			(start -1.524 0.762)
			(end 1.524 0.762)
			(stroke
				(width 0.1524)
				(type default)
			)
			(layer "B.SilkS")
		)
		(fp_line
			(start 1.524 0.762)
			(end 1.524 -0.762)
			(stroke
				(width 0.1524)
				(type default)
			)
			(layer "B.SilkS")
		)
		(fp_line
			(start -1.524 -0.762)
			(end -1.524 0.762)
			(stroke
				(width 0.1524)
				(type default)
			)
			(layer "B.SilkS")
		)
		(fp_line
			(start 1.524 -0.762)
			(end -1.524 -0.762)
			(stroke
				(width 0.1524)
				(type default)
			)
			(layer "B.SilkS")
		)
		(fp_line
			(start -1.1049 0.724916)
			(end -1.1049 -0.724916)
			(stroke
				(width 0.1)
				(type default)
			)
			(layer "B.Fab")
		)
		(fp_line
			(start 1.1049 0.724916)
			(end -1.1049 0.724916)
			(stroke
				(width 0.1)
				(type default)
			)
			(layer "B.Fab")
		)
		(fp_line
			(start -1.1049 -0.724916)
			(end 1.1049 -0.724916)
			(stroke
				(width 0.1)
				(type default)
			)
			(layer "B.Fab")
		)
		(fp_line
			(start 1.1049 -0.724916)
			(end 1.1049 0.724916)
			(stroke
				(width 0.1)
				(type default)
			)
			(layer "B.Fab")
		)
		(pad "1" smd rect
			(at 0.889 0 270)
			(size 1.016 1.27)
			(layers "B.Cu" "B.Mask" "B.Paste")
			(net "SW_P12V_AUX_PVDDCR_SOC_P1_FLT")
		)
		(pad "2" smd rect
			(at -0.889 0 270)
			(size 1.016 1.27)
			(layers "B.Cu" "B.Mask" "B.Paste")
			(net "GND")
		)
	)
	(footprint ""
		(layer "B.Cu")
		(at 352.501454 -267.52931)
		(property "Reference" "C2237"
			(at 0 0 0)
			(layer "B.SilkS")
			(hide yes)
			(effects
				(font
					(size 1.27 1.27)
				)
				(justify mirror)
			)
		)
		(property "Value" ""
			(at 0 0 0)
			(layer "B.Fab")
			(effects
				(font
					(size 1.27 1.27)
				)
				(justify mirror)
			)
		)
		(duplicate_pad_numbers_are_jumpers no)
		(fp_line
			(start -0.7874 -0.4064)
			(end -0.7874 0.4064)
			(stroke
				(width 0.1524)
				(type default)
			)
			(layer "B.SilkS")
		)
		(fp_line
			(start -0.7874 0.4064)
			(end 0.7874 0.4064)
			(stroke
				(width 0.1524)
				(type default)
			)
			(layer "B.SilkS")
		)
		(fp_line
			(start 0.7874 -0.4064)
			(end -0.7874 -0.4064)
			(stroke
				(width 0.1524)
				(type default)
			)
			(layer "B.SilkS")
		)
		(fp_line
			(start 0.7874 0.4064)
			(end 0.7874 -0.4064)
			(stroke
				(width 0.1524)
				(type default)
			)
			(layer "B.SilkS")
		)
		(fp_line
			(start -0.67945 -0.3048)
			(end -0.67945 0.3048)
			(stroke
				(width 0.1)
				(type default)
			)
			(layer "B.Fab")
		)
		(fp_line
			(start -0.67945 0.3048)
			(end -0.120396 0.3048)
			(stroke
				(width 0.1)
				(type default)
			)
			(layer "B.Fab")
		)
		(fp_line
			(start -0.12065 -0.3048)
			(end -0.67945 -0.3048)
			(stroke
				(width 0.1)
				(type default)
			)
			(layer "B.Fab")
		)
		(fp_line
			(start -0.12065 -0.2794)
			(end -0.12065 -0.3048)
			(stroke
				(width 0.1)
				(type default)
			)
			(layer "B.Fab")
		)
		(fp_line
			(start -0.120396 0.2794)
			(end 0.12065 0.2794)
			(stroke
				(width 0.1)
				(type default)
			)
			(layer "B.Fab")
		)
		(fp_line
			(start -0.120396 0.3048)
			(end -0.120396 0.2794)
			(stroke
				(width 0.1)
				(type default)
			)
			(layer "B.Fab")
		)
		(fp_line
			(start 0.12065 -0.305054)
			(end 0.12065 -0.2794)
			(stroke
				(width 0.1)
				(type default)
			)
			(layer "B.Fab")
		)
		(fp_line
			(start 0.12065 -0.2794)
			(end -0.12065 -0.2794)
			(stroke
				(width 0.1)
				(type default)
			)
			(layer "B.Fab")
		)
		(fp_line
			(start 0.12065 0.2794)
			(end 0.12065 0.3048)
			(stroke
				(width 0.1)
				(type default)
			)
			(layer "B.Fab")
		)
		(fp_line
			(start 0.12065 0.3048)
			(end 0.67945 0.3048)
			(stroke
				(width 0.1)
				(type default)
			)
			(layer "B.Fab")
		)
		(fp_line
			(start 0.67945 -0.305054)
			(end 0.12065 -0.305054)
			(stroke
				(width 0.1)
				(type default)
			)
			(layer "B.Fab")
		)
		(fp_line
			(start 0.67945 0.3048)
			(end 0.67945 -0.305054)
			(stroke
				(width 0.1)
				(type default)
			)
			(layer "B.Fab")
		)
		(pad "1" smd circle
			(at 0.40005 0 180)
			(size 0 0)
			(layers "B.Cu" "B.Mask" "B.Paste")
			(net "PVDDCR_CPU1_P0")
		)
		(pad "2" smd circle
			(at -0.40005 0 180)
			(size 0 0)
			(layers "B.Cu" "B.Mask" "B.Paste")
			(net "GND")
		)
	)
	(footprint ""
		(layer "B.Cu")
		(at 61.140594 -177.380392 90)
		(property "Reference" "PC134_6"
			(at 0 0 90)
			(layer "B.SilkS")
			(hide yes)
			(effects
				(font
					(size 1.27 1.27)
				)
				(justify mirror)
			)
		)
		(property "Value" ""
			(at 0 0 90)
			(layer "B.Fab")
			(effects
				(font
					(size 1.27 1.27)
				)
				(justify mirror)
			)
		)
		(duplicate_pad_numbers_are_jumpers no)
		(fp_line
			(start 1.524 -0.762)
			(end -1.524 -0.762)
			(stroke
				(width 0.1524)
				(type default)
			)
			(layer "B.SilkS")
		)
		(fp_line
			(start -1.524 -0.762)
			(end -1.524 0.762)
			(stroke
				(width 0.1524)
				(type default)
			)
			(layer "B.SilkS")
		)
		(fp_line
			(start 1.524 0.762)
			(end 1.524 -0.762)
			(stroke
				(width 0.1524)
				(type default)
			)
			(layer "B.SilkS")
		)
		(fp_line
			(start -1.524 0.762)
			(end 1.524 0.762)
			(stroke
				(width 0.1524)
				(type default)
			)
			(layer "B.SilkS")
		)
		(fp_line
			(start 1.1049 -0.724916)
			(end 1.1049 0.724916)
			(stroke
				(width 0.1)
				(type default)
			)
			(layer "B.Fab")
		)
		(fp_line
			(start -1.1049 -0.724916)
			(end 1.1049 -0.724916)
			(stroke
				(width 0.1)
				(type default)
			)
			(layer "B.Fab")
		)
		(fp_line
			(start 1.1049 0.724916)
			(end -1.1049 0.724916)
			(stroke
				(width 0.1)
				(type default)
			)
			(layer "B.Fab")
		)
		(fp_line
			(start -1.1049 0.724916)
			(end -1.1049 -0.724916)
			(stroke
				(width 0.1)
				(type default)
			)
			(layer "B.Fab")
		)
		(pad "1" smd rect
			(at 0.889 0 90)
			(size 1.016 1.27)
			(layers "B.Cu" "B.Mask" "B.Paste")
			(net "PVDDCR_CPU0_P1")
		)
		(pad "2" smd rect
			(at -0.889 0 90)
			(size 1.016 1.27)
			(layers "B.Cu" "B.Mask" "B.Paste")
			(net "GND")
		)
	)
	(footprint ""
		(layer "B.Cu")
		(at 108.355892 -258.795266 180)
		(property "Reference" "C2122"
			(at 0 0 0)
			(layer "B.SilkS")
			(hide yes)
			(effects
				(font
					(size 1.27 1.27)
				)
				(justify mirror)
			)
		)
		(property "Value" ""
			(at 0 0 0)
			(layer "B.Fab")
			(effects
				(font
					(size 1.27 1.27)
				)
				(justify mirror)
			)
		)
		(duplicate_pad_numbers_are_jumpers no)
		(fp_line
			(start 0.7874 0.4064)
			(end 0.7874 -0.4064)
			(stroke
				(width 0.1524)
				(type default)
			)
			(layer "B.SilkS")
		)
		(fp_line
			(start 0.7874 -0.4064)
			(end -0.7874 -0.4064)
			(stroke
				(width 0.1524)
				(type default)
			)
			(layer "B.SilkS")
		)
		(fp_line
			(start -0.7874 0.4064)
			(end 0.7874 0.4064)
			(stroke
				(width 0.1524)
				(type default)
			)
			(layer "B.SilkS")
		)
		(fp_line
			(start -0.7874 -0.4064)
			(end -0.7874 0.4064)
			(stroke
				(width 0.1524)
				(type default)
			)
			(layer "B.SilkS")
		)
		(fp_line
			(start 0.67945 0.3048)
			(end 0.67945 -0.305054)
			(stroke
				(width 0.1)
				(type default)
			)
			(layer "B.Fab")
		)
		(fp_line
			(start 0.67945 -0.305054)
			(end 0.12065 -0.305054)
			(stroke
				(width 0.1)
				(type default)
			)
			(layer "B.Fab")
		)
		(fp_line
			(start 0.12065 0.3048)
			(end 0.67945 0.3048)
			(stroke
				(width 0.1)
				(type default)
			)
			(layer "B.Fab")
		)
		(fp_line
			(start 0.12065 0.2794)
			(end 0.12065 0.3048)
			(stroke
				(width 0.1)
				(type default)
			)
			(layer "B.Fab")
		)
		(fp_line
			(start 0.12065 -0.2794)
			(end -0.12065 -0.2794)
			(stroke
				(width 0.1)
				(type default)
			)
			(layer "B.Fab")
		)
		(fp_line
			(start 0.12065 -0.305054)
			(end 0.12065 -0.2794)
			(stroke
				(width 0.1)
				(type default)
			)
			(layer "B.Fab")
		)
		(fp_line
			(start -0.120396 0.3048)
			(end -0.120396 0.2794)
			(stroke
				(width 0.1)
				(type default)
			)
			(layer "B.Fab")
		)
		(fp_line
			(start -0.120396 0.2794)
			(end 0.12065 0.2794)
			(stroke
				(width 0.1)
				(type default)
			)
			(layer "B.Fab")
		)
		(fp_line
			(start -0.12065 -0.2794)
			(end -0.12065 -0.3048)
			(stroke
				(width 0.1)
				(type default)
			)
			(layer "B.Fab")
		)
		(fp_line
			(start -0.12065 -0.3048)
			(end -0.67945 -0.3048)
			(stroke
				(width 0.1)
				(type default)
			)
			(layer "B.Fab")
		)
		(fp_line
			(start -0.67945 0.3048)
			(end -0.120396 0.3048)
			(stroke
				(width 0.1)
				(type default)
			)
			(layer "B.Fab")
		)
		(fp_line
			(start -0.67945 -0.3048)
			(end -0.67945 0.3048)
			(stroke
				(width 0.1)
				(type default)
			)
			(layer "B.Fab")
		)
		(pad "1" smd circle
			(at 0.40005 0)
			(size 0 0)
			(layers "B.Cu" "B.Mask" "B.Paste")
			(net "PVDDIO_P1")
		)
		(pad "2" smd circle
			(at -0.40005 0)
			(size 0 0)
			(layers "B.Cu" "B.Mask" "B.Paste")
			(net "GND")
		)
	)
	(footprint ""
		(layer "B.Cu")
		(at 317.553086 -416.899344 90)
		(property "Reference" "C6542"
			(at 0 0 90)
			(layer "B.SilkS")
			(hide yes)
			(effects
				(font
					(size 1.27 1.27)
				)
				(justify mirror)
			)
		)
		(property "Value" ""
			(at 0 0 90)
			(layer "B.Fab")
			(effects
				(font
					(size 1.27 1.27)
				)
				(justify mirror)
			)
		)
		(duplicate_pad_numbers_are_jumpers no)
		(fp_line
			(start 0.299974 -0.150114)
			(end -0.299974 -0.150114)
			(stroke
				(width 0.1)
				(type default)
			)
			(layer "B.Fab")
		)
		(fp_line
			(start -0.299974 -0.150114)
			(end -0.299974 0.150114)
			(stroke
				(width 0.1)
				(type default)
			)
			(layer "B.Fab")
		)
		(fp_line
			(start 0.299974 0.150114)
			(end 0.299974 -0.150114)
			(stroke
				(width 0.1)
				(type default)
			)
			(layer "B.Fab")
		)
		(fp_line
			(start -0.299974 0.150114)
			(end 0.299974 0.150114)
			(stroke
				(width 0.1)
				(type default)
			)
			(layer "B.Fab")
		)
		(pad "1" smd rect
			(at 0.2667 0 270)
			(size 0.3048 0.381)
			(layers "B.Cu" "B.Mask" "B.Paste")
			(net "P5E_CPU0_P1_TX_BUF_C_DN<4>")
		)
		(pad "2" smd rect
			(at -0.2667 0 270)
			(size 0.3048 0.381)
			(layers "B.Cu" "B.Mask" "B.Paste")
			(net "P5E_CPU0_P1_TX_BUF_DN<4>")
		)
	)
	(footprint ""
		(layer "B.Cu")
		(at 113.376964 -261.748016 90)
		(property "Reference" "C2491"
			(at 0 0 90)
			(layer "B.SilkS")
			(hide yes)
			(effects
				(font
					(size 1.27 1.27)
				)
				(justify mirror)
			)
		)
		(property "Value" ""
			(at 0 0 90)
			(layer "B.Fab")
			(effects
				(font
					(size 1.27 1.27)
				)
				(justify mirror)
			)
		)
		(duplicate_pad_numbers_are_jumpers no)
		(fp_line
			(start 0.7874 -0.4064)
			(end -0.7874 -0.4064)
			(stroke
				(width 0.1524)
				(type default)
			)
			(layer "B.SilkS")
		)
		(fp_line
			(start -0.7874 -0.4064)
			(end -0.7874 0.4064)
			(stroke
				(width 0.1524)
				(type default)
			)
			(layer "B.SilkS")
		)
		(fp_line
			(start 0.7874 0.4064)
			(end 0.7874 -0.4064)
			(stroke
				(width 0.1524)
				(type default)
			)
			(layer "B.SilkS")
		)
		(fp_line
			(start -0.7874 0.4064)
			(end 0.7874 0.4064)
			(stroke
				(width 0.1524)
				(type default)
			)
			(layer "B.SilkS")
		)
		(fp_line
			(start 0.67945 -0.305054)
			(end 0.12065 -0.305054)
			(stroke
				(width 0.1)
				(type default)
			)
			(layer "B.Fab")
		)
		(fp_line
			(start 0.12065 -0.305054)
			(end 0.12065 -0.2794)
			(stroke
				(width 0.1)
				(type default)
			)
			(layer "B.Fab")
		)
		(fp_line
			(start -0.12065 -0.3048)
			(end -0.67945 -0.3048)
			(stroke
				(width 0.1)
				(type default)
			)
			(layer "B.Fab")
		)
		(fp_line
			(start -0.67945 -0.3048)
			(end -0.67945 0.3048)
			(stroke
				(width 0.1)
				(type default)
			)
			(layer "B.Fab")
		)
		(fp_line
			(start 0.12065 -0.2794)
			(end -0.12065 -0.2794)
			(stroke
				(width 0.1)
				(type default)
			)
			(layer "B.Fab")
		)
		(fp_line
			(start -0.12065 -0.2794)
			(end -0.12065 -0.3048)
			(stroke
				(width 0.1)
				(type default)
			)
			(layer "B.Fab")
		)
		(fp_line
			(start 0.12065 0.2794)
			(end 0.12065 0.3048)
			(stroke
				(width 0.1)
				(type default)
			)
			(layer "B.Fab")
		)
		(fp_line
			(start -0.120396 0.2794)
			(end 0.12065 0.2794)
			(stroke
				(width 0.1)
				(type default)
			)
			(layer "B.Fab")
		)
		(fp_line
			(start 0.67945 0.3048)
			(end 0.67945 -0.305054)
			(stroke
				(width 0.1)
				(type default)
			)
			(layer "B.Fab")
		)
		(fp_line
			(start 0.12065 0.3048)
			(end 0.67945 0.3048)
			(stroke
				(width 0.1)
				(type default)
			)
			(layer "B.Fab")
		)
		(fp_line
			(start -0.120396 0.3048)
			(end -0.120396 0.2794)
			(stroke
				(width 0.1)
				(type default)
			)
			(layer "B.Fab")
		)
		(fp_line
			(start -0.67945 0.3048)
			(end -0.120396 0.3048)
			(stroke
				(width 0.1)
				(type default)
			)
			(layer "B.Fab")
		)
		(pad "1" smd circle
			(at 0.40005 0 270)
			(size 0 0)
			(layers "B.Cu" "B.Mask" "B.Paste")
			(net "PVDD11_S3_P1")
		)
		(pad "2" smd circle
			(at -0.40005 0 270)
			(size 0 0)
			(layers "B.Cu" "B.Mask" "B.Paste")
			(net "GND")
		)
	)
	(footprint ""
		(layer "B.Cu")
		(at 361.645454 -253.43231)
		(property "Reference" "C2556"
			(at 0 0 0)
			(layer "B.SilkS")
			(hide yes)
			(effects
				(font
					(size 1.27 1.27)
				)
				(justify mirror)
			)
		)
		(property "Value" ""
			(at 0 0 0)
			(layer "B.Fab")
			(effects
				(font
					(size 1.27 1.27)
				)
				(justify mirror)
			)
		)
		(duplicate_pad_numbers_are_jumpers no)
		(fp_line
			(start -0.7874 -0.4064)
			(end -0.7874 0.4064)
			(stroke
				(width 0.1524)
				(type default)
			)
			(layer "B.SilkS")
		)
		(fp_line
			(start -0.7874 0.4064)
			(end 0.7874 0.4064)
			(stroke
				(width 0.1524)
				(type default)
			)
			(layer "B.SilkS")
		)
		(fp_line
			(start 0.7874 -0.4064)
			(end -0.7874 -0.4064)
			(stroke
				(width 0.1524)
				(type default)
			)
			(layer "B.SilkS")
		)
		(fp_line
			(start 0.7874 0.4064)
			(end 0.7874 -0.4064)
			(stroke
				(width 0.1524)
				(type default)
			)
			(layer "B.SilkS")
		)
		(fp_line
			(start -0.67945 -0.3048)
			(end -0.67945 0.3048)
			(stroke
				(width 0.1)
				(type default)
			)
			(layer "B.Fab")
		)
		(fp_line
			(start -0.67945 0.3048)
			(end -0.120396 0.3048)
			(stroke
				(width 0.1)
				(type default)
			)
			(layer "B.Fab")
		)
		(fp_line
			(start -0.12065 -0.3048)
			(end -0.67945 -0.3048)
			(stroke
				(width 0.1)
				(type default)
			)
			(layer "B.Fab")
		)
		(fp_line
			(start -0.12065 -0.2794)
			(end -0.12065 -0.3048)
			(stroke
				(width 0.1)
				(type default)
			)
			(layer "B.Fab")
		)
		(fp_line
			(start -0.120396 0.2794)
			(end 0.12065 0.2794)
			(stroke
				(width 0.1)
				(type default)
			)
			(layer "B.Fab")
		)
		(fp_line
			(start -0.120396 0.3048)
			(end -0.120396 0.2794)
			(stroke
				(width 0.1)
				(type default)
			)
			(layer "B.Fab")
		)
		(fp_line
			(start 0.12065 -0.305054)
			(end 0.12065 -0.2794)
			(stroke
				(width 0.1)
				(type default)
			)
			(layer "B.Fab")
		)
		(fp_line
			(start 0.12065 -0.2794)
			(end -0.12065 -0.2794)
			(stroke
				(width 0.1)
				(type default)
			)
			(layer "B.Fab")
		)
		(fp_line
			(start 0.12065 0.2794)
			(end 0.12065 0.3048)
			(stroke
				(width 0.1)
				(type default)
			)
			(layer "B.Fab")
		)
		(fp_line
			(start 0.12065 0.3048)
			(end 0.67945 0.3048)
			(stroke
				(width 0.1)
				(type default)
			)
			(layer "B.Fab")
		)
		(fp_line
			(start 0.67945 -0.305054)
			(end 0.12065 -0.305054)
			(stroke
				(width 0.1)
				(type default)
			)
			(layer "B.Fab")
		)
		(fp_line
			(start 0.67945 0.3048)
			(end 0.67945 -0.305054)
			(stroke
				(width 0.1)
				(type default)
			)
			(layer "B.Fab")
		)
		(pad "1" smd circle
			(at 0.40005 0 180)
			(size 0 0)
			(layers "B.Cu" "B.Mask" "B.Paste")
			(net "PVDDCR_SOC_P0")
		)
		(pad "2" smd circle
			(at -0.40005 0 180)
			(size 0 0)
			(layers "B.Cu" "B.Mask" "B.Paste")
			(net "GND")
		)
	)
	(footprint ""
		(layer "B.Cu")
		(at 8.382 -81.153 90)
		(property "Reference" "R8014"
			(at 0 0 90)
			(layer "B.SilkS")
			(hide yes)
			(effects
				(font
					(size 1.27 1.27)
				)
				(justify mirror)
			)
		)
		(property "Value" ""
			(at 0 0 90)
			(layer "B.Fab")
			(effects
				(font
					(size 1.27 1.27)
				)
				(justify mirror)
			)
		)
		(duplicate_pad_numbers_are_jumpers no)
		(fp_line
			(start 0.7874 -0.4064)
			(end -0.7874 -0.4064)
			(stroke
				(width 0.1524)
				(type default)
			)
			(layer "B.SilkS")
		)
		(fp_line
			(start -0.7874 -0.4064)
			(end -0.7874 0.4064)
			(stroke
				(width 0.1524)
				(type default)
			)
			(layer "B.SilkS")
		)
		(fp_line
			(start 0.7874 0.4064)
			(end 0.7874 -0.4064)
			(stroke
				(width 0.1524)
				(type default)
			)
			(layer "B.SilkS")
		)
		(fp_line
			(start -0.7874 0.4064)
			(end 0.7874 0.4064)
			(stroke
				(width 0.1524)
				(type default)
			)
			(layer "B.SilkS")
		)
		(fp_line
			(start 0.67945 -0.305054)
			(end 0.12065 -0.305054)
			(stroke
				(width 0.1)
				(type default)
			)
			(layer "B.Fab")
		)
		(fp_line
			(start 0.12065 -0.305054)
			(end 0.12065 -0.2794)
			(stroke
				(width 0.1)
				(type default)
			)
			(layer "B.Fab")
		)
		(fp_line
			(start -0.12065 -0.3048)
			(end -0.67945 -0.3048)
			(stroke
				(width 0.1)
				(type default)
			)
			(layer "B.Fab")
		)
		(fp_line
			(start -0.67945 -0.3048)
			(end -0.67945 0.3048)
			(stroke
				(width 0.1)
				(type default)
			)
			(layer "B.Fab")
		)
		(fp_line
			(start 0.12065 -0.2794)
			(end -0.12065 -0.2794)
			(stroke
				(width 0.1)
				(type default)
			)
			(layer "B.Fab")
		)
		(fp_line
			(start -0.12065 -0.2794)
			(end -0.12065 -0.3048)
			(stroke
				(width 0.1)
				(type default)
			)
			(layer "B.Fab")
		)
		(fp_line
			(start 0.12065 0.2794)
			(end 0.12065 0.3048)
			(stroke
				(width 0.1)
				(type default)
			)
			(layer "B.Fab")
		)
		(fp_line
			(start -0.120396 0.2794)
			(end 0.12065 0.2794)
			(stroke
				(width 0.1)
				(type default)
			)
			(layer "B.Fab")
		)
		(fp_line
			(start 0.67945 0.3048)
			(end 0.67945 -0.305054)
			(stroke
				(width 0.1)
				(type default)
			)
			(layer "B.Fab")
		)
		(fp_line
			(start 0.12065 0.3048)
			(end 0.67945 0.3048)
			(stroke
				(width 0.1)
				(type default)
			)
			(layer "B.Fab")
		)
		(fp_line
			(start -0.120396 0.3048)
			(end -0.120396 0.2794)
			(stroke
				(width 0.1)
				(type default)
			)
			(layer "B.Fab")
		)
		(fp_line
			(start -0.67945 0.3048)
			(end -0.120396 0.3048)
			(stroke
				(width 0.1)
				(type default)
			)
			(layer "B.Fab")
		)
		(pad "1" smd circle
			(at 0.40005 0 270)
			(size 0 0)
			(layers "B.Cu" "B.Mask" "B.Paste")
			(net "OCP_SFF_PRSNT23_R_N")
		)
		(pad "2" smd circle
			(at -0.40005 0 270)
			(size 0 0)
			(layers "B.Cu" "B.Mask" "B.Paste")
			(net "OCP_SFF_PRSNT23_R1_N")
		)
	)
	(footprint ""
		(layer "B.Cu")
		(at 60.578492 -386.766562 90)
		(property "Reference" "C187"
			(at 0 0 90)
			(layer "B.SilkS")
			(hide yes)
			(effects
				(font
					(size 1.27 1.27)
				)
				(justify mirror)
			)
		)
		(property "Value" ""
			(at 0 0 90)
			(layer "B.Fab")
			(effects
				(font
					(size 1.27 1.27)
				)
				(justify mirror)
			)
		)
		(duplicate_pad_numbers_are_jumpers no)
		(fp_line
			(start 0.299974 -0.150114)
			(end -0.299974 -0.150114)
			(stroke
				(width 0.1)
				(type default)
			)
			(layer "B.Fab")
		)
		(fp_line
			(start -0.299974 -0.150114)
			(end -0.299974 0.150114)
			(stroke
				(width 0.1)
				(type default)
			)
			(layer "B.Fab")
		)
		(fp_line
			(start 0.299974 0.150114)
			(end 0.299974 -0.150114)
			(stroke
				(width 0.1)
				(type default)
			)
			(layer "B.Fab")
		)
		(fp_line
			(start -0.299974 0.150114)
			(end 0.299974 0.150114)
			(stroke
				(width 0.1)
				(type default)
			)
			(layer "B.Fab")
		)
		(pad "1" smd rect
			(at 0.2667 0 270)
			(size 0.3048 0.381)
			(layers "B.Cu" "B.Mask" "B.Paste")
			(net "P0V9_CPU1_RT0_2A_2D")
		)
		(pad "2" smd rect
			(at -0.2667 0 270)
			(size 0.3048 0.381)
			(layers "B.Cu" "B.Mask" "B.Paste")
			(net "GND")
		)
	)
	(footprint ""
		(layer "B.Cu")
		(at 350.429576 -171.35094 90)
		(property "Reference" "PC502_1"
			(at 0 0 90)
			(layer "B.SilkS")
			(hide yes)
			(effects
				(font
					(size 1.27 1.27)
				)
				(justify mirror)
			)
		)
		(property "Value" ""
			(at 0 0 90)
			(layer "B.Fab")
			(effects
				(font
					(size 1.27 1.27)
				)
				(justify mirror)
			)
		)
		(duplicate_pad_numbers_are_jumpers no)
		(fp_line
			(start 1.524 -0.762)
			(end -1.524 -0.762)
			(stroke
				(width 0.1524)
				(type default)
			)
			(layer "B.SilkS")
		)
		(fp_line
			(start -1.524 -0.762)
			(end -1.524 0.762)
			(stroke
				(width 0.1524)
				(type default)
			)
			(layer "B.SilkS")
		)
		(fp_line
			(start 1.524 0.762)
			(end 1.524 -0.762)
			(stroke
				(width 0.1524)
				(type default)
			)
			(layer "B.SilkS")
		)
		(fp_line
			(start -1.524 0.762)
			(end 1.524 0.762)
			(stroke
				(width 0.1524)
				(type default)
			)
			(layer "B.SilkS")
		)
		(fp_line
			(start 1.1049 -0.724916)
			(end 1.1049 0.724916)
			(stroke
				(width 0.1)
				(type default)
			)
			(layer "B.Fab")
		)
		(fp_line
			(start -1.1049 -0.724916)
			(end 1.1049 -0.724916)
			(stroke
				(width 0.1)
				(type default)
			)
			(layer "B.Fab")
		)
		(fp_line
			(start 1.1049 0.724916)
			(end -1.1049 0.724916)
			(stroke
				(width 0.1)
				(type default)
			)
			(layer "B.Fab")
		)
		(fp_line
			(start -1.1049 0.724916)
			(end -1.1049 -0.724916)
			(stroke
				(width 0.1)
				(type default)
			)
			(layer "B.Fab")
		)
		(pad "1" smd rect
			(at 0.889 0 90)
			(size 1.016 1.27)
			(layers "B.Cu" "B.Mask" "B.Paste")
			(net "PVDDCR_CPU0_P0")
		)
		(pad "2" smd rect
			(at -0.889 0 90)
			(size 1.016 1.27)
			(layers "B.Cu" "B.Mask" "B.Paste")
			(net "GND")
		)
	)
	(footprint ""
		(layer "B.Cu")
		(at 459.053184 -65.794382 90)
		(property "Reference" "PC1869"
			(at 0 0 90)
			(layer "B.SilkS")
			(hide yes)
			(effects
				(font
					(size 1.27 1.27)
				)
				(justify mirror)
			)
		)
		(property "Value" ""
			(at 0 0 90)
			(layer "B.Fab")
			(effects
				(font
					(size 1.27 1.27)
				)
				(justify mirror)
			)
		)
		(duplicate_pad_numbers_are_jumpers no)
		(fp_line
			(start 0.7874 -0.4064)
			(end -0.7874 -0.4064)
			(stroke
				(width 0.1524)
				(type default)
			)
			(layer "B.SilkS")
		)
		(fp_line
			(start -0.7874 -0.4064)
			(end -0.7874 0.4064)
			(stroke
				(width 0.1524)
				(type default)
			)
			(layer "B.SilkS")
		)
		(fp_line
			(start 0.7874 0.4064)
			(end 0.7874 -0.4064)
			(stroke
				(width 0.1524)
				(type default)
			)
			(layer "B.SilkS")
		)
		(fp_line
			(start -0.7874 0.4064)
			(end 0.7874 0.4064)
			(stroke
				(width 0.1524)
				(type default)
			)
			(layer "B.SilkS")
		)
		(fp_line
			(start 0.67945 -0.305054)
			(end 0.12065 -0.305054)
			(stroke
				(width 0.1)
				(type default)
			)
			(layer "B.Fab")
		)
		(fp_line
			(start 0.12065 -0.305054)
			(end 0.12065 -0.2794)
			(stroke
				(width 0.1)
				(type default)
			)
			(layer "B.Fab")
		)
		(fp_line
			(start -0.12065 -0.3048)
			(end -0.67945 -0.3048)
			(stroke
				(width 0.1)
				(type default)
			)
			(layer "B.Fab")
		)
		(fp_line
			(start -0.67945 -0.3048)
			(end -0.67945 0.3048)
			(stroke
				(width 0.1)
				(type default)
			)
			(layer "B.Fab")
		)
		(fp_line
			(start 0.12065 -0.2794)
			(end -0.12065 -0.2794)
			(stroke
				(width 0.1)
				(type default)
			)
			(layer "B.Fab")
		)
		(fp_line
			(start -0.12065 -0.2794)
			(end -0.12065 -0.3048)
			(stroke
				(width 0.1)
				(type default)
			)
			(layer "B.Fab")
		)
		(fp_line
			(start 0.12065 0.2794)
			(end 0.12065 0.3048)
			(stroke
				(width 0.1)
				(type default)
			)
			(layer "B.Fab")
		)
		(fp_line
			(start -0.120396 0.2794)
			(end 0.12065 0.2794)
			(stroke
				(width 0.1)
				(type default)
			)
			(layer "B.Fab")
		)
		(fp_line
			(start 0.67945 0.3048)
			(end 0.67945 -0.305054)
			(stroke
				(width 0.1)
				(type default)
			)
			(layer "B.Fab")
		)
		(fp_line
			(start 0.12065 0.3048)
			(end 0.67945 0.3048)
			(stroke
				(width 0.1)
				(type default)
			)
			(layer "B.Fab")
		)
		(fp_line
			(start -0.120396 0.3048)
			(end -0.120396 0.2794)
			(stroke
				(width 0.1)
				(type default)
			)
			(layer "B.Fab")
		)
		(fp_line
			(start -0.67945 0.3048)
			(end -0.120396 0.3048)
			(stroke
				(width 0.1)
				(type default)
			)
			(layer "B.Fab")
		)
		(pad "1" smd circle
			(at 0.40005 0 270)
			(size 0 0)
			(layers "B.Cu" "B.Mask" "B.Paste")
			(net "P3V3_AUX")
		)
		(pad "2" smd circle
			(at -0.40005 0 270)
			(size 0 0)
			(layers "B.Cu" "B.Mask" "B.Paste")
			(net "GND")
		)
	)
	(footprint ""
		(layer "B.Cu")
		(at 127.536448 -156.393134 -90)
		(property "Reference" "PC353_3"
			(at 0 0 90)
			(layer "B.SilkS")
			(hide yes)
			(effects
				(font
					(size 1.27 1.27)
				)
				(justify mirror)
			)
		)
		(property "Value" ""
			(at 0 0 90)
			(layer "B.Fab")
			(effects
				(font
					(size 1.27 1.27)
				)
				(justify mirror)
			)
		)
		(duplicate_pad_numbers_are_jumpers no)
		(fp_line
			(start -1.524 0.762)
			(end 1.524 0.762)
			(stroke
				(width 0.1524)
				(type default)
			)
			(layer "B.SilkS")
		)
		(fp_line
			(start 1.524 0.762)
			(end 1.524 -0.762)
			(stroke
				(width 0.1524)
				(type default)
			)
			(layer "B.SilkS")
		)
		(fp_line
			(start -1.524 -0.762)
			(end -1.524 0.762)
			(stroke
				(width 0.1524)
				(type default)
			)
			(layer "B.SilkS")
		)
		(fp_line
			(start 1.524 -0.762)
			(end -1.524 -0.762)
			(stroke
				(width 0.1524)
				(type default)
			)
			(layer "B.SilkS")
		)
		(fp_line
			(start -1.1049 0.724916)
			(end -1.1049 -0.724916)
			(stroke
				(width 0.1)
				(type default)
			)
			(layer "B.Fab")
		)
		(fp_line
			(start 1.1049 0.724916)
			(end -1.1049 0.724916)
			(stroke
				(width 0.1)
				(type default)
			)
			(layer "B.Fab")
		)
		(fp_line
			(start -1.1049 -0.724916)
			(end 1.1049 -0.724916)
			(stroke
				(width 0.1)
				(type default)
			)
			(layer "B.Fab")
		)
		(fp_line
			(start 1.1049 -0.724916)
			(end 1.1049 0.724916)
			(stroke
				(width 0.1)
				(type default)
			)
			(layer "B.Fab")
		)
		(pad "1" smd rect
			(at 0.889 0 270)
			(size 1.016 1.27)
			(layers "B.Cu" "B.Mask" "B.Paste")
			(net "SW_P12V_AUX_PVDDCR_SOC_P1_FLT")
		)
		(pad "2" smd rect
			(at -0.889 0 270)
			(size 1.016 1.27)
			(layers "B.Cu" "B.Mask" "B.Paste")
			(net "GND")
		)
	)
	(footprint ""
		(layer "B.Cu")
		(at 325.799958 -203.917296 90)
		(property "Reference" "R156"
			(at 0 0 90)
			(layer "B.SilkS")
			(hide yes)
			(effects
				(font
					(size 1.27 1.27)
				)
				(justify mirror)
			)
		)
		(property "Value" ""
			(at 0 0 90)
			(layer "B.Fab")
			(effects
				(font
					(size 1.27 1.27)
				)
				(justify mirror)
			)
		)
		(duplicate_pad_numbers_are_jumpers no)
		(fp_line
			(start 0.7874 -0.4064)
			(end -0.7874 -0.4064)
			(stroke
				(width 0.1524)
				(type default)
			)
			(layer "B.SilkS")
		)
		(fp_line
			(start -0.7874 -0.4064)
			(end -0.7874 0.4064)
			(stroke
				(width 0.1524)
				(type default)
			)
			(layer "B.SilkS")
		)
		(fp_line
			(start 0.7874 0.4064)
			(end 0.7874 -0.4064)
			(stroke
				(width 0.1524)
				(type default)
			)
			(layer "B.SilkS")
		)
		(fp_line
			(start -0.7874 0.4064)
			(end 0.7874 0.4064)
			(stroke
				(width 0.1524)
				(type default)
			)
			(layer "B.SilkS")
		)
		(fp_line
			(start 0.67945 -0.305054)
			(end 0.12065 -0.305054)
			(stroke
				(width 0.1)
				(type default)
			)
			(layer "B.Fab")
		)
		(fp_line
			(start 0.12065 -0.305054)
			(end 0.12065 -0.2794)
			(stroke
				(width 0.1)
				(type default)
			)
			(layer "B.Fab")
		)
		(fp_line
			(start -0.12065 -0.3048)
			(end -0.67945 -0.3048)
			(stroke
				(width 0.1)
				(type default)
			)
			(layer "B.Fab")
		)
		(fp_line
			(start -0.67945 -0.3048)
			(end -0.67945 0.3048)
			(stroke
				(width 0.1)
				(type default)
			)
			(layer "B.Fab")
		)
		(fp_line
			(start 0.12065 -0.2794)
			(end -0.12065 -0.2794)
			(stroke
				(width 0.1)
				(type default)
			)
			(layer "B.Fab")
		)
		(fp_line
			(start -0.12065 -0.2794)
			(end -0.12065 -0.3048)
			(stroke
				(width 0.1)
				(type default)
			)
			(layer "B.Fab")
		)
		(fp_line
			(start 0.12065 0.2794)
			(end 0.12065 0.3048)
			(stroke
				(width 0.1)
				(type default)
			)
			(layer "B.Fab")
		)
		(fp_line
			(start -0.120396 0.2794)
			(end 0.12065 0.2794)
			(stroke
				(width 0.1)
				(type default)
			)
			(layer "B.Fab")
		)
		(fp_line
			(start 0.67945 0.3048)
			(end 0.67945 -0.305054)
			(stroke
				(width 0.1)
				(type default)
			)
			(layer "B.Fab")
		)
		(fp_line
			(start 0.12065 0.3048)
			(end 0.67945 0.3048)
			(stroke
				(width 0.1)
				(type default)
			)
			(layer "B.Fab")
		)
		(fp_line
			(start -0.120396 0.3048)
			(end -0.120396 0.2794)
			(stroke
				(width 0.1)
				(type default)
			)
			(layer "B.Fab")
		)
		(fp_line
			(start -0.67945 0.3048)
			(end -0.120396 0.3048)
			(stroke
				(width 0.1)
				(type default)
			)
			(layer "B.Fab")
		)
		(pad "1" smd circle
			(at 0.40005 0 270)
			(size 0 0)
			(layers "B.Cu" "B.Mask" "B.Paste")
			(net "CPU0_XTRIG_R2_L4")
		)
		(pad "2" smd circle
			(at -0.40005 0 270)
			(size 0 0)
			(layers "B.Cu" "B.Mask" "B.Paste")
			(net "CPU0_XTRIG_L4")
		)
	)
	(footprint ""
		(layer "B.Cu")
		(at 236.67593 -49.120044)
		(property "Reference" "C1282"
			(at 0 0 0)
			(layer "B.SilkS")
			(hide yes)
			(effects
				(font
					(size 1.27 1.27)
				)
				(justify mirror)
			)
		)
		(property "Value" ""
			(at 0 0 0)
			(layer "B.Fab")
			(effects
				(font
					(size 1.27 1.27)
				)
				(justify mirror)
			)
		)
		(duplicate_pad_numbers_are_jumpers no)
		(fp_line
			(start -0.7874 -0.4064)
			(end -0.7874 0.4064)
			(stroke
				(width 0.1524)
				(type default)
			)
			(layer "B.SilkS")
		)
		(fp_line
			(start -0.7874 0.4064)
			(end 0.7874 0.4064)
			(stroke
				(width 0.1524)
				(type default)
			)
			(layer "B.SilkS")
		)
		(fp_line
			(start 0.7874 -0.4064)
			(end -0.7874 -0.4064)
			(stroke
				(width 0.1524)
				(type default)
			)
			(layer "B.SilkS")
		)
		(fp_line
			(start 0.7874 0.4064)
			(end 0.7874 -0.4064)
			(stroke
				(width 0.1524)
				(type default)
			)
			(layer "B.SilkS")
		)
		(fp_line
			(start -0.67945 -0.3048)
			(end -0.67945 0.3048)
			(stroke
				(width 0.1)
				(type default)
			)
			(layer "B.Fab")
		)
		(fp_line
			(start -0.67945 0.3048)
			(end -0.120396 0.3048)
			(stroke
				(width 0.1)
				(type default)
			)
			(layer "B.Fab")
		)
		(fp_line
			(start -0.12065 -0.3048)
			(end -0.67945 -0.3048)
			(stroke
				(width 0.1)
				(type default)
			)
			(layer "B.Fab")
		)
		(fp_line
			(start -0.12065 -0.2794)
			(end -0.12065 -0.3048)
			(stroke
				(width 0.1)
				(type default)
			)
			(layer "B.Fab")
		)
		(fp_line
			(start -0.120396 0.2794)
			(end 0.12065 0.2794)
			(stroke
				(width 0.1)
				(type default)
			)
			(layer "B.Fab")
		)
		(fp_line
			(start -0.120396 0.3048)
			(end -0.120396 0.2794)
			(stroke
				(width 0.1)
				(type default)
			)
			(layer "B.Fab")
		)
		(fp_line
			(start 0.12065 -0.305054)
			(end 0.12065 -0.2794)
			(stroke
				(width 0.1)
				(type default)
			)
			(layer "B.Fab")
		)
		(fp_line
			(start 0.12065 -0.2794)
			(end -0.12065 -0.2794)
			(stroke
				(width 0.1)
				(type default)
			)
			(layer "B.Fab")
		)
		(fp_line
			(start 0.12065 0.2794)
			(end 0.12065 0.3048)
			(stroke
				(width 0.1)
				(type default)
			)
			(layer "B.Fab")
		)
		(fp_line
			(start 0.12065 0.3048)
			(end 0.67945 0.3048)
			(stroke
				(width 0.1)
				(type default)
			)
			(layer "B.Fab")
		)
		(fp_line
			(start 0.67945 -0.305054)
			(end 0.12065 -0.305054)
			(stroke
				(width 0.1)
				(type default)
			)
			(layer "B.Fab")
		)
		(fp_line
			(start 0.67945 0.3048)
			(end 0.67945 -0.305054)
			(stroke
				(width 0.1)
				(type default)
			)
			(layer "B.Fab")
		)
		(pad "1" smd circle
			(at 0.40005 0 180)
			(size 0 0)
			(layers "B.Cu" "B.Mask" "B.Paste")
			(net "P3V3_E1S_0")
		)
		(pad "2" smd circle
			(at -0.40005 0 180)
			(size 0 0)
			(layers "B.Cu" "B.Mask" "B.Paste")
			(net "GND")
		)
	)
	(footprint ""
		(layer "B.Cu")
		(at 15.436088 -135.48741 90)
		(property "Reference" "R4077"
			(at 0 0 90)
			(layer "B.SilkS")
			(hide yes)
			(effects
				(font
					(size 1.27 1.27)
				)
				(justify mirror)
			)
		)
		(property "Value" ""
			(at 0 0 90)
			(layer "B.Fab")
			(effects
				(font
					(size 1.27 1.27)
				)
				(justify mirror)
			)
		)
		(duplicate_pad_numbers_are_jumpers no)
		(fp_line
			(start 0.7874 -0.4064)
			(end -0.7874 -0.4064)
			(stroke
				(width 0.1524)
				(type default)
			)
			(layer "B.SilkS")
		)
		(fp_line
			(start -0.7874 -0.4064)
			(end -0.7874 0.4064)
			(stroke
				(width 0.1524)
				(type default)
			)
			(layer "B.SilkS")
		)
		(fp_line
			(start 0.7874 0.4064)
			(end 0.7874 -0.4064)
			(stroke
				(width 0.1524)
				(type default)
			)
			(layer "B.SilkS")
		)
		(fp_line
			(start -0.7874 0.4064)
			(end 0.7874 0.4064)
			(stroke
				(width 0.1524)
				(type default)
			)
			(layer "B.SilkS")
		)
		(fp_line
			(start 0.67945 -0.305054)
			(end 0.12065 -0.305054)
			(stroke
				(width 0.1)
				(type default)
			)
			(layer "B.Fab")
		)
		(fp_line
			(start 0.12065 -0.305054)
			(end 0.12065 -0.2794)
			(stroke
				(width 0.1)
				(type default)
			)
			(layer "B.Fab")
		)
		(fp_line
			(start -0.12065 -0.3048)
			(end -0.67945 -0.3048)
			(stroke
				(width 0.1)
				(type default)
			)
			(layer "B.Fab")
		)
		(fp_line
			(start -0.67945 -0.3048)
			(end -0.67945 0.3048)
			(stroke
				(width 0.1)
				(type default)
			)
			(layer "B.Fab")
		)
		(fp_line
			(start 0.12065 -0.2794)
			(end -0.12065 -0.2794)
			(stroke
				(width 0.1)
				(type default)
			)
			(layer "B.Fab")
		)
		(fp_line
			(start -0.12065 -0.2794)
			(end -0.12065 -0.3048)
			(stroke
				(width 0.1)
				(type default)
			)
			(layer "B.Fab")
		)
		(fp_line
			(start 0.12065 0.2794)
			(end 0.12065 0.3048)
			(stroke
				(width 0.1)
				(type default)
			)
			(layer "B.Fab")
		)
		(fp_line
			(start -0.120396 0.2794)
			(end 0.12065 0.2794)
			(stroke
				(width 0.1)
				(type default)
			)
			(layer "B.Fab")
		)
		(fp_line
			(start 0.67945 0.3048)
			(end 0.67945 -0.305054)
			(stroke
				(width 0.1)
				(type default)
			)
			(layer "B.Fab")
		)
		(fp_line
			(start 0.12065 0.3048)
			(end 0.67945 0.3048)
			(stroke
				(width 0.1)
				(type default)
			)
			(layer "B.Fab")
		)
		(fp_line
			(start -0.120396 0.3048)
			(end -0.120396 0.2794)
			(stroke
				(width 0.1)
				(type default)
			)
			(layer "B.Fab")
		)
		(fp_line
			(start -0.67945 0.3048)
			(end -0.120396 0.3048)
			(stroke
				(width 0.1)
				(type default)
			)
			(layer "B.Fab")
		)
		(pad "1" smd circle
			(at 0.40005 0 270)
			(size 0 0)
			(layers "B.Cu" "B.Mask" "B.Paste")
			(net "VFG3P3_CLK_GEN")
		)
		(pad "2" smd circle
			(at -0.40005 0 270)
			(size 0 0)
			(layers "B.Cu" "B.Mask" "B.Paste")
			(net "VFG_3P3A_CLK_GEN")
		)
	)
	(footprint ""
		(layer "B.Cu")
		(at 395.152372 -395.127988 -90)
		(property "Reference" "C997"
			(at 0 0 90)
			(layer "B.SilkS")
			(hide yes)
			(effects
				(font
					(size 1.27 1.27)
				)
				(justify mirror)
			)
		)
		(property "Value" ""
			(at 0 0 90)
			(layer "B.Fab")
			(effects
				(font
					(size 1.27 1.27)
				)
				(justify mirror)
			)
		)
		(duplicate_pad_numbers_are_jumpers no)
		(fp_line
			(start -0.7874 0.4064)
			(end 0.7874 0.4064)
			(stroke
				(width 0.1524)
				(type default)
			)
			(layer "B.SilkS")
		)
		(fp_line
			(start 0.7874 0.4064)
			(end 0.7874 -0.4064)
			(stroke
				(width 0.1524)
				(type default)
			)
			(layer "B.SilkS")
		)
		(fp_line
			(start -0.7874 -0.4064)
			(end -0.7874 0.4064)
			(stroke
				(width 0.1524)
				(type default)
			)
			(layer "B.SilkS")
		)
		(fp_line
			(start 0.7874 -0.4064)
			(end -0.7874 -0.4064)
			(stroke
				(width 0.1524)
				(type default)
			)
			(layer "B.SilkS")
		)
		(fp_line
			(start -0.67945 0.3048)
			(end -0.120396 0.3048)
			(stroke
				(width 0.1)
				(type default)
			)
			(layer "B.Fab")
		)
		(fp_line
			(start -0.120396 0.3048)
			(end -0.120396 0.2794)
			(stroke
				(width 0.1)
				(type default)
			)
			(layer "B.Fab")
		)
		(fp_line
			(start 0.12065 0.3048)
			(end 0.67945 0.3048)
			(stroke
				(width 0.1)
				(type default)
			)
			(layer "B.Fab")
		)
		(fp_line
			(start 0.67945 0.3048)
			(end 0.67945 -0.305054)
			(stroke
				(width 0.1)
				(type default)
			)
			(layer "B.Fab")
		)
		(fp_line
			(start -0.120396 0.2794)
			(end 0.12065 0.2794)
			(stroke
				(width 0.1)
				(type default)
			)
			(layer "B.Fab")
		)
		(fp_line
			(start 0.12065 0.2794)
			(end 0.12065 0.3048)
			(stroke
				(width 0.1)
				(type default)
			)
			(layer "B.Fab")
		)
		(fp_line
			(start -0.12065 -0.2794)
			(end -0.12065 -0.3048)
			(stroke
				(width 0.1)
				(type default)
			)
			(layer "B.Fab")
		)
		(fp_line
			(start 0.12065 -0.2794)
			(end -0.12065 -0.2794)
			(stroke
				(width 0.1)
				(type default)
			)
			(layer "B.Fab")
		)
		(fp_line
			(start -0.67945 -0.3048)
			(end -0.67945 0.3048)
			(stroke
				(width 0.1)
				(type default)
			)
			(layer "B.Fab")
		)
		(fp_line
			(start -0.12065 -0.3048)
			(end -0.67945 -0.3048)
			(stroke
				(width 0.1)
				(type default)
			)
			(layer "B.Fab")
		)
		(fp_line
			(start 0.12065 -0.305054)
			(end 0.12065 -0.2794)
			(stroke
				(width 0.1)
				(type default)
			)
			(layer "B.Fab")
		)
		(fp_line
			(start 0.67945 -0.305054)
			(end 0.12065 -0.305054)
			(stroke
				(width 0.1)
				(type default)
			)
			(layer "B.Fab")
		)
		(pad "1" smd circle
			(at 0.40005 0 90)
			(size 0 0)
			(layers "B.Cu" "B.Mask" "B.Paste")
			(net "P1V8_CPU0_RT_1D")
		)
		(pad "2" smd circle
			(at -0.40005 0 90)
			(size 0 0)
			(layers "B.Cu" "B.Mask" "B.Paste")
			(net "GND")
		)
	)
	(footprint ""
		(layer "B.Cu")
		(at 19.727418 -409.04287 90)
		(property "Reference" "PR6816"
			(at 0 0 90)
			(layer "B.SilkS")
			(hide yes)
			(effects
				(font
					(size 1.27 1.27)
				)
				(justify mirror)
			)
		)
		(property "Value" ""
			(at 0 0 90)
			(layer "B.Fab")
			(effects
				(font
					(size 1.27 1.27)
				)
				(justify mirror)
			)
		)
		(duplicate_pad_numbers_are_jumpers no)
		(fp_line
			(start 0.7874 -0.4064)
			(end -0.7874 -0.4064)
			(stroke
				(width 0.1524)
				(type default)
			)
			(layer "B.SilkS")
		)
		(fp_line
			(start -0.7874 -0.4064)
			(end -0.7874 0.4064)
			(stroke
				(width 0.1524)
				(type default)
			)
			(layer "B.SilkS")
		)
		(fp_line
			(start 0.7874 0.4064)
			(end 0.7874 -0.4064)
			(stroke
				(width 0.1524)
				(type default)
			)
			(layer "B.SilkS")
		)
		(fp_line
			(start -0.7874 0.4064)
			(end 0.7874 0.4064)
			(stroke
				(width 0.1524)
				(type default)
			)
			(layer "B.SilkS")
		)
		(fp_line
			(start 0.67945 -0.305054)
			(end 0.12065 -0.305054)
			(stroke
				(width 0.1)
				(type default)
			)
			(layer "B.Fab")
		)
		(fp_line
			(start 0.12065 -0.305054)
			(end 0.12065 -0.2794)
			(stroke
				(width 0.1)
				(type default)
			)
			(layer "B.Fab")
		)
		(fp_line
			(start -0.12065 -0.3048)
			(end -0.67945 -0.3048)
			(stroke
				(width 0.1)
				(type default)
			)
			(layer "B.Fab")
		)
		(fp_line
			(start -0.67945 -0.3048)
			(end -0.67945 0.3048)
			(stroke
				(width 0.1)
				(type default)
			)
			(layer "B.Fab")
		)
		(fp_line
			(start 0.12065 -0.2794)
			(end -0.12065 -0.2794)
			(stroke
				(width 0.1)
				(type default)
			)
			(layer "B.Fab")
		)
		(fp_line
			(start -0.12065 -0.2794)
			(end -0.12065 -0.3048)
			(stroke
				(width 0.1)
				(type default)
			)
			(layer "B.Fab")
		)
		(fp_line
			(start 0.12065 0.2794)
			(end 0.12065 0.3048)
			(stroke
				(width 0.1)
				(type default)
			)
			(layer "B.Fab")
		)
		(fp_line
			(start -0.120396 0.2794)
			(end 0.12065 0.2794)
			(stroke
				(width 0.1)
				(type default)
			)
			(layer "B.Fab")
		)
		(fp_line
			(start 0.67945 0.3048)
			(end 0.67945 -0.305054)
			(stroke
				(width 0.1)
				(type default)
			)
			(layer "B.Fab")
		)
		(fp_line
			(start 0.12065 0.3048)
			(end 0.67945 0.3048)
			(stroke
				(width 0.1)
				(type default)
			)
			(layer "B.Fab")
		)
		(fp_line
			(start -0.120396 0.3048)
			(end -0.120396 0.2794)
			(stroke
				(width 0.1)
				(type default)
			)
			(layer "B.Fab")
		)
		(fp_line
			(start -0.67945 0.3048)
			(end -0.120396 0.3048)
			(stroke
				(width 0.1)
				(type default)
			)
			(layer "B.Fab")
		)
		(pad "1" smd circle
			(at 0.40005 0 270)
			(size 0 0)
			(layers "B.Cu" "B.Mask" "B.Paste")
			(net "P0V9_RETIMER_CPU1_VRHOT")
		)
		(pad "2" smd circle
			(at -0.40005 0 270)
			(size 0 0)
			(layers "B.Cu" "B.Mask" "B.Paste")
			(net "TP_P0V9_RETIMER_CPU1_VRHOT")
		)
	)
	(footprint ""
		(layer "B.Cu")
		(at 159.926782 -347.663008 180)
		(property "Reference" "PR390"
			(at 0 0 0)
			(layer "B.SilkS")
			(hide yes)
			(effects
				(font
					(size 1.27 1.27)
				)
				(justify mirror)
			)
		)
		(property "Value" ""
			(at 0 0 0)
			(layer "B.Fab")
			(effects
				(font
					(size 1.27 1.27)
				)
				(justify mirror)
			)
		)
		(duplicate_pad_numbers_are_jumpers no)
		(fp_line
			(start 0.7874 0.4064)
			(end 0.7874 -0.4064)
			(stroke
				(width 0.1524)
				(type default)
			)
			(layer "B.SilkS")
		)
		(fp_line
			(start 0.7874 -0.4064)
			(end -0.7874 -0.4064)
			(stroke
				(width 0.1524)
				(type default)
			)
			(layer "B.SilkS")
		)
		(fp_line
			(start -0.7874 0.4064)
			(end 0.7874 0.4064)
			(stroke
				(width 0.1524)
				(type default)
			)
			(layer "B.SilkS")
		)
		(fp_line
			(start -0.7874 -0.4064)
			(end -0.7874 0.4064)
			(stroke
				(width 0.1524)
				(type default)
			)
			(layer "B.SilkS")
		)
		(fp_line
			(start 0.67945 0.3048)
			(end 0.67945 -0.305054)
			(stroke
				(width 0.1)
				(type default)
			)
			(layer "B.Fab")
		)
		(fp_line
			(start 0.67945 -0.305054)
			(end 0.12065 -0.305054)
			(stroke
				(width 0.1)
				(type default)
			)
			(layer "B.Fab")
		)
		(fp_line
			(start 0.12065 0.3048)
			(end 0.67945 0.3048)
			(stroke
				(width 0.1)
				(type default)
			)
			(layer "B.Fab")
		)
		(fp_line
			(start 0.12065 0.2794)
			(end 0.12065 0.3048)
			(stroke
				(width 0.1)
				(type default)
			)
			(layer "B.Fab")
		)
		(fp_line
			(start 0.12065 -0.2794)
			(end -0.12065 -0.2794)
			(stroke
				(width 0.1)
				(type default)
			)
			(layer "B.Fab")
		)
		(fp_line
			(start 0.12065 -0.305054)
			(end 0.12065 -0.2794)
			(stroke
				(width 0.1)
				(type default)
			)
			(layer "B.Fab")
		)
		(fp_line
			(start -0.120396 0.3048)
			(end -0.120396 0.2794)
			(stroke
				(width 0.1)
				(type default)
			)
			(layer "B.Fab")
		)
		(fp_line
			(start -0.120396 0.2794)
			(end 0.12065 0.2794)
			(stroke
				(width 0.1)
				(type default)
			)
			(layer "B.Fab")
		)
		(fp_line
			(start -0.12065 -0.2794)
			(end -0.12065 -0.3048)
			(stroke
				(width 0.1)
				(type default)
			)
			(layer "B.Fab")
		)
		(fp_line
			(start -0.12065 -0.3048)
			(end -0.67945 -0.3048)
			(stroke
				(width 0.1)
				(type default)
			)
			(layer "B.Fab")
		)
		(fp_line
			(start -0.67945 0.3048)
			(end -0.120396 0.3048)
			(stroke
				(width 0.1)
				(type default)
			)
			(layer "B.Fab")
		)
		(fp_line
			(start -0.67945 -0.3048)
			(end -0.67945 0.3048)
			(stroke
				(width 0.1)
				(type default)
			)
			(layer "B.Fab")
		)
		(pad "1" smd circle
			(at 0.40005 0)
			(size 0 0)
			(layers "B.Cu" "B.Mask" "B.Paste")
			(net "PVDD11_S3_P1_RESET_N_R")
		)
		(pad "2" smd circle
			(at -0.40005 0)
			(size 0 0)
			(layers "B.Cu" "B.Mask" "B.Paste")
			(net "GND")
		)
	)
	(footprint ""
		(layer "B.Cu")
		(at 183.3753 -401.918932 -90)
		(property "Reference" "PC2186"
			(at 0 0 90)
			(layer "B.SilkS")
			(hide yes)
			(effects
				(font
					(size 1.27 1.27)
				)
				(justify mirror)
			)
		)
		(property "Value" ""
			(at 0 0 90)
			(layer "B.Fab")
			(effects
				(font
					(size 1.27 1.27)
				)
				(justify mirror)
			)
		)
		(duplicate_pad_numbers_are_jumpers no)
		(fp_line
			(start -0.7874 0.4064)
			(end 0.7874 0.4064)
			(stroke
				(width 0.1524)
				(type default)
			)
			(layer "B.SilkS")
		)
		(fp_line
			(start 0.7874 0.4064)
			(end 0.7874 -0.4064)
			(stroke
				(width 0.1524)
				(type default)
			)
			(layer "B.SilkS")
		)
		(fp_line
			(start -0.7874 -0.4064)
			(end -0.7874 0.4064)
			(stroke
				(width 0.1524)
				(type default)
			)
			(layer "B.SilkS")
		)
		(fp_line
			(start 0.7874 -0.4064)
			(end -0.7874 -0.4064)
			(stroke
				(width 0.1524)
				(type default)
			)
			(layer "B.SilkS")
		)
		(fp_line
			(start -0.67945 0.3048)
			(end -0.120396 0.3048)
			(stroke
				(width 0.1)
				(type default)
			)
			(layer "B.Fab")
		)
		(fp_line
			(start -0.120396 0.3048)
			(end -0.120396 0.2794)
			(stroke
				(width 0.1)
				(type default)
			)
			(layer "B.Fab")
		)
		(fp_line
			(start 0.12065 0.3048)
			(end 0.67945 0.3048)
			(stroke
				(width 0.1)
				(type default)
			)
			(layer "B.Fab")
		)
		(fp_line
			(start 0.67945 0.3048)
			(end 0.67945 -0.305054)
			(stroke
				(width 0.1)
				(type default)
			)
			(layer "B.Fab")
		)
		(fp_line
			(start -0.120396 0.2794)
			(end 0.12065 0.2794)
			(stroke
				(width 0.1)
				(type default)
			)
			(layer "B.Fab")
		)
		(fp_line
			(start 0.12065 0.2794)
			(end 0.12065 0.3048)
			(stroke
				(width 0.1)
				(type default)
			)
			(layer "B.Fab")
		)
		(fp_line
			(start -0.12065 -0.2794)
			(end -0.12065 -0.3048)
			(stroke
				(width 0.1)
				(type default)
			)
			(layer "B.Fab")
		)
		(fp_line
			(start 0.12065 -0.2794)
			(end -0.12065 -0.2794)
			(stroke
				(width 0.1)
				(type default)
			)
			(layer "B.Fab")
		)
		(fp_line
			(start -0.67945 -0.3048)
			(end -0.67945 0.3048)
			(stroke
				(width 0.1)
				(type default)
			)
			(layer "B.Fab")
		)
		(fp_line
			(start -0.12065 -0.3048)
			(end -0.67945 -0.3048)
			(stroke
				(width 0.1)
				(type default)
			)
			(layer "B.Fab")
		)
		(fp_line
			(start 0.12065 -0.305054)
			(end 0.12065 -0.2794)
			(stroke
				(width 0.1)
				(type default)
			)
			(layer "B.Fab")
		)
		(fp_line
			(start 0.67945 -0.305054)
			(end 0.12065 -0.305054)
			(stroke
				(width 0.1)
				(type default)
			)
			(layer "B.Fab")
		)
		(pad "1" smd circle
			(at 0.40005 0 90)
			(size 0 0)
			(layers "B.Cu" "B.Mask" "B.Paste")
			(net "HSC_VDD_R")
		)
		(pad "2" smd circle
			(at -0.40005 0 90)
			(size 0 0)
			(layers "B.Cu" "B.Mask" "B.Paste")
			(net "AGND_HSC")
		)
	)
	(footprint ""
		(layer "B.Cu")
		(at 332.187296 -151.132794 90)
		(property "Reference" "PR439"
			(at 0 0 90)
			(layer "B.SilkS")
			(hide yes)
			(effects
				(font
					(size 1.27 1.27)
				)
				(justify mirror)
			)
		)
		(property "Value" ""
			(at 0 0 90)
			(layer "B.Fab")
			(effects
				(font
					(size 1.27 1.27)
				)
				(justify mirror)
			)
		)
		(duplicate_pad_numbers_are_jumpers no)
		(fp_line
			(start 0.7874 -0.4064)
			(end -0.7874 -0.4064)
			(stroke
				(width 0.1524)
				(type default)
			)
			(layer "B.SilkS")
		)
		(fp_line
			(start -0.7874 -0.4064)
			(end -0.7874 0.4064)
			(stroke
				(width 0.1524)
				(type default)
			)
			(layer "B.SilkS")
		)
		(fp_line
			(start 0.7874 0.4064)
			(end 0.7874 -0.4064)
			(stroke
				(width 0.1524)
				(type default)
			)
			(layer "B.SilkS")
		)
		(fp_line
			(start -0.7874 0.4064)
			(end 0.7874 0.4064)
			(stroke
				(width 0.1524)
				(type default)
			)
			(layer "B.SilkS")
		)
		(fp_line
			(start 0.67945 -0.305054)
			(end 0.12065 -0.305054)
			(stroke
				(width 0.1)
				(type default)
			)
			(layer "B.Fab")
		)
		(fp_line
			(start 0.12065 -0.305054)
			(end 0.12065 -0.2794)
			(stroke
				(width 0.1)
				(type default)
			)
			(layer "B.Fab")
		)
		(fp_line
			(start -0.12065 -0.3048)
			(end -0.67945 -0.3048)
			(stroke
				(width 0.1)
				(type default)
			)
			(layer "B.Fab")
		)
		(fp_line
			(start -0.67945 -0.3048)
			(end -0.67945 0.3048)
			(stroke
				(width 0.1)
				(type default)
			)
			(layer "B.Fab")
		)
		(fp_line
			(start 0.12065 -0.2794)
			(end -0.12065 -0.2794)
			(stroke
				(width 0.1)
				(type default)
			)
			(layer "B.Fab")
		)
		(fp_line
			(start -0.12065 -0.2794)
			(end -0.12065 -0.3048)
			(stroke
				(width 0.1)
				(type default)
			)
			(layer "B.Fab")
		)
		(fp_line
			(start 0.12065 0.2794)
			(end 0.12065 0.3048)
			(stroke
				(width 0.1)
				(type default)
			)
			(layer "B.Fab")
		)
		(fp_line
			(start -0.120396 0.2794)
			(end 0.12065 0.2794)
			(stroke
				(width 0.1)
				(type default)
			)
			(layer "B.Fab")
		)
		(fp_line
			(start 0.67945 0.3048)
			(end 0.67945 -0.305054)
			(stroke
				(width 0.1)
				(type default)
			)
			(layer "B.Fab")
		)
		(fp_line
			(start 0.12065 0.3048)
			(end 0.67945 0.3048)
			(stroke
				(width 0.1)
				(type default)
			)
			(layer "B.Fab")
		)
		(fp_line
			(start -0.120396 0.3048)
			(end -0.120396 0.2794)
			(stroke
				(width 0.1)
				(type default)
			)
			(layer "B.Fab")
		)
		(fp_line
			(start -0.67945 0.3048)
			(end -0.120396 0.3048)
			(stroke
				(width 0.1)
				(type default)
			)
			(layer "B.Fab")
		)
		(pad "1" smd circle
			(at 0.40005 0 270)
			(size 0 0)
			(layers "B.Cu" "B.Mask" "B.Paste")
			(net "PVDD18_S5_P0")
		)
		(pad "2" smd circle
			(at -0.40005 0 270)
			(size 0 0)
			(layers "B.Cu" "B.Mask" "B.Paste")
			(net "GND")
		)
	)
	(footprint ""
		(layer "B.Cu")
		(at 153.228294 -202.93076 90)
		(property "Reference" "R526"
			(at 0 0 90)
			(layer "B.SilkS")
			(hide yes)
			(effects
				(font
					(size 1.27 1.27)
				)
				(justify mirror)
			)
		)
		(property "Value" ""
			(at 0 0 90)
			(layer "B.Fab")
			(effects
				(font
					(size 1.27 1.27)
				)
				(justify mirror)
			)
		)
		(duplicate_pad_numbers_are_jumpers no)
		(fp_line
			(start 0.7874 -0.4064)
			(end -0.7874 -0.4064)
			(stroke
				(width 0.1524)
				(type default)
			)
			(layer "B.SilkS")
		)
		(fp_line
			(start -0.7874 -0.4064)
			(end -0.7874 0.4064)
			(stroke
				(width 0.1524)
				(type default)
			)
			(layer "B.SilkS")
		)
		(fp_line
			(start 0.7874 0.4064)
			(end 0.7874 -0.4064)
			(stroke
				(width 0.1524)
				(type default)
			)
			(layer "B.SilkS")
		)
		(fp_line
			(start -0.7874 0.4064)
			(end 0.7874 0.4064)
			(stroke
				(width 0.1524)
				(type default)
			)
			(layer "B.SilkS")
		)
		(fp_line
			(start 0.67945 -0.305054)
			(end 0.12065 -0.305054)
			(stroke
				(width 0.1)
				(type default)
			)
			(layer "B.Fab")
		)
		(fp_line
			(start 0.12065 -0.305054)
			(end 0.12065 -0.2794)
			(stroke
				(width 0.1)
				(type default)
			)
			(layer "B.Fab")
		)
		(fp_line
			(start -0.12065 -0.3048)
			(end -0.67945 -0.3048)
			(stroke
				(width 0.1)
				(type default)
			)
			(layer "B.Fab")
		)
		(fp_line
			(start -0.67945 -0.3048)
			(end -0.67945 0.3048)
			(stroke
				(width 0.1)
				(type default)
			)
			(layer "B.Fab")
		)
		(fp_line
			(start 0.12065 -0.2794)
			(end -0.12065 -0.2794)
			(stroke
				(width 0.1)
				(type default)
			)
			(layer "B.Fab")
		)
		(fp_line
			(start -0.12065 -0.2794)
			(end -0.12065 -0.3048)
			(stroke
				(width 0.1)
				(type default)
			)
			(layer "B.Fab")
		)
		(fp_line
			(start 0.12065 0.2794)
			(end 0.12065 0.3048)
			(stroke
				(width 0.1)
				(type default)
			)
			(layer "B.Fab")
		)
		(fp_line
			(start -0.120396 0.2794)
			(end 0.12065 0.2794)
			(stroke
				(width 0.1)
				(type default)
			)
			(layer "B.Fab")
		)
		(fp_line
			(start 0.67945 0.3048)
			(end 0.67945 -0.305054)
			(stroke
				(width 0.1)
				(type default)
			)
			(layer "B.Fab")
		)
		(fp_line
			(start 0.12065 0.3048)
			(end 0.67945 0.3048)
			(stroke
				(width 0.1)
				(type default)
			)
			(layer "B.Fab")
		)
		(fp_line
			(start -0.120396 0.3048)
			(end -0.120396 0.2794)
			(stroke
				(width 0.1)
				(type default)
			)
			(layer "B.Fab")
		)
		(fp_line
			(start -0.67945 0.3048)
			(end -0.120396 0.3048)
			(stroke
				(width 0.1)
				(type default)
			)
			(layer "B.Fab")
		)
		(pad "1" smd circle
			(at 0.40005 0 270)
			(size 0 0)
			(layers "B.Cu" "B.Mask" "B.Paste")
			(net "PVDD18_S5_P1")
		)
		(pad "2" smd circle
			(at -0.40005 0 270)
			(size 0 0)
			(layers "B.Cu" "B.Mask" "B.Paste")
			(net "JTAG_CPU1_TCK")
		)
	)
	(footprint ""
		(layer "B.Cu")
		(at 104.561386 -264.354564)
		(property "Reference" "C2490"
			(at 0 0 0)
			(layer "B.SilkS")
			(hide yes)
			(effects
				(font
					(size 1.27 1.27)
				)
				(justify mirror)
			)
		)
		(property "Value" ""
			(at 0 0 0)
			(layer "B.Fab")
			(effects
				(font
					(size 1.27 1.27)
				)
				(justify mirror)
			)
		)
		(duplicate_pad_numbers_are_jumpers no)
		(fp_line
			(start -0.7874 -0.4064)
			(end -0.7874 0.4064)
			(stroke
				(width 0.1524)
				(type default)
			)
			(layer "B.SilkS")
		)
		(fp_line
			(start -0.7874 0.4064)
			(end 0.7874 0.4064)
			(stroke
				(width 0.1524)
				(type default)
			)
			(layer "B.SilkS")
		)
		(fp_line
			(start 0.7874 -0.4064)
			(end -0.7874 -0.4064)
			(stroke
				(width 0.1524)
				(type default)
			)
			(layer "B.SilkS")
		)
		(fp_line
			(start 0.7874 0.4064)
			(end 0.7874 -0.4064)
			(stroke
				(width 0.1524)
				(type default)
			)
			(layer "B.SilkS")
		)
		(fp_line
			(start -0.67945 -0.3048)
			(end -0.67945 0.3048)
			(stroke
				(width 0.1)
				(type default)
			)
			(layer "B.Fab")
		)
		(fp_line
			(start -0.67945 0.3048)
			(end -0.120396 0.3048)
			(stroke
				(width 0.1)
				(type default)
			)
			(layer "B.Fab")
		)
		(fp_line
			(start -0.12065 -0.3048)
			(end -0.67945 -0.3048)
			(stroke
				(width 0.1)
				(type default)
			)
			(layer "B.Fab")
		)
		(fp_line
			(start -0.12065 -0.2794)
			(end -0.12065 -0.3048)
			(stroke
				(width 0.1)
				(type default)
			)
			(layer "B.Fab")
		)
		(fp_line
			(start -0.120396 0.2794)
			(end 0.12065 0.2794)
			(stroke
				(width 0.1)
				(type default)
			)
			(layer "B.Fab")
		)
		(fp_line
			(start -0.120396 0.3048)
			(end -0.120396 0.2794)
			(stroke
				(width 0.1)
				(type default)
			)
			(layer "B.Fab")
		)
		(fp_line
			(start 0.12065 -0.305054)
			(end 0.12065 -0.2794)
			(stroke
				(width 0.1)
				(type default)
			)
			(layer "B.Fab")
		)
		(fp_line
			(start 0.12065 -0.2794)
			(end -0.12065 -0.2794)
			(stroke
				(width 0.1)
				(type default)
			)
			(layer "B.Fab")
		)
		(fp_line
			(start 0.12065 0.2794)
			(end 0.12065 0.3048)
			(stroke
				(width 0.1)
				(type default)
			)
			(layer "B.Fab")
		)
		(fp_line
			(start 0.12065 0.3048)
			(end 0.67945 0.3048)
			(stroke
				(width 0.1)
				(type default)
			)
			(layer "B.Fab")
		)
		(fp_line
			(start 0.67945 -0.305054)
			(end 0.12065 -0.305054)
			(stroke
				(width 0.1)
				(type default)
			)
			(layer "B.Fab")
		)
		(fp_line
			(start 0.67945 0.3048)
			(end 0.67945 -0.305054)
			(stroke
				(width 0.1)
				(type default)
			)
			(layer "B.Fab")
		)
		(pad "1" smd circle
			(at 0.40005 0 180)
			(size 0 0)
			(layers "B.Cu" "B.Mask" "B.Paste")
			(net "PVDD11_S3_P1")
		)
		(pad "2" smd circle
			(at -0.40005 0 180)
			(size 0 0)
			(layers "B.Cu" "B.Mask" "B.Paste")
			(net "GND")
		)
	)
	(footprint ""
		(layer "B.Cu")
		(at 377.818396 -396.393162 -90)
		(property "Reference" "C1000"
			(at 0 0 90)
			(layer "B.SilkS")
			(hide yes)
			(effects
				(font
					(size 1.27 1.27)
				)
				(justify mirror)
			)
		)
		(property "Value" ""
			(at 0 0 90)
			(layer "B.Fab")
			(effects
				(font
					(size 1.27 1.27)
				)
				(justify mirror)
			)
		)
		(duplicate_pad_numbers_are_jumpers no)
		(fp_line
			(start -0.299974 0.150114)
			(end 0.299974 0.150114)
			(stroke
				(width 0.1)
				(type default)
			)
			(layer "B.Fab")
		)
		(fp_line
			(start 0.299974 0.150114)
			(end 0.299974 -0.150114)
			(stroke
				(width 0.1)
				(type default)
			)
			(layer "B.Fab")
		)
		(fp_line
			(start -0.299974 -0.150114)
			(end -0.299974 0.150114)
			(stroke
				(width 0.1)
				(type default)
			)
			(layer "B.Fab")
		)
		(fp_line
			(start 0.299974 -0.150114)
			(end -0.299974 -0.150114)
			(stroke
				(width 0.1)
				(type default)
			)
			(layer "B.Fab")
		)
		(pad "1" smd rect
			(at 0.2667 0 90)
			(size 0.3048 0.381)
			(layers "B.Cu" "B.Mask" "B.Paste")
			(net "P1V8_CPU0_RT3_1A")
		)
		(pad "2" smd rect
			(at -0.2667 0 90)
			(size 0.3048 0.381)
			(layers "B.Cu" "B.Mask" "B.Paste")
			(net "GND")
		)
	)
	(footprint ""
		(layer "B.Cu")
		(at 150.97887 -13.762228 90)
		(property "Reference" "R2417"
			(at 0 0 90)
			(layer "B.SilkS")
			(hide yes)
			(effects
				(font
					(size 1.27 1.27)
				)
				(justify mirror)
			)
		)
		(property "Value" ""
			(at 0 0 90)
			(layer "B.Fab")
			(effects
				(font
					(size 1.27 1.27)
				)
				(justify mirror)
			)
		)
		(duplicate_pad_numbers_are_jumpers no)
		(fp_line
			(start 0.7874 -0.4064)
			(end -0.7874 -0.4064)
			(stroke
				(width 0.1524)
				(type default)
			)
			(layer "B.SilkS")
		)
		(fp_line
			(start -0.7874 -0.4064)
			(end -0.7874 0.4064)
			(stroke
				(width 0.1524)
				(type default)
			)
			(layer "B.SilkS")
		)
		(fp_line
			(start 0.7874 0.4064)
			(end 0.7874 -0.4064)
			(stroke
				(width 0.1524)
				(type default)
			)
			(layer "B.SilkS")
		)
		(fp_line
			(start -0.7874 0.4064)
			(end 0.7874 0.4064)
			(stroke
				(width 0.1524)
				(type default)
			)
			(layer "B.SilkS")
		)
		(fp_line
			(start 0.67945 -0.305054)
			(end 0.12065 -0.305054)
			(stroke
				(width 0.1)
				(type default)
			)
			(layer "B.Fab")
		)
		(fp_line
			(start 0.12065 -0.305054)
			(end 0.12065 -0.2794)
			(stroke
				(width 0.1)
				(type default)
			)
			(layer "B.Fab")
		)
		(fp_line
			(start -0.12065 -0.3048)
			(end -0.67945 -0.3048)
			(stroke
				(width 0.1)
				(type default)
			)
			(layer "B.Fab")
		)
		(fp_line
			(start -0.67945 -0.3048)
			(end -0.67945 0.3048)
			(stroke
				(width 0.1)
				(type default)
			)
			(layer "B.Fab")
		)
		(fp_line
			(start 0.12065 -0.2794)
			(end -0.12065 -0.2794)
			(stroke
				(width 0.1)
				(type default)
			)
			(layer "B.Fab")
		)
		(fp_line
			(start -0.12065 -0.2794)
			(end -0.12065 -0.3048)
			(stroke
				(width 0.1)
				(type default)
			)
			(layer "B.Fab")
		)
		(fp_line
			(start 0.12065 0.2794)
			(end 0.12065 0.3048)
			(stroke
				(width 0.1)
				(type default)
			)
			(layer "B.Fab")
		)
		(fp_line
			(start -0.120396 0.2794)
			(end 0.12065 0.2794)
			(stroke
				(width 0.1)
				(type default)
			)
			(layer "B.Fab")
		)
		(fp_line
			(start 0.67945 0.3048)
			(end 0.67945 -0.305054)
			(stroke
				(width 0.1)
				(type default)
			)
			(layer "B.Fab")
		)
		(fp_line
			(start 0.12065 0.3048)
			(end 0.67945 0.3048)
			(stroke
				(width 0.1)
				(type default)
			)
			(layer "B.Fab")
		)
		(fp_line
			(start -0.120396 0.3048)
			(end -0.120396 0.2794)
			(stroke
				(width 0.1)
				(type default)
			)
			(layer "B.Fab")
		)
		(fp_line
			(start -0.67945 0.3048)
			(end -0.120396 0.3048)
			(stroke
				(width 0.1)
				(type default)
			)
			(layer "B.Fab")
		)
		(pad "1" smd circle
			(at 0.40005 0 270)
			(size 0 0)
			(layers "B.Cu" "B.Mask" "B.Paste")
			(net "SMB_HOST_CLK_3V3AUX_SCL")
		)
		(pad "2" smd circle
			(at -0.40005 0 270)
			(size 0 0)
			(layers "B.Cu" "B.Mask" "B.Paste")
			(net "SMB_HOST_CLK_3V3AUX_SCL_R0")
		)
	)
	(footprint ""
		(layer "B.Cu")
		(at 113.71834 -61.76391 -90)
		(property "Reference" "R6225"
			(at 0 0 90)
			(layer "B.SilkS")
			(hide yes)
			(effects
				(font
					(size 1.27 1.27)
				)
				(justify mirror)
			)
		)
		(property "Value" ""
			(at 0 0 90)
			(layer "B.Fab")
			(effects
				(font
					(size 1.27 1.27)
				)
				(justify mirror)
			)
		)
		(duplicate_pad_numbers_are_jumpers no)
		(fp_line
			(start -0.7874 0.4064)
			(end 0.7874 0.4064)
			(stroke
				(width 0.1524)
				(type default)
			)
			(layer "B.SilkS")
		)
		(fp_line
			(start 0.7874 0.4064)
			(end 0.7874 -0.4064)
			(stroke
				(width 0.1524)
				(type default)
			)
			(layer "B.SilkS")
		)
		(fp_line
			(start -0.7874 -0.4064)
			(end -0.7874 0.4064)
			(stroke
				(width 0.1524)
				(type default)
			)
			(layer "B.SilkS")
		)
		(fp_line
			(start 0.7874 -0.4064)
			(end -0.7874 -0.4064)
			(stroke
				(width 0.1524)
				(type default)
			)
			(layer "B.SilkS")
		)
		(fp_line
			(start -0.67945 0.3048)
			(end -0.120396 0.3048)
			(stroke
				(width 0.1)
				(type default)
			)
			(layer "B.Fab")
		)
		(fp_line
			(start -0.120396 0.3048)
			(end -0.120396 0.2794)
			(stroke
				(width 0.1)
				(type default)
			)
			(layer "B.Fab")
		)
		(fp_line
			(start 0.12065 0.3048)
			(end 0.67945 0.3048)
			(stroke
				(width 0.1)
				(type default)
			)
			(layer "B.Fab")
		)
		(fp_line
			(start 0.67945 0.3048)
			(end 0.67945 -0.305054)
			(stroke
				(width 0.1)
				(type default)
			)
			(layer "B.Fab")
		)
		(fp_line
			(start -0.120396 0.2794)
			(end 0.12065 0.2794)
			(stroke
				(width 0.1)
				(type default)
			)
			(layer "B.Fab")
		)
		(fp_line
			(start 0.12065 0.2794)
			(end 0.12065 0.3048)
			(stroke
				(width 0.1)
				(type default)
			)
			(layer "B.Fab")
		)
		(fp_line
			(start -0.12065 -0.2794)
			(end -0.12065 -0.3048)
			(stroke
				(width 0.1)
				(type default)
			)
			(layer "B.Fab")
		)
		(fp_line
			(start 0.12065 -0.2794)
			(end -0.12065 -0.2794)
			(stroke
				(width 0.1)
				(type default)
			)
			(layer "B.Fab")
		)
		(fp_line
			(start -0.67945 -0.3048)
			(end -0.67945 0.3048)
			(stroke
				(width 0.1)
				(type default)
			)
			(layer "B.Fab")
		)
		(fp_line
			(start -0.12065 -0.3048)
			(end -0.67945 -0.3048)
			(stroke
				(width 0.1)
				(type default)
			)
			(layer "B.Fab")
		)
		(fp_line
			(start 0.12065 -0.305054)
			(end 0.12065 -0.2794)
			(stroke
				(width 0.1)
				(type default)
			)
			(layer "B.Fab")
		)
		(fp_line
			(start 0.67945 -0.305054)
			(end 0.12065 -0.305054)
			(stroke
				(width 0.1)
				(type default)
			)
			(layer "B.Fab")
		)
		(pad "1" smd circle
			(at 0.40005 0 90)
			(size 0 0)
			(layers "B.Cu" "B.Mask" "B.Paste")
			(net "SMB_USB_CPU0_HUB1_SDA")
		)
		(pad "2" smd circle
			(at -0.40005 0 90)
			(size 0 0)
			(layers "B.Cu" "B.Mask" "B.Paste")
			(net "SMB_USB_CPU0_HUB1_SDA_R2")
		)
	)
	(footprint ""
		(layer "B.Cu")
		(at 353.900232 -258.405122 180)
		(property "Reference" "C2638"
			(at 0 0 0)
			(layer "B.SilkS")
			(hide yes)
			(effects
				(font
					(size 1.27 1.27)
				)
				(justify mirror)
			)
		)
		(property "Value" ""
			(at 0 0 0)
			(layer "B.Fab")
			(effects
				(font
					(size 1.27 1.27)
				)
				(justify mirror)
			)
		)
		(duplicate_pad_numbers_are_jumpers no)
		(fp_line
			(start 0.7874 0.4064)
			(end 0.7874 -0.4064)
			(stroke
				(width 0.1524)
				(type default)
			)
			(layer "B.SilkS")
		)
		(fp_line
			(start 0.7874 -0.4064)
			(end -0.7874 -0.4064)
			(stroke
				(width 0.1524)
				(type default)
			)
			(layer "B.SilkS")
		)
		(fp_line
			(start -0.7874 0.4064)
			(end 0.7874 0.4064)
			(stroke
				(width 0.1524)
				(type default)
			)
			(layer "B.SilkS")
		)
		(fp_line
			(start -0.7874 -0.4064)
			(end -0.7874 0.4064)
			(stroke
				(width 0.1524)
				(type default)
			)
			(layer "B.SilkS")
		)
		(fp_line
			(start 0.67945 0.3048)
			(end 0.67945 -0.305054)
			(stroke
				(width 0.1)
				(type default)
			)
			(layer "B.Fab")
		)
		(fp_line
			(start 0.67945 -0.305054)
			(end 0.12065 -0.305054)
			(stroke
				(width 0.1)
				(type default)
			)
			(layer "B.Fab")
		)
		(fp_line
			(start 0.12065 0.3048)
			(end 0.67945 0.3048)
			(stroke
				(width 0.1)
				(type default)
			)
			(layer "B.Fab")
		)
		(fp_line
			(start 0.12065 0.2794)
			(end 0.12065 0.3048)
			(stroke
				(width 0.1)
				(type default)
			)
			(layer "B.Fab")
		)
		(fp_line
			(start 0.12065 -0.2794)
			(end -0.12065 -0.2794)
			(stroke
				(width 0.1)
				(type default)
			)
			(layer "B.Fab")
		)
		(fp_line
			(start 0.12065 -0.305054)
			(end 0.12065 -0.2794)
			(stroke
				(width 0.1)
				(type default)
			)
			(layer "B.Fab")
		)
		(fp_line
			(start -0.120396 0.3048)
			(end -0.120396 0.2794)
			(stroke
				(width 0.1)
				(type default)
			)
			(layer "B.Fab")
		)
		(fp_line
			(start -0.120396 0.2794)
			(end 0.12065 0.2794)
			(stroke
				(width 0.1)
				(type default)
			)
			(layer "B.Fab")
		)
		(fp_line
			(start -0.12065 -0.2794)
			(end -0.12065 -0.3048)
			(stroke
				(width 0.1)
				(type default)
			)
			(layer "B.Fab")
		)
		(fp_line
			(start -0.12065 -0.3048)
			(end -0.67945 -0.3048)
			(stroke
				(width 0.1)
				(type default)
			)
			(layer "B.Fab")
		)
		(fp_line
			(start -0.67945 0.3048)
			(end -0.120396 0.3048)
			(stroke
				(width 0.1)
				(type default)
			)
			(layer "B.Fab")
		)
		(fp_line
			(start -0.67945 -0.3048)
			(end -0.67945 0.3048)
			(stroke
				(width 0.1)
				(type default)
			)
			(layer "B.Fab")
		)
		(pad "1" smd circle
			(at 0.40005 0)
			(size 0 0)
			(layers "B.Cu" "B.Mask" "B.Paste")
			(net "PVDDIO_P0")
		)
		(pad "2" smd circle
			(at -0.40005 0)
			(size 0 0)
			(layers "B.Cu" "B.Mask" "B.Paste")
			(net "GND")
		)
	)
	(footprint ""
		(layer "B.Cu")
		(at 121.810272 -71.397622 180)
		(property "Reference" "C6085"
			(at 0 0 0)
			(layer "B.SilkS")
			(hide yes)
			(effects
				(font
					(size 1.27 1.27)
				)
				(justify mirror)
			)
		)
		(property "Value" ""
			(at 0 0 0)
			(layer "B.Fab")
			(effects
				(font
					(size 1.27 1.27)
				)
				(justify mirror)
			)
		)
		(duplicate_pad_numbers_are_jumpers no)
		(fp_line
			(start 0.7874 0.4064)
			(end 0.7874 -0.4064)
			(stroke
				(width 0.1524)
				(type default)
			)
			(layer "B.SilkS")
		)
		(fp_line
			(start 0.7874 -0.4064)
			(end -0.7874 -0.4064)
			(stroke
				(width 0.1524)
				(type default)
			)
			(layer "B.SilkS")
		)
		(fp_line
			(start -0.7874 0.4064)
			(end 0.7874 0.4064)
			(stroke
				(width 0.1524)
				(type default)
			)
			(layer "B.SilkS")
		)
		(fp_line
			(start -0.7874 -0.4064)
			(end -0.7874 0.4064)
			(stroke
				(width 0.1524)
				(type default)
			)
			(layer "B.SilkS")
		)
		(fp_line
			(start 0.67945 0.3048)
			(end 0.67945 -0.305054)
			(stroke
				(width 0.1)
				(type default)
			)
			(layer "B.Fab")
		)
		(fp_line
			(start 0.67945 -0.305054)
			(end 0.12065 -0.305054)
			(stroke
				(width 0.1)
				(type default)
			)
			(layer "B.Fab")
		)
		(fp_line
			(start 0.12065 0.3048)
			(end 0.67945 0.3048)
			(stroke
				(width 0.1)
				(type default)
			)
			(layer "B.Fab")
		)
		(fp_line
			(start 0.12065 0.2794)
			(end 0.12065 0.3048)
			(stroke
				(width 0.1)
				(type default)
			)
			(layer "B.Fab")
		)
		(fp_line
			(start 0.12065 -0.2794)
			(end -0.12065 -0.2794)
			(stroke
				(width 0.1)
				(type default)
			)
			(layer "B.Fab")
		)
		(fp_line
			(start 0.12065 -0.305054)
			(end 0.12065 -0.2794)
			(stroke
				(width 0.1)
				(type default)
			)
			(layer "B.Fab")
		)
		(fp_line
			(start -0.120396 0.3048)
			(end -0.120396 0.2794)
			(stroke
				(width 0.1)
				(type default)
			)
			(layer "B.Fab")
		)
		(fp_line
			(start -0.120396 0.2794)
			(end 0.12065 0.2794)
			(stroke
				(width 0.1)
				(type default)
			)
			(layer "B.Fab")
		)
		(fp_line
			(start -0.12065 -0.2794)
			(end -0.12065 -0.3048)
			(stroke
				(width 0.1)
				(type default)
			)
			(layer "B.Fab")
		)
		(fp_line
			(start -0.12065 -0.3048)
			(end -0.67945 -0.3048)
			(stroke
				(width 0.1)
				(type default)
			)
			(layer "B.Fab")
		)
		(fp_line
			(start -0.67945 0.3048)
			(end -0.120396 0.3048)
			(stroke
				(width 0.1)
				(type default)
			)
			(layer "B.Fab")
		)
		(fp_line
			(start -0.67945 -0.3048)
			(end -0.67945 0.3048)
			(stroke
				(width 0.1)
				(type default)
			)
			(layer "B.Fab")
		)
		(pad "1" smd circle
			(at 0.40005 0)
			(size 0 0)
			(layers "B.Cu" "B.Mask" "B.Paste")
			(net "PWRGD_P1V8_AUX_R")
		)
		(pad "2" smd circle
			(at -0.40005 0)
			(size 0 0)
			(layers "B.Cu" "B.Mask" "B.Paste")
			(net "GND")
		)
	)
	(footprint ""
		(layer "B.Cu")
		(at 287.149286 -428.26051)
		(property "Reference" "R2666"
			(at 0 0 0)
			(layer "B.SilkS")
			(hide yes)
			(effects
				(font
					(size 1.27 1.27)
				)
				(justify mirror)
			)
		)
		(property "Value" ""
			(at 0 0 0)
			(layer "B.Fab")
			(effects
				(font
					(size 1.27 1.27)
				)
				(justify mirror)
			)
		)
		(duplicate_pad_numbers_are_jumpers no)
		(fp_line
			(start -0.7874 -0.4064)
			(end -0.7874 0.4064)
			(stroke
				(width 0.1524)
				(type default)
			)
			(layer "B.SilkS")
		)
		(fp_line
			(start -0.7874 0.4064)
			(end 0.7874 0.4064)
			(stroke
				(width 0.1524)
				(type default)
			)
			(layer "B.SilkS")
		)
		(fp_line
			(start 0.7874 -0.4064)
			(end -0.7874 -0.4064)
			(stroke
				(width 0.1524)
				(type default)
			)
			(layer "B.SilkS")
		)
		(fp_line
			(start 0.7874 0.4064)
			(end 0.7874 -0.4064)
			(stroke
				(width 0.1524)
				(type default)
			)
			(layer "B.SilkS")
		)
		(fp_line
			(start -0.67945 -0.3048)
			(end -0.67945 0.3048)
			(stroke
				(width 0.1)
				(type default)
			)
			(layer "B.Fab")
		)
		(fp_line
			(start -0.67945 0.3048)
			(end -0.120396 0.3048)
			(stroke
				(width 0.1)
				(type default)
			)
			(layer "B.Fab")
		)
		(fp_line
			(start -0.12065 -0.3048)
			(end -0.67945 -0.3048)
			(stroke
				(width 0.1)
				(type default)
			)
			(layer "B.Fab")
		)
		(fp_line
			(start -0.12065 -0.2794)
			(end -0.12065 -0.3048)
			(stroke
				(width 0.1)
				(type default)
			)
			(layer "B.Fab")
		)
		(fp_line
			(start -0.120396 0.2794)
			(end 0.12065 0.2794)
			(stroke
				(width 0.1)
				(type default)
			)
			(layer "B.Fab")
		)
		(fp_line
			(start -0.120396 0.3048)
			(end -0.120396 0.2794)
			(stroke
				(width 0.1)
				(type default)
			)
			(layer "B.Fab")
		)
		(fp_line
			(start 0.12065 -0.305054)
			(end 0.12065 -0.2794)
			(stroke
				(width 0.1)
				(type default)
			)
			(layer "B.Fab")
		)
		(fp_line
			(start 0.12065 -0.2794)
			(end -0.12065 -0.2794)
			(stroke
				(width 0.1)
				(type default)
			)
			(layer "B.Fab")
		)
		(fp_line
			(start 0.12065 0.2794)
			(end 0.12065 0.3048)
			(stroke
				(width 0.1)
				(type default)
			)
			(layer "B.Fab")
		)
		(fp_line
			(start 0.12065 0.3048)
			(end 0.67945 0.3048)
			(stroke
				(width 0.1)
				(type default)
			)
			(layer "B.Fab")
		)
		(fp_line
			(start 0.67945 -0.305054)
			(end 0.12065 -0.305054)
			(stroke
				(width 0.1)
				(type default)
			)
			(layer "B.Fab")
		)
		(fp_line
			(start 0.67945 0.3048)
			(end 0.67945 -0.305054)
			(stroke
				(width 0.1)
				(type default)
			)
			(layer "B.Fab")
		)
		(pad "1" smd circle
			(at 0.40005 0 180)
			(size 0 0)
			(layers "B.Cu" "B.Mask" "B.Paste")
			(net "SMB_BMC_SWB_EN")
		)
		(pad "2" smd circle
			(at -0.40005 0 180)
			(size 0 0)
			(layers "B.Cu" "B.Mask" "B.Paste")
			(net "GND")
		)
	)
	(footprint ""
		(layer "B.Cu")
		(at 165.08984 -384.29946 -90)
		(property "Reference" "C426"
			(at 0 0 90)
			(layer "B.SilkS")
			(hide yes)
			(effects
				(font
					(size 1.27 1.27)
				)
				(justify mirror)
			)
		)
		(property "Value" ""
			(at 0 0 90)
			(layer "B.Fab")
			(effects
				(font
					(size 1.27 1.27)
				)
				(justify mirror)
			)
		)
		(duplicate_pad_numbers_are_jumpers no)
		(fp_line
			(start -0.299974 0.150114)
			(end 0.299974 0.150114)
			(stroke
				(width 0.1)
				(type default)
			)
			(layer "B.Fab")
		)
		(fp_line
			(start 0.299974 0.150114)
			(end 0.299974 -0.150114)
			(stroke
				(width 0.1)
				(type default)
			)
			(layer "B.Fab")
		)
		(fp_line
			(start -0.299974 -0.150114)
			(end -0.299974 0.150114)
			(stroke
				(width 0.1)
				(type default)
			)
			(layer "B.Fab")
		)
		(fp_line
			(start 0.299974 -0.150114)
			(end -0.299974 -0.150114)
			(stroke
				(width 0.1)
				(type default)
			)
			(layer "B.Fab")
		)
		(pad "1" smd rect
			(at 0.2667 0 90)
			(size 0.3048 0.381)
			(layers "B.Cu" "B.Mask" "B.Paste")
			(net "P0V9_CPU1_RT2_2A")
		)
		(pad "2" smd rect
			(at -0.2667 0 90)
			(size 0.3048 0.381)
			(layers "B.Cu" "B.Mask" "B.Paste")
			(net "GND")
		)
	)
	(footprint ""
		(layer "B.Cu")
		(at 91.392502 -207.41005 90)
		(property "Reference" "R618"
			(at 0 0 90)
			(layer "B.SilkS")
			(hide yes)
			(effects
				(font
					(size 1.27 1.27)
				)
				(justify mirror)
			)
		)
		(property "Value" ""
			(at 0 0 90)
			(layer "B.Fab")
			(effects
				(font
					(size 1.27 1.27)
				)
				(justify mirror)
			)
		)
		(duplicate_pad_numbers_are_jumpers no)
		(fp_line
			(start 0.7874 -0.4064)
			(end -0.7874 -0.4064)
			(stroke
				(width 0.1524)
				(type default)
			)
			(layer "B.SilkS")
		)
		(fp_line
			(start -0.7874 -0.4064)
			(end -0.7874 0.4064)
			(stroke
				(width 0.1524)
				(type default)
			)
			(layer "B.SilkS")
		)
		(fp_line
			(start 0.7874 0.4064)
			(end 0.7874 -0.4064)
			(stroke
				(width 0.1524)
				(type default)
			)
			(layer "B.SilkS")
		)
		(fp_line
			(start -0.7874 0.4064)
			(end 0.7874 0.4064)
			(stroke
				(width 0.1524)
				(type default)
			)
			(layer "B.SilkS")
		)
		(fp_line
			(start 0.67945 -0.305054)
			(end 0.12065 -0.305054)
			(stroke
				(width 0.1)
				(type default)
			)
			(layer "B.Fab")
		)
		(fp_line
			(start 0.12065 -0.305054)
			(end 0.12065 -0.2794)
			(stroke
				(width 0.1)
				(type default)
			)
			(layer "B.Fab")
		)
		(fp_line
			(start -0.12065 -0.3048)
			(end -0.67945 -0.3048)
			(stroke
				(width 0.1)
				(type default)
			)
			(layer "B.Fab")
		)
		(fp_line
			(start -0.67945 -0.3048)
			(end -0.67945 0.3048)
			(stroke
				(width 0.1)
				(type default)
			)
			(layer "B.Fab")
		)
		(fp_line
			(start 0.12065 -0.2794)
			(end -0.12065 -0.2794)
			(stroke
				(width 0.1)
				(type default)
			)
			(layer "B.Fab")
		)
		(fp_line
			(start -0.12065 -0.2794)
			(end -0.12065 -0.3048)
			(stroke
				(width 0.1)
				(type default)
			)
			(layer "B.Fab")
		)
		(fp_line
			(start 0.12065 0.2794)
			(end 0.12065 0.3048)
			(stroke
				(width 0.1)
				(type default)
			)
			(layer "B.Fab")
		)
		(fp_line
			(start -0.120396 0.2794)
			(end 0.12065 0.2794)
			(stroke
				(width 0.1)
				(type default)
			)
			(layer "B.Fab")
		)
		(fp_line
			(start 0.67945 0.3048)
			(end 0.67945 -0.305054)
			(stroke
				(width 0.1)
				(type default)
			)
			(layer "B.Fab")
		)
		(fp_line
			(start 0.12065 0.3048)
			(end 0.67945 0.3048)
			(stroke
				(width 0.1)
				(type default)
			)
			(layer "B.Fab")
		)
		(fp_line
			(start -0.120396 0.3048)
			(end -0.120396 0.2794)
			(stroke
				(width 0.1)
				(type default)
			)
			(layer "B.Fab")
		)
		(fp_line
			(start -0.67945 0.3048)
			(end -0.120396 0.3048)
			(stroke
				(width 0.1)
				(type default)
			)
			(layer "B.Fab")
		)
		(pad "1" smd circle
			(at 0.40005 0 270)
			(size 0 0)
			(layers "B.Cu" "B.Mask" "B.Paste")
			(net "CPU1_XTRIG_R2_L5")
		)
		(pad "2" smd circle
			(at -0.40005 0 270)
			(size 0 0)
			(layers "B.Cu" "B.Mask" "B.Paste")
			(net "CPU1_XTRIG_L5")
		)
	)
	(footprint ""
		(layer "B.Cu")
		(at 149.406356 -386.766562 90)
		(property "Reference" "C415"
			(at 0 0 90)
			(layer "B.SilkS")
			(hide yes)
			(effects
				(font
					(size 1.27 1.27)
				)
				(justify mirror)
			)
		)
		(property "Value" ""
			(at 0 0 90)
			(layer "B.Fab")
			(effects
				(font
					(size 1.27 1.27)
				)
				(justify mirror)
			)
		)
		(duplicate_pad_numbers_are_jumpers no)
		(fp_line
			(start 0.299974 -0.150114)
			(end -0.299974 -0.150114)
			(stroke
				(width 0.1)
				(type default)
			)
			(layer "B.Fab")
		)
		(fp_line
			(start -0.299974 -0.150114)
			(end -0.299974 0.150114)
			(stroke
				(width 0.1)
				(type default)
			)
			(layer "B.Fab")
		)
		(fp_line
			(start 0.299974 0.150114)
			(end 0.299974 -0.150114)
			(stroke
				(width 0.1)
				(type default)
			)
			(layer "B.Fab")
		)
		(fp_line
			(start -0.299974 0.150114)
			(end 0.299974 0.150114)
			(stroke
				(width 0.1)
				(type default)
			)
			(layer "B.Fab")
		)
		(pad "1" smd rect
			(at 0.2667 0 270)
			(size 0.3048 0.381)
			(layers "B.Cu" "B.Mask" "B.Paste")
			(net "P0V9_CPU1_RT2_2A")
		)
		(pad "2" smd rect
			(at -0.2667 0 270)
			(size 0.3048 0.381)
			(layers "B.Cu" "B.Mask" "B.Paste")
			(net "GND")
		)
	)
	(footprint ""
		(layer "B.Cu")
		(at 130.07848 -386.766562 90)
		(property "Reference" "C492"
			(at 0 0 90)
			(layer "B.SilkS")
			(hide yes)
			(effects
				(font
					(size 1.27 1.27)
				)
				(justify mirror)
			)
		)
		(property "Value" ""
			(at 0 0 90)
			(layer "B.Fab")
			(effects
				(font
					(size 1.27 1.27)
				)
				(justify mirror)
			)
		)
		(duplicate_pad_numbers_are_jumpers no)
		(fp_line
			(start 0.299974 -0.150114)
			(end -0.299974 -0.150114)
			(stroke
				(width 0.1)
				(type default)
			)
			(layer "B.Fab")
		)
		(fp_line
			(start -0.299974 -0.150114)
			(end -0.299974 0.150114)
			(stroke
				(width 0.1)
				(type default)
			)
			(layer "B.Fab")
		)
		(fp_line
			(start 0.299974 0.150114)
			(end 0.299974 -0.150114)
			(stroke
				(width 0.1)
				(type default)
			)
			(layer "B.Fab")
		)
		(fp_line
			(start -0.299974 0.150114)
			(end 0.299974 0.150114)
			(stroke
				(width 0.1)
				(type default)
			)
			(layer "B.Fab")
		)
		(pad "1" smd rect
			(at 0.2667 0 270)
			(size 0.3048 0.381)
			(layers "B.Cu" "B.Mask" "B.Paste")
			(net "P0V9_CPU1_RT3_2A")
		)
		(pad "2" smd rect
			(at -0.2667 0 270)
			(size 0.3048 0.381)
			(layers "B.Cu" "B.Mask" "B.Paste")
			(net "GND")
		)
	)
	(footprint ""
		(layer "B.Cu")
		(at 105.454196 -27.800808 -90)
		(property "Reference" "L6003"
			(at 0 0 90)
			(layer "B.SilkS")
			(hide yes)
			(effects
				(font
					(size 1.27 1.27)
				)
				(justify mirror)
			)
		)
		(property "Value" ""
			(at 0 0 90)
			(layer "B.Fab")
			(effects
				(font
					(size 1.27 1.27)
				)
				(justify mirror)
			)
		)
		(duplicate_pad_numbers_are_jumpers no)
		(fp_line
			(start -1.63576 0.8128)
			(end 1.63576 0.8128)
			(stroke
				(width 0.1524)
				(type default)
			)
			(layer "B.SilkS")
		)
		(fp_line
			(start -1.63576 -0.8128)
			(end -1.63576 0.8128)
			(stroke
				(width 0.1524)
				(type default)
			)
			(layer "B.SilkS")
		)
		(fp_line
			(start 1.63576 -0.8128)
			(end 1.63576 0.8128)
			(stroke
				(width 0.1524)
				(type default)
			)
			(layer "B.SilkS")
		)
		(fp_line
			(start 1.63576 -0.8128)
			(end -1.63576 -0.8128)
			(stroke
				(width 0.1524)
				(type default)
			)
			(layer "B.SilkS")
		)
		(fp_line
			(start -1.560576 0.7366)
			(end -1.560576 -0.738632)
			(stroke
				(width 0.1)
				(type default)
			)
			(layer "B.Fab")
		)
		(fp_line
			(start -1.524 0.7366)
			(end -1.560576 0.7366)
			(stroke
				(width 0.1)
				(type default)
			)
			(layer "B.Fab")
		)
		(fp_line
			(start 1.524 0.7366)
			(end -1.524 0.7366)
			(stroke
				(width 0.1)
				(type default)
			)
			(layer "B.Fab")
		)
		(fp_line
			(start 1.56083 0.7366)
			(end 1.524 0.7366)
			(stroke
				(width 0.1)
				(type default)
			)
			(layer "B.Fab")
		)
		(fp_line
			(start -1.560576 -0.738632)
			(end 1.56083 -0.738632)
			(stroke
				(width 0.1)
				(type default)
			)
			(layer "B.Fab")
		)
		(fp_line
			(start 1.56083 -0.738632)
			(end 1.56083 0.7366)
			(stroke
				(width 0.1)
				(type default)
			)
			(layer "B.Fab")
		)
		(pad "1" smd rect
			(at 0.94996 0 270)
			(size 1.1176 1.3716)
			(layers "B.Cu" "B.Mask" "B.Paste")
			(net "P3V3_AUX")
		)
		(pad "2" smd rect
			(at -0.94996 0 270)
			(size 1.1176 1.3716)
			(layers "B.Cu" "B.Mask" "B.Paste")
			(net "P3V3_AUX_CPU0_USB2_AVDD33")
		)
	)
	(footprint ""
		(layer "B.Cu")
		(at 349.834454 -255.84531)
		(property "Reference" "C2560"
			(at 0 0 0)
			(layer "B.SilkS")
			(hide yes)
			(effects
				(font
					(size 1.27 1.27)
				)
				(justify mirror)
			)
		)
		(property "Value" ""
			(at 0 0 0)
			(layer "B.Fab")
			(effects
				(font
					(size 1.27 1.27)
				)
				(justify mirror)
			)
		)
		(duplicate_pad_numbers_are_jumpers no)
		(fp_line
			(start -0.7874 -0.4064)
			(end -0.7874 0.4064)
			(stroke
				(width 0.1524)
				(type default)
			)
			(layer "B.SilkS")
		)
		(fp_line
			(start -0.7874 0.4064)
			(end 0.7874 0.4064)
			(stroke
				(width 0.1524)
				(type default)
			)
			(layer "B.SilkS")
		)
		(fp_line
			(start 0.7874 -0.4064)
			(end -0.7874 -0.4064)
			(stroke
				(width 0.1524)
				(type default)
			)
			(layer "B.SilkS")
		)
		(fp_line
			(start 0.7874 0.4064)
			(end 0.7874 -0.4064)
			(stroke
				(width 0.1524)
				(type default)
			)
			(layer "B.SilkS")
		)
		(fp_line
			(start -0.67945 -0.3048)
			(end -0.67945 0.3048)
			(stroke
				(width 0.1)
				(type default)
			)
			(layer "B.Fab")
		)
		(fp_line
			(start -0.67945 0.3048)
			(end -0.120396 0.3048)
			(stroke
				(width 0.1)
				(type default)
			)
			(layer "B.Fab")
		)
		(fp_line
			(start -0.12065 -0.3048)
			(end -0.67945 -0.3048)
			(stroke
				(width 0.1)
				(type default)
			)
			(layer "B.Fab")
		)
		(fp_line
			(start -0.12065 -0.2794)
			(end -0.12065 -0.3048)
			(stroke
				(width 0.1)
				(type default)
			)
			(layer "B.Fab")
		)
		(fp_line
			(start -0.120396 0.2794)
			(end 0.12065 0.2794)
			(stroke
				(width 0.1)
				(type default)
			)
			(layer "B.Fab")
		)
		(fp_line
			(start -0.120396 0.3048)
			(end -0.120396 0.2794)
			(stroke
				(width 0.1)
				(type default)
			)
			(layer "B.Fab")
		)
		(fp_line
			(start 0.12065 -0.305054)
			(end 0.12065 -0.2794)
			(stroke
				(width 0.1)
				(type default)
			)
			(layer "B.Fab")
		)
		(fp_line
			(start 0.12065 -0.2794)
			(end -0.12065 -0.2794)
			(stroke
				(width 0.1)
				(type default)
			)
			(layer "B.Fab")
		)
		(fp_line
			(start 0.12065 0.2794)
			(end 0.12065 0.3048)
			(stroke
				(width 0.1)
				(type default)
			)
			(layer "B.Fab")
		)
		(fp_line
			(start 0.12065 0.3048)
			(end 0.67945 0.3048)
			(stroke
				(width 0.1)
				(type default)
			)
			(layer "B.Fab")
		)
		(fp_line
			(start 0.67945 -0.305054)
			(end 0.12065 -0.305054)
			(stroke
				(width 0.1)
				(type default)
			)
			(layer "B.Fab")
		)
		(fp_line
			(start 0.67945 0.3048)
			(end 0.67945 -0.305054)
			(stroke
				(width 0.1)
				(type default)
			)
			(layer "B.Fab")
		)
		(pad "1" smd circle
			(at 0.40005 0 180)
			(size 0 0)
			(layers "B.Cu" "B.Mask" "B.Paste")
			(net "PVDDCR_SOC_P0")
		)
		(pad "2" smd circle
			(at -0.40005 0 180)
			(size 0 0)
			(layers "B.Cu" "B.Mask" "B.Paste")
			(net "GND")
		)
	)
	(footprint ""
		(layer "B.Cu")
		(at 204.5843 -402.744432 -90)
		(property "Reference" "PR3911"
			(at 0 0 90)
			(layer "B.SilkS")
			(hide yes)
			(effects
				(font
					(size 1.27 1.27)
				)
				(justify mirror)
			)
		)
		(property "Value" ""
			(at 0 0 90)
			(layer "B.Fab")
			(effects
				(font
					(size 1.27 1.27)
				)
				(justify mirror)
			)
		)
		(duplicate_pad_numbers_are_jumpers no)
		(fp_line
			(start -0.7874 0.4064)
			(end 0.7874 0.4064)
			(stroke
				(width 0.1524)
				(type default)
			)
			(layer "B.SilkS")
		)
		(fp_line
			(start 0.7874 0.4064)
			(end 0.7874 -0.4064)
			(stroke
				(width 0.1524)
				(type default)
			)
			(layer "B.SilkS")
		)
		(fp_line
			(start -0.7874 -0.4064)
			(end -0.7874 0.4064)
			(stroke
				(width 0.1524)
				(type default)
			)
			(layer "B.SilkS")
		)
		(fp_line
			(start 0.7874 -0.4064)
			(end -0.7874 -0.4064)
			(stroke
				(width 0.1524)
				(type default)
			)
			(layer "B.SilkS")
		)
		(fp_line
			(start -0.67945 0.3048)
			(end -0.120396 0.3048)
			(stroke
				(width 0.1)
				(type default)
			)
			(layer "B.Fab")
		)
		(fp_line
			(start -0.120396 0.3048)
			(end -0.120396 0.2794)
			(stroke
				(width 0.1)
				(type default)
			)
			(layer "B.Fab")
		)
		(fp_line
			(start 0.12065 0.3048)
			(end 0.67945 0.3048)
			(stroke
				(width 0.1)
				(type default)
			)
			(layer "B.Fab")
		)
		(fp_line
			(start 0.67945 0.3048)
			(end 0.67945 -0.305054)
			(stroke
				(width 0.1)
				(type default)
			)
			(layer "B.Fab")
		)
		(fp_line
			(start -0.120396 0.2794)
			(end 0.12065 0.2794)
			(stroke
				(width 0.1)
				(type default)
			)
			(layer "B.Fab")
		)
		(fp_line
			(start 0.12065 0.2794)
			(end 0.12065 0.3048)
			(stroke
				(width 0.1)
				(type default)
			)
			(layer "B.Fab")
		)
		(fp_line
			(start -0.12065 -0.2794)
			(end -0.12065 -0.3048)
			(stroke
				(width 0.1)
				(type default)
			)
			(layer "B.Fab")
		)
		(fp_line
			(start 0.12065 -0.2794)
			(end -0.12065 -0.2794)
			(stroke
				(width 0.1)
				(type default)
			)
			(layer "B.Fab")
		)
		(fp_line
			(start -0.67945 -0.3048)
			(end -0.67945 0.3048)
			(stroke
				(width 0.1)
				(type default)
			)
			(layer "B.Fab")
		)
		(fp_line
			(start -0.12065 -0.3048)
			(end -0.67945 -0.3048)
			(stroke
				(width 0.1)
				(type default)
			)
			(layer "B.Fab")
		)
		(fp_line
			(start 0.12065 -0.305054)
			(end 0.12065 -0.2794)
			(stroke
				(width 0.1)
				(type default)
			)
			(layer "B.Fab")
		)
		(fp_line
			(start 0.67945 -0.305054)
			(end 0.12065 -0.305054)
			(stroke
				(width 0.1)
				(type default)
			)
			(layer "B.Fab")
		)
		(pad "1" smd circle
			(at 0.40005 0 90)
			(size 0 0)
			(layers "B.Cu" "B.Mask" "B.Paste")
			(net "HSC_VDD_R_2")
		)
		(pad "2" smd circle
			(at -0.40005 0 90)
			(size 0 0)
			(layers "B.Cu" "B.Mask" "B.Paste")
			(net "HSC_VDD")
		)
	)
	(footprint ""
		(layer "B.Cu")
		(at 114.618516 -388.011162 -90)
		(property "Reference" "C500"
			(at 0 0 90)
			(layer "B.SilkS")
			(hide yes)
			(effects
				(font
					(size 1.27 1.27)
				)
				(justify mirror)
			)
		)
		(property "Value" ""
			(at 0 0 90)
			(layer "B.Fab")
			(effects
				(font
					(size 1.27 1.27)
				)
				(justify mirror)
			)
		)
		(duplicate_pad_numbers_are_jumpers no)
		(fp_line
			(start -0.299974 0.150114)
			(end 0.299974 0.150114)
			(stroke
				(width 0.1)
				(type default)
			)
			(layer "B.Fab")
		)
		(fp_line
			(start 0.299974 0.150114)
			(end 0.299974 -0.150114)
			(stroke
				(width 0.1)
				(type default)
			)
			(layer "B.Fab")
		)
		(fp_line
			(start -0.299974 -0.150114)
			(end -0.299974 0.150114)
			(stroke
				(width 0.1)
				(type default)
			)
			(layer "B.Fab")
		)
		(fp_line
			(start 0.299974 -0.150114)
			(end -0.299974 -0.150114)
			(stroke
				(width 0.1)
				(type default)
			)
			(layer "B.Fab")
		)
		(pad "1" smd rect
			(at 0.2667 0 90)
			(size 0.3048 0.381)
			(layers "B.Cu" "B.Mask" "B.Paste")
			(net "P0V9_CPU1_RT3_2A")
		)
		(pad "2" smd rect
			(at -0.2667 0 90)
			(size 0.3048 0.381)
			(layers "B.Cu" "B.Mask" "B.Paste")
			(net "GND")
		)
	)
	(footprint ""
		(layer "B.Cu")
		(at 127.678434 -386.766562 90)
		(property "Reference" "C460"
			(at 0 0 90)
			(layer "B.SilkS")
			(hide yes)
			(effects
				(font
					(size 1.27 1.27)
				)
				(justify mirror)
			)
		)
		(property "Value" ""
			(at 0 0 90)
			(layer "B.Fab")
			(effects
				(font
					(size 1.27 1.27)
				)
				(justify mirror)
			)
		)
		(duplicate_pad_numbers_are_jumpers no)
		(fp_line
			(start 0.299974 -0.150114)
			(end -0.299974 -0.150114)
			(stroke
				(width 0.1)
				(type default)
			)
			(layer "B.Fab")
		)
		(fp_line
			(start -0.299974 -0.150114)
			(end -0.299974 0.150114)
			(stroke
				(width 0.1)
				(type default)
			)
			(layer "B.Fab")
		)
		(fp_line
			(start 0.299974 0.150114)
			(end 0.299974 -0.150114)
			(stroke
				(width 0.1)
				(type default)
			)
			(layer "B.Fab")
		)
		(fp_line
			(start -0.299974 0.150114)
			(end 0.299974 0.150114)
			(stroke
				(width 0.1)
				(type default)
			)
			(layer "B.Fab")
		)
		(pad "1" smd rect
			(at 0.2667 0 270)
			(size 0.3048 0.381)
			(layers "B.Cu" "B.Mask" "B.Paste")
			(net "P0V9_CPU1_RT3_2A_2D")
		)
		(pad "2" smd rect
			(at -0.2667 0 270)
			(size 0.3048 0.381)
			(layers "B.Cu" "B.Mask" "B.Paste")
			(net "GND")
		)
	)
	(footprint ""
		(layer "B.Cu")
		(at 181.182518 -415.616644 -90)
		(property "Reference" "R2911"
			(at 0 0 90)
			(layer "B.SilkS")
			(hide yes)
			(effects
				(font
					(size 1.27 1.27)
				)
				(justify mirror)
			)
		)
		(property "Value" ""
			(at 0 0 90)
			(layer "B.Fab")
			(effects
				(font
					(size 1.27 1.27)
				)
				(justify mirror)
			)
		)
		(duplicate_pad_numbers_are_jumpers no)
		(fp_line
			(start -0.7874 0.4064)
			(end 0.7874 0.4064)
			(stroke
				(width 0.1524)
				(type default)
			)
			(layer "B.SilkS")
		)
		(fp_line
			(start 0.7874 0.4064)
			(end 0.7874 -0.4064)
			(stroke
				(width 0.1524)
				(type default)
			)
			(layer "B.SilkS")
		)
		(fp_line
			(start -0.7874 -0.4064)
			(end -0.7874 0.4064)
			(stroke
				(width 0.1524)
				(type default)
			)
			(layer "B.SilkS")
		)
		(fp_line
			(start 0.7874 -0.4064)
			(end -0.7874 -0.4064)
			(stroke
				(width 0.1524)
				(type default)
			)
			(layer "B.SilkS")
		)
		(fp_line
			(start -0.67945 0.3048)
			(end -0.120396 0.3048)
			(stroke
				(width 0.1)
				(type default)
			)
			(layer "B.Fab")
		)
		(fp_line
			(start -0.120396 0.3048)
			(end -0.120396 0.2794)
			(stroke
				(width 0.1)
				(type default)
			)
			(layer "B.Fab")
		)
		(fp_line
			(start 0.12065 0.3048)
			(end 0.67945 0.3048)
			(stroke
				(width 0.1)
				(type default)
			)
			(layer "B.Fab")
		)
		(fp_line
			(start 0.67945 0.3048)
			(end 0.67945 -0.305054)
			(stroke
				(width 0.1)
				(type default)
			)
			(layer "B.Fab")
		)
		(fp_line
			(start -0.120396 0.2794)
			(end 0.12065 0.2794)
			(stroke
				(width 0.1)
				(type default)
			)
			(layer "B.Fab")
		)
		(fp_line
			(start 0.12065 0.2794)
			(end 0.12065 0.3048)
			(stroke
				(width 0.1)
				(type default)
			)
			(layer "B.Fab")
		)
		(fp_line
			(start -0.12065 -0.2794)
			(end -0.12065 -0.3048)
			(stroke
				(width 0.1)
				(type default)
			)
			(layer "B.Fab")
		)
		(fp_line
			(start 0.12065 -0.2794)
			(end -0.12065 -0.2794)
			(stroke
				(width 0.1)
				(type default)
			)
			(layer "B.Fab")
		)
		(fp_line
			(start -0.67945 -0.3048)
			(end -0.67945 0.3048)
			(stroke
				(width 0.1)
				(type default)
			)
			(layer "B.Fab")
		)
		(fp_line
			(start -0.12065 -0.3048)
			(end -0.67945 -0.3048)
			(stroke
				(width 0.1)
				(type default)
			)
			(layer "B.Fab")
		)
		(fp_line
			(start 0.12065 -0.305054)
			(end 0.12065 -0.2794)
			(stroke
				(width 0.1)
				(type default)
			)
			(layer "B.Fab")
		)
		(fp_line
			(start 0.67945 -0.305054)
			(end 0.12065 -0.305054)
			(stroke
				(width 0.1)
				(type default)
			)
			(layer "B.Fab")
		)
		(pad "1" smd circle
			(at 0.40005 0 90)
			(size 0 0)
			(layers "B.Cu" "B.Mask" "B.Paste")
			(net "P3V3_AUX")
		)
		(pad "2" smd circle
			(at -0.40005 0 90)
			(size 0 0)
			(layers "B.Cu" "B.Mask" "B.Paste")
			(net "RST_SWB_BIC_BUF_R_N")
		)
	)
	(footprint ""
		(layer "B.Cu")
		(at 231.143048 -322.84035)
		(property "Reference" "R1259"
			(at 0 0 0)
			(layer "B.SilkS")
			(hide yes)
			(effects
				(font
					(size 1.27 1.27)
				)
				(justify mirror)
			)
		)
		(property "Value" ""
			(at 0 0 0)
			(layer "B.Fab")
			(effects
				(font
					(size 1.27 1.27)
				)
				(justify mirror)
			)
		)
		(duplicate_pad_numbers_are_jumpers no)
		(fp_line
			(start -0.7874 -0.4064)
			(end -0.7874 0.4064)
			(stroke
				(width 0.1524)
				(type default)
			)
			(layer "B.SilkS")
		)
		(fp_line
			(start -0.7874 0.4064)
			(end 0.7874 0.4064)
			(stroke
				(width 0.1524)
				(type default)
			)
			(layer "B.SilkS")
		)
		(fp_line
			(start 0.7874 -0.4064)
			(end -0.7874 -0.4064)
			(stroke
				(width 0.1524)
				(type default)
			)
			(layer "B.SilkS")
		)
		(fp_line
			(start 0.7874 0.4064)
			(end 0.7874 -0.4064)
			(stroke
				(width 0.1524)
				(type default)
			)
			(layer "B.SilkS")
		)
		(fp_line
			(start -0.67945 -0.3048)
			(end -0.67945 0.3048)
			(stroke
				(width 0.1)
				(type default)
			)
			(layer "B.Fab")
		)
		(fp_line
			(start -0.67945 0.3048)
			(end -0.120396 0.3048)
			(stroke
				(width 0.1)
				(type default)
			)
			(layer "B.Fab")
		)
		(fp_line
			(start -0.12065 -0.3048)
			(end -0.67945 -0.3048)
			(stroke
				(width 0.1)
				(type default)
			)
			(layer "B.Fab")
		)
		(fp_line
			(start -0.12065 -0.2794)
			(end -0.12065 -0.3048)
			(stroke
				(width 0.1)
				(type default)
			)
			(layer "B.Fab")
		)
		(fp_line
			(start -0.120396 0.2794)
			(end 0.12065 0.2794)
			(stroke
				(width 0.1)
				(type default)
			)
			(layer "B.Fab")
		)
		(fp_line
			(start -0.120396 0.3048)
			(end -0.120396 0.2794)
			(stroke
				(width 0.1)
				(type default)
			)
			(layer "B.Fab")
		)
		(fp_line
			(start 0.12065 -0.305054)
			(end 0.12065 -0.2794)
			(stroke
				(width 0.1)
				(type default)
			)
			(layer "B.Fab")
		)
		(fp_line
			(start 0.12065 -0.2794)
			(end -0.12065 -0.2794)
			(stroke
				(width 0.1)
				(type default)
			)
			(layer "B.Fab")
		)
		(fp_line
			(start 0.12065 0.2794)
			(end 0.12065 0.3048)
			(stroke
				(width 0.1)
				(type default)
			)
			(layer "B.Fab")
		)
		(fp_line
			(start 0.12065 0.3048)
			(end 0.67945 0.3048)
			(stroke
				(width 0.1)
				(type default)
			)
			(layer "B.Fab")
		)
		(fp_line
			(start 0.67945 -0.305054)
			(end 0.12065 -0.305054)
			(stroke
				(width 0.1)
				(type default)
			)
			(layer "B.Fab")
		)
		(fp_line
			(start 0.67945 0.3048)
			(end 0.67945 -0.305054)
			(stroke
				(width 0.1)
				(type default)
			)
			(layer "B.Fab")
		)
		(pad "1" smd rect
			(at 0.40005 0)
			(size 0.4572 0.508)
			(layers "B.Cu" "B.Mask" "B.Paste")
			(net "P1V8_AUX_ADC")
		)
		(pad "2" smd rect
			(at -0.40005 0)
			(size 0.4572 0.508)
			(layers "B.Cu" "B.Mask" "B.Paste")
			(net "P1V8_AUX_ADC_TIC")
		)
	)
	(footprint ""
		(layer "B.Cu")
		(at 114.439954 -168.142412 90)
		(property "Reference" "PC327_1"
			(at 0 0 90)
			(layer "B.SilkS")
			(hide yes)
			(effects
				(font
					(size 1.27 1.27)
				)
				(justify mirror)
			)
		)
		(property "Value" ""
			(at 0 0 90)
			(layer "B.Fab")
			(effects
				(font
					(size 1.27 1.27)
				)
				(justify mirror)
			)
		)
		(duplicate_pad_numbers_are_jumpers no)
		(fp_line
			(start 1.524 -0.762)
			(end -1.524 -0.762)
			(stroke
				(width 0.1524)
				(type default)
			)
			(layer "B.SilkS")
		)
		(fp_line
			(start -1.524 -0.762)
			(end -1.524 0.762)
			(stroke
				(width 0.1524)
				(type default)
			)
			(layer "B.SilkS")
		)
		(fp_line
			(start 1.524 0.762)
			(end 1.524 -0.762)
			(stroke
				(width 0.1524)
				(type default)
			)
			(layer "B.SilkS")
		)
		(fp_line
			(start -1.524 0.762)
			(end 1.524 0.762)
			(stroke
				(width 0.1524)
				(type default)
			)
			(layer "B.SilkS")
		)
		(fp_line
			(start 1.1049 -0.724916)
			(end 1.1049 0.724916)
			(stroke
				(width 0.1)
				(type default)
			)
			(layer "B.Fab")
		)
		(fp_line
			(start -1.1049 -0.724916)
			(end 1.1049 -0.724916)
			(stroke
				(width 0.1)
				(type default)
			)
			(layer "B.Fab")
		)
		(fp_line
			(start 1.1049 0.724916)
			(end -1.1049 0.724916)
			(stroke
				(width 0.1)
				(type default)
			)
			(layer "B.Fab")
		)
		(fp_line
			(start -1.1049 0.724916)
			(end -1.1049 -0.724916)
			(stroke
				(width 0.1)
				(type default)
			)
			(layer "B.Fab")
		)
		(pad "1" smd rect
			(at 0.889 0 90)
			(size 1.016 1.27)
			(layers "B.Cu" "B.Mask" "B.Paste")
			(net "SW_P12V_AUX_PVDDCR_SOC_P1_FLT")
		)
		(pad "2" smd rect
			(at -0.889 0 90)
			(size 1.016 1.27)
			(layers "B.Cu" "B.Mask" "B.Paste")
			(net "GND")
		)
	)
	(footprint ""
		(layer "B.Cu")
		(at 410.073602 -416.899344 90)
		(property "Reference" "C6621"
			(at 0 0 90)
			(layer "B.SilkS")
			(hide yes)
			(effects
				(font
					(size 1.27 1.27)
				)
				(justify mirror)
			)
		)
		(property "Value" ""
			(at 0 0 90)
			(layer "B.Fab")
			(effects
				(font
					(size 1.27 1.27)
				)
				(justify mirror)
			)
		)
		(duplicate_pad_numbers_are_jumpers no)
		(fp_line
			(start 0.299974 -0.150114)
			(end -0.299974 -0.150114)
			(stroke
				(width 0.1)
				(type default)
			)
			(layer "B.Fab")
		)
		(fp_line
			(start -0.299974 -0.150114)
			(end -0.299974 0.150114)
			(stroke
				(width 0.1)
				(type default)
			)
			(layer "B.Fab")
		)
		(fp_line
			(start 0.299974 0.150114)
			(end 0.299974 -0.150114)
			(stroke
				(width 0.1)
				(type default)
			)
			(layer "B.Fab")
		)
		(fp_line
			(start -0.299974 0.150114)
			(end 0.299974 0.150114)
			(stroke
				(width 0.1)
				(type default)
			)
			(layer "B.Fab")
		)
		(pad "1" smd rect
			(at 0.2667 0 270)
			(size 0.3048 0.381)
			(layers "B.Cu" "B.Mask" "B.Paste")
			(net "P5E_CPU0_P3_TX_BUF_C_DP<12>")
		)
		(pad "2" smd rect
			(at -0.2667 0 270)
			(size 0.3048 0.381)
			(layers "B.Cu" "B.Mask" "B.Paste")
			(net "P5E_CPU0_P3_TX_BUF_DP<12>")
		)
	)
	(footprint ""
		(layer "B.Cu")
		(at 474.29293 -212.746082)
		(property "Reference" "DB14"
			(at 2.639822 -5.63118 270)
			(unlocked yes)
			(layer "B.SilkS")
			(effects
				(font
					(size 0.7874 0.5842)
					(thickness 0.1524)
				)
				(justify left mirror)
			)
		)
		(property "Value" ""
			(at 0 0 0)
			(layer "B.Fab")
			(effects
				(font
					(size 1.27 1.27)
				)
				(justify mirror)
			)
		)
		(duplicate_pad_numbers_are_jumpers no)
		(fp_line
			(start -3.330702 -4.771136)
			(end 0 4.011168)
			(stroke
				(width 0.1524)
				(type default)
			)
			(layer "B.SilkS")
		)
		(fp_line
			(start 0 4.011168)
			(end 3.330702 -4.771136)
			(stroke
				(width 0.1524)
				(type default)
			)
			(layer "B.SilkS")
		)
		(fp_line
			(start 3.330702 -4.771136)
			(end -3.330702 -4.771136)
			(stroke
				(width 0.1524)
				(type default)
			)
			(layer "B.SilkS")
		)
		(fp_line
			(start -3.330702 -4.771136)
			(end 0 4.011168)
			(stroke
				(width 0.1)
				(type default)
			)
			(layer "B.Fab")
		)
		(fp_line
			(start 0 4.011168)
			(end 3.330702 -4.771136)
			(stroke
				(width 0.1)
				(type default)
			)
			(layer "B.Fab")
		)
		(fp_line
			(start 3.330702 -4.771136)
			(end -3.330702 -4.771136)
			(stroke
				(width 0.1)
				(type default)
			)
			(layer "B.Fab")
		)
		(pad "1" thru_hole circle
			(at 0 0 180)
			(size 2.159 2.159)
			(drill 1.7018)
			(layers "*.Cu" "*.Mask")
			(remove_unused_layers no)
			(net "T1_GND")
			(clearance 0.0254)
			(thermal_gap 0.0254)
		)
		(pad "2" thru_hole circle
			(at 1.27 -3.348736 180)
			(size 2.159 2.159)
			(drill 1.7018)
			(layers "*.Cu" "*.Mask")
			(remove_unused_layers no)
			(net "TDR_SE_45_OHM_IN6")
			(clearance 0.0254)
			(thermal_gap 0.0254)
		)
		(pad "3" thru_hole circle
			(at -1.27 -3.348736 180)
			(size 2.159 2.159)
			(drill 1.7018)
			(layers "*.Cu" "*.Mask")
			(remove_unused_layers no)
			(net "TDR_SE_45_OHM_IN6")
			(clearance 0.0254)
			(thermal_gap 0.0254)
		)
	)
	(footprint ""
		(layer "B.Cu")
		(at 409.809188 -165.928548 90)
		(property "Reference" "PR363"
			(at 0 0 90)
			(layer "B.SilkS")
			(hide yes)
			(effects
				(font
					(size 1.27 1.27)
				)
				(justify mirror)
			)
		)
		(property "Value" ""
			(at 0 0 90)
			(layer "B.Fab")
			(effects
				(font
					(size 1.27 1.27)
				)
				(justify mirror)
			)
		)
		(duplicate_pad_numbers_are_jumpers no)
		(fp_line
			(start 0.7874 -0.4064)
			(end -0.7874 -0.4064)
			(stroke
				(width 0.1524)
				(type default)
			)
			(layer "B.SilkS")
		)
		(fp_line
			(start -0.7874 -0.4064)
			(end -0.7874 0.4064)
			(stroke
				(width 0.1524)
				(type default)
			)
			(layer "B.SilkS")
		)
		(fp_line
			(start 0.7874 0.4064)
			(end 0.7874 -0.4064)
			(stroke
				(width 0.1524)
				(type default)
			)
			(layer "B.SilkS")
		)
		(fp_line
			(start -0.7874 0.4064)
			(end 0.7874 0.4064)
			(stroke
				(width 0.1524)
				(type default)
			)
			(layer "B.SilkS")
		)
		(fp_line
			(start 0.67945 -0.305054)
			(end 0.12065 -0.305054)
			(stroke
				(width 0.1)
				(type default)
			)
			(layer "B.Fab")
		)
		(fp_line
			(start 0.12065 -0.305054)
			(end 0.12065 -0.2794)
			(stroke
				(width 0.1)
				(type default)
			)
			(layer "B.Fab")
		)
		(fp_line
			(start -0.12065 -0.3048)
			(end -0.67945 -0.3048)
			(stroke
				(width 0.1)
				(type default)
			)
			(layer "B.Fab")
		)
		(fp_line
			(start -0.67945 -0.3048)
			(end -0.67945 0.3048)
			(stroke
				(width 0.1)
				(type default)
			)
			(layer "B.Fab")
		)
		(fp_line
			(start 0.12065 -0.2794)
			(end -0.12065 -0.2794)
			(stroke
				(width 0.1)
				(type default)
			)
			(layer "B.Fab")
		)
		(fp_line
			(start -0.12065 -0.2794)
			(end -0.12065 -0.3048)
			(stroke
				(width 0.1)
				(type default)
			)
			(layer "B.Fab")
		)
		(fp_line
			(start 0.12065 0.2794)
			(end 0.12065 0.3048)
			(stroke
				(width 0.1)
				(type default)
			)
			(layer "B.Fab")
		)
		(fp_line
			(start -0.120396 0.2794)
			(end 0.12065 0.2794)
			(stroke
				(width 0.1)
				(type default)
			)
			(layer "B.Fab")
		)
		(fp_line
			(start 0.67945 0.3048)
			(end 0.67945 -0.305054)
			(stroke
				(width 0.1)
				(type default)
			)
			(layer "B.Fab")
		)
		(fp_line
			(start 0.12065 0.3048)
			(end 0.67945 0.3048)
			(stroke
				(width 0.1)
				(type default)
			)
			(layer "B.Fab")
		)
		(fp_line
			(start -0.120396 0.3048)
			(end -0.120396 0.2794)
			(stroke
				(width 0.1)
				(type default)
			)
			(layer "B.Fab")
		)
		(fp_line
			(start -0.67945 0.3048)
			(end -0.120396 0.3048)
			(stroke
				(width 0.1)
				(type default)
			)
			(layer "B.Fab")
		)
		(pad "1" smd circle
			(at 0.40005 0 270)
			(size 0 0)
			(layers "B.Cu" "B.Mask" "B.Paste")
			(net "PVDDCR_SOC_P0_VOS2")
		)
		(pad "2" smd circle
			(at -0.40005 0 270)
			(size 0 0)
			(layers "B.Cu" "B.Mask" "B.Paste")
			(net "PVDDCR_SOC_P0")
		)
	)
	(footprint ""
		(layer "B.Cu")
		(at 187.35294 -130.468116 -90)
		(property "Reference" "R193"
			(at 0 0 90)
			(layer "B.SilkS")
			(hide yes)
			(effects
				(font
					(size 1.27 1.27)
				)
				(justify mirror)
			)
		)
		(property "Value" ""
			(at 0 0 90)
			(layer "B.Fab")
			(effects
				(font
					(size 1.27 1.27)
				)
				(justify mirror)
			)
		)
		(duplicate_pad_numbers_are_jumpers no)
		(fp_line
			(start -0.7874 0.4064)
			(end 0.7874 0.4064)
			(stroke
				(width 0.1524)
				(type default)
			)
			(layer "B.SilkS")
		)
		(fp_line
			(start 0.7874 0.4064)
			(end 0.7874 -0.4064)
			(stroke
				(width 0.1524)
				(type default)
			)
			(layer "B.SilkS")
		)
		(fp_line
			(start -0.7874 -0.4064)
			(end -0.7874 0.4064)
			(stroke
				(width 0.1524)
				(type default)
			)
			(layer "B.SilkS")
		)
		(fp_line
			(start 0.7874 -0.4064)
			(end -0.7874 -0.4064)
			(stroke
				(width 0.1524)
				(type default)
			)
			(layer "B.SilkS")
		)
		(fp_line
			(start -0.67945 0.3048)
			(end -0.120396 0.3048)
			(stroke
				(width 0.1)
				(type default)
			)
			(layer "B.Fab")
		)
		(fp_line
			(start -0.120396 0.3048)
			(end -0.120396 0.2794)
			(stroke
				(width 0.1)
				(type default)
			)
			(layer "B.Fab")
		)
		(fp_line
			(start 0.12065 0.3048)
			(end 0.67945 0.3048)
			(stroke
				(width 0.1)
				(type default)
			)
			(layer "B.Fab")
		)
		(fp_line
			(start 0.67945 0.3048)
			(end 0.67945 -0.305054)
			(stroke
				(width 0.1)
				(type default)
			)
			(layer "B.Fab")
		)
		(fp_line
			(start -0.120396 0.2794)
			(end 0.12065 0.2794)
			(stroke
				(width 0.1)
				(type default)
			)
			(layer "B.Fab")
		)
		(fp_line
			(start 0.12065 0.2794)
			(end 0.12065 0.3048)
			(stroke
				(width 0.1)
				(type default)
			)
			(layer "B.Fab")
		)
		(fp_line
			(start -0.12065 -0.2794)
			(end -0.12065 -0.3048)
			(stroke
				(width 0.1)
				(type default)
			)
			(layer "B.Fab")
		)
		(fp_line
			(start 0.12065 -0.2794)
			(end -0.12065 -0.2794)
			(stroke
				(width 0.1)
				(type default)
			)
			(layer "B.Fab")
		)
		(fp_line
			(start -0.67945 -0.3048)
			(end -0.67945 0.3048)
			(stroke
				(width 0.1)
				(type default)
			)
			(layer "B.Fab")
		)
		(fp_line
			(start -0.12065 -0.3048)
			(end -0.67945 -0.3048)
			(stroke
				(width 0.1)
				(type default)
			)
			(layer "B.Fab")
		)
		(fp_line
			(start 0.12065 -0.305054)
			(end 0.12065 -0.2794)
			(stroke
				(width 0.1)
				(type default)
			)
			(layer "B.Fab")
		)
		(fp_line
			(start 0.67945 -0.305054)
			(end 0.12065 -0.305054)
			(stroke
				(width 0.1)
				(type default)
			)
			(layer "B.Fab")
		)
		(pad "1" smd circle
			(at 0.40005 0 90)
			(size 0 0)
			(layers "B.Cu" "B.Mask" "B.Paste")
			(net "FM_CPU1_SMERR_N")
		)
		(pad "2" smd circle
			(at -0.40005 0 90)
			(size 0 0)
			(layers "B.Cu" "B.Mask" "B.Paste")
			(net "CPU1_SMERR_N")
		)
	)
	(footprint ""
		(layer "B.Cu")
		(at 299.265594 -394.29436 180)
		(property "Reference" "R982"
			(at 0 0 0)
			(layer "B.SilkS")
			(hide yes)
			(effects
				(font
					(size 1.27 1.27)
				)
				(justify mirror)
			)
		)
		(property "Value" ""
			(at 0 0 0)
			(layer "B.Fab")
			(effects
				(font
					(size 1.27 1.27)
				)
				(justify mirror)
			)
		)
		(duplicate_pad_numbers_are_jumpers no)
		(fp_line
			(start 0.32512 0.175006)
			(end 0.32512 -0.175006)
			(stroke
				(width 0.1)
				(type default)
			)
			(layer "B.Fab")
		)
		(fp_line
			(start 0.32512 -0.175006)
			(end -0.32512 -0.175006)
			(stroke
				(width 0.1)
				(type default)
			)
			(layer "B.Fab")
		)
		(fp_line
			(start -0.32512 0.175006)
			(end 0.32512 0.175006)
			(stroke
				(width 0.1)
				(type default)
			)
			(layer "B.Fab")
		)
		(fp_line
			(start -0.32512 -0.175006)
			(end -0.32512 0.175006)
			(stroke
				(width 0.1)
				(type default)
			)
			(layer "B.Fab")
		)
		(pad "1" smd rect
			(at 0.2667 0)
			(size 0.3048 0.381)
			(layers "B.Cu" "B.Mask" "B.Paste")
			(net "TEST0_RT_CPU0_P0")
		)
		(pad "2" smd rect
			(at -0.2667 0 180)
			(size 0.3048 0.381)
			(layers "B.Cu" "B.Mask" "B.Paste")
			(net "GND")
		)
	)
	(footprint ""
		(layer "B.Cu")
		(at 171.196 -115.280948)
		(property "Reference" "R992"
			(at 0 0 0)
			(layer "B.SilkS")
			(hide yes)
			(effects
				(font
					(size 1.27 1.27)
				)
				(justify mirror)
			)
		)
		(property "Value" ""
			(at 0 0 0)
			(layer "B.Fab")
			(effects
				(font
					(size 1.27 1.27)
				)
				(justify mirror)
			)
		)
		(duplicate_pad_numbers_are_jumpers no)
		(fp_line
			(start -0.7874 -0.4064)
			(end -0.7874 0.4064)
			(stroke
				(width 0.1524)
				(type default)
			)
			(layer "B.SilkS")
		)
		(fp_line
			(start -0.7874 0.4064)
			(end 0.7874 0.4064)
			(stroke
				(width 0.1524)
				(type default)
			)
			(layer "B.SilkS")
		)
		(fp_line
			(start 0.7874 -0.4064)
			(end -0.7874 -0.4064)
			(stroke
				(width 0.1524)
				(type default)
			)
			(layer "B.SilkS")
		)
		(fp_line
			(start 0.7874 0.4064)
			(end 0.7874 -0.4064)
			(stroke
				(width 0.1524)
				(type default)
			)
			(layer "B.SilkS")
		)
		(fp_line
			(start -0.67945 -0.3048)
			(end -0.67945 0.3048)
			(stroke
				(width 0.1)
				(type default)
			)
			(layer "B.Fab")
		)
		(fp_line
			(start -0.67945 0.3048)
			(end -0.120396 0.3048)
			(stroke
				(width 0.1)
				(type default)
			)
			(layer "B.Fab")
		)
		(fp_line
			(start -0.12065 -0.3048)
			(end -0.67945 -0.3048)
			(stroke
				(width 0.1)
				(type default)
			)
			(layer "B.Fab")
		)
		(fp_line
			(start -0.12065 -0.2794)
			(end -0.12065 -0.3048)
			(stroke
				(width 0.1)
				(type default)
			)
			(layer "B.Fab")
		)
		(fp_line
			(start -0.120396 0.2794)
			(end 0.12065 0.2794)
			(stroke
				(width 0.1)
				(type default)
			)
			(layer "B.Fab")
		)
		(fp_line
			(start -0.120396 0.3048)
			(end -0.120396 0.2794)
			(stroke
				(width 0.1)
				(type default)
			)
			(layer "B.Fab")
		)
		(fp_line
			(start 0.12065 -0.305054)
			(end 0.12065 -0.2794)
			(stroke
				(width 0.1)
				(type default)
			)
			(layer "B.Fab")
		)
		(fp_line
			(start 0.12065 -0.2794)
			(end -0.12065 -0.2794)
			(stroke
				(width 0.1)
				(type default)
			)
			(layer "B.Fab")
		)
		(fp_line
			(start 0.12065 0.2794)
			(end 0.12065 0.3048)
			(stroke
				(width 0.1)
				(type default)
			)
			(layer "B.Fab")
		)
		(fp_line
			(start 0.12065 0.3048)
			(end 0.67945 0.3048)
			(stroke
				(width 0.1)
				(type default)
			)
			(layer "B.Fab")
		)
		(fp_line
			(start 0.67945 -0.305054)
			(end 0.12065 -0.305054)
			(stroke
				(width 0.1)
				(type default)
			)
			(layer "B.Fab")
		)
		(fp_line
			(start 0.67945 0.3048)
			(end 0.67945 -0.305054)
			(stroke
				(width 0.1)
				(type default)
			)
			(layer "B.Fab")
		)
		(pad "1" smd circle
			(at 0.40005 0 180)
			(size 0 0)
			(layers "B.Cu" "B.Mask" "B.Paste")
			(net "FM_SYS_THROTTLE_R_N")
		)
		(pad "2" smd circle
			(at -0.40005 0 180)
			(size 0 0)
			(layers "B.Cu" "B.Mask" "B.Paste")
			(net "FM_SYS_THROTTLE_N")
		)
	)
	(footprint ""
		(layer "B.Cu")
		(at 177.965608 -126.833376 90)
		(property "Reference" "R254"
			(at 0 0 90)
			(layer "B.SilkS")
			(hide yes)
			(effects
				(font
					(size 1.27 1.27)
				)
				(justify mirror)
			)
		)
		(property "Value" ""
			(at 0 0 90)
			(layer "B.Fab")
			(effects
				(font
					(size 1.27 1.27)
				)
				(justify mirror)
			)
		)
		(duplicate_pad_numbers_are_jumpers no)
		(fp_line
			(start 0.7874 -0.4064)
			(end -0.7874 -0.4064)
			(stroke
				(width 0.1524)
				(type default)
			)
			(layer "B.SilkS")
		)
		(fp_line
			(start -0.7874 -0.4064)
			(end -0.7874 0.4064)
			(stroke
				(width 0.1524)
				(type default)
			)
			(layer "B.SilkS")
		)
		(fp_line
			(start 0.7874 0.4064)
			(end 0.7874 -0.4064)
			(stroke
				(width 0.1524)
				(type default)
			)
			(layer "B.SilkS")
		)
		(fp_line
			(start -0.7874 0.4064)
			(end 0.7874 0.4064)
			(stroke
				(width 0.1524)
				(type default)
			)
			(layer "B.SilkS")
		)
		(fp_line
			(start 0.67945 -0.305054)
			(end 0.12065 -0.305054)
			(stroke
				(width 0.1)
				(type default)
			)
			(layer "B.Fab")
		)
		(fp_line
			(start 0.12065 -0.305054)
			(end 0.12065 -0.2794)
			(stroke
				(width 0.1)
				(type default)
			)
			(layer "B.Fab")
		)
		(fp_line
			(start -0.12065 -0.3048)
			(end -0.67945 -0.3048)
			(stroke
				(width 0.1)
				(type default)
			)
			(layer "B.Fab")
		)
		(fp_line
			(start -0.67945 -0.3048)
			(end -0.67945 0.3048)
			(stroke
				(width 0.1)
				(type default)
			)
			(layer "B.Fab")
		)
		(fp_line
			(start 0.12065 -0.2794)
			(end -0.12065 -0.2794)
			(stroke
				(width 0.1)
				(type default)
			)
			(layer "B.Fab")
		)
		(fp_line
			(start -0.12065 -0.2794)
			(end -0.12065 -0.3048)
			(stroke
				(width 0.1)
				(type default)
			)
			(layer "B.Fab")
		)
		(fp_line
			(start 0.12065 0.2794)
			(end 0.12065 0.3048)
			(stroke
				(width 0.1)
				(type default)
			)
			(layer "B.Fab")
		)
		(fp_line
			(start -0.120396 0.2794)
			(end 0.12065 0.2794)
			(stroke
				(width 0.1)
				(type default)
			)
			(layer "B.Fab")
		)
		(fp_line
			(start 0.67945 0.3048)
			(end 0.67945 -0.305054)
			(stroke
				(width 0.1)
				(type default)
			)
			(layer "B.Fab")
		)
		(fp_line
			(start 0.12065 0.3048)
			(end 0.67945 0.3048)
			(stroke
				(width 0.1)
				(type default)
			)
			(layer "B.Fab")
		)
		(fp_line
			(start -0.120396 0.3048)
			(end -0.120396 0.2794)
			(stroke
				(width 0.1)
				(type default)
			)
			(layer "B.Fab")
		)
		(fp_line
			(start -0.67945 0.3048)
			(end -0.120396 0.3048)
			(stroke
				(width 0.1)
				(type default)
			)
			(layer "B.Fab")
		)
		(pad "1" smd circle
			(at 0.40005 0 270)
			(size 0 0)
			(layers "B.Cu" "B.Mask" "B.Paste")
			(net "RST_CPU0_PERST0_N")
		)
		(pad "2" smd circle
			(at -0.40005 0 270)
			(size 0 0)
			(layers "B.Cu" "B.Mask" "B.Paste")
			(net "RST_CPU0_PERST0_R_N")
		)
	)
	(footprint ""
		(layer "B.Cu")
		(at 376.6185 -396.393162 -90)
		(property "Reference" "C1009"
			(at 0 0 90)
			(layer "B.SilkS")
			(hide yes)
			(effects
				(font
					(size 1.27 1.27)
				)
				(justify mirror)
			)
		)
		(property "Value" ""
			(at 0 0 90)
			(layer "B.Fab")
			(effects
				(font
					(size 1.27 1.27)
				)
				(justify mirror)
			)
		)
		(duplicate_pad_numbers_are_jumpers no)
		(fp_line
			(start -0.299974 0.150114)
			(end 0.299974 0.150114)
			(stroke
				(width 0.1)
				(type default)
			)
			(layer "B.Fab")
		)
		(fp_line
			(start 0.299974 0.150114)
			(end 0.299974 -0.150114)
			(stroke
				(width 0.1)
				(type default)
			)
			(layer "B.Fab")
		)
		(fp_line
			(start -0.299974 -0.150114)
			(end -0.299974 0.150114)
			(stroke
				(width 0.1)
				(type default)
			)
			(layer "B.Fab")
		)
		(fp_line
			(start 0.299974 -0.150114)
			(end -0.299974 -0.150114)
			(stroke
				(width 0.1)
				(type default)
			)
			(layer "B.Fab")
		)
		(pad "1" smd rect
			(at 0.2667 0 90)
			(size 0.3048 0.381)
			(layers "B.Cu" "B.Mask" "B.Paste")
			(net "P0V9_CPU0_RT_2D")
		)
		(pad "2" smd rect
			(at -0.2667 0 90)
			(size 0.3048 0.381)
			(layers "B.Cu" "B.Mask" "B.Paste")
			(net "GND")
		)
	)
	(footprint ""
		(layer "B.Cu")
		(at 102.389432 -391.81405 180)
		(property "Reference" "C328"
			(at 0 0 0)
			(layer "B.SilkS")
			(hide yes)
			(effects
				(font
					(size 1.27 1.27)
				)
				(justify mirror)
			)
		)
		(property "Value" ""
			(at 0 0 0)
			(layer "B.Fab")
			(effects
				(font
					(size 1.27 1.27)
				)
				(justify mirror)
			)
		)
		(duplicate_pad_numbers_are_jumpers no)
		(fp_line
			(start 1.524 0.762)
			(end 1.524 -0.762)
			(stroke
				(width 0.1524)
				(type default)
			)
			(layer "B.SilkS")
		)
		(fp_line
			(start 1.524 -0.762)
			(end -1.524 -0.762)
			(stroke
				(width 0.1524)
				(type default)
			)
			(layer "B.SilkS")
		)
		(fp_line
			(start -1.524 0.762)
			(end 1.524 0.762)
			(stroke
				(width 0.1524)
				(type default)
			)
			(layer "B.SilkS")
		)
		(fp_line
			(start -1.524 -0.762)
			(end -1.524 0.762)
			(stroke
				(width 0.1524)
				(type default)
			)
			(layer "B.SilkS")
		)
		(fp_line
			(start 1.1049 0.724916)
			(end -1.1049 0.724916)
			(stroke
				(width 0.1)
				(type default)
			)
			(layer "B.Fab")
		)
		(fp_line
			(start 1.1049 -0.724916)
			(end 1.1049 0.724916)
			(stroke
				(width 0.1)
				(type default)
			)
			(layer "B.Fab")
		)
		(fp_line
			(start -1.1049 0.724916)
			(end -1.1049 -0.724916)
			(stroke
				(width 0.1)
				(type default)
			)
			(layer "B.Fab")
		)
		(fp_line
			(start -1.1049 -0.724916)
			(end 1.1049 -0.724916)
			(stroke
				(width 0.1)
				(type default)
			)
			(layer "B.Fab")
		)
		(pad "1" smd rect
			(at 0.889 0 180)
			(size 1.016 1.27)
			(layers "B.Cu" "B.Mask" "B.Paste")
			(net "P0V9_CPU1_RT1_2A")
		)
		(pad "2" smd rect
			(at -0.889 0 180)
			(size 1.016 1.27)
			(layers "B.Cu" "B.Mask" "B.Paste")
			(net "GND")
		)
	)
	(footprint ""
		(layer "B.Cu")
		(at 238.633 -337.312 180)
		(property "Reference" "R805"
			(at 0 0 0)
			(layer "B.SilkS")
			(hide yes)
			(effects
				(font
					(size 1.27 1.27)
				)
				(justify mirror)
			)
		)
		(property "Value" ""
			(at 0 0 0)
			(layer "B.Fab")
			(effects
				(font
					(size 1.27 1.27)
				)
				(justify mirror)
			)
		)
		(duplicate_pad_numbers_are_jumpers no)
		(fp_line
			(start 0.32512 0.175006)
			(end 0.32512 -0.175006)
			(stroke
				(width 0.1)
				(type default)
			)
			(layer "B.Fab")
		)
		(fp_line
			(start 0.32512 -0.175006)
			(end -0.32512 -0.175006)
			(stroke
				(width 0.1)
				(type default)
			)
			(layer "B.Fab")
		)
		(fp_line
			(start -0.32512 0.175006)
			(end 0.32512 0.175006)
			(stroke
				(width 0.1)
				(type default)
			)
			(layer "B.Fab")
		)
		(fp_line
			(start -0.32512 -0.175006)
			(end -0.32512 0.175006)
			(stroke
				(width 0.1)
				(type default)
			)
			(layer "B.Fab")
		)
		(pad "1" smd rect
			(at 0.2667 0)
			(size 0.3048 0.381)
			(layers "B.Cu" "B.Mask" "B.Paste")
			(net "SMB_RT_CPU1_P1_ROM_MUX_2D_SCL")
		)
		(pad "2" smd rect
			(at -0.2667 0 180)
			(size 0.3048 0.381)
			(layers "B.Cu" "B.Mask" "B.Paste")
			(net "SMB_RT_CPU1_P1_ROM_MUX_2D_R_SCL")
		)
	)
	(footprint ""
		(layer "B.Cu")
		(at 74.947272 -390.587484)
		(property "Reference" "C320"
			(at 0 0 0)
			(layer "B.SilkS")
			(hide yes)
			(effects
				(font
					(size 1.27 1.27)
				)
				(justify mirror)
			)
		)
		(property "Value" ""
			(at 0 0 0)
			(layer "B.Fab")
			(effects
				(font
					(size 1.27 1.27)
				)
				(justify mirror)
			)
		)
		(duplicate_pad_numbers_are_jumpers no)
		(fp_line
			(start -1.524 -0.762)
			(end -1.524 0.762)
			(stroke
				(width 0.1524)
				(type default)
			)
			(layer "B.SilkS")
		)
		(fp_line
			(start -1.524 0.762)
			(end 1.524 0.762)
			(stroke
				(width 0.1524)
				(type default)
			)
			(layer "B.SilkS")
		)
		(fp_line
			(start 1.524 -0.762)
			(end -1.524 -0.762)
			(stroke
				(width 0.1524)
				(type default)
			)
			(layer "B.SilkS")
		)
		(fp_line
			(start 1.524 0.762)
			(end 1.524 -0.762)
			(stroke
				(width 0.1524)
				(type default)
			)
			(layer "B.SilkS")
		)
		(fp_line
			(start -1.1049 -0.724916)
			(end 1.1049 -0.724916)
			(stroke
				(width 0.1)
				(type default)
			)
			(layer "B.Fab")
		)
		(fp_line
			(start -1.1049 0.724916)
			(end -1.1049 -0.724916)
			(stroke
				(width 0.1)
				(type default)
			)
			(layer "B.Fab")
		)
		(fp_line
			(start 1.1049 -0.724916)
			(end 1.1049 0.724916)
			(stroke
				(width 0.1)
				(type default)
			)
			(layer "B.Fab")
		)
		(fp_line
			(start 1.1049 0.724916)
			(end -1.1049 0.724916)
			(stroke
				(width 0.1)
				(type default)
			)
			(layer "B.Fab")
		)
		(pad "1" smd rect
			(at 0.889 0)
			(size 1.016 1.27)
			(layers "B.Cu" "B.Mask" "B.Paste")
			(net "P0V9_CPU1_RT1_2A")
		)
		(pad "2" smd rect
			(at -0.889 0)
			(size 1.016 1.27)
			(layers "B.Cu" "B.Mask" "B.Paste")
			(net "GND")
		)
	)
	(footprint ""
		(layer "B.Cu")
		(at 359.994454 -267.52931 -90)
		(property "Reference" "C2244"
			(at 0 0 90)
			(layer "B.SilkS")
			(hide yes)
			(effects
				(font
					(size 1.27 1.27)
				)
				(justify mirror)
			)
		)
		(property "Value" ""
			(at 0 0 90)
			(layer "B.Fab")
			(effects
				(font
					(size 1.27 1.27)
				)
				(justify mirror)
			)
		)
		(duplicate_pad_numbers_are_jumpers no)
		(fp_line
			(start -0.7874 0.4064)
			(end 0.7874 0.4064)
			(stroke
				(width 0.1524)
				(type default)
			)
			(layer "B.SilkS")
		)
		(fp_line
			(start 0.7874 0.4064)
			(end 0.7874 -0.4064)
			(stroke
				(width 0.1524)
				(type default)
			)
			(layer "B.SilkS")
		)
		(fp_line
			(start -0.7874 -0.4064)
			(end -0.7874 0.4064)
			(stroke
				(width 0.1524)
				(type default)
			)
			(layer "B.SilkS")
		)
		(fp_line
			(start 0.7874 -0.4064)
			(end -0.7874 -0.4064)
			(stroke
				(width 0.1524)
				(type default)
			)
			(layer "B.SilkS")
		)
		(fp_line
			(start -0.67945 0.3048)
			(end -0.120396 0.3048)
			(stroke
				(width 0.1)
				(type default)
			)
			(layer "B.Fab")
		)
		(fp_line
			(start -0.120396 0.3048)
			(end -0.120396 0.2794)
			(stroke
				(width 0.1)
				(type default)
			)
			(layer "B.Fab")
		)
		(fp_line
			(start 0.12065 0.3048)
			(end 0.67945 0.3048)
			(stroke
				(width 0.1)
				(type default)
			)
			(layer "B.Fab")
		)
		(fp_line
			(start 0.67945 0.3048)
			(end 0.67945 -0.305054)
			(stroke
				(width 0.1)
				(type default)
			)
			(layer "B.Fab")
		)
		(fp_line
			(start -0.120396 0.2794)
			(end 0.12065 0.2794)
			(stroke
				(width 0.1)
				(type default)
			)
			(layer "B.Fab")
		)
		(fp_line
			(start 0.12065 0.2794)
			(end 0.12065 0.3048)
			(stroke
				(width 0.1)
				(type default)
			)
			(layer "B.Fab")
		)
		(fp_line
			(start -0.12065 -0.2794)
			(end -0.12065 -0.3048)
			(stroke
				(width 0.1)
				(type default)
			)
			(layer "B.Fab")
		)
		(fp_line
			(start 0.12065 -0.2794)
			(end -0.12065 -0.2794)
			(stroke
				(width 0.1)
				(type default)
			)
			(layer "B.Fab")
		)
		(fp_line
			(start -0.67945 -0.3048)
			(end -0.67945 0.3048)
			(stroke
				(width 0.1)
				(type default)
			)
			(layer "B.Fab")
		)
		(fp_line
			(start -0.12065 -0.3048)
			(end -0.67945 -0.3048)
			(stroke
				(width 0.1)
				(type default)
			)
			(layer "B.Fab")
		)
		(fp_line
			(start 0.12065 -0.305054)
			(end 0.12065 -0.2794)
			(stroke
				(width 0.1)
				(type default)
			)
			(layer "B.Fab")
		)
		(fp_line
			(start 0.67945 -0.305054)
			(end 0.12065 -0.305054)
			(stroke
				(width 0.1)
				(type default)
			)
			(layer "B.Fab")
		)
		(pad "1" smd circle
			(at 0.40005 0 90)
			(size 0 0)
			(layers "B.Cu" "B.Mask" "B.Paste")
			(net "PVDDCR_CPU1_P0")
		)
		(pad "2" smd circle
			(at -0.40005 0 90)
			(size 0 0)
			(layers "B.Cu" "B.Mask" "B.Paste")
			(net "GND")
		)
	)
	(footprint ""
		(layer "B.Cu")
		(at 186.711844 -117.442996 90)
		(property "Reference" "C1133"
			(at 0 0 90)
			(layer "B.SilkS")
			(hide yes)
			(effects
				(font
					(size 1.27 1.27)
				)
				(justify mirror)
			)
		)
		(property "Value" ""
			(at 0 0 90)
			(layer "B.Fab")
			(effects
				(font
					(size 1.27 1.27)
				)
				(justify mirror)
			)
		)
		(duplicate_pad_numbers_are_jumpers no)
		(fp_line
			(start 0.69215 -0.2921)
			(end -0.69215 -0.2921)
			(stroke
				(width 0.1524)
				(type default)
			)
			(layer "B.SilkS")
		)
		(fp_line
			(start -0.69215 -0.2921)
			(end -0.69215 0.2921)
			(stroke
				(width 0.1524)
				(type default)
			)
			(layer "B.SilkS")
		)
		(fp_line
			(start 0.69215 0.2921)
			(end 0.69215 -0.2921)
			(stroke
				(width 0.1524)
				(type default)
			)
			(layer "B.SilkS")
		)
		(fp_line
			(start -0.69215 0.2921)
			(end 0.69215 0.2921)
			(stroke
				(width 0.1524)
				(type default)
			)
			(layer "B.SilkS")
		)
		(fp_line
			(start 0.51435 -0.2794)
			(end -0.51435 -0.2794)
			(stroke
				(width 0.1)
				(type default)
			)
			(layer "B.Fab")
		)
		(fp_line
			(start -0.51435 -0.2794)
			(end -0.51435 0.2794)
			(stroke
				(width 0.1)
				(type default)
			)
			(layer "B.Fab")
		)
		(fp_line
			(start 0.51435 0.2794)
			(end 0.51435 -0.2794)
			(stroke
				(width 0.1)
				(type default)
			)
			(layer "B.Fab")
		)
		(fp_line
			(start -0.51435 0.2794)
			(end 0.51435 0.2794)
			(stroke
				(width 0.1)
				(type default)
			)
			(layer "B.Fab")
		)
		(pad "1" smd circle
			(at 0.40005 0 270)
			(size 0 0)
			(layers "B.Cu" "B.Mask" "B.Paste")
			(net "P1V8_AUX")
		)
		(pad "2" smd circle
			(at -0.40005 0 270)
			(size 0 0)
			(layers "B.Cu" "B.Mask" "B.Paste")
			(net "GND")
		)
		(zone
			(layer "B.Cu")
			(hatch none 0.5)
			(connect_pads
				(clearance 0)
			)
			(min_thickness 0.25)
			(keepout
				(tracks not_allowed)
				(vias allowed)
				(pads allowed)
				(copperpour not_allowed)
				(footprints allowed)
			)
			(placement
				(enabled no)
				(sheetname "")
			)
			(fill
				(thermal_gap 0.5)
				(thermal_bridge_width 0.5)
				(island_removal_mode 0)
			)
			(polygon
				(pts
					(xy 186.565794 -117.342666) (xy 186.565794 -117.542056) (xy 186.62396 -117.633496) (xy 186.799474 -117.633496)
					(xy 186.85764 -117.542056) (xy 186.85764 -117.342666) (xy 186.799474 -117.252496) (xy 186.624214 -117.252496)
				)
			)
		)
	)
	(footprint ""
		(layer "B.Cu")
		(at 228.494082 -322.17868 180)
		(property "Reference" "C1093"
			(at 0 0 0)
			(layer "B.SilkS")
			(hide yes)
			(effects
				(font
					(size 1.27 1.27)
				)
				(justify mirror)
			)
		)
		(property "Value" ""
			(at 0 0 0)
			(layer "B.Fab")
			(effects
				(font
					(size 1.27 1.27)
				)
				(justify mirror)
			)
		)
		(duplicate_pad_numbers_are_jumpers no)
		(fp_line
			(start 0.7874 0.4064)
			(end 0.7874 -0.4064)
			(stroke
				(width 0.1524)
				(type default)
			)
			(layer "B.SilkS")
		)
		(fp_line
			(start 0.7874 -0.4064)
			(end -0.7874 -0.4064)
			(stroke
				(width 0.1524)
				(type default)
			)
			(layer "B.SilkS")
		)
		(fp_line
			(start -0.7874 0.4064)
			(end 0.7874 0.4064)
			(stroke
				(width 0.1524)
				(type default)
			)
			(layer "B.SilkS")
		)
		(fp_line
			(start -0.7874 -0.4064)
			(end -0.7874 0.4064)
			(stroke
				(width 0.1524)
				(type default)
			)
			(layer "B.SilkS")
		)
		(fp_line
			(start 0.67945 0.3048)
			(end 0.67945 -0.305054)
			(stroke
				(width 0.1)
				(type default)
			)
			(layer "B.Fab")
		)
		(fp_line
			(start 0.67945 -0.305054)
			(end 0.12065 -0.305054)
			(stroke
				(width 0.1)
				(type default)
			)
			(layer "B.Fab")
		)
		(fp_line
			(start 0.12065 0.3048)
			(end 0.67945 0.3048)
			(stroke
				(width 0.1)
				(type default)
			)
			(layer "B.Fab")
		)
		(fp_line
			(start 0.12065 0.2794)
			(end 0.12065 0.3048)
			(stroke
				(width 0.1)
				(type default)
			)
			(layer "B.Fab")
		)
		(fp_line
			(start 0.12065 -0.2794)
			(end -0.12065 -0.2794)
			(stroke
				(width 0.1)
				(type default)
			)
			(layer "B.Fab")
		)
		(fp_line
			(start 0.12065 -0.305054)
			(end 0.12065 -0.2794)
			(stroke
				(width 0.1)
				(type default)
			)
			(layer "B.Fab")
		)
		(fp_line
			(start -0.120396 0.3048)
			(end -0.120396 0.2794)
			(stroke
				(width 0.1)
				(type default)
			)
			(layer "B.Fab")
		)
		(fp_line
			(start -0.120396 0.2794)
			(end 0.12065 0.2794)
			(stroke
				(width 0.1)
				(type default)
			)
			(layer "B.Fab")
		)
		(fp_line
			(start -0.12065 -0.2794)
			(end -0.12065 -0.3048)
			(stroke
				(width 0.1)
				(type default)
			)
			(layer "B.Fab")
		)
		(fp_line
			(start -0.12065 -0.3048)
			(end -0.67945 -0.3048)
			(stroke
				(width 0.1)
				(type default)
			)
			(layer "B.Fab")
		)
		(fp_line
			(start -0.67945 0.3048)
			(end -0.120396 0.3048)
			(stroke
				(width 0.1)
				(type default)
			)
			(layer "B.Fab")
		)
		(fp_line
			(start -0.67945 -0.3048)
			(end -0.67945 0.3048)
			(stroke
				(width 0.1)
				(type default)
			)
			(layer "B.Fab")
		)
		(pad "1" smd circle
			(at 0.40005 0)
			(size 0 0)
			(layers "B.Cu" "B.Mask" "B.Paste")
			(net "P5V_AUX_ADC_TIC")
		)
		(pad "2" smd circle
			(at -0.40005 0)
			(size 0 0)
			(layers "B.Cu" "B.Mask" "B.Paste")
			(net "GND")
		)
	)
	(footprint ""
		(layer "B.Cu")
		(at 107.383834 -272.284952 180)
		(property "Reference" "C2354"
			(at 0 0 0)
			(layer "B.SilkS")
			(hide yes)
			(effects
				(font
					(size 1.27 1.27)
				)
				(justify mirror)
			)
		)
		(property "Value" ""
			(at 0 0 0)
			(layer "B.Fab")
			(effects
				(font
					(size 1.27 1.27)
				)
				(justify mirror)
			)
		)
		(duplicate_pad_numbers_are_jumpers no)
		(fp_line
			(start 0.7874 0.4064)
			(end 0.7874 -0.4064)
			(stroke
				(width 0.1524)
				(type default)
			)
			(layer "B.SilkS")
		)
		(fp_line
			(start 0.7874 -0.4064)
			(end -0.7874 -0.4064)
			(stroke
				(width 0.1524)
				(type default)
			)
			(layer "B.SilkS")
		)
		(fp_line
			(start -0.7874 0.4064)
			(end 0.7874 0.4064)
			(stroke
				(width 0.1524)
				(type default)
			)
			(layer "B.SilkS")
		)
		(fp_line
			(start -0.7874 -0.4064)
			(end -0.7874 0.4064)
			(stroke
				(width 0.1524)
				(type default)
			)
			(layer "B.SilkS")
		)
		(fp_line
			(start 0.67945 0.3048)
			(end 0.67945 -0.305054)
			(stroke
				(width 0.1)
				(type default)
			)
			(layer "B.Fab")
		)
		(fp_line
			(start 0.67945 -0.305054)
			(end 0.12065 -0.305054)
			(stroke
				(width 0.1)
				(type default)
			)
			(layer "B.Fab")
		)
		(fp_line
			(start 0.12065 0.3048)
			(end 0.67945 0.3048)
			(stroke
				(width 0.1)
				(type default)
			)
			(layer "B.Fab")
		)
		(fp_line
			(start 0.12065 0.2794)
			(end 0.12065 0.3048)
			(stroke
				(width 0.1)
				(type default)
			)
			(layer "B.Fab")
		)
		(fp_line
			(start 0.12065 -0.2794)
			(end -0.12065 -0.2794)
			(stroke
				(width 0.1)
				(type default)
			)
			(layer "B.Fab")
		)
		(fp_line
			(start 0.12065 -0.305054)
			(end 0.12065 -0.2794)
			(stroke
				(width 0.1)
				(type default)
			)
			(layer "B.Fab")
		)
		(fp_line
			(start -0.120396 0.3048)
			(end -0.120396 0.2794)
			(stroke
				(width 0.1)
				(type default)
			)
			(layer "B.Fab")
		)
		(fp_line
			(start -0.120396 0.2794)
			(end 0.12065 0.2794)
			(stroke
				(width 0.1)
				(type default)
			)
			(layer "B.Fab")
		)
		(fp_line
			(start -0.12065 -0.2794)
			(end -0.12065 -0.3048)
			(stroke
				(width 0.1)
				(type default)
			)
			(layer "B.Fab")
		)
		(fp_line
			(start -0.12065 -0.3048)
			(end -0.67945 -0.3048)
			(stroke
				(width 0.1)
				(type default)
			)
			(layer "B.Fab")
		)
		(fp_line
			(start -0.67945 0.3048)
			(end -0.120396 0.3048)
			(stroke
				(width 0.1)
				(type default)
			)
			(layer "B.Fab")
		)
		(fp_line
			(start -0.67945 -0.3048)
			(end -0.67945 0.3048)
			(stroke
				(width 0.1)
				(type default)
			)
			(layer "B.Fab")
		)
		(pad "1" smd circle
			(at 0.40005 0)
			(size 0 0)
			(layers "B.Cu" "B.Mask" "B.Paste")
			(net "PVDDCR_CPU1_P1")
		)
		(pad "2" smd circle
			(at -0.40005 0)
			(size 0 0)
			(layers "B.Cu" "B.Mask" "B.Paste")
			(net "GND")
		)
	)
	(footprint ""
		(layer "B.Cu")
		(at 114.73434 -61.76391 -90)
		(property "Reference" "R6227"
			(at 0 0 90)
			(layer "B.SilkS")
			(hide yes)
			(effects
				(font
					(size 1.27 1.27)
				)
				(justify mirror)
			)
		)
		(property "Value" ""
			(at 0 0 90)
			(layer "B.Fab")
			(effects
				(font
					(size 1.27 1.27)
				)
				(justify mirror)
			)
		)
		(duplicate_pad_numbers_are_jumpers no)
		(fp_line
			(start -0.7874 0.4064)
			(end 0.7874 0.4064)
			(stroke
				(width 0.1524)
				(type default)
			)
			(layer "B.SilkS")
		)
		(fp_line
			(start 0.7874 0.4064)
			(end 0.7874 -0.4064)
			(stroke
				(width 0.1524)
				(type default)
			)
			(layer "B.SilkS")
		)
		(fp_line
			(start -0.7874 -0.4064)
			(end -0.7874 0.4064)
			(stroke
				(width 0.1524)
				(type default)
			)
			(layer "B.SilkS")
		)
		(fp_line
			(start 0.7874 -0.4064)
			(end -0.7874 -0.4064)
			(stroke
				(width 0.1524)
				(type default)
			)
			(layer "B.SilkS")
		)
		(fp_line
			(start -0.67945 0.3048)
			(end -0.120396 0.3048)
			(stroke
				(width 0.1)
				(type default)
			)
			(layer "B.Fab")
		)
		(fp_line
			(start -0.120396 0.3048)
			(end -0.120396 0.2794)
			(stroke
				(width 0.1)
				(type default)
			)
			(layer "B.Fab")
		)
		(fp_line
			(start 0.12065 0.3048)
			(end 0.67945 0.3048)
			(stroke
				(width 0.1)
				(type default)
			)
			(layer "B.Fab")
		)
		(fp_line
			(start 0.67945 0.3048)
			(end 0.67945 -0.305054)
			(stroke
				(width 0.1)
				(type default)
			)
			(layer "B.Fab")
		)
		(fp_line
			(start -0.120396 0.2794)
			(end 0.12065 0.2794)
			(stroke
				(width 0.1)
				(type default)
			)
			(layer "B.Fab")
		)
		(fp_line
			(start 0.12065 0.2794)
			(end 0.12065 0.3048)
			(stroke
				(width 0.1)
				(type default)
			)
			(layer "B.Fab")
		)
		(fp_line
			(start -0.12065 -0.2794)
			(end -0.12065 -0.3048)
			(stroke
				(width 0.1)
				(type default)
			)
			(layer "B.Fab")
		)
		(fp_line
			(start 0.12065 -0.2794)
			(end -0.12065 -0.2794)
			(stroke
				(width 0.1)
				(type default)
			)
			(layer "B.Fab")
		)
		(fp_line
			(start -0.67945 -0.3048)
			(end -0.67945 0.3048)
			(stroke
				(width 0.1)
				(type default)
			)
			(layer "B.Fab")
		)
		(fp_line
			(start -0.12065 -0.3048)
			(end -0.67945 -0.3048)
			(stroke
				(width 0.1)
				(type default)
			)
			(layer "B.Fab")
		)
		(fp_line
			(start 0.12065 -0.305054)
			(end 0.12065 -0.2794)
			(stroke
				(width 0.1)
				(type default)
			)
			(layer "B.Fab")
		)
		(fp_line
			(start 0.67945 -0.305054)
			(end 0.12065 -0.305054)
			(stroke
				(width 0.1)
				(type default)
			)
			(layer "B.Fab")
		)
		(pad "1" smd circle
			(at 0.40005 0 90)
			(size 0 0)
			(layers "B.Cu" "B.Mask" "B.Paste")
			(net "P3V3_AUX")
		)
		(pad "2" smd circle
			(at -0.40005 0 90)
			(size 0 0)
			(layers "B.Cu" "B.Mask" "B.Paste")
			(net "SMB_USB_CPU0_HUB1_SDA_R2")
		)
	)
	(footprint ""
		(layer "B.Cu")
		(at 197.523608 -103.465376)
		(property "Reference" "R233"
			(at 0 0 0)
			(layer "B.SilkS")
			(hide yes)
			(effects
				(font
					(size 1.27 1.27)
				)
				(justify mirror)
			)
		)
		(property "Value" ""
			(at 0 0 0)
			(layer "B.Fab")
			(effects
				(font
					(size 1.27 1.27)
				)
				(justify mirror)
			)
		)
		(duplicate_pad_numbers_are_jumpers no)
		(fp_line
			(start -0.7874 -0.4064)
			(end -0.7874 0.4064)
			(stroke
				(width 0.1524)
				(type default)
			)
			(layer "B.SilkS")
		)
		(fp_line
			(start -0.7874 0.4064)
			(end 0.7874 0.4064)
			(stroke
				(width 0.1524)
				(type default)
			)
			(layer "B.SilkS")
		)
		(fp_line
			(start 0.7874 -0.4064)
			(end -0.7874 -0.4064)
			(stroke
				(width 0.1524)
				(type default)
			)
			(layer "B.SilkS")
		)
		(fp_line
			(start 0.7874 0.4064)
			(end 0.7874 -0.4064)
			(stroke
				(width 0.1524)
				(type default)
			)
			(layer "B.SilkS")
		)
		(fp_line
			(start -0.67945 -0.3048)
			(end -0.67945 0.3048)
			(stroke
				(width 0.1)
				(type default)
			)
			(layer "B.Fab")
		)
		(fp_line
			(start -0.67945 0.3048)
			(end -0.120396 0.3048)
			(stroke
				(width 0.1)
				(type default)
			)
			(layer "B.Fab")
		)
		(fp_line
			(start -0.12065 -0.3048)
			(end -0.67945 -0.3048)
			(stroke
				(width 0.1)
				(type default)
			)
			(layer "B.Fab")
		)
		(fp_line
			(start -0.12065 -0.2794)
			(end -0.12065 -0.3048)
			(stroke
				(width 0.1)
				(type default)
			)
			(layer "B.Fab")
		)
		(fp_line
			(start -0.120396 0.2794)
			(end 0.12065 0.2794)
			(stroke
				(width 0.1)
				(type default)
			)
			(layer "B.Fab")
		)
		(fp_line
			(start -0.120396 0.3048)
			(end -0.120396 0.2794)
			(stroke
				(width 0.1)
				(type default)
			)
			(layer "B.Fab")
		)
		(fp_line
			(start 0.12065 -0.305054)
			(end 0.12065 -0.2794)
			(stroke
				(width 0.1)
				(type default)
			)
			(layer "B.Fab")
		)
		(fp_line
			(start 0.12065 -0.2794)
			(end -0.12065 -0.2794)
			(stroke
				(width 0.1)
				(type default)
			)
			(layer "B.Fab")
		)
		(fp_line
			(start 0.12065 0.2794)
			(end 0.12065 0.3048)
			(stroke
				(width 0.1)
				(type default)
			)
			(layer "B.Fab")
		)
		(fp_line
			(start 0.12065 0.3048)
			(end 0.67945 0.3048)
			(stroke
				(width 0.1)
				(type default)
			)
			(layer "B.Fab")
		)
		(fp_line
			(start 0.67945 -0.305054)
			(end 0.12065 -0.305054)
			(stroke
				(width 0.1)
				(type default)
			)
			(layer "B.Fab")
		)
		(fp_line
			(start 0.67945 0.3048)
			(end 0.67945 -0.305054)
			(stroke
				(width 0.1)
				(type default)
			)
			(layer "B.Fab")
		)
		(pad "1" smd circle
			(at 0.40005 0 180)
			(size 0 0)
			(layers "B.Cu" "B.Mask" "B.Paste")
			(net "PWRGD_PVDDCR_CPU1_P0")
		)
		(pad "2" smd circle
			(at -0.40005 0 180)
			(size 0 0)
			(layers "B.Cu" "B.Mask" "B.Paste")
			(net "FM_PWRGD_PVDDCR_CPU1_P0")
		)
	)
	(footprint ""
		(layer "B.Cu")
		(at 354.406454 -264.35431)
		(property "Reference" "C2602"
			(at 0 0 0)
			(layer "B.SilkS")
			(hide yes)
			(effects
				(font
					(size 1.27 1.27)
				)
				(justify mirror)
			)
		)
		(property "Value" ""
			(at 0 0 0)
			(layer "B.Fab")
			(effects
				(font
					(size 1.27 1.27)
				)
				(justify mirror)
			)
		)
		(duplicate_pad_numbers_are_jumpers no)
		(fp_line
			(start -0.7874 -0.4064)
			(end -0.7874 0.4064)
			(stroke
				(width 0.1524)
				(type default)
			)
			(layer "B.SilkS")
		)
		(fp_line
			(start -0.7874 0.4064)
			(end 0.7874 0.4064)
			(stroke
				(width 0.1524)
				(type default)
			)
			(layer "B.SilkS")
		)
		(fp_line
			(start 0.7874 -0.4064)
			(end -0.7874 -0.4064)
			(stroke
				(width 0.1524)
				(type default)
			)
			(layer "B.SilkS")
		)
		(fp_line
			(start 0.7874 0.4064)
			(end 0.7874 -0.4064)
			(stroke
				(width 0.1524)
				(type default)
			)
			(layer "B.SilkS")
		)
		(fp_line
			(start -0.67945 -0.3048)
			(end -0.67945 0.3048)
			(stroke
				(width 0.1)
				(type default)
			)
			(layer "B.Fab")
		)
		(fp_line
			(start -0.67945 0.3048)
			(end -0.120396 0.3048)
			(stroke
				(width 0.1)
				(type default)
			)
			(layer "B.Fab")
		)
		(fp_line
			(start -0.12065 -0.3048)
			(end -0.67945 -0.3048)
			(stroke
				(width 0.1)
				(type default)
			)
			(layer "B.Fab")
		)
		(fp_line
			(start -0.12065 -0.2794)
			(end -0.12065 -0.3048)
			(stroke
				(width 0.1)
				(type default)
			)
			(layer "B.Fab")
		)
		(fp_line
			(start -0.120396 0.2794)
			(end 0.12065 0.2794)
			(stroke
				(width 0.1)
				(type default)
			)
			(layer "B.Fab")
		)
		(fp_line
			(start -0.120396 0.3048)
			(end -0.120396 0.2794)
			(stroke
				(width 0.1)
				(type default)
			)
			(layer "B.Fab")
		)
		(fp_line
			(start 0.12065 -0.305054)
			(end 0.12065 -0.2794)
			(stroke
				(width 0.1)
				(type default)
			)
			(layer "B.Fab")
		)
		(fp_line
			(start 0.12065 -0.2794)
			(end -0.12065 -0.2794)
			(stroke
				(width 0.1)
				(type default)
			)
			(layer "B.Fab")
		)
		(fp_line
			(start 0.12065 0.2794)
			(end 0.12065 0.3048)
			(stroke
				(width 0.1)
				(type default)
			)
			(layer "B.Fab")
		)
		(fp_line
			(start 0.12065 0.3048)
			(end 0.67945 0.3048)
			(stroke
				(width 0.1)
				(type default)
			)
			(layer "B.Fab")
		)
		(fp_line
			(start 0.67945 -0.305054)
			(end 0.12065 -0.305054)
			(stroke
				(width 0.1)
				(type default)
			)
			(layer "B.Fab")
		)
		(fp_line
			(start 0.67945 0.3048)
			(end 0.67945 -0.305054)
			(stroke
				(width 0.1)
				(type default)
			)
			(layer "B.Fab")
		)
		(pad "1" smd circle
			(at 0.40005 0 180)
			(size 0 0)
			(layers "B.Cu" "B.Mask" "B.Paste")
			(net "PVDD11_S3_P0")
		)
		(pad "2" smd circle
			(at -0.40005 0 180)
			(size 0 0)
			(layers "B.Cu" "B.Mask" "B.Paste")
			(net "GND")
		)
	)
	(footprint ""
		(layer "B.Cu")
		(at 363.931454 -249.36831)
		(property "Reference" "C246"
			(at 0 0 0)
			(layer "B.SilkS")
			(hide yes)
			(effects
				(font
					(size 1.27 1.27)
				)
				(justify mirror)
			)
		)
		(property "Value" ""
			(at 0 0 0)
			(layer "B.Fab")
			(effects
				(font
					(size 1.27 1.27)
				)
				(justify mirror)
			)
		)
		(duplicate_pad_numbers_are_jumpers no)
		(fp_line
			(start -0.7874 -0.4064)
			(end -0.7874 0.4064)
			(stroke
				(width 0.1524)
				(type default)
			)
			(layer "B.SilkS")
		)
		(fp_line
			(start -0.7874 0.4064)
			(end 0.7874 0.4064)
			(stroke
				(width 0.1524)
				(type default)
			)
			(layer "B.SilkS")
		)
		(fp_line
			(start 0.7874 -0.4064)
			(end -0.7874 -0.4064)
			(stroke
				(width 0.1524)
				(type default)
			)
			(layer "B.SilkS")
		)
		(fp_line
			(start 0.7874 0.4064)
			(end 0.7874 -0.4064)
			(stroke
				(width 0.1524)
				(type default)
			)
			(layer "B.SilkS")
		)
		(fp_line
			(start -0.67945 -0.3048)
			(end -0.67945 0.3048)
			(stroke
				(width 0.1)
				(type default)
			)
			(layer "B.Fab")
		)
		(fp_line
			(start -0.67945 0.3048)
			(end -0.120396 0.3048)
			(stroke
				(width 0.1)
				(type default)
			)
			(layer "B.Fab")
		)
		(fp_line
			(start -0.12065 -0.3048)
			(end -0.67945 -0.3048)
			(stroke
				(width 0.1)
				(type default)
			)
			(layer "B.Fab")
		)
		(fp_line
			(start -0.12065 -0.2794)
			(end -0.12065 -0.3048)
			(stroke
				(width 0.1)
				(type default)
			)
			(layer "B.Fab")
		)
		(fp_line
			(start -0.120396 0.2794)
			(end 0.12065 0.2794)
			(stroke
				(width 0.1)
				(type default)
			)
			(layer "B.Fab")
		)
		(fp_line
			(start -0.120396 0.3048)
			(end -0.120396 0.2794)
			(stroke
				(width 0.1)
				(type default)
			)
			(layer "B.Fab")
		)
		(fp_line
			(start 0.12065 -0.305054)
			(end 0.12065 -0.2794)
			(stroke
				(width 0.1)
				(type default)
			)
			(layer "B.Fab")
		)
		(fp_line
			(start 0.12065 -0.2794)
			(end -0.12065 -0.2794)
			(stroke
				(width 0.1)
				(type default)
			)
			(layer "B.Fab")
		)
		(fp_line
			(start 0.12065 0.2794)
			(end 0.12065 0.3048)
			(stroke
				(width 0.1)
				(type default)
			)
			(layer "B.Fab")
		)
		(fp_line
			(start 0.12065 0.3048)
			(end 0.67945 0.3048)
			(stroke
				(width 0.1)
				(type default)
			)
			(layer "B.Fab")
		)
		(fp_line
			(start 0.67945 -0.305054)
			(end 0.12065 -0.305054)
			(stroke
				(width 0.1)
				(type default)
			)
			(layer "B.Fab")
		)
		(fp_line
			(start 0.67945 0.3048)
			(end 0.67945 -0.305054)
			(stroke
				(width 0.1)
				(type default)
			)
			(layer "B.Fab")
		)
		(pad "1" smd circle
			(at 0.40005 0 180)
			(size 0 0)
			(layers "B.Cu" "B.Mask" "B.Paste")
			(net "PVDDCR_CPU0_P0")
		)
		(pad "2" smd circle
			(at -0.40005 0 180)
			(size 0 0)
			(layers "B.Cu" "B.Mask" "B.Paste")
			(net "GND")
		)
	)
	(footprint ""
		(layer "B.Cu")
		(at 348.418912 -259.729986 180)
		(property "Reference" "C2631"
			(at 0 0 0)
			(layer "B.SilkS")
			(hide yes)
			(effects
				(font
					(size 1.27 1.27)
				)
				(justify mirror)
			)
		)
		(property "Value" ""
			(at 0 0 0)
			(layer "B.Fab")
			(effects
				(font
					(size 1.27 1.27)
				)
				(justify mirror)
			)
		)
		(duplicate_pad_numbers_are_jumpers no)
		(fp_line
			(start 0.7874 0.4064)
			(end 0.7874 -0.4064)
			(stroke
				(width 0.1524)
				(type default)
			)
			(layer "B.SilkS")
		)
		(fp_line
			(start 0.7874 -0.4064)
			(end -0.7874 -0.4064)
			(stroke
				(width 0.1524)
				(type default)
			)
			(layer "B.SilkS")
		)
		(fp_line
			(start -0.7874 0.4064)
			(end 0.7874 0.4064)
			(stroke
				(width 0.1524)
				(type default)
			)
			(layer "B.SilkS")
		)
		(fp_line
			(start -0.7874 -0.4064)
			(end -0.7874 0.4064)
			(stroke
				(width 0.1524)
				(type default)
			)
			(layer "B.SilkS")
		)
		(fp_line
			(start 0.67945 0.3048)
			(end 0.67945 -0.305054)
			(stroke
				(width 0.1)
				(type default)
			)
			(layer "B.Fab")
		)
		(fp_line
			(start 0.67945 -0.305054)
			(end 0.12065 -0.305054)
			(stroke
				(width 0.1)
				(type default)
			)
			(layer "B.Fab")
		)
		(fp_line
			(start 0.12065 0.3048)
			(end 0.67945 0.3048)
			(stroke
				(width 0.1)
				(type default)
			)
			(layer "B.Fab")
		)
		(fp_line
			(start 0.12065 0.2794)
			(end 0.12065 0.3048)
			(stroke
				(width 0.1)
				(type default)
			)
			(layer "B.Fab")
		)
		(fp_line
			(start 0.12065 -0.2794)
			(end -0.12065 -0.2794)
			(stroke
				(width 0.1)
				(type default)
			)
			(layer "B.Fab")
		)
		(fp_line
			(start 0.12065 -0.305054)
			(end 0.12065 -0.2794)
			(stroke
				(width 0.1)
				(type default)
			)
			(layer "B.Fab")
		)
		(fp_line
			(start -0.120396 0.3048)
			(end -0.120396 0.2794)
			(stroke
				(width 0.1)
				(type default)
			)
			(layer "B.Fab")
		)
		(fp_line
			(start -0.120396 0.2794)
			(end 0.12065 0.2794)
			(stroke
				(width 0.1)
				(type default)
			)
			(layer "B.Fab")
		)
		(fp_line
			(start -0.12065 -0.2794)
			(end -0.12065 -0.3048)
			(stroke
				(width 0.1)
				(type default)
			)
			(layer "B.Fab")
		)
		(fp_line
			(start -0.12065 -0.3048)
			(end -0.67945 -0.3048)
			(stroke
				(width 0.1)
				(type default)
			)
			(layer "B.Fab")
		)
		(fp_line
			(start -0.67945 0.3048)
			(end -0.120396 0.3048)
			(stroke
				(width 0.1)
				(type default)
			)
			(layer "B.Fab")
		)
		(fp_line
			(start -0.67945 -0.3048)
			(end -0.67945 0.3048)
			(stroke
				(width 0.1)
				(type default)
			)
			(layer "B.Fab")
		)
		(pad "1" smd circle
			(at 0.40005 0)
			(size 0 0)
			(layers "B.Cu" "B.Mask" "B.Paste")
			(net "PVDDIO_P0")
		)
		(pad "2" smd circle
			(at -0.40005 0)
			(size 0 0)
			(layers "B.Cu" "B.Mask" "B.Paste")
			(net "GND")
		)
	)
	(footprint ""
		(layer "B.Cu")
		(at 123.441206 -408.517344 90)
		(property "Reference" "C6729"
			(at 0 0 90)
			(layer "B.SilkS")
			(hide yes)
			(effects
				(font
					(size 1.27 1.27)
				)
				(justify mirror)
			)
		)
		(property "Value" ""
			(at 0 0 90)
			(layer "B.Fab")
			(effects
				(font
					(size 1.27 1.27)
				)
				(justify mirror)
			)
		)
		(duplicate_pad_numbers_are_jumpers no)
		(fp_line
			(start 0.299974 -0.150114)
			(end -0.299974 -0.150114)
			(stroke
				(width 0.1)
				(type default)
			)
			(layer "B.Fab")
		)
		(fp_line
			(start -0.299974 -0.150114)
			(end -0.299974 0.150114)
			(stroke
				(width 0.1)
				(type default)
			)
			(layer "B.Fab")
		)
		(fp_line
			(start 0.299974 0.150114)
			(end 0.299974 -0.150114)
			(stroke
				(width 0.1)
				(type default)
			)
			(layer "B.Fab")
		)
		(fp_line
			(start -0.299974 0.150114)
			(end 0.299974 0.150114)
			(stroke
				(width 0.1)
				(type default)
			)
			(layer "B.Fab")
		)
		(pad "1" smd rect
			(at 0.2667 0 270)
			(size 0.3048 0.381)
			(layers "B.Cu" "B.Mask" "B.Paste")
			(net "P5E_CPU1_P3_TX_BUF_C_DP<2>")
		)
		(pad "2" smd rect
			(at -0.2667 0 270)
			(size 0.3048 0.381)
			(layers "B.Cu" "B.Mask" "B.Paste")
			(net "P5E_CPU1_P3_TX_BUF_DP<2>")
		)
	)
	(footprint ""
		(layer "B.Cu")
		(at 372.937278 -140.456158)
		(property "Reference" "C468"
			(at 0 0 0)
			(layer "B.SilkS")
			(hide yes)
			(effects
				(font
					(size 1.27 1.27)
				)
				(justify mirror)
			)
		)
		(property "Value" ""
			(at 0 0 0)
			(layer "B.Fab")
			(effects
				(font
					(size 1.27 1.27)
				)
				(justify mirror)
			)
		)
		(duplicate_pad_numbers_are_jumpers no)
		(fp_line
			(start -0.7874 -0.4064)
			(end -0.7874 0.4064)
			(stroke
				(width 0.1524)
				(type default)
			)
			(layer "B.SilkS")
		)
		(fp_line
			(start -0.7874 0.4064)
			(end 0.7874 0.4064)
			(stroke
				(width 0.1524)
				(type default)
			)
			(layer "B.SilkS")
		)
		(fp_line
			(start 0.7874 -0.4064)
			(end -0.7874 -0.4064)
			(stroke
				(width 0.1524)
				(type default)
			)
			(layer "B.SilkS")
		)
		(fp_line
			(start 0.7874 0.4064)
			(end 0.7874 -0.4064)
			(stroke
				(width 0.1524)
				(type default)
			)
			(layer "B.SilkS")
		)
		(fp_line
			(start -0.67945 -0.3048)
			(end -0.67945 0.3048)
			(stroke
				(width 0.1)
				(type default)
			)
			(layer "B.Fab")
		)
		(fp_line
			(start -0.67945 0.3048)
			(end -0.120396 0.3048)
			(stroke
				(width 0.1)
				(type default)
			)
			(layer "B.Fab")
		)
		(fp_line
			(start -0.12065 -0.3048)
			(end -0.67945 -0.3048)
			(stroke
				(width 0.1)
				(type default)
			)
			(layer "B.Fab")
		)
		(fp_line
			(start -0.12065 -0.2794)
			(end -0.12065 -0.3048)
			(stroke
				(width 0.1)
				(type default)
			)
			(layer "B.Fab")
		)
		(fp_line
			(start -0.120396 0.2794)
			(end 0.12065 0.2794)
			(stroke
				(width 0.1)
				(type default)
			)
			(layer "B.Fab")
		)
		(fp_line
			(start -0.120396 0.3048)
			(end -0.120396 0.2794)
			(stroke
				(width 0.1)
				(type default)
			)
			(layer "B.Fab")
		)
		(fp_line
			(start 0.12065 -0.305054)
			(end 0.12065 -0.2794)
			(stroke
				(width 0.1)
				(type default)
			)
			(layer "B.Fab")
		)
		(fp_line
			(start 0.12065 -0.2794)
			(end -0.12065 -0.2794)
			(stroke
				(width 0.1)
				(type default)
			)
			(layer "B.Fab")
		)
		(fp_line
			(start 0.12065 0.2794)
			(end 0.12065 0.3048)
			(stroke
				(width 0.1)
				(type default)
			)
			(layer "B.Fab")
		)
		(fp_line
			(start 0.12065 0.3048)
			(end 0.67945 0.3048)
			(stroke
				(width 0.1)
				(type default)
			)
			(layer "B.Fab")
		)
		(fp_line
			(start 0.67945 -0.305054)
			(end 0.12065 -0.305054)
			(stroke
				(width 0.1)
				(type default)
			)
			(layer "B.Fab")
		)
		(fp_line
			(start 0.67945 0.3048)
			(end 0.67945 -0.305054)
			(stroke
				(width 0.1)
				(type default)
			)
			(layer "B.Fab")
		)
		(pad "1" smd circle
			(at 0.40005 0 180)
			(size 0 0)
			(layers "B.Cu" "B.Mask" "B.Paste")
			(net "PVDDCR_CPU0_P0_EN_R")
		)
		(pad "2" smd circle
			(at -0.40005 0 180)
			(size 0 0)
			(layers "B.Cu" "B.Mask" "B.Paste")
			(net "GND")
		)
	)
	(footprint ""
		(layer "B.Cu")
		(at 109.550454 -33.603438 180)
		(property "Reference" "C6095"
			(at 0 0 0)
			(layer "B.SilkS")
			(hide yes)
			(effects
				(font
					(size 1.27 1.27)
				)
				(justify mirror)
			)
		)
		(property "Value" ""
			(at 0 0 0)
			(layer "B.Fab")
			(effects
				(font
					(size 1.27 1.27)
				)
				(justify mirror)
			)
		)
		(duplicate_pad_numbers_are_jumpers no)
		(fp_line
			(start 0.7874 0.4064)
			(end 0.7874 -0.4064)
			(stroke
				(width 0.1524)
				(type default)
			)
			(layer "B.SilkS")
		)
		(fp_line
			(start 0.7874 -0.4064)
			(end -0.7874 -0.4064)
			(stroke
				(width 0.1524)
				(type default)
			)
			(layer "B.SilkS")
		)
		(fp_line
			(start -0.7874 0.4064)
			(end 0.7874 0.4064)
			(stroke
				(width 0.1524)
				(type default)
			)
			(layer "B.SilkS")
		)
		(fp_line
			(start -0.7874 -0.4064)
			(end -0.7874 0.4064)
			(stroke
				(width 0.1524)
				(type default)
			)
			(layer "B.SilkS")
		)
		(fp_line
			(start 0.67945 0.3048)
			(end 0.67945 -0.305054)
			(stroke
				(width 0.1)
				(type default)
			)
			(layer "B.Fab")
		)
		(fp_line
			(start 0.67945 -0.305054)
			(end 0.12065 -0.305054)
			(stroke
				(width 0.1)
				(type default)
			)
			(layer "B.Fab")
		)
		(fp_line
			(start 0.12065 0.3048)
			(end 0.67945 0.3048)
			(stroke
				(width 0.1)
				(type default)
			)
			(layer "B.Fab")
		)
		(fp_line
			(start 0.12065 0.2794)
			(end 0.12065 0.3048)
			(stroke
				(width 0.1)
				(type default)
			)
			(layer "B.Fab")
		)
		(fp_line
			(start 0.12065 -0.2794)
			(end -0.12065 -0.2794)
			(stroke
				(width 0.1)
				(type default)
			)
			(layer "B.Fab")
		)
		(fp_line
			(start 0.12065 -0.305054)
			(end 0.12065 -0.2794)
			(stroke
				(width 0.1)
				(type default)
			)
			(layer "B.Fab")
		)
		(fp_line
			(start -0.120396 0.3048)
			(end -0.120396 0.2794)
			(stroke
				(width 0.1)
				(type default)
			)
			(layer "B.Fab")
		)
		(fp_line
			(start -0.120396 0.2794)
			(end 0.12065 0.2794)
			(stroke
				(width 0.1)
				(type default)
			)
			(layer "B.Fab")
		)
		(fp_line
			(start -0.12065 -0.2794)
			(end -0.12065 -0.3048)
			(stroke
				(width 0.1)
				(type default)
			)
			(layer "B.Fab")
		)
		(fp_line
			(start -0.12065 -0.3048)
			(end -0.67945 -0.3048)
			(stroke
				(width 0.1)
				(type default)
			)
			(layer "B.Fab")
		)
		(fp_line
			(start -0.67945 0.3048)
			(end -0.120396 0.3048)
			(stroke
				(width 0.1)
				(type default)
			)
			(layer "B.Fab")
		)
		(fp_line
			(start -0.67945 -0.3048)
			(end -0.67945 0.3048)
			(stroke
				(width 0.1)
				(type default)
			)
			(layer "B.Fab")
		)
		(pad "1" smd circle
			(at 0.40005 0)
			(size 0 0)
			(layers "B.Cu" "B.Mask" "B.Paste")
			(net "P3V3_AUX_CPU0_USB2_AVDD33")
		)
		(pad "2" smd circle
			(at -0.40005 0)
			(size 0 0)
			(layers "B.Cu" "B.Mask" "B.Paste")
			(net "GND")
		)
	)
	(footprint ""
		(layer "B.Cu")
		(at 292.608 -426.085 -90)
		(property "Reference" "R2668"
			(at 0 0 90)
			(layer "B.SilkS")
			(hide yes)
			(effects
				(font
					(size 1.27 1.27)
				)
				(justify mirror)
			)
		)
		(property "Value" ""
			(at 0 0 90)
			(layer "B.Fab")
			(effects
				(font
					(size 1.27 1.27)
				)
				(justify mirror)
			)
		)
		(duplicate_pad_numbers_are_jumpers no)
		(fp_line
			(start -0.7874 0.4064)
			(end 0.7874 0.4064)
			(stroke
				(width 0.1524)
				(type default)
			)
			(layer "B.SilkS")
		)
		(fp_line
			(start 0.7874 0.4064)
			(end 0.7874 -0.4064)
			(stroke
				(width 0.1524)
				(type default)
			)
			(layer "B.SilkS")
		)
		(fp_line
			(start -0.7874 -0.4064)
			(end -0.7874 0.4064)
			(stroke
				(width 0.1524)
				(type default)
			)
			(layer "B.SilkS")
		)
		(fp_line
			(start 0.7874 -0.4064)
			(end -0.7874 -0.4064)
			(stroke
				(width 0.1524)
				(type default)
			)
			(layer "B.SilkS")
		)
		(fp_line
			(start -0.67945 0.3048)
			(end -0.120396 0.3048)
			(stroke
				(width 0.1)
				(type default)
			)
			(layer "B.Fab")
		)
		(fp_line
			(start -0.120396 0.3048)
			(end -0.120396 0.2794)
			(stroke
				(width 0.1)
				(type default)
			)
			(layer "B.Fab")
		)
		(fp_line
			(start 0.12065 0.3048)
			(end 0.67945 0.3048)
			(stroke
				(width 0.1)
				(type default)
			)
			(layer "B.Fab")
		)
		(fp_line
			(start 0.67945 0.3048)
			(end 0.67945 -0.305054)
			(stroke
				(width 0.1)
				(type default)
			)
			(layer "B.Fab")
		)
		(fp_line
			(start -0.120396 0.2794)
			(end 0.12065 0.2794)
			(stroke
				(width 0.1)
				(type default)
			)
			(layer "B.Fab")
		)
		(fp_line
			(start 0.12065 0.2794)
			(end 0.12065 0.3048)
			(stroke
				(width 0.1)
				(type default)
			)
			(layer "B.Fab")
		)
		(fp_line
			(start -0.12065 -0.2794)
			(end -0.12065 -0.3048)
			(stroke
				(width 0.1)
				(type default)
			)
			(layer "B.Fab")
		)
		(fp_line
			(start 0.12065 -0.2794)
			(end -0.12065 -0.2794)
			(stroke
				(width 0.1)
				(type default)
			)
			(layer "B.Fab")
		)
		(fp_line
			(start -0.67945 -0.3048)
			(end -0.67945 0.3048)
			(stroke
				(width 0.1)
				(type default)
			)
			(layer "B.Fab")
		)
		(fp_line
			(start -0.12065 -0.3048)
			(end -0.67945 -0.3048)
			(stroke
				(width 0.1)
				(type default)
			)
			(layer "B.Fab")
		)
		(fp_line
			(start 0.12065 -0.305054)
			(end 0.12065 -0.2794)
			(stroke
				(width 0.1)
				(type default)
			)
			(layer "B.Fab")
		)
		(fp_line
			(start 0.67945 -0.305054)
			(end 0.12065 -0.305054)
			(stroke
				(width 0.1)
				(type default)
			)
			(layer "B.Fab")
		)
		(pad "1" smd circle
			(at 0.40005 0 90)
			(size 0 0)
			(layers "B.Cu" "B.Mask" "B.Paste")
			(net "P3V3_AUX")
		)
		(pad "2" smd circle
			(at -0.40005 0 90)
			(size 0 0)
			(layers "B.Cu" "B.Mask" "B.Paste")
			(net "I3C_BMC_SWB_BUF_R_SDA")
		)
	)
	(footprint ""
		(layer "B.Cu")
		(at 59.401202 -195.926964 180)
		(property "Reference" "R1687"
			(at 0 0 0)
			(layer "B.SilkS")
			(hide yes)
			(effects
				(font
					(size 1.27 1.27)
				)
				(justify mirror)
			)
		)
		(property "Value" ""
			(at 0 0 0)
			(layer "B.Fab")
			(effects
				(font
					(size 1.27 1.27)
				)
				(justify mirror)
			)
		)
		(duplicate_pad_numbers_are_jumpers no)
		(fp_line
			(start 0.7874 0.4064)
			(end 0.7874 -0.4064)
			(stroke
				(width 0.1524)
				(type default)
			)
			(layer "B.SilkS")
		)
		(fp_line
			(start 0.7874 -0.4064)
			(end -0.7874 -0.4064)
			(stroke
				(width 0.1524)
				(type default)
			)
			(layer "B.SilkS")
		)
		(fp_line
			(start -0.7874 0.4064)
			(end 0.7874 0.4064)
			(stroke
				(width 0.1524)
				(type default)
			)
			(layer "B.SilkS")
		)
		(fp_line
			(start -0.7874 -0.4064)
			(end -0.7874 0.4064)
			(stroke
				(width 0.1524)
				(type default)
			)
			(layer "B.SilkS")
		)
		(fp_line
			(start 0.67945 0.3048)
			(end 0.67945 -0.305054)
			(stroke
				(width 0.1)
				(type default)
			)
			(layer "B.Fab")
		)
		(fp_line
			(start 0.67945 -0.305054)
			(end 0.12065 -0.305054)
			(stroke
				(width 0.1)
				(type default)
			)
			(layer "B.Fab")
		)
		(fp_line
			(start 0.12065 0.3048)
			(end 0.67945 0.3048)
			(stroke
				(width 0.1)
				(type default)
			)
			(layer "B.Fab")
		)
		(fp_line
			(start 0.12065 0.2794)
			(end 0.12065 0.3048)
			(stroke
				(width 0.1)
				(type default)
			)
			(layer "B.Fab")
		)
		(fp_line
			(start 0.12065 -0.2794)
			(end -0.12065 -0.2794)
			(stroke
				(width 0.1)
				(type default)
			)
			(layer "B.Fab")
		)
		(fp_line
			(start 0.12065 -0.305054)
			(end 0.12065 -0.2794)
			(stroke
				(width 0.1)
				(type default)
			)
			(layer "B.Fab")
		)
		(fp_line
			(start -0.120396 0.3048)
			(end -0.120396 0.2794)
			(stroke
				(width 0.1)
				(type default)
			)
			(layer "B.Fab")
		)
		(fp_line
			(start -0.120396 0.2794)
			(end 0.12065 0.2794)
			(stroke
				(width 0.1)
				(type default)
			)
			(layer "B.Fab")
		)
		(fp_line
			(start -0.12065 -0.2794)
			(end -0.12065 -0.3048)
			(stroke
				(width 0.1)
				(type default)
			)
			(layer "B.Fab")
		)
		(fp_line
			(start -0.12065 -0.3048)
			(end -0.67945 -0.3048)
			(stroke
				(width 0.1)
				(type default)
			)
			(layer "B.Fab")
		)
		(fp_line
			(start -0.67945 0.3048)
			(end -0.120396 0.3048)
			(stroke
				(width 0.1)
				(type default)
			)
			(layer "B.Fab")
		)
		(fp_line
			(start -0.67945 -0.3048)
			(end -0.67945 0.3048)
			(stroke
				(width 0.1)
				(type default)
			)
			(layer "B.Fab")
		)
		(pad "1" smd circle
			(at 0.40005 0)
			(size 0 0)
			(layers "B.Cu" "B.Mask" "B.Paste")
			(net "I3C_SPD_DDRAF_CPU1_SDA")
		)
		(pad "2" smd circle
			(at -0.40005 0)
			(size 0 0)
			(layers "B.Cu" "B.Mask" "B.Paste")
			(net "I3C_SPD_DDRA_CPU1_SDA")
		)
	)
	(footprint ""
		(layer "B.Cu")
		(at 121.579386 -266.005564)
		(property "Reference" "C2480"
			(at 0 0 0)
			(layer "B.SilkS")
			(hide yes)
			(effects
				(font
					(size 1.27 1.27)
				)
				(justify mirror)
			)
		)
		(property "Value" ""
			(at 0 0 0)
			(layer "B.Fab")
			(effects
				(font
					(size 1.27 1.27)
				)
				(justify mirror)
			)
		)
		(duplicate_pad_numbers_are_jumpers no)
		(fp_line
			(start -0.7874 -0.4064)
			(end -0.7874 0.4064)
			(stroke
				(width 0.1524)
				(type default)
			)
			(layer "B.SilkS")
		)
		(fp_line
			(start -0.7874 0.4064)
			(end 0.7874 0.4064)
			(stroke
				(width 0.1524)
				(type default)
			)
			(layer "B.SilkS")
		)
		(fp_line
			(start 0.7874 -0.4064)
			(end -0.7874 -0.4064)
			(stroke
				(width 0.1524)
				(type default)
			)
			(layer "B.SilkS")
		)
		(fp_line
			(start 0.7874 0.4064)
			(end 0.7874 -0.4064)
			(stroke
				(width 0.1524)
				(type default)
			)
			(layer "B.SilkS")
		)
		(fp_line
			(start -0.67945 -0.3048)
			(end -0.67945 0.3048)
			(stroke
				(width 0.1)
				(type default)
			)
			(layer "B.Fab")
		)
		(fp_line
			(start -0.67945 0.3048)
			(end -0.120396 0.3048)
			(stroke
				(width 0.1)
				(type default)
			)
			(layer "B.Fab")
		)
		(fp_line
			(start -0.12065 -0.3048)
			(end -0.67945 -0.3048)
			(stroke
				(width 0.1)
				(type default)
			)
			(layer "B.Fab")
		)
		(fp_line
			(start -0.12065 -0.2794)
			(end -0.12065 -0.3048)
			(stroke
				(width 0.1)
				(type default)
			)
			(layer "B.Fab")
		)
		(fp_line
			(start -0.120396 0.2794)
			(end 0.12065 0.2794)
			(stroke
				(width 0.1)
				(type default)
			)
			(layer "B.Fab")
		)
		(fp_line
			(start -0.120396 0.3048)
			(end -0.120396 0.2794)
			(stroke
				(width 0.1)
				(type default)
			)
			(layer "B.Fab")
		)
		(fp_line
			(start 0.12065 -0.305054)
			(end 0.12065 -0.2794)
			(stroke
				(width 0.1)
				(type default)
			)
			(layer "B.Fab")
		)
		(fp_line
			(start 0.12065 -0.2794)
			(end -0.12065 -0.2794)
			(stroke
				(width 0.1)
				(type default)
			)
			(layer "B.Fab")
		)
		(fp_line
			(start 0.12065 0.2794)
			(end 0.12065 0.3048)
			(stroke
				(width 0.1)
				(type default)
			)
			(layer "B.Fab")
		)
		(fp_line
			(start 0.12065 0.3048)
			(end 0.67945 0.3048)
			(stroke
				(width 0.1)
				(type default)
			)
			(layer "B.Fab")
		)
		(fp_line
			(start 0.67945 -0.305054)
			(end 0.12065 -0.305054)
			(stroke
				(width 0.1)
				(type default)
			)
			(layer "B.Fab")
		)
		(fp_line
			(start 0.67945 0.3048)
			(end 0.67945 -0.305054)
			(stroke
				(width 0.1)
				(type default)
			)
			(layer "B.Fab")
		)
		(pad "1" smd circle
			(at 0.40005 0 180)
			(size 0 0)
			(layers "B.Cu" "B.Mask" "B.Paste")
			(net "PVDD11_S3_P1")
		)
		(pad "2" smd circle
			(at -0.40005 0 180)
			(size 0 0)
			(layers "B.Cu" "B.Mask" "B.Paste")
			(net "GND")
		)
	)
	(footprint ""
		(layer "B.Cu")
		(at 338.550758 -214.880952 90)
		(property "Reference" "R436"
			(at 0 0 90)
			(layer "B.SilkS")
			(hide yes)
			(effects
				(font
					(size 1.27 1.27)
				)
				(justify mirror)
			)
		)
		(property "Value" ""
			(at 0 0 90)
			(layer "B.Fab")
			(effects
				(font
					(size 1.27 1.27)
				)
				(justify mirror)
			)
		)
		(duplicate_pad_numbers_are_jumpers no)
		(fp_line
			(start 0.7874 -0.4064)
			(end -0.7874 -0.4064)
			(stroke
				(width 0.1524)
				(type default)
			)
			(layer "B.SilkS")
		)
		(fp_line
			(start -0.7874 -0.4064)
			(end -0.7874 -0.095758)
			(stroke
				(width 0.1524)
				(type default)
			)
			(layer "B.SilkS")
		)
		(fp_line
			(start 0.7874 -0.019558)
			(end 0.7874 -0.4064)
			(stroke
				(width 0.1524)
				(type default)
			)
			(layer "B.SilkS")
		)
		(fp_line
			(start -0.377952 0.4064)
			(end 0.384048 0.4064)
			(stroke
				(width 0.1524)
				(type default)
			)
			(layer "B.SilkS")
		)
		(fp_line
			(start 0.67945 -0.305054)
			(end 0.12065 -0.305054)
			(stroke
				(width 0.1)
				(type default)
			)
			(layer "B.Fab")
		)
		(fp_line
			(start 0.12065 -0.305054)
			(end 0.12065 -0.2794)
			(stroke
				(width 0.1)
				(type default)
			)
			(layer "B.Fab")
		)
		(fp_line
			(start -0.12065 -0.3048)
			(end -0.67945 -0.3048)
			(stroke
				(width 0.1)
				(type default)
			)
			(layer "B.Fab")
		)
		(fp_line
			(start -0.67945 -0.3048)
			(end -0.67945 0.3048)
			(stroke
				(width 0.1)
				(type default)
			)
			(layer "B.Fab")
		)
		(fp_line
			(start 0.12065 -0.2794)
			(end -0.12065 -0.2794)
			(stroke
				(width 0.1)
				(type default)
			)
			(layer "B.Fab")
		)
		(fp_line
			(start -0.12065 -0.2794)
			(end -0.12065 -0.3048)
			(stroke
				(width 0.1)
				(type default)
			)
			(layer "B.Fab")
		)
		(fp_line
			(start 0.12065 0.2794)
			(end 0.12065 0.3048)
			(stroke
				(width 0.1)
				(type default)
			)
			(layer "B.Fab")
		)
		(fp_line
			(start -0.120396 0.2794)
			(end 0.12065 0.2794)
			(stroke
				(width 0.1)
				(type default)
			)
			(layer "B.Fab")
		)
		(fp_line
			(start 0.67945 0.3048)
			(end 0.67945 -0.305054)
			(stroke
				(width 0.1)
				(type default)
			)
			(layer "B.Fab")
		)
		(fp_line
			(start 0.12065 0.3048)
			(end 0.67945 0.3048)
			(stroke
				(width 0.1)
				(type default)
			)
			(layer "B.Fab")
		)
		(fp_line
			(start -0.120396 0.3048)
			(end -0.120396 0.2794)
			(stroke
				(width 0.1)
				(type default)
			)
			(layer "B.Fab")
		)
		(fp_line
			(start -0.67945 0.3048)
			(end -0.120396 0.3048)
			(stroke
				(width 0.1)
				(type default)
			)
			(layer "B.Fab")
		)
		(pad "1" smd circle
			(at 0.40005 0 270)
			(size 0 0)
			(layers "B.Cu" "B.Mask" "B.Paste")
			(net "CLK_100M_REF_OUT_DN")
		)
		(pad "2" smd circle
			(at -0.40005 0 270)
			(size 0 0)
			(layers "B.Cu" "B.Mask" "B.Paste")
			(net "CLK_100M_REF_IN_DN")
		)
	)
	(footprint ""
		(layer "B.Cu")
		(at 367.741454 -250.89231)
		(property "Reference" "C271"
			(at 0 0 0)
			(layer "B.SilkS")
			(hide yes)
			(effects
				(font
					(size 1.27 1.27)
				)
				(justify mirror)
			)
		)
		(property "Value" ""
			(at 0 0 0)
			(layer "B.Fab")
			(effects
				(font
					(size 1.27 1.27)
				)
				(justify mirror)
			)
		)
		(duplicate_pad_numbers_are_jumpers no)
		(fp_line
			(start -0.7874 -0.4064)
			(end -0.7874 0.4064)
			(stroke
				(width 0.1524)
				(type default)
			)
			(layer "B.SilkS")
		)
		(fp_line
			(start -0.7874 0.4064)
			(end 0.7874 0.4064)
			(stroke
				(width 0.1524)
				(type default)
			)
			(layer "B.SilkS")
		)
		(fp_line
			(start 0.7874 -0.4064)
			(end -0.7874 -0.4064)
			(stroke
				(width 0.1524)
				(type default)
			)
			(layer "B.SilkS")
		)
		(fp_line
			(start 0.7874 0.4064)
			(end 0.7874 -0.4064)
			(stroke
				(width 0.1524)
				(type default)
			)
			(layer "B.SilkS")
		)
		(fp_line
			(start -0.67945 -0.3048)
			(end -0.67945 0.3048)
			(stroke
				(width 0.1)
				(type default)
			)
			(layer "B.Fab")
		)
		(fp_line
			(start -0.67945 0.3048)
			(end -0.120396 0.3048)
			(stroke
				(width 0.1)
				(type default)
			)
			(layer "B.Fab")
		)
		(fp_line
			(start -0.12065 -0.3048)
			(end -0.67945 -0.3048)
			(stroke
				(width 0.1)
				(type default)
			)
			(layer "B.Fab")
		)
		(fp_line
			(start -0.12065 -0.2794)
			(end -0.12065 -0.3048)
			(stroke
				(width 0.1)
				(type default)
			)
			(layer "B.Fab")
		)
		(fp_line
			(start -0.120396 0.2794)
			(end 0.12065 0.2794)
			(stroke
				(width 0.1)
				(type default)
			)
			(layer "B.Fab")
		)
		(fp_line
			(start -0.120396 0.3048)
			(end -0.120396 0.2794)
			(stroke
				(width 0.1)
				(type default)
			)
			(layer "B.Fab")
		)
		(fp_line
			(start 0.12065 -0.305054)
			(end 0.12065 -0.2794)
			(stroke
				(width 0.1)
				(type default)
			)
			(layer "B.Fab")
		)
		(fp_line
			(start 0.12065 -0.2794)
			(end -0.12065 -0.2794)
			(stroke
				(width 0.1)
				(type default)
			)
			(layer "B.Fab")
		)
		(fp_line
			(start 0.12065 0.2794)
			(end 0.12065 0.3048)
			(stroke
				(width 0.1)
				(type default)
			)
			(layer "B.Fab")
		)
		(fp_line
			(start 0.12065 0.3048)
			(end 0.67945 0.3048)
			(stroke
				(width 0.1)
				(type default)
			)
			(layer "B.Fab")
		)
		(fp_line
			(start 0.67945 -0.305054)
			(end 0.12065 -0.305054)
			(stroke
				(width 0.1)
				(type default)
			)
			(layer "B.Fab")
		)
		(fp_line
			(start 0.67945 0.3048)
			(end 0.67945 -0.305054)
			(stroke
				(width 0.1)
				(type default)
			)
			(layer "B.Fab")
		)
		(pad "1" smd circle
			(at 0.40005 0 180)
			(size 0 0)
			(layers "B.Cu" "B.Mask" "B.Paste")
			(net "PVDDCR_CPU0_P0")
		)
		(pad "2" smd circle
			(at -0.40005 0 180)
			(size 0 0)
			(layers "B.Cu" "B.Mask" "B.Paste")
			(net "GND")
		)
	)
	(footprint ""
		(layer "B.Cu")
		(at 299.265594 -391.06856 180)
		(property "Reference" "R972"
			(at 0 0 0)
			(layer "B.SilkS")
			(hide yes)
			(effects
				(font
					(size 1.27 1.27)
				)
				(justify mirror)
			)
		)
		(property "Value" ""
			(at 0 0 0)
			(layer "B.Fab")
			(effects
				(font
					(size 1.27 1.27)
				)
				(justify mirror)
			)
		)
		(duplicate_pad_numbers_are_jumpers no)
		(fp_line
			(start 0.32512 0.175006)
			(end 0.32512 -0.175006)
			(stroke
				(width 0.1)
				(type default)
			)
			(layer "B.Fab")
		)
		(fp_line
			(start 0.32512 -0.175006)
			(end -0.32512 -0.175006)
			(stroke
				(width 0.1)
				(type default)
			)
			(layer "B.Fab")
		)
		(fp_line
			(start -0.32512 0.175006)
			(end 0.32512 0.175006)
			(stroke
				(width 0.1)
				(type default)
			)
			(layer "B.Fab")
		)
		(fp_line
			(start -0.32512 -0.175006)
			(end -0.32512 0.175006)
			(stroke
				(width 0.1)
				(type default)
			)
			(layer "B.Fab")
		)
		(pad "1" smd rect
			(at 0.2667 0)
			(size 0.3048 0.381)
			(layers "B.Cu" "B.Mask" "B.Paste")
			(net "P1V8_CPU0_RT_1D")
		)
		(pad "2" smd rect
			(at -0.2667 0 180)
			(size 0.3048 0.381)
			(layers "B.Cu" "B.Mask" "B.Paste")
			(net "RT_CPU0_P0_SCAN_MODE")
		)
	)
	(footprint ""
		(layer "B.Cu")
		(at 165.18382 -193.996564)
		(property "Reference" "R110"
			(at 0 0 0)
			(layer "B.SilkS")
			(hide yes)
			(effects
				(font
					(size 1.27 1.27)
				)
				(justify mirror)
			)
		)
		(property "Value" ""
			(at 0 0 0)
			(layer "B.Fab")
			(effects
				(font
					(size 1.27 1.27)
				)
				(justify mirror)
			)
		)
		(duplicate_pad_numbers_are_jumpers no)
		(fp_line
			(start -0.7874 -0.4064)
			(end -0.7874 0.4064)
			(stroke
				(width 0.1524)
				(type default)
			)
			(layer "B.SilkS")
		)
		(fp_line
			(start -0.7874 0.4064)
			(end 0.7874 0.4064)
			(stroke
				(width 0.1524)
				(type default)
			)
			(layer "B.SilkS")
		)
		(fp_line
			(start 0.7874 -0.4064)
			(end -0.7874 -0.4064)
			(stroke
				(width 0.1524)
				(type default)
			)
			(layer "B.SilkS")
		)
		(fp_line
			(start 0.7874 0.4064)
			(end 0.7874 -0.4064)
			(stroke
				(width 0.1524)
				(type default)
			)
			(layer "B.SilkS")
		)
		(fp_line
			(start -0.67945 -0.3048)
			(end -0.67945 0.3048)
			(stroke
				(width 0.1)
				(type default)
			)
			(layer "B.Fab")
		)
		(fp_line
			(start -0.67945 0.3048)
			(end -0.120396 0.3048)
			(stroke
				(width 0.1)
				(type default)
			)
			(layer "B.Fab")
		)
		(fp_line
			(start -0.12065 -0.3048)
			(end -0.67945 -0.3048)
			(stroke
				(width 0.1)
				(type default)
			)
			(layer "B.Fab")
		)
		(fp_line
			(start -0.12065 -0.2794)
			(end -0.12065 -0.3048)
			(stroke
				(width 0.1)
				(type default)
			)
			(layer "B.Fab")
		)
		(fp_line
			(start -0.120396 0.2794)
			(end 0.12065 0.2794)
			(stroke
				(width 0.1)
				(type default)
			)
			(layer "B.Fab")
		)
		(fp_line
			(start -0.120396 0.3048)
			(end -0.120396 0.2794)
			(stroke
				(width 0.1)
				(type default)
			)
			(layer "B.Fab")
		)
		(fp_line
			(start 0.12065 -0.305054)
			(end 0.12065 -0.2794)
			(stroke
				(width 0.1)
				(type default)
			)
			(layer "B.Fab")
		)
		(fp_line
			(start 0.12065 -0.2794)
			(end -0.12065 -0.2794)
			(stroke
				(width 0.1)
				(type default)
			)
			(layer "B.Fab")
		)
		(fp_line
			(start 0.12065 0.2794)
			(end 0.12065 0.3048)
			(stroke
				(width 0.1)
				(type default)
			)
			(layer "B.Fab")
		)
		(fp_line
			(start 0.12065 0.3048)
			(end 0.67945 0.3048)
			(stroke
				(width 0.1)
				(type default)
			)
			(layer "B.Fab")
		)
		(fp_line
			(start 0.67945 -0.305054)
			(end 0.12065 -0.305054)
			(stroke
				(width 0.1)
				(type default)
			)
			(layer "B.Fab")
		)
		(fp_line
			(start 0.67945 0.3048)
			(end 0.67945 -0.305054)
			(stroke
				(width 0.1)
				(type default)
			)
			(layer "B.Fab")
		)
		(pad "1" smd circle
			(at 0.40005 0 180)
			(size 0 0)
			(layers "B.Cu" "B.Mask" "B.Paste")
			(net "P3V3")
		)
		(pad "2" smd circle
			(at -0.40005 0 180)
			(size 0 0)
			(layers "B.Cu" "B.Mask" "B.Paste")
			(net "PWRGD_CHG_CPU1_DIMM0")
		)
	)
	(footprint ""
		(layer "B.Cu")
		(at 134.735062 -155.471876 90)
		(property "Reference" "PR213"
			(at 0 0 90)
			(layer "B.SilkS")
			(hide yes)
			(effects
				(font
					(size 1.27 1.27)
				)
				(justify mirror)
			)
		)
		(property "Value" ""
			(at 0 0 90)
			(layer "B.Fab")
			(effects
				(font
					(size 1.27 1.27)
				)
				(justify mirror)
			)
		)
		(duplicate_pad_numbers_are_jumpers no)
		(fp_line
			(start 0.7874 -0.4064)
			(end -0.7874 -0.4064)
			(stroke
				(width 0.1524)
				(type default)
			)
			(layer "B.SilkS")
		)
		(fp_line
			(start -0.7874 -0.4064)
			(end -0.7874 0.4064)
			(stroke
				(width 0.1524)
				(type default)
			)
			(layer "B.SilkS")
		)
		(fp_line
			(start 0.7874 0.4064)
			(end 0.7874 -0.4064)
			(stroke
				(width 0.1524)
				(type default)
			)
			(layer "B.SilkS")
		)
		(fp_line
			(start -0.7874 0.4064)
			(end 0.7874 0.4064)
			(stroke
				(width 0.1524)
				(type default)
			)
			(layer "B.SilkS")
		)
		(fp_line
			(start 0.67945 -0.305054)
			(end 0.12065 -0.305054)
			(stroke
				(width 0.1)
				(type default)
			)
			(layer "B.Fab")
		)
		(fp_line
			(start 0.12065 -0.305054)
			(end 0.12065 -0.2794)
			(stroke
				(width 0.1)
				(type default)
			)
			(layer "B.Fab")
		)
		(fp_line
			(start -0.12065 -0.3048)
			(end -0.67945 -0.3048)
			(stroke
				(width 0.1)
				(type default)
			)
			(layer "B.Fab")
		)
		(fp_line
			(start -0.67945 -0.3048)
			(end -0.67945 0.3048)
			(stroke
				(width 0.1)
				(type default)
			)
			(layer "B.Fab")
		)
		(fp_line
			(start 0.12065 -0.2794)
			(end -0.12065 -0.2794)
			(stroke
				(width 0.1)
				(type default)
			)
			(layer "B.Fab")
		)
		(fp_line
			(start -0.12065 -0.2794)
			(end -0.12065 -0.3048)
			(stroke
				(width 0.1)
				(type default)
			)
			(layer "B.Fab")
		)
		(fp_line
			(start 0.12065 0.2794)
			(end 0.12065 0.3048)
			(stroke
				(width 0.1)
				(type default)
			)
			(layer "B.Fab")
		)
		(fp_line
			(start -0.120396 0.2794)
			(end 0.12065 0.2794)
			(stroke
				(width 0.1)
				(type default)
			)
			(layer "B.Fab")
		)
		(fp_line
			(start 0.67945 0.3048)
			(end 0.67945 -0.305054)
			(stroke
				(width 0.1)
				(type default)
			)
			(layer "B.Fab")
		)
		(fp_line
			(start 0.12065 0.3048)
			(end 0.67945 0.3048)
			(stroke
				(width 0.1)
				(type default)
			)
			(layer "B.Fab")
		)
		(fp_line
			(start -0.120396 0.3048)
			(end -0.120396 0.2794)
			(stroke
				(width 0.1)
				(type default)
			)
			(layer "B.Fab")
		)
		(fp_line
			(start -0.67945 0.3048)
			(end -0.120396 0.3048)
			(stroke
				(width 0.1)
				(type default)
			)
			(layer "B.Fab")
		)
		(pad "1" smd circle
			(at 0.40005 0 270)
			(size 0 0)
			(layers "B.Cu" "B.Mask" "B.Paste")
			(net "PVDDCR_CPU0_P1_PVCC")
		)
		(pad "2" smd circle
			(at -0.40005 0 270)
			(size 0 0)
			(layers "B.Cu" "B.Mask" "B.Paste")
			(net "PVDDCR_SOC_P1_VCC3")
		)
	)
	(footprint ""
		(layer "B.Cu")
		(at 139.28852 -33.526222 90)
		(property "Reference" "C6043"
			(at 0 0 90)
			(layer "B.SilkS")
			(hide yes)
			(effects
				(font
					(size 1.27 1.27)
				)
				(justify mirror)
			)
		)
		(property "Value" ""
			(at 0 0 90)
			(layer "B.Fab")
			(effects
				(font
					(size 1.27 1.27)
				)
				(justify mirror)
			)
		)
		(duplicate_pad_numbers_are_jumpers no)
		(fp_line
			(start 0.7874 -0.4064)
			(end -0.7874 -0.4064)
			(stroke
				(width 0.1524)
				(type default)
			)
			(layer "B.SilkS")
		)
		(fp_line
			(start -0.7874 -0.4064)
			(end -0.7874 0.4064)
			(stroke
				(width 0.1524)
				(type default)
			)
			(layer "B.SilkS")
		)
		(fp_line
			(start 0.7874 0.4064)
			(end 0.7874 -0.4064)
			(stroke
				(width 0.1524)
				(type default)
			)
			(layer "B.SilkS")
		)
		(fp_line
			(start -0.7874 0.4064)
			(end 0.7874 0.4064)
			(stroke
				(width 0.1524)
				(type default)
			)
			(layer "B.SilkS")
		)
		(fp_line
			(start 0.67945 -0.305054)
			(end 0.12065 -0.305054)
			(stroke
				(width 0.1)
				(type default)
			)
			(layer "B.Fab")
		)
		(fp_line
			(start 0.12065 -0.305054)
			(end 0.12065 -0.2794)
			(stroke
				(width 0.1)
				(type default)
			)
			(layer "B.Fab")
		)
		(fp_line
			(start -0.12065 -0.3048)
			(end -0.67945 -0.3048)
			(stroke
				(width 0.1)
				(type default)
			)
			(layer "B.Fab")
		)
		(fp_line
			(start -0.67945 -0.3048)
			(end -0.67945 0.3048)
			(stroke
				(width 0.1)
				(type default)
			)
			(layer "B.Fab")
		)
		(fp_line
			(start 0.12065 -0.2794)
			(end -0.12065 -0.2794)
			(stroke
				(width 0.1)
				(type default)
			)
			(layer "B.Fab")
		)
		(fp_line
			(start -0.12065 -0.2794)
			(end -0.12065 -0.3048)
			(stroke
				(width 0.1)
				(type default)
			)
			(layer "B.Fab")
		)
		(fp_line
			(start 0.12065 0.2794)
			(end 0.12065 0.3048)
			(stroke
				(width 0.1)
				(type default)
			)
			(layer "B.Fab")
		)
		(fp_line
			(start -0.120396 0.2794)
			(end 0.12065 0.2794)
			(stroke
				(width 0.1)
				(type default)
			)
			(layer "B.Fab")
		)
		(fp_line
			(start 0.67945 0.3048)
			(end 0.67945 -0.305054)
			(stroke
				(width 0.1)
				(type default)
			)
			(layer "B.Fab")
		)
		(fp_line
			(start 0.12065 0.3048)
			(end 0.67945 0.3048)
			(stroke
				(width 0.1)
				(type default)
			)
			(layer "B.Fab")
		)
		(fp_line
			(start -0.120396 0.3048)
			(end -0.120396 0.2794)
			(stroke
				(width 0.1)
				(type default)
			)
			(layer "B.Fab")
		)
		(fp_line
			(start -0.67945 0.3048)
			(end -0.120396 0.3048)
			(stroke
				(width 0.1)
				(type default)
			)
			(layer "B.Fab")
		)
		(pad "1" smd circle
			(at 0.40005 0 270)
			(size 0 0)
			(layers "B.Cu" "B.Mask" "B.Paste")
			(net "P3V3_AUX_CPU0_USB_AVDD33")
		)
		(pad "2" smd circle
			(at -0.40005 0 270)
			(size 0 0)
			(layers "B.Cu" "B.Mask" "B.Paste")
			(net "GND")
		)
	)
	(footprint ""
		(layer "B.Cu")
		(at 167.377618 -416.946588 180)
		(property "Reference" "C12"
			(at 0 0 0)
			(layer "B.SilkS")
			(hide yes)
			(effects
				(font
					(size 1.27 1.27)
				)
				(justify mirror)
			)
		)
		(property "Value" ""
			(at 0 0 0)
			(layer "B.Fab")
			(effects
				(font
					(size 1.27 1.27)
				)
				(justify mirror)
			)
		)
		(duplicate_pad_numbers_are_jumpers no)
		(fp_line
			(start 0.7874 0.4064)
			(end 0.7874 -0.4064)
			(stroke
				(width 0.1524)
				(type default)
			)
			(layer "B.SilkS")
		)
		(fp_line
			(start 0.7874 -0.4064)
			(end -0.7874 -0.4064)
			(stroke
				(width 0.1524)
				(type default)
			)
			(layer "B.SilkS")
		)
		(fp_line
			(start -0.7874 0.4064)
			(end 0.7874 0.4064)
			(stroke
				(width 0.1524)
				(type default)
			)
			(layer "B.SilkS")
		)
		(fp_line
			(start -0.7874 -0.4064)
			(end -0.7874 0.4064)
			(stroke
				(width 0.1524)
				(type default)
			)
			(layer "B.SilkS")
		)
		(fp_line
			(start 0.67945 0.3048)
			(end 0.67945 -0.305054)
			(stroke
				(width 0.1)
				(type default)
			)
			(layer "B.Fab")
		)
		(fp_line
			(start 0.67945 -0.305054)
			(end 0.12065 -0.305054)
			(stroke
				(width 0.1)
				(type default)
			)
			(layer "B.Fab")
		)
		(fp_line
			(start 0.12065 0.3048)
			(end 0.67945 0.3048)
			(stroke
				(width 0.1)
				(type default)
			)
			(layer "B.Fab")
		)
		(fp_line
			(start 0.12065 0.2794)
			(end 0.12065 0.3048)
			(stroke
				(width 0.1)
				(type default)
			)
			(layer "B.Fab")
		)
		(fp_line
			(start 0.12065 -0.2794)
			(end -0.12065 -0.2794)
			(stroke
				(width 0.1)
				(type default)
			)
			(layer "B.Fab")
		)
		(fp_line
			(start 0.12065 -0.305054)
			(end 0.12065 -0.2794)
			(stroke
				(width 0.1)
				(type default)
			)
			(layer "B.Fab")
		)
		(fp_line
			(start -0.120396 0.3048)
			(end -0.120396 0.2794)
			(stroke
				(width 0.1)
				(type default)
			)
			(layer "B.Fab")
		)
		(fp_line
			(start -0.120396 0.2794)
			(end 0.12065 0.2794)
			(stroke
				(width 0.1)
				(type default)
			)
			(layer "B.Fab")
		)
		(fp_line
			(start -0.12065 -0.2794)
			(end -0.12065 -0.3048)
			(stroke
				(width 0.1)
				(type default)
			)
			(layer "B.Fab")
		)
		(fp_line
			(start -0.12065 -0.3048)
			(end -0.67945 -0.3048)
			(stroke
				(width 0.1)
				(type default)
			)
			(layer "B.Fab")
		)
		(fp_line
			(start -0.67945 0.3048)
			(end -0.120396 0.3048)
			(stroke
				(width 0.1)
				(type default)
			)
			(layer "B.Fab")
		)
		(fp_line
			(start -0.67945 -0.3048)
			(end -0.67945 0.3048)
			(stroke
				(width 0.1)
				(type default)
			)
			(layer "B.Fab")
		)
		(pad "1" smd circle
			(at 0.40005 0)
			(size 0 0)
			(layers "B.Cu" "B.Mask" "B.Paste")
			(net "GPU_3V3IO_RSVD0_FFU_ISO")
		)
		(pad "2" smd circle
			(at -0.40005 0)
			(size 0 0)
			(layers "B.Cu" "B.Mask" "B.Paste")
			(net "GND")
		)
	)
	(footprint ""
		(layer "B.Cu")
		(at 178.689 -100.294948 -90)
		(property "Reference" "R141"
			(at 0 0 90)
			(layer "B.SilkS")
			(hide yes)
			(effects
				(font
					(size 1.27 1.27)
				)
				(justify mirror)
			)
		)
		(property "Value" ""
			(at 0 0 90)
			(layer "B.Fab")
			(effects
				(font
					(size 1.27 1.27)
				)
				(justify mirror)
			)
		)
		(duplicate_pad_numbers_are_jumpers no)
		(fp_line
			(start -0.7874 0.4064)
			(end 0.7874 0.4064)
			(stroke
				(width 0.1524)
				(type default)
			)
			(layer "B.SilkS")
		)
		(fp_line
			(start 0.7874 0.4064)
			(end 0.7874 -0.4064)
			(stroke
				(width 0.1524)
				(type default)
			)
			(layer "B.SilkS")
		)
		(fp_line
			(start -0.7874 -0.4064)
			(end -0.7874 0.4064)
			(stroke
				(width 0.1524)
				(type default)
			)
			(layer "B.SilkS")
		)
		(fp_line
			(start 0.7874 -0.4064)
			(end -0.7874 -0.4064)
			(stroke
				(width 0.1524)
				(type default)
			)
			(layer "B.SilkS")
		)
		(fp_line
			(start -0.67945 0.3048)
			(end -0.120396 0.3048)
			(stroke
				(width 0.1)
				(type default)
			)
			(layer "B.Fab")
		)
		(fp_line
			(start -0.120396 0.3048)
			(end -0.120396 0.2794)
			(stroke
				(width 0.1)
				(type default)
			)
			(layer "B.Fab")
		)
		(fp_line
			(start 0.12065 0.3048)
			(end 0.67945 0.3048)
			(stroke
				(width 0.1)
				(type default)
			)
			(layer "B.Fab")
		)
		(fp_line
			(start 0.67945 0.3048)
			(end 0.67945 -0.305054)
			(stroke
				(width 0.1)
				(type default)
			)
			(layer "B.Fab")
		)
		(fp_line
			(start -0.120396 0.2794)
			(end 0.12065 0.2794)
			(stroke
				(width 0.1)
				(type default)
			)
			(layer "B.Fab")
		)
		(fp_line
			(start 0.12065 0.2794)
			(end 0.12065 0.3048)
			(stroke
				(width 0.1)
				(type default)
			)
			(layer "B.Fab")
		)
		(fp_line
			(start -0.12065 -0.2794)
			(end -0.12065 -0.3048)
			(stroke
				(width 0.1)
				(type default)
			)
			(layer "B.Fab")
		)
		(fp_line
			(start 0.12065 -0.2794)
			(end -0.12065 -0.2794)
			(stroke
				(width 0.1)
				(type default)
			)
			(layer "B.Fab")
		)
		(fp_line
			(start -0.67945 -0.3048)
			(end -0.67945 0.3048)
			(stroke
				(width 0.1)
				(type default)
			)
			(layer "B.Fab")
		)
		(fp_line
			(start -0.12065 -0.3048)
			(end -0.67945 -0.3048)
			(stroke
				(width 0.1)
				(type default)
			)
			(layer "B.Fab")
		)
		(fp_line
			(start 0.12065 -0.305054)
			(end 0.12065 -0.2794)
			(stroke
				(width 0.1)
				(type default)
			)
			(layer "B.Fab")
		)
		(fp_line
			(start 0.67945 -0.305054)
			(end 0.12065 -0.305054)
			(stroke
				(width 0.1)
				(type default)
			)
			(layer "B.Fab")
		)
		(pad "1" smd circle
			(at 0.40005 0 90)
			(size 0 0)
			(layers "B.Cu" "B.Mask" "B.Paste")
			(net "PVDDCR_CPU1_P1_OCP_N")
		)
		(pad "2" smd circle
			(at -0.40005 0 90)
			(size 0 0)
			(layers "B.Cu" "B.Mask" "B.Paste")
			(net "FM_PVDDCR_CPU1_P1_OCP_N")
		)
	)
	(footprint ""
		(layer "B.Cu")
		(at 75.103228 -337.658202 -90)
		(property "Reference" "PR260"
			(at 0 0 90)
			(layer "B.SilkS")
			(hide yes)
			(effects
				(font
					(size 1.27 1.27)
				)
				(justify mirror)
			)
		)
		(property "Value" ""
			(at 0 0 90)
			(layer "B.Fab")
			(effects
				(font
					(size 1.27 1.27)
				)
				(justify mirror)
			)
		)
		(duplicate_pad_numbers_are_jumpers no)
		(fp_line
			(start -0.7874 0.4064)
			(end 0.7874 0.4064)
			(stroke
				(width 0.1524)
				(type default)
			)
			(layer "B.SilkS")
		)
		(fp_line
			(start 0.7874 0.4064)
			(end 0.7874 -0.4064)
			(stroke
				(width 0.1524)
				(type default)
			)
			(layer "B.SilkS")
		)
		(fp_line
			(start -0.7874 -0.4064)
			(end -0.7874 0.4064)
			(stroke
				(width 0.1524)
				(type default)
			)
			(layer "B.SilkS")
		)
		(fp_line
			(start 0.7874 -0.4064)
			(end -0.7874 -0.4064)
			(stroke
				(width 0.1524)
				(type default)
			)
			(layer "B.SilkS")
		)
		(fp_line
			(start -0.67945 0.3048)
			(end -0.120396 0.3048)
			(stroke
				(width 0.1)
				(type default)
			)
			(layer "B.Fab")
		)
		(fp_line
			(start -0.120396 0.3048)
			(end -0.120396 0.2794)
			(stroke
				(width 0.1)
				(type default)
			)
			(layer "B.Fab")
		)
		(fp_line
			(start 0.12065 0.3048)
			(end 0.67945 0.3048)
			(stroke
				(width 0.1)
				(type default)
			)
			(layer "B.Fab")
		)
		(fp_line
			(start 0.67945 0.3048)
			(end 0.67945 -0.305054)
			(stroke
				(width 0.1)
				(type default)
			)
			(layer "B.Fab")
		)
		(fp_line
			(start -0.120396 0.2794)
			(end 0.12065 0.2794)
			(stroke
				(width 0.1)
				(type default)
			)
			(layer "B.Fab")
		)
		(fp_line
			(start 0.12065 0.2794)
			(end 0.12065 0.3048)
			(stroke
				(width 0.1)
				(type default)
			)
			(layer "B.Fab")
		)
		(fp_line
			(start -0.12065 -0.2794)
			(end -0.12065 -0.3048)
			(stroke
				(width 0.1)
				(type default)
			)
			(layer "B.Fab")
		)
		(fp_line
			(start 0.12065 -0.2794)
			(end -0.12065 -0.2794)
			(stroke
				(width 0.1)
				(type default)
			)
			(layer "B.Fab")
		)
		(fp_line
			(start -0.67945 -0.3048)
			(end -0.67945 0.3048)
			(stroke
				(width 0.1)
				(type default)
			)
			(layer "B.Fab")
		)
		(fp_line
			(start -0.12065 -0.3048)
			(end -0.67945 -0.3048)
			(stroke
				(width 0.1)
				(type default)
			)
			(layer "B.Fab")
		)
		(fp_line
			(start 0.12065 -0.305054)
			(end 0.12065 -0.2794)
			(stroke
				(width 0.1)
				(type default)
			)
			(layer "B.Fab")
		)
		(fp_line
			(start 0.67945 -0.305054)
			(end 0.12065 -0.305054)
			(stroke
				(width 0.1)
				(type default)
			)
			(layer "B.Fab")
		)
		(pad "1" smd circle
			(at 0.40005 0 90)
			(size 0 0)
			(layers "B.Cu" "B.Mask" "B.Paste")
			(net "PVDDCR_CPU1_P1_VOS2")
		)
		(pad "2" smd circle
			(at -0.40005 0 90)
			(size 0 0)
			(layers "B.Cu" "B.Mask" "B.Paste")
			(net "PVDDCR_CPU1_P1")
		)
	)
	(footprint ""
		(layer "B.Cu")
		(at 436.997348 -19.07667 -90)
		(property "Reference" "R1898"
			(at 0 0 90)
			(layer "B.SilkS")
			(hide yes)
			(effects
				(font
					(size 1.27 1.27)
				)
				(justify mirror)
			)
		)
		(property "Value" ""
			(at 0 0 90)
			(layer "B.Fab")
			(effects
				(font
					(size 1.27 1.27)
				)
				(justify mirror)
			)
		)
		(duplicate_pad_numbers_are_jumpers no)
		(fp_line
			(start -0.7874 0.4064)
			(end 0.7874 0.4064)
			(stroke
				(width 0.1524)
				(type default)
			)
			(layer "B.SilkS")
		)
		(fp_line
			(start 0.7874 0.4064)
			(end 0.7874 -0.4064)
			(stroke
				(width 0.1524)
				(type default)
			)
			(layer "B.SilkS")
		)
		(fp_line
			(start -0.7874 -0.4064)
			(end -0.7874 0.4064)
			(stroke
				(width 0.1524)
				(type default)
			)
			(layer "B.SilkS")
		)
		(fp_line
			(start 0.7874 -0.4064)
			(end -0.7874 -0.4064)
			(stroke
				(width 0.1524)
				(type default)
			)
			(layer "B.SilkS")
		)
		(fp_line
			(start -0.67945 0.3048)
			(end -0.120396 0.3048)
			(stroke
				(width 0.1)
				(type default)
			)
			(layer "B.Fab")
		)
		(fp_line
			(start -0.120396 0.3048)
			(end -0.120396 0.2794)
			(stroke
				(width 0.1)
				(type default)
			)
			(layer "B.Fab")
		)
		(fp_line
			(start 0.12065 0.3048)
			(end 0.67945 0.3048)
			(stroke
				(width 0.1)
				(type default)
			)
			(layer "B.Fab")
		)
		(fp_line
			(start 0.67945 0.3048)
			(end 0.67945 -0.305054)
			(stroke
				(width 0.1)
				(type default)
			)
			(layer "B.Fab")
		)
		(fp_line
			(start -0.120396 0.2794)
			(end 0.12065 0.2794)
			(stroke
				(width 0.1)
				(type default)
			)
			(layer "B.Fab")
		)
		(fp_line
			(start 0.12065 0.2794)
			(end 0.12065 0.3048)
			(stroke
				(width 0.1)
				(type default)
			)
			(layer "B.Fab")
		)
		(fp_line
			(start -0.12065 -0.2794)
			(end -0.12065 -0.3048)
			(stroke
				(width 0.1)
				(type default)
			)
			(layer "B.Fab")
		)
		(fp_line
			(start 0.12065 -0.2794)
			(end -0.12065 -0.2794)
			(stroke
				(width 0.1)
				(type default)
			)
			(layer "B.Fab")
		)
		(fp_line
			(start -0.67945 -0.3048)
			(end -0.67945 0.3048)
			(stroke
				(width 0.1)
				(type default)
			)
			(layer "B.Fab")
		)
		(fp_line
			(start -0.12065 -0.3048)
			(end -0.67945 -0.3048)
			(stroke
				(width 0.1)
				(type default)
			)
			(layer "B.Fab")
		)
		(fp_line
			(start 0.12065 -0.305054)
			(end 0.12065 -0.2794)
			(stroke
				(width 0.1)
				(type default)
			)
			(layer "B.Fab")
		)
		(fp_line
			(start 0.67945 -0.305054)
			(end 0.12065 -0.305054)
			(stroke
				(width 0.1)
				(type default)
			)
			(layer "B.Fab")
		)
		(pad "1" smd circle
			(at 0.40005 0 90)
			(size 0 0)
			(layers "B.Cu" "B.Mask" "B.Paste")
			(net "OCP_SFF_ISO_BIF2_EN")
		)
		(pad "2" smd circle
			(at -0.40005 0 90)
			(size 0 0)
			(layers "B.Cu" "B.Mask" "B.Paste")
			(net "GND")
		)
	)
	(footprint ""
		(layer "B.Cu")
		(at 440.40171 -14.643354)
		(property "Reference" "C21"
			(at 0 0 0)
			(layer "B.SilkS")
			(hide yes)
			(effects
				(font
					(size 1.27 1.27)
				)
				(justify mirror)
			)
		)
		(property "Value" ""
			(at 0 0 0)
			(layer "B.Fab")
			(effects
				(font
					(size 1.27 1.27)
				)
				(justify mirror)
			)
		)
		(duplicate_pad_numbers_are_jumpers no)
		(fp_line
			(start -0.7874 -0.4064)
			(end -0.7874 0.4064)
			(stroke
				(width 0.1524)
				(type default)
			)
			(layer "B.SilkS")
		)
		(fp_line
			(start -0.7874 0.4064)
			(end 0.7874 0.4064)
			(stroke
				(width 0.1524)
				(type default)
			)
			(layer "B.SilkS")
		)
		(fp_line
			(start 0.7874 -0.4064)
			(end -0.7874 -0.4064)
			(stroke
				(width 0.1524)
				(type default)
			)
			(layer "B.SilkS")
		)
		(fp_line
			(start 0.7874 0.4064)
			(end 0.7874 -0.4064)
			(stroke
				(width 0.1524)
				(type default)
			)
			(layer "B.SilkS")
		)
		(fp_line
			(start -0.67945 -0.3048)
			(end -0.67945 0.3048)
			(stroke
				(width 0.1)
				(type default)
			)
			(layer "B.Fab")
		)
		(fp_line
			(start -0.67945 0.3048)
			(end -0.120396 0.3048)
			(stroke
				(width 0.1)
				(type default)
			)
			(layer "B.Fab")
		)
		(fp_line
			(start -0.12065 -0.3048)
			(end -0.67945 -0.3048)
			(stroke
				(width 0.1)
				(type default)
			)
			(layer "B.Fab")
		)
		(fp_line
			(start -0.12065 -0.2794)
			(end -0.12065 -0.3048)
			(stroke
				(width 0.1)
				(type default)
			)
			(layer "B.Fab")
		)
		(fp_line
			(start -0.120396 0.2794)
			(end 0.12065 0.2794)
			(stroke
				(width 0.1)
				(type default)
			)
			(layer "B.Fab")
		)
		(fp_line
			(start -0.120396 0.3048)
			(end -0.120396 0.2794)
			(stroke
				(width 0.1)
				(type default)
			)
			(layer "B.Fab")
		)
		(fp_line
			(start 0.12065 -0.305054)
			(end 0.12065 -0.2794)
			(stroke
				(width 0.1)
				(type default)
			)
			(layer "B.Fab")
		)
		(fp_line
			(start 0.12065 -0.2794)
			(end -0.12065 -0.2794)
			(stroke
				(width 0.1)
				(type default)
			)
			(layer "B.Fab")
		)
		(fp_line
			(start 0.12065 0.2794)
			(end 0.12065 0.3048)
			(stroke
				(width 0.1)
				(type default)
			)
			(layer "B.Fab")
		)
		(fp_line
			(start 0.12065 0.3048)
			(end 0.67945 0.3048)
			(stroke
				(width 0.1)
				(type default)
			)
			(layer "B.Fab")
		)
		(fp_line
			(start 0.67945 -0.305054)
			(end 0.12065 -0.305054)
			(stroke
				(width 0.1)
				(type default)
			)
			(layer "B.Fab")
		)
		(fp_line
			(start 0.67945 0.3048)
			(end 0.67945 -0.305054)
			(stroke
				(width 0.1)
				(type default)
			)
			(layer "B.Fab")
		)
		(pad "1" smd circle
			(at 0.40005 0 180)
			(size 0 0)
			(layers "B.Cu" "B.Mask" "B.Paste")
			(net "P12V_OCP_SFF_R")
		)
		(pad "2" smd circle
			(at -0.40005 0 180)
			(size 0 0)
			(layers "B.Cu" "B.Mask" "B.Paste")
			(net "GND")
		)
	)
	(footprint ""
		(layer "B.Cu")
		(at 56.073802 -194.885564 180)
		(property "Reference" "R36"
			(at 0 0 0)
			(layer "B.SilkS")
			(hide yes)
			(effects
				(font
					(size 1.27 1.27)
				)
				(justify mirror)
			)
		)
		(property "Value" ""
			(at 0 0 0)
			(layer "B.Fab")
			(effects
				(font
					(size 1.27 1.27)
				)
				(justify mirror)
			)
		)
		(duplicate_pad_numbers_are_jumpers no)
		(fp_line
			(start 0.7874 0.4064)
			(end 0.7874 -0.4064)
			(stroke
				(width 0.1524)
				(type default)
			)
			(layer "B.SilkS")
		)
		(fp_line
			(start 0.7874 -0.4064)
			(end -0.7874 -0.4064)
			(stroke
				(width 0.1524)
				(type default)
			)
			(layer "B.SilkS")
		)
		(fp_line
			(start -0.7874 0.4064)
			(end 0.7874 0.4064)
			(stroke
				(width 0.1524)
				(type default)
			)
			(layer "B.SilkS")
		)
		(fp_line
			(start -0.7874 -0.4064)
			(end -0.7874 0.4064)
			(stroke
				(width 0.1524)
				(type default)
			)
			(layer "B.SilkS")
		)
		(fp_line
			(start 0.67945 0.3048)
			(end 0.67945 -0.305054)
			(stroke
				(width 0.1)
				(type default)
			)
			(layer "B.Fab")
		)
		(fp_line
			(start 0.67945 -0.305054)
			(end 0.12065 -0.305054)
			(stroke
				(width 0.1)
				(type default)
			)
			(layer "B.Fab")
		)
		(fp_line
			(start 0.12065 0.3048)
			(end 0.67945 0.3048)
			(stroke
				(width 0.1)
				(type default)
			)
			(layer "B.Fab")
		)
		(fp_line
			(start 0.12065 0.2794)
			(end 0.12065 0.3048)
			(stroke
				(width 0.1)
				(type default)
			)
			(layer "B.Fab")
		)
		(fp_line
			(start 0.12065 -0.2794)
			(end -0.12065 -0.2794)
			(stroke
				(width 0.1)
				(type default)
			)
			(layer "B.Fab")
		)
		(fp_line
			(start 0.12065 -0.305054)
			(end 0.12065 -0.2794)
			(stroke
				(width 0.1)
				(type default)
			)
			(layer "B.Fab")
		)
		(fp_line
			(start -0.120396 0.3048)
			(end -0.120396 0.2794)
			(stroke
				(width 0.1)
				(type default)
			)
			(layer "B.Fab")
		)
		(fp_line
			(start -0.120396 0.2794)
			(end 0.12065 0.2794)
			(stroke
				(width 0.1)
				(type default)
			)
			(layer "B.Fab")
		)
		(fp_line
			(start -0.12065 -0.2794)
			(end -0.12065 -0.3048)
			(stroke
				(width 0.1)
				(type default)
			)
			(layer "B.Fab")
		)
		(fp_line
			(start -0.12065 -0.3048)
			(end -0.67945 -0.3048)
			(stroke
				(width 0.1)
				(type default)
			)
			(layer "B.Fab")
		)
		(fp_line
			(start -0.67945 0.3048)
			(end -0.120396 0.3048)
			(stroke
				(width 0.1)
				(type default)
			)
			(layer "B.Fab")
		)
		(fp_line
			(start -0.67945 -0.3048)
			(end -0.67945 0.3048)
			(stroke
				(width 0.1)
				(type default)
			)
			(layer "B.Fab")
		)
		(pad "1" smd circle
			(at 0.40005 0)
			(size 0 0)
			(layers "B.Cu" "B.Mask" "B.Paste")
			(net "PD_CHA_CPU1_DIMM0_SAA")
		)
		(pad "2" smd circle
			(at -0.40005 0)
			(size 0 0)
			(layers "B.Cu" "B.Mask" "B.Paste")
			(net "GND")
		)
	)
	(footprint ""
		(layer "B.Cu")
		(at 295.402 -427.228 180)
		(property "Reference" "R1211"
			(at 0 0 0)
			(layer "B.SilkS")
			(hide yes)
			(effects
				(font
					(size 1.27 1.27)
				)
				(justify mirror)
			)
		)
		(property "Value" ""
			(at 0 0 0)
			(layer "B.Fab")
			(effects
				(font
					(size 1.27 1.27)
				)
				(justify mirror)
			)
		)
		(duplicate_pad_numbers_are_jumpers no)
		(fp_line
			(start 0.32512 0.175006)
			(end 0.32512 -0.175006)
			(stroke
				(width 0.1)
				(type default)
			)
			(layer "B.Fab")
		)
		(fp_line
			(start 0.32512 -0.175006)
			(end -0.32512 -0.175006)
			(stroke
				(width 0.1)
				(type default)
			)
			(layer "B.Fab")
		)
		(fp_line
			(start -0.32512 0.175006)
			(end 0.32512 0.175006)
			(stroke
				(width 0.1)
				(type default)
			)
			(layer "B.Fab")
		)
		(fp_line
			(start -0.32512 -0.175006)
			(end -0.32512 0.175006)
			(stroke
				(width 0.1)
				(type default)
			)
			(layer "B.Fab")
		)
		(pad "1" smd rect
			(at 0.2667 0)
			(size 0.3048 0.381)
			(layers "B.Cu" "B.Mask" "B.Paste")
			(net "RST_SMB_RT_ROM_R1_N")
		)
		(pad "2" smd rect
			(at -0.2667 0 180)
			(size 0.3048 0.381)
			(layers "B.Cu" "B.Mask" "B.Paste")
			(net "FM_SMB_RT_ROM_MUX5_SEL")
		)
	)
	(footprint ""
		(layer "B.Cu")
		(at 314.68441 -337.660488 -90)
		(property "Reference" "PR92"
			(at 0 0 90)
			(layer "B.SilkS")
			(hide yes)
			(effects
				(font
					(size 1.27 1.27)
				)
				(justify mirror)
			)
		)
		(property "Value" ""
			(at 0 0 90)
			(layer "B.Fab")
			(effects
				(font
					(size 1.27 1.27)
				)
				(justify mirror)
			)
		)
		(duplicate_pad_numbers_are_jumpers no)
		(fp_line
			(start -0.7874 0.4064)
			(end 0.7874 0.4064)
			(stroke
				(width 0.1524)
				(type default)
			)
			(layer "B.SilkS")
		)
		(fp_line
			(start 0.7874 0.4064)
			(end 0.7874 -0.4064)
			(stroke
				(width 0.1524)
				(type default)
			)
			(layer "B.SilkS")
		)
		(fp_line
			(start -0.7874 -0.4064)
			(end -0.7874 0.4064)
			(stroke
				(width 0.1524)
				(type default)
			)
			(layer "B.SilkS")
		)
		(fp_line
			(start 0.7874 -0.4064)
			(end -0.7874 -0.4064)
			(stroke
				(width 0.1524)
				(type default)
			)
			(layer "B.SilkS")
		)
		(fp_line
			(start -0.67945 0.3048)
			(end -0.120396 0.3048)
			(stroke
				(width 0.1)
				(type default)
			)
			(layer "B.Fab")
		)
		(fp_line
			(start -0.120396 0.3048)
			(end -0.120396 0.2794)
			(stroke
				(width 0.1)
				(type default)
			)
			(layer "B.Fab")
		)
		(fp_line
			(start 0.12065 0.3048)
			(end 0.67945 0.3048)
			(stroke
				(width 0.1)
				(type default)
			)
			(layer "B.Fab")
		)
		(fp_line
			(start 0.67945 0.3048)
			(end 0.67945 -0.305054)
			(stroke
				(width 0.1)
				(type default)
			)
			(layer "B.Fab")
		)
		(fp_line
			(start -0.120396 0.2794)
			(end 0.12065 0.2794)
			(stroke
				(width 0.1)
				(type default)
			)
			(layer "B.Fab")
		)
		(fp_line
			(start 0.12065 0.2794)
			(end 0.12065 0.3048)
			(stroke
				(width 0.1)
				(type default)
			)
			(layer "B.Fab")
		)
		(fp_line
			(start -0.12065 -0.2794)
			(end -0.12065 -0.3048)
			(stroke
				(width 0.1)
				(type default)
			)
			(layer "B.Fab")
		)
		(fp_line
			(start 0.12065 -0.2794)
			(end -0.12065 -0.2794)
			(stroke
				(width 0.1)
				(type default)
			)
			(layer "B.Fab")
		)
		(fp_line
			(start -0.67945 -0.3048)
			(end -0.67945 0.3048)
			(stroke
				(width 0.1)
				(type default)
			)
			(layer "B.Fab")
		)
		(fp_line
			(start -0.12065 -0.3048)
			(end -0.67945 -0.3048)
			(stroke
				(width 0.1)
				(type default)
			)
			(layer "B.Fab")
		)
		(fp_line
			(start 0.12065 -0.305054)
			(end 0.12065 -0.2794)
			(stroke
				(width 0.1)
				(type default)
			)
			(layer "B.Fab")
		)
		(fp_line
			(start 0.67945 -0.305054)
			(end 0.12065 -0.305054)
			(stroke
				(width 0.1)
				(type default)
			)
			(layer "B.Fab")
		)
		(pad "1" smd circle
			(at 0.40005 0 90)
			(size 0 0)
			(layers "B.Cu" "B.Mask" "B.Paste")
			(net "PVDDCR_CPU1_P0_VOS3")
		)
		(pad "2" smd circle
			(at -0.40005 0 90)
			(size 0 0)
			(layers "B.Cu" "B.Mask" "B.Paste")
			(net "PVDDCR_CPU1_P0")
		)
	)
	(footprint ""
		(layer "B.Cu")
		(at 365.328454 -251.78131)
		(property "Reference" "C2541"
			(at 0 0 0)
			(layer "B.SilkS")
			(hide yes)
			(effects
				(font
					(size 1.27 1.27)
				)
				(justify mirror)
			)
		)
		(property "Value" ""
			(at 0 0 0)
			(layer "B.Fab")
			(effects
				(font
					(size 1.27 1.27)
				)
				(justify mirror)
			)
		)
		(duplicate_pad_numbers_are_jumpers no)
		(fp_line
			(start -0.7874 -0.4064)
			(end -0.7874 0.4064)
			(stroke
				(width 0.1524)
				(type default)
			)
			(layer "B.SilkS")
		)
		(fp_line
			(start -0.7874 0.4064)
			(end 0.7874 0.4064)
			(stroke
				(width 0.1524)
				(type default)
			)
			(layer "B.SilkS")
		)
		(fp_line
			(start 0.7874 -0.4064)
			(end -0.7874 -0.4064)
			(stroke
				(width 0.1524)
				(type default)
			)
			(layer "B.SilkS")
		)
		(fp_line
			(start 0.7874 0.4064)
			(end 0.7874 -0.4064)
			(stroke
				(width 0.1524)
				(type default)
			)
			(layer "B.SilkS")
		)
		(fp_line
			(start -0.67945 -0.3048)
			(end -0.67945 0.3048)
			(stroke
				(width 0.1)
				(type default)
			)
			(layer "B.Fab")
		)
		(fp_line
			(start -0.67945 0.3048)
			(end -0.120396 0.3048)
			(stroke
				(width 0.1)
				(type default)
			)
			(layer "B.Fab")
		)
		(fp_line
			(start -0.12065 -0.3048)
			(end -0.67945 -0.3048)
			(stroke
				(width 0.1)
				(type default)
			)
			(layer "B.Fab")
		)
		(fp_line
			(start -0.12065 -0.2794)
			(end -0.12065 -0.3048)
			(stroke
				(width 0.1)
				(type default)
			)
			(layer "B.Fab")
		)
		(fp_line
			(start -0.120396 0.2794)
			(end 0.12065 0.2794)
			(stroke
				(width 0.1)
				(type default)
			)
			(layer "B.Fab")
		)
		(fp_line
			(start -0.120396 0.3048)
			(end -0.120396 0.2794)
			(stroke
				(width 0.1)
				(type default)
			)
			(layer "B.Fab")
		)
		(fp_line
			(start 0.12065 -0.305054)
			(end 0.12065 -0.2794)
			(stroke
				(width 0.1)
				(type default)
			)
			(layer "B.Fab")
		)
		(fp_line
			(start 0.12065 -0.2794)
			(end -0.12065 -0.2794)
			(stroke
				(width 0.1)
				(type default)
			)
			(layer "B.Fab")
		)
		(fp_line
			(start 0.12065 0.2794)
			(end 0.12065 0.3048)
			(stroke
				(width 0.1)
				(type default)
			)
			(layer "B.Fab")
		)
		(fp_line
			(start 0.12065 0.3048)
			(end 0.67945 0.3048)
			(stroke
				(width 0.1)
				(type default)
			)
			(layer "B.Fab")
		)
		(fp_line
			(start 0.67945 -0.305054)
			(end 0.12065 -0.305054)
			(stroke
				(width 0.1)
				(type default)
			)
			(layer "B.Fab")
		)
		(fp_line
			(start 0.67945 0.3048)
			(end 0.67945 -0.305054)
			(stroke
				(width 0.1)
				(type default)
			)
			(layer "B.Fab")
		)
		(pad "1" smd circle
			(at 0.40005 0 180)
			(size 0 0)
			(layers "B.Cu" "B.Mask" "B.Paste")
			(net "PVDDCR_SOC_P0")
		)
		(pad "2" smd circle
			(at -0.40005 0 180)
			(size 0 0)
			(layers "B.Cu" "B.Mask" "B.Paste")
			(net "GND")
		)
	)
	(footprint ""
		(layer "B.Cu")
		(at 74.720704 -408.517344 90)
		(property "Reference" "C6677"
			(at 0 0 90)
			(layer "B.SilkS")
			(hide yes)
			(effects
				(font
					(size 1.27 1.27)
				)
				(justify mirror)
			)
		)
		(property "Value" ""
			(at 0 0 90)
			(layer "B.Fab")
			(effects
				(font
					(size 1.27 1.27)
				)
				(justify mirror)
			)
		)
		(duplicate_pad_numbers_are_jumpers no)
		(fp_line
			(start 0.299974 -0.150114)
			(end -0.299974 -0.150114)
			(stroke
				(width 0.1)
				(type default)
			)
			(layer "B.Fab")
		)
		(fp_line
			(start -0.299974 -0.150114)
			(end -0.299974 0.150114)
			(stroke
				(width 0.1)
				(type default)
			)
			(layer "B.Fab")
		)
		(fp_line
			(start 0.299974 0.150114)
			(end 0.299974 -0.150114)
			(stroke
				(width 0.1)
				(type default)
			)
			(layer "B.Fab")
		)
		(fp_line
			(start -0.299974 0.150114)
			(end 0.299974 0.150114)
			(stroke
				(width 0.1)
				(type default)
			)
			(layer "B.Fab")
		)
		(pad "1" smd rect
			(at 0.2667 0 270)
			(size 0.3048 0.381)
			(layers "B.Cu" "B.Mask" "B.Paste")
			(net "P5E_CPU1_P1_TX_BUF_C_DP<8>")
		)
		(pad "2" smd rect
			(at -0.2667 0 270)
			(size 0.3048 0.381)
			(layers "B.Cu" "B.Mask" "B.Paste")
			(net "P5E_CPU1_P1_TX_BUF_DP<8>")
		)
	)
	(footprint ""
		(layer "B.Cu")
		(at 318.43726 -328.240644 -90)
		(property "Reference" "PC97"
			(at 9.490456 -0.314706 270)
			(unlocked yes)
			(layer "B.SilkS")
			(effects
				(font
					(size 0.7874 0.5842)
					(thickness 0.1524)
				)
				(justify left mirror)
			)
		)
		(property "Value" ""
			(at 0 0 90)
			(layer "B.Fab")
			(effects
				(font
					(size 1.27 1.27)
				)
				(justify mirror)
			)
		)
		(duplicate_pad_numbers_are_jumpers no)
		(fp_line
			(start -4.533392 2.249932)
			(end 4.533392 2.249932)
			(stroke
				(width 0.1524)
				(type default)
			)
			(layer "B.SilkS")
		)
		(fp_line
			(start 4.533392 2.249932)
			(end 4.533392 -2.249932)
			(stroke
				(width 0.1524)
				(type default)
			)
			(layer "B.SilkS")
		)
		(fp_line
			(start -4.533392 -2.249932)
			(end -4.533392 2.249932)
			(stroke
				(width 0.1524)
				(type default)
			)
			(layer "B.SilkS")
		)
		(fp_line
			(start 4.533392 -2.249932)
			(end -4.533392 -2.249932)
			(stroke
				(width 0.1524)
				(type default)
			)
			(layer "B.SilkS")
		)
		(fp_rect
			(start 5.39242 2.326132)
			(end 4.533392 -2.326132)
			(stroke
				(width 0)
				(type default)
			)
			(fill yes)
			(layer "B.SilkS")
		)
		(fp_line
			(start -3.750056 2.249932)
			(end 3.750056 2.249932)
			(stroke
				(width 0.1)
				(type default)
			)
			(layer "B.Fab")
		)
		(fp_line
			(start 3.750056 2.249932)
			(end 3.750056 -2.249932)
			(stroke
				(width 0.1)
				(type default)
			)
			(layer "B.Fab")
		)
		(fp_line
			(start -3.750056 -2.249932)
			(end -3.750056 2.249932)
			(stroke
				(width 0.1)
				(type default)
			)
			(layer "B.Fab")
		)
		(fp_line
			(start 3.750056 -2.249932)
			(end -3.750056 -2.249932)
			(stroke
				(width 0.1)
				(type default)
			)
			(layer "B.Fab")
		)
		(fp_text user "-"
			(at -4.77012 2.405634 270)
			(unlocked yes)
			(layer "B.SilkS")
			(effects
				(font
					(size 1.905 1.4224)
					(thickness 0.1524)
				)
				(justify left mirror)
			)
		)
		(fp_text user "+"
			(at 6.322314 0.786384 180)
			(unlocked yes)
			(layer "B.SilkS")
			(effects
				(font
					(size 1.905 1.4224)
					(thickness 0.1524)
				)
				(justify left mirror)
			)
		)
		(fp_text user "+"
			(at 6.322314 0.786384 180)
			(unlocked yes)
			(layer "B.Fab")
			(effects
				(font
					(size 1.905 1.4224)
					(thickness 0.1524)
				)
				(justify left mirror)
			)
		)
		(fp_text user "-"
			(at -4.8514 -0.14605 270)
			(unlocked yes)
			(layer "B.Fab")
			(effects
				(font
					(size 1.905 1.4224)
					(thickness 0.1524)
				)
				(justify left mirror)
			)
		)
		(pad "1" smd rect
			(at 3.199892 0 90)
			(size 2.413 2.8194)
			(layers "B.Cu" "B.Mask" "B.Paste")
			(net "PVDDCR_CPU1_P0")
		)
		(pad "2" smd rect
			(at -3.199892 0 90)
			(size 2.413 2.8194)
			(layers "B.Cu" "B.Mask" "B.Paste")
			(net "GND")
		)
	)
	(footprint ""
		(layer "B.Cu")
		(at 206.429356 -377.666504 180)
		(property "Reference" "PR2520"
			(at 0 0 0)
			(layer "B.SilkS")
			(hide yes)
			(effects
				(font
					(size 1.27 1.27)
				)
				(justify mirror)
			)
		)
		(property "Value" ""
			(at 0 0 0)
			(layer "B.Fab")
			(effects
				(font
					(size 1.27 1.27)
				)
				(justify mirror)
			)
		)
		(duplicate_pad_numbers_are_jumpers no)
		(fp_line
			(start 0.7874 0.4064)
			(end 0.7874 -0.4064)
			(stroke
				(width 0.1524)
				(type default)
			)
			(layer "B.SilkS")
		)
		(fp_line
			(start 0.7874 -0.4064)
			(end -0.7874 -0.4064)
			(stroke
				(width 0.1524)
				(type default)
			)
			(layer "B.SilkS")
		)
		(fp_line
			(start -0.7874 0.4064)
			(end 0.7874 0.4064)
			(stroke
				(width 0.1524)
				(type default)
			)
			(layer "B.SilkS")
		)
		(fp_line
			(start -0.7874 -0.4064)
			(end -0.7874 0.4064)
			(stroke
				(width 0.1524)
				(type default)
			)
			(layer "B.SilkS")
		)
		(fp_line
			(start 0.67945 0.3048)
			(end 0.67945 -0.305054)
			(stroke
				(width 0.1)
				(type default)
			)
			(layer "B.Fab")
		)
		(fp_line
			(start 0.67945 -0.305054)
			(end 0.12065 -0.305054)
			(stroke
				(width 0.1)
				(type default)
			)
			(layer "B.Fab")
		)
		(fp_line
			(start 0.12065 0.3048)
			(end 0.67945 0.3048)
			(stroke
				(width 0.1)
				(type default)
			)
			(layer "B.Fab")
		)
		(fp_line
			(start 0.12065 0.2794)
			(end 0.12065 0.3048)
			(stroke
				(width 0.1)
				(type default)
			)
			(layer "B.Fab")
		)
		(fp_line
			(start 0.12065 -0.2794)
			(end -0.12065 -0.2794)
			(stroke
				(width 0.1)
				(type default)
			)
			(layer "B.Fab")
		)
		(fp_line
			(start 0.12065 -0.305054)
			(end 0.12065 -0.2794)
			(stroke
				(width 0.1)
				(type default)
			)
			(layer "B.Fab")
		)
		(fp_line
			(start -0.120396 0.3048)
			(end -0.120396 0.2794)
			(stroke
				(width 0.1)
				(type default)
			)
			(layer "B.Fab")
		)
		(fp_line
			(start -0.120396 0.2794)
			(end 0.12065 0.2794)
			(stroke
				(width 0.1)
				(type default)
			)
			(layer "B.Fab")
		)
		(fp_line
			(start -0.12065 -0.2794)
			(end -0.12065 -0.3048)
			(stroke
				(width 0.1)
				(type default)
			)
			(layer "B.Fab")
		)
		(fp_line
			(start -0.12065 -0.3048)
			(end -0.67945 -0.3048)
			(stroke
				(width 0.1)
				(type default)
			)
			(layer "B.Fab")
		)
		(fp_line
			(start -0.67945 0.3048)
			(end -0.120396 0.3048)
			(stroke
				(width 0.1)
				(type default)
			)
			(layer "B.Fab")
		)
		(fp_line
			(start -0.67945 -0.3048)
			(end -0.67945 0.3048)
			(stroke
				(width 0.1)
				(type default)
			)
			(layer "B.Fab")
		)
		(pad "1" smd circle
			(at 0.40005 0)
			(size 0 0)
			(layers "B.Cu" "B.Mask" "B.Paste")
			(net "P12V_HSC_SENSE2_P")
		)
		(pad "2" smd circle
			(at -0.40005 0)
			(size 0 0)
			(layers "B.Cu" "B.Mask" "B.Paste")
			(net "P12V_HSC_SENSE2_R1_P")
		)
	)
	(footprint ""
		(layer "B.Cu")
		(at 439.020966 -420.231824 180)
		(property "Reference" "R6801"
			(at 0 0 0)
			(layer "B.SilkS")
			(hide yes)
			(effects
				(font
					(size 1.27 1.27)
				)
				(justify mirror)
			)
		)
		(property "Value" ""
			(at 0 0 0)
			(layer "B.Fab")
			(effects
				(font
					(size 1.27 1.27)
				)
				(justify mirror)
			)
		)
		(duplicate_pad_numbers_are_jumpers no)
		(fp_line
			(start 0.7874 0.4064)
			(end 0.7874 -0.4064)
			(stroke
				(width 0.1524)
				(type default)
			)
			(layer "B.SilkS")
		)
		(fp_line
			(start 0.7874 -0.4064)
			(end -0.7874 -0.4064)
			(stroke
				(width 0.1524)
				(type default)
			)
			(layer "B.SilkS")
		)
		(fp_line
			(start -0.7874 0.4064)
			(end 0.7874 0.4064)
			(stroke
				(width 0.1524)
				(type default)
			)
			(layer "B.SilkS")
		)
		(fp_line
			(start -0.7874 -0.4064)
			(end -0.7874 0.4064)
			(stroke
				(width 0.1524)
				(type default)
			)
			(layer "B.SilkS")
		)
		(fp_line
			(start 0.67945 0.3048)
			(end 0.67945 -0.305054)
			(stroke
				(width 0.1)
				(type default)
			)
			(layer "B.Fab")
		)
		(fp_line
			(start 0.67945 -0.305054)
			(end 0.12065 -0.305054)
			(stroke
				(width 0.1)
				(type default)
			)
			(layer "B.Fab")
		)
		(fp_line
			(start 0.12065 0.3048)
			(end 0.67945 0.3048)
			(stroke
				(width 0.1)
				(type default)
			)
			(layer "B.Fab")
		)
		(fp_line
			(start 0.12065 0.2794)
			(end 0.12065 0.3048)
			(stroke
				(width 0.1)
				(type default)
			)
			(layer "B.Fab")
		)
		(fp_line
			(start 0.12065 -0.2794)
			(end -0.12065 -0.2794)
			(stroke
				(width 0.1)
				(type default)
			)
			(layer "B.Fab")
		)
		(fp_line
			(start 0.12065 -0.305054)
			(end 0.12065 -0.2794)
			(stroke
				(width 0.1)
				(type default)
			)
			(layer "B.Fab")
		)
		(fp_line
			(start -0.120396 0.3048)
			(end -0.120396 0.2794)
			(stroke
				(width 0.1)
				(type default)
			)
			(layer "B.Fab")
		)
		(fp_line
			(start -0.120396 0.2794)
			(end 0.12065 0.2794)
			(stroke
				(width 0.1)
				(type default)
			)
			(layer "B.Fab")
		)
		(fp_line
			(start -0.12065 -0.2794)
			(end -0.12065 -0.3048)
			(stroke
				(width 0.1)
				(type default)
			)
			(layer "B.Fab")
		)
		(fp_line
			(start -0.12065 -0.3048)
			(end -0.67945 -0.3048)
			(stroke
				(width 0.1)
				(type default)
			)
			(layer "B.Fab")
		)
		(fp_line
			(start -0.67945 0.3048)
			(end -0.120396 0.3048)
			(stroke
				(width 0.1)
				(type default)
			)
			(layer "B.Fab")
		)
		(fp_line
			(start -0.67945 -0.3048)
			(end -0.67945 0.3048)
			(stroke
				(width 0.1)
				(type default)
			)
			(layer "B.Fab")
		)
		(pad "1" smd circle
			(at 0.40005 0)
			(size 0 0)
			(layers "B.Cu" "B.Mask" "B.Paste")
			(net "GND")
		)
		(pad "2" smd circle
			(at -0.40005 0)
			(size 0 0)
			(layers "B.Cu" "B.Mask" "B.Paste")
			(net "P0V9_RETIMER_CPU0_EN1_R")
		)
	)
	(footprint ""
		(layer "B.Cu")
		(at 90.37193 -335.04632 90)
		(property "Reference" "PC384_1"
			(at 0 0 90)
			(layer "B.SilkS")
			(hide yes)
			(effects
				(font
					(size 1.27 1.27)
				)
				(justify mirror)
			)
		)
		(property "Value" ""
			(at 0 0 90)
			(layer "B.Fab")
			(effects
				(font
					(size 1.27 1.27)
				)
				(justify mirror)
			)
		)
		(duplicate_pad_numbers_are_jumpers no)
		(fp_line
			(start 1.524 -0.762)
			(end -1.524 -0.762)
			(stroke
				(width 0.1524)
				(type default)
			)
			(layer "B.SilkS")
		)
		(fp_line
			(start -1.524 -0.762)
			(end -1.524 0.762)
			(stroke
				(width 0.1524)
				(type default)
			)
			(layer "B.SilkS")
		)
		(fp_line
			(start 1.524 0.762)
			(end 1.524 -0.762)
			(stroke
				(width 0.1524)
				(type default)
			)
			(layer "B.SilkS")
		)
		(fp_line
			(start -1.524 0.762)
			(end 1.524 0.762)
			(stroke
				(width 0.1524)
				(type default)
			)
			(layer "B.SilkS")
		)
		(fp_line
			(start 1.1049 -0.724916)
			(end 1.1049 0.724916)
			(stroke
				(width 0.1)
				(type default)
			)
			(layer "B.Fab")
		)
		(fp_line
			(start -1.1049 -0.724916)
			(end 1.1049 -0.724916)
			(stroke
				(width 0.1)
				(type default)
			)
			(layer "B.Fab")
		)
		(fp_line
			(start 1.1049 0.724916)
			(end -1.1049 0.724916)
			(stroke
				(width 0.1)
				(type default)
			)
			(layer "B.Fab")
		)
		(fp_line
			(start -1.1049 0.724916)
			(end -1.1049 -0.724916)
			(stroke
				(width 0.1)
				(type default)
			)
			(layer "B.Fab")
		)
		(pad "1" smd rect
			(at 0.889 0 90)
			(size 1.016 1.27)
			(layers "B.Cu" "B.Mask" "B.Paste")
			(net "SW_P12V_AUX_PVDDCR_CPU1_P1_FLT")
		)
		(pad "2" smd rect
			(at -0.889 0 90)
			(size 1.016 1.27)
			(layers "B.Cu" "B.Mask" "B.Paste")
			(net "GND")
		)
	)
	(footprint ""
		(layer "B.Cu")
		(at 303.378362 -395.148562 90)
		(property "Reference" "C521"
			(at 0 0 90)
			(layer "B.SilkS")
			(hide yes)
			(effects
				(font
					(size 1.27 1.27)
				)
				(justify mirror)
			)
		)
		(property "Value" ""
			(at 0 0 90)
			(layer "B.Fab")
			(effects
				(font
					(size 1.27 1.27)
				)
				(justify mirror)
			)
		)
		(duplicate_pad_numbers_are_jumpers no)
		(fp_line
			(start 0.299974 -0.150114)
			(end -0.299974 -0.150114)
			(stroke
				(width 0.1)
				(type default)
			)
			(layer "B.Fab")
		)
		(fp_line
			(start -0.299974 -0.150114)
			(end -0.299974 0.150114)
			(stroke
				(width 0.1)
				(type default)
			)
			(layer "B.Fab")
		)
		(fp_line
			(start 0.299974 0.150114)
			(end 0.299974 -0.150114)
			(stroke
				(width 0.1)
				(type default)
			)
			(layer "B.Fab")
		)
		(fp_line
			(start -0.299974 0.150114)
			(end 0.299974 0.150114)
			(stroke
				(width 0.1)
				(type default)
			)
			(layer "B.Fab")
		)
		(pad "1" smd rect
			(at 0.2667 0 270)
			(size 0.3048 0.381)
			(layers "B.Cu" "B.Mask" "B.Paste")
			(net "P0V9_CPU0_RT0_2A")
		)
		(pad "2" smd rect
			(at -0.2667 0 270)
			(size 0.3048 0.381)
			(layers "B.Cu" "B.Mask" "B.Paste")
			(net "GND")
		)
	)
	(footprint ""
		(layer "B.Cu")
		(at 128.891284 -390.560052 90)
		(property "Reference" "C499"
			(at 0 0 90)
			(layer "B.SilkS")
			(hide yes)
			(effects
				(font
					(size 1.27 1.27)
				)
				(justify mirror)
			)
		)
		(property "Value" ""
			(at 0 0 90)
			(layer "B.Fab")
			(effects
				(font
					(size 1.27 1.27)
				)
				(justify mirror)
			)
		)
		(duplicate_pad_numbers_are_jumpers no)
		(fp_line
			(start 0.7874 -0.4064)
			(end -0.7874 -0.4064)
			(stroke
				(width 0.1524)
				(type default)
			)
			(layer "B.SilkS")
		)
		(fp_line
			(start -0.7874 -0.4064)
			(end -0.7874 0.4064)
			(stroke
				(width 0.1524)
				(type default)
			)
			(layer "B.SilkS")
		)
		(fp_line
			(start 0.7874 0.4064)
			(end 0.7874 -0.4064)
			(stroke
				(width 0.1524)
				(type default)
			)
			(layer "B.SilkS")
		)
		(fp_line
			(start -0.7874 0.4064)
			(end 0.7874 0.4064)
			(stroke
				(width 0.1524)
				(type default)
			)
			(layer "B.SilkS")
		)
		(fp_line
			(start 0.67945 -0.305054)
			(end 0.12065 -0.305054)
			(stroke
				(width 0.1)
				(type default)
			)
			(layer "B.Fab")
		)
		(fp_line
			(start 0.12065 -0.305054)
			(end 0.12065 -0.2794)
			(stroke
				(width 0.1)
				(type default)
			)
			(layer "B.Fab")
		)
		(fp_line
			(start -0.12065 -0.3048)
			(end -0.67945 -0.3048)
			(stroke
				(width 0.1)
				(type default)
			)
			(layer "B.Fab")
		)
		(fp_line
			(start -0.67945 -0.3048)
			(end -0.67945 0.3048)
			(stroke
				(width 0.1)
				(type default)
			)
			(layer "B.Fab")
		)
		(fp_line
			(start 0.12065 -0.2794)
			(end -0.12065 -0.2794)
			(stroke
				(width 0.1)
				(type default)
			)
			(layer "B.Fab")
		)
		(fp_line
			(start -0.12065 -0.2794)
			(end -0.12065 -0.3048)
			(stroke
				(width 0.1)
				(type default)
			)
			(layer "B.Fab")
		)
		(fp_line
			(start 0.12065 0.2794)
			(end 0.12065 0.3048)
			(stroke
				(width 0.1)
				(type default)
			)
			(layer "B.Fab")
		)
		(fp_line
			(start -0.120396 0.2794)
			(end 0.12065 0.2794)
			(stroke
				(width 0.1)
				(type default)
			)
			(layer "B.Fab")
		)
		(fp_line
			(start 0.67945 0.3048)
			(end 0.67945 -0.305054)
			(stroke
				(width 0.1)
				(type default)
			)
			(layer "B.Fab")
		)
		(fp_line
			(start 0.12065 0.3048)
			(end 0.67945 0.3048)
			(stroke
				(width 0.1)
				(type default)
			)
			(layer "B.Fab")
		)
		(fp_line
			(start -0.120396 0.3048)
			(end -0.120396 0.2794)
			(stroke
				(width 0.1)
				(type default)
			)
			(layer "B.Fab")
		)
		(fp_line
			(start -0.67945 0.3048)
			(end -0.120396 0.3048)
			(stroke
				(width 0.1)
				(type default)
			)
			(layer "B.Fab")
		)
		(pad "1" smd circle
			(at 0.40005 0 270)
			(size 0 0)
			(layers "B.Cu" "B.Mask" "B.Paste")
			(net "P0V9_CPU1_RT3_2A")
		)
		(pad "2" smd circle
			(at -0.40005 0 270)
			(size 0 0)
			(layers "B.Cu" "B.Mask" "B.Paste")
			(net "GND")
		)
	)
	(footprint ""
		(layer "B.Cu")
		(at 110.039404 -28.70327 -90)
		(property "Reference" "C6104"
			(at 0 0 90)
			(layer "B.SilkS")
			(hide yes)
			(effects
				(font
					(size 1.27 1.27)
				)
				(justify mirror)
			)
		)
		(property "Value" ""
			(at 0 0 90)
			(layer "B.Fab")
			(effects
				(font
					(size 1.27 1.27)
				)
				(justify mirror)
			)
		)
		(duplicate_pad_numbers_are_jumpers no)
		(fp_line
			(start -0.7874 0.4064)
			(end 0.7874 0.4064)
			(stroke
				(width 0.1524)
				(type default)
			)
			(layer "B.SilkS")
		)
		(fp_line
			(start 0.7874 0.4064)
			(end 0.7874 -0.4064)
			(stroke
				(width 0.1524)
				(type default)
			)
			(layer "B.SilkS")
		)
		(fp_line
			(start -0.7874 -0.4064)
			(end -0.7874 0.4064)
			(stroke
				(width 0.1524)
				(type default)
			)
			(layer "B.SilkS")
		)
		(fp_line
			(start 0.7874 -0.4064)
			(end -0.7874 -0.4064)
			(stroke
				(width 0.1524)
				(type default)
			)
			(layer "B.SilkS")
		)
		(fp_line
			(start -0.67945 0.3048)
			(end -0.120396 0.3048)
			(stroke
				(width 0.1)
				(type default)
			)
			(layer "B.Fab")
		)
		(fp_line
			(start -0.120396 0.3048)
			(end -0.120396 0.2794)
			(stroke
				(width 0.1)
				(type default)
			)
			(layer "B.Fab")
		)
		(fp_line
			(start 0.12065 0.3048)
			(end 0.67945 0.3048)
			(stroke
				(width 0.1)
				(type default)
			)
			(layer "B.Fab")
		)
		(fp_line
			(start 0.67945 0.3048)
			(end 0.67945 -0.305054)
			(stroke
				(width 0.1)
				(type default)
			)
			(layer "B.Fab")
		)
		(fp_line
			(start -0.120396 0.2794)
			(end 0.12065 0.2794)
			(stroke
				(width 0.1)
				(type default)
			)
			(layer "B.Fab")
		)
		(fp_line
			(start 0.12065 0.2794)
			(end 0.12065 0.3048)
			(stroke
				(width 0.1)
				(type default)
			)
			(layer "B.Fab")
		)
		(fp_line
			(start -0.12065 -0.2794)
			(end -0.12065 -0.3048)
			(stroke
				(width 0.1)
				(type default)
			)
			(layer "B.Fab")
		)
		(fp_line
			(start 0.12065 -0.2794)
			(end -0.12065 -0.2794)
			(stroke
				(width 0.1)
				(type default)
			)
			(layer "B.Fab")
		)
		(fp_line
			(start -0.67945 -0.3048)
			(end -0.67945 0.3048)
			(stroke
				(width 0.1)
				(type default)
			)
			(layer "B.Fab")
		)
		(fp_line
			(start -0.12065 -0.3048)
			(end -0.67945 -0.3048)
			(stroke
				(width 0.1)
				(type default)
			)
			(layer "B.Fab")
		)
		(fp_line
			(start 0.12065 -0.305054)
			(end 0.12065 -0.2794)
			(stroke
				(width 0.1)
				(type default)
			)
			(layer "B.Fab")
		)
		(fp_line
			(start 0.67945 -0.305054)
			(end 0.12065 -0.305054)
			(stroke
				(width 0.1)
				(type default)
			)
			(layer "B.Fab")
		)
		(pad "1" smd circle
			(at 0.40005 0 90)
			(size 0 0)
			(layers "B.Cu" "B.Mask" "B.Paste")
			(net "P3V3_AUX_CPU0_USB2_AVDD33")
		)
		(pad "2" smd circle
			(at -0.40005 0 90)
			(size 0 0)
			(layers "B.Cu" "B.Mask" "B.Paste")
			(net "GND")
		)
	)
	(footprint ""
		(layer "B.Cu")
		(at 303.268126 -192.660016 180)
		(property "Reference" "C142"
			(at 0 0 0)
			(layer "B.SilkS")
			(hide yes)
			(effects
				(font
					(size 1.27 1.27)
				)
				(justify mirror)
			)
		)
		(property "Value" ""
			(at 0 0 0)
			(layer "B.Fab")
			(effects
				(font
					(size 1.27 1.27)
				)
				(justify mirror)
			)
		)
		(duplicate_pad_numbers_are_jumpers no)
		(fp_line
			(start 1.524 0.762)
			(end 1.524 -0.762)
			(stroke
				(width 0.1524)
				(type default)
			)
			(layer "B.SilkS")
		)
		(fp_line
			(start 1.524 -0.762)
			(end -1.524 -0.762)
			(stroke
				(width 0.1524)
				(type default)
			)
			(layer "B.SilkS")
		)
		(fp_line
			(start -1.524 0.762)
			(end 1.524 0.762)
			(stroke
				(width 0.1524)
				(type default)
			)
			(layer "B.SilkS")
		)
		(fp_line
			(start -1.524 -0.762)
			(end -1.524 0.762)
			(stroke
				(width 0.1524)
				(type default)
			)
			(layer "B.SilkS")
		)
		(fp_line
			(start 1.1049 0.724916)
			(end -1.1049 0.724916)
			(stroke
				(width 0.1)
				(type default)
			)
			(layer "B.Fab")
		)
		(fp_line
			(start 1.1049 -0.724916)
			(end 1.1049 0.724916)
			(stroke
				(width 0.1)
				(type default)
			)
			(layer "B.Fab")
		)
		(fp_line
			(start -1.1049 0.724916)
			(end -1.1049 -0.724916)
			(stroke
				(width 0.1)
				(type default)
			)
			(layer "B.Fab")
		)
		(fp_line
			(start -1.1049 -0.724916)
			(end 1.1049 -0.724916)
			(stroke
				(width 0.1)
				(type default)
			)
			(layer "B.Fab")
		)
		(pad "1" smd rect
			(at 0.889 0 180)
			(size 1.016 1.27)
			(layers "B.Cu" "B.Mask" "B.Paste")
			(net "P12V_MEM_CPU0")
		)
		(pad "2" smd rect
			(at -0.889 0 180)
			(size 1.016 1.27)
			(layers "B.Cu" "B.Mask" "B.Paste")
			(net "GND")
		)
	)
	(footprint ""
		(layer "B.Cu")
		(at 190.881 -97.119948 -90)
		(property "Reference" "R260"
			(at 0 0 90)
			(layer "B.SilkS")
			(hide yes)
			(effects
				(font
					(size 1.27 1.27)
				)
				(justify mirror)
			)
		)
		(property "Value" ""
			(at 0 0 90)
			(layer "B.Fab")
			(effects
				(font
					(size 1.27 1.27)
				)
				(justify mirror)
			)
		)
		(duplicate_pad_numbers_are_jumpers no)
		(fp_line
			(start -0.7874 0.4064)
			(end 0.7874 0.4064)
			(stroke
				(width 0.1524)
				(type default)
			)
			(layer "B.SilkS")
		)
		(fp_line
			(start 0.7874 0.4064)
			(end 0.7874 -0.4064)
			(stroke
				(width 0.1524)
				(type default)
			)
			(layer "B.SilkS")
		)
		(fp_line
			(start -0.7874 -0.4064)
			(end -0.7874 0.4064)
			(stroke
				(width 0.1524)
				(type default)
			)
			(layer "B.SilkS")
		)
		(fp_line
			(start 0.7874 -0.4064)
			(end -0.7874 -0.4064)
			(stroke
				(width 0.1524)
				(type default)
			)
			(layer "B.SilkS")
		)
		(fp_line
			(start -0.67945 0.3048)
			(end -0.120396 0.3048)
			(stroke
				(width 0.1)
				(type default)
			)
			(layer "B.Fab")
		)
		(fp_line
			(start -0.120396 0.3048)
			(end -0.120396 0.2794)
			(stroke
				(width 0.1)
				(type default)
			)
			(layer "B.Fab")
		)
		(fp_line
			(start 0.12065 0.3048)
			(end 0.67945 0.3048)
			(stroke
				(width 0.1)
				(type default)
			)
			(layer "B.Fab")
		)
		(fp_line
			(start 0.67945 0.3048)
			(end 0.67945 -0.305054)
			(stroke
				(width 0.1)
				(type default)
			)
			(layer "B.Fab")
		)
		(fp_line
			(start -0.120396 0.2794)
			(end 0.12065 0.2794)
			(stroke
				(width 0.1)
				(type default)
			)
			(layer "B.Fab")
		)
		(fp_line
			(start 0.12065 0.2794)
			(end 0.12065 0.3048)
			(stroke
				(width 0.1)
				(type default)
			)
			(layer "B.Fab")
		)
		(fp_line
			(start -0.12065 -0.2794)
			(end -0.12065 -0.3048)
			(stroke
				(width 0.1)
				(type default)
			)
			(layer "B.Fab")
		)
		(fp_line
			(start 0.12065 -0.2794)
			(end -0.12065 -0.2794)
			(stroke
				(width 0.1)
				(type default)
			)
			(layer "B.Fab")
		)
		(fp_line
			(start -0.67945 -0.3048)
			(end -0.67945 0.3048)
			(stroke
				(width 0.1)
				(type default)
			)
			(layer "B.Fab")
		)
		(fp_line
			(start -0.12065 -0.3048)
			(end -0.67945 -0.3048)
			(stroke
				(width 0.1)
				(type default)
			)
			(layer "B.Fab")
		)
		(fp_line
			(start 0.12065 -0.305054)
			(end 0.12065 -0.2794)
			(stroke
				(width 0.1)
				(type default)
			)
			(layer "B.Fab")
		)
		(fp_line
			(start 0.67945 -0.305054)
			(end 0.12065 -0.305054)
			(stroke
				(width 0.1)
				(type default)
			)
			(layer "B.Fab")
		)
		(pad "1" smd circle
			(at 0.40005 0 90)
			(size 0 0)
			(layers "B.Cu" "B.Mask" "B.Paste")
			(net "CPU1_SP5R1")
		)
		(pad "2" smd circle
			(at -0.40005 0 90)
			(size 0 0)
			(layers "B.Cu" "B.Mask" "B.Paste")
			(net "FM_CPU1_SP5R1")
		)
	)
	(footprint ""
		(layer "B.Cu")
		(at 216.18448 -54.955948)
		(property "Reference" "C2069"
			(at 0 0 0)
			(layer "B.SilkS")
			(hide yes)
			(effects
				(font
					(size 1.27 1.27)
				)
				(justify mirror)
			)
		)
		(property "Value" ""
			(at 0 0 0)
			(layer "B.Fab")
			(effects
				(font
					(size 1.27 1.27)
				)
				(justify mirror)
			)
		)
		(duplicate_pad_numbers_are_jumpers no)
		(fp_line
			(start -0.7874 -0.4064)
			(end -0.7874 0.4064)
			(stroke
				(width 0.1524)
				(type default)
			)
			(layer "B.SilkS")
		)
		(fp_line
			(start -0.7874 0.4064)
			(end 0.7874 0.4064)
			(stroke
				(width 0.1524)
				(type default)
			)
			(layer "B.SilkS")
		)
		(fp_line
			(start 0.7874 -0.4064)
			(end -0.7874 -0.4064)
			(stroke
				(width 0.1524)
				(type default)
			)
			(layer "B.SilkS")
		)
		(fp_line
			(start 0.7874 0.4064)
			(end 0.7874 -0.4064)
			(stroke
				(width 0.1524)
				(type default)
			)
			(layer "B.SilkS")
		)
		(fp_line
			(start -0.67945 -0.3048)
			(end -0.67945 0.3048)
			(stroke
				(width 0.1)
				(type default)
			)
			(layer "B.Fab")
		)
		(fp_line
			(start -0.67945 0.3048)
			(end -0.120396 0.3048)
			(stroke
				(width 0.1)
				(type default)
			)
			(layer "B.Fab")
		)
		(fp_line
			(start -0.12065 -0.3048)
			(end -0.67945 -0.3048)
			(stroke
				(width 0.1)
				(type default)
			)
			(layer "B.Fab")
		)
		(fp_line
			(start -0.12065 -0.2794)
			(end -0.12065 -0.3048)
			(stroke
				(width 0.1)
				(type default)
			)
			(layer "B.Fab")
		)
		(fp_line
			(start -0.120396 0.2794)
			(end 0.12065 0.2794)
			(stroke
				(width 0.1)
				(type default)
			)
			(layer "B.Fab")
		)
		(fp_line
			(start -0.120396 0.3048)
			(end -0.120396 0.2794)
			(stroke
				(width 0.1)
				(type default)
			)
			(layer "B.Fab")
		)
		(fp_line
			(start 0.12065 -0.305054)
			(end 0.12065 -0.2794)
			(stroke
				(width 0.1)
				(type default)
			)
			(layer "B.Fab")
		)
		(fp_line
			(start 0.12065 -0.2794)
			(end -0.12065 -0.2794)
			(stroke
				(width 0.1)
				(type default)
			)
			(layer "B.Fab")
		)
		(fp_line
			(start 0.12065 0.2794)
			(end 0.12065 0.3048)
			(stroke
				(width 0.1)
				(type default)
			)
			(layer "B.Fab")
		)
		(fp_line
			(start 0.12065 0.3048)
			(end 0.67945 0.3048)
			(stroke
				(width 0.1)
				(type default)
			)
			(layer "B.Fab")
		)
		(fp_line
			(start 0.67945 -0.305054)
			(end 0.12065 -0.305054)
			(stroke
				(width 0.1)
				(type default)
			)
			(layer "B.Fab")
		)
		(fp_line
			(start 0.67945 0.3048)
			(end 0.67945 -0.305054)
			(stroke
				(width 0.1)
				(type default)
			)
			(layer "B.Fab")
		)
		(pad "1" smd circle
			(at 0.40005 0 180)
			(size 0 0)
			(layers "B.Cu" "B.Mask" "B.Paste")
			(net "P3V3_E1S_0_R")
		)
		(pad "2" smd circle
			(at -0.40005 0 180)
			(size 0 0)
			(layers "B.Cu" "B.Mask" "B.Paste")
			(net "GND")
		)
	)
	(footprint ""
		(layer "B.Cu")
		(at 304.023776 -193.99631)
		(property "Reference" "R89"
			(at 0 0 0)
			(layer "B.SilkS")
			(hide yes)
			(effects
				(font
					(size 1.27 1.27)
				)
				(justify mirror)
			)
		)
		(property "Value" ""
			(at 0 0 0)
			(layer "B.Fab")
			(effects
				(font
					(size 1.27 1.27)
				)
				(justify mirror)
			)
		)
		(duplicate_pad_numbers_are_jumpers no)
		(fp_line
			(start -0.7874 -0.4064)
			(end -0.7874 0.4064)
			(stroke
				(width 0.1524)
				(type default)
			)
			(layer "B.SilkS")
		)
		(fp_line
			(start -0.7874 0.4064)
			(end 0.7874 0.4064)
			(stroke
				(width 0.1524)
				(type default)
			)
			(layer "B.SilkS")
		)
		(fp_line
			(start 0.7874 -0.4064)
			(end -0.7874 -0.4064)
			(stroke
				(width 0.1524)
				(type default)
			)
			(layer "B.SilkS")
		)
		(fp_line
			(start 0.7874 0.4064)
			(end 0.7874 -0.4064)
			(stroke
				(width 0.1524)
				(type default)
			)
			(layer "B.SilkS")
		)
		(fp_line
			(start -0.67945 -0.3048)
			(end -0.67945 0.3048)
			(stroke
				(width 0.1)
				(type default)
			)
			(layer "B.Fab")
		)
		(fp_line
			(start -0.67945 0.3048)
			(end -0.120396 0.3048)
			(stroke
				(width 0.1)
				(type default)
			)
			(layer "B.Fab")
		)
		(fp_line
			(start -0.12065 -0.3048)
			(end -0.67945 -0.3048)
			(stroke
				(width 0.1)
				(type default)
			)
			(layer "B.Fab")
		)
		(fp_line
			(start -0.12065 -0.2794)
			(end -0.12065 -0.3048)
			(stroke
				(width 0.1)
				(type default)
			)
			(layer "B.Fab")
		)
		(fp_line
			(start -0.120396 0.2794)
			(end 0.12065 0.2794)
			(stroke
				(width 0.1)
				(type default)
			)
			(layer "B.Fab")
		)
		(fp_line
			(start -0.120396 0.3048)
			(end -0.120396 0.2794)
			(stroke
				(width 0.1)
				(type default)
			)
			(layer "B.Fab")
		)
		(fp_line
			(start 0.12065 -0.305054)
			(end 0.12065 -0.2794)
			(stroke
				(width 0.1)
				(type default)
			)
			(layer "B.Fab")
		)
		(fp_line
			(start 0.12065 -0.2794)
			(end -0.12065 -0.2794)
			(stroke
				(width 0.1)
				(type default)
			)
			(layer "B.Fab")
		)
		(fp_line
			(start 0.12065 0.2794)
			(end 0.12065 0.3048)
			(stroke
				(width 0.1)
				(type default)
			)
			(layer "B.Fab")
		)
		(fp_line
			(start 0.12065 0.3048)
			(end 0.67945 0.3048)
			(stroke
				(width 0.1)
				(type default)
			)
			(layer "B.Fab")
		)
		(fp_line
			(start 0.67945 -0.305054)
			(end 0.12065 -0.305054)
			(stroke
				(width 0.1)
				(type default)
			)
			(layer "B.Fab")
		)
		(fp_line
			(start 0.67945 0.3048)
			(end 0.67945 -0.305054)
			(stroke
				(width 0.1)
				(type default)
			)
			(layer "B.Fab")
		)
		(pad "1" smd circle
			(at 0.40005 0 180)
			(size 0 0)
			(layers "B.Cu" "B.Mask" "B.Paste")
			(net "P3V3")
		)
		(pad "2" smd circle
			(at -0.40005 0 180)
			(size 0 0)
			(layers "B.Cu" "B.Mask" "B.Paste")
			(net "PWRGD_CHA_CPU0_DIMM0")
		)
	)
	(footprint ""
		(layer "B.Cu")
		(at 440.333384 -16.014954)
		(property "Reference" "C34"
			(at 0 0 0)
			(layer "B.SilkS")
			(hide yes)
			(effects
				(font
					(size 1.27 1.27)
				)
				(justify mirror)
			)
		)
		(property "Value" ""
			(at 0 0 0)
			(layer "B.Fab")
			(effects
				(font
					(size 1.27 1.27)
				)
				(justify mirror)
			)
		)
		(duplicate_pad_numbers_are_jumpers no)
		(fp_line
			(start -1.524 -0.762)
			(end -1.524 0.762)
			(stroke
				(width 0.1524)
				(type default)
			)
			(layer "B.SilkS")
		)
		(fp_line
			(start -1.524 0.762)
			(end 1.524 0.762)
			(stroke
				(width 0.1524)
				(type default)
			)
			(layer "B.SilkS")
		)
		(fp_line
			(start 1.524 -0.762)
			(end -1.524 -0.762)
			(stroke
				(width 0.1524)
				(type default)
			)
			(layer "B.SilkS")
		)
		(fp_line
			(start 1.524 0.762)
			(end 1.524 -0.762)
			(stroke
				(width 0.1524)
				(type default)
			)
			(layer "B.SilkS")
		)
		(fp_line
			(start -1.1049 -0.724916)
			(end 1.1049 -0.724916)
			(stroke
				(width 0.1)
				(type default)
			)
			(layer "B.Fab")
		)
		(fp_line
			(start -1.1049 0.724916)
			(end -1.1049 -0.724916)
			(stroke
				(width 0.1)
				(type default)
			)
			(layer "B.Fab")
		)
		(fp_line
			(start 1.1049 -0.724916)
			(end 1.1049 0.724916)
			(stroke
				(width 0.1)
				(type default)
			)
			(layer "B.Fab")
		)
		(fp_line
			(start 1.1049 0.724916)
			(end -1.1049 0.724916)
			(stroke
				(width 0.1)
				(type default)
			)
			(layer "B.Fab")
		)
		(pad "1" smd rect
			(at 0.889 0)
			(size 1.016 1.27)
			(layers "B.Cu" "B.Mask" "B.Paste")
			(net "P12V_OCP_SFF_R")
		)
		(pad "2" smd rect
			(at -0.889 0)
			(size 1.016 1.27)
			(layers "B.Cu" "B.Mask" "B.Paste")
			(net "GND")
		)
	)
	(footprint ""
		(layer "B.Cu")
		(at 140.55852 -35.812222 -90)
		(property "Reference" "C6042"
			(at 0 0 90)
			(layer "B.SilkS")
			(hide yes)
			(effects
				(font
					(size 1.27 1.27)
				)
				(justify mirror)
			)
		)
		(property "Value" ""
			(at 0 0 90)
			(layer "B.Fab")
			(effects
				(font
					(size 1.27 1.27)
				)
				(justify mirror)
			)
		)
		(duplicate_pad_numbers_are_jumpers no)
		(fp_line
			(start -1.2954 0.5842)
			(end 1.2954 0.5842)
			(stroke
				(width 0.1524)
				(type default)
			)
			(layer "B.SilkS")
		)
		(fp_line
			(start 1.2954 0.5842)
			(end 1.2954 -0.5842)
			(stroke
				(width 0.1524)
				(type default)
			)
			(layer "B.SilkS")
		)
		(fp_line
			(start -1.2954 -0.5842)
			(end -1.2954 0.5842)
			(stroke
				(width 0.1524)
				(type default)
			)
			(layer "B.SilkS")
		)
		(fp_line
			(start 1.2954 -0.5842)
			(end -1.2954 -0.5842)
			(stroke
				(width 0.1524)
				(type default)
			)
			(layer "B.SilkS")
		)
		(fp_line
			(start -0.8636 0.4572)
			(end 0.8636 0.4572)
			(stroke
				(width 0.1)
				(type default)
			)
			(layer "B.Fab")
		)
		(fp_line
			(start 0.8636 0.4572)
			(end 0.8636 0.4064)
			(stroke
				(width 0.1)
				(type default)
			)
			(layer "B.Fab")
		)
		(fp_line
			(start -1.1938 0.4064)
			(end -0.8636 0.4064)
			(stroke
				(width 0.1)
				(type default)
			)
			(layer "B.Fab")
		)
		(fp_line
			(start -0.8636 0.4064)
			(end -0.8636 0.4572)
			(stroke
				(width 0.1)
				(type default)
			)
			(layer "B.Fab")
		)
		(fp_line
			(start 0.8636 0.4064)
			(end 1.1938 0.4064)
			(stroke
				(width 0.1)
				(type default)
			)
			(layer "B.Fab")
		)
		(fp_line
			(start 1.1938 0.4064)
			(end 1.1938 -0.4064)
			(stroke
				(width 0.1)
				(type default)
			)
			(layer "B.Fab")
		)
		(fp_line
			(start -1.1938 -0.4064)
			(end -1.1938 0.4064)
			(stroke
				(width 0.1)
				(type default)
			)
			(layer "B.Fab")
		)
		(fp_line
			(start -0.8636 -0.4064)
			(end -1.1938 -0.4064)
			(stroke
				(width 0.1)
				(type default)
			)
			(layer "B.Fab")
		)
		(fp_line
			(start 0.8636 -0.4064)
			(end 0.8636 -0.4572)
			(stroke
				(width 0.1)
				(type default)
			)
			(layer "B.Fab")
		)
		(fp_line
			(start 1.1938 -0.4064)
			(end 0.8636 -0.4064)
			(stroke
				(width 0.1)
				(type default)
			)
			(layer "B.Fab")
		)
		(fp_line
			(start -0.8636 -0.4572)
			(end -0.8636 -0.4064)
			(stroke
				(width 0.1)
				(type default)
			)
			(layer "B.Fab")
		)
		(fp_line
			(start 0.8636 -0.4572)
			(end -0.8636 -0.4572)
			(stroke
				(width 0.1)
				(type default)
			)
			(layer "B.Fab")
		)
		(pad "1" smd rect
			(at 0.7366 0 180)
			(size 0.7112 0.8128)
			(layers "B.Cu" "B.Mask" "B.Paste")
			(net "P3V3_AUX_CPU0_USB_AVDD33")
		)
		(pad "2" smd rect
			(at -0.7366 0 180)
			(size 0.7112 0.8128)
			(layers "B.Cu" "B.Mask" "B.Paste")
			(net "GND")
		)
	)
	(footprint ""
		(layer "B.Cu")
		(at 13.241782 -409.624784 180)
		(property "Reference" "PR6821"
			(at 0 0 0)
			(layer "B.SilkS")
			(hide yes)
			(effects
				(font
					(size 1.27 1.27)
				)
				(justify mirror)
			)
		)
		(property "Value" ""
			(at 0 0 0)
			(layer "B.Fab")
			(effects
				(font
					(size 1.27 1.27)
				)
				(justify mirror)
			)
		)
		(duplicate_pad_numbers_are_jumpers no)
		(fp_line
			(start 0.7874 0.4064)
			(end 0.7874 -0.4064)
			(stroke
				(width 0.1524)
				(type default)
			)
			(layer "B.SilkS")
		)
		(fp_line
			(start 0.7874 -0.4064)
			(end -0.7874 -0.4064)
			(stroke
				(width 0.1524)
				(type default)
			)
			(layer "B.SilkS")
		)
		(fp_line
			(start -0.7874 0.4064)
			(end 0.7874 0.4064)
			(stroke
				(width 0.1524)
				(type default)
			)
			(layer "B.SilkS")
		)
		(fp_line
			(start -0.7874 -0.4064)
			(end -0.7874 0.4064)
			(stroke
				(width 0.1524)
				(type default)
			)
			(layer "B.SilkS")
		)
		(fp_line
			(start 0.67945 0.3048)
			(end 0.67945 -0.305054)
			(stroke
				(width 0.1)
				(type default)
			)
			(layer "B.Fab")
		)
		(fp_line
			(start 0.67945 -0.305054)
			(end 0.12065 -0.305054)
			(stroke
				(width 0.1)
				(type default)
			)
			(layer "B.Fab")
		)
		(fp_line
			(start 0.12065 0.3048)
			(end 0.67945 0.3048)
			(stroke
				(width 0.1)
				(type default)
			)
			(layer "B.Fab")
		)
		(fp_line
			(start 0.12065 0.2794)
			(end 0.12065 0.3048)
			(stroke
				(width 0.1)
				(type default)
			)
			(layer "B.Fab")
		)
		(fp_line
			(start 0.12065 -0.2794)
			(end -0.12065 -0.2794)
			(stroke
				(width 0.1)
				(type default)
			)
			(layer "B.Fab")
		)
		(fp_line
			(start 0.12065 -0.305054)
			(end 0.12065 -0.2794)
			(stroke
				(width 0.1)
				(type default)
			)
			(layer "B.Fab")
		)
		(fp_line
			(start -0.120396 0.3048)
			(end -0.120396 0.2794)
			(stroke
				(width 0.1)
				(type default)
			)
			(layer "B.Fab")
		)
		(fp_line
			(start -0.120396 0.2794)
			(end 0.12065 0.2794)
			(stroke
				(width 0.1)
				(type default)
			)
			(layer "B.Fab")
		)
		(fp_line
			(start -0.12065 -0.2794)
			(end -0.12065 -0.3048)
			(stroke
				(width 0.1)
				(type default)
			)
			(layer "B.Fab")
		)
		(fp_line
			(start -0.12065 -0.3048)
			(end -0.67945 -0.3048)
			(stroke
				(width 0.1)
				(type default)
			)
			(layer "B.Fab")
		)
		(fp_line
			(start -0.67945 0.3048)
			(end -0.120396 0.3048)
			(stroke
				(width 0.1)
				(type default)
			)
			(layer "B.Fab")
		)
		(fp_line
			(start -0.67945 -0.3048)
			(end -0.67945 0.3048)
			(stroke
				(width 0.1)
				(type default)
			)
			(layer "B.Fab")
		)
		(pad "1" smd circle
			(at 0.40005 0)
			(size 0 0)
			(layers "B.Cu" "B.Mask" "B.Paste")
			(net "P0V9_RETIMER_CPU1_VMON")
		)
		(pad "2" smd circle
			(at -0.40005 0)
			(size 0 0)
			(layers "B.Cu" "B.Mask" "B.Paste")
			(net "GND")
		)
	)
	(footprint ""
		(layer "B.Cu")
		(at 328.416158 -401.624546 180)
		(property "Reference" "R1010"
			(at 0 0 0)
			(layer "B.SilkS")
			(hide yes)
			(effects
				(font
					(size 1.27 1.27)
				)
				(justify mirror)
			)
		)
		(property "Value" ""
			(at 0 0 0)
			(layer "B.Fab")
			(effects
				(font
					(size 1.27 1.27)
				)
				(justify mirror)
			)
		)
		(duplicate_pad_numbers_are_jumpers no)
		(fp_line
			(start 1.2954 0.5842)
			(end 1.2954 -0.5842)
			(stroke
				(width 0.1524)
				(type default)
			)
			(layer "B.SilkS")
		)
		(fp_line
			(start 1.2954 -0.5842)
			(end -1.2954 -0.5842)
			(stroke
				(width 0.1524)
				(type default)
			)
			(layer "B.SilkS")
		)
		(fp_line
			(start -1.2954 0.5842)
			(end 1.2954 0.5842)
			(stroke
				(width 0.1524)
				(type default)
			)
			(layer "B.SilkS")
		)
		(fp_line
			(start -1.2954 -0.5842)
			(end -1.2954 0.5842)
			(stroke
				(width 0.1524)
				(type default)
			)
			(layer "B.SilkS")
		)
		(fp_line
			(start 1.1938 0.4064)
			(end 1.1938 -0.406654)
			(stroke
				(width 0.1)
				(type default)
			)
			(layer "B.Fab")
		)
		(fp_line
			(start 1.1938 -0.406654)
			(end 0.8636 -0.406654)
			(stroke
				(width 0.1)
				(type default)
			)
			(layer "B.Fab")
		)
		(fp_line
			(start 0.8636 0.4572)
			(end 0.8636 0.4318)
			(stroke
				(width 0.1)
				(type default)
			)
			(layer "B.Fab")
		)
		(fp_line
			(start 0.8636 0.4318)
			(end 0.8636 0.4064)
			(stroke
				(width 0.1)
				(type default)
			)
			(layer "B.Fab")
		)
		(fp_line
			(start 0.8636 0.4064)
			(end 1.1938 0.4064)
			(stroke
				(width 0.1)
				(type default)
			)
			(layer "B.Fab")
		)
		(fp_line
			(start 0.8636 -0.406654)
			(end 0.8636 -0.4572)
			(stroke
				(width 0.1)
				(type default)
			)
			(layer "B.Fab")
		)
		(fp_line
			(start 0.8636 -0.4572)
			(end -0.8636 -0.4572)
			(stroke
				(width 0.1)
				(type default)
			)
			(layer "B.Fab")
		)
		(fp_line
			(start -0.8636 0.4572)
			(end 0.8636 0.4572)
			(stroke
				(width 0.1)
				(type default)
			)
			(layer "B.Fab")
		)
		(fp_line
			(start -0.8636 0.4064)
			(end -0.8636 0.4572)
			(stroke
				(width 0.1)
				(type default)
			)
			(layer "B.Fab")
		)
		(fp_line
			(start -0.8636 -0.406654)
			(end -1.1938 -0.406654)
			(stroke
				(width 0.1)
				(type default)
			)
			(layer "B.Fab")
		)
		(fp_line
			(start -0.8636 -0.4572)
			(end -0.8636 -0.406654)
			(stroke
				(width 0.1)
				(type default)
			)
			(layer "B.Fab")
		)
		(fp_line
			(start -1.1938 0.4064)
			(end -0.8636 0.4064)
			(stroke
				(width 0.1)
				(type default)
			)
			(layer "B.Fab")
		)
		(fp_line
			(start -1.1938 -0.406654)
			(end -1.1938 0.4064)
			(stroke
				(width 0.1)
				(type default)
			)
			(layer "B.Fab")
		)
		(pad "1" smd rect
			(at 0.7366 0 90)
			(size 0.7112 0.8128)
			(layers "B.Cu" "B.Mask" "B.Paste")
			(net "P0V9_CPU0_RT_2D")
		)
		(pad "2" smd rect
			(at -0.7366 0 90)
			(size 0.7112 0.8128)
			(layers "B.Cu" "B.Mask" "B.Paste")
			(net "P0V9_CPU0_RT1_2A_2D")
		)
	)
	(footprint ""
		(layer "B.Cu")
		(at 228.854 -232.156 -90)
		(property "Reference" "R147"
			(at 0 0 90)
			(layer "B.SilkS")
			(hide yes)
			(effects
				(font
					(size 1.27 1.27)
				)
				(justify mirror)
			)
		)
		(property "Value" ""
			(at 0 0 90)
			(layer "B.Fab")
			(effects
				(font
					(size 1.27 1.27)
				)
				(justify mirror)
			)
		)
		(duplicate_pad_numbers_are_jumpers no)
		(fp_line
			(start -0.7874 0.4064)
			(end 0.7874 0.4064)
			(stroke
				(width 0.1524)
				(type default)
			)
			(layer "B.SilkS")
		)
		(fp_line
			(start 0.7874 0.4064)
			(end 0.7874 -0.4064)
			(stroke
				(width 0.1524)
				(type default)
			)
			(layer "B.SilkS")
		)
		(fp_line
			(start -0.7874 -0.4064)
			(end -0.7874 0.4064)
			(stroke
				(width 0.1524)
				(type default)
			)
			(layer "B.SilkS")
		)
		(fp_line
			(start 0.7874 -0.4064)
			(end -0.7874 -0.4064)
			(stroke
				(width 0.1524)
				(type default)
			)
			(layer "B.SilkS")
		)
		(fp_line
			(start -0.67945 0.3048)
			(end -0.120396 0.3048)
			(stroke
				(width 0.1)
				(type default)
			)
			(layer "B.Fab")
		)
		(fp_line
			(start -0.120396 0.3048)
			(end -0.120396 0.2794)
			(stroke
				(width 0.1)
				(type default)
			)
			(layer "B.Fab")
		)
		(fp_line
			(start 0.12065 0.3048)
			(end 0.67945 0.3048)
			(stroke
				(width 0.1)
				(type default)
			)
			(layer "B.Fab")
		)
		(fp_line
			(start 0.67945 0.3048)
			(end 0.67945 -0.305054)
			(stroke
				(width 0.1)
				(type default)
			)
			(layer "B.Fab")
		)
		(fp_line
			(start -0.120396 0.2794)
			(end 0.12065 0.2794)
			(stroke
				(width 0.1)
				(type default)
			)
			(layer "B.Fab")
		)
		(fp_line
			(start 0.12065 0.2794)
			(end 0.12065 0.3048)
			(stroke
				(width 0.1)
				(type default)
			)
			(layer "B.Fab")
		)
		(fp_line
			(start -0.12065 -0.2794)
			(end -0.12065 -0.3048)
			(stroke
				(width 0.1)
				(type default)
			)
			(layer "B.Fab")
		)
		(fp_line
			(start 0.12065 -0.2794)
			(end -0.12065 -0.2794)
			(stroke
				(width 0.1)
				(type default)
			)
			(layer "B.Fab")
		)
		(fp_line
			(start -0.67945 -0.3048)
			(end -0.67945 0.3048)
			(stroke
				(width 0.1)
				(type default)
			)
			(layer "B.Fab")
		)
		(fp_line
			(start -0.12065 -0.3048)
			(end -0.67945 -0.3048)
			(stroke
				(width 0.1)
				(type default)
			)
			(layer "B.Fab")
		)
		(fp_line
			(start 0.12065 -0.305054)
			(end 0.12065 -0.2794)
			(stroke
				(width 0.1)
				(type default)
			)
			(layer "B.Fab")
		)
		(fp_line
			(start 0.67945 -0.305054)
			(end 0.12065 -0.305054)
			(stroke
				(width 0.1)
				(type default)
			)
			(layer "B.Fab")
		)
		(pad "1" smd circle
			(at 0.40005 0 90)
			(size 0 0)
			(layers "B.Cu" "B.Mask" "B.Paste")
			(net "SMB_CPU0_CPU1_APML_MUX1_SDA")
		)
		(pad "2" smd circle
			(at -0.40005 0 90)
			(size 0 0)
			(layers "B.Cu" "B.Mask" "B.Paste")
			(net "SMB_APML_CPU1_R_SDA")
		)
	)
	(footprint ""
		(layer "B.Cu")
		(at 143.04137 -316.465458 180)
		(property "Reference" "R5030"
			(at 0 0 0)
			(layer "B.SilkS")
			(hide yes)
			(effects
				(font
					(size 1.27 1.27)
				)
				(justify mirror)
			)
		)
		(property "Value" ""
			(at 0 0 0)
			(layer "B.Fab")
			(effects
				(font
					(size 1.27 1.27)
				)
				(justify mirror)
			)
		)
		(duplicate_pad_numbers_are_jumpers no)
		(fp_line
			(start 0.7874 0.4064)
			(end 0.7874 -0.4064)
			(stroke
				(width 0.1524)
				(type default)
			)
			(layer "B.SilkS")
		)
		(fp_line
			(start 0.7874 -0.4064)
			(end -0.7874 -0.4064)
			(stroke
				(width 0.1524)
				(type default)
			)
			(layer "B.SilkS")
		)
		(fp_line
			(start -0.7874 0.4064)
			(end 0.7874 0.4064)
			(stroke
				(width 0.1524)
				(type default)
			)
			(layer "B.SilkS")
		)
		(fp_line
			(start -0.7874 -0.4064)
			(end -0.7874 0.4064)
			(stroke
				(width 0.1524)
				(type default)
			)
			(layer "B.SilkS")
		)
		(fp_line
			(start 0.67945 0.3048)
			(end 0.67945 -0.305054)
			(stroke
				(width 0.1)
				(type default)
			)
			(layer "B.Fab")
		)
		(fp_line
			(start 0.67945 -0.305054)
			(end 0.12065 -0.305054)
			(stroke
				(width 0.1)
				(type default)
			)
			(layer "B.Fab")
		)
		(fp_line
			(start 0.12065 0.3048)
			(end 0.67945 0.3048)
			(stroke
				(width 0.1)
				(type default)
			)
			(layer "B.Fab")
		)
		(fp_line
			(start 0.12065 0.2794)
			(end 0.12065 0.3048)
			(stroke
				(width 0.1)
				(type default)
			)
			(layer "B.Fab")
		)
		(fp_line
			(start 0.12065 -0.2794)
			(end -0.12065 -0.2794)
			(stroke
				(width 0.1)
				(type default)
			)
			(layer "B.Fab")
		)
		(fp_line
			(start 0.12065 -0.305054)
			(end 0.12065 -0.2794)
			(stroke
				(width 0.1)
				(type default)
			)
			(layer "B.Fab")
		)
		(fp_line
			(start -0.120396 0.3048)
			(end -0.120396 0.2794)
			(stroke
				(width 0.1)
				(type default)
			)
			(layer "B.Fab")
		)
		(fp_line
			(start -0.120396 0.2794)
			(end 0.12065 0.2794)
			(stroke
				(width 0.1)
				(type default)
			)
			(layer "B.Fab")
		)
		(fp_line
			(start -0.12065 -0.2794)
			(end -0.12065 -0.3048)
			(stroke
				(width 0.1)
				(type default)
			)
			(layer "B.Fab")
		)
		(fp_line
			(start -0.12065 -0.3048)
			(end -0.67945 -0.3048)
			(stroke
				(width 0.1)
				(type default)
			)
			(layer "B.Fab")
		)
		(fp_line
			(start -0.67945 0.3048)
			(end -0.120396 0.3048)
			(stroke
				(width 0.1)
				(type default)
			)
			(layer "B.Fab")
		)
		(fp_line
			(start -0.67945 -0.3048)
			(end -0.67945 0.3048)
			(stroke
				(width 0.1)
				(type default)
			)
			(layer "B.Fab")
		)
		(pad "1" smd circle
			(at 0.40005 0)
			(size 0 0)
			(layers "B.Cu" "B.Mask" "B.Paste")
			(net "GND")
		)
		(pad "2" smd circle
			(at -0.40005 0)
			(size 0 0)
			(layers "B.Cu" "B.Mask" "B.Paste")
			(net "FM_BMC_TPM_PRES_N")
		)
	)
	(footprint ""
		(layer "B.Cu")
		(at 18.039588 -395.703806)
		(property "Reference" "PC6618"
			(at 0 0 0)
			(layer "B.SilkS")
			(hide yes)
			(effects
				(font
					(size 1.27 1.27)
				)
				(justify mirror)
			)
		)
		(property "Value" ""
			(at 0 0 0)
			(layer "B.Fab")
			(effects
				(font
					(size 1.27 1.27)
				)
				(justify mirror)
			)
		)
		(duplicate_pad_numbers_are_jumpers no)
		(fp_line
			(start -1.524 -0.762)
			(end -1.524 0.762)
			(stroke
				(width 0.1524)
				(type default)
			)
			(layer "B.SilkS")
		)
		(fp_line
			(start -1.524 0.762)
			(end 1.524 0.762)
			(stroke
				(width 0.1524)
				(type default)
			)
			(layer "B.SilkS")
		)
		(fp_line
			(start 1.524 -0.762)
			(end -1.524 -0.762)
			(stroke
				(width 0.1524)
				(type default)
			)
			(layer "B.SilkS")
		)
		(fp_line
			(start 1.524 0.762)
			(end 1.524 -0.762)
			(stroke
				(width 0.1524)
				(type default)
			)
			(layer "B.SilkS")
		)
		(fp_line
			(start -1.1049 -0.724916)
			(end 1.1049 -0.724916)
			(stroke
				(width 0.1)
				(type default)
			)
			(layer "B.Fab")
		)
		(fp_line
			(start -1.1049 0.724916)
			(end -1.1049 -0.724916)
			(stroke
				(width 0.1)
				(type default)
			)
			(layer "B.Fab")
		)
		(fp_line
			(start 1.1049 -0.724916)
			(end 1.1049 0.724916)
			(stroke
				(width 0.1)
				(type default)
			)
			(layer "B.Fab")
		)
		(fp_line
			(start 1.1049 0.724916)
			(end -1.1049 0.724916)
			(stroke
				(width 0.1)
				(type default)
			)
			(layer "B.Fab")
		)
		(pad "1" smd rect
			(at 0.889 0)
			(size 1.016 1.27)
			(layers "B.Cu" "B.Mask" "B.Paste")
			(net "SW_P12V_AUX_P0V9_RETIMER_CPU1_FLT")
		)
		(pad "2" smd rect
			(at -0.889 0)
			(size 1.016 1.27)
			(layers "B.Cu" "B.Mask" "B.Paste")
			(net "GND")
		)
	)
	(footprint ""
		(layer "B.Cu")
		(at 124.459492 -72.616822 180)
		(property "Reference" "R6241"
			(at 0 0 0)
			(layer "B.SilkS")
			(hide yes)
			(effects
				(font
					(size 1.27 1.27)
				)
				(justify mirror)
			)
		)
		(property "Value" ""
			(at 0 0 0)
			(layer "B.Fab")
			(effects
				(font
					(size 1.27 1.27)
				)
				(justify mirror)
			)
		)
		(duplicate_pad_numbers_are_jumpers no)
		(fp_line
			(start 0.7874 0.4064)
			(end 0.7874 -0.4064)
			(stroke
				(width 0.1524)
				(type default)
			)
			(layer "B.SilkS")
		)
		(fp_line
			(start 0.7874 -0.4064)
			(end -0.7874 -0.4064)
			(stroke
				(width 0.1524)
				(type default)
			)
			(layer "B.SilkS")
		)
		(fp_line
			(start -0.7874 0.4064)
			(end 0.7874 0.4064)
			(stroke
				(width 0.1524)
				(type default)
			)
			(layer "B.SilkS")
		)
		(fp_line
			(start -0.7874 -0.4064)
			(end -0.7874 0.4064)
			(stroke
				(width 0.1524)
				(type default)
			)
			(layer "B.SilkS")
		)
		(fp_line
			(start 0.67945 0.3048)
			(end 0.67945 -0.305054)
			(stroke
				(width 0.1)
				(type default)
			)
			(layer "B.Fab")
		)
		(fp_line
			(start 0.67945 -0.305054)
			(end 0.12065 -0.305054)
			(stroke
				(width 0.1)
				(type default)
			)
			(layer "B.Fab")
		)
		(fp_line
			(start 0.12065 0.3048)
			(end 0.67945 0.3048)
			(stroke
				(width 0.1)
				(type default)
			)
			(layer "B.Fab")
		)
		(fp_line
			(start 0.12065 0.2794)
			(end 0.12065 0.3048)
			(stroke
				(width 0.1)
				(type default)
			)
			(layer "B.Fab")
		)
		(fp_line
			(start 0.12065 -0.2794)
			(end -0.12065 -0.2794)
			(stroke
				(width 0.1)
				(type default)
			)
			(layer "B.Fab")
		)
		(fp_line
			(start 0.12065 -0.305054)
			(end 0.12065 -0.2794)
			(stroke
				(width 0.1)
				(type default)
			)
			(layer "B.Fab")
		)
		(fp_line
			(start -0.120396 0.3048)
			(end -0.120396 0.2794)
			(stroke
				(width 0.1)
				(type default)
			)
			(layer "B.Fab")
		)
		(fp_line
			(start -0.120396 0.2794)
			(end 0.12065 0.2794)
			(stroke
				(width 0.1)
				(type default)
			)
			(layer "B.Fab")
		)
		(fp_line
			(start -0.12065 -0.2794)
			(end -0.12065 -0.3048)
			(stroke
				(width 0.1)
				(type default)
			)
			(layer "B.Fab")
		)
		(fp_line
			(start -0.12065 -0.3048)
			(end -0.67945 -0.3048)
			(stroke
				(width 0.1)
				(type default)
			)
			(layer "B.Fab")
		)
		(fp_line
			(start -0.67945 0.3048)
			(end -0.120396 0.3048)
			(stroke
				(width 0.1)
				(type default)
			)
			(layer "B.Fab")
		)
		(fp_line
			(start -0.67945 -0.3048)
			(end -0.67945 0.3048)
			(stroke
				(width 0.1)
				(type default)
			)
			(layer "B.Fab")
		)
		(pad "1" smd circle
			(at 0.40005 0)
			(size 0 0)
			(layers "B.Cu" "B.Mask" "B.Paste")
			(net "PWRGD_P1V2_AUX")
		)
		(pad "2" smd circle
			(at -0.40005 0)
			(size 0 0)
			(layers "B.Cu" "B.Mask" "B.Paste")
			(net "PWRGD_P1V2_AUX_R")
		)
	)
	(footprint ""
		(layer "B.Cu")
		(at 103.672386 -262.703564 180)
		(property "Reference" "C2416"
			(at 0 0 0)
			(layer "B.SilkS")
			(hide yes)
			(effects
				(font
					(size 1.27 1.27)
				)
				(justify mirror)
			)
		)
		(property "Value" ""
			(at 0 0 0)
			(layer "B.Fab")
			(effects
				(font
					(size 1.27 1.27)
				)
				(justify mirror)
			)
		)
		(duplicate_pad_numbers_are_jumpers no)
		(fp_line
			(start 0.7874 0.4064)
			(end 0.7874 -0.4064)
			(stroke
				(width 0.1524)
				(type default)
			)
			(layer "B.SilkS")
		)
		(fp_line
			(start 0.7874 -0.4064)
			(end -0.7874 -0.4064)
			(stroke
				(width 0.1524)
				(type default)
			)
			(layer "B.SilkS")
		)
		(fp_line
			(start -0.7874 0.4064)
			(end 0.7874 0.4064)
			(stroke
				(width 0.1524)
				(type default)
			)
			(layer "B.SilkS")
		)
		(fp_line
			(start -0.7874 -0.4064)
			(end -0.7874 0.4064)
			(stroke
				(width 0.1524)
				(type default)
			)
			(layer "B.SilkS")
		)
		(fp_line
			(start 0.67945 0.3048)
			(end 0.67945 -0.305054)
			(stroke
				(width 0.1)
				(type default)
			)
			(layer "B.Fab")
		)
		(fp_line
			(start 0.67945 -0.305054)
			(end 0.12065 -0.305054)
			(stroke
				(width 0.1)
				(type default)
			)
			(layer "B.Fab")
		)
		(fp_line
			(start 0.12065 0.3048)
			(end 0.67945 0.3048)
			(stroke
				(width 0.1)
				(type default)
			)
			(layer "B.Fab")
		)
		(fp_line
			(start 0.12065 0.2794)
			(end 0.12065 0.3048)
			(stroke
				(width 0.1)
				(type default)
			)
			(layer "B.Fab")
		)
		(fp_line
			(start 0.12065 -0.2794)
			(end -0.12065 -0.2794)
			(stroke
				(width 0.1)
				(type default)
			)
			(layer "B.Fab")
		)
		(fp_line
			(start 0.12065 -0.305054)
			(end 0.12065 -0.2794)
			(stroke
				(width 0.1)
				(type default)
			)
			(layer "B.Fab")
		)
		(fp_line
			(start -0.120396 0.3048)
			(end -0.120396 0.2794)
			(stroke
				(width 0.1)
				(type default)
			)
			(layer "B.Fab")
		)
		(fp_line
			(start -0.120396 0.2794)
			(end 0.12065 0.2794)
			(stroke
				(width 0.1)
				(type default)
			)
			(layer "B.Fab")
		)
		(fp_line
			(start -0.12065 -0.2794)
			(end -0.12065 -0.3048)
			(stroke
				(width 0.1)
				(type default)
			)
			(layer "B.Fab")
		)
		(fp_line
			(start -0.12065 -0.3048)
			(end -0.67945 -0.3048)
			(stroke
				(width 0.1)
				(type default)
			)
			(layer "B.Fab")
		)
		(fp_line
			(start -0.67945 0.3048)
			(end -0.120396 0.3048)
			(stroke
				(width 0.1)
				(type default)
			)
			(layer "B.Fab")
		)
		(fp_line
			(start -0.67945 -0.3048)
			(end -0.67945 0.3048)
			(stroke
				(width 0.1)
				(type default)
			)
			(layer "B.Fab")
		)
		(pad "1" smd circle
			(at 0.40005 0)
			(size 0 0)
			(layers "B.Cu" "B.Mask" "B.Paste")
			(net "PVDDCR_SOC_P1")
		)
		(pad "2" smd circle
			(at -0.40005 0)
			(size 0 0)
			(layers "B.Cu" "B.Mask" "B.Paste")
			(net "GND")
		)
	)
	(footprint ""
		(layer "B.Cu")
		(at 101.894386 -261.179564)
		(property "Reference" "C2440"
			(at 0 0 0)
			(layer "B.SilkS")
			(hide yes)
			(effects
				(font
					(size 1.27 1.27)
				)
				(justify mirror)
			)
		)
		(property "Value" ""
			(at 0 0 0)
			(layer "B.Fab")
			(effects
				(font
					(size 1.27 1.27)
				)
				(justify mirror)
			)
		)
		(duplicate_pad_numbers_are_jumpers no)
		(fp_line
			(start -0.7874 -0.4064)
			(end -0.7874 0.4064)
			(stroke
				(width 0.1524)
				(type default)
			)
			(layer "B.SilkS")
		)
		(fp_line
			(start -0.7874 0.4064)
			(end 0.7874 0.4064)
			(stroke
				(width 0.1524)
				(type default)
			)
			(layer "B.SilkS")
		)
		(fp_line
			(start 0.7874 -0.4064)
			(end -0.7874 -0.4064)
			(stroke
				(width 0.1524)
				(type default)
			)
			(layer "B.SilkS")
		)
		(fp_line
			(start 0.7874 0.4064)
			(end 0.7874 -0.4064)
			(stroke
				(width 0.1524)
				(type default)
			)
			(layer "B.SilkS")
		)
		(fp_line
			(start -0.67945 -0.3048)
			(end -0.67945 0.3048)
			(stroke
				(width 0.1)
				(type default)
			)
			(layer "B.Fab")
		)
		(fp_line
			(start -0.67945 0.3048)
			(end -0.120396 0.3048)
			(stroke
				(width 0.1)
				(type default)
			)
			(layer "B.Fab")
		)
		(fp_line
			(start -0.12065 -0.3048)
			(end -0.67945 -0.3048)
			(stroke
				(width 0.1)
				(type default)
			)
			(layer "B.Fab")
		)
		(fp_line
			(start -0.12065 -0.2794)
			(end -0.12065 -0.3048)
			(stroke
				(width 0.1)
				(type default)
			)
			(layer "B.Fab")
		)
		(fp_line
			(start -0.120396 0.2794)
			(end 0.12065 0.2794)
			(stroke
				(width 0.1)
				(type default)
			)
			(layer "B.Fab")
		)
		(fp_line
			(start -0.120396 0.3048)
			(end -0.120396 0.2794)
			(stroke
				(width 0.1)
				(type default)
			)
			(layer "B.Fab")
		)
		(fp_line
			(start 0.12065 -0.305054)
			(end 0.12065 -0.2794)
			(stroke
				(width 0.1)
				(type default)
			)
			(layer "B.Fab")
		)
		(fp_line
			(start 0.12065 -0.2794)
			(end -0.12065 -0.2794)
			(stroke
				(width 0.1)
				(type default)
			)
			(layer "B.Fab")
		)
		(fp_line
			(start 0.12065 0.2794)
			(end 0.12065 0.3048)
			(stroke
				(width 0.1)
				(type default)
			)
			(layer "B.Fab")
		)
		(fp_line
			(start 0.12065 0.3048)
			(end 0.67945 0.3048)
			(stroke
				(width 0.1)
				(type default)
			)
			(layer "B.Fab")
		)
		(fp_line
			(start 0.67945 -0.305054)
			(end 0.12065 -0.305054)
			(stroke
				(width 0.1)
				(type default)
			)
			(layer "B.Fab")
		)
		(fp_line
			(start 0.67945 0.3048)
			(end 0.67945 -0.305054)
			(stroke
				(width 0.1)
				(type default)
			)
			(layer "B.Fab")
		)
		(pad "1" smd circle
			(at 0.40005 0 180)
			(size 0 0)
			(layers "B.Cu" "B.Mask" "B.Paste")
			(net "PVDDCR_SOC_P1")
		)
		(pad "2" smd circle
			(at -0.40005 0 180)
			(size 0 0)
			(layers "B.Cu" "B.Mask" "B.Paste")
			(net "GND")
		)
	)
	(footprint ""
		(layer "B.Cu")
		(at 166.24046 -190.821564)
		(property "Reference" "R109"
			(at 0 0 0)
			(layer "B.SilkS")
			(hide yes)
			(effects
				(font
					(size 1.27 1.27)
				)
				(justify mirror)
			)
		)
		(property "Value" ""
			(at 0 0 0)
			(layer "B.Fab")
			(effects
				(font
					(size 1.27 1.27)
				)
				(justify mirror)
			)
		)
		(duplicate_pad_numbers_are_jumpers no)
		(fp_line
			(start -0.7874 -0.4064)
			(end -0.7874 0.4064)
			(stroke
				(width 0.1524)
				(type default)
			)
			(layer "B.SilkS")
		)
		(fp_line
			(start -0.7874 0.4064)
			(end 0.7874 0.4064)
			(stroke
				(width 0.1524)
				(type default)
			)
			(layer "B.SilkS")
		)
		(fp_line
			(start 0.7874 -0.4064)
			(end -0.7874 -0.4064)
			(stroke
				(width 0.1524)
				(type default)
			)
			(layer "B.SilkS")
		)
		(fp_line
			(start 0.7874 0.4064)
			(end 0.7874 -0.4064)
			(stroke
				(width 0.1524)
				(type default)
			)
			(layer "B.SilkS")
		)
		(fp_line
			(start -0.67945 -0.3048)
			(end -0.67945 0.3048)
			(stroke
				(width 0.1)
				(type default)
			)
			(layer "B.Fab")
		)
		(fp_line
			(start -0.67945 0.3048)
			(end -0.120396 0.3048)
			(stroke
				(width 0.1)
				(type default)
			)
			(layer "B.Fab")
		)
		(fp_line
			(start -0.12065 -0.3048)
			(end -0.67945 -0.3048)
			(stroke
				(width 0.1)
				(type default)
			)
			(layer "B.Fab")
		)
		(fp_line
			(start -0.12065 -0.2794)
			(end -0.12065 -0.3048)
			(stroke
				(width 0.1)
				(type default)
			)
			(layer "B.Fab")
		)
		(fp_line
			(start -0.120396 0.2794)
			(end 0.12065 0.2794)
			(stroke
				(width 0.1)
				(type default)
			)
			(layer "B.Fab")
		)
		(fp_line
			(start -0.120396 0.3048)
			(end -0.120396 0.2794)
			(stroke
				(width 0.1)
				(type default)
			)
			(layer "B.Fab")
		)
		(fp_line
			(start 0.12065 -0.305054)
			(end 0.12065 -0.2794)
			(stroke
				(width 0.1)
				(type default)
			)
			(layer "B.Fab")
		)
		(fp_line
			(start 0.12065 -0.2794)
			(end -0.12065 -0.2794)
			(stroke
				(width 0.1)
				(type default)
			)
			(layer "B.Fab")
		)
		(fp_line
			(start 0.12065 0.2794)
			(end 0.12065 0.3048)
			(stroke
				(width 0.1)
				(type default)
			)
			(layer "B.Fab")
		)
		(fp_line
			(start 0.12065 0.3048)
			(end 0.67945 0.3048)
			(stroke
				(width 0.1)
				(type default)
			)
			(layer "B.Fab")
		)
		(fp_line
			(start 0.67945 -0.305054)
			(end 0.12065 -0.305054)
			(stroke
				(width 0.1)
				(type default)
			)
			(layer "B.Fab")
		)
		(fp_line
			(start 0.67945 0.3048)
			(end 0.67945 -0.305054)
			(stroke
				(width 0.1)
				(type default)
			)
			(layer "B.Fab")
		)
		(pad "1" smd circle
			(at 0.40005 0 180)
			(size 0 0)
			(layers "B.Cu" "B.Mask" "B.Paste")
			(net "P3V3")
		)
		(pad "2" smd circle
			(at -0.40005 0 180)
			(size 0 0)
			(layers "B.Cu" "B.Mask" "B.Paste")
			(net "PWRGD_CHGL_CPU1")
		)
	)
	(footprint ""
		(layer "B.Cu")
		(at 232.156 -240.03 180)
		(property "Reference" "R142"
			(at 0 0 0)
			(layer "B.SilkS")
			(hide yes)
			(effects
				(font
					(size 1.27 1.27)
				)
				(justify mirror)
			)
		)
		(property "Value" ""
			(at 0 0 0)
			(layer "B.Fab")
			(effects
				(font
					(size 1.27 1.27)
				)
				(justify mirror)
			)
		)
		(duplicate_pad_numbers_are_jumpers no)
		(fp_line
			(start 0.7874 0.4064)
			(end 0.7874 -0.4064)
			(stroke
				(width 0.1524)
				(type default)
			)
			(layer "B.SilkS")
		)
		(fp_line
			(start 0.7874 -0.4064)
			(end -0.7874 -0.4064)
			(stroke
				(width 0.1524)
				(type default)
			)
			(layer "B.SilkS")
		)
		(fp_line
			(start -0.7874 0.4064)
			(end 0.7874 0.4064)
			(stroke
				(width 0.1524)
				(type default)
			)
			(layer "B.SilkS")
		)
		(fp_line
			(start -0.7874 -0.4064)
			(end -0.7874 0.4064)
			(stroke
				(width 0.1524)
				(type default)
			)
			(layer "B.SilkS")
		)
		(fp_line
			(start 0.67945 0.3048)
			(end 0.67945 -0.305054)
			(stroke
				(width 0.1)
				(type default)
			)
			(layer "B.Fab")
		)
		(fp_line
			(start 0.67945 -0.305054)
			(end 0.12065 -0.305054)
			(stroke
				(width 0.1)
				(type default)
			)
			(layer "B.Fab")
		)
		(fp_line
			(start 0.12065 0.3048)
			(end 0.67945 0.3048)
			(stroke
				(width 0.1)
				(type default)
			)
			(layer "B.Fab")
		)
		(fp_line
			(start 0.12065 0.2794)
			(end 0.12065 0.3048)
			(stroke
				(width 0.1)
				(type default)
			)
			(layer "B.Fab")
		)
		(fp_line
			(start 0.12065 -0.2794)
			(end -0.12065 -0.2794)
			(stroke
				(width 0.1)
				(type default)
			)
			(layer "B.Fab")
		)
		(fp_line
			(start 0.12065 -0.305054)
			(end 0.12065 -0.2794)
			(stroke
				(width 0.1)
				(type default)
			)
			(layer "B.Fab")
		)
		(fp_line
			(start -0.120396 0.3048)
			(end -0.120396 0.2794)
			(stroke
				(width 0.1)
				(type default)
			)
			(layer "B.Fab")
		)
		(fp_line
			(start -0.120396 0.2794)
			(end 0.12065 0.2794)
			(stroke
				(width 0.1)
				(type default)
			)
			(layer "B.Fab")
		)
		(fp_line
			(start -0.12065 -0.2794)
			(end -0.12065 -0.3048)
			(stroke
				(width 0.1)
				(type default)
			)
			(layer "B.Fab")
		)
		(fp_line
			(start -0.12065 -0.3048)
			(end -0.67945 -0.3048)
			(stroke
				(width 0.1)
				(type default)
			)
			(layer "B.Fab")
		)
		(fp_line
			(start -0.67945 0.3048)
			(end -0.120396 0.3048)
			(stroke
				(width 0.1)
				(type default)
			)
			(layer "B.Fab")
		)
		(fp_line
			(start -0.67945 -0.3048)
			(end -0.67945 0.3048)
			(stroke
				(width 0.1)
				(type default)
			)
			(layer "B.Fab")
		)
		(pad "1" smd circle
			(at 0.40005 0)
			(size 0 0)
			(layers "B.Cu" "B.Mask" "B.Paste")
			(net "SMB_CPU0_CPU1_APML_MUX1_SCL")
		)
		(pad "2" smd circle
			(at -0.40005 0)
			(size 0 0)
			(layers "B.Cu" "B.Mask" "B.Paste")
			(net "SMB_APML_CPU0_R_SCL")
		)
	)
	(footprint ""
		(layer "B.Cu")
		(at 169.66692 -51.399948 180)
		(property "Reference" "C1925"
			(at 0 0 0)
			(layer "B.SilkS")
			(hide yes)
			(effects
				(font
					(size 1.27 1.27)
				)
				(justify mirror)
			)
		)
		(property "Value" ""
			(at 0 0 0)
			(layer "B.Fab")
			(effects
				(font
					(size 1.27 1.27)
				)
				(justify mirror)
			)
		)
		(duplicate_pad_numbers_are_jumpers no)
		(fp_line
			(start 0.7874 0.4064)
			(end 0.7874 -0.4064)
			(stroke
				(width 0.1524)
				(type default)
			)
			(layer "B.SilkS")
		)
		(fp_line
			(start 0.7874 -0.4064)
			(end -0.7874 -0.4064)
			(stroke
				(width 0.1524)
				(type default)
			)
			(layer "B.SilkS")
		)
		(fp_line
			(start -0.7874 0.4064)
			(end 0.7874 0.4064)
			(stroke
				(width 0.1524)
				(type default)
			)
			(layer "B.SilkS")
		)
		(fp_line
			(start -0.7874 -0.4064)
			(end -0.7874 0.4064)
			(stroke
				(width 0.1524)
				(type default)
			)
			(layer "B.SilkS")
		)
		(fp_line
			(start 0.67945 0.3048)
			(end 0.67945 -0.305054)
			(stroke
				(width 0.1)
				(type default)
			)
			(layer "B.Fab")
		)
		(fp_line
			(start 0.67945 -0.305054)
			(end 0.12065 -0.305054)
			(stroke
				(width 0.1)
				(type default)
			)
			(layer "B.Fab")
		)
		(fp_line
			(start 0.12065 0.3048)
			(end 0.67945 0.3048)
			(stroke
				(width 0.1)
				(type default)
			)
			(layer "B.Fab")
		)
		(fp_line
			(start 0.12065 0.2794)
			(end 0.12065 0.3048)
			(stroke
				(width 0.1)
				(type default)
			)
			(layer "B.Fab")
		)
		(fp_line
			(start 0.12065 -0.2794)
			(end -0.12065 -0.2794)
			(stroke
				(width 0.1)
				(type default)
			)
			(layer "B.Fab")
		)
		(fp_line
			(start 0.12065 -0.305054)
			(end 0.12065 -0.2794)
			(stroke
				(width 0.1)
				(type default)
			)
			(layer "B.Fab")
		)
		(fp_line
			(start -0.120396 0.3048)
			(end -0.120396 0.2794)
			(stroke
				(width 0.1)
				(type default)
			)
			(layer "B.Fab")
		)
		(fp_line
			(start -0.120396 0.2794)
			(end 0.12065 0.2794)
			(stroke
				(width 0.1)
				(type default)
			)
			(layer "B.Fab")
		)
		(fp_line
			(start -0.12065 -0.2794)
			(end -0.12065 -0.3048)
			(stroke
				(width 0.1)
				(type default)
			)
			(layer "B.Fab")
		)
		(fp_line
			(start -0.12065 -0.3048)
			(end -0.67945 -0.3048)
			(stroke
				(width 0.1)
				(type default)
			)
			(layer "B.Fab")
		)
		(fp_line
			(start -0.67945 0.3048)
			(end -0.120396 0.3048)
			(stroke
				(width 0.1)
				(type default)
			)
			(layer "B.Fab")
		)
		(fp_line
			(start -0.67945 -0.3048)
			(end -0.67945 0.3048)
			(stroke
				(width 0.1)
				(type default)
			)
			(layer "B.Fab")
		)
		(pad "1" smd circle
			(at 0.40005 0)
			(size 0 0)
			(layers "B.Cu" "B.Mask" "B.Paste")
			(net "P3V3_M2_0")
		)
		(pad "2" smd circle
			(at -0.40005 0)
			(size 0 0)
			(layers "B.Cu" "B.Mask" "B.Paste")
			(net "GND")
		)
	)
	(footprint ""
		(layer "B.Cu")
		(at 237.617 -248.285)
		(property "Reference" "R1155"
			(at 0 0 0)
			(layer "B.SilkS")
			(hide yes)
			(effects
				(font
					(size 1.27 1.27)
				)
				(justify mirror)
			)
		)
		(property "Value" ""
			(at 0 0 0)
			(layer "B.Fab")
			(effects
				(font
					(size 1.27 1.27)
				)
				(justify mirror)
			)
		)
		(duplicate_pad_numbers_are_jumpers no)
		(fp_line
			(start -0.7874 -0.4064)
			(end -0.7874 0.4064)
			(stroke
				(width 0.1524)
				(type default)
			)
			(layer "B.SilkS")
		)
		(fp_line
			(start -0.7874 0.4064)
			(end 0.7874 0.4064)
			(stroke
				(width 0.1524)
				(type default)
			)
			(layer "B.SilkS")
		)
		(fp_line
			(start 0.7874 -0.4064)
			(end -0.7874 -0.4064)
			(stroke
				(width 0.1524)
				(type default)
			)
			(layer "B.SilkS")
		)
		(fp_line
			(start 0.7874 0.4064)
			(end 0.7874 -0.4064)
			(stroke
				(width 0.1524)
				(type default)
			)
			(layer "B.SilkS")
		)
		(fp_line
			(start -0.67945 -0.3048)
			(end -0.67945 0.3048)
			(stroke
				(width 0.1)
				(type default)
			)
			(layer "B.Fab")
		)
		(fp_line
			(start -0.67945 0.3048)
			(end -0.120396 0.3048)
			(stroke
				(width 0.1)
				(type default)
			)
			(layer "B.Fab")
		)
		(fp_line
			(start -0.12065 -0.3048)
			(end -0.67945 -0.3048)
			(stroke
				(width 0.1)
				(type default)
			)
			(layer "B.Fab")
		)
		(fp_line
			(start -0.12065 -0.2794)
			(end -0.12065 -0.3048)
			(stroke
				(width 0.1)
				(type default)
			)
			(layer "B.Fab")
		)
		(fp_line
			(start -0.120396 0.2794)
			(end 0.12065 0.2794)
			(stroke
				(width 0.1)
				(type default)
			)
			(layer "B.Fab")
		)
		(fp_line
			(start -0.120396 0.3048)
			(end -0.120396 0.2794)
			(stroke
				(width 0.1)
				(type default)
			)
			(layer "B.Fab")
		)
		(fp_line
			(start 0.12065 -0.305054)
			(end 0.12065 -0.2794)
			(stroke
				(width 0.1)
				(type default)
			)
			(layer "B.Fab")
		)
		(fp_line
			(start 0.12065 -0.2794)
			(end -0.12065 -0.2794)
			(stroke
				(width 0.1)
				(type default)
			)
			(layer "B.Fab")
		)
		(fp_line
			(start 0.12065 0.2794)
			(end 0.12065 0.3048)
			(stroke
				(width 0.1)
				(type default)
			)
			(layer "B.Fab")
		)
		(fp_line
			(start 0.12065 0.3048)
			(end 0.67945 0.3048)
			(stroke
				(width 0.1)
				(type default)
			)
			(layer "B.Fab")
		)
		(fp_line
			(start 0.67945 -0.305054)
			(end 0.12065 -0.305054)
			(stroke
				(width 0.1)
				(type default)
			)
			(layer "B.Fab")
		)
		(fp_line
			(start 0.67945 0.3048)
			(end 0.67945 -0.305054)
			(stroke
				(width 0.1)
				(type default)
			)
			(layer "B.Fab")
		)
		(pad "1" smd rect
			(at 0.40005 0)
			(size 0.4572 0.508)
			(layers "B.Cu" "B.Mask" "B.Paste")
			(net "SMB_APML_CPU0_R_SDA")
		)
		(pad "2" smd rect
			(at -0.40005 0)
			(size 0.4572 0.508)
			(layers "B.Cu" "B.Mask" "B.Paste")
			(net "SMB_APML_CPU0_SDA")
		)
	)
	(footprint ""
		(layer "B.Cu")
		(at 170.424348 -423.799 90)
		(property "Reference" "C1066"
			(at 0 0 90)
			(layer "B.SilkS")
			(hide yes)
			(effects
				(font
					(size 1.27 1.27)
				)
				(justify mirror)
			)
		)
		(property "Value" ""
			(at 0 0 90)
			(layer "B.Fab")
			(effects
				(font
					(size 1.27 1.27)
				)
				(justify mirror)
			)
		)
		(duplicate_pad_numbers_are_jumpers no)
		(fp_line
			(start 0.299974 -0.150114)
			(end -0.299974 -0.150114)
			(stroke
				(width 0.1)
				(type default)
			)
			(layer "B.Fab")
		)
		(fp_line
			(start -0.299974 -0.150114)
			(end -0.299974 0.150114)
			(stroke
				(width 0.1)
				(type default)
			)
			(layer "B.Fab")
		)
		(fp_line
			(start 0.299974 0.150114)
			(end 0.299974 -0.150114)
			(stroke
				(width 0.1)
				(type default)
			)
			(layer "B.Fab")
		)
		(fp_line
			(start -0.299974 0.150114)
			(end 0.299974 0.150114)
			(stroke
				(width 0.1)
				(type default)
			)
			(layer "B.Fab")
		)
		(pad "1" smd rect
			(at 0.2667 0 270)
			(size 0.3048 0.381)
			(layers "B.Cu" "B.Mask" "B.Paste")
			(net "P3V3_AUX")
		)
		(pad "2" smd rect
			(at -0.2667 0 270)
			(size 0.3048 0.381)
			(layers "B.Cu" "B.Mask" "B.Paste")
			(net "GND")
		)
	)
	(footprint ""
		(layer "B.Cu")
		(at 353.918774 -398.942052 90)
		(property "Reference" "C661"
			(at 0 0 90)
			(layer "B.SilkS")
			(hide yes)
			(effects
				(font
					(size 1.27 1.27)
				)
				(justify mirror)
			)
		)
		(property "Value" ""
			(at 0 0 90)
			(layer "B.Fab")
			(effects
				(font
					(size 1.27 1.27)
				)
				(justify mirror)
			)
		)
		(duplicate_pad_numbers_are_jumpers no)
		(fp_line
			(start 0.7874 -0.4064)
			(end -0.7874 -0.4064)
			(stroke
				(width 0.1524)
				(type default)
			)
			(layer "B.SilkS")
		)
		(fp_line
			(start -0.7874 -0.4064)
			(end -0.7874 0.4064)
			(stroke
				(width 0.1524)
				(type default)
			)
			(layer "B.SilkS")
		)
		(fp_line
			(start 0.7874 0.4064)
			(end 0.7874 -0.4064)
			(stroke
				(width 0.1524)
				(type default)
			)
			(layer "B.SilkS")
		)
		(fp_line
			(start -0.7874 0.4064)
			(end 0.7874 0.4064)
			(stroke
				(width 0.1524)
				(type default)
			)
			(layer "B.SilkS")
		)
		(fp_line
			(start 0.67945 -0.305054)
			(end 0.12065 -0.305054)
			(stroke
				(width 0.1)
				(type default)
			)
			(layer "B.Fab")
		)
		(fp_line
			(start 0.12065 -0.305054)
			(end 0.12065 -0.2794)
			(stroke
				(width 0.1)
				(type default)
			)
			(layer "B.Fab")
		)
		(fp_line
			(start -0.12065 -0.3048)
			(end -0.67945 -0.3048)
			(stroke
				(width 0.1)
				(type default)
			)
			(layer "B.Fab")
		)
		(fp_line
			(start -0.67945 -0.3048)
			(end -0.67945 0.3048)
			(stroke
				(width 0.1)
				(type default)
			)
			(layer "B.Fab")
		)
		(fp_line
			(start 0.12065 -0.2794)
			(end -0.12065 -0.2794)
			(stroke
				(width 0.1)
				(type default)
			)
			(layer "B.Fab")
		)
		(fp_line
			(start -0.12065 -0.2794)
			(end -0.12065 -0.3048)
			(stroke
				(width 0.1)
				(type default)
			)
			(layer "B.Fab")
		)
		(fp_line
			(start 0.12065 0.2794)
			(end 0.12065 0.3048)
			(stroke
				(width 0.1)
				(type default)
			)
			(layer "B.Fab")
		)
		(fp_line
			(start -0.120396 0.2794)
			(end 0.12065 0.2794)
			(stroke
				(width 0.1)
				(type default)
			)
			(layer "B.Fab")
		)
		(fp_line
			(start 0.67945 0.3048)
			(end 0.67945 -0.305054)
			(stroke
				(width 0.1)
				(type default)
			)
			(layer "B.Fab")
		)
		(fp_line
			(start 0.12065 0.3048)
			(end 0.67945 0.3048)
			(stroke
				(width 0.1)
				(type default)
			)
			(layer "B.Fab")
		)
		(fp_line
			(start -0.120396 0.3048)
			(end -0.120396 0.2794)
			(stroke
				(width 0.1)
				(type default)
			)
			(layer "B.Fab")
		)
		(fp_line
			(start -0.67945 0.3048)
			(end -0.120396 0.3048)
			(stroke
				(width 0.1)
				(type default)
			)
			(layer "B.Fab")
		)
		(pad "1" smd circle
			(at 0.40005 0 270)
			(size 0 0)
			(layers "B.Cu" "B.Mask" "B.Paste")
			(net "P0V9_CPU0_RT1_2A")
		)
		(pad "2" smd circle
			(at -0.40005 0 270)
			(size 0 0)
			(layers "B.Cu" "B.Mask" "B.Paste")
			(net "GND")
		)
	)
	(footprint ""
		(layer "B.Cu")
		(at 15.094458 -420.214298)
		(property "Reference" "C6009"
			(at 0 0 0)
			(layer "B.SilkS")
			(hide yes)
			(effects
				(font
					(size 1.27 1.27)
				)
				(justify mirror)
			)
		)
		(property "Value" ""
			(at 0 0 0)
			(layer "B.Fab")
			(effects
				(font
					(size 1.27 1.27)
				)
				(justify mirror)
			)
		)
		(duplicate_pad_numbers_are_jumpers no)
		(fp_line
			(start -0.7874 -0.4064)
			(end -0.7874 0.4064)
			(stroke
				(width 0.1524)
				(type default)
			)
			(layer "B.SilkS")
		)
		(fp_line
			(start -0.7874 0.4064)
			(end 0.7874 0.4064)
			(stroke
				(width 0.1524)
				(type default)
			)
			(layer "B.SilkS")
		)
		(fp_line
			(start 0.7874 -0.4064)
			(end -0.7874 -0.4064)
			(stroke
				(width 0.1524)
				(type default)
			)
			(layer "B.SilkS")
		)
		(fp_line
			(start 0.7874 0.4064)
			(end 0.7874 -0.4064)
			(stroke
				(width 0.1524)
				(type default)
			)
			(layer "B.SilkS")
		)
		(fp_line
			(start -0.67945 -0.3048)
			(end -0.67945 0.3048)
			(stroke
				(width 0.1)
				(type default)
			)
			(layer "B.Fab")
		)
		(fp_line
			(start -0.67945 0.3048)
			(end -0.120396 0.3048)
			(stroke
				(width 0.1)
				(type default)
			)
			(layer "B.Fab")
		)
		(fp_line
			(start -0.12065 -0.3048)
			(end -0.67945 -0.3048)
			(stroke
				(width 0.1)
				(type default)
			)
			(layer "B.Fab")
		)
		(fp_line
			(start -0.12065 -0.2794)
			(end -0.12065 -0.3048)
			(stroke
				(width 0.1)
				(type default)
			)
			(layer "B.Fab")
		)
		(fp_line
			(start -0.120396 0.2794)
			(end 0.12065 0.2794)
			(stroke
				(width 0.1)
				(type default)
			)
			(layer "B.Fab")
		)
		(fp_line
			(start -0.120396 0.3048)
			(end -0.120396 0.2794)
			(stroke
				(width 0.1)
				(type default)
			)
			(layer "B.Fab")
		)
		(fp_line
			(start 0.12065 -0.305054)
			(end 0.12065 -0.2794)
			(stroke
				(width 0.1)
				(type default)
			)
			(layer "B.Fab")
		)
		(fp_line
			(start 0.12065 -0.2794)
			(end -0.12065 -0.2794)
			(stroke
				(width 0.1)
				(type default)
			)
			(layer "B.Fab")
		)
		(fp_line
			(start 0.12065 0.2794)
			(end 0.12065 0.3048)
			(stroke
				(width 0.1)
				(type default)
			)
			(layer "B.Fab")
		)
		(fp_line
			(start 0.12065 0.3048)
			(end 0.67945 0.3048)
			(stroke
				(width 0.1)
				(type default)
			)
			(layer "B.Fab")
		)
		(fp_line
			(start 0.67945 -0.305054)
			(end 0.12065 -0.305054)
			(stroke
				(width 0.1)
				(type default)
			)
			(layer "B.Fab")
		)
		(fp_line
			(start 0.67945 0.3048)
			(end 0.67945 -0.305054)
			(stroke
				(width 0.1)
				(type default)
			)
			(layer "B.Fab")
		)
		(pad "1" smd circle
			(at 0.40005 0 180)
			(size 0 0)
			(layers "B.Cu" "B.Mask" "B.Paste")
			(net "P3V3_AUX")
		)
		(pad "2" smd circle
			(at -0.40005 0 180)
			(size 0 0)
			(layers "B.Cu" "B.Mask" "B.Paste")
			(net "GND")
		)
	)
	(footprint ""
		(layer "B.Cu")
		(at 146.80057 -385.50088 -90)
		(property "Reference" "C386"
			(at 0 0 90)
			(layer "B.SilkS")
			(hide yes)
			(effects
				(font
					(size 1.27 1.27)
				)
				(justify mirror)
			)
		)
		(property "Value" ""
			(at 0 0 90)
			(layer "B.Fab")
			(effects
				(font
					(size 1.27 1.27)
				)
				(justify mirror)
			)
		)
		(duplicate_pad_numbers_are_jumpers no)
		(fp_line
			(start -0.299974 0.150114)
			(end 0.299974 0.150114)
			(stroke
				(width 0.1)
				(type default)
			)
			(layer "B.Fab")
		)
		(fp_line
			(start 0.299974 0.150114)
			(end 0.299974 -0.150114)
			(stroke
				(width 0.1)
				(type default)
			)
			(layer "B.Fab")
		)
		(fp_line
			(start -0.299974 -0.150114)
			(end -0.299974 0.150114)
			(stroke
				(width 0.1)
				(type default)
			)
			(layer "B.Fab")
		)
		(fp_line
			(start 0.299974 -0.150114)
			(end -0.299974 -0.150114)
			(stroke
				(width 0.1)
				(type default)
			)
			(layer "B.Fab")
		)
		(pad "1" smd rect
			(at 0.2667 0 90)
			(size 0.3048 0.381)
			(layers "B.Cu" "B.Mask" "B.Paste")
			(net "P0V9_CPU1_RT2_2A")
		)
		(pad "2" smd rect
			(at -0.2667 0 90)
			(size 0.3048 0.381)
			(layers "B.Cu" "B.Mask" "B.Paste")
			(net "GND")
		)
	)
	(footprint ""
		(layer "B.Cu")
		(at 426.53585 -30.927548)
		(property "Reference" "R6040"
			(at 0 0 0)
			(layer "B.SilkS")
			(hide yes)
			(effects
				(font
					(size 1.27 1.27)
				)
				(justify mirror)
			)
		)
		(property "Value" ""
			(at 0 0 0)
			(layer "B.Fab")
			(effects
				(font
					(size 1.27 1.27)
				)
				(justify mirror)
			)
		)
		(duplicate_pad_numbers_are_jumpers no)
		(fp_line
			(start -0.7874 -0.4064)
			(end -0.7874 0.4064)
			(stroke
				(width 0.1524)
				(type default)
			)
			(layer "B.SilkS")
		)
		(fp_line
			(start -0.7874 0.4064)
			(end 0.7874 0.4064)
			(stroke
				(width 0.1524)
				(type default)
			)
			(layer "B.SilkS")
		)
		(fp_line
			(start 0.7874 -0.4064)
			(end -0.7874 -0.4064)
			(stroke
				(width 0.1524)
				(type default)
			)
			(layer "B.SilkS")
		)
		(fp_line
			(start 0.7874 0.4064)
			(end 0.7874 -0.4064)
			(stroke
				(width 0.1524)
				(type default)
			)
			(layer "B.SilkS")
		)
		(fp_line
			(start -0.67945 -0.3048)
			(end -0.67945 0.3048)
			(stroke
				(width 0.1)
				(type default)
			)
			(layer "B.Fab")
		)
		(fp_line
			(start -0.67945 0.3048)
			(end -0.120396 0.3048)
			(stroke
				(width 0.1)
				(type default)
			)
			(layer "B.Fab")
		)
		(fp_line
			(start -0.12065 -0.3048)
			(end -0.67945 -0.3048)
			(stroke
				(width 0.1)
				(type default)
			)
			(layer "B.Fab")
		)
		(fp_line
			(start -0.12065 -0.2794)
			(end -0.12065 -0.3048)
			(stroke
				(width 0.1)
				(type default)
			)
			(layer "B.Fab")
		)
		(fp_line
			(start -0.120396 0.2794)
			(end 0.12065 0.2794)
			(stroke
				(width 0.1)
				(type default)
			)
			(layer "B.Fab")
		)
		(fp_line
			(start -0.120396 0.3048)
			(end -0.120396 0.2794)
			(stroke
				(width 0.1)
				(type default)
			)
			(layer "B.Fab")
		)
		(fp_line
			(start 0.12065 -0.305054)
			(end 0.12065 -0.2794)
			(stroke
				(width 0.1)
				(type default)
			)
			(layer "B.Fab")
		)
		(fp_line
			(start 0.12065 -0.2794)
			(end -0.12065 -0.2794)
			(stroke
				(width 0.1)
				(type default)
			)
			(layer "B.Fab")
		)
		(fp_line
			(start 0.12065 0.2794)
			(end 0.12065 0.3048)
			(stroke
				(width 0.1)
				(type default)
			)
			(layer "B.Fab")
		)
		(fp_line
			(start 0.12065 0.3048)
			(end 0.67945 0.3048)
			(stroke
				(width 0.1)
				(type default)
			)
			(layer "B.Fab")
		)
		(fp_line
			(start 0.67945 -0.305054)
			(end 0.12065 -0.305054)
			(stroke
				(width 0.1)
				(type default)
			)
			(layer "B.Fab")
		)
		(fp_line
			(start 0.67945 0.3048)
			(end 0.67945 -0.305054)
			(stroke
				(width 0.1)
				(type default)
			)
			(layer "B.Fab")
		)
		(pad "1" smd circle
			(at 0.40005 0 180)
			(size 0 0)
			(layers "B.Cu" "B.Mask" "B.Paste")
			(net "P1V8_AUX")
		)
		(pad "2" smd circle
			(at -0.40005 0 180)
			(size 0 0)
			(layers "B.Cu" "B.Mask" "B.Paste")
			(net "PU_FPGA_DEBUG_LED_CTRL")
		)
	)
	(footprint ""
		(layer "B.Cu")
		(at 123.766834 -245.868952 -90)
		(property "Reference" "C2336"
			(at 0 0 90)
			(layer "B.SilkS")
			(hide yes)
			(effects
				(font
					(size 1.27 1.27)
				)
				(justify mirror)
			)
		)
		(property "Value" ""
			(at 0 0 90)
			(layer "B.Fab")
			(effects
				(font
					(size 1.27 1.27)
				)
				(justify mirror)
			)
		)
		(duplicate_pad_numbers_are_jumpers no)
		(fp_line
			(start -0.7874 0.4064)
			(end 0.7874 0.4064)
			(stroke
				(width 0.1524)
				(type default)
			)
			(layer "B.SilkS")
		)
		(fp_line
			(start 0.7874 0.4064)
			(end 0.7874 -0.4064)
			(stroke
				(width 0.1524)
				(type default)
			)
			(layer "B.SilkS")
		)
		(fp_line
			(start -0.7874 -0.4064)
			(end -0.7874 0.4064)
			(stroke
				(width 0.1524)
				(type default)
			)
			(layer "B.SilkS")
		)
		(fp_line
			(start 0.7874 -0.4064)
			(end -0.7874 -0.4064)
			(stroke
				(width 0.1524)
				(type default)
			)
			(layer "B.SilkS")
		)
		(fp_line
			(start -0.67945 0.3048)
			(end -0.120396 0.3048)
			(stroke
				(width 0.1)
				(type default)
			)
			(layer "B.Fab")
		)
		(fp_line
			(start -0.120396 0.3048)
			(end -0.120396 0.2794)
			(stroke
				(width 0.1)
				(type default)
			)
			(layer "B.Fab")
		)
		(fp_line
			(start 0.12065 0.3048)
			(end 0.67945 0.3048)
			(stroke
				(width 0.1)
				(type default)
			)
			(layer "B.Fab")
		)
		(fp_line
			(start 0.67945 0.3048)
			(end 0.67945 -0.305054)
			(stroke
				(width 0.1)
				(type default)
			)
			(layer "B.Fab")
		)
		(fp_line
			(start -0.120396 0.2794)
			(end 0.12065 0.2794)
			(stroke
				(width 0.1)
				(type default)
			)
			(layer "B.Fab")
		)
		(fp_line
			(start 0.12065 0.2794)
			(end 0.12065 0.3048)
			(stroke
				(width 0.1)
				(type default)
			)
			(layer "B.Fab")
		)
		(fp_line
			(start -0.12065 -0.2794)
			(end -0.12065 -0.3048)
			(stroke
				(width 0.1)
				(type default)
			)
			(layer "B.Fab")
		)
		(fp_line
			(start 0.12065 -0.2794)
			(end -0.12065 -0.2794)
			(stroke
				(width 0.1)
				(type default)
			)
			(layer "B.Fab")
		)
		(fp_line
			(start -0.67945 -0.3048)
			(end -0.67945 0.3048)
			(stroke
				(width 0.1)
				(type default)
			)
			(layer "B.Fab")
		)
		(fp_line
			(start -0.12065 -0.3048)
			(end -0.67945 -0.3048)
			(stroke
				(width 0.1)
				(type default)
			)
			(layer "B.Fab")
		)
		(fp_line
			(start 0.12065 -0.305054)
			(end 0.12065 -0.2794)
			(stroke
				(width 0.1)
				(type default)
			)
			(layer "B.Fab")
		)
		(fp_line
			(start 0.67945 -0.305054)
			(end 0.12065 -0.305054)
			(stroke
				(width 0.1)
				(type default)
			)
			(layer "B.Fab")
		)
		(pad "1" smd circle
			(at 0.40005 0 90)
			(size 0 0)
			(layers "B.Cu" "B.Mask" "B.Paste")
			(net "PVDDCR_CPU0_P1")
		)
		(pad "2" smd circle
			(at -0.40005 0 90)
			(size 0 0)
			(layers "B.Cu" "B.Mask" "B.Paste")
			(net "GND")
		)
	)
	(footprint ""
		(layer "B.Cu")
		(at 402.42617 -202.500484)
		(property "Reference" "U3"
			(at 2.032 -2.377948 0)
			(unlocked yes)
			(layer "B.SilkS")
			(effects
				(font
					(size 0.7874 0.5842)
					(thickness 0.1524)
				)
				(justify left mirror)
			)
		)
		(property "Value" ""
			(at 0 0 0)
			(layer "B.Fab")
			(effects
				(font
					(size 1.27 1.27)
				)
				(justify mirror)
			)
		)
		(duplicate_pad_numbers_are_jumpers no)
		(fp_line
			(start -2.0574 -1.651)
			(end -2.0574 1.651)
			(stroke
				(width 0.1524)
				(type default)
			)
			(layer "B.SilkS")
		)
		(fp_line
			(start -2.0574 1.651)
			(end 2.0574 1.651)
			(stroke
				(width 0.1524)
				(type default)
			)
			(layer "B.SilkS")
		)
		(fp_line
			(start -0.381 -1.651)
			(end -2.0574 -1.651)
			(stroke
				(width 0.1524)
				(type default)
			)
			(layer "B.SilkS")
		)
		(fp_line
			(start 0 -1.016)
			(end -0.381 -1.651)
			(stroke
				(width 0.1524)
				(type default)
			)
			(layer "B.SilkS")
		)
		(fp_line
			(start 0.381 -1.651)
			(end 0 -1.016)
			(stroke
				(width 0.1524)
				(type default)
			)
			(layer "B.SilkS")
		)
		(fp_line
			(start 2.0574 -1.651)
			(end 0.381 -1.651)
			(stroke
				(width 0.1524)
				(type default)
			)
			(layer "B.SilkS")
		)
		(fp_line
			(start 2.0574 1.651)
			(end 2.0574 -1.651)
			(stroke
				(width 0.1524)
				(type default)
			)
			(layer "B.SilkS")
		)
		(fp_poly
			(pts
				(xy 2.159 -1.016) (xy 2.71272 -1.344168) (xy 2.71272 -0.719328)
			)
			(stroke
				(width 0)
				(type default)
			)
			(fill yes)
			(layer "B.SilkS")
		)
		(fp_line
			(start -1.599946 -1.199896)
			(end -1.599946 1.199896)
			(stroke
				(width 0.1)
				(type default)
			)
			(layer "B.Fab")
		)
		(fp_line
			(start -1.599946 1.199896)
			(end -0.899922 1.199896)
			(stroke
				(width 0.1)
				(type default)
			)
			(layer "B.Fab")
		)
		(fp_line
			(start -0.899922 -1.549908)
			(end -0.899922 -1.199896)
			(stroke
				(width 0.1)
				(type default)
			)
			(layer "B.Fab")
		)
		(fp_line
			(start -0.899922 -1.199896)
			(end -1.599946 -1.199896)
			(stroke
				(width 0.1)
				(type default)
			)
			(layer "B.Fab")
		)
		(fp_line
			(start -0.899922 1.199896)
			(end -0.899922 1.549908)
			(stroke
				(width 0.1)
				(type default)
			)
			(layer "B.Fab")
		)
		(fp_line
			(start -0.899922 1.549908)
			(end 0.899922 1.549908)
			(stroke
				(width 0.1)
				(type default)
			)
			(layer "B.Fab")
		)
		(fp_line
			(start 0.899922 -1.549908)
			(end -0.899922 -1.549908)
			(stroke
				(width 0.1)
				(type default)
			)
			(layer "B.Fab")
		)
		(fp_line
			(start 0.899922 -1.199896)
			(end 0.899922 -1.549908)
			(stroke
				(width 0.1)
				(type default)
			)
			(layer "B.Fab")
		)
		(fp_line
			(start 0.899922 1.199896)
			(end 1.599946 1.199896)
			(stroke
				(width 0.1)
				(type default)
			)
			(layer "B.Fab")
		)
		(fp_line
			(start 0.899922 1.549908)
			(end 0.899922 1.199896)
			(stroke
				(width 0.1)
				(type default)
			)
			(layer "B.Fab")
		)
		(fp_line
			(start 1.599946 -1.199896)
			(end 0.899922 -1.199896)
			(stroke
				(width 0.1)
				(type default)
			)
			(layer "B.Fab")
		)
		(fp_line
			(start 1.599946 1.199896)
			(end 1.599946 -1.199896)
			(stroke
				(width 0.1)
				(type default)
			)
			(layer "B.Fab")
		)
		(fp_poly
			(pts
				(xy 2.71272 -0.719328) (xy 2.71272 -1.344168) (xy 2.159 -1.016)
			)
			(stroke
				(width 0)
				(type default)
			)
			(fill yes)
			(layer "B.Fab")
		)
		(pad "1" smd rect
			(at 1.225042 -0.94996 270)
			(size 0.5588 1.3462)
			(layers "B.Cu" "B.Mask" "B.Paste")
			(net "Net_10733")
		)
		(pad "2" smd rect
			(at 1.225042 0 270)
			(size 0.5588 1.3462)
			(layers "B.Cu" "B.Mask" "B.Paste")
			(net "SCM_USB_OC_N")
		)
		(pad "3" smd rect
			(at 1.225042 0.94996 270)
			(size 0.5588 1.3462)
			(layers "B.Cu" "B.Mask" "B.Paste")
			(net "GND")
		)
		(pad "4" smd rect
			(at -1.225042 0.94996 270)
			(size 0.5588 1.3462)
			(layers "B.Cu" "B.Mask" "B.Paste")
			(net "SCM_USB_OC_BU_R_N")
		)
		(pad "5" smd rect
			(at -1.225042 -0.94996 270)
			(size 0.5588 1.3462)
			(layers "B.Cu" "B.Mask" "B.Paste")
			(net "P1V8_AUX")
		)
	)
	(footprint ""
		(layer "B.Cu")
		(at 318.306958 -203.917296 -90)
		(property "Reference" "R390"
			(at 0 0 90)
			(layer "B.SilkS")
			(hide yes)
			(effects
				(font
					(size 1.27 1.27)
				)
				(justify mirror)
			)
		)
		(property "Value" ""
			(at 0 0 90)
			(layer "B.Fab")
			(effects
				(font
					(size 1.27 1.27)
				)
				(justify mirror)
			)
		)
		(duplicate_pad_numbers_are_jumpers no)
		(fp_line
			(start -0.7874 0.4064)
			(end 0.7874 0.4064)
			(stroke
				(width 0.1524)
				(type default)
			)
			(layer "B.SilkS")
		)
		(fp_line
			(start 0.7874 0.4064)
			(end 0.7874 -0.4064)
			(stroke
				(width 0.1524)
				(type default)
			)
			(layer "B.SilkS")
		)
		(fp_line
			(start -0.7874 -0.4064)
			(end -0.7874 0.4064)
			(stroke
				(width 0.1524)
				(type default)
			)
			(layer "B.SilkS")
		)
		(fp_line
			(start 0.7874 -0.4064)
			(end -0.7874 -0.4064)
			(stroke
				(width 0.1524)
				(type default)
			)
			(layer "B.SilkS")
		)
		(fp_line
			(start -0.67945 0.3048)
			(end -0.120396 0.3048)
			(stroke
				(width 0.1)
				(type default)
			)
			(layer "B.Fab")
		)
		(fp_line
			(start -0.120396 0.3048)
			(end -0.120396 0.2794)
			(stroke
				(width 0.1)
				(type default)
			)
			(layer "B.Fab")
		)
		(fp_line
			(start 0.12065 0.3048)
			(end 0.67945 0.3048)
			(stroke
				(width 0.1)
				(type default)
			)
			(layer "B.Fab")
		)
		(fp_line
			(start 0.67945 0.3048)
			(end 0.67945 -0.305054)
			(stroke
				(width 0.1)
				(type default)
			)
			(layer "B.Fab")
		)
		(fp_line
			(start -0.120396 0.2794)
			(end 0.12065 0.2794)
			(stroke
				(width 0.1)
				(type default)
			)
			(layer "B.Fab")
		)
		(fp_line
			(start 0.12065 0.2794)
			(end 0.12065 0.3048)
			(stroke
				(width 0.1)
				(type default)
			)
			(layer "B.Fab")
		)
		(fp_line
			(start -0.12065 -0.2794)
			(end -0.12065 -0.3048)
			(stroke
				(width 0.1)
				(type default)
			)
			(layer "B.Fab")
		)
		(fp_line
			(start 0.12065 -0.2794)
			(end -0.12065 -0.2794)
			(stroke
				(width 0.1)
				(type default)
			)
			(layer "B.Fab")
		)
		(fp_line
			(start -0.67945 -0.3048)
			(end -0.67945 0.3048)
			(stroke
				(width 0.1)
				(type default)
			)
			(layer "B.Fab")
		)
		(fp_line
			(start -0.12065 -0.3048)
			(end -0.67945 -0.3048)
			(stroke
				(width 0.1)
				(type default)
			)
			(layer "B.Fab")
		)
		(fp_line
			(start 0.12065 -0.305054)
			(end 0.12065 -0.2794)
			(stroke
				(width 0.1)
				(type default)
			)
			(layer "B.Fab")
		)
		(fp_line
			(start 0.67945 -0.305054)
			(end 0.12065 -0.305054)
			(stroke
				(width 0.1)
				(type default)
			)
			(layer "B.Fab")
		)
		(pad "1" smd circle
			(at 0.40005 0 90)
			(size 0 0)
			(layers "B.Cu" "B.Mask" "B.Paste")
			(net "P3V3_AUX")
		)
		(pad "2" smd circle
			(at -0.40005 0 90)
			(size 0 0)
			(layers "B.Cu" "B.Mask" "B.Paste")
			(net "CPU0_CORETYPE0")
		)
	)
	(footprint ""
		(layer "B.Cu")
		(at 449.5546 -10.594086 90)
		(property "Reference" "R8423"
			(at 0 0 90)
			(layer "B.SilkS")
			(hide yes)
			(effects
				(font
					(size 1.27 1.27)
				)
				(justify mirror)
			)
		)
		(property "Value" ""
			(at 0 0 90)
			(layer "B.Fab")
			(effects
				(font
					(size 1.27 1.27)
				)
				(justify mirror)
			)
		)
		(duplicate_pad_numbers_are_jumpers no)
		(fp_line
			(start 0.7874 -0.4064)
			(end -0.7874 -0.4064)
			(stroke
				(width 0.1524)
				(type default)
			)
			(layer "B.SilkS")
		)
		(fp_line
			(start -0.7874 -0.4064)
			(end -0.7874 0.4064)
			(stroke
				(width 0.1524)
				(type default)
			)
			(layer "B.SilkS")
		)
		(fp_line
			(start 0.7874 0.4064)
			(end 0.7874 -0.4064)
			(stroke
				(width 0.1524)
				(type default)
			)
			(layer "B.SilkS")
		)
		(fp_line
			(start -0.7874 0.4064)
			(end 0.7874 0.4064)
			(stroke
				(width 0.1524)
				(type default)
			)
			(layer "B.SilkS")
		)
		(fp_line
			(start 0.67945 -0.305054)
			(end 0.12065 -0.305054)
			(stroke
				(width 0.1)
				(type default)
			)
			(layer "B.Fab")
		)
		(fp_line
			(start 0.12065 -0.305054)
			(end 0.12065 -0.2794)
			(stroke
				(width 0.1)
				(type default)
			)
			(layer "B.Fab")
		)
		(fp_line
			(start -0.12065 -0.3048)
			(end -0.67945 -0.3048)
			(stroke
				(width 0.1)
				(type default)
			)
			(layer "B.Fab")
		)
		(fp_line
			(start -0.67945 -0.3048)
			(end -0.67945 0.3048)
			(stroke
				(width 0.1)
				(type default)
			)
			(layer "B.Fab")
		)
		(fp_line
			(start 0.12065 -0.2794)
			(end -0.12065 -0.2794)
			(stroke
				(width 0.1)
				(type default)
			)
			(layer "B.Fab")
		)
		(fp_line
			(start -0.12065 -0.2794)
			(end -0.12065 -0.3048)
			(stroke
				(width 0.1)
				(type default)
			)
			(layer "B.Fab")
		)
		(fp_line
			(start 0.12065 0.2794)
			(end 0.12065 0.3048)
			(stroke
				(width 0.1)
				(type default)
			)
			(layer "B.Fab")
		)
		(fp_line
			(start -0.120396 0.2794)
			(end 0.12065 0.2794)
			(stroke
				(width 0.1)
				(type default)
			)
			(layer "B.Fab")
		)
		(fp_line
			(start 0.67945 0.3048)
			(end 0.67945 -0.305054)
			(stroke
				(width 0.1)
				(type default)
			)
			(layer "B.Fab")
		)
		(fp_line
			(start 0.12065 0.3048)
			(end 0.67945 0.3048)
			(stroke
				(width 0.1)
				(type default)
			)
			(layer "B.Fab")
		)
		(fp_line
			(start -0.120396 0.3048)
			(end -0.120396 0.2794)
			(stroke
				(width 0.1)
				(type default)
			)
			(layer "B.Fab")
		)
		(fp_line
			(start -0.67945 0.3048)
			(end -0.120396 0.3048)
			(stroke
				(width 0.1)
				(type default)
			)
			(layer "B.Fab")
		)
		(pad "1" smd circle
			(at 0.40005 0 270)
			(size 0 0)
			(layers "B.Cu" "B.Mask" "B.Paste")
			(net "SGPIO_OCP_SFF_CLK")
		)
		(pad "2" smd circle
			(at -0.40005 0 270)
			(size 0 0)
			(layers "B.Cu" "B.Mask" "B.Paste")
			(net "P3V3_OCP_SFF")
		)
	)
	(footprint ""
		(layer "B.Cu")
		(at 197.94855 -194.8942 180)
		(property "Reference" "R1590"
			(at 0 0 0)
			(layer "B.SilkS")
			(hide yes)
			(effects
				(font
					(size 1.27 1.27)
				)
				(justify mirror)
			)
		)
		(property "Value" ""
			(at 0 0 0)
			(layer "B.Fab")
			(effects
				(font
					(size 1.27 1.27)
				)
				(justify mirror)
			)
		)
		(duplicate_pad_numbers_are_jumpers no)
		(fp_line
			(start 0.7874 0.4064)
			(end 0.7874 -0.4064)
			(stroke
				(width 0.1524)
				(type default)
			)
			(layer "B.SilkS")
		)
		(fp_line
			(start 0.7874 -0.4064)
			(end -0.7874 -0.4064)
			(stroke
				(width 0.1524)
				(type default)
			)
			(layer "B.SilkS")
		)
		(fp_line
			(start -0.7874 0.4064)
			(end 0.7874 0.4064)
			(stroke
				(width 0.1524)
				(type default)
			)
			(layer "B.SilkS")
		)
		(fp_line
			(start -0.7874 -0.4064)
			(end -0.7874 0.4064)
			(stroke
				(width 0.1524)
				(type default)
			)
			(layer "B.SilkS")
		)
		(fp_line
			(start 0.67945 0.3048)
			(end 0.67945 -0.305054)
			(stroke
				(width 0.1)
				(type default)
			)
			(layer "B.Fab")
		)
		(fp_line
			(start 0.67945 -0.305054)
			(end 0.12065 -0.305054)
			(stroke
				(width 0.1)
				(type default)
			)
			(layer "B.Fab")
		)
		(fp_line
			(start 0.12065 0.3048)
			(end 0.67945 0.3048)
			(stroke
				(width 0.1)
				(type default)
			)
			(layer "B.Fab")
		)
		(fp_line
			(start 0.12065 0.2794)
			(end 0.12065 0.3048)
			(stroke
				(width 0.1)
				(type default)
			)
			(layer "B.Fab")
		)
		(fp_line
			(start 0.12065 -0.2794)
			(end -0.12065 -0.2794)
			(stroke
				(width 0.1)
				(type default)
			)
			(layer "B.Fab")
		)
		(fp_line
			(start 0.12065 -0.305054)
			(end 0.12065 -0.2794)
			(stroke
				(width 0.1)
				(type default)
			)
			(layer "B.Fab")
		)
		(fp_line
			(start -0.120396 0.3048)
			(end -0.120396 0.2794)
			(stroke
				(width 0.1)
				(type default)
			)
			(layer "B.Fab")
		)
		(fp_line
			(start -0.120396 0.2794)
			(end 0.12065 0.2794)
			(stroke
				(width 0.1)
				(type default)
			)
			(layer "B.Fab")
		)
		(fp_line
			(start -0.12065 -0.2794)
			(end -0.12065 -0.3048)
			(stroke
				(width 0.1)
				(type default)
			)
			(layer "B.Fab")
		)
		(fp_line
			(start -0.12065 -0.3048)
			(end -0.67945 -0.3048)
			(stroke
				(width 0.1)
				(type default)
			)
			(layer "B.Fab")
		)
		(fp_line
			(start -0.67945 0.3048)
			(end -0.120396 0.3048)
			(stroke
				(width 0.1)
				(type default)
			)
			(layer "B.Fab")
		)
		(fp_line
			(start -0.67945 -0.3048)
			(end -0.67945 0.3048)
			(stroke
				(width 0.1)
				(type default)
			)
			(layer "B.Fab")
		)
		(pad "1" smd circle
			(at 0.40005 0)
			(size 0 0)
			(layers "B.Cu" "B.Mask" "B.Paste")
			(net "I3C_SPD_DDRGL_CPU1_SCL")
		)
		(pad "2" smd circle
			(at -0.40005 0)
			(size 0 0)
			(layers "B.Cu" "B.Mask" "B.Paste")
			(net "I3C_SPD_DDRK_CPU1_SCL")
		)
	)
	(footprint ""
		(layer "B.Cu")
		(at 185.166 -359.537)
		(property "Reference" "PC8006"
			(at 0 0 0)
			(layer "B.SilkS")
			(hide yes)
			(effects
				(font
					(size 1.27 1.27)
				)
				(justify mirror)
			)
		)
		(property "Value" ""
			(at 0 0 0)
			(layer "B.Fab")
			(effects
				(font
					(size 1.27 1.27)
				)
				(justify mirror)
			)
		)
		(duplicate_pad_numbers_are_jumpers no)
		(fp_line
			(start -1.524 -0.762)
			(end -1.524 0.762)
			(stroke
				(width 0.1524)
				(type default)
			)
			(layer "B.SilkS")
		)
		(fp_line
			(start -1.524 0.762)
			(end 1.524 0.762)
			(stroke
				(width 0.1524)
				(type default)
			)
			(layer "B.SilkS")
		)
		(fp_line
			(start 1.524 -0.762)
			(end -1.524 -0.762)
			(stroke
				(width 0.1524)
				(type default)
			)
			(layer "B.SilkS")
		)
		(fp_line
			(start 1.524 0.762)
			(end 1.524 -0.762)
			(stroke
				(width 0.1524)
				(type default)
			)
			(layer "B.SilkS")
		)
		(fp_line
			(start -1.1049 -0.724916)
			(end 1.1049 -0.724916)
			(stroke
				(width 0.1)
				(type default)
			)
			(layer "B.Fab")
		)
		(fp_line
			(start -1.1049 0.724916)
			(end -1.1049 -0.724916)
			(stroke
				(width 0.1)
				(type default)
			)
			(layer "B.Fab")
		)
		(fp_line
			(start 1.1049 -0.724916)
			(end 1.1049 0.724916)
			(stroke
				(width 0.1)
				(type default)
			)
			(layer "B.Fab")
		)
		(fp_line
			(start 1.1049 0.724916)
			(end -1.1049 0.724916)
			(stroke
				(width 0.1)
				(type default)
			)
			(layer "B.Fab")
		)
		(pad "1" smd rect
			(at 0.889 0)
			(size 1.016 1.27)
			(layers "B.Cu" "B.Mask" "B.Paste")
			(net "SW_P12V_AUX_PVDD11_S3_P1_FLT")
		)
		(pad "2" smd rect
			(at -0.889 0)
			(size 1.016 1.27)
			(layers "B.Cu" "B.Mask" "B.Paste")
			(net "GND")
		)
	)
	(footprint ""
		(layer "B.Cu")
		(at 365.09579 -392.1252 180)
		(property "Reference" "R1105"
			(at 0 0 0)
			(layer "B.SilkS")
			(hide yes)
			(effects
				(font
					(size 1.27 1.27)
				)
				(justify mirror)
			)
		)
		(property "Value" ""
			(at 0 0 0)
			(layer "B.Fab")
			(effects
				(font
					(size 1.27 1.27)
				)
				(justify mirror)
			)
		)
		(duplicate_pad_numbers_are_jumpers no)
		(fp_line
			(start 0.32512 0.175006)
			(end 0.32512 -0.175006)
			(stroke
				(width 0.1)
				(type default)
			)
			(layer "B.Fab")
		)
		(fp_line
			(start 0.32512 -0.175006)
			(end -0.32512 -0.175006)
			(stroke
				(width 0.1)
				(type default)
			)
			(layer "B.Fab")
		)
		(fp_line
			(start -0.32512 0.175006)
			(end 0.32512 0.175006)
			(stroke
				(width 0.1)
				(type default)
			)
			(layer "B.Fab")
		)
		(fp_line
			(start -0.32512 -0.175006)
			(end -0.32512 0.175006)
			(stroke
				(width 0.1)
				(type default)
			)
			(layer "B.Fab")
		)
		(pad "1" smd rect
			(at 0.2667 0)
			(size 0.3048 0.381)
			(layers "B.Cu" "B.Mask" "B.Paste")
			(net "P1V8_CPU0_RT_1D")
		)
		(pad "2" smd rect
			(at -0.2667 0 180)
			(size 0.3048 0.381)
			(layers "B.Cu" "B.Mask" "B.Paste")
			(net "RT_CPU0_P3_SCAN_MODE")
		)
	)
	(footprint ""
		(layer "B.Cu")
		(at 187.815728 -193.996564)
		(property "Reference" "R113"
			(at 0 0 0)
			(layer "B.SilkS")
			(hide yes)
			(effects
				(font
					(size 1.27 1.27)
				)
				(justify mirror)
			)
		)
		(property "Value" ""
			(at 0 0 0)
			(layer "B.Fab")
			(effects
				(font
					(size 1.27 1.27)
				)
				(justify mirror)
			)
		)
		(duplicate_pad_numbers_are_jumpers no)
		(fp_line
			(start -0.7874 -0.4064)
			(end -0.7874 0.4064)
			(stroke
				(width 0.1524)
				(type default)
			)
			(layer "B.SilkS")
		)
		(fp_line
			(start -0.7874 0.4064)
			(end 0.7874 0.4064)
			(stroke
				(width 0.1524)
				(type default)
			)
			(layer "B.SilkS")
		)
		(fp_line
			(start 0.7874 -0.4064)
			(end -0.7874 -0.4064)
			(stroke
				(width 0.1524)
				(type default)
			)
			(layer "B.SilkS")
		)
		(fp_line
			(start 0.7874 0.4064)
			(end 0.7874 -0.4064)
			(stroke
				(width 0.1524)
				(type default)
			)
			(layer "B.SilkS")
		)
		(fp_line
			(start -0.67945 -0.3048)
			(end -0.67945 0.3048)
			(stroke
				(width 0.1)
				(type default)
			)
			(layer "B.Fab")
		)
		(fp_line
			(start -0.67945 0.3048)
			(end -0.120396 0.3048)
			(stroke
				(width 0.1)
				(type default)
			)
			(layer "B.Fab")
		)
		(fp_line
			(start -0.12065 -0.3048)
			(end -0.67945 -0.3048)
			(stroke
				(width 0.1)
				(type default)
			)
			(layer "B.Fab")
		)
		(fp_line
			(start -0.12065 -0.2794)
			(end -0.12065 -0.3048)
			(stroke
				(width 0.1)
				(type default)
			)
			(layer "B.Fab")
		)
		(fp_line
			(start -0.120396 0.2794)
			(end 0.12065 0.2794)
			(stroke
				(width 0.1)
				(type default)
			)
			(layer "B.Fab")
		)
		(fp_line
			(start -0.120396 0.3048)
			(end -0.120396 0.2794)
			(stroke
				(width 0.1)
				(type default)
			)
			(layer "B.Fab")
		)
		(fp_line
			(start 0.12065 -0.305054)
			(end 0.12065 -0.2794)
			(stroke
				(width 0.1)
				(type default)
			)
			(layer "B.Fab")
		)
		(fp_line
			(start 0.12065 -0.2794)
			(end -0.12065 -0.2794)
			(stroke
				(width 0.1)
				(type default)
			)
			(layer "B.Fab")
		)
		(fp_line
			(start 0.12065 0.2794)
			(end 0.12065 0.3048)
			(stroke
				(width 0.1)
				(type default)
			)
			(layer "B.Fab")
		)
		(fp_line
			(start 0.12065 0.3048)
			(end 0.67945 0.3048)
			(stroke
				(width 0.1)
				(type default)
			)
			(layer "B.Fab")
		)
		(fp_line
			(start 0.67945 -0.305054)
			(end 0.12065 -0.305054)
			(stroke
				(width 0.1)
				(type default)
			)
			(layer "B.Fab")
		)
		(fp_line
			(start 0.67945 0.3048)
			(end 0.67945 -0.305054)
			(stroke
				(width 0.1)
				(type default)
			)
			(layer "B.Fab")
		)
		(pad "1" smd circle
			(at 0.40005 0 180)
			(size 0 0)
			(layers "B.Cu" "B.Mask" "B.Paste")
			(net "P3V3")
		)
		(pad "2" smd circle
			(at -0.40005 0 180)
			(size 0 0)
			(layers "B.Cu" "B.Mask" "B.Paste")
			(net "PWRGD_CHJ_CPU1_DIMM")
		)
	)
	(footprint ""
		(layer "B.Cu")
		(at 388.478522 -395.148562 90)
		(property "Reference" "C1019"
			(at 0 0 90)
			(layer "B.SilkS")
			(hide yes)
			(effects
				(font
					(size 1.27 1.27)
				)
				(justify mirror)
			)
		)
		(property "Value" ""
			(at 0 0 90)
			(layer "B.Fab")
			(effects
				(font
					(size 1.27 1.27)
				)
				(justify mirror)
			)
		)
		(duplicate_pad_numbers_are_jumpers no)
		(fp_line
			(start 0.299974 -0.150114)
			(end -0.299974 -0.150114)
			(stroke
				(width 0.1)
				(type default)
			)
			(layer "B.Fab")
		)
		(fp_line
			(start -0.299974 -0.150114)
			(end -0.299974 0.150114)
			(stroke
				(width 0.1)
				(type default)
			)
			(layer "B.Fab")
		)
		(fp_line
			(start 0.299974 0.150114)
			(end 0.299974 -0.150114)
			(stroke
				(width 0.1)
				(type default)
			)
			(layer "B.Fab")
		)
		(fp_line
			(start -0.299974 0.150114)
			(end 0.299974 0.150114)
			(stroke
				(width 0.1)
				(type default)
			)
			(layer "B.Fab")
		)
		(pad "1" smd rect
			(at 0.2667 0 270)
			(size 0.3048 0.381)
			(layers "B.Cu" "B.Mask" "B.Paste")
			(net "P0V9_CPU0_RT3_2A")
		)
		(pad "2" smd rect
			(at -0.2667 0 270)
			(size 0.3048 0.381)
			(layers "B.Cu" "B.Mask" "B.Paste")
			(net "GND")
		)
	)
	(footprint ""
		(layer "B.Cu")
		(at 254.635 -338.51596 180)
		(property "Reference" "R1374"
			(at 0 0 0)
			(layer "B.SilkS")
			(hide yes)
			(effects
				(font
					(size 1.27 1.27)
				)
				(justify mirror)
			)
		)
		(property "Value" ""
			(at 0 0 0)
			(layer "B.Fab")
			(effects
				(font
					(size 1.27 1.27)
				)
				(justify mirror)
			)
		)
		(duplicate_pad_numbers_are_jumpers no)
		(fp_line
			(start 0.32512 0.175006)
			(end 0.32512 -0.175006)
			(stroke
				(width 0.1)
				(type default)
			)
			(layer "B.Fab")
		)
		(fp_line
			(start 0.32512 -0.175006)
			(end -0.32512 -0.175006)
			(stroke
				(width 0.1)
				(type default)
			)
			(layer "B.Fab")
		)
		(fp_line
			(start -0.32512 0.175006)
			(end 0.32512 0.175006)
			(stroke
				(width 0.1)
				(type default)
			)
			(layer "B.Fab")
		)
		(fp_line
			(start -0.32512 -0.175006)
			(end -0.32512 0.175006)
			(stroke
				(width 0.1)
				(type default)
			)
			(layer "B.Fab")
		)
		(pad "1" smd rect
			(at 0.2667 0)
			(size 0.3048 0.381)
			(layers "B.Cu" "B.Mask" "B.Paste")
			(net "P1V8_CPU0_RT_1D")
		)
		(pad "2" smd rect
			(at -0.2667 0 180)
			(size 0.3048 0.381)
			(layers "B.Cu" "B.Mask" "B.Paste")
			(net "SMB_RT_CPU0_P1_ROM_MUX_2D_R_SCL")
		)
	)
	(footprint ""
		(layer "B.Cu")
		(at 140.168376 -386.745988 -90)
		(property "Reference" "C436"
			(at 0 0 90)
			(layer "B.SilkS")
			(hide yes)
			(effects
				(font
					(size 1.27 1.27)
				)
				(justify mirror)
			)
		)
		(property "Value" ""
			(at 0 0 90)
			(layer "B.Fab")
			(effects
				(font
					(size 1.27 1.27)
				)
				(justify mirror)
			)
		)
		(duplicate_pad_numbers_are_jumpers no)
		(fp_line
			(start -0.7874 0.4064)
			(end 0.7874 0.4064)
			(stroke
				(width 0.1524)
				(type default)
			)
			(layer "B.SilkS")
		)
		(fp_line
			(start 0.7874 0.4064)
			(end 0.7874 -0.4064)
			(stroke
				(width 0.1524)
				(type default)
			)
			(layer "B.SilkS")
		)
		(fp_line
			(start -0.7874 -0.4064)
			(end -0.7874 0.4064)
			(stroke
				(width 0.1524)
				(type default)
			)
			(layer "B.SilkS")
		)
		(fp_line
			(start 0.7874 -0.4064)
			(end -0.7874 -0.4064)
			(stroke
				(width 0.1524)
				(type default)
			)
			(layer "B.SilkS")
		)
		(fp_line
			(start -0.67945 0.3048)
			(end -0.120396 0.3048)
			(stroke
				(width 0.1)
				(type default)
			)
			(layer "B.Fab")
		)
		(fp_line
			(start -0.120396 0.3048)
			(end -0.120396 0.2794)
			(stroke
				(width 0.1)
				(type default)
			)
			(layer "B.Fab")
		)
		(fp_line
			(start 0.12065 0.3048)
			(end 0.67945 0.3048)
			(stroke
				(width 0.1)
				(type default)
			)
			(layer "B.Fab")
		)
		(fp_line
			(start 0.67945 0.3048)
			(end 0.67945 -0.305054)
			(stroke
				(width 0.1)
				(type default)
			)
			(layer "B.Fab")
		)
		(fp_line
			(start -0.120396 0.2794)
			(end 0.12065 0.2794)
			(stroke
				(width 0.1)
				(type default)
			)
			(layer "B.Fab")
		)
		(fp_line
			(start 0.12065 0.2794)
			(end 0.12065 0.3048)
			(stroke
				(width 0.1)
				(type default)
			)
			(layer "B.Fab")
		)
		(fp_line
			(start -0.12065 -0.2794)
			(end -0.12065 -0.3048)
			(stroke
				(width 0.1)
				(type default)
			)
			(layer "B.Fab")
		)
		(fp_line
			(start 0.12065 -0.2794)
			(end -0.12065 -0.2794)
			(stroke
				(width 0.1)
				(type default)
			)
			(layer "B.Fab")
		)
		(fp_line
			(start -0.67945 -0.3048)
			(end -0.67945 0.3048)
			(stroke
				(width 0.1)
				(type default)
			)
			(layer "B.Fab")
		)
		(fp_line
			(start -0.12065 -0.3048)
			(end -0.67945 -0.3048)
			(stroke
				(width 0.1)
				(type default)
			)
			(layer "B.Fab")
		)
		(fp_line
			(start 0.12065 -0.305054)
			(end 0.12065 -0.2794)
			(stroke
				(width 0.1)
				(type default)
			)
			(layer "B.Fab")
		)
		(fp_line
			(start 0.67945 -0.305054)
			(end 0.12065 -0.305054)
			(stroke
				(width 0.1)
				(type default)
			)
			(layer "B.Fab")
		)
		(pad "1" smd circle
			(at 0.40005 0 90)
			(size 0 0)
			(layers "B.Cu" "B.Mask" "B.Paste")
			(net "P1V8_CPU1_RT_1D")
		)
		(pad "2" smd circle
			(at -0.40005 0 90)
			(size 0 0)
			(layers "B.Cu" "B.Mask" "B.Paste")
			(net "GND")
		)
	)
	(footprint ""
		(layer "B.Cu")
		(at 358.216454 -267.52931)
		(property "Reference" "C2240"
			(at 0 0 0)
			(layer "B.SilkS")
			(hide yes)
			(effects
				(font
					(size 1.27 1.27)
				)
				(justify mirror)
			)
		)
		(property "Value" ""
			(at 0 0 0)
			(layer "B.Fab")
			(effects
				(font
					(size 1.27 1.27)
				)
				(justify mirror)
			)
		)
		(duplicate_pad_numbers_are_jumpers no)
		(fp_line
			(start -0.7874 -0.4064)
			(end -0.7874 0.4064)
			(stroke
				(width 0.1524)
				(type default)
			)
			(layer "B.SilkS")
		)
		(fp_line
			(start -0.7874 0.4064)
			(end 0.7874 0.4064)
			(stroke
				(width 0.1524)
				(type default)
			)
			(layer "B.SilkS")
		)
		(fp_line
			(start 0.7874 -0.4064)
			(end -0.7874 -0.4064)
			(stroke
				(width 0.1524)
				(type default)
			)
			(layer "B.SilkS")
		)
		(fp_line
			(start 0.7874 0.4064)
			(end 0.7874 -0.4064)
			(stroke
				(width 0.1524)
				(type default)
			)
			(layer "B.SilkS")
		)
		(fp_line
			(start -0.67945 -0.3048)
			(end -0.67945 0.3048)
			(stroke
				(width 0.1)
				(type default)
			)
			(layer "B.Fab")
		)
		(fp_line
			(start -0.67945 0.3048)
			(end -0.120396 0.3048)
			(stroke
				(width 0.1)
				(type default)
			)
			(layer "B.Fab")
		)
		(fp_line
			(start -0.12065 -0.3048)
			(end -0.67945 -0.3048)
			(stroke
				(width 0.1)
				(type default)
			)
			(layer "B.Fab")
		)
		(fp_line
			(start -0.12065 -0.2794)
			(end -0.12065 -0.3048)
			(stroke
				(width 0.1)
				(type default)
			)
			(layer "B.Fab")
		)
		(fp_line
			(start -0.120396 0.2794)
			(end 0.12065 0.2794)
			(stroke
				(width 0.1)
				(type default)
			)
			(layer "B.Fab")
		)
		(fp_line
			(start -0.120396 0.3048)
			(end -0.120396 0.2794)
			(stroke
				(width 0.1)
				(type default)
			)
			(layer "B.Fab")
		)
		(fp_line
			(start 0.12065 -0.305054)
			(end 0.12065 -0.2794)
			(stroke
				(width 0.1)
				(type default)
			)
			(layer "B.Fab")
		)
		(fp_line
			(start 0.12065 -0.2794)
			(end -0.12065 -0.2794)
			(stroke
				(width 0.1)
				(type default)
			)
			(layer "B.Fab")
		)
		(fp_line
			(start 0.12065 0.2794)
			(end 0.12065 0.3048)
			(stroke
				(width 0.1)
				(type default)
			)
			(layer "B.Fab")
		)
		(fp_line
			(start 0.12065 0.3048)
			(end 0.67945 0.3048)
			(stroke
				(width 0.1)
				(type default)
			)
			(layer "B.Fab")
		)
		(fp_line
			(start 0.67945 -0.305054)
			(end 0.12065 -0.305054)
			(stroke
				(width 0.1)
				(type default)
			)
			(layer "B.Fab")
		)
		(fp_line
			(start 0.67945 0.3048)
			(end 0.67945 -0.305054)
			(stroke
				(width 0.1)
				(type default)
			)
			(layer "B.Fab")
		)
		(pad "1" smd circle
			(at 0.40005 0 180)
			(size 0 0)
			(layers "B.Cu" "B.Mask" "B.Paste")
			(net "PVDDCR_CPU1_P0")
		)
		(pad "2" smd circle
			(at -0.40005 0 180)
			(size 0 0)
			(layers "B.Cu" "B.Mask" "B.Paste")
			(net "GND")
		)
	)
	(footprint ""
		(layer "B.Cu")
		(at 133.506972 -41.007792 90)
		(property "Reference" "C6032"
			(at 0 0 90)
			(layer "B.SilkS")
			(hide yes)
			(effects
				(font
					(size 1.27 1.27)
				)
				(justify mirror)
			)
		)
		(property "Value" ""
			(at 0 0 90)
			(layer "B.Fab")
			(effects
				(font
					(size 1.27 1.27)
				)
				(justify mirror)
			)
		)
		(duplicate_pad_numbers_are_jumpers no)
		(fp_line
			(start 0.7874 -0.4064)
			(end -0.7874 -0.4064)
			(stroke
				(width 0.1524)
				(type default)
			)
			(layer "B.SilkS")
		)
		(fp_line
			(start -0.7874 -0.4064)
			(end -0.7874 0.4064)
			(stroke
				(width 0.1524)
				(type default)
			)
			(layer "B.SilkS")
		)
		(fp_line
			(start 0.7874 0.4064)
			(end 0.7874 -0.4064)
			(stroke
				(width 0.1524)
				(type default)
			)
			(layer "B.SilkS")
		)
		(fp_line
			(start -0.7874 0.4064)
			(end 0.7874 0.4064)
			(stroke
				(width 0.1524)
				(type default)
			)
			(layer "B.SilkS")
		)
		(fp_line
			(start 0.67945 -0.305054)
			(end 0.12065 -0.305054)
			(stroke
				(width 0.1)
				(type default)
			)
			(layer "B.Fab")
		)
		(fp_line
			(start 0.12065 -0.305054)
			(end 0.12065 -0.2794)
			(stroke
				(width 0.1)
				(type default)
			)
			(layer "B.Fab")
		)
		(fp_line
			(start -0.12065 -0.3048)
			(end -0.67945 -0.3048)
			(stroke
				(width 0.1)
				(type default)
			)
			(layer "B.Fab")
		)
		(fp_line
			(start -0.67945 -0.3048)
			(end -0.67945 0.3048)
			(stroke
				(width 0.1)
				(type default)
			)
			(layer "B.Fab")
		)
		(fp_line
			(start 0.12065 -0.2794)
			(end -0.12065 -0.2794)
			(stroke
				(width 0.1)
				(type default)
			)
			(layer "B.Fab")
		)
		(fp_line
			(start -0.12065 -0.2794)
			(end -0.12065 -0.3048)
			(stroke
				(width 0.1)
				(type default)
			)
			(layer "B.Fab")
		)
		(fp_line
			(start 0.12065 0.2794)
			(end 0.12065 0.3048)
			(stroke
				(width 0.1)
				(type default)
			)
			(layer "B.Fab")
		)
		(fp_line
			(start -0.120396 0.2794)
			(end 0.12065 0.2794)
			(stroke
				(width 0.1)
				(type default)
			)
			(layer "B.Fab")
		)
		(fp_line
			(start 0.67945 0.3048)
			(end 0.67945 -0.305054)
			(stroke
				(width 0.1)
				(type default)
			)
			(layer "B.Fab")
		)
		(fp_line
			(start 0.12065 0.3048)
			(end 0.67945 0.3048)
			(stroke
				(width 0.1)
				(type default)
			)
			(layer "B.Fab")
		)
		(fp_line
			(start -0.120396 0.3048)
			(end -0.120396 0.2794)
			(stroke
				(width 0.1)
				(type default)
			)
			(layer "B.Fab")
		)
		(fp_line
			(start -0.67945 0.3048)
			(end -0.120396 0.3048)
			(stroke
				(width 0.1)
				(type default)
			)
			(layer "B.Fab")
		)
		(pad "1" smd circle
			(at 0.40005 0 270)
			(size 0 0)
			(layers "B.Cu" "B.Mask" "B.Paste")
			(net "P1V2_CPU0_USB_DVDD12")
		)
		(pad "2" smd circle
			(at -0.40005 0 270)
			(size 0 0)
			(layers "B.Cu" "B.Mask" "B.Paste")
			(net "GND")
		)
	)
	(footprint ""
		(layer "B.Cu")
		(at 461.498188 -389.132064 -90)
		(property "Reference" "PC6567_1"
			(at 0 0 90)
			(layer "B.SilkS")
			(hide yes)
			(effects
				(font
					(size 1.27 1.27)
				)
				(justify mirror)
			)
		)
		(property "Value" ""
			(at 0 0 90)
			(layer "B.Fab")
			(effects
				(font
					(size 1.27 1.27)
				)
				(justify mirror)
			)
		)
		(duplicate_pad_numbers_are_jumpers no)
		(fp_line
			(start -1.524 0.762)
			(end 1.524 0.762)
			(stroke
				(width 0.1524)
				(type default)
			)
			(layer "B.SilkS")
		)
		(fp_line
			(start 1.524 0.762)
			(end 1.524 -0.762)
			(stroke
				(width 0.1524)
				(type default)
			)
			(layer "B.SilkS")
		)
		(fp_line
			(start -1.524 -0.762)
			(end -1.524 0.762)
			(stroke
				(width 0.1524)
				(type default)
			)
			(layer "B.SilkS")
		)
		(fp_line
			(start 1.524 -0.762)
			(end -1.524 -0.762)
			(stroke
				(width 0.1524)
				(type default)
			)
			(layer "B.SilkS")
		)
		(fp_line
			(start -1.1049 0.724916)
			(end -1.1049 -0.724916)
			(stroke
				(width 0.1)
				(type default)
			)
			(layer "B.Fab")
		)
		(fp_line
			(start 1.1049 0.724916)
			(end -1.1049 0.724916)
			(stroke
				(width 0.1)
				(type default)
			)
			(layer "B.Fab")
		)
		(fp_line
			(start -1.1049 -0.724916)
			(end 1.1049 -0.724916)
			(stroke
				(width 0.1)
				(type default)
			)
			(layer "B.Fab")
		)
		(fp_line
			(start 1.1049 -0.724916)
			(end 1.1049 0.724916)
			(stroke
				(width 0.1)
				(type default)
			)
			(layer "B.Fab")
		)
		(pad "1" smd rect
			(at 0.889 0 270)
			(size 1.016 1.27)
			(layers "B.Cu" "B.Mask" "B.Paste")
			(net "P0V9_CPU0_RT_2D")
		)
		(pad "2" smd rect
			(at -0.889 0 270)
			(size 1.016 1.27)
			(layers "B.Cu" "B.Mask" "B.Paste")
			(net "GND")
		)
	)
	(footprint ""
		(layer "B.Cu")
		(at 447.237866 -407.6573)
		(property "Reference" "PC6816"
			(at 0 0 0)
			(layer "B.SilkS")
			(hide yes)
			(effects
				(font
					(size 1.27 1.27)
				)
				(justify mirror)
			)
		)
		(property "Value" ""
			(at 0 0 0)
			(layer "B.Fab")
			(effects
				(font
					(size 1.27 1.27)
				)
				(justify mirror)
			)
		)
		(duplicate_pad_numbers_are_jumpers no)
		(fp_line
			(start -1.524 -0.762)
			(end -1.524 0.762)
			(stroke
				(width 0.1524)
				(type default)
			)
			(layer "B.SilkS")
		)
		(fp_line
			(start -1.524 0.762)
			(end 1.524 0.762)
			(stroke
				(width 0.1524)
				(type default)
			)
			(layer "B.SilkS")
		)
		(fp_line
			(start 1.524 -0.762)
			(end -1.524 -0.762)
			(stroke
				(width 0.1524)
				(type default)
			)
			(layer "B.SilkS")
		)
		(fp_line
			(start 1.524 0.762)
			(end 1.524 -0.762)
			(stroke
				(width 0.1524)
				(type default)
			)
			(layer "B.SilkS")
		)
		(fp_line
			(start -1.1049 -0.724916)
			(end 1.1049 -0.724916)
			(stroke
				(width 0.1)
				(type default)
			)
			(layer "B.Fab")
		)
		(fp_line
			(start -1.1049 0.724916)
			(end -1.1049 -0.724916)
			(stroke
				(width 0.1)
				(type default)
			)
			(layer "B.Fab")
		)
		(fp_line
			(start 1.1049 -0.724916)
			(end 1.1049 0.724916)
			(stroke
				(width 0.1)
				(type default)
			)
			(layer "B.Fab")
		)
		(fp_line
			(start 1.1049 0.724916)
			(end -1.1049 0.724916)
			(stroke
				(width 0.1)
				(type default)
			)
			(layer "B.Fab")
		)
		(pad "1" smd rect
			(at 0.889 0)
			(size 1.016 1.27)
			(layers "B.Cu" "B.Mask" "B.Paste")
			(net "SW_P12V_AUX_P0V9_RETIMER_CPU0_FLT")
		)
		(pad "2" smd rect
			(at -0.889 0)
			(size 1.016 1.27)
			(layers "B.Cu" "B.Mask" "B.Paste")
			(net "GND")
		)
	)
	(footprint ""
		(layer "B.Cu")
		(at 239.903 -340.741)
		(property "Reference" "R1403"
			(at 0 0 0)
			(layer "B.SilkS")
			(hide yes)
			(effects
				(font
					(size 1.27 1.27)
				)
				(justify mirror)
			)
		)
		(property "Value" ""
			(at 0 0 0)
			(layer "B.Fab")
			(effects
				(font
					(size 1.27 1.27)
				)
				(justify mirror)
			)
		)
		(duplicate_pad_numbers_are_jumpers no)
		(fp_line
			(start -0.32512 -0.175006)
			(end -0.32512 0.175006)
			(stroke
				(width 0.1)
				(type default)
			)
			(layer "B.Fab")
		)
		(fp_line
			(start -0.32512 0.175006)
			(end 0.32512 0.175006)
			(stroke
				(width 0.1)
				(type default)
			)
			(layer "B.Fab")
		)
		(fp_line
			(start 0.32512 -0.175006)
			(end -0.32512 -0.175006)
			(stroke
				(width 0.1)
				(type default)
			)
			(layer "B.Fab")
		)
		(fp_line
			(start 0.32512 0.175006)
			(end 0.32512 -0.175006)
			(stroke
				(width 0.1)
				(type default)
			)
			(layer "B.Fab")
		)
		(pad "1" smd rect
			(at 0.2667 0 180)
			(size 0.3048 0.381)
			(layers "B.Cu" "B.Mask" "B.Paste")
			(net "P1V8_CPU1_RT_1D")
		)
		(pad "2" smd rect
			(at -0.2667 0)
			(size 0.3048 0.381)
			(layers "B.Cu" "B.Mask" "B.Paste")
			(net "SMB_RT_CPU1_P2_ROM_MUX_2D_R_SDA")
		)
	)
	(footprint ""
		(layer "B.Cu")
		(at 59.401202 -195.012564 180)
		(property "Reference" "R1580"
			(at 0 0 0)
			(layer "B.SilkS")
			(hide yes)
			(effects
				(font
					(size 1.27 1.27)
				)
				(justify mirror)
			)
		)
		(property "Value" ""
			(at 0 0 0)
			(layer "B.Fab")
			(effects
				(font
					(size 1.27 1.27)
				)
				(justify mirror)
			)
		)
		(duplicate_pad_numbers_are_jumpers no)
		(fp_line
			(start 0.7874 0.4064)
			(end 0.7874 -0.4064)
			(stroke
				(width 0.1524)
				(type default)
			)
			(layer "B.SilkS")
		)
		(fp_line
			(start 0.7874 -0.4064)
			(end -0.7874 -0.4064)
			(stroke
				(width 0.1524)
				(type default)
			)
			(layer "B.SilkS")
		)
		(fp_line
			(start -0.7874 0.4064)
			(end 0.7874 0.4064)
			(stroke
				(width 0.1524)
				(type default)
			)
			(layer "B.SilkS")
		)
		(fp_line
			(start -0.7874 -0.4064)
			(end -0.7874 0.4064)
			(stroke
				(width 0.1524)
				(type default)
			)
			(layer "B.SilkS")
		)
		(fp_line
			(start 0.67945 0.3048)
			(end 0.67945 -0.305054)
			(stroke
				(width 0.1)
				(type default)
			)
			(layer "B.Fab")
		)
		(fp_line
			(start 0.67945 -0.305054)
			(end 0.12065 -0.305054)
			(stroke
				(width 0.1)
				(type default)
			)
			(layer "B.Fab")
		)
		(fp_line
			(start 0.12065 0.3048)
			(end 0.67945 0.3048)
			(stroke
				(width 0.1)
				(type default)
			)
			(layer "B.Fab")
		)
		(fp_line
			(start 0.12065 0.2794)
			(end 0.12065 0.3048)
			(stroke
				(width 0.1)
				(type default)
			)
			(layer "B.Fab")
		)
		(fp_line
			(start 0.12065 -0.2794)
			(end -0.12065 -0.2794)
			(stroke
				(width 0.1)
				(type default)
			)
			(layer "B.Fab")
		)
		(fp_line
			(start 0.12065 -0.305054)
			(end 0.12065 -0.2794)
			(stroke
				(width 0.1)
				(type default)
			)
			(layer "B.Fab")
		)
		(fp_line
			(start -0.120396 0.3048)
			(end -0.120396 0.2794)
			(stroke
				(width 0.1)
				(type default)
			)
			(layer "B.Fab")
		)
		(fp_line
			(start -0.120396 0.2794)
			(end 0.12065 0.2794)
			(stroke
				(width 0.1)
				(type default)
			)
			(layer "B.Fab")
		)
		(fp_line
			(start -0.12065 -0.2794)
			(end -0.12065 -0.3048)
			(stroke
				(width 0.1)
				(type default)
			)
			(layer "B.Fab")
		)
		(fp_line
			(start -0.12065 -0.3048)
			(end -0.67945 -0.3048)
			(stroke
				(width 0.1)
				(type default)
			)
			(layer "B.Fab")
		)
		(fp_line
			(start -0.67945 0.3048)
			(end -0.120396 0.3048)
			(stroke
				(width 0.1)
				(type default)
			)
			(layer "B.Fab")
		)
		(fp_line
			(start -0.67945 -0.3048)
			(end -0.67945 0.3048)
			(stroke
				(width 0.1)
				(type default)
			)
			(layer "B.Fab")
		)
		(pad "1" smd circle
			(at 0.40005 0)
			(size 0 0)
			(layers "B.Cu" "B.Mask" "B.Paste")
			(net "I3C_SPD_DDRAF_CPU1_SCL")
		)
		(pad "2" smd circle
			(at -0.40005 0)
			(size 0 0)
			(layers "B.Cu" "B.Mask" "B.Paste")
			(net "I3C_SPD_DDRA_CPU1_SCL")
		)
	)
	(footprint ""
		(layer "B.Cu")
		(at 423.668698 -343.961212 -90)
		(property "Reference" "PC223"
			(at 7.654036 -3.431286 270)
			(unlocked yes)
			(layer "B.SilkS")
			(effects
				(font
					(size 0.7874 0.5842)
					(thickness 0.1524)
				)
				(justify left mirror)
			)
		)
		(property "Value" ""
			(at 0 0 90)
			(layer "B.Fab")
			(effects
				(font
					(size 1.27 1.27)
				)
				(justify mirror)
			)
		)
		(duplicate_pad_numbers_are_jumpers no)
		(fp_line
			(start -4.533392 2.249932)
			(end 4.533392 2.249932)
			(stroke
				(width 0.1524)
				(type default)
			)
			(layer "B.SilkS")
		)
		(fp_line
			(start 4.533392 2.249932)
			(end 4.533392 -2.249932)
			(stroke
				(width 0.1524)
				(type default)
			)
			(layer "B.SilkS")
		)
		(fp_line
			(start -4.533392 -2.249932)
			(end -4.533392 2.249932)
			(stroke
				(width 0.1524)
				(type default)
			)
			(layer "B.SilkS")
		)
		(fp_line
			(start 4.533392 -2.249932)
			(end -4.533392 -2.249932)
			(stroke
				(width 0.1524)
				(type default)
			)
			(layer "B.SilkS")
		)
		(fp_rect
			(start 5.39242 2.326132)
			(end 4.533392 -2.326132)
			(stroke
				(width 0)
				(type default)
			)
			(fill yes)
			(layer "B.SilkS")
		)
		(fp_line
			(start -3.750056 2.249932)
			(end 3.750056 2.249932)
			(stroke
				(width 0.1)
				(type default)
			)
			(layer "B.Fab")
		)
		(fp_line
			(start 3.750056 2.249932)
			(end 3.750056 -2.249932)
			(stroke
				(width 0.1)
				(type default)
			)
			(layer "B.Fab")
		)
		(fp_line
			(start -3.750056 -2.249932)
			(end -3.750056 2.249932)
			(stroke
				(width 0.1)
				(type default)
			)
			(layer "B.Fab")
		)
		(fp_line
			(start 3.750056 -2.249932)
			(end -3.750056 -2.249932)
			(stroke
				(width 0.1)
				(type default)
			)
			(layer "B.Fab")
		)
		(fp_text user "+"
			(at 6.322314 0.786384 180)
			(unlocked yes)
			(layer "B.SilkS")
			(effects
				(font
					(size 1.905 1.4224)
					(thickness 0.1524)
				)
				(justify left mirror)
			)
		)
		(fp_text user "-"
			(at -4.8514 -0.14605 270)
			(unlocked yes)
			(layer "B.SilkS")
			(effects
				(font
					(size 1.905 1.4224)
					(thickness 0.1524)
				)
				(justify left mirror)
			)
		)
		(fp_text user "+"
			(at 6.322314 0.786384 180)
			(unlocked yes)
			(layer "B.Fab")
			(effects
				(font
					(size 1.905 1.4224)
					(thickness 0.1524)
				)
				(justify left mirror)
			)
		)
		(fp_text user "-"
			(at -4.8514 -0.14605 270)
			(unlocked yes)
			(layer "B.Fab")
			(effects
				(font
					(size 1.905 1.4224)
					(thickness 0.1524)
				)
				(justify left mirror)
			)
		)
		(pad "1" smd rect
			(at 3.199892 0 90)
			(size 2.413 2.8194)
			(layers "B.Cu" "B.Mask" "B.Paste")
			(net "PVDD11_S3_P0")
		)
		(pad "2" smd rect
			(at -3.199892 0 90)
			(size 2.413 2.8194)
			(layers "B.Cu" "B.Mask" "B.Paste")
			(net "GND")
		)
	)
	(footprint ""
		(layer "B.Cu")
		(at 136.040114 -37.898578)
		(property "Reference" "C6067"
			(at 0 0 0)
			(layer "B.SilkS")
			(hide yes)
			(effects
				(font
					(size 1.27 1.27)
				)
				(justify mirror)
			)
		)
		(property "Value" ""
			(at 0 0 0)
			(layer "B.Fab")
			(effects
				(font
					(size 1.27 1.27)
				)
				(justify mirror)
			)
		)
		(duplicate_pad_numbers_are_jumpers no)
		(fp_line
			(start -0.7874 -0.4064)
			(end -0.7874 0.4064)
			(stroke
				(width 0.1524)
				(type default)
			)
			(layer "B.SilkS")
		)
		(fp_line
			(start -0.7874 0.4064)
			(end 0.7874 0.4064)
			(stroke
				(width 0.1524)
				(type default)
			)
			(layer "B.SilkS")
		)
		(fp_line
			(start 0.7874 -0.4064)
			(end -0.7874 -0.4064)
			(stroke
				(width 0.1524)
				(type default)
			)
			(layer "B.SilkS")
		)
		(fp_line
			(start 0.7874 0.4064)
			(end 0.7874 -0.4064)
			(stroke
				(width 0.1524)
				(type default)
			)
			(layer "B.SilkS")
		)
		(fp_line
			(start -0.67945 -0.3048)
			(end -0.67945 0.3048)
			(stroke
				(width 0.1)
				(type default)
			)
			(layer "B.Fab")
		)
		(fp_line
			(start -0.67945 0.3048)
			(end -0.120396 0.3048)
			(stroke
				(width 0.1)
				(type default)
			)
			(layer "B.Fab")
		)
		(fp_line
			(start -0.12065 -0.3048)
			(end -0.67945 -0.3048)
			(stroke
				(width 0.1)
				(type default)
			)
			(layer "B.Fab")
		)
		(fp_line
			(start -0.12065 -0.2794)
			(end -0.12065 -0.3048)
			(stroke
				(width 0.1)
				(type default)
			)
			(layer "B.Fab")
		)
		(fp_line
			(start -0.120396 0.2794)
			(end 0.12065 0.2794)
			(stroke
				(width 0.1)
				(type default)
			)
			(layer "B.Fab")
		)
		(fp_line
			(start -0.120396 0.3048)
			(end -0.120396 0.2794)
			(stroke
				(width 0.1)
				(type default)
			)
			(layer "B.Fab")
		)
		(fp_line
			(start 0.12065 -0.305054)
			(end 0.12065 -0.2794)
			(stroke
				(width 0.1)
				(type default)
			)
			(layer "B.Fab")
		)
		(fp_line
			(start 0.12065 -0.2794)
			(end -0.12065 -0.2794)
			(stroke
				(width 0.1)
				(type default)
			)
			(layer "B.Fab")
		)
		(fp_line
			(start 0.12065 0.2794)
			(end 0.12065 0.3048)
			(stroke
				(width 0.1)
				(type default)
			)
			(layer "B.Fab")
		)
		(fp_line
			(start 0.12065 0.3048)
			(end 0.67945 0.3048)
			(stroke
				(width 0.1)
				(type default)
			)
			(layer "B.Fab")
		)
		(fp_line
			(start 0.67945 -0.305054)
			(end 0.12065 -0.305054)
			(stroke
				(width 0.1)
				(type default)
			)
			(layer "B.Fab")
		)
		(fp_line
			(start 0.67945 0.3048)
			(end 0.67945 -0.305054)
			(stroke
				(width 0.1)
				(type default)
			)
			(layer "B.Fab")
		)
		(pad "1" smd circle
			(at 0.40005 0 180)
			(size 0 0)
			(layers "B.Cu" "B.Mask" "B.Paste")
			(net "P1V2_AUX")
		)
		(pad "2" smd circle
			(at -0.40005 0 180)
			(size 0 0)
			(layers "B.Cu" "B.Mask" "B.Paste")
			(net "GND")
		)
	)
	(footprint ""
		(layer "B.Cu")
		(at 234.952286 -257.70713 180)
		(property "Reference" ""
			(at 0 0 0)
			(layer "B.SilkS")
			(hide yes)
			(effects
				(font
					(size 1.27 1.27)
				)
				(justify mirror)
			)
		)
		(property "Value" ""
			(at 0 0 0)
			(layer "B.Fab")
			(effects
				(font
					(size 1.27 1.27)
				)
				(justify mirror)
			)
		)
		(duplicate_pad_numbers_are_jumpers no)
		(pad "1" smd circle
			(at 0 0)
			(size 0.9906 0.9906)
			(layers "B.Cu" "B.Mask" "B.Paste")
			(net "Net_46")
		)
		(zone
			(layer "B.Cu")
			(hatch none 0.5)
			(connect_pads
				(clearance 0)
			)
			(min_thickness 0.25)
			(keepout
				(tracks not_allowed)
				(vias allowed)
				(pads allowed)
				(copperpour not_allowed)
				(footprints allowed)
			)
			(placement
				(enabled no)
				(sheetname "")
			)
			(fill
				(thermal_gap 0.5)
				(thermal_bridge_width 0.5)
				(island_removal_mode 0)
			)
			(polygon
				(pts
					(arc
						(start 236.577886 -257.70713)
						(mid 233.326686 -257.70713)
						(end 236.577886 -257.70713)
					)
				)
			)
		)
	)
	(footprint ""
		(layer "B.Cu")
		(at 310.411876 -78.775814 90)
		(property "Reference" "R4605"
			(at 0 0 90)
			(layer "B.SilkS")
			(hide yes)
			(effects
				(font
					(size 1.27 1.27)
				)
				(justify mirror)
			)
		)
		(property "Value" ""
			(at 0 0 90)
			(layer "B.Fab")
			(effects
				(font
					(size 1.27 1.27)
				)
				(justify mirror)
			)
		)
		(duplicate_pad_numbers_are_jumpers no)
		(fp_line
			(start 0.7874 -0.4064)
			(end -0.7874 -0.4064)
			(stroke
				(width 0.1524)
				(type default)
			)
			(layer "B.SilkS")
		)
		(fp_line
			(start -0.7874 -0.4064)
			(end -0.7874 0.4064)
			(stroke
				(width 0.1524)
				(type default)
			)
			(layer "B.SilkS")
		)
		(fp_line
			(start 0.7874 0.4064)
			(end 0.7874 -0.4064)
			(stroke
				(width 0.1524)
				(type default)
			)
			(layer "B.SilkS")
		)
		(fp_line
			(start -0.7874 0.4064)
			(end 0.7874 0.4064)
			(stroke
				(width 0.1524)
				(type default)
			)
			(layer "B.SilkS")
		)
		(fp_line
			(start 0.67945 -0.305054)
			(end 0.12065 -0.305054)
			(stroke
				(width 0.1)
				(type default)
			)
			(layer "B.Fab")
		)
		(fp_line
			(start 0.12065 -0.305054)
			(end 0.12065 -0.2794)
			(stroke
				(width 0.1)
				(type default)
			)
			(layer "B.Fab")
		)
		(fp_line
			(start -0.12065 -0.3048)
			(end -0.67945 -0.3048)
			(stroke
				(width 0.1)
				(type default)
			)
			(layer "B.Fab")
		)
		(fp_line
			(start -0.67945 -0.3048)
			(end -0.67945 0.3048)
			(stroke
				(width 0.1)
				(type default)
			)
			(layer "B.Fab")
		)
		(fp_line
			(start 0.12065 -0.2794)
			(end -0.12065 -0.2794)
			(stroke
				(width 0.1)
				(type default)
			)
			(layer "B.Fab")
		)
		(fp_line
			(start -0.12065 -0.2794)
			(end -0.12065 -0.3048)
			(stroke
				(width 0.1)
				(type default)
			)
			(layer "B.Fab")
		)
		(fp_line
			(start 0.12065 0.2794)
			(end 0.12065 0.3048)
			(stroke
				(width 0.1)
				(type default)
			)
			(layer "B.Fab")
		)
		(fp_line
			(start -0.120396 0.2794)
			(end 0.12065 0.2794)
			(stroke
				(width 0.1)
				(type default)
			)
			(layer "B.Fab")
		)
		(fp_line
			(start 0.67945 0.3048)
			(end 0.67945 -0.305054)
			(stroke
				(width 0.1)
				(type default)
			)
			(layer "B.Fab")
		)
		(fp_line
			(start 0.12065 0.3048)
			(end 0.67945 0.3048)
			(stroke
				(width 0.1)
				(type default)
			)
			(layer "B.Fab")
		)
		(fp_line
			(start -0.120396 0.3048)
			(end -0.120396 0.2794)
			(stroke
				(width 0.1)
				(type default)
			)
			(layer "B.Fab")
		)
		(fp_line
			(start -0.67945 0.3048)
			(end -0.120396 0.3048)
			(stroke
				(width 0.1)
				(type default)
			)
			(layer "B.Fab")
		)
		(pad "1" smd circle
			(at 0.40005 0 270)
			(size 0 0)
			(layers "B.Cu" "B.Mask" "B.Paste")
			(net "P3V3_AUX")
		)
		(pad "2" smd circle
			(at -0.40005 0 270)
			(size 0 0)
			(layers "B.Cu" "B.Mask" "B.Paste")
			(net "PWRGD_PS_PWROK_PLD_ISO")
		)
	)
	(footprint ""
		(layer "B.Cu")
		(at 147.00631 -386.766562 90)
		(property "Reference" "C407"
			(at 0 0 90)
			(layer "B.SilkS")
			(hide yes)
			(effects
				(font
					(size 1.27 1.27)
				)
				(justify mirror)
			)
		)
		(property "Value" ""
			(at 0 0 90)
			(layer "B.Fab")
			(effects
				(font
					(size 1.27 1.27)
				)
				(justify mirror)
			)
		)
		(duplicate_pad_numbers_are_jumpers no)
		(fp_line
			(start 0.299974 -0.150114)
			(end -0.299974 -0.150114)
			(stroke
				(width 0.1)
				(type default)
			)
			(layer "B.Fab")
		)
		(fp_line
			(start -0.299974 -0.150114)
			(end -0.299974 0.150114)
			(stroke
				(width 0.1)
				(type default)
			)
			(layer "B.Fab")
		)
		(fp_line
			(start 0.299974 0.150114)
			(end 0.299974 -0.150114)
			(stroke
				(width 0.1)
				(type default)
			)
			(layer "B.Fab")
		)
		(fp_line
			(start -0.299974 0.150114)
			(end 0.299974 0.150114)
			(stroke
				(width 0.1)
				(type default)
			)
			(layer "B.Fab")
		)
		(pad "1" smd rect
			(at 0.2667 0 270)
			(size 0.3048 0.381)
			(layers "B.Cu" "B.Mask" "B.Paste")
			(net "P0V9_CPU1_RT2_2A")
		)
		(pad "2" smd rect
			(at -0.2667 0 270)
			(size 0.3048 0.381)
			(layers "B.Cu" "B.Mask" "B.Paste")
			(net "GND")
		)
	)
	(footprint ""
		(layer "B.Cu")
		(at 216.916 -342.011 90)
		(property "Reference" "R6753"
			(at 0 0 90)
			(layer "B.SilkS")
			(hide yes)
			(effects
				(font
					(size 1.27 1.27)
				)
				(justify mirror)
			)
		)
		(property "Value" ""
			(at 0 0 90)
			(layer "B.Fab")
			(effects
				(font
					(size 1.27 1.27)
				)
				(justify mirror)
			)
		)
		(duplicate_pad_numbers_are_jumpers no)
		(fp_line
			(start 0.32512 -0.175006)
			(end -0.32512 -0.175006)
			(stroke
				(width 0.1)
				(type default)
			)
			(layer "B.Fab")
		)
		(fp_line
			(start -0.32512 -0.175006)
			(end -0.32512 0.175006)
			(stroke
				(width 0.1)
				(type default)
			)
			(layer "B.Fab")
		)
		(fp_line
			(start 0.32512 0.175006)
			(end 0.32512 -0.175006)
			(stroke
				(width 0.1)
				(type default)
			)
			(layer "B.Fab")
		)
		(fp_line
			(start -0.32512 0.175006)
			(end 0.32512 0.175006)
			(stroke
				(width 0.1)
				(type default)
			)
			(layer "B.Fab")
		)
		(pad "1" smd rect
			(at 0.2667 0 270)
			(size 0.3048 0.381)
			(layers "B.Cu" "B.Mask" "B.Paste")
			(net "P1V8_CPU1_RT_1D")
		)
		(pad "2" smd rect
			(at -0.2667 0 90)
			(size 0.3048 0.381)
			(layers "B.Cu" "B.Mask" "B.Paste")
			(net "SMB_RT_CPU1_P2_R_SCL")
		)
	)
	(footprint ""
		(layer "B.Cu")
		(at 79.906368 -386.766562 90)
		(property "Reference" "C326"
			(at 0 0 90)
			(layer "B.SilkS")
			(hide yes)
			(effects
				(font
					(size 1.27 1.27)
				)
				(justify mirror)
			)
		)
		(property "Value" ""
			(at 0 0 90)
			(layer "B.Fab")
			(effects
				(font
					(size 1.27 1.27)
				)
				(justify mirror)
			)
		)
		(duplicate_pad_numbers_are_jumpers no)
		(fp_line
			(start 0.299974 -0.150114)
			(end -0.299974 -0.150114)
			(stroke
				(width 0.1)
				(type default)
			)
			(layer "B.Fab")
		)
		(fp_line
			(start -0.299974 -0.150114)
			(end -0.299974 0.150114)
			(stroke
				(width 0.1)
				(type default)
			)
			(layer "B.Fab")
		)
		(fp_line
			(start 0.299974 0.150114)
			(end 0.299974 -0.150114)
			(stroke
				(width 0.1)
				(type default)
			)
			(layer "B.Fab")
		)
		(fp_line
			(start -0.299974 0.150114)
			(end 0.299974 0.150114)
			(stroke
				(width 0.1)
				(type default)
			)
			(layer "B.Fab")
		)
		(pad "1" smd rect
			(at 0.2667 0 270)
			(size 0.3048 0.381)
			(layers "B.Cu" "B.Mask" "B.Paste")
			(net "P0V9_CPU1_RT1_2A")
		)
		(pad "2" smd rect
			(at -0.2667 0 270)
			(size 0.3048 0.381)
			(layers "B.Cu" "B.Mask" "B.Paste")
			(net "GND")
		)
	)
	(footprint ""
		(layer "B.Cu")
		(at 183.164734 -399.867882)
		(property "Reference" "PR3932"
			(at 0 0 0)
			(layer "B.SilkS")
			(hide yes)
			(effects
				(font
					(size 1.27 1.27)
				)
				(justify mirror)
			)
		)
		(property "Value" ""
			(at 0 0 0)
			(layer "B.Fab")
			(effects
				(font
					(size 1.27 1.27)
				)
				(justify mirror)
			)
		)
		(duplicate_pad_numbers_are_jumpers no)
		(fp_line
			(start -0.7874 -0.4064)
			(end -0.7874 0.4064)
			(stroke
				(width 0.1524)
				(type default)
			)
			(layer "B.SilkS")
		)
		(fp_line
			(start -0.7874 0.4064)
			(end 0.7874 0.4064)
			(stroke
				(width 0.1524)
				(type default)
			)
			(layer "B.SilkS")
		)
		(fp_line
			(start 0.7874 -0.4064)
			(end -0.7874 -0.4064)
			(stroke
				(width 0.1524)
				(type default)
			)
			(layer "B.SilkS")
		)
		(fp_line
			(start 0.7874 0.4064)
			(end 0.7874 -0.4064)
			(stroke
				(width 0.1524)
				(type default)
			)
			(layer "B.SilkS")
		)
		(fp_line
			(start -0.67945 -0.3048)
			(end -0.67945 0.3048)
			(stroke
				(width 0.1)
				(type default)
			)
			(layer "B.Fab")
		)
		(fp_line
			(start -0.67945 0.3048)
			(end -0.120396 0.3048)
			(stroke
				(width 0.1)
				(type default)
			)
			(layer "B.Fab")
		)
		(fp_line
			(start -0.12065 -0.3048)
			(end -0.67945 -0.3048)
			(stroke
				(width 0.1)
				(type default)
			)
			(layer "B.Fab")
		)
		(fp_line
			(start -0.12065 -0.2794)
			(end -0.12065 -0.3048)
			(stroke
				(width 0.1)
				(type default)
			)
			(layer "B.Fab")
		)
		(fp_line
			(start -0.120396 0.2794)
			(end 0.12065 0.2794)
			(stroke
				(width 0.1)
				(type default)
			)
			(layer "B.Fab")
		)
		(fp_line
			(start -0.120396 0.3048)
			(end -0.120396 0.2794)
			(stroke
				(width 0.1)
				(type default)
			)
			(layer "B.Fab")
		)
		(fp_line
			(start 0.12065 -0.305054)
			(end 0.12065 -0.2794)
			(stroke
				(width 0.1)
				(type default)
			)
			(layer "B.Fab")
		)
		(fp_line
			(start 0.12065 -0.2794)
			(end -0.12065 -0.2794)
			(stroke
				(width 0.1)
				(type default)
			)
			(layer "B.Fab")
		)
		(fp_line
			(start 0.12065 0.2794)
			(end 0.12065 0.3048)
			(stroke
				(width 0.1)
				(type default)
			)
			(layer "B.Fab")
		)
		(fp_line
			(start 0.12065 0.3048)
			(end 0.67945 0.3048)
			(stroke
				(width 0.1)
				(type default)
			)
			(layer "B.Fab")
		)
		(fp_line
			(start 0.67945 -0.305054)
			(end 0.12065 -0.305054)
			(stroke
				(width 0.1)
				(type default)
			)
			(layer "B.Fab")
		)
		(fp_line
			(start 0.67945 0.3048)
			(end 0.67945 -0.305054)
			(stroke
				(width 0.1)
				(type default)
			)
			(layer "B.Fab")
		)
		(pad "1" smd circle
			(at 0.40005 0 180)
			(size 0 0)
			(layers "B.Cu" "B.Mask" "B.Paste")
			(net "HSC_VOSEN")
		)
		(pad "2" smd circle
			(at -0.40005 0 180)
			(size 0 0)
			(layers "B.Cu" "B.Mask" "B.Paste")
			(net "AGND_HSC")
		)
	)
	(footprint ""
		(layer "B.Cu")
		(at 160.218882 -390.560052 90)
		(property "Reference" "C416"
			(at 0 0 90)
			(layer "B.SilkS")
			(hide yes)
			(effects
				(font
					(size 1.27 1.27)
				)
				(justify mirror)
			)
		)
		(property "Value" ""
			(at 0 0 90)
			(layer "B.Fab")
			(effects
				(font
					(size 1.27 1.27)
				)
				(justify mirror)
			)
		)
		(duplicate_pad_numbers_are_jumpers no)
		(fp_line
			(start 0.7874 -0.4064)
			(end -0.7874 -0.4064)
			(stroke
				(width 0.1524)
				(type default)
			)
			(layer "B.SilkS")
		)
		(fp_line
			(start -0.7874 -0.4064)
			(end -0.7874 0.4064)
			(stroke
				(width 0.1524)
				(type default)
			)
			(layer "B.SilkS")
		)
		(fp_line
			(start 0.7874 0.4064)
			(end 0.7874 -0.4064)
			(stroke
				(width 0.1524)
				(type default)
			)
			(layer "B.SilkS")
		)
		(fp_line
			(start -0.7874 0.4064)
			(end 0.7874 0.4064)
			(stroke
				(width 0.1524)
				(type default)
			)
			(layer "B.SilkS")
		)
		(fp_line
			(start 0.67945 -0.305054)
			(end 0.12065 -0.305054)
			(stroke
				(width 0.1)
				(type default)
			)
			(layer "B.Fab")
		)
		(fp_line
			(start 0.12065 -0.305054)
			(end 0.12065 -0.2794)
			(stroke
				(width 0.1)
				(type default)
			)
			(layer "B.Fab")
		)
		(fp_line
			(start -0.12065 -0.3048)
			(end -0.67945 -0.3048)
			(stroke
				(width 0.1)
				(type default)
			)
			(layer "B.Fab")
		)
		(fp_line
			(start -0.67945 -0.3048)
			(end -0.67945 0.3048)
			(stroke
				(width 0.1)
				(type default)
			)
			(layer "B.Fab")
		)
		(fp_line
			(start 0.12065 -0.2794)
			(end -0.12065 -0.2794)
			(stroke
				(width 0.1)
				(type default)
			)
			(layer "B.Fab")
		)
		(fp_line
			(start -0.12065 -0.2794)
			(end -0.12065 -0.3048)
			(stroke
				(width 0.1)
				(type default)
			)
			(layer "B.Fab")
		)
		(fp_line
			(start 0.12065 0.2794)
			(end 0.12065 0.3048)
			(stroke
				(width 0.1)
				(type default)
			)
			(layer "B.Fab")
		)
		(fp_line
			(start -0.120396 0.2794)
			(end 0.12065 0.2794)
			(stroke
				(width 0.1)
				(type default)
			)
			(layer "B.Fab")
		)
		(fp_line
			(start 0.67945 0.3048)
			(end 0.67945 -0.305054)
			(stroke
				(width 0.1)
				(type default)
			)
			(layer "B.Fab")
		)
		(fp_line
			(start 0.12065 0.3048)
			(end 0.67945 0.3048)
			(stroke
				(width 0.1)
				(type default)
			)
			(layer "B.Fab")
		)
		(fp_line
			(start -0.120396 0.3048)
			(end -0.120396 0.2794)
			(stroke
				(width 0.1)
				(type default)
			)
			(layer "B.Fab")
		)
		(fp_line
			(start -0.67945 0.3048)
			(end -0.120396 0.3048)
			(stroke
				(width 0.1)
				(type default)
			)
			(layer "B.Fab")
		)
		(pad "1" smd circle
			(at 0.40005 0 270)
			(size 0 0)
			(layers "B.Cu" "B.Mask" "B.Paste")
			(net "P0V9_CPU1_RT2_2A")
		)
		(pad "2" smd circle
			(at -0.40005 0 270)
			(size 0 0)
			(layers "B.Cu" "B.Mask" "B.Paste")
			(net "GND")
		)
	)
	(footprint ""
		(layer "B.Cu")
		(at 341.079328 -336.083656 -90)
		(property "Reference" "PR94"
			(at 0 0 90)
			(layer "B.SilkS")
			(hide yes)
			(effects
				(font
					(size 1.27 1.27)
				)
				(justify mirror)
			)
		)
		(property "Value" ""
			(at 0 0 90)
			(layer "B.Fab")
			(effects
				(font
					(size 1.27 1.27)
				)
				(justify mirror)
			)
		)
		(duplicate_pad_numbers_are_jumpers no)
		(fp_line
			(start -0.7874 0.4064)
			(end 0.7874 0.4064)
			(stroke
				(width 0.1524)
				(type default)
			)
			(layer "B.SilkS")
		)
		(fp_line
			(start 0.7874 0.4064)
			(end 0.7874 -0.4064)
			(stroke
				(width 0.1524)
				(type default)
			)
			(layer "B.SilkS")
		)
		(fp_line
			(start -0.7874 -0.4064)
			(end -0.7874 0.4064)
			(stroke
				(width 0.1524)
				(type default)
			)
			(layer "B.SilkS")
		)
		(fp_line
			(start 0.7874 -0.4064)
			(end -0.7874 -0.4064)
			(stroke
				(width 0.1524)
				(type default)
			)
			(layer "B.SilkS")
		)
		(fp_line
			(start -0.67945 0.3048)
			(end -0.120396 0.3048)
			(stroke
				(width 0.1)
				(type default)
			)
			(layer "B.Fab")
		)
		(fp_line
			(start -0.120396 0.3048)
			(end -0.120396 0.2794)
			(stroke
				(width 0.1)
				(type default)
			)
			(layer "B.Fab")
		)
		(fp_line
			(start 0.12065 0.3048)
			(end 0.67945 0.3048)
			(stroke
				(width 0.1)
				(type default)
			)
			(layer "B.Fab")
		)
		(fp_line
			(start 0.67945 0.3048)
			(end 0.67945 -0.305054)
			(stroke
				(width 0.1)
				(type default)
			)
			(layer "B.Fab")
		)
		(fp_line
			(start -0.120396 0.2794)
			(end 0.12065 0.2794)
			(stroke
				(width 0.1)
				(type default)
			)
			(layer "B.Fab")
		)
		(fp_line
			(start 0.12065 0.2794)
			(end 0.12065 0.3048)
			(stroke
				(width 0.1)
				(type default)
			)
			(layer "B.Fab")
		)
		(fp_line
			(start -0.12065 -0.2794)
			(end -0.12065 -0.3048)
			(stroke
				(width 0.1)
				(type default)
			)
			(layer "B.Fab")
		)
		(fp_line
			(start 0.12065 -0.2794)
			(end -0.12065 -0.2794)
			(stroke
				(width 0.1)
				(type default)
			)
			(layer "B.Fab")
		)
		(fp_line
			(start -0.67945 -0.3048)
			(end -0.67945 0.3048)
			(stroke
				(width 0.1)
				(type default)
			)
			(layer "B.Fab")
		)
		(fp_line
			(start -0.12065 -0.3048)
			(end -0.67945 -0.3048)
			(stroke
				(width 0.1)
				(type default)
			)
			(layer "B.Fab")
		)
		(fp_line
			(start 0.12065 -0.305054)
			(end 0.12065 -0.2794)
			(stroke
				(width 0.1)
				(type default)
			)
			(layer "B.Fab")
		)
		(fp_line
			(start 0.67945 -0.305054)
			(end 0.12065 -0.305054)
			(stroke
				(width 0.1)
				(type default)
			)
			(layer "B.Fab")
		)
		(pad "1" smd circle
			(at 0.40005 0 90)
			(size 0 0)
			(layers "B.Cu" "B.Mask" "B.Paste")
			(net "PVDDCR_CPU1_P0_PVCC")
		)
		(pad "2" smd circle
			(at -0.40005 0 90)
			(size 0 0)
			(layers "B.Cu" "B.Mask" "B.Paste")
			(net "PVDDCR_CPU1_P0_VCC5")
		)
	)
	(footprint ""
		(layer "B.Cu")
		(at 310.578246 -395.148562 90)
		(property "Reference" "C520"
			(at 0 0 90)
			(layer "B.SilkS")
			(hide yes)
			(effects
				(font
					(size 1.27 1.27)
				)
				(justify mirror)
			)
		)
		(property "Value" ""
			(at 0 0 90)
			(layer "B.Fab")
			(effects
				(font
					(size 1.27 1.27)
				)
				(justify mirror)
			)
		)
		(duplicate_pad_numbers_are_jumpers no)
		(fp_line
			(start 0.299974 -0.150114)
			(end -0.299974 -0.150114)
			(stroke
				(width 0.1)
				(type default)
			)
			(layer "B.Fab")
		)
		(fp_line
			(start -0.299974 -0.150114)
			(end -0.299974 0.150114)
			(stroke
				(width 0.1)
				(type default)
			)
			(layer "B.Fab")
		)
		(fp_line
			(start 0.299974 0.150114)
			(end 0.299974 -0.150114)
			(stroke
				(width 0.1)
				(type default)
			)
			(layer "B.Fab")
		)
		(fp_line
			(start -0.299974 0.150114)
			(end 0.299974 0.150114)
			(stroke
				(width 0.1)
				(type default)
			)
			(layer "B.Fab")
		)
		(pad "1" smd rect
			(at 0.2667 0 270)
			(size 0.3048 0.381)
			(layers "B.Cu" "B.Mask" "B.Paste")
			(net "P1V8_CPU0_RT0_1A")
		)
		(pad "2" smd rect
			(at -0.2667 0 270)
			(size 0.3048 0.381)
			(layers "B.Cu" "B.Mask" "B.Paste")
			(net "GND")
		)
	)
	(footprint ""
		(layer "B.Cu")
		(at 150.606252 -386.766562 90)
		(property "Reference" "C389"
			(at 0 0 90)
			(layer "B.SilkS")
			(hide yes)
			(effects
				(font
					(size 1.27 1.27)
				)
				(justify mirror)
			)
		)
		(property "Value" ""
			(at 0 0 90)
			(layer "B.Fab")
			(effects
				(font
					(size 1.27 1.27)
				)
				(justify mirror)
			)
		)
		(duplicate_pad_numbers_are_jumpers no)
		(fp_line
			(start 0.299974 -0.150114)
			(end -0.299974 -0.150114)
			(stroke
				(width 0.1)
				(type default)
			)
			(layer "B.Fab")
		)
		(fp_line
			(start -0.299974 -0.150114)
			(end -0.299974 0.150114)
			(stroke
				(width 0.1)
				(type default)
			)
			(layer "B.Fab")
		)
		(fp_line
			(start 0.299974 0.150114)
			(end 0.299974 -0.150114)
			(stroke
				(width 0.1)
				(type default)
			)
			(layer "B.Fab")
		)
		(fp_line
			(start -0.299974 0.150114)
			(end 0.299974 0.150114)
			(stroke
				(width 0.1)
				(type default)
			)
			(layer "B.Fab")
		)
		(pad "1" smd rect
			(at 0.2667 0 270)
			(size 0.3048 0.381)
			(layers "B.Cu" "B.Mask" "B.Paste")
			(net "P0V9_CPU1_RT2_2A")
		)
		(pad "2" smd rect
			(at -0.2667 0 270)
			(size 0.3048 0.381)
			(layers "B.Cu" "B.Mask" "B.Paste")
			(net "GND")
		)
	)
	(footprint ""
		(layer "B.Cu")
		(at 50.718974 -419.723316 180)
		(property "Reference" "R5236"
			(at 0 0 0)
			(layer "B.SilkS")
			(hide yes)
			(effects
				(font
					(size 1.27 1.27)
				)
				(justify mirror)
			)
		)
		(property "Value" ""
			(at 0 0 0)
			(layer "B.Fab")
			(effects
				(font
					(size 1.27 1.27)
				)
				(justify mirror)
			)
		)
		(duplicate_pad_numbers_are_jumpers no)
		(fp_line
			(start 0.7874 0.4064)
			(end 0.7874 -0.4064)
			(stroke
				(width 0.1524)
				(type default)
			)
			(layer "B.SilkS")
		)
		(fp_line
			(start 0.7874 -0.4064)
			(end -0.7874 -0.4064)
			(stroke
				(width 0.1524)
				(type default)
			)
			(layer "B.SilkS")
		)
		(fp_line
			(start -0.7874 0.4064)
			(end 0.7874 0.4064)
			(stroke
				(width 0.1524)
				(type default)
			)
			(layer "B.SilkS")
		)
		(fp_line
			(start -0.7874 -0.4064)
			(end -0.7874 0.4064)
			(stroke
				(width 0.1524)
				(type default)
			)
			(layer "B.SilkS")
		)
		(fp_line
			(start 0.67945 0.3048)
			(end 0.67945 -0.305054)
			(stroke
				(width 0.1)
				(type default)
			)
			(layer "B.Fab")
		)
		(fp_line
			(start 0.67945 -0.305054)
			(end 0.12065 -0.305054)
			(stroke
				(width 0.1)
				(type default)
			)
			(layer "B.Fab")
		)
		(fp_line
			(start 0.12065 0.3048)
			(end 0.67945 0.3048)
			(stroke
				(width 0.1)
				(type default)
			)
			(layer "B.Fab")
		)
		(fp_line
			(start 0.12065 0.2794)
			(end 0.12065 0.3048)
			(stroke
				(width 0.1)
				(type default)
			)
			(layer "B.Fab")
		)
		(fp_line
			(start 0.12065 -0.2794)
			(end -0.12065 -0.2794)
			(stroke
				(width 0.1)
				(type default)
			)
			(layer "B.Fab")
		)
		(fp_line
			(start 0.12065 -0.305054)
			(end 0.12065 -0.2794)
			(stroke
				(width 0.1)
				(type default)
			)
			(layer "B.Fab")
		)
		(fp_line
			(start -0.120396 0.3048)
			(end -0.120396 0.2794)
			(stroke
				(width 0.1)
				(type default)
			)
			(layer "B.Fab")
		)
		(fp_line
			(start -0.120396 0.2794)
			(end 0.12065 0.2794)
			(stroke
				(width 0.1)
				(type default)
			)
			(layer "B.Fab")
		)
		(fp_line
			(start -0.12065 -0.2794)
			(end -0.12065 -0.3048)
			(stroke
				(width 0.1)
				(type default)
			)
			(layer "B.Fab")
		)
		(fp_line
			(start -0.12065 -0.3048)
			(end -0.67945 -0.3048)
			(stroke
				(width 0.1)
				(type default)
			)
			(layer "B.Fab")
		)
		(fp_line
			(start -0.67945 0.3048)
			(end -0.120396 0.3048)
			(stroke
				(width 0.1)
				(type default)
			)
			(layer "B.Fab")
		)
		(fp_line
			(start -0.67945 -0.3048)
			(end -0.67945 0.3048)
			(stroke
				(width 0.1)
				(type default)
			)
			(layer "B.Fab")
		)
		(pad "1" smd circle
			(at 0.40005 0)
			(size 0 0)
			(layers "B.Cu" "B.Mask" "B.Paste")
			(net "USB2_HUB_BUF_SWB_R_DN")
		)
		(pad "2" smd circle
			(at -0.40005 0)
			(size 0 0)
			(layers "B.Cu" "B.Mask" "B.Paste")
			(net "USB2_HUB_BUF_SWB_DN")
		)
	)
	(footprint ""
		(layer "B.Cu")
		(at 180.681376 -133.053328 90)
		(property "Reference" "R203"
			(at 0 0 90)
			(layer "B.SilkS")
			(hide yes)
			(effects
				(font
					(size 1.27 1.27)
				)
				(justify mirror)
			)
		)
		(property "Value" ""
			(at 0 0 90)
			(layer "B.Fab")
			(effects
				(font
					(size 1.27 1.27)
				)
				(justify mirror)
			)
		)
		(duplicate_pad_numbers_are_jumpers no)
		(fp_line
			(start 0.7874 -0.4064)
			(end -0.7874 -0.4064)
			(stroke
				(width 0.1524)
				(type default)
			)
			(layer "B.SilkS")
		)
		(fp_line
			(start -0.7874 -0.4064)
			(end -0.7874 0.4064)
			(stroke
				(width 0.1524)
				(type default)
			)
			(layer "B.SilkS")
		)
		(fp_line
			(start 0.7874 0.4064)
			(end 0.7874 -0.4064)
			(stroke
				(width 0.1524)
				(type default)
			)
			(layer "B.SilkS")
		)
		(fp_line
			(start -0.7874 0.4064)
			(end 0.7874 0.4064)
			(stroke
				(width 0.1524)
				(type default)
			)
			(layer "B.SilkS")
		)
		(fp_line
			(start 0.67945 -0.305054)
			(end 0.12065 -0.305054)
			(stroke
				(width 0.1)
				(type default)
			)
			(layer "B.Fab")
		)
		(fp_line
			(start 0.12065 -0.305054)
			(end 0.12065 -0.2794)
			(stroke
				(width 0.1)
				(type default)
			)
			(layer "B.Fab")
		)
		(fp_line
			(start -0.12065 -0.3048)
			(end -0.67945 -0.3048)
			(stroke
				(width 0.1)
				(type default)
			)
			(layer "B.Fab")
		)
		(fp_line
			(start -0.67945 -0.3048)
			(end -0.67945 0.3048)
			(stroke
				(width 0.1)
				(type default)
			)
			(layer "B.Fab")
		)
		(fp_line
			(start 0.12065 -0.2794)
			(end -0.12065 -0.2794)
			(stroke
				(width 0.1)
				(type default)
			)
			(layer "B.Fab")
		)
		(fp_line
			(start -0.12065 -0.2794)
			(end -0.12065 -0.3048)
			(stroke
				(width 0.1)
				(type default)
			)
			(layer "B.Fab")
		)
		(fp_line
			(start 0.12065 0.2794)
			(end 0.12065 0.3048)
			(stroke
				(width 0.1)
				(type default)
			)
			(layer "B.Fab")
		)
		(fp_line
			(start -0.120396 0.2794)
			(end 0.12065 0.2794)
			(stroke
				(width 0.1)
				(type default)
			)
			(layer "B.Fab")
		)
		(fp_line
			(start 0.67945 0.3048)
			(end 0.67945 -0.305054)
			(stroke
				(width 0.1)
				(type default)
			)
			(layer "B.Fab")
		)
		(fp_line
			(start 0.12065 0.3048)
			(end 0.67945 0.3048)
			(stroke
				(width 0.1)
				(type default)
			)
			(layer "B.Fab")
		)
		(fp_line
			(start -0.120396 0.3048)
			(end -0.120396 0.2794)
			(stroke
				(width 0.1)
				(type default)
			)
			(layer "B.Fab")
		)
		(fp_line
			(start -0.67945 0.3048)
			(end -0.120396 0.3048)
			(stroke
				(width 0.1)
				(type default)
			)
			(layer "B.Fab")
		)
		(pad "1" smd circle
			(at 0.40005 0 270)
			(size 0 0)
			(layers "B.Cu" "B.Mask" "B.Paste")
			(net "PWRGD_CPU1_PWROK")
		)
		(pad "2" smd circle
			(at -0.40005 0 270)
			(size 0 0)
			(layers "B.Cu" "B.Mask" "B.Paste")
			(net "FM_PWRGD_CPU1_PWROK")
		)
	)
	(footprint ""
		(layer "B.Cu")
		(at 186.345322 -13.60043 -90)
		(property "Reference" "R6004"
			(at 0 0 90)
			(layer "B.SilkS")
			(hide yes)
			(effects
				(font
					(size 1.27 1.27)
				)
				(justify mirror)
			)
		)
		(property "Value" ""
			(at 0 0 90)
			(layer "B.Fab")
			(effects
				(font
					(size 1.27 1.27)
				)
				(justify mirror)
			)
		)
		(duplicate_pad_numbers_are_jumpers no)
		(fp_line
			(start -0.7874 0.4064)
			(end 0.7874 0.4064)
			(stroke
				(width 0.1524)
				(type default)
			)
			(layer "B.SilkS")
		)
		(fp_line
			(start 0.7874 0.4064)
			(end 0.7874 -0.4064)
			(stroke
				(width 0.1524)
				(type default)
			)
			(layer "B.SilkS")
		)
		(fp_line
			(start -0.7874 -0.4064)
			(end -0.7874 0.4064)
			(stroke
				(width 0.1524)
				(type default)
			)
			(layer "B.SilkS")
		)
		(fp_line
			(start 0.7874 -0.4064)
			(end -0.7874 -0.4064)
			(stroke
				(width 0.1524)
				(type default)
			)
			(layer "B.SilkS")
		)
		(fp_line
			(start -0.67945 0.3048)
			(end -0.120396 0.3048)
			(stroke
				(width 0.1)
				(type default)
			)
			(layer "B.Fab")
		)
		(fp_line
			(start -0.120396 0.3048)
			(end -0.120396 0.2794)
			(stroke
				(width 0.1)
				(type default)
			)
			(layer "B.Fab")
		)
		(fp_line
			(start 0.12065 0.3048)
			(end 0.67945 0.3048)
			(stroke
				(width 0.1)
				(type default)
			)
			(layer "B.Fab")
		)
		(fp_line
			(start 0.67945 0.3048)
			(end 0.67945 -0.305054)
			(stroke
				(width 0.1)
				(type default)
			)
			(layer "B.Fab")
		)
		(fp_line
			(start -0.120396 0.2794)
			(end 0.12065 0.2794)
			(stroke
				(width 0.1)
				(type default)
			)
			(layer "B.Fab")
		)
		(fp_line
			(start 0.12065 0.2794)
			(end 0.12065 0.3048)
			(stroke
				(width 0.1)
				(type default)
			)
			(layer "B.Fab")
		)
		(fp_line
			(start -0.12065 -0.2794)
			(end -0.12065 -0.3048)
			(stroke
				(width 0.1)
				(type default)
			)
			(layer "B.Fab")
		)
		(fp_line
			(start 0.12065 -0.2794)
			(end -0.12065 -0.2794)
			(stroke
				(width 0.1)
				(type default)
			)
			(layer "B.Fab")
		)
		(fp_line
			(start -0.67945 -0.3048)
			(end -0.67945 0.3048)
			(stroke
				(width 0.1)
				(type default)
			)
			(layer "B.Fab")
		)
		(fp_line
			(start -0.12065 -0.3048)
			(end -0.67945 -0.3048)
			(stroke
				(width 0.1)
				(type default)
			)
			(layer "B.Fab")
		)
		(fp_line
			(start 0.12065 -0.305054)
			(end 0.12065 -0.2794)
			(stroke
				(width 0.1)
				(type default)
			)
			(layer "B.Fab")
		)
		(fp_line
			(start 0.67945 -0.305054)
			(end 0.12065 -0.305054)
			(stroke
				(width 0.1)
				(type default)
			)
			(layer "B.Fab")
		)
		(pad "1" smd circle
			(at 0.40005 0 90)
			(size 0 0)
			(layers "B.Cu" "B.Mask" "B.Paste")
			(net "I3C_SCM_2_SCL")
		)
		(pad "2" smd circle
			(at -0.40005 0 90)
			(size 0 0)
			(layers "B.Cu" "B.Mask" "B.Paste")
			(net "I3C_SCM_2_R_SCL")
		)
	)
	(footprint ""
		(layer "B.Cu")
		(at 415.018982 -399.291302 90)
		(property "Reference" "C980"
			(at 0 0 90)
			(layer "B.SilkS")
			(hide yes)
			(effects
				(font
					(size 1.27 1.27)
				)
				(justify mirror)
			)
		)
		(property "Value" ""
			(at 0 0 90)
			(layer "B.Fab")
			(effects
				(font
					(size 1.27 1.27)
				)
				(justify mirror)
			)
		)
		(duplicate_pad_numbers_are_jumpers no)
		(fp_line
			(start 0.299974 -0.150114)
			(end -0.299974 -0.150114)
			(stroke
				(width 0.1)
				(type default)
			)
			(layer "B.Fab")
		)
		(fp_line
			(start -0.299974 -0.150114)
			(end -0.299974 0.150114)
			(stroke
				(width 0.1)
				(type default)
			)
			(layer "B.Fab")
		)
		(fp_line
			(start 0.299974 0.150114)
			(end 0.299974 -0.150114)
			(stroke
				(width 0.1)
				(type default)
			)
			(layer "B.Fab")
		)
		(fp_line
			(start -0.299974 0.150114)
			(end 0.299974 0.150114)
			(stroke
				(width 0.1)
				(type default)
			)
			(layer "B.Fab")
		)
		(pad "1" smd rect
			(at 0.2667 0 270)
			(size 0.3048 0.381)
			(layers "B.Cu" "B.Mask" "B.Paste")
			(net "P0V9_CPU0_RT_2D")
		)
		(pad "2" smd rect
			(at -0.2667 0 270)
			(size 0.3048 0.381)
			(layers "B.Cu" "B.Mask" "B.Paste")
			(net "GND")
		)
	)
	(footprint ""
		(layer "B.Cu")
		(at 52.881022 -244.085364 180)
		(property "Reference" "R501"
			(at 0 0 0)
			(layer "B.SilkS")
			(hide yes)
			(effects
				(font
					(size 1.27 1.27)
				)
				(justify mirror)
			)
		)
		(property "Value" ""
			(at 0 0 0)
			(layer "B.Fab")
			(effects
				(font
					(size 1.27 1.27)
				)
				(justify mirror)
			)
		)
		(duplicate_pad_numbers_are_jumpers no)
		(fp_line
			(start 0.7874 0.4064)
			(end 0.7874 -0.4064)
			(stroke
				(width 0.1524)
				(type default)
			)
			(layer "B.SilkS")
		)
		(fp_line
			(start 0.7874 -0.4064)
			(end -0.7874 -0.4064)
			(stroke
				(width 0.1524)
				(type default)
			)
			(layer "B.SilkS")
		)
		(fp_line
			(start -0.7874 0.4064)
			(end 0.7874 0.4064)
			(stroke
				(width 0.1524)
				(type default)
			)
			(layer "B.SilkS")
		)
		(fp_line
			(start -0.7874 -0.4064)
			(end -0.7874 0.4064)
			(stroke
				(width 0.1524)
				(type default)
			)
			(layer "B.SilkS")
		)
		(fp_line
			(start 0.67945 0.3048)
			(end 0.67945 -0.305054)
			(stroke
				(width 0.1)
				(type default)
			)
			(layer "B.Fab")
		)
		(fp_line
			(start 0.67945 -0.305054)
			(end 0.12065 -0.305054)
			(stroke
				(width 0.1)
				(type default)
			)
			(layer "B.Fab")
		)
		(fp_line
			(start 0.12065 0.3048)
			(end 0.67945 0.3048)
			(stroke
				(width 0.1)
				(type default)
			)
			(layer "B.Fab")
		)
		(fp_line
			(start 0.12065 0.2794)
			(end 0.12065 0.3048)
			(stroke
				(width 0.1)
				(type default)
			)
			(layer "B.Fab")
		)
		(fp_line
			(start 0.12065 -0.2794)
			(end -0.12065 -0.2794)
			(stroke
				(width 0.1)
				(type default)
			)
			(layer "B.Fab")
		)
		(fp_line
			(start 0.12065 -0.305054)
			(end 0.12065 -0.2794)
			(stroke
				(width 0.1)
				(type default)
			)
			(layer "B.Fab")
		)
		(fp_line
			(start -0.120396 0.3048)
			(end -0.120396 0.2794)
			(stroke
				(width 0.1)
				(type default)
			)
			(layer "B.Fab")
		)
		(fp_line
			(start -0.120396 0.2794)
			(end 0.12065 0.2794)
			(stroke
				(width 0.1)
				(type default)
			)
			(layer "B.Fab")
		)
		(fp_line
			(start -0.12065 -0.2794)
			(end -0.12065 -0.3048)
			(stroke
				(width 0.1)
				(type default)
			)
			(layer "B.Fab")
		)
		(fp_line
			(start -0.12065 -0.3048)
			(end -0.67945 -0.3048)
			(stroke
				(width 0.1)
				(type default)
			)
			(layer "B.Fab")
		)
		(fp_line
			(start -0.67945 0.3048)
			(end -0.120396 0.3048)
			(stroke
				(width 0.1)
				(type default)
			)
			(layer "B.Fab")
		)
		(fp_line
			(start -0.67945 -0.3048)
			(end -0.67945 0.3048)
			(stroke
				(width 0.1)
				(type default)
			)
			(layer "B.Fab")
		)
		(pad "1" smd circle
			(at 0.40005 0)
			(size 0 0)
			(layers "B.Cu" "B.Mask" "B.Paste")
			(net "M_B_CPU1_ALERT_N")
		)
		(pad "2" smd circle
			(at -0.40005 0)
			(size 0 0)
			(layers "B.Cu" "B.Mask" "B.Paste")
			(net "M_B_CPU1_ALERT_R_N")
		)
	)
	(footprint ""
		(layer "B.Cu")
		(at 138.112246 -32.135318 -90)
		(property "Reference" "C6046"
			(at 0 0 90)
			(layer "B.SilkS")
			(hide yes)
			(effects
				(font
					(size 1.27 1.27)
				)
				(justify mirror)
			)
		)
		(property "Value" ""
			(at 0 0 90)
			(layer "B.Fab")
			(effects
				(font
					(size 1.27 1.27)
				)
				(justify mirror)
			)
		)
		(duplicate_pad_numbers_are_jumpers no)
		(fp_line
			(start -1.2954 0.5842)
			(end 1.2954 0.5842)
			(stroke
				(width 0.1524)
				(type default)
			)
			(layer "B.SilkS")
		)
		(fp_line
			(start 1.2954 0.5842)
			(end 1.2954 -0.5842)
			(stroke
				(width 0.1524)
				(type default)
			)
			(layer "B.SilkS")
		)
		(fp_line
			(start -1.2954 -0.5842)
			(end -1.2954 0.5842)
			(stroke
				(width 0.1524)
				(type default)
			)
			(layer "B.SilkS")
		)
		(fp_line
			(start 1.2954 -0.5842)
			(end -1.2954 -0.5842)
			(stroke
				(width 0.1524)
				(type default)
			)
			(layer "B.SilkS")
		)
		(fp_line
			(start -0.8636 0.4572)
			(end 0.8636 0.4572)
			(stroke
				(width 0.1)
				(type default)
			)
			(layer "B.Fab")
		)
		(fp_line
			(start 0.8636 0.4572)
			(end 0.8636 0.4064)
			(stroke
				(width 0.1)
				(type default)
			)
			(layer "B.Fab")
		)
		(fp_line
			(start -1.1938 0.4064)
			(end -0.8636 0.4064)
			(stroke
				(width 0.1)
				(type default)
			)
			(layer "B.Fab")
		)
		(fp_line
			(start -0.8636 0.4064)
			(end -0.8636 0.4572)
			(stroke
				(width 0.1)
				(type default)
			)
			(layer "B.Fab")
		)
		(fp_line
			(start 0.8636 0.4064)
			(end 1.1938 0.4064)
			(stroke
				(width 0.1)
				(type default)
			)
			(layer "B.Fab")
		)
		(fp_line
			(start 1.1938 0.4064)
			(end 1.1938 -0.4064)
			(stroke
				(width 0.1)
				(type default)
			)
			(layer "B.Fab")
		)
		(fp_line
			(start -1.1938 -0.4064)
			(end -1.1938 0.4064)
			(stroke
				(width 0.1)
				(type default)
			)
			(layer "B.Fab")
		)
		(fp_line
			(start -0.8636 -0.4064)
			(end -1.1938 -0.4064)
			(stroke
				(width 0.1)
				(type default)
			)
			(layer "B.Fab")
		)
		(fp_line
			(start 0.8636 -0.4064)
			(end 0.8636 -0.4572)
			(stroke
				(width 0.1)
				(type default)
			)
			(layer "B.Fab")
		)
		(fp_line
			(start 1.1938 -0.4064)
			(end 0.8636 -0.4064)
			(stroke
				(width 0.1)
				(type default)
			)
			(layer "B.Fab")
		)
		(fp_line
			(start -0.8636 -0.4572)
			(end -0.8636 -0.4064)
			(stroke
				(width 0.1)
				(type default)
			)
			(layer "B.Fab")
		)
		(fp_line
			(start 0.8636 -0.4572)
			(end -0.8636 -0.4572)
			(stroke
				(width 0.1)
				(type default)
			)
			(layer "B.Fab")
		)
		(pad "1" smd rect
			(at 0.7366 0 180)
			(size 0.7112 0.8128)
			(layers "B.Cu" "B.Mask" "B.Paste")
			(net "P3V3_AUX")
		)
		(pad "2" smd rect
			(at -0.7366 0 180)
			(size 0.7112 0.8128)
			(layers "B.Cu" "B.Mask" "B.Paste")
			(net "GND")
		)
	)
	(footprint ""
		(layer "B.Cu")
		(at 198.7042 -192.66027)
		(property "Reference" "C546"
			(at 0 0 0)
			(layer "B.SilkS")
			(hide yes)
			(effects
				(font
					(size 1.27 1.27)
				)
				(justify mirror)
			)
		)
		(property "Value" ""
			(at 0 0 0)
			(layer "B.Fab")
			(effects
				(font
					(size 1.27 1.27)
				)
				(justify mirror)
			)
		)
		(duplicate_pad_numbers_are_jumpers no)
		(fp_line
			(start -1.524 -0.762)
			(end -1.524 0.762)
			(stroke
				(width 0.1524)
				(type default)
			)
			(layer "B.SilkS")
		)
		(fp_line
			(start -1.524 0.762)
			(end 1.524 0.762)
			(stroke
				(width 0.1524)
				(type default)
			)
			(layer "B.SilkS")
		)
		(fp_line
			(start 1.524 -0.762)
			(end -1.524 -0.762)
			(stroke
				(width 0.1524)
				(type default)
			)
			(layer "B.SilkS")
		)
		(fp_line
			(start 1.524 0.762)
			(end 1.524 -0.762)
			(stroke
				(width 0.1524)
				(type default)
			)
			(layer "B.SilkS")
		)
		(fp_line
			(start -1.1049 -0.724916)
			(end 1.1049 -0.724916)
			(stroke
				(width 0.1)
				(type default)
			)
			(layer "B.Fab")
		)
		(fp_line
			(start -1.1049 0.724916)
			(end -1.1049 -0.724916)
			(stroke
				(width 0.1)
				(type default)
			)
			(layer "B.Fab")
		)
		(fp_line
			(start 1.1049 -0.724916)
			(end 1.1049 0.724916)
			(stroke
				(width 0.1)
				(type default)
			)
			(layer "B.Fab")
		)
		(fp_line
			(start 1.1049 0.724916)
			(end -1.1049 0.724916)
			(stroke
				(width 0.1)
				(type default)
			)
			(layer "B.Fab")
		)
		(pad "1" smd rect
			(at 0.889 0)
			(size 1.016 1.27)
			(layers "B.Cu" "B.Mask" "B.Paste")
			(net "P12V_MEM_CPU1")
		)
		(pad "2" smd rect
			(at -0.889 0)
			(size 1.016 1.27)
			(layers "B.Cu" "B.Mask" "B.Paste")
			(net "GND")
		)
	)
	(footprint ""
		(layer "B.Cu")
		(at 13.649452 -101.21138 90)
		(property "Reference" "C2031"
			(at 0 0 90)
			(layer "B.SilkS")
			(hide yes)
			(effects
				(font
					(size 1.27 1.27)
				)
				(justify mirror)
			)
		)
		(property "Value" ""
			(at 0 0 90)
			(layer "B.Fab")
			(effects
				(font
					(size 1.27 1.27)
				)
				(justify mirror)
			)
		)
		(duplicate_pad_numbers_are_jumpers no)
		(fp_line
			(start 0.7874 -0.4064)
			(end -0.7874 -0.4064)
			(stroke
				(width 0.1524)
				(type default)
			)
			(layer "B.SilkS")
		)
		(fp_line
			(start -0.7874 -0.4064)
			(end -0.7874 0.4064)
			(stroke
				(width 0.1524)
				(type default)
			)
			(layer "B.SilkS")
		)
		(fp_line
			(start 0.7874 0.4064)
			(end 0.7874 -0.4064)
			(stroke
				(width 0.1524)
				(type default)
			)
			(layer "B.SilkS")
		)
		(fp_line
			(start -0.7874 0.4064)
			(end 0.7874 0.4064)
			(stroke
				(width 0.1524)
				(type default)
			)
			(layer "B.SilkS")
		)
		(fp_line
			(start 0.67945 -0.305054)
			(end 0.12065 -0.305054)
			(stroke
				(width 0.1)
				(type default)
			)
			(layer "B.Fab")
		)
		(fp_line
			(start 0.12065 -0.305054)
			(end 0.12065 -0.2794)
			(stroke
				(width 0.1)
				(type default)
			)
			(layer "B.Fab")
		)
		(fp_line
			(start -0.12065 -0.3048)
			(end -0.67945 -0.3048)
			(stroke
				(width 0.1)
				(type default)
			)
			(layer "B.Fab")
		)
		(fp_line
			(start -0.67945 -0.3048)
			(end -0.67945 0.3048)
			(stroke
				(width 0.1)
				(type default)
			)
			(layer "B.Fab")
		)
		(fp_line
			(start 0.12065 -0.2794)
			(end -0.12065 -0.2794)
			(stroke
				(width 0.1)
				(type default)
			)
			(layer "B.Fab")
		)
		(fp_line
			(start -0.12065 -0.2794)
			(end -0.12065 -0.3048)
			(stroke
				(width 0.1)
				(type default)
			)
			(layer "B.Fab")
		)
		(fp_line
			(start 0.12065 0.2794)
			(end 0.12065 0.3048)
			(stroke
				(width 0.1)
				(type default)
			)
			(layer "B.Fab")
		)
		(fp_line
			(start -0.120396 0.2794)
			(end 0.12065 0.2794)
			(stroke
				(width 0.1)
				(type default)
			)
			(layer "B.Fab")
		)
		(fp_line
			(start 0.67945 0.3048)
			(end 0.67945 -0.305054)
			(stroke
				(width 0.1)
				(type default)
			)
			(layer "B.Fab")
		)
		(fp_line
			(start 0.12065 0.3048)
			(end 0.67945 0.3048)
			(stroke
				(width 0.1)
				(type default)
			)
			(layer "B.Fab")
		)
		(fp_line
			(start -0.120396 0.3048)
			(end -0.120396 0.2794)
			(stroke
				(width 0.1)
				(type default)
			)
			(layer "B.Fab")
		)
		(fp_line
			(start -0.67945 0.3048)
			(end -0.120396 0.3048)
			(stroke
				(width 0.1)
				(type default)
			)
			(layer "B.Fab")
		)
		(pad "1" smd circle
			(at 0.40005 0 270)
			(size 0 0)
			(layers "B.Cu" "B.Mask" "B.Paste")
			(net "P3V3_AUX_USB_HUB")
		)
		(pad "2" smd circle
			(at -0.40005 0 270)
			(size 0 0)
			(layers "B.Cu" "B.Mask" "B.Paste")
			(net "GND")
		)
	)
	(footprint ""
		(layer "B.Cu")
		(at 106.352848 -178.110134 -90)
		(property "Reference" "PC299_4"
			(at 0 0 90)
			(layer "B.SilkS")
			(hide yes)
			(effects
				(font
					(size 1.27 1.27)
				)
				(justify mirror)
			)
		)
		(property "Value" ""
			(at 0 0 90)
			(layer "B.Fab")
			(effects
				(font
					(size 1.27 1.27)
				)
				(justify mirror)
			)
		)
		(duplicate_pad_numbers_are_jumpers no)
		(fp_line
			(start -1.524 0.762)
			(end 1.524 0.762)
			(stroke
				(width 0.1524)
				(type default)
			)
			(layer "B.SilkS")
		)
		(fp_line
			(start 1.524 0.762)
			(end 1.524 -0.762)
			(stroke
				(width 0.1524)
				(type default)
			)
			(layer "B.SilkS")
		)
		(fp_line
			(start -1.524 -0.762)
			(end -1.524 0.762)
			(stroke
				(width 0.1524)
				(type default)
			)
			(layer "B.SilkS")
		)
		(fp_line
			(start 1.524 -0.762)
			(end -1.524 -0.762)
			(stroke
				(width 0.1524)
				(type default)
			)
			(layer "B.SilkS")
		)
		(fp_line
			(start -1.1049 0.724916)
			(end -1.1049 -0.724916)
			(stroke
				(width 0.1)
				(type default)
			)
			(layer "B.Fab")
		)
		(fp_line
			(start 1.1049 0.724916)
			(end -1.1049 0.724916)
			(stroke
				(width 0.1)
				(type default)
			)
			(layer "B.Fab")
		)
		(fp_line
			(start -1.1049 -0.724916)
			(end 1.1049 -0.724916)
			(stroke
				(width 0.1)
				(type default)
			)
			(layer "B.Fab")
		)
		(fp_line
			(start 1.1049 -0.724916)
			(end 1.1049 0.724916)
			(stroke
				(width 0.1)
				(type default)
			)
			(layer "B.Fab")
		)
		(pad "1" smd rect
			(at 0.889 0 270)
			(size 1.016 1.27)
			(layers "B.Cu" "B.Mask" "B.Paste")
			(net "SW_P12V_AUX_PVDDCR_CPU0_P1_FLT")
		)
		(pad "2" smd rect
			(at -0.889 0 270)
			(size 1.016 1.27)
			(layers "B.Cu" "B.Mask" "B.Paste")
			(net "GND")
		)
	)
	(footprint ""
		(layer "B.Cu")
		(at 343.118694 -398.942052 90)
		(property "Reference" "C646"
			(at 0 0 90)
			(layer "B.SilkS")
			(hide yes)
			(effects
				(font
					(size 1.27 1.27)
				)
				(justify mirror)
			)
		)
		(property "Value" ""
			(at 0 0 90)
			(layer "B.Fab")
			(effects
				(font
					(size 1.27 1.27)
				)
				(justify mirror)
			)
		)
		(duplicate_pad_numbers_are_jumpers no)
		(fp_line
			(start 0.7874 -0.4064)
			(end -0.7874 -0.4064)
			(stroke
				(width 0.1524)
				(type default)
			)
			(layer "B.SilkS")
		)
		(fp_line
			(start -0.7874 -0.4064)
			(end -0.7874 0.4064)
			(stroke
				(width 0.1524)
				(type default)
			)
			(layer "B.SilkS")
		)
		(fp_line
			(start 0.7874 0.4064)
			(end 0.7874 -0.4064)
			(stroke
				(width 0.1524)
				(type default)
			)
			(layer "B.SilkS")
		)
		(fp_line
			(start -0.7874 0.4064)
			(end 0.7874 0.4064)
			(stroke
				(width 0.1524)
				(type default)
			)
			(layer "B.SilkS")
		)
		(fp_line
			(start 0.67945 -0.305054)
			(end 0.12065 -0.305054)
			(stroke
				(width 0.1)
				(type default)
			)
			(layer "B.Fab")
		)
		(fp_line
			(start 0.12065 -0.305054)
			(end 0.12065 -0.2794)
			(stroke
				(width 0.1)
				(type default)
			)
			(layer "B.Fab")
		)
		(fp_line
			(start -0.12065 -0.3048)
			(end -0.67945 -0.3048)
			(stroke
				(width 0.1)
				(type default)
			)
			(layer "B.Fab")
		)
		(fp_line
			(start -0.67945 -0.3048)
			(end -0.67945 0.3048)
			(stroke
				(width 0.1)
				(type default)
			)
			(layer "B.Fab")
		)
		(fp_line
			(start 0.12065 -0.2794)
			(end -0.12065 -0.2794)
			(stroke
				(width 0.1)
				(type default)
			)
			(layer "B.Fab")
		)
		(fp_line
			(start -0.12065 -0.2794)
			(end -0.12065 -0.3048)
			(stroke
				(width 0.1)
				(type default)
			)
			(layer "B.Fab")
		)
		(fp_line
			(start 0.12065 0.2794)
			(end 0.12065 0.3048)
			(stroke
				(width 0.1)
				(type default)
			)
			(layer "B.Fab")
		)
		(fp_line
			(start -0.120396 0.2794)
			(end 0.12065 0.2794)
			(stroke
				(width 0.1)
				(type default)
			)
			(layer "B.Fab")
		)
		(fp_line
			(start 0.67945 0.3048)
			(end 0.67945 -0.305054)
			(stroke
				(width 0.1)
				(type default)
			)
			(layer "B.Fab")
		)
		(fp_line
			(start 0.12065 0.3048)
			(end 0.67945 0.3048)
			(stroke
				(width 0.1)
				(type default)
			)
			(layer "B.Fab")
		)
		(fp_line
			(start -0.120396 0.3048)
			(end -0.120396 0.2794)
			(stroke
				(width 0.1)
				(type default)
			)
			(layer "B.Fab")
		)
		(fp_line
			(start -0.67945 0.3048)
			(end -0.120396 0.3048)
			(stroke
				(width 0.1)
				(type default)
			)
			(layer "B.Fab")
		)
		(pad "1" smd circle
			(at 0.40005 0 270)
			(size 0 0)
			(layers "B.Cu" "B.Mask" "B.Paste")
			(net "P0V9_CPU0_RT_2D")
		)
		(pad "2" smd circle
			(at -0.40005 0 270)
			(size 0 0)
			(layers "B.Cu" "B.Mask" "B.Paste")
			(net "GND")
		)
	)
	(footprint ""
		(layer "B.Cu")
		(at 214.122 -335.026)
		(property "Reference" "R6812"
			(at 0 0 0)
			(layer "B.SilkS")
			(hide yes)
			(effects
				(font
					(size 1.27 1.27)
				)
				(justify mirror)
			)
		)
		(property "Value" ""
			(at 0 0 0)
			(layer "B.Fab")
			(effects
				(font
					(size 1.27 1.27)
				)
				(justify mirror)
			)
		)
		(duplicate_pad_numbers_are_jumpers no)
		(fp_line
			(start -0.32512 -0.175006)
			(end -0.32512 0.175006)
			(stroke
				(width 0.1)
				(type default)
			)
			(layer "B.Fab")
		)
		(fp_line
			(start -0.32512 0.175006)
			(end 0.32512 0.175006)
			(stroke
				(width 0.1)
				(type default)
			)
			(layer "B.Fab")
		)
		(fp_line
			(start 0.32512 -0.175006)
			(end -0.32512 -0.175006)
			(stroke
				(width 0.1)
				(type default)
			)
			(layer "B.Fab")
		)
		(fp_line
			(start 0.32512 0.175006)
			(end 0.32512 -0.175006)
			(stroke
				(width 0.1)
				(type default)
			)
			(layer "B.Fab")
		)
		(pad "1" smd rect
			(at 0.2667 0 180)
			(size 0.3048 0.381)
			(layers "B.Cu" "B.Mask" "B.Paste")
			(net "SMB_RT_CPU1_P0_R_SCL")
		)
		(pad "2" smd rect
			(at -0.2667 0)
			(size 0.3048 0.381)
			(layers "B.Cu" "B.Mask" "B.Paste")
			(net "SMB_RT_CPU1_P0_R2_SCL")
		)
	)
	(footprint ""
		(layer "B.Cu")
		(at 62.991238 -390.560052 90)
		(property "Reference" "C284"
			(at 0 0 90)
			(layer "B.SilkS")
			(hide yes)
			(effects
				(font
					(size 1.27 1.27)
				)
				(justify mirror)
			)
		)
		(property "Value" ""
			(at 0 0 90)
			(layer "B.Fab")
			(effects
				(font
					(size 1.27 1.27)
				)
				(justify mirror)
			)
		)
		(duplicate_pad_numbers_are_jumpers no)
		(fp_line
			(start 0.7874 -0.4064)
			(end -0.7874 -0.4064)
			(stroke
				(width 0.1524)
				(type default)
			)
			(layer "B.SilkS")
		)
		(fp_line
			(start -0.7874 -0.4064)
			(end -0.7874 0.4064)
			(stroke
				(width 0.1524)
				(type default)
			)
			(layer "B.SilkS")
		)
		(fp_line
			(start 0.7874 0.4064)
			(end 0.7874 -0.4064)
			(stroke
				(width 0.1524)
				(type default)
			)
			(layer "B.SilkS")
		)
		(fp_line
			(start -0.7874 0.4064)
			(end 0.7874 0.4064)
			(stroke
				(width 0.1524)
				(type default)
			)
			(layer "B.SilkS")
		)
		(fp_line
			(start 0.67945 -0.305054)
			(end 0.12065 -0.305054)
			(stroke
				(width 0.1)
				(type default)
			)
			(layer "B.Fab")
		)
		(fp_line
			(start 0.12065 -0.305054)
			(end 0.12065 -0.2794)
			(stroke
				(width 0.1)
				(type default)
			)
			(layer "B.Fab")
		)
		(fp_line
			(start -0.12065 -0.3048)
			(end -0.67945 -0.3048)
			(stroke
				(width 0.1)
				(type default)
			)
			(layer "B.Fab")
		)
		(fp_line
			(start -0.67945 -0.3048)
			(end -0.67945 0.3048)
			(stroke
				(width 0.1)
				(type default)
			)
			(layer "B.Fab")
		)
		(fp_line
			(start 0.12065 -0.2794)
			(end -0.12065 -0.2794)
			(stroke
				(width 0.1)
				(type default)
			)
			(layer "B.Fab")
		)
		(fp_line
			(start -0.12065 -0.2794)
			(end -0.12065 -0.3048)
			(stroke
				(width 0.1)
				(type default)
			)
			(layer "B.Fab")
		)
		(fp_line
			(start 0.12065 0.2794)
			(end 0.12065 0.3048)
			(stroke
				(width 0.1)
				(type default)
			)
			(layer "B.Fab")
		)
		(fp_line
			(start -0.120396 0.2794)
			(end 0.12065 0.2794)
			(stroke
				(width 0.1)
				(type default)
			)
			(layer "B.Fab")
		)
		(fp_line
			(start 0.67945 0.3048)
			(end 0.67945 -0.305054)
			(stroke
				(width 0.1)
				(type default)
			)
			(layer "B.Fab")
		)
		(fp_line
			(start 0.12065 0.3048)
			(end 0.67945 0.3048)
			(stroke
				(width 0.1)
				(type default)
			)
			(layer "B.Fab")
		)
		(fp_line
			(start -0.120396 0.3048)
			(end -0.120396 0.2794)
			(stroke
				(width 0.1)
				(type default)
			)
			(layer "B.Fab")
		)
		(fp_line
			(start -0.67945 0.3048)
			(end -0.120396 0.3048)
			(stroke
				(width 0.1)
				(type default)
			)
			(layer "B.Fab")
		)
		(pad "1" smd circle
			(at 0.40005 0 270)
			(size 0 0)
			(layers "B.Cu" "B.Mask" "B.Paste")
			(net "P0V9_CPU1_RT0_2A")
		)
		(pad "2" smd circle
			(at -0.40005 0 270)
			(size 0 0)
			(layers "B.Cu" "B.Mask" "B.Paste")
			(net "GND")
		)
	)
	(footprint ""
		(layer "B.Cu")
		(at 242.951 -228.092 -90)
		(property "Reference" "R1153"
			(at 0 0 90)
			(layer "B.SilkS")
			(hide yes)
			(effects
				(font
					(size 1.27 1.27)
				)
				(justify mirror)
			)
		)
		(property "Value" ""
			(at 0 0 90)
			(layer "B.Fab")
			(effects
				(font
					(size 1.27 1.27)
				)
				(justify mirror)
			)
		)
		(duplicate_pad_numbers_are_jumpers no)
		(fp_line
			(start -0.7874 0.4064)
			(end 0.7874 0.4064)
			(stroke
				(width 0.1524)
				(type default)
			)
			(layer "B.SilkS")
		)
		(fp_line
			(start 0.7874 0.4064)
			(end 0.7874 -0.4064)
			(stroke
				(width 0.1524)
				(type default)
			)
			(layer "B.SilkS")
		)
		(fp_line
			(start -0.7874 -0.4064)
			(end -0.7874 0.4064)
			(stroke
				(width 0.1524)
				(type default)
			)
			(layer "B.SilkS")
		)
		(fp_line
			(start 0.7874 -0.4064)
			(end -0.7874 -0.4064)
			(stroke
				(width 0.1524)
				(type default)
			)
			(layer "B.SilkS")
		)
		(fp_line
			(start -0.67945 0.3048)
			(end -0.120396 0.3048)
			(stroke
				(width 0.1)
				(type default)
			)
			(layer "B.Fab")
		)
		(fp_line
			(start -0.120396 0.3048)
			(end -0.120396 0.2794)
			(stroke
				(width 0.1)
				(type default)
			)
			(layer "B.Fab")
		)
		(fp_line
			(start 0.12065 0.3048)
			(end 0.67945 0.3048)
			(stroke
				(width 0.1)
				(type default)
			)
			(layer "B.Fab")
		)
		(fp_line
			(start 0.67945 0.3048)
			(end 0.67945 -0.305054)
			(stroke
				(width 0.1)
				(type default)
			)
			(layer "B.Fab")
		)
		(fp_line
			(start -0.120396 0.2794)
			(end 0.12065 0.2794)
			(stroke
				(width 0.1)
				(type default)
			)
			(layer "B.Fab")
		)
		(fp_line
			(start 0.12065 0.2794)
			(end 0.12065 0.3048)
			(stroke
				(width 0.1)
				(type default)
			)
			(layer "B.Fab")
		)
		(fp_line
			(start -0.12065 -0.2794)
			(end -0.12065 -0.3048)
			(stroke
				(width 0.1)
				(type default)
			)
			(layer "B.Fab")
		)
		(fp_line
			(start 0.12065 -0.2794)
			(end -0.12065 -0.2794)
			(stroke
				(width 0.1)
				(type default)
			)
			(layer "B.Fab")
		)
		(fp_line
			(start -0.67945 -0.3048)
			(end -0.67945 0.3048)
			(stroke
				(width 0.1)
				(type default)
			)
			(layer "B.Fab")
		)
		(fp_line
			(start -0.12065 -0.3048)
			(end -0.67945 -0.3048)
			(stroke
				(width 0.1)
				(type default)
			)
			(layer "B.Fab")
		)
		(fp_line
			(start 0.12065 -0.305054)
			(end 0.12065 -0.2794)
			(stroke
				(width 0.1)
				(type default)
			)
			(layer "B.Fab")
		)
		(fp_line
			(start 0.67945 -0.305054)
			(end 0.12065 -0.305054)
			(stroke
				(width 0.1)
				(type default)
			)
			(layer "B.Fab")
		)
		(pad "1" smd circle
			(at 0.40005 0 90)
			(size 0 0)
			(layers "B.Cu" "B.Mask" "B.Paste")
			(net "SMB_CPU0_CPU1_SEC_SCL_R1")
		)
		(pad "2" smd circle
			(at -0.40005 0 90)
			(size 0 0)
			(layers "B.Cu" "B.Mask" "B.Paste")
			(net "SMB_CPU0_CPU1_SEC_SCL_R2")
		)
	)
	(footprint ""
		(layer "B.Cu")
		(at 186.817 -100.294948 -90)
		(property "Reference" "R181"
			(at 0 0 90)
			(layer "B.SilkS")
			(hide yes)
			(effects
				(font
					(size 1.27 1.27)
				)
				(justify mirror)
			)
		)
		(property "Value" ""
			(at 0 0 90)
			(layer "B.Fab")
			(effects
				(font
					(size 1.27 1.27)
				)
				(justify mirror)
			)
		)
		(duplicate_pad_numbers_are_jumpers no)
		(fp_line
			(start -0.7874 0.4064)
			(end 0.7874 0.4064)
			(stroke
				(width 0.1524)
				(type default)
			)
			(layer "B.SilkS")
		)
		(fp_line
			(start 0.7874 0.4064)
			(end 0.7874 -0.4064)
			(stroke
				(width 0.1524)
				(type default)
			)
			(layer "B.SilkS")
		)
		(fp_line
			(start -0.7874 -0.4064)
			(end -0.7874 0.4064)
			(stroke
				(width 0.1524)
				(type default)
			)
			(layer "B.SilkS")
		)
		(fp_line
			(start 0.7874 -0.4064)
			(end -0.7874 -0.4064)
			(stroke
				(width 0.1524)
				(type default)
			)
			(layer "B.SilkS")
		)
		(fp_line
			(start -0.67945 0.3048)
			(end -0.120396 0.3048)
			(stroke
				(width 0.1)
				(type default)
			)
			(layer "B.Fab")
		)
		(fp_line
			(start -0.120396 0.3048)
			(end -0.120396 0.2794)
			(stroke
				(width 0.1)
				(type default)
			)
			(layer "B.Fab")
		)
		(fp_line
			(start 0.12065 0.3048)
			(end 0.67945 0.3048)
			(stroke
				(width 0.1)
				(type default)
			)
			(layer "B.Fab")
		)
		(fp_line
			(start 0.67945 0.3048)
			(end 0.67945 -0.305054)
			(stroke
				(width 0.1)
				(type default)
			)
			(layer "B.Fab")
		)
		(fp_line
			(start -0.120396 0.2794)
			(end 0.12065 0.2794)
			(stroke
				(width 0.1)
				(type default)
			)
			(layer "B.Fab")
		)
		(fp_line
			(start 0.12065 0.2794)
			(end 0.12065 0.3048)
			(stroke
				(width 0.1)
				(type default)
			)
			(layer "B.Fab")
		)
		(fp_line
			(start -0.12065 -0.2794)
			(end -0.12065 -0.3048)
			(stroke
				(width 0.1)
				(type default)
			)
			(layer "B.Fab")
		)
		(fp_line
			(start 0.12065 -0.2794)
			(end -0.12065 -0.2794)
			(stroke
				(width 0.1)
				(type default)
			)
			(layer "B.Fab")
		)
		(fp_line
			(start -0.67945 -0.3048)
			(end -0.67945 0.3048)
			(stroke
				(width 0.1)
				(type default)
			)
			(layer "B.Fab")
		)
		(fp_line
			(start -0.12065 -0.3048)
			(end -0.67945 -0.3048)
			(stroke
				(width 0.1)
				(type default)
			)
			(layer "B.Fab")
		)
		(fp_line
			(start 0.12065 -0.305054)
			(end 0.12065 -0.2794)
			(stroke
				(width 0.1)
				(type default)
			)
			(layer "B.Fab")
		)
		(fp_line
			(start 0.67945 -0.305054)
			(end 0.12065 -0.305054)
			(stroke
				(width 0.1)
				(type default)
			)
			(layer "B.Fab")
		)
		(pad "1" smd circle
			(at 0.40005 0 90)
			(size 0 0)
			(layers "B.Cu" "B.Mask" "B.Paste")
			(net "CPU0_SP5R2")
		)
		(pad "2" smd circle
			(at -0.40005 0 90)
			(size 0 0)
			(layers "B.Cu" "B.Mask" "B.Paste")
			(net "FM_CPU0_SP5R2")
		)
	)
	(footprint ""
		(layer "B.Cu")
		(at 158.39948 -352.566478 180)
		(property "Reference" "R8385"
			(at 0 0 0)
			(layer "B.SilkS")
			(hide yes)
			(effects
				(font
					(size 1.27 1.27)
				)
				(justify mirror)
			)
		)
		(property "Value" ""
			(at 0 0 0)
			(layer "B.Fab")
			(effects
				(font
					(size 1.27 1.27)
				)
				(justify mirror)
			)
		)
		(duplicate_pad_numbers_are_jumpers no)
		(fp_line
			(start 0.7874 0.4064)
			(end 0.7874 -0.4064)
			(stroke
				(width 0.1524)
				(type default)
			)
			(layer "B.SilkS")
		)
		(fp_line
			(start 0.7874 -0.4064)
			(end -0.7874 -0.4064)
			(stroke
				(width 0.1524)
				(type default)
			)
			(layer "B.SilkS")
		)
		(fp_line
			(start -0.7874 0.4064)
			(end 0.7874 0.4064)
			(stroke
				(width 0.1524)
				(type default)
			)
			(layer "B.SilkS")
		)
		(fp_line
			(start -0.7874 -0.4064)
			(end -0.7874 0.4064)
			(stroke
				(width 0.1524)
				(type default)
			)
			(layer "B.SilkS")
		)
		(fp_line
			(start 0.67945 0.3048)
			(end 0.67945 -0.305054)
			(stroke
				(width 0.1)
				(type default)
			)
			(layer "B.Fab")
		)
		(fp_line
			(start 0.67945 -0.305054)
			(end 0.12065 -0.305054)
			(stroke
				(width 0.1)
				(type default)
			)
			(layer "B.Fab")
		)
		(fp_line
			(start 0.12065 0.3048)
			(end 0.67945 0.3048)
			(stroke
				(width 0.1)
				(type default)
			)
			(layer "B.Fab")
		)
		(fp_line
			(start 0.12065 0.2794)
			(end 0.12065 0.3048)
			(stroke
				(width 0.1)
				(type default)
			)
			(layer "B.Fab")
		)
		(fp_line
			(start 0.12065 -0.2794)
			(end -0.12065 -0.2794)
			(stroke
				(width 0.1)
				(type default)
			)
			(layer "B.Fab")
		)
		(fp_line
			(start 0.12065 -0.305054)
			(end 0.12065 -0.2794)
			(stroke
				(width 0.1)
				(type default)
			)
			(layer "B.Fab")
		)
		(fp_line
			(start -0.120396 0.3048)
			(end -0.120396 0.2794)
			(stroke
				(width 0.1)
				(type default)
			)
			(layer "B.Fab")
		)
		(fp_line
			(start -0.120396 0.2794)
			(end 0.12065 0.2794)
			(stroke
				(width 0.1)
				(type default)
			)
			(layer "B.Fab")
		)
		(fp_line
			(start -0.12065 -0.2794)
			(end -0.12065 -0.3048)
			(stroke
				(width 0.1)
				(type default)
			)
			(layer "B.Fab")
		)
		(fp_line
			(start -0.12065 -0.3048)
			(end -0.67945 -0.3048)
			(stroke
				(width 0.1)
				(type default)
			)
			(layer "B.Fab")
		)
		(fp_line
			(start -0.67945 0.3048)
			(end -0.120396 0.3048)
			(stroke
				(width 0.1)
				(type default)
			)
			(layer "B.Fab")
		)
		(fp_line
			(start -0.67945 -0.3048)
			(end -0.67945 0.3048)
			(stroke
				(width 0.1)
				(type default)
			)
			(layer "B.Fab")
		)
		(pad "1" smd circle
			(at 0.40005 0)
			(size 0 0)
			(layers "B.Cu" "B.Mask" "B.Paste")
			(net "PWRGD_PVDD11_S3_P1")
		)
		(pad "2" smd circle
			(at -0.40005 0)
			(size 0 0)
			(layers "B.Cu" "B.Mask" "B.Paste")
			(net "PWRGD_PVDD11_S3_P1_R")
		)
	)
	(footprint ""
		(layer "B.Cu")
		(at 230.65105 -223.041972 -90)
		(property "Reference" "U2"
			(at 0.982218 2.852674 270)
			(unlocked yes)
			(layer "B.SilkS")
			(effects
				(font
					(size 0.7874 0.5842)
					(thickness 0.1524)
				)
				(justify left mirror)
			)
		)
		(property "Value" ""
			(at 0 0 90)
			(layer "B.Fab")
			(effects
				(font
					(size 1.27 1.27)
				)
				(justify mirror)
			)
		)
		(duplicate_pad_numbers_are_jumpers no)
		(fp_line
			(start -1.463548 1.549908)
			(end 1.463548 1.549908)
			(stroke
				(width 0.1524)
				(type default)
			)
			(layer "B.SilkS")
		)
		(fp_line
			(start 1.463548 1.549908)
			(end 1.463548 -1.549908)
			(stroke
				(width 0.1524)
				(type default)
			)
			(layer "B.SilkS")
		)
		(fp_line
			(start 0 -0.762)
			(end -0.762 -1.549908)
			(stroke
				(width 0.1524)
				(type default)
			)
			(layer "B.SilkS")
		)
		(fp_line
			(start -1.463548 -1.549908)
			(end -1.463548 1.549908)
			(stroke
				(width 0.1524)
				(type default)
			)
			(layer "B.SilkS")
		)
		(fp_line
			(start -0.762 -1.549908)
			(end -1.463548 -1.549908)
			(stroke
				(width 0.1524)
				(type default)
			)
			(layer "B.SilkS")
		)
		(fp_line
			(start 0.787908 -1.549908)
			(end 0 -0.762)
			(stroke
				(width 0.1524)
				(type default)
			)
			(layer "B.SilkS")
		)
		(fp_line
			(start 1.463548 -1.549908)
			(end 0.787908 -1.549908)
			(stroke
				(width 0.1524)
				(type default)
			)
			(layer "B.SilkS")
		)
		(fp_poly
			(pts
				(xy 3.780282 -1.017524) (xy 3.160522 -1.327404) (xy 3.780282 -1.637284)
			)
			(stroke
				(width 0)
				(type default)
			)
			(fill yes)
			(layer "B.SilkS")
		)
		(fp_line
			(start -1.549908 1.549908)
			(end 1.549908 1.549908)
			(stroke
				(width 0.1)
				(type default)
			)
			(layer "B.Fab")
		)
		(fp_line
			(start 1.549908 1.549908)
			(end 1.549908 -1.549908)
			(stroke
				(width 0.1)
				(type default)
			)
			(layer "B.Fab")
		)
		(fp_line
			(start -1.549908 -1.549908)
			(end -1.549908 1.549908)
			(stroke
				(width 0.1)
				(type default)
			)
			(layer "B.Fab")
		)
		(fp_line
			(start 1.549908 -1.549908)
			(end -1.549908 -1.549908)
			(stroke
				(width 0.1)
				(type default)
			)
			(layer "B.Fab")
		)
		(fp_poly
			(pts
				(xy 3.4798 -1.359916) (xy 2.86004 -1.050036) (xy 3.4798 -0.740156)
			)
			(stroke
				(width 0)
				(type default)
			)
			(fill yes)
			(layer "B.Fab")
		)
		(pad "1" smd rect
			(at 2.175002 -1.050036)
			(size 0.6096 1.1684)
			(layers "B.Cu" "B.Mask" "B.Paste")
			(net "PVDD11_S3_P0")
		)
		(pad "2" smd rect
			(at 2.175002 -0.32512)
			(size 0.4318 1.1684)
			(layers "B.Cu" "B.Mask" "B.Paste")
			(net "SMB_CPU0_CPU1_APML_BUF2_SCL_R1")
		)
		(pad "3" smd rect
			(at 2.175002 0.32512)
			(size 0.4318 1.1684)
			(layers "B.Cu" "B.Mask" "B.Paste")
			(net "SMB_CPU0_CPU1_APML_BUF2_SDA_R1")
		)
		(pad "4" smd rect
			(at 2.175002 1.050036)
			(size 0.6096 1.1684)
			(layers "B.Cu" "B.Mask" "B.Paste")
			(net "GND")
		)
		(pad "5" smd rect
			(at -2.175002 1.050036)
			(size 0.6096 1.1684)
			(layers "B.Cu" "B.Mask" "B.Paste")
			(net "PU_U2_EN")
		)
		(pad "6" smd rect
			(at -2.175002 0.32512)
			(size 0.4318 1.1684)
			(layers "B.Cu" "B.Mask" "B.Paste")
			(net "SMB_CPU0_CPU1_APML_BUF2_SDA")
		)
		(pad "7" smd rect
			(at -2.175002 -0.32512)
			(size 0.4318 1.1684)
			(layers "B.Cu" "B.Mask" "B.Paste")
			(net "SMB_CPU0_CPU1_APML_BUF2_SCL")
		)
		(pad "8" smd rect
			(at -2.175002 -1.050036)
			(size 0.6096 1.1684)
			(layers "B.Cu" "B.Mask" "B.Paste")
			(net "P3V3_AUX")
		)
	)
	(footprint ""
		(layer "B.Cu")
		(at 102.811834 -249.368564 180)
		(property "Reference" "C2343"
			(at 0 0 0)
			(layer "B.SilkS")
			(hide yes)
			(effects
				(font
					(size 1.27 1.27)
				)
				(justify mirror)
			)
		)
		(property "Value" ""
			(at 0 0 0)
			(layer "B.Fab")
			(effects
				(font
					(size 1.27 1.27)
				)
				(justify mirror)
			)
		)
		(duplicate_pad_numbers_are_jumpers no)
		(fp_line
			(start 0.7874 0.4064)
			(end 0.7874 -0.4064)
			(stroke
				(width 0.1524)
				(type default)
			)
			(layer "B.SilkS")
		)
		(fp_line
			(start 0.7874 -0.4064)
			(end -0.7874 -0.4064)
			(stroke
				(width 0.1524)
				(type default)
			)
			(layer "B.SilkS")
		)
		(fp_line
			(start -0.7874 0.4064)
			(end 0.7874 0.4064)
			(stroke
				(width 0.1524)
				(type default)
			)
			(layer "B.SilkS")
		)
		(fp_line
			(start -0.7874 -0.4064)
			(end -0.7874 0.4064)
			(stroke
				(width 0.1524)
				(type default)
			)
			(layer "B.SilkS")
		)
		(fp_line
			(start 0.67945 0.3048)
			(end 0.67945 -0.305054)
			(stroke
				(width 0.1)
				(type default)
			)
			(layer "B.Fab")
		)
		(fp_line
			(start 0.67945 -0.305054)
			(end 0.12065 -0.305054)
			(stroke
				(width 0.1)
				(type default)
			)
			(layer "B.Fab")
		)
		(fp_line
			(start 0.12065 0.3048)
			(end 0.67945 0.3048)
			(stroke
				(width 0.1)
				(type default)
			)
			(layer "B.Fab")
		)
		(fp_line
			(start 0.12065 0.2794)
			(end 0.12065 0.3048)
			(stroke
				(width 0.1)
				(type default)
			)
			(layer "B.Fab")
		)
		(fp_line
			(start 0.12065 -0.2794)
			(end -0.12065 -0.2794)
			(stroke
				(width 0.1)
				(type default)
			)
			(layer "B.Fab")
		)
		(fp_line
			(start 0.12065 -0.305054)
			(end 0.12065 -0.2794)
			(stroke
				(width 0.1)
				(type default)
			)
			(layer "B.Fab")
		)
		(fp_line
			(start -0.120396 0.3048)
			(end -0.120396 0.2794)
			(stroke
				(width 0.1)
				(type default)
			)
			(layer "B.Fab")
		)
		(fp_line
			(start -0.120396 0.2794)
			(end 0.12065 0.2794)
			(stroke
				(width 0.1)
				(type default)
			)
			(layer "B.Fab")
		)
		(fp_line
			(start -0.12065 -0.2794)
			(end -0.12065 -0.3048)
			(stroke
				(width 0.1)
				(type default)
			)
			(layer "B.Fab")
		)
		(fp_line
			(start -0.12065 -0.3048)
			(end -0.67945 -0.3048)
			(stroke
				(width 0.1)
				(type default)
			)
			(layer "B.Fab")
		)
		(fp_line
			(start -0.67945 0.3048)
			(end -0.120396 0.3048)
			(stroke
				(width 0.1)
				(type default)
			)
			(layer "B.Fab")
		)
		(fp_line
			(start -0.67945 -0.3048)
			(end -0.67945 0.3048)
			(stroke
				(width 0.1)
				(type default)
			)
			(layer "B.Fab")
		)
		(pad "1" smd circle
			(at 0.40005 0)
			(size 0 0)
			(layers "B.Cu" "B.Mask" "B.Paste")
			(net "PVDDCR_CPU0_P1")
		)
		(pad "2" smd circle
			(at -0.40005 0)
			(size 0 0)
			(layers "B.Cu" "B.Mask" "B.Paste")
			(net "GND")
		)
	)
	(footprint ""
		(layer "B.Cu")
		(at 182.468774 -133.843014 90)
		(property "Reference" "R6793"
			(at 0 0 90)
			(layer "B.SilkS")
			(hide yes)
			(effects
				(font
					(size 1.27 1.27)
				)
				(justify mirror)
			)
		)
		(property "Value" ""
			(at 0 0 90)
			(layer "B.Fab")
			(effects
				(font
					(size 1.27 1.27)
				)
				(justify mirror)
			)
		)
		(duplicate_pad_numbers_are_jumpers no)
		(fp_line
			(start 0.7874 -0.4064)
			(end -0.7874 -0.4064)
			(stroke
				(width 0.1524)
				(type default)
			)
			(layer "B.SilkS")
		)
		(fp_line
			(start -0.7874 -0.4064)
			(end -0.7874 0.4064)
			(stroke
				(width 0.1524)
				(type default)
			)
			(layer "B.SilkS")
		)
		(fp_line
			(start 0.7874 0.4064)
			(end 0.7874 -0.4064)
			(stroke
				(width 0.1524)
				(type default)
			)
			(layer "B.SilkS")
		)
		(fp_line
			(start -0.7874 0.4064)
			(end 0.7874 0.4064)
			(stroke
				(width 0.1524)
				(type default)
			)
			(layer "B.SilkS")
		)
		(fp_line
			(start 0.67945 -0.305054)
			(end 0.12065 -0.305054)
			(stroke
				(width 0.1)
				(type default)
			)
			(layer "B.Fab")
		)
		(fp_line
			(start 0.12065 -0.305054)
			(end 0.12065 -0.2794)
			(stroke
				(width 0.1)
				(type default)
			)
			(layer "B.Fab")
		)
		(fp_line
			(start -0.12065 -0.3048)
			(end -0.67945 -0.3048)
			(stroke
				(width 0.1)
				(type default)
			)
			(layer "B.Fab")
		)
		(fp_line
			(start -0.67945 -0.3048)
			(end -0.67945 0.3048)
			(stroke
				(width 0.1)
				(type default)
			)
			(layer "B.Fab")
		)
		(fp_line
			(start 0.12065 -0.2794)
			(end -0.12065 -0.2794)
			(stroke
				(width 0.1)
				(type default)
			)
			(layer "B.Fab")
		)
		(fp_line
			(start -0.12065 -0.2794)
			(end -0.12065 -0.3048)
			(stroke
				(width 0.1)
				(type default)
			)
			(layer "B.Fab")
		)
		(fp_line
			(start 0.12065 0.2794)
			(end 0.12065 0.3048)
			(stroke
				(width 0.1)
				(type default)
			)
			(layer "B.Fab")
		)
		(fp_line
			(start -0.120396 0.2794)
			(end 0.12065 0.2794)
			(stroke
				(width 0.1)
				(type default)
			)
			(layer "B.Fab")
		)
		(fp_line
			(start 0.67945 0.3048)
			(end 0.67945 -0.305054)
			(stroke
				(width 0.1)
				(type default)
			)
			(layer "B.Fab")
		)
		(fp_line
			(start 0.12065 0.3048)
			(end 0.67945 0.3048)
			(stroke
				(width 0.1)
				(type default)
			)
			(layer "B.Fab")
		)
		(fp_line
			(start -0.120396 0.3048)
			(end -0.120396 0.2794)
			(stroke
				(width 0.1)
				(type default)
			)
			(layer "B.Fab")
		)
		(fp_line
			(start -0.67945 0.3048)
			(end -0.120396 0.3048)
			(stroke
				(width 0.1)
				(type default)
			)
			(layer "B.Fab")
		)
		(pad "1" smd circle
			(at 0.40005 0 270)
			(size 0 0)
			(layers "B.Cu" "B.Mask" "B.Paste")
			(net "RST_RT_CPU1_P2_RESET_R_N")
		)
		(pad "2" smd circle
			(at -0.40005 0 270)
			(size 0 0)
			(layers "B.Cu" "B.Mask" "B.Paste")
			(net "RST_RT_CPU1_P2_RESET_R2_N")
		)
	)
	(footprint ""
		(layer "B.Cu")
		(at 185.680858 -147.837144 180)
		(property "Reference" "R8034"
			(at 0 0 0)
			(layer "B.SilkS")
			(hide yes)
			(effects
				(font
					(size 1.27 1.27)
				)
				(justify mirror)
			)
		)
		(property "Value" ""
			(at 0 0 0)
			(layer "B.Fab")
			(effects
				(font
					(size 1.27 1.27)
				)
				(justify mirror)
			)
		)
		(duplicate_pad_numbers_are_jumpers no)
		(fp_line
			(start 0.7874 0.4064)
			(end 0.7874 -0.4064)
			(stroke
				(width 0.1524)
				(type default)
			)
			(layer "B.SilkS")
		)
		(fp_line
			(start 0.7874 -0.4064)
			(end -0.7874 -0.4064)
			(stroke
				(width 0.1524)
				(type default)
			)
			(layer "B.SilkS")
		)
		(fp_line
			(start -0.7874 0.4064)
			(end 0.7874 0.4064)
			(stroke
				(width 0.1524)
				(type default)
			)
			(layer "B.SilkS")
		)
		(fp_line
			(start -0.7874 -0.4064)
			(end -0.7874 0.4064)
			(stroke
				(width 0.1524)
				(type default)
			)
			(layer "B.SilkS")
		)
		(fp_line
			(start 0.67945 0.3048)
			(end 0.67945 -0.305054)
			(stroke
				(width 0.1)
				(type default)
			)
			(layer "B.Fab")
		)
		(fp_line
			(start 0.67945 -0.305054)
			(end 0.12065 -0.305054)
			(stroke
				(width 0.1)
				(type default)
			)
			(layer "B.Fab")
		)
		(fp_line
			(start 0.12065 0.3048)
			(end 0.67945 0.3048)
			(stroke
				(width 0.1)
				(type default)
			)
			(layer "B.Fab")
		)
		(fp_line
			(start 0.12065 0.2794)
			(end 0.12065 0.3048)
			(stroke
				(width 0.1)
				(type default)
			)
			(layer "B.Fab")
		)
		(fp_line
			(start 0.12065 -0.2794)
			(end -0.12065 -0.2794)
			(stroke
				(width 0.1)
				(type default)
			)
			(layer "B.Fab")
		)
		(fp_line
			(start 0.12065 -0.305054)
			(end 0.12065 -0.2794)
			(stroke
				(width 0.1)
				(type default)
			)
			(layer "B.Fab")
		)
		(fp_line
			(start -0.120396 0.3048)
			(end -0.120396 0.2794)
			(stroke
				(width 0.1)
				(type default)
			)
			(layer "B.Fab")
		)
		(fp_line
			(start -0.120396 0.2794)
			(end 0.12065 0.2794)
			(stroke
				(width 0.1)
				(type default)
			)
			(layer "B.Fab")
		)
		(fp_line
			(start -0.12065 -0.2794)
			(end -0.12065 -0.3048)
			(stroke
				(width 0.1)
				(type default)
			)
			(layer "B.Fab")
		)
		(fp_line
			(start -0.12065 -0.3048)
			(end -0.67945 -0.3048)
			(stroke
				(width 0.1)
				(type default)
			)
			(layer "B.Fab")
		)
		(fp_line
			(start -0.67945 0.3048)
			(end -0.120396 0.3048)
			(stroke
				(width 0.1)
				(type default)
			)
			(layer "B.Fab")
		)
		(fp_line
			(start -0.67945 -0.3048)
			(end -0.67945 0.3048)
			(stroke
				(width 0.1)
				(type default)
			)
			(layer "B.Fab")
		)
		(pad "1" smd circle
			(at 0.40005 0)
			(size 0 0)
			(layers "B.Cu" "B.Mask" "B.Paste")
			(net "ESPI_CPU0_ALERT_R1_N")
		)
		(pad "2" smd circle
			(at -0.40005 0)
			(size 0 0)
			(layers "B.Cu" "B.Mask" "B.Paste")
			(net "ESPI_CPU0_ALERT_N")
		)
	)
	(footprint ""
		(layer "B.Cu")
		(at 383.732278 -144.647158 -90)
		(property "Reference" "PC464"
			(at 0 0 90)
			(layer "B.SilkS")
			(hide yes)
			(effects
				(font
					(size 1.27 1.27)
				)
				(justify mirror)
			)
		)
		(property "Value" ""
			(at 0 0 90)
			(layer "B.Fab")
			(effects
				(font
					(size 1.27 1.27)
				)
				(justify mirror)
			)
		)
		(duplicate_pad_numbers_are_jumpers no)
		(fp_line
			(start -0.7874 0.4064)
			(end 0.7874 0.4064)
			(stroke
				(width 0.1524)
				(type default)
			)
			(layer "B.SilkS")
		)
		(fp_line
			(start 0.7874 0.4064)
			(end 0.7874 -0.4064)
			(stroke
				(width 0.1524)
				(type default)
			)
			(layer "B.SilkS")
		)
		(fp_line
			(start -0.7874 -0.4064)
			(end -0.7874 0.4064)
			(stroke
				(width 0.1524)
				(type default)
			)
			(layer "B.SilkS")
		)
		(fp_line
			(start 0.7874 -0.4064)
			(end -0.7874 -0.4064)
			(stroke
				(width 0.1524)
				(type default)
			)
			(layer "B.SilkS")
		)
		(fp_line
			(start -0.67945 0.3048)
			(end -0.120396 0.3048)
			(stroke
				(width 0.1)
				(type default)
			)
			(layer "B.Fab")
		)
		(fp_line
			(start -0.120396 0.3048)
			(end -0.120396 0.2794)
			(stroke
				(width 0.1)
				(type default)
			)
			(layer "B.Fab")
		)
		(fp_line
			(start 0.12065 0.3048)
			(end 0.67945 0.3048)
			(stroke
				(width 0.1)
				(type default)
			)
			(layer "B.Fab")
		)
		(fp_line
			(start 0.67945 0.3048)
			(end 0.67945 -0.305054)
			(stroke
				(width 0.1)
				(type default)
			)
			(layer "B.Fab")
		)
		(fp_line
			(start -0.120396 0.2794)
			(end 0.12065 0.2794)
			(stroke
				(width 0.1)
				(type default)
			)
			(layer "B.Fab")
		)
		(fp_line
			(start 0.12065 0.2794)
			(end 0.12065 0.3048)
			(stroke
				(width 0.1)
				(type default)
			)
			(layer "B.Fab")
		)
		(fp_line
			(start -0.12065 -0.2794)
			(end -0.12065 -0.3048)
			(stroke
				(width 0.1)
				(type default)
			)
			(layer "B.Fab")
		)
		(fp_line
			(start 0.12065 -0.2794)
			(end -0.12065 -0.2794)
			(stroke
				(width 0.1)
				(type default)
			)
			(layer "B.Fab")
		)
		(fp_line
			(start -0.67945 -0.3048)
			(end -0.67945 0.3048)
			(stroke
				(width 0.1)
				(type default)
			)
			(layer "B.Fab")
		)
		(fp_line
			(start -0.12065 -0.3048)
			(end -0.67945 -0.3048)
			(stroke
				(width 0.1)
				(type default)
			)
			(layer "B.Fab")
		)
		(fp_line
			(start 0.12065 -0.305054)
			(end 0.12065 -0.2794)
			(stroke
				(width 0.1)
				(type default)
			)
			(layer "B.Fab")
		)
		(fp_line
			(start 0.67945 -0.305054)
			(end 0.12065 -0.305054)
			(stroke
				(width 0.1)
				(type default)
			)
			(layer "B.Fab")
		)
		(pad "1" smd circle
			(at 0.40005 0 90)
			(size 0 0)
			(layers "B.Cu" "B.Mask" "B.Paste")
			(net "VSENSE_PVDDCR_SOC_P0_VSEN1")
		)
		(pad "2" smd circle
			(at -0.40005 0 90)
			(size 0 0)
			(layers "B.Cu" "B.Mask" "B.Paste")
			(net "VSENSE_VSS_SENSE_A_P0")
		)
	)
	(footprint ""
		(layer "B.Cu")
		(at 102.938834 -250.892564 180)
		(property "Reference" "C2348"
			(at 0 0 0)
			(layer "B.SilkS")
			(hide yes)
			(effects
				(font
					(size 1.27 1.27)
				)
				(justify mirror)
			)
		)
		(property "Value" ""
			(at 0 0 0)
			(layer "B.Fab")
			(effects
				(font
					(size 1.27 1.27)
				)
				(justify mirror)
			)
		)
		(duplicate_pad_numbers_are_jumpers no)
		(fp_line
			(start 0.7874 0.4064)
			(end 0.7874 -0.4064)
			(stroke
				(width 0.1524)
				(type default)
			)
			(layer "B.SilkS")
		)
		(fp_line
			(start 0.7874 -0.4064)
			(end -0.7874 -0.4064)
			(stroke
				(width 0.1524)
				(type default)
			)
			(layer "B.SilkS")
		)
		(fp_line
			(start -0.7874 0.4064)
			(end 0.7874 0.4064)
			(stroke
				(width 0.1524)
				(type default)
			)
			(layer "B.SilkS")
		)
		(fp_line
			(start -0.7874 -0.4064)
			(end -0.7874 0.4064)
			(stroke
				(width 0.1524)
				(type default)
			)
			(layer "B.SilkS")
		)
		(fp_line
			(start 0.67945 0.3048)
			(end 0.67945 -0.305054)
			(stroke
				(width 0.1)
				(type default)
			)
			(layer "B.Fab")
		)
		(fp_line
			(start 0.67945 -0.305054)
			(end 0.12065 -0.305054)
			(stroke
				(width 0.1)
				(type default)
			)
			(layer "B.Fab")
		)
		(fp_line
			(start 0.12065 0.3048)
			(end 0.67945 0.3048)
			(stroke
				(width 0.1)
				(type default)
			)
			(layer "B.Fab")
		)
		(fp_line
			(start 0.12065 0.2794)
			(end 0.12065 0.3048)
			(stroke
				(width 0.1)
				(type default)
			)
			(layer "B.Fab")
		)
		(fp_line
			(start 0.12065 -0.2794)
			(end -0.12065 -0.2794)
			(stroke
				(width 0.1)
				(type default)
			)
			(layer "B.Fab")
		)
		(fp_line
			(start 0.12065 -0.305054)
			(end 0.12065 -0.2794)
			(stroke
				(width 0.1)
				(type default)
			)
			(layer "B.Fab")
		)
		(fp_line
			(start -0.120396 0.3048)
			(end -0.120396 0.2794)
			(stroke
				(width 0.1)
				(type default)
			)
			(layer "B.Fab")
		)
		(fp_line
			(start -0.120396 0.2794)
			(end 0.12065 0.2794)
			(stroke
				(width 0.1)
				(type default)
			)
			(layer "B.Fab")
		)
		(fp_line
			(start -0.12065 -0.2794)
			(end -0.12065 -0.3048)
			(stroke
				(width 0.1)
				(type default)
			)
			(layer "B.Fab")
		)
		(fp_line
			(start -0.12065 -0.3048)
			(end -0.67945 -0.3048)
			(stroke
				(width 0.1)
				(type default)
			)
			(layer "B.Fab")
		)
		(fp_line
			(start -0.67945 0.3048)
			(end -0.120396 0.3048)
			(stroke
				(width 0.1)
				(type default)
			)
			(layer "B.Fab")
		)
		(fp_line
			(start -0.67945 -0.3048)
			(end -0.67945 0.3048)
			(stroke
				(width 0.1)
				(type default)
			)
			(layer "B.Fab")
		)
		(pad "1" smd circle
			(at 0.40005 0)
			(size 0 0)
			(layers "B.Cu" "B.Mask" "B.Paste")
			(net "PVDDCR_CPU0_P1")
		)
		(pad "2" smd circle
			(at -0.40005 0)
			(size 0 0)
			(layers "B.Cu" "B.Mask" "B.Paste")
			(net "GND")
		)
	)
	(footprint ""
		(layer "B.Cu")
		(at 438.903618 -343.656412 -90)
		(property "Reference" "PC800"
			(at 7.654036 -3.431286 270)
			(unlocked yes)
			(layer "B.SilkS")
			(effects
				(font
					(size 0.7874 0.5842)
					(thickness 0.1524)
				)
				(justify left mirror)
			)
		)
		(property "Value" ""
			(at 0 0 90)
			(layer "B.Fab")
			(effects
				(font
					(size 1.27 1.27)
				)
				(justify mirror)
			)
		)
		(duplicate_pad_numbers_are_jumpers no)
		(fp_line
			(start -4.533392 2.249932)
			(end 4.533392 2.249932)
			(stroke
				(width 0.1524)
				(type default)
			)
			(layer "B.SilkS")
		)
		(fp_line
			(start 4.533392 2.249932)
			(end 4.533392 -2.249932)
			(stroke
				(width 0.1524)
				(type default)
			)
			(layer "B.SilkS")
		)
		(fp_line
			(start -4.533392 -2.249932)
			(end -4.533392 2.249932)
			(stroke
				(width 0.1524)
				(type default)
			)
			(layer "B.SilkS")
		)
		(fp_line
			(start 4.533392 -2.249932)
			(end -4.533392 -2.249932)
			(stroke
				(width 0.1524)
				(type default)
			)
			(layer "B.SilkS")
		)
		(fp_rect
			(start 5.39242 2.326132)
			(end 4.533392 -2.326132)
			(stroke
				(width 0)
				(type default)
			)
			(fill yes)
			(layer "B.SilkS")
		)
		(fp_line
			(start -3.750056 2.249932)
			(end 3.750056 2.249932)
			(stroke
				(width 0.1)
				(type default)
			)
			(layer "B.Fab")
		)
		(fp_line
			(start 3.750056 2.249932)
			(end 3.750056 -2.249932)
			(stroke
				(width 0.1)
				(type default)
			)
			(layer "B.Fab")
		)
		(fp_line
			(start -3.750056 -2.249932)
			(end -3.750056 2.249932)
			(stroke
				(width 0.1)
				(type default)
			)
			(layer "B.Fab")
		)
		(fp_line
			(start 3.750056 -2.249932)
			(end -3.750056 -2.249932)
			(stroke
				(width 0.1)
				(type default)
			)
			(layer "B.Fab")
		)
		(fp_text user "+"
			(at 6.322314 0.786384 180)
			(unlocked yes)
			(layer "B.SilkS")
			(effects
				(font
					(size 1.905 1.4224)
					(thickness 0.1524)
				)
				(justify left mirror)
			)
		)
		(fp_text user "-"
			(at -4.618228 0.045466 270)
			(unlocked yes)
			(layer "B.SilkS")
			(effects
				(font
					(size 1.905 1.4224)
					(thickness 0.1524)
				)
				(justify left mirror)
			)
		)
		(fp_text user "+"
			(at 6.322314 0.786384 180)
			(unlocked yes)
			(layer "B.Fab")
			(effects
				(font
					(size 1.905 1.4224)
					(thickness 0.1524)
				)
				(justify left mirror)
			)
		)
		(fp_text user "-"
			(at -4.8514 -0.14605 270)
			(unlocked yes)
			(layer "B.Fab")
			(effects
				(font
					(size 1.905 1.4224)
					(thickness 0.1524)
				)
				(justify left mirror)
			)
		)
		(pad "1" smd rect
			(at 3.199892 0 90)
			(size 2.413 2.8194)
			(layers "B.Cu" "B.Mask" "B.Paste")
			(net "PVDD11_S3_P0")
		)
		(pad "2" smd rect
			(at -3.199892 0 90)
			(size 2.413 2.8194)
			(layers "B.Cu" "B.Mask" "B.Paste")
			(net "GND")
		)
	)
	(footprint ""
		(layer "B.Cu")
		(at 367.595658 -139.780772 -90)
		(property "Reference" "PQ17"
			(at -0.07112 -2.670048 270)
			(unlocked yes)
			(layer "B.SilkS")
			(effects
				(font
					(size 0.7874 0.5842)
					(thickness 0.1524)
				)
				(justify mirror)
			)
		)
		(property "Value" ""
			(at 0 0 90)
			(layer "B.Fab")
			(effects
				(font
					(size 1.27 1.27)
				)
				(justify mirror)
			)
		)
		(duplicate_pad_numbers_are_jumpers no)
		(fp_line
			(start -1.949958 1.610106)
			(end 1.949958 1.610106)
			(stroke
				(width 0.1524)
				(type default)
			)
			(layer "B.SilkS")
		)
		(fp_line
			(start 1.949958 1.610106)
			(end 1.949958 -1.610106)
			(stroke
				(width 0.1524)
				(type default)
			)
			(layer "B.SilkS")
		)
		(fp_line
			(start -1.949958 -1.560068)
			(end -1.949958 1.610106)
			(stroke
				(width 0.1524)
				(type default)
			)
			(layer "B.SilkS")
		)
		(fp_line
			(start 1.949958 -1.610106)
			(end -1.949958 -1.610106)
			(stroke
				(width 0.1524)
				(type default)
			)
			(layer "B.SilkS")
		)
		(fp_line
			(start -0.750062 1.560068)
			(end 0.750062 1.560068)
			(stroke
				(width 0.1)
				(type default)
			)
			(layer "B.Fab")
		)
		(fp_line
			(start 0.750062 1.560068)
			(end 0.750062 -1.560068)
			(stroke
				(width 0.1)
				(type default)
			)
			(layer "B.Fab")
		)
		(fp_line
			(start -0.750062 -1.560068)
			(end -0.750062 1.560068)
			(stroke
				(width 0.1)
				(type default)
			)
			(layer "B.Fab")
		)
		(fp_line
			(start 0.750062 -1.560068)
			(end -0.750062 -1.560068)
			(stroke
				(width 0.1)
				(type default)
			)
			(layer "B.Fab")
		)
		(pad "D" smd rect
			(at -1.100074 0 180)
			(size 1.016 1.4224)
			(layers "B.Cu" "B.Mask" "B.Paste")
			(net "PVDDCR_SOC_P0_EN_GD")
		)
		(pad "G" smd rect
			(at 1.100074 -0.94996 180)
			(size 1.016 1.4224)
			(layers "B.Cu" "B.Mask" "B.Paste")
			(net "PVDDCR_SOC_P0_EN_RC")
		)
		(pad "S" smd rect
			(at 1.100074 0.94996 180)
			(size 1.016 1.4224)
			(layers "B.Cu" "B.Mask" "B.Paste")
			(net "GND")
		)
	)
	(footprint ""
		(layer "B.Cu")
		(at 109.095794 -385.58216 180)
		(property "Reference" "R918"
			(at 0 0 0)
			(layer "B.SilkS")
			(hide yes)
			(effects
				(font
					(size 1.27 1.27)
				)
				(justify mirror)
			)
		)
		(property "Value" ""
			(at 0 0 0)
			(layer "B.Fab")
			(effects
				(font
					(size 1.27 1.27)
				)
				(justify mirror)
			)
		)
		(duplicate_pad_numbers_are_jumpers no)
		(fp_line
			(start 0.32512 0.175006)
			(end 0.32512 -0.175006)
			(stroke
				(width 0.1)
				(type default)
			)
			(layer "B.Fab")
		)
		(fp_line
			(start 0.32512 -0.175006)
			(end -0.32512 -0.175006)
			(stroke
				(width 0.1)
				(type default)
			)
			(layer "B.Fab")
		)
		(fp_line
			(start -0.32512 0.175006)
			(end 0.32512 0.175006)
			(stroke
				(width 0.1)
				(type default)
			)
			(layer "B.Fab")
		)
		(fp_line
			(start -0.32512 -0.175006)
			(end -0.32512 0.175006)
			(stroke
				(width 0.1)
				(type default)
			)
			(layer "B.Fab")
		)
		(pad "1" smd rect
			(at 0.2667 0)
			(size 0.3048 0.381)
			(layers "B.Cu" "B.Mask" "B.Paste")
			(net "P1V8_CPU1_RT_1D")
		)
		(pad "2" smd rect
			(at -0.2667 0 180)
			(size 0.3048 0.381)
			(layers "B.Cu" "B.Mask" "B.Paste")
			(net "TEST0_RT_CPU1_P3")
		)
	)
	(footprint ""
		(layer "B.Cu")
		(at 68.143374 -177.349912 90)
		(property "Reference" "PC315_5"
			(at 0 0 90)
			(layer "B.SilkS")
			(hide yes)
			(effects
				(font
					(size 1.27 1.27)
				)
				(justify mirror)
			)
		)
		(property "Value" ""
			(at 0 0 90)
			(layer "B.Fab")
			(effects
				(font
					(size 1.27 1.27)
				)
				(justify mirror)
			)
		)
		(duplicate_pad_numbers_are_jumpers no)
		(fp_line
			(start 1.524 -0.762)
			(end -1.524 -0.762)
			(stroke
				(width 0.1524)
				(type default)
			)
			(layer "B.SilkS")
		)
		(fp_line
			(start -1.524 -0.762)
			(end -1.524 0.762)
			(stroke
				(width 0.1524)
				(type default)
			)
			(layer "B.SilkS")
		)
		(fp_line
			(start 1.524 0.762)
			(end 1.524 -0.762)
			(stroke
				(width 0.1524)
				(type default)
			)
			(layer "B.SilkS")
		)
		(fp_line
			(start -1.524 0.762)
			(end 1.524 0.762)
			(stroke
				(width 0.1524)
				(type default)
			)
			(layer "B.SilkS")
		)
		(fp_line
			(start 1.1049 -0.724916)
			(end 1.1049 0.724916)
			(stroke
				(width 0.1)
				(type default)
			)
			(layer "B.Fab")
		)
		(fp_line
			(start -1.1049 -0.724916)
			(end 1.1049 -0.724916)
			(stroke
				(width 0.1)
				(type default)
			)
			(layer "B.Fab")
		)
		(fp_line
			(start 1.1049 0.724916)
			(end -1.1049 0.724916)
			(stroke
				(width 0.1)
				(type default)
			)
			(layer "B.Fab")
		)
		(fp_line
			(start -1.1049 0.724916)
			(end -1.1049 -0.724916)
			(stroke
				(width 0.1)
				(type default)
			)
			(layer "B.Fab")
		)
		(pad "1" smd rect
			(at 0.889 0 90)
			(size 1.016 1.27)
			(layers "B.Cu" "B.Mask" "B.Paste")
			(net "PVDDCR_CPU0_P1")
		)
		(pad "2" smd rect
			(at -0.889 0 90)
			(size 1.016 1.27)
			(layers "B.Cu" "B.Mask" "B.Paste")
			(net "GND")
		)
	)
	(footprint ""
		(layer "B.Cu")
		(at 402.11502 -399.722848 -90)
		(property "Reference" "C970"
			(at 0 0 90)
			(layer "B.SilkS")
			(hide yes)
			(effects
				(font
					(size 1.27 1.27)
				)
				(justify mirror)
			)
		)
		(property "Value" ""
			(at 0 0 90)
			(layer "B.Fab")
			(effects
				(font
					(size 1.27 1.27)
				)
				(justify mirror)
			)
		)
		(duplicate_pad_numbers_are_jumpers no)
		(fp_line
			(start -0.7874 0.4064)
			(end 0.7874 0.4064)
			(stroke
				(width 0.1524)
				(type default)
			)
			(layer "B.SilkS")
		)
		(fp_line
			(start 0.7874 0.4064)
			(end 0.7874 -0.4064)
			(stroke
				(width 0.1524)
				(type default)
			)
			(layer "B.SilkS")
		)
		(fp_line
			(start -0.7874 -0.4064)
			(end -0.7874 0.4064)
			(stroke
				(width 0.1524)
				(type default)
			)
			(layer "B.SilkS")
		)
		(fp_line
			(start 0.7874 -0.4064)
			(end -0.7874 -0.4064)
			(stroke
				(width 0.1524)
				(type default)
			)
			(layer "B.SilkS")
		)
		(fp_line
			(start -0.67945 0.3048)
			(end -0.120396 0.3048)
			(stroke
				(width 0.1)
				(type default)
			)
			(layer "B.Fab")
		)
		(fp_line
			(start -0.120396 0.3048)
			(end -0.120396 0.2794)
			(stroke
				(width 0.1)
				(type default)
			)
			(layer "B.Fab")
		)
		(fp_line
			(start 0.12065 0.3048)
			(end 0.67945 0.3048)
			(stroke
				(width 0.1)
				(type default)
			)
			(layer "B.Fab")
		)
		(fp_line
			(start 0.67945 0.3048)
			(end 0.67945 -0.305054)
			(stroke
				(width 0.1)
				(type default)
			)
			(layer "B.Fab")
		)
		(fp_line
			(start -0.120396 0.2794)
			(end 0.12065 0.2794)
			(stroke
				(width 0.1)
				(type default)
			)
			(layer "B.Fab")
		)
		(fp_line
			(start 0.12065 0.2794)
			(end 0.12065 0.3048)
			(stroke
				(width 0.1)
				(type default)
			)
			(layer "B.Fab")
		)
		(fp_line
			(start -0.12065 -0.2794)
			(end -0.12065 -0.3048)
			(stroke
				(width 0.1)
				(type default)
			)
			(layer "B.Fab")
		)
		(fp_line
			(start 0.12065 -0.2794)
			(end -0.12065 -0.2794)
			(stroke
				(width 0.1)
				(type default)
			)
			(layer "B.Fab")
		)
		(fp_line
			(start -0.67945 -0.3048)
			(end -0.67945 0.3048)
			(stroke
				(width 0.1)
				(type default)
			)
			(layer "B.Fab")
		)
		(fp_line
			(start -0.12065 -0.3048)
			(end -0.67945 -0.3048)
			(stroke
				(width 0.1)
				(type default)
			)
			(layer "B.Fab")
		)
		(fp_line
			(start 0.12065 -0.305054)
			(end 0.12065 -0.2794)
			(stroke
				(width 0.1)
				(type default)
			)
			(layer "B.Fab")
		)
		(fp_line
			(start 0.67945 -0.305054)
			(end 0.12065 -0.305054)
			(stroke
				(width 0.1)
				(type default)
			)
			(layer "B.Fab")
		)
		(pad "1" smd circle
			(at 0.40005 0 90)
			(size 0 0)
			(layers "B.Cu" "B.Mask" "B.Paste")
			(net "P0V9_CPU0_RT2_2A")
		)
		(pad "2" smd circle
			(at -0.40005 0 90)
			(size 0 0)
			(layers "B.Cu" "B.Mask" "B.Paste")
			(net "GND")
		)
	)
	(footprint ""
		(layer "B.Cu")
		(at 346.464636 -157.37586 90)
		(property "Reference" "PC157_6"
			(at 0 0 90)
			(layer "B.SilkS")
			(hide yes)
			(effects
				(font
					(size 1.27 1.27)
				)
				(justify mirror)
			)
		)
		(property "Value" ""
			(at 0 0 90)
			(layer "B.Fab")
			(effects
				(font
					(size 1.27 1.27)
				)
				(justify mirror)
			)
		)
		(duplicate_pad_numbers_are_jumpers no)
		(fp_line
			(start 1.524 -0.762)
			(end -1.524 -0.762)
			(stroke
				(width 0.1524)
				(type default)
			)
			(layer "B.SilkS")
		)
		(fp_line
			(start -1.524 -0.762)
			(end -1.524 0.762)
			(stroke
				(width 0.1524)
				(type default)
			)
			(layer "B.SilkS")
		)
		(fp_line
			(start 1.524 0.762)
			(end 1.524 -0.762)
			(stroke
				(width 0.1524)
				(type default)
			)
			(layer "B.SilkS")
		)
		(fp_line
			(start -1.524 0.762)
			(end 1.524 0.762)
			(stroke
				(width 0.1524)
				(type default)
			)
			(layer "B.SilkS")
		)
		(fp_line
			(start 1.1049 -0.724916)
			(end 1.1049 0.724916)
			(stroke
				(width 0.1)
				(type default)
			)
			(layer "B.Fab")
		)
		(fp_line
			(start -1.1049 -0.724916)
			(end 1.1049 -0.724916)
			(stroke
				(width 0.1)
				(type default)
			)
			(layer "B.Fab")
		)
		(fp_line
			(start 1.1049 0.724916)
			(end -1.1049 0.724916)
			(stroke
				(width 0.1)
				(type default)
			)
			(layer "B.Fab")
		)
		(fp_line
			(start -1.1049 0.724916)
			(end -1.1049 -0.724916)
			(stroke
				(width 0.1)
				(type default)
			)
			(layer "B.Fab")
		)
		(pad "1" smd rect
			(at 0.889 0 90)
			(size 1.016 1.27)
			(layers "B.Cu" "B.Mask" "B.Paste")
			(net "SW_P12V_AUX_PVDDCR_CPU0_P0_FLT")
		)
		(pad "2" smd rect
			(at -0.889 0 90)
			(size 1.016 1.27)
			(layers "B.Cu" "B.Mask" "B.Paste")
			(net "GND")
		)
	)
	(footprint ""
		(layer "B.Cu")
		(at 506.598428 -142.846806 -90)
		(property "Reference" "X8027"
			(at 4.4577 -1.50495 270)
			(unlocked yes)
			(layer "B.SilkS")
			(effects
				(font
					(size 0.7874 0.5842)
					(thickness 0.1524)
				)
				(justify left mirror)
			)
		)
		(property "Value" ""
			(at 0 0 90)
			(layer "B.Fab")
			(effects
				(font
					(size 1.27 1.27)
				)
				(justify mirror)
			)
		)
		(property "Device Type" "TP_TDR_4P_FTS_TH-TP_TDR_4P_DIP,EMPTY,TP15"
			(at -1.30175 1.27 180)
			(unlocked yes)
			(layer "B.Fab")
			(hide yes)
			(effects
				(font
					(size 0.635 0.4064)
					(thickness 0.1524)
				)
				(justify mirror)
			)
		)
		(property "User Part Number" "N_A"
			(at -1.30175 1.27 180)
			(unlocked yes)
			(layer "Cmts.User")
			(hide yes)
			(effects
				(font
					(size 0.635 0.4064)
					(thickness 0.1524)
				)
				(justify mirror)
			)
		)
		(duplicate_pad_numbers_are_jumpers no)
		(fp_line
			(start -2.54 3.81)
			(end -2.54 3.6703)
			(stroke
				(width 0.1524)
				(type default)
			)
			(layer "B.SilkS")
		)
		(fp_line
			(start 0 3.81)
			(end -2.54 3.81)
			(stroke
				(width 0.1524)
				(type default)
			)
			(layer "B.SilkS")
		)
		(fp_line
			(start 0 3.175)
			(end 0 3.81)
			(stroke
				(width 0.1524)
				(type default)
			)
			(layer "B.SilkS")
		)
		(fp_line
			(start -2.54 1.4097)
			(end -2.54 1.1303)
			(stroke
				(width 0.1524)
				(type default)
			)
			(layer "B.SilkS")
		)
		(fp_line
			(start 0 0.635)
			(end 0 1.905)
			(stroke
				(width 0.1524)
				(type default)
			)
			(layer "B.SilkS")
		)
		(fp_line
			(start -2.54 -1.1303)
			(end -2.54 -1.27)
			(stroke
				(width 0.1524)
				(type default)
			)
			(layer "B.SilkS")
		)
		(fp_line
			(start -2.54 -1.27)
			(end 0 -1.27)
			(stroke
				(width 0.1524)
				(type default)
			)
			(layer "B.SilkS")
		)
		(fp_line
			(start 0 -1.27)
			(end 0 -0.635)
			(stroke
				(width 0.1524)
				(type default)
			)
			(layer "B.SilkS")
		)
		(fp_poly
			(pts
				(xy 0.761746 0) (xy 2.285746 -0.762) (xy 2.285746 0.762)
			)
			(stroke
				(width 0)
				(type default)
			)
			(fill yes)
			(layer "B.SilkS")
		)
		(fp_line
			(start -2.54 3.81)
			(end -2.54 -1.27)
			(stroke
				(width 0.1)
				(type default)
			)
			(layer "B.Fab")
		)
		(fp_line
			(start 0 3.81)
			(end -2.54 3.81)
			(stroke
				(width 0.1)
				(type default)
			)
			(layer "B.Fab")
		)
		(fp_line
			(start -2.54 -1.27)
			(end 0 -1.27)
			(stroke
				(width 0.1)
				(type default)
			)
			(layer "B.Fab")
		)
		(fp_line
			(start 0 -1.27)
			(end 0 3.81)
			(stroke
				(width 0.1)
				(type default)
			)
			(layer "B.Fab")
		)
		(fp_poly
			(pts
				(xy 0.761746 0) (xy 2.285746 -0.762) (xy 2.285746 0.762)
			)
			(stroke
				(width 0)
				(type default)
			)
			(fill yes)
			(layer "B.Fab")
		)
		(pad "1" thru_hole circle
			(at 0 0 90)
			(size 1.0033 1.0033)
			(drill 0.249936)
			(layers "*.Cu" "*.Mask")
			(remove_unused_layers no)
			(net "TDR_DIFF_85_IN5_DN")
			(clearance 0.10795)
			(padstack
				(mode front_inner_back)
				(layer "Inner"
					(shape circle)
					(size 0.8001 0.8001)
					(clearance 0.1524)
				)
				(layer "B.Cu"
					(shape circle)
					(size 1.0033 1.0033)
					(thermal_gap 0.10795)
					(clearance 0.10795)
				)
			)
		)
		(pad "2" thru_hole circle
			(at -2.54 0 90)
			(size 1.9939 1.9939)
			(drill 0.249936)
			(layers "*.Cu" "*.Mask")
			(remove_unused_layers no)
			(net "T1_GND")
			(clearance 0.10795)
			(padstack
				(mode front_inner_back)
				(layer "Inner"
					(shape circle)
					(size 0.8001 0.8001)
					(clearance 0.1524)
				)
				(layer "B.Cu"
					(shape circle)
					(size 1.9939 1.9939)
					(thermal_gap 0.10795)
					(clearance 0.10795)
				)
			)
		)
		(pad "3" thru_hole circle
			(at -2.54 2.54 90)
			(size 1.9939 1.9939)
			(drill 0.249936)
			(layers "*.Cu" "*.Mask")
			(remove_unused_layers no)
			(net "T1_GND")
			(clearance 0.10795)
			(padstack
				(mode front_inner_back)
				(layer "Inner"
					(shape circle)
					(size 0.8001 0.8001)
					(clearance 0.1524)
				)
				(layer "B.Cu"
					(shape circle)
					(size 1.9939 1.9939)
					(thermal_gap 0.10795)
					(clearance 0.10795)
				)
			)
		)
		(pad "4" thru_hole circle
			(at 0 2.54 90)
			(size 1.0033 1.0033)
			(drill 0.249936)
			(layers "*.Cu" "*.Mask")
			(remove_unused_layers no)
			(net "TDR_DIFF_85_IN5_DP")
			(clearance 0.10795)
			(padstack
				(mode front_inner_back)
				(layer "Inner"
					(shape circle)
					(size 0.8001 0.8001)
					(clearance 0.1524)
				)
				(layer "B.Cu"
					(shape circle)
					(size 1.0033 1.0033)
					(thermal_gap 0.10795)
					(clearance 0.10795)
				)
			)
		)
	)
	(footprint ""
		(layer "B.Cu")
		(at 426.757338 -332.627732 90)
		(property "Reference" "PR414"
			(at 0 0 90)
			(layer "B.SilkS")
			(hide yes)
			(effects
				(font
					(size 1.27 1.27)
				)
				(justify mirror)
			)
		)
		(property "Value" ""
			(at 0 0 90)
			(layer "B.Fab")
			(effects
				(font
					(size 1.27 1.27)
				)
				(justify mirror)
			)
		)
		(duplicate_pad_numbers_are_jumpers no)
		(fp_line
			(start 0.7874 -0.4064)
			(end -0.7874 -0.4064)
			(stroke
				(width 0.1524)
				(type default)
			)
			(layer "B.SilkS")
		)
		(fp_line
			(start -0.7874 -0.4064)
			(end -0.7874 0.4064)
			(stroke
				(width 0.1524)
				(type default)
			)
			(layer "B.SilkS")
		)
		(fp_line
			(start 0.7874 0.4064)
			(end 0.7874 -0.4064)
			(stroke
				(width 0.1524)
				(type default)
			)
			(layer "B.SilkS")
		)
		(fp_line
			(start -0.7874 0.4064)
			(end 0.7874 0.4064)
			(stroke
				(width 0.1524)
				(type default)
			)
			(layer "B.SilkS")
		)
		(fp_line
			(start 0.67945 -0.305054)
			(end 0.12065 -0.305054)
			(stroke
				(width 0.1)
				(type default)
			)
			(layer "B.Fab")
		)
		(fp_line
			(start 0.12065 -0.305054)
			(end 0.12065 -0.2794)
			(stroke
				(width 0.1)
				(type default)
			)
			(layer "B.Fab")
		)
		(fp_line
			(start -0.12065 -0.3048)
			(end -0.67945 -0.3048)
			(stroke
				(width 0.1)
				(type default)
			)
			(layer "B.Fab")
		)
		(fp_line
			(start -0.67945 -0.3048)
			(end -0.67945 0.3048)
			(stroke
				(width 0.1)
				(type default)
			)
			(layer "B.Fab")
		)
		(fp_line
			(start 0.12065 -0.2794)
			(end -0.12065 -0.2794)
			(stroke
				(width 0.1)
				(type default)
			)
			(layer "B.Fab")
		)
		(fp_line
			(start -0.12065 -0.2794)
			(end -0.12065 -0.3048)
			(stroke
				(width 0.1)
				(type default)
			)
			(layer "B.Fab")
		)
		(fp_line
			(start 0.12065 0.2794)
			(end 0.12065 0.3048)
			(stroke
				(width 0.1)
				(type default)
			)
			(layer "B.Fab")
		)
		(fp_line
			(start -0.120396 0.2794)
			(end 0.12065 0.2794)
			(stroke
				(width 0.1)
				(type default)
			)
			(layer "B.Fab")
		)
		(fp_line
			(start 0.67945 0.3048)
			(end 0.67945 -0.305054)
			(stroke
				(width 0.1)
				(type default)
			)
			(layer "B.Fab")
		)
		(fp_line
			(start 0.12065 0.3048)
			(end 0.67945 0.3048)
			(stroke
				(width 0.1)
				(type default)
			)
			(layer "B.Fab")
		)
		(fp_line
			(start -0.120396 0.3048)
			(end -0.120396 0.2794)
			(stroke
				(width 0.1)
				(type default)
			)
			(layer "B.Fab")
		)
		(fp_line
			(start -0.67945 0.3048)
			(end -0.120396 0.3048)
			(stroke
				(width 0.1)
				(type default)
			)
			(layer "B.Fab")
		)
		(pad "1" smd circle
			(at 0.40005 0 270)
			(size 0 0)
			(layers "B.Cu" "B.Mask" "B.Paste")
			(net "PVDD11_S3_P0")
		)
		(pad "2" smd circle
			(at -0.40005 0 270)
			(size 0 0)
			(layers "B.Cu" "B.Mask" "B.Paste")
			(net "GND")
		)
	)
	(footprint ""
		(layer "B.Cu")
		(at 79.886302 -335.060798 90)
		(property "Reference" "PC382_2"
			(at 0 0 90)
			(layer "B.SilkS")
			(hide yes)
			(effects
				(font
					(size 1.27 1.27)
				)
				(justify mirror)
			)
		)
		(property "Value" ""
			(at 0 0 90)
			(layer "B.Fab")
			(effects
				(font
					(size 1.27 1.27)
				)
				(justify mirror)
			)
		)
		(duplicate_pad_numbers_are_jumpers no)
		(fp_line
			(start 1.524 -0.762)
			(end -1.524 -0.762)
			(stroke
				(width 0.1524)
				(type default)
			)
			(layer "B.SilkS")
		)
		(fp_line
			(start -1.524 -0.762)
			(end -1.524 0.762)
			(stroke
				(width 0.1524)
				(type default)
			)
			(layer "B.SilkS")
		)
		(fp_line
			(start 1.524 0.762)
			(end 1.524 -0.762)
			(stroke
				(width 0.1524)
				(type default)
			)
			(layer "B.SilkS")
		)
		(fp_line
			(start -1.524 0.762)
			(end 1.524 0.762)
			(stroke
				(width 0.1524)
				(type default)
			)
			(layer "B.SilkS")
		)
		(fp_line
			(start 1.1049 -0.724916)
			(end 1.1049 0.724916)
			(stroke
				(width 0.1)
				(type default)
			)
			(layer "B.Fab")
		)
		(fp_line
			(start -1.1049 -0.724916)
			(end 1.1049 -0.724916)
			(stroke
				(width 0.1)
				(type default)
			)
			(layer "B.Fab")
		)
		(fp_line
			(start 1.1049 0.724916)
			(end -1.1049 0.724916)
			(stroke
				(width 0.1)
				(type default)
			)
			(layer "B.Fab")
		)
		(fp_line
			(start -1.1049 0.724916)
			(end -1.1049 -0.724916)
			(stroke
				(width 0.1)
				(type default)
			)
			(layer "B.Fab")
		)
		(pad "1" smd rect
			(at 0.889 0 90)
			(size 1.016 1.27)
			(layers "B.Cu" "B.Mask" "B.Paste")
			(net "SW_P12V_AUX_PVDDCR_CPU1_P1_FLT")
		)
		(pad "2" smd rect
			(at -0.889 0 90)
			(size 1.016 1.27)
			(layers "B.Cu" "B.Mask" "B.Paste")
			(net "GND")
		)
	)
	(footprint ""
		(layer "B.Cu")
		(at 339.148928 -312.053986)
		(property "Reference" "PR60"
			(at 0 0 0)
			(layer "B.SilkS")
			(hide yes)
			(effects
				(font
					(size 1.27 1.27)
				)
				(justify mirror)
			)
		)
		(property "Value" ""
			(at 0 0 0)
			(layer "B.Fab")
			(effects
				(font
					(size 1.27 1.27)
				)
				(justify mirror)
			)
		)
		(duplicate_pad_numbers_are_jumpers no)
		(fp_line
			(start -0.7874 -0.4064)
			(end -0.7874 0.4064)
			(stroke
				(width 0.1524)
				(type default)
			)
			(layer "B.SilkS")
		)
		(fp_line
			(start -0.7874 0.4064)
			(end 0.7874 0.4064)
			(stroke
				(width 0.1524)
				(type default)
			)
			(layer "B.SilkS")
		)
		(fp_line
			(start 0.7874 -0.4064)
			(end -0.7874 -0.4064)
			(stroke
				(width 0.1524)
				(type default)
			)
			(layer "B.SilkS")
		)
		(fp_line
			(start 0.7874 0.4064)
			(end 0.7874 -0.4064)
			(stroke
				(width 0.1524)
				(type default)
			)
			(layer "B.SilkS")
		)
		(fp_line
			(start -0.67945 -0.3048)
			(end -0.67945 0.3048)
			(stroke
				(width 0.1)
				(type default)
			)
			(layer "B.Fab")
		)
		(fp_line
			(start -0.67945 0.3048)
			(end -0.120396 0.3048)
			(stroke
				(width 0.1)
				(type default)
			)
			(layer "B.Fab")
		)
		(fp_line
			(start -0.12065 -0.3048)
			(end -0.67945 -0.3048)
			(stroke
				(width 0.1)
				(type default)
			)
			(layer "B.Fab")
		)
		(fp_line
			(start -0.12065 -0.2794)
			(end -0.12065 -0.3048)
			(stroke
				(width 0.1)
				(type default)
			)
			(layer "B.Fab")
		)
		(fp_line
			(start -0.120396 0.2794)
			(end 0.12065 0.2794)
			(stroke
				(width 0.1)
				(type default)
			)
			(layer "B.Fab")
		)
		(fp_line
			(start -0.120396 0.3048)
			(end -0.120396 0.2794)
			(stroke
				(width 0.1)
				(type default)
			)
			(layer "B.Fab")
		)
		(fp_line
			(start 0.12065 -0.305054)
			(end 0.12065 -0.2794)
			(stroke
				(width 0.1)
				(type default)
			)
			(layer "B.Fab")
		)
		(fp_line
			(start 0.12065 -0.2794)
			(end -0.12065 -0.2794)
			(stroke
				(width 0.1)
				(type default)
			)
			(layer "B.Fab")
		)
		(fp_line
			(start 0.12065 0.2794)
			(end 0.12065 0.3048)
			(stroke
				(width 0.1)
				(type default)
			)
			(layer "B.Fab")
		)
		(fp_line
			(start 0.12065 0.3048)
			(end 0.67945 0.3048)
			(stroke
				(width 0.1)
				(type default)
			)
			(layer "B.Fab")
		)
		(fp_line
			(start 0.67945 -0.305054)
			(end 0.12065 -0.305054)
			(stroke
				(width 0.1)
				(type default)
			)
			(layer "B.Fab")
		)
		(fp_line
			(start 0.67945 0.3048)
			(end 0.67945 -0.305054)
			(stroke
				(width 0.1)
				(type default)
			)
			(layer "B.Fab")
		)
		(pad "1" smd circle
			(at 0.40005 0 180)
			(size 0 0)
			(layers "B.Cu" "B.Mask" "B.Paste")
			(net "SVID_PVDDCR_CPU1_P0_SVD_R")
		)
		(pad "2" smd circle
			(at -0.40005 0 180)
			(size 0 0)
			(layers "B.Cu" "B.Mask" "B.Paste")
			(net "SVID_PVDDCR_CPU1_P0_SVD")
		)
	)
	(footprint ""
		(layer "B.Cu")
		(at 361.54106 -186.225942 90)
		(property "Reference" "PC499_2"
			(at 0 0 90)
			(layer "B.SilkS")
			(hide yes)
			(effects
				(font
					(size 1.27 1.27)
				)
				(justify mirror)
			)
		)
		(property "Value" ""
			(at 0 0 90)
			(layer "B.Fab")
			(effects
				(font
					(size 1.27 1.27)
				)
				(justify mirror)
			)
		)
		(duplicate_pad_numbers_are_jumpers no)
		(fp_line
			(start 1.524 -0.762)
			(end -1.524 -0.762)
			(stroke
				(width 0.1524)
				(type default)
			)
			(layer "B.SilkS")
		)
		(fp_line
			(start -1.524 -0.762)
			(end -1.524 0.762)
			(stroke
				(width 0.1524)
				(type default)
			)
			(layer "B.SilkS")
		)
		(fp_line
			(start 1.524 0.762)
			(end 1.524 -0.762)
			(stroke
				(width 0.1524)
				(type default)
			)
			(layer "B.SilkS")
		)
		(fp_line
			(start -1.524 0.762)
			(end 1.524 0.762)
			(stroke
				(width 0.1524)
				(type default)
			)
			(layer "B.SilkS")
		)
		(fp_line
			(start 1.1049 -0.724916)
			(end 1.1049 0.724916)
			(stroke
				(width 0.1)
				(type default)
			)
			(layer "B.Fab")
		)
		(fp_line
			(start -1.1049 -0.724916)
			(end 1.1049 -0.724916)
			(stroke
				(width 0.1)
				(type default)
			)
			(layer "B.Fab")
		)
		(fp_line
			(start 1.1049 0.724916)
			(end -1.1049 0.724916)
			(stroke
				(width 0.1)
				(type default)
			)
			(layer "B.Fab")
		)
		(fp_line
			(start -1.1049 0.724916)
			(end -1.1049 -0.724916)
			(stroke
				(width 0.1)
				(type default)
			)
			(layer "B.Fab")
		)
		(pad "1" smd rect
			(at 0.889 0 90)
			(size 1.016 1.27)
			(layers "B.Cu" "B.Mask" "B.Paste")
			(net "PVDDCR_CPU0_P0")
		)
		(pad "2" smd rect
			(at -0.889 0 90)
			(size 1.016 1.27)
			(layers "B.Cu" "B.Mask" "B.Paste")
			(net "GND")
		)
	)
	(footprint ""
		(layer "B.Cu")
		(at 167.531034 -244.085364)
		(property "Reference" "R506"
			(at 0 0 0)
			(layer "B.SilkS")
			(hide yes)
			(effects
				(font
					(size 1.27 1.27)
				)
				(justify mirror)
			)
		)
		(property "Value" ""
			(at 0 0 0)
			(layer "B.Fab")
			(effects
				(font
					(size 1.27 1.27)
				)
				(justify mirror)
			)
		)
		(duplicate_pad_numbers_are_jumpers no)
		(fp_line
			(start -0.7874 -0.4064)
			(end -0.7874 0.4064)
			(stroke
				(width 0.1524)
				(type default)
			)
			(layer "B.SilkS")
		)
		(fp_line
			(start -0.7874 0.4064)
			(end 0.7874 0.4064)
			(stroke
				(width 0.1524)
				(type default)
			)
			(layer "B.SilkS")
		)
		(fp_line
			(start 0.7874 -0.4064)
			(end -0.7874 -0.4064)
			(stroke
				(width 0.1524)
				(type default)
			)
			(layer "B.SilkS")
		)
		(fp_line
			(start 0.7874 0.4064)
			(end 0.7874 -0.4064)
			(stroke
				(width 0.1524)
				(type default)
			)
			(layer "B.SilkS")
		)
		(fp_line
			(start -0.67945 -0.3048)
			(end -0.67945 0.3048)
			(stroke
				(width 0.1)
				(type default)
			)
			(layer "B.Fab")
		)
		(fp_line
			(start -0.67945 0.3048)
			(end -0.120396 0.3048)
			(stroke
				(width 0.1)
				(type default)
			)
			(layer "B.Fab")
		)
		(fp_line
			(start -0.12065 -0.3048)
			(end -0.67945 -0.3048)
			(stroke
				(width 0.1)
				(type default)
			)
			(layer "B.Fab")
		)
		(fp_line
			(start -0.12065 -0.2794)
			(end -0.12065 -0.3048)
			(stroke
				(width 0.1)
				(type default)
			)
			(layer "B.Fab")
		)
		(fp_line
			(start -0.120396 0.2794)
			(end 0.12065 0.2794)
			(stroke
				(width 0.1)
				(type default)
			)
			(layer "B.Fab")
		)
		(fp_line
			(start -0.120396 0.3048)
			(end -0.120396 0.2794)
			(stroke
				(width 0.1)
				(type default)
			)
			(layer "B.Fab")
		)
		(fp_line
			(start 0.12065 -0.305054)
			(end 0.12065 -0.2794)
			(stroke
				(width 0.1)
				(type default)
			)
			(layer "B.Fab")
		)
		(fp_line
			(start 0.12065 -0.2794)
			(end -0.12065 -0.2794)
			(stroke
				(width 0.1)
				(type default)
			)
			(layer "B.Fab")
		)
		(fp_line
			(start 0.12065 0.2794)
			(end 0.12065 0.3048)
			(stroke
				(width 0.1)
				(type default)
			)
			(layer "B.Fab")
		)
		(fp_line
			(start 0.12065 0.3048)
			(end 0.67945 0.3048)
			(stroke
				(width 0.1)
				(type default)
			)
			(layer "B.Fab")
		)
		(fp_line
			(start 0.67945 -0.305054)
			(end 0.12065 -0.305054)
			(stroke
				(width 0.1)
				(type default)
			)
			(layer "B.Fab")
		)
		(fp_line
			(start 0.67945 0.3048)
			(end 0.67945 -0.305054)
			(stroke
				(width 0.1)
				(type default)
			)
			(layer "B.Fab")
		)
		(pad "1" smd circle
			(at 0.40005 0 180)
			(size 0 0)
			(layers "B.Cu" "B.Mask" "B.Paste")
			(net "M_G_CPU1_ALERT_N")
		)
		(pad "2" smd circle
			(at -0.40005 0 180)
			(size 0 0)
			(layers "B.Cu" "B.Mask" "B.Paste")
			(net "M_G_CPU1_ALERT_R_N")
		)
	)
	(footprint ""
		(layer "B.Cu")
		(at 448.38874 -397.05407 90)
		(property "Reference" "PC6557_1"
			(at 0 0 90)
			(layer "B.SilkS")
			(hide yes)
			(effects
				(font
					(size 1.27 1.27)
				)
				(justify mirror)
			)
		)
		(property "Value" ""
			(at 0 0 90)
			(layer "B.Fab")
			(effects
				(font
					(size 1.27 1.27)
				)
				(justify mirror)
			)
		)
		(duplicate_pad_numbers_are_jumpers no)
		(fp_line
			(start 1.524 -0.762)
			(end -1.524 -0.762)
			(stroke
				(width 0.1524)
				(type default)
			)
			(layer "B.SilkS")
		)
		(fp_line
			(start -1.524 -0.762)
			(end -1.524 0.762)
			(stroke
				(width 0.1524)
				(type default)
			)
			(layer "B.SilkS")
		)
		(fp_line
			(start 1.524 0.762)
			(end 1.524 -0.762)
			(stroke
				(width 0.1524)
				(type default)
			)
			(layer "B.SilkS")
		)
		(fp_line
			(start -1.524 0.762)
			(end 1.524 0.762)
			(stroke
				(width 0.1524)
				(type default)
			)
			(layer "B.SilkS")
		)
		(fp_line
			(start 1.1049 -0.724916)
			(end 1.1049 0.724916)
			(stroke
				(width 0.1)
				(type default)
			)
			(layer "B.Fab")
		)
		(fp_line
			(start -1.1049 -0.724916)
			(end 1.1049 -0.724916)
			(stroke
				(width 0.1)
				(type default)
			)
			(layer "B.Fab")
		)
		(fp_line
			(start 1.1049 0.724916)
			(end -1.1049 0.724916)
			(stroke
				(width 0.1)
				(type default)
			)
			(layer "B.Fab")
		)
		(fp_line
			(start -1.1049 0.724916)
			(end -1.1049 -0.724916)
			(stroke
				(width 0.1)
				(type default)
			)
			(layer "B.Fab")
		)
		(pad "1" smd rect
			(at 0.889 0 90)
			(size 1.016 1.27)
			(layers "B.Cu" "B.Mask" "B.Paste")
			(net "SW_P12V_AUX_P0V9_RETIMER_CPU0_FLT")
		)
		(pad "2" smd rect
			(at -0.889 0 90)
			(size 1.016 1.27)
			(layers "B.Cu" "B.Mask" "B.Paste")
			(net "GND")
		)
	)
	(footprint ""
		(layer "B.Cu")
		(at 415.712402 -194.88531 180)
		(property "Reference" "R1574"
			(at 0 0 0)
			(layer "B.SilkS")
			(hide yes)
			(effects
				(font
					(size 1.27 1.27)
				)
				(justify mirror)
			)
		)
		(property "Value" ""
			(at 0 0 0)
			(layer "B.Fab")
			(effects
				(font
					(size 1.27 1.27)
				)
				(justify mirror)
			)
		)
		(duplicate_pad_numbers_are_jumpers no)
		(fp_line
			(start 0.7874 0.4064)
			(end 0.7874 -0.4064)
			(stroke
				(width 0.1524)
				(type default)
			)
			(layer "B.SilkS")
		)
		(fp_line
			(start 0.7874 -0.4064)
			(end -0.7874 -0.4064)
			(stroke
				(width 0.1524)
				(type default)
			)
			(layer "B.SilkS")
		)
		(fp_line
			(start -0.7874 0.4064)
			(end 0.7874 0.4064)
			(stroke
				(width 0.1524)
				(type default)
			)
			(layer "B.SilkS")
		)
		(fp_line
			(start -0.7874 -0.4064)
			(end -0.7874 0.4064)
			(stroke
				(width 0.1524)
				(type default)
			)
			(layer "B.SilkS")
		)
		(fp_line
			(start 0.67945 0.3048)
			(end 0.67945 -0.305054)
			(stroke
				(width 0.1)
				(type default)
			)
			(layer "B.Fab")
		)
		(fp_line
			(start 0.67945 -0.305054)
			(end 0.12065 -0.305054)
			(stroke
				(width 0.1)
				(type default)
			)
			(layer "B.Fab")
		)
		(fp_line
			(start 0.12065 0.3048)
			(end 0.67945 0.3048)
			(stroke
				(width 0.1)
				(type default)
			)
			(layer "B.Fab")
		)
		(fp_line
			(start 0.12065 0.2794)
			(end 0.12065 0.3048)
			(stroke
				(width 0.1)
				(type default)
			)
			(layer "B.Fab")
		)
		(fp_line
			(start 0.12065 -0.2794)
			(end -0.12065 -0.2794)
			(stroke
				(width 0.1)
				(type default)
			)
			(layer "B.Fab")
		)
		(fp_line
			(start 0.12065 -0.305054)
			(end 0.12065 -0.2794)
			(stroke
				(width 0.1)
				(type default)
			)
			(layer "B.Fab")
		)
		(fp_line
			(start -0.120396 0.3048)
			(end -0.120396 0.2794)
			(stroke
				(width 0.1)
				(type default)
			)
			(layer "B.Fab")
		)
		(fp_line
			(start -0.120396 0.2794)
			(end 0.12065 0.2794)
			(stroke
				(width 0.1)
				(type default)
			)
			(layer "B.Fab")
		)
		(fp_line
			(start -0.12065 -0.2794)
			(end -0.12065 -0.3048)
			(stroke
				(width 0.1)
				(type default)
			)
			(layer "B.Fab")
		)
		(fp_line
			(start -0.12065 -0.3048)
			(end -0.67945 -0.3048)
			(stroke
				(width 0.1)
				(type default)
			)
			(layer "B.Fab")
		)
		(fp_line
			(start -0.67945 0.3048)
			(end -0.120396 0.3048)
			(stroke
				(width 0.1)
				(type default)
			)
			(layer "B.Fab")
		)
		(fp_line
			(start -0.67945 -0.3048)
			(end -0.67945 0.3048)
			(stroke
				(width 0.1)
				(type default)
			)
			(layer "B.Fab")
		)
		(pad "1" smd circle
			(at 0.40005 0)
			(size 0 0)
			(layers "B.Cu" "B.Mask" "B.Paste")
			(net "I3C_SPD_DDRGL_CPU0_SCL")
		)
		(pad "2" smd circle
			(at -0.40005 0)
			(size 0 0)
			(layers "B.Cu" "B.Mask" "B.Paste")
			(net "I3C_SPD_DDRG_CPU0_SCL")
		)
	)
	(footprint ""
		(layer "B.Cu")
		(at 430.80051 -194.88531 180)
		(property "Reference" "R1576"
			(at 0 0 0)
			(layer "B.SilkS")
			(hide yes)
			(effects
				(font
					(size 1.27 1.27)
				)
				(justify mirror)
			)
		)
		(property "Value" ""
			(at 0 0 0)
			(layer "B.Fab")
			(effects
				(font
					(size 1.27 1.27)
				)
				(justify mirror)
			)
		)
		(duplicate_pad_numbers_are_jumpers no)
		(fp_line
			(start 0.7874 0.4064)
			(end 0.7874 -0.4064)
			(stroke
				(width 0.1524)
				(type default)
			)
			(layer "B.SilkS")
		)
		(fp_line
			(start 0.7874 -0.4064)
			(end -0.7874 -0.4064)
			(stroke
				(width 0.1524)
				(type default)
			)
			(layer "B.SilkS")
		)
		(fp_line
			(start -0.7874 0.4064)
			(end 0.7874 0.4064)
			(stroke
				(width 0.1524)
				(type default)
			)
			(layer "B.SilkS")
		)
		(fp_line
			(start -0.7874 -0.4064)
			(end -0.7874 0.4064)
			(stroke
				(width 0.1524)
				(type default)
			)
			(layer "B.SilkS")
		)
		(fp_line
			(start 0.67945 0.3048)
			(end 0.67945 -0.305054)
			(stroke
				(width 0.1)
				(type default)
			)
			(layer "B.Fab")
		)
		(fp_line
			(start 0.67945 -0.305054)
			(end 0.12065 -0.305054)
			(stroke
				(width 0.1)
				(type default)
			)
			(layer "B.Fab")
		)
		(fp_line
			(start 0.12065 0.3048)
			(end 0.67945 0.3048)
			(stroke
				(width 0.1)
				(type default)
			)
			(layer "B.Fab")
		)
		(fp_line
			(start 0.12065 0.2794)
			(end 0.12065 0.3048)
			(stroke
				(width 0.1)
				(type default)
			)
			(layer "B.Fab")
		)
		(fp_line
			(start 0.12065 -0.2794)
			(end -0.12065 -0.2794)
			(stroke
				(width 0.1)
				(type default)
			)
			(layer "B.Fab")
		)
		(fp_line
			(start 0.12065 -0.305054)
			(end 0.12065 -0.2794)
			(stroke
				(width 0.1)
				(type default)
			)
			(layer "B.Fab")
		)
		(fp_line
			(start -0.120396 0.3048)
			(end -0.120396 0.2794)
			(stroke
				(width 0.1)
				(type default)
			)
			(layer "B.Fab")
		)
		(fp_line
			(start -0.120396 0.2794)
			(end 0.12065 0.2794)
			(stroke
				(width 0.1)
				(type default)
			)
			(layer "B.Fab")
		)
		(fp_line
			(start -0.12065 -0.2794)
			(end -0.12065 -0.3048)
			(stroke
				(width 0.1)
				(type default)
			)
			(layer "B.Fab")
		)
		(fp_line
			(start -0.12065 -0.3048)
			(end -0.67945 -0.3048)
			(stroke
				(width 0.1)
				(type default)
			)
			(layer "B.Fab")
		)
		(fp_line
			(start -0.67945 0.3048)
			(end -0.120396 0.3048)
			(stroke
				(width 0.1)
				(type default)
			)
			(layer "B.Fab")
		)
		(fp_line
			(start -0.67945 -0.3048)
			(end -0.67945 0.3048)
			(stroke
				(width 0.1)
				(type default)
			)
			(layer "B.Fab")
		)
		(pad "1" smd circle
			(at 0.40005 0)
			(size 0 0)
			(layers "B.Cu" "B.Mask" "B.Paste")
			(net "I3C_SPD_DDRGL_CPU0_SCL")
		)
		(pad "2" smd circle
			(at -0.40005 0)
			(size 0 0)
			(layers "B.Cu" "B.Mask" "B.Paste")
			(net "I3C_SPD_DDRI_CPU0_SCL")
		)
	)
	(footprint ""
		(layer "B.Cu")
		(at 188.071506 -126.833376 -90)
		(property "Reference" "R1558"
			(at 0 0 90)
			(layer "B.SilkS")
			(hide yes)
			(effects
				(font
					(size 1.27 1.27)
				)
				(justify mirror)
			)
		)
		(property "Value" ""
			(at 0 0 90)
			(layer "B.Fab")
			(effects
				(font
					(size 1.27 1.27)
				)
				(justify mirror)
			)
		)
		(duplicate_pad_numbers_are_jumpers no)
		(fp_line
			(start -0.7874 0.4064)
			(end 0.7874 0.4064)
			(stroke
				(width 0.1524)
				(type default)
			)
			(layer "B.SilkS")
		)
		(fp_line
			(start 0.7874 0.4064)
			(end 0.7874 -0.4064)
			(stroke
				(width 0.1524)
				(type default)
			)
			(layer "B.SilkS")
		)
		(fp_line
			(start -0.7874 -0.4064)
			(end -0.7874 0.4064)
			(stroke
				(width 0.1524)
				(type default)
			)
			(layer "B.SilkS")
		)
		(fp_line
			(start 0.7874 -0.4064)
			(end -0.7874 -0.4064)
			(stroke
				(width 0.1524)
				(type default)
			)
			(layer "B.SilkS")
		)
		(fp_line
			(start -0.67945 0.3048)
			(end -0.120396 0.3048)
			(stroke
				(width 0.1)
				(type default)
			)
			(layer "B.Fab")
		)
		(fp_line
			(start -0.120396 0.3048)
			(end -0.120396 0.2794)
			(stroke
				(width 0.1)
				(type default)
			)
			(layer "B.Fab")
		)
		(fp_line
			(start 0.12065 0.3048)
			(end 0.67945 0.3048)
			(stroke
				(width 0.1)
				(type default)
			)
			(layer "B.Fab")
		)
		(fp_line
			(start 0.67945 0.3048)
			(end 0.67945 -0.305054)
			(stroke
				(width 0.1)
				(type default)
			)
			(layer "B.Fab")
		)
		(fp_line
			(start -0.120396 0.2794)
			(end 0.12065 0.2794)
			(stroke
				(width 0.1)
				(type default)
			)
			(layer "B.Fab")
		)
		(fp_line
			(start 0.12065 0.2794)
			(end 0.12065 0.3048)
			(stroke
				(width 0.1)
				(type default)
			)
			(layer "B.Fab")
		)
		(fp_line
			(start -0.12065 -0.2794)
			(end -0.12065 -0.3048)
			(stroke
				(width 0.1)
				(type default)
			)
			(layer "B.Fab")
		)
		(fp_line
			(start 0.12065 -0.2794)
			(end -0.12065 -0.2794)
			(stroke
				(width 0.1)
				(type default)
			)
			(layer "B.Fab")
		)
		(fp_line
			(start -0.67945 -0.3048)
			(end -0.67945 0.3048)
			(stroke
				(width 0.1)
				(type default)
			)
			(layer "B.Fab")
		)
		(fp_line
			(start -0.12065 -0.3048)
			(end -0.67945 -0.3048)
			(stroke
				(width 0.1)
				(type default)
			)
			(layer "B.Fab")
		)
		(fp_line
			(start 0.12065 -0.305054)
			(end 0.12065 -0.2794)
			(stroke
				(width 0.1)
				(type default)
			)
			(layer "B.Fab")
		)
		(fp_line
			(start 0.67945 -0.305054)
			(end 0.12065 -0.305054)
			(stroke
				(width 0.1)
				(type default)
			)
			(layer "B.Fab")
		)
		(pad "1" smd circle
			(at 0.40005 0 90)
			(size 0 0)
			(layers "B.Cu" "B.Mask" "B.Paste")
			(net "RST_ESPI_CPU0_RSTOUT_R_N")
		)
		(pad "2" smd circle
			(at -0.40005 0 90)
			(size 0 0)
			(layers "B.Cu" "B.Mask" "B.Paste")
			(net "RST_ESPI_CPU0_RSTOUT_N")
		)
	)
	(footprint ""
		(layer "B.Cu")
		(at 288.935668 -193.99631)
		(property "Reference" "R91"
			(at 0 0 0)
			(layer "B.SilkS")
			(hide yes)
			(effects
				(font
					(size 1.27 1.27)
				)
				(justify mirror)
			)
		)
		(property "Value" ""
			(at 0 0 0)
			(layer "B.Fab")
			(effects
				(font
					(size 1.27 1.27)
				)
				(justify mirror)
			)
		)
		(duplicate_pad_numbers_are_jumpers no)
		(fp_line
			(start -0.7874 -0.4064)
			(end -0.7874 0.4064)
			(stroke
				(width 0.1524)
				(type default)
			)
			(layer "B.SilkS")
		)
		(fp_line
			(start -0.7874 0.4064)
			(end 0.7874 0.4064)
			(stroke
				(width 0.1524)
				(type default)
			)
			(layer "B.SilkS")
		)
		(fp_line
			(start 0.7874 -0.4064)
			(end -0.7874 -0.4064)
			(stroke
				(width 0.1524)
				(type default)
			)
			(layer "B.SilkS")
		)
		(fp_line
			(start 0.7874 0.4064)
			(end 0.7874 -0.4064)
			(stroke
				(width 0.1524)
				(type default)
			)
			(layer "B.SilkS")
		)
		(fp_line
			(start -0.67945 -0.3048)
			(end -0.67945 0.3048)
			(stroke
				(width 0.1)
				(type default)
			)
			(layer "B.Fab")
		)
		(fp_line
			(start -0.67945 0.3048)
			(end -0.120396 0.3048)
			(stroke
				(width 0.1)
				(type default)
			)
			(layer "B.Fab")
		)
		(fp_line
			(start -0.12065 -0.3048)
			(end -0.67945 -0.3048)
			(stroke
				(width 0.1)
				(type default)
			)
			(layer "B.Fab")
		)
		(fp_line
			(start -0.12065 -0.2794)
			(end -0.12065 -0.3048)
			(stroke
				(width 0.1)
				(type default)
			)
			(layer "B.Fab")
		)
		(fp_line
			(start -0.120396 0.2794)
			(end 0.12065 0.2794)
			(stroke
				(width 0.1)
				(type default)
			)
			(layer "B.Fab")
		)
		(fp_line
			(start -0.120396 0.3048)
			(end -0.120396 0.2794)
			(stroke
				(width 0.1)
				(type default)
			)
			(layer "B.Fab")
		)
		(fp_line
			(start 0.12065 -0.305054)
			(end 0.12065 -0.2794)
			(stroke
				(width 0.1)
				(type default)
			)
			(layer "B.Fab")
		)
		(fp_line
			(start 0.12065 -0.2794)
			(end -0.12065 -0.2794)
			(stroke
				(width 0.1)
				(type default)
			)
			(layer "B.Fab")
		)
		(fp_line
			(start 0.12065 0.2794)
			(end 0.12065 0.3048)
			(stroke
				(width 0.1)
				(type default)
			)
			(layer "B.Fab")
		)
		(fp_line
			(start 0.12065 0.3048)
			(end 0.67945 0.3048)
			(stroke
				(width 0.1)
				(type default)
			)
			(layer "B.Fab")
		)
		(fp_line
			(start 0.67945 -0.305054)
			(end 0.12065 -0.305054)
			(stroke
				(width 0.1)
				(type default)
			)
			(layer "B.Fab")
		)
		(fp_line
			(start 0.67945 0.3048)
			(end 0.67945 -0.305054)
			(stroke
				(width 0.1)
				(type default)
			)
			(layer "B.Fab")
		)
		(pad "1" smd circle
			(at 0.40005 0 180)
			(size 0 0)
			(layers "B.Cu" "B.Mask" "B.Paste")
			(net "P3V3")
		)
		(pad "2" smd circle
			(at -0.40005 0 180)
			(size 0 0)
			(layers "B.Cu" "B.Mask" "B.Paste")
			(net "PWRGD_CHC_CPU0_DIMM")
		)
	)
	(footprint ""
		(layer "B.Cu")
		(at 376.722386 -214.523828 90)
		(property "Reference" "R8565"
			(at 0 0 90)
			(layer "B.SilkS")
			(hide yes)
			(effects
				(font
					(size 1.27 1.27)
				)
				(justify mirror)
			)
		)
		(property "Value" ""
			(at 0 0 90)
			(layer "B.Fab")
			(effects
				(font
					(size 1.27 1.27)
				)
				(justify mirror)
			)
		)
		(duplicate_pad_numbers_are_jumpers no)
		(fp_line
			(start 0.385572 -0.4064)
			(end -0.351028 -0.4064)
			(stroke
				(width 0.1524)
				(type default)
			)
			(layer "B.SilkS")
		)
		(fp_line
			(start -0.7874 0.086614)
			(end -0.7874 0.4064)
			(stroke
				(width 0.1524)
				(type default)
			)
			(layer "B.SilkS")
		)
		(fp_line
			(start 0.7874 0.4064)
			(end 0.7874 -0.014986)
			(stroke
				(width 0.1524)
				(type default)
			)
			(layer "B.SilkS")
		)
		(fp_line
			(start -0.7874 0.4064)
			(end 0.7874 0.4064)
			(stroke
				(width 0.1524)
				(type default)
			)
			(layer "B.SilkS")
		)
		(fp_line
			(start 0.67945 -0.305054)
			(end 0.12065 -0.305054)
			(stroke
				(width 0.1)
				(type default)
			)
			(layer "B.Fab")
		)
		(fp_line
			(start 0.12065 -0.305054)
			(end 0.12065 -0.2794)
			(stroke
				(width 0.1)
				(type default)
			)
			(layer "B.Fab")
		)
		(fp_line
			(start -0.12065 -0.3048)
			(end -0.67945 -0.3048)
			(stroke
				(width 0.1)
				(type default)
			)
			(layer "B.Fab")
		)
		(fp_line
			(start -0.67945 -0.3048)
			(end -0.67945 0.3048)
			(stroke
				(width 0.1)
				(type default)
			)
			(layer "B.Fab")
		)
		(fp_line
			(start 0.12065 -0.2794)
			(end -0.12065 -0.2794)
			(stroke
				(width 0.1)
				(type default)
			)
			(layer "B.Fab")
		)
		(fp_line
			(start -0.12065 -0.2794)
			(end -0.12065 -0.3048)
			(stroke
				(width 0.1)
				(type default)
			)
			(layer "B.Fab")
		)
		(fp_line
			(start 0.12065 0.2794)
			(end 0.12065 0.3048)
			(stroke
				(width 0.1)
				(type default)
			)
			(layer "B.Fab")
		)
		(fp_line
			(start -0.120396 0.2794)
			(end 0.12065 0.2794)
			(stroke
				(width 0.1)
				(type default)
			)
			(layer "B.Fab")
		)
		(fp_line
			(start 0.67945 0.3048)
			(end 0.67945 -0.305054)
			(stroke
				(width 0.1)
				(type default)
			)
			(layer "B.Fab")
		)
		(fp_line
			(start 0.12065 0.3048)
			(end 0.67945 0.3048)
			(stroke
				(width 0.1)
				(type default)
			)
			(layer "B.Fab")
		)
		(fp_line
			(start -0.120396 0.3048)
			(end -0.120396 0.2794)
			(stroke
				(width 0.1)
				(type default)
			)
			(layer "B.Fab")
		)
		(fp_line
			(start -0.67945 0.3048)
			(end -0.120396 0.3048)
			(stroke
				(width 0.1)
				(type default)
			)
			(layer "B.Fab")
		)
		(pad "1" smd circle
			(at 0.40005 0 270)
			(size 0 0)
			(layers "B.Cu" "B.Mask" "B.Paste")
			(net "CLK_100M_CPU0_CLK03_R_DP")
		)
		(pad "2" smd circle
			(at -0.40005 0 270)
			(size 0 0)
			(layers "B.Cu" "B.Mask" "B.Paste")
			(net "CLK_100M_CPU0_CLK03_DP")
		)
	)
	(footprint ""
		(layer "B.Cu")
		(at 414.085786 -151.33701 90)
		(property "Reference" "PC1855"
			(at 0 0 90)
			(layer "B.SilkS")
			(hide yes)
			(effects
				(font
					(size 1.27 1.27)
				)
				(justify mirror)
			)
		)
		(property "Value" ""
			(at 0 0 90)
			(layer "B.Fab")
			(effects
				(font
					(size 1.27 1.27)
				)
				(justify mirror)
			)
		)
		(duplicate_pad_numbers_are_jumpers no)
		(fp_line
			(start 1.524 -0.762)
			(end -1.524 -0.762)
			(stroke
				(width 0.1524)
				(type default)
			)
			(layer "B.SilkS")
		)
		(fp_line
			(start -1.524 -0.762)
			(end -1.524 0.762)
			(stroke
				(width 0.1524)
				(type default)
			)
			(layer "B.SilkS")
		)
		(fp_line
			(start 1.524 0.762)
			(end 1.524 -0.762)
			(stroke
				(width 0.1524)
				(type default)
			)
			(layer "B.SilkS")
		)
		(fp_line
			(start -1.524 0.762)
			(end 1.524 0.762)
			(stroke
				(width 0.1524)
				(type default)
			)
			(layer "B.SilkS")
		)
		(fp_line
			(start 1.1049 -0.724916)
			(end 1.1049 0.724916)
			(stroke
				(width 0.1)
				(type default)
			)
			(layer "B.Fab")
		)
		(fp_line
			(start -1.1049 -0.724916)
			(end 1.1049 -0.724916)
			(stroke
				(width 0.1)
				(type default)
			)
			(layer "B.Fab")
		)
		(fp_line
			(start 1.1049 0.724916)
			(end -1.1049 0.724916)
			(stroke
				(width 0.1)
				(type default)
			)
			(layer "B.Fab")
		)
		(fp_line
			(start -1.1049 0.724916)
			(end -1.1049 -0.724916)
			(stroke
				(width 0.1)
				(type default)
			)
			(layer "B.Fab")
		)
		(pad "1" smd rect
			(at 0.889 0 90)
			(size 1.016 1.27)
			(layers "B.Cu" "B.Mask" "B.Paste")
			(net "P5V_AUX")
		)
		(pad "2" smd rect
			(at -0.889 0 90)
			(size 1.016 1.27)
			(layers "B.Cu" "B.Mask" "B.Paste")
			(net "GND")
		)
	)
	(footprint ""
		(layer "B.Cu")
		(at 131.418584 -388.011162 -90)
		(property "Reference" "C462"
			(at 0 0 90)
			(layer "B.SilkS")
			(hide yes)
			(effects
				(font
					(size 1.27 1.27)
				)
				(justify mirror)
			)
		)
		(property "Value" ""
			(at 0 0 90)
			(layer "B.Fab")
			(effects
				(font
					(size 1.27 1.27)
				)
				(justify mirror)
			)
		)
		(duplicate_pad_numbers_are_jumpers no)
		(fp_line
			(start -0.299974 0.150114)
			(end 0.299974 0.150114)
			(stroke
				(width 0.1)
				(type default)
			)
			(layer "B.Fab")
		)
		(fp_line
			(start 0.299974 0.150114)
			(end 0.299974 -0.150114)
			(stroke
				(width 0.1)
				(type default)
			)
			(layer "B.Fab")
		)
		(fp_line
			(start -0.299974 -0.150114)
			(end -0.299974 0.150114)
			(stroke
				(width 0.1)
				(type default)
			)
			(layer "B.Fab")
		)
		(fp_line
			(start 0.299974 -0.150114)
			(end -0.299974 -0.150114)
			(stroke
				(width 0.1)
				(type default)
			)
			(layer "B.Fab")
		)
		(pad "1" smd rect
			(at 0.2667 0 90)
			(size 0.3048 0.381)
			(layers "B.Cu" "B.Mask" "B.Paste")
			(net "P0V9_CPU1_RT3_2A")
		)
		(pad "2" smd rect
			(at -0.2667 0 90)
			(size 0.3048 0.381)
			(layers "B.Cu" "B.Mask" "B.Paste")
			(net "GND")
		)
	)
	(footprint ""
		(layer "B.Cu")
		(at 411.576266 -139.42949 90)
		(property "Reference" "R2356"
			(at 0 0 90)
			(layer "B.SilkS")
			(hide yes)
			(effects
				(font
					(size 1.27 1.27)
				)
				(justify mirror)
			)
		)
		(property "Value" ""
			(at 0 0 90)
			(layer "B.Fab")
			(effects
				(font
					(size 1.27 1.27)
				)
				(justify mirror)
			)
		)
		(duplicate_pad_numbers_are_jumpers no)
		(fp_line
			(start 0.7874 -0.4064)
			(end -0.7874 -0.4064)
			(stroke
				(width 0.1524)
				(type default)
			)
			(layer "B.SilkS")
		)
		(fp_line
			(start -0.7874 -0.4064)
			(end -0.7874 0.4064)
			(stroke
				(width 0.1524)
				(type default)
			)
			(layer "B.SilkS")
		)
		(fp_line
			(start 0.7874 0.4064)
			(end 0.7874 -0.4064)
			(stroke
				(width 0.1524)
				(type default)
			)
			(layer "B.SilkS")
		)
		(fp_line
			(start -0.7874 0.4064)
			(end 0.7874 0.4064)
			(stroke
				(width 0.1524)
				(type default)
			)
			(layer "B.SilkS")
		)
		(fp_line
			(start 0.67945 -0.305054)
			(end 0.12065 -0.305054)
			(stroke
				(width 0.1)
				(type default)
			)
			(layer "B.Fab")
		)
		(fp_line
			(start 0.12065 -0.305054)
			(end 0.12065 -0.2794)
			(stroke
				(width 0.1)
				(type default)
			)
			(layer "B.Fab")
		)
		(fp_line
			(start -0.12065 -0.3048)
			(end -0.67945 -0.3048)
			(stroke
				(width 0.1)
				(type default)
			)
			(layer "B.Fab")
		)
		(fp_line
			(start -0.67945 -0.3048)
			(end -0.67945 0.3048)
			(stroke
				(width 0.1)
				(type default)
			)
			(layer "B.Fab")
		)
		(fp_line
			(start 0.12065 -0.2794)
			(end -0.12065 -0.2794)
			(stroke
				(width 0.1)
				(type default)
			)
			(layer "B.Fab")
		)
		(fp_line
			(start -0.12065 -0.2794)
			(end -0.12065 -0.3048)
			(stroke
				(width 0.1)
				(type default)
			)
			(layer "B.Fab")
		)
		(fp_line
			(start 0.12065 0.2794)
			(end 0.12065 0.3048)
			(stroke
				(width 0.1)
				(type default)
			)
			(layer "B.Fab")
		)
		(fp_line
			(start -0.120396 0.2794)
			(end 0.12065 0.2794)
			(stroke
				(width 0.1)
				(type default)
			)
			(layer "B.Fab")
		)
		(fp_line
			(start 0.67945 0.3048)
			(end 0.67945 -0.305054)
			(stroke
				(width 0.1)
				(type default)
			)
			(layer "B.Fab")
		)
		(fp_line
			(start 0.12065 0.3048)
			(end 0.67945 0.3048)
			(stroke
				(width 0.1)
				(type default)
			)
			(layer "B.Fab")
		)
		(fp_line
			(start -0.120396 0.3048)
			(end -0.120396 0.2794)
			(stroke
				(width 0.1)
				(type default)
			)
			(layer "B.Fab")
		)
		(fp_line
			(start -0.67945 0.3048)
			(end -0.120396 0.3048)
			(stroke
				(width 0.1)
				(type default)
			)
			(layer "B.Fab")
		)
		(pad "1" smd circle
			(at 0.40005 0 270)
			(size 0 0)
			(layers "B.Cu" "B.Mask" "B.Paste")
			(net "P5V_AUX_VCC")
		)
		(pad "2" smd circle
			(at -0.40005 0 270)
			(size 0 0)
			(layers "B.Cu" "B.Mask" "B.Paste")
			(net "PWRGD_P5V_AUX_R")
		)
	)
	(footprint ""
		(layer "B.Cu")
		(at 85.024976 -381.11303 180)
		(property "Reference" "C7024"
			(at -1.773428 -2.989072 0)
			(unlocked yes)
			(layer "B.SilkS")
			(effects
				(font
					(size 0.7874 0.5842)
					(thickness 0.1524)
				)
				(justify left mirror)
			)
		)
		(property "Value" ""
			(at 0 0 0)
			(layer "B.Fab")
			(effects
				(font
					(size 1.27 1.27)
				)
				(justify mirror)
			)
		)
		(duplicate_pad_numbers_are_jumpers no)
		(fp_line
			(start 4.84378 -2.150618)
			(end 4.842256 2.163064)
			(stroke
				(width 0.1524)
				(type default)
			)
			(layer "B.SilkS")
		)
		(fp_line
			(start 4.84378 -2.150618)
			(end 4.53898 -2.150618)
			(stroke
				(width 0.1524)
				(type default)
			)
			(layer "B.SilkS")
		)
		(fp_line
			(start 4.83108 2.150364)
			(end 4.447794 2.149348)
			(stroke
				(width 0.1524)
				(type default)
			)
			(layer "B.SilkS")
		)
		(fp_line
			(start 4.69138 -2.150618)
			(end 4.692396 2.161032)
			(stroke
				(width 0.1524)
				(type default)
			)
			(layer "B.SilkS")
		)
		(fp_line
			(start 4.53898 2.15011)
			(end 4.53898 -2.15011)
			(stroke
				(width 0.1524)
				(type default)
			)
			(layer "B.SilkS")
		)
		(fp_line
			(start 4.53898 -2.15011)
			(end -4.53898 -2.15011)
			(stroke
				(width 0.1524)
				(type default)
			)
			(layer "B.SilkS")
		)
		(fp_line
			(start 4.53898 -2.150618)
			(end 4.539742 2.152142)
			(stroke
				(width 0.1524)
				(type default)
			)
			(layer "B.SilkS")
		)
		(fp_line
			(start -4.53898 2.15011)
			(end 4.53898 2.15011)
			(stroke
				(width 0.1524)
				(type default)
			)
			(layer "B.SilkS")
		)
		(fp_line
			(start -4.53898 -2.15011)
			(end -4.53898 2.15011)
			(stroke
				(width 0.1524)
				(type default)
			)
			(layer "B.SilkS")
		)
		(fp_line
			(start 3.64998 2.15011)
			(end 3.64998 -2.15011)
			(stroke
				(width 0.1)
				(type default)
			)
			(layer "B.Fab")
		)
		(fp_line
			(start 3.64998 -2.15011)
			(end -3.64998 -2.15011)
			(stroke
				(width 0.1)
				(type default)
			)
			(layer "B.Fab")
		)
		(fp_line
			(start -3.64998 2.15011)
			(end 3.64998 2.15011)
			(stroke
				(width 0.1)
				(type default)
			)
			(layer "B.Fab")
		)
		(fp_line
			(start -3.64998 -2.15011)
			(end -3.64998 2.15011)
			(stroke
				(width 0.1)
				(type default)
			)
			(layer "B.Fab")
		)
		(fp_text user "+"
			(at 4.256532 -3.098038 180)
			(unlocked yes)
			(layer "B.SilkS")
			(effects
				(font
					(size 1.905 1.4224)
					(thickness 0.1524)
				)
				(justify left mirror)
			)
		)
		(fp_text user "-"
			(at -2.946654 -2.901188 180)
			(unlocked yes)
			(layer "B.SilkS")
			(effects
				(font
					(size 1.905 1.4224)
					(thickness 0.1524)
				)
				(justify left mirror)
			)
		)
		(fp_text user "+"
			(at 6.214872 -0.337058 180)
			(unlocked yes)
			(layer "B.Fab")
			(effects
				(font
					(size 1.905 1.4224)
					(thickness 0.1524)
				)
				(justify left mirror)
			)
		)
		(fp_text user "-"
			(at -4.313174 -0.094488 180)
			(unlocked yes)
			(layer "B.Fab")
			(effects
				(font
					(size 1.905 1.4224)
					(thickness 0.1524)
				)
				(justify left mirror)
			)
		)
		(pad "1" smd rect
			(at 3.199892 0)
			(size 2.413 2.8194)
			(layers "B.Cu" "B.Mask" "B.Paste")
			(net "P0V9_CPU1_RT1_2A")
		)
		(pad "2" smd rect
			(at -3.199892 0)
			(size 2.413 2.8194)
			(layers "B.Cu" "B.Mask" "B.Paste")
			(net "GND")
		)
	)
	(footprint ""
		(layer "B.Cu")
		(at 429.659796 -352.199448 -90)
		(property "Reference" "PR132"
			(at 0 0 90)
			(layer "B.SilkS")
			(hide yes)
			(effects
				(font
					(size 1.27 1.27)
				)
				(justify mirror)
			)
		)
		(property "Value" ""
			(at 0 0 90)
			(layer "B.Fab")
			(effects
				(font
					(size 1.27 1.27)
				)
				(justify mirror)
			)
		)
		(duplicate_pad_numbers_are_jumpers no)
		(fp_line
			(start -0.7874 0.4064)
			(end 0.7874 0.4064)
			(stroke
				(width 0.1524)
				(type default)
			)
			(layer "B.SilkS")
		)
		(fp_line
			(start 0.7874 0.4064)
			(end 0.7874 -0.4064)
			(stroke
				(width 0.1524)
				(type default)
			)
			(layer "B.SilkS")
		)
		(fp_line
			(start -0.7874 -0.4064)
			(end -0.7874 0.4064)
			(stroke
				(width 0.1524)
				(type default)
			)
			(layer "B.SilkS")
		)
		(fp_line
			(start 0.7874 -0.4064)
			(end -0.7874 -0.4064)
			(stroke
				(width 0.1524)
				(type default)
			)
			(layer "B.SilkS")
		)
		(fp_line
			(start -0.67945 0.3048)
			(end -0.120396 0.3048)
			(stroke
				(width 0.1)
				(type default)
			)
			(layer "B.Fab")
		)
		(fp_line
			(start -0.120396 0.3048)
			(end -0.120396 0.2794)
			(stroke
				(width 0.1)
				(type default)
			)
			(layer "B.Fab")
		)
		(fp_line
			(start 0.12065 0.3048)
			(end 0.67945 0.3048)
			(stroke
				(width 0.1)
				(type default)
			)
			(layer "B.Fab")
		)
		(fp_line
			(start 0.67945 0.3048)
			(end 0.67945 -0.305054)
			(stroke
				(width 0.1)
				(type default)
			)
			(layer "B.Fab")
		)
		(fp_line
			(start -0.120396 0.2794)
			(end 0.12065 0.2794)
			(stroke
				(width 0.1)
				(type default)
			)
			(layer "B.Fab")
		)
		(fp_line
			(start 0.12065 0.2794)
			(end 0.12065 0.3048)
			(stroke
				(width 0.1)
				(type default)
			)
			(layer "B.Fab")
		)
		(fp_line
			(start -0.12065 -0.2794)
			(end -0.12065 -0.3048)
			(stroke
				(width 0.1)
				(type default)
			)
			(layer "B.Fab")
		)
		(fp_line
			(start 0.12065 -0.2794)
			(end -0.12065 -0.2794)
			(stroke
				(width 0.1)
				(type default)
			)
			(layer "B.Fab")
		)
		(fp_line
			(start -0.67945 -0.3048)
			(end -0.67945 0.3048)
			(stroke
				(width 0.1)
				(type default)
			)
			(layer "B.Fab")
		)
		(fp_line
			(start -0.12065 -0.3048)
			(end -0.67945 -0.3048)
			(stroke
				(width 0.1)
				(type default)
			)
			(layer "B.Fab")
		)
		(fp_line
			(start 0.12065 -0.305054)
			(end 0.12065 -0.2794)
			(stroke
				(width 0.1)
				(type default)
			)
			(layer "B.Fab")
		)
		(fp_line
			(start 0.67945 -0.305054)
			(end 0.12065 -0.305054)
			(stroke
				(width 0.1)
				(type default)
			)
			(layer "B.Fab")
		)
		(pad "1" smd circle
			(at 0.40005 0 90)
			(size 0 0)
			(layers "B.Cu" "B.Mask" "B.Paste")
			(net "PVDD11_S3_P0_PVCC")
		)
		(pad "2" smd circle
			(at -0.40005 0 90)
			(size 0 0)
			(layers "B.Cu" "B.Mask" "B.Paste")
			(net "PVDD11_S3_P0_VCC2")
		)
	)
	(footprint ""
		(layer "B.Cu")
		(at 115.130834 -246.376952 180)
		(property "Reference" "C2324"
			(at 0 0 0)
			(layer "B.SilkS")
			(hide yes)
			(effects
				(font
					(size 1.27 1.27)
				)
				(justify mirror)
			)
		)
		(property "Value" ""
			(at 0 0 0)
			(layer "B.Fab")
			(effects
				(font
					(size 1.27 1.27)
				)
				(justify mirror)
			)
		)
		(duplicate_pad_numbers_are_jumpers no)
		(fp_line
			(start 0.7874 0.4064)
			(end 0.7874 -0.4064)
			(stroke
				(width 0.1524)
				(type default)
			)
			(layer "B.SilkS")
		)
		(fp_line
			(start 0.7874 -0.4064)
			(end -0.7874 -0.4064)
			(stroke
				(width 0.1524)
				(type default)
			)
			(layer "B.SilkS")
		)
		(fp_line
			(start -0.7874 0.4064)
			(end 0.7874 0.4064)
			(stroke
				(width 0.1524)
				(type default)
			)
			(layer "B.SilkS")
		)
		(fp_line
			(start -0.7874 -0.4064)
			(end -0.7874 0.4064)
			(stroke
				(width 0.1524)
				(type default)
			)
			(layer "B.SilkS")
		)
		(fp_line
			(start 0.67945 0.3048)
			(end 0.67945 -0.305054)
			(stroke
				(width 0.1)
				(type default)
			)
			(layer "B.Fab")
		)
		(fp_line
			(start 0.67945 -0.305054)
			(end 0.12065 -0.305054)
			(stroke
				(width 0.1)
				(type default)
			)
			(layer "B.Fab")
		)
		(fp_line
			(start 0.12065 0.3048)
			(end 0.67945 0.3048)
			(stroke
				(width 0.1)
				(type default)
			)
			(layer "B.Fab")
		)
		(fp_line
			(start 0.12065 0.2794)
			(end 0.12065 0.3048)
			(stroke
				(width 0.1)
				(type default)
			)
			(layer "B.Fab")
		)
		(fp_line
			(start 0.12065 -0.2794)
			(end -0.12065 -0.2794)
			(stroke
				(width 0.1)
				(type default)
			)
			(layer "B.Fab")
		)
		(fp_line
			(start 0.12065 -0.305054)
			(end 0.12065 -0.2794)
			(stroke
				(width 0.1)
				(type default)
			)
			(layer "B.Fab")
		)
		(fp_line
			(start -0.120396 0.3048)
			(end -0.120396 0.2794)
			(stroke
				(width 0.1)
				(type default)
			)
			(layer "B.Fab")
		)
		(fp_line
			(start -0.120396 0.2794)
			(end 0.12065 0.2794)
			(stroke
				(width 0.1)
				(type default)
			)
			(layer "B.Fab")
		)
		(fp_line
			(start -0.12065 -0.2794)
			(end -0.12065 -0.3048)
			(stroke
				(width 0.1)
				(type default)
			)
			(layer "B.Fab")
		)
		(fp_line
			(start -0.12065 -0.3048)
			(end -0.67945 -0.3048)
			(stroke
				(width 0.1)
				(type default)
			)
			(layer "B.Fab")
		)
		(fp_line
			(start -0.67945 0.3048)
			(end -0.120396 0.3048)
			(stroke
				(width 0.1)
				(type default)
			)
			(layer "B.Fab")
		)
		(fp_line
			(start -0.67945 -0.3048)
			(end -0.67945 0.3048)
			(stroke
				(width 0.1)
				(type default)
			)
			(layer "B.Fab")
		)
		(pad "1" smd circle
			(at 0.40005 0)
			(size 0 0)
			(layers "B.Cu" "B.Mask" "B.Paste")
			(net "PVDDCR_CPU0_P1")
		)
		(pad "2" smd circle
			(at -0.40005 0)
			(size 0 0)
			(layers "B.Cu" "B.Mask" "B.Paste")
			(net "GND")
		)
	)
	(footprint ""
		(layer "B.Cu")
		(at 399.034508 -330.090272)
		(property "Reference" "R474"
			(at 0 0 0)
			(layer "B.SilkS")
			(hide yes)
			(effects
				(font
					(size 1.27 1.27)
				)
				(justify mirror)
			)
		)
		(property "Value" ""
			(at 0 0 0)
			(layer "B.Fab")
			(effects
				(font
					(size 1.27 1.27)
				)
				(justify mirror)
			)
		)
		(duplicate_pad_numbers_are_jumpers no)
		(fp_line
			(start -0.7874 -0.4064)
			(end -0.7874 0.4064)
			(stroke
				(width 0.1524)
				(type default)
			)
			(layer "B.SilkS")
		)
		(fp_line
			(start -0.7874 0.4064)
			(end 0.7874 0.4064)
			(stroke
				(width 0.1524)
				(type default)
			)
			(layer "B.SilkS")
		)
		(fp_line
			(start 0.7874 -0.4064)
			(end -0.7874 -0.4064)
			(stroke
				(width 0.1524)
				(type default)
			)
			(layer "B.SilkS")
		)
		(fp_line
			(start 0.7874 0.4064)
			(end 0.7874 -0.4064)
			(stroke
				(width 0.1524)
				(type default)
			)
			(layer "B.SilkS")
		)
		(fp_line
			(start -0.67945 -0.3048)
			(end -0.67945 0.3048)
			(stroke
				(width 0.1)
				(type default)
			)
			(layer "B.Fab")
		)
		(fp_line
			(start -0.67945 0.3048)
			(end -0.120396 0.3048)
			(stroke
				(width 0.1)
				(type default)
			)
			(layer "B.Fab")
		)
		(fp_line
			(start -0.12065 -0.3048)
			(end -0.67945 -0.3048)
			(stroke
				(width 0.1)
				(type default)
			)
			(layer "B.Fab")
		)
		(fp_line
			(start -0.12065 -0.2794)
			(end -0.12065 -0.3048)
			(stroke
				(width 0.1)
				(type default)
			)
			(layer "B.Fab")
		)
		(fp_line
			(start -0.120396 0.2794)
			(end 0.12065 0.2794)
			(stroke
				(width 0.1)
				(type default)
			)
			(layer "B.Fab")
		)
		(fp_line
			(start -0.120396 0.3048)
			(end -0.120396 0.2794)
			(stroke
				(width 0.1)
				(type default)
			)
			(layer "B.Fab")
		)
		(fp_line
			(start 0.12065 -0.305054)
			(end 0.12065 -0.2794)
			(stroke
				(width 0.1)
				(type default)
			)
			(layer "B.Fab")
		)
		(fp_line
			(start 0.12065 -0.2794)
			(end -0.12065 -0.2794)
			(stroke
				(width 0.1)
				(type default)
			)
			(layer "B.Fab")
		)
		(fp_line
			(start 0.12065 0.2794)
			(end 0.12065 0.3048)
			(stroke
				(width 0.1)
				(type default)
			)
			(layer "B.Fab")
		)
		(fp_line
			(start 0.12065 0.3048)
			(end 0.67945 0.3048)
			(stroke
				(width 0.1)
				(type default)
			)
			(layer "B.Fab")
		)
		(fp_line
			(start 0.67945 -0.305054)
			(end 0.12065 -0.305054)
			(stroke
				(width 0.1)
				(type default)
			)
			(layer "B.Fab")
		)
		(fp_line
			(start 0.67945 0.3048)
			(end 0.67945 -0.305054)
			(stroke
				(width 0.1)
				(type default)
			)
			(layer "B.Fab")
		)
		(pad "1" smd circle
			(at 0.40005 0 180)
			(size 0 0)
			(layers "B.Cu" "B.Mask" "B.Paste")
			(net "RST_ESPI_CPU0_RSTOUT_N")
		)
		(pad "2" smd circle
			(at -0.40005 0 180)
			(size 0 0)
			(layers "B.Cu" "B.Mask" "B.Paste")
			(net "RST_ESPI_CPU0_R_RSTOUT_N")
		)
	)
	(footprint ""
		(layer "B.Cu")
		(at 115.818412 -388.011162 -90)
		(property "Reference" "C457"
			(at 0 0 90)
			(layer "B.SilkS")
			(hide yes)
			(effects
				(font
					(size 1.27 1.27)
				)
				(justify mirror)
			)
		)
		(property "Value" ""
			(at 0 0 90)
			(layer "B.Fab")
			(effects
				(font
					(size 1.27 1.27)
				)
				(justify mirror)
			)
		)
		(duplicate_pad_numbers_are_jumpers no)
		(fp_line
			(start -0.299974 0.150114)
			(end 0.299974 0.150114)
			(stroke
				(width 0.1)
				(type default)
			)
			(layer "B.Fab")
		)
		(fp_line
			(start 0.299974 0.150114)
			(end 0.299974 -0.150114)
			(stroke
				(width 0.1)
				(type default)
			)
			(layer "B.Fab")
		)
		(fp_line
			(start -0.299974 -0.150114)
			(end -0.299974 0.150114)
			(stroke
				(width 0.1)
				(type default)
			)
			(layer "B.Fab")
		)
		(fp_line
			(start 0.299974 -0.150114)
			(end -0.299974 -0.150114)
			(stroke
				(width 0.1)
				(type default)
			)
			(layer "B.Fab")
		)
		(pad "1" smd rect
			(at 0.2667 0 90)
			(size 0.3048 0.381)
			(layers "B.Cu" "B.Mask" "B.Paste")
			(net "P0V9_CPU1_RT3_2A")
		)
		(pad "2" smd rect
			(at -0.2667 0 90)
			(size 0.3048 0.381)
			(layers "B.Cu" "B.Mask" "B.Paste")
			(net "GND")
		)
	)
	(footprint ""
		(layer "B.Cu")
		(at 321.595496 -335.063084 90)
		(property "Reference" "PC124_3"
			(at 0 0 90)
			(layer "B.SilkS")
			(hide yes)
			(effects
				(font
					(size 1.27 1.27)
				)
				(justify mirror)
			)
		)
		(property "Value" ""
			(at 0 0 90)
			(layer "B.Fab")
			(effects
				(font
					(size 1.27 1.27)
				)
				(justify mirror)
			)
		)
		(duplicate_pad_numbers_are_jumpers no)
		(fp_line
			(start 1.524 -0.762)
			(end -1.524 -0.762)
			(stroke
				(width 0.1524)
				(type default)
			)
			(layer "B.SilkS")
		)
		(fp_line
			(start -1.524 -0.762)
			(end -1.524 0.762)
			(stroke
				(width 0.1524)
				(type default)
			)
			(layer "B.SilkS")
		)
		(fp_line
			(start 1.524 0.762)
			(end 1.524 -0.762)
			(stroke
				(width 0.1524)
				(type default)
			)
			(layer "B.SilkS")
		)
		(fp_line
			(start -1.524 0.762)
			(end 1.524 0.762)
			(stroke
				(width 0.1524)
				(type default)
			)
			(layer "B.SilkS")
		)
		(fp_line
			(start 1.1049 -0.724916)
			(end 1.1049 0.724916)
			(stroke
				(width 0.1)
				(type default)
			)
			(layer "B.Fab")
		)
		(fp_line
			(start -1.1049 -0.724916)
			(end 1.1049 -0.724916)
			(stroke
				(width 0.1)
				(type default)
			)
			(layer "B.Fab")
		)
		(fp_line
			(start 1.1049 0.724916)
			(end -1.1049 0.724916)
			(stroke
				(width 0.1)
				(type default)
			)
			(layer "B.Fab")
		)
		(fp_line
			(start -1.1049 0.724916)
			(end -1.1049 -0.724916)
			(stroke
				(width 0.1)
				(type default)
			)
			(layer "B.Fab")
		)
		(pad "1" smd rect
			(at 0.889 0 90)
			(size 1.016 1.27)
			(layers "B.Cu" "B.Mask" "B.Paste")
			(net "SW_P12V_AUX_PVDDCR_CPU1_P0_FLT")
		)
		(pad "2" smd rect
			(at -0.889 0 90)
			(size 1.016 1.27)
			(layers "B.Cu" "B.Mask" "B.Paste")
			(net "GND")
		)
	)
	(footprint ""
		(layer "B.Cu")
		(at 370.905278 -145.536158)
		(property "Reference" "C302"
			(at 0 0 0)
			(layer "B.SilkS")
			(hide yes)
			(effects
				(font
					(size 1.27 1.27)
				)
				(justify mirror)
			)
		)
		(property "Value" ""
			(at 0 0 0)
			(layer "B.Fab")
			(effects
				(font
					(size 1.27 1.27)
				)
				(justify mirror)
			)
		)
		(duplicate_pad_numbers_are_jumpers no)
		(fp_line
			(start -0.7874 -0.4064)
			(end -0.7874 0.4064)
			(stroke
				(width 0.1524)
				(type default)
			)
			(layer "B.SilkS")
		)
		(fp_line
			(start -0.7874 0.4064)
			(end 0.7874 0.4064)
			(stroke
				(width 0.1524)
				(type default)
			)
			(layer "B.SilkS")
		)
		(fp_line
			(start 0.7874 -0.4064)
			(end -0.7874 -0.4064)
			(stroke
				(width 0.1524)
				(type default)
			)
			(layer "B.SilkS")
		)
		(fp_line
			(start 0.7874 0.4064)
			(end 0.7874 -0.4064)
			(stroke
				(width 0.1524)
				(type default)
			)
			(layer "B.SilkS")
		)
		(fp_line
			(start -0.67945 -0.3048)
			(end -0.67945 0.3048)
			(stroke
				(width 0.1)
				(type default)
			)
			(layer "B.Fab")
		)
		(fp_line
			(start -0.67945 0.3048)
			(end -0.120396 0.3048)
			(stroke
				(width 0.1)
				(type default)
			)
			(layer "B.Fab")
		)
		(fp_line
			(start -0.12065 -0.3048)
			(end -0.67945 -0.3048)
			(stroke
				(width 0.1)
				(type default)
			)
			(layer "B.Fab")
		)
		(fp_line
			(start -0.12065 -0.2794)
			(end -0.12065 -0.3048)
			(stroke
				(width 0.1)
				(type default)
			)
			(layer "B.Fab")
		)
		(fp_line
			(start -0.120396 0.2794)
			(end 0.12065 0.2794)
			(stroke
				(width 0.1)
				(type default)
			)
			(layer "B.Fab")
		)
		(fp_line
			(start -0.120396 0.3048)
			(end -0.120396 0.2794)
			(stroke
				(width 0.1)
				(type default)
			)
			(layer "B.Fab")
		)
		(fp_line
			(start 0.12065 -0.305054)
			(end 0.12065 -0.2794)
			(stroke
				(width 0.1)
				(type default)
			)
			(layer "B.Fab")
		)
		(fp_line
			(start 0.12065 -0.2794)
			(end -0.12065 -0.2794)
			(stroke
				(width 0.1)
				(type default)
			)
			(layer "B.Fab")
		)
		(fp_line
			(start 0.12065 0.2794)
			(end 0.12065 0.3048)
			(stroke
				(width 0.1)
				(type default)
			)
			(layer "B.Fab")
		)
		(fp_line
			(start 0.12065 0.3048)
			(end 0.67945 0.3048)
			(stroke
				(width 0.1)
				(type default)
			)
			(layer "B.Fab")
		)
		(fp_line
			(start 0.67945 -0.305054)
			(end 0.12065 -0.305054)
			(stroke
				(width 0.1)
				(type default)
			)
			(layer "B.Fab")
		)
		(fp_line
			(start 0.67945 0.3048)
			(end 0.67945 -0.305054)
			(stroke
				(width 0.1)
				(type default)
			)
			(layer "B.Fab")
		)
		(pad "1" smd circle
			(at 0.40005 0 180)
			(size 0 0)
			(layers "B.Cu" "B.Mask" "B.Paste")
			(net "SVID_PVDDCR_CPU0_P0_SVC_R")
		)
		(pad "2" smd circle
			(at -0.40005 0 180)
			(size 0 0)
			(layers "B.Cu" "B.Mask" "B.Paste")
			(net "GND")
		)
	)
	(footprint ""
		(layer "B.Cu")
		(at 82.306414 -386.766562 90)
		(property "Reference" "C337"
			(at 0 0 90)
			(layer "B.SilkS")
			(hide yes)
			(effects
				(font
					(size 1.27 1.27)
				)
				(justify mirror)
			)
		)
		(property "Value" ""
			(at 0 0 90)
			(layer "B.Fab")
			(effects
				(font
					(size 1.27 1.27)
				)
				(justify mirror)
			)
		)
		(duplicate_pad_numbers_are_jumpers no)
		(fp_line
			(start 0.299974 -0.150114)
			(end -0.299974 -0.150114)
			(stroke
				(width 0.1)
				(type default)
			)
			(layer "B.Fab")
		)
		(fp_line
			(start -0.299974 -0.150114)
			(end -0.299974 0.150114)
			(stroke
				(width 0.1)
				(type default)
			)
			(layer "B.Fab")
		)
		(fp_line
			(start 0.299974 0.150114)
			(end 0.299974 -0.150114)
			(stroke
				(width 0.1)
				(type default)
			)
			(layer "B.Fab")
		)
		(fp_line
			(start -0.299974 0.150114)
			(end 0.299974 0.150114)
			(stroke
				(width 0.1)
				(type default)
			)
			(layer "B.Fab")
		)
		(pad "1" smd rect
			(at 0.2667 0 270)
			(size 0.3048 0.381)
			(layers "B.Cu" "B.Mask" "B.Paste")
			(net "P0V9_CPU1_RT1_2A")
		)
		(pad "2" smd rect
			(at -0.2667 0 270)
			(size 0.3048 0.381)
			(layers "B.Cu" "B.Mask" "B.Paste")
			(net "GND")
		)
	)
	(footprint ""
		(layer "B.Cu")
		(at 365.09579 -393.96416 180)
		(property "Reference" "R1114"
			(at 0 0 0)
			(layer "B.SilkS")
			(hide yes)
			(effects
				(font
					(size 1.27 1.27)
				)
				(justify mirror)
			)
		)
		(property "Value" ""
			(at 0 0 0)
			(layer "B.Fab")
			(effects
				(font
					(size 1.27 1.27)
				)
				(justify mirror)
			)
		)
		(duplicate_pad_numbers_are_jumpers no)
		(fp_line
			(start 0.32512 0.175006)
			(end 0.32512 -0.175006)
			(stroke
				(width 0.1)
				(type default)
			)
			(layer "B.Fab")
		)
		(fp_line
			(start 0.32512 -0.175006)
			(end -0.32512 -0.175006)
			(stroke
				(width 0.1)
				(type default)
			)
			(layer "B.Fab")
		)
		(fp_line
			(start -0.32512 0.175006)
			(end 0.32512 0.175006)
			(stroke
				(width 0.1)
				(type default)
			)
			(layer "B.Fab")
		)
		(fp_line
			(start -0.32512 -0.175006)
			(end -0.32512 0.175006)
			(stroke
				(width 0.1)
				(type default)
			)
			(layer "B.Fab")
		)
		(pad "1" smd rect
			(at 0.2667 0)
			(size 0.3048 0.381)
			(layers "B.Cu" "B.Mask" "B.Paste")
			(net "P1V8_CPU0_RT_1D")
		)
		(pad "2" smd rect
			(at -0.2667 0 180)
			(size 0.3048 0.381)
			(layers "B.Cu" "B.Mask" "B.Paste")
			(net "TEST0_RT_CPU0_P3")
		)
	)
	(footprint ""
		(layer "B.Cu")
		(at 355.006656 -169.619676 -90)
		(property "Reference" "PC573_5"
			(at 0 0 90)
			(layer "B.SilkS")
			(hide yes)
			(effects
				(font
					(size 1.27 1.27)
				)
				(justify mirror)
			)
		)
		(property "Value" ""
			(at 0 0 90)
			(layer "B.Fab")
			(effects
				(font
					(size 1.27 1.27)
				)
				(justify mirror)
			)
		)
		(duplicate_pad_numbers_are_jumpers no)
		(fp_line
			(start -1.524 0.762)
			(end 1.524 0.762)
			(stroke
				(width 0.1524)
				(type default)
			)
			(layer "B.SilkS")
		)
		(fp_line
			(start 1.524 0.762)
			(end 1.524 -0.762)
			(stroke
				(width 0.1524)
				(type default)
			)
			(layer "B.SilkS")
		)
		(fp_line
			(start -1.524 -0.762)
			(end -1.524 0.762)
			(stroke
				(width 0.1524)
				(type default)
			)
			(layer "B.SilkS")
		)
		(fp_line
			(start 1.524 -0.762)
			(end -1.524 -0.762)
			(stroke
				(width 0.1524)
				(type default)
			)
			(layer "B.SilkS")
		)
		(fp_line
			(start -1.1049 0.724916)
			(end -1.1049 -0.724916)
			(stroke
				(width 0.1)
				(type default)
			)
			(layer "B.Fab")
		)
		(fp_line
			(start 1.1049 0.724916)
			(end -1.1049 0.724916)
			(stroke
				(width 0.1)
				(type default)
			)
			(layer "B.Fab")
		)
		(fp_line
			(start -1.1049 -0.724916)
			(end 1.1049 -0.724916)
			(stroke
				(width 0.1)
				(type default)
			)
			(layer "B.Fab")
		)
		(fp_line
			(start 1.1049 -0.724916)
			(end 1.1049 0.724916)
			(stroke
				(width 0.1)
				(type default)
			)
			(layer "B.Fab")
		)
		(pad "1" smd rect
			(at 0.889 0 270)
			(size 1.016 1.27)
			(layers "B.Cu" "B.Mask" "B.Paste")
			(net "SW_P12V_AUX_PVDDCR_CPU0_P0_FLT")
		)
		(pad "2" smd rect
			(at -0.889 0 270)
			(size 1.016 1.27)
			(layers "B.Cu" "B.Mask" "B.Paste")
			(net "GND")
		)
	)
	(footprint ""
		(layer "B.Cu")
		(at 78.072488 -381.238252)
		(property "Reference" "C7025"
			(at 0 0 0)
			(layer "B.SilkS")
			(hide yes)
			(effects
				(font
					(size 1.27 1.27)
				)
				(justify mirror)
			)
		)
		(property "Value" ""
			(at 0 0 0)
			(layer "B.Fab")
			(effects
				(font
					(size 1.27 1.27)
				)
				(justify mirror)
			)
		)
		(duplicate_pad_numbers_are_jumpers no)
		(fp_line
			(start -1.524 -0.762)
			(end -1.524 0.762)
			(stroke
				(width 0.1524)
				(type default)
			)
			(layer "B.SilkS")
		)
		(fp_line
			(start -1.524 0.762)
			(end 1.524 0.762)
			(stroke
				(width 0.1524)
				(type default)
			)
			(layer "B.SilkS")
		)
		(fp_line
			(start 1.524 -0.762)
			(end -1.524 -0.762)
			(stroke
				(width 0.1524)
				(type default)
			)
			(layer "B.SilkS")
		)
		(fp_line
			(start 1.524 0.762)
			(end 1.524 -0.762)
			(stroke
				(width 0.1524)
				(type default)
			)
			(layer "B.SilkS")
		)
		(fp_line
			(start -1.1049 -0.724916)
			(end 1.1049 -0.724916)
			(stroke
				(width 0.1)
				(type default)
			)
			(layer "B.Fab")
		)
		(fp_line
			(start -1.1049 0.724916)
			(end -1.1049 -0.724916)
			(stroke
				(width 0.1)
				(type default)
			)
			(layer "B.Fab")
		)
		(fp_line
			(start 1.1049 -0.724916)
			(end 1.1049 0.724916)
			(stroke
				(width 0.1)
				(type default)
			)
			(layer "B.Fab")
		)
		(fp_line
			(start 1.1049 0.724916)
			(end -1.1049 0.724916)
			(stroke
				(width 0.1)
				(type default)
			)
			(layer "B.Fab")
		)
		(pad "1" smd rect
			(at 0.889 0)
			(size 1.016 1.27)
			(layers "B.Cu" "B.Mask" "B.Paste")
			(net "P0V9_CPU1_RT1_2A")
		)
		(pad "2" smd rect
			(at -0.889 0)
			(size 1.016 1.27)
			(layers "B.Cu" "B.Mask" "B.Paste")
			(net "GND")
		)
	)
	(footprint ""
		(layer "B.Cu")
		(at 398.563592 -341.172292 90)
		(property "Reference" "R934"
			(at 0 0 90)
			(layer "B.SilkS")
			(hide yes)
			(effects
				(font
					(size 1.27 1.27)
				)
				(justify mirror)
			)
		)
		(property "Value" ""
			(at 0 0 90)
			(layer "B.Fab")
			(effects
				(font
					(size 1.27 1.27)
				)
				(justify mirror)
			)
		)
		(duplicate_pad_numbers_are_jumpers no)
		(fp_line
			(start 0.7874 -0.4064)
			(end -0.7874 -0.4064)
			(stroke
				(width 0.1524)
				(type default)
			)
			(layer "B.SilkS")
		)
		(fp_line
			(start -0.7874 -0.4064)
			(end -0.7874 0.4064)
			(stroke
				(width 0.1524)
				(type default)
			)
			(layer "B.SilkS")
		)
		(fp_line
			(start 0.7874 0.4064)
			(end 0.7874 -0.4064)
			(stroke
				(width 0.1524)
				(type default)
			)
			(layer "B.SilkS")
		)
		(fp_line
			(start -0.7874 0.4064)
			(end 0.7874 0.4064)
			(stroke
				(width 0.1524)
				(type default)
			)
			(layer "B.SilkS")
		)
		(fp_line
			(start 0.67945 -0.305054)
			(end 0.12065 -0.305054)
			(stroke
				(width 0.1)
				(type default)
			)
			(layer "B.Fab")
		)
		(fp_line
			(start 0.12065 -0.305054)
			(end 0.12065 -0.2794)
			(stroke
				(width 0.1)
				(type default)
			)
			(layer "B.Fab")
		)
		(fp_line
			(start -0.12065 -0.3048)
			(end -0.67945 -0.3048)
			(stroke
				(width 0.1)
				(type default)
			)
			(layer "B.Fab")
		)
		(fp_line
			(start -0.67945 -0.3048)
			(end -0.67945 0.3048)
			(stroke
				(width 0.1)
				(type default)
			)
			(layer "B.Fab")
		)
		(fp_line
			(start 0.12065 -0.2794)
			(end -0.12065 -0.2794)
			(stroke
				(width 0.1)
				(type default)
			)
			(layer "B.Fab")
		)
		(fp_line
			(start -0.12065 -0.2794)
			(end -0.12065 -0.3048)
			(stroke
				(width 0.1)
				(type default)
			)
			(layer "B.Fab")
		)
		(fp_line
			(start 0.12065 0.2794)
			(end 0.12065 0.3048)
			(stroke
				(width 0.1)
				(type default)
			)
			(layer "B.Fab")
		)
		(fp_line
			(start -0.120396 0.2794)
			(end 0.12065 0.2794)
			(stroke
				(width 0.1)
				(type default)
			)
			(layer "B.Fab")
		)
		(fp_line
			(start 0.67945 0.3048)
			(end 0.67945 -0.305054)
			(stroke
				(width 0.1)
				(type default)
			)
			(layer "B.Fab")
		)
		(fp_line
			(start 0.12065 0.3048)
			(end 0.67945 0.3048)
			(stroke
				(width 0.1)
				(type default)
			)
			(layer "B.Fab")
		)
		(fp_line
			(start -0.120396 0.3048)
			(end -0.120396 0.2794)
			(stroke
				(width 0.1)
				(type default)
			)
			(layer "B.Fab")
		)
		(fp_line
			(start -0.67945 0.3048)
			(end -0.120396 0.3048)
			(stroke
				(width 0.1)
				(type default)
			)
			(layer "B.Fab")
		)
		(pad "1" smd circle
			(at 0.40005 0 270)
			(size 0 0)
			(layers "B.Cu" "B.Mask" "B.Paste")
			(net "FM_BIOS_POST_CMPLT_N")
		)
		(pad "2" smd circle
			(at -0.40005 0 270)
			(size 0 0)
			(layers "B.Cu" "B.Mask" "B.Paste")
			(net "BOOT_RDY_R1_N")
		)
	)
	(footprint ""
		(layer "B.Cu")
		(at 151.819102 -390.560052 90)
		(property "Reference" "C399"
			(at 0 0 90)
			(layer "B.SilkS")
			(hide yes)
			(effects
				(font
					(size 1.27 1.27)
				)
				(justify mirror)
			)
		)
		(property "Value" ""
			(at 0 0 90)
			(layer "B.Fab")
			(effects
				(font
					(size 1.27 1.27)
				)
				(justify mirror)
			)
		)
		(duplicate_pad_numbers_are_jumpers no)
		(fp_line
			(start 0.7874 -0.4064)
			(end -0.7874 -0.4064)
			(stroke
				(width 0.1524)
				(type default)
			)
			(layer "B.SilkS")
		)
		(fp_line
			(start -0.7874 -0.4064)
			(end -0.7874 0.4064)
			(stroke
				(width 0.1524)
				(type default)
			)
			(layer "B.SilkS")
		)
		(fp_line
			(start 0.7874 0.4064)
			(end 0.7874 -0.4064)
			(stroke
				(width 0.1524)
				(type default)
			)
			(layer "B.SilkS")
		)
		(fp_line
			(start -0.7874 0.4064)
			(end 0.7874 0.4064)
			(stroke
				(width 0.1524)
				(type default)
			)
			(layer "B.SilkS")
		)
		(fp_line
			(start 0.67945 -0.305054)
			(end 0.12065 -0.305054)
			(stroke
				(width 0.1)
				(type default)
			)
			(layer "B.Fab")
		)
		(fp_line
			(start 0.12065 -0.305054)
			(end 0.12065 -0.2794)
			(stroke
				(width 0.1)
				(type default)
			)
			(layer "B.Fab")
		)
		(fp_line
			(start -0.12065 -0.3048)
			(end -0.67945 -0.3048)
			(stroke
				(width 0.1)
				(type default)
			)
			(layer "B.Fab")
		)
		(fp_line
			(start -0.67945 -0.3048)
			(end -0.67945 0.3048)
			(stroke
				(width 0.1)
				(type default)
			)
			(layer "B.Fab")
		)
		(fp_line
			(start 0.12065 -0.2794)
			(end -0.12065 -0.2794)
			(stroke
				(width 0.1)
				(type default)
			)
			(layer "B.Fab")
		)
		(fp_line
			(start -0.12065 -0.2794)
			(end -0.12065 -0.3048)
			(stroke
				(width 0.1)
				(type default)
			)
			(layer "B.Fab")
		)
		(fp_line
			(start 0.12065 0.2794)
			(end 0.12065 0.3048)
			(stroke
				(width 0.1)
				(type default)
			)
			(layer "B.Fab")
		)
		(fp_line
			(start -0.120396 0.2794)
			(end 0.12065 0.2794)
			(stroke
				(width 0.1)
				(type default)
			)
			(layer "B.Fab")
		)
		(fp_line
			(start 0.67945 0.3048)
			(end 0.67945 -0.305054)
			(stroke
				(width 0.1)
				(type default)
			)
			(layer "B.Fab")
		)
		(fp_line
			(start 0.12065 0.3048)
			(end 0.67945 0.3048)
			(stroke
				(width 0.1)
				(type default)
			)
			(layer "B.Fab")
		)
		(fp_line
			(start -0.120396 0.3048)
			(end -0.120396 0.2794)
			(stroke
				(width 0.1)
				(type default)
			)
			(layer "B.Fab")
		)
		(fp_line
			(start -0.67945 0.3048)
			(end -0.120396 0.3048)
			(stroke
				(width 0.1)
				(type default)
			)
			(layer "B.Fab")
		)
		(pad "1" smd circle
			(at 0.40005 0 270)
			(size 0 0)
			(layers "B.Cu" "B.Mask" "B.Paste")
			(net "P0V9_CPU1_RT2_2A")
		)
		(pad "2" smd circle
			(at -0.40005 0 270)
			(size 0 0)
			(layers "B.Cu" "B.Mask" "B.Paste")
			(net "GND")
		)
	)
	(footprint ""
		(layer "B.Cu")
		(at 295.416986 -424.118786 180)
		(property "Reference" "R1219"
			(at 0 0 0)
			(layer "B.SilkS")
			(hide yes)
			(effects
				(font
					(size 1.27 1.27)
				)
				(justify mirror)
			)
		)
		(property "Value" ""
			(at 0 0 0)
			(layer "B.Fab")
			(effects
				(font
					(size 1.27 1.27)
				)
				(justify mirror)
			)
		)
		(duplicate_pad_numbers_are_jumpers no)
		(fp_line
			(start 0.32512 0.175006)
			(end 0.32512 -0.175006)
			(stroke
				(width 0.1)
				(type default)
			)
			(layer "B.Fab")
		)
		(fp_line
			(start 0.32512 -0.175006)
			(end -0.32512 -0.175006)
			(stroke
				(width 0.1)
				(type default)
			)
			(layer "B.Fab")
		)
		(fp_line
			(start -0.32512 0.175006)
			(end 0.32512 0.175006)
			(stroke
				(width 0.1)
				(type default)
			)
			(layer "B.Fab")
		)
		(fp_line
			(start -0.32512 -0.175006)
			(end -0.32512 0.175006)
			(stroke
				(width 0.1)
				(type default)
			)
			(layer "B.Fab")
		)
		(pad "1" smd rect
			(at 0.2667 0)
			(size 0.3048 0.381)
			(layers "B.Cu" "B.Mask" "B.Paste")
			(net "GND")
		)
		(pad "2" smd rect
			(at -0.2667 0 180)
			(size 0.3048 0.381)
			(layers "B.Cu" "B.Mask" "B.Paste")
			(net "RT_ROM_MUX5_OE_N")
		)
	)
	(footprint ""
		(layer "B.Cu")
		(at 183.3245 -404.051262 180)
		(property "Reference" "R3924"
			(at 0 0 0)
			(layer "B.SilkS")
			(hide yes)
			(effects
				(font
					(size 1.27 1.27)
				)
				(justify mirror)
			)
		)
		(property "Value" ""
			(at 0 0 0)
			(layer "B.Fab")
			(effects
				(font
					(size 1.27 1.27)
				)
				(justify mirror)
			)
		)
		(duplicate_pad_numbers_are_jumpers no)
		(fp_line
			(start 0.7874 0.4064)
			(end 0.7874 -0.4064)
			(stroke
				(width 0.1524)
				(type default)
			)
			(layer "B.SilkS")
		)
		(fp_line
			(start 0.7874 -0.4064)
			(end -0.7874 -0.4064)
			(stroke
				(width 0.1524)
				(type default)
			)
			(layer "B.SilkS")
		)
		(fp_line
			(start -0.7874 0.4064)
			(end 0.7874 0.4064)
			(stroke
				(width 0.1524)
				(type default)
			)
			(layer "B.SilkS")
		)
		(fp_line
			(start -0.7874 -0.4064)
			(end -0.7874 0.4064)
			(stroke
				(width 0.1524)
				(type default)
			)
			(layer "B.SilkS")
		)
		(fp_line
			(start 0.67945 0.3048)
			(end 0.67945 -0.305054)
			(stroke
				(width 0.1)
				(type default)
			)
			(layer "B.Fab")
		)
		(fp_line
			(start 0.67945 -0.305054)
			(end 0.12065 -0.305054)
			(stroke
				(width 0.1)
				(type default)
			)
			(layer "B.Fab")
		)
		(fp_line
			(start 0.12065 0.3048)
			(end 0.67945 0.3048)
			(stroke
				(width 0.1)
				(type default)
			)
			(layer "B.Fab")
		)
		(fp_line
			(start 0.12065 0.2794)
			(end 0.12065 0.3048)
			(stroke
				(width 0.1)
				(type default)
			)
			(layer "B.Fab")
		)
		(fp_line
			(start 0.12065 -0.2794)
			(end -0.12065 -0.2794)
			(stroke
				(width 0.1)
				(type default)
			)
			(layer "B.Fab")
		)
		(fp_line
			(start 0.12065 -0.305054)
			(end 0.12065 -0.2794)
			(stroke
				(width 0.1)
				(type default)
			)
			(layer "B.Fab")
		)
		(fp_line
			(start -0.120396 0.3048)
			(end -0.120396 0.2794)
			(stroke
				(width 0.1)
				(type default)
			)
			(layer "B.Fab")
		)
		(fp_line
			(start -0.120396 0.2794)
			(end 0.12065 0.2794)
			(stroke
				(width 0.1)
				(type default)
			)
			(layer "B.Fab")
		)
		(fp_line
			(start -0.12065 -0.2794)
			(end -0.12065 -0.3048)
			(stroke
				(width 0.1)
				(type default)
			)
			(layer "B.Fab")
		)
		(fp_line
			(start -0.12065 -0.3048)
			(end -0.67945 -0.3048)
			(stroke
				(width 0.1)
				(type default)
			)
			(layer "B.Fab")
		)
		(fp_line
			(start -0.67945 0.3048)
			(end -0.120396 0.3048)
			(stroke
				(width 0.1)
				(type default)
			)
			(layer "B.Fab")
		)
		(fp_line
			(start -0.67945 -0.3048)
			(end -0.67945 0.3048)
			(stroke
				(width 0.1)
				(type default)
			)
			(layer "B.Fab")
		)
		(pad "1" smd circle
			(at 0.40005 0)
			(size 0 0)
			(layers "B.Cu" "B.Mask" "B.Paste")
			(net "IRQ_SML1_PMBUS_ALERT_N")
		)
		(pad "2" smd circle
			(at -0.40005 0)
			(size 0 0)
			(layers "B.Cu" "B.Mask" "B.Paste")
			(net "IRQ_SML1_PMBUS_ALERT")
		)
	)
	(footprint ""
		(layer "B.Cu")
		(at 90.209878 -140.82141 180)
		(property "Reference" "R8177"
			(at 0 0 0)
			(layer "B.SilkS")
			(hide yes)
			(effects
				(font
					(size 1.27 1.27)
				)
				(justify mirror)
			)
		)
		(property "Value" ""
			(at 0 0 0)
			(layer "B.Fab")
			(effects
				(font
					(size 1.27 1.27)
				)
				(justify mirror)
			)
		)
		(duplicate_pad_numbers_are_jumpers no)
		(fp_line
			(start 0.7874 0.4064)
			(end 0.7874 -0.4064)
			(stroke
				(width 0.1524)
				(type default)
			)
			(layer "B.SilkS")
		)
		(fp_line
			(start 0.7874 -0.4064)
			(end -0.7874 -0.4064)
			(stroke
				(width 0.1524)
				(type default)
			)
			(layer "B.SilkS")
		)
		(fp_line
			(start -0.7874 0.4064)
			(end 0.7874 0.4064)
			(stroke
				(width 0.1524)
				(type default)
			)
			(layer "B.SilkS")
		)
		(fp_line
			(start -0.7874 -0.4064)
			(end -0.7874 0.4064)
			(stroke
				(width 0.1524)
				(type default)
			)
			(layer "B.SilkS")
		)
		(fp_line
			(start 0.67945 0.3048)
			(end 0.67945 -0.305054)
			(stroke
				(width 0.1)
				(type default)
			)
			(layer "B.Fab")
		)
		(fp_line
			(start 0.67945 -0.305054)
			(end 0.12065 -0.305054)
			(stroke
				(width 0.1)
				(type default)
			)
			(layer "B.Fab")
		)
		(fp_line
			(start 0.12065 0.3048)
			(end 0.67945 0.3048)
			(stroke
				(width 0.1)
				(type default)
			)
			(layer "B.Fab")
		)
		(fp_line
			(start 0.12065 0.2794)
			(end 0.12065 0.3048)
			(stroke
				(width 0.1)
				(type default)
			)
			(layer "B.Fab")
		)
		(fp_line
			(start 0.12065 -0.2794)
			(end -0.12065 -0.2794)
			(stroke
				(width 0.1)
				(type default)
			)
			(layer "B.Fab")
		)
		(fp_line
			(start 0.12065 -0.305054)
			(end 0.12065 -0.2794)
			(stroke
				(width 0.1)
				(type default)
			)
			(layer "B.Fab")
		)
		(fp_line
			(start -0.120396 0.3048)
			(end -0.120396 0.2794)
			(stroke
				(width 0.1)
				(type default)
			)
			(layer "B.Fab")
		)
		(fp_line
			(start -0.120396 0.2794)
			(end 0.12065 0.2794)
			(stroke
				(width 0.1)
				(type default)
			)
			(layer "B.Fab")
		)
		(fp_line
			(start -0.12065 -0.2794)
			(end -0.12065 -0.3048)
			(stroke
				(width 0.1)
				(type default)
			)
			(layer "B.Fab")
		)
		(fp_line
			(start -0.12065 -0.3048)
			(end -0.67945 -0.3048)
			(stroke
				(width 0.1)
				(type default)
			)
			(layer "B.Fab")
		)
		(fp_line
			(start -0.67945 0.3048)
			(end -0.120396 0.3048)
			(stroke
				(width 0.1)
				(type default)
			)
			(layer "B.Fab")
		)
		(fp_line
			(start -0.67945 -0.3048)
			(end -0.67945 0.3048)
			(stroke
				(width 0.1)
				(type default)
			)
			(layer "B.Fab")
		)
		(pad "1" smd circle
			(at 0.40005 0)
			(size 0 0)
			(layers "B.Cu" "B.Mask" "B.Paste")
			(net "PVDDCR_CPU0_P1_PMALERT")
		)
		(pad "2" smd circle
			(at -0.40005 0)
			(size 0 0)
			(layers "B.Cu" "B.Mask" "B.Paste")
			(net "PVDDCR_CPU0_P1_PMALERT_R")
		)
	)
	(footprint ""
		(layer "B.Cu")
		(at 55.328058 -192.66027 180)
		(property "Reference" "C173"
			(at 0 0 0)
			(layer "B.SilkS")
			(hide yes)
			(effects
				(font
					(size 1.27 1.27)
				)
				(justify mirror)
			)
		)
		(property "Value" ""
			(at 0 0 0)
			(layer "B.Fab")
			(effects
				(font
					(size 1.27 1.27)
				)
				(justify mirror)
			)
		)
		(duplicate_pad_numbers_are_jumpers no)
		(fp_line
			(start 1.524 0.762)
			(end 1.524 -0.762)
			(stroke
				(width 0.1524)
				(type default)
			)
			(layer "B.SilkS")
		)
		(fp_line
			(start 1.524 -0.762)
			(end -1.524 -0.762)
			(stroke
				(width 0.1524)
				(type default)
			)
			(layer "B.SilkS")
		)
		(fp_line
			(start -1.524 0.762)
			(end 1.524 0.762)
			(stroke
				(width 0.1524)
				(type default)
			)
			(layer "B.SilkS")
		)
		(fp_line
			(start -1.524 -0.762)
			(end -1.524 0.762)
			(stroke
				(width 0.1524)
				(type default)
			)
			(layer "B.SilkS")
		)
		(fp_line
			(start 1.1049 0.724916)
			(end -1.1049 0.724916)
			(stroke
				(width 0.1)
				(type default)
			)
			(layer "B.Fab")
		)
		(fp_line
			(start 1.1049 -0.724916)
			(end 1.1049 0.724916)
			(stroke
				(width 0.1)
				(type default)
			)
			(layer "B.Fab")
		)
		(fp_line
			(start -1.1049 0.724916)
			(end -1.1049 -0.724916)
			(stroke
				(width 0.1)
				(type default)
			)
			(layer "B.Fab")
		)
		(fp_line
			(start -1.1049 -0.724916)
			(end 1.1049 -0.724916)
			(stroke
				(width 0.1)
				(type default)
			)
			(layer "B.Fab")
		)
		(pad "1" smd rect
			(at 0.889 0 180)
			(size 1.016 1.27)
			(layers "B.Cu" "B.Mask" "B.Paste")
			(net "P12V_MEM_CPU1")
		)
		(pad "2" smd rect
			(at -0.889 0 180)
			(size 1.016 1.27)
			(layers "B.Cu" "B.Mask" "B.Paste")
			(net "GND")
		)
	)
	(footprint ""
		(layer "B.Cu")
		(at 396.546578 -328.655172 180)
		(property "Reference" "R463"
			(at 0 0 0)
			(layer "B.SilkS")
			(hide yes)
			(effects
				(font
					(size 1.27 1.27)
				)
				(justify mirror)
			)
		)
		(property "Value" ""
			(at 0 0 0)
			(layer "B.Fab")
			(effects
				(font
					(size 1.27 1.27)
				)
				(justify mirror)
			)
		)
		(duplicate_pad_numbers_are_jumpers no)
		(fp_line
			(start 0.7874 0.4064)
			(end 0.7874 -0.4064)
			(stroke
				(width 0.1524)
				(type default)
			)
			(layer "B.SilkS")
		)
		(fp_line
			(start 0.7874 -0.4064)
			(end -0.7874 -0.4064)
			(stroke
				(width 0.1524)
				(type default)
			)
			(layer "B.SilkS")
		)
		(fp_line
			(start -0.7874 0.4064)
			(end 0.7874 0.4064)
			(stroke
				(width 0.1524)
				(type default)
			)
			(layer "B.SilkS")
		)
		(fp_line
			(start -0.7874 -0.4064)
			(end -0.7874 0.4064)
			(stroke
				(width 0.1524)
				(type default)
			)
			(layer "B.SilkS")
		)
		(fp_line
			(start 0.67945 0.3048)
			(end 0.67945 -0.305054)
			(stroke
				(width 0.1)
				(type default)
			)
			(layer "B.Fab")
		)
		(fp_line
			(start 0.67945 -0.305054)
			(end 0.12065 -0.305054)
			(stroke
				(width 0.1)
				(type default)
			)
			(layer "B.Fab")
		)
		(fp_line
			(start 0.12065 0.3048)
			(end 0.67945 0.3048)
			(stroke
				(width 0.1)
				(type default)
			)
			(layer "B.Fab")
		)
		(fp_line
			(start 0.12065 0.2794)
			(end 0.12065 0.3048)
			(stroke
				(width 0.1)
				(type default)
			)
			(layer "B.Fab")
		)
		(fp_line
			(start 0.12065 -0.2794)
			(end -0.12065 -0.2794)
			(stroke
				(width 0.1)
				(type default)
			)
			(layer "B.Fab")
		)
		(fp_line
			(start 0.12065 -0.305054)
			(end 0.12065 -0.2794)
			(stroke
				(width 0.1)
				(type default)
			)
			(layer "B.Fab")
		)
		(fp_line
			(start -0.120396 0.3048)
			(end -0.120396 0.2794)
			(stroke
				(width 0.1)
				(type default)
			)
			(layer "B.Fab")
		)
		(fp_line
			(start -0.120396 0.2794)
			(end 0.12065 0.2794)
			(stroke
				(width 0.1)
				(type default)
			)
			(layer "B.Fab")
		)
		(fp_line
			(start -0.12065 -0.2794)
			(end -0.12065 -0.3048)
			(stroke
				(width 0.1)
				(type default)
			)
			(layer "B.Fab")
		)
		(fp_line
			(start -0.12065 -0.3048)
			(end -0.67945 -0.3048)
			(stroke
				(width 0.1)
				(type default)
			)
			(layer "B.Fab")
		)
		(fp_line
			(start -0.67945 0.3048)
			(end -0.120396 0.3048)
			(stroke
				(width 0.1)
				(type default)
			)
			(layer "B.Fab")
		)
		(fp_line
			(start -0.67945 -0.3048)
			(end -0.67945 0.3048)
			(stroke
				(width 0.1)
				(type default)
			)
			(layer "B.Fab")
		)
		(pad "1" smd circle
			(at 0.40005 0)
			(size 0 0)
			(layers "B.Cu" "B.Mask" "B.Paste")
			(net "RST_CPU0_KBRST_R_N")
		)
		(pad "2" smd circle
			(at -0.40005 0)
			(size 0 0)
			(layers "B.Cu" "B.Mask" "B.Paste")
			(net "RST_CPU0_KBRST_N")
		)
	)
	(footprint ""
		(layer "B.Cu")
		(at 98.70313 -335.09712 90)
		(property "Reference" "PC426_5"
			(at 0 0 90)
			(layer "B.SilkS")
			(hide yes)
			(effects
				(font
					(size 1.27 1.27)
				)
				(justify mirror)
			)
		)
		(property "Value" ""
			(at 0 0 90)
			(layer "B.Fab")
			(effects
				(font
					(size 1.27 1.27)
				)
				(justify mirror)
			)
		)
		(duplicate_pad_numbers_are_jumpers no)
		(fp_line
			(start 1.524 -0.762)
			(end -1.524 -0.762)
			(stroke
				(width 0.1524)
				(type default)
			)
			(layer "B.SilkS")
		)
		(fp_line
			(start -1.524 -0.762)
			(end -1.524 0.762)
			(stroke
				(width 0.1524)
				(type default)
			)
			(layer "B.SilkS")
		)
		(fp_line
			(start 1.524 0.762)
			(end 1.524 -0.762)
			(stroke
				(width 0.1524)
				(type default)
			)
			(layer "B.SilkS")
		)
		(fp_line
			(start -1.524 0.762)
			(end 1.524 0.762)
			(stroke
				(width 0.1524)
				(type default)
			)
			(layer "B.SilkS")
		)
		(fp_line
			(start 1.1049 -0.724916)
			(end 1.1049 0.724916)
			(stroke
				(width 0.1)
				(type default)
			)
			(layer "B.Fab")
		)
		(fp_line
			(start -1.1049 -0.724916)
			(end 1.1049 -0.724916)
			(stroke
				(width 0.1)
				(type default)
			)
			(layer "B.Fab")
		)
		(fp_line
			(start 1.1049 0.724916)
			(end -1.1049 0.724916)
			(stroke
				(width 0.1)
				(type default)
			)
			(layer "B.Fab")
		)
		(fp_line
			(start -1.1049 0.724916)
			(end -1.1049 -0.724916)
			(stroke
				(width 0.1)
				(type default)
			)
			(layer "B.Fab")
		)
		(pad "1" smd rect
			(at 0.889 0 90)
			(size 1.016 1.27)
			(layers "B.Cu" "B.Mask" "B.Paste")
			(net "SW_P12V_AUX_PVDDCR_CPU1_P1_FLT")
		)
		(pad "2" smd rect
			(at -0.889 0 90)
			(size 1.016 1.27)
			(layers "B.Cu" "B.Mask" "B.Paste")
			(net "GND")
		)
	)
	(footprint ""
		(layer "B.Cu")
		(at 320.19113 -398.942052 90)
		(property "Reference" "C571"
			(at 0 0 90)
			(layer "B.SilkS")
			(hide yes)
			(effects
				(font
					(size 1.27 1.27)
				)
				(justify mirror)
			)
		)
		(property "Value" ""
			(at 0 0 90)
			(layer "B.Fab")
			(effects
				(font
					(size 1.27 1.27)
				)
				(justify mirror)
			)
		)
		(duplicate_pad_numbers_are_jumpers no)
		(fp_line
			(start 0.7874 -0.4064)
			(end -0.7874 -0.4064)
			(stroke
				(width 0.1524)
				(type default)
			)
			(layer "B.SilkS")
		)
		(fp_line
			(start -0.7874 -0.4064)
			(end -0.7874 0.4064)
			(stroke
				(width 0.1524)
				(type default)
			)
			(layer "B.SilkS")
		)
		(fp_line
			(start 0.7874 0.4064)
			(end 0.7874 -0.4064)
			(stroke
				(width 0.1524)
				(type default)
			)
			(layer "B.SilkS")
		)
		(fp_line
			(start -0.7874 0.4064)
			(end 0.7874 0.4064)
			(stroke
				(width 0.1524)
				(type default)
			)
			(layer "B.SilkS")
		)
		(fp_line
			(start 0.67945 -0.305054)
			(end 0.12065 -0.305054)
			(stroke
				(width 0.1)
				(type default)
			)
			(layer "B.Fab")
		)
		(fp_line
			(start 0.12065 -0.305054)
			(end 0.12065 -0.2794)
			(stroke
				(width 0.1)
				(type default)
			)
			(layer "B.Fab")
		)
		(fp_line
			(start -0.12065 -0.3048)
			(end -0.67945 -0.3048)
			(stroke
				(width 0.1)
				(type default)
			)
			(layer "B.Fab")
		)
		(fp_line
			(start -0.67945 -0.3048)
			(end -0.67945 0.3048)
			(stroke
				(width 0.1)
				(type default)
			)
			(layer "B.Fab")
		)
		(fp_line
			(start 0.12065 -0.2794)
			(end -0.12065 -0.2794)
			(stroke
				(width 0.1)
				(type default)
			)
			(layer "B.Fab")
		)
		(fp_line
			(start -0.12065 -0.2794)
			(end -0.12065 -0.3048)
			(stroke
				(width 0.1)
				(type default)
			)
			(layer "B.Fab")
		)
		(fp_line
			(start 0.12065 0.2794)
			(end 0.12065 0.3048)
			(stroke
				(width 0.1)
				(type default)
			)
			(layer "B.Fab")
		)
		(fp_line
			(start -0.120396 0.2794)
			(end 0.12065 0.2794)
			(stroke
				(width 0.1)
				(type default)
			)
			(layer "B.Fab")
		)
		(fp_line
			(start 0.67945 0.3048)
			(end 0.67945 -0.305054)
			(stroke
				(width 0.1)
				(type default)
			)
			(layer "B.Fab")
		)
		(fp_line
			(start 0.12065 0.3048)
			(end 0.67945 0.3048)
			(stroke
				(width 0.1)
				(type default)
			)
			(layer "B.Fab")
		)
		(fp_line
			(start -0.120396 0.3048)
			(end -0.120396 0.2794)
			(stroke
				(width 0.1)
				(type default)
			)
			(layer "B.Fab")
		)
		(fp_line
			(start -0.67945 0.3048)
			(end -0.120396 0.3048)
			(stroke
				(width 0.1)
				(type default)
			)
			(layer "B.Fab")
		)
		(pad "1" smd circle
			(at 0.40005 0 270)
			(size 0 0)
			(layers "B.Cu" "B.Mask" "B.Paste")
			(net "P0V9_CPU0_RT0_2A")
		)
		(pad "2" smd circle
			(at -0.40005 0 270)
			(size 0 0)
			(layers "B.Cu" "B.Mask" "B.Paste")
			(net "GND")
		)
	)
	(footprint ""
		(layer "B.Cu")
		(at 367.102898 -215.303608 180)
		(property "Reference" "PR302"
			(at 0 0 0)
			(layer "B.SilkS")
			(hide yes)
			(effects
				(font
					(size 1.27 1.27)
				)
				(justify mirror)
			)
		)
		(property "Value" ""
			(at 0 0 0)
			(layer "B.Fab")
			(effects
				(font
					(size 1.27 1.27)
				)
				(justify mirror)
			)
		)
		(duplicate_pad_numbers_are_jumpers no)
		(fp_line
			(start 0.7874 0.4064)
			(end 0.7874 -0.4064)
			(stroke
				(width 0.1524)
				(type default)
			)
			(layer "B.SilkS")
		)
		(fp_line
			(start 0.7874 -0.4064)
			(end -0.7874 -0.4064)
			(stroke
				(width 0.1524)
				(type default)
			)
			(layer "B.SilkS")
		)
		(fp_line
			(start -0.7874 0.4064)
			(end 0.7874 0.4064)
			(stroke
				(width 0.1524)
				(type default)
			)
			(layer "B.SilkS")
		)
		(fp_line
			(start -0.7874 -0.4064)
			(end -0.7874 0.4064)
			(stroke
				(width 0.1524)
				(type default)
			)
			(layer "B.SilkS")
		)
		(fp_line
			(start 0.67945 0.3048)
			(end 0.67945 -0.305054)
			(stroke
				(width 0.1)
				(type default)
			)
			(layer "B.Fab")
		)
		(fp_line
			(start 0.67945 -0.305054)
			(end 0.12065 -0.305054)
			(stroke
				(width 0.1)
				(type default)
			)
			(layer "B.Fab")
		)
		(fp_line
			(start 0.12065 0.3048)
			(end 0.67945 0.3048)
			(stroke
				(width 0.1)
				(type default)
			)
			(layer "B.Fab")
		)
		(fp_line
			(start 0.12065 0.2794)
			(end 0.12065 0.3048)
			(stroke
				(width 0.1)
				(type default)
			)
			(layer "B.Fab")
		)
		(fp_line
			(start 0.12065 -0.2794)
			(end -0.12065 -0.2794)
			(stroke
				(width 0.1)
				(type default)
			)
			(layer "B.Fab")
		)
		(fp_line
			(start 0.12065 -0.305054)
			(end 0.12065 -0.2794)
			(stroke
				(width 0.1)
				(type default)
			)
			(layer "B.Fab")
		)
		(fp_line
			(start -0.120396 0.3048)
			(end -0.120396 0.2794)
			(stroke
				(width 0.1)
				(type default)
			)
			(layer "B.Fab")
		)
		(fp_line
			(start -0.120396 0.2794)
			(end 0.12065 0.2794)
			(stroke
				(width 0.1)
				(type default)
			)
			(layer "B.Fab")
		)
		(fp_line
			(start -0.12065 -0.2794)
			(end -0.12065 -0.3048)
			(stroke
				(width 0.1)
				(type default)
			)
			(layer "B.Fab")
		)
		(fp_line
			(start -0.12065 -0.3048)
			(end -0.67945 -0.3048)
			(stroke
				(width 0.1)
				(type default)
			)
			(layer "B.Fab")
		)
		(fp_line
			(start -0.67945 0.3048)
			(end -0.120396 0.3048)
			(stroke
				(width 0.1)
				(type default)
			)
			(layer "B.Fab")
		)
		(fp_line
			(start -0.67945 -0.3048)
			(end -0.67945 0.3048)
			(stroke
				(width 0.1)
				(type default)
			)
			(layer "B.Fab")
		)
		(pad "1" smd circle
			(at 0.40005 0)
			(size 0 0)
			(layers "B.Cu" "B.Mask" "B.Paste")
			(net "SVID_PVDDCR_CPU0_P0_SVC_R")
		)
		(pad "2" smd circle
			(at -0.40005 0)
			(size 0 0)
			(layers "B.Cu" "B.Mask" "B.Paste")
			(net "SVID_PVDDCR_CPU0_P0_SVC")
		)
	)
	(footprint ""
		(layer "B.Cu")
		(at 311.427876 -78.775814 -90)
		(property "Reference" "R9446"
			(at 0 0 90)
			(layer "B.SilkS")
			(hide yes)
			(effects
				(font
					(size 1.27 1.27)
				)
				(justify mirror)
			)
		)
		(property "Value" ""
			(at 0 0 90)
			(layer "B.Fab")
			(effects
				(font
					(size 1.27 1.27)
				)
				(justify mirror)
			)
		)
		(duplicate_pad_numbers_are_jumpers no)
		(fp_line
			(start -0.7874 0.4064)
			(end 0.7874 0.4064)
			(stroke
				(width 0.1524)
				(type default)
			)
			(layer "B.SilkS")
		)
		(fp_line
			(start 0.7874 0.4064)
			(end 0.7874 -0.4064)
			(stroke
				(width 0.1524)
				(type default)
			)
			(layer "B.SilkS")
		)
		(fp_line
			(start -0.7874 -0.4064)
			(end -0.7874 0.4064)
			(stroke
				(width 0.1524)
				(type default)
			)
			(layer "B.SilkS")
		)
		(fp_line
			(start 0.7874 -0.4064)
			(end -0.7874 -0.4064)
			(stroke
				(width 0.1524)
				(type default)
			)
			(layer "B.SilkS")
		)
		(fp_line
			(start -0.67945 0.3048)
			(end -0.120396 0.3048)
			(stroke
				(width 0.1)
				(type default)
			)
			(layer "B.Fab")
		)
		(fp_line
			(start -0.120396 0.3048)
			(end -0.120396 0.2794)
			(stroke
				(width 0.1)
				(type default)
			)
			(layer "B.Fab")
		)
		(fp_line
			(start 0.12065 0.3048)
			(end 0.67945 0.3048)
			(stroke
				(width 0.1)
				(type default)
			)
			(layer "B.Fab")
		)
		(fp_line
			(start 0.67945 0.3048)
			(end 0.67945 -0.305054)
			(stroke
				(width 0.1)
				(type default)
			)
			(layer "B.Fab")
		)
		(fp_line
			(start -0.120396 0.2794)
			(end 0.12065 0.2794)
			(stroke
				(width 0.1)
				(type default)
			)
			(layer "B.Fab")
		)
		(fp_line
			(start 0.12065 0.2794)
			(end 0.12065 0.3048)
			(stroke
				(width 0.1)
				(type default)
			)
			(layer "B.Fab")
		)
		(fp_line
			(start -0.12065 -0.2794)
			(end -0.12065 -0.3048)
			(stroke
				(width 0.1)
				(type default)
			)
			(layer "B.Fab")
		)
		(fp_line
			(start 0.12065 -0.2794)
			(end -0.12065 -0.2794)
			(stroke
				(width 0.1)
				(type default)
			)
			(layer "B.Fab")
		)
		(fp_line
			(start -0.67945 -0.3048)
			(end -0.67945 0.3048)
			(stroke
				(width 0.1)
				(type default)
			)
			(layer "B.Fab")
		)
		(fp_line
			(start -0.12065 -0.3048)
			(end -0.67945 -0.3048)
			(stroke
				(width 0.1)
				(type default)
			)
			(layer "B.Fab")
		)
		(fp_line
			(start 0.12065 -0.305054)
			(end 0.12065 -0.2794)
			(stroke
				(width 0.1)
				(type default)
			)
			(layer "B.Fab")
		)
		(fp_line
			(start 0.67945 -0.305054)
			(end 0.12065 -0.305054)
			(stroke
				(width 0.1)
				(type default)
			)
			(layer "B.Fab")
		)
		(pad "1" smd circle
			(at 0.40005 0 90)
			(size 0 0)
			(layers "B.Cu" "B.Mask" "B.Paste")
			(net "PWRGD_PS_PWROK_PLD_ISO")
		)
		(pad "2" smd circle
			(at -0.40005 0 90)
			(size 0 0)
			(layers "B.Cu" "B.Mask" "B.Paste")
			(net "PWRGD_PS_PWROK_PLD_ISO_R")
		)
	)
	(footprint ""
		(layer "B.Cu")
		(at 70.743064 -408.517344 90)
		(property "Reference" "C6676"
			(at 0 0 90)
			(layer "B.SilkS")
			(hide yes)
			(effects
				(font
					(size 1.27 1.27)
				)
				(justify mirror)
			)
		)
		(property "Value" ""
			(at 0 0 90)
			(layer "B.Fab")
			(effects
				(font
					(size 1.27 1.27)
				)
				(justify mirror)
			)
		)
		(duplicate_pad_numbers_are_jumpers no)
		(fp_line
			(start 0.299974 -0.150114)
			(end -0.299974 -0.150114)
			(stroke
				(width 0.1)
				(type default)
			)
			(layer "B.Fab")
		)
		(fp_line
			(start -0.299974 -0.150114)
			(end -0.299974 0.150114)
			(stroke
				(width 0.1)
				(type default)
			)
			(layer "B.Fab")
		)
		(fp_line
			(start 0.299974 0.150114)
			(end 0.299974 -0.150114)
			(stroke
				(width 0.1)
				(type default)
			)
			(layer "B.Fab")
		)
		(fp_line
			(start -0.299974 0.150114)
			(end 0.299974 0.150114)
			(stroke
				(width 0.1)
				(type default)
			)
			(layer "B.Fab")
		)
		(pad "1" smd rect
			(at 0.2667 0 270)
			(size 0.3048 0.381)
			(layers "B.Cu" "B.Mask" "B.Paste")
			(net "P5E_CPU1_P1_TX_BUF_C_DN<7>")
		)
		(pad "2" smd rect
			(at -0.2667 0 270)
			(size 0.3048 0.381)
			(layers "B.Cu" "B.Mask" "B.Paste")
			(net "P5E_CPU1_P1_TX_BUF_DN<7>")
		)
	)
	(footprint ""
		(layer "B.Cu")
		(at 160.346136 -388.011162 -90)
		(property "Reference" "C397"
			(at 0 0 90)
			(layer "B.SilkS")
			(hide yes)
			(effects
				(font
					(size 1.27 1.27)
				)
				(justify mirror)
			)
		)
		(property "Value" ""
			(at 0 0 90)
			(layer "B.Fab")
			(effects
				(font
					(size 1.27 1.27)
				)
				(justify mirror)
			)
		)
		(duplicate_pad_numbers_are_jumpers no)
		(fp_line
			(start -0.299974 0.150114)
			(end 0.299974 0.150114)
			(stroke
				(width 0.1)
				(type default)
			)
			(layer "B.Fab")
		)
		(fp_line
			(start 0.299974 0.150114)
			(end 0.299974 -0.150114)
			(stroke
				(width 0.1)
				(type default)
			)
			(layer "B.Fab")
		)
		(fp_line
			(start -0.299974 -0.150114)
			(end -0.299974 0.150114)
			(stroke
				(width 0.1)
				(type default)
			)
			(layer "B.Fab")
		)
		(fp_line
			(start 0.299974 -0.150114)
			(end -0.299974 -0.150114)
			(stroke
				(width 0.1)
				(type default)
			)
			(layer "B.Fab")
		)
		(pad "1" smd rect
			(at 0.2667 0 90)
			(size 0.3048 0.381)
			(layers "B.Cu" "B.Mask" "B.Paste")
			(net "P0V9_CPU1_RT2_2A_2D")
		)
		(pad "2" smd rect
			(at -0.2667 0 90)
			(size 0.3048 0.381)
			(layers "B.Cu" "B.Mask" "B.Paste")
			(net "GND")
		)
	)
	(footprint ""
		(layer "B.Cu")
		(at 70.0532 -382.8796 180)
		(property "Reference" "R709"
			(at 0 0 0)
			(layer "B.SilkS")
			(hide yes)
			(effects
				(font
					(size 1.27 1.27)
				)
				(justify mirror)
			)
		)
		(property "Value" ""
			(at 0 0 0)
			(layer "B.Fab")
			(effects
				(font
					(size 1.27 1.27)
				)
				(justify mirror)
			)
		)
		(duplicate_pad_numbers_are_jumpers no)
		(fp_line
			(start 0.32512 0.175006)
			(end 0.32512 -0.175006)
			(stroke
				(width 0.1)
				(type default)
			)
			(layer "B.Fab")
		)
		(fp_line
			(start 0.32512 -0.175006)
			(end -0.32512 -0.175006)
			(stroke
				(width 0.1)
				(type default)
			)
			(layer "B.Fab")
		)
		(fp_line
			(start -0.32512 0.175006)
			(end 0.32512 0.175006)
			(stroke
				(width 0.1)
				(type default)
			)
			(layer "B.Fab")
		)
		(fp_line
			(start -0.32512 -0.175006)
			(end -0.32512 0.175006)
			(stroke
				(width 0.1)
				(type default)
			)
			(layer "B.Fab")
		)
		(pad "1" smd rect
			(at 0.2667 0)
			(size 0.3048 0.381)
			(layers "B.Cu" "B.Mask" "B.Paste")
			(net "NCF_CPU1_P0_GND")
		)
		(pad "2" smd rect
			(at -0.2667 0 180)
			(size 0.3048 0.381)
			(layers "B.Cu" "B.Mask" "B.Paste")
			(net "GND")
		)
	)
	(footprint ""
		(layer "B.Cu")
		(at 153.456386 -318.53505 180)
		(property "Reference" "Y5"
			(at -3.805936 0.462026 0)
			(unlocked yes)
			(layer "B.SilkS")
			(effects
				(font
					(size 0.7874 0.5842)
					(thickness 0.1524)
				)
				(justify left mirror)
			)
		)
		(property "Value" ""
			(at 0 0 0)
			(layer "B.Fab")
			(effects
				(font
					(size 1.27 1.27)
				)
				(justify mirror)
			)
		)
		(duplicate_pad_numbers_are_jumpers no)
		(fp_line
			(start 1.905 1.0414)
			(end -1.905 1.0414)
			(stroke
				(width 0.1524)
				(type default)
			)
			(layer "B.SilkS")
		)
		(fp_line
			(start 1.905 -1.0414)
			(end 1.905 1.0414)
			(stroke
				(width 0.1524)
				(type default)
			)
			(layer "B.SilkS")
		)
		(fp_line
			(start -1.905 1.0414)
			(end -1.905 -1.0414)
			(stroke
				(width 0.1524)
				(type default)
			)
			(layer "B.SilkS")
		)
		(fp_line
			(start -1.905 -1.0414)
			(end 1.905 -1.0414)
			(stroke
				(width 0.1524)
				(type default)
			)
			(layer "B.SilkS")
		)
		(fp_line
			(start 1.649984 0.824992)
			(end -1.649984 0.824992)
			(stroke
				(width 0.1)
				(type default)
			)
			(layer "B.Fab")
		)
		(fp_line
			(start 1.649984 -0.824992)
			(end 1.649984 0.824992)
			(stroke
				(width 0.1)
				(type default)
			)
			(layer "B.Fab")
		)
		(fp_line
			(start -1.649984 0.824992)
			(end -1.649984 -0.824992)
			(stroke
				(width 0.1)
				(type default)
			)
			(layer "B.Fab")
		)
		(fp_line
			(start -1.649984 -0.824992)
			(end 1.649984 -0.824992)
			(stroke
				(width 0.1)
				(type default)
			)
			(layer "B.Fab")
		)
		(pad "1" smd rect
			(at 1.249934 0)
			(size 1.016 1.8034)
			(layers "B.Cu" "B.Mask" "B.Paste")
			(net "XTAL_CPU1_R_X32K_X1")
		)
		(pad "2" smd rect
			(at -1.249934 0 180)
			(size 1.016 1.8034)
			(layers "B.Cu" "B.Mask" "B.Paste")
			(net "XTAL_CPU1_R_X32K_X2")
		)
		(zone
			(layer "B.Cu")
			(hatch none 0.5)
			(connect_pads
				(clearance 0)
			)
			(min_thickness 0.25)
			(keepout
				(tracks not_allowed)
				(vias allowed)
				(pads allowed)
				(copperpour not_allowed)
				(footprints allowed)
			)
			(placement
				(enabled no)
				(sheetname "")
			)
			(fill
				(thermal_gap 0.5)
				(thermal_bridge_width 0.5)
				(island_removal_mode 0)
			)
			(polygon
				(pts
					(xy 152.765252 -317.58255) (xy 152.765252 -319.48755) (xy 154.14752 -319.48755) (xy 154.14752 -317.58255)
				)
			)
		)
	)
	(footprint ""
		(layer "B.Cu")
		(at 130.408934 -31.622492 180)
		(property "Reference" "C6064"
			(at 0 0 0)
			(layer "B.SilkS")
			(hide yes)
			(effects
				(font
					(size 1.27 1.27)
				)
				(justify mirror)
			)
		)
		(property "Value" ""
			(at 0 0 0)
			(layer "B.Fab")
			(effects
				(font
					(size 1.27 1.27)
				)
				(justify mirror)
			)
		)
		(duplicate_pad_numbers_are_jumpers no)
		(fp_line
			(start 0.7874 0.4064)
			(end 0.7874 -0.4064)
			(stroke
				(width 0.1524)
				(type default)
			)
			(layer "B.SilkS")
		)
		(fp_line
			(start 0.7874 -0.4064)
			(end -0.7874 -0.4064)
			(stroke
				(width 0.1524)
				(type default)
			)
			(layer "B.SilkS")
		)
		(fp_line
			(start -0.7874 0.4064)
			(end 0.7874 0.4064)
			(stroke
				(width 0.1524)
				(type default)
			)
			(layer "B.SilkS")
		)
		(fp_line
			(start -0.7874 -0.4064)
			(end -0.7874 0.4064)
			(stroke
				(width 0.1524)
				(type default)
			)
			(layer "B.SilkS")
		)
		(fp_line
			(start 0.67945 0.3048)
			(end 0.67945 -0.305054)
			(stroke
				(width 0.1)
				(type default)
			)
			(layer "B.Fab")
		)
		(fp_line
			(start 0.67945 -0.305054)
			(end 0.12065 -0.305054)
			(stroke
				(width 0.1)
				(type default)
			)
			(layer "B.Fab")
		)
		(fp_line
			(start 0.12065 0.3048)
			(end 0.67945 0.3048)
			(stroke
				(width 0.1)
				(type default)
			)
			(layer "B.Fab")
		)
		(fp_line
			(start 0.12065 0.2794)
			(end 0.12065 0.3048)
			(stroke
				(width 0.1)
				(type default)
			)
			(layer "B.Fab")
		)
		(fp_line
			(start 0.12065 -0.2794)
			(end -0.12065 -0.2794)
			(stroke
				(width 0.1)
				(type default)
			)
			(layer "B.Fab")
		)
		(fp_line
			(start 0.12065 -0.305054)
			(end 0.12065 -0.2794)
			(stroke
				(width 0.1)
				(type default)
			)
			(layer "B.Fab")
		)
		(fp_line
			(start -0.120396 0.3048)
			(end -0.120396 0.2794)
			(stroke
				(width 0.1)
				(type default)
			)
			(layer "B.Fab")
		)
		(fp_line
			(start -0.120396 0.2794)
			(end 0.12065 0.2794)
			(stroke
				(width 0.1)
				(type default)
			)
			(layer "B.Fab")
		)
		(fp_line
			(start -0.12065 -0.2794)
			(end -0.12065 -0.3048)
			(stroke
				(width 0.1)
				(type default)
			)
			(layer "B.Fab")
		)
		(fp_line
			(start -0.12065 -0.3048)
			(end -0.67945 -0.3048)
			(stroke
				(width 0.1)
				(type default)
			)
			(layer "B.Fab")
		)
		(fp_line
			(start -0.67945 0.3048)
			(end -0.120396 0.3048)
			(stroke
				(width 0.1)
				(type default)
			)
			(layer "B.Fab")
		)
		(fp_line
			(start -0.67945 -0.3048)
			(end -0.67945 0.3048)
			(stroke
				(width 0.1)
				(type default)
			)
			(layer "B.Fab")
		)
		(pad "1" smd circle
			(at 0.40005 0)
			(size 0 0)
			(layers "B.Cu" "B.Mask" "B.Paste")
			(net "P1V2_AUX")
		)
		(pad "2" smd circle
			(at -0.40005 0)
			(size 0 0)
			(layers "B.Cu" "B.Mask" "B.Paste")
			(net "GND")
		)
	)
	(footprint ""
		(layer "B.Cu")
		(at 424.646598 -362.378244)
		(property "Reference" "PR113"
			(at 0 0 0)
			(layer "B.SilkS")
			(hide yes)
			(effects
				(font
					(size 1.27 1.27)
				)
				(justify mirror)
			)
		)
		(property "Value" ""
			(at 0 0 0)
			(layer "B.Fab")
			(effects
				(font
					(size 1.27 1.27)
				)
				(justify mirror)
			)
		)
		(duplicate_pad_numbers_are_jumpers no)
		(fp_line
			(start -0.7874 -0.4064)
			(end -0.7874 0.4064)
			(stroke
				(width 0.1524)
				(type default)
			)
			(layer "B.SilkS")
		)
		(fp_line
			(start -0.7874 0.4064)
			(end 0.7874 0.4064)
			(stroke
				(width 0.1524)
				(type default)
			)
			(layer "B.SilkS")
		)
		(fp_line
			(start 0.7874 -0.4064)
			(end -0.7874 -0.4064)
			(stroke
				(width 0.1524)
				(type default)
			)
			(layer "B.SilkS")
		)
		(fp_line
			(start 0.7874 0.4064)
			(end 0.7874 -0.4064)
			(stroke
				(width 0.1524)
				(type default)
			)
			(layer "B.SilkS")
		)
		(fp_line
			(start -0.67945 -0.3048)
			(end -0.67945 0.3048)
			(stroke
				(width 0.1)
				(type default)
			)
			(layer "B.Fab")
		)
		(fp_line
			(start -0.67945 0.3048)
			(end -0.120396 0.3048)
			(stroke
				(width 0.1)
				(type default)
			)
			(layer "B.Fab")
		)
		(fp_line
			(start -0.12065 -0.3048)
			(end -0.67945 -0.3048)
			(stroke
				(width 0.1)
				(type default)
			)
			(layer "B.Fab")
		)
		(fp_line
			(start -0.12065 -0.2794)
			(end -0.12065 -0.3048)
			(stroke
				(width 0.1)
				(type default)
			)
			(layer "B.Fab")
		)
		(fp_line
			(start -0.120396 0.2794)
			(end 0.12065 0.2794)
			(stroke
				(width 0.1)
				(type default)
			)
			(layer "B.Fab")
		)
		(fp_line
			(start -0.120396 0.3048)
			(end -0.120396 0.2794)
			(stroke
				(width 0.1)
				(type default)
			)
			(layer "B.Fab")
		)
		(fp_line
			(start 0.12065 -0.305054)
			(end 0.12065 -0.2794)
			(stroke
				(width 0.1)
				(type default)
			)
			(layer "B.Fab")
		)
		(fp_line
			(start 0.12065 -0.2794)
			(end -0.12065 -0.2794)
			(stroke
				(width 0.1)
				(type default)
			)
			(layer "B.Fab")
		)
		(fp_line
			(start 0.12065 0.2794)
			(end 0.12065 0.3048)
			(stroke
				(width 0.1)
				(type default)
			)
			(layer "B.Fab")
		)
		(fp_line
			(start 0.12065 0.3048)
			(end 0.67945 0.3048)
			(stroke
				(width 0.1)
				(type default)
			)
			(layer "B.Fab")
		)
		(fp_line
			(start 0.67945 -0.305054)
			(end 0.12065 -0.305054)
			(stroke
				(width 0.1)
				(type default)
			)
			(layer "B.Fab")
		)
		(fp_line
			(start 0.67945 0.3048)
			(end 0.67945 -0.305054)
			(stroke
				(width 0.1)
				(type default)
			)
			(layer "B.Fab")
		)
		(pad "1" smd circle
			(at 0.40005 0 180)
			(size 0 0)
			(layers "B.Cu" "B.Mask" "B.Paste")
			(net "P5V_AUX")
		)
		(pad "2" smd circle
			(at -0.40005 0 180)
			(size 0 0)
			(layers "B.Cu" "B.Mask" "B.Paste")
			(net "PVDD11_S3_P0_VMON")
		)
	)
	(footprint ""
		(layer "B.Cu")
		(at 342.498934 -301.911258 -90)
		(property "Reference" "R4304"
			(at 0 0 90)
			(layer "B.SilkS")
			(hide yes)
			(effects
				(font
					(size 1.27 1.27)
				)
				(justify mirror)
			)
		)
		(property "Value" ""
			(at 0 0 90)
			(layer "B.Fab")
			(effects
				(font
					(size 1.27 1.27)
				)
				(justify mirror)
			)
		)
		(duplicate_pad_numbers_are_jumpers no)
		(fp_line
			(start -0.7874 0.4064)
			(end 0.7874 0.4064)
			(stroke
				(width 0.1524)
				(type default)
			)
			(layer "B.SilkS")
		)
		(fp_line
			(start 0.7874 0.4064)
			(end 0.7874 0.056134)
			(stroke
				(width 0.1524)
				(type default)
			)
			(layer "B.SilkS")
		)
		(fp_line
			(start -0.7874 0.056134)
			(end -0.7874 0.4064)
			(stroke
				(width 0.1524)
				(type default)
			)
			(layer "B.SilkS")
		)
		(fp_line
			(start 0.311658 -0.4064)
			(end -0.374142 -0.4064)
			(stroke
				(width 0.1524)
				(type default)
			)
			(layer "B.SilkS")
		)
		(fp_line
			(start -0.67945 0.3048)
			(end -0.120396 0.3048)
			(stroke
				(width 0.1)
				(type default)
			)
			(layer "B.Fab")
		)
		(fp_line
			(start -0.120396 0.3048)
			(end -0.120396 0.2794)
			(stroke
				(width 0.1)
				(type default)
			)
			(layer "B.Fab")
		)
		(fp_line
			(start 0.12065 0.3048)
			(end 0.67945 0.3048)
			(stroke
				(width 0.1)
				(type default)
			)
			(layer "B.Fab")
		)
		(fp_line
			(start 0.67945 0.3048)
			(end 0.67945 -0.305054)
			(stroke
				(width 0.1)
				(type default)
			)
			(layer "B.Fab")
		)
		(fp_line
			(start -0.120396 0.2794)
			(end 0.12065 0.2794)
			(stroke
				(width 0.1)
				(type default)
			)
			(layer "B.Fab")
		)
		(fp_line
			(start 0.12065 0.2794)
			(end 0.12065 0.3048)
			(stroke
				(width 0.1)
				(type default)
			)
			(layer "B.Fab")
		)
		(fp_line
			(start -0.12065 -0.2794)
			(end -0.12065 -0.3048)
			(stroke
				(width 0.1)
				(type default)
			)
			(layer "B.Fab")
		)
		(fp_line
			(start 0.12065 -0.2794)
			(end -0.12065 -0.2794)
			(stroke
				(width 0.1)
				(type default)
			)
			(layer "B.Fab")
		)
		(fp_line
			(start -0.67945 -0.3048)
			(end -0.67945 0.3048)
			(stroke
				(width 0.1)
				(type default)
			)
			(layer "B.Fab")
		)
		(fp_line
			(start -0.12065 -0.3048)
			(end -0.67945 -0.3048)
			(stroke
				(width 0.1)
				(type default)
			)
			(layer "B.Fab")
		)
		(fp_line
			(start 0.12065 -0.305054)
			(end 0.12065 -0.2794)
			(stroke
				(width 0.1)
				(type default)
			)
			(layer "B.Fab")
		)
		(fp_line
			(start 0.67945 -0.305054)
			(end 0.12065 -0.305054)
			(stroke
				(width 0.1)
				(type default)
			)
			(layer "B.Fab")
		)
		(pad "1" smd circle
			(at 0.40005 0 90)
			(size 0 0)
			(layers "B.Cu" "B.Mask" "B.Paste")
			(net "CLK_100M_CPU0_CLK12_R_DN")
		)
		(pad "2" smd circle
			(at -0.40005 0 90)
			(size 0 0)
			(layers "B.Cu" "B.Mask" "B.Paste")
			(net "CLK_100M_CPU0_CLK12_DN")
		)
	)
	(footprint ""
		(layer "B.Cu")
		(at 177.443638 -13.762228 90)
		(property "Reference" "R4506"
			(at 0 0 90)
			(layer "B.SilkS")
			(hide yes)
			(effects
				(font
					(size 1.27 1.27)
				)
				(justify mirror)
			)
		)
		(property "Value" ""
			(at 0 0 90)
			(layer "B.Fab")
			(effects
				(font
					(size 1.27 1.27)
				)
				(justify mirror)
			)
		)
		(duplicate_pad_numbers_are_jumpers no)
		(fp_line
			(start 0.7874 -0.4064)
			(end -0.7874 -0.4064)
			(stroke
				(width 0.1524)
				(type default)
			)
			(layer "B.SilkS")
		)
		(fp_line
			(start -0.7874 -0.4064)
			(end -0.7874 0.4064)
			(stroke
				(width 0.1524)
				(type default)
			)
			(layer "B.SilkS")
		)
		(fp_line
			(start 0.7874 0.4064)
			(end 0.7874 -0.4064)
			(stroke
				(width 0.1524)
				(type default)
			)
			(layer "B.SilkS")
		)
		(fp_line
			(start -0.7874 0.4064)
			(end 0.7874 0.4064)
			(stroke
				(width 0.1524)
				(type default)
			)
			(layer "B.SilkS")
		)
		(fp_line
			(start 0.67945 -0.305054)
			(end 0.12065 -0.305054)
			(stroke
				(width 0.1)
				(type default)
			)
			(layer "B.Fab")
		)
		(fp_line
			(start 0.12065 -0.305054)
			(end 0.12065 -0.2794)
			(stroke
				(width 0.1)
				(type default)
			)
			(layer "B.Fab")
		)
		(fp_line
			(start -0.12065 -0.3048)
			(end -0.67945 -0.3048)
			(stroke
				(width 0.1)
				(type default)
			)
			(layer "B.Fab")
		)
		(fp_line
			(start -0.67945 -0.3048)
			(end -0.67945 0.3048)
			(stroke
				(width 0.1)
				(type default)
			)
			(layer "B.Fab")
		)
		(fp_line
			(start 0.12065 -0.2794)
			(end -0.12065 -0.2794)
			(stroke
				(width 0.1)
				(type default)
			)
			(layer "B.Fab")
		)
		(fp_line
			(start -0.12065 -0.2794)
			(end -0.12065 -0.3048)
			(stroke
				(width 0.1)
				(type default)
			)
			(layer "B.Fab")
		)
		(fp_line
			(start 0.12065 0.2794)
			(end 0.12065 0.3048)
			(stroke
				(width 0.1)
				(type default)
			)
			(layer "B.Fab")
		)
		(fp_line
			(start -0.120396 0.2794)
			(end 0.12065 0.2794)
			(stroke
				(width 0.1)
				(type default)
			)
			(layer "B.Fab")
		)
		(fp_line
			(start 0.67945 0.3048)
			(end 0.67945 -0.305054)
			(stroke
				(width 0.1)
				(type default)
			)
			(layer "B.Fab")
		)
		(fp_line
			(start 0.12065 0.3048)
			(end 0.67945 0.3048)
			(stroke
				(width 0.1)
				(type default)
			)
			(layer "B.Fab")
		)
		(fp_line
			(start -0.120396 0.3048)
			(end -0.120396 0.2794)
			(stroke
				(width 0.1)
				(type default)
			)
			(layer "B.Fab")
		)
		(fp_line
			(start -0.67945 0.3048)
			(end -0.120396 0.3048)
			(stroke
				(width 0.1)
				(type default)
			)
			(layer "B.Fab")
		)
		(pad "1" smd circle
			(at 0.40005 0 270)
			(size 0 0)
			(layers "B.Cu" "B.Mask" "B.Paste")
			(net "SMB_CPU0_CPU1_SEC_SCL")
		)
		(pad "2" smd circle
			(at -0.40005 0 270)
			(size 0 0)
			(layers "B.Cu" "B.Mask" "B.Paste")
			(net "SMB_CPU0_CPU1_SEC_SCL_R")
		)
	)
	(footprint ""
		(layer "B.Cu")
		(at 14.340332 -383.53873 -90)
		(property "Reference" "PC6813"
			(at -3.17627 3.191002 270)
			(unlocked yes)
			(layer "B.SilkS")
			(effects
				(font
					(size 0.7874 0.5842)
					(thickness 0.1524)
				)
				(justify left mirror)
			)
		)
		(property "Value" ""
			(at 0 0 90)
			(layer "B.Fab")
			(effects
				(font
					(size 1.27 1.27)
				)
				(justify mirror)
			)
		)
		(duplicate_pad_numbers_are_jumpers no)
		(fp_line
			(start 4.83108 2.150364)
			(end 4.447794 2.149348)
			(stroke
				(width 0.1524)
				(type default)
			)
			(layer "B.SilkS")
		)
		(fp_line
			(start -4.53898 2.15011)
			(end 4.53898 2.15011)
			(stroke
				(width 0.1524)
				(type default)
			)
			(layer "B.SilkS")
		)
		(fp_line
			(start 4.53898 2.15011)
			(end 4.53898 -2.15011)
			(stroke
				(width 0.1524)
				(type default)
			)
			(layer "B.SilkS")
		)
		(fp_line
			(start -4.53898 -2.15011)
			(end -4.53898 2.15011)
			(stroke
				(width 0.1524)
				(type default)
			)
			(layer "B.SilkS")
		)
		(fp_line
			(start 4.53898 -2.15011)
			(end -4.53898 -2.15011)
			(stroke
				(width 0.1524)
				(type default)
			)
			(layer "B.SilkS")
		)
		(fp_line
			(start 4.53898 -2.150618)
			(end 4.539742 2.152142)
			(stroke
				(width 0.1524)
				(type default)
			)
			(layer "B.SilkS")
		)
		(fp_line
			(start 4.69138 -2.150618)
			(end 4.692396 2.161032)
			(stroke
				(width 0.1524)
				(type default)
			)
			(layer "B.SilkS")
		)
		(fp_line
			(start 4.84378 -2.150618)
			(end 4.842256 2.163064)
			(stroke
				(width 0.1524)
				(type default)
			)
			(layer "B.SilkS")
		)
		(fp_line
			(start 4.84378 -2.150618)
			(end 4.53898 -2.150618)
			(stroke
				(width 0.1524)
				(type default)
			)
			(layer "B.SilkS")
		)
		(fp_line
			(start -3.64998 2.15011)
			(end 3.64998 2.15011)
			(stroke
				(width 0.1)
				(type default)
			)
			(layer "B.Fab")
		)
		(fp_line
			(start 3.64998 2.15011)
			(end 3.64998 -2.15011)
			(stroke
				(width 0.1)
				(type default)
			)
			(layer "B.Fab")
		)
		(fp_line
			(start -3.64998 -2.15011)
			(end -3.64998 2.15011)
			(stroke
				(width 0.1)
				(type default)
			)
			(layer "B.Fab")
		)
		(fp_line
			(start 3.64998 -2.15011)
			(end -3.64998 -2.15011)
			(stroke
				(width 0.1)
				(type default)
			)
			(layer "B.Fab")
		)
		(fp_text user "-"
			(at -4.535678 -1.371346 270)
			(unlocked yes)
			(layer "B.SilkS")
			(effects
				(font
					(size 1.905 1.4224)
					(thickness 0.1524)
				)
				(justify left mirror)
			)
		)
		(fp_text user "+"
			(at 6.222492 -1.50114 270)
			(unlocked yes)
			(layer "B.SilkS")
			(effects
				(font
					(size 1.905 1.4224)
					(thickness 0.1524)
				)
				(justify left mirror)
			)
		)
		(fp_text user "-"
			(at -4.313174 -0.094488 270)
			(unlocked yes)
			(layer "B.Fab")
			(effects
				(font
					(size 1.905 1.4224)
					(thickness 0.1524)
				)
				(justify left mirror)
			)
		)
		(fp_text user "+"
			(at 6.214872 -0.337058 270)
			(unlocked yes)
			(layer "B.Fab")
			(effects
				(font
					(size 1.905 1.4224)
					(thickness 0.1524)
				)
				(justify left mirror)
			)
		)
		(pad "1" smd rect
			(at 3.199892 0 90)
			(size 2.413 2.8194)
			(layers "B.Cu" "B.Mask" "B.Paste")
			(net "P0V9_CPU1_RT_2D")
		)
		(pad "2" smd rect
			(at -3.199892 0 90)
			(size 2.413 2.8194)
			(layers "B.Cu" "B.Mask" "B.Paste")
			(net "GND")
		)
	)
	(footprint ""
		(layer "B.Cu")
		(at 113.705386 -253.432564)
		(property "Reference" "C2284"
			(at 0 0 0)
			(layer "B.SilkS")
			(hide yes)
			(effects
				(font
					(size 1.27 1.27)
				)
				(justify mirror)
			)
		)
		(property "Value" ""
			(at 0 0 0)
			(layer "B.Fab")
			(effects
				(font
					(size 1.27 1.27)
				)
				(justify mirror)
			)
		)
		(duplicate_pad_numbers_are_jumpers no)
		(fp_line
			(start -0.7874 -0.4064)
			(end -0.7874 0.4064)
			(stroke
				(width 0.1524)
				(type default)
			)
			(layer "B.SilkS")
		)
		(fp_line
			(start -0.7874 0.4064)
			(end 0.7874 0.4064)
			(stroke
				(width 0.1524)
				(type default)
			)
			(layer "B.SilkS")
		)
		(fp_line
			(start 0.7874 -0.4064)
			(end -0.7874 -0.4064)
			(stroke
				(width 0.1524)
				(type default)
			)
			(layer "B.SilkS")
		)
		(fp_line
			(start 0.7874 0.4064)
			(end 0.7874 -0.4064)
			(stroke
				(width 0.1524)
				(type default)
			)
			(layer "B.SilkS")
		)
		(fp_line
			(start -0.67945 -0.3048)
			(end -0.67945 0.3048)
			(stroke
				(width 0.1)
				(type default)
			)
			(layer "B.Fab")
		)
		(fp_line
			(start -0.67945 0.3048)
			(end -0.120396 0.3048)
			(stroke
				(width 0.1)
				(type default)
			)
			(layer "B.Fab")
		)
		(fp_line
			(start -0.12065 -0.3048)
			(end -0.67945 -0.3048)
			(stroke
				(width 0.1)
				(type default)
			)
			(layer "B.Fab")
		)
		(fp_line
			(start -0.12065 -0.2794)
			(end -0.12065 -0.3048)
			(stroke
				(width 0.1)
				(type default)
			)
			(layer "B.Fab")
		)
		(fp_line
			(start -0.120396 0.2794)
			(end 0.12065 0.2794)
			(stroke
				(width 0.1)
				(type default)
			)
			(layer "B.Fab")
		)
		(fp_line
			(start -0.120396 0.3048)
			(end -0.120396 0.2794)
			(stroke
				(width 0.1)
				(type default)
			)
			(layer "B.Fab")
		)
		(fp_line
			(start 0.12065 -0.305054)
			(end 0.12065 -0.2794)
			(stroke
				(width 0.1)
				(type default)
			)
			(layer "B.Fab")
		)
		(fp_line
			(start 0.12065 -0.2794)
			(end -0.12065 -0.2794)
			(stroke
				(width 0.1)
				(type default)
			)
			(layer "B.Fab")
		)
		(fp_line
			(start 0.12065 0.2794)
			(end 0.12065 0.3048)
			(stroke
				(width 0.1)
				(type default)
			)
			(layer "B.Fab")
		)
		(fp_line
			(start 0.12065 0.3048)
			(end 0.67945 0.3048)
			(stroke
				(width 0.1)
				(type default)
			)
			(layer "B.Fab")
		)
		(fp_line
			(start 0.67945 -0.305054)
			(end 0.12065 -0.305054)
			(stroke
				(width 0.1)
				(type default)
			)
			(layer "B.Fab")
		)
		(fp_line
			(start 0.67945 0.3048)
			(end 0.67945 -0.305054)
			(stroke
				(width 0.1)
				(type default)
			)
			(layer "B.Fab")
		)
		(pad "1" smd circle
			(at 0.40005 0 180)
			(size 0 0)
			(layers "B.Cu" "B.Mask" "B.Paste")
			(net "PVDDCR_SOC_P1")
		)
		(pad "2" smd circle
			(at -0.40005 0 180)
			(size 0 0)
			(layers "B.Cu" "B.Mask" "B.Paste")
			(net "GND")
		)
	)
	(footprint ""
		(layer "B.Cu")
		(at 169.66692 -52.415948 180)
		(property "Reference" "C1924"
			(at 0 0 0)
			(layer "B.SilkS")
			(hide yes)
			(effects
				(font
					(size 1.27 1.27)
				)
				(justify mirror)
			)
		)
		(property "Value" ""
			(at 0 0 0)
			(layer "B.Fab")
			(effects
				(font
					(size 1.27 1.27)
				)
				(justify mirror)
			)
		)
		(duplicate_pad_numbers_are_jumpers no)
		(fp_line
			(start 0.7874 0.4064)
			(end 0.7874 -0.4064)
			(stroke
				(width 0.1524)
				(type default)
			)
			(layer "B.SilkS")
		)
		(fp_line
			(start 0.7874 -0.4064)
			(end -0.7874 -0.4064)
			(stroke
				(width 0.1524)
				(type default)
			)
			(layer "B.SilkS")
		)
		(fp_line
			(start -0.7874 0.4064)
			(end 0.7874 0.4064)
			(stroke
				(width 0.1524)
				(type default)
			)
			(layer "B.SilkS")
		)
		(fp_line
			(start -0.7874 -0.4064)
			(end -0.7874 0.4064)
			(stroke
				(width 0.1524)
				(type default)
			)
			(layer "B.SilkS")
		)
		(fp_line
			(start 0.67945 0.3048)
			(end 0.67945 -0.305054)
			(stroke
				(width 0.1)
				(type default)
			)
			(layer "B.Fab")
		)
		(fp_line
			(start 0.67945 -0.305054)
			(end 0.12065 -0.305054)
			(stroke
				(width 0.1)
				(type default)
			)
			(layer "B.Fab")
		)
		(fp_line
			(start 0.12065 0.3048)
			(end 0.67945 0.3048)
			(stroke
				(width 0.1)
				(type default)
			)
			(layer "B.Fab")
		)
		(fp_line
			(start 0.12065 0.2794)
			(end 0.12065 0.3048)
			(stroke
				(width 0.1)
				(type default)
			)
			(layer "B.Fab")
		)
		(fp_line
			(start 0.12065 -0.2794)
			(end -0.12065 -0.2794)
			(stroke
				(width 0.1)
				(type default)
			)
			(layer "B.Fab")
		)
		(fp_line
			(start 0.12065 -0.305054)
			(end 0.12065 -0.2794)
			(stroke
				(width 0.1)
				(type default)
			)
			(layer "B.Fab")
		)
		(fp_line
			(start -0.120396 0.3048)
			(end -0.120396 0.2794)
			(stroke
				(width 0.1)
				(type default)
			)
			(layer "B.Fab")
		)
		(fp_line
			(start -0.120396 0.2794)
			(end 0.12065 0.2794)
			(stroke
				(width 0.1)
				(type default)
			)
			(layer "B.Fab")
		)
		(fp_line
			(start -0.12065 -0.2794)
			(end -0.12065 -0.3048)
			(stroke
				(width 0.1)
				(type default)
			)
			(layer "B.Fab")
		)
		(fp_line
			(start -0.12065 -0.3048)
			(end -0.67945 -0.3048)
			(stroke
				(width 0.1)
				(type default)
			)
			(layer "B.Fab")
		)
		(fp_line
			(start -0.67945 0.3048)
			(end -0.120396 0.3048)
			(stroke
				(width 0.1)
				(type default)
			)
			(layer "B.Fab")
		)
		(fp_line
			(start -0.67945 -0.3048)
			(end -0.67945 0.3048)
			(stroke
				(width 0.1)
				(type default)
			)
			(layer "B.Fab")
		)
		(pad "1" smd circle
			(at 0.40005 0)
			(size 0 0)
			(layers "B.Cu" "B.Mask" "B.Paste")
			(net "P3V3_M2_0")
		)
		(pad "2" smd circle
			(at -0.40005 0)
			(size 0 0)
			(layers "B.Cu" "B.Mask" "B.Paste")
			(net "GND")
		)
	)
	(footprint ""
		(layer "B.Cu")
		(at 121.944638 -263.465564)
		(property "Reference" "C2482"
			(at 0 0 0)
			(layer "B.SilkS")
			(hide yes)
			(effects
				(font
					(size 1.27 1.27)
				)
				(justify mirror)
			)
		)
		(property "Value" ""
			(at 0 0 0)
			(layer "B.Fab")
			(effects
				(font
					(size 1.27 1.27)
				)
				(justify mirror)
			)
		)
		(duplicate_pad_numbers_are_jumpers no)
		(fp_line
			(start -0.7874 -0.4064)
			(end -0.7874 0.4064)
			(stroke
				(width 0.1524)
				(type default)
			)
			(layer "B.SilkS")
		)
		(fp_line
			(start -0.7874 0.4064)
			(end 0.7874 0.4064)
			(stroke
				(width 0.1524)
				(type default)
			)
			(layer "B.SilkS")
		)
		(fp_line
			(start 0.7874 -0.4064)
			(end -0.7874 -0.4064)
			(stroke
				(width 0.1524)
				(type default)
			)
			(layer "B.SilkS")
		)
		(fp_line
			(start 0.7874 0.4064)
			(end 0.7874 -0.4064)
			(stroke
				(width 0.1524)
				(type default)
			)
			(layer "B.SilkS")
		)
		(fp_line
			(start -0.67945 -0.3048)
			(end -0.67945 0.3048)
			(stroke
				(width 0.1)
				(type default)
			)
			(layer "B.Fab")
		)
		(fp_line
			(start -0.67945 0.3048)
			(end -0.120396 0.3048)
			(stroke
				(width 0.1)
				(type default)
			)
			(layer "B.Fab")
		)
		(fp_line
			(start -0.12065 -0.3048)
			(end -0.67945 -0.3048)
			(stroke
				(width 0.1)
				(type default)
			)
			(layer "B.Fab")
		)
		(fp_line
			(start -0.12065 -0.2794)
			(end -0.12065 -0.3048)
			(stroke
				(width 0.1)
				(type default)
			)
			(layer "B.Fab")
		)
		(fp_line
			(start -0.120396 0.2794)
			(end 0.12065 0.2794)
			(stroke
				(width 0.1)
				(type default)
			)
			(layer "B.Fab")
		)
		(fp_line
			(start -0.120396 0.3048)
			(end -0.120396 0.2794)
			(stroke
				(width 0.1)
				(type default)
			)
			(layer "B.Fab")
		)
		(fp_line
			(start 0.12065 -0.305054)
			(end 0.12065 -0.2794)
			(stroke
				(width 0.1)
				(type default)
			)
			(layer "B.Fab")
		)
		(fp_line
			(start 0.12065 -0.2794)
			(end -0.12065 -0.2794)
			(stroke
				(width 0.1)
				(type default)
			)
			(layer "B.Fab")
		)
		(fp_line
			(start 0.12065 0.2794)
			(end 0.12065 0.3048)
			(stroke
				(width 0.1)
				(type default)
			)
			(layer "B.Fab")
		)
		(fp_line
			(start 0.12065 0.3048)
			(end 0.67945 0.3048)
			(stroke
				(width 0.1)
				(type default)
			)
			(layer "B.Fab")
		)
		(fp_line
			(start 0.67945 -0.305054)
			(end 0.12065 -0.305054)
			(stroke
				(width 0.1)
				(type default)
			)
			(layer "B.Fab")
		)
		(fp_line
			(start 0.67945 0.3048)
			(end 0.67945 -0.305054)
			(stroke
				(width 0.1)
				(type default)
			)
			(layer "B.Fab")
		)
		(pad "1" smd circle
			(at 0.40005 0 180)
			(size 0 0)
			(layers "B.Cu" "B.Mask" "B.Paste")
			(net "PVDD11_S3_P1")
		)
		(pad "2" smd circle
			(at -0.40005 0 180)
			(size 0 0)
			(layers "B.Cu" "B.Mask" "B.Paste")
			(net "GND")
		)
	)
	(footprint ""
		(layer "B.Cu")
		(at 349.320358 -248.47931 180)
		(property "Reference" "C4178"
			(at 0 0 0)
			(layer "B.SilkS")
			(hide yes)
			(effects
				(font
					(size 1.27 1.27)
				)
				(justify mirror)
			)
		)
		(property "Value" ""
			(at 0 0 0)
			(layer "B.Fab")
			(effects
				(font
					(size 1.27 1.27)
				)
				(justify mirror)
			)
		)
		(duplicate_pad_numbers_are_jumpers no)
		(fp_line
			(start 0.7874 0.4064)
			(end 0.7874 -0.4064)
			(stroke
				(width 0.1524)
				(type default)
			)
			(layer "B.SilkS")
		)
		(fp_line
			(start 0.7874 -0.4064)
			(end -0.7874 -0.4064)
			(stroke
				(width 0.1524)
				(type default)
			)
			(layer "B.SilkS")
		)
		(fp_line
			(start -0.7874 0.4064)
			(end 0.7874 0.4064)
			(stroke
				(width 0.1524)
				(type default)
			)
			(layer "B.SilkS")
		)
		(fp_line
			(start -0.7874 -0.4064)
			(end -0.7874 0.4064)
			(stroke
				(width 0.1524)
				(type default)
			)
			(layer "B.SilkS")
		)
		(fp_line
			(start 0.67945 0.3048)
			(end 0.67945 -0.305054)
			(stroke
				(width 0.1)
				(type default)
			)
			(layer "B.Fab")
		)
		(fp_line
			(start 0.67945 -0.305054)
			(end 0.12065 -0.305054)
			(stroke
				(width 0.1)
				(type default)
			)
			(layer "B.Fab")
		)
		(fp_line
			(start 0.12065 0.3048)
			(end 0.67945 0.3048)
			(stroke
				(width 0.1)
				(type default)
			)
			(layer "B.Fab")
		)
		(fp_line
			(start 0.12065 0.2794)
			(end 0.12065 0.3048)
			(stroke
				(width 0.1)
				(type default)
			)
			(layer "B.Fab")
		)
		(fp_line
			(start 0.12065 -0.2794)
			(end -0.12065 -0.2794)
			(stroke
				(width 0.1)
				(type default)
			)
			(layer "B.Fab")
		)
		(fp_line
			(start 0.12065 -0.305054)
			(end 0.12065 -0.2794)
			(stroke
				(width 0.1)
				(type default)
			)
			(layer "B.Fab")
		)
		(fp_line
			(start -0.120396 0.3048)
			(end -0.120396 0.2794)
			(stroke
				(width 0.1)
				(type default)
			)
			(layer "B.Fab")
		)
		(fp_line
			(start -0.120396 0.2794)
			(end 0.12065 0.2794)
			(stroke
				(width 0.1)
				(type default)
			)
			(layer "B.Fab")
		)
		(fp_line
			(start -0.12065 -0.2794)
			(end -0.12065 -0.3048)
			(stroke
				(width 0.1)
				(type default)
			)
			(layer "B.Fab")
		)
		(fp_line
			(start -0.12065 -0.3048)
			(end -0.67945 -0.3048)
			(stroke
				(width 0.1)
				(type default)
			)
			(layer "B.Fab")
		)
		(fp_line
			(start -0.67945 0.3048)
			(end -0.120396 0.3048)
			(stroke
				(width 0.1)
				(type default)
			)
			(layer "B.Fab")
		)
		(fp_line
			(start -0.67945 -0.3048)
			(end -0.67945 0.3048)
			(stroke
				(width 0.1)
				(type default)
			)
			(layer "B.Fab")
		)
		(pad "1" smd circle
			(at 0.40005 0)
			(size 0 0)
			(layers "B.Cu" "B.Mask" "B.Paste")
			(net "PVDDCR_CPU0_P0")
		)
		(pad "2" smd circle
			(at -0.40005 0)
			(size 0 0)
			(layers "B.Cu" "B.Mask" "B.Paste")
			(net "GND")
		)
	)
	(footprint ""
		(layer "B.Cu")
		(at 119.674386 -266.005564)
		(property "Reference" "C2481"
			(at 0 0 0)
			(layer "B.SilkS")
			(hide yes)
			(effects
				(font
					(size 1.27 1.27)
				)
				(justify mirror)
			)
		)
		(property "Value" ""
			(at 0 0 0)
			(layer "B.Fab")
			(effects
				(font
					(size 1.27 1.27)
				)
				(justify mirror)
			)
		)
		(duplicate_pad_numbers_are_jumpers no)
		(fp_line
			(start -0.7874 -0.4064)
			(end -0.7874 0.4064)
			(stroke
				(width 0.1524)
				(type default)
			)
			(layer "B.SilkS")
		)
		(fp_line
			(start -0.7874 0.4064)
			(end 0.7874 0.4064)
			(stroke
				(width 0.1524)
				(type default)
			)
			(layer "B.SilkS")
		)
		(fp_line
			(start 0.7874 -0.4064)
			(end -0.7874 -0.4064)
			(stroke
				(width 0.1524)
				(type default)
			)
			(layer "B.SilkS")
		)
		(fp_line
			(start 0.7874 0.4064)
			(end 0.7874 -0.4064)
			(stroke
				(width 0.1524)
				(type default)
			)
			(layer "B.SilkS")
		)
		(fp_line
			(start -0.67945 -0.3048)
			(end -0.67945 0.3048)
			(stroke
				(width 0.1)
				(type default)
			)
			(layer "B.Fab")
		)
		(fp_line
			(start -0.67945 0.3048)
			(end -0.120396 0.3048)
			(stroke
				(width 0.1)
				(type default)
			)
			(layer "B.Fab")
		)
		(fp_line
			(start -0.12065 -0.3048)
			(end -0.67945 -0.3048)
			(stroke
				(width 0.1)
				(type default)
			)
			(layer "B.Fab")
		)
		(fp_line
			(start -0.12065 -0.2794)
			(end -0.12065 -0.3048)
			(stroke
				(width 0.1)
				(type default)
			)
			(layer "B.Fab")
		)
		(fp_line
			(start -0.120396 0.2794)
			(end 0.12065 0.2794)
			(stroke
				(width 0.1)
				(type default)
			)
			(layer "B.Fab")
		)
		(fp_line
			(start -0.120396 0.3048)
			(end -0.120396 0.2794)
			(stroke
				(width 0.1)
				(type default)
			)
			(layer "B.Fab")
		)
		(fp_line
			(start 0.12065 -0.305054)
			(end 0.12065 -0.2794)
			(stroke
				(width 0.1)
				(type default)
			)
			(layer "B.Fab")
		)
		(fp_line
			(start 0.12065 -0.2794)
			(end -0.12065 -0.2794)
			(stroke
				(width 0.1)
				(type default)
			)
			(layer "B.Fab")
		)
		(fp_line
			(start 0.12065 0.2794)
			(end 0.12065 0.3048)
			(stroke
				(width 0.1)
				(type default)
			)
			(layer "B.Fab")
		)
		(fp_line
			(start 0.12065 0.3048)
			(end 0.67945 0.3048)
			(stroke
				(width 0.1)
				(type default)
			)
			(layer "B.Fab")
		)
		(fp_line
			(start 0.67945 -0.305054)
			(end 0.12065 -0.305054)
			(stroke
				(width 0.1)
				(type default)
			)
			(layer "B.Fab")
		)
		(fp_line
			(start 0.67945 0.3048)
			(end 0.67945 -0.305054)
			(stroke
				(width 0.1)
				(type default)
			)
			(layer "B.Fab")
		)
		(pad "1" smd circle
			(at 0.40005 0 180)
			(size 0 0)
			(layers "B.Cu" "B.Mask" "B.Paste")
			(net "PVDD11_S3_P1")
		)
		(pad "2" smd circle
			(at -0.40005 0 180)
			(size 0 0)
			(layers "B.Cu" "B.Mask" "B.Paste")
			(net "GND")
		)
	)
	(footprint ""
		(layer "B.Cu")
		(at 45.332396 -337.989672 -90)
		(property "Reference" "PC460_2"
			(at 0 0 90)
			(layer "B.SilkS")
			(hide yes)
			(effects
				(font
					(size 1.27 1.27)
				)
				(justify mirror)
			)
		)
		(property "Value" ""
			(at 0 0 90)
			(layer "B.Fab")
			(effects
				(font
					(size 1.27 1.27)
				)
				(justify mirror)
			)
		)
		(duplicate_pad_numbers_are_jumpers no)
		(fp_line
			(start -1.524 0.762)
			(end 1.524 0.762)
			(stroke
				(width 0.1524)
				(type default)
			)
			(layer "B.SilkS")
		)
		(fp_line
			(start 1.524 0.762)
			(end 1.524 -0.762)
			(stroke
				(width 0.1524)
				(type default)
			)
			(layer "B.SilkS")
		)
		(fp_line
			(start -1.524 -0.762)
			(end -1.524 0.762)
			(stroke
				(width 0.1524)
				(type default)
			)
			(layer "B.SilkS")
		)
		(fp_line
			(start 1.524 -0.762)
			(end -1.524 -0.762)
			(stroke
				(width 0.1524)
				(type default)
			)
			(layer "B.SilkS")
		)
		(fp_line
			(start -1.1049 0.724916)
			(end -1.1049 -0.724916)
			(stroke
				(width 0.1)
				(type default)
			)
			(layer "B.Fab")
		)
		(fp_line
			(start 1.1049 0.724916)
			(end -1.1049 0.724916)
			(stroke
				(width 0.1)
				(type default)
			)
			(layer "B.Fab")
		)
		(fp_line
			(start -1.1049 -0.724916)
			(end 1.1049 -0.724916)
			(stroke
				(width 0.1)
				(type default)
			)
			(layer "B.Fab")
		)
		(fp_line
			(start 1.1049 -0.724916)
			(end 1.1049 0.724916)
			(stroke
				(width 0.1)
				(type default)
			)
			(layer "B.Fab")
		)
		(pad "1" smd rect
			(at 0.889 0 270)
			(size 1.016 1.27)
			(layers "B.Cu" "B.Mask" "B.Paste")
			(net "PVDDIO_P1")
		)
		(pad "2" smd rect
			(at -0.889 0 270)
			(size 1.016 1.27)
			(layers "B.Cu" "B.Mask" "B.Paste")
			(net "GND")
		)
	)
	(footprint ""
		(layer "B.Cu")
		(at 12.720574 -373.339614 90)
		(property "Reference" "PC6626"
			(at -3.515614 -3.095244 270)
			(unlocked yes)
			(layer "B.SilkS")
			(effects
				(font
					(size 0.7874 0.5842)
					(thickness 0.1524)
				)
				(justify left mirror)
			)
		)
		(property "Value" ""
			(at 0 0 90)
			(layer "B.Fab")
			(effects
				(font
					(size 1.27 1.27)
				)
				(justify mirror)
			)
		)
		(duplicate_pad_numbers_are_jumpers no)
		(fp_line
			(start 4.84378 -2.150618)
			(end 4.53898 -2.150618)
			(stroke
				(width 0.1524)
				(type default)
			)
			(layer "B.SilkS")
		)
		(fp_line
			(start 4.84378 -2.150618)
			(end 4.842256 2.163064)
			(stroke
				(width 0.1524)
				(type default)
			)
			(layer "B.SilkS")
		)
		(fp_line
			(start 4.69138 -2.150618)
			(end 4.692396 2.161032)
			(stroke
				(width 0.1524)
				(type default)
			)
			(layer "B.SilkS")
		)
		(fp_line
			(start 4.53898 -2.150618)
			(end 4.539742 2.152142)
			(stroke
				(width 0.1524)
				(type default)
			)
			(layer "B.SilkS")
		)
		(fp_line
			(start 4.53898 -2.15011)
			(end -4.53898 -2.15011)
			(stroke
				(width 0.1524)
				(type default)
			)
			(layer "B.SilkS")
		)
		(fp_line
			(start -4.53898 -2.15011)
			(end -4.53898 2.15011)
			(stroke
				(width 0.1524)
				(type default)
			)
			(layer "B.SilkS")
		)
		(fp_line
			(start 4.53898 2.15011)
			(end 4.53898 -2.15011)
			(stroke
				(width 0.1524)
				(type default)
			)
			(layer "B.SilkS")
		)
		(fp_line
			(start -4.53898 2.15011)
			(end 4.53898 2.15011)
			(stroke
				(width 0.1524)
				(type default)
			)
			(layer "B.SilkS")
		)
		(fp_line
			(start 4.83108 2.150364)
			(end 4.447794 2.149348)
			(stroke
				(width 0.1524)
				(type default)
			)
			(layer "B.SilkS")
		)
		(fp_line
			(start 3.64998 -2.15011)
			(end -3.64998 -2.15011)
			(stroke
				(width 0.1)
				(type default)
			)
			(layer "B.Fab")
		)
		(fp_line
			(start -3.64998 -2.15011)
			(end -3.64998 2.15011)
			(stroke
				(width 0.1)
				(type default)
			)
			(layer "B.Fab")
		)
		(fp_line
			(start 3.64998 2.15011)
			(end 3.64998 -2.15011)
			(stroke
				(width 0.1)
				(type default)
			)
			(layer "B.Fab")
		)
		(fp_line
			(start -3.64998 2.15011)
			(end 3.64998 2.15011)
			(stroke
				(width 0.1)
				(type default)
			)
			(layer "B.Fab")
		)
		(fp_text user "+"
			(at 5.206746 -2.983484 90)
			(unlocked yes)
			(layer "B.SilkS")
			(effects
				(font
					(size 1.905 1.4224)
					(thickness 0.1524)
				)
				(justify left mirror)
			)
		)
		(fp_text user "-"
			(at -4.313174 -0.094488 90)
			(unlocked yes)
			(layer "B.SilkS")
			(effects
				(font
					(size 1.905 1.4224)
					(thickness 0.1524)
				)
				(justify left mirror)
			)
		)
		(fp_text user "+"
			(at 6.214872 -0.337058 90)
			(unlocked yes)
			(layer "B.Fab")
			(effects
				(font
					(size 1.905 1.4224)
					(thickness 0.1524)
				)
				(justify left mirror)
			)
		)
		(fp_text user "-"
			(at -4.313174 -0.094488 90)
			(unlocked yes)
			(layer "B.Fab")
			(effects
				(font
					(size 1.905 1.4224)
					(thickness 0.1524)
				)
				(justify left mirror)
			)
		)
		(pad "1" smd rect
			(at 3.199892 0 270)
			(size 2.413 2.8194)
			(layers "B.Cu" "B.Mask" "B.Paste")
			(net "P0V9_CPU1_RT_2D")
		)
		(pad "2" smd rect
			(at -3.199892 0 270)
			(size 2.413 2.8194)
			(layers "B.Cu" "B.Mask" "B.Paste")
			(net "GND")
		)
	)
	(footprint ""
		(layer "B.Cu")
		(at 183.769 -100.294948 -90)
		(property "Reference" "R959"
			(at 0 0 90)
			(layer "B.SilkS")
			(hide yes)
			(effects
				(font
					(size 1.27 1.27)
				)
				(justify mirror)
			)
		)
		(property "Value" ""
			(at 0 0 90)
			(layer "B.Fab")
			(effects
				(font
					(size 1.27 1.27)
				)
				(justify mirror)
			)
		)
		(duplicate_pad_numbers_are_jumpers no)
		(fp_line
			(start -0.7874 0.4064)
			(end 0.7874 0.4064)
			(stroke
				(width 0.1524)
				(type default)
			)
			(layer "B.SilkS")
		)
		(fp_line
			(start 0.7874 0.4064)
			(end 0.7874 -0.4064)
			(stroke
				(width 0.1524)
				(type default)
			)
			(layer "B.SilkS")
		)
		(fp_line
			(start -0.7874 -0.4064)
			(end -0.7874 0.4064)
			(stroke
				(width 0.1524)
				(type default)
			)
			(layer "B.SilkS")
		)
		(fp_line
			(start 0.7874 -0.4064)
			(end -0.7874 -0.4064)
			(stroke
				(width 0.1524)
				(type default)
			)
			(layer "B.SilkS")
		)
		(fp_line
			(start -0.67945 0.3048)
			(end -0.120396 0.3048)
			(stroke
				(width 0.1)
				(type default)
			)
			(layer "B.Fab")
		)
		(fp_line
			(start -0.120396 0.3048)
			(end -0.120396 0.2794)
			(stroke
				(width 0.1)
				(type default)
			)
			(layer "B.Fab")
		)
		(fp_line
			(start 0.12065 0.3048)
			(end 0.67945 0.3048)
			(stroke
				(width 0.1)
				(type default)
			)
			(layer "B.Fab")
		)
		(fp_line
			(start 0.67945 0.3048)
			(end 0.67945 -0.305054)
			(stroke
				(width 0.1)
				(type default)
			)
			(layer "B.Fab")
		)
		(fp_line
			(start -0.120396 0.2794)
			(end 0.12065 0.2794)
			(stroke
				(width 0.1)
				(type default)
			)
			(layer "B.Fab")
		)
		(fp_line
			(start 0.12065 0.2794)
			(end 0.12065 0.3048)
			(stroke
				(width 0.1)
				(type default)
			)
			(layer "B.Fab")
		)
		(fp_line
			(start -0.12065 -0.2794)
			(end -0.12065 -0.3048)
			(stroke
				(width 0.1)
				(type default)
			)
			(layer "B.Fab")
		)
		(fp_line
			(start 0.12065 -0.2794)
			(end -0.12065 -0.2794)
			(stroke
				(width 0.1)
				(type default)
			)
			(layer "B.Fab")
		)
		(fp_line
			(start -0.67945 -0.3048)
			(end -0.67945 0.3048)
			(stroke
				(width 0.1)
				(type default)
			)
			(layer "B.Fab")
		)
		(fp_line
			(start -0.12065 -0.3048)
			(end -0.67945 -0.3048)
			(stroke
				(width 0.1)
				(type default)
			)
			(layer "B.Fab")
		)
		(fp_line
			(start 0.12065 -0.305054)
			(end 0.12065 -0.2794)
			(stroke
				(width 0.1)
				(type default)
			)
			(layer "B.Fab")
		)
		(fp_line
			(start 0.67945 -0.305054)
			(end 0.12065 -0.305054)
			(stroke
				(width 0.1)
				(type default)
			)
			(layer "B.Fab")
		)
		(pad "1" smd circle
			(at 0.40005 0 90)
			(size 0 0)
			(layers "B.Cu" "B.Mask" "B.Paste")
			(net "OCP_SFF_MAIN_PWR_EN")
		)
		(pad "2" smd circle
			(at -0.40005 0 90)
			(size 0 0)
			(layers "B.Cu" "B.Mask" "B.Paste")
			(net "FM_PLD_OCP_SFF_MAIN_PWR_EN_R")
		)
	)
	(footprint ""
		(layer "B.Cu")
		(at 418.746178 -396.393162 -90)
		(property "Reference" "C804"
			(at 0 0 90)
			(layer "B.SilkS")
			(hide yes)
			(effects
				(font
					(size 1.27 1.27)
				)
				(justify mirror)
			)
		)
		(property "Value" ""
			(at 0 0 90)
			(layer "B.Fab")
			(effects
				(font
					(size 1.27 1.27)
				)
				(justify mirror)
			)
		)
		(duplicate_pad_numbers_are_jumpers no)
		(fp_line
			(start -0.299974 0.150114)
			(end 0.299974 0.150114)
			(stroke
				(width 0.1)
				(type default)
			)
			(layer "B.Fab")
		)
		(fp_line
			(start 0.299974 0.150114)
			(end 0.299974 -0.150114)
			(stroke
				(width 0.1)
				(type default)
			)
			(layer "B.Fab")
		)
		(fp_line
			(start -0.299974 -0.150114)
			(end -0.299974 0.150114)
			(stroke
				(width 0.1)
				(type default)
			)
			(layer "B.Fab")
		)
		(fp_line
			(start 0.299974 -0.150114)
			(end -0.299974 -0.150114)
			(stroke
				(width 0.1)
				(type default)
			)
			(layer "B.Fab")
		)
		(pad "1" smd rect
			(at 0.2667 0 90)
			(size 0.3048 0.381)
			(layers "B.Cu" "B.Mask" "B.Paste")
			(net "P0V9_CPU0_RT2_2A")
		)
		(pad "2" smd rect
			(at -0.2667 0 90)
			(size 0.3048 0.381)
			(layers "B.Cu" "B.Mask" "B.Paste")
			(net "GND")
		)
	)
	(footprint ""
		(layer "B.Cu")
		(at 229.8446 -340.868 180)
		(property "Reference" "R6755"
			(at 0 0 0)
			(layer "B.SilkS")
			(hide yes)
			(effects
				(font
					(size 1.27 1.27)
				)
				(justify mirror)
			)
		)
		(property "Value" ""
			(at 0 0 0)
			(layer "B.Fab")
			(effects
				(font
					(size 1.27 1.27)
				)
				(justify mirror)
			)
		)
		(duplicate_pad_numbers_are_jumpers no)
		(fp_line
			(start 0.32512 0.175006)
			(end 0.32512 -0.175006)
			(stroke
				(width 0.1)
				(type default)
			)
			(layer "B.Fab")
		)
		(fp_line
			(start 0.32512 -0.175006)
			(end -0.32512 -0.175006)
			(stroke
				(width 0.1)
				(type default)
			)
			(layer "B.Fab")
		)
		(fp_line
			(start -0.32512 0.175006)
			(end 0.32512 0.175006)
			(stroke
				(width 0.1)
				(type default)
			)
			(layer "B.Fab")
		)
		(fp_line
			(start -0.32512 -0.175006)
			(end -0.32512 0.175006)
			(stroke
				(width 0.1)
				(type default)
			)
			(layer "B.Fab")
		)
		(pad "1" smd rect
			(at 0.2667 0)
			(size 0.3048 0.381)
			(layers "B.Cu" "B.Mask" "B.Paste")
			(net "SMB_RT_CPU0_P0_SCL")
		)
		(pad "2" smd rect
			(at -0.2667 0 180)
			(size 0.3048 0.381)
			(layers "B.Cu" "B.Mask" "B.Paste")
			(net "SMB_RT_CPU0_P0_R_SCL")
		)
	)
	(footprint ""
		(layer "B.Cu")
		(at 147.947126 -408.517344 90)
		(property "Reference" "C6745"
			(at 0 0 90)
			(layer "B.SilkS")
			(hide yes)
			(effects
				(font
					(size 1.27 1.27)
				)
				(justify mirror)
			)
		)
		(property "Value" ""
			(at 0 0 90)
			(layer "B.Fab")
			(effects
				(font
					(size 1.27 1.27)
				)
				(justify mirror)
			)
		)
		(duplicate_pad_numbers_are_jumpers no)
		(fp_line
			(start 0.299974 -0.150114)
			(end -0.299974 -0.150114)
			(stroke
				(width 0.1)
				(type default)
			)
			(layer "B.Fab")
		)
		(fp_line
			(start -0.299974 -0.150114)
			(end -0.299974 0.150114)
			(stroke
				(width 0.1)
				(type default)
			)
			(layer "B.Fab")
		)
		(fp_line
			(start 0.299974 0.150114)
			(end 0.299974 -0.150114)
			(stroke
				(width 0.1)
				(type default)
			)
			(layer "B.Fab")
		)
		(fp_line
			(start -0.299974 0.150114)
			(end 0.299974 0.150114)
			(stroke
				(width 0.1)
				(type default)
			)
			(layer "B.Fab")
		)
		(pad "1" smd rect
			(at 0.2667 0 270)
			(size 0.3048 0.381)
			(layers "B.Cu" "B.Mask" "B.Paste")
			(net "P5E_CPU1_P3_TX_BUF_C_DP<10>")
		)
		(pad "2" smd rect
			(at -0.2667 0 270)
			(size 0.3048 0.381)
			(layers "B.Cu" "B.Mask" "B.Paste")
			(net "P5E_CPU1_P3_TX_BUF_DP<10>")
		)
	)
	(footprint ""
		(layer "B.Cu")
		(at 379.520958 -208.530952 90)
		(property "Reference" "C211"
			(at 0 0 90)
			(layer "B.SilkS")
			(hide yes)
			(effects
				(font
					(size 1.27 1.27)
				)
				(justify mirror)
			)
		)
		(property "Value" ""
			(at 0 0 90)
			(layer "B.Fab")
			(effects
				(font
					(size 1.27 1.27)
				)
				(justify mirror)
			)
		)
		(duplicate_pad_numbers_are_jumpers no)
		(fp_line
			(start 0.7874 -0.4064)
			(end -0.7874 -0.4064)
			(stroke
				(width 0.1524)
				(type default)
			)
			(layer "B.SilkS")
		)
		(fp_line
			(start -0.7874 -0.4064)
			(end -0.7874 0.4064)
			(stroke
				(width 0.1524)
				(type default)
			)
			(layer "B.SilkS")
		)
		(fp_line
			(start 0.7874 0.4064)
			(end 0.7874 -0.4064)
			(stroke
				(width 0.1524)
				(type default)
			)
			(layer "B.SilkS")
		)
		(fp_line
			(start -0.7874 0.4064)
			(end 0.7874 0.4064)
			(stroke
				(width 0.1524)
				(type default)
			)
			(layer "B.SilkS")
		)
		(fp_line
			(start 0.67945 -0.305054)
			(end 0.12065 -0.305054)
			(stroke
				(width 0.1)
				(type default)
			)
			(layer "B.Fab")
		)
		(fp_line
			(start 0.12065 -0.305054)
			(end 0.12065 -0.2794)
			(stroke
				(width 0.1)
				(type default)
			)
			(layer "B.Fab")
		)
		(fp_line
			(start -0.12065 -0.3048)
			(end -0.67945 -0.3048)
			(stroke
				(width 0.1)
				(type default)
			)
			(layer "B.Fab")
		)
		(fp_line
			(start -0.67945 -0.3048)
			(end -0.67945 0.3048)
			(stroke
				(width 0.1)
				(type default)
			)
			(layer "B.Fab")
		)
		(fp_line
			(start 0.12065 -0.2794)
			(end -0.12065 -0.2794)
			(stroke
				(width 0.1)
				(type default)
			)
			(layer "B.Fab")
		)
		(fp_line
			(start -0.12065 -0.2794)
			(end -0.12065 -0.3048)
			(stroke
				(width 0.1)
				(type default)
			)
			(layer "B.Fab")
		)
		(fp_line
			(start 0.12065 0.2794)
			(end 0.12065 0.3048)
			(stroke
				(width 0.1)
				(type default)
			)
			(layer "B.Fab")
		)
		(fp_line
			(start -0.120396 0.2794)
			(end 0.12065 0.2794)
			(stroke
				(width 0.1)
				(type default)
			)
			(layer "B.Fab")
		)
		(fp_line
			(start 0.67945 0.3048)
			(end 0.67945 -0.305054)
			(stroke
				(width 0.1)
				(type default)
			)
			(layer "B.Fab")
		)
		(fp_line
			(start 0.12065 0.3048)
			(end 0.67945 0.3048)
			(stroke
				(width 0.1)
				(type default)
			)
			(layer "B.Fab")
		)
		(fp_line
			(start -0.120396 0.3048)
			(end -0.120396 0.2794)
			(stroke
				(width 0.1)
				(type default)
			)
			(layer "B.Fab")
		)
		(fp_line
			(start -0.67945 0.3048)
			(end -0.120396 0.3048)
			(stroke
				(width 0.1)
				(type default)
			)
			(layer "B.Fab")
		)
		(pad "1" smd circle
			(at 0.40005 0 270)
			(size 0 0)
			(layers "B.Cu" "B.Mask" "B.Paste")
			(net "JTAG_CPU0_TMS")
		)
		(pad "2" smd circle
			(at -0.40005 0 270)
			(size 0 0)
			(layers "B.Cu" "B.Mask" "B.Paste")
			(net "GND")
		)
	)
	(footprint ""
		(layer "B.Cu")
		(at 331.639164 -136.474962 180)
		(property "Reference" "PR477"
			(at 0 0 0)
			(layer "B.SilkS")
			(hide yes)
			(effects
				(font
					(size 1.27 1.27)
				)
				(justify mirror)
			)
		)
		(property "Value" ""
			(at 0 0 0)
			(layer "B.Fab")
			(effects
				(font
					(size 1.27 1.27)
				)
				(justify mirror)
			)
		)
		(duplicate_pad_numbers_are_jumpers no)
		(fp_line
			(start 0.7874 0.4064)
			(end 0.7874 -0.4064)
			(stroke
				(width 0.1524)
				(type default)
			)
			(layer "B.SilkS")
		)
		(fp_line
			(start 0.7874 -0.4064)
			(end -0.7874 -0.4064)
			(stroke
				(width 0.1524)
				(type default)
			)
			(layer "B.SilkS")
		)
		(fp_line
			(start -0.7874 0.4064)
			(end 0.7874 0.4064)
			(stroke
				(width 0.1524)
				(type default)
			)
			(layer "B.SilkS")
		)
		(fp_line
			(start -0.7874 -0.4064)
			(end -0.7874 0.4064)
			(stroke
				(width 0.1524)
				(type default)
			)
			(layer "B.SilkS")
		)
		(fp_line
			(start 0.67945 0.3048)
			(end 0.67945 -0.305054)
			(stroke
				(width 0.1)
				(type default)
			)
			(layer "B.Fab")
		)
		(fp_line
			(start 0.67945 -0.305054)
			(end 0.12065 -0.305054)
			(stroke
				(width 0.1)
				(type default)
			)
			(layer "B.Fab")
		)
		(fp_line
			(start 0.12065 0.3048)
			(end 0.67945 0.3048)
			(stroke
				(width 0.1)
				(type default)
			)
			(layer "B.Fab")
		)
		(fp_line
			(start 0.12065 0.2794)
			(end 0.12065 0.3048)
			(stroke
				(width 0.1)
				(type default)
			)
			(layer "B.Fab")
		)
		(fp_line
			(start 0.12065 -0.2794)
			(end -0.12065 -0.2794)
			(stroke
				(width 0.1)
				(type default)
			)
			(layer "B.Fab")
		)
		(fp_line
			(start 0.12065 -0.305054)
			(end 0.12065 -0.2794)
			(stroke
				(width 0.1)
				(type default)
			)
			(layer "B.Fab")
		)
		(fp_line
			(start -0.120396 0.3048)
			(end -0.120396 0.2794)
			(stroke
				(width 0.1)
				(type default)
			)
			(layer "B.Fab")
		)
		(fp_line
			(start -0.120396 0.2794)
			(end 0.12065 0.2794)
			(stroke
				(width 0.1)
				(type default)
			)
			(layer "B.Fab")
		)
		(fp_line
			(start -0.12065 -0.2794)
			(end -0.12065 -0.3048)
			(stroke
				(width 0.1)
				(type default)
			)
			(layer "B.Fab")
		)
		(fp_line
			(start -0.12065 -0.3048)
			(end -0.67945 -0.3048)
			(stroke
				(width 0.1)
				(type default)
			)
			(layer "B.Fab")
		)
		(fp_line
			(start -0.67945 0.3048)
			(end -0.120396 0.3048)
			(stroke
				(width 0.1)
				(type default)
			)
			(layer "B.Fab")
		)
		(fp_line
			(start -0.67945 -0.3048)
			(end -0.67945 0.3048)
			(stroke
				(width 0.1)
				(type default)
			)
			(layer "B.Fab")
		)
		(pad "1" smd circle
			(at 0.40005 0)
			(size 0 0)
			(layers "B.Cu" "B.Mask" "B.Paste")
			(net "P3V3_AUX")
		)
		(pad "2" smd circle
			(at -0.40005 0)
			(size 0 0)
			(layers "B.Cu" "B.Mask" "B.Paste")
			(net "PVDD18_S5_P0_VCC")
		)
	)
	(footprint ""
		(layer "B.Cu")
		(at 393.602718 -323.692012)
		(property "Reference" "R468"
			(at 0 0 0)
			(layer "B.SilkS")
			(hide yes)
			(effects
				(font
					(size 1.27 1.27)
				)
				(justify mirror)
			)
		)
		(property "Value" ""
			(at 0 0 0)
			(layer "B.Fab")
			(effects
				(font
					(size 1.27 1.27)
				)
				(justify mirror)
			)
		)
		(duplicate_pad_numbers_are_jumpers no)
		(fp_line
			(start -0.7874 -0.4064)
			(end -0.7874 0.4064)
			(stroke
				(width 0.1524)
				(type default)
			)
			(layer "B.SilkS")
		)
		(fp_line
			(start -0.7874 0.4064)
			(end 0.7874 0.4064)
			(stroke
				(width 0.1524)
				(type default)
			)
			(layer "B.SilkS")
		)
		(fp_line
			(start 0.7874 -0.4064)
			(end -0.7874 -0.4064)
			(stroke
				(width 0.1524)
				(type default)
			)
			(layer "B.SilkS")
		)
		(fp_line
			(start 0.7874 0.4064)
			(end 0.7874 -0.4064)
			(stroke
				(width 0.1524)
				(type default)
			)
			(layer "B.SilkS")
		)
		(fp_line
			(start -0.67945 -0.3048)
			(end -0.67945 0.3048)
			(stroke
				(width 0.1)
				(type default)
			)
			(layer "B.Fab")
		)
		(fp_line
			(start -0.67945 0.3048)
			(end -0.120396 0.3048)
			(stroke
				(width 0.1)
				(type default)
			)
			(layer "B.Fab")
		)
		(fp_line
			(start -0.12065 -0.3048)
			(end -0.67945 -0.3048)
			(stroke
				(width 0.1)
				(type default)
			)
			(layer "B.Fab")
		)
		(fp_line
			(start -0.12065 -0.2794)
			(end -0.12065 -0.3048)
			(stroke
				(width 0.1)
				(type default)
			)
			(layer "B.Fab")
		)
		(fp_line
			(start -0.120396 0.2794)
			(end 0.12065 0.2794)
			(stroke
				(width 0.1)
				(type default)
			)
			(layer "B.Fab")
		)
		(fp_line
			(start -0.120396 0.3048)
			(end -0.120396 0.2794)
			(stroke
				(width 0.1)
				(type default)
			)
			(layer "B.Fab")
		)
		(fp_line
			(start 0.12065 -0.305054)
			(end 0.12065 -0.2794)
			(stroke
				(width 0.1)
				(type default)
			)
			(layer "B.Fab")
		)
		(fp_line
			(start 0.12065 -0.2794)
			(end -0.12065 -0.2794)
			(stroke
				(width 0.1)
				(type default)
			)
			(layer "B.Fab")
		)
		(fp_line
			(start 0.12065 0.2794)
			(end 0.12065 0.3048)
			(stroke
				(width 0.1)
				(type default)
			)
			(layer "B.Fab")
		)
		(fp_line
			(start 0.12065 0.3048)
			(end 0.67945 0.3048)
			(stroke
				(width 0.1)
				(type default)
			)
			(layer "B.Fab")
		)
		(fp_line
			(start 0.67945 -0.305054)
			(end 0.12065 -0.305054)
			(stroke
				(width 0.1)
				(type default)
			)
			(layer "B.Fab")
		)
		(fp_line
			(start 0.67945 0.3048)
			(end 0.67945 -0.305054)
			(stroke
				(width 0.1)
				(type default)
			)
			(layer "B.Fab")
		)
		(pad "1" smd circle
			(at 0.40005 0 180)
			(size 0 0)
			(layers "B.Cu" "B.Mask" "B.Paste")
			(net "ESPI_CPU0_D0")
		)
		(pad "2" smd circle
			(at -0.40005 0 180)
			(size 0 0)
			(layers "B.Cu" "B.Mask" "B.Paste")
			(net "ESPI_CPU0_R_D0")
		)
	)
	(footprint ""
		(layer "B.Cu")
		(at 233.172 -336.296 180)
		(property "Reference" "R1109"
			(at 0 0 0)
			(layer "B.SilkS")
			(hide yes)
			(effects
				(font
					(size 1.27 1.27)
				)
				(justify mirror)
			)
		)
		(property "Value" ""
			(at 0 0 0)
			(layer "B.Fab")
			(effects
				(font
					(size 1.27 1.27)
				)
				(justify mirror)
			)
		)
		(duplicate_pad_numbers_are_jumpers no)
		(fp_line
			(start 0.32512 0.175006)
			(end 0.32512 -0.175006)
			(stroke
				(width 0.1)
				(type default)
			)
			(layer "B.Fab")
		)
		(fp_line
			(start 0.32512 -0.175006)
			(end -0.32512 -0.175006)
			(stroke
				(width 0.1)
				(type default)
			)
			(layer "B.Fab")
		)
		(fp_line
			(start -0.32512 0.175006)
			(end 0.32512 0.175006)
			(stroke
				(width 0.1)
				(type default)
			)
			(layer "B.Fab")
		)
		(fp_line
			(start -0.32512 -0.175006)
			(end -0.32512 0.175006)
			(stroke
				(width 0.1)
				(type default)
			)
			(layer "B.Fab")
		)
		(pad "1" smd rect
			(at 0.2667 0)
			(size 0.3048 0.381)
			(layers "B.Cu" "B.Mask" "B.Paste")
			(net "SMB_RT_CPU0_P3_R_SCL")
		)
		(pad "2" smd rect
			(at -0.2667 0 180)
			(size 0.3048 0.381)
			(layers "B.Cu" "B.Mask" "B.Paste")
			(net "SMB_RT_CPU0_P3_R2_SCL")
		)
	)
	(footprint ""
		(layer "B.Cu")
		(at 456.690476 -45.978826 -90)
		(property "Reference" "R3117"
			(at 0 0 90)
			(layer "B.SilkS")
			(hide yes)
			(effects
				(font
					(size 1.27 1.27)
				)
				(justify mirror)
			)
		)
		(property "Value" ""
			(at 0 0 90)
			(layer "B.Fab")
			(effects
				(font
					(size 1.27 1.27)
				)
				(justify mirror)
			)
		)
		(duplicate_pad_numbers_are_jumpers no)
		(fp_line
			(start -0.7874 0.4064)
			(end 0.7874 0.4064)
			(stroke
				(width 0.1524)
				(type default)
			)
			(layer "B.SilkS")
		)
		(fp_line
			(start 0.7874 0.4064)
			(end 0.7874 -0.4064)
			(stroke
				(width 0.1524)
				(type default)
			)
			(layer "B.SilkS")
		)
		(fp_line
			(start -0.7874 -0.4064)
			(end -0.7874 0.4064)
			(stroke
				(width 0.1524)
				(type default)
			)
			(layer "B.SilkS")
		)
		(fp_line
			(start 0.7874 -0.4064)
			(end -0.7874 -0.4064)
			(stroke
				(width 0.1524)
				(type default)
			)
			(layer "B.SilkS")
		)
		(fp_line
			(start -0.67945 0.3048)
			(end -0.120396 0.3048)
			(stroke
				(width 0.1)
				(type default)
			)
			(layer "B.Fab")
		)
		(fp_line
			(start -0.120396 0.3048)
			(end -0.120396 0.2794)
			(stroke
				(width 0.1)
				(type default)
			)
			(layer "B.Fab")
		)
		(fp_line
			(start 0.12065 0.3048)
			(end 0.67945 0.3048)
			(stroke
				(width 0.1)
				(type default)
			)
			(layer "B.Fab")
		)
		(fp_line
			(start 0.67945 0.3048)
			(end 0.67945 -0.305054)
			(stroke
				(width 0.1)
				(type default)
			)
			(layer "B.Fab")
		)
		(fp_line
			(start -0.120396 0.2794)
			(end 0.12065 0.2794)
			(stroke
				(width 0.1)
				(type default)
			)
			(layer "B.Fab")
		)
		(fp_line
			(start 0.12065 0.2794)
			(end 0.12065 0.3048)
			(stroke
				(width 0.1)
				(type default)
			)
			(layer "B.Fab")
		)
		(fp_line
			(start -0.12065 -0.2794)
			(end -0.12065 -0.3048)
			(stroke
				(width 0.1)
				(type default)
			)
			(layer "B.Fab")
		)
		(fp_line
			(start 0.12065 -0.2794)
			(end -0.12065 -0.2794)
			(stroke
				(width 0.1)
				(type default)
			)
			(layer "B.Fab")
		)
		(fp_line
			(start -0.67945 -0.3048)
			(end -0.67945 0.3048)
			(stroke
				(width 0.1)
				(type default)
			)
			(layer "B.Fab")
		)
		(fp_line
			(start -0.12065 -0.3048)
			(end -0.67945 -0.3048)
			(stroke
				(width 0.1)
				(type default)
			)
			(layer "B.Fab")
		)
		(fp_line
			(start 0.12065 -0.305054)
			(end 0.12065 -0.2794)
			(stroke
				(width 0.1)
				(type default)
			)
			(layer "B.Fab")
		)
		(fp_line
			(start 0.67945 -0.305054)
			(end 0.12065 -0.305054)
			(stroke
				(width 0.1)
				(type default)
			)
			(layer "B.Fab")
		)
		(pad "1" smd circle
			(at 0.40005 0 90)
			(size 0 0)
			(layers "B.Cu" "B.Mask" "B.Paste")
			(net "P12V_AUX")
		)
		(pad "2" smd circle
			(at -0.40005 0 90)
			(size 0 0)
			(layers "B.Cu" "B.Mask" "B.Paste")
			(net "P3V3_AUX_EN")
		)
	)
	(footprint ""
		(layer "B.Cu")
		(at 67.679824 -408.517344 90)
		(property "Reference" "C6674"
			(at 0 0 90)
			(layer "B.SilkS")
			(hide yes)
			(effects
				(font
					(size 1.27 1.27)
				)
				(justify mirror)
			)
		)
		(property "Value" ""
			(at 0 0 90)
			(layer "B.Fab")
			(effects
				(font
					(size 1.27 1.27)
				)
				(justify mirror)
			)
		)
		(duplicate_pad_numbers_are_jumpers no)
		(fp_line
			(start 0.299974 -0.150114)
			(end -0.299974 -0.150114)
			(stroke
				(width 0.1)
				(type default)
			)
			(layer "B.Fab")
		)
		(fp_line
			(start -0.299974 -0.150114)
			(end -0.299974 0.150114)
			(stroke
				(width 0.1)
				(type default)
			)
			(layer "B.Fab")
		)
		(fp_line
			(start 0.299974 0.150114)
			(end 0.299974 -0.150114)
			(stroke
				(width 0.1)
				(type default)
			)
			(layer "B.Fab")
		)
		(fp_line
			(start -0.299974 0.150114)
			(end 0.299974 0.150114)
			(stroke
				(width 0.1)
				(type default)
			)
			(layer "B.Fab")
		)
		(pad "1" smd rect
			(at 0.2667 0 270)
			(size 0.3048 0.381)
			(layers "B.Cu" "B.Mask" "B.Paste")
			(net "P5E_CPU1_P1_TX_BUF_C_DN<6>")
		)
		(pad "2" smd rect
			(at -0.2667 0 270)
			(size 0.3048 0.381)
			(layers "B.Cu" "B.Mask" "B.Paste")
			(net "P5E_CPU1_P1_TX_BUF_DN<6>")
		)
	)
	(footprint ""
		(layer "B.Cu")
		(at 233.807 -339.598 180)
		(property "Reference" "R1026"
			(at 0 0 0)
			(layer "B.SilkS")
			(hide yes)
			(effects
				(font
					(size 1.27 1.27)
				)
				(justify mirror)
			)
		)
		(property "Value" ""
			(at 0 0 0)
			(layer "B.Fab")
			(effects
				(font
					(size 1.27 1.27)
				)
				(justify mirror)
			)
		)
		(duplicate_pad_numbers_are_jumpers no)
		(fp_line
			(start 0.32512 0.175006)
			(end 0.32512 -0.175006)
			(stroke
				(width 0.1)
				(type default)
			)
			(layer "B.Fab")
		)
		(fp_line
			(start 0.32512 -0.175006)
			(end -0.32512 -0.175006)
			(stroke
				(width 0.1)
				(type default)
			)
			(layer "B.Fab")
		)
		(fp_line
			(start -0.32512 0.175006)
			(end 0.32512 0.175006)
			(stroke
				(width 0.1)
				(type default)
			)
			(layer "B.Fab")
		)
		(fp_line
			(start -0.32512 -0.175006)
			(end -0.32512 0.175006)
			(stroke
				(width 0.1)
				(type default)
			)
			(layer "B.Fab")
		)
		(pad "1" smd rect
			(at 0.2667 0)
			(size 0.3048 0.381)
			(layers "B.Cu" "B.Mask" "B.Paste")
			(net "SMB_RT_CPU0_P1_R_SDA")
		)
		(pad "2" smd rect
			(at -0.2667 0 180)
			(size 0.3048 0.381)
			(layers "B.Cu" "B.Mask" "B.Paste")
			(net "SMB_RT_CPU0_P1_R2_SDA")
		)
	)
	(footprint ""
		(layer "B.Cu")
		(at 109.150404 -28.70327 -90)
		(property "Reference" "C6096"
			(at 0 0 90)
			(layer "B.SilkS")
			(hide yes)
			(effects
				(font
					(size 1.27 1.27)
				)
				(justify mirror)
			)
		)
		(property "Value" ""
			(at 0 0 90)
			(layer "B.Fab")
			(effects
				(font
					(size 1.27 1.27)
				)
				(justify mirror)
			)
		)
		(duplicate_pad_numbers_are_jumpers no)
		(fp_line
			(start -0.7874 0.4064)
			(end 0.7874 0.4064)
			(stroke
				(width 0.1524)
				(type default)
			)
			(layer "B.SilkS")
		)
		(fp_line
			(start 0.7874 0.4064)
			(end 0.7874 -0.4064)
			(stroke
				(width 0.1524)
				(type default)
			)
			(layer "B.SilkS")
		)
		(fp_line
			(start -0.7874 -0.4064)
			(end -0.7874 0.4064)
			(stroke
				(width 0.1524)
				(type default)
			)
			(layer "B.SilkS")
		)
		(fp_line
			(start 0.7874 -0.4064)
			(end -0.7874 -0.4064)
			(stroke
				(width 0.1524)
				(type default)
			)
			(layer "B.SilkS")
		)
		(fp_line
			(start -0.67945 0.3048)
			(end -0.120396 0.3048)
			(stroke
				(width 0.1)
				(type default)
			)
			(layer "B.Fab")
		)
		(fp_line
			(start -0.120396 0.3048)
			(end -0.120396 0.2794)
			(stroke
				(width 0.1)
				(type default)
			)
			(layer "B.Fab")
		)
		(fp_line
			(start 0.12065 0.3048)
			(end 0.67945 0.3048)
			(stroke
				(width 0.1)
				(type default)
			)
			(layer "B.Fab")
		)
		(fp_line
			(start 0.67945 0.3048)
			(end 0.67945 -0.305054)
			(stroke
				(width 0.1)
				(type default)
			)
			(layer "B.Fab")
		)
		(fp_line
			(start -0.120396 0.2794)
			(end 0.12065 0.2794)
			(stroke
				(width 0.1)
				(type default)
			)
			(layer "B.Fab")
		)
		(fp_line
			(start 0.12065 0.2794)
			(end 0.12065 0.3048)
			(stroke
				(width 0.1)
				(type default)
			)
			(layer "B.Fab")
		)
		(fp_line
			(start -0.12065 -0.2794)
			(end -0.12065 -0.3048)
			(stroke
				(width 0.1)
				(type default)
			)
			(layer "B.Fab")
		)
		(fp_line
			(start 0.12065 -0.2794)
			(end -0.12065 -0.2794)
			(stroke
				(width 0.1)
				(type default)
			)
			(layer "B.Fab")
		)
		(fp_line
			(start -0.67945 -0.3048)
			(end -0.67945 0.3048)
			(stroke
				(width 0.1)
				(type default)
			)
			(layer "B.Fab")
		)
		(fp_line
			(start -0.12065 -0.3048)
			(end -0.67945 -0.3048)
			(stroke
				(width 0.1)
				(type default)
			)
			(layer "B.Fab")
		)
		(fp_line
			(start 0.12065 -0.305054)
			(end 0.12065 -0.2794)
			(stroke
				(width 0.1)
				(type default)
			)
			(layer "B.Fab")
		)
		(fp_line
			(start 0.67945 -0.305054)
			(end 0.12065 -0.305054)
			(stroke
				(width 0.1)
				(type default)
			)
			(layer "B.Fab")
		)
		(pad "1" smd circle
			(at 0.40005 0 90)
			(size 0 0)
			(layers "B.Cu" "B.Mask" "B.Paste")
			(net "P3V3_AUX_CPU0_USB2_AVDD33")
		)
		(pad "2" smd circle
			(at -0.40005 0 90)
			(size 0 0)
			(layers "B.Cu" "B.Mask" "B.Paste")
			(net "GND")
		)
	)
	(footprint ""
		(layer "B.Cu")
		(at 101.38029 -248.479564 180)
		(property "Reference" "C2326"
			(at 0 0 0)
			(layer "B.SilkS")
			(hide yes)
			(effects
				(font
					(size 1.27 1.27)
				)
				(justify mirror)
			)
		)
		(property "Value" ""
			(at 0 0 0)
			(layer "B.Fab")
			(effects
				(font
					(size 1.27 1.27)
				)
				(justify mirror)
			)
		)
		(duplicate_pad_numbers_are_jumpers no)
		(fp_line
			(start 0.7874 0.4064)
			(end 0.7874 -0.4064)
			(stroke
				(width 0.1524)
				(type default)
			)
			(layer "B.SilkS")
		)
		(fp_line
			(start 0.7874 -0.4064)
			(end -0.7874 -0.4064)
			(stroke
				(width 0.1524)
				(type default)
			)
			(layer "B.SilkS")
		)
		(fp_line
			(start -0.7874 0.4064)
			(end 0.7874 0.4064)
			(stroke
				(width 0.1524)
				(type default)
			)
			(layer "B.SilkS")
		)
		(fp_line
			(start -0.7874 -0.4064)
			(end -0.7874 0.4064)
			(stroke
				(width 0.1524)
				(type default)
			)
			(layer "B.SilkS")
		)
		(fp_line
			(start 0.67945 0.3048)
			(end 0.67945 -0.305054)
			(stroke
				(width 0.1)
				(type default)
			)
			(layer "B.Fab")
		)
		(fp_line
			(start 0.67945 -0.305054)
			(end 0.12065 -0.305054)
			(stroke
				(width 0.1)
				(type default)
			)
			(layer "B.Fab")
		)
		(fp_line
			(start 0.12065 0.3048)
			(end 0.67945 0.3048)
			(stroke
				(width 0.1)
				(type default)
			)
			(layer "B.Fab")
		)
		(fp_line
			(start 0.12065 0.2794)
			(end 0.12065 0.3048)
			(stroke
				(width 0.1)
				(type default)
			)
			(layer "B.Fab")
		)
		(fp_line
			(start 0.12065 -0.2794)
			(end -0.12065 -0.2794)
			(stroke
				(width 0.1)
				(type default)
			)
			(layer "B.Fab")
		)
		(fp_line
			(start 0.12065 -0.305054)
			(end 0.12065 -0.2794)
			(stroke
				(width 0.1)
				(type default)
			)
			(layer "B.Fab")
		)
		(fp_line
			(start -0.120396 0.3048)
			(end -0.120396 0.2794)
			(stroke
				(width 0.1)
				(type default)
			)
			(layer "B.Fab")
		)
		(fp_line
			(start -0.120396 0.2794)
			(end 0.12065 0.2794)
			(stroke
				(width 0.1)
				(type default)
			)
			(layer "B.Fab")
		)
		(fp_line
			(start -0.12065 -0.2794)
			(end -0.12065 -0.3048)
			(stroke
				(width 0.1)
				(type default)
			)
			(layer "B.Fab")
		)
		(fp_line
			(start -0.12065 -0.3048)
			(end -0.67945 -0.3048)
			(stroke
				(width 0.1)
				(type default)
			)
			(layer "B.Fab")
		)
		(fp_line
			(start -0.67945 0.3048)
			(end -0.120396 0.3048)
			(stroke
				(width 0.1)
				(type default)
			)
			(layer "B.Fab")
		)
		(fp_line
			(start -0.67945 -0.3048)
			(end -0.67945 0.3048)
			(stroke
				(width 0.1)
				(type default)
			)
			(layer "B.Fab")
		)
		(pad "1" smd circle
			(at 0.40005 0)
			(size 0 0)
			(layers "B.Cu" "B.Mask" "B.Paste")
			(net "PVDDCR_CPU0_P1")
		)
		(pad "2" smd circle
			(at -0.40005 0)
			(size 0 0)
			(layers "B.Cu" "B.Mask" "B.Paste")
			(net "GND")
		)
	)
	(footprint ""
		(layer "B.Cu")
		(at 180.509164 -23.655782 -90)
		(property "Reference" "R3062"
			(at 0 0 90)
			(layer "B.SilkS")
			(hide yes)
			(effects
				(font
					(size 1.27 1.27)
				)
				(justify mirror)
			)
		)
		(property "Value" ""
			(at 0 0 90)
			(layer "B.Fab")
			(effects
				(font
					(size 1.27 1.27)
				)
				(justify mirror)
			)
		)
		(duplicate_pad_numbers_are_jumpers no)
		(fp_line
			(start -0.7874 0.4064)
			(end 0.7874 0.4064)
			(stroke
				(width 0.1524)
				(type default)
			)
			(layer "B.SilkS")
		)
		(fp_line
			(start 0.7874 0.4064)
			(end 0.7874 -0.4064)
			(stroke
				(width 0.1524)
				(type default)
			)
			(layer "B.SilkS")
		)
		(fp_line
			(start -0.7874 -0.4064)
			(end -0.7874 0.4064)
			(stroke
				(width 0.1524)
				(type default)
			)
			(layer "B.SilkS")
		)
		(fp_line
			(start 0.7874 -0.4064)
			(end -0.7874 -0.4064)
			(stroke
				(width 0.1524)
				(type default)
			)
			(layer "B.SilkS")
		)
		(fp_line
			(start -0.67945 0.3048)
			(end -0.120396 0.3048)
			(stroke
				(width 0.1)
				(type default)
			)
			(layer "B.Fab")
		)
		(fp_line
			(start -0.120396 0.3048)
			(end -0.120396 0.2794)
			(stroke
				(width 0.1)
				(type default)
			)
			(layer "B.Fab")
		)
		(fp_line
			(start 0.12065 0.3048)
			(end 0.67945 0.3048)
			(stroke
				(width 0.1)
				(type default)
			)
			(layer "B.Fab")
		)
		(fp_line
			(start 0.67945 0.3048)
			(end 0.67945 -0.305054)
			(stroke
				(width 0.1)
				(type default)
			)
			(layer "B.Fab")
		)
		(fp_line
			(start -0.120396 0.2794)
			(end 0.12065 0.2794)
			(stroke
				(width 0.1)
				(type default)
			)
			(layer "B.Fab")
		)
		(fp_line
			(start 0.12065 0.2794)
			(end 0.12065 0.3048)
			(stroke
				(width 0.1)
				(type default)
			)
			(layer "B.Fab")
		)
		(fp_line
			(start -0.12065 -0.2794)
			(end -0.12065 -0.3048)
			(stroke
				(width 0.1)
				(type default)
			)
			(layer "B.Fab")
		)
		(fp_line
			(start 0.12065 -0.2794)
			(end -0.12065 -0.2794)
			(stroke
				(width 0.1)
				(type default)
			)
			(layer "B.Fab")
		)
		(fp_line
			(start -0.67945 -0.3048)
			(end -0.67945 0.3048)
			(stroke
				(width 0.1)
				(type default)
			)
			(layer "B.Fab")
		)
		(fp_line
			(start -0.12065 -0.3048)
			(end -0.67945 -0.3048)
			(stroke
				(width 0.1)
				(type default)
			)
			(layer "B.Fab")
		)
		(fp_line
			(start 0.12065 -0.305054)
			(end 0.12065 -0.2794)
			(stroke
				(width 0.1)
				(type default)
			)
			(layer "B.Fab")
		)
		(fp_line
			(start 0.67945 -0.305054)
			(end 0.12065 -0.305054)
			(stroke
				(width 0.1)
				(type default)
			)
			(layer "B.Fab")
		)
		(pad "1" smd circle
			(at 0.40005 0 90)
			(size 0 0)
			(layers "B.Cu" "B.Mask" "B.Paste")
			(net "SMB_CPU0_CPU1_APML_SDA")
		)
		(pad "2" smd circle
			(at -0.40005 0 90)
			(size 0 0)
			(layers "B.Cu" "B.Mask" "B.Paste")
			(net "P3V3_AUX")
		)
	)
	(footprint ""
		(layer "B.Cu")
		(at 90.209878 -148.94941 180)
		(property "Reference" "R8171"
			(at 0 0 0)
			(layer "B.SilkS")
			(hide yes)
			(effects
				(font
					(size 1.27 1.27)
				)
				(justify mirror)
			)
		)
		(property "Value" ""
			(at 0 0 0)
			(layer "B.Fab")
			(effects
				(font
					(size 1.27 1.27)
				)
				(justify mirror)
			)
		)
		(duplicate_pad_numbers_are_jumpers no)
		(fp_line
			(start 0.7874 0.4064)
			(end 0.7874 -0.4064)
			(stroke
				(width 0.1524)
				(type default)
			)
			(layer "B.SilkS")
		)
		(fp_line
			(start 0.7874 -0.4064)
			(end -0.7874 -0.4064)
			(stroke
				(width 0.1524)
				(type default)
			)
			(layer "B.SilkS")
		)
		(fp_line
			(start -0.7874 0.4064)
			(end 0.7874 0.4064)
			(stroke
				(width 0.1524)
				(type default)
			)
			(layer "B.SilkS")
		)
		(fp_line
			(start -0.7874 -0.4064)
			(end -0.7874 0.4064)
			(stroke
				(width 0.1524)
				(type default)
			)
			(layer "B.SilkS")
		)
		(fp_line
			(start 0.67945 0.3048)
			(end 0.67945 -0.305054)
			(stroke
				(width 0.1)
				(type default)
			)
			(layer "B.Fab")
		)
		(fp_line
			(start 0.67945 -0.305054)
			(end 0.12065 -0.305054)
			(stroke
				(width 0.1)
				(type default)
			)
			(layer "B.Fab")
		)
		(fp_line
			(start 0.12065 0.3048)
			(end 0.67945 0.3048)
			(stroke
				(width 0.1)
				(type default)
			)
			(layer "B.Fab")
		)
		(fp_line
			(start 0.12065 0.2794)
			(end 0.12065 0.3048)
			(stroke
				(width 0.1)
				(type default)
			)
			(layer "B.Fab")
		)
		(fp_line
			(start 0.12065 -0.2794)
			(end -0.12065 -0.2794)
			(stroke
				(width 0.1)
				(type default)
			)
			(layer "B.Fab")
		)
		(fp_line
			(start 0.12065 -0.305054)
			(end 0.12065 -0.2794)
			(stroke
				(width 0.1)
				(type default)
			)
			(layer "B.Fab")
		)
		(fp_line
			(start -0.120396 0.3048)
			(end -0.120396 0.2794)
			(stroke
				(width 0.1)
				(type default)
			)
			(layer "B.Fab")
		)
		(fp_line
			(start -0.120396 0.2794)
			(end 0.12065 0.2794)
			(stroke
				(width 0.1)
				(type default)
			)
			(layer "B.Fab")
		)
		(fp_line
			(start -0.12065 -0.2794)
			(end -0.12065 -0.3048)
			(stroke
				(width 0.1)
				(type default)
			)
			(layer "B.Fab")
		)
		(fp_line
			(start -0.12065 -0.3048)
			(end -0.67945 -0.3048)
			(stroke
				(width 0.1)
				(type default)
			)
			(layer "B.Fab")
		)
		(fp_line
			(start -0.67945 0.3048)
			(end -0.120396 0.3048)
			(stroke
				(width 0.1)
				(type default)
			)
			(layer "B.Fab")
		)
		(fp_line
			(start -0.67945 -0.3048)
			(end -0.67945 0.3048)
			(stroke
				(width 0.1)
				(type default)
			)
			(layer "B.Fab")
		)
		(pad "1" smd circle
			(at 0.40005 0)
			(size 0 0)
			(layers "B.Cu" "B.Mask" "B.Paste")
			(net "SVID_PVDDCR_CPU0_P1_SVTO")
		)
		(pad "2" smd circle
			(at -0.40005 0)
			(size 0 0)
			(layers "B.Cu" "B.Mask" "B.Paste")
			(net "SVID_PVDDCR_CPU0_P1_SVTO_R")
		)
	)
	(footprint ""
		(layer "B.Cu")
		(at 50.991262 -390.560052 90)
		(property "Reference" "C254"
			(at 0 0 90)
			(layer "B.SilkS")
			(hide yes)
			(effects
				(font
					(size 1.27 1.27)
				)
				(justify mirror)
			)
		)
		(property "Value" ""
			(at 0 0 90)
			(layer "B.Fab")
			(effects
				(font
					(size 1.27 1.27)
				)
				(justify mirror)
			)
		)
		(duplicate_pad_numbers_are_jumpers no)
		(fp_line
			(start 0.7874 -0.4064)
			(end -0.7874 -0.4064)
			(stroke
				(width 0.1524)
				(type default)
			)
			(layer "B.SilkS")
		)
		(fp_line
			(start -0.7874 -0.4064)
			(end -0.7874 0.4064)
			(stroke
				(width 0.1524)
				(type default)
			)
			(layer "B.SilkS")
		)
		(fp_line
			(start 0.7874 0.4064)
			(end 0.7874 -0.4064)
			(stroke
				(width 0.1524)
				(type default)
			)
			(layer "B.SilkS")
		)
		(fp_line
			(start -0.7874 0.4064)
			(end 0.7874 0.4064)
			(stroke
				(width 0.1524)
				(type default)
			)
			(layer "B.SilkS")
		)
		(fp_line
			(start 0.67945 -0.305054)
			(end 0.12065 -0.305054)
			(stroke
				(width 0.1)
				(type default)
			)
			(layer "B.Fab")
		)
		(fp_line
			(start 0.12065 -0.305054)
			(end 0.12065 -0.2794)
			(stroke
				(width 0.1)
				(type default)
			)
			(layer "B.Fab")
		)
		(fp_line
			(start -0.12065 -0.3048)
			(end -0.67945 -0.3048)
			(stroke
				(width 0.1)
				(type default)
			)
			(layer "B.Fab")
		)
		(fp_line
			(start -0.67945 -0.3048)
			(end -0.67945 0.3048)
			(stroke
				(width 0.1)
				(type default)
			)
			(layer "B.Fab")
		)
		(fp_line
			(start 0.12065 -0.2794)
			(end -0.12065 -0.2794)
			(stroke
				(width 0.1)
				(type default)
			)
			(layer "B.Fab")
		)
		(fp_line
			(start -0.12065 -0.2794)
			(end -0.12065 -0.3048)
			(stroke
				(width 0.1)
				(type default)
			)
			(layer "B.Fab")
		)
		(fp_line
			(start 0.12065 0.2794)
			(end 0.12065 0.3048)
			(stroke
				(width 0.1)
				(type default)
			)
			(layer "B.Fab")
		)
		(fp_line
			(start -0.120396 0.2794)
			(end 0.12065 0.2794)
			(stroke
				(width 0.1)
				(type default)
			)
			(layer "B.Fab")
		)
		(fp_line
			(start 0.67945 0.3048)
			(end 0.67945 -0.305054)
			(stroke
				(width 0.1)
				(type default)
			)
			(layer "B.Fab")
		)
		(fp_line
			(start 0.12065 0.3048)
			(end 0.67945 0.3048)
			(stroke
				(width 0.1)
				(type default)
			)
			(layer "B.Fab")
		)
		(fp_line
			(start -0.120396 0.3048)
			(end -0.120396 0.2794)
			(stroke
				(width 0.1)
				(type default)
			)
			(layer "B.Fab")
		)
		(fp_line
			(start -0.67945 0.3048)
			(end -0.120396 0.3048)
			(stroke
				(width 0.1)
				(type default)
			)
			(layer "B.Fab")
		)
		(pad "1" smd circle
			(at 0.40005 0 270)
			(size 0 0)
			(layers "B.Cu" "B.Mask" "B.Paste")
			(net "P0V9_CPU1_RT0_2A")
		)
		(pad "2" smd circle
			(at -0.40005 0 270)
			(size 0 0)
			(layers "B.Cu" "B.Mask" "B.Paste")
			(net "GND")
		)
	)
	(footprint ""
		(layer "B.Cu")
		(at 440.78525 8.689848)
		(property "Reference" "J8068"
			(at 4.466336 1.99136 270)
			(unlocked yes)
			(layer "B.SilkS")
			(effects
				(font
					(size 0.7874 0.5842)
					(thickness 0.1524)
				)
				(justify left mirror)
			)
		)
		(property "Value" ""
			(at 0 0 0)
			(layer "B.Fab")
			(effects
				(font
					(size 1.27 1.27)
				)
				(justify mirror)
			)
		)
		(duplicate_pad_numbers_are_jumpers no)
		(fp_line
			(start -1.2192 -2.06756)
			(end -1.2192 2.06756)
			(stroke
				(width 0.1524)
				(type default)
			)
			(layer "B.SilkS")
		)
		(fp_line
			(start -1.2192 2.06756)
			(end 1.2192 2.06756)
			(stroke
				(width 0.1524)
				(type default)
			)
			(layer "B.SilkS")
		)
		(fp_line
			(start 1.2192 -2.06756)
			(end -1.2192 -2.06756)
			(stroke
				(width 0.1524)
				(type default)
			)
			(layer "B.SilkS")
		)
		(fp_line
			(start 1.2192 2.06756)
			(end 1.2192 -2.06756)
			(stroke
				(width 0.1524)
				(type default)
			)
			(layer "B.SilkS")
		)
		(pad "" np_thru_hole circle
			(at -3.4671 -1.27 270)
			(size 1.0414 1.0414)
			(drill 1.0414)
			(layers "*.Cu" "*.Mask")
			(clearance 0.381)
			(thermal_gap 0.381)
		)
		(pad "" np_thru_hole circle
			(at -3.4671 1.27 270)
			(size 1.0414 1.0414)
			(drill 1.0414)
			(layers "*.Cu" "*.Mask")
			(clearance 0.381)
			(thermal_gap 0.381)
		)
		(pad "" np_thru_hole circle
			(at 2.8829 -1.27 270)
			(size 1.0414 1.0414)
			(drill 1.0414)
			(layers "*.Cu" "*.Mask")
			(clearance 0.381)
			(thermal_gap 0.381)
		)
		(pad "" np_thru_hole circle
			(at 2.8829 1.27 270)
			(size 1.0414 1.0414)
			(drill 1.0414)
			(layers "*.Cu" "*.Mask")
			(clearance 0.381)
			(thermal_gap 0.381)
		)
		(pad "1" smd rect
			(at -0.8255 -0.249936 270)
			(size 0.3048 0.508)
			(layers "B.Cu" "B.Mask" "B.Paste")
			(net "DELTA_L_85_5INCH_IN4_DP")
		)
		(pad "2" smd rect
			(at -0.8255 0.249936 270)
			(size 0.3048 0.508)
			(layers "B.Cu" "B.Mask" "B.Paste")
			(net "DELTA_L_85_5INCH_IN4_DN")
		)
		(pad "3" smd circle
			(at 0 0 180)
			(size 0 0)
			(layers "B.Cu" "B.Mask" "B.Paste")
			(net "DELTA_L_GND_1")
		)
		(zone
			(layers "F.Cu" "B.Cu" "In1.Cu" "In2.Cu" "In3.Cu" "In4.Cu" "In5.Cu" "In6.Cu"
				"In7.Cu" "In8.Cu" "In9.Cu" "In10.Cu" "In11.Cu" "In12.Cu" "In13.Cu" "In14.Cu"
				"In15.Cu" "In16.Cu"
			)
			(hatch none 0.5)
			(connect_pads
				(clearance 0)
			)
			(min_thickness 0.25)
			(keepout
				(tracks not_allowed)
				(vias allowed)
				(pads allowed)
				(copperpour not_allowed)
				(footprints allowed)
			)
			(placement
				(enabled no)
				(sheetname "")
			)
			(fill
				(thermal_gap 0.5)
				(thermal_bridge_width 0.5)
				(island_removal_mode 0)
			)
			(polygon
				(pts
					(arc
						(start 438.24525 7.419848)
						(mid 436.39105 7.419848)
						(end 438.24525 7.419848)
					)
				)
			)
		)
		(zone
			(layers "F.Cu" "B.Cu" "In1.Cu" "In2.Cu" "In3.Cu" "In4.Cu" "In5.Cu" "In6.Cu"
				"In7.Cu" "In8.Cu" "In9.Cu" "In10.Cu" "In11.Cu" "In12.Cu" "In13.Cu" "In14.Cu"
				"In15.Cu" "In16.Cu"
			)
			(hatch none 0.5)
			(connect_pads
				(clearance 0)
			)
			(min_thickness 0.25)
			(keepout
				(tracks not_allowed)
				(vias allowed)
				(pads allowed)
				(copperpour not_allowed)
				(footprints allowed)
			)
			(placement
				(enabled no)
				(sheetname "")
			)
			(fill
				(thermal_gap 0.5)
				(thermal_bridge_width 0.5)
				(island_removal_mode 0)
			)
			(polygon
				(pts
					(arc
						(start 438.24525 9.959848)
						(mid 436.39105 9.959848)
						(end 438.24525 9.959848)
					)
				)
			)
		)
		(zone
			(layers "F.Cu" "B.Cu" "In1.Cu" "In2.Cu" "In3.Cu" "In4.Cu" "In5.Cu" "In6.Cu"
				"In7.Cu" "In8.Cu" "In9.Cu" "In10.Cu" "In11.Cu" "In12.Cu" "In13.Cu" "In14.Cu"
				"In15.Cu" "In16.Cu"
			)
			(hatch none 0.5)
			(connect_pads
				(clearance 0)
			)
			(min_thickness 0.25)
			(keepout
				(tracks not_allowed)
				(vias allowed)
				(pads allowed)
				(copperpour not_allowed)
				(footprints allowed)
			)
			(placement
				(enabled no)
				(sheetname "")
			)
			(fill
				(thermal_gap 0.5)
				(thermal_bridge_width 0.5)
				(island_removal_mode 0)
			)
			(polygon
				(pts
					(arc
						(start 444.59525 7.419848)
						(mid 442.74105 7.419848)
						(end 444.59525 7.419848)
					)
				)
			)
		)
		(zone
			(layers "F.Cu" "B.Cu" "In1.Cu" "In2.Cu" "In3.Cu" "In4.Cu" "In5.Cu" "In6.Cu"
				"In7.Cu" "In8.Cu" "In9.Cu" "In10.Cu" "In11.Cu" "In12.Cu" "In13.Cu" "In14.Cu"
				"In15.Cu" "In16.Cu"
			)
			(hatch none 0.5)
			(connect_pads
				(clearance 0)
			)
			(min_thickness 0.25)
			(keepout
				(tracks not_allowed)
				(vias allowed)
				(pads allowed)
				(copperpour not_allowed)
				(footprints allowed)
			)
			(placement
				(enabled no)
				(sheetname "")
			)
			(fill
				(thermal_gap 0.5)
				(thermal_bridge_width 0.5)
				(island_removal_mode 0)
			)
			(polygon
				(pts
					(arc
						(start 444.59525 9.959848)
						(mid 442.74105 9.959848)
						(end 444.59525 9.959848)
					)
				)
			)
		)
		(zone
			(layer "B.Cu")
			(hatch none 0.5)
			(connect_pads
				(clearance 0)
			)
			(min_thickness 0.25)
			(keepout
				(tracks not_allowed)
				(vias allowed)
				(pads allowed)
				(copperpour not_allowed)
				(footprints allowed)
			)
			(placement
				(enabled no)
				(sheetname "")
			)
			(fill
				(thermal_gap 0.5)
				(thermal_bridge_width 0.5)
				(island_removal_mode 0)
			)
			(polygon
				(pts
					(xy 439.66765 8.141208) (xy 439.66765 8.236712) (xy 440.26455 8.236712) (xy 440.26455 8.643112)
					(xy 439.66765 8.643112) (xy 439.66765 8.736584) (xy 440.26455 8.736584) (xy 440.26455 9.142984)
					(xy 439.66765 9.142984) (xy 439.66765 9.238488) (xy 440.36615 9.238488) (xy 440.36615 8.141208)
				)
			)
		)
	)
	(footprint ""
		(layer "B.Cu")
		(at 241.758978 -315.95568 -90)
		(property "Reference" "PC6511"
			(at 0 0 90)
			(layer "B.SilkS")
			(hide yes)
			(effects
				(font
					(size 1.27 1.27)
				)
				(justify mirror)
			)
		)
		(property "Value" ""
			(at 0 0 90)
			(layer "B.Fab")
			(effects
				(font
					(size 1.27 1.27)
				)
				(justify mirror)
			)
		)
		(duplicate_pad_numbers_are_jumpers no)
		(fp_line
			(start -1.524 0.762)
			(end 1.524 0.762)
			(stroke
				(width 0.1524)
				(type default)
			)
			(layer "B.SilkS")
		)
		(fp_line
			(start 1.524 0.762)
			(end 1.524 -0.762)
			(stroke
				(width 0.1524)
				(type default)
			)
			(layer "B.SilkS")
		)
		(fp_line
			(start -1.524 -0.762)
			(end -1.524 0.762)
			(stroke
				(width 0.1524)
				(type default)
			)
			(layer "B.SilkS")
		)
		(fp_line
			(start 1.524 -0.762)
			(end -1.524 -0.762)
			(stroke
				(width 0.1524)
				(type default)
			)
			(layer "B.SilkS")
		)
		(fp_line
			(start -1.1049 0.724916)
			(end -1.1049 -0.724916)
			(stroke
				(width 0.1)
				(type default)
			)
			(layer "B.Fab")
		)
		(fp_line
			(start 1.1049 0.724916)
			(end -1.1049 0.724916)
			(stroke
				(width 0.1)
				(type default)
			)
			(layer "B.Fab")
		)
		(fp_line
			(start -1.1049 -0.724916)
			(end 1.1049 -0.724916)
			(stroke
				(width 0.1)
				(type default)
			)
			(layer "B.Fab")
		)
		(fp_line
			(start 1.1049 -0.724916)
			(end 1.1049 0.724916)
			(stroke
				(width 0.1)
				(type default)
			)
			(layer "B.Fab")
		)
		(pad "1" smd rect
			(at 0.889 0 270)
			(size 1.016 1.27)
			(layers "B.Cu" "B.Mask" "B.Paste")
			(net "P1V8_CPU0_RT_1D")
		)
		(pad "2" smd rect
			(at -0.889 0 270)
			(size 1.016 1.27)
			(layers "B.Cu" "B.Mask" "B.Paste")
			(net "GND")
		)
	)
	(footprint ""
		(layer "B.Cu")
		(at 428.98695 -31.181548 180)
		(property "Reference" "R6106"
			(at 0 0 0)
			(layer "B.SilkS")
			(hide yes)
			(effects
				(font
					(size 1.27 1.27)
				)
				(justify mirror)
			)
		)
		(property "Value" ""
			(at 0 0 0)
			(layer "B.Fab")
			(effects
				(font
					(size 1.27 1.27)
				)
				(justify mirror)
			)
		)
		(duplicate_pad_numbers_are_jumpers no)
		(fp_line
			(start 0.7874 0.4064)
			(end 0.7874 -0.4064)
			(stroke
				(width 0.1524)
				(type default)
			)
			(layer "B.SilkS")
		)
		(fp_line
			(start 0.7874 -0.4064)
			(end -0.7874 -0.4064)
			(stroke
				(width 0.1524)
				(type default)
			)
			(layer "B.SilkS")
		)
		(fp_line
			(start -0.7874 0.4064)
			(end 0.7874 0.4064)
			(stroke
				(width 0.1524)
				(type default)
			)
			(layer "B.SilkS")
		)
		(fp_line
			(start -0.7874 -0.4064)
			(end -0.7874 0.4064)
			(stroke
				(width 0.1524)
				(type default)
			)
			(layer "B.SilkS")
		)
		(fp_line
			(start 0.67945 0.3048)
			(end 0.67945 -0.305054)
			(stroke
				(width 0.1)
				(type default)
			)
			(layer "B.Fab")
		)
		(fp_line
			(start 0.67945 -0.305054)
			(end 0.12065 -0.305054)
			(stroke
				(width 0.1)
				(type default)
			)
			(layer "B.Fab")
		)
		(fp_line
			(start 0.12065 0.3048)
			(end 0.67945 0.3048)
			(stroke
				(width 0.1)
				(type default)
			)
			(layer "B.Fab")
		)
		(fp_line
			(start 0.12065 0.2794)
			(end 0.12065 0.3048)
			(stroke
				(width 0.1)
				(type default)
			)
			(layer "B.Fab")
		)
		(fp_line
			(start 0.12065 -0.2794)
			(end -0.12065 -0.2794)
			(stroke
				(width 0.1)
				(type default)
			)
			(layer "B.Fab")
		)
		(fp_line
			(start 0.12065 -0.305054)
			(end 0.12065 -0.2794)
			(stroke
				(width 0.1)
				(type default)
			)
			(layer "B.Fab")
		)
		(fp_line
			(start -0.120396 0.3048)
			(end -0.120396 0.2794)
			(stroke
				(width 0.1)
				(type default)
			)
			(layer "B.Fab")
		)
		(fp_line
			(start -0.120396 0.2794)
			(end 0.12065 0.2794)
			(stroke
				(width 0.1)
				(type default)
			)
			(layer "B.Fab")
		)
		(fp_line
			(start -0.12065 -0.2794)
			(end -0.12065 -0.3048)
			(stroke
				(width 0.1)
				(type default)
			)
			(layer "B.Fab")
		)
		(fp_line
			(start -0.12065 -0.3048)
			(end -0.67945 -0.3048)
			(stroke
				(width 0.1)
				(type default)
			)
			(layer "B.Fab")
		)
		(fp_line
			(start -0.67945 0.3048)
			(end -0.120396 0.3048)
			(stroke
				(width 0.1)
				(type default)
			)
			(layer "B.Fab")
		)
		(fp_line
			(start -0.67945 -0.3048)
			(end -0.67945 0.3048)
			(stroke
				(width 0.1)
				(type default)
			)
			(layer "B.Fab")
		)
		(pad "1" smd circle
			(at 0.40005 0)
			(size 0 0)
			(layers "B.Cu" "B.Mask" "B.Paste")
			(net "PVDD18_S5_P0")
		)
		(pad "2" smd circle
			(at -0.40005 0)
			(size 0 0)
			(layers "B.Cu" "B.Mask" "B.Paste")
			(net "FM_PASSWORD_CLEAR_N")
		)
	)
	(footprint ""
		(layer "B.Cu")
		(at 242.062 -328.168)
		(property "Reference" "L24"
			(at 0 0 0)
			(layer "B.SilkS")
			(hide yes)
			(effects
				(font
					(size 1.27 1.27)
				)
				(justify mirror)
			)
		)
		(property "Value" ""
			(at 0 0 0)
			(layer "B.Fab")
			(effects
				(font
					(size 1.27 1.27)
				)
				(justify mirror)
			)
		)
		(duplicate_pad_numbers_are_jumpers no)
		(fp_line
			(start -1.27 0.5842)
			(end -1.27 -0.5842)
			(stroke
				(width 0.1524)
				(type default)
			)
			(layer "B.SilkS")
		)
		(fp_line
			(start -1.27 0.5842)
			(end 1.27 0.5842)
			(stroke
				(width 0.1524)
				(type default)
			)
			(layer "B.SilkS")
		)
		(fp_line
			(start 1.27 -0.5842)
			(end -1.27 -0.5842)
			(stroke
				(width 0.1524)
				(type default)
			)
			(layer "B.SilkS")
		)
		(fp_line
			(start 1.27 -0.5588)
			(end 1.27 -0.5842)
			(stroke
				(width 0.1524)
				(type default)
			)
			(layer "B.SilkS")
		)
		(fp_line
			(start 1.27 0.5842)
			(end 1.27 -0.5842)
			(stroke
				(width 0.1524)
				(type default)
			)
			(layer "B.SilkS")
		)
		(fp_line
			(start -1.1938 -0.406654)
			(end -1.1938 0.4064)
			(stroke
				(width 0.1)
				(type default)
			)
			(layer "B.Fab")
		)
		(fp_line
			(start -1.1938 0.4064)
			(end -0.9144 0.4064)
			(stroke
				(width 0.1)
				(type default)
			)
			(layer "B.Fab")
		)
		(fp_line
			(start -0.9144 -0.508)
			(end -0.9144 -0.406654)
			(stroke
				(width 0.1)
				(type default)
			)
			(layer "B.Fab")
		)
		(fp_line
			(start -0.9144 -0.406654)
			(end -1.1938 -0.406654)
			(stroke
				(width 0.1)
				(type default)
			)
			(layer "B.Fab")
		)
		(fp_line
			(start -0.9144 0.4064)
			(end -0.9144 0.508)
			(stroke
				(width 0.1)
				(type default)
			)
			(layer "B.Fab")
		)
		(fp_line
			(start -0.9144 0.508)
			(end 0.9144 0.508)
			(stroke
				(width 0.1)
				(type default)
			)
			(layer "B.Fab")
		)
		(fp_line
			(start 0.9144 -0.508)
			(end -0.9144 -0.508)
			(stroke
				(width 0.1)
				(type default)
			)
			(layer "B.Fab")
		)
		(fp_line
			(start 0.9144 -0.406654)
			(end 0.9144 -0.508)
			(stroke
				(width 0.1)
				(type default)
			)
			(layer "B.Fab")
		)
		(fp_line
			(start 0.9144 0.406654)
			(end 1.194308 0.406654)
			(stroke
				(width 0.1)
				(type default)
			)
			(layer "B.Fab")
		)
		(fp_line
			(start 0.9144 0.508)
			(end 0.9144 0.406654)
			(stroke
				(width 0.1)
				(type default)
			)
			(layer "B.Fab")
		)
		(fp_line
			(start 1.194308 -0.406654)
			(end 0.9144 -0.406654)
			(stroke
				(width 0.1)
				(type default)
			)
			(layer "B.Fab")
		)
		(fp_line
			(start 1.194308 0.406654)
			(end 1.194308 -0.406654)
			(stroke
				(width 0.1)
				(type default)
			)
			(layer "B.Fab")
		)
		(pad "1" smd rect
			(at 0.7366 0 270)
			(size 0.7112 0.8128)
			(layers "B.Cu" "B.Mask" "B.Paste")
			(net "P3V3_MAX11617_2_VDD")
		)
		(pad "2" smd rect
			(at -0.7366 0 270)
			(size 0.7112 0.8128)
			(layers "B.Cu" "B.Mask" "B.Paste")
			(net "P3V3_AUX")
		)
	)
	(footprint ""
		(layer "B.Cu")
		(at 130.218434 -388.011162 -90)
		(property "Reference" "C496"
			(at 0 0 90)
			(layer "B.SilkS")
			(hide yes)
			(effects
				(font
					(size 1.27 1.27)
				)
				(justify mirror)
			)
		)
		(property "Value" ""
			(at 0 0 90)
			(layer "B.Fab")
			(effects
				(font
					(size 1.27 1.27)
				)
				(justify mirror)
			)
		)
		(duplicate_pad_numbers_are_jumpers no)
		(fp_line
			(start -0.299974 0.150114)
			(end 0.299974 0.150114)
			(stroke
				(width 0.1)
				(type default)
			)
			(layer "B.Fab")
		)
		(fp_line
			(start 0.299974 0.150114)
			(end 0.299974 -0.150114)
			(stroke
				(width 0.1)
				(type default)
			)
			(layer "B.Fab")
		)
		(fp_line
			(start -0.299974 -0.150114)
			(end -0.299974 0.150114)
			(stroke
				(width 0.1)
				(type default)
			)
			(layer "B.Fab")
		)
		(fp_line
			(start 0.299974 -0.150114)
			(end -0.299974 -0.150114)
			(stroke
				(width 0.1)
				(type default)
			)
			(layer "B.Fab")
		)
		(pad "1" smd rect
			(at 0.2667 0 90)
			(size 0.3048 0.381)
			(layers "B.Cu" "B.Mask" "B.Paste")
			(net "P0V9_CPU1_RT3_2A")
		)
		(pad "2" smd rect
			(at -0.2667 0 90)
			(size 0.3048 0.381)
			(layers "B.Cu" "B.Mask" "B.Paste")
			(net "GND")
		)
	)
	(footprint ""
		(layer "B.Cu")
		(at 326.742806 -416.899344 90)
		(property "Reference" "C6548"
			(at 0 0 90)
			(layer "B.SilkS")
			(hide yes)
			(effects
				(font
					(size 1.27 1.27)
				)
				(justify mirror)
			)
		)
		(property "Value" ""
			(at 0 0 90)
			(layer "B.Fab")
			(effects
				(font
					(size 1.27 1.27)
				)
				(justify mirror)
			)
		)
		(duplicate_pad_numbers_are_jumpers no)
		(fp_line
			(start 0.299974 -0.150114)
			(end -0.299974 -0.150114)
			(stroke
				(width 0.1)
				(type default)
			)
			(layer "B.Fab")
		)
		(fp_line
			(start -0.299974 -0.150114)
			(end -0.299974 0.150114)
			(stroke
				(width 0.1)
				(type default)
			)
			(layer "B.Fab")
		)
		(fp_line
			(start 0.299974 0.150114)
			(end 0.299974 -0.150114)
			(stroke
				(width 0.1)
				(type default)
			)
			(layer "B.Fab")
		)
		(fp_line
			(start -0.299974 0.150114)
			(end 0.299974 0.150114)
			(stroke
				(width 0.1)
				(type default)
			)
			(layer "B.Fab")
		)
		(pad "1" smd rect
			(at 0.2667 0 270)
			(size 0.3048 0.381)
			(layers "B.Cu" "B.Mask" "B.Paste")
			(net "P5E_CPU0_P1_TX_BUF_C_DN<7>")
		)
		(pad "2" smd rect
			(at -0.2667 0 270)
			(size 0.3048 0.381)
			(layers "B.Cu" "B.Mask" "B.Paste")
			(net "P5E_CPU0_P1_TX_BUF_DN<7>")
		)
	)
	(footprint ""
		(layer "B.Cu")
		(at 180.271674 -194.885564 180)
		(property "Reference" "R775"
			(at 0 0 0)
			(layer "B.SilkS")
			(hide yes)
			(effects
				(font
					(size 1.27 1.27)
				)
				(justify mirror)
			)
		)
		(property "Value" ""
			(at 0 0 0)
			(layer "B.Fab")
			(effects
				(font
					(size 1.27 1.27)
				)
				(justify mirror)
			)
		)
		(duplicate_pad_numbers_are_jumpers no)
		(fp_line
			(start 0.7874 0.4064)
			(end 0.7874 -0.4064)
			(stroke
				(width 0.1524)
				(type default)
			)
			(layer "B.SilkS")
		)
		(fp_line
			(start 0.7874 -0.4064)
			(end -0.7874 -0.4064)
			(stroke
				(width 0.1524)
				(type default)
			)
			(layer "B.SilkS")
		)
		(fp_line
			(start -0.7874 0.4064)
			(end 0.7874 0.4064)
			(stroke
				(width 0.1524)
				(type default)
			)
			(layer "B.SilkS")
		)
		(fp_line
			(start -0.7874 -0.4064)
			(end -0.7874 0.4064)
			(stroke
				(width 0.1524)
				(type default)
			)
			(layer "B.SilkS")
		)
		(fp_line
			(start 0.67945 0.3048)
			(end 0.67945 -0.305054)
			(stroke
				(width 0.1)
				(type default)
			)
			(layer "B.Fab")
		)
		(fp_line
			(start 0.67945 -0.305054)
			(end 0.12065 -0.305054)
			(stroke
				(width 0.1)
				(type default)
			)
			(layer "B.Fab")
		)
		(fp_line
			(start 0.12065 0.3048)
			(end 0.67945 0.3048)
			(stroke
				(width 0.1)
				(type default)
			)
			(layer "B.Fab")
		)
		(fp_line
			(start 0.12065 0.2794)
			(end 0.12065 0.3048)
			(stroke
				(width 0.1)
				(type default)
			)
			(layer "B.Fab")
		)
		(fp_line
			(start 0.12065 -0.2794)
			(end -0.12065 -0.2794)
			(stroke
				(width 0.1)
				(type default)
			)
			(layer "B.Fab")
		)
		(fp_line
			(start 0.12065 -0.305054)
			(end 0.12065 -0.2794)
			(stroke
				(width 0.1)
				(type default)
			)
			(layer "B.Fab")
		)
		(fp_line
			(start -0.120396 0.3048)
			(end -0.120396 0.2794)
			(stroke
				(width 0.1)
				(type default)
			)
			(layer "B.Fab")
		)
		(fp_line
			(start -0.120396 0.2794)
			(end 0.12065 0.2794)
			(stroke
				(width 0.1)
				(type default)
			)
			(layer "B.Fab")
		)
		(fp_line
			(start -0.12065 -0.2794)
			(end -0.12065 -0.3048)
			(stroke
				(width 0.1)
				(type default)
			)
			(layer "B.Fab")
		)
		(fp_line
			(start -0.12065 -0.3048)
			(end -0.67945 -0.3048)
			(stroke
				(width 0.1)
				(type default)
			)
			(layer "B.Fab")
		)
		(fp_line
			(start -0.67945 0.3048)
			(end -0.120396 0.3048)
			(stroke
				(width 0.1)
				(type default)
			)
			(layer "B.Fab")
		)
		(fp_line
			(start -0.67945 -0.3048)
			(end -0.67945 0.3048)
			(stroke
				(width 0.1)
				(type default)
			)
			(layer "B.Fab")
		)
		(pad "1" smd circle
			(at 0.40005 0)
			(size 0 0)
			(layers "B.Cu" "B.Mask" "B.Paste")
			(net "PD_CHI_CPU1_DIMM_SAA")
		)
		(pad "2" smd circle
			(at -0.40005 0)
			(size 0 0)
			(layers "B.Cu" "B.Mask" "B.Paste")
			(net "GND")
		)
	)
	(footprint ""
		(layer "B.Cu")
		(at 417.406328 -395.148562 90)
		(property "Reference" "C792"
			(at 0 0 90)
			(layer "B.SilkS")
			(hide yes)
			(effects
				(font
					(size 1.27 1.27)
				)
				(justify mirror)
			)
		)
		(property "Value" ""
			(at 0 0 90)
			(layer "B.Fab")
			(effects
				(font
					(size 1.27 1.27)
				)
				(justify mirror)
			)
		)
		(duplicate_pad_numbers_are_jumpers no)
		(fp_line
			(start 0.299974 -0.150114)
			(end -0.299974 -0.150114)
			(stroke
				(width 0.1)
				(type default)
			)
			(layer "B.Fab")
		)
		(fp_line
			(start -0.299974 -0.150114)
			(end -0.299974 0.150114)
			(stroke
				(width 0.1)
				(type default)
			)
			(layer "B.Fab")
		)
		(fp_line
			(start 0.299974 0.150114)
			(end 0.299974 -0.150114)
			(stroke
				(width 0.1)
				(type default)
			)
			(layer "B.Fab")
		)
		(fp_line
			(start -0.299974 0.150114)
			(end 0.299974 0.150114)
			(stroke
				(width 0.1)
				(type default)
			)
			(layer "B.Fab")
		)
		(pad "1" smd rect
			(at 0.2667 0 270)
			(size 0.3048 0.381)
			(layers "B.Cu" "B.Mask" "B.Paste")
			(net "P0V9_CPU0_RT2_2A")
		)
		(pad "2" smd rect
			(at -0.2667 0 270)
			(size 0.3048 0.381)
			(layers "B.Cu" "B.Mask" "B.Paste")
			(net "GND")
		)
	)
	(footprint ""
		(layer "B.Cu")
		(at 164.403532 -430.59858 -90)
		(property "Reference" "R4123"
			(at 0 0 90)
			(layer "B.SilkS")
			(hide yes)
			(effects
				(font
					(size 1.27 1.27)
				)
				(justify mirror)
			)
		)
		(property "Value" ""
			(at 0 0 90)
			(layer "B.Fab")
			(effects
				(font
					(size 1.27 1.27)
				)
				(justify mirror)
			)
		)
		(duplicate_pad_numbers_are_jumpers no)
		(fp_line
			(start -0.7874 0.4064)
			(end 0.7874 0.4064)
			(stroke
				(width 0.1524)
				(type default)
			)
			(layer "B.SilkS")
		)
		(fp_line
			(start 0.7874 0.4064)
			(end 0.7874 -0.4064)
			(stroke
				(width 0.1524)
				(type default)
			)
			(layer "B.SilkS")
		)
		(fp_line
			(start -0.7874 -0.4064)
			(end -0.7874 0.4064)
			(stroke
				(width 0.1524)
				(type default)
			)
			(layer "B.SilkS")
		)
		(fp_line
			(start 0.7874 -0.4064)
			(end -0.7874 -0.4064)
			(stroke
				(width 0.1524)
				(type default)
			)
			(layer "B.SilkS")
		)
		(fp_line
			(start -0.67945 0.3048)
			(end -0.120396 0.3048)
			(stroke
				(width 0.1)
				(type default)
			)
			(layer "B.Fab")
		)
		(fp_line
			(start -0.120396 0.3048)
			(end -0.120396 0.2794)
			(stroke
				(width 0.1)
				(type default)
			)
			(layer "B.Fab")
		)
		(fp_line
			(start 0.12065 0.3048)
			(end 0.67945 0.3048)
			(stroke
				(width 0.1)
				(type default)
			)
			(layer "B.Fab")
		)
		(fp_line
			(start 0.67945 0.3048)
			(end 0.67945 -0.305054)
			(stroke
				(width 0.1)
				(type default)
			)
			(layer "B.Fab")
		)
		(fp_line
			(start -0.120396 0.2794)
			(end 0.12065 0.2794)
			(stroke
				(width 0.1)
				(type default)
			)
			(layer "B.Fab")
		)
		(fp_line
			(start 0.12065 0.2794)
			(end 0.12065 0.3048)
			(stroke
				(width 0.1)
				(type default)
			)
			(layer "B.Fab")
		)
		(fp_line
			(start -0.12065 -0.2794)
			(end -0.12065 -0.3048)
			(stroke
				(width 0.1)
				(type default)
			)
			(layer "B.Fab")
		)
		(fp_line
			(start 0.12065 -0.2794)
			(end -0.12065 -0.2794)
			(stroke
				(width 0.1)
				(type default)
			)
			(layer "B.Fab")
		)
		(fp_line
			(start -0.67945 -0.3048)
			(end -0.67945 0.3048)
			(stroke
				(width 0.1)
				(type default)
			)
			(layer "B.Fab")
		)
		(fp_line
			(start -0.12065 -0.3048)
			(end -0.67945 -0.3048)
			(stroke
				(width 0.1)
				(type default)
			)
			(layer "B.Fab")
		)
		(fp_line
			(start 0.12065 -0.305054)
			(end 0.12065 -0.2794)
			(stroke
				(width 0.1)
				(type default)
			)
			(layer "B.Fab")
		)
		(fp_line
			(start 0.67945 -0.305054)
			(end 0.12065 -0.305054)
			(stroke
				(width 0.1)
				(type default)
			)
			(layer "B.Fab")
		)
		(pad "1" smd circle
			(at 0.40005 0 90)
			(size 0 0)
			(layers "B.Cu" "B.Mask" "B.Paste")
			(net "P3V3_AUX")
		)
		(pad "2" smd circle
			(at -0.40005 0 90)
			(size 0 0)
			(layers "B.Cu" "B.Mask" "B.Paste")
			(net "GPU_3V3IO_RSVD1_FFU")
		)
	)
	(footprint ""
		(layer "B.Cu")
		(at 410.20619 -395.148562 90)
		(property "Reference" "C778"
			(at 0 0 90)
			(layer "B.SilkS")
			(hide yes)
			(effects
				(font
					(size 1.27 1.27)
				)
				(justify mirror)
			)
		)
		(property "Value" ""
			(at 0 0 90)
			(layer "B.Fab")
			(effects
				(font
					(size 1.27 1.27)
				)
				(justify mirror)
			)
		)
		(duplicate_pad_numbers_are_jumpers no)
		(fp_line
			(start 0.299974 -0.150114)
			(end -0.299974 -0.150114)
			(stroke
				(width 0.1)
				(type default)
			)
			(layer "B.Fab")
		)
		(fp_line
			(start -0.299974 -0.150114)
			(end -0.299974 0.150114)
			(stroke
				(width 0.1)
				(type default)
			)
			(layer "B.Fab")
		)
		(fp_line
			(start 0.299974 0.150114)
			(end 0.299974 -0.150114)
			(stroke
				(width 0.1)
				(type default)
			)
			(layer "B.Fab")
		)
		(fp_line
			(start -0.299974 0.150114)
			(end 0.299974 0.150114)
			(stroke
				(width 0.1)
				(type default)
			)
			(layer "B.Fab")
		)
		(pad "1" smd rect
			(at 0.2667 0 270)
			(size 0.3048 0.381)
			(layers "B.Cu" "B.Mask" "B.Paste")
			(net "P1V8_CPU0_RT2_1A")
		)
		(pad "2" smd rect
			(at -0.2667 0 270)
			(size 0.3048 0.381)
			(layers "B.Cu" "B.Mask" "B.Paste")
			(net "GND")
		)
	)
	(footprint ""
		(layer "B.Cu")
		(at 447.275966 -419.850824 -90)
		(property "Reference" "PR6807"
			(at 0 0 90)
			(layer "B.SilkS")
			(hide yes)
			(effects
				(font
					(size 1.27 1.27)
				)
				(justify mirror)
			)
		)
		(property "Value" ""
			(at 0 0 90)
			(layer "B.Fab")
			(effects
				(font
					(size 1.27 1.27)
				)
				(justify mirror)
			)
		)
		(duplicate_pad_numbers_are_jumpers no)
		(fp_line
			(start -0.7874 0.4064)
			(end 0.7874 0.4064)
			(stroke
				(width 0.1524)
				(type default)
			)
			(layer "B.SilkS")
		)
		(fp_line
			(start 0.7874 0.4064)
			(end 0.7874 -0.4064)
			(stroke
				(width 0.1524)
				(type default)
			)
			(layer "B.SilkS")
		)
		(fp_line
			(start -0.7874 -0.4064)
			(end -0.7874 0.4064)
			(stroke
				(width 0.1524)
				(type default)
			)
			(layer "B.SilkS")
		)
		(fp_line
			(start 0.7874 -0.4064)
			(end -0.7874 -0.4064)
			(stroke
				(width 0.1524)
				(type default)
			)
			(layer "B.SilkS")
		)
		(fp_line
			(start -0.67945 0.3048)
			(end -0.120396 0.3048)
			(stroke
				(width 0.1)
				(type default)
			)
			(layer "B.Fab")
		)
		(fp_line
			(start -0.120396 0.3048)
			(end -0.120396 0.2794)
			(stroke
				(width 0.1)
				(type default)
			)
			(layer "B.Fab")
		)
		(fp_line
			(start 0.12065 0.3048)
			(end 0.67945 0.3048)
			(stroke
				(width 0.1)
				(type default)
			)
			(layer "B.Fab")
		)
		(fp_line
			(start 0.67945 0.3048)
			(end 0.67945 -0.305054)
			(stroke
				(width 0.1)
				(type default)
			)
			(layer "B.Fab")
		)
		(fp_line
			(start -0.120396 0.2794)
			(end 0.12065 0.2794)
			(stroke
				(width 0.1)
				(type default)
			)
			(layer "B.Fab")
		)
		(fp_line
			(start 0.12065 0.2794)
			(end 0.12065 0.3048)
			(stroke
				(width 0.1)
				(type default)
			)
			(layer "B.Fab")
		)
		(fp_line
			(start -0.12065 -0.2794)
			(end -0.12065 -0.3048)
			(stroke
				(width 0.1)
				(type default)
			)
			(layer "B.Fab")
		)
		(fp_line
			(start 0.12065 -0.2794)
			(end -0.12065 -0.2794)
			(stroke
				(width 0.1)
				(type default)
			)
			(layer "B.Fab")
		)
		(fp_line
			(start -0.67945 -0.3048)
			(end -0.67945 0.3048)
			(stroke
				(width 0.1)
				(type default)
			)
			(layer "B.Fab")
		)
		(fp_line
			(start -0.12065 -0.3048)
			(end -0.67945 -0.3048)
			(stroke
				(width 0.1)
				(type default)
			)
			(layer "B.Fab")
		)
		(fp_line
			(start 0.12065 -0.305054)
			(end 0.12065 -0.2794)
			(stroke
				(width 0.1)
				(type default)
			)
			(layer "B.Fab")
		)
		(fp_line
			(start 0.67945 -0.305054)
			(end 0.12065 -0.305054)
			(stroke
				(width 0.1)
				(type default)
			)
			(layer "B.Fab")
		)
		(pad "1" smd circle
			(at 0.40005 0 90)
			(size 0 0)
			(layers "B.Cu" "B.Mask" "B.Paste")
			(net "P12V_AUX")
		)
		(pad "2" smd circle
			(at -0.40005 0 90)
			(size 0 0)
			(layers "B.Cu" "B.Mask" "B.Paste")
			(net "P0V9_RETIMER_CPU0_VMON")
		)
	)
	(footprint ""
		(layer "B.Cu")
		(at 404.218902 -398.942052 90)
		(property "Reference" "C974"
			(at 0 0 90)
			(layer "B.SilkS")
			(hide yes)
			(effects
				(font
					(size 1.27 1.27)
				)
				(justify mirror)
			)
		)
		(property "Value" ""
			(at 0 0 90)
			(layer "B.Fab")
			(effects
				(font
					(size 1.27 1.27)
				)
				(justify mirror)
			)
		)
		(duplicate_pad_numbers_are_jumpers no)
		(fp_line
			(start 0.7874 -0.4064)
			(end -0.7874 -0.4064)
			(stroke
				(width 0.1524)
				(type default)
			)
			(layer "B.SilkS")
		)
		(fp_line
			(start -0.7874 -0.4064)
			(end -0.7874 0.4064)
			(stroke
				(width 0.1524)
				(type default)
			)
			(layer "B.SilkS")
		)
		(fp_line
			(start 0.7874 0.4064)
			(end 0.7874 -0.4064)
			(stroke
				(width 0.1524)
				(type default)
			)
			(layer "B.SilkS")
		)
		(fp_line
			(start -0.7874 0.4064)
			(end 0.7874 0.4064)
			(stroke
				(width 0.1524)
				(type default)
			)
			(layer "B.SilkS")
		)
		(fp_line
			(start 0.67945 -0.305054)
			(end 0.12065 -0.305054)
			(stroke
				(width 0.1)
				(type default)
			)
			(layer "B.Fab")
		)
		(fp_line
			(start 0.12065 -0.305054)
			(end 0.12065 -0.2794)
			(stroke
				(width 0.1)
				(type default)
			)
			(layer "B.Fab")
		)
		(fp_line
			(start -0.12065 -0.3048)
			(end -0.67945 -0.3048)
			(stroke
				(width 0.1)
				(type default)
			)
			(layer "B.Fab")
		)
		(fp_line
			(start -0.67945 -0.3048)
			(end -0.67945 0.3048)
			(stroke
				(width 0.1)
				(type default)
			)
			(layer "B.Fab")
		)
		(fp_line
			(start 0.12065 -0.2794)
			(end -0.12065 -0.2794)
			(stroke
				(width 0.1)
				(type default)
			)
			(layer "B.Fab")
		)
		(fp_line
			(start -0.12065 -0.2794)
			(end -0.12065 -0.3048)
			(stroke
				(width 0.1)
				(type default)
			)
			(layer "B.Fab")
		)
		(fp_line
			(start 0.12065 0.2794)
			(end 0.12065 0.3048)
			(stroke
				(width 0.1)
				(type default)
			)
			(layer "B.Fab")
		)
		(fp_line
			(start -0.120396 0.2794)
			(end 0.12065 0.2794)
			(stroke
				(width 0.1)
				(type default)
			)
			(layer "B.Fab")
		)
		(fp_line
			(start 0.67945 0.3048)
			(end 0.67945 -0.305054)
			(stroke
				(width 0.1)
				(type default)
			)
			(layer "B.Fab")
		)
		(fp_line
			(start 0.12065 0.3048)
			(end 0.67945 0.3048)
			(stroke
				(width 0.1)
				(type default)
			)
			(layer "B.Fab")
		)
		(fp_line
			(start -0.120396 0.3048)
			(end -0.120396 0.2794)
			(stroke
				(width 0.1)
				(type default)
			)
			(layer "B.Fab")
		)
		(fp_line
			(start -0.67945 0.3048)
			(end -0.120396 0.3048)
			(stroke
				(width 0.1)
				(type default)
			)
			(layer "B.Fab")
		)
		(pad "1" smd circle
			(at 0.40005 0 270)
			(size 0 0)
			(layers "B.Cu" "B.Mask" "B.Paste")
			(net "P0V9_CPU0_RT2_2A")
		)
		(pad "2" smd circle
			(at -0.40005 0 270)
			(size 0 0)
			(layers "B.Cu" "B.Mask" "B.Paste")
			(net "GND")
		)
	)
	(footprint ""
		(layer "B.Cu")
		(at 302.133 -359.283 180)
		(property "Reference" "C5005"
			(at 0 0 0)
			(layer "B.SilkS")
			(hide yes)
			(effects
				(font
					(size 1.27 1.27)
				)
				(justify mirror)
			)
		)
		(property "Value" ""
			(at 0 0 0)
			(layer "B.Fab")
			(effects
				(font
					(size 1.27 1.27)
				)
				(justify mirror)
			)
		)
		(duplicate_pad_numbers_are_jumpers no)
		(fp_line
			(start 0.7874 0.4064)
			(end 0.7874 -0.4064)
			(stroke
				(width 0.1524)
				(type default)
			)
			(layer "B.SilkS")
		)
		(fp_line
			(start 0.7874 -0.4064)
			(end -0.7874 -0.4064)
			(stroke
				(width 0.1524)
				(type default)
			)
			(layer "B.SilkS")
		)
		(fp_line
			(start -0.7874 0.4064)
			(end 0.7874 0.4064)
			(stroke
				(width 0.1524)
				(type default)
			)
			(layer "B.SilkS")
		)
		(fp_line
			(start -0.7874 -0.4064)
			(end -0.7874 0.4064)
			(stroke
				(width 0.1524)
				(type default)
			)
			(layer "B.SilkS")
		)
		(fp_line
			(start 0.67945 0.3048)
			(end 0.67945 -0.305054)
			(stroke
				(width 0.1)
				(type default)
			)
			(layer "B.Fab")
		)
		(fp_line
			(start 0.67945 -0.305054)
			(end 0.12065 -0.305054)
			(stroke
				(width 0.1)
				(type default)
			)
			(layer "B.Fab")
		)
		(fp_line
			(start 0.12065 0.3048)
			(end 0.67945 0.3048)
			(stroke
				(width 0.1)
				(type default)
			)
			(layer "B.Fab")
		)
		(fp_line
			(start 0.12065 0.2794)
			(end 0.12065 0.3048)
			(stroke
				(width 0.1)
				(type default)
			)
			(layer "B.Fab")
		)
		(fp_line
			(start 0.12065 -0.2794)
			(end -0.12065 -0.2794)
			(stroke
				(width 0.1)
				(type default)
			)
			(layer "B.Fab")
		)
		(fp_line
			(start 0.12065 -0.305054)
			(end 0.12065 -0.2794)
			(stroke
				(width 0.1)
				(type default)
			)
			(layer "B.Fab")
		)
		(fp_line
			(start -0.120396 0.3048)
			(end -0.120396 0.2794)
			(stroke
				(width 0.1)
				(type default)
			)
			(layer "B.Fab")
		)
		(fp_line
			(start -0.120396 0.2794)
			(end 0.12065 0.2794)
			(stroke
				(width 0.1)
				(type default)
			)
			(layer "B.Fab")
		)
		(fp_line
			(start -0.12065 -0.2794)
			(end -0.12065 -0.3048)
			(stroke
				(width 0.1)
				(type default)
			)
			(layer "B.Fab")
		)
		(fp_line
			(start -0.12065 -0.3048)
			(end -0.67945 -0.3048)
			(stroke
				(width 0.1)
				(type default)
			)
			(layer "B.Fab")
		)
		(fp_line
			(start -0.67945 0.3048)
			(end -0.120396 0.3048)
			(stroke
				(width 0.1)
				(type default)
			)
			(layer "B.Fab")
		)
		(fp_line
			(start -0.67945 -0.3048)
			(end -0.67945 0.3048)
			(stroke
				(width 0.1)
				(type default)
			)
			(layer "B.Fab")
		)
		(pad "1" smd circle
			(at 0.40005 0)
			(size 0 0)
			(layers "B.Cu" "B.Mask" "B.Paste")
			(net "GND")
		)
		(pad "2" smd circle
			(at -0.40005 0)
			(size 0 0)
			(layers "B.Cu" "B.Mask" "B.Paste")
			(net "PWRGD_PVDDIO_P0")
		)
	)
	(footprint ""
		(layer "B.Cu")
		(at 119.59717 -381.11303 180)
		(property "Reference" "C7029"
			(at -1.78308 -3.179572 0)
			(unlocked yes)
			(layer "B.SilkS")
			(effects
				(font
					(size 0.7874 0.5842)
					(thickness 0.1524)
				)
				(justify left mirror)
			)
		)
		(property "Value" ""
			(at 0 0 0)
			(layer "B.Fab")
			(effects
				(font
					(size 1.27 1.27)
				)
				(justify mirror)
			)
		)
		(duplicate_pad_numbers_are_jumpers no)
		(fp_line
			(start 4.84378 -2.150618)
			(end 4.842256 2.163064)
			(stroke
				(width 0.1524)
				(type default)
			)
			(layer "B.SilkS")
		)
		(fp_line
			(start 4.84378 -2.150618)
			(end 4.53898 -2.150618)
			(stroke
				(width 0.1524)
				(type default)
			)
			(layer "B.SilkS")
		)
		(fp_line
			(start 4.83108 2.150364)
			(end 4.447794 2.149348)
			(stroke
				(width 0.1524)
				(type default)
			)
			(layer "B.SilkS")
		)
		(fp_line
			(start 4.69138 -2.150618)
			(end 4.692396 2.161032)
			(stroke
				(width 0.1524)
				(type default)
			)
			(layer "B.SilkS")
		)
		(fp_line
			(start 4.53898 2.15011)
			(end 4.53898 -2.15011)
			(stroke
				(width 0.1524)
				(type default)
			)
			(layer "B.SilkS")
		)
		(fp_line
			(start 4.53898 -2.15011)
			(end -4.53898 -2.15011)
			(stroke
				(width 0.1524)
				(type default)
			)
			(layer "B.SilkS")
		)
		(fp_line
			(start 4.53898 -2.150618)
			(end 4.539742 2.152142)
			(stroke
				(width 0.1524)
				(type default)
			)
			(layer "B.SilkS")
		)
		(fp_line
			(start -4.53898 2.15011)
			(end 4.53898 2.15011)
			(stroke
				(width 0.1524)
				(type default)
			)
			(layer "B.SilkS")
		)
		(fp_line
			(start -4.53898 -2.15011)
			(end -4.53898 2.15011)
			(stroke
				(width 0.1524)
				(type default)
			)
			(layer "B.SilkS")
		)
		(fp_line
			(start 3.64998 2.15011)
			(end 3.64998 -2.15011)
			(stroke
				(width 0.1)
				(type default)
			)
			(layer "B.Fab")
		)
		(fp_line
			(start 3.64998 -2.15011)
			(end -3.64998 -2.15011)
			(stroke
				(width 0.1)
				(type default)
			)
			(layer "B.Fab")
		)
		(fp_line
			(start -3.64998 2.15011)
			(end 3.64998 2.15011)
			(stroke
				(width 0.1)
				(type default)
			)
			(layer "B.Fab")
		)
		(fp_line
			(start -3.64998 -2.15011)
			(end -3.64998 2.15011)
			(stroke
				(width 0.1)
				(type default)
			)
			(layer "B.Fab")
		)
		(fp_text user "+"
			(at 4.327652 -3.357118 180)
			(unlocked yes)
			(layer "B.SilkS")
			(effects
				(font
					(size 1.905 1.4224)
					(thickness 0.1524)
				)
				(justify left mirror)
			)
		)
		(fp_text user "-"
			(at -2.992374 -2.830068 180)
			(unlocked yes)
			(layer "B.SilkS")
			(effects
				(font
					(size 1.905 1.4224)
					(thickness 0.1524)
				)
				(justify left mirror)
			)
		)
		(fp_text user "+"
			(at 6.214872 -0.337058 180)
			(unlocked yes)
			(layer "B.Fab")
			(effects
				(font
					(size 1.905 1.4224)
					(thickness 0.1524)
				)
				(justify left mirror)
			)
		)
		(fp_text user "-"
			(at -4.313174 -0.094488 180)
			(unlocked yes)
			(layer "B.Fab")
			(effects
				(font
					(size 1.905 1.4224)
					(thickness 0.1524)
				)
				(justify left mirror)
			)
		)
		(pad "1" smd rect
			(at 3.199892 0)
			(size 2.413 2.8194)
			(layers "B.Cu" "B.Mask" "B.Paste")
			(net "P0V9_CPU1_RT3_2A")
		)
		(pad "2" smd rect
			(at -3.199892 0)
			(size 2.413 2.8194)
			(layers "B.Cu" "B.Mask" "B.Paste")
			(net "GND")
		)
	)
	(footprint ""
		(layer "B.Cu")
		(at 99.862386 -269.307564)
		(property "Reference" "C2358"
			(at 0 0 0)
			(layer "B.SilkS")
			(hide yes)
			(effects
				(font
					(size 1.27 1.27)
				)
				(justify mirror)
			)
		)
		(property "Value" ""
			(at 0 0 0)
			(layer "B.Fab")
			(effects
				(font
					(size 1.27 1.27)
				)
				(justify mirror)
			)
		)
		(duplicate_pad_numbers_are_jumpers no)
		(fp_line
			(start -0.7874 -0.4064)
			(end -0.7874 0.4064)
			(stroke
				(width 0.1524)
				(type default)
			)
			(layer "B.SilkS")
		)
		(fp_line
			(start -0.7874 0.4064)
			(end 0.7874 0.4064)
			(stroke
				(width 0.1524)
				(type default)
			)
			(layer "B.SilkS")
		)
		(fp_line
			(start 0.7874 -0.4064)
			(end -0.7874 -0.4064)
			(stroke
				(width 0.1524)
				(type default)
			)
			(layer "B.SilkS")
		)
		(fp_line
			(start 0.7874 0.4064)
			(end 0.7874 -0.4064)
			(stroke
				(width 0.1524)
				(type default)
			)
			(layer "B.SilkS")
		)
		(fp_line
			(start -0.67945 -0.3048)
			(end -0.67945 0.3048)
			(stroke
				(width 0.1)
				(type default)
			)
			(layer "B.Fab")
		)
		(fp_line
			(start -0.67945 0.3048)
			(end -0.120396 0.3048)
			(stroke
				(width 0.1)
				(type default)
			)
			(layer "B.Fab")
		)
		(fp_line
			(start -0.12065 -0.3048)
			(end -0.67945 -0.3048)
			(stroke
				(width 0.1)
				(type default)
			)
			(layer "B.Fab")
		)
		(fp_line
			(start -0.12065 -0.2794)
			(end -0.12065 -0.3048)
			(stroke
				(width 0.1)
				(type default)
			)
			(layer "B.Fab")
		)
		(fp_line
			(start -0.120396 0.2794)
			(end 0.12065 0.2794)
			(stroke
				(width 0.1)
				(type default)
			)
			(layer "B.Fab")
		)
		(fp_line
			(start -0.120396 0.3048)
			(end -0.120396 0.2794)
			(stroke
				(width 0.1)
				(type default)
			)
			(layer "B.Fab")
		)
		(fp_line
			(start 0.12065 -0.305054)
			(end 0.12065 -0.2794)
			(stroke
				(width 0.1)
				(type default)
			)
			(layer "B.Fab")
		)
		(fp_line
			(start 0.12065 -0.2794)
			(end -0.12065 -0.2794)
			(stroke
				(width 0.1)
				(type default)
			)
			(layer "B.Fab")
		)
		(fp_line
			(start 0.12065 0.2794)
			(end 0.12065 0.3048)
			(stroke
				(width 0.1)
				(type default)
			)
			(layer "B.Fab")
		)
		(fp_line
			(start 0.12065 0.3048)
			(end 0.67945 0.3048)
			(stroke
				(width 0.1)
				(type default)
			)
			(layer "B.Fab")
		)
		(fp_line
			(start 0.67945 -0.305054)
			(end 0.12065 -0.305054)
			(stroke
				(width 0.1)
				(type default)
			)
			(layer "B.Fab")
		)
		(fp_line
			(start 0.67945 0.3048)
			(end 0.67945 -0.305054)
			(stroke
				(width 0.1)
				(type default)
			)
			(layer "B.Fab")
		)
		(pad "1" smd circle
			(at 0.40005 0 180)
			(size 0 0)
			(layers "B.Cu" "B.Mask" "B.Paste")
			(net "PVDDCR_CPU1_P1")
		)
		(pad "2" smd circle
			(at -0.40005 0 180)
			(size 0 0)
			(layers "B.Cu" "B.Mask" "B.Paste")
			(net "GND")
		)
	)
	(footprint ""
		(layer "B.Cu")
		(at 371.551454 -255.84531)
		(property "Reference" "C2154"
			(at 0 0 0)
			(layer "B.SilkS")
			(hide yes)
			(effects
				(font
					(size 1.27 1.27)
				)
				(justify mirror)
			)
		)
		(property "Value" ""
			(at 0 0 0)
			(layer "B.Fab")
			(effects
				(font
					(size 1.27 1.27)
				)
				(justify mirror)
			)
		)
		(duplicate_pad_numbers_are_jumpers no)
		(fp_line
			(start -0.7874 -0.4064)
			(end -0.7874 0.4064)
			(stroke
				(width 0.1524)
				(type default)
			)
			(layer "B.SilkS")
		)
		(fp_line
			(start -0.7874 0.4064)
			(end 0.7874 0.4064)
			(stroke
				(width 0.1524)
				(type default)
			)
			(layer "B.SilkS")
		)
		(fp_line
			(start 0.7874 -0.4064)
			(end -0.7874 -0.4064)
			(stroke
				(width 0.1524)
				(type default)
			)
			(layer "B.SilkS")
		)
		(fp_line
			(start 0.7874 0.4064)
			(end 0.7874 -0.4064)
			(stroke
				(width 0.1524)
				(type default)
			)
			(layer "B.SilkS")
		)
		(fp_line
			(start -0.67945 -0.3048)
			(end -0.67945 0.3048)
			(stroke
				(width 0.1)
				(type default)
			)
			(layer "B.Fab")
		)
		(fp_line
			(start -0.67945 0.3048)
			(end -0.120396 0.3048)
			(stroke
				(width 0.1)
				(type default)
			)
			(layer "B.Fab")
		)
		(fp_line
			(start -0.12065 -0.3048)
			(end -0.67945 -0.3048)
			(stroke
				(width 0.1)
				(type default)
			)
			(layer "B.Fab")
		)
		(fp_line
			(start -0.12065 -0.2794)
			(end -0.12065 -0.3048)
			(stroke
				(width 0.1)
				(type default)
			)
			(layer "B.Fab")
		)
		(fp_line
			(start -0.120396 0.2794)
			(end 0.12065 0.2794)
			(stroke
				(width 0.1)
				(type default)
			)
			(layer "B.Fab")
		)
		(fp_line
			(start -0.120396 0.3048)
			(end -0.120396 0.2794)
			(stroke
				(width 0.1)
				(type default)
			)
			(layer "B.Fab")
		)
		(fp_line
			(start 0.12065 -0.305054)
			(end 0.12065 -0.2794)
			(stroke
				(width 0.1)
				(type default)
			)
			(layer "B.Fab")
		)
		(fp_line
			(start 0.12065 -0.2794)
			(end -0.12065 -0.2794)
			(stroke
				(width 0.1)
				(type default)
			)
			(layer "B.Fab")
		)
		(fp_line
			(start 0.12065 0.2794)
			(end 0.12065 0.3048)
			(stroke
				(width 0.1)
				(type default)
			)
			(layer "B.Fab")
		)
		(fp_line
			(start 0.12065 0.3048)
			(end 0.67945 0.3048)
			(stroke
				(width 0.1)
				(type default)
			)
			(layer "B.Fab")
		)
		(fp_line
			(start 0.67945 -0.305054)
			(end 0.12065 -0.305054)
			(stroke
				(width 0.1)
				(type default)
			)
			(layer "B.Fab")
		)
		(fp_line
			(start 0.67945 0.3048)
			(end 0.67945 -0.305054)
			(stroke
				(width 0.1)
				(type default)
			)
			(layer "B.Fab")
		)
		(pad "1" smd circle
			(at 0.40005 0 180)
			(size 0 0)
			(layers "B.Cu" "B.Mask" "B.Paste")
			(net "PVDDCR_SOC_P0")
		)
		(pad "2" smd circle
			(at -0.40005 0 180)
			(size 0 0)
			(layers "B.Cu" "B.Mask" "B.Paste")
			(net "GND")
		)
	)
	(footprint ""
		(layer "B.Cu")
		(at 116.878608 -386.766562 90)
		(property "Reference" "C452"
			(at 0 0 90)
			(layer "B.SilkS")
			(hide yes)
			(effects
				(font
					(size 1.27 1.27)
				)
				(justify mirror)
			)
		)
		(property "Value" ""
			(at 0 0 90)
			(layer "B.Fab")
			(effects
				(font
					(size 1.27 1.27)
				)
				(justify mirror)
			)
		)
		(duplicate_pad_numbers_are_jumpers no)
		(fp_line
			(start 0.299974 -0.150114)
			(end -0.299974 -0.150114)
			(stroke
				(width 0.1)
				(type default)
			)
			(layer "B.Fab")
		)
		(fp_line
			(start -0.299974 -0.150114)
			(end -0.299974 0.150114)
			(stroke
				(width 0.1)
				(type default)
			)
			(layer "B.Fab")
		)
		(fp_line
			(start 0.299974 0.150114)
			(end 0.299974 -0.150114)
			(stroke
				(width 0.1)
				(type default)
			)
			(layer "B.Fab")
		)
		(fp_line
			(start -0.299974 0.150114)
			(end 0.299974 0.150114)
			(stroke
				(width 0.1)
				(type default)
			)
			(layer "B.Fab")
		)
		(pad "1" smd rect
			(at 0.2667 0 270)
			(size 0.3048 0.381)
			(layers "B.Cu" "B.Mask" "B.Paste")
			(net "P0V9_CPU1_RT3_2A")
		)
		(pad "2" smd rect
			(at -0.2667 0 270)
			(size 0.3048 0.381)
			(layers "B.Cu" "B.Mask" "B.Paste")
			(net "GND")
		)
	)
	(footprint ""
		(layer "B.Cu")
		(at 181.013608 -126.833376 90)
		(property "Reference" "R253"
			(at 0 0 90)
			(layer "B.SilkS")
			(hide yes)
			(effects
				(font
					(size 1.27 1.27)
				)
				(justify mirror)
			)
		)
		(property "Value" ""
			(at 0 0 90)
			(layer "B.Fab")
			(effects
				(font
					(size 1.27 1.27)
				)
				(justify mirror)
			)
		)
		(duplicate_pad_numbers_are_jumpers no)
		(fp_line
			(start 0.7874 -0.4064)
			(end -0.7874 -0.4064)
			(stroke
				(width 0.1524)
				(type default)
			)
			(layer "B.SilkS")
		)
		(fp_line
			(start -0.7874 -0.4064)
			(end -0.7874 0.4064)
			(stroke
				(width 0.1524)
				(type default)
			)
			(layer "B.SilkS")
		)
		(fp_line
			(start 0.7874 0.4064)
			(end 0.7874 -0.4064)
			(stroke
				(width 0.1524)
				(type default)
			)
			(layer "B.SilkS")
		)
		(fp_line
			(start -0.7874 0.4064)
			(end 0.7874 0.4064)
			(stroke
				(width 0.1524)
				(type default)
			)
			(layer "B.SilkS")
		)
		(fp_line
			(start 0.67945 -0.305054)
			(end 0.12065 -0.305054)
			(stroke
				(width 0.1)
				(type default)
			)
			(layer "B.Fab")
		)
		(fp_line
			(start 0.12065 -0.305054)
			(end 0.12065 -0.2794)
			(stroke
				(width 0.1)
				(type default)
			)
			(layer "B.Fab")
		)
		(fp_line
			(start -0.12065 -0.3048)
			(end -0.67945 -0.3048)
			(stroke
				(width 0.1)
				(type default)
			)
			(layer "B.Fab")
		)
		(fp_line
			(start -0.67945 -0.3048)
			(end -0.67945 0.3048)
			(stroke
				(width 0.1)
				(type default)
			)
			(layer "B.Fab")
		)
		(fp_line
			(start 0.12065 -0.2794)
			(end -0.12065 -0.2794)
			(stroke
				(width 0.1)
				(type default)
			)
			(layer "B.Fab")
		)
		(fp_line
			(start -0.12065 -0.2794)
			(end -0.12065 -0.3048)
			(stroke
				(width 0.1)
				(type default)
			)
			(layer "B.Fab")
		)
		(fp_line
			(start 0.12065 0.2794)
			(end 0.12065 0.3048)
			(stroke
				(width 0.1)
				(type default)
			)
			(layer "B.Fab")
		)
		(fp_line
			(start -0.120396 0.2794)
			(end 0.12065 0.2794)
			(stroke
				(width 0.1)
				(type default)
			)
			(layer "B.Fab")
		)
		(fp_line
			(start 0.67945 0.3048)
			(end 0.67945 -0.305054)
			(stroke
				(width 0.1)
				(type default)
			)
			(layer "B.Fab")
		)
		(fp_line
			(start 0.12065 0.3048)
			(end 0.67945 0.3048)
			(stroke
				(width 0.1)
				(type default)
			)
			(layer "B.Fab")
		)
		(fp_line
			(start -0.120396 0.3048)
			(end -0.120396 0.2794)
			(stroke
				(width 0.1)
				(type default)
			)
			(layer "B.Fab")
		)
		(fp_line
			(start -0.67945 0.3048)
			(end -0.120396 0.3048)
			(stroke
				(width 0.1)
				(type default)
			)
			(layer "B.Fab")
		)
		(pad "1" smd circle
			(at 0.40005 0 270)
			(size 0 0)
			(layers "B.Cu" "B.Mask" "B.Paste")
			(net "CPU0_NV_SAVE_N")
		)
		(pad "2" smd circle
			(at -0.40005 0 270)
			(size 0 0)
			(layers "B.Cu" "B.Mask" "B.Paste")
			(net "FM_CPU0_NV_SAVE_N")
		)
	)
	(footprint ""
		(layer "B.Cu")
		(at 33.467294 -193.996564)
		(property "Reference" "R106"
			(at 0 0 0)
			(layer "B.SilkS")
			(hide yes)
			(effects
				(font
					(size 1.27 1.27)
				)
				(justify mirror)
			)
		)
		(property "Value" ""
			(at 0 0 0)
			(layer "B.Fab")
			(effects
				(font
					(size 1.27 1.27)
				)
				(justify mirror)
			)
		)
		(duplicate_pad_numbers_are_jumpers no)
		(fp_line
			(start -0.7874 -0.4064)
			(end -0.7874 0.4064)
			(stroke
				(width 0.1524)
				(type default)
			)
			(layer "B.SilkS")
		)
		(fp_line
			(start -0.7874 0.4064)
			(end 0.7874 0.4064)
			(stroke
				(width 0.1524)
				(type default)
			)
			(layer "B.SilkS")
		)
		(fp_line
			(start 0.7874 -0.4064)
			(end -0.7874 -0.4064)
			(stroke
				(width 0.1524)
				(type default)
			)
			(layer "B.SilkS")
		)
		(fp_line
			(start 0.7874 0.4064)
			(end 0.7874 -0.4064)
			(stroke
				(width 0.1524)
				(type default)
			)
			(layer "B.SilkS")
		)
		(fp_line
			(start -0.67945 -0.3048)
			(end -0.67945 0.3048)
			(stroke
				(width 0.1)
				(type default)
			)
			(layer "B.Fab")
		)
		(fp_line
			(start -0.67945 0.3048)
			(end -0.120396 0.3048)
			(stroke
				(width 0.1)
				(type default)
			)
			(layer "B.Fab")
		)
		(fp_line
			(start -0.12065 -0.3048)
			(end -0.67945 -0.3048)
			(stroke
				(width 0.1)
				(type default)
			)
			(layer "B.Fab")
		)
		(fp_line
			(start -0.12065 -0.2794)
			(end -0.12065 -0.3048)
			(stroke
				(width 0.1)
				(type default)
			)
			(layer "B.Fab")
		)
		(fp_line
			(start -0.120396 0.2794)
			(end 0.12065 0.2794)
			(stroke
				(width 0.1)
				(type default)
			)
			(layer "B.Fab")
		)
		(fp_line
			(start -0.120396 0.3048)
			(end -0.120396 0.2794)
			(stroke
				(width 0.1)
				(type default)
			)
			(layer "B.Fab")
		)
		(fp_line
			(start 0.12065 -0.305054)
			(end 0.12065 -0.2794)
			(stroke
				(width 0.1)
				(type default)
			)
			(layer "B.Fab")
		)
		(fp_line
			(start 0.12065 -0.2794)
			(end -0.12065 -0.2794)
			(stroke
				(width 0.1)
				(type default)
			)
			(layer "B.Fab")
		)
		(fp_line
			(start 0.12065 0.2794)
			(end 0.12065 0.3048)
			(stroke
				(width 0.1)
				(type default)
			)
			(layer "B.Fab")
		)
		(fp_line
			(start 0.12065 0.3048)
			(end 0.67945 0.3048)
			(stroke
				(width 0.1)
				(type default)
			)
			(layer "B.Fab")
		)
		(fp_line
			(start 0.67945 -0.305054)
			(end 0.12065 -0.305054)
			(stroke
				(width 0.1)
				(type default)
			)
			(layer "B.Fab")
		)
		(fp_line
			(start 0.67945 0.3048)
			(end 0.67945 -0.305054)
			(stroke
				(width 0.1)
				(type default)
			)
			(layer "B.Fab")
		)
		(pad "1" smd circle
			(at 0.40005 0 180)
			(size 0 0)
			(layers "B.Cu" "B.Mask" "B.Paste")
			(net "P3V3")
		)
		(pad "2" smd circle
			(at -0.40005 0 180)
			(size 0 0)
			(layers "B.Cu" "B.Mask" "B.Paste")
			(net "PWRGD_CHD_CPU1_DIMM")
		)
	)
	(footprint ""
		(layer "B.Cu")
		(at 10.808208 -138.93927 180)
		(property "Reference" "L17"
			(at 0 0 0)
			(layer "B.SilkS")
			(hide yes)
			(effects
				(font
					(size 1.27 1.27)
				)
				(justify mirror)
			)
		)
		(property "Value" ""
			(at 0 0 0)
			(layer "B.Fab")
			(effects
				(font
					(size 1.27 1.27)
				)
				(justify mirror)
			)
		)
		(duplicate_pad_numbers_are_jumpers no)
		(fp_line
			(start 1.63576 -0.8128)
			(end 1.63576 0.8128)
			(stroke
				(width 0.1524)
				(type default)
			)
			(layer "B.SilkS")
		)
		(fp_line
			(start 1.63576 -0.8128)
			(end -1.63576 -0.8128)
			(stroke
				(width 0.1524)
				(type default)
			)
			(layer "B.SilkS")
		)
		(fp_line
			(start -1.63576 0.8128)
			(end 1.63576 0.8128)
			(stroke
				(width 0.1524)
				(type default)
			)
			(layer "B.SilkS")
		)
		(fp_line
			(start -1.63576 -0.8128)
			(end -1.63576 0.8128)
			(stroke
				(width 0.1524)
				(type default)
			)
			(layer "B.SilkS")
		)
		(fp_line
			(start 1.56083 0.7366)
			(end 1.524 0.7366)
			(stroke
				(width 0.1)
				(type default)
			)
			(layer "B.Fab")
		)
		(fp_line
			(start 1.56083 -0.738632)
			(end 1.56083 0.7366)
			(stroke
				(width 0.1)
				(type default)
			)
			(layer "B.Fab")
		)
		(fp_line
			(start 1.524 0.7366)
			(end -1.524 0.7366)
			(stroke
				(width 0.1)
				(type default)
			)
			(layer "B.Fab")
		)
		(fp_line
			(start -1.524 0.7366)
			(end -1.560576 0.7366)
			(stroke
				(width 0.1)
				(type default)
			)
			(layer "B.Fab")
		)
		(fp_line
			(start -1.560576 0.7366)
			(end -1.560576 -0.738632)
			(stroke
				(width 0.1)
				(type default)
			)
			(layer "B.Fab")
		)
		(fp_line
			(start -1.560576 -0.738632)
			(end 1.56083 -0.738632)
			(stroke
				(width 0.1)
				(type default)
			)
			(layer "B.Fab")
		)
		(pad "1" smd rect
			(at 0.94996 0 180)
			(size 1.1176 1.3716)
			(layers "B.Cu" "B.Mask" "B.Paste")
			(net "P3V3_AUX")
		)
		(pad "2" smd rect
			(at -0.94996 0 180)
			(size 1.1176 1.3716)
			(layers "B.Cu" "B.Mask" "B.Paste")
			(net "VFG3P3_CLK_GEN")
		)
	)
	(footprint ""
		(layer "B.Cu")
		(at 473.874592 -202.415902 180)
		(property "Reference" "DB13"
			(at 2.443988 -8.440928 270)
			(unlocked yes)
			(layer "B.SilkS")
			(effects
				(font
					(size 0.7874 0.5842)
					(thickness 0.1524)
				)
				(justify left mirror)
			)
		)
		(property "Value" ""
			(at 0 0 0)
			(layer "B.Fab")
			(effects
				(font
					(size 1.27 1.27)
				)
				(justify mirror)
			)
		)
		(duplicate_pad_numbers_are_jumpers no)
		(fp_line
			(start 3.330702 -4.771136)
			(end -3.330702 -4.771136)
			(stroke
				(width 0.1524)
				(type default)
			)
			(layer "B.SilkS")
		)
		(fp_line
			(start 0 4.011168)
			(end 3.330702 -4.771136)
			(stroke
				(width 0.1524)
				(type default)
			)
			(layer "B.SilkS")
		)
		(fp_line
			(start -3.330702 -4.771136)
			(end 0 4.011168)
			(stroke
				(width 0.1524)
				(type default)
			)
			(layer "B.SilkS")
		)
		(fp_line
			(start 3.330702 -4.771136)
			(end -3.330702 -4.771136)
			(stroke
				(width 0.1)
				(type default)
			)
			(layer "B.Fab")
		)
		(fp_line
			(start 0 4.011168)
			(end 3.330702 -4.771136)
			(stroke
				(width 0.1)
				(type default)
			)
			(layer "B.Fab")
		)
		(fp_line
			(start -3.330702 -4.771136)
			(end 0 4.011168)
			(stroke
				(width 0.1)
				(type default)
			)
			(layer "B.Fab")
		)
		(pad "1" thru_hole circle
			(at 0 0)
			(size 2.159 2.159)
			(drill 1.7018)
			(layers "*.Cu" "*.Mask")
			(remove_unused_layers no)
			(net "T1_GND")
			(clearance 0.0254)
			(thermal_gap 0.0254)
		)
		(pad "2" thru_hole circle
			(at 1.27 -3.348736)
			(size 2.159 2.159)
			(drill 1.7018)
			(layers "*.Cu" "*.Mask")
			(remove_unused_layers no)
			(net "TDR_SE_45_OHM_IN5")
			(clearance 0.0254)
			(thermal_gap 0.0254)
		)
		(pad "3" thru_hole circle
			(at -1.27 -3.348736)
			(size 2.159 2.159)
			(drill 1.7018)
			(layers "*.Cu" "*.Mask")
			(remove_unused_layers no)
			(net "TDR_SE_45_OHM_IN5")
			(clearance 0.0254)
			(thermal_gap 0.0254)
		)
	)
	(footprint ""
		(layer "B.Cu")
		(at 182.801768 -413.743394 180)
		(property "Reference" "R2917"
			(at 0 0 0)
			(layer "B.SilkS")
			(hide yes)
			(effects
				(font
					(size 1.27 1.27)
				)
				(justify mirror)
			)
		)
		(property "Value" ""
			(at 0 0 0)
			(layer "B.Fab")
			(effects
				(font
					(size 1.27 1.27)
				)
				(justify mirror)
			)
		)
		(duplicate_pad_numbers_are_jumpers no)
		(fp_line
			(start 0.7874 0.4064)
			(end 0.7874 -0.4064)
			(stroke
				(width 0.1524)
				(type default)
			)
			(layer "B.SilkS")
		)
		(fp_line
			(start 0.7874 -0.4064)
			(end -0.7874 -0.4064)
			(stroke
				(width 0.1524)
				(type default)
			)
			(layer "B.SilkS")
		)
		(fp_line
			(start -0.7874 0.4064)
			(end 0.7874 0.4064)
			(stroke
				(width 0.1524)
				(type default)
			)
			(layer "B.SilkS")
		)
		(fp_line
			(start -0.7874 -0.4064)
			(end -0.7874 0.4064)
			(stroke
				(width 0.1524)
				(type default)
			)
			(layer "B.SilkS")
		)
		(fp_line
			(start 0.67945 0.3048)
			(end 0.67945 -0.305054)
			(stroke
				(width 0.1)
				(type default)
			)
			(layer "B.Fab")
		)
		(fp_line
			(start 0.67945 -0.305054)
			(end 0.12065 -0.305054)
			(stroke
				(width 0.1)
				(type default)
			)
			(layer "B.Fab")
		)
		(fp_line
			(start 0.12065 0.3048)
			(end 0.67945 0.3048)
			(stroke
				(width 0.1)
				(type default)
			)
			(layer "B.Fab")
		)
		(fp_line
			(start 0.12065 0.2794)
			(end 0.12065 0.3048)
			(stroke
				(width 0.1)
				(type default)
			)
			(layer "B.Fab")
		)
		(fp_line
			(start 0.12065 -0.2794)
			(end -0.12065 -0.2794)
			(stroke
				(width 0.1)
				(type default)
			)
			(layer "B.Fab")
		)
		(fp_line
			(start 0.12065 -0.305054)
			(end 0.12065 -0.2794)
			(stroke
				(width 0.1)
				(type default)
			)
			(layer "B.Fab")
		)
		(fp_line
			(start -0.120396 0.3048)
			(end -0.120396 0.2794)
			(stroke
				(width 0.1)
				(type default)
			)
			(layer "B.Fab")
		)
		(fp_line
			(start -0.120396 0.2794)
			(end 0.12065 0.2794)
			(stroke
				(width 0.1)
				(type default)
			)
			(layer "B.Fab")
		)
		(fp_line
			(start -0.12065 -0.2794)
			(end -0.12065 -0.3048)
			(stroke
				(width 0.1)
				(type default)
			)
			(layer "B.Fab")
		)
		(fp_line
			(start -0.12065 -0.3048)
			(end -0.67945 -0.3048)
			(stroke
				(width 0.1)
				(type default)
			)
			(layer "B.Fab")
		)
		(fp_line
			(start -0.67945 0.3048)
			(end -0.120396 0.3048)
			(stroke
				(width 0.1)
				(type default)
			)
			(layer "B.Fab")
		)
		(fp_line
			(start -0.67945 -0.3048)
			(end -0.67945 0.3048)
			(stroke
				(width 0.1)
				(type default)
			)
			(layer "B.Fab")
		)
		(pad "1" smd circle
			(at 0.40005 0)
			(size 0 0)
			(layers "B.Cu" "B.Mask" "B.Paste")
			(net "BMC_MONITER_BUF_R")
		)
		(pad "2" smd circle
			(at -0.40005 0)
			(size 0 0)
			(layers "B.Cu" "B.Mask" "B.Paste")
			(net "BMC_MONITER_BUF")
		)
	)
	(footprint ""
		(layer "B.Cu")
		(at 19.748246 -383.038096 -90)
		(property "Reference" "PC6643_2"
			(at 0 0 90)
			(layer "B.SilkS")
			(hide yes)
			(effects
				(font
					(size 1.27 1.27)
				)
				(justify mirror)
			)
		)
		(property "Value" ""
			(at 0 0 90)
			(layer "B.Fab")
			(effects
				(font
					(size 1.27 1.27)
				)
				(justify mirror)
			)
		)
		(duplicate_pad_numbers_are_jumpers no)
		(fp_line
			(start -1.524 0.762)
			(end 1.524 0.762)
			(stroke
				(width 0.1524)
				(type default)
			)
			(layer "B.SilkS")
		)
		(fp_line
			(start 1.524 0.762)
			(end 1.524 -0.762)
			(stroke
				(width 0.1524)
				(type default)
			)
			(layer "B.SilkS")
		)
		(fp_line
			(start -1.524 -0.762)
			(end -1.524 0.762)
			(stroke
				(width 0.1524)
				(type default)
			)
			(layer "B.SilkS")
		)
		(fp_line
			(start 1.524 -0.762)
			(end -1.524 -0.762)
			(stroke
				(width 0.1524)
				(type default)
			)
			(layer "B.SilkS")
		)
		(fp_line
			(start -1.1049 0.724916)
			(end -1.1049 -0.724916)
			(stroke
				(width 0.1)
				(type default)
			)
			(layer "B.Fab")
		)
		(fp_line
			(start 1.1049 0.724916)
			(end -1.1049 0.724916)
			(stroke
				(width 0.1)
				(type default)
			)
			(layer "B.Fab")
		)
		(fp_line
			(start -1.1049 -0.724916)
			(end 1.1049 -0.724916)
			(stroke
				(width 0.1)
				(type default)
			)
			(layer "B.Fab")
		)
		(fp_line
			(start 1.1049 -0.724916)
			(end 1.1049 0.724916)
			(stroke
				(width 0.1)
				(type default)
			)
			(layer "B.Fab")
		)
		(pad "1" smd rect
			(at 0.889 0 270)
			(size 1.016 1.27)
			(layers "B.Cu" "B.Mask" "B.Paste")
			(net "P0V9_CPU1_RT_2D")
		)
		(pad "2" smd rect
			(at -0.889 0 270)
			(size 1.016 1.27)
			(layers "B.Cu" "B.Mask" "B.Paste")
			(net "GND")
		)
	)
	(footprint ""
		(layer "B.Cu")
		(at 438.344564 -194.893946 180)
		(property "Reference" "R1577"
			(at 0 0 0)
			(layer "B.SilkS")
			(hide yes)
			(effects
				(font
					(size 1.27 1.27)
				)
				(justify mirror)
			)
		)
		(property "Value" ""
			(at 0 0 0)
			(layer "B.Fab")
			(effects
				(font
					(size 1.27 1.27)
				)
				(justify mirror)
			)
		)
		(duplicate_pad_numbers_are_jumpers no)
		(fp_line
			(start 0.7874 0.4064)
			(end 0.7874 -0.4064)
			(stroke
				(width 0.1524)
				(type default)
			)
			(layer "B.SilkS")
		)
		(fp_line
			(start 0.7874 -0.4064)
			(end -0.7874 -0.4064)
			(stroke
				(width 0.1524)
				(type default)
			)
			(layer "B.SilkS")
		)
		(fp_line
			(start -0.7874 0.4064)
			(end 0.7874 0.4064)
			(stroke
				(width 0.1524)
				(type default)
			)
			(layer "B.SilkS")
		)
		(fp_line
			(start -0.7874 -0.4064)
			(end -0.7874 0.4064)
			(stroke
				(width 0.1524)
				(type default)
			)
			(layer "B.SilkS")
		)
		(fp_line
			(start 0.67945 0.3048)
			(end 0.67945 -0.305054)
			(stroke
				(width 0.1)
				(type default)
			)
			(layer "B.Fab")
		)
		(fp_line
			(start 0.67945 -0.305054)
			(end 0.12065 -0.305054)
			(stroke
				(width 0.1)
				(type default)
			)
			(layer "B.Fab")
		)
		(fp_line
			(start 0.12065 0.3048)
			(end 0.67945 0.3048)
			(stroke
				(width 0.1)
				(type default)
			)
			(layer "B.Fab")
		)
		(fp_line
			(start 0.12065 0.2794)
			(end 0.12065 0.3048)
			(stroke
				(width 0.1)
				(type default)
			)
			(layer "B.Fab")
		)
		(fp_line
			(start 0.12065 -0.2794)
			(end -0.12065 -0.2794)
			(stroke
				(width 0.1)
				(type default)
			)
			(layer "B.Fab")
		)
		(fp_line
			(start 0.12065 -0.305054)
			(end 0.12065 -0.2794)
			(stroke
				(width 0.1)
				(type default)
			)
			(layer "B.Fab")
		)
		(fp_line
			(start -0.120396 0.3048)
			(end -0.120396 0.2794)
			(stroke
				(width 0.1)
				(type default)
			)
			(layer "B.Fab")
		)
		(fp_line
			(start -0.120396 0.2794)
			(end 0.12065 0.2794)
			(stroke
				(width 0.1)
				(type default)
			)
			(layer "B.Fab")
		)
		(fp_line
			(start -0.12065 -0.2794)
			(end -0.12065 -0.3048)
			(stroke
				(width 0.1)
				(type default)
			)
			(layer "B.Fab")
		)
		(fp_line
			(start -0.12065 -0.3048)
			(end -0.67945 -0.3048)
			(stroke
				(width 0.1)
				(type default)
			)
			(layer "B.Fab")
		)
		(fp_line
			(start -0.67945 0.3048)
			(end -0.120396 0.3048)
			(stroke
				(width 0.1)
				(type default)
			)
			(layer "B.Fab")
		)
		(fp_line
			(start -0.67945 -0.3048)
			(end -0.67945 0.3048)
			(stroke
				(width 0.1)
				(type default)
			)
			(layer "B.Fab")
		)
		(pad "1" smd circle
			(at 0.40005 0)
			(size 0 0)
			(layers "B.Cu" "B.Mask" "B.Paste")
			(net "I3C_SPD_DDRGL_CPU0_SCL")
		)
		(pad "2" smd circle
			(at -0.40005 0)
			(size 0 0)
			(layers "B.Cu" "B.Mask" "B.Paste")
			(net "I3C_SPD_DDRJ_CPU0_SCL")
		)
	)
	(footprint ""
		(layer "B.Cu")
		(at 348.04604 -396.393162 -90)
		(property "Reference" "C615"
			(at 0 0 90)
			(layer "B.SilkS")
			(hide yes)
			(effects
				(font
					(size 1.27 1.27)
				)
				(justify mirror)
			)
		)
		(property "Value" ""
			(at 0 0 90)
			(layer "B.Fab")
			(effects
				(font
					(size 1.27 1.27)
				)
				(justify mirror)
			)
		)
		(duplicate_pad_numbers_are_jumpers no)
		(fp_line
			(start -0.299974 0.150114)
			(end 0.299974 0.150114)
			(stroke
				(width 0.1)
				(type default)
			)
			(layer "B.Fab")
		)
		(fp_line
			(start 0.299974 0.150114)
			(end 0.299974 -0.150114)
			(stroke
				(width 0.1)
				(type default)
			)
			(layer "B.Fab")
		)
		(fp_line
			(start -0.299974 -0.150114)
			(end -0.299974 0.150114)
			(stroke
				(width 0.1)
				(type default)
			)
			(layer "B.Fab")
		)
		(fp_line
			(start 0.299974 -0.150114)
			(end -0.299974 -0.150114)
			(stroke
				(width 0.1)
				(type default)
			)
			(layer "B.Fab")
		)
		(pad "1" smd rect
			(at 0.2667 0 90)
			(size 0.3048 0.381)
			(layers "B.Cu" "B.Mask" "B.Paste")
			(net "P0V9_CPU0_RT_2D")
		)
		(pad "2" smd rect
			(at -0.2667 0 90)
			(size 0.3048 0.381)
			(layers "B.Cu" "B.Mask" "B.Paste")
			(net "GND")
		)
	)
	(footprint ""
		(layer "B.Cu")
		(at 332.464664 -73.534778)
		(property "Reference" "Q81"
			(at 1.4859 2.394712 0)
			(unlocked yes)
			(layer "B.SilkS")
			(effects
				(font
					(size 0.7874 0.5842)
					(thickness 0.1524)
				)
				(justify left mirror)
			)
		)
		(property "Value" ""
			(at 0 0 0)
			(layer "B.Fab")
			(effects
				(font
					(size 1.27 1.27)
				)
				(justify mirror)
			)
		)
		(duplicate_pad_numbers_are_jumpers no)
		(fp_line
			(start -1.332738 -1.100074)
			(end -1.332738 1.100074)
			(stroke
				(width 0.1524)
				(type default)
			)
			(layer "B.SilkS")
		)
		(fp_line
			(start -1.332738 1.100074)
			(end 1.332738 1.100074)
			(stroke
				(width 0.1524)
				(type default)
			)
			(layer "B.SilkS")
		)
		(fp_line
			(start -0.4826 -1.100074)
			(end -1.332738 -1.100074)
			(stroke
				(width 0.1524)
				(type default)
			)
			(layer "B.SilkS")
		)
		(fp_line
			(start 0 -0.541274)
			(end -0.4826 -1.100074)
			(stroke
				(width 0.1524)
				(type default)
			)
			(layer "B.SilkS")
		)
		(fp_line
			(start 0.4826 -1.100074)
			(end 0 -0.541274)
			(stroke
				(width 0.1524)
				(type default)
			)
			(layer "B.SilkS")
		)
		(fp_line
			(start 1.332738 -1.100074)
			(end 0.4826 -1.100074)
			(stroke
				(width 0.1524)
				(type default)
			)
			(layer "B.SilkS")
		)
		(fp_line
			(start 1.332738 1.100074)
			(end 1.332738 -1.100074)
			(stroke
				(width 0.1524)
				(type default)
			)
			(layer "B.SilkS")
		)
		(fp_poly
			(pts
				(xy 1.533144 -0.649986) (xy 2.2352 -1.001014) (xy 2.2352 -0.298958)
			)
			(stroke
				(width 0)
				(type default)
			)
			(fill yes)
			(layer "B.SilkS")
		)
		(fp_line
			(start -0.674878 -1.100074)
			(end -0.674878 1.100074)
			(stroke
				(width 0.1)
				(type default)
			)
			(layer "B.Fab")
		)
		(fp_line
			(start -0.674878 1.100074)
			(end 0.674878 1.100074)
			(stroke
				(width 0.1)
				(type default)
			)
			(layer "B.Fab")
		)
		(fp_line
			(start 0.674878 -1.100074)
			(end -0.674878 -1.100074)
			(stroke
				(width 0.1)
				(type default)
			)
			(layer "B.Fab")
		)
		(fp_line
			(start 0.674878 1.100074)
			(end 0.674878 -1.100074)
			(stroke
				(width 0.1)
				(type default)
			)
			(layer "B.Fab")
		)
		(fp_poly
			(pts
				(xy 2.2352 -0.298958) (xy 2.2352 -1.001014) (xy 1.533144 -0.649986)
			)
			(stroke
				(width 0)
				(type default)
			)
			(fill yes)
			(layer "B.Fab")
		)
		(pad "1" smd rect
			(at 0.94996 -0.649986 90)
			(size 0.4318 0.508)
			(layers "B.Cu" "B.Mask" "B.Paste")
			(net "GND")
		)
		(pad "2" smd rect
			(at 0.94996 0 90)
			(size 0.4318 0.508)
			(layers "B.Cu" "B.Mask" "B.Paste")
			(net "FM_LED_PWRGD_PVDDIO_P0")
		)
		(pad "3" smd rect
			(at 0.94996 0.649986 90)
			(size 0.4318 0.508)
			(layers "B.Cu" "B.Mask" "B.Paste")
			(net "LED_PWRGD_PVDD11_S3_P0_D")
		)
		(pad "4" smd rect
			(at -0.94996 0.649986 90)
			(size 0.4318 0.508)
			(layers "B.Cu" "B.Mask" "B.Paste")
			(net "GND")
		)
		(pad "5" smd rect
			(at -0.94996 0 90)
			(size 0.4318 0.508)
			(layers "B.Cu" "B.Mask" "B.Paste")
			(net "FM_LED_PWRGD_PVDD11_S3_P0")
		)
		(pad "6" smd rect
			(at -0.94996 -0.649986 90)
			(size 0.4318 0.508)
			(layers "B.Cu" "B.Mask" "B.Paste")
			(net "LED_PWRGD_PVDDIO_P0_D")
		)
	)
	(footprint ""
		(layer "B.Cu")
		(at 171.976288 -427.923706 180)
		(property "Reference" "R6236"
			(at 0 0 0)
			(layer "B.SilkS")
			(hide yes)
			(effects
				(font
					(size 1.27 1.27)
				)
				(justify mirror)
			)
		)
		(property "Value" ""
			(at 0 0 0)
			(layer "B.Fab")
			(effects
				(font
					(size 1.27 1.27)
				)
				(justify mirror)
			)
		)
		(duplicate_pad_numbers_are_jumpers no)
		(fp_line
			(start 0.7874 0.4064)
			(end 0.7874 -0.4064)
			(stroke
				(width 0.1524)
				(type default)
			)
			(layer "B.SilkS")
		)
		(fp_line
			(start 0.7874 -0.4064)
			(end -0.7874 -0.4064)
			(stroke
				(width 0.1524)
				(type default)
			)
			(layer "B.SilkS")
		)
		(fp_line
			(start -0.7874 0.4064)
			(end 0.7874 0.4064)
			(stroke
				(width 0.1524)
				(type default)
			)
			(layer "B.SilkS")
		)
		(fp_line
			(start -0.7874 -0.4064)
			(end -0.7874 0.4064)
			(stroke
				(width 0.1524)
				(type default)
			)
			(layer "B.SilkS")
		)
		(fp_line
			(start 0.67945 0.3048)
			(end 0.67945 -0.305054)
			(stroke
				(width 0.1)
				(type default)
			)
			(layer "B.Fab")
		)
		(fp_line
			(start 0.67945 -0.305054)
			(end 0.12065 -0.305054)
			(stroke
				(width 0.1)
				(type default)
			)
			(layer "B.Fab")
		)
		(fp_line
			(start 0.12065 0.3048)
			(end 0.67945 0.3048)
			(stroke
				(width 0.1)
				(type default)
			)
			(layer "B.Fab")
		)
		(fp_line
			(start 0.12065 0.2794)
			(end 0.12065 0.3048)
			(stroke
				(width 0.1)
				(type default)
			)
			(layer "B.Fab")
		)
		(fp_line
			(start 0.12065 -0.2794)
			(end -0.12065 -0.2794)
			(stroke
				(width 0.1)
				(type default)
			)
			(layer "B.Fab")
		)
		(fp_line
			(start 0.12065 -0.305054)
			(end 0.12065 -0.2794)
			(stroke
				(width 0.1)
				(type default)
			)
			(layer "B.Fab")
		)
		(fp_line
			(start -0.120396 0.3048)
			(end -0.120396 0.2794)
			(stroke
				(width 0.1)
				(type default)
			)
			(layer "B.Fab")
		)
		(fp_line
			(start -0.120396 0.2794)
			(end 0.12065 0.2794)
			(stroke
				(width 0.1)
				(type default)
			)
			(layer "B.Fab")
		)
		(fp_line
			(start -0.12065 -0.2794)
			(end -0.12065 -0.3048)
			(stroke
				(width 0.1)
				(type default)
			)
			(layer "B.Fab")
		)
		(fp_line
			(start -0.12065 -0.3048)
			(end -0.67945 -0.3048)
			(stroke
				(width 0.1)
				(type default)
			)
			(layer "B.Fab")
		)
		(fp_line
			(start -0.67945 0.3048)
			(end -0.120396 0.3048)
			(stroke
				(width 0.1)
				(type default)
			)
			(layer "B.Fab")
		)
		(fp_line
			(start -0.67945 -0.3048)
			(end -0.67945 0.3048)
			(stroke
				(width 0.1)
				(type default)
			)
			(layer "B.Fab")
		)
		(pad "1" smd circle
			(at 0.40005 0)
			(size 0 0)
			(layers "B.Cu" "B.Mask" "B.Paste")
			(net "P3V3_AUX")
		)
		(pad "2" smd circle
			(at -0.40005 0)
			(size 0 0)
			(layers "B.Cu" "B.Mask" "B.Paste")
			(net "A_HSC_LOW_GATE")
		)
	)
	(footprint ""
		(layer "B.Cu")
		(at 448.051682 -53.20411 -90)
		(property "Reference" "PC8013"
			(at 0 0 90)
			(layer "B.SilkS")
			(hide yes)
			(effects
				(font
					(size 1.27 1.27)
				)
				(justify mirror)
			)
		)
		(property "Value" ""
			(at 0 0 90)
			(layer "B.Fab")
			(effects
				(font
					(size 1.27 1.27)
				)
				(justify mirror)
			)
		)
		(duplicate_pad_numbers_are_jumpers no)
		(fp_line
			(start -1.524 0.762)
			(end 1.524 0.762)
			(stroke
				(width 0.1524)
				(type default)
			)
			(layer "B.SilkS")
		)
		(fp_line
			(start 1.524 0.762)
			(end 1.524 -0.762)
			(stroke
				(width 0.1524)
				(type default)
			)
			(layer "B.SilkS")
		)
		(fp_line
			(start -1.524 -0.762)
			(end -1.524 0.762)
			(stroke
				(width 0.1524)
				(type default)
			)
			(layer "B.SilkS")
		)
		(fp_line
			(start 1.524 -0.762)
			(end -1.524 -0.762)
			(stroke
				(width 0.1524)
				(type default)
			)
			(layer "B.SilkS")
		)
		(fp_line
			(start -1.1049 0.724916)
			(end -1.1049 -0.724916)
			(stroke
				(width 0.1)
				(type default)
			)
			(layer "B.Fab")
		)
		(fp_line
			(start 1.1049 0.724916)
			(end -1.1049 0.724916)
			(stroke
				(width 0.1)
				(type default)
			)
			(layer "B.Fab")
		)
		(fp_line
			(start -1.1049 -0.724916)
			(end 1.1049 -0.724916)
			(stroke
				(width 0.1)
				(type default)
			)
			(layer "B.Fab")
		)
		(fp_line
			(start 1.1049 -0.724916)
			(end 1.1049 0.724916)
			(stroke
				(width 0.1)
				(type default)
			)
			(layer "B.Fab")
		)
		(pad "1" smd rect
			(at 0.889 0 270)
			(size 1.016 1.27)
			(layers "B.Cu" "B.Mask" "B.Paste")
			(net "SW_P3V3_AUX_FLT")
		)
		(pad "2" smd rect
			(at -0.889 0 270)
			(size 1.016 1.27)
			(layers "B.Cu" "B.Mask" "B.Paste")
			(net "GND")
		)
	)
	(footprint ""
		(layer "B.Cu")
		(at 47.391066 -390.560052 90)
		(property "Reference" "C250"
			(at 0 0 90)
			(layer "B.SilkS")
			(hide yes)
			(effects
				(font
					(size 1.27 1.27)
				)
				(justify mirror)
			)
		)
		(property "Value" ""
			(at 0 0 90)
			(layer "B.Fab")
			(effects
				(font
					(size 1.27 1.27)
				)
				(justify mirror)
			)
		)
		(duplicate_pad_numbers_are_jumpers no)
		(fp_line
			(start 0.7874 -0.4064)
			(end -0.7874 -0.4064)
			(stroke
				(width 0.1524)
				(type default)
			)
			(layer "B.SilkS")
		)
		(fp_line
			(start -0.7874 -0.4064)
			(end -0.7874 0.4064)
			(stroke
				(width 0.1524)
				(type default)
			)
			(layer "B.SilkS")
		)
		(fp_line
			(start 0.7874 0.4064)
			(end 0.7874 -0.4064)
			(stroke
				(width 0.1524)
				(type default)
			)
			(layer "B.SilkS")
		)
		(fp_line
			(start -0.7874 0.4064)
			(end 0.7874 0.4064)
			(stroke
				(width 0.1524)
				(type default)
			)
			(layer "B.SilkS")
		)
		(fp_line
			(start 0.67945 -0.305054)
			(end 0.12065 -0.305054)
			(stroke
				(width 0.1)
				(type default)
			)
			(layer "B.Fab")
		)
		(fp_line
			(start 0.12065 -0.305054)
			(end 0.12065 -0.2794)
			(stroke
				(width 0.1)
				(type default)
			)
			(layer "B.Fab")
		)
		(fp_line
			(start -0.12065 -0.3048)
			(end -0.67945 -0.3048)
			(stroke
				(width 0.1)
				(type default)
			)
			(layer "B.Fab")
		)
		(fp_line
			(start -0.67945 -0.3048)
			(end -0.67945 0.3048)
			(stroke
				(width 0.1)
				(type default)
			)
			(layer "B.Fab")
		)
		(fp_line
			(start 0.12065 -0.2794)
			(end -0.12065 -0.2794)
			(stroke
				(width 0.1)
				(type default)
			)
			(layer "B.Fab")
		)
		(fp_line
			(start -0.12065 -0.2794)
			(end -0.12065 -0.3048)
			(stroke
				(width 0.1)
				(type default)
			)
			(layer "B.Fab")
		)
		(fp_line
			(start 0.12065 0.2794)
			(end 0.12065 0.3048)
			(stroke
				(width 0.1)
				(type default)
			)
			(layer "B.Fab")
		)
		(fp_line
			(start -0.120396 0.2794)
			(end 0.12065 0.2794)
			(stroke
				(width 0.1)
				(type default)
			)
			(layer "B.Fab")
		)
		(fp_line
			(start 0.67945 0.3048)
			(end 0.67945 -0.305054)
			(stroke
				(width 0.1)
				(type default)
			)
			(layer "B.Fab")
		)
		(fp_line
			(start 0.12065 0.3048)
			(end 0.67945 0.3048)
			(stroke
				(width 0.1)
				(type default)
			)
			(layer "B.Fab")
		)
		(fp_line
			(start -0.120396 0.3048)
			(end -0.120396 0.2794)
			(stroke
				(width 0.1)
				(type default)
			)
			(layer "B.Fab")
		)
		(fp_line
			(start -0.67945 0.3048)
			(end -0.120396 0.3048)
			(stroke
				(width 0.1)
				(type default)
			)
			(layer "B.Fab")
		)
		(pad "1" smd circle
			(at 0.40005 0 270)
			(size 0 0)
			(layers "B.Cu" "B.Mask" "B.Paste")
			(net "P0V9_CPU1_RT0_2A")
		)
		(pad "2" smd circle
			(at -0.40005 0 270)
			(size 0 0)
			(layers "B.Cu" "B.Mask" "B.Paste")
			(net "GND")
		)
	)
	(footprint ""
		(layer "B.Cu")
		(at 271.760696 -349.381572 -90)
		(property "Reference" "PR112"
			(at 0 0 90)
			(layer "B.SilkS")
			(hide yes)
			(effects
				(font
					(size 1.27 1.27)
				)
				(justify mirror)
			)
		)
		(property "Value" ""
			(at 0 0 90)
			(layer "B.Fab")
			(effects
				(font
					(size 1.27 1.27)
				)
				(justify mirror)
			)
		)
		(duplicate_pad_numbers_are_jumpers no)
		(fp_line
			(start -0.7874 0.4064)
			(end 0.7874 0.4064)
			(stroke
				(width 0.1524)
				(type default)
			)
			(layer "B.SilkS")
		)
		(fp_line
			(start 0.7874 0.4064)
			(end 0.7874 -0.4064)
			(stroke
				(width 0.1524)
				(type default)
			)
			(layer "B.SilkS")
		)
		(fp_line
			(start -0.7874 -0.4064)
			(end -0.7874 0.4064)
			(stroke
				(width 0.1524)
				(type default)
			)
			(layer "B.SilkS")
		)
		(fp_line
			(start 0.7874 -0.4064)
			(end -0.7874 -0.4064)
			(stroke
				(width 0.1524)
				(type default)
			)
			(layer "B.SilkS")
		)
		(fp_line
			(start -0.67945 0.3048)
			(end -0.120396 0.3048)
			(stroke
				(width 0.1)
				(type default)
			)
			(layer "B.Fab")
		)
		(fp_line
			(start -0.120396 0.3048)
			(end -0.120396 0.2794)
			(stroke
				(width 0.1)
				(type default)
			)
			(layer "B.Fab")
		)
		(fp_line
			(start 0.12065 0.3048)
			(end 0.67945 0.3048)
			(stroke
				(width 0.1)
				(type default)
			)
			(layer "B.Fab")
		)
		(fp_line
			(start 0.67945 0.3048)
			(end 0.67945 -0.305054)
			(stroke
				(width 0.1)
				(type default)
			)
			(layer "B.Fab")
		)
		(fp_line
			(start -0.120396 0.2794)
			(end 0.12065 0.2794)
			(stroke
				(width 0.1)
				(type default)
			)
			(layer "B.Fab")
		)
		(fp_line
			(start 0.12065 0.2794)
			(end 0.12065 0.3048)
			(stroke
				(width 0.1)
				(type default)
			)
			(layer "B.Fab")
		)
		(fp_line
			(start -0.12065 -0.2794)
			(end -0.12065 -0.3048)
			(stroke
				(width 0.1)
				(type default)
			)
			(layer "B.Fab")
		)
		(fp_line
			(start 0.12065 -0.2794)
			(end -0.12065 -0.2794)
			(stroke
				(width 0.1)
				(type default)
			)
			(layer "B.Fab")
		)
		(fp_line
			(start -0.67945 -0.3048)
			(end -0.67945 0.3048)
			(stroke
				(width 0.1)
				(type default)
			)
			(layer "B.Fab")
		)
		(fp_line
			(start -0.12065 -0.3048)
			(end -0.67945 -0.3048)
			(stroke
				(width 0.1)
				(type default)
			)
			(layer "B.Fab")
		)
		(fp_line
			(start 0.12065 -0.305054)
			(end 0.12065 -0.2794)
			(stroke
				(width 0.1)
				(type default)
			)
			(layer "B.Fab")
		)
		(fp_line
			(start 0.67945 -0.305054)
			(end 0.12065 -0.305054)
			(stroke
				(width 0.1)
				(type default)
			)
			(layer "B.Fab")
		)
		(pad "1" smd circle
			(at 0.40005 0 90)
			(size 0 0)
			(layers "B.Cu" "B.Mask" "B.Paste")
			(net "PVDDIO_P0_VOS4")
		)
		(pad "2" smd circle
			(at -0.40005 0 90)
			(size 0 0)
			(layers "B.Cu" "B.Mask" "B.Paste")
			(net "PVDDIO_P0")
		)
	)
	(footprint ""
		(layer "B.Cu")
		(at 198.47433 -70.903084)
		(property "Reference" "U223"
			(at 1.73482 3.30073 0)
			(unlocked yes)
			(layer "B.SilkS")
			(effects
				(font
					(size 0.7874 0.5842)
					(thickness 0.1524)
				)
				(justify left mirror)
			)
		)
		(property "Value" ""
			(at 0 0 0)
			(layer "B.Fab")
			(effects
				(font
					(size 1.27 1.27)
				)
				(justify mirror)
			)
		)
		(duplicate_pad_numbers_are_jumpers no)
		(fp_line
			(start -2.0066 -2.5527)
			(end -2.0066 2.5527)
			(stroke
				(width 0.1524)
				(type default)
			)
			(layer "B.SilkS")
		)
		(fp_line
			(start -2.0066 2.5527)
			(end 2.0066 2.5527)
			(stroke
				(width 0.1524)
				(type default)
			)
			(layer "B.SilkS")
		)
		(fp_line
			(start -0.5715 -2.5527)
			(end -2.0066 -2.5527)
			(stroke
				(width 0.1524)
				(type default)
			)
			(layer "B.SilkS")
		)
		(fp_line
			(start 0 -1.9812)
			(end -0.5715 -2.5527)
			(stroke
				(width 0.1524)
				(type default)
			)
			(layer "B.SilkS")
		)
		(fp_line
			(start 0.5715 -2.5527)
			(end 0 -1.9812)
			(stroke
				(width 0.1524)
				(type default)
			)
			(layer "B.SilkS")
		)
		(fp_line
			(start 2.0066 -2.5527)
			(end 0.5715 -2.5527)
			(stroke
				(width 0.1524)
				(type default)
			)
			(layer "B.SilkS")
		)
		(fp_line
			(start 2.0066 2.5527)
			(end 2.0066 -2.5527)
			(stroke
				(width 0.1524)
				(type default)
			)
			(layer "B.SilkS")
		)
		(fp_poly
			(pts
				(xy 3.81 -1.905) (xy 4.36372 -2.233168) (xy 4.36372 -1.608328)
			)
			(stroke
				(width 0)
				(type default)
			)
			(fill yes)
			(layer "B.SilkS")
		)
		(fp_line
			(start -2.249932 -2.549906)
			(end -2.249932 2.549906)
			(stroke
				(width 0.1)
				(type default)
			)
			(layer "B.Fab")
		)
		(fp_line
			(start -2.249932 2.549906)
			(end 2.249932 2.549906)
			(stroke
				(width 0.1)
				(type default)
			)
			(layer "B.Fab")
		)
		(fp_line
			(start 2.249932 -2.549906)
			(end -2.249932 -2.549906)
			(stroke
				(width 0.1)
				(type default)
			)
			(layer "B.Fab")
		)
		(fp_line
			(start 2.249932 2.549906)
			(end 2.249932 -2.549906)
			(stroke
				(width 0.1)
				(type default)
			)
			(layer "B.Fab")
		)
		(fp_poly
			(pts
				(xy 4.36372 -1.608328) (xy 4.36372 -2.233168) (xy 3.81 -1.905)
			)
			(stroke
				(width 0)
				(type default)
			)
			(fill yes)
			(layer "B.Fab")
		)
		(pad "1" smd rect
			(at 2.921 -1.949958 270)
			(size 0.3556 1.4986)
			(layers "B.Cu" "B.Mask" "B.Paste")
			(net "FB_BMC_ISOLATE1")
		)
		(pad "2" smd rect
			(at 2.921 -1.299972 270)
			(size 0.3556 1.4986)
			(layers "B.Cu" "B.Mask" "B.Paste")
			(net "NCSI_BMC_TXD1_R1")
		)
		(pad "3" smd rect
			(at 2.921 -0.649986 270)
			(size 0.3556 1.4986)
			(layers "B.Cu" "B.Mask" "B.Paste")
			(net "NCSI_OCP_V3_2_TXD1")
		)
		(pad "4" smd rect
			(at 2.921 0 270)
			(size 0.3556 1.4986)
			(layers "B.Cu" "B.Mask" "B.Paste")
			(net "FB_BMC_ISOLATE1")
		)
		(pad "5" smd rect
			(at 2.921 0.649986 270)
			(size 0.3556 1.4986)
			(layers "B.Cu" "B.Mask" "B.Paste")
			(net "NCSI_BMC_TXD0_R1")
		)
		(pad "6" smd rect
			(at 2.921 1.299972 270)
			(size 0.3556 1.4986)
			(layers "B.Cu" "B.Mask" "B.Paste")
			(net "NCSI_OCP_V3_2_TXD0")
		)
		(pad "7" smd rect
			(at 2.921 1.949958 270)
			(size 0.3556 1.4986)
			(layers "B.Cu" "B.Mask" "B.Paste")
			(net "GND")
		)
		(pad "8" smd rect
			(at -2.921 1.949958 270)
			(size 0.3556 1.4986)
			(layers "B.Cu" "B.Mask" "B.Paste")
			(net "NCSI_OCP_V3_2_TX_EN")
		)
		(pad "9" smd rect
			(at -2.921 1.299972 270)
			(size 0.3556 1.4986)
			(layers "B.Cu" "B.Mask" "B.Paste")
			(net "NCSI_BMC_TX_EN_R1")
		)
		(pad "10" smd rect
			(at -2.921 0.649986 270)
			(size 0.3556 1.4986)
			(layers "B.Cu" "B.Mask" "B.Paste")
			(net "FB_BMC_ISOLATE1")
		)
		(pad "11" smd rect
			(at -2.921 0 270)
			(size 0.3556 1.4986)
			(layers "B.Cu" "B.Mask" "B.Paste")
			(net "OCP_V3_2_ISO2_RBT_ARB_OUT")
		)
		(pad "12" smd rect
			(at -2.921 -0.649986 270)
			(size 0.3556 1.4986)
			(layers "B.Cu" "B.Mask" "B.Paste")
			(net "OCP_V3_2_RBT_ARB_OUT")
		)
		(pad "13" smd rect
			(at -2.921 -1.299972 270)
			(size 0.3556 1.4986)
			(layers "B.Cu" "B.Mask" "B.Paste")
			(net "FB_BMC_ISOLATE1")
		)
		(pad "14" smd rect
			(at -2.921 -1.949958 270)
			(size 0.3556 1.4986)
			(layers "B.Cu" "B.Mask" "B.Paste")
			(net "P3V3_AUX")
		)
	)
	(footprint ""
		(layer "B.Cu")
		(at 330.947014 -398.969484)
		(property "Reference" "C633"
			(at 0 0 0)
			(layer "B.SilkS")
			(hide yes)
			(effects
				(font
					(size 1.27 1.27)
				)
				(justify mirror)
			)
		)
		(property "Value" ""
			(at 0 0 0)
			(layer "B.Fab")
			(effects
				(font
					(size 1.27 1.27)
				)
				(justify mirror)
			)
		)
		(duplicate_pad_numbers_are_jumpers no)
		(fp_line
			(start -1.524 -0.762)
			(end -1.524 0.762)
			(stroke
				(width 0.1524)
				(type default)
			)
			(layer "B.SilkS")
		)
		(fp_line
			(start -1.524 0.762)
			(end 1.524 0.762)
			(stroke
				(width 0.1524)
				(type default)
			)
			(layer "B.SilkS")
		)
		(fp_line
			(start 1.524 -0.762)
			(end -1.524 -0.762)
			(stroke
				(width 0.1524)
				(type default)
			)
			(layer "B.SilkS")
		)
		(fp_line
			(start 1.524 0.762)
			(end 1.524 -0.762)
			(stroke
				(width 0.1524)
				(type default)
			)
			(layer "B.SilkS")
		)
		(fp_line
			(start -1.1049 -0.724916)
			(end 1.1049 -0.724916)
			(stroke
				(width 0.1)
				(type default)
			)
			(layer "B.Fab")
		)
		(fp_line
			(start -1.1049 0.724916)
			(end -1.1049 -0.724916)
			(stroke
				(width 0.1)
				(type default)
			)
			(layer "B.Fab")
		)
		(fp_line
			(start 1.1049 -0.724916)
			(end 1.1049 0.724916)
			(stroke
				(width 0.1)
				(type default)
			)
			(layer "B.Fab")
		)
		(fp_line
			(start 1.1049 0.724916)
			(end -1.1049 0.724916)
			(stroke
				(width 0.1)
				(type default)
			)
			(layer "B.Fab")
		)
		(pad "1" smd rect
			(at 0.889 0)
			(size 1.016 1.27)
			(layers "B.Cu" "B.Mask" "B.Paste")
			(net "P0V9_CPU0_RT1_2A")
		)
		(pad "2" smd rect
			(at -0.889 0)
			(size 1.016 1.27)
			(layers "B.Cu" "B.Mask" "B.Paste")
			(net "GND")
		)
	)
	(footprint ""
		(layer "B.Cu")
		(at 316.93739 -76.639928 90)
		(property "Reference" "R4604"
			(at 0 0 90)
			(layer "B.SilkS")
			(hide yes)
			(effects
				(font
					(size 1.27 1.27)
				)
				(justify mirror)
			)
		)
		(property "Value" ""
			(at 0 0 90)
			(layer "B.Fab")
			(effects
				(font
					(size 1.27 1.27)
				)
				(justify mirror)
			)
		)
		(duplicate_pad_numbers_are_jumpers no)
		(fp_line
			(start 0.7874 -0.4064)
			(end -0.7874 -0.4064)
			(stroke
				(width 0.1524)
				(type default)
			)
			(layer "B.SilkS")
		)
		(fp_line
			(start -0.7874 -0.4064)
			(end -0.7874 0.4064)
			(stroke
				(width 0.1524)
				(type default)
			)
			(layer "B.SilkS")
		)
		(fp_line
			(start 0.7874 0.4064)
			(end 0.7874 -0.4064)
			(stroke
				(width 0.1524)
				(type default)
			)
			(layer "B.SilkS")
		)
		(fp_line
			(start -0.7874 0.4064)
			(end 0.7874 0.4064)
			(stroke
				(width 0.1524)
				(type default)
			)
			(layer "B.SilkS")
		)
		(fp_line
			(start 0.67945 -0.305054)
			(end 0.12065 -0.305054)
			(stroke
				(width 0.1)
				(type default)
			)
			(layer "B.Fab")
		)
		(fp_line
			(start 0.12065 -0.305054)
			(end 0.12065 -0.2794)
			(stroke
				(width 0.1)
				(type default)
			)
			(layer "B.Fab")
		)
		(fp_line
			(start -0.12065 -0.3048)
			(end -0.67945 -0.3048)
			(stroke
				(width 0.1)
				(type default)
			)
			(layer "B.Fab")
		)
		(fp_line
			(start -0.67945 -0.3048)
			(end -0.67945 0.3048)
			(stroke
				(width 0.1)
				(type default)
			)
			(layer "B.Fab")
		)
		(fp_line
			(start 0.12065 -0.2794)
			(end -0.12065 -0.2794)
			(stroke
				(width 0.1)
				(type default)
			)
			(layer "B.Fab")
		)
		(fp_line
			(start -0.12065 -0.2794)
			(end -0.12065 -0.3048)
			(stroke
				(width 0.1)
				(type default)
			)
			(layer "B.Fab")
		)
		(fp_line
			(start 0.12065 0.2794)
			(end 0.12065 0.3048)
			(stroke
				(width 0.1)
				(type default)
			)
			(layer "B.Fab")
		)
		(fp_line
			(start -0.120396 0.2794)
			(end 0.12065 0.2794)
			(stroke
				(width 0.1)
				(type default)
			)
			(layer "B.Fab")
		)
		(fp_line
			(start 0.67945 0.3048)
			(end 0.67945 -0.305054)
			(stroke
				(width 0.1)
				(type default)
			)
			(layer "B.Fab")
		)
		(fp_line
			(start 0.12065 0.3048)
			(end 0.67945 0.3048)
			(stroke
				(width 0.1)
				(type default)
			)
			(layer "B.Fab")
		)
		(fp_line
			(start -0.120396 0.3048)
			(end -0.120396 0.2794)
			(stroke
				(width 0.1)
				(type default)
			)
			(layer "B.Fab")
		)
		(fp_line
			(start -0.67945 0.3048)
			(end -0.120396 0.3048)
			(stroke
				(width 0.1)
				(type default)
			)
			(layer "B.Fab")
		)
		(pad "1" smd circle
			(at 0.40005 0 270)
			(size 0 0)
			(layers "B.Cu" "B.Mask" "B.Paste")
			(net "P3V3_AUX")
		)
		(pad "2" smd circle
			(at -0.40005 0 270)
			(size 0 0)
			(layers "B.Cu" "B.Mask" "B.Paste")
			(net "PWRGD_PS_PWROK_PLD_N")
		)
	)
	(footprint ""
		(layer "B.Cu")
		(at 400.761962 -314.925964)
		(property "Reference" "C215"
			(at 0 0 0)
			(layer "B.SilkS")
			(hide yes)
			(effects
				(font
					(size 1.27 1.27)
				)
				(justify mirror)
			)
		)
		(property "Value" ""
			(at 0 0 0)
			(layer "B.Fab")
			(effects
				(font
					(size 1.27 1.27)
				)
				(justify mirror)
			)
		)
		(duplicate_pad_numbers_are_jumpers no)
		(fp_line
			(start -0.7874 -0.4064)
			(end -0.7874 0.4064)
			(stroke
				(width 0.1524)
				(type default)
			)
			(layer "B.SilkS")
		)
		(fp_line
			(start -0.7874 0.4064)
			(end 0.7874 0.4064)
			(stroke
				(width 0.1524)
				(type default)
			)
			(layer "B.SilkS")
		)
		(fp_line
			(start 0.7874 -0.4064)
			(end -0.7874 -0.4064)
			(stroke
				(width 0.1524)
				(type default)
			)
			(layer "B.SilkS")
		)
		(fp_line
			(start 0.7874 0.4064)
			(end 0.7874 -0.4064)
			(stroke
				(width 0.1524)
				(type default)
			)
			(layer "B.SilkS")
		)
		(fp_line
			(start -0.67945 -0.3048)
			(end -0.67945 0.3048)
			(stroke
				(width 0.1)
				(type default)
			)
			(layer "B.Fab")
		)
		(fp_line
			(start -0.67945 0.3048)
			(end -0.120396 0.3048)
			(stroke
				(width 0.1)
				(type default)
			)
			(layer "B.Fab")
		)
		(fp_line
			(start -0.12065 -0.3048)
			(end -0.67945 -0.3048)
			(stroke
				(width 0.1)
				(type default)
			)
			(layer "B.Fab")
		)
		(fp_line
			(start -0.12065 -0.2794)
			(end -0.12065 -0.3048)
			(stroke
				(width 0.1)
				(type default)
			)
			(layer "B.Fab")
		)
		(fp_line
			(start -0.120396 0.2794)
			(end 0.12065 0.2794)
			(stroke
				(width 0.1)
				(type default)
			)
			(layer "B.Fab")
		)
		(fp_line
			(start -0.120396 0.3048)
			(end -0.120396 0.2794)
			(stroke
				(width 0.1)
				(type default)
			)
			(layer "B.Fab")
		)
		(fp_line
			(start 0.12065 -0.305054)
			(end 0.12065 -0.2794)
			(stroke
				(width 0.1)
				(type default)
			)
			(layer "B.Fab")
		)
		(fp_line
			(start 0.12065 -0.2794)
			(end -0.12065 -0.2794)
			(stroke
				(width 0.1)
				(type default)
			)
			(layer "B.Fab")
		)
		(fp_line
			(start 0.12065 0.2794)
			(end 0.12065 0.3048)
			(stroke
				(width 0.1)
				(type default)
			)
			(layer "B.Fab")
		)
		(fp_line
			(start 0.12065 0.3048)
			(end 0.67945 0.3048)
			(stroke
				(width 0.1)
				(type default)
			)
			(layer "B.Fab")
		)
		(fp_line
			(start 0.67945 -0.305054)
			(end 0.12065 -0.305054)
			(stroke
				(width 0.1)
				(type default)
			)
			(layer "B.Fab")
		)
		(fp_line
			(start 0.67945 0.3048)
			(end 0.67945 -0.305054)
			(stroke
				(width 0.1)
				(type default)
			)
			(layer "B.Fab")
		)
		(pad "1" smd circle
			(at 0.40005 0 180)
			(size 0 0)
			(layers "B.Cu" "B.Mask" "B.Paste")
			(net "XTAL_CPU0_X32K_X1")
		)
		(pad "2" smd circle
			(at -0.40005 0 180)
			(size 0 0)
			(layers "B.Cu" "B.Mask" "B.Paste")
			(net "GND")
		)
	)
	(footprint ""
		(layer "B.Cu")
		(at 63.619634 -197.202552 180)
		(property "Reference" "R516"
			(at 0 0 0)
			(layer "B.SilkS")
			(hide yes)
			(effects
				(font
					(size 1.27 1.27)
				)
				(justify mirror)
			)
		)
		(property "Value" ""
			(at 0 0 0)
			(layer "B.Fab")
			(effects
				(font
					(size 1.27 1.27)
				)
				(justify mirror)
			)
		)
		(duplicate_pad_numbers_are_jumpers no)
		(fp_line
			(start 0.7874 0.4064)
			(end 0.7874 -0.4064)
			(stroke
				(width 0.1524)
				(type default)
			)
			(layer "B.SilkS")
		)
		(fp_line
			(start 0.7874 -0.4064)
			(end -0.7874 -0.4064)
			(stroke
				(width 0.1524)
				(type default)
			)
			(layer "B.SilkS")
		)
		(fp_line
			(start -0.7874 0.4064)
			(end 0.7874 0.4064)
			(stroke
				(width 0.1524)
				(type default)
			)
			(layer "B.SilkS")
		)
		(fp_line
			(start -0.7874 -0.4064)
			(end -0.7874 0.4064)
			(stroke
				(width 0.1524)
				(type default)
			)
			(layer "B.SilkS")
		)
		(fp_line
			(start 0.67945 0.3048)
			(end 0.67945 -0.305054)
			(stroke
				(width 0.1)
				(type default)
			)
			(layer "B.Fab")
		)
		(fp_line
			(start 0.67945 -0.305054)
			(end 0.12065 -0.305054)
			(stroke
				(width 0.1)
				(type default)
			)
			(layer "B.Fab")
		)
		(fp_line
			(start 0.12065 0.3048)
			(end 0.67945 0.3048)
			(stroke
				(width 0.1)
				(type default)
			)
			(layer "B.Fab")
		)
		(fp_line
			(start 0.12065 0.2794)
			(end 0.12065 0.3048)
			(stroke
				(width 0.1)
				(type default)
			)
			(layer "B.Fab")
		)
		(fp_line
			(start 0.12065 -0.2794)
			(end -0.12065 -0.2794)
			(stroke
				(width 0.1)
				(type default)
			)
			(layer "B.Fab")
		)
		(fp_line
			(start 0.12065 -0.305054)
			(end 0.12065 -0.2794)
			(stroke
				(width 0.1)
				(type default)
			)
			(layer "B.Fab")
		)
		(fp_line
			(start -0.120396 0.3048)
			(end -0.120396 0.2794)
			(stroke
				(width 0.1)
				(type default)
			)
			(layer "B.Fab")
		)
		(fp_line
			(start -0.120396 0.2794)
			(end 0.12065 0.2794)
			(stroke
				(width 0.1)
				(type default)
			)
			(layer "B.Fab")
		)
		(fp_line
			(start -0.12065 -0.2794)
			(end -0.12065 -0.3048)
			(stroke
				(width 0.1)
				(type default)
			)
			(layer "B.Fab")
		)
		(fp_line
			(start -0.12065 -0.3048)
			(end -0.67945 -0.3048)
			(stroke
				(width 0.1)
				(type default)
			)
			(layer "B.Fab")
		)
		(fp_line
			(start -0.67945 0.3048)
			(end -0.120396 0.3048)
			(stroke
				(width 0.1)
				(type default)
			)
			(layer "B.Fab")
		)
		(fp_line
			(start -0.67945 -0.3048)
			(end -0.67945 0.3048)
			(stroke
				(width 0.1)
				(type default)
			)
			(layer "B.Fab")
		)
		(pad "1" smd circle
			(at 0.40005 0)
			(size 0 0)
			(layers "B.Cu" "B.Mask" "B.Paste")
			(net "P3V3_AUX")
		)
		(pad "2" smd circle
			(at -0.40005 0)
			(size 0 0)
			(layers "B.Cu" "B.Mask" "B.Paste")
			(net "CPU1_CORETYPE0")
		)
	)
	(footprint ""
		(layer "B.Cu")
		(at 238.708692 -422.849548 90)
		(property "Reference" "C74"
			(at 0 0 90)
			(layer "B.SilkS")
			(hide yes)
			(effects
				(font
					(size 1.27 1.27)
				)
				(justify mirror)
			)
		)
		(property "Value" ""
			(at 0 0 90)
			(layer "B.Fab")
			(effects
				(font
					(size 1.27 1.27)
				)
				(justify mirror)
			)
		)
		(duplicate_pad_numbers_are_jumpers no)
		(fp_line
			(start 0.7874 -0.4064)
			(end -0.7874 -0.4064)
			(stroke
				(width 0.1524)
				(type default)
			)
			(layer "B.SilkS")
		)
		(fp_line
			(start -0.7874 -0.4064)
			(end -0.7874 0.4064)
			(stroke
				(width 0.1524)
				(type default)
			)
			(layer "B.SilkS")
		)
		(fp_line
			(start 0.7874 0.4064)
			(end 0.7874 -0.4064)
			(stroke
				(width 0.1524)
				(type default)
			)
			(layer "B.SilkS")
		)
		(fp_line
			(start -0.7874 0.4064)
			(end 0.7874 0.4064)
			(stroke
				(width 0.1524)
				(type default)
			)
			(layer "B.SilkS")
		)
		(fp_line
			(start 0.67945 -0.305054)
			(end 0.12065 -0.305054)
			(stroke
				(width 0.1)
				(type default)
			)
			(layer "B.Fab")
		)
		(fp_line
			(start 0.12065 -0.305054)
			(end 0.12065 -0.2794)
			(stroke
				(width 0.1)
				(type default)
			)
			(layer "B.Fab")
		)
		(fp_line
			(start -0.12065 -0.3048)
			(end -0.67945 -0.3048)
			(stroke
				(width 0.1)
				(type default)
			)
			(layer "B.Fab")
		)
		(fp_line
			(start -0.67945 -0.3048)
			(end -0.67945 0.3048)
			(stroke
				(width 0.1)
				(type default)
			)
			(layer "B.Fab")
		)
		(fp_line
			(start 0.12065 -0.2794)
			(end -0.12065 -0.2794)
			(stroke
				(width 0.1)
				(type default)
			)
			(layer "B.Fab")
		)
		(fp_line
			(start -0.12065 -0.2794)
			(end -0.12065 -0.3048)
			(stroke
				(width 0.1)
				(type default)
			)
			(layer "B.Fab")
		)
		(fp_line
			(start 0.12065 0.2794)
			(end 0.12065 0.3048)
			(stroke
				(width 0.1)
				(type default)
			)
			(layer "B.Fab")
		)
		(fp_line
			(start -0.120396 0.2794)
			(end 0.12065 0.2794)
			(stroke
				(width 0.1)
				(type default)
			)
			(layer "B.Fab")
		)
		(fp_line
			(start 0.67945 0.3048)
			(end 0.67945 -0.305054)
			(stroke
				(width 0.1)
				(type default)
			)
			(layer "B.Fab")
		)
		(fp_line
			(start 0.12065 0.3048)
			(end 0.67945 0.3048)
			(stroke
				(width 0.1)
				(type default)
			)
			(layer "B.Fab")
		)
		(fp_line
			(start -0.120396 0.3048)
			(end -0.120396 0.2794)
			(stroke
				(width 0.1)
				(type default)
			)
			(layer "B.Fab")
		)
		(fp_line
			(start -0.67945 0.3048)
			(end -0.120396 0.3048)
			(stroke
				(width 0.1)
				(type default)
			)
			(layer "B.Fab")
		)
		(pad "1" smd circle
			(at 0.40005 0 270)
			(size 0 0)
			(layers "B.Cu" "B.Mask" "B.Paste")
			(net "RST_SMB_SWITCH_R_N")
		)
		(pad "2" smd circle
			(at -0.40005 0 270)
			(size 0 0)
			(layers "B.Cu" "B.Mask" "B.Paste")
			(net "GND")
		)
	)
	(footprint ""
		(layer "B.Cu")
		(at 59.51855 -388.011162 -90)
		(property "Reference" "C137"
			(at 0 0 90)
			(layer "B.SilkS")
			(hide yes)
			(effects
				(font
					(size 1.27 1.27)
				)
				(justify mirror)
			)
		)
		(property "Value" ""
			(at 0 0 90)
			(layer "B.Fab")
			(effects
				(font
					(size 1.27 1.27)
				)
				(justify mirror)
			)
		)
		(duplicate_pad_numbers_are_jumpers no)
		(fp_line
			(start -0.299974 0.150114)
			(end 0.299974 0.150114)
			(stroke
				(width 0.1)
				(type default)
			)
			(layer "B.Fab")
		)
		(fp_line
			(start 0.299974 0.150114)
			(end 0.299974 -0.150114)
			(stroke
				(width 0.1)
				(type default)
			)
			(layer "B.Fab")
		)
		(fp_line
			(start -0.299974 -0.150114)
			(end -0.299974 0.150114)
			(stroke
				(width 0.1)
				(type default)
			)
			(layer "B.Fab")
		)
		(fp_line
			(start 0.299974 -0.150114)
			(end -0.299974 -0.150114)
			(stroke
				(width 0.1)
				(type default)
			)
			(layer "B.Fab")
		)
		(pad "1" smd rect
			(at 0.2667 0 90)
			(size 0.3048 0.381)
			(layers "B.Cu" "B.Mask" "B.Paste")
			(net "P0V9_CPU1_RT_2D")
		)
		(pad "2" smd rect
			(at -0.2667 0 90)
			(size 0.3048 0.381)
			(layers "B.Cu" "B.Mask" "B.Paste")
			(net "GND")
		)
	)
	(footprint ""
		(layer "B.Cu")
		(at 458.346302 -405.972264 180)
		(property "Reference" "PC6817"
			(at 0 0 0)
			(layer "B.SilkS")
			(hide yes)
			(effects
				(font
					(size 1.27 1.27)
				)
				(justify mirror)
			)
		)
		(property "Value" ""
			(at 0 0 0)
			(layer "B.Fab")
			(effects
				(font
					(size 1.27 1.27)
				)
				(justify mirror)
			)
		)
		(duplicate_pad_numbers_are_jumpers no)
		(fp_line
			(start 1.524 0.762)
			(end 1.524 -0.762)
			(stroke
				(width 0.1524)
				(type default)
			)
			(layer "B.SilkS")
		)
		(fp_line
			(start 1.524 -0.762)
			(end -1.524 -0.762)
			(stroke
				(width 0.1524)
				(type default)
			)
			(layer "B.SilkS")
		)
		(fp_line
			(start -1.524 0.762)
			(end 1.524 0.762)
			(stroke
				(width 0.1524)
				(type default)
			)
			(layer "B.SilkS")
		)
		(fp_line
			(start -1.524 -0.762)
			(end -1.524 0.762)
			(stroke
				(width 0.1524)
				(type default)
			)
			(layer "B.SilkS")
		)
		(fp_line
			(start 1.1049 0.724916)
			(end -1.1049 0.724916)
			(stroke
				(width 0.1)
				(type default)
			)
			(layer "B.Fab")
		)
		(fp_line
			(start 1.1049 -0.724916)
			(end 1.1049 0.724916)
			(stroke
				(width 0.1)
				(type default)
			)
			(layer "B.Fab")
		)
		(fp_line
			(start -1.1049 0.724916)
			(end -1.1049 -0.724916)
			(stroke
				(width 0.1)
				(type default)
			)
			(layer "B.Fab")
		)
		(fp_line
			(start -1.1049 -0.724916)
			(end 1.1049 -0.724916)
			(stroke
				(width 0.1)
				(type default)
			)
			(layer "B.Fab")
		)
		(pad "1" smd rect
			(at 0.889 0 180)
			(size 1.016 1.27)
			(layers "B.Cu" "B.Mask" "B.Paste")
			(net "SW_P12V_AUX_P0V9_RETIMER_CPU0_FLT")
		)
		(pad "2" smd rect
			(at -0.889 0 180)
			(size 1.016 1.27)
			(layers "B.Cu" "B.Mask" "B.Paste")
			(net "GND")
		)
	)
	(footprint ""
		(layer "B.Cu")
		(at 321.51828 -396.393162 -90)
		(property "Reference" "C585"
			(at 0 0 90)
			(layer "B.SilkS")
			(hide yes)
			(effects
				(font
					(size 1.27 1.27)
				)
				(justify mirror)
			)
		)
		(property "Value" ""
			(at 0 0 90)
			(layer "B.Fab")
			(effects
				(font
					(size 1.27 1.27)
				)
				(justify mirror)
			)
		)
		(duplicate_pad_numbers_are_jumpers no)
		(fp_line
			(start -0.299974 0.150114)
			(end 0.299974 0.150114)
			(stroke
				(width 0.1)
				(type default)
			)
			(layer "B.Fab")
		)
		(fp_line
			(start 0.299974 0.150114)
			(end 0.299974 -0.150114)
			(stroke
				(width 0.1)
				(type default)
			)
			(layer "B.Fab")
		)
		(fp_line
			(start -0.299974 -0.150114)
			(end -0.299974 0.150114)
			(stroke
				(width 0.1)
				(type default)
			)
			(layer "B.Fab")
		)
		(fp_line
			(start 0.299974 -0.150114)
			(end -0.299974 -0.150114)
			(stroke
				(width 0.1)
				(type default)
			)
			(layer "B.Fab")
		)
		(pad "1" smd rect
			(at 0.2667 0 90)
			(size 0.3048 0.381)
			(layers "B.Cu" "B.Mask" "B.Paste")
			(net "P0V9_CPU0_RT0_2A")
		)
		(pad "2" smd rect
			(at -0.2667 0 90)
			(size 0.3048 0.381)
			(layers "B.Cu" "B.Mask" "B.Paste")
			(net "GND")
		)
	)
	(footprint ""
		(layer "B.Cu")
		(at 257.719576 -326.335898 180)
		(property "Reference" "C1076"
			(at 0 0 0)
			(layer "B.SilkS")
			(hide yes)
			(effects
				(font
					(size 1.27 1.27)
				)
				(justify mirror)
			)
		)
		(property "Value" ""
			(at 0 0 0)
			(layer "B.Fab")
			(effects
				(font
					(size 1.27 1.27)
				)
				(justify mirror)
			)
		)
		(duplicate_pad_numbers_are_jumpers no)
		(fp_line
			(start 1.524 0.762)
			(end 1.524 -0.762)
			(stroke
				(width 0.1524)
				(type default)
			)
			(layer "B.SilkS")
		)
		(fp_line
			(start 1.524 -0.762)
			(end -1.524 -0.762)
			(stroke
				(width 0.1524)
				(type default)
			)
			(layer "B.SilkS")
		)
		(fp_line
			(start -1.524 0.762)
			(end 1.524 0.762)
			(stroke
				(width 0.1524)
				(type default)
			)
			(layer "B.SilkS")
		)
		(fp_line
			(start -1.524 -0.762)
			(end -1.524 0.762)
			(stroke
				(width 0.1524)
				(type default)
			)
			(layer "B.SilkS")
		)
		(fp_line
			(start 1.1049 0.724916)
			(end -1.1049 0.724916)
			(stroke
				(width 0.1)
				(type default)
			)
			(layer "B.Fab")
		)
		(fp_line
			(start 1.1049 -0.724916)
			(end 1.1049 0.724916)
			(stroke
				(width 0.1)
				(type default)
			)
			(layer "B.Fab")
		)
		(fp_line
			(start -1.1049 0.724916)
			(end -1.1049 -0.724916)
			(stroke
				(width 0.1)
				(type default)
			)
			(layer "B.Fab")
		)
		(fp_line
			(start -1.1049 -0.724916)
			(end 1.1049 -0.724916)
			(stroke
				(width 0.1)
				(type default)
			)
			(layer "B.Fab")
		)
		(pad "1" smd rect
			(at 0.889 0 180)
			(size 1.016 1.27)
			(layers "B.Cu" "B.Mask" "B.Paste")
			(net "MAX11617_2_VREF")
		)
		(pad "2" smd rect
			(at -0.889 0 180)
			(size 1.016 1.27)
			(layers "B.Cu" "B.Mask" "B.Paste")
			(net "GND")
		)
	)
	(footprint ""
		(layer "B.Cu")
		(at 146.220434 -203.679552 90)
		(property "Reference" "R527"
			(at 0 0 90)
			(layer "B.SilkS")
			(hide yes)
			(effects
				(font
					(size 1.27 1.27)
				)
				(justify mirror)
			)
		)
		(property "Value" ""
			(at 0 0 90)
			(layer "B.Fab")
			(effects
				(font
					(size 1.27 1.27)
				)
				(justify mirror)
			)
		)
		(duplicate_pad_numbers_are_jumpers no)
		(fp_line
			(start 0.7874 -0.4064)
			(end -0.7874 -0.4064)
			(stroke
				(width 0.1524)
				(type default)
			)
			(layer "B.SilkS")
		)
		(fp_line
			(start -0.7874 -0.4064)
			(end -0.7874 0.4064)
			(stroke
				(width 0.1524)
				(type default)
			)
			(layer "B.SilkS")
		)
		(fp_line
			(start 0.7874 0.4064)
			(end 0.7874 -0.4064)
			(stroke
				(width 0.1524)
				(type default)
			)
			(layer "B.SilkS")
		)
		(fp_line
			(start -0.7874 0.4064)
			(end 0.7874 0.4064)
			(stroke
				(width 0.1524)
				(type default)
			)
			(layer "B.SilkS")
		)
		(fp_line
			(start 0.67945 -0.305054)
			(end 0.12065 -0.305054)
			(stroke
				(width 0.1)
				(type default)
			)
			(layer "B.Fab")
		)
		(fp_line
			(start 0.12065 -0.305054)
			(end 0.12065 -0.2794)
			(stroke
				(width 0.1)
				(type default)
			)
			(layer "B.Fab")
		)
		(fp_line
			(start -0.12065 -0.3048)
			(end -0.67945 -0.3048)
			(stroke
				(width 0.1)
				(type default)
			)
			(layer "B.Fab")
		)
		(fp_line
			(start -0.67945 -0.3048)
			(end -0.67945 0.3048)
			(stroke
				(width 0.1)
				(type default)
			)
			(layer "B.Fab")
		)
		(fp_line
			(start 0.12065 -0.2794)
			(end -0.12065 -0.2794)
			(stroke
				(width 0.1)
				(type default)
			)
			(layer "B.Fab")
		)
		(fp_line
			(start -0.12065 -0.2794)
			(end -0.12065 -0.3048)
			(stroke
				(width 0.1)
				(type default)
			)
			(layer "B.Fab")
		)
		(fp_line
			(start 0.12065 0.2794)
			(end 0.12065 0.3048)
			(stroke
				(width 0.1)
				(type default)
			)
			(layer "B.Fab")
		)
		(fp_line
			(start -0.120396 0.2794)
			(end 0.12065 0.2794)
			(stroke
				(width 0.1)
				(type default)
			)
			(layer "B.Fab")
		)
		(fp_line
			(start 0.67945 0.3048)
			(end 0.67945 -0.305054)
			(stroke
				(width 0.1)
				(type default)
			)
			(layer "B.Fab")
		)
		(fp_line
			(start 0.12065 0.3048)
			(end 0.67945 0.3048)
			(stroke
				(width 0.1)
				(type default)
			)
			(layer "B.Fab")
		)
		(fp_line
			(start -0.120396 0.3048)
			(end -0.120396 0.2794)
			(stroke
				(width 0.1)
				(type default)
			)
			(layer "B.Fab")
		)
		(fp_line
			(start -0.67945 0.3048)
			(end -0.120396 0.3048)
			(stroke
				(width 0.1)
				(type default)
			)
			(layer "B.Fab")
		)
		(pad "1" smd circle
			(at 0.40005 0 270)
			(size 0 0)
			(layers "B.Cu" "B.Mask" "B.Paste")
			(net "PVDD18_S5_P1")
		)
		(pad "2" smd circle
			(at -0.40005 0 270)
			(size 0 0)
			(layers "B.Cu" "B.Mask" "B.Paste")
			(net "JTAG_CPU1_TMS")
		)
	)
	(footprint ""
		(layer "B.Cu")
		(at 166.211504 -386.766562 90)
		(property "Reference" "C418"
			(at 0 0 90)
			(layer "B.SilkS")
			(hide yes)
			(effects
				(font
					(size 1.27 1.27)
				)
				(justify mirror)
			)
		)
		(property "Value" ""
			(at 0 0 90)
			(layer "B.Fab")
			(effects
				(font
					(size 1.27 1.27)
				)
				(justify mirror)
			)
		)
		(duplicate_pad_numbers_are_jumpers no)
		(fp_line
			(start 0.299974 -0.150114)
			(end -0.299974 -0.150114)
			(stroke
				(width 0.1)
				(type default)
			)
			(layer "B.Fab")
		)
		(fp_line
			(start -0.299974 -0.150114)
			(end -0.299974 0.150114)
			(stroke
				(width 0.1)
				(type default)
			)
			(layer "B.Fab")
		)
		(fp_line
			(start 0.299974 0.150114)
			(end 0.299974 -0.150114)
			(stroke
				(width 0.1)
				(type default)
			)
			(layer "B.Fab")
		)
		(fp_line
			(start -0.299974 0.150114)
			(end 0.299974 0.150114)
			(stroke
				(width 0.1)
				(type default)
			)
			(layer "B.Fab")
		)
		(pad "1" smd rect
			(at 0.2667 0 270)
			(size 0.3048 0.381)
			(layers "B.Cu" "B.Mask" "B.Paste")
			(net "P0V9_CPU1_RT2_2A")
		)
		(pad "2" smd rect
			(at -0.2667 0 270)
			(size 0.3048 0.381)
			(layers "B.Cu" "B.Mask" "B.Paste")
			(net "GND")
		)
	)
	(footprint ""
		(layer "B.Cu")
		(at 100.478844 -258.830318 180)
		(property "Reference" "C2507"
			(at 0 0 0)
			(layer "B.SilkS")
			(hide yes)
			(effects
				(font
					(size 1.27 1.27)
				)
				(justify mirror)
			)
		)
		(property "Value" ""
			(at 0 0 0)
			(layer "B.Fab")
			(effects
				(font
					(size 1.27 1.27)
				)
				(justify mirror)
			)
		)
		(duplicate_pad_numbers_are_jumpers no)
		(fp_line
			(start 0.7874 0.4064)
			(end 0.7874 -0.4064)
			(stroke
				(width 0.1524)
				(type default)
			)
			(layer "B.SilkS")
		)
		(fp_line
			(start 0.7874 -0.4064)
			(end -0.7874 -0.4064)
			(stroke
				(width 0.1524)
				(type default)
			)
			(layer "B.SilkS")
		)
		(fp_line
			(start -0.7874 0.4064)
			(end 0.7874 0.4064)
			(stroke
				(width 0.1524)
				(type default)
			)
			(layer "B.SilkS")
		)
		(fp_line
			(start -0.7874 -0.4064)
			(end -0.7874 0.4064)
			(stroke
				(width 0.1524)
				(type default)
			)
			(layer "B.SilkS")
		)
		(fp_line
			(start 0.67945 0.3048)
			(end 0.67945 -0.305054)
			(stroke
				(width 0.1)
				(type default)
			)
			(layer "B.Fab")
		)
		(fp_line
			(start 0.67945 -0.305054)
			(end 0.12065 -0.305054)
			(stroke
				(width 0.1)
				(type default)
			)
			(layer "B.Fab")
		)
		(fp_line
			(start 0.12065 0.3048)
			(end 0.67945 0.3048)
			(stroke
				(width 0.1)
				(type default)
			)
			(layer "B.Fab")
		)
		(fp_line
			(start 0.12065 0.2794)
			(end 0.12065 0.3048)
			(stroke
				(width 0.1)
				(type default)
			)
			(layer "B.Fab")
		)
		(fp_line
			(start 0.12065 -0.2794)
			(end -0.12065 -0.2794)
			(stroke
				(width 0.1)
				(type default)
			)
			(layer "B.Fab")
		)
		(fp_line
			(start 0.12065 -0.305054)
			(end 0.12065 -0.2794)
			(stroke
				(width 0.1)
				(type default)
			)
			(layer "B.Fab")
		)
		(fp_line
			(start -0.120396 0.3048)
			(end -0.120396 0.2794)
			(stroke
				(width 0.1)
				(type default)
			)
			(layer "B.Fab")
		)
		(fp_line
			(start -0.120396 0.2794)
			(end 0.12065 0.2794)
			(stroke
				(width 0.1)
				(type default)
			)
			(layer "B.Fab")
		)
		(fp_line
			(start -0.12065 -0.2794)
			(end -0.12065 -0.3048)
			(stroke
				(width 0.1)
				(type default)
			)
			(layer "B.Fab")
		)
		(fp_line
			(start -0.12065 -0.3048)
			(end -0.67945 -0.3048)
			(stroke
				(width 0.1)
				(type default)
			)
			(layer "B.Fab")
		)
		(fp_line
			(start -0.67945 0.3048)
			(end -0.120396 0.3048)
			(stroke
				(width 0.1)
				(type default)
			)
			(layer "B.Fab")
		)
		(fp_line
			(start -0.67945 -0.3048)
			(end -0.67945 0.3048)
			(stroke
				(width 0.1)
				(type default)
			)
			(layer "B.Fab")
		)
		(pad "1" smd circle
			(at 0.40005 0)
			(size 0 0)
			(layers "B.Cu" "B.Mask" "B.Paste")
			(net "PVDDIO_P1")
		)
		(pad "2" smd circle
			(at -0.40005 0)
			(size 0 0)
			(layers "B.Cu" "B.Mask" "B.Paste")
			(net "GND")
		)
	)
	(footprint ""
		(layer "B.Cu")
		(at 46.434502 -424.305984 -90)
		(property "Reference" "R2842"
			(at 0 0 90)
			(layer "B.SilkS")
			(hide yes)
			(effects
				(font
					(size 1.27 1.27)
				)
				(justify mirror)
			)
		)
		(property "Value" ""
			(at 0 0 90)
			(layer "B.Fab")
			(effects
				(font
					(size 1.27 1.27)
				)
				(justify mirror)
			)
		)
		(duplicate_pad_numbers_are_jumpers no)
		(fp_line
			(start -0.7874 0.4064)
			(end 0.7874 0.4064)
			(stroke
				(width 0.1524)
				(type default)
			)
			(layer "B.SilkS")
		)
		(fp_line
			(start 0.7874 0.4064)
			(end 0.7874 -0.4064)
			(stroke
				(width 0.1524)
				(type default)
			)
			(layer "B.SilkS")
		)
		(fp_line
			(start -0.7874 -0.4064)
			(end -0.7874 0.4064)
			(stroke
				(width 0.1524)
				(type default)
			)
			(layer "B.SilkS")
		)
		(fp_line
			(start 0.7874 -0.4064)
			(end -0.7874 -0.4064)
			(stroke
				(width 0.1524)
				(type default)
			)
			(layer "B.SilkS")
		)
		(fp_line
			(start -0.67945 0.3048)
			(end -0.120396 0.3048)
			(stroke
				(width 0.1)
				(type default)
			)
			(layer "B.Fab")
		)
		(fp_line
			(start -0.120396 0.3048)
			(end -0.120396 0.2794)
			(stroke
				(width 0.1)
				(type default)
			)
			(layer "B.Fab")
		)
		(fp_line
			(start 0.12065 0.3048)
			(end 0.67945 0.3048)
			(stroke
				(width 0.1)
				(type default)
			)
			(layer "B.Fab")
		)
		(fp_line
			(start 0.67945 0.3048)
			(end 0.67945 -0.305054)
			(stroke
				(width 0.1)
				(type default)
			)
			(layer "B.Fab")
		)
		(fp_line
			(start -0.120396 0.2794)
			(end 0.12065 0.2794)
			(stroke
				(width 0.1)
				(type default)
			)
			(layer "B.Fab")
		)
		(fp_line
			(start 0.12065 0.2794)
			(end 0.12065 0.3048)
			(stroke
				(width 0.1)
				(type default)
			)
			(layer "B.Fab")
		)
		(fp_line
			(start -0.12065 -0.2794)
			(end -0.12065 -0.3048)
			(stroke
				(width 0.1)
				(type default)
			)
			(layer "B.Fab")
		)
		(fp_line
			(start 0.12065 -0.2794)
			(end -0.12065 -0.2794)
			(stroke
				(width 0.1)
				(type default)
			)
			(layer "B.Fab")
		)
		(fp_line
			(start -0.67945 -0.3048)
			(end -0.67945 0.3048)
			(stroke
				(width 0.1)
				(type default)
			)
			(layer "B.Fab")
		)
		(fp_line
			(start -0.12065 -0.3048)
			(end -0.67945 -0.3048)
			(stroke
				(width 0.1)
				(type default)
			)
			(layer "B.Fab")
		)
		(fp_line
			(start 0.12065 -0.305054)
			(end 0.12065 -0.2794)
			(stroke
				(width 0.1)
				(type default)
			)
			(layer "B.Fab")
		)
		(fp_line
			(start 0.67945 -0.305054)
			(end 0.12065 -0.305054)
			(stroke
				(width 0.1)
				(type default)
			)
			(layer "B.Fab")
		)
		(pad "1" smd circle
			(at 0.40005 0 90)
			(size 0 0)
			(layers "B.Cu" "B.Mask" "B.Paste")
			(net "P3V3_AUX")
		)
		(pad "2" smd circle
			(at -0.40005 0 90)
			(size 0 0)
			(layers "B.Cu" "B.Mask" "B.Paste")
			(net "FM_GPU_PWRGD_N")
		)
	)
	(footprint ""
		(layer "B.Cu")
		(at 179.32146 -190.948564 180)
		(property "Reference" "R311"
			(at 0 0 0)
			(layer "B.SilkS")
			(hide yes)
			(effects
				(font
					(size 1.27 1.27)
				)
				(justify mirror)
			)
		)
		(property "Value" ""
			(at 0 0 0)
			(layer "B.Fab")
			(effects
				(font
					(size 1.27 1.27)
				)
				(justify mirror)
			)
		)
		(duplicate_pad_numbers_are_jumpers no)
		(fp_line
			(start 0.7874 0.4064)
			(end 0.7874 -0.4064)
			(stroke
				(width 0.1524)
				(type default)
			)
			(layer "B.SilkS")
		)
		(fp_line
			(start 0.7874 -0.4064)
			(end -0.7874 -0.4064)
			(stroke
				(width 0.1524)
				(type default)
			)
			(layer "B.SilkS")
		)
		(fp_line
			(start -0.7874 0.4064)
			(end 0.7874 0.4064)
			(stroke
				(width 0.1524)
				(type default)
			)
			(layer "B.SilkS")
		)
		(fp_line
			(start -0.7874 -0.4064)
			(end -0.7874 0.4064)
			(stroke
				(width 0.1524)
				(type default)
			)
			(layer "B.SilkS")
		)
		(fp_line
			(start 0.67945 0.3048)
			(end 0.67945 -0.305054)
			(stroke
				(width 0.1)
				(type default)
			)
			(layer "B.Fab")
		)
		(fp_line
			(start 0.67945 -0.305054)
			(end 0.12065 -0.305054)
			(stroke
				(width 0.1)
				(type default)
			)
			(layer "B.Fab")
		)
		(fp_line
			(start 0.12065 0.3048)
			(end 0.67945 0.3048)
			(stroke
				(width 0.1)
				(type default)
			)
			(layer "B.Fab")
		)
		(fp_line
			(start 0.12065 0.2794)
			(end 0.12065 0.3048)
			(stroke
				(width 0.1)
				(type default)
			)
			(layer "B.Fab")
		)
		(fp_line
			(start 0.12065 -0.2794)
			(end -0.12065 -0.2794)
			(stroke
				(width 0.1)
				(type default)
			)
			(layer "B.Fab")
		)
		(fp_line
			(start 0.12065 -0.305054)
			(end 0.12065 -0.2794)
			(stroke
				(width 0.1)
				(type default)
			)
			(layer "B.Fab")
		)
		(fp_line
			(start -0.120396 0.3048)
			(end -0.120396 0.2794)
			(stroke
				(width 0.1)
				(type default)
			)
			(layer "B.Fab")
		)
		(fp_line
			(start -0.120396 0.2794)
			(end 0.12065 0.2794)
			(stroke
				(width 0.1)
				(type default)
			)
			(layer "B.Fab")
		)
		(fp_line
			(start -0.12065 -0.2794)
			(end -0.12065 -0.3048)
			(stroke
				(width 0.1)
				(type default)
			)
			(layer "B.Fab")
		)
		(fp_line
			(start -0.12065 -0.3048)
			(end -0.67945 -0.3048)
			(stroke
				(width 0.1)
				(type default)
			)
			(layer "B.Fab")
		)
		(fp_line
			(start -0.67945 0.3048)
			(end -0.120396 0.3048)
			(stroke
				(width 0.1)
				(type default)
			)
			(layer "B.Fab")
		)
		(fp_line
			(start -0.67945 -0.3048)
			(end -0.67945 0.3048)
			(stroke
				(width 0.1)
				(type default)
			)
			(layer "B.Fab")
		)
		(pad "1" smd circle
			(at 0.40005 0)
			(size 0 0)
			(layers "B.Cu" "B.Mask" "B.Paste")
			(net "PWRGD_CHI_CPU1_DIMM")
		)
		(pad "2" smd circle
			(at -0.40005 0)
			(size 0 0)
			(layers "B.Cu" "B.Mask" "B.Paste")
			(net "PWRGD_CHGL_CPU1")
		)
	)
	(footprint ""
		(layer "B.Cu")
		(at 201.12355 -115.955572 180)
		(property "Reference" "R2"
			(at 0 0 0)
			(layer "B.SilkS")
			(hide yes)
			(effects
				(font
					(size 1.27 1.27)
				)
				(justify mirror)
			)
		)
		(property "Value" ""
			(at 0 0 0)
			(layer "B.Fab")
			(effects
				(font
					(size 1.27 1.27)
				)
				(justify mirror)
			)
		)
		(duplicate_pad_numbers_are_jumpers no)
		(fp_line
			(start 0.7874 0.4064)
			(end 0.7874 -0.4064)
			(stroke
				(width 0.1524)
				(type default)
			)
			(layer "B.SilkS")
		)
		(fp_line
			(start 0.7874 -0.4064)
			(end -0.7874 -0.4064)
			(stroke
				(width 0.1524)
				(type default)
			)
			(layer "B.SilkS")
		)
		(fp_line
			(start -0.7874 0.4064)
			(end 0.7874 0.4064)
			(stroke
				(width 0.1524)
				(type default)
			)
			(layer "B.SilkS")
		)
		(fp_line
			(start -0.7874 -0.4064)
			(end -0.7874 0.4064)
			(stroke
				(width 0.1524)
				(type default)
			)
			(layer "B.SilkS")
		)
		(fp_line
			(start 0.67945 0.3048)
			(end 0.67945 -0.305054)
			(stroke
				(width 0.1)
				(type default)
			)
			(layer "B.Fab")
		)
		(fp_line
			(start 0.67945 -0.305054)
			(end 0.12065 -0.305054)
			(stroke
				(width 0.1)
				(type default)
			)
			(layer "B.Fab")
		)
		(fp_line
			(start 0.12065 0.3048)
			(end 0.67945 0.3048)
			(stroke
				(width 0.1)
				(type default)
			)
			(layer "B.Fab")
		)
		(fp_line
			(start 0.12065 0.2794)
			(end 0.12065 0.3048)
			(stroke
				(width 0.1)
				(type default)
			)
			(layer "B.Fab")
		)
		(fp_line
			(start 0.12065 -0.2794)
			(end -0.12065 -0.2794)
			(stroke
				(width 0.1)
				(type default)
			)
			(layer "B.Fab")
		)
		(fp_line
			(start 0.12065 -0.305054)
			(end 0.12065 -0.2794)
			(stroke
				(width 0.1)
				(type default)
			)
			(layer "B.Fab")
		)
		(fp_line
			(start -0.120396 0.3048)
			(end -0.120396 0.2794)
			(stroke
				(width 0.1)
				(type default)
			)
			(layer "B.Fab")
		)
		(fp_line
			(start -0.120396 0.2794)
			(end 0.12065 0.2794)
			(stroke
				(width 0.1)
				(type default)
			)
			(layer "B.Fab")
		)
		(fp_line
			(start -0.12065 -0.2794)
			(end -0.12065 -0.3048)
			(stroke
				(width 0.1)
				(type default)
			)
			(layer "B.Fab")
		)
		(fp_line
			(start -0.12065 -0.3048)
			(end -0.67945 -0.3048)
			(stroke
				(width 0.1)
				(type default)
			)
			(layer "B.Fab")
		)
		(fp_line
			(start -0.67945 0.3048)
			(end -0.120396 0.3048)
			(stroke
				(width 0.1)
				(type default)
			)
			(layer "B.Fab")
		)
		(fp_line
			(start -0.67945 -0.3048)
			(end -0.67945 0.3048)
			(stroke
				(width 0.1)
				(type default)
			)
			(layer "B.Fab")
		)
		(pad "1" smd circle
			(at 0.40005 0)
			(size 0 0)
			(layers "B.Cu" "B.Mask" "B.Paste")
			(net "RST_PERST_CPU1_SWB_1_N")
		)
		(pad "2" smd circle
			(at -0.40005 0)
			(size 0 0)
			(layers "B.Cu" "B.Mask" "B.Paste")
			(net "RST_PERST_CPU1_SWB_1_R_N")
		)
	)
	(footprint ""
		(layer "B.Cu")
		(at 116.400326 -408.517344 90)
		(property "Reference" "C6726"
			(at 0 0 90)
			(layer "B.SilkS")
			(hide yes)
			(effects
				(font
					(size 1.27 1.27)
				)
				(justify mirror)
			)
		)
		(property "Value" ""
			(at 0 0 90)
			(layer "B.Fab")
			(effects
				(font
					(size 1.27 1.27)
				)
				(justify mirror)
			)
		)
		(duplicate_pad_numbers_are_jumpers no)
		(fp_line
			(start 0.299974 -0.150114)
			(end -0.299974 -0.150114)
			(stroke
				(width 0.1)
				(type default)
			)
			(layer "B.Fab")
		)
		(fp_line
			(start -0.299974 -0.150114)
			(end -0.299974 0.150114)
			(stroke
				(width 0.1)
				(type default)
			)
			(layer "B.Fab")
		)
		(fp_line
			(start 0.299974 0.150114)
			(end 0.299974 -0.150114)
			(stroke
				(width 0.1)
				(type default)
			)
			(layer "B.Fab")
		)
		(fp_line
			(start -0.299974 0.150114)
			(end 0.299974 0.150114)
			(stroke
				(width 0.1)
				(type default)
			)
			(layer "B.Fab")
		)
		(pad "1" smd rect
			(at 0.2667 0 270)
			(size 0.3048 0.381)
			(layers "B.Cu" "B.Mask" "B.Paste")
			(net "P5E_CPU1_P3_TX_BUF_C_DN<0>")
		)
		(pad "2" smd rect
			(at -0.2667 0 270)
			(size 0.3048 0.381)
			(layers "B.Cu" "B.Mask" "B.Paste")
			(net "P5E_CPU1_P3_TX_BUF_DN<0>")
		)
	)
	(footprint ""
		(layer "B.Cu")
		(at 105.960164 -257.455416 180)
		(property "Reference" "C2111"
			(at 0 0 0)
			(layer "B.SilkS")
			(hide yes)
			(effects
				(font
					(size 1.27 1.27)
				)
				(justify mirror)
			)
		)
		(property "Value" ""
			(at 0 0 0)
			(layer "B.Fab")
			(effects
				(font
					(size 1.27 1.27)
				)
				(justify mirror)
			)
		)
		(duplicate_pad_numbers_are_jumpers no)
		(fp_line
			(start 0.7874 0.4064)
			(end 0.7874 -0.4064)
			(stroke
				(width 0.1524)
				(type default)
			)
			(layer "B.SilkS")
		)
		(fp_line
			(start 0.7874 -0.4064)
			(end -0.7874 -0.4064)
			(stroke
				(width 0.1524)
				(type default)
			)
			(layer "B.SilkS")
		)
		(fp_line
			(start -0.7874 0.4064)
			(end 0.7874 0.4064)
			(stroke
				(width 0.1524)
				(type default)
			)
			(layer "B.SilkS")
		)
		(fp_line
			(start -0.7874 -0.4064)
			(end -0.7874 0.4064)
			(stroke
				(width 0.1524)
				(type default)
			)
			(layer "B.SilkS")
		)
		(fp_line
			(start 0.67945 0.3048)
			(end 0.67945 -0.305054)
			(stroke
				(width 0.1)
				(type default)
			)
			(layer "B.Fab")
		)
		(fp_line
			(start 0.67945 -0.305054)
			(end 0.12065 -0.305054)
			(stroke
				(width 0.1)
				(type default)
			)
			(layer "B.Fab")
		)
		(fp_line
			(start 0.12065 0.3048)
			(end 0.67945 0.3048)
			(stroke
				(width 0.1)
				(type default)
			)
			(layer "B.Fab")
		)
		(fp_line
			(start 0.12065 0.2794)
			(end 0.12065 0.3048)
			(stroke
				(width 0.1)
				(type default)
			)
			(layer "B.Fab")
		)
		(fp_line
			(start 0.12065 -0.2794)
			(end -0.12065 -0.2794)
			(stroke
				(width 0.1)
				(type default)
			)
			(layer "B.Fab")
		)
		(fp_line
			(start 0.12065 -0.305054)
			(end 0.12065 -0.2794)
			(stroke
				(width 0.1)
				(type default)
			)
			(layer "B.Fab")
		)
		(fp_line
			(start -0.120396 0.3048)
			(end -0.120396 0.2794)
			(stroke
				(width 0.1)
				(type default)
			)
			(layer "B.Fab")
		)
		(fp_line
			(start -0.120396 0.2794)
			(end 0.12065 0.2794)
			(stroke
				(width 0.1)
				(type default)
			)
			(layer "B.Fab")
		)
		(fp_line
			(start -0.12065 -0.2794)
			(end -0.12065 -0.3048)
			(stroke
				(width 0.1)
				(type default)
			)
			(layer "B.Fab")
		)
		(fp_line
			(start -0.12065 -0.3048)
			(end -0.67945 -0.3048)
			(stroke
				(width 0.1)
				(type default)
			)
			(layer "B.Fab")
		)
		(fp_line
			(start -0.67945 0.3048)
			(end -0.120396 0.3048)
			(stroke
				(width 0.1)
				(type default)
			)
			(layer "B.Fab")
		)
		(fp_line
			(start -0.67945 -0.3048)
			(end -0.67945 0.3048)
			(stroke
				(width 0.1)
				(type default)
			)
			(layer "B.Fab")
		)
		(pad "1" smd circle
			(at 0.40005 0)
			(size 0 0)
			(layers "B.Cu" "B.Mask" "B.Paste")
			(net "PVDDIO_P1")
		)
		(pad "2" smd circle
			(at -0.40005 0)
			(size 0 0)
			(layers "B.Cu" "B.Mask" "B.Paste")
			(net "GND")
		)
	)
	(footprint ""
		(layer "B.Cu")
		(at 229.8446 -336.296 180)
		(property "Reference" "R6759"
			(at 0 0 0)
			(layer "B.SilkS")
			(hide yes)
			(effects
				(font
					(size 1.27 1.27)
				)
				(justify mirror)
			)
		)
		(property "Value" ""
			(at 0 0 0)
			(layer "B.Fab")
			(effects
				(font
					(size 1.27 1.27)
				)
				(justify mirror)
			)
		)
		(duplicate_pad_numbers_are_jumpers no)
		(fp_line
			(start 0.32512 0.175006)
			(end 0.32512 -0.175006)
			(stroke
				(width 0.1)
				(type default)
			)
			(layer "B.Fab")
		)
		(fp_line
			(start 0.32512 -0.175006)
			(end -0.32512 -0.175006)
			(stroke
				(width 0.1)
				(type default)
			)
			(layer "B.Fab")
		)
		(fp_line
			(start -0.32512 0.175006)
			(end 0.32512 0.175006)
			(stroke
				(width 0.1)
				(type default)
			)
			(layer "B.Fab")
		)
		(fp_line
			(start -0.32512 -0.175006)
			(end -0.32512 0.175006)
			(stroke
				(width 0.1)
				(type default)
			)
			(layer "B.Fab")
		)
		(pad "1" smd rect
			(at 0.2667 0)
			(size 0.3048 0.381)
			(layers "B.Cu" "B.Mask" "B.Paste")
			(net "SMB_RT_CPU0_P3_SCL")
		)
		(pad "2" smd rect
			(at -0.2667 0 180)
			(size 0.3048 0.381)
			(layers "B.Cu" "B.Mask" "B.Paste")
			(net "SMB_RT_CPU0_P3_R_SCL")
		)
	)
	(footprint ""
		(layer "B.Cu")
		(at 115.610386 -253.432564)
		(property "Reference" "C2426"
			(at 0 0 0)
			(layer "B.SilkS")
			(hide yes)
			(effects
				(font
					(size 1.27 1.27)
				)
				(justify mirror)
			)
		)
		(property "Value" ""
			(at 0 0 0)
			(layer "B.Fab")
			(effects
				(font
					(size 1.27 1.27)
				)
				(justify mirror)
			)
		)
		(duplicate_pad_numbers_are_jumpers no)
		(fp_line
			(start -0.7874 -0.4064)
			(end -0.7874 0.4064)
			(stroke
				(width 0.1524)
				(type default)
			)
			(layer "B.SilkS")
		)
		(fp_line
			(start -0.7874 0.4064)
			(end 0.7874 0.4064)
			(stroke
				(width 0.1524)
				(type default)
			)
			(layer "B.SilkS")
		)
		(fp_line
			(start 0.7874 -0.4064)
			(end -0.7874 -0.4064)
			(stroke
				(width 0.1524)
				(type default)
			)
			(layer "B.SilkS")
		)
		(fp_line
			(start 0.7874 0.4064)
			(end 0.7874 -0.4064)
			(stroke
				(width 0.1524)
				(type default)
			)
			(layer "B.SilkS")
		)
		(fp_line
			(start -0.67945 -0.3048)
			(end -0.67945 0.3048)
			(stroke
				(width 0.1)
				(type default)
			)
			(layer "B.Fab")
		)
		(fp_line
			(start -0.67945 0.3048)
			(end -0.120396 0.3048)
			(stroke
				(width 0.1)
				(type default)
			)
			(layer "B.Fab")
		)
		(fp_line
			(start -0.12065 -0.3048)
			(end -0.67945 -0.3048)
			(stroke
				(width 0.1)
				(type default)
			)
			(layer "B.Fab")
		)
		(fp_line
			(start -0.12065 -0.2794)
			(end -0.12065 -0.3048)
			(stroke
				(width 0.1)
				(type default)
			)
			(layer "B.Fab")
		)
		(fp_line
			(start -0.120396 0.2794)
			(end 0.12065 0.2794)
			(stroke
				(width 0.1)
				(type default)
			)
			(layer "B.Fab")
		)
		(fp_line
			(start -0.120396 0.3048)
			(end -0.120396 0.2794)
			(stroke
				(width 0.1)
				(type default)
			)
			(layer "B.Fab")
		)
		(fp_line
			(start 0.12065 -0.305054)
			(end 0.12065 -0.2794)
			(stroke
				(width 0.1)
				(type default)
			)
			(layer "B.Fab")
		)
		(fp_line
			(start 0.12065 -0.2794)
			(end -0.12065 -0.2794)
			(stroke
				(width 0.1)
				(type default)
			)
			(layer "B.Fab")
		)
		(fp_line
			(start 0.12065 0.2794)
			(end 0.12065 0.3048)
			(stroke
				(width 0.1)
				(type default)
			)
			(layer "B.Fab")
		)
		(fp_line
			(start 0.12065 0.3048)
			(end 0.67945 0.3048)
			(stroke
				(width 0.1)
				(type default)
			)
			(layer "B.Fab")
		)
		(fp_line
			(start 0.67945 -0.305054)
			(end 0.12065 -0.305054)
			(stroke
				(width 0.1)
				(type default)
			)
			(layer "B.Fab")
		)
		(fp_line
			(start 0.67945 0.3048)
			(end 0.67945 -0.305054)
			(stroke
				(width 0.1)
				(type default)
			)
			(layer "B.Fab")
		)
		(pad "1" smd circle
			(at 0.40005 0 180)
			(size 0 0)
			(layers "B.Cu" "B.Mask" "B.Paste")
			(net "PVDDCR_SOC_P1")
		)
		(pad "2" smd circle
			(at -0.40005 0 180)
			(size 0 0)
			(layers "B.Cu" "B.Mask" "B.Paste")
			(net "GND")
		)
	)
	(footprint ""
		(layer "B.Cu")
		(at 193.6369 -402.033232 -90)
		(property "Reference" "PR3910"
			(at 0 0 90)
			(layer "B.SilkS")
			(hide yes)
			(effects
				(font
					(size 1.27 1.27)
				)
				(justify mirror)
			)
		)
		(property "Value" ""
			(at 0 0 90)
			(layer "B.Fab")
			(effects
				(font
					(size 1.27 1.27)
				)
				(justify mirror)
			)
		)
		(duplicate_pad_numbers_are_jumpers no)
		(fp_line
			(start -0.7874 0.4064)
			(end 0.7874 0.4064)
			(stroke
				(width 0.1524)
				(type default)
			)
			(layer "B.SilkS")
		)
		(fp_line
			(start 0.7874 0.4064)
			(end 0.7874 -0.4064)
			(stroke
				(width 0.1524)
				(type default)
			)
			(layer "B.SilkS")
		)
		(fp_line
			(start -0.7874 -0.4064)
			(end -0.7874 0.4064)
			(stroke
				(width 0.1524)
				(type default)
			)
			(layer "B.SilkS")
		)
		(fp_line
			(start 0.7874 -0.4064)
			(end -0.7874 -0.4064)
			(stroke
				(width 0.1524)
				(type default)
			)
			(layer "B.SilkS")
		)
		(fp_line
			(start -0.67945 0.3048)
			(end -0.120396 0.3048)
			(stroke
				(width 0.1)
				(type default)
			)
			(layer "B.Fab")
		)
		(fp_line
			(start -0.120396 0.3048)
			(end -0.120396 0.2794)
			(stroke
				(width 0.1)
				(type default)
			)
			(layer "B.Fab")
		)
		(fp_line
			(start 0.12065 0.3048)
			(end 0.67945 0.3048)
			(stroke
				(width 0.1)
				(type default)
			)
			(layer "B.Fab")
		)
		(fp_line
			(start 0.67945 0.3048)
			(end 0.67945 -0.305054)
			(stroke
				(width 0.1)
				(type default)
			)
			(layer "B.Fab")
		)
		(fp_line
			(start -0.120396 0.2794)
			(end 0.12065 0.2794)
			(stroke
				(width 0.1)
				(type default)
			)
			(layer "B.Fab")
		)
		(fp_line
			(start 0.12065 0.2794)
			(end 0.12065 0.3048)
			(stroke
				(width 0.1)
				(type default)
			)
			(layer "B.Fab")
		)
		(fp_line
			(start -0.12065 -0.2794)
			(end -0.12065 -0.3048)
			(stroke
				(width 0.1)
				(type default)
			)
			(layer "B.Fab")
		)
		(fp_line
			(start 0.12065 -0.2794)
			(end -0.12065 -0.2794)
			(stroke
				(width 0.1)
				(type default)
			)
			(layer "B.Fab")
		)
		(fp_line
			(start -0.67945 -0.3048)
			(end -0.67945 0.3048)
			(stroke
				(width 0.1)
				(type default)
			)
			(layer "B.Fab")
		)
		(fp_line
			(start -0.12065 -0.3048)
			(end -0.67945 -0.3048)
			(stroke
				(width 0.1)
				(type default)
			)
			(layer "B.Fab")
		)
		(fp_line
			(start 0.12065 -0.305054)
			(end 0.12065 -0.2794)
			(stroke
				(width 0.1)
				(type default)
			)
			(layer "B.Fab")
		)
		(fp_line
			(start 0.67945 -0.305054)
			(end 0.12065 -0.305054)
			(stroke
				(width 0.1)
				(type default)
			)
			(layer "B.Fab")
		)
		(pad "1" smd circle
			(at 0.40005 0 90)
			(size 0 0)
			(layers "B.Cu" "B.Mask" "B.Paste")
			(net "HSC_VDD_R_1")
		)
		(pad "2" smd circle
			(at -0.40005 0 90)
			(size 0 0)
			(layers "B.Cu" "B.Mask" "B.Paste")
			(net "HSC_VDD")
		)
	)
	(footprint ""
		(layer "B.Cu")
		(at 16.610838 -97.314512 90)
		(property "Reference" "C2039"
			(at 0 0 90)
			(layer "B.SilkS")
			(hide yes)
			(effects
				(font
					(size 1.27 1.27)
				)
				(justify mirror)
			)
		)
		(property "Value" ""
			(at 0 0 90)
			(layer "B.Fab")
			(effects
				(font
					(size 1.27 1.27)
				)
				(justify mirror)
			)
		)
		(duplicate_pad_numbers_are_jumpers no)
		(fp_line
			(start 0.7874 -0.4064)
			(end -0.7874 -0.4064)
			(stroke
				(width 0.1524)
				(type default)
			)
			(layer "B.SilkS")
		)
		(fp_line
			(start -0.7874 -0.4064)
			(end -0.7874 0.4064)
			(stroke
				(width 0.1524)
				(type default)
			)
			(layer "B.SilkS")
		)
		(fp_line
			(start 0.7874 0.4064)
			(end 0.7874 -0.4064)
			(stroke
				(width 0.1524)
				(type default)
			)
			(layer "B.SilkS")
		)
		(fp_line
			(start -0.7874 0.4064)
			(end 0.7874 0.4064)
			(stroke
				(width 0.1524)
				(type default)
			)
			(layer "B.SilkS")
		)
		(fp_line
			(start 0.67945 -0.305054)
			(end 0.12065 -0.305054)
			(stroke
				(width 0.1)
				(type default)
			)
			(layer "B.Fab")
		)
		(fp_line
			(start 0.12065 -0.305054)
			(end 0.12065 -0.2794)
			(stroke
				(width 0.1)
				(type default)
			)
			(layer "B.Fab")
		)
		(fp_line
			(start -0.12065 -0.3048)
			(end -0.67945 -0.3048)
			(stroke
				(width 0.1)
				(type default)
			)
			(layer "B.Fab")
		)
		(fp_line
			(start -0.67945 -0.3048)
			(end -0.67945 0.3048)
			(stroke
				(width 0.1)
				(type default)
			)
			(layer "B.Fab")
		)
		(fp_line
			(start 0.12065 -0.2794)
			(end -0.12065 -0.2794)
			(stroke
				(width 0.1)
				(type default)
			)
			(layer "B.Fab")
		)
		(fp_line
			(start -0.12065 -0.2794)
			(end -0.12065 -0.3048)
			(stroke
				(width 0.1)
				(type default)
			)
			(layer "B.Fab")
		)
		(fp_line
			(start 0.12065 0.2794)
			(end 0.12065 0.3048)
			(stroke
				(width 0.1)
				(type default)
			)
			(layer "B.Fab")
		)
		(fp_line
			(start -0.120396 0.2794)
			(end 0.12065 0.2794)
			(stroke
				(width 0.1)
				(type default)
			)
			(layer "B.Fab")
		)
		(fp_line
			(start 0.67945 0.3048)
			(end 0.67945 -0.305054)
			(stroke
				(width 0.1)
				(type default)
			)
			(layer "B.Fab")
		)
		(fp_line
			(start 0.12065 0.3048)
			(end 0.67945 0.3048)
			(stroke
				(width 0.1)
				(type default)
			)
			(layer "B.Fab")
		)
		(fp_line
			(start -0.120396 0.3048)
			(end -0.120396 0.2794)
			(stroke
				(width 0.1)
				(type default)
			)
			(layer "B.Fab")
		)
		(fp_line
			(start -0.67945 0.3048)
			(end -0.120396 0.3048)
			(stroke
				(width 0.1)
				(type default)
			)
			(layer "B.Fab")
		)
		(pad "1" smd circle
			(at 0.40005 0 270)
			(size 0 0)
			(layers "B.Cu" "B.Mask" "B.Paste")
			(net "P3V3_AUX_USB_HUB")
		)
		(pad "2" smd circle
			(at -0.40005 0 270)
			(size 0 0)
			(layers "B.Cu" "B.Mask" "B.Paste")
			(net "GND")
		)
	)
	(footprint ""
		(layer "B.Cu")
		(at 399.057622 -204.232002)
		(property "Reference" "C30"
			(at 0 0 0)
			(layer "B.SilkS")
			(hide yes)
			(effects
				(font
					(size 1.27 1.27)
				)
				(justify mirror)
			)
		)
		(property "Value" ""
			(at 0 0 0)
			(layer "B.Fab")
			(effects
				(font
					(size 1.27 1.27)
				)
				(justify mirror)
			)
		)
		(duplicate_pad_numbers_are_jumpers no)
		(fp_line
			(start -0.7874 -0.4064)
			(end -0.7874 0.4064)
			(stroke
				(width 0.1524)
				(type default)
			)
			(layer "B.SilkS")
		)
		(fp_line
			(start -0.7874 0.4064)
			(end 0.7874 0.4064)
			(stroke
				(width 0.1524)
				(type default)
			)
			(layer "B.SilkS")
		)
		(fp_line
			(start 0.7874 -0.4064)
			(end -0.7874 -0.4064)
			(stroke
				(width 0.1524)
				(type default)
			)
			(layer "B.SilkS")
		)
		(fp_line
			(start 0.7874 0.4064)
			(end 0.7874 -0.4064)
			(stroke
				(width 0.1524)
				(type default)
			)
			(layer "B.SilkS")
		)
		(fp_line
			(start -0.67945 -0.3048)
			(end -0.67945 0.3048)
			(stroke
				(width 0.1)
				(type default)
			)
			(layer "B.Fab")
		)
		(fp_line
			(start -0.67945 0.3048)
			(end -0.120396 0.3048)
			(stroke
				(width 0.1)
				(type default)
			)
			(layer "B.Fab")
		)
		(fp_line
			(start -0.12065 -0.3048)
			(end -0.67945 -0.3048)
			(stroke
				(width 0.1)
				(type default)
			)
			(layer "B.Fab")
		)
		(fp_line
			(start -0.12065 -0.2794)
			(end -0.12065 -0.3048)
			(stroke
				(width 0.1)
				(type default)
			)
			(layer "B.Fab")
		)
		(fp_line
			(start -0.120396 0.2794)
			(end 0.12065 0.2794)
			(stroke
				(width 0.1)
				(type default)
			)
			(layer "B.Fab")
		)
		(fp_line
			(start -0.120396 0.3048)
			(end -0.120396 0.2794)
			(stroke
				(width 0.1)
				(type default)
			)
			(layer "B.Fab")
		)
		(fp_line
			(start 0.12065 -0.305054)
			(end 0.12065 -0.2794)
			(stroke
				(width 0.1)
				(type default)
			)
			(layer "B.Fab")
		)
		(fp_line
			(start 0.12065 -0.2794)
			(end -0.12065 -0.2794)
			(stroke
				(width 0.1)
				(type default)
			)
			(layer "B.Fab")
		)
		(fp_line
			(start 0.12065 0.2794)
			(end 0.12065 0.3048)
			(stroke
				(width 0.1)
				(type default)
			)
			(layer "B.Fab")
		)
		(fp_line
			(start 0.12065 0.3048)
			(end 0.67945 0.3048)
			(stroke
				(width 0.1)
				(type default)
			)
			(layer "B.Fab")
		)
		(fp_line
			(start 0.67945 -0.305054)
			(end 0.12065 -0.305054)
			(stroke
				(width 0.1)
				(type default)
			)
			(layer "B.Fab")
		)
		(fp_line
			(start 0.67945 0.3048)
			(end 0.67945 -0.305054)
			(stroke
				(width 0.1)
				(type default)
			)
			(layer "B.Fab")
		)
		(pad "1" smd circle
			(at 0.40005 0 180)
			(size 0 0)
			(layers "B.Cu" "B.Mask" "B.Paste")
			(net "P1V8_AUX")
		)
		(pad "2" smd circle
			(at -0.40005 0 180)
			(size 0 0)
			(layers "B.Cu" "B.Mask" "B.Paste")
			(net "GND")
		)
	)
	(footprint ""
		(layer "B.Cu")
		(at 349.118682 -398.942052 90)
		(property "Reference" "C644"
			(at 0 0 90)
			(layer "B.SilkS")
			(hide yes)
			(effects
				(font
					(size 1.27 1.27)
				)
				(justify mirror)
			)
		)
		(property "Value" ""
			(at 0 0 90)
			(layer "B.Fab")
			(effects
				(font
					(size 1.27 1.27)
				)
				(justify mirror)
			)
		)
		(duplicate_pad_numbers_are_jumpers no)
		(fp_line
			(start 0.7874 -0.4064)
			(end -0.7874 -0.4064)
			(stroke
				(width 0.1524)
				(type default)
			)
			(layer "B.SilkS")
		)
		(fp_line
			(start -0.7874 -0.4064)
			(end -0.7874 0.4064)
			(stroke
				(width 0.1524)
				(type default)
			)
			(layer "B.SilkS")
		)
		(fp_line
			(start 0.7874 0.4064)
			(end 0.7874 -0.4064)
			(stroke
				(width 0.1524)
				(type default)
			)
			(layer "B.SilkS")
		)
		(fp_line
			(start -0.7874 0.4064)
			(end 0.7874 0.4064)
			(stroke
				(width 0.1524)
				(type default)
			)
			(layer "B.SilkS")
		)
		(fp_line
			(start 0.67945 -0.305054)
			(end 0.12065 -0.305054)
			(stroke
				(width 0.1)
				(type default)
			)
			(layer "B.Fab")
		)
		(fp_line
			(start 0.12065 -0.305054)
			(end 0.12065 -0.2794)
			(stroke
				(width 0.1)
				(type default)
			)
			(layer "B.Fab")
		)
		(fp_line
			(start -0.12065 -0.3048)
			(end -0.67945 -0.3048)
			(stroke
				(width 0.1)
				(type default)
			)
			(layer "B.Fab")
		)
		(fp_line
			(start -0.67945 -0.3048)
			(end -0.67945 0.3048)
			(stroke
				(width 0.1)
				(type default)
			)
			(layer "B.Fab")
		)
		(fp_line
			(start 0.12065 -0.2794)
			(end -0.12065 -0.2794)
			(stroke
				(width 0.1)
				(type default)
			)
			(layer "B.Fab")
		)
		(fp_line
			(start -0.12065 -0.2794)
			(end -0.12065 -0.3048)
			(stroke
				(width 0.1)
				(type default)
			)
			(layer "B.Fab")
		)
		(fp_line
			(start 0.12065 0.2794)
			(end 0.12065 0.3048)
			(stroke
				(width 0.1)
				(type default)
			)
			(layer "B.Fab")
		)
		(fp_line
			(start -0.120396 0.2794)
			(end 0.12065 0.2794)
			(stroke
				(width 0.1)
				(type default)
			)
			(layer "B.Fab")
		)
		(fp_line
			(start 0.67945 0.3048)
			(end 0.67945 -0.305054)
			(stroke
				(width 0.1)
				(type default)
			)
			(layer "B.Fab")
		)
		(fp_line
			(start 0.12065 0.3048)
			(end 0.67945 0.3048)
			(stroke
				(width 0.1)
				(type default)
			)
			(layer "B.Fab")
		)
		(fp_line
			(start -0.120396 0.3048)
			(end -0.120396 0.2794)
			(stroke
				(width 0.1)
				(type default)
			)
			(layer "B.Fab")
		)
		(fp_line
			(start -0.67945 0.3048)
			(end -0.120396 0.3048)
			(stroke
				(width 0.1)
				(type default)
			)
			(layer "B.Fab")
		)
		(pad "1" smd circle
			(at 0.40005 0 270)
			(size 0 0)
			(layers "B.Cu" "B.Mask" "B.Paste")
			(net "P0V9_CPU0_RT1_2A")
		)
		(pad "2" smd circle
			(at -0.40005 0 270)
			(size 0 0)
			(layers "B.Cu" "B.Mask" "B.Paste")
			(net "GND")
		)
	)
	(footprint ""
		(layer "B.Cu")
		(at 188.712094 -113.862866)
		(property "Reference" "C356"
			(at 0 0 0)
			(layer "B.SilkS")
			(hide yes)
			(effects
				(font
					(size 1.27 1.27)
				)
				(justify mirror)
			)
		)
		(property "Value" ""
			(at 0 0 0)
			(layer "B.Fab")
			(effects
				(font
					(size 1.27 1.27)
				)
				(justify mirror)
			)
		)
		(duplicate_pad_numbers_are_jumpers no)
		(fp_line
			(start -0.69215 -0.2921)
			(end -0.69215 0.2921)
			(stroke
				(width 0.1524)
				(type default)
			)
			(layer "B.SilkS")
		)
		(fp_line
			(start -0.69215 0.2921)
			(end 0.69215 0.2921)
			(stroke
				(width 0.1524)
				(type default)
			)
			(layer "B.SilkS")
		)
		(fp_line
			(start 0.69215 -0.2921)
			(end -0.69215 -0.2921)
			(stroke
				(width 0.1524)
				(type default)
			)
			(layer "B.SilkS")
		)
		(fp_line
			(start 0.69215 0.2921)
			(end 0.69215 -0.2921)
			(stroke
				(width 0.1524)
				(type default)
			)
			(layer "B.SilkS")
		)
		(fp_line
			(start -0.51435 -0.2794)
			(end -0.51435 0.2794)
			(stroke
				(width 0.1)
				(type default)
			)
			(layer "B.Fab")
		)
		(fp_line
			(start -0.51435 0.2794)
			(end 0.51435 0.2794)
			(stroke
				(width 0.1)
				(type default)
			)
			(layer "B.Fab")
		)
		(fp_line
			(start 0.51435 -0.2794)
			(end -0.51435 -0.2794)
			(stroke
				(width 0.1)
				(type default)
			)
			(layer "B.Fab")
		)
		(fp_line
			(start 0.51435 0.2794)
			(end 0.51435 -0.2794)
			(stroke
				(width 0.1)
				(type default)
			)
			(layer "B.Fab")
		)
		(pad "1" smd circle
			(at 0.40005 0 180)
			(size 0 0)
			(layers "B.Cu" "B.Mask" "B.Paste")
			(net "P3V3_AUX")
		)
		(pad "2" smd circle
			(at -0.40005 0 180)
			(size 0 0)
			(layers "B.Cu" "B.Mask" "B.Paste")
			(net "GND")
		)
		(zone
			(layer "B.Cu")
			(hatch none 0.5)
			(connect_pads
				(clearance 0)
			)
			(min_thickness 0.25)
			(keepout
				(tracks not_allowed)
				(vias allowed)
				(pads allowed)
				(copperpour not_allowed)
				(footprints allowed)
			)
			(placement
				(enabled no)
				(sheetname "")
			)
			(fill
				(thermal_gap 0.5)
				(thermal_bridge_width 0.5)
				(island_removal_mode 0)
			)
			(polygon
				(pts
					(xy 188.521594 -113.775236) (xy 188.521594 -113.950496) (xy 188.611764 -114.008916) (xy 188.811154 -114.008916)
					(xy 188.902594 -113.95075) (xy 188.902594 -113.775236) (xy 188.811154 -113.71707) (xy 188.611764 -113.71707)
				)
			)
		)
	)
	(footprint ""
		(layer "B.Cu")
		(at 362.267246 -261.747762 90)
		(property "Reference" "C2634"
			(at 0 0 90)
			(layer "B.SilkS")
			(hide yes)
			(effects
				(font
					(size 1.27 1.27)
				)
				(justify mirror)
			)
		)
		(property "Value" ""
			(at 0 0 90)
			(layer "B.Fab")
			(effects
				(font
					(size 1.27 1.27)
				)
				(justify mirror)
			)
		)
		(duplicate_pad_numbers_are_jumpers no)
		(fp_line
			(start 0.7874 -0.4064)
			(end -0.7874 -0.4064)
			(stroke
				(width 0.1524)
				(type default)
			)
			(layer "B.SilkS")
		)
		(fp_line
			(start -0.7874 -0.4064)
			(end -0.7874 0.4064)
			(stroke
				(width 0.1524)
				(type default)
			)
			(layer "B.SilkS")
		)
		(fp_line
			(start 0.7874 0.4064)
			(end 0.7874 -0.4064)
			(stroke
				(width 0.1524)
				(type default)
			)
			(layer "B.SilkS")
		)
		(fp_line
			(start -0.7874 0.4064)
			(end 0.7874 0.4064)
			(stroke
				(width 0.1524)
				(type default)
			)
			(layer "B.SilkS")
		)
		(fp_line
			(start 0.67945 -0.305054)
			(end 0.12065 -0.305054)
			(stroke
				(width 0.1)
				(type default)
			)
			(layer "B.Fab")
		)
		(fp_line
			(start 0.12065 -0.305054)
			(end 0.12065 -0.2794)
			(stroke
				(width 0.1)
				(type default)
			)
			(layer "B.Fab")
		)
		(fp_line
			(start -0.12065 -0.3048)
			(end -0.67945 -0.3048)
			(stroke
				(width 0.1)
				(type default)
			)
			(layer "B.Fab")
		)
		(fp_line
			(start -0.67945 -0.3048)
			(end -0.67945 0.3048)
			(stroke
				(width 0.1)
				(type default)
			)
			(layer "B.Fab")
		)
		(fp_line
			(start 0.12065 -0.2794)
			(end -0.12065 -0.2794)
			(stroke
				(width 0.1)
				(type default)
			)
			(layer "B.Fab")
		)
		(fp_line
			(start -0.12065 -0.2794)
			(end -0.12065 -0.3048)
			(stroke
				(width 0.1)
				(type default)
			)
			(layer "B.Fab")
		)
		(fp_line
			(start 0.12065 0.2794)
			(end 0.12065 0.3048)
			(stroke
				(width 0.1)
				(type default)
			)
			(layer "B.Fab")
		)
		(fp_line
			(start -0.120396 0.2794)
			(end 0.12065 0.2794)
			(stroke
				(width 0.1)
				(type default)
			)
			(layer "B.Fab")
		)
		(fp_line
			(start 0.67945 0.3048)
			(end 0.67945 -0.305054)
			(stroke
				(width 0.1)
				(type default)
			)
			(layer "B.Fab")
		)
		(fp_line
			(start 0.12065 0.3048)
			(end 0.67945 0.3048)
			(stroke
				(width 0.1)
				(type default)
			)
			(layer "B.Fab")
		)
		(fp_line
			(start -0.120396 0.3048)
			(end -0.120396 0.2794)
			(stroke
				(width 0.1)
				(type default)
			)
			(layer "B.Fab")
		)
		(fp_line
			(start -0.67945 0.3048)
			(end -0.120396 0.3048)
			(stroke
				(width 0.1)
				(type default)
			)
			(layer "B.Fab")
		)
		(pad "1" smd circle
			(at 0.40005 0 270)
			(size 0 0)
			(layers "B.Cu" "B.Mask" "B.Paste")
			(net "PVDD11_S3_P0")
		)
		(pad "2" smd circle
			(at -0.40005 0 270)
			(size 0 0)
			(layers "B.Cu" "B.Mask" "B.Paste")
			(net "GND")
		)
	)
	(footprint ""
		(layer "B.Cu")
		(at 20.32 -367.919)
		(property "Reference" "R1496"
			(at 0 0 0)
			(layer "B.SilkS")
			(hide yes)
			(effects
				(font
					(size 1.27 1.27)
				)
				(justify mirror)
			)
		)
		(property "Value" ""
			(at 0 0 0)
			(layer "B.Fab")
			(effects
				(font
					(size 1.27 1.27)
				)
				(justify mirror)
			)
		)
		(duplicate_pad_numbers_are_jumpers no)
		(fp_line
			(start -0.7874 -0.4064)
			(end -0.7874 0.4064)
			(stroke
				(width 0.1524)
				(type default)
			)
			(layer "B.SilkS")
		)
		(fp_line
			(start -0.7874 0.4064)
			(end 0.7874 0.4064)
			(stroke
				(width 0.1524)
				(type default)
			)
			(layer "B.SilkS")
		)
		(fp_line
			(start 0.7874 -0.4064)
			(end -0.7874 -0.4064)
			(stroke
				(width 0.1524)
				(type default)
			)
			(layer "B.SilkS")
		)
		(fp_line
			(start 0.7874 0.4064)
			(end 0.7874 -0.4064)
			(stroke
				(width 0.1524)
				(type default)
			)
			(layer "B.SilkS")
		)
		(fp_line
			(start -0.67945 -0.3048)
			(end -0.67945 0.3048)
			(stroke
				(width 0.1)
				(type default)
			)
			(layer "B.Fab")
		)
		(fp_line
			(start -0.67945 0.3048)
			(end -0.120396 0.3048)
			(stroke
				(width 0.1)
				(type default)
			)
			(layer "B.Fab")
		)
		(fp_line
			(start -0.12065 -0.3048)
			(end -0.67945 -0.3048)
			(stroke
				(width 0.1)
				(type default)
			)
			(layer "B.Fab")
		)
		(fp_line
			(start -0.12065 -0.2794)
			(end -0.12065 -0.3048)
			(stroke
				(width 0.1)
				(type default)
			)
			(layer "B.Fab")
		)
		(fp_line
			(start -0.120396 0.2794)
			(end 0.12065 0.2794)
			(stroke
				(width 0.1)
				(type default)
			)
			(layer "B.Fab")
		)
		(fp_line
			(start -0.120396 0.3048)
			(end -0.120396 0.2794)
			(stroke
				(width 0.1)
				(type default)
			)
			(layer "B.Fab")
		)
		(fp_line
			(start 0.12065 -0.305054)
			(end 0.12065 -0.2794)
			(stroke
				(width 0.1)
				(type default)
			)
			(layer "B.Fab")
		)
		(fp_line
			(start 0.12065 -0.2794)
			(end -0.12065 -0.2794)
			(stroke
				(width 0.1)
				(type default)
			)
			(layer "B.Fab")
		)
		(fp_line
			(start 0.12065 0.2794)
			(end 0.12065 0.3048)
			(stroke
				(width 0.1)
				(type default)
			)
			(layer "B.Fab")
		)
		(fp_line
			(start 0.12065 0.3048)
			(end 0.67945 0.3048)
			(stroke
				(width 0.1)
				(type default)
			)
			(layer "B.Fab")
		)
		(fp_line
			(start 0.67945 -0.305054)
			(end 0.12065 -0.305054)
			(stroke
				(width 0.1)
				(type default)
			)
			(layer "B.Fab")
		)
		(fp_line
			(start 0.67945 0.3048)
			(end 0.67945 -0.305054)
			(stroke
				(width 0.1)
				(type default)
			)
			(layer "B.Fab")
		)
		(pad "1" smd circle
			(at 0.40005 0 180)
			(size 0 0)
			(layers "B.Cu" "B.Mask" "B.Paste")
			(net "SMB_SCM_2_R1_SDA")
		)
		(pad "2" smd circle
			(at -0.40005 0 180)
			(size 0 0)
			(layers "B.Cu" "B.Mask" "B.Paste")
			(net "SMB_SCM_2_R2_SDA")
		)
	)
	(footprint ""
		(layer "B.Cu")
		(at 77.783944 -408.517344 90)
		(property "Reference" "C6679"
			(at 0 0 90)
			(layer "B.SilkS")
			(hide yes)
			(effects
				(font
					(size 1.27 1.27)
				)
				(justify mirror)
			)
		)
		(property "Value" ""
			(at 0 0 90)
			(layer "B.Fab")
			(effects
				(font
					(size 1.27 1.27)
				)
				(justify mirror)
			)
		)
		(duplicate_pad_numbers_are_jumpers no)
		(fp_line
			(start 0.299974 -0.150114)
			(end -0.299974 -0.150114)
			(stroke
				(width 0.1)
				(type default)
			)
			(layer "B.Fab")
		)
		(fp_line
			(start -0.299974 -0.150114)
			(end -0.299974 0.150114)
			(stroke
				(width 0.1)
				(type default)
			)
			(layer "B.Fab")
		)
		(fp_line
			(start 0.299974 0.150114)
			(end 0.299974 -0.150114)
			(stroke
				(width 0.1)
				(type default)
			)
			(layer "B.Fab")
		)
		(fp_line
			(start -0.299974 0.150114)
			(end 0.299974 0.150114)
			(stroke
				(width 0.1)
				(type default)
			)
			(layer "B.Fab")
		)
		(pad "1" smd rect
			(at 0.2667 0 270)
			(size 0.3048 0.381)
			(layers "B.Cu" "B.Mask" "B.Paste")
			(net "P5E_CPU1_P1_TX_BUF_C_DP<9>")
		)
		(pad "2" smd rect
			(at -0.2667 0 270)
			(size 0.3048 0.381)
			(layers "B.Cu" "B.Mask" "B.Paste")
			(net "P5E_CPU1_P1_TX_BUF_DP<9>")
		)
	)
	(footprint ""
		(layer "B.Cu")
		(at 318.539876 -66.708782 90)
		(property "Reference" "R3071"
			(at 0 0 90)
			(layer "B.SilkS")
			(hide yes)
			(effects
				(font
					(size 1.27 1.27)
				)
				(justify mirror)
			)
		)
		(property "Value" ""
			(at 0 0 90)
			(layer "B.Fab")
			(effects
				(font
					(size 1.27 1.27)
				)
				(justify mirror)
			)
		)
		(duplicate_pad_numbers_are_jumpers no)
		(fp_line
			(start 0.7874 -0.4064)
			(end -0.7874 -0.4064)
			(stroke
				(width 0.1524)
				(type default)
			)
			(layer "B.SilkS")
		)
		(fp_line
			(start -0.7874 -0.4064)
			(end -0.7874 0.4064)
			(stroke
				(width 0.1524)
				(type default)
			)
			(layer "B.SilkS")
		)
		(fp_line
			(start 0.7874 0.4064)
			(end 0.7874 -0.4064)
			(stroke
				(width 0.1524)
				(type default)
			)
			(layer "B.SilkS")
		)
		(fp_line
			(start -0.7874 0.4064)
			(end 0.7874 0.4064)
			(stroke
				(width 0.1524)
				(type default)
			)
			(layer "B.SilkS")
		)
		(fp_line
			(start 0.67945 -0.305054)
			(end 0.12065 -0.305054)
			(stroke
				(width 0.1)
				(type default)
			)
			(layer "B.Fab")
		)
		(fp_line
			(start 0.12065 -0.305054)
			(end 0.12065 -0.2794)
			(stroke
				(width 0.1)
				(type default)
			)
			(layer "B.Fab")
		)
		(fp_line
			(start -0.12065 -0.3048)
			(end -0.67945 -0.3048)
			(stroke
				(width 0.1)
				(type default)
			)
			(layer "B.Fab")
		)
		(fp_line
			(start -0.67945 -0.3048)
			(end -0.67945 0.3048)
			(stroke
				(width 0.1)
				(type default)
			)
			(layer "B.Fab")
		)
		(fp_line
			(start 0.12065 -0.2794)
			(end -0.12065 -0.2794)
			(stroke
				(width 0.1)
				(type default)
			)
			(layer "B.Fab")
		)
		(fp_line
			(start -0.12065 -0.2794)
			(end -0.12065 -0.3048)
			(stroke
				(width 0.1)
				(type default)
			)
			(layer "B.Fab")
		)
		(fp_line
			(start 0.12065 0.2794)
			(end 0.12065 0.3048)
			(stroke
				(width 0.1)
				(type default)
			)
			(layer "B.Fab")
		)
		(fp_line
			(start -0.120396 0.2794)
			(end 0.12065 0.2794)
			(stroke
				(width 0.1)
				(type default)
			)
			(layer "B.Fab")
		)
		(fp_line
			(start 0.67945 0.3048)
			(end 0.67945 -0.305054)
			(stroke
				(width 0.1)
				(type default)
			)
			(layer "B.Fab")
		)
		(fp_line
			(start 0.12065 0.3048)
			(end 0.67945 0.3048)
			(stroke
				(width 0.1)
				(type default)
			)
			(layer "B.Fab")
		)
		(fp_line
			(start -0.120396 0.3048)
			(end -0.120396 0.2794)
			(stroke
				(width 0.1)
				(type default)
			)
			(layer "B.Fab")
		)
		(fp_line
			(start -0.67945 0.3048)
			(end -0.120396 0.3048)
			(stroke
				(width 0.1)
				(type default)
			)
			(layer "B.Fab")
		)
		(pad "1" smd circle
			(at 0.40005 0 270)
			(size 0 0)
			(layers "B.Cu" "B.Mask" "B.Paste")
			(net "LED_PWRGD_P1V8_AUX")
		)
		(pad "2" smd circle
			(at -0.40005 0 270)
			(size 0 0)
			(layers "B.Cu" "B.Mask" "B.Paste")
			(net "P3V3_AUX")
		)
	)
	(footprint ""
		(layer "B.Cu")
		(at 490.160564 -457.29144 -90)
		(property "Reference" "X9026"
			(at 4.7244 -1.61163 270)
			(unlocked yes)
			(layer "B.SilkS")
			(effects
				(font
					(size 0.7874 0.5842)
					(thickness 0.1524)
				)
				(justify left mirror)
			)
		)
		(property "Value" ""
			(at 0 0 90)
			(layer "B.Fab")
			(effects
				(font
					(size 1.27 1.27)
				)
				(justify mirror)
			)
		)
		(property "User Part Number" "N_A"
			(at -1.30175 1.27 180)
			(unlocked yes)
			(layer "Cmts.User")
			(hide yes)
			(effects
				(font
					(size 0.635 0.4064)
					(thickness 0.1524)
				)
				(justify mirror)
			)
		)
		(property "Device Type" "TP_TDR_4P_FTS_TH-TP_TDR_4P_DIP,EMPTY,TP15"
			(at -1.30175 1.27 180)
			(unlocked yes)
			(layer "B.Fab")
			(hide yes)
			(effects
				(font
					(size 0.635 0.4064)
					(thickness 0.1524)
				)
				(justify mirror)
			)
		)
		(duplicate_pad_numbers_are_jumpers no)
		(fp_line
			(start -2.54 3.81)
			(end -2.54 3.6703)
			(stroke
				(width 0.1524)
				(type default)
			)
			(layer "B.SilkS")
		)
		(fp_line
			(start 0 3.81)
			(end -2.54 3.81)
			(stroke
				(width 0.1524)
				(type default)
			)
			(layer "B.SilkS")
		)
		(fp_line
			(start 0 3.175)
			(end 0 3.81)
			(stroke
				(width 0.1524)
				(type default)
			)
			(layer "B.SilkS")
		)
		(fp_line
			(start -2.54 1.4097)
			(end -2.54 1.1303)
			(stroke
				(width 0.1524)
				(type default)
			)
			(layer "B.SilkS")
		)
		(fp_line
			(start 0 0.635)
			(end 0 1.905)
			(stroke
				(width 0.1524)
				(type default)
			)
			(layer "B.SilkS")
		)
		(fp_line
			(start -2.54 -1.1303)
			(end -2.54 -1.27)
			(stroke
				(width 0.1524)
				(type default)
			)
			(layer "B.SilkS")
		)
		(fp_line
			(start -2.54 -1.27)
			(end 0 -1.27)
			(stroke
				(width 0.1524)
				(type default)
			)
			(layer "B.SilkS")
		)
		(fp_line
			(start 0 -1.27)
			(end 0 -0.635)
			(stroke
				(width 0.1524)
				(type default)
			)
			(layer "B.SilkS")
		)
		(fp_poly
			(pts
				(xy 0.761746 0) (xy 2.285746 -0.762) (xy 2.285746 0.762)
			)
			(stroke
				(width 0)
				(type default)
			)
			(fill yes)
			(layer "B.SilkS")
		)
		(fp_line
			(start -2.54 3.81)
			(end -2.54 -1.27)
			(stroke
				(width 0.1)
				(type default)
			)
			(layer "B.Fab")
		)
		(fp_line
			(start 0 3.81)
			(end -2.54 3.81)
			(stroke
				(width 0.1)
				(type default)
			)
			(layer "B.Fab")
		)
		(fp_line
			(start -2.54 -1.27)
			(end 0 -1.27)
			(stroke
				(width 0.1)
				(type default)
			)
			(layer "B.Fab")
		)
		(fp_line
			(start 0 -1.27)
			(end 0 3.81)
			(stroke
				(width 0.1)
				(type default)
			)
			(layer "B.Fab")
		)
		(fp_poly
			(pts
				(xy 0.761746 0) (xy 2.285746 -0.762) (xy 2.285746 0.762)
			)
			(stroke
				(width 0)
				(type default)
			)
			(fill yes)
			(layer "B.Fab")
		)
		(pad "1" thru_hole circle
			(at 0 0 90)
			(size 1.0033 1.0033)
			(drill 0.249936)
			(layers "*.Cu" "*.Mask")
			(remove_unused_layers no)
			(net "TDR_DIFF_85_NECK_IN6_DP")
			(clearance 0.10795)
			(padstack
				(mode front_inner_back)
				(layer "Inner"
					(shape circle)
					(size 0.8001 0.8001)
					(clearance 0.1524)
				)
				(layer "B.Cu"
					(shape circle)
					(size 1.0033 1.0033)
					(thermal_gap 0.10795)
					(clearance 0.10795)
				)
			)
		)
		(pad "2" thru_hole circle
			(at -2.54 0 90)
			(size 1.9939 1.9939)
			(drill 0.249936)
			(layers "*.Cu" "*.Mask")
			(remove_unused_layers no)
			(net "T1_GND")
			(clearance 0.10795)
			(padstack
				(mode front_inner_back)
				(layer "Inner"
					(shape circle)
					(size 0.8001 0.8001)
					(clearance 0.1524)
				)
				(layer "B.Cu"
					(shape circle)
					(size 1.9939 1.9939)
					(thermal_gap 0.10795)
					(clearance 0.10795)
				)
			)
		)
		(pad "3" thru_hole circle
			(at -2.54 2.54 90)
			(size 1.9939 1.9939)
			(drill 0.249936)
			(layers "*.Cu" "*.Mask")
			(remove_unused_layers no)
			(net "T1_GND")
			(clearance 0.10795)
			(padstack
				(mode front_inner_back)
				(layer "Inner"
					(shape circle)
					(size 0.8001 0.8001)
					(clearance 0.1524)
				)
				(layer "B.Cu"
					(shape circle)
					(size 1.9939 1.9939)
					(thermal_gap 0.10795)
					(clearance 0.10795)
				)
			)
		)
		(pad "4" thru_hole circle
			(at 0 2.54 90)
			(size 1.0033 1.0033)
			(drill 0.249936)
			(layers "*.Cu" "*.Mask")
			(remove_unused_layers no)
			(net "TDR_DIFF_85_NECK_IN6_DN")
			(clearance 0.10795)
			(padstack
				(mode front_inner_back)
				(layer "Inner"
					(shape circle)
					(size 0.8001 0.8001)
					(clearance 0.1524)
				)
				(layer "B.Cu"
					(shape circle)
					(size 1.0033 1.0033)
					(thermal_gap 0.10795)
					(clearance 0.10795)
				)
			)
		)
	)
	(footprint ""
		(layer "B.Cu")
		(at 197.269608 -106.513376)
		(property "Reference" "R289"
			(at 0 0 0)
			(layer "B.SilkS")
			(hide yes)
			(effects
				(font
					(size 1.27 1.27)
				)
				(justify mirror)
			)
		)
		(property "Value" ""
			(at 0 0 0)
			(layer "B.Fab")
			(effects
				(font
					(size 1.27 1.27)
				)
				(justify mirror)
			)
		)
		(duplicate_pad_numbers_are_jumpers no)
		(fp_line
			(start -0.7874 -0.4064)
			(end -0.7874 0.4064)
			(stroke
				(width 0.1524)
				(type default)
			)
			(layer "B.SilkS")
		)
		(fp_line
			(start -0.7874 0.4064)
			(end 0.7874 0.4064)
			(stroke
				(width 0.1524)
				(type default)
			)
			(layer "B.SilkS")
		)
		(fp_line
			(start 0.7874 -0.4064)
			(end -0.7874 -0.4064)
			(stroke
				(width 0.1524)
				(type default)
			)
			(layer "B.SilkS")
		)
		(fp_line
			(start 0.7874 0.4064)
			(end 0.7874 -0.4064)
			(stroke
				(width 0.1524)
				(type default)
			)
			(layer "B.SilkS")
		)
		(fp_line
			(start -0.67945 -0.3048)
			(end -0.67945 0.3048)
			(stroke
				(width 0.1)
				(type default)
			)
			(layer "B.Fab")
		)
		(fp_line
			(start -0.67945 0.3048)
			(end -0.120396 0.3048)
			(stroke
				(width 0.1)
				(type default)
			)
			(layer "B.Fab")
		)
		(fp_line
			(start -0.12065 -0.3048)
			(end -0.67945 -0.3048)
			(stroke
				(width 0.1)
				(type default)
			)
			(layer "B.Fab")
		)
		(fp_line
			(start -0.12065 -0.2794)
			(end -0.12065 -0.3048)
			(stroke
				(width 0.1)
				(type default)
			)
			(layer "B.Fab")
		)
		(fp_line
			(start -0.120396 0.2794)
			(end 0.12065 0.2794)
			(stroke
				(width 0.1)
				(type default)
			)
			(layer "B.Fab")
		)
		(fp_line
			(start -0.120396 0.3048)
			(end -0.120396 0.2794)
			(stroke
				(width 0.1)
				(type default)
			)
			(layer "B.Fab")
		)
		(fp_line
			(start 0.12065 -0.305054)
			(end 0.12065 -0.2794)
			(stroke
				(width 0.1)
				(type default)
			)
			(layer "B.Fab")
		)
		(fp_line
			(start 0.12065 -0.2794)
			(end -0.12065 -0.2794)
			(stroke
				(width 0.1)
				(type default)
			)
			(layer "B.Fab")
		)
		(fp_line
			(start 0.12065 0.2794)
			(end 0.12065 0.3048)
			(stroke
				(width 0.1)
				(type default)
			)
			(layer "B.Fab")
		)
		(fp_line
			(start 0.12065 0.3048)
			(end 0.67945 0.3048)
			(stroke
				(width 0.1)
				(type default)
			)
			(layer "B.Fab")
		)
		(fp_line
			(start 0.67945 -0.305054)
			(end 0.12065 -0.305054)
			(stroke
				(width 0.1)
				(type default)
			)
			(layer "B.Fab")
		)
		(fp_line
			(start 0.67945 0.3048)
			(end 0.67945 -0.305054)
			(stroke
				(width 0.1)
				(type default)
			)
			(layer "B.Fab")
		)
		(pad "1" smd circle
			(at 0.40005 0 180)
			(size 0 0)
			(layers "B.Cu" "B.Mask" "B.Paste")
			(net "PVDD18_S5_P1_EN")
		)
		(pad "2" smd circle
			(at -0.40005 0 180)
			(size 0 0)
			(layers "B.Cu" "B.Mask" "B.Paste")
			(net "PVDD18_S5_P1_R_EN")
		)
	)
	(footprint ""
		(layer "B.Cu")
		(at 405.086058 -319.748916 -90)
		(property "Reference" "R431"
			(at 0 0 90)
			(layer "B.SilkS")
			(hide yes)
			(effects
				(font
					(size 1.27 1.27)
				)
				(justify mirror)
			)
		)
		(property "Value" ""
			(at 0 0 90)
			(layer "B.Fab")
			(effects
				(font
					(size 1.27 1.27)
				)
				(justify mirror)
			)
		)
		(duplicate_pad_numbers_are_jumpers no)
		(fp_line
			(start -0.7874 0.4064)
			(end 0.7874 0.4064)
			(stroke
				(width 0.1524)
				(type default)
			)
			(layer "B.SilkS")
		)
		(fp_line
			(start 0.7874 0.4064)
			(end 0.7874 -0.4064)
			(stroke
				(width 0.1524)
				(type default)
			)
			(layer "B.SilkS")
		)
		(fp_line
			(start -0.7874 -0.4064)
			(end -0.7874 0.4064)
			(stroke
				(width 0.1524)
				(type default)
			)
			(layer "B.SilkS")
		)
		(fp_line
			(start 0.7874 -0.4064)
			(end -0.7874 -0.4064)
			(stroke
				(width 0.1524)
				(type default)
			)
			(layer "B.SilkS")
		)
		(fp_line
			(start -0.67945 0.3048)
			(end -0.120396 0.3048)
			(stroke
				(width 0.1)
				(type default)
			)
			(layer "B.Fab")
		)
		(fp_line
			(start -0.120396 0.3048)
			(end -0.120396 0.2794)
			(stroke
				(width 0.1)
				(type default)
			)
			(layer "B.Fab")
		)
		(fp_line
			(start 0.12065 0.3048)
			(end 0.67945 0.3048)
			(stroke
				(width 0.1)
				(type default)
			)
			(layer "B.Fab")
		)
		(fp_line
			(start 0.67945 0.3048)
			(end 0.67945 -0.305054)
			(stroke
				(width 0.1)
				(type default)
			)
			(layer "B.Fab")
		)
		(fp_line
			(start -0.120396 0.2794)
			(end 0.12065 0.2794)
			(stroke
				(width 0.1)
				(type default)
			)
			(layer "B.Fab")
		)
		(fp_line
			(start 0.12065 0.2794)
			(end 0.12065 0.3048)
			(stroke
				(width 0.1)
				(type default)
			)
			(layer "B.Fab")
		)
		(fp_line
			(start -0.12065 -0.2794)
			(end -0.12065 -0.3048)
			(stroke
				(width 0.1)
				(type default)
			)
			(layer "B.Fab")
		)
		(fp_line
			(start 0.12065 -0.2794)
			(end -0.12065 -0.2794)
			(stroke
				(width 0.1)
				(type default)
			)
			(layer "B.Fab")
		)
		(fp_line
			(start -0.67945 -0.3048)
			(end -0.67945 0.3048)
			(stroke
				(width 0.1)
				(type default)
			)
			(layer "B.Fab")
		)
		(fp_line
			(start -0.12065 -0.3048)
			(end -0.67945 -0.3048)
			(stroke
				(width 0.1)
				(type default)
			)
			(layer "B.Fab")
		)
		(fp_line
			(start 0.12065 -0.305054)
			(end 0.12065 -0.2794)
			(stroke
				(width 0.1)
				(type default)
			)
			(layer "B.Fab")
		)
		(fp_line
			(start 0.67945 -0.305054)
			(end 0.12065 -0.305054)
			(stroke
				(width 0.1)
				(type default)
			)
			(layer "B.Fab")
		)
		(pad "1" smd circle
			(at 0.40005 0 90)
			(size 0 0)
			(layers "B.Cu" "B.Mask" "B.Paste")
			(net "SMB_CPU0_4_R_SDA")
		)
		(pad "2" smd circle
			(at -0.40005 0 90)
			(size 0 0)
			(layers "B.Cu" "B.Mask" "B.Paste")
			(net "SMB_CPU0_4_SDA")
		)
	)
	(footprint ""
		(layer "B.Cu")
		(at 236.119162 -224.515934 -90)
		(property "Reference" "C23"
			(at 0 0 90)
			(layer "B.SilkS")
			(hide yes)
			(effects
				(font
					(size 1.27 1.27)
				)
				(justify mirror)
			)
		)
		(property "Value" ""
			(at 0 0 90)
			(layer "B.Fab")
			(effects
				(font
					(size 1.27 1.27)
				)
				(justify mirror)
			)
		)
		(duplicate_pad_numbers_are_jumpers no)
		(fp_line
			(start -0.7874 0.4064)
			(end 0.7874 0.4064)
			(stroke
				(width 0.1524)
				(type default)
			)
			(layer "B.SilkS")
		)
		(fp_line
			(start 0.7874 0.4064)
			(end 0.7874 -0.4064)
			(stroke
				(width 0.1524)
				(type default)
			)
			(layer "B.SilkS")
		)
		(fp_line
			(start -0.7874 -0.4064)
			(end -0.7874 0.4064)
			(stroke
				(width 0.1524)
				(type default)
			)
			(layer "B.SilkS")
		)
		(fp_line
			(start 0.7874 -0.4064)
			(end -0.7874 -0.4064)
			(stroke
				(width 0.1524)
				(type default)
			)
			(layer "B.SilkS")
		)
		(fp_line
			(start -0.67945 0.3048)
			(end -0.120396 0.3048)
			(stroke
				(width 0.1)
				(type default)
			)
			(layer "B.Fab")
		)
		(fp_line
			(start -0.120396 0.3048)
			(end -0.120396 0.2794)
			(stroke
				(width 0.1)
				(type default)
			)
			(layer "B.Fab")
		)
		(fp_line
			(start 0.12065 0.3048)
			(end 0.67945 0.3048)
			(stroke
				(width 0.1)
				(type default)
			)
			(layer "B.Fab")
		)
		(fp_line
			(start 0.67945 0.3048)
			(end 0.67945 -0.305054)
			(stroke
				(width 0.1)
				(type default)
			)
			(layer "B.Fab")
		)
		(fp_line
			(start -0.120396 0.2794)
			(end 0.12065 0.2794)
			(stroke
				(width 0.1)
				(type default)
			)
			(layer "B.Fab")
		)
		(fp_line
			(start 0.12065 0.2794)
			(end 0.12065 0.3048)
			(stroke
				(width 0.1)
				(type default)
			)
			(layer "B.Fab")
		)
		(fp_line
			(start -0.12065 -0.2794)
			(end -0.12065 -0.3048)
			(stroke
				(width 0.1)
				(type default)
			)
			(layer "B.Fab")
		)
		(fp_line
			(start 0.12065 -0.2794)
			(end -0.12065 -0.2794)
			(stroke
				(width 0.1)
				(type default)
			)
			(layer "B.Fab")
		)
		(fp_line
			(start -0.67945 -0.3048)
			(end -0.67945 0.3048)
			(stroke
				(width 0.1)
				(type default)
			)
			(layer "B.Fab")
		)
		(fp_line
			(start -0.12065 -0.3048)
			(end -0.67945 -0.3048)
			(stroke
				(width 0.1)
				(type default)
			)
			(layer "B.Fab")
		)
		(fp_line
			(start 0.12065 -0.305054)
			(end 0.12065 -0.2794)
			(stroke
				(width 0.1)
				(type default)
			)
			(layer "B.Fab")
		)
		(fp_line
			(start 0.67945 -0.305054)
			(end 0.12065 -0.305054)
			(stroke
				(width 0.1)
				(type default)
			)
			(layer "B.Fab")
		)
		(pad "1" smd circle
			(at 0.40005 0 90)
			(size 0 0)
			(layers "B.Cu" "B.Mask" "B.Paste")
			(net "P3V3_AUX")
		)
		(pad "2" smd circle
			(at -0.40005 0 90)
			(size 0 0)
			(layers "B.Cu" "B.Mask" "B.Paste")
			(net "GND")
		)
	)
	(footprint ""
		(layer "B.Cu")
		(at 95.837502 -205.14945 90)
		(property "Reference" "R531"
			(at 0 0 90)
			(layer "B.SilkS")
			(hide yes)
			(effects
				(font
					(size 1.27 1.27)
				)
				(justify mirror)
			)
		)
		(property "Value" ""
			(at 0 0 90)
			(layer "B.Fab")
			(effects
				(font
					(size 1.27 1.27)
				)
				(justify mirror)
			)
		)
		(duplicate_pad_numbers_are_jumpers no)
		(fp_line
			(start 0.7874 -0.4064)
			(end -0.7874 -0.4064)
			(stroke
				(width 0.1524)
				(type default)
			)
			(layer "B.SilkS")
		)
		(fp_line
			(start -0.7874 -0.4064)
			(end -0.7874 0.4064)
			(stroke
				(width 0.1524)
				(type default)
			)
			(layer "B.SilkS")
		)
		(fp_line
			(start 0.7874 0.4064)
			(end 0.7874 -0.4064)
			(stroke
				(width 0.1524)
				(type default)
			)
			(layer "B.SilkS")
		)
		(fp_line
			(start -0.7874 0.4064)
			(end 0.7874 0.4064)
			(stroke
				(width 0.1524)
				(type default)
			)
			(layer "B.SilkS")
		)
		(fp_line
			(start 0.67945 -0.305054)
			(end 0.12065 -0.305054)
			(stroke
				(width 0.1)
				(type default)
			)
			(layer "B.Fab")
		)
		(fp_line
			(start 0.12065 -0.305054)
			(end 0.12065 -0.2794)
			(stroke
				(width 0.1)
				(type default)
			)
			(layer "B.Fab")
		)
		(fp_line
			(start -0.12065 -0.3048)
			(end -0.67945 -0.3048)
			(stroke
				(width 0.1)
				(type default)
			)
			(layer "B.Fab")
		)
		(fp_line
			(start -0.67945 -0.3048)
			(end -0.67945 0.3048)
			(stroke
				(width 0.1)
				(type default)
			)
			(layer "B.Fab")
		)
		(fp_line
			(start 0.12065 -0.2794)
			(end -0.12065 -0.2794)
			(stroke
				(width 0.1)
				(type default)
			)
			(layer "B.Fab")
		)
		(fp_line
			(start -0.12065 -0.2794)
			(end -0.12065 -0.3048)
			(stroke
				(width 0.1)
				(type default)
			)
			(layer "B.Fab")
		)
		(fp_line
			(start 0.12065 0.2794)
			(end 0.12065 0.3048)
			(stroke
				(width 0.1)
				(type default)
			)
			(layer "B.Fab")
		)
		(fp_line
			(start -0.120396 0.2794)
			(end 0.12065 0.2794)
			(stroke
				(width 0.1)
				(type default)
			)
			(layer "B.Fab")
		)
		(fp_line
			(start 0.67945 0.3048)
			(end 0.67945 -0.305054)
			(stroke
				(width 0.1)
				(type default)
			)
			(layer "B.Fab")
		)
		(fp_line
			(start 0.12065 0.3048)
			(end 0.67945 0.3048)
			(stroke
				(width 0.1)
				(type default)
			)
			(layer "B.Fab")
		)
		(fp_line
			(start -0.120396 0.3048)
			(end -0.120396 0.2794)
			(stroke
				(width 0.1)
				(type default)
			)
			(layer "B.Fab")
		)
		(fp_line
			(start -0.67945 0.3048)
			(end -0.120396 0.3048)
			(stroke
				(width 0.1)
				(type default)
			)
			(layer "B.Fab")
		)
		(pad "1" smd circle
			(at 0.40005 0 270)
			(size 0 0)
			(layers "B.Cu" "B.Mask" "B.Paste")
			(net "CPU1_BP0")
		)
		(pad "2" smd circle
			(at -0.40005 0 270)
			(size 0 0)
			(layers "B.Cu" "B.Mask" "B.Paste")
			(net "PVDD18_S5_P1")
		)
	)
	(footprint ""
		(layer "B.Cu")
		(at 318.97828 -395.148562 90)
		(property "Reference" "C570"
			(at 0 0 90)
			(layer "B.SilkS")
			(hide yes)
			(effects
				(font
					(size 1.27 1.27)
				)
				(justify mirror)
			)
		)
		(property "Value" ""
			(at 0 0 90)
			(layer "B.Fab")
			(effects
				(font
					(size 1.27 1.27)
				)
				(justify mirror)
			)
		)
		(duplicate_pad_numbers_are_jumpers no)
		(fp_line
			(start 0.299974 -0.150114)
			(end -0.299974 -0.150114)
			(stroke
				(width 0.1)
				(type default)
			)
			(layer "B.Fab")
		)
		(fp_line
			(start -0.299974 -0.150114)
			(end -0.299974 0.150114)
			(stroke
				(width 0.1)
				(type default)
			)
			(layer "B.Fab")
		)
		(fp_line
			(start 0.299974 0.150114)
			(end 0.299974 -0.150114)
			(stroke
				(width 0.1)
				(type default)
			)
			(layer "B.Fab")
		)
		(fp_line
			(start -0.299974 0.150114)
			(end 0.299974 0.150114)
			(stroke
				(width 0.1)
				(type default)
			)
			(layer "B.Fab")
		)
		(pad "1" smd rect
			(at 0.2667 0 270)
			(size 0.3048 0.381)
			(layers "B.Cu" "B.Mask" "B.Paste")
			(net "P0V9_CPU0_RT0_2A")
		)
		(pad "2" smd rect
			(at -0.2667 0 270)
			(size 0.3048 0.381)
			(layers "B.Cu" "B.Mask" "B.Paste")
			(net "GND")
		)
	)
	(footprint ""
		(layer "B.Cu")
		(at 166.373048 -390.560052 90)
		(property "Reference" "C402"
			(at 0 0 90)
			(layer "B.SilkS")
			(hide yes)
			(effects
				(font
					(size 1.27 1.27)
				)
				(justify mirror)
			)
		)
		(property "Value" ""
			(at 0 0 90)
			(layer "B.Fab")
			(effects
				(font
					(size 1.27 1.27)
				)
				(justify mirror)
			)
		)
		(duplicate_pad_numbers_are_jumpers no)
		(fp_line
			(start 0.7874 -0.4064)
			(end -0.7874 -0.4064)
			(stroke
				(width 0.1524)
				(type default)
			)
			(layer "B.SilkS")
		)
		(fp_line
			(start -0.7874 -0.4064)
			(end -0.7874 0.4064)
			(stroke
				(width 0.1524)
				(type default)
			)
			(layer "B.SilkS")
		)
		(fp_line
			(start 0.7874 0.4064)
			(end 0.7874 -0.4064)
			(stroke
				(width 0.1524)
				(type default)
			)
			(layer "B.SilkS")
		)
		(fp_line
			(start -0.7874 0.4064)
			(end 0.7874 0.4064)
			(stroke
				(width 0.1524)
				(type default)
			)
			(layer "B.SilkS")
		)
		(fp_line
			(start 0.67945 -0.305054)
			(end 0.12065 -0.305054)
			(stroke
				(width 0.1)
				(type default)
			)
			(layer "B.Fab")
		)
		(fp_line
			(start 0.12065 -0.305054)
			(end 0.12065 -0.2794)
			(stroke
				(width 0.1)
				(type default)
			)
			(layer "B.Fab")
		)
		(fp_line
			(start -0.12065 -0.3048)
			(end -0.67945 -0.3048)
			(stroke
				(width 0.1)
				(type default)
			)
			(layer "B.Fab")
		)
		(fp_line
			(start -0.67945 -0.3048)
			(end -0.67945 0.3048)
			(stroke
				(width 0.1)
				(type default)
			)
			(layer "B.Fab")
		)
		(fp_line
			(start 0.12065 -0.2794)
			(end -0.12065 -0.2794)
			(stroke
				(width 0.1)
				(type default)
			)
			(layer "B.Fab")
		)
		(fp_line
			(start -0.12065 -0.2794)
			(end -0.12065 -0.3048)
			(stroke
				(width 0.1)
				(type default)
			)
			(layer "B.Fab")
		)
		(fp_line
			(start 0.12065 0.2794)
			(end 0.12065 0.3048)
			(stroke
				(width 0.1)
				(type default)
			)
			(layer "B.Fab")
		)
		(fp_line
			(start -0.120396 0.2794)
			(end 0.12065 0.2794)
			(stroke
				(width 0.1)
				(type default)
			)
			(layer "B.Fab")
		)
		(fp_line
			(start 0.67945 0.3048)
			(end 0.67945 -0.305054)
			(stroke
				(width 0.1)
				(type default)
			)
			(layer "B.Fab")
		)
		(fp_line
			(start 0.12065 0.3048)
			(end 0.67945 0.3048)
			(stroke
				(width 0.1)
				(type default)
			)
			(layer "B.Fab")
		)
		(fp_line
			(start -0.120396 0.3048)
			(end -0.120396 0.2794)
			(stroke
				(width 0.1)
				(type default)
			)
			(layer "B.Fab")
		)
		(fp_line
			(start -0.67945 0.3048)
			(end -0.120396 0.3048)
			(stroke
				(width 0.1)
				(type default)
			)
			(layer "B.Fab")
		)
		(pad "1" smd circle
			(at 0.40005 0 270)
			(size 0 0)
			(layers "B.Cu" "B.Mask" "B.Paste")
			(net "P0V9_CPU1_RT2_2A")
		)
		(pad "2" smd circle
			(at -0.40005 0 270)
			(size 0 0)
			(layers "B.Cu" "B.Mask" "B.Paste")
			(net "GND")
		)
	)
	(footprint ""
		(layer "B.Cu")
		(at 356.311454 -267.52931)
		(property "Reference" "C2227"
			(at 0 0 0)
			(layer "B.SilkS")
			(hide yes)
			(effects
				(font
					(size 1.27 1.27)
				)
				(justify mirror)
			)
		)
		(property "Value" ""
			(at 0 0 0)
			(layer "B.Fab")
			(effects
				(font
					(size 1.27 1.27)
				)
				(justify mirror)
			)
		)
		(duplicate_pad_numbers_are_jumpers no)
		(fp_line
			(start -0.7874 -0.4064)
			(end -0.7874 0.4064)
			(stroke
				(width 0.1524)
				(type default)
			)
			(layer "B.SilkS")
		)
		(fp_line
			(start -0.7874 0.4064)
			(end 0.7874 0.4064)
			(stroke
				(width 0.1524)
				(type default)
			)
			(layer "B.SilkS")
		)
		(fp_line
			(start 0.7874 -0.4064)
			(end -0.7874 -0.4064)
			(stroke
				(width 0.1524)
				(type default)
			)
			(layer "B.SilkS")
		)
		(fp_line
			(start 0.7874 0.4064)
			(end 0.7874 -0.4064)
			(stroke
				(width 0.1524)
				(type default)
			)
			(layer "B.SilkS")
		)
		(fp_line
			(start -0.67945 -0.3048)
			(end -0.67945 0.3048)
			(stroke
				(width 0.1)
				(type default)
			)
			(layer "B.Fab")
		)
		(fp_line
			(start -0.67945 0.3048)
			(end -0.120396 0.3048)
			(stroke
				(width 0.1)
				(type default)
			)
			(layer "B.Fab")
		)
		(fp_line
			(start -0.12065 -0.3048)
			(end -0.67945 -0.3048)
			(stroke
				(width 0.1)
				(type default)
			)
			(layer "B.Fab")
		)
		(fp_line
			(start -0.12065 -0.2794)
			(end -0.12065 -0.3048)
			(stroke
				(width 0.1)
				(type default)
			)
			(layer "B.Fab")
		)
		(fp_line
			(start -0.120396 0.2794)
			(end 0.12065 0.2794)
			(stroke
				(width 0.1)
				(type default)
			)
			(layer "B.Fab")
		)
		(fp_line
			(start -0.120396 0.3048)
			(end -0.120396 0.2794)
			(stroke
				(width 0.1)
				(type default)
			)
			(layer "B.Fab")
		)
		(fp_line
			(start 0.12065 -0.305054)
			(end 0.12065 -0.2794)
			(stroke
				(width 0.1)
				(type default)
			)
			(layer "B.Fab")
		)
		(fp_line
			(start 0.12065 -0.2794)
			(end -0.12065 -0.2794)
			(stroke
				(width 0.1)
				(type default)
			)
			(layer "B.Fab")
		)
		(fp_line
			(start 0.12065 0.2794)
			(end 0.12065 0.3048)
			(stroke
				(width 0.1)
				(type default)
			)
			(layer "B.Fab")
		)
		(fp_line
			(start 0.12065 0.3048)
			(end 0.67945 0.3048)
			(stroke
				(width 0.1)
				(type default)
			)
			(layer "B.Fab")
		)
		(fp_line
			(start 0.67945 -0.305054)
			(end 0.12065 -0.305054)
			(stroke
				(width 0.1)
				(type default)
			)
			(layer "B.Fab")
		)
		(fp_line
			(start 0.67945 0.3048)
			(end 0.67945 -0.305054)
			(stroke
				(width 0.1)
				(type default)
			)
			(layer "B.Fab")
		)
		(pad "1" smd circle
			(at 0.40005 0 180)
			(size 0 0)
			(layers "B.Cu" "B.Mask" "B.Paste")
			(net "PVDDCR_CPU1_P0")
		)
		(pad "2" smd circle
			(at -0.40005 0 180)
			(size 0 0)
			(layers "B.Cu" "B.Mask" "B.Paste")
			(net "GND")
		)
	)
	(footprint ""
		(layer "B.Cu")
		(at 358.057958 -248.916952 120)
		(property "Reference" "C2182"
			(at 0 0 120)
			(layer "B.SilkS")
			(hide yes)
			(effects
				(font
					(size 1.27 1.27)
				)
				(justify mirror)
			)
		)
		(property "Value" ""
			(at 0 0 120)
			(layer "B.Fab")
			(effects
				(font
					(size 1.27 1.27)
				)
				(justify mirror)
			)
		)
		(duplicate_pad_numbers_are_jumpers no)
		(fp_line
			(start 0.787516 -0.406438)
			(end -0.787425 -0.40652)
			(stroke
				(width 0.1524)
				(type default)
			)
			(layer "B.SilkS")
		)
		(fp_line
			(start 0.787425 0.40652)
			(end 0.787516 -0.406438)
			(stroke
				(width 0.1524)
				(type default)
			)
			(layer "B.SilkS")
		)
		(fp_line
			(start -0.787425 -0.40652)
			(end -0.787516 0.406438)
			(stroke
				(width 0.1524)
				(type default)
			)
			(layer "B.SilkS")
		)
		(fp_line
			(start -0.787516 0.406438)
			(end 0.787425 0.40652)
			(stroke
				(width 0.1524)
				(type default)
			)
			(layer "B.SilkS")
		)
		(fp_line
			(start 0.679475 -0.305158)
			(end 0.120732 -0.305125)
			(stroke
				(width 0.1)
				(type default)
			)
			(layer "B.Fab")
		)
		(fp_line
			(start 0.120732 -0.305125)
			(end 0.120554 -0.279418)
			(stroke
				(width 0.1)
				(type default)
			)
			(layer "B.Fab")
		)
		(fp_line
			(start 0.120554 -0.279418)
			(end -0.120587 -0.279326)
			(stroke
				(width 0.1)
				(type default)
			)
			(layer "B.Fab")
		)
		(fp_line
			(start -0.120536 -0.304813)
			(end -0.6795 -0.304908)
			(stroke
				(width 0.1)
				(type default)
			)
			(layer "B.Fab")
		)
		(fp_line
			(start -0.120587 -0.279326)
			(end -0.120536 -0.304813)
			(stroke
				(width 0.1)
				(type default)
			)
			(layer "B.Fab")
		)
		(fp_line
			(start 0.6795 0.304908)
			(end 0.679475 -0.305158)
			(stroke
				(width 0.1)
				(type default)
			)
			(layer "B.Fab")
		)
		(fp_line
			(start -0.6795 -0.304908)
			(end -0.679568 0.304811)
			(stroke
				(width 0.1)
				(type default)
			)
			(layer "B.Fab")
		)
		(fp_line
			(start 0.120587 0.279326)
			(end 0.120536 0.304813)
			(stroke
				(width 0.1)
				(type default)
			)
			(layer "B.Fab")
		)
		(fp_line
			(start 0.120536 0.304813)
			(end 0.6795 0.304908)
			(stroke
				(width 0.1)
				(type default)
			)
			(layer "B.Fab")
		)
		(fp_line
			(start -0.120334 0.279545)
			(end 0.120587 0.279326)
			(stroke
				(width 0.1)
				(type default)
			)
			(layer "B.Fab")
		)
		(fp_line
			(start -0.120258 0.304812)
			(end -0.120334 0.279545)
			(stroke
				(width 0.1)
				(type default)
			)
			(layer "B.Fab")
		)
		(fp_line
			(start -0.679568 0.304811)
			(end -0.120258 0.304812)
			(stroke
				(width 0.1)
				(type default)
			)
			(layer "B.Fab")
		)
		(pad "1" smd circle
			(at 0.40005 0 300)
			(size 0 0)
			(layers "B.Cu" "B.Mask" "B.Paste")
			(net "PVDDCR_CPU0_P0")
		)
		(pad "2" smd circle
			(at -0.40005 0 300)
			(size 0 0)
			(layers "B.Cu" "B.Mask" "B.Paste")
			(net "GND")
		)
	)
	(footprint ""
		(layer "B.Cu")
		(at 65.12433 -346.788994 90)
		(property "Reference" "PC411_4"
			(at 0 0 90)
			(layer "B.SilkS")
			(hide yes)
			(effects
				(font
					(size 1.27 1.27)
				)
				(justify mirror)
			)
		)
		(property "Value" ""
			(at 0 0 90)
			(layer "B.Fab")
			(effects
				(font
					(size 1.27 1.27)
				)
				(justify mirror)
			)
		)
		(duplicate_pad_numbers_are_jumpers no)
		(fp_line
			(start 1.524 -0.762)
			(end -1.524 -0.762)
			(stroke
				(width 0.1524)
				(type default)
			)
			(layer "B.SilkS")
		)
		(fp_line
			(start -1.524 -0.762)
			(end -1.524 0.762)
			(stroke
				(width 0.1524)
				(type default)
			)
			(layer "B.SilkS")
		)
		(fp_line
			(start 1.524 0.762)
			(end 1.524 -0.762)
			(stroke
				(width 0.1524)
				(type default)
			)
			(layer "B.SilkS")
		)
		(fp_line
			(start -1.524 0.762)
			(end 1.524 0.762)
			(stroke
				(width 0.1524)
				(type default)
			)
			(layer "B.SilkS")
		)
		(fp_line
			(start 1.1049 -0.724916)
			(end 1.1049 0.724916)
			(stroke
				(width 0.1)
				(type default)
			)
			(layer "B.Fab")
		)
		(fp_line
			(start -1.1049 -0.724916)
			(end 1.1049 -0.724916)
			(stroke
				(width 0.1)
				(type default)
			)
			(layer "B.Fab")
		)
		(fp_line
			(start 1.1049 0.724916)
			(end -1.1049 0.724916)
			(stroke
				(width 0.1)
				(type default)
			)
			(layer "B.Fab")
		)
		(fp_line
			(start -1.1049 0.724916)
			(end -1.1049 -0.724916)
			(stroke
				(width 0.1)
				(type default)
			)
			(layer "B.Fab")
		)
		(pad "1" smd rect
			(at 0.889 0 90)
			(size 1.016 1.27)
			(layers "B.Cu" "B.Mask" "B.Paste")
			(net "SW_P12V_AUX_PVDDCR_CPU1_P1_FLT")
		)
		(pad "2" smd rect
			(at -0.889 0 90)
			(size 1.016 1.27)
			(layers "B.Cu" "B.Mask" "B.Paste")
			(net "GND")
		)
	)
	(footprint ""
		(layer "B.Cu")
		(at 421.895778 -177.861722)
		(property "Reference" "TP10"
			(at -0.61468 0.184912 0)
			(unlocked yes)
			(layer "B.SilkS")
			(effects
				(font
					(size 0.7874 0.5842)
					(thickness 0.1524)
				)
				(justify left mirror)
			)
		)
		(property "Value" ""
			(at 0 0 0)
			(layer "B.Fab")
			(effects
				(font
					(size 1.27 1.27)
				)
				(justify mirror)
			)
		)
		(duplicate_pad_numbers_are_jumpers no)
		(pad "1" smd circle
			(at 0 0 180)
			(size 0.6604 0.6604)
			(layers "B.Cu" "B.Mask" "B.Paste")
			(net "VSENSE_PVDDCR_SOC_P0_DP")
		)
	)
	(footprint ""
		(layer "B.Cu")
		(at 241.756692 -422.849548 90)
		(property "Reference" "R2803"
			(at 0 0 90)
			(layer "B.SilkS")
			(hide yes)
			(effects
				(font
					(size 1.27 1.27)
				)
				(justify mirror)
			)
		)
		(property "Value" ""
			(at 0 0 90)
			(layer "B.Fab")
			(effects
				(font
					(size 1.27 1.27)
				)
				(justify mirror)
			)
		)
		(duplicate_pad_numbers_are_jumpers no)
		(fp_line
			(start 0.7874 -0.4064)
			(end -0.7874 -0.4064)
			(stroke
				(width 0.1524)
				(type default)
			)
			(layer "B.SilkS")
		)
		(fp_line
			(start -0.7874 -0.4064)
			(end -0.7874 0.4064)
			(stroke
				(width 0.1524)
				(type default)
			)
			(layer "B.SilkS")
		)
		(fp_line
			(start 0.7874 0.4064)
			(end 0.7874 -0.4064)
			(stroke
				(width 0.1524)
				(type default)
			)
			(layer "B.SilkS")
		)
		(fp_line
			(start -0.7874 0.4064)
			(end 0.7874 0.4064)
			(stroke
				(width 0.1524)
				(type default)
			)
			(layer "B.SilkS")
		)
		(fp_line
			(start 0.67945 -0.305054)
			(end 0.12065 -0.305054)
			(stroke
				(width 0.1)
				(type default)
			)
			(layer "B.Fab")
		)
		(fp_line
			(start 0.12065 -0.305054)
			(end 0.12065 -0.2794)
			(stroke
				(width 0.1)
				(type default)
			)
			(layer "B.Fab")
		)
		(fp_line
			(start -0.12065 -0.3048)
			(end -0.67945 -0.3048)
			(stroke
				(width 0.1)
				(type default)
			)
			(layer "B.Fab")
		)
		(fp_line
			(start -0.67945 -0.3048)
			(end -0.67945 0.3048)
			(stroke
				(width 0.1)
				(type default)
			)
			(layer "B.Fab")
		)
		(fp_line
			(start 0.12065 -0.2794)
			(end -0.12065 -0.2794)
			(stroke
				(width 0.1)
				(type default)
			)
			(layer "B.Fab")
		)
		(fp_line
			(start -0.12065 -0.2794)
			(end -0.12065 -0.3048)
			(stroke
				(width 0.1)
				(type default)
			)
			(layer "B.Fab")
		)
		(fp_line
			(start 0.12065 0.2794)
			(end 0.12065 0.3048)
			(stroke
				(width 0.1)
				(type default)
			)
			(layer "B.Fab")
		)
		(fp_line
			(start -0.120396 0.2794)
			(end 0.12065 0.2794)
			(stroke
				(width 0.1)
				(type default)
			)
			(layer "B.Fab")
		)
		(fp_line
			(start 0.67945 0.3048)
			(end 0.67945 -0.305054)
			(stroke
				(width 0.1)
				(type default)
			)
			(layer "B.Fab")
		)
		(fp_line
			(start 0.12065 0.3048)
			(end 0.67945 0.3048)
			(stroke
				(width 0.1)
				(type default)
			)
			(layer "B.Fab")
		)
		(fp_line
			(start -0.120396 0.3048)
			(end -0.120396 0.2794)
			(stroke
				(width 0.1)
				(type default)
			)
			(layer "B.Fab")
		)
		(fp_line
			(start -0.67945 0.3048)
			(end -0.120396 0.3048)
			(stroke
				(width 0.1)
				(type default)
			)
			(layer "B.Fab")
		)
		(pad "1" smd circle
			(at 0.40005 0 270)
			(size 0 0)
			(layers "B.Cu" "B.Mask" "B.Paste")
			(net "FM_FAN_PWR_EN_R")
		)
		(pad "2" smd circle
			(at -0.40005 0 270)
			(size 0 0)
			(layers "B.Cu" "B.Mask" "B.Paste")
			(net "FM_FAN_PWR_EN")
		)
	)
	(footprint ""
		(layer "B.Cu")
		(at 346.754958 -269.30731 180)
		(property "Reference" "C2256"
			(at 0 0 0)
			(layer "B.SilkS")
			(hide yes)
			(effects
				(font
					(size 1.27 1.27)
				)
				(justify mirror)
			)
		)
		(property "Value" ""
			(at 0 0 0)
			(layer "B.Fab")
			(effects
				(font
					(size 1.27 1.27)
				)
				(justify mirror)
			)
		)
		(duplicate_pad_numbers_are_jumpers no)
		(fp_line
			(start 0.7874 0.4064)
			(end 0.7874 -0.4064)
			(stroke
				(width 0.1524)
				(type default)
			)
			(layer "B.SilkS")
		)
		(fp_line
			(start 0.7874 -0.4064)
			(end -0.7874 -0.4064)
			(stroke
				(width 0.1524)
				(type default)
			)
			(layer "B.SilkS")
		)
		(fp_line
			(start -0.7874 0.4064)
			(end 0.7874 0.4064)
			(stroke
				(width 0.1524)
				(type default)
			)
			(layer "B.SilkS")
		)
		(fp_line
			(start -0.7874 -0.4064)
			(end -0.7874 0.4064)
			(stroke
				(width 0.1524)
				(type default)
			)
			(layer "B.SilkS")
		)
		(fp_line
			(start 0.67945 0.3048)
			(end 0.67945 -0.305054)
			(stroke
				(width 0.1)
				(type default)
			)
			(layer "B.Fab")
		)
		(fp_line
			(start 0.67945 -0.305054)
			(end 0.12065 -0.305054)
			(stroke
				(width 0.1)
				(type default)
			)
			(layer "B.Fab")
		)
		(fp_line
			(start 0.12065 0.3048)
			(end 0.67945 0.3048)
			(stroke
				(width 0.1)
				(type default)
			)
			(layer "B.Fab")
		)
		(fp_line
			(start 0.12065 0.2794)
			(end 0.12065 0.3048)
			(stroke
				(width 0.1)
				(type default)
			)
			(layer "B.Fab")
		)
		(fp_line
			(start 0.12065 -0.2794)
			(end -0.12065 -0.2794)
			(stroke
				(width 0.1)
				(type default)
			)
			(layer "B.Fab")
		)
		(fp_line
			(start 0.12065 -0.305054)
			(end 0.12065 -0.2794)
			(stroke
				(width 0.1)
				(type default)
			)
			(layer "B.Fab")
		)
		(fp_line
			(start -0.120396 0.3048)
			(end -0.120396 0.2794)
			(stroke
				(width 0.1)
				(type default)
			)
			(layer "B.Fab")
		)
		(fp_line
			(start -0.120396 0.2794)
			(end 0.12065 0.2794)
			(stroke
				(width 0.1)
				(type default)
			)
			(layer "B.Fab")
		)
		(fp_line
			(start -0.12065 -0.2794)
			(end -0.12065 -0.3048)
			(stroke
				(width 0.1)
				(type default)
			)
			(layer "B.Fab")
		)
		(fp_line
			(start -0.12065 -0.3048)
			(end -0.67945 -0.3048)
			(stroke
				(width 0.1)
				(type default)
			)
			(layer "B.Fab")
		)
		(fp_line
			(start -0.67945 0.3048)
			(end -0.120396 0.3048)
			(stroke
				(width 0.1)
				(type default)
			)
			(layer "B.Fab")
		)
		(fp_line
			(start -0.67945 -0.3048)
			(end -0.67945 0.3048)
			(stroke
				(width 0.1)
				(type default)
			)
			(layer "B.Fab")
		)
		(pad "1" smd circle
			(at 0.40005 0)
			(size 0 0)
			(layers "B.Cu" "B.Mask" "B.Paste")
			(net "PVDDCR_CPU1_P0")
		)
		(pad "2" smd circle
			(at -0.40005 0)
			(size 0 0)
			(layers "B.Cu" "B.Mask" "B.Paste")
			(net "GND")
		)
	)
	(footprint ""
		(layer "B.Cu")
		(at 191.26454 -402.741892 90)
		(property "Reference" "R2587"
			(at 0 0 90)
			(layer "B.SilkS")
			(hide yes)
			(effects
				(font
					(size 1.27 1.27)
				)
				(justify mirror)
			)
		)
		(property "Value" ""
			(at 0 0 90)
			(layer "B.Fab")
			(effects
				(font
					(size 1.27 1.27)
				)
				(justify mirror)
			)
		)
		(duplicate_pad_numbers_are_jumpers no)
		(fp_line
			(start 0.7874 -0.4064)
			(end -0.7874 -0.4064)
			(stroke
				(width 0.1524)
				(type default)
			)
			(layer "B.SilkS")
		)
		(fp_line
			(start -0.7874 -0.4064)
			(end -0.7874 0.4064)
			(stroke
				(width 0.1524)
				(type default)
			)
			(layer "B.SilkS")
		)
		(fp_line
			(start 0.7874 0.4064)
			(end 0.7874 -0.4064)
			(stroke
				(width 0.1524)
				(type default)
			)
			(layer "B.SilkS")
		)
		(fp_line
			(start -0.7874 0.4064)
			(end 0.7874 0.4064)
			(stroke
				(width 0.1524)
				(type default)
			)
			(layer "B.SilkS")
		)
		(fp_line
			(start 0.67945 -0.305054)
			(end 0.12065 -0.305054)
			(stroke
				(width 0.1)
				(type default)
			)
			(layer "B.Fab")
		)
		(fp_line
			(start 0.12065 -0.305054)
			(end 0.12065 -0.2794)
			(stroke
				(width 0.1)
				(type default)
			)
			(layer "B.Fab")
		)
		(fp_line
			(start -0.12065 -0.3048)
			(end -0.67945 -0.3048)
			(stroke
				(width 0.1)
				(type default)
			)
			(layer "B.Fab")
		)
		(fp_line
			(start -0.67945 -0.3048)
			(end -0.67945 0.3048)
			(stroke
				(width 0.1)
				(type default)
			)
			(layer "B.Fab")
		)
		(fp_line
			(start 0.12065 -0.2794)
			(end -0.12065 -0.2794)
			(stroke
				(width 0.1)
				(type default)
			)
			(layer "B.Fab")
		)
		(fp_line
			(start -0.12065 -0.2794)
			(end -0.12065 -0.3048)
			(stroke
				(width 0.1)
				(type default)
			)
			(layer "B.Fab")
		)
		(fp_line
			(start 0.12065 0.2794)
			(end 0.12065 0.3048)
			(stroke
				(width 0.1)
				(type default)
			)
			(layer "B.Fab")
		)
		(fp_line
			(start -0.120396 0.2794)
			(end 0.12065 0.2794)
			(stroke
				(width 0.1)
				(type default)
			)
			(layer "B.Fab")
		)
		(fp_line
			(start 0.67945 0.3048)
			(end 0.67945 -0.305054)
			(stroke
				(width 0.1)
				(type default)
			)
			(layer "B.Fab")
		)
		(fp_line
			(start 0.12065 0.3048)
			(end 0.67945 0.3048)
			(stroke
				(width 0.1)
				(type default)
			)
			(layer "B.Fab")
		)
		(fp_line
			(start -0.120396 0.3048)
			(end -0.120396 0.2794)
			(stroke
				(width 0.1)
				(type default)
			)
			(layer "B.Fab")
		)
		(fp_line
			(start -0.67945 0.3048)
			(end -0.120396 0.3048)
			(stroke
				(width 0.1)
				(type default)
			)
			(layer "B.Fab")
		)
		(pad "1" smd circle
			(at 0.40005 0 270)
			(size 0 0)
			(layers "B.Cu" "B.Mask" "B.Paste")
			(net "IRQ_HSC_FAULT_N")
		)
		(pad "2" smd circle
			(at -0.40005 0 270)
			(size 0 0)
			(layers "B.Cu" "B.Mask" "B.Paste")
			(net "HSC_VDD")
		)
	)
	(footprint ""
		(layer "B.Cu")
		(at 167.31869 -14.462506 -90)
		(property "Reference" "R2995"
			(at 0 0 90)
			(layer "B.SilkS")
			(hide yes)
			(effects
				(font
					(size 1.27 1.27)
				)
				(justify mirror)
			)
		)
		(property "Value" ""
			(at 0 0 90)
			(layer "B.Fab")
			(effects
				(font
					(size 1.27 1.27)
				)
				(justify mirror)
			)
		)
		(duplicate_pad_numbers_are_jumpers no)
		(fp_line
			(start -0.7874 0.4064)
			(end 0.7874 0.4064)
			(stroke
				(width 0.1524)
				(type default)
			)
			(layer "B.SilkS")
		)
		(fp_line
			(start 0.7874 0.4064)
			(end 0.7874 -0.4064)
			(stroke
				(width 0.1524)
				(type default)
			)
			(layer "B.SilkS")
		)
		(fp_line
			(start -0.7874 -0.4064)
			(end -0.7874 0.4064)
			(stroke
				(width 0.1524)
				(type default)
			)
			(layer "B.SilkS")
		)
		(fp_line
			(start 0.7874 -0.4064)
			(end -0.7874 -0.4064)
			(stroke
				(width 0.1524)
				(type default)
			)
			(layer "B.SilkS")
		)
		(fp_line
			(start -0.67945 0.3048)
			(end -0.120396 0.3048)
			(stroke
				(width 0.1)
				(type default)
			)
			(layer "B.Fab")
		)
		(fp_line
			(start -0.120396 0.3048)
			(end -0.120396 0.2794)
			(stroke
				(width 0.1)
				(type default)
			)
			(layer "B.Fab")
		)
		(fp_line
			(start 0.12065 0.3048)
			(end 0.67945 0.3048)
			(stroke
				(width 0.1)
				(type default)
			)
			(layer "B.Fab")
		)
		(fp_line
			(start 0.67945 0.3048)
			(end 0.67945 -0.305054)
			(stroke
				(width 0.1)
				(type default)
			)
			(layer "B.Fab")
		)
		(fp_line
			(start -0.120396 0.2794)
			(end 0.12065 0.2794)
			(stroke
				(width 0.1)
				(type default)
			)
			(layer "B.Fab")
		)
		(fp_line
			(start 0.12065 0.2794)
			(end 0.12065 0.3048)
			(stroke
				(width 0.1)
				(type default)
			)
			(layer "B.Fab")
		)
		(fp_line
			(start -0.12065 -0.2794)
			(end -0.12065 -0.3048)
			(stroke
				(width 0.1)
				(type default)
			)
			(layer "B.Fab")
		)
		(fp_line
			(start 0.12065 -0.2794)
			(end -0.12065 -0.2794)
			(stroke
				(width 0.1)
				(type default)
			)
			(layer "B.Fab")
		)
		(fp_line
			(start -0.67945 -0.3048)
			(end -0.67945 0.3048)
			(stroke
				(width 0.1)
				(type default)
			)
			(layer "B.Fab")
		)
		(fp_line
			(start -0.12065 -0.3048)
			(end -0.67945 -0.3048)
			(stroke
				(width 0.1)
				(type default)
			)
			(layer "B.Fab")
		)
		(fp_line
			(start 0.12065 -0.305054)
			(end 0.12065 -0.2794)
			(stroke
				(width 0.1)
				(type default)
			)
			(layer "B.Fab")
		)
		(fp_line
			(start 0.67945 -0.305054)
			(end 0.12065 -0.305054)
			(stroke
				(width 0.1)
				(type default)
			)
			(layer "B.Fab")
		)
		(pad "1" smd circle
			(at 0.40005 0 90)
			(size 0 0)
			(layers "B.Cu" "B.Mask" "B.Paste")
			(net "SMB_PMBUS_3V3AUX_SCL")
		)
		(pad "2" smd circle
			(at -0.40005 0 90)
			(size 0 0)
			(layers "B.Cu" "B.Mask" "B.Paste")
			(net "SMB_SML1_PMBUS_HSC_SCL")
		)
	)
	(footprint ""
		(layer "B.Cu")
		(at 149.087586 -316.88405 90)
		(property "Reference" "Y4"
			(at 2.626106 1.482598 0)
			(unlocked yes)
			(layer "B.SilkS")
			(effects
				(font
					(size 0.7874 0.5842)
					(thickness 0.1524)
				)
				(justify left mirror)
			)
		)
		(property "Value" ""
			(at 0 0 90)
			(layer "B.Fab")
			(effects
				(font
					(size 1.27 1.27)
				)
				(justify mirror)
			)
		)
		(duplicate_pad_numbers_are_jumpers no)
		(fp_line
			(start 1.538732 -1.937004)
			(end -1.538732 -1.937004)
			(stroke
				(width 0.1524)
				(type default)
			)
			(layer "B.SilkS")
		)
		(fp_line
			(start -1.538732 -1.937004)
			(end -1.538732 1.937004)
			(stroke
				(width 0.1524)
				(type default)
			)
			(layer "B.SilkS")
		)
		(fp_line
			(start 1.538732 1.937004)
			(end 1.538732 -1.937004)
			(stroke
				(width 0.1524)
				(type default)
			)
			(layer "B.SilkS")
		)
		(fp_line
			(start -1.538732 1.937004)
			(end 1.538732 1.937004)
			(stroke
				(width 0.1524)
				(type default)
			)
			(layer "B.SilkS")
		)
		(fp_poly
			(pts
				(xy 2.251964 -1.24841) (xy 3.118358 -1.681734) (xy 3.118358 -0.81534)
			)
			(stroke
				(width 0)
				(type default)
			)
			(fill yes)
			(layer "B.SilkS")
		)
		(fp_line
			(start 1.299972 -1.649984)
			(end -1.299972 -1.649984)
			(stroke
				(width 0.1)
				(type default)
			)
			(layer "B.Fab")
		)
		(fp_line
			(start -1.299972 -1.649984)
			(end -1.299972 1.649984)
			(stroke
				(width 0.1)
				(type default)
			)
			(layer "B.Fab")
		)
		(fp_line
			(start 1.299972 1.649984)
			(end 1.299972 -1.649984)
			(stroke
				(width 0.1)
				(type default)
			)
			(layer "B.Fab")
		)
		(fp_line
			(start -1.299972 1.649984)
			(end 1.299972 1.649984)
			(stroke
				(width 0.1)
				(type default)
			)
			(layer "B.Fab")
		)
		(fp_poly
			(pts
				(xy 2.5908 -0.626872) (xy 2.5908 -1.493266) (xy 1.724406 -1.059942)
			)
			(stroke
				(width 0)
				(type default)
			)
			(fill yes)
			(layer "B.Fab")
		)
		(pad "1" smd rect
			(at 0.8001 -1.059942 270)
			(size 1.2192 1.4986)
			(layers "B.Cu" "B.Mask" "B.Paste")
			(net "XTAL_CPU1_X48M_X1")
		)
		(pad "2" smd rect
			(at 0.8001 1.059942 270)
			(size 1.2192 1.4986)
			(layers "B.Cu" "B.Mask" "B.Paste")
			(net "GND")
		)
		(pad "3" smd rect
			(at -0.8001 1.059942 270)
			(size 1.2192 1.4986)
			(layers "B.Cu" "B.Mask" "B.Paste")
			(net "XTAL_CPU1_X48M_X2_R")
		)
		(pad "4" smd rect
			(at -0.8001 -1.059942 270)
			(size 1.2192 1.4986)
			(layers "B.Cu" "B.Mask" "B.Paste")
			(net "GND")
		)
	)
	(footprint ""
		(layer "B.Cu")
		(at 370.905278 -146.552158)
		(property "Reference" "C298"
			(at 0 0 0)
			(layer "B.SilkS")
			(hide yes)
			(effects
				(font
					(size 1.27 1.27)
				)
				(justify mirror)
			)
		)
		(property "Value" ""
			(at 0 0 0)
			(layer "B.Fab")
			(effects
				(font
					(size 1.27 1.27)
				)
				(justify mirror)
			)
		)
		(duplicate_pad_numbers_are_jumpers no)
		(fp_line
			(start -0.7874 -0.4064)
			(end -0.7874 0.4064)
			(stroke
				(width 0.1524)
				(type default)
			)
			(layer "B.SilkS")
		)
		(fp_line
			(start -0.7874 0.4064)
			(end 0.7874 0.4064)
			(stroke
				(width 0.1524)
				(type default)
			)
			(layer "B.SilkS")
		)
		(fp_line
			(start 0.7874 -0.4064)
			(end -0.7874 -0.4064)
			(stroke
				(width 0.1524)
				(type default)
			)
			(layer "B.SilkS")
		)
		(fp_line
			(start 0.7874 0.4064)
			(end 0.7874 -0.4064)
			(stroke
				(width 0.1524)
				(type default)
			)
			(layer "B.SilkS")
		)
		(fp_line
			(start -0.67945 -0.3048)
			(end -0.67945 0.3048)
			(stroke
				(width 0.1)
				(type default)
			)
			(layer "B.Fab")
		)
		(fp_line
			(start -0.67945 0.3048)
			(end -0.120396 0.3048)
			(stroke
				(width 0.1)
				(type default)
			)
			(layer "B.Fab")
		)
		(fp_line
			(start -0.12065 -0.3048)
			(end -0.67945 -0.3048)
			(stroke
				(width 0.1)
				(type default)
			)
			(layer "B.Fab")
		)
		(fp_line
			(start -0.12065 -0.2794)
			(end -0.12065 -0.3048)
			(stroke
				(width 0.1)
				(type default)
			)
			(layer "B.Fab")
		)
		(fp_line
			(start -0.120396 0.2794)
			(end 0.12065 0.2794)
			(stroke
				(width 0.1)
				(type default)
			)
			(layer "B.Fab")
		)
		(fp_line
			(start -0.120396 0.3048)
			(end -0.120396 0.2794)
			(stroke
				(width 0.1)
				(type default)
			)
			(layer "B.Fab")
		)
		(fp_line
			(start 0.12065 -0.305054)
			(end 0.12065 -0.2794)
			(stroke
				(width 0.1)
				(type default)
			)
			(layer "B.Fab")
		)
		(fp_line
			(start 0.12065 -0.2794)
			(end -0.12065 -0.2794)
			(stroke
				(width 0.1)
				(type default)
			)
			(layer "B.Fab")
		)
		(fp_line
			(start 0.12065 0.2794)
			(end 0.12065 0.3048)
			(stroke
				(width 0.1)
				(type default)
			)
			(layer "B.Fab")
		)
		(fp_line
			(start 0.12065 0.3048)
			(end 0.67945 0.3048)
			(stroke
				(width 0.1)
				(type default)
			)
			(layer "B.Fab")
		)
		(fp_line
			(start 0.67945 -0.305054)
			(end 0.12065 -0.305054)
			(stroke
				(width 0.1)
				(type default)
			)
			(layer "B.Fab")
		)
		(fp_line
			(start 0.67945 0.3048)
			(end 0.67945 -0.305054)
			(stroke
				(width 0.1)
				(type default)
			)
			(layer "B.Fab")
		)
		(pad "1" smd circle
			(at 0.40005 0 180)
			(size 0 0)
			(layers "B.Cu" "B.Mask" "B.Paste")
			(net "SVID_PVDDCR_CPU0_P0_SVTO")
		)
		(pad "2" smd circle
			(at -0.40005 0 180)
			(size 0 0)
			(layers "B.Cu" "B.Mask" "B.Paste")
			(net "GND")
		)
	)
	(footprint ""
		(layer "B.Cu")
		(at 328.92365 -34.139886 180)
		(property "Reference" "C35"
			(at 0 0 0)
			(layer "B.SilkS")
			(hide yes)
			(effects
				(font
					(size 1.27 1.27)
				)
				(justify mirror)
			)
		)
		(property "Value" ""
			(at 0 0 0)
			(layer "B.Fab")
			(effects
				(font
					(size 1.27 1.27)
				)
				(justify mirror)
			)
		)
		(duplicate_pad_numbers_are_jumpers no)
		(fp_line
			(start 0.7874 0.4064)
			(end 0.7874 -0.4064)
			(stroke
				(width 0.1524)
				(type default)
			)
			(layer "B.SilkS")
		)
		(fp_line
			(start 0.7874 -0.4064)
			(end -0.7874 -0.4064)
			(stroke
				(width 0.1524)
				(type default)
			)
			(layer "B.SilkS")
		)
		(fp_line
			(start -0.7874 0.4064)
			(end 0.7874 0.4064)
			(stroke
				(width 0.1524)
				(type default)
			)
			(layer "B.SilkS")
		)
		(fp_line
			(start -0.7874 -0.4064)
			(end -0.7874 0.4064)
			(stroke
				(width 0.1524)
				(type default)
			)
			(layer "B.SilkS")
		)
		(fp_line
			(start 0.67945 0.3048)
			(end 0.67945 -0.305054)
			(stroke
				(width 0.1)
				(type default)
			)
			(layer "B.Fab")
		)
		(fp_line
			(start 0.67945 -0.305054)
			(end 0.12065 -0.305054)
			(stroke
				(width 0.1)
				(type default)
			)
			(layer "B.Fab")
		)
		(fp_line
			(start 0.12065 0.3048)
			(end 0.67945 0.3048)
			(stroke
				(width 0.1)
				(type default)
			)
			(layer "B.Fab")
		)
		(fp_line
			(start 0.12065 0.2794)
			(end 0.12065 0.3048)
			(stroke
				(width 0.1)
				(type default)
			)
			(layer "B.Fab")
		)
		(fp_line
			(start 0.12065 -0.2794)
			(end -0.12065 -0.2794)
			(stroke
				(width 0.1)
				(type default)
			)
			(layer "B.Fab")
		)
		(fp_line
			(start 0.12065 -0.305054)
			(end 0.12065 -0.2794)
			(stroke
				(width 0.1)
				(type default)
			)
			(layer "B.Fab")
		)
		(fp_line
			(start -0.120396 0.3048)
			(end -0.120396 0.2794)
			(stroke
				(width 0.1)
				(type default)
			)
			(layer "B.Fab")
		)
		(fp_line
			(start -0.120396 0.2794)
			(end 0.12065 0.2794)
			(stroke
				(width 0.1)
				(type default)
			)
			(layer "B.Fab")
		)
		(fp_line
			(start -0.12065 -0.2794)
			(end -0.12065 -0.3048)
			(stroke
				(width 0.1)
				(type default)
			)
			(layer "B.Fab")
		)
		(fp_line
			(start -0.12065 -0.3048)
			(end -0.67945 -0.3048)
			(stroke
				(width 0.1)
				(type default)
			)
			(layer "B.Fab")
		)
		(fp_line
			(start -0.67945 0.3048)
			(end -0.120396 0.3048)
			(stroke
				(width 0.1)
				(type default)
			)
			(layer "B.Fab")
		)
		(fp_line
			(start -0.67945 -0.3048)
			(end -0.67945 0.3048)
			(stroke
				(width 0.1)
				(type default)
			)
			(layer "B.Fab")
		)
		(pad "1" smd circle
			(at 0.40005 0)
			(size 0 0)
			(layers "B.Cu" "B.Mask" "B.Paste")
			(net "P12V_E1S_0_ISENSE_MAM")
		)
		(pad "2" smd circle
			(at -0.40005 0)
			(size 0 0)
			(layers "B.Cu" "B.Mask" "B.Paste")
			(net "GND")
		)
	)
	(footprint ""
		(layer "B.Cu")
		(at 371.900958 -271.853152 90)
		(property "Reference" "C2249"
			(at 0 0 90)
			(layer "B.SilkS")
			(hide yes)
			(effects
				(font
					(size 1.27 1.27)
				)
				(justify mirror)
			)
		)
		(property "Value" ""
			(at 0 0 90)
			(layer "B.Fab")
			(effects
				(font
					(size 1.27 1.27)
				)
				(justify mirror)
			)
		)
		(duplicate_pad_numbers_are_jumpers no)
		(fp_line
			(start 0.7874 -0.4064)
			(end -0.7874 -0.4064)
			(stroke
				(width 0.1524)
				(type default)
			)
			(layer "B.SilkS")
		)
		(fp_line
			(start -0.7874 -0.4064)
			(end -0.7874 0.4064)
			(stroke
				(width 0.1524)
				(type default)
			)
			(layer "B.SilkS")
		)
		(fp_line
			(start 0.7874 0.4064)
			(end 0.7874 -0.4064)
			(stroke
				(width 0.1524)
				(type default)
			)
			(layer "B.SilkS")
		)
		(fp_line
			(start -0.7874 0.4064)
			(end 0.7874 0.4064)
			(stroke
				(width 0.1524)
				(type default)
			)
			(layer "B.SilkS")
		)
		(fp_line
			(start 0.67945 -0.305054)
			(end 0.12065 -0.305054)
			(stroke
				(width 0.1)
				(type default)
			)
			(layer "B.Fab")
		)
		(fp_line
			(start 0.12065 -0.305054)
			(end 0.12065 -0.2794)
			(stroke
				(width 0.1)
				(type default)
			)
			(layer "B.Fab")
		)
		(fp_line
			(start -0.12065 -0.3048)
			(end -0.67945 -0.3048)
			(stroke
				(width 0.1)
				(type default)
			)
			(layer "B.Fab")
		)
		(fp_line
			(start -0.67945 -0.3048)
			(end -0.67945 0.3048)
			(stroke
				(width 0.1)
				(type default)
			)
			(layer "B.Fab")
		)
		(fp_line
			(start 0.12065 -0.2794)
			(end -0.12065 -0.2794)
			(stroke
				(width 0.1)
				(type default)
			)
			(layer "B.Fab")
		)
		(fp_line
			(start -0.12065 -0.2794)
			(end -0.12065 -0.3048)
			(stroke
				(width 0.1)
				(type default)
			)
			(layer "B.Fab")
		)
		(fp_line
			(start 0.12065 0.2794)
			(end 0.12065 0.3048)
			(stroke
				(width 0.1)
				(type default)
			)
			(layer "B.Fab")
		)
		(fp_line
			(start -0.120396 0.2794)
			(end 0.12065 0.2794)
			(stroke
				(width 0.1)
				(type default)
			)
			(layer "B.Fab")
		)
		(fp_line
			(start 0.67945 0.3048)
			(end 0.67945 -0.305054)
			(stroke
				(width 0.1)
				(type default)
			)
			(layer "B.Fab")
		)
		(fp_line
			(start 0.12065 0.3048)
			(end 0.67945 0.3048)
			(stroke
				(width 0.1)
				(type default)
			)
			(layer "B.Fab")
		)
		(fp_line
			(start -0.120396 0.3048)
			(end -0.120396 0.2794)
			(stroke
				(width 0.1)
				(type default)
			)
			(layer "B.Fab")
		)
		(fp_line
			(start -0.67945 0.3048)
			(end -0.120396 0.3048)
			(stroke
				(width 0.1)
				(type default)
			)
			(layer "B.Fab")
		)
		(pad "1" smd circle
			(at 0.40005 0 270)
			(size 0 0)
			(layers "B.Cu" "B.Mask" "B.Paste")
			(net "PVDDCR_CPU1_P0")
		)
		(pad "2" smd circle
			(at -0.40005 0 270)
			(size 0 0)
			(layers "B.Cu" "B.Mask" "B.Paste")
			(net "GND")
		)
	)
	(footprint ""
		(layer "B.Cu")
		(at 88.306402 -386.766562 90)
		(property "Reference" "C288"
			(at 0 0 90)
			(layer "B.SilkS")
			(hide yes)
			(effects
				(font
					(size 1.27 1.27)
				)
				(justify mirror)
			)
		)
		(property "Value" ""
			(at 0 0 90)
			(layer "B.Fab")
			(effects
				(font
					(size 1.27 1.27)
				)
				(justify mirror)
			)
		)
		(duplicate_pad_numbers_are_jumpers no)
		(fp_line
			(start 0.299974 -0.150114)
			(end -0.299974 -0.150114)
			(stroke
				(width 0.1)
				(type default)
			)
			(layer "B.Fab")
		)
		(fp_line
			(start -0.299974 -0.150114)
			(end -0.299974 0.150114)
			(stroke
				(width 0.1)
				(type default)
			)
			(layer "B.Fab")
		)
		(fp_line
			(start 0.299974 0.150114)
			(end 0.299974 -0.150114)
			(stroke
				(width 0.1)
				(type default)
			)
			(layer "B.Fab")
		)
		(fp_line
			(start -0.299974 0.150114)
			(end 0.299974 0.150114)
			(stroke
				(width 0.1)
				(type default)
			)
			(layer "B.Fab")
		)
		(pad "1" smd rect
			(at 0.2667 0 270)
			(size 0.3048 0.381)
			(layers "B.Cu" "B.Mask" "B.Paste")
			(net "P1V8_CPU1_RT1_1A")
		)
		(pad "2" smd rect
			(at -0.2667 0 270)
			(size 0.3048 0.381)
			(layers "B.Cu" "B.Mask" "B.Paste")
			(net "GND")
		)
	)
	(footprint ""
		(layer "B.Cu")
		(at 402.539962 -314.925964 180)
		(property "Reference" "C216"
			(at 0 0 0)
			(layer "B.SilkS")
			(hide yes)
			(effects
				(font
					(size 1.27 1.27)
				)
				(justify mirror)
			)
		)
		(property "Value" ""
			(at 0 0 0)
			(layer "B.Fab")
			(effects
				(font
					(size 1.27 1.27)
				)
				(justify mirror)
			)
		)
		(duplicate_pad_numbers_are_jumpers no)
		(fp_line
			(start 0.7874 0.4064)
			(end 0.7874 -0.4064)
			(stroke
				(width 0.1524)
				(type default)
			)
			(layer "B.SilkS")
		)
		(fp_line
			(start 0.7874 -0.4064)
			(end -0.7874 -0.4064)
			(stroke
				(width 0.1524)
				(type default)
			)
			(layer "B.SilkS")
		)
		(fp_line
			(start -0.7874 0.4064)
			(end 0.7874 0.4064)
			(stroke
				(width 0.1524)
				(type default)
			)
			(layer "B.SilkS")
		)
		(fp_line
			(start -0.7874 -0.4064)
			(end -0.7874 0.4064)
			(stroke
				(width 0.1524)
				(type default)
			)
			(layer "B.SilkS")
		)
		(fp_line
			(start 0.67945 0.3048)
			(end 0.67945 -0.305054)
			(stroke
				(width 0.1)
				(type default)
			)
			(layer "B.Fab")
		)
		(fp_line
			(start 0.67945 -0.305054)
			(end 0.12065 -0.305054)
			(stroke
				(width 0.1)
				(type default)
			)
			(layer "B.Fab")
		)
		(fp_line
			(start 0.12065 0.3048)
			(end 0.67945 0.3048)
			(stroke
				(width 0.1)
				(type default)
			)
			(layer "B.Fab")
		)
		(fp_line
			(start 0.12065 0.2794)
			(end 0.12065 0.3048)
			(stroke
				(width 0.1)
				(type default)
			)
			(layer "B.Fab")
		)
		(fp_line
			(start 0.12065 -0.2794)
			(end -0.12065 -0.2794)
			(stroke
				(width 0.1)
				(type default)
			)
			(layer "B.Fab")
		)
		(fp_line
			(start 0.12065 -0.305054)
			(end 0.12065 -0.2794)
			(stroke
				(width 0.1)
				(type default)
			)
			(layer "B.Fab")
		)
		(fp_line
			(start -0.120396 0.3048)
			(end -0.120396 0.2794)
			(stroke
				(width 0.1)
				(type default)
			)
			(layer "B.Fab")
		)
		(fp_line
			(start -0.120396 0.2794)
			(end 0.12065 0.2794)
			(stroke
				(width 0.1)
				(type default)
			)
			(layer "B.Fab")
		)
		(fp_line
			(start -0.12065 -0.2794)
			(end -0.12065 -0.3048)
			(stroke
				(width 0.1)
				(type default)
			)
			(layer "B.Fab")
		)
		(fp_line
			(start -0.12065 -0.3048)
			(end -0.67945 -0.3048)
			(stroke
				(width 0.1)
				(type default)
			)
			(layer "B.Fab")
		)
		(fp_line
			(start -0.67945 0.3048)
			(end -0.120396 0.3048)
			(stroke
				(width 0.1)
				(type default)
			)
			(layer "B.Fab")
		)
		(fp_line
			(start -0.67945 -0.3048)
			(end -0.67945 0.3048)
			(stroke
				(width 0.1)
				(type default)
			)
			(layer "B.Fab")
		)
		(pad "1" smd circle
			(at 0.40005 0)
			(size 0 0)
			(layers "B.Cu" "B.Mask" "B.Paste")
			(net "XTAL_CPU0_X32K_X2")
		)
		(pad "2" smd circle
			(at -0.40005 0)
			(size 0 0)
			(layers "B.Cu" "B.Mask" "B.Paste")
			(net "GND")
		)
	)
	(footprint ""
		(layer "B.Cu")
		(at 239.980978 -315.95568 -90)
		(property "Reference" "PC6510"
			(at 0 0 90)
			(layer "B.SilkS")
			(hide yes)
			(effects
				(font
					(size 1.27 1.27)
				)
				(justify mirror)
			)
		)
		(property "Value" ""
			(at 0 0 90)
			(layer "B.Fab")
			(effects
				(font
					(size 1.27 1.27)
				)
				(justify mirror)
			)
		)
		(duplicate_pad_numbers_are_jumpers no)
		(fp_line
			(start -1.524 0.762)
			(end 1.524 0.762)
			(stroke
				(width 0.1524)
				(type default)
			)
			(layer "B.SilkS")
		)
		(fp_line
			(start 1.524 0.762)
			(end 1.524 -0.762)
			(stroke
				(width 0.1524)
				(type default)
			)
			(layer "B.SilkS")
		)
		(fp_line
			(start -1.524 -0.762)
			(end -1.524 0.762)
			(stroke
				(width 0.1524)
				(type default)
			)
			(layer "B.SilkS")
		)
		(fp_line
			(start 1.524 -0.762)
			(end -1.524 -0.762)
			(stroke
				(width 0.1524)
				(type default)
			)
			(layer "B.SilkS")
		)
		(fp_line
			(start -1.1049 0.724916)
			(end -1.1049 -0.724916)
			(stroke
				(width 0.1)
				(type default)
			)
			(layer "B.Fab")
		)
		(fp_line
			(start 1.1049 0.724916)
			(end -1.1049 0.724916)
			(stroke
				(width 0.1)
				(type default)
			)
			(layer "B.Fab")
		)
		(fp_line
			(start -1.1049 -0.724916)
			(end 1.1049 -0.724916)
			(stroke
				(width 0.1)
				(type default)
			)
			(layer "B.Fab")
		)
		(fp_line
			(start 1.1049 -0.724916)
			(end 1.1049 0.724916)
			(stroke
				(width 0.1)
				(type default)
			)
			(layer "B.Fab")
		)
		(pad "1" smd rect
			(at 0.889 0 270)
			(size 1.016 1.27)
			(layers "B.Cu" "B.Mask" "B.Paste")
			(net "P1V8_CPU0_RT_1D")
		)
		(pad "2" smd rect
			(at -0.889 0 270)
			(size 1.016 1.27)
			(layers "B.Cu" "B.Mask" "B.Paste")
			(net "GND")
		)
	)
	(footprint ""
		(layer "B.Cu")
		(at 105.960164 -260.305296 180)
		(property "Reference" "C2265"
			(at 0 0 0)
			(layer "B.SilkS")
			(hide yes)
			(effects
				(font
					(size 1.27 1.27)
				)
				(justify mirror)
			)
		)
		(property "Value" ""
			(at 0 0 0)
			(layer "B.Fab")
			(effects
				(font
					(size 1.27 1.27)
				)
				(justify mirror)
			)
		)
		(duplicate_pad_numbers_are_jumpers no)
		(fp_line
			(start 0.7874 0.4064)
			(end 0.7874 -0.4064)
			(stroke
				(width 0.1524)
				(type default)
			)
			(layer "B.SilkS")
		)
		(fp_line
			(start 0.7874 -0.4064)
			(end -0.7874 -0.4064)
			(stroke
				(width 0.1524)
				(type default)
			)
			(layer "B.SilkS")
		)
		(fp_line
			(start -0.7874 0.4064)
			(end 0.7874 0.4064)
			(stroke
				(width 0.1524)
				(type default)
			)
			(layer "B.SilkS")
		)
		(fp_line
			(start -0.7874 -0.4064)
			(end -0.7874 0.4064)
			(stroke
				(width 0.1524)
				(type default)
			)
			(layer "B.SilkS")
		)
		(fp_line
			(start 0.67945 0.3048)
			(end 0.67945 -0.305054)
			(stroke
				(width 0.1)
				(type default)
			)
			(layer "B.Fab")
		)
		(fp_line
			(start 0.67945 -0.305054)
			(end 0.12065 -0.305054)
			(stroke
				(width 0.1)
				(type default)
			)
			(layer "B.Fab")
		)
		(fp_line
			(start 0.12065 0.3048)
			(end 0.67945 0.3048)
			(stroke
				(width 0.1)
				(type default)
			)
			(layer "B.Fab")
		)
		(fp_line
			(start 0.12065 0.2794)
			(end 0.12065 0.3048)
			(stroke
				(width 0.1)
				(type default)
			)
			(layer "B.Fab")
		)
		(fp_line
			(start 0.12065 -0.2794)
			(end -0.12065 -0.2794)
			(stroke
				(width 0.1)
				(type default)
			)
			(layer "B.Fab")
		)
		(fp_line
			(start 0.12065 -0.305054)
			(end 0.12065 -0.2794)
			(stroke
				(width 0.1)
				(type default)
			)
			(layer "B.Fab")
		)
		(fp_line
			(start -0.120396 0.3048)
			(end -0.120396 0.2794)
			(stroke
				(width 0.1)
				(type default)
			)
			(layer "B.Fab")
		)
		(fp_line
			(start -0.120396 0.2794)
			(end 0.12065 0.2794)
			(stroke
				(width 0.1)
				(type default)
			)
			(layer "B.Fab")
		)
		(fp_line
			(start -0.12065 -0.2794)
			(end -0.12065 -0.3048)
			(stroke
				(width 0.1)
				(type default)
			)
			(layer "B.Fab")
		)
		(fp_line
			(start -0.12065 -0.3048)
			(end -0.67945 -0.3048)
			(stroke
				(width 0.1)
				(type default)
			)
			(layer "B.Fab")
		)
		(fp_line
			(start -0.67945 0.3048)
			(end -0.120396 0.3048)
			(stroke
				(width 0.1)
				(type default)
			)
			(layer "B.Fab")
		)
		(fp_line
			(start -0.67945 -0.3048)
			(end -0.67945 0.3048)
			(stroke
				(width 0.1)
				(type default)
			)
			(layer "B.Fab")
		)
		(pad "1" smd circle
			(at 0.40005 0)
			(size 0 0)
			(layers "B.Cu" "B.Mask" "B.Paste")
			(net "PVDDIO_P1")
		)
		(pad "2" smd circle
			(at -0.40005 0)
			(size 0 0)
			(layers "B.Cu" "B.Mask" "B.Paste")
			(net "GND")
		)
	)
	(footprint ""
		(layer "B.Cu")
		(at 398.502124 -344.850212 -90)
		(property "Reference" "R6100"
			(at 0 0 90)
			(layer "B.SilkS")
			(hide yes)
			(effects
				(font
					(size 1.27 1.27)
				)
				(justify mirror)
			)
		)
		(property "Value" ""
			(at 0 0 90)
			(layer "B.Fab")
			(effects
				(font
					(size 1.27 1.27)
				)
				(justify mirror)
			)
		)
		(duplicate_pad_numbers_are_jumpers no)
		(fp_line
			(start -0.7874 0.4064)
			(end 0.7874 0.4064)
			(stroke
				(width 0.1524)
				(type default)
			)
			(layer "B.SilkS")
		)
		(fp_line
			(start 0.7874 0.4064)
			(end 0.7874 -0.4064)
			(stroke
				(width 0.1524)
				(type default)
			)
			(layer "B.SilkS")
		)
		(fp_line
			(start -0.7874 -0.4064)
			(end -0.7874 0.4064)
			(stroke
				(width 0.1524)
				(type default)
			)
			(layer "B.SilkS")
		)
		(fp_line
			(start 0.7874 -0.4064)
			(end -0.7874 -0.4064)
			(stroke
				(width 0.1524)
				(type default)
			)
			(layer "B.SilkS")
		)
		(fp_line
			(start -0.67945 0.3048)
			(end -0.120396 0.3048)
			(stroke
				(width 0.1)
				(type default)
			)
			(layer "B.Fab")
		)
		(fp_line
			(start -0.120396 0.3048)
			(end -0.120396 0.2794)
			(stroke
				(width 0.1)
				(type default)
			)
			(layer "B.Fab")
		)
		(fp_line
			(start 0.12065 0.3048)
			(end 0.67945 0.3048)
			(stroke
				(width 0.1)
				(type default)
			)
			(layer "B.Fab")
		)
		(fp_line
			(start 0.67945 0.3048)
			(end 0.67945 -0.305054)
			(stroke
				(width 0.1)
				(type default)
			)
			(layer "B.Fab")
		)
		(fp_line
			(start -0.120396 0.2794)
			(end 0.12065 0.2794)
			(stroke
				(width 0.1)
				(type default)
			)
			(layer "B.Fab")
		)
		(fp_line
			(start 0.12065 0.2794)
			(end 0.12065 0.3048)
			(stroke
				(width 0.1)
				(type default)
			)
			(layer "B.Fab")
		)
		(fp_line
			(start -0.12065 -0.2794)
			(end -0.12065 -0.3048)
			(stroke
				(width 0.1)
				(type default)
			)
			(layer "B.Fab")
		)
		(fp_line
			(start 0.12065 -0.2794)
			(end -0.12065 -0.2794)
			(stroke
				(width 0.1)
				(type default)
			)
			(layer "B.Fab")
		)
		(fp_line
			(start -0.67945 -0.3048)
			(end -0.67945 0.3048)
			(stroke
				(width 0.1)
				(type default)
			)
			(layer "B.Fab")
		)
		(fp_line
			(start -0.12065 -0.3048)
			(end -0.67945 -0.3048)
			(stroke
				(width 0.1)
				(type default)
			)
			(layer "B.Fab")
		)
		(fp_line
			(start 0.12065 -0.305054)
			(end 0.12065 -0.2794)
			(stroke
				(width 0.1)
				(type default)
			)
			(layer "B.Fab")
		)
		(fp_line
			(start 0.67945 -0.305054)
			(end 0.12065 -0.305054)
			(stroke
				(width 0.1)
				(type default)
			)
			(layer "B.Fab")
		)
		(pad "1" smd circle
			(at 0.40005 0 90)
			(size 0 0)
			(layers "B.Cu" "B.Mask" "B.Paste")
			(net "FM_BIOS_POST_CMPLT_BUF_R1_N")
		)
		(pad "2" smd circle
			(at -0.40005 0 90)
			(size 0 0)
			(layers "B.Cu" "B.Mask" "B.Paste")
			(net "FM_BIOS_POST_CMPLT_BUF_N")
		)
	)
	(footprint ""
		(layer "B.Cu")
		(at 397.876014 -183.888888 90)
		(property "Reference" "PC601"
			(at 6.967728 0.110998 270)
			(unlocked yes)
			(layer "B.SilkS")
			(effects
				(font
					(size 0.7874 0.5842)
					(thickness 0.1524)
				)
				(justify left mirror)
			)
		)
		(property "Value" ""
			(at 0 0 90)
			(layer "B.Fab")
			(effects
				(font
					(size 1.27 1.27)
				)
				(justify mirror)
			)
		)
		(duplicate_pad_numbers_are_jumpers no)
		(fp_line
			(start 4.533392 -2.249932)
			(end -4.533392 -2.249932)
			(stroke
				(width 0.1524)
				(type default)
			)
			(layer "B.SilkS")
		)
		(fp_line
			(start -4.533392 -2.249932)
			(end -4.533392 2.249932)
			(stroke
				(width 0.1524)
				(type default)
			)
			(layer "B.SilkS")
		)
		(fp_line
			(start 4.533392 2.249932)
			(end 4.533392 -2.249932)
			(stroke
				(width 0.1524)
				(type default)
			)
			(layer "B.SilkS")
		)
		(fp_line
			(start -4.533392 2.249932)
			(end 4.533392 2.249932)
			(stroke
				(width 0.1524)
				(type default)
			)
			(layer "B.SilkS")
		)
		(fp_rect
			(start 4.533392 -2.326132)
			(end 5.39242 2.326132)
			(stroke
				(width 0)
				(type default)
			)
			(fill yes)
			(layer "B.SilkS")
		)
		(fp_line
			(start 3.750056 -2.249932)
			(end -3.750056 -2.249932)
			(stroke
				(width 0.1)
				(type default)
			)
			(layer "B.Fab")
		)
		(fp_line
			(start -3.750056 -2.249932)
			(end -3.750056 2.249932)
			(stroke
				(width 0.1)
				(type default)
			)
			(layer "B.Fab")
		)
		(fp_line
			(start 3.750056 2.249932)
			(end 3.750056 -2.249932)
			(stroke
				(width 0.1)
				(type default)
			)
			(layer "B.Fab")
		)
		(fp_line
			(start -3.750056 2.249932)
			(end 3.750056 2.249932)
			(stroke
				(width 0.1)
				(type default)
			)
			(layer "B.Fab")
		)
		(fp_text user "-"
			(at -4.8514 -0.14605 90)
			(unlocked yes)
			(layer "B.SilkS")
			(effects
				(font
					(size 1.905 1.4224)
					(thickness 0.1524)
				)
				(justify left mirror)
			)
		)
		(fp_text user "+"
			(at 6.322314 0.786384 0)
			(unlocked yes)
			(layer "B.SilkS")
			(effects
				(font
					(size 1.905 1.4224)
					(thickness 0.1524)
				)
				(justify left mirror)
			)
		)
		(fp_text user "-"
			(at -4.8514 -0.14605 90)
			(unlocked yes)
			(layer "B.Fab")
			(effects
				(font
					(size 1.905 1.4224)
					(thickness 0.1524)
				)
				(justify left mirror)
			)
		)
		(fp_text user "+"
			(at 6.322314 0.786384 0)
			(unlocked yes)
			(layer "B.Fab")
			(effects
				(font
					(size 1.905 1.4224)
					(thickness 0.1524)
				)
				(justify left mirror)
			)
		)
		(pad "1" smd rect
			(at 3.199892 0 270)
			(size 2.413 2.8194)
			(layers "B.Cu" "B.Mask" "B.Paste")
			(net "PVDDCR_SOC_P0")
		)
		(pad "2" smd rect
			(at -3.199892 0 270)
			(size 2.413 2.8194)
			(layers "B.Cu" "B.Mask" "B.Paste")
			(net "GND")
		)
	)
	(footprint ""
		(layer "B.Cu")
		(at 370.272818 -393.88288 -90)
		(property "Reference" "C1006"
			(at 0 0 90)
			(layer "B.SilkS")
			(hide yes)
			(effects
				(font
					(size 1.27 1.27)
				)
				(justify mirror)
			)
		)
		(property "Value" ""
			(at 0 0 90)
			(layer "B.Fab")
			(effects
				(font
					(size 1.27 1.27)
				)
				(justify mirror)
			)
		)
		(duplicate_pad_numbers_are_jumpers no)
		(fp_line
			(start -0.299974 0.150114)
			(end 0.299974 0.150114)
			(stroke
				(width 0.1)
				(type default)
			)
			(layer "B.Fab")
		)
		(fp_line
			(start 0.299974 0.150114)
			(end 0.299974 -0.150114)
			(stroke
				(width 0.1)
				(type default)
			)
			(layer "B.Fab")
		)
		(fp_line
			(start -0.299974 -0.150114)
			(end -0.299974 0.150114)
			(stroke
				(width 0.1)
				(type default)
			)
			(layer "B.Fab")
		)
		(fp_line
			(start 0.299974 -0.150114)
			(end -0.299974 -0.150114)
			(stroke
				(width 0.1)
				(type default)
			)
			(layer "B.Fab")
		)
		(pad "1" smd rect
			(at 0.2667 0 90)
			(size 0.3048 0.381)
			(layers "B.Cu" "B.Mask" "B.Paste")
			(net "P0V9_CPU0_RT3_2A")
		)
		(pad "2" smd rect
			(at -0.2667 0 90)
			(size 0.3048 0.381)
			(layers "B.Cu" "B.Mask" "B.Paste")
			(net "GND")
		)
	)
	(footprint ""
		(layer "B.Cu")
		(at 190.404496 -194.8942 180)
		(property "Reference" "R1589"
			(at 0 0 0)
			(layer "B.SilkS")
			(hide yes)
			(effects
				(font
					(size 1.27 1.27)
				)
				(justify mirror)
			)
		)
		(property "Value" ""
			(at 0 0 0)
			(layer "B.Fab")
			(effects
				(font
					(size 1.27 1.27)
				)
				(justify mirror)
			)
		)
		(duplicate_pad_numbers_are_jumpers no)
		(fp_line
			(start 0.7874 0.4064)
			(end 0.7874 -0.4064)
			(stroke
				(width 0.1524)
				(type default)
			)
			(layer "B.SilkS")
		)
		(fp_line
			(start 0.7874 -0.4064)
			(end -0.7874 -0.4064)
			(stroke
				(width 0.1524)
				(type default)
			)
			(layer "B.SilkS")
		)
		(fp_line
			(start -0.7874 0.4064)
			(end 0.7874 0.4064)
			(stroke
				(width 0.1524)
				(type default)
			)
			(layer "B.SilkS")
		)
		(fp_line
			(start -0.7874 -0.4064)
			(end -0.7874 0.4064)
			(stroke
				(width 0.1524)
				(type default)
			)
			(layer "B.SilkS")
		)
		(fp_line
			(start 0.67945 0.3048)
			(end 0.67945 -0.305054)
			(stroke
				(width 0.1)
				(type default)
			)
			(layer "B.Fab")
		)
		(fp_line
			(start 0.67945 -0.305054)
			(end 0.12065 -0.305054)
			(stroke
				(width 0.1)
				(type default)
			)
			(layer "B.Fab")
		)
		(fp_line
			(start 0.12065 0.3048)
			(end 0.67945 0.3048)
			(stroke
				(width 0.1)
				(type default)
			)
			(layer "B.Fab")
		)
		(fp_line
			(start 0.12065 0.2794)
			(end 0.12065 0.3048)
			(stroke
				(width 0.1)
				(type default)
			)
			(layer "B.Fab")
		)
		(fp_line
			(start 0.12065 -0.2794)
			(end -0.12065 -0.2794)
			(stroke
				(width 0.1)
				(type default)
			)
			(layer "B.Fab")
		)
		(fp_line
			(start 0.12065 -0.305054)
			(end 0.12065 -0.2794)
			(stroke
				(width 0.1)
				(type default)
			)
			(layer "B.Fab")
		)
		(fp_line
			(start -0.120396 0.3048)
			(end -0.120396 0.2794)
			(stroke
				(width 0.1)
				(type default)
			)
			(layer "B.Fab")
		)
		(fp_line
			(start -0.120396 0.2794)
			(end 0.12065 0.2794)
			(stroke
				(width 0.1)
				(type default)
			)
			(layer "B.Fab")
		)
		(fp_line
			(start -0.12065 -0.2794)
			(end -0.12065 -0.3048)
			(stroke
				(width 0.1)
				(type default)
			)
			(layer "B.Fab")
		)
		(fp_line
			(start -0.12065 -0.3048)
			(end -0.67945 -0.3048)
			(stroke
				(width 0.1)
				(type default)
			)
			(layer "B.Fab")
		)
		(fp_line
			(start -0.67945 0.3048)
			(end -0.120396 0.3048)
			(stroke
				(width 0.1)
				(type default)
			)
			(layer "B.Fab")
		)
		(fp_line
			(start -0.67945 -0.3048)
			(end -0.67945 0.3048)
			(stroke
				(width 0.1)
				(type default)
			)
			(layer "B.Fab")
		)
		(pad "1" smd circle
			(at 0.40005 0)
			(size 0 0)
			(layers "B.Cu" "B.Mask" "B.Paste")
			(net "I3C_SPD_DDRGL_CPU1_SCL")
		)
		(pad "2" smd circle
			(at -0.40005 0)
			(size 0 0)
			(layers "B.Cu" "B.Mask" "B.Paste")
			(net "I3C_SPD_DDRJ_CPU1_SCL")
		)
	)
	(footprint ""
		(layer "B.Cu")
		(at 173.583092 -418.7571 -90)
		(property "Reference" "R2801"
			(at 0 0 90)
			(layer "B.SilkS")
			(hide yes)
			(effects
				(font
					(size 1.27 1.27)
				)
				(justify mirror)
			)
		)
		(property "Value" ""
			(at 0 0 90)
			(layer "B.Fab")
			(effects
				(font
					(size 1.27 1.27)
				)
				(justify mirror)
			)
		)
		(duplicate_pad_numbers_are_jumpers no)
		(fp_line
			(start -0.7874 0.4064)
			(end 0.7874 0.4064)
			(stroke
				(width 0.1524)
				(type default)
			)
			(layer "B.SilkS")
		)
		(fp_line
			(start 0.7874 0.4064)
			(end 0.7874 -0.4064)
			(stroke
				(width 0.1524)
				(type default)
			)
			(layer "B.SilkS")
		)
		(fp_line
			(start -0.7874 -0.4064)
			(end -0.7874 0.4064)
			(stroke
				(width 0.1524)
				(type default)
			)
			(layer "B.SilkS")
		)
		(fp_line
			(start 0.7874 -0.4064)
			(end -0.7874 -0.4064)
			(stroke
				(width 0.1524)
				(type default)
			)
			(layer "B.SilkS")
		)
		(fp_line
			(start -0.67945 0.3048)
			(end -0.120396 0.3048)
			(stroke
				(width 0.1)
				(type default)
			)
			(layer "B.Fab")
		)
		(fp_line
			(start -0.120396 0.3048)
			(end -0.120396 0.2794)
			(stroke
				(width 0.1)
				(type default)
			)
			(layer "B.Fab")
		)
		(fp_line
			(start 0.12065 0.3048)
			(end 0.67945 0.3048)
			(stroke
				(width 0.1)
				(type default)
			)
			(layer "B.Fab")
		)
		(fp_line
			(start 0.67945 0.3048)
			(end 0.67945 -0.305054)
			(stroke
				(width 0.1)
				(type default)
			)
			(layer "B.Fab")
		)
		(fp_line
			(start -0.120396 0.2794)
			(end 0.12065 0.2794)
			(stroke
				(width 0.1)
				(type default)
			)
			(layer "B.Fab")
		)
		(fp_line
			(start 0.12065 0.2794)
			(end 0.12065 0.3048)
			(stroke
				(width 0.1)
				(type default)
			)
			(layer "B.Fab")
		)
		(fp_line
			(start -0.12065 -0.2794)
			(end -0.12065 -0.3048)
			(stroke
				(width 0.1)
				(type default)
			)
			(layer "B.Fab")
		)
		(fp_line
			(start 0.12065 -0.2794)
			(end -0.12065 -0.2794)
			(stroke
				(width 0.1)
				(type default)
			)
			(layer "B.Fab")
		)
		(fp_line
			(start -0.67945 -0.3048)
			(end -0.67945 0.3048)
			(stroke
				(width 0.1)
				(type default)
			)
			(layer "B.Fab")
		)
		(fp_line
			(start -0.12065 -0.3048)
			(end -0.67945 -0.3048)
			(stroke
				(width 0.1)
				(type default)
			)
			(layer "B.Fab")
		)
		(fp_line
			(start 0.12065 -0.305054)
			(end 0.12065 -0.2794)
			(stroke
				(width 0.1)
				(type default)
			)
			(layer "B.Fab")
		)
		(fp_line
			(start 0.67945 -0.305054)
			(end 0.12065 -0.305054)
			(stroke
				(width 0.1)
				(type default)
			)
			(layer "B.Fab")
		)
		(pad "1" smd circle
			(at 0.40005 0 90)
			(size 0 0)
			(layers "B.Cu" "B.Mask" "B.Paste")
			(net "SMB_FAN_3V3AUX_R_SDA")
		)
		(pad "2" smd circle
			(at -0.40005 0 90)
			(size 0 0)
			(layers "B.Cu" "B.Mask" "B.Paste")
			(net "SMB_FAN_3V3AUX_BUF_SDA")
		)
	)
	(footprint ""
		(layer "B.Cu")
		(at 453.432418 -193.99631)
		(property "Reference" "C112"
			(at 0 0 0)
			(layer "B.SilkS")
			(hide yes)
			(effects
				(font
					(size 1.27 1.27)
				)
				(justify mirror)
			)
		)
		(property "Value" ""
			(at 0 0 0)
			(layer "B.Fab")
			(effects
				(font
					(size 1.27 1.27)
				)
				(justify mirror)
			)
		)
		(duplicate_pad_numbers_are_jumpers no)
		(fp_line
			(start -0.7874 -0.4064)
			(end -0.7874 0.4064)
			(stroke
				(width 0.1524)
				(type default)
			)
			(layer "B.SilkS")
		)
		(fp_line
			(start -0.7874 0.4064)
			(end 0.7874 0.4064)
			(stroke
				(width 0.1524)
				(type default)
			)
			(layer "B.SilkS")
		)
		(fp_line
			(start 0.7874 -0.4064)
			(end -0.7874 -0.4064)
			(stroke
				(width 0.1524)
				(type default)
			)
			(layer "B.SilkS")
		)
		(fp_line
			(start 0.7874 0.4064)
			(end 0.7874 -0.4064)
			(stroke
				(width 0.1524)
				(type default)
			)
			(layer "B.SilkS")
		)
		(fp_line
			(start -0.67945 -0.3048)
			(end -0.67945 0.3048)
			(stroke
				(width 0.1)
				(type default)
			)
			(layer "B.Fab")
		)
		(fp_line
			(start -0.67945 0.3048)
			(end -0.120396 0.3048)
			(stroke
				(width 0.1)
				(type default)
			)
			(layer "B.Fab")
		)
		(fp_line
			(start -0.12065 -0.3048)
			(end -0.67945 -0.3048)
			(stroke
				(width 0.1)
				(type default)
			)
			(layer "B.Fab")
		)
		(fp_line
			(start -0.12065 -0.2794)
			(end -0.12065 -0.3048)
			(stroke
				(width 0.1)
				(type default)
			)
			(layer "B.Fab")
		)
		(fp_line
			(start -0.120396 0.2794)
			(end 0.12065 0.2794)
			(stroke
				(width 0.1)
				(type default)
			)
			(layer "B.Fab")
		)
		(fp_line
			(start -0.120396 0.3048)
			(end -0.120396 0.2794)
			(stroke
				(width 0.1)
				(type default)
			)
			(layer "B.Fab")
		)
		(fp_line
			(start 0.12065 -0.305054)
			(end 0.12065 -0.2794)
			(stroke
				(width 0.1)
				(type default)
			)
			(layer "B.Fab")
		)
		(fp_line
			(start 0.12065 -0.2794)
			(end -0.12065 -0.2794)
			(stroke
				(width 0.1)
				(type default)
			)
			(layer "B.Fab")
		)
		(fp_line
			(start 0.12065 0.2794)
			(end 0.12065 0.3048)
			(stroke
				(width 0.1)
				(type default)
			)
			(layer "B.Fab")
		)
		(fp_line
			(start 0.12065 0.3048)
			(end 0.67945 0.3048)
			(stroke
				(width 0.1)
				(type default)
			)
			(layer "B.Fab")
		)
		(fp_line
			(start 0.67945 -0.305054)
			(end 0.12065 -0.305054)
			(stroke
				(width 0.1)
				(type default)
			)
			(layer "B.Fab")
		)
		(fp_line
			(start 0.67945 0.3048)
			(end 0.67945 -0.305054)
			(stroke
				(width 0.1)
				(type default)
			)
			(layer "B.Fab")
		)
		(pad "1" smd circle
			(at 0.40005 0 180)
			(size 0 0)
			(layers "B.Cu" "B.Mask" "B.Paste")
			(net "P3V3_AUX")
		)
		(pad "2" smd circle
			(at -0.40005 0 180)
			(size 0 0)
			(layers "B.Cu" "B.Mask" "B.Paste")
			(net "GND")
		)
	)
	(footprint ""
		(layer "B.Cu")
		(at 365.709454 -266.00531)
		(property "Reference" "C2640"
			(at 0 0 0)
			(layer "B.SilkS")
			(hide yes)
			(effects
				(font
					(size 1.27 1.27)
				)
				(justify mirror)
			)
		)
		(property "Value" ""
			(at 0 0 0)
			(layer "B.Fab")
			(effects
				(font
					(size 1.27 1.27)
				)
				(justify mirror)
			)
		)
		(duplicate_pad_numbers_are_jumpers no)
		(fp_line
			(start -0.7874 -0.4064)
			(end -0.7874 0.4064)
			(stroke
				(width 0.1524)
				(type default)
			)
			(layer "B.SilkS")
		)
		(fp_line
			(start -0.7874 0.4064)
			(end 0.7874 0.4064)
			(stroke
				(width 0.1524)
				(type default)
			)
			(layer "B.SilkS")
		)
		(fp_line
			(start 0.7874 -0.4064)
			(end -0.7874 -0.4064)
			(stroke
				(width 0.1524)
				(type default)
			)
			(layer "B.SilkS")
		)
		(fp_line
			(start 0.7874 0.4064)
			(end 0.7874 -0.4064)
			(stroke
				(width 0.1524)
				(type default)
			)
			(layer "B.SilkS")
		)
		(fp_line
			(start -0.67945 -0.3048)
			(end -0.67945 0.3048)
			(stroke
				(width 0.1)
				(type default)
			)
			(layer "B.Fab")
		)
		(fp_line
			(start -0.67945 0.3048)
			(end -0.120396 0.3048)
			(stroke
				(width 0.1)
				(type default)
			)
			(layer "B.Fab")
		)
		(fp_line
			(start -0.12065 -0.3048)
			(end -0.67945 -0.3048)
			(stroke
				(width 0.1)
				(type default)
			)
			(layer "B.Fab")
		)
		(fp_line
			(start -0.12065 -0.2794)
			(end -0.12065 -0.3048)
			(stroke
				(width 0.1)
				(type default)
			)
			(layer "B.Fab")
		)
		(fp_line
			(start -0.120396 0.2794)
			(end 0.12065 0.2794)
			(stroke
				(width 0.1)
				(type default)
			)
			(layer "B.Fab")
		)
		(fp_line
			(start -0.120396 0.3048)
			(end -0.120396 0.2794)
			(stroke
				(width 0.1)
				(type default)
			)
			(layer "B.Fab")
		)
		(fp_line
			(start 0.12065 -0.305054)
			(end 0.12065 -0.2794)
			(stroke
				(width 0.1)
				(type default)
			)
			(layer "B.Fab")
		)
		(fp_line
			(start 0.12065 -0.2794)
			(end -0.12065 -0.2794)
			(stroke
				(width 0.1)
				(type default)
			)
			(layer "B.Fab")
		)
		(fp_line
			(start 0.12065 0.2794)
			(end 0.12065 0.3048)
			(stroke
				(width 0.1)
				(type default)
			)
			(layer "B.Fab")
		)
		(fp_line
			(start 0.12065 0.3048)
			(end 0.67945 0.3048)
			(stroke
				(width 0.1)
				(type default)
			)
			(layer "B.Fab")
		)
		(fp_line
			(start 0.67945 -0.305054)
			(end 0.12065 -0.305054)
			(stroke
				(width 0.1)
				(type default)
			)
			(layer "B.Fab")
		)
		(fp_line
			(start 0.67945 0.3048)
			(end 0.67945 -0.305054)
			(stroke
				(width 0.1)
				(type default)
			)
			(layer "B.Fab")
		)
		(pad "1" smd circle
			(at 0.40005 0 180)
			(size 0 0)
			(layers "B.Cu" "B.Mask" "B.Paste")
			(net "PVDD11_S3_P0")
		)
		(pad "2" smd circle
			(at -0.40005 0 180)
			(size 0 0)
			(layers "B.Cu" "B.Mask" "B.Paste")
			(net "GND")
		)
	)
	(footprint ""
		(layer "B.Cu")
		(at 56.79313 -346.788994 90)
		(property "Reference" "PC444_1"
			(at 0 0 90)
			(layer "B.SilkS")
			(hide yes)
			(effects
				(font
					(size 1.27 1.27)
				)
				(justify mirror)
			)
		)
		(property "Value" ""
			(at 0 0 90)
			(layer "B.Fab")
			(effects
				(font
					(size 1.27 1.27)
				)
				(justify mirror)
			)
		)
		(duplicate_pad_numbers_are_jumpers no)
		(fp_line
			(start 1.524 -0.762)
			(end -1.524 -0.762)
			(stroke
				(width 0.1524)
				(type default)
			)
			(layer "B.SilkS")
		)
		(fp_line
			(start -1.524 -0.762)
			(end -1.524 0.762)
			(stroke
				(width 0.1524)
				(type default)
			)
			(layer "B.SilkS")
		)
		(fp_line
			(start 1.524 0.762)
			(end 1.524 -0.762)
			(stroke
				(width 0.1524)
				(type default)
			)
			(layer "B.SilkS")
		)
		(fp_line
			(start -1.524 0.762)
			(end 1.524 0.762)
			(stroke
				(width 0.1524)
				(type default)
			)
			(layer "B.SilkS")
		)
		(fp_line
			(start 1.1049 -0.724916)
			(end 1.1049 0.724916)
			(stroke
				(width 0.1)
				(type default)
			)
			(layer "B.Fab")
		)
		(fp_line
			(start -1.1049 -0.724916)
			(end 1.1049 -0.724916)
			(stroke
				(width 0.1)
				(type default)
			)
			(layer "B.Fab")
		)
		(fp_line
			(start 1.1049 0.724916)
			(end -1.1049 0.724916)
			(stroke
				(width 0.1)
				(type default)
			)
			(layer "B.Fab")
		)
		(fp_line
			(start -1.1049 0.724916)
			(end -1.1049 -0.724916)
			(stroke
				(width 0.1)
				(type default)
			)
			(layer "B.Fab")
		)
		(pad "1" smd rect
			(at 0.889 0 90)
			(size 1.016 1.27)
			(layers "B.Cu" "B.Mask" "B.Paste")
			(net "SW_P12V_AUX_PVDDIO_P1_FLT")
		)
		(pad "2" smd rect
			(at -0.889 0 90)
			(size 1.016 1.27)
			(layers "B.Cu" "B.Mask" "B.Paste")
			(net "GND")
		)
	)
	(footprint ""
		(layer "B.Cu")
		(at 168.783762 -383.304288 180)
		(property "Reference" "R6797"
			(at 0 0 0)
			(layer "B.SilkS")
			(hide yes)
			(effects
				(font
					(size 1.27 1.27)
				)
				(justify mirror)
			)
		)
		(property "Value" ""
			(at 0 0 0)
			(layer "B.Fab")
			(effects
				(font
					(size 1.27 1.27)
				)
				(justify mirror)
			)
		)
		(duplicate_pad_numbers_are_jumpers no)
		(fp_line
			(start 0.32512 0.175006)
			(end 0.32512 -0.175006)
			(stroke
				(width 0.1)
				(type default)
			)
			(layer "B.Fab")
		)
		(fp_line
			(start 0.32512 -0.175006)
			(end -0.32512 -0.175006)
			(stroke
				(width 0.1)
				(type default)
			)
			(layer "B.Fab")
		)
		(fp_line
			(start -0.32512 0.175006)
			(end 0.32512 0.175006)
			(stroke
				(width 0.1)
				(type default)
			)
			(layer "B.Fab")
		)
		(fp_line
			(start -0.32512 -0.175006)
			(end -0.32512 0.175006)
			(stroke
				(width 0.1)
				(type default)
			)
			(layer "B.Fab")
		)
		(pad "1" smd rect
			(at 0.2667 0)
			(size 0.3048 0.381)
			(layers "B.Cu" "B.Mask" "B.Paste")
			(net "NCF_CPU1_P2_GND")
		)
		(pad "2" smd rect
			(at -0.2667 0 180)
			(size 0.3048 0.381)
			(layers "B.Cu" "B.Mask" "B.Paste")
			(net "GND")
		)
	)
	(footprint ""
		(layer "B.Cu")
		(at 413.123634 -194.88531 180)
		(property "Reference" "R35"
			(at 0 0 0)
			(layer "B.SilkS")
			(hide yes)
			(effects
				(font
					(size 1.27 1.27)
				)
				(justify mirror)
			)
		)
		(property "Value" ""
			(at 0 0 0)
			(layer "B.Fab")
			(effects
				(font
					(size 1.27 1.27)
				)
				(justify mirror)
			)
		)
		(duplicate_pad_numbers_are_jumpers no)
		(fp_line
			(start 0.7874 0.4064)
			(end 0.7874 -0.4064)
			(stroke
				(width 0.1524)
				(type default)
			)
			(layer "B.SilkS")
		)
		(fp_line
			(start 0.7874 -0.4064)
			(end -0.7874 -0.4064)
			(stroke
				(width 0.1524)
				(type default)
			)
			(layer "B.SilkS")
		)
		(fp_line
			(start -0.7874 0.4064)
			(end 0.7874 0.4064)
			(stroke
				(width 0.1524)
				(type default)
			)
			(layer "B.SilkS")
		)
		(fp_line
			(start -0.7874 -0.4064)
			(end -0.7874 0.4064)
			(stroke
				(width 0.1524)
				(type default)
			)
			(layer "B.SilkS")
		)
		(fp_line
			(start 0.67945 0.3048)
			(end 0.67945 -0.305054)
			(stroke
				(width 0.1)
				(type default)
			)
			(layer "B.Fab")
		)
		(fp_line
			(start 0.67945 -0.305054)
			(end 0.12065 -0.305054)
			(stroke
				(width 0.1)
				(type default)
			)
			(layer "B.Fab")
		)
		(fp_line
			(start 0.12065 0.3048)
			(end 0.67945 0.3048)
			(stroke
				(width 0.1)
				(type default)
			)
			(layer "B.Fab")
		)
		(fp_line
			(start 0.12065 0.2794)
			(end 0.12065 0.3048)
			(stroke
				(width 0.1)
				(type default)
			)
			(layer "B.Fab")
		)
		(fp_line
			(start 0.12065 -0.2794)
			(end -0.12065 -0.2794)
			(stroke
				(width 0.1)
				(type default)
			)
			(layer "B.Fab")
		)
		(fp_line
			(start 0.12065 -0.305054)
			(end 0.12065 -0.2794)
			(stroke
				(width 0.1)
				(type default)
			)
			(layer "B.Fab")
		)
		(fp_line
			(start -0.120396 0.3048)
			(end -0.120396 0.2794)
			(stroke
				(width 0.1)
				(type default)
			)
			(layer "B.Fab")
		)
		(fp_line
			(start -0.120396 0.2794)
			(end 0.12065 0.2794)
			(stroke
				(width 0.1)
				(type default)
			)
			(layer "B.Fab")
		)
		(fp_line
			(start -0.12065 -0.2794)
			(end -0.12065 -0.3048)
			(stroke
				(width 0.1)
				(type default)
			)
			(layer "B.Fab")
		)
		(fp_line
			(start -0.12065 -0.3048)
			(end -0.67945 -0.3048)
			(stroke
				(width 0.1)
				(type default)
			)
			(layer "B.Fab")
		)
		(fp_line
			(start -0.67945 0.3048)
			(end -0.120396 0.3048)
			(stroke
				(width 0.1)
				(type default)
			)
			(layer "B.Fab")
		)
		(fp_line
			(start -0.67945 -0.3048)
			(end -0.67945 0.3048)
			(stroke
				(width 0.1)
				(type default)
			)
			(layer "B.Fab")
		)
		(pad "1" smd circle
			(at 0.40005 0)
			(size 0 0)
			(layers "B.Cu" "B.Mask" "B.Paste")
			(net "PD_CHG_CPU0_DIMM0_SAA")
		)
		(pad "2" smd circle
			(at -0.40005 0)
			(size 0 0)
			(layers "B.Cu" "B.Mask" "B.Paste")
			(net "GND")
		)
	)
	(footprint ""
		(layer "B.Cu")
		(at 312.144664 -73.534778)
		(property "Reference" "Q87"
			(at 1.157478 2.63525 0)
			(unlocked yes)
			(layer "B.SilkS")
			(effects
				(font
					(size 0.7874 0.5842)
					(thickness 0.1524)
				)
				(justify left mirror)
			)
		)
		(property "Value" ""
			(at 0 0 0)
			(layer "B.Fab")
			(effects
				(font
					(size 1.27 1.27)
				)
				(justify mirror)
			)
		)
		(duplicate_pad_numbers_are_jumpers no)
		(fp_line
			(start -1.332738 -1.100074)
			(end -1.332738 1.100074)
			(stroke
				(width 0.1524)
				(type default)
			)
			(layer "B.SilkS")
		)
		(fp_line
			(start -1.332738 1.100074)
			(end 1.332738 1.100074)
			(stroke
				(width 0.1524)
				(type default)
			)
			(layer "B.SilkS")
		)
		(fp_line
			(start -0.4826 -1.100074)
			(end -1.332738 -1.100074)
			(stroke
				(width 0.1524)
				(type default)
			)
			(layer "B.SilkS")
		)
		(fp_line
			(start 0 -0.541274)
			(end -0.4826 -1.100074)
			(stroke
				(width 0.1524)
				(type default)
			)
			(layer "B.SilkS")
		)
		(fp_line
			(start 0.4826 -1.100074)
			(end 0 -0.541274)
			(stroke
				(width 0.1524)
				(type default)
			)
			(layer "B.SilkS")
		)
		(fp_line
			(start 1.332738 -1.100074)
			(end 0.4826 -1.100074)
			(stroke
				(width 0.1524)
				(type default)
			)
			(layer "B.SilkS")
		)
		(fp_line
			(start 1.332738 1.100074)
			(end 1.332738 -1.100074)
			(stroke
				(width 0.1524)
				(type default)
			)
			(layer "B.SilkS")
		)
		(fp_poly
			(pts
				(xy 1.533144 -0.649986) (xy 2.2352 -1.001014) (xy 2.2352 -0.298958)
			)
			(stroke
				(width 0)
				(type default)
			)
			(fill yes)
			(layer "B.SilkS")
		)
		(fp_line
			(start -0.674878 -1.100074)
			(end -0.674878 1.100074)
			(stroke
				(width 0.1)
				(type default)
			)
			(layer "B.Fab")
		)
		(fp_line
			(start -0.674878 1.100074)
			(end 0.674878 1.100074)
			(stroke
				(width 0.1)
				(type default)
			)
			(layer "B.Fab")
		)
		(fp_line
			(start 0.674878 -1.100074)
			(end -0.674878 -1.100074)
			(stroke
				(width 0.1)
				(type default)
			)
			(layer "B.Fab")
		)
		(fp_line
			(start 0.674878 1.100074)
			(end 0.674878 -1.100074)
			(stroke
				(width 0.1)
				(type default)
			)
			(layer "B.Fab")
		)
		(fp_poly
			(pts
				(xy 2.2352 -0.298958) (xy 2.2352 -1.001014) (xy 1.533144 -0.649986)
			)
			(stroke
				(width 0)
				(type default)
			)
			(fill yes)
			(layer "B.Fab")
		)
		(pad "1" smd rect
			(at 0.94996 -0.649986 90)
			(size 0.4318 0.508)
			(layers "B.Cu" "B.Mask" "B.Paste")
			(net "GND")
		)
		(pad "2" smd rect
			(at 0.94996 0 90)
			(size 0.4318 0.508)
			(layers "B.Cu" "B.Mask" "B.Paste")
			(net "RST_CPU0_RSMRST_N")
		)
		(pad "3" smd rect
			(at 0.94996 0.649986 90)
			(size 0.4318 0.508)
			(layers "B.Cu" "B.Mask" "B.Paste")
			(net "LED_PWRGD_SYS_PWROK_R_D")
		)
		(pad "4" smd rect
			(at -0.94996 0.649986 90)
			(size 0.4318 0.508)
			(layers "B.Cu" "B.Mask" "B.Paste")
			(net "GND")
		)
		(pad "5" smd rect
			(at -0.94996 0 90)
			(size 0.4318 0.508)
			(layers "B.Cu" "B.Mask" "B.Paste")
			(net "SCM_SYS_PWROK_R2")
		)
		(pad "6" smd rect
			(at -0.94996 -0.649986 90)
			(size 0.4318 0.508)
			(layers "B.Cu" "B.Mask" "B.Paste")
			(net "LED_RST_RSMRST_PLD_R_N_D")
		)
	)
	(footprint ""
		(layer "B.Cu")
		(at 443.29985 -193.99631)
		(property "Reference" "R100"
			(at 0 0 0)
			(layer "B.SilkS")
			(hide yes)
			(effects
				(font
					(size 1.27 1.27)
				)
				(justify mirror)
			)
		)
		(property "Value" ""
			(at 0 0 0)
			(layer "B.Fab")
			(effects
				(font
					(size 1.27 1.27)
				)
				(justify mirror)
			)
		)
		(duplicate_pad_numbers_are_jumpers no)
		(fp_line
			(start -0.7874 -0.4064)
			(end -0.7874 0.4064)
			(stroke
				(width 0.1524)
				(type default)
			)
			(layer "B.SilkS")
		)
		(fp_line
			(start -0.7874 0.4064)
			(end 0.7874 0.4064)
			(stroke
				(width 0.1524)
				(type default)
			)
			(layer "B.SilkS")
		)
		(fp_line
			(start 0.7874 -0.4064)
			(end -0.7874 -0.4064)
			(stroke
				(width 0.1524)
				(type default)
			)
			(layer "B.SilkS")
		)
		(fp_line
			(start 0.7874 0.4064)
			(end 0.7874 -0.4064)
			(stroke
				(width 0.1524)
				(type default)
			)
			(layer "B.SilkS")
		)
		(fp_line
			(start -0.67945 -0.3048)
			(end -0.67945 0.3048)
			(stroke
				(width 0.1)
				(type default)
			)
			(layer "B.Fab")
		)
		(fp_line
			(start -0.67945 0.3048)
			(end -0.120396 0.3048)
			(stroke
				(width 0.1)
				(type default)
			)
			(layer "B.Fab")
		)
		(fp_line
			(start -0.12065 -0.3048)
			(end -0.67945 -0.3048)
			(stroke
				(width 0.1)
				(type default)
			)
			(layer "B.Fab")
		)
		(fp_line
			(start -0.12065 -0.2794)
			(end -0.12065 -0.3048)
			(stroke
				(width 0.1)
				(type default)
			)
			(layer "B.Fab")
		)
		(fp_line
			(start -0.120396 0.2794)
			(end 0.12065 0.2794)
			(stroke
				(width 0.1)
				(type default)
			)
			(layer "B.Fab")
		)
		(fp_line
			(start -0.120396 0.3048)
			(end -0.120396 0.2794)
			(stroke
				(width 0.1)
				(type default)
			)
			(layer "B.Fab")
		)
		(fp_line
			(start 0.12065 -0.305054)
			(end 0.12065 -0.2794)
			(stroke
				(width 0.1)
				(type default)
			)
			(layer "B.Fab")
		)
		(fp_line
			(start 0.12065 -0.2794)
			(end -0.12065 -0.2794)
			(stroke
				(width 0.1)
				(type default)
			)
			(layer "B.Fab")
		)
		(fp_line
			(start 0.12065 0.2794)
			(end 0.12065 0.3048)
			(stroke
				(width 0.1)
				(type default)
			)
			(layer "B.Fab")
		)
		(fp_line
			(start 0.12065 0.3048)
			(end 0.67945 0.3048)
			(stroke
				(width 0.1)
				(type default)
			)
			(layer "B.Fab")
		)
		(fp_line
			(start 0.67945 -0.305054)
			(end 0.12065 -0.305054)
			(stroke
				(width 0.1)
				(type default)
			)
			(layer "B.Fab")
		)
		(fp_line
			(start 0.67945 0.3048)
			(end 0.67945 -0.305054)
			(stroke
				(width 0.1)
				(type default)
			)
			(layer "B.Fab")
		)
		(pad "1" smd circle
			(at 0.40005 0 180)
			(size 0 0)
			(layers "B.Cu" "B.Mask" "B.Paste")
			(net "P3V3")
		)
		(pad "2" smd circle
			(at -0.40005 0 180)
			(size 0 0)
			(layers "B.Cu" "B.Mask" "B.Paste")
			(net "PWRGD_CHK_CPU0_DIMM")
		)
	)
	(footprint ""
		(layer "B.Cu")
		(at 103.125524 -414.329626 180)
		(property "Reference" "R1517"
			(at 0 0 0)
			(layer "B.SilkS")
			(hide yes)
			(effects
				(font
					(size 1.27 1.27)
				)
				(justify mirror)
			)
		)
		(property "Value" ""
			(at 0 0 0)
			(layer "B.Fab")
			(effects
				(font
					(size 1.27 1.27)
				)
				(justify mirror)
			)
		)
		(duplicate_pad_numbers_are_jumpers no)
		(fp_line
			(start 0.7874 0.4064)
			(end 0.7874 -0.4064)
			(stroke
				(width 0.1524)
				(type default)
			)
			(layer "B.SilkS")
		)
		(fp_line
			(start 0.7874 -0.4064)
			(end -0.7874 -0.4064)
			(stroke
				(width 0.1524)
				(type default)
			)
			(layer "B.SilkS")
		)
		(fp_line
			(start -0.7874 0.4064)
			(end 0.7874 0.4064)
			(stroke
				(width 0.1524)
				(type default)
			)
			(layer "B.SilkS")
		)
		(fp_line
			(start -0.7874 -0.4064)
			(end -0.7874 0.4064)
			(stroke
				(width 0.1524)
				(type default)
			)
			(layer "B.SilkS")
		)
		(fp_line
			(start 0.67945 0.3048)
			(end 0.67945 -0.305054)
			(stroke
				(width 0.1)
				(type default)
			)
			(layer "B.Fab")
		)
		(fp_line
			(start 0.67945 -0.305054)
			(end 0.12065 -0.305054)
			(stroke
				(width 0.1)
				(type default)
			)
			(layer "B.Fab")
		)
		(fp_line
			(start 0.12065 0.3048)
			(end 0.67945 0.3048)
			(stroke
				(width 0.1)
				(type default)
			)
			(layer "B.Fab")
		)
		(fp_line
			(start 0.12065 0.2794)
			(end 0.12065 0.3048)
			(stroke
				(width 0.1)
				(type default)
			)
			(layer "B.Fab")
		)
		(fp_line
			(start 0.12065 -0.2794)
			(end -0.12065 -0.2794)
			(stroke
				(width 0.1)
				(type default)
			)
			(layer "B.Fab")
		)
		(fp_line
			(start 0.12065 -0.305054)
			(end 0.12065 -0.2794)
			(stroke
				(width 0.1)
				(type default)
			)
			(layer "B.Fab")
		)
		(fp_line
			(start -0.120396 0.3048)
			(end -0.120396 0.2794)
			(stroke
				(width 0.1)
				(type default)
			)
			(layer "B.Fab")
		)
		(fp_line
			(start -0.120396 0.2794)
			(end 0.12065 0.2794)
			(stroke
				(width 0.1)
				(type default)
			)
			(layer "B.Fab")
		)
		(fp_line
			(start -0.12065 -0.2794)
			(end -0.12065 -0.3048)
			(stroke
				(width 0.1)
				(type default)
			)
			(layer "B.Fab")
		)
		(fp_line
			(start -0.12065 -0.3048)
			(end -0.67945 -0.3048)
			(stroke
				(width 0.1)
				(type default)
			)
			(layer "B.Fab")
		)
		(fp_line
			(start -0.67945 0.3048)
			(end -0.120396 0.3048)
			(stroke
				(width 0.1)
				(type default)
			)
			(layer "B.Fab")
		)
		(fp_line
			(start -0.67945 -0.3048)
			(end -0.67945 0.3048)
			(stroke
				(width 0.1)
				(type default)
			)
			(layer "B.Fab")
		)
		(pad "1" smd circle
			(at 0.40005 0)
			(size 0 0)
			(layers "B.Cu" "B.Mask" "B.Paste")
			(net "SMB_HOST_CLK_3V3AUX_SDA")
		)
		(pad "2" smd circle
			(at -0.40005 0)
			(size 0 0)
			(layers "B.Cu" "B.Mask" "B.Paste")
			(net "SMB_HOST_CLK_3V3AUX_SDA_R1")
		)
	)
	(footprint ""
		(layer "B.Cu")
		(at 43.265852 -386.72516 180)
		(property "Reference" "R716"
			(at 0 0 0)
			(layer "B.SilkS")
			(hide yes)
			(effects
				(font
					(size 1.27 1.27)
				)
				(justify mirror)
			)
		)
		(property "Value" ""
			(at 0 0 0)
			(layer "B.Fab")
			(effects
				(font
					(size 1.27 1.27)
				)
				(justify mirror)
			)
		)
		(duplicate_pad_numbers_are_jumpers no)
		(fp_line
			(start 0.32512 0.175006)
			(end 0.32512 -0.175006)
			(stroke
				(width 0.1)
				(type default)
			)
			(layer "B.Fab")
		)
		(fp_line
			(start 0.32512 -0.175006)
			(end -0.32512 -0.175006)
			(stroke
				(width 0.1)
				(type default)
			)
			(layer "B.Fab")
		)
		(fp_line
			(start -0.32512 0.175006)
			(end 0.32512 0.175006)
			(stroke
				(width 0.1)
				(type default)
			)
			(layer "B.Fab")
		)
		(fp_line
			(start -0.32512 -0.175006)
			(end -0.32512 0.175006)
			(stroke
				(width 0.1)
				(type default)
			)
			(layer "B.Fab")
		)
		(pad "1" smd rect
			(at 0.2667 0)
			(size 0.3048 0.381)
			(layers "B.Cu" "B.Mask" "B.Paste")
			(net "P1V8_CPU1_RT_1D")
		)
		(pad "2" smd rect
			(at -0.2667 0 180)
			(size 0.3048 0.381)
			(layers "B.Cu" "B.Mask" "B.Paste")
			(net "TEST0_RT_CPU1_P0")
		)
	)
	(footprint ""
		(layer "B.Cu")
		(at 444.617602 -418.58311 90)
		(property "Reference" "PR6610"
			(at 0 0 90)
			(layer "B.SilkS")
			(hide yes)
			(effects
				(font
					(size 1.27 1.27)
				)
				(justify mirror)
			)
		)
		(property "Value" ""
			(at 0 0 90)
			(layer "B.Fab")
			(effects
				(font
					(size 1.27 1.27)
				)
				(justify mirror)
			)
		)
		(duplicate_pad_numbers_are_jumpers no)
		(fp_line
			(start 0.7874 -0.4064)
			(end -0.7874 -0.4064)
			(stroke
				(width 0.1524)
				(type default)
			)
			(layer "B.SilkS")
		)
		(fp_line
			(start -0.7874 -0.4064)
			(end -0.7874 0.4064)
			(stroke
				(width 0.1524)
				(type default)
			)
			(layer "B.SilkS")
		)
		(fp_line
			(start 0.7874 0.4064)
			(end 0.7874 -0.4064)
			(stroke
				(width 0.1524)
				(type default)
			)
			(layer "B.SilkS")
		)
		(fp_line
			(start -0.7874 0.4064)
			(end 0.7874 0.4064)
			(stroke
				(width 0.1524)
				(type default)
			)
			(layer "B.SilkS")
		)
		(fp_line
			(start 0.67945 -0.305054)
			(end 0.12065 -0.305054)
			(stroke
				(width 0.1)
				(type default)
			)
			(layer "B.Fab")
		)
		(fp_line
			(start 0.12065 -0.305054)
			(end 0.12065 -0.2794)
			(stroke
				(width 0.1)
				(type default)
			)
			(layer "B.Fab")
		)
		(fp_line
			(start -0.12065 -0.3048)
			(end -0.67945 -0.3048)
			(stroke
				(width 0.1)
				(type default)
			)
			(layer "B.Fab")
		)
		(fp_line
			(start -0.67945 -0.3048)
			(end -0.67945 0.3048)
			(stroke
				(width 0.1)
				(type default)
			)
			(layer "B.Fab")
		)
		(fp_line
			(start 0.12065 -0.2794)
			(end -0.12065 -0.2794)
			(stroke
				(width 0.1)
				(type default)
			)
			(layer "B.Fab")
		)
		(fp_line
			(start -0.12065 -0.2794)
			(end -0.12065 -0.3048)
			(stroke
				(width 0.1)
				(type default)
			)
			(layer "B.Fab")
		)
		(fp_line
			(start 0.12065 0.2794)
			(end 0.12065 0.3048)
			(stroke
				(width 0.1)
				(type default)
			)
			(layer "B.Fab")
		)
		(fp_line
			(start -0.120396 0.2794)
			(end 0.12065 0.2794)
			(stroke
				(width 0.1)
				(type default)
			)
			(layer "B.Fab")
		)
		(fp_line
			(start 0.67945 0.3048)
			(end 0.67945 -0.305054)
			(stroke
				(width 0.1)
				(type default)
			)
			(layer "B.Fab")
		)
		(fp_line
			(start 0.12065 0.3048)
			(end 0.67945 0.3048)
			(stroke
				(width 0.1)
				(type default)
			)
			(layer "B.Fab")
		)
		(fp_line
			(start -0.120396 0.3048)
			(end -0.120396 0.2794)
			(stroke
				(width 0.1)
				(type default)
			)
			(layer "B.Fab")
		)
		(fp_line
			(start -0.67945 0.3048)
			(end -0.120396 0.3048)
			(stroke
				(width 0.1)
				(type default)
			)
			(layer "B.Fab")
		)
		(pad "1" smd circle
			(at 0.40005 0 270)
			(size 0 0)
			(layers "B.Cu" "B.Mask" "B.Paste")
			(net "NC_P0V9_RETIMER_CPU0_IMON4")
		)
		(pad "2" smd circle
			(at -0.40005 0 270)
			(size 0 0)
			(layers "B.Cu" "B.Mask" "B.Paste")
			(net "GND")
		)
	)
	(footprint ""
		(layer "B.Cu")
		(at 462.124552 -380.027434 90)
		(property "Reference" "PC534"
			(at -6.293104 1.933448 0)
			(unlocked yes)
			(layer "B.SilkS")
			(effects
				(font
					(size 0.7874 0.5842)
					(thickness 0.1524)
				)
				(justify left mirror)
			)
		)
		(property "Value" ""
			(at 0 0 90)
			(layer "B.Fab")
			(effects
				(font
					(size 1.27 1.27)
				)
				(justify mirror)
			)
		)
		(duplicate_pad_numbers_are_jumpers no)
		(fp_line
			(start 4.84378 -2.150618)
			(end 4.53898 -2.150618)
			(stroke
				(width 0.1524)
				(type default)
			)
			(layer "B.SilkS")
		)
		(fp_line
			(start 4.84378 -2.150618)
			(end 4.842256 2.163064)
			(stroke
				(width 0.1524)
				(type default)
			)
			(layer "B.SilkS")
		)
		(fp_line
			(start 4.69138 -2.150618)
			(end 4.692396 2.161032)
			(stroke
				(width 0.1524)
				(type default)
			)
			(layer "B.SilkS")
		)
		(fp_line
			(start 4.53898 -2.150618)
			(end 4.539742 2.152142)
			(stroke
				(width 0.1524)
				(type default)
			)
			(layer "B.SilkS")
		)
		(fp_line
			(start 4.53898 -2.15011)
			(end -4.53898 -2.15011)
			(stroke
				(width 0.1524)
				(type default)
			)
			(layer "B.SilkS")
		)
		(fp_line
			(start -4.53898 -2.15011)
			(end -4.53898 1.882648)
			(stroke
				(width 0.1524)
				(type default)
			)
			(layer "B.SilkS")
		)
		(fp_line
			(start 4.53898 2.15011)
			(end 4.53898 -2.15011)
			(stroke
				(width 0.1524)
				(type default)
			)
			(layer "B.SilkS")
		)
		(fp_line
			(start -4.056634 2.15011)
			(end 4.53898 2.15011)
			(stroke
				(width 0.1524)
				(type default)
			)
			(layer "B.SilkS")
		)
		(fp_line
			(start 4.83108 2.150364)
			(end 4.447794 2.149348)
			(stroke
				(width 0.1524)
				(type default)
			)
			(layer "B.SilkS")
		)
		(fp_line
			(start 3.64998 -2.15011)
			(end -3.64998 -2.15011)
			(stroke
				(width 0.1)
				(type default)
			)
			(layer "B.Fab")
		)
		(fp_line
			(start -3.64998 -2.15011)
			(end -3.64998 2.15011)
			(stroke
				(width 0.1)
				(type default)
			)
			(layer "B.Fab")
		)
		(fp_line
			(start 3.64998 2.15011)
			(end 3.64998 -2.15011)
			(stroke
				(width 0.1)
				(type default)
			)
			(layer "B.Fab")
		)
		(fp_line
			(start -3.64998 2.15011)
			(end 3.64998 2.15011)
			(stroke
				(width 0.1)
				(type default)
			)
			(layer "B.Fab")
		)
		(fp_text user "+"
			(at 6.214872 -0.337058 90)
			(unlocked yes)
			(layer "B.SilkS")
			(effects
				(font
					(size 1.905 1.4224)
					(thickness 0.1524)
				)
				(justify left mirror)
			)
		)
		(fp_text user "-"
			(at -4.313174 -0.094488 90)
			(unlocked yes)
			(layer "B.SilkS")
			(effects
				(font
					(size 1.905 1.4224)
					(thickness 0.1524)
				)
				(justify left mirror)
			)
		)
		(fp_text user "+"
			(at 6.214872 -0.337058 90)
			(unlocked yes)
			(layer "B.Fab")
			(effects
				(font
					(size 1.905 1.4224)
					(thickness 0.1524)
				)
				(justify left mirror)
			)
		)
		(fp_text user "-"
			(at -4.313174 -0.094488 90)
			(unlocked yes)
			(layer "B.Fab")
			(effects
				(font
					(size 1.905 1.4224)
					(thickness 0.1524)
				)
				(justify left mirror)
			)
		)
		(pad "1" smd rect
			(at 3.199892 0 270)
			(size 2.413 2.8194)
			(layers "B.Cu" "B.Mask" "B.Paste")
			(net "P0V9_CPU0_RT_2D")
		)
		(pad "2" smd rect
			(at -3.199892 0 270)
			(size 2.413 2.8194)
			(layers "B.Cu" "B.Mask" "B.Paste")
			(net "GND")
		)
	)
	(footprint ""
		(layer "B.Cu")
		(at 474.16466 -297.49877 180)
		(property "Reference" "DB6"
			(at 2.845308 -7.762748 270)
			(unlocked yes)
			(layer "B.SilkS")
			(effects
				(font
					(size 0.7874 0.5842)
					(thickness 0.1524)
				)
				(justify left mirror)
			)
		)
		(property "Value" ""
			(at 0 0 0)
			(layer "B.Fab")
			(effects
				(font
					(size 1.27 1.27)
				)
				(justify mirror)
			)
		)
		(duplicate_pad_numbers_are_jumpers no)
		(fp_line
			(start 3.330702 -4.771136)
			(end -3.330702 -4.771136)
			(stroke
				(width 0.1524)
				(type default)
			)
			(layer "B.SilkS")
		)
		(fp_line
			(start 0 4.011168)
			(end 3.330702 -4.771136)
			(stroke
				(width 0.1524)
				(type default)
			)
			(layer "B.SilkS")
		)
		(fp_line
			(start -3.330702 -4.771136)
			(end 0 4.011168)
			(stroke
				(width 0.1524)
				(type default)
			)
			(layer "B.SilkS")
		)
		(fp_line
			(start 3.330702 -4.771136)
			(end -3.330702 -4.771136)
			(stroke
				(width 0.1)
				(type default)
			)
			(layer "B.Fab")
		)
		(fp_line
			(start 0 4.011168)
			(end 3.330702 -4.771136)
			(stroke
				(width 0.1)
				(type default)
			)
			(layer "B.Fab")
		)
		(fp_line
			(start -3.330702 -4.771136)
			(end 0 4.011168)
			(stroke
				(width 0.1)
				(type default)
			)
			(layer "B.Fab")
		)
		(pad "1" thru_hole circle
			(at 0 0)
			(size 2.159 2.159)
			(drill 1.7018)
			(layers "*.Cu" "*.Mask")
			(remove_unused_layers no)
			(net "T1_GND")
			(clearance 0.0254)
			(thermal_gap 0.0254)
		)
		(pad "2" thru_hole circle
			(at 1.27 -3.348736)
			(size 2.159 2.159)
			(drill 1.7018)
			(layers "*.Cu" "*.Mask")
			(remove_unused_layers no)
			(net "TDR_SE_45_OHM_BOT")
			(clearance 0.0254)
			(thermal_gap 0.0254)
		)
		(pad "3" thru_hole circle
			(at -1.27 -3.348736)
			(size 2.159 2.159)
			(drill 1.7018)
			(layers "*.Cu" "*.Mask")
			(remove_unused_layers no)
			(net "TDR_SE_45_OHM_BOT")
			(clearance 0.0254)
			(thermal_gap 0.0254)
		)
	)
	(footprint ""
		(layer "B.Cu")
		(at 163.46932 -413.5374 90)
		(property "Reference" "R691"
			(at 0 0 90)
			(layer "B.SilkS")
			(hide yes)
			(effects
				(font
					(size 1.27 1.27)
				)
				(justify mirror)
			)
		)
		(property "Value" ""
			(at 0 0 90)
			(layer "B.Fab")
			(effects
				(font
					(size 1.27 1.27)
				)
				(justify mirror)
			)
		)
		(duplicate_pad_numbers_are_jumpers no)
		(fp_line
			(start 0.32512 -0.175006)
			(end -0.32512 -0.175006)
			(stroke
				(width 0.1)
				(type default)
			)
			(layer "B.Fab")
		)
		(fp_line
			(start -0.32512 -0.175006)
			(end -0.32512 0.175006)
			(stroke
				(width 0.1)
				(type default)
			)
			(layer "B.Fab")
		)
		(fp_line
			(start 0.32512 0.175006)
			(end 0.32512 -0.175006)
			(stroke
				(width 0.1)
				(type default)
			)
			(layer "B.Fab")
		)
		(fp_line
			(start -0.32512 0.175006)
			(end 0.32512 0.175006)
			(stroke
				(width 0.1)
				(type default)
			)
			(layer "B.Fab")
		)
		(pad "1" smd rect
			(at 0.2667 0 270)
			(size 0.3048 0.381)
			(layers "B.Cu" "B.Mask" "B.Paste")
			(net "SMB_RT_CPU1_P2_ROM_MUX_1D_SCL")
		)
		(pad "2" smd rect
			(at -0.2667 0 90)
			(size 0.3048 0.381)
			(layers "B.Cu" "B.Mask" "B.Paste")
			(net "SMB_RT_CPU1_P2_ROM_MUX_1D_R_SCL")
		)
	)
	(footprint ""
		(layer "B.Cu")
		(at 320.318384 -396.393162 -90)
		(property "Reference" "C541"
			(at 0 0 90)
			(layer "B.SilkS")
			(hide yes)
			(effects
				(font
					(size 1.27 1.27)
				)
				(justify mirror)
			)
		)
		(property "Value" ""
			(at 0 0 90)
			(layer "B.Fab")
			(effects
				(font
					(size 1.27 1.27)
				)
				(justify mirror)
			)
		)
		(duplicate_pad_numbers_are_jumpers no)
		(fp_line
			(start -0.299974 0.150114)
			(end 0.299974 0.150114)
			(stroke
				(width 0.1)
				(type default)
			)
			(layer "B.Fab")
		)
		(fp_line
			(start 0.299974 0.150114)
			(end 0.299974 -0.150114)
			(stroke
				(width 0.1)
				(type default)
			)
			(layer "B.Fab")
		)
		(fp_line
			(start -0.299974 -0.150114)
			(end -0.299974 0.150114)
			(stroke
				(width 0.1)
				(type default)
			)
			(layer "B.Fab")
		)
		(fp_line
			(start 0.299974 -0.150114)
			(end -0.299974 -0.150114)
			(stroke
				(width 0.1)
				(type default)
			)
			(layer "B.Fab")
		)
		(pad "1" smd rect
			(at 0.2667 0 90)
			(size 0.3048 0.381)
			(layers "B.Cu" "B.Mask" "B.Paste")
			(net "P0V9_CPU0_RT0_2A")
		)
		(pad "2" smd rect
			(at -0.2667 0 90)
			(size 0.3048 0.381)
			(layers "B.Cu" "B.Mask" "B.Paste")
			(net "GND")
		)
	)
	(footprint ""
		(layer "B.Cu")
		(at 87.106252 -386.766562 90)
		(property "Reference" "C205"
			(at 0 0 90)
			(layer "B.SilkS")
			(hide yes)
			(effects
				(font
					(size 1.27 1.27)
				)
				(justify mirror)
			)
		)
		(property "Value" ""
			(at 0 0 90)
			(layer "B.Fab")
			(effects
				(font
					(size 1.27 1.27)
				)
				(justify mirror)
			)
		)
		(duplicate_pad_numbers_are_jumpers no)
		(fp_line
			(start 0.299974 -0.150114)
			(end -0.299974 -0.150114)
			(stroke
				(width 0.1)
				(type default)
			)
			(layer "B.Fab")
		)
		(fp_line
			(start -0.299974 -0.150114)
			(end -0.299974 0.150114)
			(stroke
				(width 0.1)
				(type default)
			)
			(layer "B.Fab")
		)
		(fp_line
			(start 0.299974 0.150114)
			(end 0.299974 -0.150114)
			(stroke
				(width 0.1)
				(type default)
			)
			(layer "B.Fab")
		)
		(fp_line
			(start -0.299974 0.150114)
			(end 0.299974 0.150114)
			(stroke
				(width 0.1)
				(type default)
			)
			(layer "B.Fab")
		)
		(pad "1" smd rect
			(at 0.2667 0 270)
			(size 0.3048 0.381)
			(layers "B.Cu" "B.Mask" "B.Paste")
			(net "P1V8_CPU1_RT1_1A")
		)
		(pad "2" smd rect
			(at -0.2667 0 270)
			(size 0.3048 0.381)
			(layers "B.Cu" "B.Mask" "B.Paste")
			(net "GND")
		)
	)
	(footprint ""
		(layer "B.Cu")
		(at 105.960164 -261.255256 180)
		(property "Reference" "C2509"
			(at 0 0 0)
			(layer "B.SilkS")
			(hide yes)
			(effects
				(font
					(size 1.27 1.27)
				)
				(justify mirror)
			)
		)
		(property "Value" ""
			(at 0 0 0)
			(layer "B.Fab")
			(effects
				(font
					(size 1.27 1.27)
				)
				(justify mirror)
			)
		)
		(duplicate_pad_numbers_are_jumpers no)
		(fp_line
			(start 0.7874 0.4064)
			(end 0.7874 -0.4064)
			(stroke
				(width 0.1524)
				(type default)
			)
			(layer "B.SilkS")
		)
		(fp_line
			(start 0.7874 -0.4064)
			(end -0.7874 -0.4064)
			(stroke
				(width 0.1524)
				(type default)
			)
			(layer "B.SilkS")
		)
		(fp_line
			(start -0.7874 0.4064)
			(end 0.7874 0.4064)
			(stroke
				(width 0.1524)
				(type default)
			)
			(layer "B.SilkS")
		)
		(fp_line
			(start -0.7874 -0.4064)
			(end -0.7874 0.4064)
			(stroke
				(width 0.1524)
				(type default)
			)
			(layer "B.SilkS")
		)
		(fp_line
			(start 0.67945 0.3048)
			(end 0.67945 -0.305054)
			(stroke
				(width 0.1)
				(type default)
			)
			(layer "B.Fab")
		)
		(fp_line
			(start 0.67945 -0.305054)
			(end 0.12065 -0.305054)
			(stroke
				(width 0.1)
				(type default)
			)
			(layer "B.Fab")
		)
		(fp_line
			(start 0.12065 0.3048)
			(end 0.67945 0.3048)
			(stroke
				(width 0.1)
				(type default)
			)
			(layer "B.Fab")
		)
		(fp_line
			(start 0.12065 0.2794)
			(end 0.12065 0.3048)
			(stroke
				(width 0.1)
				(type default)
			)
			(layer "B.Fab")
		)
		(fp_line
			(start 0.12065 -0.2794)
			(end -0.12065 -0.2794)
			(stroke
				(width 0.1)
				(type default)
			)
			(layer "B.Fab")
		)
		(fp_line
			(start 0.12065 -0.305054)
			(end 0.12065 -0.2794)
			(stroke
				(width 0.1)
				(type default)
			)
			(layer "B.Fab")
		)
		(fp_line
			(start -0.120396 0.3048)
			(end -0.120396 0.2794)
			(stroke
				(width 0.1)
				(type default)
			)
			(layer "B.Fab")
		)
		(fp_line
			(start -0.120396 0.2794)
			(end 0.12065 0.2794)
			(stroke
				(width 0.1)
				(type default)
			)
			(layer "B.Fab")
		)
		(fp_line
			(start -0.12065 -0.2794)
			(end -0.12065 -0.3048)
			(stroke
				(width 0.1)
				(type default)
			)
			(layer "B.Fab")
		)
		(fp_line
			(start -0.12065 -0.3048)
			(end -0.67945 -0.3048)
			(stroke
				(width 0.1)
				(type default)
			)
			(layer "B.Fab")
		)
		(fp_line
			(start -0.67945 0.3048)
			(end -0.120396 0.3048)
			(stroke
				(width 0.1)
				(type default)
			)
			(layer "B.Fab")
		)
		(fp_line
			(start -0.67945 -0.3048)
			(end -0.67945 0.3048)
			(stroke
				(width 0.1)
				(type default)
			)
			(layer "B.Fab")
		)
		(pad "1" smd circle
			(at 0.40005 0)
			(size 0 0)
			(layers "B.Cu" "B.Mask" "B.Paste")
			(net "PVDDIO_P1")
		)
		(pad "2" smd circle
			(at -0.40005 0)
			(size 0 0)
			(layers "B.Cu" "B.Mask" "B.Paste")
			(net "GND")
		)
	)
	(footprint ""
		(layer "B.Cu")
		(at 367.671858 -135.970772)
		(property "Reference" "R6089"
			(at 0 0 0)
			(layer "B.SilkS")
			(hide yes)
			(effects
				(font
					(size 1.27 1.27)
				)
				(justify mirror)
			)
		)
		(property "Value" ""
			(at 0 0 0)
			(layer "B.Fab")
			(effects
				(font
					(size 1.27 1.27)
				)
				(justify mirror)
			)
		)
		(duplicate_pad_numbers_are_jumpers no)
		(fp_line
			(start -0.7874 -0.4064)
			(end -0.7874 0.4064)
			(stroke
				(width 0.1524)
				(type default)
			)
			(layer "B.SilkS")
		)
		(fp_line
			(start -0.7874 0.4064)
			(end 0.7874 0.4064)
			(stroke
				(width 0.1524)
				(type default)
			)
			(layer "B.SilkS")
		)
		(fp_line
			(start 0.7874 -0.4064)
			(end -0.7874 -0.4064)
			(stroke
				(width 0.1524)
				(type default)
			)
			(layer "B.SilkS")
		)
		(fp_line
			(start 0.7874 0.4064)
			(end 0.7874 -0.4064)
			(stroke
				(width 0.1524)
				(type default)
			)
			(layer "B.SilkS")
		)
		(fp_line
			(start -0.67945 -0.3048)
			(end -0.67945 0.3048)
			(stroke
				(width 0.1)
				(type default)
			)
			(layer "B.Fab")
		)
		(fp_line
			(start -0.67945 0.3048)
			(end -0.120396 0.3048)
			(stroke
				(width 0.1)
				(type default)
			)
			(layer "B.Fab")
		)
		(fp_line
			(start -0.12065 -0.3048)
			(end -0.67945 -0.3048)
			(stroke
				(width 0.1)
				(type default)
			)
			(layer "B.Fab")
		)
		(fp_line
			(start -0.12065 -0.2794)
			(end -0.12065 -0.3048)
			(stroke
				(width 0.1)
				(type default)
			)
			(layer "B.Fab")
		)
		(fp_line
			(start -0.120396 0.2794)
			(end 0.12065 0.2794)
			(stroke
				(width 0.1)
				(type default)
			)
			(layer "B.Fab")
		)
		(fp_line
			(start -0.120396 0.3048)
			(end -0.120396 0.2794)
			(stroke
				(width 0.1)
				(type default)
			)
			(layer "B.Fab")
		)
		(fp_line
			(start 0.12065 -0.305054)
			(end 0.12065 -0.2794)
			(stroke
				(width 0.1)
				(type default)
			)
			(layer "B.Fab")
		)
		(fp_line
			(start 0.12065 -0.2794)
			(end -0.12065 -0.2794)
			(stroke
				(width 0.1)
				(type default)
			)
			(layer "B.Fab")
		)
		(fp_line
			(start 0.12065 0.2794)
			(end 0.12065 0.3048)
			(stroke
				(width 0.1)
				(type default)
			)
			(layer "B.Fab")
		)
		(fp_line
			(start 0.12065 0.3048)
			(end 0.67945 0.3048)
			(stroke
				(width 0.1)
				(type default)
			)
			(layer "B.Fab")
		)
		(fp_line
			(start 0.67945 -0.305054)
			(end 0.12065 -0.305054)
			(stroke
				(width 0.1)
				(type default)
			)
			(layer "B.Fab")
		)
		(fp_line
			(start 0.67945 0.3048)
			(end 0.67945 -0.305054)
			(stroke
				(width 0.1)
				(type default)
			)
			(layer "B.Fab")
		)
		(pad "1" smd circle
			(at 0.40005 0 180)
			(size 0 0)
			(layers "B.Cu" "B.Mask" "B.Paste")
			(net "PVDDCR_SOC_P0_EN_RC")
		)
		(pad "2" smd circle
			(at -0.40005 0 180)
			(size 0 0)
			(layers "B.Cu" "B.Mask" "B.Paste")
			(net "GND")
		)
	)
	(footprint ""
		(layer "B.Cu")
		(at 173.213776 -19.209258)
		(property "Reference" "R6028"
			(at 0 0 0)
			(layer "B.SilkS")
			(hide yes)
			(effects
				(font
					(size 1.27 1.27)
				)
				(justify mirror)
			)
		)
		(property "Value" ""
			(at 0 0 0)
			(layer "B.Fab")
			(effects
				(font
					(size 1.27 1.27)
				)
				(justify mirror)
			)
		)
		(duplicate_pad_numbers_are_jumpers no)
		(fp_line
			(start -0.7874 -0.4064)
			(end -0.7874 0.4064)
			(stroke
				(width 0.1524)
				(type default)
			)
			(layer "B.SilkS")
		)
		(fp_line
			(start -0.7874 0.4064)
			(end 0.7874 0.4064)
			(stroke
				(width 0.1524)
				(type default)
			)
			(layer "B.SilkS")
		)
		(fp_line
			(start 0.7874 -0.4064)
			(end -0.7874 -0.4064)
			(stroke
				(width 0.1524)
				(type default)
			)
			(layer "B.SilkS")
		)
		(fp_line
			(start 0.7874 0.4064)
			(end 0.7874 -0.4064)
			(stroke
				(width 0.1524)
				(type default)
			)
			(layer "B.SilkS")
		)
		(fp_line
			(start -0.67945 -0.3048)
			(end -0.67945 0.3048)
			(stroke
				(width 0.1)
				(type default)
			)
			(layer "B.Fab")
		)
		(fp_line
			(start -0.67945 0.3048)
			(end -0.120396 0.3048)
			(stroke
				(width 0.1)
				(type default)
			)
			(layer "B.Fab")
		)
		(fp_line
			(start -0.12065 -0.3048)
			(end -0.67945 -0.3048)
			(stroke
				(width 0.1)
				(type default)
			)
			(layer "B.Fab")
		)
		(fp_line
			(start -0.12065 -0.2794)
			(end -0.12065 -0.3048)
			(stroke
				(width 0.1)
				(type default)
			)
			(layer "B.Fab")
		)
		(fp_line
			(start -0.120396 0.2794)
			(end 0.12065 0.2794)
			(stroke
				(width 0.1)
				(type default)
			)
			(layer "B.Fab")
		)
		(fp_line
			(start -0.120396 0.3048)
			(end -0.120396 0.2794)
			(stroke
				(width 0.1)
				(type default)
			)
			(layer "B.Fab")
		)
		(fp_line
			(start 0.12065 -0.305054)
			(end 0.12065 -0.2794)
			(stroke
				(width 0.1)
				(type default)
			)
			(layer "B.Fab")
		)
		(fp_line
			(start 0.12065 -0.2794)
			(end -0.12065 -0.2794)
			(stroke
				(width 0.1)
				(type default)
			)
			(layer "B.Fab")
		)
		(fp_line
			(start 0.12065 0.2794)
			(end 0.12065 0.3048)
			(stroke
				(width 0.1)
				(type default)
			)
			(layer "B.Fab")
		)
		(fp_line
			(start 0.12065 0.3048)
			(end 0.67945 0.3048)
			(stroke
				(width 0.1)
				(type default)
			)
			(layer "B.Fab")
		)
		(fp_line
			(start 0.67945 -0.305054)
			(end 0.12065 -0.305054)
			(stroke
				(width 0.1)
				(type default)
			)
			(layer "B.Fab")
		)
		(fp_line
			(start 0.67945 0.3048)
			(end 0.67945 -0.305054)
			(stroke
				(width 0.1)
				(type default)
			)
			(layer "B.Fab")
		)
		(pad "1" smd circle
			(at 0.40005 0 180)
			(size 0 0)
			(layers "B.Cu" "B.Mask" "B.Paste")
			(net "FM_LPC_ESPI_SEL")
		)
		(pad "2" smd circle
			(at -0.40005 0 180)
			(size 0 0)
			(layers "B.Cu" "B.Mask" "B.Paste")
			(net "GND")
		)
	)
	(footprint ""
		(layer "B.Cu")
		(at 234.4801 -228.092 180)
		(property "Reference" "R150"
			(at 0 0 0)
			(layer "B.SilkS")
			(hide yes)
			(effects
				(font
					(size 1.27 1.27)
				)
				(justify mirror)
			)
		)
		(property "Value" ""
			(at 0 0 0)
			(layer "B.Fab")
			(effects
				(font
					(size 1.27 1.27)
				)
				(justify mirror)
			)
		)
		(duplicate_pad_numbers_are_jumpers no)
		(fp_line
			(start 0.7874 0.4064)
			(end 0.7874 -0.4064)
			(stroke
				(width 0.1524)
				(type default)
			)
			(layer "B.SilkS")
		)
		(fp_line
			(start 0.7874 -0.4064)
			(end -0.7874 -0.4064)
			(stroke
				(width 0.1524)
				(type default)
			)
			(layer "B.SilkS")
		)
		(fp_line
			(start -0.7874 0.4064)
			(end 0.7874 0.4064)
			(stroke
				(width 0.1524)
				(type default)
			)
			(layer "B.SilkS")
		)
		(fp_line
			(start -0.7874 -0.4064)
			(end -0.7874 0.4064)
			(stroke
				(width 0.1524)
				(type default)
			)
			(layer "B.SilkS")
		)
		(fp_line
			(start 0.67945 0.3048)
			(end 0.67945 -0.305054)
			(stroke
				(width 0.1)
				(type default)
			)
			(layer "B.Fab")
		)
		(fp_line
			(start 0.67945 -0.305054)
			(end 0.12065 -0.305054)
			(stroke
				(width 0.1)
				(type default)
			)
			(layer "B.Fab")
		)
		(fp_line
			(start 0.12065 0.3048)
			(end 0.67945 0.3048)
			(stroke
				(width 0.1)
				(type default)
			)
			(layer "B.Fab")
		)
		(fp_line
			(start 0.12065 0.2794)
			(end 0.12065 0.3048)
			(stroke
				(width 0.1)
				(type default)
			)
			(layer "B.Fab")
		)
		(fp_line
			(start 0.12065 -0.2794)
			(end -0.12065 -0.2794)
			(stroke
				(width 0.1)
				(type default)
			)
			(layer "B.Fab")
		)
		(fp_line
			(start 0.12065 -0.305054)
			(end 0.12065 -0.2794)
			(stroke
				(width 0.1)
				(type default)
			)
			(layer "B.Fab")
		)
		(fp_line
			(start -0.120396 0.3048)
			(end -0.120396 0.2794)
			(stroke
				(width 0.1)
				(type default)
			)
			(layer "B.Fab")
		)
		(fp_line
			(start -0.120396 0.2794)
			(end 0.12065 0.2794)
			(stroke
				(width 0.1)
				(type default)
			)
			(layer "B.Fab")
		)
		(fp_line
			(start -0.12065 -0.2794)
			(end -0.12065 -0.3048)
			(stroke
				(width 0.1)
				(type default)
			)
			(layer "B.Fab")
		)
		(fp_line
			(start -0.12065 -0.3048)
			(end -0.67945 -0.3048)
			(stroke
				(width 0.1)
				(type default)
			)
			(layer "B.Fab")
		)
		(fp_line
			(start -0.67945 0.3048)
			(end -0.120396 0.3048)
			(stroke
				(width 0.1)
				(type default)
			)
			(layer "B.Fab")
		)
		(fp_line
			(start -0.67945 -0.3048)
			(end -0.67945 0.3048)
			(stroke
				(width 0.1)
				(type default)
			)
			(layer "B.Fab")
		)
		(pad "1" smd rect
			(at 0.40005 0 180)
			(size 0.4572 0.508)
			(layers "B.Cu" "B.Mask" "B.Paste")
			(net "SMB_CPU0_CPU1_APML_SDA")
		)
		(pad "2" smd rect
			(at -0.40005 0 180)
			(size 0.4572 0.508)
			(layers "B.Cu" "B.Mask" "B.Paste")
			(net "SMB_CPU0_CPU1_APML_BUF1_SDA")
		)
	)
	(footprint ""
		(layer "B.Cu")
		(at 310.411876 -76.489814 -90)
		(property "Reference" "R3048"
			(at 0 0 90)
			(layer "B.SilkS")
			(hide yes)
			(effects
				(font
					(size 1.27 1.27)
				)
				(justify mirror)
			)
		)
		(property "Value" ""
			(at 0 0 90)
			(layer "B.Fab")
			(effects
				(font
					(size 1.27 1.27)
				)
				(justify mirror)
			)
		)
		(duplicate_pad_numbers_are_jumpers no)
		(fp_line
			(start -0.7874 0.4064)
			(end 0.7874 0.4064)
			(stroke
				(width 0.1524)
				(type default)
			)
			(layer "B.SilkS")
		)
		(fp_line
			(start 0.7874 0.4064)
			(end 0.7874 -0.4064)
			(stroke
				(width 0.1524)
				(type default)
			)
			(layer "B.SilkS")
		)
		(fp_line
			(start -0.7874 -0.4064)
			(end -0.7874 0.4064)
			(stroke
				(width 0.1524)
				(type default)
			)
			(layer "B.SilkS")
		)
		(fp_line
			(start 0.7874 -0.4064)
			(end -0.7874 -0.4064)
			(stroke
				(width 0.1524)
				(type default)
			)
			(layer "B.SilkS")
		)
		(fp_line
			(start -0.67945 0.3048)
			(end -0.120396 0.3048)
			(stroke
				(width 0.1)
				(type default)
			)
			(layer "B.Fab")
		)
		(fp_line
			(start -0.120396 0.3048)
			(end -0.120396 0.2794)
			(stroke
				(width 0.1)
				(type default)
			)
			(layer "B.Fab")
		)
		(fp_line
			(start 0.12065 0.3048)
			(end 0.67945 0.3048)
			(stroke
				(width 0.1)
				(type default)
			)
			(layer "B.Fab")
		)
		(fp_line
			(start 0.67945 0.3048)
			(end 0.67945 -0.305054)
			(stroke
				(width 0.1)
				(type default)
			)
			(layer "B.Fab")
		)
		(fp_line
			(start -0.120396 0.2794)
			(end 0.12065 0.2794)
			(stroke
				(width 0.1)
				(type default)
			)
			(layer "B.Fab")
		)
		(fp_line
			(start 0.12065 0.2794)
			(end 0.12065 0.3048)
			(stroke
				(width 0.1)
				(type default)
			)
			(layer "B.Fab")
		)
		(fp_line
			(start -0.12065 -0.2794)
			(end -0.12065 -0.3048)
			(stroke
				(width 0.1)
				(type default)
			)
			(layer "B.Fab")
		)
		(fp_line
			(start 0.12065 -0.2794)
			(end -0.12065 -0.2794)
			(stroke
				(width 0.1)
				(type default)
			)
			(layer "B.Fab")
		)
		(fp_line
			(start -0.67945 -0.3048)
			(end -0.67945 0.3048)
			(stroke
				(width 0.1)
				(type default)
			)
			(layer "B.Fab")
		)
		(fp_line
			(start -0.12065 -0.3048)
			(end -0.67945 -0.3048)
			(stroke
				(width 0.1)
				(type default)
			)
			(layer "B.Fab")
		)
		(fp_line
			(start 0.12065 -0.305054)
			(end 0.12065 -0.2794)
			(stroke
				(width 0.1)
				(type default)
			)
			(layer "B.Fab")
		)
		(fp_line
			(start 0.67945 -0.305054)
			(end 0.12065 -0.305054)
			(stroke
				(width 0.1)
				(type default)
			)
			(layer "B.Fab")
		)
		(pad "1" smd circle
			(at 0.40005 0 90)
			(size 0 0)
			(layers "B.Cu" "B.Mask" "B.Paste")
			(net "MB0_P12V_STBY_PWRGD")
		)
		(pad "2" smd circle
			(at -0.40005 0 90)
			(size 0 0)
			(layers "B.Cu" "B.Mask" "B.Paste")
			(net "PWRGD_PS_PWROK")
		)
	)
	(footprint ""
		(layer "B.Cu")
		(at 242.702842 -383.483358 180)
		(property "Reference" "PR2537"
			(at 0 0 0)
			(layer "B.SilkS")
			(hide yes)
			(effects
				(font
					(size 1.27 1.27)
				)
				(justify mirror)
			)
		)
		(property "Value" ""
			(at 0 0 0)
			(layer "B.Fab")
			(effects
				(font
					(size 1.27 1.27)
				)
				(justify mirror)
			)
		)
		(duplicate_pad_numbers_are_jumpers no)
		(fp_line
			(start 0.7874 0.4064)
			(end 0.7874 -0.4064)
			(stroke
				(width 0.1524)
				(type default)
			)
			(layer "B.SilkS")
		)
		(fp_line
			(start 0.7874 -0.4064)
			(end -0.7874 -0.4064)
			(stroke
				(width 0.1524)
				(type default)
			)
			(layer "B.SilkS")
		)
		(fp_line
			(start -0.7874 0.4064)
			(end 0.7874 0.4064)
			(stroke
				(width 0.1524)
				(type default)
			)
			(layer "B.SilkS")
		)
		(fp_line
			(start -0.7874 -0.4064)
			(end -0.7874 0.4064)
			(stroke
				(width 0.1524)
				(type default)
			)
			(layer "B.SilkS")
		)
		(fp_line
			(start 0.67945 0.3048)
			(end 0.67945 -0.305054)
			(stroke
				(width 0.1)
				(type default)
			)
			(layer "B.Fab")
		)
		(fp_line
			(start 0.67945 -0.305054)
			(end 0.12065 -0.305054)
			(stroke
				(width 0.1)
				(type default)
			)
			(layer "B.Fab")
		)
		(fp_line
			(start 0.12065 0.3048)
			(end 0.67945 0.3048)
			(stroke
				(width 0.1)
				(type default)
			)
			(layer "B.Fab")
		)
		(fp_line
			(start 0.12065 0.2794)
			(end 0.12065 0.3048)
			(stroke
				(width 0.1)
				(type default)
			)
			(layer "B.Fab")
		)
		(fp_line
			(start 0.12065 -0.2794)
			(end -0.12065 -0.2794)
			(stroke
				(width 0.1)
				(type default)
			)
			(layer "B.Fab")
		)
		(fp_line
			(start 0.12065 -0.305054)
			(end 0.12065 -0.2794)
			(stroke
				(width 0.1)
				(type default)
			)
			(layer "B.Fab")
		)
		(fp_line
			(start -0.120396 0.3048)
			(end -0.120396 0.2794)
			(stroke
				(width 0.1)
				(type default)
			)
			(layer "B.Fab")
		)
		(fp_line
			(start -0.120396 0.2794)
			(end 0.12065 0.2794)
			(stroke
				(width 0.1)
				(type default)
			)
			(layer "B.Fab")
		)
		(fp_line
			(start -0.12065 -0.2794)
			(end -0.12065 -0.3048)
			(stroke
				(width 0.1)
				(type default)
			)
			(layer "B.Fab")
		)
		(fp_line
			(start -0.12065 -0.3048)
			(end -0.67945 -0.3048)
			(stroke
				(width 0.1)
				(type default)
			)
			(layer "B.Fab")
		)
		(fp_line
			(start -0.67945 0.3048)
			(end -0.120396 0.3048)
			(stroke
				(width 0.1)
				(type default)
			)
			(layer "B.Fab")
		)
		(fp_line
			(start -0.67945 -0.3048)
			(end -0.67945 0.3048)
			(stroke
				(width 0.1)
				(type default)
			)
			(layer "B.Fab")
		)
		(pad "1" smd circle
			(at 0.40005 0)
			(size 0 0)
			(layers "B.Cu" "B.Mask" "B.Paste")
			(net "P12V_AUX")
		)
		(pad "2" smd circle
			(at -0.40005 0)
			(size 0 0)
			(layers "B.Cu" "B.Mask" "B.Paste")
			(net "P12V_HSC_GATE_RC")
		)
	)
	(footprint ""
		(layer "B.Cu")
		(at 43.265852 -384.28676 180)
		(property "Reference" "R723"
			(at 0 0 0)
			(layer "B.SilkS")
			(hide yes)
			(effects
				(font
					(size 1.27 1.27)
				)
				(justify mirror)
			)
		)
		(property "Value" ""
			(at 0 0 0)
			(layer "B.Fab")
			(effects
				(font
					(size 1.27 1.27)
				)
				(justify mirror)
			)
		)
		(duplicate_pad_numbers_are_jumpers no)
		(fp_line
			(start 0.32512 0.175006)
			(end 0.32512 -0.175006)
			(stroke
				(width 0.1)
				(type default)
			)
			(layer "B.Fab")
		)
		(fp_line
			(start 0.32512 -0.175006)
			(end -0.32512 -0.175006)
			(stroke
				(width 0.1)
				(type default)
			)
			(layer "B.Fab")
		)
		(fp_line
			(start -0.32512 0.175006)
			(end 0.32512 0.175006)
			(stroke
				(width 0.1)
				(type default)
			)
			(layer "B.Fab")
		)
		(fp_line
			(start -0.32512 -0.175006)
			(end -0.32512 0.175006)
			(stroke
				(width 0.1)
				(type default)
			)
			(layer "B.Fab")
		)
		(pad "1" smd rect
			(at 0.2667 0)
			(size 0.3048 0.381)
			(layers "B.Cu" "B.Mask" "B.Paste")
			(net "TEST1_RT_CPU1_P0")
		)
		(pad "2" smd rect
			(at -0.2667 0 180)
			(size 0.3048 0.381)
			(layers "B.Cu" "B.Mask" "B.Paste")
			(net "GND")
		)
	)
	(footprint ""
		(layer "B.Cu")
		(at 16.237712 -112.693958 180)
		(property "Reference" "C5236"
			(at 0 0 0)
			(layer "B.SilkS")
			(hide yes)
			(effects
				(font
					(size 1.27 1.27)
				)
				(justify mirror)
			)
		)
		(property "Value" ""
			(at 0 0 0)
			(layer "B.Fab")
			(effects
				(font
					(size 1.27 1.27)
				)
				(justify mirror)
			)
		)
		(duplicate_pad_numbers_are_jumpers no)
		(fp_line
			(start 0.7874 0.4064)
			(end 0.7874 -0.4064)
			(stroke
				(width 0.1524)
				(type default)
			)
			(layer "B.SilkS")
		)
		(fp_line
			(start 0.7874 -0.4064)
			(end -0.7874 -0.4064)
			(stroke
				(width 0.1524)
				(type default)
			)
			(layer "B.SilkS")
		)
		(fp_line
			(start -0.7874 0.4064)
			(end 0.7874 0.4064)
			(stroke
				(width 0.1524)
				(type default)
			)
			(layer "B.SilkS")
		)
		(fp_line
			(start -0.7874 -0.4064)
			(end -0.7874 0.4064)
			(stroke
				(width 0.1524)
				(type default)
			)
			(layer "B.SilkS")
		)
		(fp_line
			(start 0.67945 0.3048)
			(end 0.67945 -0.305054)
			(stroke
				(width 0.1)
				(type default)
			)
			(layer "B.Fab")
		)
		(fp_line
			(start 0.67945 -0.305054)
			(end 0.12065 -0.305054)
			(stroke
				(width 0.1)
				(type default)
			)
			(layer "B.Fab")
		)
		(fp_line
			(start 0.12065 0.3048)
			(end 0.67945 0.3048)
			(stroke
				(width 0.1)
				(type default)
			)
			(layer "B.Fab")
		)
		(fp_line
			(start 0.12065 0.2794)
			(end 0.12065 0.3048)
			(stroke
				(width 0.1)
				(type default)
			)
			(layer "B.Fab")
		)
		(fp_line
			(start 0.12065 -0.2794)
			(end -0.12065 -0.2794)
			(stroke
				(width 0.1)
				(type default)
			)
			(layer "B.Fab")
		)
		(fp_line
			(start 0.12065 -0.305054)
			(end 0.12065 -0.2794)
			(stroke
				(width 0.1)
				(type default)
			)
			(layer "B.Fab")
		)
		(fp_line
			(start -0.120396 0.3048)
			(end -0.120396 0.2794)
			(stroke
				(width 0.1)
				(type default)
			)
			(layer "B.Fab")
		)
		(fp_line
			(start -0.120396 0.2794)
			(end 0.12065 0.2794)
			(stroke
				(width 0.1)
				(type default)
			)
			(layer "B.Fab")
		)
		(fp_line
			(start -0.12065 -0.2794)
			(end -0.12065 -0.3048)
			(stroke
				(width 0.1)
				(type default)
			)
			(layer "B.Fab")
		)
		(fp_line
			(start -0.12065 -0.3048)
			(end -0.67945 -0.3048)
			(stroke
				(width 0.1)
				(type default)
			)
			(layer "B.Fab")
		)
		(fp_line
			(start -0.67945 0.3048)
			(end -0.120396 0.3048)
			(stroke
				(width 0.1)
				(type default)
			)
			(layer "B.Fab")
		)
		(fp_line
			(start -0.67945 -0.3048)
			(end -0.67945 0.3048)
			(stroke
				(width 0.1)
				(type default)
			)
			(layer "B.Fab")
		)
		(pad "1" smd circle
			(at 0.40005 0)
			(size 0 0)
			(layers "B.Cu" "B.Mask" "B.Paste")
			(net "PD_U5201_VREG")
		)
		(pad "2" smd circle
			(at -0.40005 0)
			(size 0 0)
			(layers "B.Cu" "B.Mask" "B.Paste")
			(net "GND")
		)
	)
	(footprint ""
		(layer "B.Cu")
		(at 495.90833 -142.853918 -90)
		(property "Reference" "X8028"
			(at 4.4577 -1.50495 270)
			(unlocked yes)
			(layer "B.SilkS")
			(effects
				(font
					(size 0.7874 0.5842)
					(thickness 0.1524)
				)
				(justify left mirror)
			)
		)
		(property "Value" ""
			(at 0 0 90)
			(layer "B.Fab")
			(effects
				(font
					(size 1.27 1.27)
				)
				(justify mirror)
			)
		)
		(property "Device Type" "TP_TDR_4P_FTS_TH-TP_TDR_4P_DIP,EMPTY,TP15"
			(at -1.30175 1.27 180)
			(unlocked yes)
			(layer "B.Fab")
			(hide yes)
			(effects
				(font
					(size 0.635 0.4064)
					(thickness 0.1524)
				)
				(justify mirror)
			)
		)
		(property "User Part Number" "N_A"
			(at -1.30175 1.27 180)
			(unlocked yes)
			(layer "Cmts.User")
			(hide yes)
			(effects
				(font
					(size 0.635 0.4064)
					(thickness 0.1524)
				)
				(justify mirror)
			)
		)
		(duplicate_pad_numbers_are_jumpers no)
		(fp_line
			(start -2.54 3.81)
			(end -2.54 3.6703)
			(stroke
				(width 0.1524)
				(type default)
			)
			(layer "B.SilkS")
		)
		(fp_line
			(start 0 3.81)
			(end -2.54 3.81)
			(stroke
				(width 0.1524)
				(type default)
			)
			(layer "B.SilkS")
		)
		(fp_line
			(start 0 3.175)
			(end 0 3.81)
			(stroke
				(width 0.1524)
				(type default)
			)
			(layer "B.SilkS")
		)
		(fp_line
			(start -2.54 1.4097)
			(end -2.54 1.1303)
			(stroke
				(width 0.1524)
				(type default)
			)
			(layer "B.SilkS")
		)
		(fp_line
			(start 0 0.635)
			(end 0 1.905)
			(stroke
				(width 0.1524)
				(type default)
			)
			(layer "B.SilkS")
		)
		(fp_line
			(start -2.54 -1.1303)
			(end -2.54 -1.27)
			(stroke
				(width 0.1524)
				(type default)
			)
			(layer "B.SilkS")
		)
		(fp_line
			(start -2.54 -1.27)
			(end 0 -1.27)
			(stroke
				(width 0.1524)
				(type default)
			)
			(layer "B.SilkS")
		)
		(fp_line
			(start 0 -1.27)
			(end 0 -0.635)
			(stroke
				(width 0.1524)
				(type default)
			)
			(layer "B.SilkS")
		)
		(fp_poly
			(pts
				(xy 0.761746 0) (xy 2.285746 -0.762) (xy 2.285746 0.762)
			)
			(stroke
				(width 0)
				(type default)
			)
			(fill yes)
			(layer "B.SilkS")
		)
		(fp_line
			(start -2.54 3.81)
			(end -2.54 -1.27)
			(stroke
				(width 0.1)
				(type default)
			)
			(layer "B.Fab")
		)
		(fp_line
			(start 0 3.81)
			(end -2.54 3.81)
			(stroke
				(width 0.1)
				(type default)
			)
			(layer "B.Fab")
		)
		(fp_line
			(start -2.54 -1.27)
			(end 0 -1.27)
			(stroke
				(width 0.1)
				(type default)
			)
			(layer "B.Fab")
		)
		(fp_line
			(start 0 -1.27)
			(end 0 3.81)
			(stroke
				(width 0.1)
				(type default)
			)
			(layer "B.Fab")
		)
		(fp_poly
			(pts
				(xy 0.761746 0) (xy 2.285746 -0.762) (xy 2.285746 0.762)
			)
			(stroke
				(width 0)
				(type default)
			)
			(fill yes)
			(layer "B.Fab")
		)
		(pad "1" thru_hole circle
			(at 0 0 90)
			(size 1.0033 1.0033)
			(drill 0.249936)
			(layers "*.Cu" "*.Mask")
			(remove_unused_layers no)
			(net "TDR_DIFF_85_IN6_DN")
			(clearance 0.10795)
			(padstack
				(mode front_inner_back)
				(layer "Inner"
					(shape circle)
					(size 0.8001 0.8001)
					(clearance 0.1524)
				)
				(layer "B.Cu"
					(shape circle)
					(size 1.0033 1.0033)
					(thermal_gap 0.10795)
					(clearance 0.10795)
				)
			)
		)
		(pad "2" thru_hole circle
			(at -2.54 0 90)
			(size 1.9939 1.9939)
			(drill 0.249936)
			(layers "*.Cu" "*.Mask")
			(remove_unused_layers no)
			(net "T1_GND")
			(clearance 0.10795)
			(padstack
				(mode front_inner_back)
				(layer "Inner"
					(shape circle)
					(size 0.8001 0.8001)
					(clearance 0.1524)
				)
				(layer "B.Cu"
					(shape circle)
					(size 1.9939 1.9939)
					(thermal_gap 0.10795)
					(clearance 0.10795)
				)
			)
		)
		(pad "3" thru_hole circle
			(at -2.54 2.54 90)
			(size 1.9939 1.9939)
			(drill 0.249936)
			(layers "*.Cu" "*.Mask")
			(remove_unused_layers no)
			(net "T1_GND")
			(clearance 0.10795)
			(padstack
				(mode front_inner_back)
				(layer "Inner"
					(shape circle)
					(size 0.8001 0.8001)
					(clearance 0.1524)
				)
				(layer "B.Cu"
					(shape circle)
					(size 1.9939 1.9939)
					(thermal_gap 0.10795)
					(clearance 0.10795)
				)
			)
		)
		(pad "4" thru_hole circle
			(at 0 2.54 90)
			(size 1.0033 1.0033)
			(drill 0.249936)
			(layers "*.Cu" "*.Mask")
			(remove_unused_layers no)
			(net "TDR_DIFF_85_IN6_DP")
			(clearance 0.10795)
			(padstack
				(mode front_inner_back)
				(layer "Inner"
					(shape circle)
					(size 0.8001 0.8001)
					(clearance 0.1524)
				)
				(layer "B.Cu"
					(shape circle)
					(size 1.0033 1.0033)
					(thermal_gap 0.10795)
					(clearance 0.10795)
				)
			)
		)
	)
	(footprint ""
		(layer "B.Cu")
		(at 299.06849 -193.99631)
		(property "Reference" "C92"
			(at 0 0 0)
			(layer "B.SilkS")
			(hide yes)
			(effects
				(font
					(size 1.27 1.27)
				)
				(justify mirror)
			)
		)
		(property "Value" ""
			(at 0 0 0)
			(layer "B.Fab")
			(effects
				(font
					(size 1.27 1.27)
				)
				(justify mirror)
			)
		)
		(duplicate_pad_numbers_are_jumpers no)
		(fp_line
			(start -0.7874 -0.4064)
			(end -0.7874 0.4064)
			(stroke
				(width 0.1524)
				(type default)
			)
			(layer "B.SilkS")
		)
		(fp_line
			(start -0.7874 0.4064)
			(end 0.7874 0.4064)
			(stroke
				(width 0.1524)
				(type default)
			)
			(layer "B.SilkS")
		)
		(fp_line
			(start 0.7874 -0.4064)
			(end -0.7874 -0.4064)
			(stroke
				(width 0.1524)
				(type default)
			)
			(layer "B.SilkS")
		)
		(fp_line
			(start 0.7874 0.4064)
			(end 0.7874 -0.4064)
			(stroke
				(width 0.1524)
				(type default)
			)
			(layer "B.SilkS")
		)
		(fp_line
			(start -0.67945 -0.3048)
			(end -0.67945 0.3048)
			(stroke
				(width 0.1)
				(type default)
			)
			(layer "B.Fab")
		)
		(fp_line
			(start -0.67945 0.3048)
			(end -0.120396 0.3048)
			(stroke
				(width 0.1)
				(type default)
			)
			(layer "B.Fab")
		)
		(fp_line
			(start -0.12065 -0.3048)
			(end -0.67945 -0.3048)
			(stroke
				(width 0.1)
				(type default)
			)
			(layer "B.Fab")
		)
		(fp_line
			(start -0.12065 -0.2794)
			(end -0.12065 -0.3048)
			(stroke
				(width 0.1)
				(type default)
			)
			(layer "B.Fab")
		)
		(fp_line
			(start -0.120396 0.2794)
			(end 0.12065 0.2794)
			(stroke
				(width 0.1)
				(type default)
			)
			(layer "B.Fab")
		)
		(fp_line
			(start -0.120396 0.3048)
			(end -0.120396 0.2794)
			(stroke
				(width 0.1)
				(type default)
			)
			(layer "B.Fab")
		)
		(fp_line
			(start 0.12065 -0.305054)
			(end 0.12065 -0.2794)
			(stroke
				(width 0.1)
				(type default)
			)
			(layer "B.Fab")
		)
		(fp_line
			(start 0.12065 -0.2794)
			(end -0.12065 -0.2794)
			(stroke
				(width 0.1)
				(type default)
			)
			(layer "B.Fab")
		)
		(fp_line
			(start 0.12065 0.2794)
			(end 0.12065 0.3048)
			(stroke
				(width 0.1)
				(type default)
			)
			(layer "B.Fab")
		)
		(fp_line
			(start 0.12065 0.3048)
			(end 0.67945 0.3048)
			(stroke
				(width 0.1)
				(type default)
			)
			(layer "B.Fab")
		)
		(fp_line
			(start 0.67945 -0.305054)
			(end 0.12065 -0.305054)
			(stroke
				(width 0.1)
				(type default)
			)
			(layer "B.Fab")
		)
		(fp_line
			(start 0.67945 0.3048)
			(end 0.67945 -0.305054)
			(stroke
				(width 0.1)
				(type default)
			)
			(layer "B.Fab")
		)
		(pad "1" smd circle
			(at 0.40005 0 180)
			(size 0 0)
			(layers "B.Cu" "B.Mask" "B.Paste")
			(net "P3V3_AUX")
		)
		(pad "2" smd circle
			(at -0.40005 0 180)
			(size 0 0)
			(layers "B.Cu" "B.Mask" "B.Paste")
			(net "GND")
		)
	)
	(footprint ""
		(layer "B.Cu")
		(at 121.960386 -268.418564)
		(property "Reference" "C2370"
			(at 0 0 0)
			(layer "B.SilkS")
			(hide yes)
			(effects
				(font
					(size 1.27 1.27)
				)
				(justify mirror)
			)
		)
		(property "Value" ""
			(at 0 0 0)
			(layer "B.Fab")
			(effects
				(font
					(size 1.27 1.27)
				)
				(justify mirror)
			)
		)
		(duplicate_pad_numbers_are_jumpers no)
		(fp_line
			(start -0.7874 -0.4064)
			(end -0.7874 0.4064)
			(stroke
				(width 0.1524)
				(type default)
			)
			(layer "B.SilkS")
		)
		(fp_line
			(start -0.7874 0.4064)
			(end 0.7874 0.4064)
			(stroke
				(width 0.1524)
				(type default)
			)
			(layer "B.SilkS")
		)
		(fp_line
			(start 0.7874 -0.4064)
			(end -0.7874 -0.4064)
			(stroke
				(width 0.1524)
				(type default)
			)
			(layer "B.SilkS")
		)
		(fp_line
			(start 0.7874 0.4064)
			(end 0.7874 -0.4064)
			(stroke
				(width 0.1524)
				(type default)
			)
			(layer "B.SilkS")
		)
		(fp_line
			(start -0.67945 -0.3048)
			(end -0.67945 0.3048)
			(stroke
				(width 0.1)
				(type default)
			)
			(layer "B.Fab")
		)
		(fp_line
			(start -0.67945 0.3048)
			(end -0.120396 0.3048)
			(stroke
				(width 0.1)
				(type default)
			)
			(layer "B.Fab")
		)
		(fp_line
			(start -0.12065 -0.3048)
			(end -0.67945 -0.3048)
			(stroke
				(width 0.1)
				(type default)
			)
			(layer "B.Fab")
		)
		(fp_line
			(start -0.12065 -0.2794)
			(end -0.12065 -0.3048)
			(stroke
				(width 0.1)
				(type default)
			)
			(layer "B.Fab")
		)
		(fp_line
			(start -0.120396 0.2794)
			(end 0.12065 0.2794)
			(stroke
				(width 0.1)
				(type default)
			)
			(layer "B.Fab")
		)
		(fp_line
			(start -0.120396 0.3048)
			(end -0.120396 0.2794)
			(stroke
				(width 0.1)
				(type default)
			)
			(layer "B.Fab")
		)
		(fp_line
			(start 0.12065 -0.305054)
			(end 0.12065 -0.2794)
			(stroke
				(width 0.1)
				(type default)
			)
			(layer "B.Fab")
		)
		(fp_line
			(start 0.12065 -0.2794)
			(end -0.12065 -0.2794)
			(stroke
				(width 0.1)
				(type default)
			)
			(layer "B.Fab")
		)
		(fp_line
			(start 0.12065 0.2794)
			(end 0.12065 0.3048)
			(stroke
				(width 0.1)
				(type default)
			)
			(layer "B.Fab")
		)
		(fp_line
			(start 0.12065 0.3048)
			(end 0.67945 0.3048)
			(stroke
				(width 0.1)
				(type default)
			)
			(layer "B.Fab")
		)
		(fp_line
			(start 0.67945 -0.305054)
			(end 0.12065 -0.305054)
			(stroke
				(width 0.1)
				(type default)
			)
			(layer "B.Fab")
		)
		(fp_line
			(start 0.67945 0.3048)
			(end 0.67945 -0.305054)
			(stroke
				(width 0.1)
				(type default)
			)
			(layer "B.Fab")
		)
		(pad "1" smd circle
			(at 0.40005 0 180)
			(size 0 0)
			(layers "B.Cu" "B.Mask" "B.Paste")
			(net "PVDDCR_CPU1_P1")
		)
		(pad "2" smd circle
			(at -0.40005 0 180)
			(size 0 0)
			(layers "B.Cu" "B.Mask" "B.Paste")
			(net "GND")
		)
	)
	(footprint ""
		(layer "B.Cu")
		(at 412.256986 -151.346916 90)
		(property "Reference" "PC1856"
			(at 0 0 90)
			(layer "B.SilkS")
			(hide yes)
			(effects
				(font
					(size 1.27 1.27)
				)
				(justify mirror)
			)
		)
		(property "Value" ""
			(at 0 0 90)
			(layer "B.Fab")
			(effects
				(font
					(size 1.27 1.27)
				)
				(justify mirror)
			)
		)
		(duplicate_pad_numbers_are_jumpers no)
		(fp_line
			(start 1.524 -0.762)
			(end -1.524 -0.762)
			(stroke
				(width 0.1524)
				(type default)
			)
			(layer "B.SilkS")
		)
		(fp_line
			(start -1.524 -0.762)
			(end -1.524 0.762)
			(stroke
				(width 0.1524)
				(type default)
			)
			(layer "B.SilkS")
		)
		(fp_line
			(start 1.524 0.762)
			(end 1.524 -0.762)
			(stroke
				(width 0.1524)
				(type default)
			)
			(layer "B.SilkS")
		)
		(fp_line
			(start -1.524 0.762)
			(end 1.524 0.762)
			(stroke
				(width 0.1524)
				(type default)
			)
			(layer "B.SilkS")
		)
		(fp_line
			(start 1.1049 -0.724916)
			(end 1.1049 0.724916)
			(stroke
				(width 0.1)
				(type default)
			)
			(layer "B.Fab")
		)
		(fp_line
			(start -1.1049 -0.724916)
			(end 1.1049 -0.724916)
			(stroke
				(width 0.1)
				(type default)
			)
			(layer "B.Fab")
		)
		(fp_line
			(start 1.1049 0.724916)
			(end -1.1049 0.724916)
			(stroke
				(width 0.1)
				(type default)
			)
			(layer "B.Fab")
		)
		(fp_line
			(start -1.1049 0.724916)
			(end -1.1049 -0.724916)
			(stroke
				(width 0.1)
				(type default)
			)
			(layer "B.Fab")
		)
		(pad "1" smd rect
			(at 0.889 0 90)
			(size 1.016 1.27)
			(layers "B.Cu" "B.Mask" "B.Paste")
			(net "P5V_AUX")
		)
		(pad "2" smd rect
			(at -0.889 0 90)
			(size 1.016 1.27)
			(layers "B.Cu" "B.Mask" "B.Paste")
			(net "GND")
		)
	)
	(footprint ""
		(layer "B.Cu")
		(at 117.896386 -249.368564)
		(property "Reference" "C2297"
			(at 0 0 0)
			(layer "B.SilkS")
			(hide yes)
			(effects
				(font
					(size 1.27 1.27)
				)
				(justify mirror)
			)
		)
		(property "Value" ""
			(at 0 0 0)
			(layer "B.Fab")
			(effects
				(font
					(size 1.27 1.27)
				)
				(justify mirror)
			)
		)
		(duplicate_pad_numbers_are_jumpers no)
		(fp_line
			(start -0.7874 -0.4064)
			(end -0.7874 0.4064)
			(stroke
				(width 0.1524)
				(type default)
			)
			(layer "B.SilkS")
		)
		(fp_line
			(start -0.7874 0.4064)
			(end 0.7874 0.4064)
			(stroke
				(width 0.1524)
				(type default)
			)
			(layer "B.SilkS")
		)
		(fp_line
			(start 0.7874 -0.4064)
			(end -0.7874 -0.4064)
			(stroke
				(width 0.1524)
				(type default)
			)
			(layer "B.SilkS")
		)
		(fp_line
			(start 0.7874 0.4064)
			(end 0.7874 -0.4064)
			(stroke
				(width 0.1524)
				(type default)
			)
			(layer "B.SilkS")
		)
		(fp_line
			(start -0.67945 -0.3048)
			(end -0.67945 0.3048)
			(stroke
				(width 0.1)
				(type default)
			)
			(layer "B.Fab")
		)
		(fp_line
			(start -0.67945 0.3048)
			(end -0.120396 0.3048)
			(stroke
				(width 0.1)
				(type default)
			)
			(layer "B.Fab")
		)
		(fp_line
			(start -0.12065 -0.3048)
			(end -0.67945 -0.3048)
			(stroke
				(width 0.1)
				(type default)
			)
			(layer "B.Fab")
		)
		(fp_line
			(start -0.12065 -0.2794)
			(end -0.12065 -0.3048)
			(stroke
				(width 0.1)
				(type default)
			)
			(layer "B.Fab")
		)
		(fp_line
			(start -0.120396 0.2794)
			(end 0.12065 0.2794)
			(stroke
				(width 0.1)
				(type default)
			)
			(layer "B.Fab")
		)
		(fp_line
			(start -0.120396 0.3048)
			(end -0.120396 0.2794)
			(stroke
				(width 0.1)
				(type default)
			)
			(layer "B.Fab")
		)
		(fp_line
			(start 0.12065 -0.305054)
			(end 0.12065 -0.2794)
			(stroke
				(width 0.1)
				(type default)
			)
			(layer "B.Fab")
		)
		(fp_line
			(start 0.12065 -0.2794)
			(end -0.12065 -0.2794)
			(stroke
				(width 0.1)
				(type default)
			)
			(layer "B.Fab")
		)
		(fp_line
			(start 0.12065 0.2794)
			(end 0.12065 0.3048)
			(stroke
				(width 0.1)
				(type default)
			)
			(layer "B.Fab")
		)
		(fp_line
			(start 0.12065 0.3048)
			(end 0.67945 0.3048)
			(stroke
				(width 0.1)
				(type default)
			)
			(layer "B.Fab")
		)
		(fp_line
			(start 0.67945 -0.305054)
			(end 0.12065 -0.305054)
			(stroke
				(width 0.1)
				(type default)
			)
			(layer "B.Fab")
		)
		(fp_line
			(start 0.67945 0.3048)
			(end 0.67945 -0.305054)
			(stroke
				(width 0.1)
				(type default)
			)
			(layer "B.Fab")
		)
		(pad "1" smd circle
			(at 0.40005 0 180)
			(size 0 0)
			(layers "B.Cu" "B.Mask" "B.Paste")
			(net "PVDDCR_CPU0_P1")
		)
		(pad "2" smd circle
			(at -0.40005 0 180)
			(size 0 0)
			(layers "B.Cu" "B.Mask" "B.Paste")
			(net "GND")
		)
	)
	(footprint ""
		(layer "B.Cu")
		(at 312.341006 -416.899344 90)
		(property "Reference" "C6537"
			(at 0 0 90)
			(layer "B.SilkS")
			(hide yes)
			(effects
				(font
					(size 1.27 1.27)
				)
				(justify mirror)
			)
		)
		(property "Value" ""
			(at 0 0 90)
			(layer "B.Fab")
			(effects
				(font
					(size 1.27 1.27)
				)
				(justify mirror)
			)
		)
		(duplicate_pad_numbers_are_jumpers no)
		(fp_line
			(start 0.299974 -0.150114)
			(end -0.299974 -0.150114)
			(stroke
				(width 0.1)
				(type default)
			)
			(layer "B.Fab")
		)
		(fp_line
			(start -0.299974 -0.150114)
			(end -0.299974 0.150114)
			(stroke
				(width 0.1)
				(type default)
			)
			(layer "B.Fab")
		)
		(fp_line
			(start 0.299974 0.150114)
			(end 0.299974 -0.150114)
			(stroke
				(width 0.1)
				(type default)
			)
			(layer "B.Fab")
		)
		(fp_line
			(start -0.299974 0.150114)
			(end 0.299974 0.150114)
			(stroke
				(width 0.1)
				(type default)
			)
			(layer "B.Fab")
		)
		(pad "1" smd rect
			(at 0.2667 0 270)
			(size 0.3048 0.381)
			(layers "B.Cu" "B.Mask" "B.Paste")
			(net "P5E_CPU0_P1_TX_BUF_C_DP<2>")
		)
		(pad "2" smd rect
			(at -0.2667 0 270)
			(size 0.3048 0.381)
			(layers "B.Cu" "B.Mask" "B.Paste")
			(net "P5E_CPU0_P1_TX_BUF_DP<2>")
		)
	)
	(footprint ""
		(layer "B.Cu")
		(at 419.062916 -172.407072 90)
		(property "Reference" "PC615_3"
			(at 0 0 90)
			(layer "B.SilkS")
			(hide yes)
			(effects
				(font
					(size 1.27 1.27)
				)
				(justify mirror)
			)
		)
		(property "Value" ""
			(at 0 0 90)
			(layer "B.Fab")
			(effects
				(font
					(size 1.27 1.27)
				)
				(justify mirror)
			)
		)
		(duplicate_pad_numbers_are_jumpers no)
		(fp_line
			(start 1.524 -0.762)
			(end -1.524 -0.762)
			(stroke
				(width 0.1524)
				(type default)
			)
			(layer "B.SilkS")
		)
		(fp_line
			(start -1.524 -0.762)
			(end -1.524 0.762)
			(stroke
				(width 0.1524)
				(type default)
			)
			(layer "B.SilkS")
		)
		(fp_line
			(start 1.524 0.762)
			(end 1.524 -0.762)
			(stroke
				(width 0.1524)
				(type default)
			)
			(layer "B.SilkS")
		)
		(fp_line
			(start -1.524 0.762)
			(end 1.524 0.762)
			(stroke
				(width 0.1524)
				(type default)
			)
			(layer "B.SilkS")
		)
		(fp_line
			(start 1.1049 -0.724916)
			(end 1.1049 0.724916)
			(stroke
				(width 0.1)
				(type default)
			)
			(layer "B.Fab")
		)
		(fp_line
			(start -1.1049 -0.724916)
			(end 1.1049 -0.724916)
			(stroke
				(width 0.1)
				(type default)
			)
			(layer "B.Fab")
		)
		(fp_line
			(start 1.1049 0.724916)
			(end -1.1049 0.724916)
			(stroke
				(width 0.1)
				(type default)
			)
			(layer "B.Fab")
		)
		(fp_line
			(start -1.1049 0.724916)
			(end -1.1049 -0.724916)
			(stroke
				(width 0.1)
				(type default)
			)
			(layer "B.Fab")
		)
		(pad "1" smd rect
			(at 0.889 0 90)
			(size 1.016 1.27)
			(layers "B.Cu" "B.Mask" "B.Paste")
			(net "PVDDCR_SOC_P0")
		)
		(pad "2" smd rect
			(at -0.889 0 90)
			(size 1.016 1.27)
			(layers "B.Cu" "B.Mask" "B.Paste")
			(net "GND")
		)
	)
	(footprint ""
		(layer "B.Cu")
		(at 358.796082 -258.795012 180)
		(property "Reference" "C2616"
			(at 0 0 0)
			(layer "B.SilkS")
			(hide yes)
			(effects
				(font
					(size 1.27 1.27)
				)
				(justify mirror)
			)
		)
		(property "Value" ""
			(at 0 0 0)
			(layer "B.Fab")
			(effects
				(font
					(size 1.27 1.27)
				)
				(justify mirror)
			)
		)
		(duplicate_pad_numbers_are_jumpers no)
		(fp_line
			(start 0.7874 0.4064)
			(end 0.7874 -0.4064)
			(stroke
				(width 0.1524)
				(type default)
			)
			(layer "B.SilkS")
		)
		(fp_line
			(start 0.7874 -0.4064)
			(end -0.7874 -0.4064)
			(stroke
				(width 0.1524)
				(type default)
			)
			(layer "B.SilkS")
		)
		(fp_line
			(start -0.7874 0.4064)
			(end 0.7874 0.4064)
			(stroke
				(width 0.1524)
				(type default)
			)
			(layer "B.SilkS")
		)
		(fp_line
			(start -0.7874 -0.4064)
			(end -0.7874 0.4064)
			(stroke
				(width 0.1524)
				(type default)
			)
			(layer "B.SilkS")
		)
		(fp_line
			(start 0.67945 0.3048)
			(end 0.67945 -0.305054)
			(stroke
				(width 0.1)
				(type default)
			)
			(layer "B.Fab")
		)
		(fp_line
			(start 0.67945 -0.305054)
			(end 0.12065 -0.305054)
			(stroke
				(width 0.1)
				(type default)
			)
			(layer "B.Fab")
		)
		(fp_line
			(start 0.12065 0.3048)
			(end 0.67945 0.3048)
			(stroke
				(width 0.1)
				(type default)
			)
			(layer "B.Fab")
		)
		(fp_line
			(start 0.12065 0.2794)
			(end 0.12065 0.3048)
			(stroke
				(width 0.1)
				(type default)
			)
			(layer "B.Fab")
		)
		(fp_line
			(start 0.12065 -0.2794)
			(end -0.12065 -0.2794)
			(stroke
				(width 0.1)
				(type default)
			)
			(layer "B.Fab")
		)
		(fp_line
			(start 0.12065 -0.305054)
			(end 0.12065 -0.2794)
			(stroke
				(width 0.1)
				(type default)
			)
			(layer "B.Fab")
		)
		(fp_line
			(start -0.120396 0.3048)
			(end -0.120396 0.2794)
			(stroke
				(width 0.1)
				(type default)
			)
			(layer "B.Fab")
		)
		(fp_line
			(start -0.120396 0.2794)
			(end 0.12065 0.2794)
			(stroke
				(width 0.1)
				(type default)
			)
			(layer "B.Fab")
		)
		(fp_line
			(start -0.12065 -0.2794)
			(end -0.12065 -0.3048)
			(stroke
				(width 0.1)
				(type default)
			)
			(layer "B.Fab")
		)
		(fp_line
			(start -0.12065 -0.3048)
			(end -0.67945 -0.3048)
			(stroke
				(width 0.1)
				(type default)
			)
			(layer "B.Fab")
		)
		(fp_line
			(start -0.67945 0.3048)
			(end -0.120396 0.3048)
			(stroke
				(width 0.1)
				(type default)
			)
			(layer "B.Fab")
		)
		(fp_line
			(start -0.67945 -0.3048)
			(end -0.67945 0.3048)
			(stroke
				(width 0.1)
				(type default)
			)
			(layer "B.Fab")
		)
		(pad "1" smd circle
			(at 0.40005 0)
			(size 0 0)
			(layers "B.Cu" "B.Mask" "B.Paste")
			(net "PVDD11_S3_P0")
		)
		(pad "2" smd circle
			(at -0.40005 0)
			(size 0 0)
			(layers "B.Cu" "B.Mask" "B.Paste")
			(net "GND")
		)
	)
	(footprint ""
		(layer "B.Cu")
		(at 244.475 -229.489)
		(property "Reference" "R406"
			(at 0 0 0)
			(layer "B.SilkS")
			(hide yes)
			(effects
				(font
					(size 1.27 1.27)
				)
				(justify mirror)
			)
		)
		(property "Value" ""
			(at 0 0 0)
			(layer "B.Fab")
			(effects
				(font
					(size 1.27 1.27)
				)
				(justify mirror)
			)
		)
		(duplicate_pad_numbers_are_jumpers no)
		(fp_line
			(start -0.7874 -0.4064)
			(end -0.7874 0.4064)
			(stroke
				(width 0.1524)
				(type default)
			)
			(layer "B.SilkS")
		)
		(fp_line
			(start -0.7874 0.4064)
			(end 0.7874 0.4064)
			(stroke
				(width 0.1524)
				(type default)
			)
			(layer "B.SilkS")
		)
		(fp_line
			(start 0.7874 -0.4064)
			(end -0.7874 -0.4064)
			(stroke
				(width 0.1524)
				(type default)
			)
			(layer "B.SilkS")
		)
		(fp_line
			(start 0.7874 0.4064)
			(end 0.7874 -0.4064)
			(stroke
				(width 0.1524)
				(type default)
			)
			(layer "B.SilkS")
		)
		(fp_line
			(start -0.67945 -0.3048)
			(end -0.67945 0.3048)
			(stroke
				(width 0.1)
				(type default)
			)
			(layer "B.Fab")
		)
		(fp_line
			(start -0.67945 0.3048)
			(end -0.120396 0.3048)
			(stroke
				(width 0.1)
				(type default)
			)
			(layer "B.Fab")
		)
		(fp_line
			(start -0.12065 -0.3048)
			(end -0.67945 -0.3048)
			(stroke
				(width 0.1)
				(type default)
			)
			(layer "B.Fab")
		)
		(fp_line
			(start -0.12065 -0.2794)
			(end -0.12065 -0.3048)
			(stroke
				(width 0.1)
				(type default)
			)
			(layer "B.Fab")
		)
		(fp_line
			(start -0.120396 0.2794)
			(end 0.12065 0.2794)
			(stroke
				(width 0.1)
				(type default)
			)
			(layer "B.Fab")
		)
		(fp_line
			(start -0.120396 0.3048)
			(end -0.120396 0.2794)
			(stroke
				(width 0.1)
				(type default)
			)
			(layer "B.Fab")
		)
		(fp_line
			(start 0.12065 -0.305054)
			(end 0.12065 -0.2794)
			(stroke
				(width 0.1)
				(type default)
			)
			(layer "B.Fab")
		)
		(fp_line
			(start 0.12065 -0.2794)
			(end -0.12065 -0.2794)
			(stroke
				(width 0.1)
				(type default)
			)
			(layer "B.Fab")
		)
		(fp_line
			(start 0.12065 0.2794)
			(end 0.12065 0.3048)
			(stroke
				(width 0.1)
				(type default)
			)
			(layer "B.Fab")
		)
		(fp_line
			(start 0.12065 0.3048)
			(end 0.67945 0.3048)
			(stroke
				(width 0.1)
				(type default)
			)
			(layer "B.Fab")
		)
		(fp_line
			(start 0.67945 -0.305054)
			(end 0.12065 -0.305054)
			(stroke
				(width 0.1)
				(type default)
			)
			(layer "B.Fab")
		)
		(fp_line
			(start 0.67945 0.3048)
			(end 0.67945 -0.305054)
			(stroke
				(width 0.1)
				(type default)
			)
			(layer "B.Fab")
		)
		(pad "1" smd circle
			(at 0.40005 0 180)
			(size 0 0)
			(layers "B.Cu" "B.Mask" "B.Paste")
			(net "PVDD18_S5_P0")
		)
		(pad "2" smd circle
			(at -0.40005 0 180)
			(size 0 0)
			(layers "B.Cu" "B.Mask" "B.Paste")
			(net "SMB_CPU0_CPU1_SEC_SDA_R2")
		)
	)
	(footprint ""
		(layer "B.Cu")
		(at 338.306156 -395.148562 90)
		(property "Reference" "C654"
			(at 0 0 90)
			(layer "B.SilkS")
			(hide yes)
			(effects
				(font
					(size 1.27 1.27)
				)
				(justify mirror)
			)
		)
		(property "Value" ""
			(at 0 0 90)
			(layer "B.Fab")
			(effects
				(font
					(size 1.27 1.27)
				)
				(justify mirror)
			)
		)
		(duplicate_pad_numbers_are_jumpers no)
		(fp_line
			(start 0.299974 -0.150114)
			(end -0.299974 -0.150114)
			(stroke
				(width 0.1)
				(type default)
			)
			(layer "B.Fab")
		)
		(fp_line
			(start -0.299974 -0.150114)
			(end -0.299974 0.150114)
			(stroke
				(width 0.1)
				(type default)
			)
			(layer "B.Fab")
		)
		(fp_line
			(start 0.299974 0.150114)
			(end 0.299974 -0.150114)
			(stroke
				(width 0.1)
				(type default)
			)
			(layer "B.Fab")
		)
		(fp_line
			(start -0.299974 0.150114)
			(end 0.299974 0.150114)
			(stroke
				(width 0.1)
				(type default)
			)
			(layer "B.Fab")
		)
		(pad "1" smd rect
			(at 0.2667 0 270)
			(size 0.3048 0.381)
			(layers "B.Cu" "B.Mask" "B.Paste")
			(net "P0V9_CPU0_RT1_2A")
		)
		(pad "2" smd rect
			(at -0.2667 0 270)
			(size 0.3048 0.381)
			(layers "B.Cu" "B.Mask" "B.Paste")
			(net "GND")
		)
	)
	(footprint ""
		(layer "B.Cu")
		(at 185.240676 -13.60043 -90)
		(property "Reference" "R6005"
			(at 0 0 90)
			(layer "B.SilkS")
			(hide yes)
			(effects
				(font
					(size 1.27 1.27)
				)
				(justify mirror)
			)
		)
		(property "Value" ""
			(at 0 0 90)
			(layer "B.Fab")
			(effects
				(font
					(size 1.27 1.27)
				)
				(justify mirror)
			)
		)
		(duplicate_pad_numbers_are_jumpers no)
		(fp_line
			(start -0.7874 0.4064)
			(end 0.7874 0.4064)
			(stroke
				(width 0.1524)
				(type default)
			)
			(layer "B.SilkS")
		)
		(fp_line
			(start 0.7874 0.4064)
			(end 0.7874 -0.4064)
			(stroke
				(width 0.1524)
				(type default)
			)
			(layer "B.SilkS")
		)
		(fp_line
			(start -0.7874 -0.4064)
			(end -0.7874 0.4064)
			(stroke
				(width 0.1524)
				(type default)
			)
			(layer "B.SilkS")
		)
		(fp_line
			(start 0.7874 -0.4064)
			(end -0.7874 -0.4064)
			(stroke
				(width 0.1524)
				(type default)
			)
			(layer "B.SilkS")
		)
		(fp_line
			(start -0.67945 0.3048)
			(end -0.120396 0.3048)
			(stroke
				(width 0.1)
				(type default)
			)
			(layer "B.Fab")
		)
		(fp_line
			(start -0.120396 0.3048)
			(end -0.120396 0.2794)
			(stroke
				(width 0.1)
				(type default)
			)
			(layer "B.Fab")
		)
		(fp_line
			(start 0.12065 0.3048)
			(end 0.67945 0.3048)
			(stroke
				(width 0.1)
				(type default)
			)
			(layer "B.Fab")
		)
		(fp_line
			(start 0.67945 0.3048)
			(end 0.67945 -0.305054)
			(stroke
				(width 0.1)
				(type default)
			)
			(layer "B.Fab")
		)
		(fp_line
			(start -0.120396 0.2794)
			(end 0.12065 0.2794)
			(stroke
				(width 0.1)
				(type default)
			)
			(layer "B.Fab")
		)
		(fp_line
			(start 0.12065 0.2794)
			(end 0.12065 0.3048)
			(stroke
				(width 0.1)
				(type default)
			)
			(layer "B.Fab")
		)
		(fp_line
			(start -0.12065 -0.2794)
			(end -0.12065 -0.3048)
			(stroke
				(width 0.1)
				(type default)
			)
			(layer "B.Fab")
		)
		(fp_line
			(start 0.12065 -0.2794)
			(end -0.12065 -0.2794)
			(stroke
				(width 0.1)
				(type default)
			)
			(layer "B.Fab")
		)
		(fp_line
			(start -0.67945 -0.3048)
			(end -0.67945 0.3048)
			(stroke
				(width 0.1)
				(type default)
			)
			(layer "B.Fab")
		)
		(fp_line
			(start -0.12065 -0.3048)
			(end -0.67945 -0.3048)
			(stroke
				(width 0.1)
				(type default)
			)
			(layer "B.Fab")
		)
		(fp_line
			(start 0.12065 -0.305054)
			(end 0.12065 -0.2794)
			(stroke
				(width 0.1)
				(type default)
			)
			(layer "B.Fab")
		)
		(fp_line
			(start 0.67945 -0.305054)
			(end 0.12065 -0.305054)
			(stroke
				(width 0.1)
				(type default)
			)
			(layer "B.Fab")
		)
		(pad "1" smd circle
			(at 0.40005 0 90)
			(size 0 0)
			(layers "B.Cu" "B.Mask" "B.Paste")
			(net "I3C_SCM_2_SDA")
		)
		(pad "2" smd circle
			(at -0.40005 0 90)
			(size 0 0)
			(layers "B.Cu" "B.Mask" "B.Paste")
			(net "I3C_SCM_2_R_SDA")
		)
	)
	(footprint ""
		(layer "B.Cu")
		(at 152.202642 -80.81518)
		(property "Reference" "PC867"
			(at 0 0 0)
			(layer "B.SilkS")
			(hide yes)
			(effects
				(font
					(size 1.27 1.27)
				)
				(justify mirror)
			)
		)
		(property "Value" ""
			(at 0 0 0)
			(layer "B.Fab")
			(effects
				(font
					(size 1.27 1.27)
				)
				(justify mirror)
			)
		)
		(duplicate_pad_numbers_are_jumpers no)
		(fp_line
			(start -1.524 -0.762)
			(end -1.524 0.762)
			(stroke
				(width 0.1524)
				(type default)
			)
			(layer "B.SilkS")
		)
		(fp_line
			(start -1.524 0.762)
			(end 1.524 0.762)
			(stroke
				(width 0.1524)
				(type default)
			)
			(layer "B.SilkS")
		)
		(fp_line
			(start 1.524 -0.762)
			(end -1.524 -0.762)
			(stroke
				(width 0.1524)
				(type default)
			)
			(layer "B.SilkS")
		)
		(fp_line
			(start 1.524 0.762)
			(end 1.524 -0.762)
			(stroke
				(width 0.1524)
				(type default)
			)
			(layer "B.SilkS")
		)
		(fp_line
			(start -1.1049 -0.724916)
			(end 1.1049 -0.724916)
			(stroke
				(width 0.1)
				(type default)
			)
			(layer "B.Fab")
		)
		(fp_line
			(start -1.1049 0.724916)
			(end -1.1049 -0.724916)
			(stroke
				(width 0.1)
				(type default)
			)
			(layer "B.Fab")
		)
		(fp_line
			(start 1.1049 -0.724916)
			(end 1.1049 0.724916)
			(stroke
				(width 0.1)
				(type default)
			)
			(layer "B.Fab")
		)
		(fp_line
			(start 1.1049 0.724916)
			(end -1.1049 0.724916)
			(stroke
				(width 0.1)
				(type default)
			)
			(layer "B.Fab")
		)
		(pad "1" smd rect
			(at 0.889 0)
			(size 1.016 1.27)
			(layers "B.Cu" "B.Mask" "B.Paste")
			(net "P1V8_AUX")
		)
		(pad "2" smd rect
			(at -0.889 0)
			(size 1.016 1.27)
			(layers "B.Cu" "B.Mask" "B.Paste")
			(net "GND")
		)
	)
	(footprint ""
		(layer "B.Cu")
		(at 365.835692 -260.305042)
		(property "Reference" "C2531"
			(at 0 0 0)
			(layer "B.SilkS")
			(hide yes)
			(effects
				(font
					(size 1.27 1.27)
				)
				(justify mirror)
			)
		)
		(property "Value" ""
			(at 0 0 0)
			(layer "B.Fab")
			(effects
				(font
					(size 1.27 1.27)
				)
				(justify mirror)
			)
		)
		(duplicate_pad_numbers_are_jumpers no)
		(fp_line
			(start -0.7874 -0.4064)
			(end -0.7874 0.4064)
			(stroke
				(width 0.1524)
				(type default)
			)
			(layer "B.SilkS")
		)
		(fp_line
			(start -0.7874 0.4064)
			(end 0.7874 0.4064)
			(stroke
				(width 0.1524)
				(type default)
			)
			(layer "B.SilkS")
		)
		(fp_line
			(start 0.7874 -0.4064)
			(end -0.7874 -0.4064)
			(stroke
				(width 0.1524)
				(type default)
			)
			(layer "B.SilkS")
		)
		(fp_line
			(start 0.7874 0.4064)
			(end 0.7874 -0.4064)
			(stroke
				(width 0.1524)
				(type default)
			)
			(layer "B.SilkS")
		)
		(fp_line
			(start -0.67945 -0.3048)
			(end -0.67945 0.3048)
			(stroke
				(width 0.1)
				(type default)
			)
			(layer "B.Fab")
		)
		(fp_line
			(start -0.67945 0.3048)
			(end -0.120396 0.3048)
			(stroke
				(width 0.1)
				(type default)
			)
			(layer "B.Fab")
		)
		(fp_line
			(start -0.12065 -0.3048)
			(end -0.67945 -0.3048)
			(stroke
				(width 0.1)
				(type default)
			)
			(layer "B.Fab")
		)
		(fp_line
			(start -0.12065 -0.2794)
			(end -0.12065 -0.3048)
			(stroke
				(width 0.1)
				(type default)
			)
			(layer "B.Fab")
		)
		(fp_line
			(start -0.120396 0.2794)
			(end 0.12065 0.2794)
			(stroke
				(width 0.1)
				(type default)
			)
			(layer "B.Fab")
		)
		(fp_line
			(start -0.120396 0.3048)
			(end -0.120396 0.2794)
			(stroke
				(width 0.1)
				(type default)
			)
			(layer "B.Fab")
		)
		(fp_line
			(start 0.12065 -0.305054)
			(end 0.12065 -0.2794)
			(stroke
				(width 0.1)
				(type default)
			)
			(layer "B.Fab")
		)
		(fp_line
			(start 0.12065 -0.2794)
			(end -0.12065 -0.2794)
			(stroke
				(width 0.1)
				(type default)
			)
			(layer "B.Fab")
		)
		(fp_line
			(start 0.12065 0.2794)
			(end 0.12065 0.3048)
			(stroke
				(width 0.1)
				(type default)
			)
			(layer "B.Fab")
		)
		(fp_line
			(start 0.12065 0.3048)
			(end 0.67945 0.3048)
			(stroke
				(width 0.1)
				(type default)
			)
			(layer "B.Fab")
		)
		(fp_line
			(start 0.67945 -0.305054)
			(end 0.12065 -0.305054)
			(stroke
				(width 0.1)
				(type default)
			)
			(layer "B.Fab")
		)
		(fp_line
			(start 0.67945 0.3048)
			(end 0.67945 -0.305054)
			(stroke
				(width 0.1)
				(type default)
			)
			(layer "B.Fab")
		)
		(pad "1" smd circle
			(at 0.40005 0 180)
			(size 0 0)
			(layers "B.Cu" "B.Mask" "B.Paste")
			(net "PVDDCR_SOC_P0")
		)
		(pad "2" smd circle
			(at -0.40005 0 180)
			(size 0 0)
			(layers "B.Cu" "B.Mask" "B.Paste")
			(net "GND")
		)
	)
	(footprint ""
		(layer "B.Cu")
		(at 124.373386 -262.82523)
		(property "Reference" "C2444"
			(at 0 0 0)
			(layer "B.SilkS")
			(hide yes)
			(effects
				(font
					(size 1.27 1.27)
				)
				(justify mirror)
			)
		)
		(property "Value" ""
			(at 0 0 0)
			(layer "B.Fab")
			(effects
				(font
					(size 1.27 1.27)
				)
				(justify mirror)
			)
		)
		(duplicate_pad_numbers_are_jumpers no)
		(fp_line
			(start -0.7874 -0.4064)
			(end -0.7874 0.4064)
			(stroke
				(width 0.1524)
				(type default)
			)
			(layer "B.SilkS")
		)
		(fp_line
			(start -0.7874 0.4064)
			(end 0.7874 0.4064)
			(stroke
				(width 0.1524)
				(type default)
			)
			(layer "B.SilkS")
		)
		(fp_line
			(start 0.7874 -0.4064)
			(end -0.7874 -0.4064)
			(stroke
				(width 0.1524)
				(type default)
			)
			(layer "B.SilkS")
		)
		(fp_line
			(start 0.7874 0.4064)
			(end 0.7874 -0.4064)
			(stroke
				(width 0.1524)
				(type default)
			)
			(layer "B.SilkS")
		)
		(fp_line
			(start -0.67945 -0.3048)
			(end -0.67945 0.3048)
			(stroke
				(width 0.1)
				(type default)
			)
			(layer "B.Fab")
		)
		(fp_line
			(start -0.67945 0.3048)
			(end -0.120396 0.3048)
			(stroke
				(width 0.1)
				(type default)
			)
			(layer "B.Fab")
		)
		(fp_line
			(start -0.12065 -0.3048)
			(end -0.67945 -0.3048)
			(stroke
				(width 0.1)
				(type default)
			)
			(layer "B.Fab")
		)
		(fp_line
			(start -0.12065 -0.2794)
			(end -0.12065 -0.3048)
			(stroke
				(width 0.1)
				(type default)
			)
			(layer "B.Fab")
		)
		(fp_line
			(start -0.120396 0.2794)
			(end 0.12065 0.2794)
			(stroke
				(width 0.1)
				(type default)
			)
			(layer "B.Fab")
		)
		(fp_line
			(start -0.120396 0.3048)
			(end -0.120396 0.2794)
			(stroke
				(width 0.1)
				(type default)
			)
			(layer "B.Fab")
		)
		(fp_line
			(start 0.12065 -0.305054)
			(end 0.12065 -0.2794)
			(stroke
				(width 0.1)
				(type default)
			)
			(layer "B.Fab")
		)
		(fp_line
			(start 0.12065 -0.2794)
			(end -0.12065 -0.2794)
			(stroke
				(width 0.1)
				(type default)
			)
			(layer "B.Fab")
		)
		(fp_line
			(start 0.12065 0.2794)
			(end 0.12065 0.3048)
			(stroke
				(width 0.1)
				(type default)
			)
			(layer "B.Fab")
		)
		(fp_line
			(start 0.12065 0.3048)
			(end 0.67945 0.3048)
			(stroke
				(width 0.1)
				(type default)
			)
			(layer "B.Fab")
		)
		(fp_line
			(start 0.67945 -0.305054)
			(end 0.12065 -0.305054)
			(stroke
				(width 0.1)
				(type default)
			)
			(layer "B.Fab")
		)
		(fp_line
			(start 0.67945 0.3048)
			(end 0.67945 -0.305054)
			(stroke
				(width 0.1)
				(type default)
			)
			(layer "B.Fab")
		)
		(pad "1" smd circle
			(at 0.40005 0 180)
			(size 0 0)
			(layers "B.Cu" "B.Mask" "B.Paste")
			(net "PVDDCR_SOC_P1")
		)
		(pad "2" smd circle
			(at -0.40005 0 180)
			(size 0 0)
			(layers "B.Cu" "B.Mask" "B.Paste")
			(net "GND")
		)
	)
	(footprint ""
		(layer "B.Cu")
		(at 215.0618 -340.868)
		(property "Reference" "R873"
			(at 0 0 0)
			(layer "B.SilkS")
			(hide yes)
			(effects
				(font
					(size 1.27 1.27)
				)
				(justify mirror)
			)
		)
		(property "Value" ""
			(at 0 0 0)
			(layer "B.Fab")
			(effects
				(font
					(size 1.27 1.27)
				)
				(justify mirror)
			)
		)
		(duplicate_pad_numbers_are_jumpers no)
		(fp_line
			(start -0.32512 -0.175006)
			(end -0.32512 0.175006)
			(stroke
				(width 0.1)
				(type default)
			)
			(layer "B.Fab")
		)
		(fp_line
			(start -0.32512 0.175006)
			(end 0.32512 0.175006)
			(stroke
				(width 0.1)
				(type default)
			)
			(layer "B.Fab")
		)
		(fp_line
			(start 0.32512 -0.175006)
			(end -0.32512 -0.175006)
			(stroke
				(width 0.1)
				(type default)
			)
			(layer "B.Fab")
		)
		(fp_line
			(start 0.32512 0.175006)
			(end 0.32512 -0.175006)
			(stroke
				(width 0.1)
				(type default)
			)
			(layer "B.Fab")
		)
		(pad "1" smd rect
			(at 0.2667 0 180)
			(size 0.3048 0.381)
			(layers "B.Cu" "B.Mask" "B.Paste")
			(net "SMB_RT_CPU1_P2_R_SDA")
		)
		(pad "2" smd rect
			(at -0.2667 0)
			(size 0.3048 0.381)
			(layers "B.Cu" "B.Mask" "B.Paste")
			(net "SMB_RT_CPU1_P2_R2_SDA")
		)
	)
	(footprint ""
		(layer "B.Cu")
		(at 237.905544 -325.65721)
		(property "Reference" "R1234"
			(at 0 0 0)
			(layer "B.SilkS")
			(hide yes)
			(effects
				(font
					(size 1.27 1.27)
				)
				(justify mirror)
			)
		)
		(property "Value" ""
			(at 0 0 0)
			(layer "B.Fab")
			(effects
				(font
					(size 1.27 1.27)
				)
				(justify mirror)
			)
		)
		(duplicate_pad_numbers_are_jumpers no)
		(fp_line
			(start -0.7874 -0.4064)
			(end -0.7874 0.4064)
			(stroke
				(width 0.1524)
				(type default)
			)
			(layer "B.SilkS")
		)
		(fp_line
			(start -0.7874 0.4064)
			(end 0.7874 0.4064)
			(stroke
				(width 0.1524)
				(type default)
			)
			(layer "B.SilkS")
		)
		(fp_line
			(start 0.7874 -0.4064)
			(end -0.7874 -0.4064)
			(stroke
				(width 0.1524)
				(type default)
			)
			(layer "B.SilkS")
		)
		(fp_line
			(start 0.7874 0.4064)
			(end 0.7874 -0.4064)
			(stroke
				(width 0.1524)
				(type default)
			)
			(layer "B.SilkS")
		)
		(fp_line
			(start -0.67945 -0.3048)
			(end -0.67945 0.3048)
			(stroke
				(width 0.1)
				(type default)
			)
			(layer "B.Fab")
		)
		(fp_line
			(start -0.67945 0.3048)
			(end -0.120396 0.3048)
			(stroke
				(width 0.1)
				(type default)
			)
			(layer "B.Fab")
		)
		(fp_line
			(start -0.12065 -0.3048)
			(end -0.67945 -0.3048)
			(stroke
				(width 0.1)
				(type default)
			)
			(layer "B.Fab")
		)
		(fp_line
			(start -0.12065 -0.2794)
			(end -0.12065 -0.3048)
			(stroke
				(width 0.1)
				(type default)
			)
			(layer "B.Fab")
		)
		(fp_line
			(start -0.120396 0.2794)
			(end 0.12065 0.2794)
			(stroke
				(width 0.1)
				(type default)
			)
			(layer "B.Fab")
		)
		(fp_line
			(start -0.120396 0.3048)
			(end -0.120396 0.2794)
			(stroke
				(width 0.1)
				(type default)
			)
			(layer "B.Fab")
		)
		(fp_line
			(start 0.12065 -0.305054)
			(end 0.12065 -0.2794)
			(stroke
				(width 0.1)
				(type default)
			)
			(layer "B.Fab")
		)
		(fp_line
			(start 0.12065 -0.2794)
			(end -0.12065 -0.2794)
			(stroke
				(width 0.1)
				(type default)
			)
			(layer "B.Fab")
		)
		(fp_line
			(start 0.12065 0.2794)
			(end 0.12065 0.3048)
			(stroke
				(width 0.1)
				(type default)
			)
			(layer "B.Fab")
		)
		(fp_line
			(start 0.12065 0.3048)
			(end 0.67945 0.3048)
			(stroke
				(width 0.1)
				(type default)
			)
			(layer "B.Fab")
		)
		(fp_line
			(start 0.67945 -0.305054)
			(end 0.12065 -0.305054)
			(stroke
				(width 0.1)
				(type default)
			)
			(layer "B.Fab")
		)
		(fp_line
			(start 0.67945 0.3048)
			(end 0.67945 -0.305054)
			(stroke
				(width 0.1)
				(type default)
			)
			(layer "B.Fab")
		)
		(pad "1" smd circle
			(at 0.40005 0 180)
			(size 0 0)
			(layers "B.Cu" "B.Mask" "B.Paste")
			(net "P1V8_CPU1_RT_1D")
		)
		(pad "2" smd circle
			(at -0.40005 0 180)
			(size 0 0)
			(layers "B.Cu" "B.Mask" "B.Paste")
			(net "P1V8_CPU1_RT_1D_ADC")
		)
	)
	(footprint ""
		(layer "B.Cu")
		(at 41.525444 -349.386398 -90)
		(property "Reference" "PR281"
			(at 0 0 90)
			(layer "B.SilkS")
			(hide yes)
			(effects
				(font
					(size 1.27 1.27)
				)
				(justify mirror)
			)
		)
		(property "Value" ""
			(at 0 0 90)
			(layer "B.Fab")
			(effects
				(font
					(size 1.27 1.27)
				)
				(justify mirror)
			)
		)
		(duplicate_pad_numbers_are_jumpers no)
		(fp_line
			(start -0.7874 0.4064)
			(end 0.7874 0.4064)
			(stroke
				(width 0.1524)
				(type default)
			)
			(layer "B.SilkS")
		)
		(fp_line
			(start 0.7874 0.4064)
			(end 0.7874 -0.4064)
			(stroke
				(width 0.1524)
				(type default)
			)
			(layer "B.SilkS")
		)
		(fp_line
			(start -0.7874 -0.4064)
			(end -0.7874 0.4064)
			(stroke
				(width 0.1524)
				(type default)
			)
			(layer "B.SilkS")
		)
		(fp_line
			(start 0.7874 -0.4064)
			(end -0.7874 -0.4064)
			(stroke
				(width 0.1524)
				(type default)
			)
			(layer "B.SilkS")
		)
		(fp_line
			(start -0.67945 0.3048)
			(end -0.120396 0.3048)
			(stroke
				(width 0.1)
				(type default)
			)
			(layer "B.Fab")
		)
		(fp_line
			(start -0.120396 0.3048)
			(end -0.120396 0.2794)
			(stroke
				(width 0.1)
				(type default)
			)
			(layer "B.Fab")
		)
		(fp_line
			(start 0.12065 0.3048)
			(end 0.67945 0.3048)
			(stroke
				(width 0.1)
				(type default)
			)
			(layer "B.Fab")
		)
		(fp_line
			(start 0.67945 0.3048)
			(end 0.67945 -0.305054)
			(stroke
				(width 0.1)
				(type default)
			)
			(layer "B.Fab")
		)
		(fp_line
			(start -0.120396 0.2794)
			(end 0.12065 0.2794)
			(stroke
				(width 0.1)
				(type default)
			)
			(layer "B.Fab")
		)
		(fp_line
			(start 0.12065 0.2794)
			(end 0.12065 0.3048)
			(stroke
				(width 0.1)
				(type default)
			)
			(layer "B.Fab")
		)
		(fp_line
			(start -0.12065 -0.2794)
			(end -0.12065 -0.3048)
			(stroke
				(width 0.1)
				(type default)
			)
			(layer "B.Fab")
		)
		(fp_line
			(start 0.12065 -0.2794)
			(end -0.12065 -0.2794)
			(stroke
				(width 0.1)
				(type default)
			)
			(layer "B.Fab")
		)
		(fp_line
			(start -0.67945 -0.3048)
			(end -0.67945 0.3048)
			(stroke
				(width 0.1)
				(type default)
			)
			(layer "B.Fab")
		)
		(fp_line
			(start -0.12065 -0.3048)
			(end -0.67945 -0.3048)
			(stroke
				(width 0.1)
				(type default)
			)
			(layer "B.Fab")
		)
		(fp_line
			(start 0.12065 -0.305054)
			(end 0.12065 -0.2794)
			(stroke
				(width 0.1)
				(type default)
			)
			(layer "B.Fab")
		)
		(fp_line
			(start 0.67945 -0.305054)
			(end 0.12065 -0.305054)
			(stroke
				(width 0.1)
				(type default)
			)
			(layer "B.Fab")
		)
		(pad "1" smd circle
			(at 0.40005 0 90)
			(size 0 0)
			(layers "B.Cu" "B.Mask" "B.Paste")
			(net "PVDDIO_P1_VOS2")
		)
		(pad "2" smd circle
			(at -0.40005 0 90)
			(size 0 0)
			(layers "B.Cu" "B.Mask" "B.Paste")
			(net "PVDDIO_P1")
		)
	)
	(footprint ""
		(layer "B.Cu")
		(at 131.554474 -165.190932 90)
		(property "Reference" "PC339_2"
			(at 0 0 90)
			(layer "B.SilkS")
			(hide yes)
			(effects
				(font
					(size 1.27 1.27)
				)
				(justify mirror)
			)
		)
		(property "Value" ""
			(at 0 0 90)
			(layer "B.Fab")
			(effects
				(font
					(size 1.27 1.27)
				)
				(justify mirror)
			)
		)
		(duplicate_pad_numbers_are_jumpers no)
		(fp_line
			(start 1.524 -0.762)
			(end -1.524 -0.762)
			(stroke
				(width 0.1524)
				(type default)
			)
			(layer "B.SilkS")
		)
		(fp_line
			(start -1.524 -0.762)
			(end -1.524 0.762)
			(stroke
				(width 0.1524)
				(type default)
			)
			(layer "B.SilkS")
		)
		(fp_line
			(start 1.524 0.762)
			(end 1.524 -0.762)
			(stroke
				(width 0.1524)
				(type default)
			)
			(layer "B.SilkS")
		)
		(fp_line
			(start -1.524 0.762)
			(end 1.524 0.762)
			(stroke
				(width 0.1524)
				(type default)
			)
			(layer "B.SilkS")
		)
		(fp_line
			(start 1.1049 -0.724916)
			(end 1.1049 0.724916)
			(stroke
				(width 0.1)
				(type default)
			)
			(layer "B.Fab")
		)
		(fp_line
			(start -1.1049 -0.724916)
			(end 1.1049 -0.724916)
			(stroke
				(width 0.1)
				(type default)
			)
			(layer "B.Fab")
		)
		(fp_line
			(start 1.1049 0.724916)
			(end -1.1049 0.724916)
			(stroke
				(width 0.1)
				(type default)
			)
			(layer "B.Fab")
		)
		(fp_line
			(start -1.1049 0.724916)
			(end -1.1049 -0.724916)
			(stroke
				(width 0.1)
				(type default)
			)
			(layer "B.Fab")
		)
		(pad "1" smd rect
			(at 0.889 0 90)
			(size 1.016 1.27)
			(layers "B.Cu" "B.Mask" "B.Paste")
			(net "PVDDCR_SOC_P1")
		)
		(pad "2" smd rect
			(at -0.889 0 90)
			(size 1.016 1.27)
			(layers "B.Cu" "B.Mask" "B.Paste")
			(net "GND")
		)
	)
	(footprint ""
		(layer "B.Cu")
		(at 254.635 -340.76132 180)
		(property "Reference" "R1367"
			(at 0 0 0)
			(layer "B.SilkS")
			(hide yes)
			(effects
				(font
					(size 1.27 1.27)
				)
				(justify mirror)
			)
		)
		(property "Value" ""
			(at 0 0 0)
			(layer "B.Fab")
			(effects
				(font
					(size 1.27 1.27)
				)
				(justify mirror)
			)
		)
		(duplicate_pad_numbers_are_jumpers no)
		(fp_line
			(start 0.32512 0.175006)
			(end 0.32512 -0.175006)
			(stroke
				(width 0.1)
				(type default)
			)
			(layer "B.Fab")
		)
		(fp_line
			(start 0.32512 -0.175006)
			(end -0.32512 -0.175006)
			(stroke
				(width 0.1)
				(type default)
			)
			(layer "B.Fab")
		)
		(fp_line
			(start -0.32512 0.175006)
			(end 0.32512 0.175006)
			(stroke
				(width 0.1)
				(type default)
			)
			(layer "B.Fab")
		)
		(fp_line
			(start -0.32512 -0.175006)
			(end -0.32512 0.175006)
			(stroke
				(width 0.1)
				(type default)
			)
			(layer "B.Fab")
		)
		(pad "1" smd rect
			(at 0.2667 0)
			(size 0.3048 0.381)
			(layers "B.Cu" "B.Mask" "B.Paste")
			(net "P1V8_CPU0_RT_1D")
		)
		(pad "2" smd rect
			(at -0.2667 0 180)
			(size 0.3048 0.381)
			(layers "B.Cu" "B.Mask" "B.Paste")
			(net "SMB_RT_CPU0_P0_ROM_MUX_2D_R_SCL")
		)
	)
	(footprint ""
		(layer "B.Cu")
		(at 64.546988 -8.98398 90)
		(property "Reference" "C1835"
			(at 0 0 90)
			(layer "B.SilkS")
			(hide yes)
			(effects
				(font
					(size 1.27 1.27)
				)
				(justify mirror)
			)
		)
		(property "Value" ""
			(at 0 0 90)
			(layer "B.Fab")
			(effects
				(font
					(size 1.27 1.27)
				)
				(justify mirror)
			)
		)
		(duplicate_pad_numbers_are_jumpers no)
		(fp_line
			(start 0.7874 -0.4064)
			(end -0.7874 -0.4064)
			(stroke
				(width 0.1524)
				(type default)
			)
			(layer "B.SilkS")
		)
		(fp_line
			(start -0.7874 -0.4064)
			(end -0.7874 0.4064)
			(stroke
				(width 0.1524)
				(type default)
			)
			(layer "B.SilkS")
		)
		(fp_line
			(start 0.7874 0.4064)
			(end 0.7874 -0.4064)
			(stroke
				(width 0.1524)
				(type default)
			)
			(layer "B.SilkS")
		)
		(fp_line
			(start -0.7874 0.4064)
			(end 0.7874 0.4064)
			(stroke
				(width 0.1524)
				(type default)
			)
			(layer "B.SilkS")
		)
		(fp_line
			(start 0.67945 -0.305054)
			(end 0.12065 -0.305054)
			(stroke
				(width 0.1)
				(type default)
			)
			(layer "B.Fab")
		)
		(fp_line
			(start 0.12065 -0.305054)
			(end 0.12065 -0.2794)
			(stroke
				(width 0.1)
				(type default)
			)
			(layer "B.Fab")
		)
		(fp_line
			(start -0.12065 -0.3048)
			(end -0.67945 -0.3048)
			(stroke
				(width 0.1)
				(type default)
			)
			(layer "B.Fab")
		)
		(fp_line
			(start -0.67945 -0.3048)
			(end -0.67945 0.3048)
			(stroke
				(width 0.1)
				(type default)
			)
			(layer "B.Fab")
		)
		(fp_line
			(start 0.12065 -0.2794)
			(end -0.12065 -0.2794)
			(stroke
				(width 0.1)
				(type default)
			)
			(layer "B.Fab")
		)
		(fp_line
			(start -0.12065 -0.2794)
			(end -0.12065 -0.3048)
			(stroke
				(width 0.1)
				(type default)
			)
			(layer "B.Fab")
		)
		(fp_line
			(start 0.12065 0.2794)
			(end 0.12065 0.3048)
			(stroke
				(width 0.1)
				(type default)
			)
			(layer "B.Fab")
		)
		(fp_line
			(start -0.120396 0.2794)
			(end 0.12065 0.2794)
			(stroke
				(width 0.1)
				(type default)
			)
			(layer "B.Fab")
		)
		(fp_line
			(start 0.67945 0.3048)
			(end 0.67945 -0.305054)
			(stroke
				(width 0.1)
				(type default)
			)
			(layer "B.Fab")
		)
		(fp_line
			(start 0.12065 0.3048)
			(end 0.67945 0.3048)
			(stroke
				(width 0.1)
				(type default)
			)
			(layer "B.Fab")
		)
		(fp_line
			(start -0.120396 0.3048)
			(end -0.120396 0.2794)
			(stroke
				(width 0.1)
				(type default)
			)
			(layer "B.Fab")
		)
		(fp_line
			(start -0.67945 0.3048)
			(end -0.120396 0.3048)
			(stroke
				(width 0.1)
				(type default)
			)
			(layer "B.Fab")
		)
		(pad "1" smd circle
			(at 0.40005 0 270)
			(size 0 0)
			(layers "B.Cu" "B.Mask" "B.Paste")
			(net "P3V3_OCP_V3_2")
		)
		(pad "2" smd circle
			(at -0.40005 0 270)
			(size 0 0)
			(layers "B.Cu" "B.Mask" "B.Paste")
			(net "GND")
		)
	)
	(footprint ""
		(layer "B.Cu")
		(at 28.46324 -195.012564 180)
		(property "Reference" "R1584"
			(at 0 0 0)
			(layer "B.SilkS")
			(hide yes)
			(effects
				(font
					(size 1.27 1.27)
				)
				(justify mirror)
			)
		)
		(property "Value" ""
			(at 0 0 0)
			(layer "B.Fab")
			(effects
				(font
					(size 1.27 1.27)
				)
				(justify mirror)
			)
		)
		(duplicate_pad_numbers_are_jumpers no)
		(fp_line
			(start 0.7874 0.4064)
			(end 0.7874 -0.4064)
			(stroke
				(width 0.1524)
				(type default)
			)
			(layer "B.SilkS")
		)
		(fp_line
			(start 0.7874 -0.4064)
			(end -0.7874 -0.4064)
			(stroke
				(width 0.1524)
				(type default)
			)
			(layer "B.SilkS")
		)
		(fp_line
			(start -0.7874 0.4064)
			(end 0.7874 0.4064)
			(stroke
				(width 0.1524)
				(type default)
			)
			(layer "B.SilkS")
		)
		(fp_line
			(start -0.7874 -0.4064)
			(end -0.7874 0.4064)
			(stroke
				(width 0.1524)
				(type default)
			)
			(layer "B.SilkS")
		)
		(fp_line
			(start 0.67945 0.3048)
			(end 0.67945 -0.305054)
			(stroke
				(width 0.1)
				(type default)
			)
			(layer "B.Fab")
		)
		(fp_line
			(start 0.67945 -0.305054)
			(end 0.12065 -0.305054)
			(stroke
				(width 0.1)
				(type default)
			)
			(layer "B.Fab")
		)
		(fp_line
			(start 0.12065 0.3048)
			(end 0.67945 0.3048)
			(stroke
				(width 0.1)
				(type default)
			)
			(layer "B.Fab")
		)
		(fp_line
			(start 0.12065 0.2794)
			(end 0.12065 0.3048)
			(stroke
				(width 0.1)
				(type default)
			)
			(layer "B.Fab")
		)
		(fp_line
			(start 0.12065 -0.2794)
			(end -0.12065 -0.2794)
			(stroke
				(width 0.1)
				(type default)
			)
			(layer "B.Fab")
		)
		(fp_line
			(start 0.12065 -0.305054)
			(end 0.12065 -0.2794)
			(stroke
				(width 0.1)
				(type default)
			)
			(layer "B.Fab")
		)
		(fp_line
			(start -0.120396 0.3048)
			(end -0.120396 0.2794)
			(stroke
				(width 0.1)
				(type default)
			)
			(layer "B.Fab")
		)
		(fp_line
			(start -0.120396 0.2794)
			(end 0.12065 0.2794)
			(stroke
				(width 0.1)
				(type default)
			)
			(layer "B.Fab")
		)
		(fp_line
			(start -0.12065 -0.2794)
			(end -0.12065 -0.3048)
			(stroke
				(width 0.1)
				(type default)
			)
			(layer "B.Fab")
		)
		(fp_line
			(start -0.12065 -0.3048)
			(end -0.67945 -0.3048)
			(stroke
				(width 0.1)
				(type default)
			)
			(layer "B.Fab")
		)
		(fp_line
			(start -0.67945 0.3048)
			(end -0.120396 0.3048)
			(stroke
				(width 0.1)
				(type default)
			)
			(layer "B.Fab")
		)
		(fp_line
			(start -0.67945 -0.3048)
			(end -0.67945 0.3048)
			(stroke
				(width 0.1)
				(type default)
			)
			(layer "B.Fab")
		)
		(pad "1" smd circle
			(at 0.40005 0)
			(size 0 0)
			(layers "B.Cu" "B.Mask" "B.Paste")
			(net "I3C_SPD_DDRAF_CPU1_SCL")
		)
		(pad "2" smd circle
			(at -0.40005 0)
			(size 0 0)
			(layers "B.Cu" "B.Mask" "B.Paste")
			(net "I3C_SPD_DDRE_CPU1_SCL")
		)
	)
	(footprint ""
		(layer "B.Cu")
		(at 192.189608 -126.833376 -90)
		(property "Reference" "R158"
			(at 0 0 90)
			(layer "B.SilkS")
			(hide yes)
			(effects
				(font
					(size 1.27 1.27)
				)
				(justify mirror)
			)
		)
		(property "Value" ""
			(at 0 0 90)
			(layer "B.Fab")
			(effects
				(font
					(size 1.27 1.27)
				)
				(justify mirror)
			)
		)
		(duplicate_pad_numbers_are_jumpers no)
		(fp_line
			(start -0.7874 0.4064)
			(end 0.7874 0.4064)
			(stroke
				(width 0.1524)
				(type default)
			)
			(layer "B.SilkS")
		)
		(fp_line
			(start 0.7874 0.4064)
			(end 0.7874 -0.4064)
			(stroke
				(width 0.1524)
				(type default)
			)
			(layer "B.SilkS")
		)
		(fp_line
			(start -0.7874 -0.4064)
			(end -0.7874 0.4064)
			(stroke
				(width 0.1524)
				(type default)
			)
			(layer "B.SilkS")
		)
		(fp_line
			(start 0.7874 -0.4064)
			(end -0.7874 -0.4064)
			(stroke
				(width 0.1524)
				(type default)
			)
			(layer "B.SilkS")
		)
		(fp_line
			(start -0.67945 0.3048)
			(end -0.120396 0.3048)
			(stroke
				(width 0.1)
				(type default)
			)
			(layer "B.Fab")
		)
		(fp_line
			(start -0.120396 0.3048)
			(end -0.120396 0.2794)
			(stroke
				(width 0.1)
				(type default)
			)
			(layer "B.Fab")
		)
		(fp_line
			(start 0.12065 0.3048)
			(end 0.67945 0.3048)
			(stroke
				(width 0.1)
				(type default)
			)
			(layer "B.Fab")
		)
		(fp_line
			(start 0.67945 0.3048)
			(end 0.67945 -0.305054)
			(stroke
				(width 0.1)
				(type default)
			)
			(layer "B.Fab")
		)
		(fp_line
			(start -0.120396 0.2794)
			(end 0.12065 0.2794)
			(stroke
				(width 0.1)
				(type default)
			)
			(layer "B.Fab")
		)
		(fp_line
			(start 0.12065 0.2794)
			(end 0.12065 0.3048)
			(stroke
				(width 0.1)
				(type default)
			)
			(layer "B.Fab")
		)
		(fp_line
			(start -0.12065 -0.2794)
			(end -0.12065 -0.3048)
			(stroke
				(width 0.1)
				(type default)
			)
			(layer "B.Fab")
		)
		(fp_line
			(start 0.12065 -0.2794)
			(end -0.12065 -0.2794)
			(stroke
				(width 0.1)
				(type default)
			)
			(layer "B.Fab")
		)
		(fp_line
			(start -0.67945 -0.3048)
			(end -0.67945 0.3048)
			(stroke
				(width 0.1)
				(type default)
			)
			(layer "B.Fab")
		)
		(fp_line
			(start -0.12065 -0.3048)
			(end -0.67945 -0.3048)
			(stroke
				(width 0.1)
				(type default)
			)
			(layer "B.Fab")
		)
		(fp_line
			(start 0.12065 -0.305054)
			(end 0.12065 -0.2794)
			(stroke
				(width 0.1)
				(type default)
			)
			(layer "B.Fab")
		)
		(fp_line
			(start 0.67945 -0.305054)
			(end 0.12065 -0.305054)
			(stroke
				(width 0.1)
				(type default)
			)
			(layer "B.Fab")
		)
		(pad "1" smd circle
			(at 0.40005 0 90)
			(size 0 0)
			(layers "B.Cu" "B.Mask" "B.Paste")
			(net "FM_PLD_CPU0_PRSNT_HDT")
		)
		(pad "2" smd circle
			(at -0.40005 0 90)
			(size 0 0)
			(layers "B.Cu" "B.Mask" "B.Paste")
			(net "CPU0_HDT_BYPASS_SEL")
		)
	)
	(footprint ""
		(layer "B.Cu")
		(at 175.333914 -14.308328 90)
		(property "Reference" "R1385"
			(at 0 0 90)
			(layer "B.SilkS")
			(hide yes)
			(effects
				(font
					(size 1.27 1.27)
				)
				(justify mirror)
			)
		)
		(property "Value" ""
			(at 0 0 90)
			(layer "B.Fab")
			(effects
				(font
					(size 1.27 1.27)
				)
				(justify mirror)
			)
		)
		(duplicate_pad_numbers_are_jumpers no)
		(fp_line
			(start 0.7874 -0.4064)
			(end -0.7874 -0.4064)
			(stroke
				(width 0.1524)
				(type default)
			)
			(layer "B.SilkS")
		)
		(fp_line
			(start -0.7874 -0.4064)
			(end -0.7874 0.4064)
			(stroke
				(width 0.1524)
				(type default)
			)
			(layer "B.SilkS")
		)
		(fp_line
			(start 0.7874 0.4064)
			(end 0.7874 -0.4064)
			(stroke
				(width 0.1524)
				(type default)
			)
			(layer "B.SilkS")
		)
		(fp_line
			(start -0.7874 0.4064)
			(end 0.7874 0.4064)
			(stroke
				(width 0.1524)
				(type default)
			)
			(layer "B.SilkS")
		)
		(fp_line
			(start 0.67945 -0.305054)
			(end 0.12065 -0.305054)
			(stroke
				(width 0.1)
				(type default)
			)
			(layer "B.Fab")
		)
		(fp_line
			(start 0.12065 -0.305054)
			(end 0.12065 -0.2794)
			(stroke
				(width 0.1)
				(type default)
			)
			(layer "B.Fab")
		)
		(fp_line
			(start -0.12065 -0.3048)
			(end -0.67945 -0.3048)
			(stroke
				(width 0.1)
				(type default)
			)
			(layer "B.Fab")
		)
		(fp_line
			(start -0.67945 -0.3048)
			(end -0.67945 0.3048)
			(stroke
				(width 0.1)
				(type default)
			)
			(layer "B.Fab")
		)
		(fp_line
			(start 0.12065 -0.2794)
			(end -0.12065 -0.2794)
			(stroke
				(width 0.1)
				(type default)
			)
			(layer "B.Fab")
		)
		(fp_line
			(start -0.12065 -0.2794)
			(end -0.12065 -0.3048)
			(stroke
				(width 0.1)
				(type default)
			)
			(layer "B.Fab")
		)
		(fp_line
			(start 0.12065 0.2794)
			(end 0.12065 0.3048)
			(stroke
				(width 0.1)
				(type default)
			)
			(layer "B.Fab")
		)
		(fp_line
			(start -0.120396 0.2794)
			(end 0.12065 0.2794)
			(stroke
				(width 0.1)
				(type default)
			)
			(layer "B.Fab")
		)
		(fp_line
			(start 0.67945 0.3048)
			(end 0.67945 -0.305054)
			(stroke
				(width 0.1)
				(type default)
			)
			(layer "B.Fab")
		)
		(fp_line
			(start 0.12065 0.3048)
			(end 0.67945 0.3048)
			(stroke
				(width 0.1)
				(type default)
			)
			(layer "B.Fab")
		)
		(fp_line
			(start -0.120396 0.3048)
			(end -0.120396 0.2794)
			(stroke
				(width 0.1)
				(type default)
			)
			(layer "B.Fab")
		)
		(fp_line
			(start -0.67945 0.3048)
			(end -0.120396 0.3048)
			(stroke
				(width 0.1)
				(type default)
			)
			(layer "B.Fab")
		)
		(pad "1" smd circle
			(at 0.40005 0 270)
			(size 0 0)
			(layers "B.Cu" "B.Mask" "B.Paste")
			(net "SMB_CPU0_CPU1_SEC_SDA")
		)
		(pad "2" smd circle
			(at -0.40005 0 270)
			(size 0 0)
			(layers "B.Cu" "B.Mask" "B.Paste")
			(net "P3V3_AUX")
		)
	)
	(footprint ""
		(layer "B.Cu")
		(at 175.641 -100.294948 -90)
		(property "Reference" "R204"
			(at 0 0 90)
			(layer "B.SilkS")
			(hide yes)
			(effects
				(font
					(size 1.27 1.27)
				)
				(justify mirror)
			)
		)
		(property "Value" ""
			(at 0 0 90)
			(layer "B.Fab")
			(effects
				(font
					(size 1.27 1.27)
				)
				(justify mirror)
			)
		)
		(duplicate_pad_numbers_are_jumpers no)
		(fp_line
			(start -0.7874 0.4064)
			(end 0.7874 0.4064)
			(stroke
				(width 0.1524)
				(type default)
			)
			(layer "B.SilkS")
		)
		(fp_line
			(start 0.7874 0.4064)
			(end 0.7874 -0.4064)
			(stroke
				(width 0.1524)
				(type default)
			)
			(layer "B.SilkS")
		)
		(fp_line
			(start -0.7874 -0.4064)
			(end -0.7874 0.4064)
			(stroke
				(width 0.1524)
				(type default)
			)
			(layer "B.SilkS")
		)
		(fp_line
			(start 0.7874 -0.4064)
			(end -0.7874 -0.4064)
			(stroke
				(width 0.1524)
				(type default)
			)
			(layer "B.SilkS")
		)
		(fp_line
			(start -0.67945 0.3048)
			(end -0.120396 0.3048)
			(stroke
				(width 0.1)
				(type default)
			)
			(layer "B.Fab")
		)
		(fp_line
			(start -0.120396 0.3048)
			(end -0.120396 0.2794)
			(stroke
				(width 0.1)
				(type default)
			)
			(layer "B.Fab")
		)
		(fp_line
			(start 0.12065 0.3048)
			(end 0.67945 0.3048)
			(stroke
				(width 0.1)
				(type default)
			)
			(layer "B.Fab")
		)
		(fp_line
			(start 0.67945 0.3048)
			(end 0.67945 -0.305054)
			(stroke
				(width 0.1)
				(type default)
			)
			(layer "B.Fab")
		)
		(fp_line
			(start -0.120396 0.2794)
			(end 0.12065 0.2794)
			(stroke
				(width 0.1)
				(type default)
			)
			(layer "B.Fab")
		)
		(fp_line
			(start 0.12065 0.2794)
			(end 0.12065 0.3048)
			(stroke
				(width 0.1)
				(type default)
			)
			(layer "B.Fab")
		)
		(fp_line
			(start -0.12065 -0.2794)
			(end -0.12065 -0.3048)
			(stroke
				(width 0.1)
				(type default)
			)
			(layer "B.Fab")
		)
		(fp_line
			(start 0.12065 -0.2794)
			(end -0.12065 -0.2794)
			(stroke
				(width 0.1)
				(type default)
			)
			(layer "B.Fab")
		)
		(fp_line
			(start -0.67945 -0.3048)
			(end -0.67945 0.3048)
			(stroke
				(width 0.1)
				(type default)
			)
			(layer "B.Fab")
		)
		(fp_line
			(start -0.12065 -0.3048)
			(end -0.67945 -0.3048)
			(stroke
				(width 0.1)
				(type default)
			)
			(layer "B.Fab")
		)
		(fp_line
			(start 0.12065 -0.305054)
			(end 0.12065 -0.2794)
			(stroke
				(width 0.1)
				(type default)
			)
			(layer "B.Fab")
		)
		(fp_line
			(start 0.67945 -0.305054)
			(end 0.12065 -0.305054)
			(stroke
				(width 0.1)
				(type default)
			)
			(layer "B.Fab")
		)
		(pad "1" smd circle
			(at 0.40005 0 90)
			(size 0 0)
			(layers "B.Cu" "B.Mask" "B.Paste")
			(net "CPU1_XTRIG_L4")
		)
		(pad "2" smd circle
			(at -0.40005 0 90)
			(size 0 0)
			(layers "B.Cu" "B.Mask" "B.Paste")
			(net "FM_CPU1_XTRIG_L4")
		)
	)
	(footprint ""
		(layer "B.Cu")
		(at 368.892836 -191.32423 90)
		(property "Reference" "PC501_2"
			(at 0 0 90)
			(layer "B.SilkS")
			(hide yes)
			(effects
				(font
					(size 1.27 1.27)
				)
				(justify mirror)
			)
		)
		(property "Value" ""
			(at 0 0 90)
			(layer "B.Fab")
			(effects
				(font
					(size 1.27 1.27)
				)
				(justify mirror)
			)
		)
		(duplicate_pad_numbers_are_jumpers no)
		(fp_line
			(start 1.524 -0.762)
			(end -1.524 -0.762)
			(stroke
				(width 0.1524)
				(type default)
			)
			(layer "B.SilkS")
		)
		(fp_line
			(start -1.524 -0.762)
			(end -1.524 0.762)
			(stroke
				(width 0.1524)
				(type default)
			)
			(layer "B.SilkS")
		)
		(fp_line
			(start 1.524 0.762)
			(end 1.524 -0.762)
			(stroke
				(width 0.1524)
				(type default)
			)
			(layer "B.SilkS")
		)
		(fp_line
			(start -1.524 0.762)
			(end 1.524 0.762)
			(stroke
				(width 0.1524)
				(type default)
			)
			(layer "B.SilkS")
		)
		(fp_line
			(start 1.1049 -0.724916)
			(end 1.1049 0.724916)
			(stroke
				(width 0.1)
				(type default)
			)
			(layer "B.Fab")
		)
		(fp_line
			(start -1.1049 -0.724916)
			(end 1.1049 -0.724916)
			(stroke
				(width 0.1)
				(type default)
			)
			(layer "B.Fab")
		)
		(fp_line
			(start 1.1049 0.724916)
			(end -1.1049 0.724916)
			(stroke
				(width 0.1)
				(type default)
			)
			(layer "B.Fab")
		)
		(fp_line
			(start -1.1049 0.724916)
			(end -1.1049 -0.724916)
			(stroke
				(width 0.1)
				(type default)
			)
			(layer "B.Fab")
		)
		(pad "1" smd rect
			(at 0.889 0 90)
			(size 1.016 1.27)
			(layers "B.Cu" "B.Mask" "B.Paste")
			(net "PVDDCR_CPU0_P0")
		)
		(pad "2" smd rect
			(at -0.889 0 90)
			(size 1.016 1.27)
			(layers "B.Cu" "B.Mask" "B.Paste")
			(net "GND")
		)
	)
	(footprint ""
		(layer "B.Cu")
		(at 183.132476 -117.842792)
		(property "Reference" "C1129"
			(at 0 0 0)
			(layer "B.SilkS")
			(hide yes)
			(effects
				(font
					(size 1.27 1.27)
				)
				(justify mirror)
			)
		)
		(property "Value" ""
			(at 0 0 0)
			(layer "B.Fab")
			(effects
				(font
					(size 1.27 1.27)
				)
				(justify mirror)
			)
		)
		(duplicate_pad_numbers_are_jumpers no)
		(fp_line
			(start -0.69215 -0.2921)
			(end -0.69215 0.2921)
			(stroke
				(width 0.1524)
				(type default)
			)
			(layer "B.SilkS")
		)
		(fp_line
			(start -0.69215 0.2921)
			(end 0.69215 0.2921)
			(stroke
				(width 0.1524)
				(type default)
			)
			(layer "B.SilkS")
		)
		(fp_line
			(start 0.69215 -0.2921)
			(end -0.69215 -0.2921)
			(stroke
				(width 0.1524)
				(type default)
			)
			(layer "B.SilkS")
		)
		(fp_line
			(start 0.69215 0.2921)
			(end 0.69215 -0.2921)
			(stroke
				(width 0.1524)
				(type default)
			)
			(layer "B.SilkS")
		)
		(fp_line
			(start -0.51435 -0.2794)
			(end -0.51435 0.2794)
			(stroke
				(width 0.1)
				(type default)
			)
			(layer "B.Fab")
		)
		(fp_line
			(start -0.51435 0.2794)
			(end 0.51435 0.2794)
			(stroke
				(width 0.1)
				(type default)
			)
			(layer "B.Fab")
		)
		(fp_line
			(start 0.51435 -0.2794)
			(end -0.51435 -0.2794)
			(stroke
				(width 0.1)
				(type default)
			)
			(layer "B.Fab")
		)
		(fp_line
			(start 0.51435 0.2794)
			(end 0.51435 -0.2794)
			(stroke
				(width 0.1)
				(type default)
			)
			(layer "B.Fab")
		)
		(pad "1" smd circle
			(at 0.40005 0 180)
			(size 0 0)
			(layers "B.Cu" "B.Mask" "B.Paste")
			(net "P1V8_AUX")
		)
		(pad "2" smd circle
			(at -0.40005 0 180)
			(size 0 0)
			(layers "B.Cu" "B.Mask" "B.Paste")
			(net "GND")
		)
		(zone
			(layer "B.Cu")
			(hatch none 0.5)
			(connect_pads
				(clearance 0)
			)
			(min_thickness 0.25)
			(keepout
				(tracks not_allowed)
				(vias allowed)
				(pads allowed)
				(copperpour not_allowed)
				(footprints allowed)
			)
			(placement
				(enabled no)
				(sheetname "")
			)
			(fill
				(thermal_gap 0.5)
				(thermal_bridge_width 0.5)
				(island_removal_mode 0)
			)
			(polygon
				(pts
					(xy 182.941976 -117.755162) (xy 182.941976 -117.930422) (xy 183.032146 -117.988842) (xy 183.231536 -117.988842)
					(xy 183.322976 -117.930676) (xy 183.322976 -117.755162) (xy 183.231536 -117.696996) (xy 183.032146 -117.696996)
				)
			)
		)
	)
	(footprint ""
		(layer "B.Cu")
		(at 254.635 -336.25536 180)
		(property "Reference" "R1379"
			(at 0 0 0)
			(layer "B.SilkS")
			(hide yes)
			(effects
				(font
					(size 1.27 1.27)
				)
				(justify mirror)
			)
		)
		(property "Value" ""
			(at 0 0 0)
			(layer "B.Fab")
			(effects
				(font
					(size 1.27 1.27)
				)
				(justify mirror)
			)
		)
		(duplicate_pad_numbers_are_jumpers no)
		(fp_line
			(start 0.32512 0.175006)
			(end 0.32512 -0.175006)
			(stroke
				(width 0.1)
				(type default)
			)
			(layer "B.Fab")
		)
		(fp_line
			(start 0.32512 -0.175006)
			(end -0.32512 -0.175006)
			(stroke
				(width 0.1)
				(type default)
			)
			(layer "B.Fab")
		)
		(fp_line
			(start -0.32512 0.175006)
			(end 0.32512 0.175006)
			(stroke
				(width 0.1)
				(type default)
			)
			(layer "B.Fab")
		)
		(fp_line
			(start -0.32512 -0.175006)
			(end -0.32512 0.175006)
			(stroke
				(width 0.1)
				(type default)
			)
			(layer "B.Fab")
		)
		(pad "1" smd rect
			(at 0.2667 0)
			(size 0.3048 0.381)
			(layers "B.Cu" "B.Mask" "B.Paste")
			(net "P1V8_CPU0_RT_1D")
		)
		(pad "2" smd rect
			(at -0.2667 0 180)
			(size 0.3048 0.381)
			(layers "B.Cu" "B.Mask" "B.Paste")
			(net "SMB_RT_CPU0_P3_ROM_MUX_2D_R_SCL")
		)
	)
	(footprint ""
		(layer "B.Cu")
		(at 118.078504 -386.766562 90)
		(property "Reference" "C497"
			(at 0 0 90)
			(layer "B.SilkS")
			(hide yes)
			(effects
				(font
					(size 1.27 1.27)
				)
				(justify mirror)
			)
		)
		(property "Value" ""
			(at 0 0 90)
			(layer "B.Fab")
			(effects
				(font
					(size 1.27 1.27)
				)
				(justify mirror)
			)
		)
		(duplicate_pad_numbers_are_jumpers no)
		(fp_line
			(start 0.299974 -0.150114)
			(end -0.299974 -0.150114)
			(stroke
				(width 0.1)
				(type default)
			)
			(layer "B.Fab")
		)
		(fp_line
			(start -0.299974 -0.150114)
			(end -0.299974 0.150114)
			(stroke
				(width 0.1)
				(type default)
			)
			(layer "B.Fab")
		)
		(fp_line
			(start 0.299974 0.150114)
			(end 0.299974 -0.150114)
			(stroke
				(width 0.1)
				(type default)
			)
			(layer "B.Fab")
		)
		(fp_line
			(start -0.299974 0.150114)
			(end 0.299974 0.150114)
			(stroke
				(width 0.1)
				(type default)
			)
			(layer "B.Fab")
		)
		(pad "1" smd rect
			(at 0.2667 0 270)
			(size 0.3048 0.381)
			(layers "B.Cu" "B.Mask" "B.Paste")
			(net "P0V9_CPU1_RT3_2A")
		)
		(pad "2" smd rect
			(at -0.2667 0 270)
			(size 0.3048 0.381)
			(layers "B.Cu" "B.Mask" "B.Paste")
			(net "GND")
		)
	)
	(footprint ""
		(layer "B.Cu")
		(at 333.783686 -416.899344 90)
		(property "Reference" "C6551"
			(at 0 0 90)
			(layer "B.SilkS")
			(hide yes)
			(effects
				(font
					(size 1.27 1.27)
				)
				(justify mirror)
			)
		)
		(property "Value" ""
			(at 0 0 90)
			(layer "B.Fab")
			(effects
				(font
					(size 1.27 1.27)
				)
				(justify mirror)
			)
		)
		(duplicate_pad_numbers_are_jumpers no)
		(fp_line
			(start 0.299974 -0.150114)
			(end -0.299974 -0.150114)
			(stroke
				(width 0.1)
				(type default)
			)
			(layer "B.Fab")
		)
		(fp_line
			(start -0.299974 -0.150114)
			(end -0.299974 0.150114)
			(stroke
				(width 0.1)
				(type default)
			)
			(layer "B.Fab")
		)
		(fp_line
			(start 0.299974 0.150114)
			(end 0.299974 -0.150114)
			(stroke
				(width 0.1)
				(type default)
			)
			(layer "B.Fab")
		)
		(fp_line
			(start -0.299974 0.150114)
			(end 0.299974 0.150114)
			(stroke
				(width 0.1)
				(type default)
			)
			(layer "B.Fab")
		)
		(pad "1" smd rect
			(at 0.2667 0 270)
			(size 0.3048 0.381)
			(layers "B.Cu" "B.Mask" "B.Paste")
			(net "P5E_CPU0_P1_TX_BUF_C_DP<9>")
		)
		(pad "2" smd rect
			(at -0.2667 0 270)
			(size 0.3048 0.381)
			(layers "B.Cu" "B.Mask" "B.Paste")
			(net "P5E_CPU0_P1_TX_BUF_DP<9>")
		)
	)
	(footprint ""
		(layer "B.Cu")
		(at 181.297834 -421.37711 -90)
		(property "Reference" "R9020"
			(at 0 0 90)
			(layer "B.SilkS")
			(hide yes)
			(effects
				(font
					(size 1.27 1.27)
				)
				(justify mirror)
			)
		)
		(property "Value" ""
			(at 0 0 90)
			(layer "B.Fab")
			(effects
				(font
					(size 1.27 1.27)
				)
				(justify mirror)
			)
		)
		(duplicate_pad_numbers_are_jumpers no)
		(fp_line
			(start -0.7874 0.4064)
			(end 0.7874 0.4064)
			(stroke
				(width 0.1524)
				(type default)
			)
			(layer "B.SilkS")
		)
		(fp_line
			(start 0.7874 0.4064)
			(end 0.7874 -0.4064)
			(stroke
				(width 0.1524)
				(type default)
			)
			(layer "B.SilkS")
		)
		(fp_line
			(start -0.7874 -0.4064)
			(end -0.7874 0.4064)
			(stroke
				(width 0.1524)
				(type default)
			)
			(layer "B.SilkS")
		)
		(fp_line
			(start 0.7874 -0.4064)
			(end -0.7874 -0.4064)
			(stroke
				(width 0.1524)
				(type default)
			)
			(layer "B.SilkS")
		)
		(fp_line
			(start -0.67945 0.3048)
			(end -0.120396 0.3048)
			(stroke
				(width 0.1)
				(type default)
			)
			(layer "B.Fab")
		)
		(fp_line
			(start -0.120396 0.3048)
			(end -0.120396 0.2794)
			(stroke
				(width 0.1)
				(type default)
			)
			(layer "B.Fab")
		)
		(fp_line
			(start 0.12065 0.3048)
			(end 0.67945 0.3048)
			(stroke
				(width 0.1)
				(type default)
			)
			(layer "B.Fab")
		)
		(fp_line
			(start 0.67945 0.3048)
			(end 0.67945 -0.305054)
			(stroke
				(width 0.1)
				(type default)
			)
			(layer "B.Fab")
		)
		(fp_line
			(start -0.120396 0.2794)
			(end 0.12065 0.2794)
			(stroke
				(width 0.1)
				(type default)
			)
			(layer "B.Fab")
		)
		(fp_line
			(start 0.12065 0.2794)
			(end 0.12065 0.3048)
			(stroke
				(width 0.1)
				(type default)
			)
			(layer "B.Fab")
		)
		(fp_line
			(start -0.12065 -0.2794)
			(end -0.12065 -0.3048)
			(stroke
				(width 0.1)
				(type default)
			)
			(layer "B.Fab")
		)
		(fp_line
			(start 0.12065 -0.2794)
			(end -0.12065 -0.2794)
			(stroke
				(width 0.1)
				(type default)
			)
			(layer "B.Fab")
		)
		(fp_line
			(start -0.67945 -0.3048)
			(end -0.67945 0.3048)
			(stroke
				(width 0.1)
				(type default)
			)
			(layer "B.Fab")
		)
		(fp_line
			(start -0.12065 -0.3048)
			(end -0.67945 -0.3048)
			(stroke
				(width 0.1)
				(type default)
			)
			(layer "B.Fab")
		)
		(fp_line
			(start 0.12065 -0.305054)
			(end 0.12065 -0.2794)
			(stroke
				(width 0.1)
				(type default)
			)
			(layer "B.Fab")
		)
		(fp_line
			(start 0.67945 -0.305054)
			(end 0.12065 -0.305054)
			(stroke
				(width 0.1)
				(type default)
			)
			(layer "B.Fab")
		)
		(pad "1" smd circle
			(at 0.40005 0 90)
			(size 0 0)
			(layers "B.Cu" "B.Mask" "B.Paste")
			(net "P3V3_AUX")
		)
		(pad "2" smd circle
			(at -0.40005 0 90)
			(size 0 0)
			(layers "B.Cu" "B.Mask" "B.Paste")
			(net "U142_VS")
		)
	)
	(footprint ""
		(layer "B.Cu")
		(at 72.908668 -177.513234 -90)
		(property "Reference" "PC311_5"
			(at 0 0 90)
			(layer "B.SilkS")
			(hide yes)
			(effects
				(font
					(size 1.27 1.27)
				)
				(justify mirror)
			)
		)
		(property "Value" ""
			(at 0 0 90)
			(layer "B.Fab")
			(effects
				(font
					(size 1.27 1.27)
				)
				(justify mirror)
			)
		)
		(duplicate_pad_numbers_are_jumpers no)
		(fp_line
			(start -1.524 0.762)
			(end 1.524 0.762)
			(stroke
				(width 0.1524)
				(type default)
			)
			(layer "B.SilkS")
		)
		(fp_line
			(start 1.524 0.762)
			(end 1.524 -0.762)
			(stroke
				(width 0.1524)
				(type default)
			)
			(layer "B.SilkS")
		)
		(fp_line
			(start -1.524 -0.762)
			(end -1.524 0.762)
			(stroke
				(width 0.1524)
				(type default)
			)
			(layer "B.SilkS")
		)
		(fp_line
			(start 1.524 -0.762)
			(end -1.524 -0.762)
			(stroke
				(width 0.1524)
				(type default)
			)
			(layer "B.SilkS")
		)
		(fp_line
			(start -1.1049 0.724916)
			(end -1.1049 -0.724916)
			(stroke
				(width 0.1)
				(type default)
			)
			(layer "B.Fab")
		)
		(fp_line
			(start 1.1049 0.724916)
			(end -1.1049 0.724916)
			(stroke
				(width 0.1)
				(type default)
			)
			(layer "B.Fab")
		)
		(fp_line
			(start -1.1049 -0.724916)
			(end 1.1049 -0.724916)
			(stroke
				(width 0.1)
				(type default)
			)
			(layer "B.Fab")
		)
		(fp_line
			(start 1.1049 -0.724916)
			(end 1.1049 0.724916)
			(stroke
				(width 0.1)
				(type default)
			)
			(layer "B.Fab")
		)
		(pad "1" smd rect
			(at 0.889 0 270)
			(size 1.016 1.27)
			(layers "B.Cu" "B.Mask" "B.Paste")
			(net "SW_P12V_AUX_PVDDCR_CPU0_P1_FLT")
		)
		(pad "2" smd rect
			(at -0.889 0 270)
			(size 1.016 1.27)
			(layers "B.Cu" "B.Mask" "B.Paste")
			(net "GND")
		)
	)
	(footprint ""
		(layer "B.Cu")
		(at 167.39743 -105.755694 90)
		(property "Reference" "R11"
			(at 0 0 90)
			(layer "B.SilkS")
			(hide yes)
			(effects
				(font
					(size 1.27 1.27)
				)
				(justify mirror)
			)
		)
		(property "Value" ""
			(at 0 0 90)
			(layer "B.Fab")
			(effects
				(font
					(size 1.27 1.27)
				)
				(justify mirror)
			)
		)
		(duplicate_pad_numbers_are_jumpers no)
		(fp_line
			(start 0.7874 -0.4064)
			(end -0.7874 -0.4064)
			(stroke
				(width 0.1524)
				(type default)
			)
			(layer "B.SilkS")
		)
		(fp_line
			(start -0.7874 -0.4064)
			(end -0.7874 0.4064)
			(stroke
				(width 0.1524)
				(type default)
			)
			(layer "B.SilkS")
		)
		(fp_line
			(start 0.7874 0.4064)
			(end 0.7874 -0.4064)
			(stroke
				(width 0.1524)
				(type default)
			)
			(layer "B.SilkS")
		)
		(fp_line
			(start -0.7874 0.4064)
			(end 0.7874 0.4064)
			(stroke
				(width 0.1524)
				(type default)
			)
			(layer "B.SilkS")
		)
		(fp_line
			(start 0.67945 -0.305054)
			(end 0.12065 -0.305054)
			(stroke
				(width 0.1)
				(type default)
			)
			(layer "B.Fab")
		)
		(fp_line
			(start 0.12065 -0.305054)
			(end 0.12065 -0.2794)
			(stroke
				(width 0.1)
				(type default)
			)
			(layer "B.Fab")
		)
		(fp_line
			(start -0.12065 -0.3048)
			(end -0.67945 -0.3048)
			(stroke
				(width 0.1)
				(type default)
			)
			(layer "B.Fab")
		)
		(fp_line
			(start -0.67945 -0.3048)
			(end -0.67945 0.3048)
			(stroke
				(width 0.1)
				(type default)
			)
			(layer "B.Fab")
		)
		(fp_line
			(start 0.12065 -0.2794)
			(end -0.12065 -0.2794)
			(stroke
				(width 0.1)
				(type default)
			)
			(layer "B.Fab")
		)
		(fp_line
			(start -0.12065 -0.2794)
			(end -0.12065 -0.3048)
			(stroke
				(width 0.1)
				(type default)
			)
			(layer "B.Fab")
		)
		(fp_line
			(start 0.12065 0.2794)
			(end 0.12065 0.3048)
			(stroke
				(width 0.1)
				(type default)
			)
			(layer "B.Fab")
		)
		(fp_line
			(start -0.120396 0.2794)
			(end 0.12065 0.2794)
			(stroke
				(width 0.1)
				(type default)
			)
			(layer "B.Fab")
		)
		(fp_line
			(start 0.67945 0.3048)
			(end 0.67945 -0.305054)
			(stroke
				(width 0.1)
				(type default)
			)
			(layer "B.Fab")
		)
		(fp_line
			(start 0.12065 0.3048)
			(end 0.67945 0.3048)
			(stroke
				(width 0.1)
				(type default)
			)
			(layer "B.Fab")
		)
		(fp_line
			(start -0.120396 0.3048)
			(end -0.120396 0.2794)
			(stroke
				(width 0.1)
				(type default)
			)
			(layer "B.Fab")
		)
		(fp_line
			(start -0.67945 0.3048)
			(end -0.120396 0.3048)
			(stroke
				(width 0.1)
				(type default)
			)
			(layer "B.Fab")
		)
		(pad "1" smd circle
			(at 0.40005 0 270)
			(size 0 0)
			(layers "B.Cu" "B.Mask" "B.Paste")
			(net "FM_I3C_CPU0_MUX1_OE_N")
		)
		(pad "2" smd circle
			(at -0.40005 0 270)
			(size 0 0)
			(layers "B.Cu" "B.Mask" "B.Paste")
			(net "GND")
		)
	)
	(footprint ""
		(layer "B.Cu")
		(at 116.116354 -415.910268 90)
		(property "Reference" "C1988"
			(at 0 0 90)
			(layer "B.SilkS")
			(hide yes)
			(effects
				(font
					(size 1.27 1.27)
				)
				(justify mirror)
			)
		)
		(property "Value" ""
			(at 0 0 90)
			(layer "B.Fab")
			(effects
				(font
					(size 1.27 1.27)
				)
				(justify mirror)
			)
		)
		(duplicate_pad_numbers_are_jumpers no)
		(fp_line
			(start 0.7874 -0.4064)
			(end -0.7874 -0.4064)
			(stroke
				(width 0.1524)
				(type default)
			)
			(layer "B.SilkS")
		)
		(fp_line
			(start -0.7874 -0.4064)
			(end -0.7874 0.4064)
			(stroke
				(width 0.1524)
				(type default)
			)
			(layer "B.SilkS")
		)
		(fp_line
			(start 0.7874 0.4064)
			(end 0.7874 -0.4064)
			(stroke
				(width 0.1524)
				(type default)
			)
			(layer "B.SilkS")
		)
		(fp_line
			(start -0.7874 0.4064)
			(end 0.7874 0.4064)
			(stroke
				(width 0.1524)
				(type default)
			)
			(layer "B.SilkS")
		)
		(fp_line
			(start 0.67945 -0.305054)
			(end 0.12065 -0.305054)
			(stroke
				(width 0.1)
				(type default)
			)
			(layer "B.Fab")
		)
		(fp_line
			(start 0.12065 -0.305054)
			(end 0.12065 -0.2794)
			(stroke
				(width 0.1)
				(type default)
			)
			(layer "B.Fab")
		)
		(fp_line
			(start -0.12065 -0.3048)
			(end -0.67945 -0.3048)
			(stroke
				(width 0.1)
				(type default)
			)
			(layer "B.Fab")
		)
		(fp_line
			(start -0.67945 -0.3048)
			(end -0.67945 0.3048)
			(stroke
				(width 0.1)
				(type default)
			)
			(layer "B.Fab")
		)
		(fp_line
			(start 0.12065 -0.2794)
			(end -0.12065 -0.2794)
			(stroke
				(width 0.1)
				(type default)
			)
			(layer "B.Fab")
		)
		(fp_line
			(start -0.12065 -0.2794)
			(end -0.12065 -0.3048)
			(stroke
				(width 0.1)
				(type default)
			)
			(layer "B.Fab")
		)
		(fp_line
			(start 0.12065 0.2794)
			(end 0.12065 0.3048)
			(stroke
				(width 0.1)
				(type default)
			)
			(layer "B.Fab")
		)
		(fp_line
			(start -0.120396 0.2794)
			(end 0.12065 0.2794)
			(stroke
				(width 0.1)
				(type default)
			)
			(layer "B.Fab")
		)
		(fp_line
			(start 0.67945 0.3048)
			(end 0.67945 -0.305054)
			(stroke
				(width 0.1)
				(type default)
			)
			(layer "B.Fab")
		)
		(fp_line
			(start 0.12065 0.3048)
			(end 0.67945 0.3048)
			(stroke
				(width 0.1)
				(type default)
			)
			(layer "B.Fab")
		)
		(fp_line
			(start -0.120396 0.3048)
			(end -0.120396 0.2794)
			(stroke
				(width 0.1)
				(type default)
			)
			(layer "B.Fab")
		)
		(fp_line
			(start -0.67945 0.3048)
			(end -0.120396 0.3048)
			(stroke
				(width 0.1)
				(type default)
			)
			(layer "B.Fab")
		)
		(pad "1" smd circle
			(at 0.40005 0 270)
			(size 0 0)
			(layers "B.Cu" "B.Mask" "B.Paste")
			(net "GPU_FPGA_EROT_FATALERR_ISO_N")
		)
		(pad "2" smd circle
			(at -0.40005 0 270)
			(size 0 0)
			(layers "B.Cu" "B.Mask" "B.Paste")
			(net "GND")
		)
	)
	(footprint ""
		(layer "B.Cu")
		(at 85.919056 -390.560052 90)
		(property "Reference" "C338"
			(at 0 0 90)
			(layer "B.SilkS")
			(hide yes)
			(effects
				(font
					(size 1.27 1.27)
				)
				(justify mirror)
			)
		)
		(property "Value" ""
			(at 0 0 90)
			(layer "B.Fab")
			(effects
				(font
					(size 1.27 1.27)
				)
				(justify mirror)
			)
		)
		(duplicate_pad_numbers_are_jumpers no)
		(fp_line
			(start 0.7874 -0.4064)
			(end -0.7874 -0.4064)
			(stroke
				(width 0.1524)
				(type default)
			)
			(layer "B.SilkS")
		)
		(fp_line
			(start -0.7874 -0.4064)
			(end -0.7874 0.4064)
			(stroke
				(width 0.1524)
				(type default)
			)
			(layer "B.SilkS")
		)
		(fp_line
			(start 0.7874 0.4064)
			(end 0.7874 -0.4064)
			(stroke
				(width 0.1524)
				(type default)
			)
			(layer "B.SilkS")
		)
		(fp_line
			(start -0.7874 0.4064)
			(end 0.7874 0.4064)
			(stroke
				(width 0.1524)
				(type default)
			)
			(layer "B.SilkS")
		)
		(fp_line
			(start 0.67945 -0.305054)
			(end 0.12065 -0.305054)
			(stroke
				(width 0.1)
				(type default)
			)
			(layer "B.Fab")
		)
		(fp_line
			(start 0.12065 -0.305054)
			(end 0.12065 -0.2794)
			(stroke
				(width 0.1)
				(type default)
			)
			(layer "B.Fab")
		)
		(fp_line
			(start -0.12065 -0.3048)
			(end -0.67945 -0.3048)
			(stroke
				(width 0.1)
				(type default)
			)
			(layer "B.Fab")
		)
		(fp_line
			(start -0.67945 -0.3048)
			(end -0.67945 0.3048)
			(stroke
				(width 0.1)
				(type default)
			)
			(layer "B.Fab")
		)
		(fp_line
			(start 0.12065 -0.2794)
			(end -0.12065 -0.2794)
			(stroke
				(width 0.1)
				(type default)
			)
			(layer "B.Fab")
		)
		(fp_line
			(start -0.12065 -0.2794)
			(end -0.12065 -0.3048)
			(stroke
				(width 0.1)
				(type default)
			)
			(layer "B.Fab")
		)
		(fp_line
			(start 0.12065 0.2794)
			(end 0.12065 0.3048)
			(stroke
				(width 0.1)
				(type default)
			)
			(layer "B.Fab")
		)
		(fp_line
			(start -0.120396 0.2794)
			(end 0.12065 0.2794)
			(stroke
				(width 0.1)
				(type default)
			)
			(layer "B.Fab")
		)
		(fp_line
			(start 0.67945 0.3048)
			(end 0.67945 -0.305054)
			(stroke
				(width 0.1)
				(type default)
			)
			(layer "B.Fab")
		)
		(fp_line
			(start 0.12065 0.3048)
			(end 0.67945 0.3048)
			(stroke
				(width 0.1)
				(type default)
			)
			(layer "B.Fab")
		)
		(fp_line
			(start -0.120396 0.3048)
			(end -0.120396 0.2794)
			(stroke
				(width 0.1)
				(type default)
			)
			(layer "B.Fab")
		)
		(fp_line
			(start -0.67945 0.3048)
			(end -0.120396 0.3048)
			(stroke
				(width 0.1)
				(type default)
			)
			(layer "B.Fab")
		)
		(pad "1" smd circle
			(at 0.40005 0 270)
			(size 0 0)
			(layers "B.Cu" "B.Mask" "B.Paste")
			(net "P0V9_CPU1_RT_2D")
		)
		(pad "2" smd circle
			(at -0.40005 0 270)
			(size 0 0)
			(layers "B.Cu" "B.Mask" "B.Paste")
			(net "GND")
		)
	)
	(footprint ""
		(layer "B.Cu")
		(at 381.192786 -214.523828 90)
		(property "Reference" "R8563"
			(at 0 0 90)
			(layer "B.SilkS")
			(hide yes)
			(effects
				(font
					(size 1.27 1.27)
				)
				(justify mirror)
			)
		)
		(property "Value" ""
			(at 0 0 90)
			(layer "B.Fab")
			(effects
				(font
					(size 1.27 1.27)
				)
				(justify mirror)
			)
		)
		(duplicate_pad_numbers_are_jumpers no)
		(fp_line
			(start 0.436372 -0.4064)
			(end -0.325628 -0.4064)
			(stroke
				(width 0.1524)
				(type default)
			)
			(layer "B.SilkS")
		)
		(fp_line
			(start -0.7874 0.061214)
			(end -0.7874 0.4064)
			(stroke
				(width 0.1524)
				(type default)
			)
			(layer "B.SilkS")
		)
		(fp_line
			(start 0.7874 0.4064)
			(end 0.7874 -0.014986)
			(stroke
				(width 0.1524)
				(type default)
			)
			(layer "B.SilkS")
		)
		(fp_line
			(start -0.7874 0.4064)
			(end 0.7874 0.4064)
			(stroke
				(width 0.1524)
				(type default)
			)
			(layer "B.SilkS")
		)
		(fp_line
			(start 0.67945 -0.305054)
			(end 0.12065 -0.305054)
			(stroke
				(width 0.1)
				(type default)
			)
			(layer "B.Fab")
		)
		(fp_line
			(start 0.12065 -0.305054)
			(end 0.12065 -0.2794)
			(stroke
				(width 0.1)
				(type default)
			)
			(layer "B.Fab")
		)
		(fp_line
			(start -0.12065 -0.3048)
			(end -0.67945 -0.3048)
			(stroke
				(width 0.1)
				(type default)
			)
			(layer "B.Fab")
		)
		(fp_line
			(start -0.67945 -0.3048)
			(end -0.67945 0.3048)
			(stroke
				(width 0.1)
				(type default)
			)
			(layer "B.Fab")
		)
		(fp_line
			(start 0.12065 -0.2794)
			(end -0.12065 -0.2794)
			(stroke
				(width 0.1)
				(type default)
			)
			(layer "B.Fab")
		)
		(fp_line
			(start -0.12065 -0.2794)
			(end -0.12065 -0.3048)
			(stroke
				(width 0.1)
				(type default)
			)
			(layer "B.Fab")
		)
		(fp_line
			(start 0.12065 0.2794)
			(end 0.12065 0.3048)
			(stroke
				(width 0.1)
				(type default)
			)
			(layer "B.Fab")
		)
		(fp_line
			(start -0.120396 0.2794)
			(end 0.12065 0.2794)
			(stroke
				(width 0.1)
				(type default)
			)
			(layer "B.Fab")
		)
		(fp_line
			(start 0.67945 0.3048)
			(end 0.67945 -0.305054)
			(stroke
				(width 0.1)
				(type default)
			)
			(layer "B.Fab")
		)
		(fp_line
			(start 0.12065 0.3048)
			(end 0.67945 0.3048)
			(stroke
				(width 0.1)
				(type default)
			)
			(layer "B.Fab")
		)
		(fp_line
			(start -0.120396 0.3048)
			(end -0.120396 0.2794)
			(stroke
				(width 0.1)
				(type default)
			)
			(layer "B.Fab")
		)
		(fp_line
			(start -0.67945 0.3048)
			(end -0.120396 0.3048)
			(stroke
				(width 0.1)
				(type default)
			)
			(layer "B.Fab")
		)
		(pad "1" smd circle
			(at 0.40005 0 270)
			(size 0 0)
			(layers "B.Cu" "B.Mask" "B.Paste")
			(net "CLK_100M_CPU0_CLK02_R_DP")
		)
		(pad "2" smd circle
			(at -0.40005 0 270)
			(size 0 0)
			(layers "B.Cu" "B.Mask" "B.Paste")
			(net "CLK_100M_CPU0_CLK02_DP")
		)
	)
	(footprint ""
		(layer "B.Cu")
		(at 364.788958 -272.284952)
		(property "Reference" "C2221"
			(at 0 0 0)
			(layer "B.SilkS")
			(hide yes)
			(effects
				(font
					(size 1.27 1.27)
				)
				(justify mirror)
			)
		)
		(property "Value" ""
			(at 0 0 0)
			(layer "B.Fab")
			(effects
				(font
					(size 1.27 1.27)
				)
				(justify mirror)
			)
		)
		(duplicate_pad_numbers_are_jumpers no)
		(fp_line
			(start -0.7874 -0.4064)
			(end -0.7874 0.4064)
			(stroke
				(width 0.1524)
				(type default)
			)
			(layer "B.SilkS")
		)
		(fp_line
			(start -0.7874 0.4064)
			(end 0.7874 0.4064)
			(stroke
				(width 0.1524)
				(type default)
			)
			(layer "B.SilkS")
		)
		(fp_line
			(start 0.7874 -0.4064)
			(end -0.7874 -0.4064)
			(stroke
				(width 0.1524)
				(type default)
			)
			(layer "B.SilkS")
		)
		(fp_line
			(start 0.7874 0.4064)
			(end 0.7874 -0.4064)
			(stroke
				(width 0.1524)
				(type default)
			)
			(layer "B.SilkS")
		)
		(fp_line
			(start -0.67945 -0.3048)
			(end -0.67945 0.3048)
			(stroke
				(width 0.1)
				(type default)
			)
			(layer "B.Fab")
		)
		(fp_line
			(start -0.67945 0.3048)
			(end -0.120396 0.3048)
			(stroke
				(width 0.1)
				(type default)
			)
			(layer "B.Fab")
		)
		(fp_line
			(start -0.12065 -0.3048)
			(end -0.67945 -0.3048)
			(stroke
				(width 0.1)
				(type default)
			)
			(layer "B.Fab")
		)
		(fp_line
			(start -0.12065 -0.2794)
			(end -0.12065 -0.3048)
			(stroke
				(width 0.1)
				(type default)
			)
			(layer "B.Fab")
		)
		(fp_line
			(start -0.120396 0.2794)
			(end 0.12065 0.2794)
			(stroke
				(width 0.1)
				(type default)
			)
			(layer "B.Fab")
		)
		(fp_line
			(start -0.120396 0.3048)
			(end -0.120396 0.2794)
			(stroke
				(width 0.1)
				(type default)
			)
			(layer "B.Fab")
		)
		(fp_line
			(start 0.12065 -0.305054)
			(end 0.12065 -0.2794)
			(stroke
				(width 0.1)
				(type default)
			)
			(layer "B.Fab")
		)
		(fp_line
			(start 0.12065 -0.2794)
			(end -0.12065 -0.2794)
			(stroke
				(width 0.1)
				(type default)
			)
			(layer "B.Fab")
		)
		(fp_line
			(start 0.12065 0.2794)
			(end 0.12065 0.3048)
			(stroke
				(width 0.1)
				(type default)
			)
			(layer "B.Fab")
		)
		(fp_line
			(start 0.12065 0.3048)
			(end 0.67945 0.3048)
			(stroke
				(width 0.1)
				(type default)
			)
			(layer "B.Fab")
		)
		(fp_line
			(start 0.67945 -0.305054)
			(end 0.12065 -0.305054)
			(stroke
				(width 0.1)
				(type default)
			)
			(layer "B.Fab")
		)
		(fp_line
			(start 0.67945 0.3048)
			(end 0.67945 -0.305054)
			(stroke
				(width 0.1)
				(type default)
			)
			(layer "B.Fab")
		)
		(pad "1" smd circle
			(at 0.40005 0 180)
			(size 0 0)
			(layers "B.Cu" "B.Mask" "B.Paste")
			(net "PVDDCR_CPU1_P0")
		)
		(pad "2" smd circle
			(at -0.40005 0 180)
			(size 0 0)
			(layers "B.Cu" "B.Mask" "B.Paste")
			(net "GND")
		)
	)
	(footprint ""
		(layer "B.Cu")
		(at 123.611386 -257.930396)
		(property "Reference" "C3915"
			(at 0 0 0)
			(layer "B.SilkS")
			(hide yes)
			(effects
				(font
					(size 1.27 1.27)
				)
				(justify mirror)
			)
		)
		(property "Value" ""
			(at 0 0 0)
			(layer "B.Fab")
			(effects
				(font
					(size 1.27 1.27)
				)
				(justify mirror)
			)
		)
		(duplicate_pad_numbers_are_jumpers no)
		(fp_line
			(start -0.7874 -0.4064)
			(end -0.7874 0.4064)
			(stroke
				(width 0.1524)
				(type default)
			)
			(layer "B.SilkS")
		)
		(fp_line
			(start -0.7874 0.4064)
			(end 0.7874 0.4064)
			(stroke
				(width 0.1524)
				(type default)
			)
			(layer "B.SilkS")
		)
		(fp_line
			(start 0.7874 -0.4064)
			(end -0.7874 -0.4064)
			(stroke
				(width 0.1524)
				(type default)
			)
			(layer "B.SilkS")
		)
		(fp_line
			(start 0.7874 0.4064)
			(end 0.7874 -0.4064)
			(stroke
				(width 0.1524)
				(type default)
			)
			(layer "B.SilkS")
		)
		(fp_line
			(start -0.67945 -0.3048)
			(end -0.67945 0.3048)
			(stroke
				(width 0.1)
				(type default)
			)
			(layer "B.Fab")
		)
		(fp_line
			(start -0.67945 0.3048)
			(end -0.120396 0.3048)
			(stroke
				(width 0.1)
				(type default)
			)
			(layer "B.Fab")
		)
		(fp_line
			(start -0.12065 -0.3048)
			(end -0.67945 -0.3048)
			(stroke
				(width 0.1)
				(type default)
			)
			(layer "B.Fab")
		)
		(fp_line
			(start -0.12065 -0.2794)
			(end -0.12065 -0.3048)
			(stroke
				(width 0.1)
				(type default)
			)
			(layer "B.Fab")
		)
		(fp_line
			(start -0.120396 0.2794)
			(end 0.12065 0.2794)
			(stroke
				(width 0.1)
				(type default)
			)
			(layer "B.Fab")
		)
		(fp_line
			(start -0.120396 0.3048)
			(end -0.120396 0.2794)
			(stroke
				(width 0.1)
				(type default)
			)
			(layer "B.Fab")
		)
		(fp_line
			(start 0.12065 -0.305054)
			(end 0.12065 -0.2794)
			(stroke
				(width 0.1)
				(type default)
			)
			(layer "B.Fab")
		)
		(fp_line
			(start 0.12065 -0.2794)
			(end -0.12065 -0.2794)
			(stroke
				(width 0.1)
				(type default)
			)
			(layer "B.Fab")
		)
		(fp_line
			(start 0.12065 0.2794)
			(end 0.12065 0.3048)
			(stroke
				(width 0.1)
				(type default)
			)
			(layer "B.Fab")
		)
		(fp_line
			(start 0.12065 0.3048)
			(end 0.67945 0.3048)
			(stroke
				(width 0.1)
				(type default)
			)
			(layer "B.Fab")
		)
		(fp_line
			(start 0.67945 -0.305054)
			(end 0.12065 -0.305054)
			(stroke
				(width 0.1)
				(type default)
			)
			(layer "B.Fab")
		)
		(fp_line
			(start 0.67945 0.3048)
			(end 0.67945 -0.305054)
			(stroke
				(width 0.1)
				(type default)
			)
			(layer "B.Fab")
		)
		(pad "1" smd circle
			(at 0.40005 0 180)
			(size 0 0)
			(layers "B.Cu" "B.Mask" "B.Paste")
			(net "PVDDCR_SOC_P1")
		)
		(pad "2" smd circle
			(at -0.40005 0 180)
			(size 0 0)
			(layers "B.Cu" "B.Mask" "B.Paste")
			(net "GND")
		)
	)
	(footprint ""
		(layer "B.Cu")
		(at 399.522696 -341.172292 90)
		(property "Reference" "R941"
			(at 0 0 90)
			(layer "B.SilkS")
			(hide yes)
			(effects
				(font
					(size 1.27 1.27)
				)
				(justify mirror)
			)
		)
		(property "Value" ""
			(at 0 0 90)
			(layer "B.Fab")
			(effects
				(font
					(size 1.27 1.27)
				)
				(justify mirror)
			)
		)
		(duplicate_pad_numbers_are_jumpers no)
		(fp_line
			(start 0.7874 -0.4064)
			(end -0.7874 -0.4064)
			(stroke
				(width 0.1524)
				(type default)
			)
			(layer "B.SilkS")
		)
		(fp_line
			(start -0.7874 -0.4064)
			(end -0.7874 0.4064)
			(stroke
				(width 0.1524)
				(type default)
			)
			(layer "B.SilkS")
		)
		(fp_line
			(start 0.7874 0.4064)
			(end 0.7874 -0.4064)
			(stroke
				(width 0.1524)
				(type default)
			)
			(layer "B.SilkS")
		)
		(fp_line
			(start -0.7874 0.4064)
			(end 0.7874 0.4064)
			(stroke
				(width 0.1524)
				(type default)
			)
			(layer "B.SilkS")
		)
		(fp_line
			(start 0.67945 -0.305054)
			(end 0.12065 -0.305054)
			(stroke
				(width 0.1)
				(type default)
			)
			(layer "B.Fab")
		)
		(fp_line
			(start 0.12065 -0.305054)
			(end 0.12065 -0.2794)
			(stroke
				(width 0.1)
				(type default)
			)
			(layer "B.Fab")
		)
		(fp_line
			(start -0.12065 -0.3048)
			(end -0.67945 -0.3048)
			(stroke
				(width 0.1)
				(type default)
			)
			(layer "B.Fab")
		)
		(fp_line
			(start -0.67945 -0.3048)
			(end -0.67945 0.3048)
			(stroke
				(width 0.1)
				(type default)
			)
			(layer "B.Fab")
		)
		(fp_line
			(start 0.12065 -0.2794)
			(end -0.12065 -0.2794)
			(stroke
				(width 0.1)
				(type default)
			)
			(layer "B.Fab")
		)
		(fp_line
			(start -0.12065 -0.2794)
			(end -0.12065 -0.3048)
			(stroke
				(width 0.1)
				(type default)
			)
			(layer "B.Fab")
		)
		(fp_line
			(start 0.12065 0.2794)
			(end 0.12065 0.3048)
			(stroke
				(width 0.1)
				(type default)
			)
			(layer "B.Fab")
		)
		(fp_line
			(start -0.120396 0.2794)
			(end 0.12065 0.2794)
			(stroke
				(width 0.1)
				(type default)
			)
			(layer "B.Fab")
		)
		(fp_line
			(start 0.67945 0.3048)
			(end 0.67945 -0.305054)
			(stroke
				(width 0.1)
				(type default)
			)
			(layer "B.Fab")
		)
		(fp_line
			(start 0.12065 0.3048)
			(end 0.67945 0.3048)
			(stroke
				(width 0.1)
				(type default)
			)
			(layer "B.Fab")
		)
		(fp_line
			(start -0.120396 0.3048)
			(end -0.120396 0.2794)
			(stroke
				(width 0.1)
				(type default)
			)
			(layer "B.Fab")
		)
		(fp_line
			(start -0.67945 0.3048)
			(end -0.120396 0.3048)
			(stroke
				(width 0.1)
				(type default)
			)
			(layer "B.Fab")
		)
		(pad "1" smd circle
			(at 0.40005 0 270)
			(size 0 0)
			(layers "B.Cu" "B.Mask" "B.Paste")
			(net "BOOT_RDY_H")
		)
		(pad "2" smd circle
			(at -0.40005 0 270)
			(size 0 0)
			(layers "B.Cu" "B.Mask" "B.Paste")
			(net "BOOT_RDY_R1_N")
		)
	)
	(footprint ""
		(layer "B.Cu")
		(at 371.551454 -254.19431)
		(property "Reference" "C2579"
			(at 0 0 0)
			(layer "B.SilkS")
			(hide yes)
			(effects
				(font
					(size 1.27 1.27)
				)
				(justify mirror)
			)
		)
		(property "Value" ""
			(at 0 0 0)
			(layer "B.Fab")
			(effects
				(font
					(size 1.27 1.27)
				)
				(justify mirror)
			)
		)
		(duplicate_pad_numbers_are_jumpers no)
		(fp_line
			(start -0.7874 -0.4064)
			(end -0.7874 0.4064)
			(stroke
				(width 0.1524)
				(type default)
			)
			(layer "B.SilkS")
		)
		(fp_line
			(start -0.7874 0.4064)
			(end 0.7874 0.4064)
			(stroke
				(width 0.1524)
				(type default)
			)
			(layer "B.SilkS")
		)
		(fp_line
			(start 0.7874 -0.4064)
			(end -0.7874 -0.4064)
			(stroke
				(width 0.1524)
				(type default)
			)
			(layer "B.SilkS")
		)
		(fp_line
			(start 0.7874 0.4064)
			(end 0.7874 -0.4064)
			(stroke
				(width 0.1524)
				(type default)
			)
			(layer "B.SilkS")
		)
		(fp_line
			(start -0.67945 -0.3048)
			(end -0.67945 0.3048)
			(stroke
				(width 0.1)
				(type default)
			)
			(layer "B.Fab")
		)
		(fp_line
			(start -0.67945 0.3048)
			(end -0.120396 0.3048)
			(stroke
				(width 0.1)
				(type default)
			)
			(layer "B.Fab")
		)
		(fp_line
			(start -0.12065 -0.3048)
			(end -0.67945 -0.3048)
			(stroke
				(width 0.1)
				(type default)
			)
			(layer "B.Fab")
		)
		(fp_line
			(start -0.12065 -0.2794)
			(end -0.12065 -0.3048)
			(stroke
				(width 0.1)
				(type default)
			)
			(layer "B.Fab")
		)
		(fp_line
			(start -0.120396 0.2794)
			(end 0.12065 0.2794)
			(stroke
				(width 0.1)
				(type default)
			)
			(layer "B.Fab")
		)
		(fp_line
			(start -0.120396 0.3048)
			(end -0.120396 0.2794)
			(stroke
				(width 0.1)
				(type default)
			)
			(layer "B.Fab")
		)
		(fp_line
			(start 0.12065 -0.305054)
			(end 0.12065 -0.2794)
			(stroke
				(width 0.1)
				(type default)
			)
			(layer "B.Fab")
		)
		(fp_line
			(start 0.12065 -0.2794)
			(end -0.12065 -0.2794)
			(stroke
				(width 0.1)
				(type default)
			)
			(layer "B.Fab")
		)
		(fp_line
			(start 0.12065 0.2794)
			(end 0.12065 0.3048)
			(stroke
				(width 0.1)
				(type default)
			)
			(layer "B.Fab")
		)
		(fp_line
			(start 0.12065 0.3048)
			(end 0.67945 0.3048)
			(stroke
				(width 0.1)
				(type default)
			)
			(layer "B.Fab")
		)
		(fp_line
			(start 0.67945 -0.305054)
			(end 0.12065 -0.305054)
			(stroke
				(width 0.1)
				(type default)
			)
			(layer "B.Fab")
		)
		(fp_line
			(start 0.67945 0.3048)
			(end 0.67945 -0.305054)
			(stroke
				(width 0.1)
				(type default)
			)
			(layer "B.Fab")
		)
		(pad "1" smd circle
			(at 0.40005 0 180)
			(size 0 0)
			(layers "B.Cu" "B.Mask" "B.Paste")
			(net "PVDDCR_SOC_P0")
		)
		(pad "2" smd circle
			(at -0.40005 0 180)
			(size 0 0)
			(layers "B.Cu" "B.Mask" "B.Paste")
			(net "GND")
		)
	)
	(footprint ""
		(layer "B.Cu")
		(at 293.277036 -244.08511 180)
		(property "Reference" "R377"
			(at 0 0 0)
			(layer "B.SilkS")
			(hide yes)
			(effects
				(font
					(size 1.27 1.27)
				)
				(justify mirror)
			)
		)
		(property "Value" ""
			(at 0 0 0)
			(layer "B.Fab")
			(effects
				(font
					(size 1.27 1.27)
				)
				(justify mirror)
			)
		)
		(duplicate_pad_numbers_are_jumpers no)
		(fp_line
			(start 0.7874 0.4064)
			(end 0.7874 -0.4064)
			(stroke
				(width 0.1524)
				(type default)
			)
			(layer "B.SilkS")
		)
		(fp_line
			(start 0.7874 -0.4064)
			(end -0.7874 -0.4064)
			(stroke
				(width 0.1524)
				(type default)
			)
			(layer "B.SilkS")
		)
		(fp_line
			(start -0.7874 0.4064)
			(end 0.7874 0.4064)
			(stroke
				(width 0.1524)
				(type default)
			)
			(layer "B.SilkS")
		)
		(fp_line
			(start -0.7874 -0.4064)
			(end -0.7874 0.4064)
			(stroke
				(width 0.1524)
				(type default)
			)
			(layer "B.SilkS")
		)
		(fp_line
			(start 0.67945 0.3048)
			(end 0.67945 -0.305054)
			(stroke
				(width 0.1)
				(type default)
			)
			(layer "B.Fab")
		)
		(fp_line
			(start 0.67945 -0.305054)
			(end 0.12065 -0.305054)
			(stroke
				(width 0.1)
				(type default)
			)
			(layer "B.Fab")
		)
		(fp_line
			(start 0.12065 0.3048)
			(end 0.67945 0.3048)
			(stroke
				(width 0.1)
				(type default)
			)
			(layer "B.Fab")
		)
		(fp_line
			(start 0.12065 0.2794)
			(end 0.12065 0.3048)
			(stroke
				(width 0.1)
				(type default)
			)
			(layer "B.Fab")
		)
		(fp_line
			(start 0.12065 -0.2794)
			(end -0.12065 -0.2794)
			(stroke
				(width 0.1)
				(type default)
			)
			(layer "B.Fab")
		)
		(fp_line
			(start 0.12065 -0.305054)
			(end 0.12065 -0.2794)
			(stroke
				(width 0.1)
				(type default)
			)
			(layer "B.Fab")
		)
		(fp_line
			(start -0.120396 0.3048)
			(end -0.120396 0.2794)
			(stroke
				(width 0.1)
				(type default)
			)
			(layer "B.Fab")
		)
		(fp_line
			(start -0.120396 0.2794)
			(end 0.12065 0.2794)
			(stroke
				(width 0.1)
				(type default)
			)
			(layer "B.Fab")
		)
		(fp_line
			(start -0.12065 -0.2794)
			(end -0.12065 -0.3048)
			(stroke
				(width 0.1)
				(type default)
			)
			(layer "B.Fab")
		)
		(fp_line
			(start -0.12065 -0.3048)
			(end -0.67945 -0.3048)
			(stroke
				(width 0.1)
				(type default)
			)
			(layer "B.Fab")
		)
		(fp_line
			(start -0.67945 0.3048)
			(end -0.120396 0.3048)
			(stroke
				(width 0.1)
				(type default)
			)
			(layer "B.Fab")
		)
		(fp_line
			(start -0.67945 -0.3048)
			(end -0.67945 0.3048)
			(stroke
				(width 0.1)
				(type default)
			)
			(layer "B.Fab")
		)
		(pad "1" smd circle
			(at 0.40005 0)
			(size 0 0)
			(layers "B.Cu" "B.Mask" "B.Paste")
			(net "M_C_CPU0_ALERT_N")
		)
		(pad "2" smd circle
			(at -0.40005 0)
			(size 0 0)
			(layers "B.Cu" "B.Mask" "B.Paste")
			(net "M_C_CPU0_ALERT_R_N")
		)
	)
	(footprint ""
		(layer "B.Cu")
		(at 150.988776 -17.693894 -90)
		(property "Reference" "R2212"
			(at 0 0 90)
			(layer "B.SilkS")
			(hide yes)
			(effects
				(font
					(size 1.27 1.27)
				)
				(justify mirror)
			)
		)
		(property "Value" ""
			(at 0 0 90)
			(layer "B.Fab")
			(effects
				(font
					(size 1.27 1.27)
				)
				(justify mirror)
			)
		)
		(duplicate_pad_numbers_are_jumpers no)
		(fp_line
			(start -0.7874 0.4064)
			(end 0.7874 0.4064)
			(stroke
				(width 0.1524)
				(type default)
			)
			(layer "B.SilkS")
		)
		(fp_line
			(start 0.7874 0.4064)
			(end 0.7874 -0.4064)
			(stroke
				(width 0.1524)
				(type default)
			)
			(layer "B.SilkS")
		)
		(fp_line
			(start -0.7874 -0.4064)
			(end -0.7874 0.4064)
			(stroke
				(width 0.1524)
				(type default)
			)
			(layer "B.SilkS")
		)
		(fp_line
			(start 0.7874 -0.4064)
			(end -0.7874 -0.4064)
			(stroke
				(width 0.1524)
				(type default)
			)
			(layer "B.SilkS")
		)
		(fp_line
			(start -0.67945 0.3048)
			(end -0.120396 0.3048)
			(stroke
				(width 0.1)
				(type default)
			)
			(layer "B.Fab")
		)
		(fp_line
			(start -0.120396 0.3048)
			(end -0.120396 0.2794)
			(stroke
				(width 0.1)
				(type default)
			)
			(layer "B.Fab")
		)
		(fp_line
			(start 0.12065 0.3048)
			(end 0.67945 0.3048)
			(stroke
				(width 0.1)
				(type default)
			)
			(layer "B.Fab")
		)
		(fp_line
			(start 0.67945 0.3048)
			(end 0.67945 -0.305054)
			(stroke
				(width 0.1)
				(type default)
			)
			(layer "B.Fab")
		)
		(fp_line
			(start -0.120396 0.2794)
			(end 0.12065 0.2794)
			(stroke
				(width 0.1)
				(type default)
			)
			(layer "B.Fab")
		)
		(fp_line
			(start 0.12065 0.2794)
			(end 0.12065 0.3048)
			(stroke
				(width 0.1)
				(type default)
			)
			(layer "B.Fab")
		)
		(fp_line
			(start -0.12065 -0.2794)
			(end -0.12065 -0.3048)
			(stroke
				(width 0.1)
				(type default)
			)
			(layer "B.Fab")
		)
		(fp_line
			(start 0.12065 -0.2794)
			(end -0.12065 -0.2794)
			(stroke
				(width 0.1)
				(type default)
			)
			(layer "B.Fab")
		)
		(fp_line
			(start -0.67945 -0.3048)
			(end -0.67945 0.3048)
			(stroke
				(width 0.1)
				(type default)
			)
			(layer "B.Fab")
		)
		(fp_line
			(start -0.12065 -0.3048)
			(end -0.67945 -0.3048)
			(stroke
				(width 0.1)
				(type default)
			)
			(layer "B.Fab")
		)
		(fp_line
			(start 0.12065 -0.305054)
			(end 0.12065 -0.2794)
			(stroke
				(width 0.1)
				(type default)
			)
			(layer "B.Fab")
		)
		(fp_line
			(start 0.67945 -0.305054)
			(end 0.12065 -0.305054)
			(stroke
				(width 0.1)
				(type default)
			)
			(layer "B.Fab")
		)
		(pad "1" smd circle
			(at 0.40005 0 90)
			(size 0 0)
			(layers "B.Cu" "B.Mask" "B.Paste")
			(net "SMB_HOST_CLK_3V3AUX_SCL")
		)
		(pad "2" smd circle
			(at -0.40005 0 90)
			(size 0 0)
			(layers "B.Cu" "B.Mask" "B.Paste")
			(net "P3V3_AUX")
		)
	)
	(footprint ""
		(layer "B.Cu")
		(at 340.891876 -66.708782 90)
		(property "Reference" "R3096"
			(at 0 0 90)
			(layer "B.SilkS")
			(hide yes)
			(effects
				(font
					(size 1.27 1.27)
				)
				(justify mirror)
			)
		)
		(property "Value" ""
			(at 0 0 90)
			(layer "B.Fab")
			(effects
				(font
					(size 1.27 1.27)
				)
				(justify mirror)
			)
		)
		(duplicate_pad_numbers_are_jumpers no)
		(fp_line
			(start 0.7874 -0.4064)
			(end -0.7874 -0.4064)
			(stroke
				(width 0.1524)
				(type default)
			)
			(layer "B.SilkS")
		)
		(fp_line
			(start -0.7874 -0.4064)
			(end -0.7874 0.4064)
			(stroke
				(width 0.1524)
				(type default)
			)
			(layer "B.SilkS")
		)
		(fp_line
			(start 0.7874 0.4064)
			(end 0.7874 -0.4064)
			(stroke
				(width 0.1524)
				(type default)
			)
			(layer "B.SilkS")
		)
		(fp_line
			(start -0.7874 0.4064)
			(end 0.7874 0.4064)
			(stroke
				(width 0.1524)
				(type default)
			)
			(layer "B.SilkS")
		)
		(fp_line
			(start 0.67945 -0.305054)
			(end 0.12065 -0.305054)
			(stroke
				(width 0.1)
				(type default)
			)
			(layer "B.Fab")
		)
		(fp_line
			(start 0.12065 -0.305054)
			(end 0.12065 -0.2794)
			(stroke
				(width 0.1)
				(type default)
			)
			(layer "B.Fab")
		)
		(fp_line
			(start -0.12065 -0.3048)
			(end -0.67945 -0.3048)
			(stroke
				(width 0.1)
				(type default)
			)
			(layer "B.Fab")
		)
		(fp_line
			(start -0.67945 -0.3048)
			(end -0.67945 0.3048)
			(stroke
				(width 0.1)
				(type default)
			)
			(layer "B.Fab")
		)
		(fp_line
			(start 0.12065 -0.2794)
			(end -0.12065 -0.2794)
			(stroke
				(width 0.1)
				(type default)
			)
			(layer "B.Fab")
		)
		(fp_line
			(start -0.12065 -0.2794)
			(end -0.12065 -0.3048)
			(stroke
				(width 0.1)
				(type default)
			)
			(layer "B.Fab")
		)
		(fp_line
			(start 0.12065 0.2794)
			(end 0.12065 0.3048)
			(stroke
				(width 0.1)
				(type default)
			)
			(layer "B.Fab")
		)
		(fp_line
			(start -0.120396 0.2794)
			(end 0.12065 0.2794)
			(stroke
				(width 0.1)
				(type default)
			)
			(layer "B.Fab")
		)
		(fp_line
			(start 0.67945 0.3048)
			(end 0.67945 -0.305054)
			(stroke
				(width 0.1)
				(type default)
			)
			(layer "B.Fab")
		)
		(fp_line
			(start 0.12065 0.3048)
			(end 0.67945 0.3048)
			(stroke
				(width 0.1)
				(type default)
			)
			(layer "B.Fab")
		)
		(fp_line
			(start -0.120396 0.3048)
			(end -0.120396 0.2794)
			(stroke
				(width 0.1)
				(type default)
			)
			(layer "B.Fab")
		)
		(fp_line
			(start -0.67945 0.3048)
			(end -0.120396 0.3048)
			(stroke
				(width 0.1)
				(type default)
			)
			(layer "B.Fab")
		)
		(pad "1" smd circle
			(at 0.40005 0 270)
			(size 0 0)
			(layers "B.Cu" "B.Mask" "B.Paste")
			(net "LED_PWRGD_PVDDCR_CPU1_P1_R")
		)
		(pad "2" smd circle
			(at -0.40005 0 270)
			(size 0 0)
			(layers "B.Cu" "B.Mask" "B.Paste")
			(net "P3V3_AUX")
		)
	)
	(footprint ""
		(layer "B.Cu")
		(at 194.945 -100.294948 -90)
		(property "Reference" "R267"
			(at 0 0 90)
			(layer "B.SilkS")
			(hide yes)
			(effects
				(font
					(size 1.27 1.27)
				)
				(justify mirror)
			)
		)
		(property "Value" ""
			(at 0 0 90)
			(layer "B.Fab")
			(effects
				(font
					(size 1.27 1.27)
				)
				(justify mirror)
			)
		)
		(duplicate_pad_numbers_are_jumpers no)
		(fp_line
			(start -0.7874 0.4064)
			(end 0.7874 0.4064)
			(stroke
				(width 0.1524)
				(type default)
			)
			(layer "B.SilkS")
		)
		(fp_line
			(start 0.7874 0.4064)
			(end 0.7874 -0.4064)
			(stroke
				(width 0.1524)
				(type default)
			)
			(layer "B.SilkS")
		)
		(fp_line
			(start -0.7874 -0.4064)
			(end -0.7874 0.4064)
			(stroke
				(width 0.1524)
				(type default)
			)
			(layer "B.SilkS")
		)
		(fp_line
			(start 0.7874 -0.4064)
			(end -0.7874 -0.4064)
			(stroke
				(width 0.1524)
				(type default)
			)
			(layer "B.SilkS")
		)
		(fp_line
			(start -0.67945 0.3048)
			(end -0.120396 0.3048)
			(stroke
				(width 0.1)
				(type default)
			)
			(layer "B.Fab")
		)
		(fp_line
			(start -0.120396 0.3048)
			(end -0.120396 0.2794)
			(stroke
				(width 0.1)
				(type default)
			)
			(layer "B.Fab")
		)
		(fp_line
			(start 0.12065 0.3048)
			(end 0.67945 0.3048)
			(stroke
				(width 0.1)
				(type default)
			)
			(layer "B.Fab")
		)
		(fp_line
			(start 0.67945 0.3048)
			(end 0.67945 -0.305054)
			(stroke
				(width 0.1)
				(type default)
			)
			(layer "B.Fab")
		)
		(fp_line
			(start -0.120396 0.2794)
			(end 0.12065 0.2794)
			(stroke
				(width 0.1)
				(type default)
			)
			(layer "B.Fab")
		)
		(fp_line
			(start 0.12065 0.2794)
			(end 0.12065 0.3048)
			(stroke
				(width 0.1)
				(type default)
			)
			(layer "B.Fab")
		)
		(fp_line
			(start -0.12065 -0.2794)
			(end -0.12065 -0.3048)
			(stroke
				(width 0.1)
				(type default)
			)
			(layer "B.Fab")
		)
		(fp_line
			(start 0.12065 -0.2794)
			(end -0.12065 -0.2794)
			(stroke
				(width 0.1)
				(type default)
			)
			(layer "B.Fab")
		)
		(fp_line
			(start -0.67945 -0.3048)
			(end -0.67945 0.3048)
			(stroke
				(width 0.1)
				(type default)
			)
			(layer "B.Fab")
		)
		(fp_line
			(start -0.12065 -0.3048)
			(end -0.67945 -0.3048)
			(stroke
				(width 0.1)
				(type default)
			)
			(layer "B.Fab")
		)
		(fp_line
			(start 0.12065 -0.305054)
			(end 0.12065 -0.2794)
			(stroke
				(width 0.1)
				(type default)
			)
			(layer "B.Fab")
		)
		(fp_line
			(start 0.67945 -0.305054)
			(end 0.12065 -0.305054)
			(stroke
				(width 0.1)
				(type default)
			)
			(layer "B.Fab")
		)
		(pad "1" smd circle
			(at 0.40005 0 90)
			(size 0 0)
			(layers "B.Cu" "B.Mask" "B.Paste")
			(net "CPU1_SA1")
		)
		(pad "2" smd circle
			(at -0.40005 0 90)
			(size 0 0)
			(layers "B.Cu" "B.Mask" "B.Paste")
			(net "FM_CPU1_SA1")
		)
	)
	(footprint ""
		(layer "B.Cu")
		(at 424.012106 -192.660016)
		(property "Reference" "C159"
			(at 0 0 0)
			(layer "B.SilkS")
			(hide yes)
			(effects
				(font
					(size 1.27 1.27)
				)
				(justify mirror)
			)
		)
		(property "Value" ""
			(at 0 0 0)
			(layer "B.Fab")
			(effects
				(font
					(size 1.27 1.27)
				)
				(justify mirror)
			)
		)
		(duplicate_pad_numbers_are_jumpers no)
		(fp_line
			(start -1.524 -0.762)
			(end -1.524 0.762)
			(stroke
				(width 0.1524)
				(type default)
			)
			(layer "B.SilkS")
		)
		(fp_line
			(start -1.524 0.762)
			(end 1.524 0.762)
			(stroke
				(width 0.1524)
				(type default)
			)
			(layer "B.SilkS")
		)
		(fp_line
			(start 1.524 -0.762)
			(end -1.524 -0.762)
			(stroke
				(width 0.1524)
				(type default)
			)
			(layer "B.SilkS")
		)
		(fp_line
			(start 1.524 0.762)
			(end 1.524 -0.762)
			(stroke
				(width 0.1524)
				(type default)
			)
			(layer "B.SilkS")
		)
		(fp_line
			(start -1.1049 -0.724916)
			(end 1.1049 -0.724916)
			(stroke
				(width 0.1)
				(type default)
			)
			(layer "B.Fab")
		)
		(fp_line
			(start -1.1049 0.724916)
			(end -1.1049 -0.724916)
			(stroke
				(width 0.1)
				(type default)
			)
			(layer "B.Fab")
		)
		(fp_line
			(start 1.1049 -0.724916)
			(end 1.1049 0.724916)
			(stroke
				(width 0.1)
				(type default)
			)
			(layer "B.Fab")
		)
		(fp_line
			(start 1.1049 0.724916)
			(end -1.1049 0.724916)
			(stroke
				(width 0.1)
				(type default)
			)
			(layer "B.Fab")
		)
		(pad "1" smd rect
			(at 0.889 0)
			(size 1.016 1.27)
			(layers "B.Cu" "B.Mask" "B.Paste")
			(net "P12V_MEM_CPU0")
		)
		(pad "2" smd rect
			(at -0.889 0)
			(size 1.016 1.27)
			(layers "B.Cu" "B.Mask" "B.Paste")
			(net "GND")
		)
	)
	(footprint ""
		(layer "B.Cu")
		(at 194.33413 -351.23882 90)
		(property "Reference" "PC514_2"
			(at 0 0 90)
			(layer "B.SilkS")
			(hide yes)
			(effects
				(font
					(size 1.27 1.27)
				)
				(justify mirror)
			)
		)
		(property "Value" ""
			(at 0 0 90)
			(layer "B.Fab")
			(effects
				(font
					(size 1.27 1.27)
				)
				(justify mirror)
			)
		)
		(duplicate_pad_numbers_are_jumpers no)
		(fp_line
			(start 1.524 -0.762)
			(end -1.524 -0.762)
			(stroke
				(width 0.1524)
				(type default)
			)
			(layer "B.SilkS")
		)
		(fp_line
			(start -1.524 -0.762)
			(end -1.524 0.762)
			(stroke
				(width 0.1524)
				(type default)
			)
			(layer "B.SilkS")
		)
		(fp_line
			(start 1.524 0.762)
			(end 1.524 -0.762)
			(stroke
				(width 0.1524)
				(type default)
			)
			(layer "B.SilkS")
		)
		(fp_line
			(start -1.524 0.762)
			(end 1.524 0.762)
			(stroke
				(width 0.1524)
				(type default)
			)
			(layer "B.SilkS")
		)
		(fp_line
			(start 1.1049 -0.724916)
			(end 1.1049 0.724916)
			(stroke
				(width 0.1)
				(type default)
			)
			(layer "B.Fab")
		)
		(fp_line
			(start -1.1049 -0.724916)
			(end 1.1049 -0.724916)
			(stroke
				(width 0.1)
				(type default)
			)
			(layer "B.Fab")
		)
		(fp_line
			(start 1.1049 0.724916)
			(end -1.1049 0.724916)
			(stroke
				(width 0.1)
				(type default)
			)
			(layer "B.Fab")
		)
		(fp_line
			(start -1.1049 0.724916)
			(end -1.1049 -0.724916)
			(stroke
				(width 0.1)
				(type default)
			)
			(layer "B.Fab")
		)
		(pad "1" smd rect
			(at 0.889 0 90)
			(size 1.016 1.27)
			(layers "B.Cu" "B.Mask" "B.Paste")
			(net "SW_P12V_AUX_PVDD11_S3_P1_FLT")
		)
		(pad "2" smd rect
			(at -0.889 0 90)
			(size 1.016 1.27)
			(layers "B.Cu" "B.Mask" "B.Paste")
			(net "GND")
		)
	)
	(footprint ""
		(layer "B.Cu")
		(at 217.678 -338.582 180)
		(property "Reference" "R6746"
			(at 0 0 0)
			(layer "B.SilkS")
			(hide yes)
			(effects
				(font
					(size 1.27 1.27)
				)
				(justify mirror)
			)
		)
		(property "Value" ""
			(at 0 0 0)
			(layer "B.Fab")
			(effects
				(font
					(size 1.27 1.27)
				)
				(justify mirror)
			)
		)
		(duplicate_pad_numbers_are_jumpers no)
		(fp_line
			(start 0.32512 0.175006)
			(end 0.32512 -0.175006)
			(stroke
				(width 0.1)
				(type default)
			)
			(layer "B.Fab")
		)
		(fp_line
			(start 0.32512 -0.175006)
			(end -0.32512 -0.175006)
			(stroke
				(width 0.1)
				(type default)
			)
			(layer "B.Fab")
		)
		(fp_line
			(start -0.32512 0.175006)
			(end 0.32512 0.175006)
			(stroke
				(width 0.1)
				(type default)
			)
			(layer "B.Fab")
		)
		(fp_line
			(start -0.32512 -0.175006)
			(end -0.32512 0.175006)
			(stroke
				(width 0.1)
				(type default)
			)
			(layer "B.Fab")
		)
		(pad "1" smd rect
			(at 0.2667 0)
			(size 0.3048 0.381)
			(layers "B.Cu" "B.Mask" "B.Paste")
			(net "SMB_RT_CPU1_P3_R_SDA")
		)
		(pad "2" smd rect
			(at -0.2667 0 180)
			(size 0.3048 0.381)
			(layers "B.Cu" "B.Mask" "B.Paste")
			(net "SMB_RT_CPU1_P3_SDA")
		)
	)
	(footprint ""
		(layer "B.Cu")
		(at 231.648 -340.741 -90)
		(property "Reference" "R6763"
			(at 0 0 90)
			(layer "B.SilkS")
			(hide yes)
			(effects
				(font
					(size 1.27 1.27)
				)
				(justify mirror)
			)
		)
		(property "Value" ""
			(at 0 0 90)
			(layer "B.Fab")
			(effects
				(font
					(size 1.27 1.27)
				)
				(justify mirror)
			)
		)
		(duplicate_pad_numbers_are_jumpers no)
		(fp_line
			(start -0.32512 0.175006)
			(end 0.32512 0.175006)
			(stroke
				(width 0.1)
				(type default)
			)
			(layer "B.Fab")
		)
		(fp_line
			(start 0.32512 0.175006)
			(end 0.32512 -0.175006)
			(stroke
				(width 0.1)
				(type default)
			)
			(layer "B.Fab")
		)
		(fp_line
			(start -0.32512 -0.175006)
			(end -0.32512 0.175006)
			(stroke
				(width 0.1)
				(type default)
			)
			(layer "B.Fab")
		)
		(fp_line
			(start 0.32512 -0.175006)
			(end -0.32512 -0.175006)
			(stroke
				(width 0.1)
				(type default)
			)
			(layer "B.Fab")
		)
		(pad "1" smd rect
			(at 0.2667 0 90)
			(size 0.3048 0.381)
			(layers "B.Cu" "B.Mask" "B.Paste")
			(net "P1V8_CPU0_RT_1D")
		)
		(pad "2" smd rect
			(at -0.2667 0 270)
			(size 0.3048 0.381)
			(layers "B.Cu" "B.Mask" "B.Paste")
			(net "SMB_RT_CPU0_P0_R_SCL")
		)
	)
	(footprint ""
		(layer "B.Cu")
		(at 409.018994 -398.942052 90)
		(property "Reference" "C976"
			(at 0 0 90)
			(layer "B.SilkS")
			(hide yes)
			(effects
				(font
					(size 1.27 1.27)
				)
				(justify mirror)
			)
		)
		(property "Value" ""
			(at 0 0 90)
			(layer "B.Fab")
			(effects
				(font
					(size 1.27 1.27)
				)
				(justify mirror)
			)
		)
		(duplicate_pad_numbers_are_jumpers no)
		(fp_line
			(start 0.7874 -0.4064)
			(end -0.7874 -0.4064)
			(stroke
				(width 0.1524)
				(type default)
			)
			(layer "B.SilkS")
		)
		(fp_line
			(start -0.7874 -0.4064)
			(end -0.7874 0.4064)
			(stroke
				(width 0.1524)
				(type default)
			)
			(layer "B.SilkS")
		)
		(fp_line
			(start 0.7874 0.4064)
			(end 0.7874 -0.4064)
			(stroke
				(width 0.1524)
				(type default)
			)
			(layer "B.SilkS")
		)
		(fp_line
			(start -0.7874 0.4064)
			(end 0.7874 0.4064)
			(stroke
				(width 0.1524)
				(type default)
			)
			(layer "B.SilkS")
		)
		(fp_line
			(start 0.67945 -0.305054)
			(end 0.12065 -0.305054)
			(stroke
				(width 0.1)
				(type default)
			)
			(layer "B.Fab")
		)
		(fp_line
			(start 0.12065 -0.305054)
			(end 0.12065 -0.2794)
			(stroke
				(width 0.1)
				(type default)
			)
			(layer "B.Fab")
		)
		(fp_line
			(start -0.12065 -0.3048)
			(end -0.67945 -0.3048)
			(stroke
				(width 0.1)
				(type default)
			)
			(layer "B.Fab")
		)
		(fp_line
			(start -0.67945 -0.3048)
			(end -0.67945 0.3048)
			(stroke
				(width 0.1)
				(type default)
			)
			(layer "B.Fab")
		)
		(fp_line
			(start 0.12065 -0.2794)
			(end -0.12065 -0.2794)
			(stroke
				(width 0.1)
				(type default)
			)
			(layer "B.Fab")
		)
		(fp_line
			(start -0.12065 -0.2794)
			(end -0.12065 -0.3048)
			(stroke
				(width 0.1)
				(type default)
			)
			(layer "B.Fab")
		)
		(fp_line
			(start 0.12065 0.2794)
			(end 0.12065 0.3048)
			(stroke
				(width 0.1)
				(type default)
			)
			(layer "B.Fab")
		)
		(fp_line
			(start -0.120396 0.2794)
			(end 0.12065 0.2794)
			(stroke
				(width 0.1)
				(type default)
			)
			(layer "B.Fab")
		)
		(fp_line
			(start 0.67945 0.3048)
			(end 0.67945 -0.305054)
			(stroke
				(width 0.1)
				(type default)
			)
			(layer "B.Fab")
		)
		(fp_line
			(start 0.12065 0.3048)
			(end 0.67945 0.3048)
			(stroke
				(width 0.1)
				(type default)
			)
			(layer "B.Fab")
		)
		(fp_line
			(start -0.120396 0.3048)
			(end -0.120396 0.2794)
			(stroke
				(width 0.1)
				(type default)
			)
			(layer "B.Fab")
		)
		(fp_line
			(start -0.67945 0.3048)
			(end -0.120396 0.3048)
			(stroke
				(width 0.1)
				(type default)
			)
			(layer "B.Fab")
		)
		(pad "1" smd circle
			(at 0.40005 0 270)
			(size 0 0)
			(layers "B.Cu" "B.Mask" "B.Paste")
			(net "P0V9_CPU0_RT_2D")
		)
		(pad "2" smd circle
			(at -0.40005 0 270)
			(size 0 0)
			(layers "B.Cu" "B.Mask" "B.Paste")
			(net "GND")
		)
	)
	(footprint ""
		(layer "B.Cu")
		(at 62.68847 -15.58036 90)
		(property "Reference" "R3208"
			(at 0 0 90)
			(layer "B.SilkS")
			(hide yes)
			(effects
				(font
					(size 1.27 1.27)
				)
				(justify mirror)
			)
		)
		(property "Value" ""
			(at 0 0 90)
			(layer "B.Fab")
			(effects
				(font
					(size 1.27 1.27)
				)
				(justify mirror)
			)
		)
		(duplicate_pad_numbers_are_jumpers no)
		(fp_line
			(start 0.7874 -0.4064)
			(end -0.7874 -0.4064)
			(stroke
				(width 0.1524)
				(type default)
			)
			(layer "B.SilkS")
		)
		(fp_line
			(start -0.7874 -0.4064)
			(end -0.7874 0.4064)
			(stroke
				(width 0.1524)
				(type default)
			)
			(layer "B.SilkS")
		)
		(fp_line
			(start 0.7874 0.4064)
			(end 0.7874 -0.4064)
			(stroke
				(width 0.1524)
				(type default)
			)
			(layer "B.SilkS")
		)
		(fp_line
			(start -0.7874 0.4064)
			(end 0.7874 0.4064)
			(stroke
				(width 0.1524)
				(type default)
			)
			(layer "B.SilkS")
		)
		(fp_line
			(start 0.67945 -0.305054)
			(end 0.12065 -0.305054)
			(stroke
				(width 0.1)
				(type default)
			)
			(layer "B.Fab")
		)
		(fp_line
			(start 0.12065 -0.305054)
			(end 0.12065 -0.2794)
			(stroke
				(width 0.1)
				(type default)
			)
			(layer "B.Fab")
		)
		(fp_line
			(start -0.12065 -0.3048)
			(end -0.67945 -0.3048)
			(stroke
				(width 0.1)
				(type default)
			)
			(layer "B.Fab")
		)
		(fp_line
			(start -0.67945 -0.3048)
			(end -0.67945 0.3048)
			(stroke
				(width 0.1)
				(type default)
			)
			(layer "B.Fab")
		)
		(fp_line
			(start 0.12065 -0.2794)
			(end -0.12065 -0.2794)
			(stroke
				(width 0.1)
				(type default)
			)
			(layer "B.Fab")
		)
		(fp_line
			(start -0.12065 -0.2794)
			(end -0.12065 -0.3048)
			(stroke
				(width 0.1)
				(type default)
			)
			(layer "B.Fab")
		)
		(fp_line
			(start 0.12065 0.2794)
			(end 0.12065 0.3048)
			(stroke
				(width 0.1)
				(type default)
			)
			(layer "B.Fab")
		)
		(fp_line
			(start -0.120396 0.2794)
			(end 0.12065 0.2794)
			(stroke
				(width 0.1)
				(type default)
			)
			(layer "B.Fab")
		)
		(fp_line
			(start 0.67945 0.3048)
			(end 0.67945 -0.305054)
			(stroke
				(width 0.1)
				(type default)
			)
			(layer "B.Fab")
		)
		(fp_line
			(start 0.12065 0.3048)
			(end 0.67945 0.3048)
			(stroke
				(width 0.1)
				(type default)
			)
			(layer "B.Fab")
		)
		(fp_line
			(start -0.120396 0.3048)
			(end -0.120396 0.2794)
			(stroke
				(width 0.1)
				(type default)
			)
			(layer "B.Fab")
		)
		(fp_line
			(start -0.67945 0.3048)
			(end -0.120396 0.3048)
			(stroke
				(width 0.1)
				(type default)
			)
			(layer "B.Fab")
		)
		(pad "1" smd circle
			(at 0.40005 0 270)
			(size 0 0)
			(layers "B.Cu" "B.Mask" "B.Paste")
			(net "OCP_V3_2_ISO_BIF0_EN")
		)
		(pad "2" smd circle
			(at -0.40005 0 270)
			(size 0 0)
			(layers "B.Cu" "B.Mask" "B.Paste")
			(net "GND")
		)
	)
	(footprint ""
		(layer "B.Cu")
		(at 421.333168 -352.174048 -90)
		(property "Reference" "PR131"
			(at 0 0 90)
			(layer "B.SilkS")
			(hide yes)
			(effects
				(font
					(size 1.27 1.27)
				)
				(justify mirror)
			)
		)
		(property "Value" ""
			(at 0 0 90)
			(layer "B.Fab")
			(effects
				(font
					(size 1.27 1.27)
				)
				(justify mirror)
			)
		)
		(duplicate_pad_numbers_are_jumpers no)
		(fp_line
			(start -0.7874 0.4064)
			(end 0.7874 0.4064)
			(stroke
				(width 0.1524)
				(type default)
			)
			(layer "B.SilkS")
		)
		(fp_line
			(start 0.7874 0.4064)
			(end 0.7874 -0.4064)
			(stroke
				(width 0.1524)
				(type default)
			)
			(layer "B.SilkS")
		)
		(fp_line
			(start -0.7874 -0.4064)
			(end -0.7874 0.4064)
			(stroke
				(width 0.1524)
				(type default)
			)
			(layer "B.SilkS")
		)
		(fp_line
			(start 0.7874 -0.4064)
			(end -0.7874 -0.4064)
			(stroke
				(width 0.1524)
				(type default)
			)
			(layer "B.SilkS")
		)
		(fp_line
			(start -0.67945 0.3048)
			(end -0.120396 0.3048)
			(stroke
				(width 0.1)
				(type default)
			)
			(layer "B.Fab")
		)
		(fp_line
			(start -0.120396 0.3048)
			(end -0.120396 0.2794)
			(stroke
				(width 0.1)
				(type default)
			)
			(layer "B.Fab")
		)
		(fp_line
			(start 0.12065 0.3048)
			(end 0.67945 0.3048)
			(stroke
				(width 0.1)
				(type default)
			)
			(layer "B.Fab")
		)
		(fp_line
			(start 0.67945 0.3048)
			(end 0.67945 -0.305054)
			(stroke
				(width 0.1)
				(type default)
			)
			(layer "B.Fab")
		)
		(fp_line
			(start -0.120396 0.2794)
			(end 0.12065 0.2794)
			(stroke
				(width 0.1)
				(type default)
			)
			(layer "B.Fab")
		)
		(fp_line
			(start 0.12065 0.2794)
			(end 0.12065 0.3048)
			(stroke
				(width 0.1)
				(type default)
			)
			(layer "B.Fab")
		)
		(fp_line
			(start -0.12065 -0.2794)
			(end -0.12065 -0.3048)
			(stroke
				(width 0.1)
				(type default)
			)
			(layer "B.Fab")
		)
		(fp_line
			(start 0.12065 -0.2794)
			(end -0.12065 -0.2794)
			(stroke
				(width 0.1)
				(type default)
			)
			(layer "B.Fab")
		)
		(fp_line
			(start -0.67945 -0.3048)
			(end -0.67945 0.3048)
			(stroke
				(width 0.1)
				(type default)
			)
			(layer "B.Fab")
		)
		(fp_line
			(start -0.12065 -0.3048)
			(end -0.67945 -0.3048)
			(stroke
				(width 0.1)
				(type default)
			)
			(layer "B.Fab")
		)
		(fp_line
			(start 0.12065 -0.305054)
			(end 0.12065 -0.2794)
			(stroke
				(width 0.1)
				(type default)
			)
			(layer "B.Fab")
		)
		(fp_line
			(start 0.67945 -0.305054)
			(end 0.12065 -0.305054)
			(stroke
				(width 0.1)
				(type default)
			)
			(layer "B.Fab")
		)
		(pad "1" smd circle
			(at 0.40005 0 90)
			(size 0 0)
			(layers "B.Cu" "B.Mask" "B.Paste")
			(net "PVDD11_S3_P0_PVCC")
		)
		(pad "2" smd circle
			(at -0.40005 0 90)
			(size 0 0)
			(layers "B.Cu" "B.Mask" "B.Paste")
			(net "PVDD11_S3_P0_VCC1")
		)
	)
	(footprint ""
		(layer "B.Cu")
		(at 388.537958 -202.612752 180)
		(property "Reference" "R29"
			(at 0 0 0)
			(layer "B.SilkS")
			(hide yes)
			(effects
				(font
					(size 1.27 1.27)
				)
				(justify mirror)
			)
		)
		(property "Value" ""
			(at 0 0 0)
			(layer "B.Fab")
			(effects
				(font
					(size 1.27 1.27)
				)
				(justify mirror)
			)
		)
		(duplicate_pad_numbers_are_jumpers no)
		(fp_line
			(start 0.7874 0.4064)
			(end 0.7874 -0.4064)
			(stroke
				(width 0.1524)
				(type default)
			)
			(layer "B.SilkS")
		)
		(fp_line
			(start 0.7874 -0.4064)
			(end -0.7874 -0.4064)
			(stroke
				(width 0.1524)
				(type default)
			)
			(layer "B.SilkS")
		)
		(fp_line
			(start -0.7874 0.4064)
			(end 0.7874 0.4064)
			(stroke
				(width 0.1524)
				(type default)
			)
			(layer "B.SilkS")
		)
		(fp_line
			(start -0.7874 -0.4064)
			(end -0.7874 0.4064)
			(stroke
				(width 0.1524)
				(type default)
			)
			(layer "B.SilkS")
		)
		(fp_line
			(start 0.67945 0.3048)
			(end 0.67945 -0.305054)
			(stroke
				(width 0.1)
				(type default)
			)
			(layer "B.Fab")
		)
		(fp_line
			(start 0.67945 -0.305054)
			(end 0.12065 -0.305054)
			(stroke
				(width 0.1)
				(type default)
			)
			(layer "B.Fab")
		)
		(fp_line
			(start 0.12065 0.3048)
			(end 0.67945 0.3048)
			(stroke
				(width 0.1)
				(type default)
			)
			(layer "B.Fab")
		)
		(fp_line
			(start 0.12065 0.2794)
			(end 0.12065 0.3048)
			(stroke
				(width 0.1)
				(type default)
			)
			(layer "B.Fab")
		)
		(fp_line
			(start 0.12065 -0.2794)
			(end -0.12065 -0.2794)
			(stroke
				(width 0.1)
				(type default)
			)
			(layer "B.Fab")
		)
		(fp_line
			(start 0.12065 -0.305054)
			(end 0.12065 -0.2794)
			(stroke
				(width 0.1)
				(type default)
			)
			(layer "B.Fab")
		)
		(fp_line
			(start -0.120396 0.3048)
			(end -0.120396 0.2794)
			(stroke
				(width 0.1)
				(type default)
			)
			(layer "B.Fab")
		)
		(fp_line
			(start -0.120396 0.2794)
			(end 0.12065 0.2794)
			(stroke
				(width 0.1)
				(type default)
			)
			(layer "B.Fab")
		)
		(fp_line
			(start -0.12065 -0.2794)
			(end -0.12065 -0.3048)
			(stroke
				(width 0.1)
				(type default)
			)
			(layer "B.Fab")
		)
		(fp_line
			(start -0.12065 -0.3048)
			(end -0.67945 -0.3048)
			(stroke
				(width 0.1)
				(type default)
			)
			(layer "B.Fab")
		)
		(fp_line
			(start -0.67945 0.3048)
			(end -0.120396 0.3048)
			(stroke
				(width 0.1)
				(type default)
			)
			(layer "B.Fab")
		)
		(fp_line
			(start -0.67945 -0.3048)
			(end -0.67945 0.3048)
			(stroke
				(width 0.1)
				(type default)
			)
			(layer "B.Fab")
		)
		(pad "1" smd circle
			(at 0.40005 0)
			(size 0 0)
			(layers "B.Cu" "B.Mask" "B.Paste")
			(net "SMB_CPU0_3_R_SCL")
		)
		(pad "2" smd circle
			(at -0.40005 0)
			(size 0 0)
			(layers "B.Cu" "B.Mask" "B.Paste")
			(net "SMB_CPU0_3_SCL")
		)
	)
	(footprint ""
		(layer "B.Cu")
		(at 228.834442 -315.95568 -90)
		(property "Reference" "PC6527"
			(at 0 0 90)
			(layer "B.SilkS")
			(hide yes)
			(effects
				(font
					(size 1.27 1.27)
				)
				(justify mirror)
			)
		)
		(property "Value" ""
			(at 0 0 90)
			(layer "B.Fab")
			(effects
				(font
					(size 1.27 1.27)
				)
				(justify mirror)
			)
		)
		(duplicate_pad_numbers_are_jumpers no)
		(fp_line
			(start -1.524 0.762)
			(end 1.524 0.762)
			(stroke
				(width 0.1524)
				(type default)
			)
			(layer "B.SilkS")
		)
		(fp_line
			(start 1.524 0.762)
			(end 1.524 -0.762)
			(stroke
				(width 0.1524)
				(type default)
			)
			(layer "B.SilkS")
		)
		(fp_line
			(start -1.524 -0.762)
			(end -1.524 0.762)
			(stroke
				(width 0.1524)
				(type default)
			)
			(layer "B.SilkS")
		)
		(fp_line
			(start 1.524 -0.762)
			(end -1.524 -0.762)
			(stroke
				(width 0.1524)
				(type default)
			)
			(layer "B.SilkS")
		)
		(fp_line
			(start -1.1049 0.724916)
			(end -1.1049 -0.724916)
			(stroke
				(width 0.1)
				(type default)
			)
			(layer "B.Fab")
		)
		(fp_line
			(start 1.1049 0.724916)
			(end -1.1049 0.724916)
			(stroke
				(width 0.1)
				(type default)
			)
			(layer "B.Fab")
		)
		(fp_line
			(start -1.1049 -0.724916)
			(end 1.1049 -0.724916)
			(stroke
				(width 0.1)
				(type default)
			)
			(layer "B.Fab")
		)
		(fp_line
			(start 1.1049 -0.724916)
			(end 1.1049 0.724916)
			(stroke
				(width 0.1)
				(type default)
			)
			(layer "B.Fab")
		)
		(pad "1" smd rect
			(at 0.889 0 270)
			(size 1.016 1.27)
			(layers "B.Cu" "B.Mask" "B.Paste")
			(net "P1V8_CPU1_RT_1D")
		)
		(pad "2" smd rect
			(at -0.889 0 270)
			(size 1.016 1.27)
			(layers "B.Cu" "B.Mask" "B.Paste")
			(net "GND")
		)
	)
	(footprint ""
		(layer "B.Cu")
		(at 447.656966 -421.374824)
		(property "Reference" "PR6604"
			(at 0 0 0)
			(layer "B.SilkS")
			(hide yes)
			(effects
				(font
					(size 1.27 1.27)
				)
				(justify mirror)
			)
		)
		(property "Value" ""
			(at 0 0 0)
			(layer "B.Fab")
			(effects
				(font
					(size 1.27 1.27)
				)
				(justify mirror)
			)
		)
		(duplicate_pad_numbers_are_jumpers no)
		(fp_line
			(start -0.7874 -0.4064)
			(end -0.7874 0.4064)
			(stroke
				(width 0.1524)
				(type default)
			)
			(layer "B.SilkS")
		)
		(fp_line
			(start -0.7874 0.4064)
			(end 0.7874 0.4064)
			(stroke
				(width 0.1524)
				(type default)
			)
			(layer "B.SilkS")
		)
		(fp_line
			(start 0.7874 -0.4064)
			(end -0.7874 -0.4064)
			(stroke
				(width 0.1524)
				(type default)
			)
			(layer "B.SilkS")
		)
		(fp_line
			(start 0.7874 0.4064)
			(end 0.7874 -0.4064)
			(stroke
				(width 0.1524)
				(type default)
			)
			(layer "B.SilkS")
		)
		(fp_line
			(start -0.67945 -0.3048)
			(end -0.67945 0.3048)
			(stroke
				(width 0.1)
				(type default)
			)
			(layer "B.Fab")
		)
		(fp_line
			(start -0.67945 0.3048)
			(end -0.120396 0.3048)
			(stroke
				(width 0.1)
				(type default)
			)
			(layer "B.Fab")
		)
		(fp_line
			(start -0.12065 -0.3048)
			(end -0.67945 -0.3048)
			(stroke
				(width 0.1)
				(type default)
			)
			(layer "B.Fab")
		)
		(fp_line
			(start -0.12065 -0.2794)
			(end -0.12065 -0.3048)
			(stroke
				(width 0.1)
				(type default)
			)
			(layer "B.Fab")
		)
		(fp_line
			(start -0.120396 0.2794)
			(end 0.12065 0.2794)
			(stroke
				(width 0.1)
				(type default)
			)
			(layer "B.Fab")
		)
		(fp_line
			(start -0.120396 0.3048)
			(end -0.120396 0.2794)
			(stroke
				(width 0.1)
				(type default)
			)
			(layer "B.Fab")
		)
		(fp_line
			(start 0.12065 -0.305054)
			(end 0.12065 -0.2794)
			(stroke
				(width 0.1)
				(type default)
			)
			(layer "B.Fab")
		)
		(fp_line
			(start 0.12065 -0.2794)
			(end -0.12065 -0.2794)
			(stroke
				(width 0.1)
				(type default)
			)
			(layer "B.Fab")
		)
		(fp_line
			(start 0.12065 0.2794)
			(end 0.12065 0.3048)
			(stroke
				(width 0.1)
				(type default)
			)
			(layer "B.Fab")
		)
		(fp_line
			(start 0.12065 0.3048)
			(end 0.67945 0.3048)
			(stroke
				(width 0.1)
				(type default)
			)
			(layer "B.Fab")
		)
		(fp_line
			(start 0.67945 -0.305054)
			(end 0.12065 -0.305054)
			(stroke
				(width 0.1)
				(type default)
			)
			(layer "B.Fab")
		)
		(fp_line
			(start 0.67945 0.3048)
			(end 0.67945 -0.305054)
			(stroke
				(width 0.1)
				(type default)
			)
			(layer "B.Fab")
		)
		(pad "1" smd circle
			(at 0.40005 0 180)
			(size 0 0)
			(layers "B.Cu" "B.Mask" "B.Paste")
			(net "P5V_AUX")
		)
		(pad "2" smd circle
			(at -0.40005 0 180)
			(size 0 0)
			(layers "B.Cu" "B.Mask" "B.Paste")
			(net "P0V9_RETIMER_CPU0_VMON")
		)
	)
	(footprint ""
		(layer "B.Cu")
		(at 120.377966 -408.517344 90)
		(property "Reference" "C6727"
			(at 0 0 90)
			(layer "B.SilkS")
			(hide yes)
			(effects
				(font
					(size 1.27 1.27)
				)
				(justify mirror)
			)
		)
		(property "Value" ""
			(at 0 0 90)
			(layer "B.Fab")
			(effects
				(font
					(size 1.27 1.27)
				)
				(justify mirror)
			)
		)
		(duplicate_pad_numbers_are_jumpers no)
		(fp_line
			(start 0.299974 -0.150114)
			(end -0.299974 -0.150114)
			(stroke
				(width 0.1)
				(type default)
			)
			(layer "B.Fab")
		)
		(fp_line
			(start -0.299974 -0.150114)
			(end -0.299974 0.150114)
			(stroke
				(width 0.1)
				(type default)
			)
			(layer "B.Fab")
		)
		(fp_line
			(start 0.299974 0.150114)
			(end 0.299974 -0.150114)
			(stroke
				(width 0.1)
				(type default)
			)
			(layer "B.Fab")
		)
		(fp_line
			(start -0.299974 0.150114)
			(end 0.299974 0.150114)
			(stroke
				(width 0.1)
				(type default)
			)
			(layer "B.Fab")
		)
		(pad "1" smd rect
			(at 0.2667 0 270)
			(size 0.3048 0.381)
			(layers "B.Cu" "B.Mask" "B.Paste")
			(net "P5E_CPU1_P3_TX_BUF_C_DP<1>")
		)
		(pad "2" smd rect
			(at -0.2667 0 270)
			(size 0.3048 0.381)
			(layers "B.Cu" "B.Mask" "B.Paste")
			(net "P5E_CPU1_P3_TX_BUF_DP<1>")
		)
	)
	(footprint ""
		(layer "B.Cu")
		(at 190.367412 -13.60043 -90)
		(property "Reference" "R6000"
			(at 0 0 90)
			(layer "B.SilkS")
			(hide yes)
			(effects
				(font
					(size 1.27 1.27)
				)
				(justify mirror)
			)
		)
		(property "Value" ""
			(at 0 0 90)
			(layer "B.Fab")
			(effects
				(font
					(size 1.27 1.27)
				)
				(justify mirror)
			)
		)
		(duplicate_pad_numbers_are_jumpers no)
		(fp_line
			(start -0.7874 0.4064)
			(end 0.7874 0.4064)
			(stroke
				(width 0.1524)
				(type default)
			)
			(layer "B.SilkS")
		)
		(fp_line
			(start 0.7874 0.4064)
			(end 0.7874 -0.4064)
			(stroke
				(width 0.1524)
				(type default)
			)
			(layer "B.SilkS")
		)
		(fp_line
			(start -0.7874 -0.4064)
			(end -0.7874 0.4064)
			(stroke
				(width 0.1524)
				(type default)
			)
			(layer "B.SilkS")
		)
		(fp_line
			(start 0.7874 -0.4064)
			(end -0.7874 -0.4064)
			(stroke
				(width 0.1524)
				(type default)
			)
			(layer "B.SilkS")
		)
		(fp_line
			(start -0.67945 0.3048)
			(end -0.120396 0.3048)
			(stroke
				(width 0.1)
				(type default)
			)
			(layer "B.Fab")
		)
		(fp_line
			(start -0.120396 0.3048)
			(end -0.120396 0.2794)
			(stroke
				(width 0.1)
				(type default)
			)
			(layer "B.Fab")
		)
		(fp_line
			(start 0.12065 0.3048)
			(end 0.67945 0.3048)
			(stroke
				(width 0.1)
				(type default)
			)
			(layer "B.Fab")
		)
		(fp_line
			(start 0.67945 0.3048)
			(end 0.67945 -0.305054)
			(stroke
				(width 0.1)
				(type default)
			)
			(layer "B.Fab")
		)
		(fp_line
			(start -0.120396 0.2794)
			(end 0.12065 0.2794)
			(stroke
				(width 0.1)
				(type default)
			)
			(layer "B.Fab")
		)
		(fp_line
			(start 0.12065 0.2794)
			(end 0.12065 0.3048)
			(stroke
				(width 0.1)
				(type default)
			)
			(layer "B.Fab")
		)
		(fp_line
			(start -0.12065 -0.2794)
			(end -0.12065 -0.3048)
			(stroke
				(width 0.1)
				(type default)
			)
			(layer "B.Fab")
		)
		(fp_line
			(start 0.12065 -0.2794)
			(end -0.12065 -0.2794)
			(stroke
				(width 0.1)
				(type default)
			)
			(layer "B.Fab")
		)
		(fp_line
			(start -0.67945 -0.3048)
			(end -0.67945 0.3048)
			(stroke
				(width 0.1)
				(type default)
			)
			(layer "B.Fab")
		)
		(fp_line
			(start -0.12065 -0.3048)
			(end -0.67945 -0.3048)
			(stroke
				(width 0.1)
				(type default)
			)
			(layer "B.Fab")
		)
		(fp_line
			(start 0.12065 -0.305054)
			(end 0.12065 -0.2794)
			(stroke
				(width 0.1)
				(type default)
			)
			(layer "B.Fab")
		)
		(fp_line
			(start 0.67945 -0.305054)
			(end 0.12065 -0.305054)
			(stroke
				(width 0.1)
				(type default)
			)
			(layer "B.Fab")
		)
		(pad "1" smd circle
			(at 0.40005 0 90)
			(size 0 0)
			(layers "B.Cu" "B.Mask" "B.Paste")
			(net "I3C_SCM_0_SCL")
		)
		(pad "2" smd circle
			(at -0.40005 0 90)
			(size 0 0)
			(layers "B.Cu" "B.Mask" "B.Paste")
			(net "I3C_SCM_0_R_SCL")
		)
	)
	(footprint ""
		(layer "B.Cu")
		(at 49.778666 -386.766562 90)
		(property "Reference" "C138"
			(at 0 0 90)
			(layer "B.SilkS")
			(hide yes)
			(effects
				(font
					(size 1.27 1.27)
				)
				(justify mirror)
			)
		)
		(property "Value" ""
			(at 0 0 90)
			(layer "B.Fab")
			(effects
				(font
					(size 1.27 1.27)
				)
				(justify mirror)
			)
		)
		(duplicate_pad_numbers_are_jumpers no)
		(fp_line
			(start 0.299974 -0.150114)
			(end -0.299974 -0.150114)
			(stroke
				(width 0.1)
				(type default)
			)
			(layer "B.Fab")
		)
		(fp_line
			(start -0.299974 -0.150114)
			(end -0.299974 0.150114)
			(stroke
				(width 0.1)
				(type default)
			)
			(layer "B.Fab")
		)
		(fp_line
			(start 0.299974 0.150114)
			(end 0.299974 -0.150114)
			(stroke
				(width 0.1)
				(type default)
			)
			(layer "B.Fab")
		)
		(fp_line
			(start -0.299974 0.150114)
			(end 0.299974 0.150114)
			(stroke
				(width 0.1)
				(type default)
			)
			(layer "B.Fab")
		)
		(pad "1" smd rect
			(at 0.2667 0 270)
			(size 0.3048 0.381)
			(layers "B.Cu" "B.Mask" "B.Paste")
			(net "P0V9_CPU1_RT0_2A")
		)
		(pad "2" smd rect
			(at -0.2667 0 270)
			(size 0.3048 0.381)
			(layers "B.Cu" "B.Mask" "B.Paste")
			(net "GND")
		)
	)
	(footprint ""
		(layer "B.Cu")
		(at 82.446368 -388.011162 -90)
		(property "Reference" "C319"
			(at 0 0 90)
			(layer "B.SilkS")
			(hide yes)
			(effects
				(font
					(size 1.27 1.27)
				)
				(justify mirror)
			)
		)
		(property "Value" ""
			(at 0 0 90)
			(layer "B.Fab")
			(effects
				(font
					(size 1.27 1.27)
				)
				(justify mirror)
			)
		)
		(duplicate_pad_numbers_are_jumpers no)
		(fp_line
			(start -0.299974 0.150114)
			(end 0.299974 0.150114)
			(stroke
				(width 0.1)
				(type default)
			)
			(layer "B.Fab")
		)
		(fp_line
			(start 0.299974 0.150114)
			(end 0.299974 -0.150114)
			(stroke
				(width 0.1)
				(type default)
			)
			(layer "B.Fab")
		)
		(fp_line
			(start -0.299974 -0.150114)
			(end -0.299974 0.150114)
			(stroke
				(width 0.1)
				(type default)
			)
			(layer "B.Fab")
		)
		(fp_line
			(start 0.299974 -0.150114)
			(end -0.299974 -0.150114)
			(stroke
				(width 0.1)
				(type default)
			)
			(layer "B.Fab")
		)
		(pad "1" smd rect
			(at 0.2667 0 90)
			(size 0.3048 0.381)
			(layers "B.Cu" "B.Mask" "B.Paste")
			(net "P0V9_CPU1_RT1_2A")
		)
		(pad "2" smd rect
			(at -0.2667 0 90)
			(size 0.3048 0.381)
			(layers "B.Cu" "B.Mask" "B.Paste")
			(net "GND")
		)
	)
	(footprint ""
		(layer "B.Cu")
		(at 286.893 -415.798 -90)
		(property "Reference" "C80"
			(at 0 0 90)
			(layer "B.SilkS")
			(hide yes)
			(effects
				(font
					(size 1.27 1.27)
				)
				(justify mirror)
			)
		)
		(property "Value" ""
			(at 0 0 90)
			(layer "B.Fab")
			(effects
				(font
					(size 1.27 1.27)
				)
				(justify mirror)
			)
		)
		(duplicate_pad_numbers_are_jumpers no)
		(fp_line
			(start -0.7874 0.4064)
			(end 0.7874 0.4064)
			(stroke
				(width 0.1524)
				(type default)
			)
			(layer "B.SilkS")
		)
		(fp_line
			(start 0.7874 0.4064)
			(end 0.7874 -0.4064)
			(stroke
				(width 0.1524)
				(type default)
			)
			(layer "B.SilkS")
		)
		(fp_line
			(start -0.7874 -0.4064)
			(end -0.7874 0.4064)
			(stroke
				(width 0.1524)
				(type default)
			)
			(layer "B.SilkS")
		)
		(fp_line
			(start 0.7874 -0.4064)
			(end -0.7874 -0.4064)
			(stroke
				(width 0.1524)
				(type default)
			)
			(layer "B.SilkS")
		)
		(fp_line
			(start -0.67945 0.3048)
			(end -0.120396 0.3048)
			(stroke
				(width 0.1)
				(type default)
			)
			(layer "B.Fab")
		)
		(fp_line
			(start -0.120396 0.3048)
			(end -0.120396 0.2794)
			(stroke
				(width 0.1)
				(type default)
			)
			(layer "B.Fab")
		)
		(fp_line
			(start 0.12065 0.3048)
			(end 0.67945 0.3048)
			(stroke
				(width 0.1)
				(type default)
			)
			(layer "B.Fab")
		)
		(fp_line
			(start 0.67945 0.3048)
			(end 0.67945 -0.305054)
			(stroke
				(width 0.1)
				(type default)
			)
			(layer "B.Fab")
		)
		(fp_line
			(start -0.120396 0.2794)
			(end 0.12065 0.2794)
			(stroke
				(width 0.1)
				(type default)
			)
			(layer "B.Fab")
		)
		(fp_line
			(start 0.12065 0.2794)
			(end 0.12065 0.3048)
			(stroke
				(width 0.1)
				(type default)
			)
			(layer "B.Fab")
		)
		(fp_line
			(start -0.12065 -0.2794)
			(end -0.12065 -0.3048)
			(stroke
				(width 0.1)
				(type default)
			)
			(layer "B.Fab")
		)
		(fp_line
			(start 0.12065 -0.2794)
			(end -0.12065 -0.2794)
			(stroke
				(width 0.1)
				(type default)
			)
			(layer "B.Fab")
		)
		(fp_line
			(start -0.67945 -0.3048)
			(end -0.67945 0.3048)
			(stroke
				(width 0.1)
				(type default)
			)
			(layer "B.Fab")
		)
		(fp_line
			(start -0.12065 -0.3048)
			(end -0.67945 -0.3048)
			(stroke
				(width 0.1)
				(type default)
			)
			(layer "B.Fab")
		)
		(fp_line
			(start 0.12065 -0.305054)
			(end 0.12065 -0.2794)
			(stroke
				(width 0.1)
				(type default)
			)
			(layer "B.Fab")
		)
		(fp_line
			(start 0.67945 -0.305054)
			(end 0.12065 -0.305054)
			(stroke
				(width 0.1)
				(type default)
			)
			(layer "B.Fab")
		)
		(pad "1" smd circle
			(at 0.40005 0 90)
			(size 0 0)
			(layers "B.Cu" "B.Mask" "B.Paste")
			(net "P3V3_9ZXL045_P0_VDD")
		)
		(pad "2" smd circle
			(at -0.40005 0 90)
			(size 0 0)
			(layers "B.Cu" "B.Mask" "B.Paste")
			(net "GND")
		)
	)
	(footprint ""
		(layer "B.Cu")
		(at 17.779492 -97.342198 90)
		(property "Reference" "C2040"
			(at 0 0 90)
			(layer "B.SilkS")
			(hide yes)
			(effects
				(font
					(size 1.27 1.27)
				)
				(justify mirror)
			)
		)
		(property "Value" ""
			(at 0 0 90)
			(layer "B.Fab")
			(effects
				(font
					(size 1.27 1.27)
				)
				(justify mirror)
			)
		)
		(duplicate_pad_numbers_are_jumpers no)
		(fp_line
			(start 0.7874 -0.4064)
			(end -0.7874 -0.4064)
			(stroke
				(width 0.1524)
				(type default)
			)
			(layer "B.SilkS")
		)
		(fp_line
			(start -0.7874 -0.4064)
			(end -0.7874 0.4064)
			(stroke
				(width 0.1524)
				(type default)
			)
			(layer "B.SilkS")
		)
		(fp_line
			(start 0.7874 0.4064)
			(end 0.7874 -0.4064)
			(stroke
				(width 0.1524)
				(type default)
			)
			(layer "B.SilkS")
		)
		(fp_line
			(start -0.7874 0.4064)
			(end 0.7874 0.4064)
			(stroke
				(width 0.1524)
				(type default)
			)
			(layer "B.SilkS")
		)
		(fp_line
			(start 0.67945 -0.305054)
			(end 0.12065 -0.305054)
			(stroke
				(width 0.1)
				(type default)
			)
			(layer "B.Fab")
		)
		(fp_line
			(start 0.12065 -0.305054)
			(end 0.12065 -0.2794)
			(stroke
				(width 0.1)
				(type default)
			)
			(layer "B.Fab")
		)
		(fp_line
			(start -0.12065 -0.3048)
			(end -0.67945 -0.3048)
			(stroke
				(width 0.1)
				(type default)
			)
			(layer "B.Fab")
		)
		(fp_line
			(start -0.67945 -0.3048)
			(end -0.67945 0.3048)
			(stroke
				(width 0.1)
				(type default)
			)
			(layer "B.Fab")
		)
		(fp_line
			(start 0.12065 -0.2794)
			(end -0.12065 -0.2794)
			(stroke
				(width 0.1)
				(type default)
			)
			(layer "B.Fab")
		)
		(fp_line
			(start -0.12065 -0.2794)
			(end -0.12065 -0.3048)
			(stroke
				(width 0.1)
				(type default)
			)
			(layer "B.Fab")
		)
		(fp_line
			(start 0.12065 0.2794)
			(end 0.12065 0.3048)
			(stroke
				(width 0.1)
				(type default)
			)
			(layer "B.Fab")
		)
		(fp_line
			(start -0.120396 0.2794)
			(end 0.12065 0.2794)
			(stroke
				(width 0.1)
				(type default)
			)
			(layer "B.Fab")
		)
		(fp_line
			(start 0.67945 0.3048)
			(end 0.67945 -0.305054)
			(stroke
				(width 0.1)
				(type default)
			)
			(layer "B.Fab")
		)
		(fp_line
			(start 0.12065 0.3048)
			(end 0.67945 0.3048)
			(stroke
				(width 0.1)
				(type default)
			)
			(layer "B.Fab")
		)
		(fp_line
			(start -0.120396 0.3048)
			(end -0.120396 0.2794)
			(stroke
				(width 0.1)
				(type default)
			)
			(layer "B.Fab")
		)
		(fp_line
			(start -0.67945 0.3048)
			(end -0.120396 0.3048)
			(stroke
				(width 0.1)
				(type default)
			)
			(layer "B.Fab")
		)
		(pad "1" smd circle
			(at 0.40005 0 270)
			(size 0 0)
			(layers "B.Cu" "B.Mask" "B.Paste")
			(net "P3V3_AUX_USB_HUB")
		)
		(pad "2" smd circle
			(at -0.40005 0 270)
			(size 0 0)
			(layers "B.Cu" "B.Mask" "B.Paste")
			(net "GND")
		)
	)
	(footprint ""
		(layer "B.Cu")
		(at 331.793342 -392.1252 180)
		(property "Reference" "R1022"
			(at 0 0 0)
			(layer "B.SilkS")
			(hide yes)
			(effects
				(font
					(size 1.27 1.27)
				)
				(justify mirror)
			)
		)
		(property "Value" ""
			(at 0 0 0)
			(layer "B.Fab")
			(effects
				(font
					(size 1.27 1.27)
				)
				(justify mirror)
			)
		)
		(duplicate_pad_numbers_are_jumpers no)
		(fp_line
			(start 0.32512 0.175006)
			(end 0.32512 -0.175006)
			(stroke
				(width 0.1)
				(type default)
			)
			(layer "B.Fab")
		)
		(fp_line
			(start 0.32512 -0.175006)
			(end -0.32512 -0.175006)
			(stroke
				(width 0.1)
				(type default)
			)
			(layer "B.Fab")
		)
		(fp_line
			(start -0.32512 0.175006)
			(end 0.32512 0.175006)
			(stroke
				(width 0.1)
				(type default)
			)
			(layer "B.Fab")
		)
		(fp_line
			(start -0.32512 -0.175006)
			(end -0.32512 0.175006)
			(stroke
				(width 0.1)
				(type default)
			)
			(layer "B.Fab")
		)
		(pad "1" smd rect
			(at 0.2667 0)
			(size 0.3048 0.381)
			(layers "B.Cu" "B.Mask" "B.Paste")
			(net "RT_CPU0_P1_SCAN_MODE")
		)
		(pad "2" smd rect
			(at -0.2667 0 180)
			(size 0.3048 0.381)
			(layers "B.Cu" "B.Mask" "B.Paste")
			(net "GND")
		)
	)
	(footprint ""
		(layer "B.Cu")
		(at 367.614454 -266.00531)
		(property "Reference" "C2142"
			(at 0 0 0)
			(layer "B.SilkS")
			(hide yes)
			(effects
				(font
					(size 1.27 1.27)
				)
				(justify mirror)
			)
		)
		(property "Value" ""
			(at 0 0 0)
			(layer "B.Fab")
			(effects
				(font
					(size 1.27 1.27)
				)
				(justify mirror)
			)
		)
		(duplicate_pad_numbers_are_jumpers no)
		(fp_line
			(start -0.7874 -0.4064)
			(end -0.7874 0.4064)
			(stroke
				(width 0.1524)
				(type default)
			)
			(layer "B.SilkS")
		)
		(fp_line
			(start -0.7874 0.4064)
			(end 0.7874 0.4064)
			(stroke
				(width 0.1524)
				(type default)
			)
			(layer "B.SilkS")
		)
		(fp_line
			(start 0.7874 -0.4064)
			(end -0.7874 -0.4064)
			(stroke
				(width 0.1524)
				(type default)
			)
			(layer "B.SilkS")
		)
		(fp_line
			(start 0.7874 0.4064)
			(end 0.7874 -0.4064)
			(stroke
				(width 0.1524)
				(type default)
			)
			(layer "B.SilkS")
		)
		(fp_line
			(start -0.67945 -0.3048)
			(end -0.67945 0.3048)
			(stroke
				(width 0.1)
				(type default)
			)
			(layer "B.Fab")
		)
		(fp_line
			(start -0.67945 0.3048)
			(end -0.120396 0.3048)
			(stroke
				(width 0.1)
				(type default)
			)
			(layer "B.Fab")
		)
		(fp_line
			(start -0.12065 -0.3048)
			(end -0.67945 -0.3048)
			(stroke
				(width 0.1)
				(type default)
			)
			(layer "B.Fab")
		)
		(fp_line
			(start -0.12065 -0.2794)
			(end -0.12065 -0.3048)
			(stroke
				(width 0.1)
				(type default)
			)
			(layer "B.Fab")
		)
		(fp_line
			(start -0.120396 0.2794)
			(end 0.12065 0.2794)
			(stroke
				(width 0.1)
				(type default)
			)
			(layer "B.Fab")
		)
		(fp_line
			(start -0.120396 0.3048)
			(end -0.120396 0.2794)
			(stroke
				(width 0.1)
				(type default)
			)
			(layer "B.Fab")
		)
		(fp_line
			(start 0.12065 -0.305054)
			(end 0.12065 -0.2794)
			(stroke
				(width 0.1)
				(type default)
			)
			(layer "B.Fab")
		)
		(fp_line
			(start 0.12065 -0.2794)
			(end -0.12065 -0.2794)
			(stroke
				(width 0.1)
				(type default)
			)
			(layer "B.Fab")
		)
		(fp_line
			(start 0.12065 0.2794)
			(end 0.12065 0.3048)
			(stroke
				(width 0.1)
				(type default)
			)
			(layer "B.Fab")
		)
		(fp_line
			(start 0.12065 0.3048)
			(end 0.67945 0.3048)
			(stroke
				(width 0.1)
				(type default)
			)
			(layer "B.Fab")
		)
		(fp_line
			(start 0.67945 -0.305054)
			(end 0.12065 -0.305054)
			(stroke
				(width 0.1)
				(type default)
			)
			(layer "B.Fab")
		)
		(fp_line
			(start 0.67945 0.3048)
			(end 0.67945 -0.305054)
			(stroke
				(width 0.1)
				(type default)
			)
			(layer "B.Fab")
		)
		(pad "1" smd circle
			(at 0.40005 0 180)
			(size 0 0)
			(layers "B.Cu" "B.Mask" "B.Paste")
			(net "PVDD11_S3_P0")
		)
		(pad "2" smd circle
			(at -0.40005 0 180)
			(size 0 0)
			(layers "B.Cu" "B.Mask" "B.Paste")
			(net "GND")
		)
	)
	(footprint ""
		(layer "B.Cu")
		(at 101.668834 -272.284952 180)
		(property "Reference" "C2389"
			(at 0 0 0)
			(layer "B.SilkS")
			(hide yes)
			(effects
				(font
					(size 1.27 1.27)
				)
				(justify mirror)
			)
		)
		(property "Value" ""
			(at 0 0 0)
			(layer "B.Fab")
			(effects
				(font
					(size 1.27 1.27)
				)
				(justify mirror)
			)
		)
		(duplicate_pad_numbers_are_jumpers no)
		(fp_line
			(start 0.7874 0.4064)
			(end 0.7874 -0.4064)
			(stroke
				(width 0.1524)
				(type default)
			)
			(layer "B.SilkS")
		)
		(fp_line
			(start 0.7874 -0.4064)
			(end -0.7874 -0.4064)
			(stroke
				(width 0.1524)
				(type default)
			)
			(layer "B.SilkS")
		)
		(fp_line
			(start -0.7874 0.4064)
			(end 0.7874 0.4064)
			(stroke
				(width 0.1524)
				(type default)
			)
			(layer "B.SilkS")
		)
		(fp_line
			(start -0.7874 -0.4064)
			(end -0.7874 0.4064)
			(stroke
				(width 0.1524)
				(type default)
			)
			(layer "B.SilkS")
		)
		(fp_line
			(start 0.67945 0.3048)
			(end 0.67945 -0.305054)
			(stroke
				(width 0.1)
				(type default)
			)
			(layer "B.Fab")
		)
		(fp_line
			(start 0.67945 -0.305054)
			(end 0.12065 -0.305054)
			(stroke
				(width 0.1)
				(type default)
			)
			(layer "B.Fab")
		)
		(fp_line
			(start 0.12065 0.3048)
			(end 0.67945 0.3048)
			(stroke
				(width 0.1)
				(type default)
			)
			(layer "B.Fab")
		)
		(fp_line
			(start 0.12065 0.2794)
			(end 0.12065 0.3048)
			(stroke
				(width 0.1)
				(type default)
			)
			(layer "B.Fab")
		)
		(fp_line
			(start 0.12065 -0.2794)
			(end -0.12065 -0.2794)
			(stroke
				(width 0.1)
				(type default)
			)
			(layer "B.Fab")
		)
		(fp_line
			(start 0.12065 -0.305054)
			(end 0.12065 -0.2794)
			(stroke
				(width 0.1)
				(type default)
			)
			(layer "B.Fab")
		)
		(fp_line
			(start -0.120396 0.3048)
			(end -0.120396 0.2794)
			(stroke
				(width 0.1)
				(type default)
			)
			(layer "B.Fab")
		)
		(fp_line
			(start -0.120396 0.2794)
			(end 0.12065 0.2794)
			(stroke
				(width 0.1)
				(type default)
			)
			(layer "B.Fab")
		)
		(fp_line
			(start -0.12065 -0.2794)
			(end -0.12065 -0.3048)
			(stroke
				(width 0.1)
				(type default)
			)
			(layer "B.Fab")
		)
		(fp_line
			(start -0.12065 -0.3048)
			(end -0.67945 -0.3048)
			(stroke
				(width 0.1)
				(type default)
			)
			(layer "B.Fab")
		)
		(fp_line
			(start -0.67945 0.3048)
			(end -0.120396 0.3048)
			(stroke
				(width 0.1)
				(type default)
			)
			(layer "B.Fab")
		)
		(fp_line
			(start -0.67945 -0.3048)
			(end -0.67945 0.3048)
			(stroke
				(width 0.1)
				(type default)
			)
			(layer "B.Fab")
		)
		(pad "1" smd circle
			(at 0.40005 0)
			(size 0 0)
			(layers "B.Cu" "B.Mask" "B.Paste")
			(net "PVDDCR_CPU1_P1")
		)
		(pad "2" smd circle
			(at -0.40005 0)
			(size 0 0)
			(layers "B.Cu" "B.Mask" "B.Paste")
			(net "GND")
		)
	)
	(footprint ""
		(layer "B.Cu")
		(at 375.29135 -398.942052 90)
		(property "Reference" "C1041"
			(at 0 0 90)
			(layer "B.SilkS")
			(hide yes)
			(effects
				(font
					(size 1.27 1.27)
				)
				(justify mirror)
			)
		)
		(property "Value" ""
			(at 0 0 90)
			(layer "B.Fab")
			(effects
				(font
					(size 1.27 1.27)
				)
				(justify mirror)
			)
		)
		(duplicate_pad_numbers_are_jumpers no)
		(fp_line
			(start 0.7874 -0.4064)
			(end -0.7874 -0.4064)
			(stroke
				(width 0.1524)
				(type default)
			)
			(layer "B.SilkS")
		)
		(fp_line
			(start -0.7874 -0.4064)
			(end -0.7874 0.4064)
			(stroke
				(width 0.1524)
				(type default)
			)
			(layer "B.SilkS")
		)
		(fp_line
			(start 0.7874 0.4064)
			(end 0.7874 -0.4064)
			(stroke
				(width 0.1524)
				(type default)
			)
			(layer "B.SilkS")
		)
		(fp_line
			(start -0.7874 0.4064)
			(end 0.7874 0.4064)
			(stroke
				(width 0.1524)
				(type default)
			)
			(layer "B.SilkS")
		)
		(fp_line
			(start 0.67945 -0.305054)
			(end 0.12065 -0.305054)
			(stroke
				(width 0.1)
				(type default)
			)
			(layer "B.Fab")
		)
		(fp_line
			(start 0.12065 -0.305054)
			(end 0.12065 -0.2794)
			(stroke
				(width 0.1)
				(type default)
			)
			(layer "B.Fab")
		)
		(fp_line
			(start -0.12065 -0.3048)
			(end -0.67945 -0.3048)
			(stroke
				(width 0.1)
				(type default)
			)
			(layer "B.Fab")
		)
		(fp_line
			(start -0.67945 -0.3048)
			(end -0.67945 0.3048)
			(stroke
				(width 0.1)
				(type default)
			)
			(layer "B.Fab")
		)
		(fp_line
			(start 0.12065 -0.2794)
			(end -0.12065 -0.2794)
			(stroke
				(width 0.1)
				(type default)
			)
			(layer "B.Fab")
		)
		(fp_line
			(start -0.12065 -0.2794)
			(end -0.12065 -0.3048)
			(stroke
				(width 0.1)
				(type default)
			)
			(layer "B.Fab")
		)
		(fp_line
			(start 0.12065 0.2794)
			(end 0.12065 0.3048)
			(stroke
				(width 0.1)
				(type default)
			)
			(layer "B.Fab")
		)
		(fp_line
			(start -0.120396 0.2794)
			(end 0.12065 0.2794)
			(stroke
				(width 0.1)
				(type default)
			)
			(layer "B.Fab")
		)
		(fp_line
			(start 0.67945 0.3048)
			(end 0.67945 -0.305054)
			(stroke
				(width 0.1)
				(type default)
			)
			(layer "B.Fab")
		)
		(fp_line
			(start 0.12065 0.3048)
			(end 0.67945 0.3048)
			(stroke
				(width 0.1)
				(type default)
			)
			(layer "B.Fab")
		)
		(fp_line
			(start -0.120396 0.3048)
			(end -0.120396 0.2794)
			(stroke
				(width 0.1)
				(type default)
			)
			(layer "B.Fab")
		)
		(fp_line
			(start -0.67945 0.3048)
			(end -0.120396 0.3048)
			(stroke
				(width 0.1)
				(type default)
			)
			(layer "B.Fab")
		)
		(pad "1" smd circle
			(at 0.40005 0 270)
			(size 0 0)
			(layers "B.Cu" "B.Mask" "B.Paste")
			(net "P0V9_CPU0_RT3_2A")
		)
		(pad "2" smd circle
			(at -0.40005 0 270)
			(size 0 0)
			(layers "B.Cu" "B.Mask" "B.Paste")
			(net "GND")
		)
	)
	(footprint ""
		(layer "B.Cu")
		(at 149.243034 -203.704952 90)
		(property "Reference" "R528"
			(at 0 0 90)
			(layer "B.SilkS")
			(hide yes)
			(effects
				(font
					(size 1.27 1.27)
				)
				(justify mirror)
			)
		)
		(property "Value" ""
			(at 0 0 90)
			(layer "B.Fab")
			(effects
				(font
					(size 1.27 1.27)
				)
				(justify mirror)
			)
		)
		(duplicate_pad_numbers_are_jumpers no)
		(fp_line
			(start 0.7874 -0.4064)
			(end -0.7874 -0.4064)
			(stroke
				(width 0.1524)
				(type default)
			)
			(layer "B.SilkS")
		)
		(fp_line
			(start -0.7874 -0.4064)
			(end -0.7874 0.4064)
			(stroke
				(width 0.1524)
				(type default)
			)
			(layer "B.SilkS")
		)
		(fp_line
			(start 0.7874 0.4064)
			(end 0.7874 -0.4064)
			(stroke
				(width 0.1524)
				(type default)
			)
			(layer "B.SilkS")
		)
		(fp_line
			(start -0.7874 0.4064)
			(end 0.7874 0.4064)
			(stroke
				(width 0.1524)
				(type default)
			)
			(layer "B.SilkS")
		)
		(fp_line
			(start 0.67945 -0.305054)
			(end 0.12065 -0.305054)
			(stroke
				(width 0.1)
				(type default)
			)
			(layer "B.Fab")
		)
		(fp_line
			(start 0.12065 -0.305054)
			(end 0.12065 -0.2794)
			(stroke
				(width 0.1)
				(type default)
			)
			(layer "B.Fab")
		)
		(fp_line
			(start -0.12065 -0.3048)
			(end -0.67945 -0.3048)
			(stroke
				(width 0.1)
				(type default)
			)
			(layer "B.Fab")
		)
		(fp_line
			(start -0.67945 -0.3048)
			(end -0.67945 0.3048)
			(stroke
				(width 0.1)
				(type default)
			)
			(layer "B.Fab")
		)
		(fp_line
			(start 0.12065 -0.2794)
			(end -0.12065 -0.2794)
			(stroke
				(width 0.1)
				(type default)
			)
			(layer "B.Fab")
		)
		(fp_line
			(start -0.12065 -0.2794)
			(end -0.12065 -0.3048)
			(stroke
				(width 0.1)
				(type default)
			)
			(layer "B.Fab")
		)
		(fp_line
			(start 0.12065 0.2794)
			(end 0.12065 0.3048)
			(stroke
				(width 0.1)
				(type default)
			)
			(layer "B.Fab")
		)
		(fp_line
			(start -0.120396 0.2794)
			(end 0.12065 0.2794)
			(stroke
				(width 0.1)
				(type default)
			)
			(layer "B.Fab")
		)
		(fp_line
			(start 0.67945 0.3048)
			(end 0.67945 -0.305054)
			(stroke
				(width 0.1)
				(type default)
			)
			(layer "B.Fab")
		)
		(fp_line
			(start 0.12065 0.3048)
			(end 0.67945 0.3048)
			(stroke
				(width 0.1)
				(type default)
			)
			(layer "B.Fab")
		)
		(fp_line
			(start -0.120396 0.3048)
			(end -0.120396 0.2794)
			(stroke
				(width 0.1)
				(type default)
			)
			(layer "B.Fab")
		)
		(fp_line
			(start -0.67945 0.3048)
			(end -0.120396 0.3048)
			(stroke
				(width 0.1)
				(type default)
			)
			(layer "B.Fab")
		)
		(pad "1" smd circle
			(at 0.40005 0 270)
			(size 0 0)
			(layers "B.Cu" "B.Mask" "B.Paste")
			(net "PVDD18_S5_P1")
		)
		(pad "2" smd circle
			(at -0.40005 0 270)
			(size 0 0)
			(layers "B.Cu" "B.Mask" "B.Paste")
			(net "JTAG_CPU1_DBREQ_N")
		)
	)
	(footprint ""
		(layer "B.Cu")
		(at 125.135386 -264.354564)
		(property "Reference" "C2120"
			(at 0 0 0)
			(layer "B.SilkS")
			(hide yes)
			(effects
				(font
					(size 1.27 1.27)
				)
				(justify mirror)
			)
		)
		(property "Value" ""
			(at 0 0 0)
			(layer "B.Fab")
			(effects
				(font
					(size 1.27 1.27)
				)
				(justify mirror)
			)
		)
		(duplicate_pad_numbers_are_jumpers no)
		(fp_line
			(start -0.7874 -0.4064)
			(end -0.7874 0.4064)
			(stroke
				(width 0.1524)
				(type default)
			)
			(layer "B.SilkS")
		)
		(fp_line
			(start -0.7874 0.4064)
			(end 0.7874 0.4064)
			(stroke
				(width 0.1524)
				(type default)
			)
			(layer "B.SilkS")
		)
		(fp_line
			(start 0.7874 -0.4064)
			(end -0.7874 -0.4064)
			(stroke
				(width 0.1524)
				(type default)
			)
			(layer "B.SilkS")
		)
		(fp_line
			(start 0.7874 0.4064)
			(end 0.7874 -0.4064)
			(stroke
				(width 0.1524)
				(type default)
			)
			(layer "B.SilkS")
		)
		(fp_line
			(start -0.67945 -0.3048)
			(end -0.67945 0.3048)
			(stroke
				(width 0.1)
				(type default)
			)
			(layer "B.Fab")
		)
		(fp_line
			(start -0.67945 0.3048)
			(end -0.120396 0.3048)
			(stroke
				(width 0.1)
				(type default)
			)
			(layer "B.Fab")
		)
		(fp_line
			(start -0.12065 -0.3048)
			(end -0.67945 -0.3048)
			(stroke
				(width 0.1)
				(type default)
			)
			(layer "B.Fab")
		)
		(fp_line
			(start -0.12065 -0.2794)
			(end -0.12065 -0.3048)
			(stroke
				(width 0.1)
				(type default)
			)
			(layer "B.Fab")
		)
		(fp_line
			(start -0.120396 0.2794)
			(end 0.12065 0.2794)
			(stroke
				(width 0.1)
				(type default)
			)
			(layer "B.Fab")
		)
		(fp_line
			(start -0.120396 0.3048)
			(end -0.120396 0.2794)
			(stroke
				(width 0.1)
				(type default)
			)
			(layer "B.Fab")
		)
		(fp_line
			(start 0.12065 -0.305054)
			(end 0.12065 -0.2794)
			(stroke
				(width 0.1)
				(type default)
			)
			(layer "B.Fab")
		)
		(fp_line
			(start 0.12065 -0.2794)
			(end -0.12065 -0.2794)
			(stroke
				(width 0.1)
				(type default)
			)
			(layer "B.Fab")
		)
		(fp_line
			(start 0.12065 0.2794)
			(end 0.12065 0.3048)
			(stroke
				(width 0.1)
				(type default)
			)
			(layer "B.Fab")
		)
		(fp_line
			(start 0.12065 0.3048)
			(end 0.67945 0.3048)
			(stroke
				(width 0.1)
				(type default)
			)
			(layer "B.Fab")
		)
		(fp_line
			(start 0.67945 -0.305054)
			(end 0.12065 -0.305054)
			(stroke
				(width 0.1)
				(type default)
			)
			(layer "B.Fab")
		)
		(fp_line
			(start 0.67945 0.3048)
			(end 0.67945 -0.305054)
			(stroke
				(width 0.1)
				(type default)
			)
			(layer "B.Fab")
		)
		(pad "1" smd circle
			(at 0.40005 0 180)
			(size 0 0)
			(layers "B.Cu" "B.Mask" "B.Paste")
			(net "PVDD11_S3_P1")
		)
		(pad "2" smd circle
			(at -0.40005 0 180)
			(size 0 0)
			(layers "B.Cu" "B.Mask" "B.Paste")
			(net "GND")
		)
	)
	(footprint ""
		(layer "B.Cu")
		(at 420.968424 -420.534592)
		(property "Reference" "R680"
			(at 0 0 0)
			(layer "B.SilkS")
			(hide yes)
			(effects
				(font
					(size 1.27 1.27)
				)
				(justify mirror)
			)
		)
		(property "Value" ""
			(at 0 0 0)
			(layer "B.Fab")
			(effects
				(font
					(size 1.27 1.27)
				)
				(justify mirror)
			)
		)
		(duplicate_pad_numbers_are_jumpers no)
		(fp_line
			(start -0.32512 -0.175006)
			(end -0.32512 0.175006)
			(stroke
				(width 0.1)
				(type default)
			)
			(layer "B.Fab")
		)
		(fp_line
			(start -0.32512 0.175006)
			(end 0.32512 0.175006)
			(stroke
				(width 0.1)
				(type default)
			)
			(layer "B.Fab")
		)
		(fp_line
			(start 0.32512 -0.175006)
			(end -0.32512 -0.175006)
			(stroke
				(width 0.1)
				(type default)
			)
			(layer "B.Fab")
		)
		(fp_line
			(start 0.32512 0.175006)
			(end 0.32512 -0.175006)
			(stroke
				(width 0.1)
				(type default)
			)
			(layer "B.Fab")
		)
		(pad "1" smd rect
			(at 0.2667 0 180)
			(size 0.3048 0.381)
			(layers "B.Cu" "B.Mask" "B.Paste")
			(net "SMB_RT_CPU0_P2_ROM_MUX_1D_SCL")
		)
		(pad "2" smd rect
			(at -0.2667 0)
			(size 0.3048 0.381)
			(layers "B.Cu" "B.Mask" "B.Paste")
			(net "SMB_RT_CPU0_P2_ROM_MUX_1D_R_SCL")
		)
	)
	(footprint ""
		(layer "B.Cu")
		(at 355.26599 -417.63696)
		(property "Reference" "Q71"
			(at -1.36906 -2.460244 0)
			(unlocked yes)
			(layer "B.SilkS")
			(effects
				(font
					(size 0.7874 0.5842)
					(thickness 0.1524)
				)
				(justify left mirror)
			)
		)
		(property "Value" ""
			(at 0 0 0)
			(layer "B.Fab")
			(effects
				(font
					(size 1.27 1.27)
				)
				(justify mirror)
			)
		)
		(duplicate_pad_numbers_are_jumpers no)
		(fp_line
			(start -1.332738 -1.100074)
			(end -1.332738 1.100074)
			(stroke
				(width 0.1524)
				(type default)
			)
			(layer "B.SilkS")
		)
		(fp_line
			(start -1.332738 1.100074)
			(end 1.332738 1.100074)
			(stroke
				(width 0.1524)
				(type default)
			)
			(layer "B.SilkS")
		)
		(fp_line
			(start -0.4826 -1.100074)
			(end -1.332738 -1.100074)
			(stroke
				(width 0.1524)
				(type default)
			)
			(layer "B.SilkS")
		)
		(fp_line
			(start 0 -0.541274)
			(end -0.4826 -1.100074)
			(stroke
				(width 0.1524)
				(type default)
			)
			(layer "B.SilkS")
		)
		(fp_line
			(start 0.4826 -1.100074)
			(end 0 -0.541274)
			(stroke
				(width 0.1524)
				(type default)
			)
			(layer "B.SilkS")
		)
		(fp_line
			(start 1.332738 -1.100074)
			(end 0.4826 -1.100074)
			(stroke
				(width 0.1524)
				(type default)
			)
			(layer "B.SilkS")
		)
		(fp_line
			(start 1.332738 1.100074)
			(end 1.332738 -1.100074)
			(stroke
				(width 0.1524)
				(type default)
			)
			(layer "B.SilkS")
		)
		(fp_poly
			(pts
				(xy 0.939038 -1.628648) (xy 1.290066 -2.33045) (xy 0.58801 -2.33045)
			)
			(stroke
				(width 0)
				(type default)
			)
			(fill yes)
			(layer "B.SilkS")
		)
		(fp_line
			(start -0.674878 -1.100074)
			(end -0.674878 1.100074)
			(stroke
				(width 0.1)
				(type default)
			)
			(layer "B.Fab")
		)
		(fp_line
			(start -0.674878 1.100074)
			(end 0.674878 1.100074)
			(stroke
				(width 0.1)
				(type default)
			)
			(layer "B.Fab")
		)
		(fp_line
			(start 0.674878 -1.100074)
			(end -0.674878 -1.100074)
			(stroke
				(width 0.1)
				(type default)
			)
			(layer "B.Fab")
		)
		(fp_line
			(start 0.674878 1.100074)
			(end 0.674878 -1.100074)
			(stroke
				(width 0.1)
				(type default)
			)
			(layer "B.Fab")
		)
		(fp_poly
			(pts
				(xy 2.2352 -0.298958) (xy 2.2352 -1.001014) (xy 1.533144 -0.649986)
			)
			(stroke
				(width 0)
				(type default)
			)
			(fill yes)
			(layer "B.Fab")
		)
		(pad "1" smd rect
			(at 0.94996 -0.649986 90)
			(size 0.4318 0.508)
			(layers "B.Cu" "B.Mask" "B.Paste")
			(net "GND")
		)
		(pad "2" smd rect
			(at 0.94996 0 90)
			(size 0.4318 0.508)
			(layers "B.Cu" "B.Mask" "B.Paste")
			(net "FM_SWB_PWRGD")
		)
		(pad "3" smd rect
			(at 0.94996 0.649986 90)
			(size 0.4318 0.508)
			(layers "B.Cu" "B.Mask" "B.Paste")
			(net "FM_SWB_PWRGD_ISO")
		)
		(pad "4" smd rect
			(at -0.94996 0.649986 90)
			(size 0.4318 0.508)
			(layers "B.Cu" "B.Mask" "B.Paste")
			(net "GND")
		)
		(pad "5" smd rect
			(at -0.94996 0 90)
			(size 0.4318 0.508)
			(layers "B.Cu" "B.Mask" "B.Paste")
			(net "FM_SWB_PWRGD_N")
		)
		(pad "6" smd rect
			(at -0.94996 -0.649986 90)
			(size 0.4318 0.508)
			(layers "B.Cu" "B.Mask" "B.Paste")
			(net "FM_SWB_PWRGD_N")
		)
	)
	(footprint ""
		(layer "B.Cu")
		(at 301.535338 -424.449748 -90)
		(property "Reference" "R1410"
			(at 0 0 90)
			(layer "B.SilkS")
			(hide yes)
			(effects
				(font
					(size 1.27 1.27)
				)
				(justify mirror)
			)
		)
		(property "Value" ""
			(at 0 0 90)
			(layer "B.Fab")
			(effects
				(font
					(size 1.27 1.27)
				)
				(justify mirror)
			)
		)
		(duplicate_pad_numbers_are_jumpers no)
		(fp_line
			(start -0.32512 0.175006)
			(end 0.32512 0.175006)
			(stroke
				(width 0.1)
				(type default)
			)
			(layer "B.Fab")
		)
		(fp_line
			(start 0.32512 0.175006)
			(end 0.32512 -0.175006)
			(stroke
				(width 0.1)
				(type default)
			)
			(layer "B.Fab")
		)
		(fp_line
			(start -0.32512 -0.175006)
			(end -0.32512 0.175006)
			(stroke
				(width 0.1)
				(type default)
			)
			(layer "B.Fab")
		)
		(fp_line
			(start 0.32512 -0.175006)
			(end -0.32512 -0.175006)
			(stroke
				(width 0.1)
				(type default)
			)
			(layer "B.Fab")
		)
		(pad "1" smd rect
			(at 0.2667 0 90)
			(size 0.3048 0.381)
			(layers "B.Cu" "B.Mask" "B.Paste")
			(net "P1V8_CPU0_RT_1D")
		)
		(pad "2" smd rect
			(at -0.2667 0 270)
			(size 0.3048 0.381)
			(layers "B.Cu" "B.Mask" "B.Paste")
			(net "SMB_RT_CPU0_P0_ROM_MUX_1D_SDA")
		)
	)
	(footprint ""
		(layer "B.Cu")
		(at 100.881434 -252.599952 180)
		(property "Reference" "C2665"
			(at 0 0 0)
			(layer "B.SilkS")
			(hide yes)
			(effects
				(font
					(size 1.27 1.27)
				)
				(justify mirror)
			)
		)
		(property "Value" ""
			(at 0 0 0)
			(layer "B.Fab")
			(effects
				(font
					(size 1.27 1.27)
				)
				(justify mirror)
			)
		)
		(duplicate_pad_numbers_are_jumpers no)
		(fp_line
			(start 0.7874 0.4064)
			(end 0.7874 -0.4064)
			(stroke
				(width 0.1524)
				(type default)
			)
			(layer "B.SilkS")
		)
		(fp_line
			(start 0.7874 -0.4064)
			(end -0.7874 -0.4064)
			(stroke
				(width 0.1524)
				(type default)
			)
			(layer "B.SilkS")
		)
		(fp_line
			(start -0.7874 0.4064)
			(end 0.7874 0.4064)
			(stroke
				(width 0.1524)
				(type default)
			)
			(layer "B.SilkS")
		)
		(fp_line
			(start -0.7874 -0.4064)
			(end -0.7874 0.4064)
			(stroke
				(width 0.1524)
				(type default)
			)
			(layer "B.SilkS")
		)
		(fp_line
			(start 0.67945 0.3048)
			(end 0.67945 -0.305054)
			(stroke
				(width 0.1)
				(type default)
			)
			(layer "B.Fab")
		)
		(fp_line
			(start 0.67945 -0.305054)
			(end 0.12065 -0.305054)
			(stroke
				(width 0.1)
				(type default)
			)
			(layer "B.Fab")
		)
		(fp_line
			(start 0.12065 0.3048)
			(end 0.67945 0.3048)
			(stroke
				(width 0.1)
				(type default)
			)
			(layer "B.Fab")
		)
		(fp_line
			(start 0.12065 0.2794)
			(end 0.12065 0.3048)
			(stroke
				(width 0.1)
				(type default)
			)
			(layer "B.Fab")
		)
		(fp_line
			(start 0.12065 -0.2794)
			(end -0.12065 -0.2794)
			(stroke
				(width 0.1)
				(type default)
			)
			(layer "B.Fab")
		)
		(fp_line
			(start 0.12065 -0.305054)
			(end 0.12065 -0.2794)
			(stroke
				(width 0.1)
				(type default)
			)
			(layer "B.Fab")
		)
		(fp_line
			(start -0.120396 0.3048)
			(end -0.120396 0.2794)
			(stroke
				(width 0.1)
				(type default)
			)
			(layer "B.Fab")
		)
		(fp_line
			(start -0.120396 0.2794)
			(end 0.12065 0.2794)
			(stroke
				(width 0.1)
				(type default)
			)
			(layer "B.Fab")
		)
		(fp_line
			(start -0.12065 -0.2794)
			(end -0.12065 -0.3048)
			(stroke
				(width 0.1)
				(type default)
			)
			(layer "B.Fab")
		)
		(fp_line
			(start -0.12065 -0.3048)
			(end -0.67945 -0.3048)
			(stroke
				(width 0.1)
				(type default)
			)
			(layer "B.Fab")
		)
		(fp_line
			(start -0.67945 0.3048)
			(end -0.120396 0.3048)
			(stroke
				(width 0.1)
				(type default)
			)
			(layer "B.Fab")
		)
		(fp_line
			(start -0.67945 -0.3048)
			(end -0.67945 0.3048)
			(stroke
				(width 0.1)
				(type default)
			)
			(layer "B.Fab")
		)
		(pad "1" smd circle
			(at 0.40005 0)
			(size 0 0)
			(layers "B.Cu" "B.Mask" "B.Paste")
			(net "PVDD18_S5_P1")
		)
		(pad "2" smd circle
			(at -0.40005 0)
			(size 0 0)
			(layers "B.Cu" "B.Mask" "B.Paste")
			(net "GND")
		)
	)
	(footprint ""
		(layer "B.Cu")
		(at 326.815958 -202.113896 90)
		(property "Reference" "R414"
			(at 0 0 90)
			(layer "B.SilkS")
			(hide yes)
			(effects
				(font
					(size 1.27 1.27)
				)
				(justify mirror)
			)
		)
		(property "Value" ""
			(at 0 0 90)
			(layer "B.Fab")
			(effects
				(font
					(size 1.27 1.27)
				)
				(justify mirror)
			)
		)
		(duplicate_pad_numbers_are_jumpers no)
		(fp_line
			(start 0.7874 -0.4064)
			(end -0.7874 -0.4064)
			(stroke
				(width 0.1524)
				(type default)
			)
			(layer "B.SilkS")
		)
		(fp_line
			(start -0.7874 -0.4064)
			(end -0.7874 0.4064)
			(stroke
				(width 0.1524)
				(type default)
			)
			(layer "B.SilkS")
		)
		(fp_line
			(start 0.7874 0.4064)
			(end 0.7874 -0.4064)
			(stroke
				(width 0.1524)
				(type default)
			)
			(layer "B.SilkS")
		)
		(fp_line
			(start -0.7874 0.4064)
			(end 0.7874 0.4064)
			(stroke
				(width 0.1524)
				(type default)
			)
			(layer "B.SilkS")
		)
		(fp_line
			(start 0.67945 -0.305054)
			(end 0.12065 -0.305054)
			(stroke
				(width 0.1)
				(type default)
			)
			(layer "B.Fab")
		)
		(fp_line
			(start 0.12065 -0.305054)
			(end 0.12065 -0.2794)
			(stroke
				(width 0.1)
				(type default)
			)
			(layer "B.Fab")
		)
		(fp_line
			(start -0.12065 -0.3048)
			(end -0.67945 -0.3048)
			(stroke
				(width 0.1)
				(type default)
			)
			(layer "B.Fab")
		)
		(fp_line
			(start -0.67945 -0.3048)
			(end -0.67945 0.3048)
			(stroke
				(width 0.1)
				(type default)
			)
			(layer "B.Fab")
		)
		(fp_line
			(start 0.12065 -0.2794)
			(end -0.12065 -0.2794)
			(stroke
				(width 0.1)
				(type default)
			)
			(layer "B.Fab")
		)
		(fp_line
			(start -0.12065 -0.2794)
			(end -0.12065 -0.3048)
			(stroke
				(width 0.1)
				(type default)
			)
			(layer "B.Fab")
		)
		(fp_line
			(start 0.12065 0.2794)
			(end 0.12065 0.3048)
			(stroke
				(width 0.1)
				(type default)
			)
			(layer "B.Fab")
		)
		(fp_line
			(start -0.120396 0.2794)
			(end 0.12065 0.2794)
			(stroke
				(width 0.1)
				(type default)
			)
			(layer "B.Fab")
		)
		(fp_line
			(start 0.67945 0.3048)
			(end 0.67945 -0.305054)
			(stroke
				(width 0.1)
				(type default)
			)
			(layer "B.Fab")
		)
		(fp_line
			(start 0.12065 0.3048)
			(end 0.67945 0.3048)
			(stroke
				(width 0.1)
				(type default)
			)
			(layer "B.Fab")
		)
		(fp_line
			(start -0.120396 0.3048)
			(end -0.120396 0.2794)
			(stroke
				(width 0.1)
				(type default)
			)
			(layer "B.Fab")
		)
		(fp_line
			(start -0.67945 0.3048)
			(end -0.120396 0.3048)
			(stroke
				(width 0.1)
				(type default)
			)
			(layer "B.Fab")
		)
		(pad "1" smd circle
			(at 0.40005 0 270)
			(size 0 0)
			(layers "B.Cu" "B.Mask" "B.Paste")
			(net "CPU0_XTRIG_L5")
		)
		(pad "2" smd circle
			(at -0.40005 0 270)
			(size 0 0)
			(layers "B.Cu" "B.Mask" "B.Paste")
			(net "PVDD18_S5_P0")
		)
	)
	(footprint ""
		(layer "B.Cu")
		(at 235.1151 -215.186514)
		(property "Reference" "R256"
			(at 0 0 0)
			(layer "B.SilkS")
			(hide yes)
			(effects
				(font
					(size 1.27 1.27)
				)
				(justify mirror)
			)
		)
		(property "Value" ""
			(at 0 0 0)
			(layer "B.Fab")
			(effects
				(font
					(size 1.27 1.27)
				)
				(justify mirror)
			)
		)
		(duplicate_pad_numbers_are_jumpers no)
		(fp_line
			(start -0.7874 -0.4064)
			(end -0.7874 0.4064)
			(stroke
				(width 0.1524)
				(type default)
			)
			(layer "B.SilkS")
		)
		(fp_line
			(start -0.7874 0.4064)
			(end 0.7874 0.4064)
			(stroke
				(width 0.1524)
				(type default)
			)
			(layer "B.SilkS")
		)
		(fp_line
			(start 0.7874 -0.4064)
			(end -0.7874 -0.4064)
			(stroke
				(width 0.1524)
				(type default)
			)
			(layer "B.SilkS")
		)
		(fp_line
			(start 0.7874 0.4064)
			(end 0.7874 -0.4064)
			(stroke
				(width 0.1524)
				(type default)
			)
			(layer "B.SilkS")
		)
		(fp_line
			(start -0.67945 -0.3048)
			(end -0.67945 0.3048)
			(stroke
				(width 0.1)
				(type default)
			)
			(layer "B.Fab")
		)
		(fp_line
			(start -0.67945 0.3048)
			(end -0.120396 0.3048)
			(stroke
				(width 0.1)
				(type default)
			)
			(layer "B.Fab")
		)
		(fp_line
			(start -0.12065 -0.3048)
			(end -0.67945 -0.3048)
			(stroke
				(width 0.1)
				(type default)
			)
			(layer "B.Fab")
		)
		(fp_line
			(start -0.12065 -0.2794)
			(end -0.12065 -0.3048)
			(stroke
				(width 0.1)
				(type default)
			)
			(layer "B.Fab")
		)
		(fp_line
			(start -0.120396 0.2794)
			(end 0.12065 0.2794)
			(stroke
				(width 0.1)
				(type default)
			)
			(layer "B.Fab")
		)
		(fp_line
			(start -0.120396 0.3048)
			(end -0.120396 0.2794)
			(stroke
				(width 0.1)
				(type default)
			)
			(layer "B.Fab")
		)
		(fp_line
			(start 0.12065 -0.305054)
			(end 0.12065 -0.2794)
			(stroke
				(width 0.1)
				(type default)
			)
			(layer "B.Fab")
		)
		(fp_line
			(start 0.12065 -0.2794)
			(end -0.12065 -0.2794)
			(stroke
				(width 0.1)
				(type default)
			)
			(layer "B.Fab")
		)
		(fp_line
			(start 0.12065 0.2794)
			(end 0.12065 0.3048)
			(stroke
				(width 0.1)
				(type default)
			)
			(layer "B.Fab")
		)
		(fp_line
			(start 0.12065 0.3048)
			(end 0.67945 0.3048)
			(stroke
				(width 0.1)
				(type default)
			)
			(layer "B.Fab")
		)
		(fp_line
			(start 0.67945 -0.305054)
			(end 0.12065 -0.305054)
			(stroke
				(width 0.1)
				(type default)
			)
			(layer "B.Fab")
		)
		(fp_line
			(start 0.67945 0.3048)
			(end 0.67945 -0.305054)
			(stroke
				(width 0.1)
				(type default)
			)
			(layer "B.Fab")
		)
		(pad "1" smd rect
			(at 0.40005 0)
			(size 0.4572 0.508)
			(layers "B.Cu" "B.Mask" "B.Paste")
			(net "SMB_CPU0_CPU1_APML_BUF1_SCL_R2")
		)
		(pad "2" smd rect
			(at -0.40005 0)
			(size 0.4572 0.508)
			(layers "B.Cu" "B.Mask" "B.Paste")
			(net "SMB_CPU0_CPU1_APML_SCL_R2")
		)
	)
	(footprint ""
		(layer "B.Cu")
		(at 208.56448 -35.804348 90)
		(property "Reference" "C2019"
			(at 0 0 90)
			(layer "B.SilkS")
			(hide yes)
			(effects
				(font
					(size 1.27 1.27)
				)
				(justify mirror)
			)
		)
		(property "Value" ""
			(at 0 0 90)
			(layer "B.Fab")
			(effects
				(font
					(size 1.27 1.27)
				)
				(justify mirror)
			)
		)
		(duplicate_pad_numbers_are_jumpers no)
		(fp_line
			(start 0.7874 -0.4064)
			(end -0.7874 -0.4064)
			(stroke
				(width 0.1524)
				(type default)
			)
			(layer "B.SilkS")
		)
		(fp_line
			(start -0.7874 -0.4064)
			(end -0.7874 0.4064)
			(stroke
				(width 0.1524)
				(type default)
			)
			(layer "B.SilkS")
		)
		(fp_line
			(start 0.7874 0.4064)
			(end 0.7874 -0.4064)
			(stroke
				(width 0.1524)
				(type default)
			)
			(layer "B.SilkS")
		)
		(fp_line
			(start -0.7874 0.4064)
			(end 0.7874 0.4064)
			(stroke
				(width 0.1524)
				(type default)
			)
			(layer "B.SilkS")
		)
		(fp_line
			(start 0.67945 -0.305054)
			(end 0.12065 -0.305054)
			(stroke
				(width 0.1)
				(type default)
			)
			(layer "B.Fab")
		)
		(fp_line
			(start 0.12065 -0.305054)
			(end 0.12065 -0.2794)
			(stroke
				(width 0.1)
				(type default)
			)
			(layer "B.Fab")
		)
		(fp_line
			(start -0.12065 -0.3048)
			(end -0.67945 -0.3048)
			(stroke
				(width 0.1)
				(type default)
			)
			(layer "B.Fab")
		)
		(fp_line
			(start -0.67945 -0.3048)
			(end -0.67945 0.3048)
			(stroke
				(width 0.1)
				(type default)
			)
			(layer "B.Fab")
		)
		(fp_line
			(start 0.12065 -0.2794)
			(end -0.12065 -0.2794)
			(stroke
				(width 0.1)
				(type default)
			)
			(layer "B.Fab")
		)
		(fp_line
			(start -0.12065 -0.2794)
			(end -0.12065 -0.3048)
			(stroke
				(width 0.1)
				(type default)
			)
			(layer "B.Fab")
		)
		(fp_line
			(start 0.12065 0.2794)
			(end 0.12065 0.3048)
			(stroke
				(width 0.1)
				(type default)
			)
			(layer "B.Fab")
		)
		(fp_line
			(start -0.120396 0.2794)
			(end 0.12065 0.2794)
			(stroke
				(width 0.1)
				(type default)
			)
			(layer "B.Fab")
		)
		(fp_line
			(start 0.67945 0.3048)
			(end 0.67945 -0.305054)
			(stroke
				(width 0.1)
				(type default)
			)
			(layer "B.Fab")
		)
		(fp_line
			(start 0.12065 0.3048)
			(end 0.67945 0.3048)
			(stroke
				(width 0.1)
				(type default)
			)
			(layer "B.Fab")
		)
		(fp_line
			(start -0.120396 0.3048)
			(end -0.120396 0.2794)
			(stroke
				(width 0.1)
				(type default)
			)
			(layer "B.Fab")
		)
		(fp_line
			(start -0.67945 0.3048)
			(end -0.120396 0.3048)
			(stroke
				(width 0.1)
				(type default)
			)
			(layer "B.Fab")
		)
		(pad "1" smd circle
			(at 0.40005 0 270)
			(size 0 0)
			(layers "B.Cu" "B.Mask" "B.Paste")
			(net "P12V_SCM_R")
		)
		(pad "2" smd circle
			(at -0.40005 0 270)
			(size 0 0)
			(layers "B.Cu" "B.Mask" "B.Paste")
			(net "GND")
		)
	)
	(footprint ""
		(layer "B.Cu")
		(at 357.044244 -331.408532 -90)
		(property "Reference" "PR444"
			(at 0 0 90)
			(layer "B.SilkS")
			(hide yes)
			(effects
				(font
					(size 1.27 1.27)
				)
				(justify mirror)
			)
		)
		(property "Value" ""
			(at 0 0 90)
			(layer "B.Fab")
			(effects
				(font
					(size 1.27 1.27)
				)
				(justify mirror)
			)
		)
		(duplicate_pad_numbers_are_jumpers no)
		(fp_line
			(start -0.7874 0.4064)
			(end 0.7874 0.4064)
			(stroke
				(width 0.1524)
				(type default)
			)
			(layer "B.SilkS")
		)
		(fp_line
			(start 0.7874 0.4064)
			(end 0.7874 -0.4064)
			(stroke
				(width 0.1524)
				(type default)
			)
			(layer "B.SilkS")
		)
		(fp_line
			(start -0.7874 -0.4064)
			(end -0.7874 0.4064)
			(stroke
				(width 0.1524)
				(type default)
			)
			(layer "B.SilkS")
		)
		(fp_line
			(start 0.7874 -0.4064)
			(end -0.7874 -0.4064)
			(stroke
				(width 0.1524)
				(type default)
			)
			(layer "B.SilkS")
		)
		(fp_line
			(start -0.67945 0.3048)
			(end -0.120396 0.3048)
			(stroke
				(width 0.1)
				(type default)
			)
			(layer "B.Fab")
		)
		(fp_line
			(start -0.120396 0.3048)
			(end -0.120396 0.2794)
			(stroke
				(width 0.1)
				(type default)
			)
			(layer "B.Fab")
		)
		(fp_line
			(start 0.12065 0.3048)
			(end 0.67945 0.3048)
			(stroke
				(width 0.1)
				(type default)
			)
			(layer "B.Fab")
		)
		(fp_line
			(start 0.67945 0.3048)
			(end 0.67945 -0.305054)
			(stroke
				(width 0.1)
				(type default)
			)
			(layer "B.Fab")
		)
		(fp_line
			(start -0.120396 0.2794)
			(end 0.12065 0.2794)
			(stroke
				(width 0.1)
				(type default)
			)
			(layer "B.Fab")
		)
		(fp_line
			(start 0.12065 0.2794)
			(end 0.12065 0.3048)
			(stroke
				(width 0.1)
				(type default)
			)
			(layer "B.Fab")
		)
		(fp_line
			(start -0.12065 -0.2794)
			(end -0.12065 -0.3048)
			(stroke
				(width 0.1)
				(type default)
			)
			(layer "B.Fab")
		)
		(fp_line
			(start 0.12065 -0.2794)
			(end -0.12065 -0.2794)
			(stroke
				(width 0.1)
				(type default)
			)
			(layer "B.Fab")
		)
		(fp_line
			(start -0.67945 -0.3048)
			(end -0.67945 0.3048)
			(stroke
				(width 0.1)
				(type default)
			)
			(layer "B.Fab")
		)
		(fp_line
			(start -0.12065 -0.3048)
			(end -0.67945 -0.3048)
			(stroke
				(width 0.1)
				(type default)
			)
			(layer "B.Fab")
		)
		(fp_line
			(start 0.12065 -0.305054)
			(end 0.12065 -0.2794)
			(stroke
				(width 0.1)
				(type default)
			)
			(layer "B.Fab")
		)
		(fp_line
			(start 0.67945 -0.305054)
			(end 0.12065 -0.305054)
			(stroke
				(width 0.1)
				(type default)
			)
			(layer "B.Fab")
		)
		(pad "1" smd circle
			(at 0.40005 0 90)
			(size 0 0)
			(layers "B.Cu" "B.Mask" "B.Paste")
			(net "PVDDCR_CPU1_P0")
		)
		(pad "2" smd circle
			(at -0.40005 0 90)
			(size 0 0)
			(layers "B.Cu" "B.Mask" "B.Paste")
			(net "GND")
		)
	)
	(footprint ""
		(layer "B.Cu")
		(at 214.43188 -55.971948)
		(property "Reference" "R3764"
			(at 0 0 0)
			(layer "B.SilkS")
			(hide yes)
			(effects
				(font
					(size 1.27 1.27)
				)
				(justify mirror)
			)
		)
		(property "Value" ""
			(at 0 0 0)
			(layer "B.Fab")
			(effects
				(font
					(size 1.27 1.27)
				)
				(justify mirror)
			)
		)
		(duplicate_pad_numbers_are_jumpers no)
		(fp_line
			(start -0.7874 -0.4064)
			(end -0.7874 0.4064)
			(stroke
				(width 0.1524)
				(type default)
			)
			(layer "B.SilkS")
		)
		(fp_line
			(start -0.7874 0.4064)
			(end 0.7874 0.4064)
			(stroke
				(width 0.1524)
				(type default)
			)
			(layer "B.SilkS")
		)
		(fp_line
			(start 0.7874 -0.4064)
			(end -0.7874 -0.4064)
			(stroke
				(width 0.1524)
				(type default)
			)
			(layer "B.SilkS")
		)
		(fp_line
			(start 0.7874 0.4064)
			(end 0.7874 -0.4064)
			(stroke
				(width 0.1524)
				(type default)
			)
			(layer "B.SilkS")
		)
		(fp_line
			(start -0.67945 -0.3048)
			(end -0.67945 0.3048)
			(stroke
				(width 0.1)
				(type default)
			)
			(layer "B.Fab")
		)
		(fp_line
			(start -0.67945 0.3048)
			(end -0.120396 0.3048)
			(stroke
				(width 0.1)
				(type default)
			)
			(layer "B.Fab")
		)
		(fp_line
			(start -0.12065 -0.3048)
			(end -0.67945 -0.3048)
			(stroke
				(width 0.1)
				(type default)
			)
			(layer "B.Fab")
		)
		(fp_line
			(start -0.12065 -0.2794)
			(end -0.12065 -0.3048)
			(stroke
				(width 0.1)
				(type default)
			)
			(layer "B.Fab")
		)
		(fp_line
			(start -0.120396 0.2794)
			(end 0.12065 0.2794)
			(stroke
				(width 0.1)
				(type default)
			)
			(layer "B.Fab")
		)
		(fp_line
			(start -0.120396 0.3048)
			(end -0.120396 0.2794)
			(stroke
				(width 0.1)
				(type default)
			)
			(layer "B.Fab")
		)
		(fp_line
			(start 0.12065 -0.305054)
			(end 0.12065 -0.2794)
			(stroke
				(width 0.1)
				(type default)
			)
			(layer "B.Fab")
		)
		(fp_line
			(start 0.12065 -0.2794)
			(end -0.12065 -0.2794)
			(stroke
				(width 0.1)
				(type default)
			)
			(layer "B.Fab")
		)
		(fp_line
			(start 0.12065 0.2794)
			(end 0.12065 0.3048)
			(stroke
				(width 0.1)
				(type default)
			)
			(layer "B.Fab")
		)
		(fp_line
			(start 0.12065 0.3048)
			(end 0.67945 0.3048)
			(stroke
				(width 0.1)
				(type default)
			)
			(layer "B.Fab")
		)
		(fp_line
			(start 0.67945 -0.305054)
			(end 0.12065 -0.305054)
			(stroke
				(width 0.1)
				(type default)
			)
			(layer "B.Fab")
		)
		(fp_line
			(start 0.67945 0.3048)
			(end 0.67945 -0.305054)
			(stroke
				(width 0.1)
				(type default)
			)
			(layer "B.Fab")
		)
		(pad "1" smd circle
			(at 0.40005 0 180)
			(size 0 0)
			(layers "B.Cu" "B.Mask" "B.Paste")
			(net "GND")
		)
		(pad "2" smd circle
			(at -0.40005 0 180)
			(size 0 0)
			(layers "B.Cu" "B.Mask" "B.Paste")
			(net "INA230_2_A0")
		)
	)
	(footprint ""
		(layer "B.Cu")
		(at 293.80688 -337.984846 -90)
		(property "Reference" "PC169_1"
			(at 0 0 90)
			(layer "B.SilkS")
			(hide yes)
			(effects
				(font
					(size 1.27 1.27)
				)
				(justify mirror)
			)
		)
		(property "Value" ""
			(at 0 0 90)
			(layer "B.Fab")
			(effects
				(font
					(size 1.27 1.27)
				)
				(justify mirror)
			)
		)
		(duplicate_pad_numbers_are_jumpers no)
		(fp_line
			(start -1.524 0.762)
			(end 1.524 0.762)
			(stroke
				(width 0.1524)
				(type default)
			)
			(layer "B.SilkS")
		)
		(fp_line
			(start 1.524 0.762)
			(end 1.524 -0.762)
			(stroke
				(width 0.1524)
				(type default)
			)
			(layer "B.SilkS")
		)
		(fp_line
			(start -1.524 -0.762)
			(end -1.524 0.762)
			(stroke
				(width 0.1524)
				(type default)
			)
			(layer "B.SilkS")
		)
		(fp_line
			(start 1.524 -0.762)
			(end -1.524 -0.762)
			(stroke
				(width 0.1524)
				(type default)
			)
			(layer "B.SilkS")
		)
		(fp_line
			(start -1.1049 0.724916)
			(end -1.1049 -0.724916)
			(stroke
				(width 0.1)
				(type default)
			)
			(layer "B.Fab")
		)
		(fp_line
			(start 1.1049 0.724916)
			(end -1.1049 0.724916)
			(stroke
				(width 0.1)
				(type default)
			)
			(layer "B.Fab")
		)
		(fp_line
			(start -1.1049 -0.724916)
			(end 1.1049 -0.724916)
			(stroke
				(width 0.1)
				(type default)
			)
			(layer "B.Fab")
		)
		(fp_line
			(start 1.1049 -0.724916)
			(end 1.1049 0.724916)
			(stroke
				(width 0.1)
				(type default)
			)
			(layer "B.Fab")
		)
		(pad "1" smd rect
			(at 0.889 0 270)
			(size 1.016 1.27)
			(layers "B.Cu" "B.Mask" "B.Paste")
			(net "PVDDIO_P0")
		)
		(pad "2" smd rect
			(at -0.889 0 270)
			(size 1.016 1.27)
			(layers "B.Cu" "B.Mask" "B.Paste")
			(net "GND")
		)
	)
	(footprint ""
		(layer "B.Cu")
		(at 163.387532 -435.93258 90)
		(property "Reference" "R4129"
			(at 0 0 90)
			(layer "B.SilkS")
			(hide yes)
			(effects
				(font
					(size 1.27 1.27)
				)
				(justify mirror)
			)
		)
		(property "Value" ""
			(at 0 0 90)
			(layer "B.Fab")
			(effects
				(font
					(size 1.27 1.27)
				)
				(justify mirror)
			)
		)
		(duplicate_pad_numbers_are_jumpers no)
		(fp_line
			(start 0.7874 -0.4064)
			(end -0.7874 -0.4064)
			(stroke
				(width 0.1524)
				(type default)
			)
			(layer "B.SilkS")
		)
		(fp_line
			(start -0.7874 -0.4064)
			(end -0.7874 0.4064)
			(stroke
				(width 0.1524)
				(type default)
			)
			(layer "B.SilkS")
		)
		(fp_line
			(start 0.7874 0.4064)
			(end 0.7874 -0.4064)
			(stroke
				(width 0.1524)
				(type default)
			)
			(layer "B.SilkS")
		)
		(fp_line
			(start -0.7874 0.4064)
			(end 0.7874 0.4064)
			(stroke
				(width 0.1524)
				(type default)
			)
			(layer "B.SilkS")
		)
		(fp_line
			(start 0.67945 -0.305054)
			(end 0.12065 -0.305054)
			(stroke
				(width 0.1)
				(type default)
			)
			(layer "B.Fab")
		)
		(fp_line
			(start 0.12065 -0.305054)
			(end 0.12065 -0.2794)
			(stroke
				(width 0.1)
				(type default)
			)
			(layer "B.Fab")
		)
		(fp_line
			(start -0.12065 -0.3048)
			(end -0.67945 -0.3048)
			(stroke
				(width 0.1)
				(type default)
			)
			(layer "B.Fab")
		)
		(fp_line
			(start -0.67945 -0.3048)
			(end -0.67945 0.3048)
			(stroke
				(width 0.1)
				(type default)
			)
			(layer "B.Fab")
		)
		(fp_line
			(start 0.12065 -0.2794)
			(end -0.12065 -0.2794)
			(stroke
				(width 0.1)
				(type default)
			)
			(layer "B.Fab")
		)
		(fp_line
			(start -0.12065 -0.2794)
			(end -0.12065 -0.3048)
			(stroke
				(width 0.1)
				(type default)
			)
			(layer "B.Fab")
		)
		(fp_line
			(start 0.12065 0.2794)
			(end 0.12065 0.3048)
			(stroke
				(width 0.1)
				(type default)
			)
			(layer "B.Fab")
		)
		(fp_line
			(start -0.120396 0.2794)
			(end 0.12065 0.2794)
			(stroke
				(width 0.1)
				(type default)
			)
			(layer "B.Fab")
		)
		(fp_line
			(start 0.67945 0.3048)
			(end 0.67945 -0.305054)
			(stroke
				(width 0.1)
				(type default)
			)
			(layer "B.Fab")
		)
		(fp_line
			(start 0.12065 0.3048)
			(end 0.67945 0.3048)
			(stroke
				(width 0.1)
				(type default)
			)
			(layer "B.Fab")
		)
		(fp_line
			(start -0.120396 0.3048)
			(end -0.120396 0.2794)
			(stroke
				(width 0.1)
				(type default)
			)
			(layer "B.Fab")
		)
		(fp_line
			(start -0.67945 0.3048)
			(end -0.120396 0.3048)
			(stroke
				(width 0.1)
				(type default)
			)
			(layer "B.Fab")
		)
		(pad "1" smd circle
			(at 0.40005 0 270)
			(size 0 0)
			(layers "B.Cu" "B.Mask" "B.Paste")
			(net "P3V3_AUX")
		)
		(pad "2" smd circle
			(at -0.40005 0 270)
			(size 0 0)
			(layers "B.Cu" "B.Mask" "B.Paste")
			(net "PRSNT_CABLE_GPU_B3_ISO_N")
		)
	)
	(footprint ""
		(layer "B.Cu")
		(at 339.646006 -396.393162 -90)
		(property "Reference" "C662"
			(at 0 0 90)
			(layer "B.SilkS")
			(hide yes)
			(effects
				(font
					(size 1.27 1.27)
				)
				(justify mirror)
			)
		)
		(property "Value" ""
			(at 0 0 90)
			(layer "B.Fab")
			(effects
				(font
					(size 1.27 1.27)
				)
				(justify mirror)
			)
		)
		(duplicate_pad_numbers_are_jumpers no)
		(fp_line
			(start -0.299974 0.150114)
			(end 0.299974 0.150114)
			(stroke
				(width 0.1)
				(type default)
			)
			(layer "B.Fab")
		)
		(fp_line
			(start 0.299974 0.150114)
			(end 0.299974 -0.150114)
			(stroke
				(width 0.1)
				(type default)
			)
			(layer "B.Fab")
		)
		(fp_line
			(start -0.299974 -0.150114)
			(end -0.299974 0.150114)
			(stroke
				(width 0.1)
				(type default)
			)
			(layer "B.Fab")
		)
		(fp_line
			(start 0.299974 -0.150114)
			(end -0.299974 -0.150114)
			(stroke
				(width 0.1)
				(type default)
			)
			(layer "B.Fab")
		)
		(pad "1" smd rect
			(at 0.2667 0 90)
			(size 0.3048 0.381)
			(layers "B.Cu" "B.Mask" "B.Paste")
			(net "P0V9_CPU0_RT1_2A")
		)
		(pad "2" smd rect
			(at -0.2667 0 90)
			(size 0.3048 0.381)
			(layers "B.Cu" "B.Mask" "B.Paste")
			(net "GND")
		)
	)
	(footprint ""
		(layer "B.Cu")
		(at 99.103434 -252.599952 180)
		(property "Reference" "C2663"
			(at 0 0 0)
			(layer "B.SilkS")
			(hide yes)
			(effects
				(font
					(size 1.27 1.27)
				)
				(justify mirror)
			)
		)
		(property "Value" ""
			(at 0 0 0)
			(layer "B.Fab")
			(effects
				(font
					(size 1.27 1.27)
				)
				(justify mirror)
			)
		)
		(duplicate_pad_numbers_are_jumpers no)
		(fp_line
			(start 0.7874 0.4064)
			(end 0.7874 -0.4064)
			(stroke
				(width 0.1524)
				(type default)
			)
			(layer "B.SilkS")
		)
		(fp_line
			(start 0.7874 -0.4064)
			(end -0.7874 -0.4064)
			(stroke
				(width 0.1524)
				(type default)
			)
			(layer "B.SilkS")
		)
		(fp_line
			(start -0.7874 0.4064)
			(end 0.7874 0.4064)
			(stroke
				(width 0.1524)
				(type default)
			)
			(layer "B.SilkS")
		)
		(fp_line
			(start -0.7874 -0.4064)
			(end -0.7874 0.4064)
			(stroke
				(width 0.1524)
				(type default)
			)
			(layer "B.SilkS")
		)
		(fp_line
			(start 0.67945 0.3048)
			(end 0.67945 -0.305054)
			(stroke
				(width 0.1)
				(type default)
			)
			(layer "B.Fab")
		)
		(fp_line
			(start 0.67945 -0.305054)
			(end 0.12065 -0.305054)
			(stroke
				(width 0.1)
				(type default)
			)
			(layer "B.Fab")
		)
		(fp_line
			(start 0.12065 0.3048)
			(end 0.67945 0.3048)
			(stroke
				(width 0.1)
				(type default)
			)
			(layer "B.Fab")
		)
		(fp_line
			(start 0.12065 0.2794)
			(end 0.12065 0.3048)
			(stroke
				(width 0.1)
				(type default)
			)
			(layer "B.Fab")
		)
		(fp_line
			(start 0.12065 -0.2794)
			(end -0.12065 -0.2794)
			(stroke
				(width 0.1)
				(type default)
			)
			(layer "B.Fab")
		)
		(fp_line
			(start 0.12065 -0.305054)
			(end 0.12065 -0.2794)
			(stroke
				(width 0.1)
				(type default)
			)
			(layer "B.Fab")
		)
		(fp_line
			(start -0.120396 0.3048)
			(end -0.120396 0.2794)
			(stroke
				(width 0.1)
				(type default)
			)
			(layer "B.Fab")
		)
		(fp_line
			(start -0.120396 0.2794)
			(end 0.12065 0.2794)
			(stroke
				(width 0.1)
				(type default)
			)
			(layer "B.Fab")
		)
		(fp_line
			(start -0.12065 -0.2794)
			(end -0.12065 -0.3048)
			(stroke
				(width 0.1)
				(type default)
			)
			(layer "B.Fab")
		)
		(fp_line
			(start -0.12065 -0.3048)
			(end -0.67945 -0.3048)
			(stroke
				(width 0.1)
				(type default)
			)
			(layer "B.Fab")
		)
		(fp_line
			(start -0.67945 0.3048)
			(end -0.120396 0.3048)
			(stroke
				(width 0.1)
				(type default)
			)
			(layer "B.Fab")
		)
		(fp_line
			(start -0.67945 -0.3048)
			(end -0.67945 0.3048)
			(stroke
				(width 0.1)
				(type default)
			)
			(layer "B.Fab")
		)
		(pad "1" smd circle
			(at 0.40005 0)
			(size 0 0)
			(layers "B.Cu" "B.Mask" "B.Paste")
			(net "PVDD18_S5_P1")
		)
		(pad "2" smd circle
			(at -0.40005 0)
			(size 0 0)
			(layers "B.Cu" "B.Mask" "B.Paste")
			(net "GND")
		)
	)
	(footprint ""
		(layer "B.Cu")
		(at 81.522316 -326.312276 -90)
		(property "Reference" "PC398_1"
			(at 0 0 90)
			(layer "B.SilkS")
			(hide yes)
			(effects
				(font
					(size 1.27 1.27)
				)
				(justify mirror)
			)
		)
		(property "Value" ""
			(at 0 0 90)
			(layer "B.Fab")
			(effects
				(font
					(size 1.27 1.27)
				)
				(justify mirror)
			)
		)
		(duplicate_pad_numbers_are_jumpers no)
		(fp_line
			(start -1.524 0.762)
			(end 1.524 0.762)
			(stroke
				(width 0.1524)
				(type default)
			)
			(layer "B.SilkS")
		)
		(fp_line
			(start 1.524 0.762)
			(end 1.524 -0.762)
			(stroke
				(width 0.1524)
				(type default)
			)
			(layer "B.SilkS")
		)
		(fp_line
			(start -1.524 -0.762)
			(end -1.524 0.762)
			(stroke
				(width 0.1524)
				(type default)
			)
			(layer "B.SilkS")
		)
		(fp_line
			(start 1.524 -0.762)
			(end -1.524 -0.762)
			(stroke
				(width 0.1524)
				(type default)
			)
			(layer "B.SilkS")
		)
		(fp_line
			(start -1.1049 0.724916)
			(end -1.1049 -0.724916)
			(stroke
				(width 0.1)
				(type default)
			)
			(layer "B.Fab")
		)
		(fp_line
			(start 1.1049 0.724916)
			(end -1.1049 0.724916)
			(stroke
				(width 0.1)
				(type default)
			)
			(layer "B.Fab")
		)
		(fp_line
			(start -1.1049 -0.724916)
			(end 1.1049 -0.724916)
			(stroke
				(width 0.1)
				(type default)
			)
			(layer "B.Fab")
		)
		(fp_line
			(start 1.1049 -0.724916)
			(end 1.1049 0.724916)
			(stroke
				(width 0.1)
				(type default)
			)
			(layer "B.Fab")
		)
		(pad "1" smd rect
			(at 0.889 0 270)
			(size 1.016 1.27)
			(layers "B.Cu" "B.Mask" "B.Paste")
			(net "PVDDCR_CPU1_P1")
		)
		(pad "2" smd rect
			(at -0.889 0 270)
			(size 1.016 1.27)
			(layers "B.Cu" "B.Mask" "B.Paste")
			(net "GND")
		)
	)
	(footprint ""
		(layer "B.Cu")
		(at 229.997 -218.059 90)
		(property "Reference" "R206"
			(at 0 0 90)
			(layer "B.SilkS")
			(hide yes)
			(effects
				(font
					(size 1.27 1.27)
				)
				(justify mirror)
			)
		)
		(property "Value" ""
			(at 0 0 90)
			(layer "B.Fab")
			(effects
				(font
					(size 1.27 1.27)
				)
				(justify mirror)
			)
		)
		(duplicate_pad_numbers_are_jumpers no)
		(fp_line
			(start 0.7874 -0.4064)
			(end -0.7874 -0.4064)
			(stroke
				(width 0.1524)
				(type default)
			)
			(layer "B.SilkS")
		)
		(fp_line
			(start -0.7874 -0.4064)
			(end -0.7874 0.4064)
			(stroke
				(width 0.1524)
				(type default)
			)
			(layer "B.SilkS")
		)
		(fp_line
			(start 0.7874 0.4064)
			(end 0.7874 -0.4064)
			(stroke
				(width 0.1524)
				(type default)
			)
			(layer "B.SilkS")
		)
		(fp_line
			(start -0.7874 0.4064)
			(end 0.7874 0.4064)
			(stroke
				(width 0.1524)
				(type default)
			)
			(layer "B.SilkS")
		)
		(fp_line
			(start 0.67945 -0.305054)
			(end 0.12065 -0.305054)
			(stroke
				(width 0.1)
				(type default)
			)
			(layer "B.Fab")
		)
		(fp_line
			(start 0.12065 -0.305054)
			(end 0.12065 -0.2794)
			(stroke
				(width 0.1)
				(type default)
			)
			(layer "B.Fab")
		)
		(fp_line
			(start -0.12065 -0.3048)
			(end -0.67945 -0.3048)
			(stroke
				(width 0.1)
				(type default)
			)
			(layer "B.Fab")
		)
		(fp_line
			(start -0.67945 -0.3048)
			(end -0.67945 0.3048)
			(stroke
				(width 0.1)
				(type default)
			)
			(layer "B.Fab")
		)
		(fp_line
			(start 0.12065 -0.2794)
			(end -0.12065 -0.2794)
			(stroke
				(width 0.1)
				(type default)
			)
			(layer "B.Fab")
		)
		(fp_line
			(start -0.12065 -0.2794)
			(end -0.12065 -0.3048)
			(stroke
				(width 0.1)
				(type default)
			)
			(layer "B.Fab")
		)
		(fp_line
			(start 0.12065 0.2794)
			(end 0.12065 0.3048)
			(stroke
				(width 0.1)
				(type default)
			)
			(layer "B.Fab")
		)
		(fp_line
			(start -0.120396 0.2794)
			(end 0.12065 0.2794)
			(stroke
				(width 0.1)
				(type default)
			)
			(layer "B.Fab")
		)
		(fp_line
			(start 0.67945 0.3048)
			(end 0.67945 -0.305054)
			(stroke
				(width 0.1)
				(type default)
			)
			(layer "B.Fab")
		)
		(fp_line
			(start 0.12065 0.3048)
			(end 0.67945 0.3048)
			(stroke
				(width 0.1)
				(type default)
			)
			(layer "B.Fab")
		)
		(fp_line
			(start -0.120396 0.3048)
			(end -0.120396 0.2794)
			(stroke
				(width 0.1)
				(type default)
			)
			(layer "B.Fab")
		)
		(fp_line
			(start -0.67945 0.3048)
			(end -0.120396 0.3048)
			(stroke
				(width 0.1)
				(type default)
			)
			(layer "B.Fab")
		)
		(pad "1" smd circle
			(at 0.40005 0 270)
			(size 0 0)
			(layers "B.Cu" "B.Mask" "B.Paste")
			(net "SMB_CPU0_CPU1_APML_BUF2_SDA_R1")
		)
		(pad "2" smd circle
			(at -0.40005 0 270)
			(size 0 0)
			(layers "B.Cu" "B.Mask" "B.Paste")
			(net "SMB_CPU0_CPU1_APML_BUF2_SDA_R2")
		)
	)
	(footprint ""
		(layer "B.Cu")
		(at 188.101224 -145.585434 180)
		(property "Reference" "R1197"
			(at 0 0 0)
			(layer "B.SilkS")
			(hide yes)
			(effects
				(font
					(size 1.27 1.27)
				)
				(justify mirror)
			)
		)
		(property "Value" ""
			(at 0 0 0)
			(layer "B.Fab")
			(effects
				(font
					(size 1.27 1.27)
				)
				(justify mirror)
			)
		)
		(duplicate_pad_numbers_are_jumpers no)
		(fp_line
			(start 0.7874 0.4064)
			(end 0.7874 -0.4064)
			(stroke
				(width 0.1524)
				(type default)
			)
			(layer "B.SilkS")
		)
		(fp_line
			(start 0.7874 -0.4064)
			(end -0.7874 -0.4064)
			(stroke
				(width 0.1524)
				(type default)
			)
			(layer "B.SilkS")
		)
		(fp_line
			(start -0.7874 0.4064)
			(end 0.7874 0.4064)
			(stroke
				(width 0.1524)
				(type default)
			)
			(layer "B.SilkS")
		)
		(fp_line
			(start -0.7874 -0.4064)
			(end -0.7874 0.4064)
			(stroke
				(width 0.1524)
				(type default)
			)
			(layer "B.SilkS")
		)
		(fp_line
			(start 0.67945 0.3048)
			(end 0.67945 -0.305054)
			(stroke
				(width 0.1)
				(type default)
			)
			(layer "B.Fab")
		)
		(fp_line
			(start 0.67945 -0.305054)
			(end 0.12065 -0.305054)
			(stroke
				(width 0.1)
				(type default)
			)
			(layer "B.Fab")
		)
		(fp_line
			(start 0.12065 0.3048)
			(end 0.67945 0.3048)
			(stroke
				(width 0.1)
				(type default)
			)
			(layer "B.Fab")
		)
		(fp_line
			(start 0.12065 0.2794)
			(end 0.12065 0.3048)
			(stroke
				(width 0.1)
				(type default)
			)
			(layer "B.Fab")
		)
		(fp_line
			(start 0.12065 -0.2794)
			(end -0.12065 -0.2794)
			(stroke
				(width 0.1)
				(type default)
			)
			(layer "B.Fab")
		)
		(fp_line
			(start 0.12065 -0.305054)
			(end 0.12065 -0.2794)
			(stroke
				(width 0.1)
				(type default)
			)
			(layer "B.Fab")
		)
		(fp_line
			(start -0.120396 0.3048)
			(end -0.120396 0.2794)
			(stroke
				(width 0.1)
				(type default)
			)
			(layer "B.Fab")
		)
		(fp_line
			(start -0.120396 0.2794)
			(end 0.12065 0.2794)
			(stroke
				(width 0.1)
				(type default)
			)
			(layer "B.Fab")
		)
		(fp_line
			(start -0.12065 -0.2794)
			(end -0.12065 -0.3048)
			(stroke
				(width 0.1)
				(type default)
			)
			(layer "B.Fab")
		)
		(fp_line
			(start -0.12065 -0.3048)
			(end -0.67945 -0.3048)
			(stroke
				(width 0.1)
				(type default)
			)
			(layer "B.Fab")
		)
		(fp_line
			(start -0.67945 0.3048)
			(end -0.120396 0.3048)
			(stroke
				(width 0.1)
				(type default)
			)
			(layer "B.Fab")
		)
		(fp_line
			(start -0.67945 -0.3048)
			(end -0.67945 0.3048)
			(stroke
				(width 0.1)
				(type default)
			)
			(layer "B.Fab")
		)
		(pad "1" smd circle
			(at 0.40005 0)
			(size 0 0)
			(layers "B.Cu" "B.Mask" "B.Paste")
			(net "ESPI_CPU0_ALERT_P0_N")
		)
		(pad "2" smd circle
			(at -0.40005 0)
			(size 0 0)
			(layers "B.Cu" "B.Mask" "B.Paste")
			(net "ESPI_CPU0_ALERT_N")
		)
	)
	(footprint ""
		(layer "B.Cu")
		(at 124.97689 -248.479564)
		(property "Reference" "C2333"
			(at 0 0 0)
			(layer "B.SilkS")
			(hide yes)
			(effects
				(font
					(size 1.27 1.27)
				)
				(justify mirror)
			)
		)
		(property "Value" ""
			(at 0 0 0)
			(layer "B.Fab")
			(effects
				(font
					(size 1.27 1.27)
				)
				(justify mirror)
			)
		)
		(duplicate_pad_numbers_are_jumpers no)
		(fp_line
			(start -0.7874 -0.4064)
			(end -0.7874 0.4064)
			(stroke
				(width 0.1524)
				(type default)
			)
			(layer "B.SilkS")
		)
		(fp_line
			(start -0.7874 0.4064)
			(end 0.7874 0.4064)
			(stroke
				(width 0.1524)
				(type default)
			)
			(layer "B.SilkS")
		)
		(fp_line
			(start 0.7874 -0.4064)
			(end -0.7874 -0.4064)
			(stroke
				(width 0.1524)
				(type default)
			)
			(layer "B.SilkS")
		)
		(fp_line
			(start 0.7874 0.4064)
			(end 0.7874 -0.4064)
			(stroke
				(width 0.1524)
				(type default)
			)
			(layer "B.SilkS")
		)
		(fp_line
			(start -0.67945 -0.3048)
			(end -0.67945 0.3048)
			(stroke
				(width 0.1)
				(type default)
			)
			(layer "B.Fab")
		)
		(fp_line
			(start -0.67945 0.3048)
			(end -0.120396 0.3048)
			(stroke
				(width 0.1)
				(type default)
			)
			(layer "B.Fab")
		)
		(fp_line
			(start -0.12065 -0.3048)
			(end -0.67945 -0.3048)
			(stroke
				(width 0.1)
				(type default)
			)
			(layer "B.Fab")
		)
		(fp_line
			(start -0.12065 -0.2794)
			(end -0.12065 -0.3048)
			(stroke
				(width 0.1)
				(type default)
			)
			(layer "B.Fab")
		)
		(fp_line
			(start -0.120396 0.2794)
			(end 0.12065 0.2794)
			(stroke
				(width 0.1)
				(type default)
			)
			(layer "B.Fab")
		)
		(fp_line
			(start -0.120396 0.3048)
			(end -0.120396 0.2794)
			(stroke
				(width 0.1)
				(type default)
			)
			(layer "B.Fab")
		)
		(fp_line
			(start 0.12065 -0.305054)
			(end 0.12065 -0.2794)
			(stroke
				(width 0.1)
				(type default)
			)
			(layer "B.Fab")
		)
		(fp_line
			(start 0.12065 -0.2794)
			(end -0.12065 -0.2794)
			(stroke
				(width 0.1)
				(type default)
			)
			(layer "B.Fab")
		)
		(fp_line
			(start 0.12065 0.2794)
			(end 0.12065 0.3048)
			(stroke
				(width 0.1)
				(type default)
			)
			(layer "B.Fab")
		)
		(fp_line
			(start 0.12065 0.3048)
			(end 0.67945 0.3048)
			(stroke
				(width 0.1)
				(type default)
			)
			(layer "B.Fab")
		)
		(fp_line
			(start 0.67945 -0.305054)
			(end 0.12065 -0.305054)
			(stroke
				(width 0.1)
				(type default)
			)
			(layer "B.Fab")
		)
		(fp_line
			(start 0.67945 0.3048)
			(end 0.67945 -0.305054)
			(stroke
				(width 0.1)
				(type default)
			)
			(layer "B.Fab")
		)
		(pad "1" smd circle
			(at 0.40005 0 180)
			(size 0 0)
			(layers "B.Cu" "B.Mask" "B.Paste")
			(net "PVDDCR_CPU0_P1")
		)
		(pad "2" smd circle
			(at -0.40005 0 180)
			(size 0 0)
			(layers "B.Cu" "B.Mask" "B.Paste")
			(net "GND")
		)
	)
	(footprint ""
		(layer "B.Cu")
		(at 352.718878 -398.942052 90)
		(property "Reference" "C652"
			(at 0 0 90)
			(layer "B.SilkS")
			(hide yes)
			(effects
				(font
					(size 1.27 1.27)
				)
				(justify mirror)
			)
		)
		(property "Value" ""
			(at 0 0 90)
			(layer "B.Fab")
			(effects
				(font
					(size 1.27 1.27)
				)
				(justify mirror)
			)
		)
		(duplicate_pad_numbers_are_jumpers no)
		(fp_line
			(start 0.7874 -0.4064)
			(end -0.7874 -0.4064)
			(stroke
				(width 0.1524)
				(type default)
			)
			(layer "B.SilkS")
		)
		(fp_line
			(start -0.7874 -0.4064)
			(end -0.7874 0.4064)
			(stroke
				(width 0.1524)
				(type default)
			)
			(layer "B.SilkS")
		)
		(fp_line
			(start 0.7874 0.4064)
			(end 0.7874 -0.4064)
			(stroke
				(width 0.1524)
				(type default)
			)
			(layer "B.SilkS")
		)
		(fp_line
			(start -0.7874 0.4064)
			(end 0.7874 0.4064)
			(stroke
				(width 0.1524)
				(type default)
			)
			(layer "B.SilkS")
		)
		(fp_line
			(start 0.67945 -0.305054)
			(end 0.12065 -0.305054)
			(stroke
				(width 0.1)
				(type default)
			)
			(layer "B.Fab")
		)
		(fp_line
			(start 0.12065 -0.305054)
			(end 0.12065 -0.2794)
			(stroke
				(width 0.1)
				(type default)
			)
			(layer "B.Fab")
		)
		(fp_line
			(start -0.12065 -0.3048)
			(end -0.67945 -0.3048)
			(stroke
				(width 0.1)
				(type default)
			)
			(layer "B.Fab")
		)
		(fp_line
			(start -0.67945 -0.3048)
			(end -0.67945 0.3048)
			(stroke
				(width 0.1)
				(type default)
			)
			(layer "B.Fab")
		)
		(fp_line
			(start 0.12065 -0.2794)
			(end -0.12065 -0.2794)
			(stroke
				(width 0.1)
				(type default)
			)
			(layer "B.Fab")
		)
		(fp_line
			(start -0.12065 -0.2794)
			(end -0.12065 -0.3048)
			(stroke
				(width 0.1)
				(type default)
			)
			(layer "B.Fab")
		)
		(fp_line
			(start 0.12065 0.2794)
			(end 0.12065 0.3048)
			(stroke
				(width 0.1)
				(type default)
			)
			(layer "B.Fab")
		)
		(fp_line
			(start -0.120396 0.2794)
			(end 0.12065 0.2794)
			(stroke
				(width 0.1)
				(type default)
			)
			(layer "B.Fab")
		)
		(fp_line
			(start 0.67945 0.3048)
			(end 0.67945 -0.305054)
			(stroke
				(width 0.1)
				(type default)
			)
			(layer "B.Fab")
		)
		(fp_line
			(start 0.12065 0.3048)
			(end 0.67945 0.3048)
			(stroke
				(width 0.1)
				(type default)
			)
			(layer "B.Fab")
		)
		(fp_line
			(start -0.120396 0.3048)
			(end -0.120396 0.2794)
			(stroke
				(width 0.1)
				(type default)
			)
			(layer "B.Fab")
		)
		(fp_line
			(start -0.67945 0.3048)
			(end -0.120396 0.3048)
			(stroke
				(width 0.1)
				(type default)
			)
			(layer "B.Fab")
		)
		(pad "1" smd circle
			(at 0.40005 0 270)
			(size 0 0)
			(layers "B.Cu" "B.Mask" "B.Paste")
			(net "P0V9_CPU0_RT1_2A")
		)
		(pad "2" smd circle
			(at -0.40005 0 270)
			(size 0 0)
			(layers "B.Cu" "B.Mask" "B.Paste")
			(net "GND")
		)
	)
	(footprint ""
		(layer "B.Cu")
		(at 25.92324 -194.885564 180)
		(property "Reference" "R6"
			(at 0 0 0)
			(layer "B.SilkS")
			(hide yes)
			(effects
				(font
					(size 1.27 1.27)
				)
				(justify mirror)
			)
		)
		(property "Value" ""
			(at 0 0 0)
			(layer "B.Fab")
			(effects
				(font
					(size 1.27 1.27)
				)
				(justify mirror)
			)
		)
		(duplicate_pad_numbers_are_jumpers no)
		(fp_line
			(start 0.7874 0.4064)
			(end 0.7874 -0.4064)
			(stroke
				(width 0.1524)
				(type default)
			)
			(layer "B.SilkS")
		)
		(fp_line
			(start 0.7874 -0.4064)
			(end -0.7874 -0.4064)
			(stroke
				(width 0.1524)
				(type default)
			)
			(layer "B.SilkS")
		)
		(fp_line
			(start -0.7874 0.4064)
			(end 0.7874 0.4064)
			(stroke
				(width 0.1524)
				(type default)
			)
			(layer "B.SilkS")
		)
		(fp_line
			(start -0.7874 -0.4064)
			(end -0.7874 0.4064)
			(stroke
				(width 0.1524)
				(type default)
			)
			(layer "B.SilkS")
		)
		(fp_line
			(start 0.67945 0.3048)
			(end 0.67945 -0.305054)
			(stroke
				(width 0.1)
				(type default)
			)
			(layer "B.Fab")
		)
		(fp_line
			(start 0.67945 -0.305054)
			(end 0.12065 -0.305054)
			(stroke
				(width 0.1)
				(type default)
			)
			(layer "B.Fab")
		)
		(fp_line
			(start 0.12065 0.3048)
			(end 0.67945 0.3048)
			(stroke
				(width 0.1)
				(type default)
			)
			(layer "B.Fab")
		)
		(fp_line
			(start 0.12065 0.2794)
			(end 0.12065 0.3048)
			(stroke
				(width 0.1)
				(type default)
			)
			(layer "B.Fab")
		)
		(fp_line
			(start 0.12065 -0.2794)
			(end -0.12065 -0.2794)
			(stroke
				(width 0.1)
				(type default)
			)
			(layer "B.Fab")
		)
		(fp_line
			(start 0.12065 -0.305054)
			(end 0.12065 -0.2794)
			(stroke
				(width 0.1)
				(type default)
			)
			(layer "B.Fab")
		)
		(fp_line
			(start -0.120396 0.3048)
			(end -0.120396 0.2794)
			(stroke
				(width 0.1)
				(type default)
			)
			(layer "B.Fab")
		)
		(fp_line
			(start -0.120396 0.2794)
			(end 0.12065 0.2794)
			(stroke
				(width 0.1)
				(type default)
			)
			(layer "B.Fab")
		)
		(fp_line
			(start -0.12065 -0.2794)
			(end -0.12065 -0.3048)
			(stroke
				(width 0.1)
				(type default)
			)
			(layer "B.Fab")
		)
		(fp_line
			(start -0.12065 -0.3048)
			(end -0.67945 -0.3048)
			(stroke
				(width 0.1)
				(type default)
			)
			(layer "B.Fab")
		)
		(fp_line
			(start -0.67945 0.3048)
			(end -0.120396 0.3048)
			(stroke
				(width 0.1)
				(type default)
			)
			(layer "B.Fab")
		)
		(fp_line
			(start -0.67945 -0.3048)
			(end -0.67945 0.3048)
			(stroke
				(width 0.1)
				(type default)
			)
			(layer "B.Fab")
		)
		(pad "1" smd circle
			(at 0.40005 0)
			(size 0 0)
			(layers "B.Cu" "B.Mask" "B.Paste")
			(net "PD_CHE_CPU1_DIMM_SAA")
		)
		(pad "2" smd circle
			(at -0.40005 0)
			(size 0 0)
			(layers "B.Cu" "B.Mask" "B.Paste")
			(net "GND")
		)
	)
	(footprint ""
		(layer "B.Cu")
		(at 215.0618 -336.296)
		(property "Reference" "R780"
			(at 0 0 0)
			(layer "B.SilkS")
			(hide yes)
			(effects
				(font
					(size 1.27 1.27)
				)
				(justify mirror)
			)
		)
		(property "Value" ""
			(at 0 0 0)
			(layer "B.Fab")
			(effects
				(font
					(size 1.27 1.27)
				)
				(justify mirror)
			)
		)
		(duplicate_pad_numbers_are_jumpers no)
		(fp_line
			(start -0.32512 -0.175006)
			(end -0.32512 0.175006)
			(stroke
				(width 0.1)
				(type default)
			)
			(layer "B.Fab")
		)
		(fp_line
			(start -0.32512 0.175006)
			(end 0.32512 0.175006)
			(stroke
				(width 0.1)
				(type default)
			)
			(layer "B.Fab")
		)
		(fp_line
			(start 0.32512 -0.175006)
			(end -0.32512 -0.175006)
			(stroke
				(width 0.1)
				(type default)
			)
			(layer "B.Fab")
		)
		(fp_line
			(start 0.32512 0.175006)
			(end 0.32512 -0.175006)
			(stroke
				(width 0.1)
				(type default)
			)
			(layer "B.Fab")
		)
		(pad "1" smd rect
			(at 0.2667 0 180)
			(size 0.3048 0.381)
			(layers "B.Cu" "B.Mask" "B.Paste")
			(net "SMB_RT_CPU1_P1_R_SDA")
		)
		(pad "2" smd rect
			(at -0.2667 0)
			(size 0.3048 0.381)
			(layers "B.Cu" "B.Mask" "B.Paste")
			(net "SMB_RT_CPU1_P1_R2_SDA")
		)
	)
	(footprint ""
		(layer "B.Cu")
		(at 136.874504 -31.874206 -90)
		(property "Reference" "C6047"
			(at 0 0 90)
			(layer "B.SilkS")
			(hide yes)
			(effects
				(font
					(size 1.27 1.27)
				)
				(justify mirror)
			)
		)
		(property "Value" ""
			(at 0 0 90)
			(layer "B.Fab")
			(effects
				(font
					(size 1.27 1.27)
				)
				(justify mirror)
			)
		)
		(duplicate_pad_numbers_are_jumpers no)
		(fp_line
			(start -0.7874 0.4064)
			(end 0.7874 0.4064)
			(stroke
				(width 0.1524)
				(type default)
			)
			(layer "B.SilkS")
		)
		(fp_line
			(start 0.7874 0.4064)
			(end 0.7874 -0.4064)
			(stroke
				(width 0.1524)
				(type default)
			)
			(layer "B.SilkS")
		)
		(fp_line
			(start -0.7874 -0.4064)
			(end -0.7874 0.4064)
			(stroke
				(width 0.1524)
				(type default)
			)
			(layer "B.SilkS")
		)
		(fp_line
			(start 0.7874 -0.4064)
			(end -0.7874 -0.4064)
			(stroke
				(width 0.1524)
				(type default)
			)
			(layer "B.SilkS")
		)
		(fp_line
			(start -0.67945 0.3048)
			(end -0.120396 0.3048)
			(stroke
				(width 0.1)
				(type default)
			)
			(layer "B.Fab")
		)
		(fp_line
			(start -0.120396 0.3048)
			(end -0.120396 0.2794)
			(stroke
				(width 0.1)
				(type default)
			)
			(layer "B.Fab")
		)
		(fp_line
			(start 0.12065 0.3048)
			(end 0.67945 0.3048)
			(stroke
				(width 0.1)
				(type default)
			)
			(layer "B.Fab")
		)
		(fp_line
			(start 0.67945 0.3048)
			(end 0.67945 -0.305054)
			(stroke
				(width 0.1)
				(type default)
			)
			(layer "B.Fab")
		)
		(fp_line
			(start -0.120396 0.2794)
			(end 0.12065 0.2794)
			(stroke
				(width 0.1)
				(type default)
			)
			(layer "B.Fab")
		)
		(fp_line
			(start 0.12065 0.2794)
			(end 0.12065 0.3048)
			(stroke
				(width 0.1)
				(type default)
			)
			(layer "B.Fab")
		)
		(fp_line
			(start -0.12065 -0.2794)
			(end -0.12065 -0.3048)
			(stroke
				(width 0.1)
				(type default)
			)
			(layer "B.Fab")
		)
		(fp_line
			(start 0.12065 -0.2794)
			(end -0.12065 -0.2794)
			(stroke
				(width 0.1)
				(type default)
			)
			(layer "B.Fab")
		)
		(fp_line
			(start -0.67945 -0.3048)
			(end -0.67945 0.3048)
			(stroke
				(width 0.1)
				(type default)
			)
			(layer "B.Fab")
		)
		(fp_line
			(start -0.12065 -0.3048)
			(end -0.67945 -0.3048)
			(stroke
				(width 0.1)
				(type default)
			)
			(layer "B.Fab")
		)
		(fp_line
			(start 0.12065 -0.305054)
			(end 0.12065 -0.2794)
			(stroke
				(width 0.1)
				(type default)
			)
			(layer "B.Fab")
		)
		(fp_line
			(start 0.67945 -0.305054)
			(end 0.12065 -0.305054)
			(stroke
				(width 0.1)
				(type default)
			)
			(layer "B.Fab")
		)
		(pad "1" smd circle
			(at 0.40005 0 90)
			(size 0 0)
			(layers "B.Cu" "B.Mask" "B.Paste")
			(net "P3V3_AUX")
		)
		(pad "2" smd circle
			(at -0.40005 0 90)
			(size 0 0)
			(layers "B.Cu" "B.Mask" "B.Paste")
			(net "GND")
		)
	)
	(footprint ""
		(layer "B.Cu")
		(at 388.618476 -396.393162 -90)
		(property "Reference" "C1043"
			(at 0 0 90)
			(layer "B.SilkS")
			(hide yes)
			(effects
				(font
					(size 1.27 1.27)
				)
				(justify mirror)
			)
		)
		(property "Value" ""
			(at 0 0 90)
			(layer "B.Fab")
			(effects
				(font
					(size 1.27 1.27)
				)
				(justify mirror)
			)
		)
		(duplicate_pad_numbers_are_jumpers no)
		(fp_line
			(start -0.299974 0.150114)
			(end 0.299974 0.150114)
			(stroke
				(width 0.1)
				(type default)
			)
			(layer "B.Fab")
		)
		(fp_line
			(start 0.299974 0.150114)
			(end 0.299974 -0.150114)
			(stroke
				(width 0.1)
				(type default)
			)
			(layer "B.Fab")
		)
		(fp_line
			(start -0.299974 -0.150114)
			(end -0.299974 0.150114)
			(stroke
				(width 0.1)
				(type default)
			)
			(layer "B.Fab")
		)
		(fp_line
			(start 0.299974 -0.150114)
			(end -0.299974 -0.150114)
			(stroke
				(width 0.1)
				(type default)
			)
			(layer "B.Fab")
		)
		(pad "1" smd rect
			(at 0.2667 0 90)
			(size 0.3048 0.381)
			(layers "B.Cu" "B.Mask" "B.Paste")
			(net "P0V9_CPU0_RT3_2A")
		)
		(pad "2" smd rect
			(at -0.2667 0 90)
			(size 0.3048 0.381)
			(layers "B.Cu" "B.Mask" "B.Paste")
			(net "GND")
		)
	)
	(footprint ""
		(layer "B.Cu")
		(at 116.078 -417.957 90)
		(property "Reference" "R3525"
			(at 0 0 90)
			(layer "B.SilkS")
			(hide yes)
			(effects
				(font
					(size 1.27 1.27)
				)
				(justify mirror)
			)
		)
		(property "Value" ""
			(at 0 0 90)
			(layer "B.Fab")
			(effects
				(font
					(size 1.27 1.27)
				)
				(justify mirror)
			)
		)
		(duplicate_pad_numbers_are_jumpers no)
		(fp_line
			(start 0.7874 -0.4064)
			(end -0.7874 -0.4064)
			(stroke
				(width 0.1524)
				(type default)
			)
			(layer "B.SilkS")
		)
		(fp_line
			(start -0.7874 -0.4064)
			(end -0.7874 0.4064)
			(stroke
				(width 0.1524)
				(type default)
			)
			(layer "B.SilkS")
		)
		(fp_line
			(start 0.7874 0.4064)
			(end 0.7874 -0.4064)
			(stroke
				(width 0.1524)
				(type default)
			)
			(layer "B.SilkS")
		)
		(fp_line
			(start -0.7874 0.4064)
			(end 0.7874 0.4064)
			(stroke
				(width 0.1524)
				(type default)
			)
			(layer "B.SilkS")
		)
		(fp_line
			(start 0.67945 -0.305054)
			(end 0.12065 -0.305054)
			(stroke
				(width 0.1)
				(type default)
			)
			(layer "B.Fab")
		)
		(fp_line
			(start 0.12065 -0.305054)
			(end 0.12065 -0.2794)
			(stroke
				(width 0.1)
				(type default)
			)
			(layer "B.Fab")
		)
		(fp_line
			(start -0.12065 -0.3048)
			(end -0.67945 -0.3048)
			(stroke
				(width 0.1)
				(type default)
			)
			(layer "B.Fab")
		)
		(fp_line
			(start -0.67945 -0.3048)
			(end -0.67945 0.3048)
			(stroke
				(width 0.1)
				(type default)
			)
			(layer "B.Fab")
		)
		(fp_line
			(start 0.12065 -0.2794)
			(end -0.12065 -0.2794)
			(stroke
				(width 0.1)
				(type default)
			)
			(layer "B.Fab")
		)
		(fp_line
			(start -0.12065 -0.2794)
			(end -0.12065 -0.3048)
			(stroke
				(width 0.1)
				(type default)
			)
			(layer "B.Fab")
		)
		(fp_line
			(start 0.12065 0.2794)
			(end 0.12065 0.3048)
			(stroke
				(width 0.1)
				(type default)
			)
			(layer "B.Fab")
		)
		(fp_line
			(start -0.120396 0.2794)
			(end 0.12065 0.2794)
			(stroke
				(width 0.1)
				(type default)
			)
			(layer "B.Fab")
		)
		(fp_line
			(start 0.67945 0.3048)
			(end 0.67945 -0.305054)
			(stroke
				(width 0.1)
				(type default)
			)
			(layer "B.Fab")
		)
		(fp_line
			(start 0.12065 0.3048)
			(end 0.67945 0.3048)
			(stroke
				(width 0.1)
				(type default)
			)
			(layer "B.Fab")
		)
		(fp_line
			(start -0.120396 0.3048)
			(end -0.120396 0.2794)
			(stroke
				(width 0.1)
				(type default)
			)
			(layer "B.Fab")
		)
		(fp_line
			(start -0.67945 0.3048)
			(end -0.120396 0.3048)
			(stroke
				(width 0.1)
				(type default)
			)
			(layer "B.Fab")
		)
		(pad "1" smd circle
			(at 0.40005 0 270)
			(size 0 0)
			(layers "B.Cu" "B.Mask" "B.Paste")
			(net "P3V3_AUX")
		)
		(pad "2" smd circle
			(at -0.40005 0 270)
			(size 0 0)
			(layers "B.Cu" "B.Mask" "B.Paste")
			(net "GPU_FPGA_EROT_FATALERR_N")
		)
	)
	(footprint ""
		(layer "B.Cu")
		(at 96.706436 -386.766562 90)
		(property "Reference" "C346"
			(at 0 0 90)
			(layer "B.SilkS")
			(hide yes)
			(effects
				(font
					(size 1.27 1.27)
				)
				(justify mirror)
			)
		)
		(property "Value" ""
			(at 0 0 90)
			(layer "B.Fab")
			(effects
				(font
					(size 1.27 1.27)
				)
				(justify mirror)
			)
		)
		(duplicate_pad_numbers_are_jumpers no)
		(fp_line
			(start 0.299974 -0.150114)
			(end -0.299974 -0.150114)
			(stroke
				(width 0.1)
				(type default)
			)
			(layer "B.Fab")
		)
		(fp_line
			(start -0.299974 -0.150114)
			(end -0.299974 0.150114)
			(stroke
				(width 0.1)
				(type default)
			)
			(layer "B.Fab")
		)
		(fp_line
			(start 0.299974 0.150114)
			(end 0.299974 -0.150114)
			(stroke
				(width 0.1)
				(type default)
			)
			(layer "B.Fab")
		)
		(fp_line
			(start -0.299974 0.150114)
			(end 0.299974 0.150114)
			(stroke
				(width 0.1)
				(type default)
			)
			(layer "B.Fab")
		)
		(pad "1" smd rect
			(at 0.2667 0 270)
			(size 0.3048 0.381)
			(layers "B.Cu" "B.Mask" "B.Paste")
			(net "P0V9_CPU1_RT1_2A")
		)
		(pad "2" smd rect
			(at -0.2667 0 270)
			(size 0.3048 0.381)
			(layers "B.Cu" "B.Mask" "B.Paste")
			(net "GND")
		)
	)
	(footprint ""
		(layer "B.Cu")
		(at 52.782978 -428.06493 -90)
		(property "Reference" "R3475"
			(at 0 0 90)
			(layer "B.SilkS")
			(hide yes)
			(effects
				(font
					(size 1.27 1.27)
				)
				(justify mirror)
			)
		)
		(property "Value" ""
			(at 0 0 90)
			(layer "B.Fab")
			(effects
				(font
					(size 1.27 1.27)
				)
				(justify mirror)
			)
		)
		(duplicate_pad_numbers_are_jumpers no)
		(fp_line
			(start -0.7874 0.4064)
			(end 0.7874 0.4064)
			(stroke
				(width 0.1524)
				(type default)
			)
			(layer "B.SilkS")
		)
		(fp_line
			(start 0.7874 0.4064)
			(end 0.7874 -0.4064)
			(stroke
				(width 0.1524)
				(type default)
			)
			(layer "B.SilkS")
		)
		(fp_line
			(start -0.7874 -0.4064)
			(end -0.7874 0.4064)
			(stroke
				(width 0.1524)
				(type default)
			)
			(layer "B.SilkS")
		)
		(fp_line
			(start 0.7874 -0.4064)
			(end -0.7874 -0.4064)
			(stroke
				(width 0.1524)
				(type default)
			)
			(layer "B.SilkS")
		)
		(fp_line
			(start -0.67945 0.3048)
			(end -0.120396 0.3048)
			(stroke
				(width 0.1)
				(type default)
			)
			(layer "B.Fab")
		)
		(fp_line
			(start -0.120396 0.3048)
			(end -0.120396 0.2794)
			(stroke
				(width 0.1)
				(type default)
			)
			(layer "B.Fab")
		)
		(fp_line
			(start 0.12065 0.3048)
			(end 0.67945 0.3048)
			(stroke
				(width 0.1)
				(type default)
			)
			(layer "B.Fab")
		)
		(fp_line
			(start 0.67945 0.3048)
			(end 0.67945 -0.305054)
			(stroke
				(width 0.1)
				(type default)
			)
			(layer "B.Fab")
		)
		(fp_line
			(start -0.120396 0.2794)
			(end 0.12065 0.2794)
			(stroke
				(width 0.1)
				(type default)
			)
			(layer "B.Fab")
		)
		(fp_line
			(start 0.12065 0.2794)
			(end 0.12065 0.3048)
			(stroke
				(width 0.1)
				(type default)
			)
			(layer "B.Fab")
		)
		(fp_line
			(start -0.12065 -0.2794)
			(end -0.12065 -0.3048)
			(stroke
				(width 0.1)
				(type default)
			)
			(layer "B.Fab")
		)
		(fp_line
			(start 0.12065 -0.2794)
			(end -0.12065 -0.2794)
			(stroke
				(width 0.1)
				(type default)
			)
			(layer "B.Fab")
		)
		(fp_line
			(start -0.67945 -0.3048)
			(end -0.67945 0.3048)
			(stroke
				(width 0.1)
				(type default)
			)
			(layer "B.Fab")
		)
		(fp_line
			(start -0.12065 -0.3048)
			(end -0.67945 -0.3048)
			(stroke
				(width 0.1)
				(type default)
			)
			(layer "B.Fab")
		)
		(fp_line
			(start 0.12065 -0.305054)
			(end 0.12065 -0.2794)
			(stroke
				(width 0.1)
				(type default)
			)
			(layer "B.Fab")
		)
		(fp_line
			(start 0.67945 -0.305054)
			(end 0.12065 -0.305054)
			(stroke
				(width 0.1)
				(type default)
			)
			(layer "B.Fab")
		)
		(pad "1" smd circle
			(at 0.40005 0 90)
			(size 0 0)
			(layers "B.Cu" "B.Mask" "B.Paste")
			(net "P3V3_AUX")
		)
		(pad "2" smd circle
			(at -0.40005 0 90)
			(size 0 0)
			(layers "B.Cu" "B.Mask" "B.Paste")
			(net "GPU_PRSNT_N_ISO")
		)
	)
	(footprint ""
		(layer "B.Cu")
		(at 100.478844 -257.930396 180)
		(property "Reference" "C2112"
			(at 0 0 0)
			(layer "B.SilkS")
			(hide yes)
			(effects
				(font
					(size 1.27 1.27)
				)
				(justify mirror)
			)
		)
		(property "Value" ""
			(at 0 0 0)
			(layer "B.Fab")
			(effects
				(font
					(size 1.27 1.27)
				)
				(justify mirror)
			)
		)
		(duplicate_pad_numbers_are_jumpers no)
		(fp_line
			(start 0.7874 0.4064)
			(end 0.7874 -0.4064)
			(stroke
				(width 0.1524)
				(type default)
			)
			(layer "B.SilkS")
		)
		(fp_line
			(start 0.7874 -0.4064)
			(end -0.7874 -0.4064)
			(stroke
				(width 0.1524)
				(type default)
			)
			(layer "B.SilkS")
		)
		(fp_line
			(start -0.7874 0.4064)
			(end 0.7874 0.4064)
			(stroke
				(width 0.1524)
				(type default)
			)
			(layer "B.SilkS")
		)
		(fp_line
			(start -0.7874 -0.4064)
			(end -0.7874 0.4064)
			(stroke
				(width 0.1524)
				(type default)
			)
			(layer "B.SilkS")
		)
		(fp_line
			(start 0.67945 0.3048)
			(end 0.67945 -0.305054)
			(stroke
				(width 0.1)
				(type default)
			)
			(layer "B.Fab")
		)
		(fp_line
			(start 0.67945 -0.305054)
			(end 0.12065 -0.305054)
			(stroke
				(width 0.1)
				(type default)
			)
			(layer "B.Fab")
		)
		(fp_line
			(start 0.12065 0.3048)
			(end 0.67945 0.3048)
			(stroke
				(width 0.1)
				(type default)
			)
			(layer "B.Fab")
		)
		(fp_line
			(start 0.12065 0.2794)
			(end 0.12065 0.3048)
			(stroke
				(width 0.1)
				(type default)
			)
			(layer "B.Fab")
		)
		(fp_line
			(start 0.12065 -0.2794)
			(end -0.12065 -0.2794)
			(stroke
				(width 0.1)
				(type default)
			)
			(layer "B.Fab")
		)
		(fp_line
			(start 0.12065 -0.305054)
			(end 0.12065 -0.2794)
			(stroke
				(width 0.1)
				(type default)
			)
			(layer "B.Fab")
		)
		(fp_line
			(start -0.120396 0.3048)
			(end -0.120396 0.2794)
			(stroke
				(width 0.1)
				(type default)
			)
			(layer "B.Fab")
		)
		(fp_line
			(start -0.120396 0.2794)
			(end 0.12065 0.2794)
			(stroke
				(width 0.1)
				(type default)
			)
			(layer "B.Fab")
		)
		(fp_line
			(start -0.12065 -0.2794)
			(end -0.12065 -0.3048)
			(stroke
				(width 0.1)
				(type default)
			)
			(layer "B.Fab")
		)
		(fp_line
			(start -0.12065 -0.3048)
			(end -0.67945 -0.3048)
			(stroke
				(width 0.1)
				(type default)
			)
			(layer "B.Fab")
		)
		(fp_line
			(start -0.67945 0.3048)
			(end -0.120396 0.3048)
			(stroke
				(width 0.1)
				(type default)
			)
			(layer "B.Fab")
		)
		(fp_line
			(start -0.67945 -0.3048)
			(end -0.67945 0.3048)
			(stroke
				(width 0.1)
				(type default)
			)
			(layer "B.Fab")
		)
		(pad "1" smd circle
			(at 0.40005 0)
			(size 0 0)
			(layers "B.Cu" "B.Mask" "B.Paste")
			(net "PVDDIO_P1")
		)
		(pad "2" smd circle
			(at -0.40005 0)
			(size 0 0)
			(layers "B.Cu" "B.Mask" "B.Paste")
			(net "GND")
		)
	)
	(footprint ""
		(layer "B.Cu")
		(at 123.611386 -254.194564)
		(property "Reference" "C2454"
			(at 0 0 0)
			(layer "B.SilkS")
			(hide yes)
			(effects
				(font
					(size 1.27 1.27)
				)
				(justify mirror)
			)
		)
		(property "Value" ""
			(at 0 0 0)
			(layer "B.Fab")
			(effects
				(font
					(size 1.27 1.27)
				)
				(justify mirror)
			)
		)
		(duplicate_pad_numbers_are_jumpers no)
		(fp_line
			(start -0.7874 -0.4064)
			(end -0.7874 0.4064)
			(stroke
				(width 0.1524)
				(type default)
			)
			(layer "B.SilkS")
		)
		(fp_line
			(start -0.7874 0.4064)
			(end 0.7874 0.4064)
			(stroke
				(width 0.1524)
				(type default)
			)
			(layer "B.SilkS")
		)
		(fp_line
			(start 0.7874 -0.4064)
			(end -0.7874 -0.4064)
			(stroke
				(width 0.1524)
				(type default)
			)
			(layer "B.SilkS")
		)
		(fp_line
			(start 0.7874 0.4064)
			(end 0.7874 -0.4064)
			(stroke
				(width 0.1524)
				(type default)
			)
			(layer "B.SilkS")
		)
		(fp_line
			(start -0.67945 -0.3048)
			(end -0.67945 0.3048)
			(stroke
				(width 0.1)
				(type default)
			)
			(layer "B.Fab")
		)
		(fp_line
			(start -0.67945 0.3048)
			(end -0.120396 0.3048)
			(stroke
				(width 0.1)
				(type default)
			)
			(layer "B.Fab")
		)
		(fp_line
			(start -0.12065 -0.3048)
			(end -0.67945 -0.3048)
			(stroke
				(width 0.1)
				(type default)
			)
			(layer "B.Fab")
		)
		(fp_line
			(start -0.12065 -0.2794)
			(end -0.12065 -0.3048)
			(stroke
				(width 0.1)
				(type default)
			)
			(layer "B.Fab")
		)
		(fp_line
			(start -0.120396 0.2794)
			(end 0.12065 0.2794)
			(stroke
				(width 0.1)
				(type default)
			)
			(layer "B.Fab")
		)
		(fp_line
			(start -0.120396 0.3048)
			(end -0.120396 0.2794)
			(stroke
				(width 0.1)
				(type default)
			)
			(layer "B.Fab")
		)
		(fp_line
			(start 0.12065 -0.305054)
			(end 0.12065 -0.2794)
			(stroke
				(width 0.1)
				(type default)
			)
			(layer "B.Fab")
		)
		(fp_line
			(start 0.12065 -0.2794)
			(end -0.12065 -0.2794)
			(stroke
				(width 0.1)
				(type default)
			)
			(layer "B.Fab")
		)
		(fp_line
			(start 0.12065 0.2794)
			(end 0.12065 0.3048)
			(stroke
				(width 0.1)
				(type default)
			)
			(layer "B.Fab")
		)
		(fp_line
			(start 0.12065 0.3048)
			(end 0.67945 0.3048)
			(stroke
				(width 0.1)
				(type default)
			)
			(layer "B.Fab")
		)
		(fp_line
			(start 0.67945 -0.305054)
			(end 0.12065 -0.305054)
			(stroke
				(width 0.1)
				(type default)
			)
			(layer "B.Fab")
		)
		(fp_line
			(start 0.67945 0.3048)
			(end 0.67945 -0.305054)
			(stroke
				(width 0.1)
				(type default)
			)
			(layer "B.Fab")
		)
		(pad "1" smd circle
			(at 0.40005 0 180)
			(size 0 0)
			(layers "B.Cu" "B.Mask" "B.Paste")
			(net "PVDDCR_SOC_P1")
		)
		(pad "2" smd circle
			(at -0.40005 0 180)
			(size 0 0)
			(layers "B.Cu" "B.Mask" "B.Paste")
			(net "GND")
		)
	)
	(footprint ""
		(layer "B.Cu")
		(at 134.840218 -40.111426)
		(property "Reference" "C6035"
			(at 0 0 0)
			(layer "B.SilkS")
			(hide yes)
			(effects
				(font
					(size 1.27 1.27)
				)
				(justify mirror)
			)
		)
		(property "Value" ""
			(at 0 0 0)
			(layer "B.Fab")
			(effects
				(font
					(size 1.27 1.27)
				)
				(justify mirror)
			)
		)
		(duplicate_pad_numbers_are_jumpers no)
		(fp_line
			(start -0.7874 -0.4064)
			(end -0.7874 0.4064)
			(stroke
				(width 0.1524)
				(type default)
			)
			(layer "B.SilkS")
		)
		(fp_line
			(start -0.7874 0.4064)
			(end 0.7874 0.4064)
			(stroke
				(width 0.1524)
				(type default)
			)
			(layer "B.SilkS")
		)
		(fp_line
			(start 0.7874 -0.4064)
			(end -0.7874 -0.4064)
			(stroke
				(width 0.1524)
				(type default)
			)
			(layer "B.SilkS")
		)
		(fp_line
			(start 0.7874 0.4064)
			(end 0.7874 -0.4064)
			(stroke
				(width 0.1524)
				(type default)
			)
			(layer "B.SilkS")
		)
		(fp_line
			(start -0.67945 -0.3048)
			(end -0.67945 0.3048)
			(stroke
				(width 0.1)
				(type default)
			)
			(layer "B.Fab")
		)
		(fp_line
			(start -0.67945 0.3048)
			(end -0.120396 0.3048)
			(stroke
				(width 0.1)
				(type default)
			)
			(layer "B.Fab")
		)
		(fp_line
			(start -0.12065 -0.3048)
			(end -0.67945 -0.3048)
			(stroke
				(width 0.1)
				(type default)
			)
			(layer "B.Fab")
		)
		(fp_line
			(start -0.12065 -0.2794)
			(end -0.12065 -0.3048)
			(stroke
				(width 0.1)
				(type default)
			)
			(layer "B.Fab")
		)
		(fp_line
			(start -0.120396 0.2794)
			(end 0.12065 0.2794)
			(stroke
				(width 0.1)
				(type default)
			)
			(layer "B.Fab")
		)
		(fp_line
			(start -0.120396 0.3048)
			(end -0.120396 0.2794)
			(stroke
				(width 0.1)
				(type default)
			)
			(layer "B.Fab")
		)
		(fp_line
			(start 0.12065 -0.305054)
			(end 0.12065 -0.2794)
			(stroke
				(width 0.1)
				(type default)
			)
			(layer "B.Fab")
		)
		(fp_line
			(start 0.12065 -0.2794)
			(end -0.12065 -0.2794)
			(stroke
				(width 0.1)
				(type default)
			)
			(layer "B.Fab")
		)
		(fp_line
			(start 0.12065 0.2794)
			(end 0.12065 0.3048)
			(stroke
				(width 0.1)
				(type default)
			)
			(layer "B.Fab")
		)
		(fp_line
			(start 0.12065 0.3048)
			(end 0.67945 0.3048)
			(stroke
				(width 0.1)
				(type default)
			)
			(layer "B.Fab")
		)
		(fp_line
			(start 0.67945 -0.305054)
			(end 0.12065 -0.305054)
			(stroke
				(width 0.1)
				(type default)
			)
			(layer "B.Fab")
		)
		(fp_line
			(start 0.67945 0.3048)
			(end 0.67945 -0.305054)
			(stroke
				(width 0.1)
				(type default)
			)
			(layer "B.Fab")
		)
		(pad "1" smd circle
			(at 0.40005 0 180)
			(size 0 0)
			(layers "B.Cu" "B.Mask" "B.Paste")
			(net "P1V2_CPU0_USB_DVDD12")
		)
		(pad "2" smd circle
			(at -0.40005 0 180)
			(size 0 0)
			(layers "B.Cu" "B.Mask" "B.Paste")
			(net "GND")
		)
	)
	(footprint ""
		(layer "B.Cu")
		(at 37.565076 -339.915754 -90)
		(property "Reference" "PC452"
			(at 9.447276 1.051814 270)
			(unlocked yes)
			(layer "B.SilkS")
			(effects
				(font
					(size 0.7874 0.5842)
					(thickness 0.1524)
				)
				(justify left mirror)
			)
		)
		(property "Value" ""
			(at 0 0 90)
			(layer "B.Fab")
			(effects
				(font
					(size 1.27 1.27)
				)
				(justify mirror)
			)
		)
		(duplicate_pad_numbers_are_jumpers no)
		(fp_line
			(start -4.533392 2.249932)
			(end 4.533392 2.249932)
			(stroke
				(width 0.1524)
				(type default)
			)
			(layer "B.SilkS")
		)
		(fp_line
			(start 4.533392 2.249932)
			(end 4.533392 -2.249932)
			(stroke
				(width 0.1524)
				(type default)
			)
			(layer "B.SilkS")
		)
		(fp_line
			(start -4.533392 -2.249932)
			(end -4.533392 2.249932)
			(stroke
				(width 0.1524)
				(type default)
			)
			(layer "B.SilkS")
		)
		(fp_line
			(start 4.533392 -2.249932)
			(end -4.533392 -2.249932)
			(stroke
				(width 0.1524)
				(type default)
			)
			(layer "B.SilkS")
		)
		(fp_rect
			(start 5.39242 2.326132)
			(end 4.533392 -2.326132)
			(stroke
				(width 0)
				(type default)
			)
			(fill yes)
			(layer "B.SilkS")
		)
		(fp_line
			(start -3.750056 2.249932)
			(end 3.750056 2.249932)
			(stroke
				(width 0.1)
				(type default)
			)
			(layer "B.Fab")
		)
		(fp_line
			(start 3.750056 2.249932)
			(end 3.750056 -2.249932)
			(stroke
				(width 0.1)
				(type default)
			)
			(layer "B.Fab")
		)
		(fp_line
			(start -3.750056 -2.249932)
			(end -3.750056 2.249932)
			(stroke
				(width 0.1)
				(type default)
			)
			(layer "B.Fab")
		)
		(fp_line
			(start 3.750056 -2.249932)
			(end -3.750056 -2.249932)
			(stroke
				(width 0.1)
				(type default)
			)
			(layer "B.Fab")
		)
		(fp_text user "+"
			(at 6.322314 0.786384 180)
			(unlocked yes)
			(layer "B.SilkS")
			(effects
				(font
					(size 1.905 1.4224)
					(thickness 0.1524)
				)
				(justify left mirror)
			)
		)
		(fp_text user "-"
			(at -4.27736 -1.846072 270)
			(unlocked yes)
			(layer "B.SilkS")
			(effects
				(font
					(size 1.905 1.4224)
					(thickness 0.1524)
				)
				(justify left mirror)
			)
		)
		(fp_text user "+"
			(at 6.322314 0.786384 180)
			(unlocked yes)
			(layer "B.Fab")
			(effects
				(font
					(size 1.905 1.4224)
					(thickness 0.1524)
				)
				(justify left mirror)
			)
		)
		(fp_text user "-"
			(at -4.8514 -0.14605 270)
			(unlocked yes)
			(layer "B.Fab")
			(effects
				(font
					(size 1.905 1.4224)
					(thickness 0.1524)
				)
				(justify left mirror)
			)
		)
		(pad "1" smd rect
			(at 3.199892 0 90)
			(size 2.413 2.8194)
			(layers "B.Cu" "B.Mask" "B.Paste")
			(net "PVDDIO_P1")
		)
		(pad "2" smd rect
			(at -3.199892 0 90)
			(size 2.413 2.8194)
			(layers "B.Cu" "B.Mask" "B.Paste")
			(net "GND")
		)
	)
	(footprint ""
		(layer "B.Cu")
		(at 112.624108 -381.321818)
		(property "Reference" "C7031"
			(at 0 0 0)
			(layer "B.SilkS")
			(hide yes)
			(effects
				(font
					(size 1.27 1.27)
				)
				(justify mirror)
			)
		)
		(property "Value" ""
			(at 0 0 0)
			(layer "B.Fab")
			(effects
				(font
					(size 1.27 1.27)
				)
				(justify mirror)
			)
		)
		(duplicate_pad_numbers_are_jumpers no)
		(fp_line
			(start -1.524 -0.762)
			(end -1.524 0.762)
			(stroke
				(width 0.1524)
				(type default)
			)
			(layer "B.SilkS")
		)
		(fp_line
			(start -1.524 0.762)
			(end 1.524 0.762)
			(stroke
				(width 0.1524)
				(type default)
			)
			(layer "B.SilkS")
		)
		(fp_line
			(start 1.524 -0.762)
			(end -1.524 -0.762)
			(stroke
				(width 0.1524)
				(type default)
			)
			(layer "B.SilkS")
		)
		(fp_line
			(start 1.524 0.762)
			(end 1.524 -0.762)
			(stroke
				(width 0.1524)
				(type default)
			)
			(layer "B.SilkS")
		)
		(fp_line
			(start -1.1049 -0.724916)
			(end 1.1049 -0.724916)
			(stroke
				(width 0.1)
				(type default)
			)
			(layer "B.Fab")
		)
		(fp_line
			(start -1.1049 0.724916)
			(end -1.1049 -0.724916)
			(stroke
				(width 0.1)
				(type default)
			)
			(layer "B.Fab")
		)
		(fp_line
			(start 1.1049 -0.724916)
			(end 1.1049 0.724916)
			(stroke
				(width 0.1)
				(type default)
			)
			(layer "B.Fab")
		)
		(fp_line
			(start 1.1049 0.724916)
			(end -1.1049 0.724916)
			(stroke
				(width 0.1)
				(type default)
			)
			(layer "B.Fab")
		)
		(pad "1" smd rect
			(at 0.889 0)
			(size 1.016 1.27)
			(layers "B.Cu" "B.Mask" "B.Paste")
			(net "P0V9_CPU1_RT3_2A")
		)
		(pad "2" smd rect
			(at -0.889 0)
			(size 1.016 1.27)
			(layers "B.Cu" "B.Mask" "B.Paste")
			(net "GND")
		)
	)
	(footprint ""
		(layer "B.Cu")
		(at 179.516278 -192.66027 180)
		(property "Reference" "C534"
			(at 0 0 0)
			(layer "B.SilkS")
			(hide yes)
			(effects
				(font
					(size 1.27 1.27)
				)
				(justify mirror)
			)
		)
		(property "Value" ""
			(at 0 0 0)
			(layer "B.Fab")
			(effects
				(font
					(size 1.27 1.27)
				)
				(justify mirror)
			)
		)
		(duplicate_pad_numbers_are_jumpers no)
		(fp_line
			(start 1.524 0.762)
			(end 1.524 -0.762)
			(stroke
				(width 0.1524)
				(type default)
			)
			(layer "B.SilkS")
		)
		(fp_line
			(start 1.524 -0.762)
			(end -1.524 -0.762)
			(stroke
				(width 0.1524)
				(type default)
			)
			(layer "B.SilkS")
		)
		(fp_line
			(start -1.524 0.762)
			(end 1.524 0.762)
			(stroke
				(width 0.1524)
				(type default)
			)
			(layer "B.SilkS")
		)
		(fp_line
			(start -1.524 -0.762)
			(end -1.524 0.762)
			(stroke
				(width 0.1524)
				(type default)
			)
			(layer "B.SilkS")
		)
		(fp_line
			(start 1.1049 0.724916)
			(end -1.1049 0.724916)
			(stroke
				(width 0.1)
				(type default)
			)
			(layer "B.Fab")
		)
		(fp_line
			(start 1.1049 -0.724916)
			(end 1.1049 0.724916)
			(stroke
				(width 0.1)
				(type default)
			)
			(layer "B.Fab")
		)
		(fp_line
			(start -1.1049 0.724916)
			(end -1.1049 -0.724916)
			(stroke
				(width 0.1)
				(type default)
			)
			(layer "B.Fab")
		)
		(fp_line
			(start -1.1049 -0.724916)
			(end 1.1049 -0.724916)
			(stroke
				(width 0.1)
				(type default)
			)
			(layer "B.Fab")
		)
		(pad "1" smd rect
			(at 0.889 0 180)
			(size 1.016 1.27)
			(layers "B.Cu" "B.Mask" "B.Paste")
			(net "P12V_MEM_CPU1")
		)
		(pad "2" smd rect
			(at -0.889 0 180)
			(size 1.016 1.27)
			(layers "B.Cu" "B.Mask" "B.Paste")
			(net "GND")
		)
	)
	(footprint ""
		(layer "B.Cu")
		(at 413.304736 -159.989012 90)
		(property "Reference" "PC611_3"
			(at 0 0 90)
			(layer "B.SilkS")
			(hide yes)
			(effects
				(font
					(size 1.27 1.27)
				)
				(justify mirror)
			)
		)
		(property "Value" ""
			(at 0 0 90)
			(layer "B.Fab")
			(effects
				(font
					(size 1.27 1.27)
				)
				(justify mirror)
			)
		)
		(duplicate_pad_numbers_are_jumpers no)
		(fp_line
			(start 1.524 -0.762)
			(end -1.524 -0.762)
			(stroke
				(width 0.1524)
				(type default)
			)
			(layer "B.SilkS")
		)
		(fp_line
			(start -1.524 -0.762)
			(end -1.524 0.762)
			(stroke
				(width 0.1524)
				(type default)
			)
			(layer "B.SilkS")
		)
		(fp_line
			(start 1.524 0.762)
			(end 1.524 -0.762)
			(stroke
				(width 0.1524)
				(type default)
			)
			(layer "B.SilkS")
		)
		(fp_line
			(start -1.524 0.762)
			(end 1.524 0.762)
			(stroke
				(width 0.1524)
				(type default)
			)
			(layer "B.SilkS")
		)
		(fp_line
			(start 1.1049 -0.724916)
			(end 1.1049 0.724916)
			(stroke
				(width 0.1)
				(type default)
			)
			(layer "B.Fab")
		)
		(fp_line
			(start -1.1049 -0.724916)
			(end 1.1049 -0.724916)
			(stroke
				(width 0.1)
				(type default)
			)
			(layer "B.Fab")
		)
		(fp_line
			(start 1.1049 0.724916)
			(end -1.1049 0.724916)
			(stroke
				(width 0.1)
				(type default)
			)
			(layer "B.Fab")
		)
		(fp_line
			(start -1.1049 0.724916)
			(end -1.1049 -0.724916)
			(stroke
				(width 0.1)
				(type default)
			)
			(layer "B.Fab")
		)
		(pad "1" smd rect
			(at 0.889 0 90)
			(size 1.016 1.27)
			(layers "B.Cu" "B.Mask" "B.Paste")
			(net "SW_P12V_AUX_PVDDCR_SOC_P0_FLT")
		)
		(pad "2" smd rect
			(at -0.889 0 90)
			(size 1.016 1.27)
			(layers "B.Cu" "B.Mask" "B.Paste")
			(net "GND")
		)
	)
	(footprint ""
		(layer "B.Cu")
		(at 234.80522 -325.894192 180)
		(property "Reference" "R1223"
			(at 0 0 0)
			(layer "B.SilkS")
			(hide yes)
			(effects
				(font
					(size 1.27 1.27)
				)
				(justify mirror)
			)
		)
		(property "Value" ""
			(at 0 0 0)
			(layer "B.Fab")
			(effects
				(font
					(size 1.27 1.27)
				)
				(justify mirror)
			)
		)
		(duplicate_pad_numbers_are_jumpers no)
		(fp_line
			(start 0.7874 0.4064)
			(end 0.7874 -0.4064)
			(stroke
				(width 0.1524)
				(type default)
			)
			(layer "B.SilkS")
		)
		(fp_line
			(start 0.7874 -0.4064)
			(end -0.7874 -0.4064)
			(stroke
				(width 0.1524)
				(type default)
			)
			(layer "B.SilkS")
		)
		(fp_line
			(start -0.7874 0.4064)
			(end 0.7874 0.4064)
			(stroke
				(width 0.1524)
				(type default)
			)
			(layer "B.SilkS")
		)
		(fp_line
			(start -0.7874 -0.4064)
			(end -0.7874 0.4064)
			(stroke
				(width 0.1524)
				(type default)
			)
			(layer "B.SilkS")
		)
		(fp_line
			(start 0.67945 0.3048)
			(end 0.67945 -0.305054)
			(stroke
				(width 0.1)
				(type default)
			)
			(layer "B.Fab")
		)
		(fp_line
			(start 0.67945 -0.305054)
			(end 0.12065 -0.305054)
			(stroke
				(width 0.1)
				(type default)
			)
			(layer "B.Fab")
		)
		(fp_line
			(start 0.12065 0.3048)
			(end 0.67945 0.3048)
			(stroke
				(width 0.1)
				(type default)
			)
			(layer "B.Fab")
		)
		(fp_line
			(start 0.12065 0.2794)
			(end 0.12065 0.3048)
			(stroke
				(width 0.1)
				(type default)
			)
			(layer "B.Fab")
		)
		(fp_line
			(start 0.12065 -0.2794)
			(end -0.12065 -0.2794)
			(stroke
				(width 0.1)
				(type default)
			)
			(layer "B.Fab")
		)
		(fp_line
			(start 0.12065 -0.305054)
			(end 0.12065 -0.2794)
			(stroke
				(width 0.1)
				(type default)
			)
			(layer "B.Fab")
		)
		(fp_line
			(start -0.120396 0.3048)
			(end -0.120396 0.2794)
			(stroke
				(width 0.1)
				(type default)
			)
			(layer "B.Fab")
		)
		(fp_line
			(start -0.120396 0.2794)
			(end 0.12065 0.2794)
			(stroke
				(width 0.1)
				(type default)
			)
			(layer "B.Fab")
		)
		(fp_line
			(start -0.12065 -0.2794)
			(end -0.12065 -0.3048)
			(stroke
				(width 0.1)
				(type default)
			)
			(layer "B.Fab")
		)
		(fp_line
			(start -0.12065 -0.3048)
			(end -0.67945 -0.3048)
			(stroke
				(width 0.1)
				(type default)
			)
			(layer "B.Fab")
		)
		(fp_line
			(start -0.67945 0.3048)
			(end -0.120396 0.3048)
			(stroke
				(width 0.1)
				(type default)
			)
			(layer "B.Fab")
		)
		(fp_line
			(start -0.67945 -0.3048)
			(end -0.67945 0.3048)
			(stroke
				(width 0.1)
				(type default)
			)
			(layer "B.Fab")
		)
		(pad "1" smd circle
			(at 0.40005 0)
			(size 0 0)
			(layers "B.Cu" "B.Mask" "B.Paste")
			(net "P1V8_CPU1_RT_1D_ADC")
		)
		(pad "2" smd circle
			(at -0.40005 0)
			(size 0 0)
			(layers "B.Cu" "B.Mask" "B.Paste")
			(net "GND")
		)
	)
	(footprint ""
		(layer "B.Cu")
		(at 361.046014 -259.845048 180)
		(property "Reference" "C2160"
			(at 0 0 0)
			(layer "B.SilkS")
			(hide yes)
			(effects
				(font
					(size 1.27 1.27)
				)
				(justify mirror)
			)
		)
		(property "Value" ""
			(at 0 0 0)
			(layer "B.Fab")
			(effects
				(font
					(size 1.27 1.27)
				)
				(justify mirror)
			)
		)
		(duplicate_pad_numbers_are_jumpers no)
		(fp_line
			(start 0.7874 0.4064)
			(end 0.7874 -0.4064)
			(stroke
				(width 0.1524)
				(type default)
			)
			(layer "B.SilkS")
		)
		(fp_line
			(start 0.7874 -0.4064)
			(end -0.7874 -0.4064)
			(stroke
				(width 0.1524)
				(type default)
			)
			(layer "B.SilkS")
		)
		(fp_line
			(start -0.7874 0.4064)
			(end 0.7874 0.4064)
			(stroke
				(width 0.1524)
				(type default)
			)
			(layer "B.SilkS")
		)
		(fp_line
			(start -0.7874 -0.4064)
			(end -0.7874 0.4064)
			(stroke
				(width 0.1524)
				(type default)
			)
			(layer "B.SilkS")
		)
		(fp_line
			(start 0.67945 0.3048)
			(end 0.67945 -0.305054)
			(stroke
				(width 0.1)
				(type default)
			)
			(layer "B.Fab")
		)
		(fp_line
			(start 0.67945 -0.305054)
			(end 0.12065 -0.305054)
			(stroke
				(width 0.1)
				(type default)
			)
			(layer "B.Fab")
		)
		(fp_line
			(start 0.12065 0.3048)
			(end 0.67945 0.3048)
			(stroke
				(width 0.1)
				(type default)
			)
			(layer "B.Fab")
		)
		(fp_line
			(start 0.12065 0.2794)
			(end 0.12065 0.3048)
			(stroke
				(width 0.1)
				(type default)
			)
			(layer "B.Fab")
		)
		(fp_line
			(start 0.12065 -0.2794)
			(end -0.12065 -0.2794)
			(stroke
				(width 0.1)
				(type default)
			)
			(layer "B.Fab")
		)
		(fp_line
			(start 0.12065 -0.305054)
			(end 0.12065 -0.2794)
			(stroke
				(width 0.1)
				(type default)
			)
			(layer "B.Fab")
		)
		(fp_line
			(start -0.120396 0.3048)
			(end -0.120396 0.2794)
			(stroke
				(width 0.1)
				(type default)
			)
			(layer "B.Fab")
		)
		(fp_line
			(start -0.120396 0.2794)
			(end 0.12065 0.2794)
			(stroke
				(width 0.1)
				(type default)
			)
			(layer "B.Fab")
		)
		(fp_line
			(start -0.12065 -0.2794)
			(end -0.12065 -0.3048)
			(stroke
				(width 0.1)
				(type default)
			)
			(layer "B.Fab")
		)
		(fp_line
			(start -0.12065 -0.3048)
			(end -0.67945 -0.3048)
			(stroke
				(width 0.1)
				(type default)
			)
			(layer "B.Fab")
		)
		(fp_line
			(start -0.67945 0.3048)
			(end -0.120396 0.3048)
			(stroke
				(width 0.1)
				(type default)
			)
			(layer "B.Fab")
		)
		(fp_line
			(start -0.67945 -0.3048)
			(end -0.67945 0.3048)
			(stroke
				(width 0.1)
				(type default)
			)
			(layer "B.Fab")
		)
		(pad "1" smd circle
			(at 0.40005 0)
			(size 0 0)
			(layers "B.Cu" "B.Mask" "B.Paste")
			(net "PVDD11_S3_P0")
		)
		(pad "2" smd circle
			(at -0.40005 0)
			(size 0 0)
			(layers "B.Cu" "B.Mask" "B.Paste")
			(net "GND")
		)
	)
	(footprint ""
		(layer "B.Cu")
		(at 298.526454 -190.82131 180)
		(property "Reference" "R88"
			(at 0 0 0)
			(layer "B.SilkS")
			(hide yes)
			(effects
				(font
					(size 1.27 1.27)
				)
				(justify mirror)
			)
		)
		(property "Value" ""
			(at 0 0 0)
			(layer "B.Fab")
			(effects
				(font
					(size 1.27 1.27)
				)
				(justify mirror)
			)
		)
		(duplicate_pad_numbers_are_jumpers no)
		(fp_line
			(start 0.7874 0.4064)
			(end 0.7874 -0.4064)
			(stroke
				(width 0.1524)
				(type default)
			)
			(layer "B.SilkS")
		)
		(fp_line
			(start 0.7874 -0.4064)
			(end -0.7874 -0.4064)
			(stroke
				(width 0.1524)
				(type default)
			)
			(layer "B.SilkS")
		)
		(fp_line
			(start -0.7874 0.4064)
			(end 0.7874 0.4064)
			(stroke
				(width 0.1524)
				(type default)
			)
			(layer "B.SilkS")
		)
		(fp_line
			(start -0.7874 -0.4064)
			(end -0.7874 0.4064)
			(stroke
				(width 0.1524)
				(type default)
			)
			(layer "B.SilkS")
		)
		(fp_line
			(start 0.67945 0.3048)
			(end 0.67945 -0.305054)
			(stroke
				(width 0.1)
				(type default)
			)
			(layer "B.Fab")
		)
		(fp_line
			(start 0.67945 -0.305054)
			(end 0.12065 -0.305054)
			(stroke
				(width 0.1)
				(type default)
			)
			(layer "B.Fab")
		)
		(fp_line
			(start 0.12065 0.3048)
			(end 0.67945 0.3048)
			(stroke
				(width 0.1)
				(type default)
			)
			(layer "B.Fab")
		)
		(fp_line
			(start 0.12065 0.2794)
			(end 0.12065 0.3048)
			(stroke
				(width 0.1)
				(type default)
			)
			(layer "B.Fab")
		)
		(fp_line
			(start 0.12065 -0.2794)
			(end -0.12065 -0.2794)
			(stroke
				(width 0.1)
				(type default)
			)
			(layer "B.Fab")
		)
		(fp_line
			(start 0.12065 -0.305054)
			(end 0.12065 -0.2794)
			(stroke
				(width 0.1)
				(type default)
			)
			(layer "B.Fab")
		)
		(fp_line
			(start -0.120396 0.3048)
			(end -0.120396 0.2794)
			(stroke
				(width 0.1)
				(type default)
			)
			(layer "B.Fab")
		)
		(fp_line
			(start -0.120396 0.2794)
			(end 0.12065 0.2794)
			(stroke
				(width 0.1)
				(type default)
			)
			(layer "B.Fab")
		)
		(fp_line
			(start -0.12065 -0.2794)
			(end -0.12065 -0.3048)
			(stroke
				(width 0.1)
				(type default)
			)
			(layer "B.Fab")
		)
		(fp_line
			(start -0.12065 -0.3048)
			(end -0.67945 -0.3048)
			(stroke
				(width 0.1)
				(type default)
			)
			(layer "B.Fab")
		)
		(fp_line
			(start -0.67945 0.3048)
			(end -0.120396 0.3048)
			(stroke
				(width 0.1)
				(type default)
			)
			(layer "B.Fab")
		)
		(fp_line
			(start -0.67945 -0.3048)
			(end -0.67945 0.3048)
			(stroke
				(width 0.1)
				(type default)
			)
			(layer "B.Fab")
		)
		(pad "1" smd circle
			(at 0.40005 0)
			(size 0 0)
			(layers "B.Cu" "B.Mask" "B.Paste")
			(net "P3V3")
		)
		(pad "2" smd circle
			(at -0.40005 0)
			(size 0 0)
			(layers "B.Cu" "B.Mask" "B.Paste")
			(net "PWRGD_CHAF_CPU0")
		)
	)
	(footprint ""
		(layer "B.Cu")
		(at 255.905 -337.37804 180)
		(property "Reference" "R830"
			(at 0 0 0)
			(layer "B.SilkS")
			(hide yes)
			(effects
				(font
					(size 1.27 1.27)
				)
				(justify mirror)
			)
		)
		(property "Value" ""
			(at 0 0 0)
			(layer "B.Fab")
			(effects
				(font
					(size 1.27 1.27)
				)
				(justify mirror)
			)
		)
		(duplicate_pad_numbers_are_jumpers no)
		(fp_line
			(start 0.32512 0.175006)
			(end 0.32512 -0.175006)
			(stroke
				(width 0.1)
				(type default)
			)
			(layer "B.Fab")
		)
		(fp_line
			(start 0.32512 -0.175006)
			(end -0.32512 -0.175006)
			(stroke
				(width 0.1)
				(type default)
			)
			(layer "B.Fab")
		)
		(fp_line
			(start -0.32512 0.175006)
			(end 0.32512 0.175006)
			(stroke
				(width 0.1)
				(type default)
			)
			(layer "B.Fab")
		)
		(fp_line
			(start -0.32512 -0.175006)
			(end -0.32512 0.175006)
			(stroke
				(width 0.1)
				(type default)
			)
			(layer "B.Fab")
		)
		(pad "1" smd rect
			(at 0.2667 0)
			(size 0.3048 0.381)
			(layers "B.Cu" "B.Mask" "B.Paste")
			(net "SMB_RT_CPU0_P3_ROM_MUX_2D_R_SDA")
		)
		(pad "2" smd rect
			(at -0.2667 0 180)
			(size 0.3048 0.381)
			(layers "B.Cu" "B.Mask" "B.Paste")
			(net "SMB_RT_CPU0_P3_ROM_MUX_2D_SDA")
		)
	)
	(footprint ""
		(layer "B.Cu")
		(at 44.14901 -412.853378)
		(property "Reference" "C2074"
			(at 0 0 0)
			(layer "B.SilkS")
			(hide yes)
			(effects
				(font
					(size 1.27 1.27)
				)
				(justify mirror)
			)
		)
		(property "Value" ""
			(at 0 0 0)
			(layer "B.Fab")
			(effects
				(font
					(size 1.27 1.27)
				)
				(justify mirror)
			)
		)
		(duplicate_pad_numbers_are_jumpers no)
		(fp_line
			(start -0.299974 -0.150114)
			(end -0.299974 0.150114)
			(stroke
				(width 0.1)
				(type default)
			)
			(layer "B.Fab")
		)
		(fp_line
			(start -0.299974 0.150114)
			(end 0.299974 0.150114)
			(stroke
				(width 0.1)
				(type default)
			)
			(layer "B.Fab")
		)
		(fp_line
			(start 0.299974 -0.150114)
			(end -0.299974 -0.150114)
			(stroke
				(width 0.1)
				(type default)
			)
			(layer "B.Fab")
		)
		(fp_line
			(start 0.299974 0.150114)
			(end 0.299974 -0.150114)
			(stroke
				(width 0.1)
				(type default)
			)
			(layer "B.Fab")
		)
		(pad "1" smd rect
			(at 0.2667 0 180)
			(size 0.3048 0.381)
			(layers "B.Cu" "B.Mask" "B.Paste")
			(net "P3E_CPU1_P5_TX_C_DN<1>")
		)
		(pad "2" smd rect
			(at -0.2667 0 180)
			(size 0.3048 0.381)
			(layers "B.Cu" "B.Mask" "B.Paste")
			(net "P3E_CPU1_P5_TX_DN<1>")
		)
	)
	(footprint ""
		(layer "B.Cu")
		(at 350.199198 -252.224032 60)
		(property "Reference" "C2567"
			(at 0 0 60)
			(layer "B.SilkS")
			(hide yes)
			(effects
				(font
					(size 1.27 1.27)
				)
				(justify mirror)
			)
		)
		(property "Value" ""
			(at 0 0 60)
			(layer "B.Fab")
			(effects
				(font
					(size 1.27 1.27)
				)
				(justify mirror)
			)
		)
		(duplicate_pad_numbers_are_jumpers no)
		(fp_line
			(start -0.787516 -0.406438)
			(end -0.787425 0.40652)
			(stroke
				(width 0.1524)
				(type default)
			)
			(layer "B.SilkS")
		)
		(fp_line
			(start -0.787425 0.40652)
			(end 0.787516 0.406438)
			(stroke
				(width 0.1524)
				(type default)
			)
			(layer "B.SilkS")
		)
		(fp_line
			(start 0.787425 -0.40652)
			(end -0.787516 -0.406438)
			(stroke
				(width 0.1524)
				(type default)
			)
			(layer "B.SilkS")
		)
		(fp_line
			(start 0.787516 0.406438)
			(end 0.787425 -0.40652)
			(stroke
				(width 0.1524)
				(type default)
			)
			(layer "B.SilkS")
		)
		(fp_line
			(start -0.679568 -0.304811)
			(end -0.6795 0.304908)
			(stroke
				(width 0.1)
				(type default)
			)
			(layer "B.Fab")
		)
		(fp_line
			(start -0.120605 -0.304905)
			(end -0.679568 -0.304811)
			(stroke
				(width 0.1)
				(type default)
			)
			(layer "B.Fab")
		)
		(fp_line
			(start -0.120554 -0.279418)
			(end -0.120605 -0.304905)
			(stroke
				(width 0.1)
				(type default)
			)
			(layer "B.Fab")
		)
		(fp_line
			(start 0.120629 -0.30516)
			(end 0.120587 -0.279326)
			(stroke
				(width 0.1)
				(type default)
			)
			(layer "B.Fab")
		)
		(fp_line
			(start 0.120587 -0.279326)
			(end -0.120554 -0.279418)
			(stroke
				(width 0.1)
				(type default)
			)
			(layer "B.Fab")
		)
		(fp_line
			(start -0.6795 0.304908)
			(end -0.120316 0.304686)
			(stroke
				(width 0.1)
				(type default)
			)
			(layer "B.Fab")
		)
		(fp_line
			(start 0.679373 -0.305128)
			(end 0.120629 -0.30516)
			(stroke
				(width 0.1)
				(type default)
			)
			(layer "B.Fab")
		)
		(fp_line
			(start -0.12024 0.279419)
			(end 0.120554 0.279418)
			(stroke
				(width 0.1)
				(type default)
			)
			(layer "B.Fab")
		)
		(fp_line
			(start -0.120316 0.304686)
			(end -0.12024 0.279419)
			(stroke
				(width 0.1)
				(type default)
			)
			(layer "B.Fab")
		)
		(fp_line
			(start 0.120554 0.279418)
			(end 0.120605 0.304905)
			(stroke
				(width 0.1)
				(type default)
			)
			(layer "B.Fab")
		)
		(fp_line
			(start 0.120605 0.304905)
			(end 0.679568 0.304811)
			(stroke
				(width 0.1)
				(type default)
			)
			(layer "B.Fab")
		)
		(fp_line
			(start 0.679568 0.304811)
			(end 0.679373 -0.305128)
			(stroke
				(width 0.1)
				(type default)
			)
			(layer "B.Fab")
		)
		(pad "1" smd circle
			(at 0.40005 0 240)
			(size 0 0)
			(layers "B.Cu" "B.Mask" "B.Paste")
			(net "PVDDCR_SOC_P0")
		)
		(pad "2" smd circle
			(at -0.40005 0 240)
			(size 0 0)
			(layers "B.Cu" "B.Mask" "B.Paste")
			(net "GND")
		)
	)
	(footprint ""
		(layer "B.Cu")
		(at 405.809196 -354.439728 -90)
		(property "Reference" "R6125"
			(at 0 0 90)
			(layer "B.SilkS")
			(hide yes)
			(effects
				(font
					(size 1.27 1.27)
				)
				(justify mirror)
			)
		)
		(property "Value" ""
			(at 0 0 90)
			(layer "B.Fab")
			(effects
				(font
					(size 1.27 1.27)
				)
				(justify mirror)
			)
		)
		(duplicate_pad_numbers_are_jumpers no)
		(fp_line
			(start -0.7874 0.4064)
			(end 0.7874 0.4064)
			(stroke
				(width 0.1524)
				(type default)
			)
			(layer "B.SilkS")
		)
		(fp_line
			(start 0.7874 0.4064)
			(end 0.7874 -0.4064)
			(stroke
				(width 0.1524)
				(type default)
			)
			(layer "B.SilkS")
		)
		(fp_line
			(start -0.7874 -0.4064)
			(end -0.7874 0.4064)
			(stroke
				(width 0.1524)
				(type default)
			)
			(layer "B.SilkS")
		)
		(fp_line
			(start 0.7874 -0.4064)
			(end -0.7874 -0.4064)
			(stroke
				(width 0.1524)
				(type default)
			)
			(layer "B.SilkS")
		)
		(fp_line
			(start -0.67945 0.3048)
			(end -0.120396 0.3048)
			(stroke
				(width 0.1)
				(type default)
			)
			(layer "B.Fab")
		)
		(fp_line
			(start -0.120396 0.3048)
			(end -0.120396 0.2794)
			(stroke
				(width 0.1)
				(type default)
			)
			(layer "B.Fab")
		)
		(fp_line
			(start 0.12065 0.3048)
			(end 0.67945 0.3048)
			(stroke
				(width 0.1)
				(type default)
			)
			(layer "B.Fab")
		)
		(fp_line
			(start 0.67945 0.3048)
			(end 0.67945 -0.305054)
			(stroke
				(width 0.1)
				(type default)
			)
			(layer "B.Fab")
		)
		(fp_line
			(start -0.120396 0.2794)
			(end 0.12065 0.2794)
			(stroke
				(width 0.1)
				(type default)
			)
			(layer "B.Fab")
		)
		(fp_line
			(start 0.12065 0.2794)
			(end 0.12065 0.3048)
			(stroke
				(width 0.1)
				(type default)
			)
			(layer "B.Fab")
		)
		(fp_line
			(start -0.12065 -0.2794)
			(end -0.12065 -0.3048)
			(stroke
				(width 0.1)
				(type default)
			)
			(layer "B.Fab")
		)
		(fp_line
			(start 0.12065 -0.2794)
			(end -0.12065 -0.2794)
			(stroke
				(width 0.1)
				(type default)
			)
			(layer "B.Fab")
		)
		(fp_line
			(start -0.67945 -0.3048)
			(end -0.67945 0.3048)
			(stroke
				(width 0.1)
				(type default)
			)
			(layer "B.Fab")
		)
		(fp_line
			(start -0.12065 -0.3048)
			(end -0.67945 -0.3048)
			(stroke
				(width 0.1)
				(type default)
			)
			(layer "B.Fab")
		)
		(fp_line
			(start 0.12065 -0.305054)
			(end 0.12065 -0.2794)
			(stroke
				(width 0.1)
				(type default)
			)
			(layer "B.Fab")
		)
		(fp_line
			(start 0.67945 -0.305054)
			(end 0.12065 -0.305054)
			(stroke
				(width 0.1)
				(type default)
			)
			(layer "B.Fab")
		)
		(pad "1" smd circle
			(at 0.40005 0 90)
			(size 0 0)
			(layers "B.Cu" "B.Mask" "B.Paste")
			(net "FM_BOARD_SKU_ID4")
		)
		(pad "2" smd circle
			(at -0.40005 0 90)
			(size 0 0)
			(layers "B.Cu" "B.Mask" "B.Paste")
			(net "GND")
		)
	)
	(footprint ""
		(layer "B.Cu")
		(at 363.645958 -258.795012 180)
		(property "Reference" "C2558"
			(at 0 0 0)
			(layer "B.SilkS")
			(hide yes)
			(effects
				(font
					(size 1.27 1.27)
				)
				(justify mirror)
			)
		)
		(property "Value" ""
			(at 0 0 0)
			(layer "B.Fab")
			(effects
				(font
					(size 1.27 1.27)
				)
				(justify mirror)
			)
		)
		(duplicate_pad_numbers_are_jumpers no)
		(fp_line
			(start 0.7874 0.4064)
			(end 0.7874 -0.4064)
			(stroke
				(width 0.1524)
				(type default)
			)
			(layer "B.SilkS")
		)
		(fp_line
			(start 0.7874 -0.4064)
			(end -0.7874 -0.4064)
			(stroke
				(width 0.1524)
				(type default)
			)
			(layer "B.SilkS")
		)
		(fp_line
			(start -0.7874 0.4064)
			(end 0.7874 0.4064)
			(stroke
				(width 0.1524)
				(type default)
			)
			(layer "B.SilkS")
		)
		(fp_line
			(start -0.7874 -0.4064)
			(end -0.7874 0.4064)
			(stroke
				(width 0.1524)
				(type default)
			)
			(layer "B.SilkS")
		)
		(fp_line
			(start 0.67945 0.3048)
			(end 0.67945 -0.305054)
			(stroke
				(width 0.1)
				(type default)
			)
			(layer "B.Fab")
		)
		(fp_line
			(start 0.67945 -0.305054)
			(end 0.12065 -0.305054)
			(stroke
				(width 0.1)
				(type default)
			)
			(layer "B.Fab")
		)
		(fp_line
			(start 0.12065 0.3048)
			(end 0.67945 0.3048)
			(stroke
				(width 0.1)
				(type default)
			)
			(layer "B.Fab")
		)
		(fp_line
			(start 0.12065 0.2794)
			(end 0.12065 0.3048)
			(stroke
				(width 0.1)
				(type default)
			)
			(layer "B.Fab")
		)
		(fp_line
			(start 0.12065 -0.2794)
			(end -0.12065 -0.2794)
			(stroke
				(width 0.1)
				(type default)
			)
			(layer "B.Fab")
		)
		(fp_line
			(start 0.12065 -0.305054)
			(end 0.12065 -0.2794)
			(stroke
				(width 0.1)
				(type default)
			)
			(layer "B.Fab")
		)
		(fp_line
			(start -0.120396 0.3048)
			(end -0.120396 0.2794)
			(stroke
				(width 0.1)
				(type default)
			)
			(layer "B.Fab")
		)
		(fp_line
			(start -0.120396 0.2794)
			(end 0.12065 0.2794)
			(stroke
				(width 0.1)
				(type default)
			)
			(layer "B.Fab")
		)
		(fp_line
			(start -0.12065 -0.2794)
			(end -0.12065 -0.3048)
			(stroke
				(width 0.1)
				(type default)
			)
			(layer "B.Fab")
		)
		(fp_line
			(start -0.12065 -0.3048)
			(end -0.67945 -0.3048)
			(stroke
				(width 0.1)
				(type default)
			)
			(layer "B.Fab")
		)
		(fp_line
			(start -0.67945 0.3048)
			(end -0.120396 0.3048)
			(stroke
				(width 0.1)
				(type default)
			)
			(layer "B.Fab")
		)
		(fp_line
			(start -0.67945 -0.3048)
			(end -0.67945 0.3048)
			(stroke
				(width 0.1)
				(type default)
			)
			(layer "B.Fab")
		)
		(pad "1" smd circle
			(at 0.40005 0)
			(size 0 0)
			(layers "B.Cu" "B.Mask" "B.Paste")
			(net "PVDDCR_SOC_P0")
		)
		(pad "2" smd circle
			(at -0.40005 0)
			(size 0 0)
			(layers "B.Cu" "B.Mask" "B.Paste")
			(net "GND")
		)
	)
	(footprint ""
		(layer "B.Cu")
		(at 171.214288 -107.188 180)
		(property "Reference" "R234"
			(at 0 0 0)
			(layer "B.SilkS")
			(hide yes)
			(effects
				(font
					(size 1.27 1.27)
				)
				(justify mirror)
			)
		)
		(property "Value" ""
			(at 0 0 0)
			(layer "B.Fab")
			(effects
				(font
					(size 1.27 1.27)
				)
				(justify mirror)
			)
		)
		(duplicate_pad_numbers_are_jumpers no)
		(fp_line
			(start 0.7874 0.4064)
			(end 0.7874 -0.4064)
			(stroke
				(width 0.1524)
				(type default)
			)
			(layer "B.SilkS")
		)
		(fp_line
			(start 0.7874 -0.4064)
			(end -0.7874 -0.4064)
			(stroke
				(width 0.1524)
				(type default)
			)
			(layer "B.SilkS")
		)
		(fp_line
			(start -0.7874 0.4064)
			(end 0.7874 0.4064)
			(stroke
				(width 0.1524)
				(type default)
			)
			(layer "B.SilkS")
		)
		(fp_line
			(start -0.7874 -0.4064)
			(end -0.7874 0.4064)
			(stroke
				(width 0.1524)
				(type default)
			)
			(layer "B.SilkS")
		)
		(fp_line
			(start 0.67945 0.3048)
			(end 0.67945 -0.305054)
			(stroke
				(width 0.1)
				(type default)
			)
			(layer "B.Fab")
		)
		(fp_line
			(start 0.67945 -0.305054)
			(end 0.12065 -0.305054)
			(stroke
				(width 0.1)
				(type default)
			)
			(layer "B.Fab")
		)
		(fp_line
			(start 0.12065 0.3048)
			(end 0.67945 0.3048)
			(stroke
				(width 0.1)
				(type default)
			)
			(layer "B.Fab")
		)
		(fp_line
			(start 0.12065 0.2794)
			(end 0.12065 0.3048)
			(stroke
				(width 0.1)
				(type default)
			)
			(layer "B.Fab")
		)
		(fp_line
			(start 0.12065 -0.2794)
			(end -0.12065 -0.2794)
			(stroke
				(width 0.1)
				(type default)
			)
			(layer "B.Fab")
		)
		(fp_line
			(start 0.12065 -0.305054)
			(end 0.12065 -0.2794)
			(stroke
				(width 0.1)
				(type default)
			)
			(layer "B.Fab")
		)
		(fp_line
			(start -0.120396 0.3048)
			(end -0.120396 0.2794)
			(stroke
				(width 0.1)
				(type default)
			)
			(layer "B.Fab")
		)
		(fp_line
			(start -0.120396 0.2794)
			(end 0.12065 0.2794)
			(stroke
				(width 0.1)
				(type default)
			)
			(layer "B.Fab")
		)
		(fp_line
			(start -0.12065 -0.2794)
			(end -0.12065 -0.3048)
			(stroke
				(width 0.1)
				(type default)
			)
			(layer "B.Fab")
		)
		(fp_line
			(start -0.12065 -0.3048)
			(end -0.67945 -0.3048)
			(stroke
				(width 0.1)
				(type default)
			)
			(layer "B.Fab")
		)
		(fp_line
			(start -0.67945 0.3048)
			(end -0.120396 0.3048)
			(stroke
				(width 0.1)
				(type default)
			)
			(layer "B.Fab")
		)
		(fp_line
			(start -0.67945 -0.3048)
			(end -0.67945 0.3048)
			(stroke
				(width 0.1)
				(type default)
			)
			(layer "B.Fab")
		)
		(pad "1" smd circle
			(at 0.40005 0)
			(size 0 0)
			(layers "B.Cu" "B.Mask" "B.Paste")
			(net "CPU1_XTRIG_L6")
		)
		(pad "2" smd circle
			(at -0.40005 0)
			(size 0 0)
			(layers "B.Cu" "B.Mask" "B.Paste")
			(net "FM_CPU1_XTRIG_L6")
		)
	)
	(footprint ""
		(layer "B.Cu")
		(at 203.073 -75.053952)
		(property "Reference" "R3210"
			(at 0 0 0)
			(layer "B.SilkS")
			(hide yes)
			(effects
				(font
					(size 1.27 1.27)
				)
				(justify mirror)
			)
		)
		(property "Value" ""
			(at 0 0 0)
			(layer "B.Fab")
			(effects
				(font
					(size 1.27 1.27)
				)
				(justify mirror)
			)
		)
		(duplicate_pad_numbers_are_jumpers no)
		(fp_line
			(start -0.7874 -0.4064)
			(end -0.7874 0.4064)
			(stroke
				(width 0.1524)
				(type default)
			)
			(layer "B.SilkS")
		)
		(fp_line
			(start -0.7874 0.4064)
			(end 0.7874 0.4064)
			(stroke
				(width 0.1524)
				(type default)
			)
			(layer "B.SilkS")
		)
		(fp_line
			(start 0.7874 -0.4064)
			(end -0.7874 -0.4064)
			(stroke
				(width 0.1524)
				(type default)
			)
			(layer "B.SilkS")
		)
		(fp_line
			(start 0.7874 0.4064)
			(end 0.7874 -0.4064)
			(stroke
				(width 0.1524)
				(type default)
			)
			(layer "B.SilkS")
		)
		(fp_line
			(start -0.67945 -0.3048)
			(end -0.67945 0.3048)
			(stroke
				(width 0.1)
				(type default)
			)
			(layer "B.Fab")
		)
		(fp_line
			(start -0.67945 0.3048)
			(end -0.120396 0.3048)
			(stroke
				(width 0.1)
				(type default)
			)
			(layer "B.Fab")
		)
		(fp_line
			(start -0.12065 -0.3048)
			(end -0.67945 -0.3048)
			(stroke
				(width 0.1)
				(type default)
			)
			(layer "B.Fab")
		)
		(fp_line
			(start -0.12065 -0.2794)
			(end -0.12065 -0.3048)
			(stroke
				(width 0.1)
				(type default)
			)
			(layer "B.Fab")
		)
		(fp_line
			(start -0.120396 0.2794)
			(end 0.12065 0.2794)
			(stroke
				(width 0.1)
				(type default)
			)
			(layer "B.Fab")
		)
		(fp_line
			(start -0.120396 0.3048)
			(end -0.120396 0.2794)
			(stroke
				(width 0.1)
				(type default)
			)
			(layer "B.Fab")
		)
		(fp_line
			(start 0.12065 -0.305054)
			(end 0.12065 -0.2794)
			(stroke
				(width 0.1)
				(type default)
			)
			(layer "B.Fab")
		)
		(fp_line
			(start 0.12065 -0.2794)
			(end -0.12065 -0.2794)
			(stroke
				(width 0.1)
				(type default)
			)
			(layer "B.Fab")
		)
		(fp_line
			(start 0.12065 0.2794)
			(end 0.12065 0.3048)
			(stroke
				(width 0.1)
				(type default)
			)
			(layer "B.Fab")
		)
		(fp_line
			(start 0.12065 0.3048)
			(end 0.67945 0.3048)
			(stroke
				(width 0.1)
				(type default)
			)
			(layer "B.Fab")
		)
		(fp_line
			(start 0.67945 -0.305054)
			(end 0.12065 -0.305054)
			(stroke
				(width 0.1)
				(type default)
			)
			(layer "B.Fab")
		)
		(fp_line
			(start 0.67945 0.3048)
			(end 0.67945 -0.305054)
			(stroke
				(width 0.1)
				(type default)
			)
			(layer "B.Fab")
		)
		(pad "1" smd circle
			(at 0.40005 0 180)
			(size 0 0)
			(layers "B.Cu" "B.Mask" "B.Paste")
			(net "NCSI_BMC_CRS_DV_R1")
		)
		(pad "2" smd circle
			(at -0.40005 0 180)
			(size 0 0)
			(layers "B.Cu" "B.Mask" "B.Paste")
			(net "RMII_OCP_BMC_CRSDV")
		)
	)
	(footprint ""
		(layer "B.Cu")
		(at 316.507876 -66.708782 90)
		(property "Reference" "R3100"
			(at 0 0 90)
			(layer "B.SilkS")
			(hide yes)
			(effects
				(font
					(size 1.27 1.27)
				)
				(justify mirror)
			)
		)
		(property "Value" ""
			(at 0 0 90)
			(layer "B.Fab")
			(effects
				(font
					(size 1.27 1.27)
				)
				(justify mirror)
			)
		)
		(duplicate_pad_numbers_are_jumpers no)
		(fp_line
			(start 0.7874 -0.4064)
			(end -0.7874 -0.4064)
			(stroke
				(width 0.1524)
				(type default)
			)
			(layer "B.SilkS")
		)
		(fp_line
			(start -0.7874 -0.4064)
			(end -0.7874 0.4064)
			(stroke
				(width 0.1524)
				(type default)
			)
			(layer "B.SilkS")
		)
		(fp_line
			(start 0.7874 0.4064)
			(end 0.7874 -0.4064)
			(stroke
				(width 0.1524)
				(type default)
			)
			(layer "B.SilkS")
		)
		(fp_line
			(start -0.7874 0.4064)
			(end 0.7874 0.4064)
			(stroke
				(width 0.1524)
				(type default)
			)
			(layer "B.SilkS")
		)
		(fp_line
			(start 0.67945 -0.305054)
			(end 0.12065 -0.305054)
			(stroke
				(width 0.1)
				(type default)
			)
			(layer "B.Fab")
		)
		(fp_line
			(start 0.12065 -0.305054)
			(end 0.12065 -0.2794)
			(stroke
				(width 0.1)
				(type default)
			)
			(layer "B.Fab")
		)
		(fp_line
			(start -0.12065 -0.3048)
			(end -0.67945 -0.3048)
			(stroke
				(width 0.1)
				(type default)
			)
			(layer "B.Fab")
		)
		(fp_line
			(start -0.67945 -0.3048)
			(end -0.67945 0.3048)
			(stroke
				(width 0.1)
				(type default)
			)
			(layer "B.Fab")
		)
		(fp_line
			(start 0.12065 -0.2794)
			(end -0.12065 -0.2794)
			(stroke
				(width 0.1)
				(type default)
			)
			(layer "B.Fab")
		)
		(fp_line
			(start -0.12065 -0.2794)
			(end -0.12065 -0.3048)
			(stroke
				(width 0.1)
				(type default)
			)
			(layer "B.Fab")
		)
		(fp_line
			(start 0.12065 0.2794)
			(end 0.12065 0.3048)
			(stroke
				(width 0.1)
				(type default)
			)
			(layer "B.Fab")
		)
		(fp_line
			(start -0.120396 0.2794)
			(end 0.12065 0.2794)
			(stroke
				(width 0.1)
				(type default)
			)
			(layer "B.Fab")
		)
		(fp_line
			(start 0.67945 0.3048)
			(end 0.67945 -0.305054)
			(stroke
				(width 0.1)
				(type default)
			)
			(layer "B.Fab")
		)
		(fp_line
			(start 0.12065 0.3048)
			(end 0.67945 0.3048)
			(stroke
				(width 0.1)
				(type default)
			)
			(layer "B.Fab")
		)
		(fp_line
			(start -0.120396 0.3048)
			(end -0.120396 0.2794)
			(stroke
				(width 0.1)
				(type default)
			)
			(layer "B.Fab")
		)
		(fp_line
			(start -0.67945 0.3048)
			(end -0.120396 0.3048)
			(stroke
				(width 0.1)
				(type default)
			)
			(layer "B.Fab")
		)
		(pad "1" smd circle
			(at 0.40005 0 270)
			(size 0 0)
			(layers "B.Cu" "B.Mask" "B.Paste")
			(net "LED_P3V3")
		)
		(pad "2" smd circle
			(at -0.40005 0 270)
			(size 0 0)
			(layers "B.Cu" "B.Mask" "B.Paste")
			(net "P3V3")
		)
	)
	(footprint ""
		(layer "B.Cu")
		(at 321.100958 -203.917296 -90)
		(property "Reference" "R387"
			(at 0 0 90)
			(layer "B.SilkS")
			(hide yes)
			(effects
				(font
					(size 1.27 1.27)
				)
				(justify mirror)
			)
		)
		(property "Value" ""
			(at 0 0 90)
			(layer "B.Fab")
			(effects
				(font
					(size 1.27 1.27)
				)
				(justify mirror)
			)
		)
		(duplicate_pad_numbers_are_jumpers no)
		(fp_line
			(start -0.7874 0.4064)
			(end 0.7874 0.4064)
			(stroke
				(width 0.1524)
				(type default)
			)
			(layer "B.SilkS")
		)
		(fp_line
			(start 0.7874 0.4064)
			(end 0.7874 -0.4064)
			(stroke
				(width 0.1524)
				(type default)
			)
			(layer "B.SilkS")
		)
		(fp_line
			(start -0.7874 -0.4064)
			(end -0.7874 0.4064)
			(stroke
				(width 0.1524)
				(type default)
			)
			(layer "B.SilkS")
		)
		(fp_line
			(start 0.7874 -0.4064)
			(end -0.7874 -0.4064)
			(stroke
				(width 0.1524)
				(type default)
			)
			(layer "B.SilkS")
		)
		(fp_line
			(start -0.67945 0.3048)
			(end -0.120396 0.3048)
			(stroke
				(width 0.1)
				(type default)
			)
			(layer "B.Fab")
		)
		(fp_line
			(start -0.120396 0.3048)
			(end -0.120396 0.2794)
			(stroke
				(width 0.1)
				(type default)
			)
			(layer "B.Fab")
		)
		(fp_line
			(start 0.12065 0.3048)
			(end 0.67945 0.3048)
			(stroke
				(width 0.1)
				(type default)
			)
			(layer "B.Fab")
		)
		(fp_line
			(start 0.67945 0.3048)
			(end 0.67945 -0.305054)
			(stroke
				(width 0.1)
				(type default)
			)
			(layer "B.Fab")
		)
		(fp_line
			(start -0.120396 0.2794)
			(end 0.12065 0.2794)
			(stroke
				(width 0.1)
				(type default)
			)
			(layer "B.Fab")
		)
		(fp_line
			(start 0.12065 0.2794)
			(end 0.12065 0.3048)
			(stroke
				(width 0.1)
				(type default)
			)
			(layer "B.Fab")
		)
		(fp_line
			(start -0.12065 -0.2794)
			(end -0.12065 -0.3048)
			(stroke
				(width 0.1)
				(type default)
			)
			(layer "B.Fab")
		)
		(fp_line
			(start 0.12065 -0.2794)
			(end -0.12065 -0.2794)
			(stroke
				(width 0.1)
				(type default)
			)
			(layer "B.Fab")
		)
		(fp_line
			(start -0.67945 -0.3048)
			(end -0.67945 0.3048)
			(stroke
				(width 0.1)
				(type default)
			)
			(layer "B.Fab")
		)
		(fp_line
			(start -0.12065 -0.3048)
			(end -0.67945 -0.3048)
			(stroke
				(width 0.1)
				(type default)
			)
			(layer "B.Fab")
		)
		(fp_line
			(start 0.12065 -0.305054)
			(end 0.12065 -0.2794)
			(stroke
				(width 0.1)
				(type default)
			)
			(layer "B.Fab")
		)
		(fp_line
			(start 0.67945 -0.305054)
			(end 0.12065 -0.305054)
			(stroke
				(width 0.1)
				(type default)
			)
			(layer "B.Fab")
		)
		(pad "1" smd circle
			(at 0.40005 0 90)
			(size 0 0)
			(layers "B.Cu" "B.Mask" "B.Paste")
			(net "P3V3_AUX")
		)
		(pad "2" smd circle
			(at -0.40005 0 90)
			(size 0 0)
			(layers "B.Cu" "B.Mask" "B.Paste")
			(net "CPU0_CORETYPE2")
		)
	)
	(footprint ""
		(layer "B.Cu")
		(at 100.271834 -261.947152)
		(property "Reference" "C2106"
			(at 0 0 0)
			(layer "B.SilkS")
			(hide yes)
			(effects
				(font
					(size 1.27 1.27)
				)
				(justify mirror)
			)
		)
		(property "Value" ""
			(at 0 0 0)
			(layer "B.Fab")
			(effects
				(font
					(size 1.27 1.27)
				)
				(justify mirror)
			)
		)
		(duplicate_pad_numbers_are_jumpers no)
		(fp_line
			(start -0.7874 -0.4064)
			(end -0.7874 0.4064)
			(stroke
				(width 0.1524)
				(type default)
			)
			(layer "B.SilkS")
		)
		(fp_line
			(start -0.7874 0.4064)
			(end 0.7874 0.4064)
			(stroke
				(width 0.1524)
				(type default)
			)
			(layer "B.SilkS")
		)
		(fp_line
			(start 0.7874 -0.4064)
			(end -0.7874 -0.4064)
			(stroke
				(width 0.1524)
				(type default)
			)
			(layer "B.SilkS")
		)
		(fp_line
			(start 0.7874 0.4064)
			(end 0.7874 -0.4064)
			(stroke
				(width 0.1524)
				(type default)
			)
			(layer "B.SilkS")
		)
		(fp_line
			(start -0.67945 -0.3048)
			(end -0.67945 0.3048)
			(stroke
				(width 0.1)
				(type default)
			)
			(layer "B.Fab")
		)
		(fp_line
			(start -0.67945 0.3048)
			(end -0.120396 0.3048)
			(stroke
				(width 0.1)
				(type default)
			)
			(layer "B.Fab")
		)
		(fp_line
			(start -0.12065 -0.3048)
			(end -0.67945 -0.3048)
			(stroke
				(width 0.1)
				(type default)
			)
			(layer "B.Fab")
		)
		(fp_line
			(start -0.12065 -0.2794)
			(end -0.12065 -0.3048)
			(stroke
				(width 0.1)
				(type default)
			)
			(layer "B.Fab")
		)
		(fp_line
			(start -0.120396 0.2794)
			(end 0.12065 0.2794)
			(stroke
				(width 0.1)
				(type default)
			)
			(layer "B.Fab")
		)
		(fp_line
			(start -0.120396 0.3048)
			(end -0.120396 0.2794)
			(stroke
				(width 0.1)
				(type default)
			)
			(layer "B.Fab")
		)
		(fp_line
			(start 0.12065 -0.305054)
			(end 0.12065 -0.2794)
			(stroke
				(width 0.1)
				(type default)
			)
			(layer "B.Fab")
		)
		(fp_line
			(start 0.12065 -0.2794)
			(end -0.12065 -0.2794)
			(stroke
				(width 0.1)
				(type default)
			)
			(layer "B.Fab")
		)
		(fp_line
			(start 0.12065 0.2794)
			(end 0.12065 0.3048)
			(stroke
				(width 0.1)
				(type default)
			)
			(layer "B.Fab")
		)
		(fp_line
			(start 0.12065 0.3048)
			(end 0.67945 0.3048)
			(stroke
				(width 0.1)
				(type default)
			)
			(layer "B.Fab")
		)
		(fp_line
			(start 0.67945 -0.305054)
			(end 0.12065 -0.305054)
			(stroke
				(width 0.1)
				(type default)
			)
			(layer "B.Fab")
		)
		(fp_line
			(start 0.67945 0.3048)
			(end 0.67945 -0.305054)
			(stroke
				(width 0.1)
				(type default)
			)
			(layer "B.Fab")
		)
		(pad "1" smd circle
			(at 0.40005 0 180)
			(size 0 0)
			(layers "B.Cu" "B.Mask" "B.Paste")
			(net "PVDDIO_P1")
		)
		(pad "2" smd circle
			(at -0.40005 0 180)
			(size 0 0)
			(layers "B.Cu" "B.Mask" "B.Paste")
			(net "GND")
		)
	)
	(footprint ""
		(layer "B.Cu")
		(at 237.692692 -422.849548 90)
		(property "Reference" "R2906"
			(at 0 0 90)
			(layer "B.SilkS")
			(hide yes)
			(effects
				(font
					(size 1.27 1.27)
				)
				(justify mirror)
			)
		)
		(property "Value" ""
			(at 0 0 90)
			(layer "B.Fab")
			(effects
				(font
					(size 1.27 1.27)
				)
				(justify mirror)
			)
		)
		(duplicate_pad_numbers_are_jumpers no)
		(fp_line
			(start 0.7874 -0.4064)
			(end -0.7874 -0.4064)
			(stroke
				(width 0.1524)
				(type default)
			)
			(layer "B.SilkS")
		)
		(fp_line
			(start -0.7874 -0.4064)
			(end -0.7874 0.4064)
			(stroke
				(width 0.1524)
				(type default)
			)
			(layer "B.SilkS")
		)
		(fp_line
			(start 0.7874 0.4064)
			(end 0.7874 -0.4064)
			(stroke
				(width 0.1524)
				(type default)
			)
			(layer "B.SilkS")
		)
		(fp_line
			(start -0.7874 0.4064)
			(end 0.7874 0.4064)
			(stroke
				(width 0.1524)
				(type default)
			)
			(layer "B.SilkS")
		)
		(fp_line
			(start 0.67945 -0.305054)
			(end 0.12065 -0.305054)
			(stroke
				(width 0.1)
				(type default)
			)
			(layer "B.Fab")
		)
		(fp_line
			(start 0.12065 -0.305054)
			(end 0.12065 -0.2794)
			(stroke
				(width 0.1)
				(type default)
			)
			(layer "B.Fab")
		)
		(fp_line
			(start -0.12065 -0.3048)
			(end -0.67945 -0.3048)
			(stroke
				(width 0.1)
				(type default)
			)
			(layer "B.Fab")
		)
		(fp_line
			(start -0.67945 -0.3048)
			(end -0.67945 0.3048)
			(stroke
				(width 0.1)
				(type default)
			)
			(layer "B.Fab")
		)
		(fp_line
			(start 0.12065 -0.2794)
			(end -0.12065 -0.2794)
			(stroke
				(width 0.1)
				(type default)
			)
			(layer "B.Fab")
		)
		(fp_line
			(start -0.12065 -0.2794)
			(end -0.12065 -0.3048)
			(stroke
				(width 0.1)
				(type default)
			)
			(layer "B.Fab")
		)
		(fp_line
			(start 0.12065 0.2794)
			(end 0.12065 0.3048)
			(stroke
				(width 0.1)
				(type default)
			)
			(layer "B.Fab")
		)
		(fp_line
			(start -0.120396 0.2794)
			(end 0.12065 0.2794)
			(stroke
				(width 0.1)
				(type default)
			)
			(layer "B.Fab")
		)
		(fp_line
			(start 0.67945 0.3048)
			(end 0.67945 -0.305054)
			(stroke
				(width 0.1)
				(type default)
			)
			(layer "B.Fab")
		)
		(fp_line
			(start 0.12065 0.3048)
			(end 0.67945 0.3048)
			(stroke
				(width 0.1)
				(type default)
			)
			(layer "B.Fab")
		)
		(fp_line
			(start -0.120396 0.3048)
			(end -0.120396 0.2794)
			(stroke
				(width 0.1)
				(type default)
			)
			(layer "B.Fab")
		)
		(fp_line
			(start -0.67945 0.3048)
			(end -0.120396 0.3048)
			(stroke
				(width 0.1)
				(type default)
			)
			(layer "B.Fab")
		)
		(pad "1" smd circle
			(at 0.40005 0 270)
			(size 0 0)
			(layers "B.Cu" "B.Mask" "B.Paste")
			(net "FM_GPU_HSC_EN_BUF_R1")
		)
		(pad "2" smd circle
			(at -0.40005 0 270)
			(size 0 0)
			(layers "B.Cu" "B.Mask" "B.Paste")
			(net "FM_GPU_HSC_EN_BUF")
		)
	)
	(footprint ""
		(layer "B.Cu")
		(at 22.479 -358.775 180)
		(property "Reference" "R8220"
			(at 0 0 0)
			(layer "B.SilkS")
			(hide yes)
			(effects
				(font
					(size 1.27 1.27)
				)
				(justify mirror)
			)
		)
		(property "Value" ""
			(at 0 0 0)
			(layer "B.Fab")
			(effects
				(font
					(size 1.27 1.27)
				)
				(justify mirror)
			)
		)
		(duplicate_pad_numbers_are_jumpers no)
		(fp_line
			(start 0.7874 0.4064)
			(end 0.7874 -0.4064)
			(stroke
				(width 0.1524)
				(type default)
			)
			(layer "B.SilkS")
		)
		(fp_line
			(start 0.7874 -0.4064)
			(end -0.7874 -0.4064)
			(stroke
				(width 0.1524)
				(type default)
			)
			(layer "B.SilkS")
		)
		(fp_line
			(start -0.7874 0.4064)
			(end 0.7874 0.4064)
			(stroke
				(width 0.1524)
				(type default)
			)
			(layer "B.SilkS")
		)
		(fp_line
			(start -0.7874 -0.4064)
			(end -0.7874 0.4064)
			(stroke
				(width 0.1524)
				(type default)
			)
			(layer "B.SilkS")
		)
		(fp_line
			(start 0.67945 0.3048)
			(end 0.67945 -0.305054)
			(stroke
				(width 0.1)
				(type default)
			)
			(layer "B.Fab")
		)
		(fp_line
			(start 0.67945 -0.305054)
			(end 0.12065 -0.305054)
			(stroke
				(width 0.1)
				(type default)
			)
			(layer "B.Fab")
		)
		(fp_line
			(start 0.12065 0.3048)
			(end 0.67945 0.3048)
			(stroke
				(width 0.1)
				(type default)
			)
			(layer "B.Fab")
		)
		(fp_line
			(start 0.12065 0.2794)
			(end 0.12065 0.3048)
			(stroke
				(width 0.1)
				(type default)
			)
			(layer "B.Fab")
		)
		(fp_line
			(start 0.12065 -0.2794)
			(end -0.12065 -0.2794)
			(stroke
				(width 0.1)
				(type default)
			)
			(layer "B.Fab")
		)
		(fp_line
			(start 0.12065 -0.305054)
			(end 0.12065 -0.2794)
			(stroke
				(width 0.1)
				(type default)
			)
			(layer "B.Fab")
		)
		(fp_line
			(start -0.120396 0.3048)
			(end -0.120396 0.2794)
			(stroke
				(width 0.1)
				(type default)
			)
			(layer "B.Fab")
		)
		(fp_line
			(start -0.120396 0.2794)
			(end 0.12065 0.2794)
			(stroke
				(width 0.1)
				(type default)
			)
			(layer "B.Fab")
		)
		(fp_line
			(start -0.12065 -0.2794)
			(end -0.12065 -0.3048)
			(stroke
				(width 0.1)
				(type default)
			)
			(layer "B.Fab")
		)
		(fp_line
			(start -0.12065 -0.3048)
			(end -0.67945 -0.3048)
			(stroke
				(width 0.1)
				(type default)
			)
			(layer "B.Fab")
		)
		(fp_line
			(start -0.67945 0.3048)
			(end -0.120396 0.3048)
			(stroke
				(width 0.1)
				(type default)
			)
			(layer "B.Fab")
		)
		(fp_line
			(start -0.67945 -0.3048)
			(end -0.67945 0.3048)
			(stroke
				(width 0.1)
				(type default)
			)
			(layer "B.Fab")
		)
		(pad "1" smd circle
			(at 0.40005 0)
			(size 0 0)
			(layers "B.Cu" "B.Mask" "B.Paste")
			(net "PVDD18_S5_P1")
		)
		(pad "2" smd circle
			(at -0.40005 0)
			(size 0 0)
			(layers "B.Cu" "B.Mask" "B.Paste")
			(net "SVID_PVDDCR_CPU1_P1_SVTO")
		)
	)
	(footprint ""
		(layer "B.Cu")
		(at 63.194438 -28.382722)
		(property "Reference" "R1196"
			(at 0 0 0)
			(layer "B.SilkS")
			(hide yes)
			(effects
				(font
					(size 1.27 1.27)
				)
				(justify mirror)
			)
		)
		(property "Value" ""
			(at 0 0 0)
			(layer "B.Fab")
			(effects
				(font
					(size 1.27 1.27)
				)
				(justify mirror)
			)
		)
		(duplicate_pad_numbers_are_jumpers no)
		(fp_line
			(start -0.7874 -0.4064)
			(end -0.7874 0.4064)
			(stroke
				(width 0.1524)
				(type default)
			)
			(layer "B.SilkS")
		)
		(fp_line
			(start -0.7874 0.4064)
			(end 0.7874 0.4064)
			(stroke
				(width 0.1524)
				(type default)
			)
			(layer "B.SilkS")
		)
		(fp_line
			(start 0.7874 -0.4064)
			(end -0.7874 -0.4064)
			(stroke
				(width 0.1524)
				(type default)
			)
			(layer "B.SilkS")
		)
		(fp_line
			(start 0.7874 0.4064)
			(end 0.7874 -0.4064)
			(stroke
				(width 0.1524)
				(type default)
			)
			(layer "B.SilkS")
		)
		(fp_line
			(start -0.67945 -0.3048)
			(end -0.67945 0.3048)
			(stroke
				(width 0.1)
				(type default)
			)
			(layer "B.Fab")
		)
		(fp_line
			(start -0.67945 0.3048)
			(end -0.120396 0.3048)
			(stroke
				(width 0.1)
				(type default)
			)
			(layer "B.Fab")
		)
		(fp_line
			(start -0.12065 -0.3048)
			(end -0.67945 -0.3048)
			(stroke
				(width 0.1)
				(type default)
			)
			(layer "B.Fab")
		)
		(fp_line
			(start -0.12065 -0.2794)
			(end -0.12065 -0.3048)
			(stroke
				(width 0.1)
				(type default)
			)
			(layer "B.Fab")
		)
		(fp_line
			(start -0.120396 0.2794)
			(end 0.12065 0.2794)
			(stroke
				(width 0.1)
				(type default)
			)
			(layer "B.Fab")
		)
		(fp_line
			(start -0.120396 0.3048)
			(end -0.120396 0.2794)
			(stroke
				(width 0.1)
				(type default)
			)
			(layer "B.Fab")
		)
		(fp_line
			(start 0.12065 -0.305054)
			(end 0.12065 -0.2794)
			(stroke
				(width 0.1)
				(type default)
			)
			(layer "B.Fab")
		)
		(fp_line
			(start 0.12065 -0.2794)
			(end -0.12065 -0.2794)
			(stroke
				(width 0.1)
				(type default)
			)
			(layer "B.Fab")
		)
		(fp_line
			(start 0.12065 0.2794)
			(end 0.12065 0.3048)
			(stroke
				(width 0.1)
				(type default)
			)
			(layer "B.Fab")
		)
		(fp_line
			(start 0.12065 0.3048)
			(end 0.67945 0.3048)
			(stroke
				(width 0.1)
				(type default)
			)
			(layer "B.Fab")
		)
		(fp_line
			(start 0.67945 -0.305054)
			(end 0.12065 -0.305054)
			(stroke
				(width 0.1)
				(type default)
			)
			(layer "B.Fab")
		)
		(fp_line
			(start 0.67945 0.3048)
			(end 0.67945 -0.305054)
			(stroke
				(width 0.1)
				(type default)
			)
			(layer "B.Fab")
		)
		(pad "1" smd circle
			(at 0.40005 0 180)
			(size 0 0)
			(layers "B.Cu" "B.Mask" "B.Paste")
			(net "HP_LVC3_OCP_V3_2_P12V_PWRGD")
		)
		(pad "2" smd circle
			(at -0.40005 0 180)
			(size 0 0)
			(layers "B.Cu" "B.Mask" "B.Paste")
			(net "P3V3_OCP_EN_2")
		)
	)
	(footprint ""
		(layer "B.Cu")
		(at 75.7936 -384.66268 180)
		(property "Reference" "R787"
			(at 0 0 0)
			(layer "B.SilkS")
			(hide yes)
			(effects
				(font
					(size 1.27 1.27)
				)
				(justify mirror)
			)
		)
		(property "Value" ""
			(at 0 0 0)
			(layer "B.Fab")
			(effects
				(font
					(size 1.27 1.27)
				)
				(justify mirror)
			)
		)
		(duplicate_pad_numbers_are_jumpers no)
		(fp_line
			(start 0.32512 0.175006)
			(end 0.32512 -0.175006)
			(stroke
				(width 0.1)
				(type default)
			)
			(layer "B.Fab")
		)
		(fp_line
			(start 0.32512 -0.175006)
			(end -0.32512 -0.175006)
			(stroke
				(width 0.1)
				(type default)
			)
			(layer "B.Fab")
		)
		(fp_line
			(start -0.32512 0.175006)
			(end 0.32512 0.175006)
			(stroke
				(width 0.1)
				(type default)
			)
			(layer "B.Fab")
		)
		(fp_line
			(start -0.32512 -0.175006)
			(end -0.32512 0.175006)
			(stroke
				(width 0.1)
				(type default)
			)
			(layer "B.Fab")
		)
		(pad "1" smd rect
			(at 0.2667 0)
			(size 0.3048 0.381)
			(layers "B.Cu" "B.Mask" "B.Paste")
			(net "TEST1_RT_CPU1_P1")
		)
		(pad "2" smd rect
			(at -0.2667 0 180)
			(size 0.3048 0.381)
			(layers "B.Cu" "B.Mask" "B.Paste")
			(net "GND")
		)
	)
	(footprint ""
		(layer "B.Cu")
		(at 36.040568 -193.9798)
		(property "Reference" "C148"
			(at 0 0 0)
			(layer "B.SilkS")
			(hide yes)
			(effects
				(font
					(size 1.27 1.27)
				)
				(justify mirror)
			)
		)
		(property "Value" ""
			(at 0 0 0)
			(layer "B.Fab")
			(effects
				(font
					(size 1.27 1.27)
				)
				(justify mirror)
			)
		)
		(duplicate_pad_numbers_are_jumpers no)
		(fp_line
			(start -0.7874 -0.4064)
			(end -0.7874 0.4064)
			(stroke
				(width 0.1524)
				(type default)
			)
			(layer "B.SilkS")
		)
		(fp_line
			(start -0.7874 0.4064)
			(end 0.7874 0.4064)
			(stroke
				(width 0.1524)
				(type default)
			)
			(layer "B.SilkS")
		)
		(fp_line
			(start 0.7874 -0.4064)
			(end -0.7874 -0.4064)
			(stroke
				(width 0.1524)
				(type default)
			)
			(layer "B.SilkS")
		)
		(fp_line
			(start 0.7874 0.4064)
			(end 0.7874 -0.4064)
			(stroke
				(width 0.1524)
				(type default)
			)
			(layer "B.SilkS")
		)
		(fp_line
			(start -0.67945 -0.3048)
			(end -0.67945 0.3048)
			(stroke
				(width 0.1)
				(type default)
			)
			(layer "B.Fab")
		)
		(fp_line
			(start -0.67945 0.3048)
			(end -0.120396 0.3048)
			(stroke
				(width 0.1)
				(type default)
			)
			(layer "B.Fab")
		)
		(fp_line
			(start -0.12065 -0.3048)
			(end -0.67945 -0.3048)
			(stroke
				(width 0.1)
				(type default)
			)
			(layer "B.Fab")
		)
		(fp_line
			(start -0.12065 -0.2794)
			(end -0.12065 -0.3048)
			(stroke
				(width 0.1)
				(type default)
			)
			(layer "B.Fab")
		)
		(fp_line
			(start -0.120396 0.2794)
			(end 0.12065 0.2794)
			(stroke
				(width 0.1)
				(type default)
			)
			(layer "B.Fab")
		)
		(fp_line
			(start -0.120396 0.3048)
			(end -0.120396 0.2794)
			(stroke
				(width 0.1)
				(type default)
			)
			(layer "B.Fab")
		)
		(fp_line
			(start 0.12065 -0.305054)
			(end 0.12065 -0.2794)
			(stroke
				(width 0.1)
				(type default)
			)
			(layer "B.Fab")
		)
		(fp_line
			(start 0.12065 -0.2794)
			(end -0.12065 -0.2794)
			(stroke
				(width 0.1)
				(type default)
			)
			(layer "B.Fab")
		)
		(fp_line
			(start 0.12065 0.2794)
			(end 0.12065 0.3048)
			(stroke
				(width 0.1)
				(type default)
			)
			(layer "B.Fab")
		)
		(fp_line
			(start 0.12065 0.3048)
			(end 0.67945 0.3048)
			(stroke
				(width 0.1)
				(type default)
			)
			(layer "B.Fab")
		)
		(fp_line
			(start 0.67945 -0.305054)
			(end 0.12065 -0.305054)
			(stroke
				(width 0.1)
				(type default)
			)
			(layer "B.Fab")
		)
		(fp_line
			(start 0.67945 0.3048)
			(end 0.67945 -0.305054)
			(stroke
				(width 0.1)
				(type default)
			)
			(layer "B.Fab")
		)
		(pad "1" smd circle
			(at 0.40005 0 180)
			(size 0 0)
			(layers "B.Cu" "B.Mask" "B.Paste")
			(net "P3V3_AUX")
		)
		(pad "2" smd circle
			(at -0.40005 0 180)
			(size 0 0)
			(layers "B.Cu" "B.Mask" "B.Paste")
			(net "GND")
		)
	)
	(footprint ""
		(layer "B.Cu")
		(at 153.456386 -315.36005 180)
		(property "Reference" "R572"
			(at 0 0 0)
			(layer "B.SilkS")
			(hide yes)
			(effects
				(font
					(size 1.27 1.27)
				)
				(justify mirror)
			)
		)
		(property "Value" ""
			(at 0 0 0)
			(layer "B.Fab")
			(effects
				(font
					(size 1.27 1.27)
				)
				(justify mirror)
			)
		)
		(duplicate_pad_numbers_are_jumpers no)
		(fp_line
			(start 0.7874 0.4064)
			(end 0.7874 -0.4064)
			(stroke
				(width 0.1524)
				(type default)
			)
			(layer "B.SilkS")
		)
		(fp_line
			(start 0.7874 -0.4064)
			(end -0.7874 -0.4064)
			(stroke
				(width 0.1524)
				(type default)
			)
			(layer "B.SilkS")
		)
		(fp_line
			(start -0.7874 0.4064)
			(end 0.7874 0.4064)
			(stroke
				(width 0.1524)
				(type default)
			)
			(layer "B.SilkS")
		)
		(fp_line
			(start -0.7874 -0.4064)
			(end -0.7874 0.4064)
			(stroke
				(width 0.1524)
				(type default)
			)
			(layer "B.SilkS")
		)
		(fp_line
			(start 0.67945 0.3048)
			(end 0.67945 -0.305054)
			(stroke
				(width 0.1)
				(type default)
			)
			(layer "B.Fab")
		)
		(fp_line
			(start 0.67945 -0.305054)
			(end 0.12065 -0.305054)
			(stroke
				(width 0.1)
				(type default)
			)
			(layer "B.Fab")
		)
		(fp_line
			(start 0.12065 0.3048)
			(end 0.67945 0.3048)
			(stroke
				(width 0.1)
				(type default)
			)
			(layer "B.Fab")
		)
		(fp_line
			(start 0.12065 0.2794)
			(end 0.12065 0.3048)
			(stroke
				(width 0.1)
				(type default)
			)
			(layer "B.Fab")
		)
		(fp_line
			(start 0.12065 -0.2794)
			(end -0.12065 -0.2794)
			(stroke
				(width 0.1)
				(type default)
			)
			(layer "B.Fab")
		)
		(fp_line
			(start 0.12065 -0.305054)
			(end 0.12065 -0.2794)
			(stroke
				(width 0.1)
				(type default)
			)
			(layer "B.Fab")
		)
		(fp_line
			(start -0.120396 0.3048)
			(end -0.120396 0.2794)
			(stroke
				(width 0.1)
				(type default)
			)
			(layer "B.Fab")
		)
		(fp_line
			(start -0.120396 0.2794)
			(end 0.12065 0.2794)
			(stroke
				(width 0.1)
				(type default)
			)
			(layer "B.Fab")
		)
		(fp_line
			(start -0.12065 -0.2794)
			(end -0.12065 -0.3048)
			(stroke
				(width 0.1)
				(type default)
			)
			(layer "B.Fab")
		)
		(fp_line
			(start -0.12065 -0.3048)
			(end -0.67945 -0.3048)
			(stroke
				(width 0.1)
				(type default)
			)
			(layer "B.Fab")
		)
		(fp_line
			(start -0.67945 0.3048)
			(end -0.120396 0.3048)
			(stroke
				(width 0.1)
				(type default)
			)
			(layer "B.Fab")
		)
		(fp_line
			(start -0.67945 -0.3048)
			(end -0.67945 0.3048)
			(stroke
				(width 0.1)
				(type default)
			)
			(layer "B.Fab")
		)
		(pad "1" smd circle
			(at 0.40005 0)
			(size 0 0)
			(layers "B.Cu" "B.Mask" "B.Paste")
			(net "XTAL_CPU1_R_X32K_X1")
		)
		(pad "2" smd circle
			(at -0.40005 0)
			(size 0 0)
			(layers "B.Cu" "B.Mask" "B.Paste")
			(net "XTAL_CPU1_R_X32K_X2")
		)
	)
	(footprint ""
		(layer "B.Cu")
		(at 40.13073 -346.788994 90)
		(property "Reference" "PC632_3"
			(at 0 0 90)
			(layer "B.SilkS")
			(hide yes)
			(effects
				(font
					(size 1.27 1.27)
				)
				(justify mirror)
			)
		)
		(property "Value" ""
			(at 0 0 90)
			(layer "B.Fab")
			(effects
				(font
					(size 1.27 1.27)
				)
				(justify mirror)
			)
		)
		(duplicate_pad_numbers_are_jumpers no)
		(fp_line
			(start 1.524 -0.762)
			(end -1.524 -0.762)
			(stroke
				(width 0.1524)
				(type default)
			)
			(layer "B.SilkS")
		)
		(fp_line
			(start -1.524 -0.762)
			(end -1.524 0.762)
			(stroke
				(width 0.1524)
				(type default)
			)
			(layer "B.SilkS")
		)
		(fp_line
			(start 1.524 0.762)
			(end 1.524 -0.762)
			(stroke
				(width 0.1524)
				(type default)
			)
			(layer "B.SilkS")
		)
		(fp_line
			(start -1.524 0.762)
			(end 1.524 0.762)
			(stroke
				(width 0.1524)
				(type default)
			)
			(layer "B.SilkS")
		)
		(fp_line
			(start 1.1049 -0.724916)
			(end 1.1049 0.724916)
			(stroke
				(width 0.1)
				(type default)
			)
			(layer "B.Fab")
		)
		(fp_line
			(start -1.1049 -0.724916)
			(end 1.1049 -0.724916)
			(stroke
				(width 0.1)
				(type default)
			)
			(layer "B.Fab")
		)
		(fp_line
			(start 1.1049 0.724916)
			(end -1.1049 0.724916)
			(stroke
				(width 0.1)
				(type default)
			)
			(layer "B.Fab")
		)
		(fp_line
			(start -1.1049 0.724916)
			(end -1.1049 -0.724916)
			(stroke
				(width 0.1)
				(type default)
			)
			(layer "B.Fab")
		)
		(pad "1" smd rect
			(at 0.889 0 90)
			(size 1.016 1.27)
			(layers "B.Cu" "B.Mask" "B.Paste")
			(net "SW_P12V_AUX_PVDDIO_P1_FLT")
		)
		(pad "2" smd rect
			(at -0.889 0 90)
			(size 1.016 1.27)
			(layers "B.Cu" "B.Mask" "B.Paste")
			(net "GND")
		)
	)
	(footprint ""
		(layer "B.Cu")
		(at 116.227098 -261.748016 90)
		(property "Reference" "C2271"
			(at 0 0 90)
			(layer "B.SilkS")
			(hide yes)
			(effects
				(font
					(size 1.27 1.27)
				)
				(justify mirror)
			)
		)
		(property "Value" ""
			(at 0 0 90)
			(layer "B.Fab")
			(effects
				(font
					(size 1.27 1.27)
				)
				(justify mirror)
			)
		)
		(duplicate_pad_numbers_are_jumpers no)
		(fp_line
			(start 0.7874 -0.4064)
			(end -0.7874 -0.4064)
			(stroke
				(width 0.1524)
				(type default)
			)
			(layer "B.SilkS")
		)
		(fp_line
			(start -0.7874 -0.4064)
			(end -0.7874 0.4064)
			(stroke
				(width 0.1524)
				(type default)
			)
			(layer "B.SilkS")
		)
		(fp_line
			(start 0.7874 0.4064)
			(end 0.7874 -0.4064)
			(stroke
				(width 0.1524)
				(type default)
			)
			(layer "B.SilkS")
		)
		(fp_line
			(start -0.7874 0.4064)
			(end 0.7874 0.4064)
			(stroke
				(width 0.1524)
				(type default)
			)
			(layer "B.SilkS")
		)
		(fp_line
			(start 0.67945 -0.305054)
			(end 0.12065 -0.305054)
			(stroke
				(width 0.1)
				(type default)
			)
			(layer "B.Fab")
		)
		(fp_line
			(start 0.12065 -0.305054)
			(end 0.12065 -0.2794)
			(stroke
				(width 0.1)
				(type default)
			)
			(layer "B.Fab")
		)
		(fp_line
			(start -0.12065 -0.3048)
			(end -0.67945 -0.3048)
			(stroke
				(width 0.1)
				(type default)
			)
			(layer "B.Fab")
		)
		(fp_line
			(start -0.67945 -0.3048)
			(end -0.67945 0.3048)
			(stroke
				(width 0.1)
				(type default)
			)
			(layer "B.Fab")
		)
		(fp_line
			(start 0.12065 -0.2794)
			(end -0.12065 -0.2794)
			(stroke
				(width 0.1)
				(type default)
			)
			(layer "B.Fab")
		)
		(fp_line
			(start -0.12065 -0.2794)
			(end -0.12065 -0.3048)
			(stroke
				(width 0.1)
				(type default)
			)
			(layer "B.Fab")
		)
		(fp_line
			(start 0.12065 0.2794)
			(end 0.12065 0.3048)
			(stroke
				(width 0.1)
				(type default)
			)
			(layer "B.Fab")
		)
		(fp_line
			(start -0.120396 0.2794)
			(end 0.12065 0.2794)
			(stroke
				(width 0.1)
				(type default)
			)
			(layer "B.Fab")
		)
		(fp_line
			(start 0.67945 0.3048)
			(end 0.67945 -0.305054)
			(stroke
				(width 0.1)
				(type default)
			)
			(layer "B.Fab")
		)
		(fp_line
			(start 0.12065 0.3048)
			(end 0.67945 0.3048)
			(stroke
				(width 0.1)
				(type default)
			)
			(layer "B.Fab")
		)
		(fp_line
			(start -0.120396 0.3048)
			(end -0.120396 0.2794)
			(stroke
				(width 0.1)
				(type default)
			)
			(layer "B.Fab")
		)
		(fp_line
			(start -0.67945 0.3048)
			(end -0.120396 0.3048)
			(stroke
				(width 0.1)
				(type default)
			)
			(layer "B.Fab")
		)
		(pad "1" smd circle
			(at 0.40005 0 270)
			(size 0 0)
			(layers "B.Cu" "B.Mask" "B.Paste")
			(net "PVDD11_S3_P1")
		)
		(pad "2" smd circle
			(at -0.40005 0 270)
			(size 0 0)
			(layers "B.Cu" "B.Mask" "B.Paste")
			(net "GND")
		)
	)
	(footprint ""
		(layer "B.Cu")
		(at 346.71889 -398.942052 90)
		(property "Reference" "C636"
			(at 0 0 90)
			(layer "B.SilkS")
			(hide yes)
			(effects
				(font
					(size 1.27 1.27)
				)
				(justify mirror)
			)
		)
		(property "Value" ""
			(at 0 0 90)
			(layer "B.Fab")
			(effects
				(font
					(size 1.27 1.27)
				)
				(justify mirror)
			)
		)
		(duplicate_pad_numbers_are_jumpers no)
		(fp_line
			(start 0.7874 -0.4064)
			(end -0.7874 -0.4064)
			(stroke
				(width 0.1524)
				(type default)
			)
			(layer "B.SilkS")
		)
		(fp_line
			(start -0.7874 -0.4064)
			(end -0.7874 0.4064)
			(stroke
				(width 0.1524)
				(type default)
			)
			(layer "B.SilkS")
		)
		(fp_line
			(start 0.7874 0.4064)
			(end 0.7874 -0.4064)
			(stroke
				(width 0.1524)
				(type default)
			)
			(layer "B.SilkS")
		)
		(fp_line
			(start -0.7874 0.4064)
			(end 0.7874 0.4064)
			(stroke
				(width 0.1524)
				(type default)
			)
			(layer "B.SilkS")
		)
		(fp_line
			(start 0.67945 -0.305054)
			(end 0.12065 -0.305054)
			(stroke
				(width 0.1)
				(type default)
			)
			(layer "B.Fab")
		)
		(fp_line
			(start 0.12065 -0.305054)
			(end 0.12065 -0.2794)
			(stroke
				(width 0.1)
				(type default)
			)
			(layer "B.Fab")
		)
		(fp_line
			(start -0.12065 -0.3048)
			(end -0.67945 -0.3048)
			(stroke
				(width 0.1)
				(type default)
			)
			(layer "B.Fab")
		)
		(fp_line
			(start -0.67945 -0.3048)
			(end -0.67945 0.3048)
			(stroke
				(width 0.1)
				(type default)
			)
			(layer "B.Fab")
		)
		(fp_line
			(start 0.12065 -0.2794)
			(end -0.12065 -0.2794)
			(stroke
				(width 0.1)
				(type default)
			)
			(layer "B.Fab")
		)
		(fp_line
			(start -0.12065 -0.2794)
			(end -0.12065 -0.3048)
			(stroke
				(width 0.1)
				(type default)
			)
			(layer "B.Fab")
		)
		(fp_line
			(start 0.12065 0.2794)
			(end 0.12065 0.3048)
			(stroke
				(width 0.1)
				(type default)
			)
			(layer "B.Fab")
		)
		(fp_line
			(start -0.120396 0.2794)
			(end 0.12065 0.2794)
			(stroke
				(width 0.1)
				(type default)
			)
			(layer "B.Fab")
		)
		(fp_line
			(start 0.67945 0.3048)
			(end 0.67945 -0.305054)
			(stroke
				(width 0.1)
				(type default)
			)
			(layer "B.Fab")
		)
		(fp_line
			(start 0.12065 0.3048)
			(end 0.67945 0.3048)
			(stroke
				(width 0.1)
				(type default)
			)
			(layer "B.Fab")
		)
		(fp_line
			(start -0.120396 0.3048)
			(end -0.120396 0.2794)
			(stroke
				(width 0.1)
				(type default)
			)
			(layer "B.Fab")
		)
		(fp_line
			(start -0.67945 0.3048)
			(end -0.120396 0.3048)
			(stroke
				(width 0.1)
				(type default)
			)
			(layer "B.Fab")
		)
		(pad "1" smd circle
			(at 0.40005 0 270)
			(size 0 0)
			(layers "B.Cu" "B.Mask" "B.Paste")
			(net "P0V9_CPU0_RT_2D")
		)
		(pad "2" smd circle
			(at -0.40005 0 270)
			(size 0 0)
			(layers "B.Cu" "B.Mask" "B.Paste")
			(net "GND")
		)
	)
	(footprint ""
		(layer "B.Cu")
		(at 132.490972 -41.007792 90)
		(property "Reference" "C6033"
			(at 0 0 90)
			(layer "B.SilkS")
			(hide yes)
			(effects
				(font
					(size 1.27 1.27)
				)
				(justify mirror)
			)
		)
		(property "Value" ""
			(at 0 0 90)
			(layer "B.Fab")
			(effects
				(font
					(size 1.27 1.27)
				)
				(justify mirror)
			)
		)
		(duplicate_pad_numbers_are_jumpers no)
		(fp_line
			(start 0.7874 -0.4064)
			(end -0.7874 -0.4064)
			(stroke
				(width 0.1524)
				(type default)
			)
			(layer "B.SilkS")
		)
		(fp_line
			(start -0.7874 -0.4064)
			(end -0.7874 0.4064)
			(stroke
				(width 0.1524)
				(type default)
			)
			(layer "B.SilkS")
		)
		(fp_line
			(start 0.7874 0.4064)
			(end 0.7874 -0.4064)
			(stroke
				(width 0.1524)
				(type default)
			)
			(layer "B.SilkS")
		)
		(fp_line
			(start -0.7874 0.4064)
			(end 0.7874 0.4064)
			(stroke
				(width 0.1524)
				(type default)
			)
			(layer "B.SilkS")
		)
		(fp_line
			(start 0.67945 -0.305054)
			(end 0.12065 -0.305054)
			(stroke
				(width 0.1)
				(type default)
			)
			(layer "B.Fab")
		)
		(fp_line
			(start 0.12065 -0.305054)
			(end 0.12065 -0.2794)
			(stroke
				(width 0.1)
				(type default)
			)
			(layer "B.Fab")
		)
		(fp_line
			(start -0.12065 -0.3048)
			(end -0.67945 -0.3048)
			(stroke
				(width 0.1)
				(type default)
			)
			(layer "B.Fab")
		)
		(fp_line
			(start -0.67945 -0.3048)
			(end -0.67945 0.3048)
			(stroke
				(width 0.1)
				(type default)
			)
			(layer "B.Fab")
		)
		(fp_line
			(start 0.12065 -0.2794)
			(end -0.12065 -0.2794)
			(stroke
				(width 0.1)
				(type default)
			)
			(layer "B.Fab")
		)
		(fp_line
			(start -0.12065 -0.2794)
			(end -0.12065 -0.3048)
			(stroke
				(width 0.1)
				(type default)
			)
			(layer "B.Fab")
		)
		(fp_line
			(start 0.12065 0.2794)
			(end 0.12065 0.3048)
			(stroke
				(width 0.1)
				(type default)
			)
			(layer "B.Fab")
		)
		(fp_line
			(start -0.120396 0.2794)
			(end 0.12065 0.2794)
			(stroke
				(width 0.1)
				(type default)
			)
			(layer "B.Fab")
		)
		(fp_line
			(start 0.67945 0.3048)
			(end 0.67945 -0.305054)
			(stroke
				(width 0.1)
				(type default)
			)
			(layer "B.Fab")
		)
		(fp_line
			(start 0.12065 0.3048)
			(end 0.67945 0.3048)
			(stroke
				(width 0.1)
				(type default)
			)
			(layer "B.Fab")
		)
		(fp_line
			(start -0.120396 0.3048)
			(end -0.120396 0.2794)
			(stroke
				(width 0.1)
				(type default)
			)
			(layer "B.Fab")
		)
		(fp_line
			(start -0.67945 0.3048)
			(end -0.120396 0.3048)
			(stroke
				(width 0.1)
				(type default)
			)
			(layer "B.Fab")
		)
		(pad "1" smd circle
			(at 0.40005 0 270)
			(size 0 0)
			(layers "B.Cu" "B.Mask" "B.Paste")
			(net "P1V2_CPU0_USB_DVDD12")
		)
		(pad "2" smd circle
			(at -0.40005 0 270)
			(size 0 0)
			(layers "B.Cu" "B.Mask" "B.Paste")
			(net "GND")
		)
	)
	(footprint ""
		(layer "B.Cu")
		(at 236.093 -234.061 -90)
		(property "Reference" "R148"
			(at 0 0 90)
			(layer "B.SilkS")
			(hide yes)
			(effects
				(font
					(size 1.27 1.27)
				)
				(justify mirror)
			)
		)
		(property "Value" ""
			(at 0 0 90)
			(layer "B.Fab")
			(effects
				(font
					(size 1.27 1.27)
				)
				(justify mirror)
			)
		)
		(duplicate_pad_numbers_are_jumpers no)
		(fp_line
			(start -0.7874 0.4064)
			(end 0.7874 0.4064)
			(stroke
				(width 0.1524)
				(type default)
			)
			(layer "B.SilkS")
		)
		(fp_line
			(start 0.7874 0.4064)
			(end 0.7874 -0.4064)
			(stroke
				(width 0.1524)
				(type default)
			)
			(layer "B.SilkS")
		)
		(fp_line
			(start -0.7874 -0.4064)
			(end -0.7874 0.4064)
			(stroke
				(width 0.1524)
				(type default)
			)
			(layer "B.SilkS")
		)
		(fp_line
			(start 0.7874 -0.4064)
			(end -0.7874 -0.4064)
			(stroke
				(width 0.1524)
				(type default)
			)
			(layer "B.SilkS")
		)
		(fp_line
			(start -0.67945 0.3048)
			(end -0.120396 0.3048)
			(stroke
				(width 0.1)
				(type default)
			)
			(layer "B.Fab")
		)
		(fp_line
			(start -0.120396 0.3048)
			(end -0.120396 0.2794)
			(stroke
				(width 0.1)
				(type default)
			)
			(layer "B.Fab")
		)
		(fp_line
			(start 0.12065 0.3048)
			(end 0.67945 0.3048)
			(stroke
				(width 0.1)
				(type default)
			)
			(layer "B.Fab")
		)
		(fp_line
			(start 0.67945 0.3048)
			(end 0.67945 -0.305054)
			(stroke
				(width 0.1)
				(type default)
			)
			(layer "B.Fab")
		)
		(fp_line
			(start -0.120396 0.2794)
			(end 0.12065 0.2794)
			(stroke
				(width 0.1)
				(type default)
			)
			(layer "B.Fab")
		)
		(fp_line
			(start 0.12065 0.2794)
			(end 0.12065 0.3048)
			(stroke
				(width 0.1)
				(type default)
			)
			(layer "B.Fab")
		)
		(fp_line
			(start -0.12065 -0.2794)
			(end -0.12065 -0.3048)
			(stroke
				(width 0.1)
				(type default)
			)
			(layer "B.Fab")
		)
		(fp_line
			(start 0.12065 -0.2794)
			(end -0.12065 -0.2794)
			(stroke
				(width 0.1)
				(type default)
			)
			(layer "B.Fab")
		)
		(fp_line
			(start -0.67945 -0.3048)
			(end -0.67945 0.3048)
			(stroke
				(width 0.1)
				(type default)
			)
			(layer "B.Fab")
		)
		(fp_line
			(start -0.12065 -0.3048)
			(end -0.67945 -0.3048)
			(stroke
				(width 0.1)
				(type default)
			)
			(layer "B.Fab")
		)
		(fp_line
			(start 0.12065 -0.305054)
			(end 0.12065 -0.2794)
			(stroke
				(width 0.1)
				(type default)
			)
			(layer "B.Fab")
		)
		(fp_line
			(start 0.67945 -0.305054)
			(end 0.12065 -0.305054)
			(stroke
				(width 0.1)
				(type default)
			)
			(layer "B.Fab")
		)
		(pad "1" smd circle
			(at 0.40005 0 90)
			(size 0 0)
			(layers "B.Cu" "B.Mask" "B.Paste")
			(net "SMB_CPU0_CPU1_SEC_SDA_R2")
		)
		(pad "2" smd circle
			(at -0.40005 0 90)
			(size 0 0)
			(layers "B.Cu" "B.Mask" "B.Paste")
			(net "SMB_CPU1_SEC_R_SDA")
		)
	)
	(footprint ""
		(layer "B.Cu")
		(at 257.232658 -327.684384 180)
		(property "Reference" "C1074"
			(at 0 0 0)
			(layer "B.SilkS")
			(hide yes)
			(effects
				(font
					(size 1.27 1.27)
				)
				(justify mirror)
			)
		)
		(property "Value" ""
			(at 0 0 0)
			(layer "B.Fab")
			(effects
				(font
					(size 1.27 1.27)
				)
				(justify mirror)
			)
		)
		(duplicate_pad_numbers_are_jumpers no)
		(fp_line
			(start 0.7874 0.4064)
			(end 0.7874 -0.4064)
			(stroke
				(width 0.1524)
				(type default)
			)
			(layer "B.SilkS")
		)
		(fp_line
			(start 0.7874 -0.4064)
			(end -0.7874 -0.4064)
			(stroke
				(width 0.1524)
				(type default)
			)
			(layer "B.SilkS")
		)
		(fp_line
			(start -0.7874 0.4064)
			(end 0.7874 0.4064)
			(stroke
				(width 0.1524)
				(type default)
			)
			(layer "B.SilkS")
		)
		(fp_line
			(start -0.7874 -0.4064)
			(end -0.7874 0.4064)
			(stroke
				(width 0.1524)
				(type default)
			)
			(layer "B.SilkS")
		)
		(fp_line
			(start 0.67945 0.3048)
			(end 0.67945 -0.305054)
			(stroke
				(width 0.1)
				(type default)
			)
			(layer "B.Fab")
		)
		(fp_line
			(start 0.67945 -0.305054)
			(end 0.12065 -0.305054)
			(stroke
				(width 0.1)
				(type default)
			)
			(layer "B.Fab")
		)
		(fp_line
			(start 0.12065 0.3048)
			(end 0.67945 0.3048)
			(stroke
				(width 0.1)
				(type default)
			)
			(layer "B.Fab")
		)
		(fp_line
			(start 0.12065 0.2794)
			(end 0.12065 0.3048)
			(stroke
				(width 0.1)
				(type default)
			)
			(layer "B.Fab")
		)
		(fp_line
			(start 0.12065 -0.2794)
			(end -0.12065 -0.2794)
			(stroke
				(width 0.1)
				(type default)
			)
			(layer "B.Fab")
		)
		(fp_line
			(start 0.12065 -0.305054)
			(end 0.12065 -0.2794)
			(stroke
				(width 0.1)
				(type default)
			)
			(layer "B.Fab")
		)
		(fp_line
			(start -0.120396 0.3048)
			(end -0.120396 0.2794)
			(stroke
				(width 0.1)
				(type default)
			)
			(layer "B.Fab")
		)
		(fp_line
			(start -0.120396 0.2794)
			(end 0.12065 0.2794)
			(stroke
				(width 0.1)
				(type default)
			)
			(layer "B.Fab")
		)
		(fp_line
			(start -0.12065 -0.2794)
			(end -0.12065 -0.3048)
			(stroke
				(width 0.1)
				(type default)
			)
			(layer "B.Fab")
		)
		(fp_line
			(start -0.12065 -0.3048)
			(end -0.67945 -0.3048)
			(stroke
				(width 0.1)
				(type default)
			)
			(layer "B.Fab")
		)
		(fp_line
			(start -0.67945 0.3048)
			(end -0.120396 0.3048)
			(stroke
				(width 0.1)
				(type default)
			)
			(layer "B.Fab")
		)
		(fp_line
			(start -0.67945 -0.3048)
			(end -0.67945 0.3048)
			(stroke
				(width 0.1)
				(type default)
			)
			(layer "B.Fab")
		)
		(pad "1" smd circle
			(at 0.40005 0)
			(size 0 0)
			(layers "B.Cu" "B.Mask" "B.Paste")
			(net "MAX11617_2_VREF")
		)
		(pad "2" smd circle
			(at -0.40005 0)
			(size 0 0)
			(layers "B.Cu" "B.Mask" "B.Paste")
			(net "GND")
		)
	)
	(footprint ""
		(layer "B.Cu")
		(at 189.879224 -145.585434)
		(property "Reference" "R8035"
			(at 0 0 0)
			(layer "B.SilkS")
			(hide yes)
			(effects
				(font
					(size 1.27 1.27)
				)
				(justify mirror)
			)
		)
		(property "Value" ""
			(at 0 0 0)
			(layer "B.Fab")
			(effects
				(font
					(size 1.27 1.27)
				)
				(justify mirror)
			)
		)
		(duplicate_pad_numbers_are_jumpers no)
		(fp_line
			(start -0.7874 -0.4064)
			(end -0.7874 0.4064)
			(stroke
				(width 0.1524)
				(type default)
			)
			(layer "B.SilkS")
		)
		(fp_line
			(start -0.7874 0.4064)
			(end 0.7874 0.4064)
			(stroke
				(width 0.1524)
				(type default)
			)
			(layer "B.SilkS")
		)
		(fp_line
			(start 0.7874 -0.4064)
			(end -0.7874 -0.4064)
			(stroke
				(width 0.1524)
				(type default)
			)
			(layer "B.SilkS")
		)
		(fp_line
			(start 0.7874 0.4064)
			(end 0.7874 -0.4064)
			(stroke
				(width 0.1524)
				(type default)
			)
			(layer "B.SilkS")
		)
		(fp_line
			(start -0.67945 -0.3048)
			(end -0.67945 0.3048)
			(stroke
				(width 0.1)
				(type default)
			)
			(layer "B.Fab")
		)
		(fp_line
			(start -0.67945 0.3048)
			(end -0.120396 0.3048)
			(stroke
				(width 0.1)
				(type default)
			)
			(layer "B.Fab")
		)
		(fp_line
			(start -0.12065 -0.3048)
			(end -0.67945 -0.3048)
			(stroke
				(width 0.1)
				(type default)
			)
			(layer "B.Fab")
		)
		(fp_line
			(start -0.12065 -0.2794)
			(end -0.12065 -0.3048)
			(stroke
				(width 0.1)
				(type default)
			)
			(layer "B.Fab")
		)
		(fp_line
			(start -0.120396 0.2794)
			(end 0.12065 0.2794)
			(stroke
				(width 0.1)
				(type default)
			)
			(layer "B.Fab")
		)
		(fp_line
			(start -0.120396 0.3048)
			(end -0.120396 0.2794)
			(stroke
				(width 0.1)
				(type default)
			)
			(layer "B.Fab")
		)
		(fp_line
			(start 0.12065 -0.305054)
			(end 0.12065 -0.2794)
			(stroke
				(width 0.1)
				(type default)
			)
			(layer "B.Fab")
		)
		(fp_line
			(start 0.12065 -0.2794)
			(end -0.12065 -0.2794)
			(stroke
				(width 0.1)
				(type default)
			)
			(layer "B.Fab")
		)
		(fp_line
			(start 0.12065 0.2794)
			(end 0.12065 0.3048)
			(stroke
				(width 0.1)
				(type default)
			)
			(layer "B.Fab")
		)
		(fp_line
			(start 0.12065 0.3048)
			(end 0.67945 0.3048)
			(stroke
				(width 0.1)
				(type default)
			)
			(layer "B.Fab")
		)
		(fp_line
			(start 0.67945 -0.305054)
			(end 0.12065 -0.305054)
			(stroke
				(width 0.1)
				(type default)
			)
			(layer "B.Fab")
		)
		(fp_line
			(start 0.67945 0.3048)
			(end 0.67945 -0.305054)
			(stroke
				(width 0.1)
				(type default)
			)
			(layer "B.Fab")
		)
		(pad "1" smd circle
			(at 0.40005 0 180)
			(size 0 0)
			(layers "B.Cu" "B.Mask" "B.Paste")
			(net "P1V8_AUX")
		)
		(pad "2" smd circle
			(at -0.40005 0 180)
			(size 0 0)
			(layers "B.Cu" "B.Mask" "B.Paste")
			(net "ESPI_CPU0_ALERT_N")
		)
	)
	(footprint ""
		(layer "B.Cu")
		(at 203.33208 -35.372548 180)
		(property "Reference" "R3579"
			(at 0 0 0)
			(layer "B.SilkS")
			(hide yes)
			(effects
				(font
					(size 1.27 1.27)
				)
				(justify mirror)
			)
		)
		(property "Value" ""
			(at 0 0 0)
			(layer "B.Fab")
			(effects
				(font
					(size 1.27 1.27)
				)
				(justify mirror)
			)
		)
		(duplicate_pad_numbers_are_jumpers no)
		(fp_line
			(start 0.7874 0.4064)
			(end 0.7874 -0.4064)
			(stroke
				(width 0.1524)
				(type default)
			)
			(layer "B.SilkS")
		)
		(fp_line
			(start 0.7874 -0.4064)
			(end -0.7874 -0.4064)
			(stroke
				(width 0.1524)
				(type default)
			)
			(layer "B.SilkS")
		)
		(fp_line
			(start -0.7874 0.4064)
			(end 0.7874 0.4064)
			(stroke
				(width 0.1524)
				(type default)
			)
			(layer "B.SilkS")
		)
		(fp_line
			(start -0.7874 -0.4064)
			(end -0.7874 0.4064)
			(stroke
				(width 0.1524)
				(type default)
			)
			(layer "B.SilkS")
		)
		(fp_line
			(start 0.67945 0.3048)
			(end 0.67945 -0.305054)
			(stroke
				(width 0.1)
				(type default)
			)
			(layer "B.Fab")
		)
		(fp_line
			(start 0.67945 -0.305054)
			(end 0.12065 -0.305054)
			(stroke
				(width 0.1)
				(type default)
			)
			(layer "B.Fab")
		)
		(fp_line
			(start 0.12065 0.3048)
			(end 0.67945 0.3048)
			(stroke
				(width 0.1)
				(type default)
			)
			(layer "B.Fab")
		)
		(fp_line
			(start 0.12065 0.2794)
			(end 0.12065 0.3048)
			(stroke
				(width 0.1)
				(type default)
			)
			(layer "B.Fab")
		)
		(fp_line
			(start 0.12065 -0.2794)
			(end -0.12065 -0.2794)
			(stroke
				(width 0.1)
				(type default)
			)
			(layer "B.Fab")
		)
		(fp_line
			(start 0.12065 -0.305054)
			(end 0.12065 -0.2794)
			(stroke
				(width 0.1)
				(type default)
			)
			(layer "B.Fab")
		)
		(fp_line
			(start -0.120396 0.3048)
			(end -0.120396 0.2794)
			(stroke
				(width 0.1)
				(type default)
			)
			(layer "B.Fab")
		)
		(fp_line
			(start -0.120396 0.2794)
			(end 0.12065 0.2794)
			(stroke
				(width 0.1)
				(type default)
			)
			(layer "B.Fab")
		)
		(fp_line
			(start -0.12065 -0.2794)
			(end -0.12065 -0.3048)
			(stroke
				(width 0.1)
				(type default)
			)
			(layer "B.Fab")
		)
		(fp_line
			(start -0.12065 -0.3048)
			(end -0.67945 -0.3048)
			(stroke
				(width 0.1)
				(type default)
			)
			(layer "B.Fab")
		)
		(fp_line
			(start -0.67945 0.3048)
			(end -0.120396 0.3048)
			(stroke
				(width 0.1)
				(type default)
			)
			(layer "B.Fab")
		)
		(fp_line
			(start -0.67945 -0.3048)
			(end -0.67945 0.3048)
			(stroke
				(width 0.1)
				(type default)
			)
			(layer "B.Fab")
		)
		(pad "1" smd circle
			(at 0.40005 0)
			(size 0 0)
			(layers "B.Cu" "B.Mask" "B.Paste")
			(net "P12V_SCM")
		)
		(pad "2" smd circle
			(at -0.40005 0)
			(size 0 0)
			(layers "B.Cu" "B.Mask" "B.Paste")
			(net "VSENSE_P12V_INA230_5_INN")
		)
	)
	(footprint ""
		(layer "B.Cu")
		(at 70.645528 -387.084062 -90)
		(property "Reference" "C113"
			(at 0 0 90)
			(layer "B.SilkS")
			(hide yes)
			(effects
				(font
					(size 1.27 1.27)
				)
				(justify mirror)
			)
		)
		(property "Value" ""
			(at 0 0 90)
			(layer "B.Fab")
			(effects
				(font
					(size 1.27 1.27)
				)
				(justify mirror)
			)
		)
		(duplicate_pad_numbers_are_jumpers no)
		(fp_line
			(start -1.524 0.762)
			(end 1.524 0.762)
			(stroke
				(width 0.1524)
				(type default)
			)
			(layer "B.SilkS")
		)
		(fp_line
			(start 1.524 0.762)
			(end 1.524 -0.762)
			(stroke
				(width 0.1524)
				(type default)
			)
			(layer "B.SilkS")
		)
		(fp_line
			(start -1.524 -0.762)
			(end -1.524 0.762)
			(stroke
				(width 0.1524)
				(type default)
			)
			(layer "B.SilkS")
		)
		(fp_line
			(start 1.524 -0.762)
			(end -1.524 -0.762)
			(stroke
				(width 0.1524)
				(type default)
			)
			(layer "B.SilkS")
		)
		(fp_line
			(start -1.1049 0.724916)
			(end -1.1049 -0.724916)
			(stroke
				(width 0.1)
				(type default)
			)
			(layer "B.Fab")
		)
		(fp_line
			(start 1.1049 0.724916)
			(end -1.1049 0.724916)
			(stroke
				(width 0.1)
				(type default)
			)
			(layer "B.Fab")
		)
		(fp_line
			(start -1.1049 -0.724916)
			(end 1.1049 -0.724916)
			(stroke
				(width 0.1)
				(type default)
			)
			(layer "B.Fab")
		)
		(fp_line
			(start 1.1049 -0.724916)
			(end 1.1049 0.724916)
			(stroke
				(width 0.1)
				(type default)
			)
			(layer "B.Fab")
		)
		(pad "1" smd rect
			(at 0.889 0 270)
			(size 1.016 1.27)
			(layers "B.Cu" "B.Mask" "B.Paste")
			(net "P1V8_CPU1_RT_1D")
		)
		(pad "2" smd rect
			(at -0.889 0 270)
			(size 1.016 1.27)
			(layers "B.Cu" "B.Mask" "B.Paste")
			(net "GND")
		)
	)
	(footprint ""
		(layer "B.Cu")
		(at 95.518986 -390.560052 90)
		(property "Reference" "C335"
			(at 0 0 90)
			(layer "B.SilkS")
			(hide yes)
			(effects
				(font
					(size 1.27 1.27)
				)
				(justify mirror)
			)
		)
		(property "Value" ""
			(at 0 0 90)
			(layer "B.Fab")
			(effects
				(font
					(size 1.27 1.27)
				)
				(justify mirror)
			)
		)
		(duplicate_pad_numbers_are_jumpers no)
		(fp_line
			(start 0.7874 -0.4064)
			(end -0.7874 -0.4064)
			(stroke
				(width 0.1524)
				(type default)
			)
			(layer "B.SilkS")
		)
		(fp_line
			(start -0.7874 -0.4064)
			(end -0.7874 0.4064)
			(stroke
				(width 0.1524)
				(type default)
			)
			(layer "B.SilkS")
		)
		(fp_line
			(start 0.7874 0.4064)
			(end 0.7874 -0.4064)
			(stroke
				(width 0.1524)
				(type default)
			)
			(layer "B.SilkS")
		)
		(fp_line
			(start -0.7874 0.4064)
			(end 0.7874 0.4064)
			(stroke
				(width 0.1524)
				(type default)
			)
			(layer "B.SilkS")
		)
		(fp_line
			(start 0.67945 -0.305054)
			(end 0.12065 -0.305054)
			(stroke
				(width 0.1)
				(type default)
			)
			(layer "B.Fab")
		)
		(fp_line
			(start 0.12065 -0.305054)
			(end 0.12065 -0.2794)
			(stroke
				(width 0.1)
				(type default)
			)
			(layer "B.Fab")
		)
		(fp_line
			(start -0.12065 -0.3048)
			(end -0.67945 -0.3048)
			(stroke
				(width 0.1)
				(type default)
			)
			(layer "B.Fab")
		)
		(fp_line
			(start -0.67945 -0.3048)
			(end -0.67945 0.3048)
			(stroke
				(width 0.1)
				(type default)
			)
			(layer "B.Fab")
		)
		(fp_line
			(start 0.12065 -0.2794)
			(end -0.12065 -0.2794)
			(stroke
				(width 0.1)
				(type default)
			)
			(layer "B.Fab")
		)
		(fp_line
			(start -0.12065 -0.2794)
			(end -0.12065 -0.3048)
			(stroke
				(width 0.1)
				(type default)
			)
			(layer "B.Fab")
		)
		(fp_line
			(start 0.12065 0.2794)
			(end 0.12065 0.3048)
			(stroke
				(width 0.1)
				(type default)
			)
			(layer "B.Fab")
		)
		(fp_line
			(start -0.120396 0.2794)
			(end 0.12065 0.2794)
			(stroke
				(width 0.1)
				(type default)
			)
			(layer "B.Fab")
		)
		(fp_line
			(start 0.67945 0.3048)
			(end 0.67945 -0.305054)
			(stroke
				(width 0.1)
				(type default)
			)
			(layer "B.Fab")
		)
		(fp_line
			(start 0.12065 0.3048)
			(end 0.67945 0.3048)
			(stroke
				(width 0.1)
				(type default)
			)
			(layer "B.Fab")
		)
		(fp_line
			(start -0.120396 0.3048)
			(end -0.120396 0.2794)
			(stroke
				(width 0.1)
				(type default)
			)
			(layer "B.Fab")
		)
		(fp_line
			(start -0.67945 0.3048)
			(end -0.120396 0.3048)
			(stroke
				(width 0.1)
				(type default)
			)
			(layer "B.Fab")
		)
		(pad "1" smd circle
			(at 0.40005 0 270)
			(size 0 0)
			(layers "B.Cu" "B.Mask" "B.Paste")
			(net "P0V9_CPU1_RT1_2A")
		)
		(pad "2" smd circle
			(at -0.40005 0 270)
			(size 0 0)
			(layers "B.Cu" "B.Mask" "B.Paste")
			(net "GND")
		)
	)
	(footprint ""
		(layer "B.Cu")
		(at 301.377604 -426.498512 180)
		(property "Reference" "R666"
			(at 0 0 0)
			(layer "B.SilkS")
			(hide yes)
			(effects
				(font
					(size 1.27 1.27)
				)
				(justify mirror)
			)
		)
		(property "Value" ""
			(at 0 0 0)
			(layer "B.Fab")
			(effects
				(font
					(size 1.27 1.27)
				)
				(justify mirror)
			)
		)
		(duplicate_pad_numbers_are_jumpers no)
		(fp_line
			(start 0.32512 0.175006)
			(end 0.32512 -0.175006)
			(stroke
				(width 0.1)
				(type default)
			)
			(layer "B.Fab")
		)
		(fp_line
			(start 0.32512 -0.175006)
			(end -0.32512 -0.175006)
			(stroke
				(width 0.1)
				(type default)
			)
			(layer "B.Fab")
		)
		(fp_line
			(start -0.32512 0.175006)
			(end 0.32512 0.175006)
			(stroke
				(width 0.1)
				(type default)
			)
			(layer "B.Fab")
		)
		(fp_line
			(start -0.32512 -0.175006)
			(end -0.32512 0.175006)
			(stroke
				(width 0.1)
				(type default)
			)
			(layer "B.Fab")
		)
		(pad "1" smd rect
			(at 0.2667 0)
			(size 0.3048 0.381)
			(layers "B.Cu" "B.Mask" "B.Paste")
			(net "SMB_RT_CPU0_P0_ROM_MUX_1D_SCL")
		)
		(pad "2" smd rect
			(at -0.2667 0 180)
			(size 0.3048 0.381)
			(layers "B.Cu" "B.Mask" "B.Paste")
			(net "SMB_RT_CPU0_P0_ROM_MUX_1D_R_SCL")
		)
	)
	(footprint ""
		(layer "B.Cu")
		(at 94.460314 -307.730652 180)
		(property "Reference" "R491"
			(at 0 0 0)
			(layer "B.SilkS")
			(hide yes)
			(effects
				(font
					(size 1.27 1.27)
				)
				(justify mirror)
			)
		)
		(property "Value" ""
			(at 0 0 0)
			(layer "B.Fab")
			(effects
				(font
					(size 1.27 1.27)
				)
				(justify mirror)
			)
		)
		(duplicate_pad_numbers_are_jumpers no)
		(fp_line
			(start 0.7874 0.4064)
			(end 0.7874 -0.4064)
			(stroke
				(width 0.1524)
				(type default)
			)
			(layer "B.SilkS")
		)
		(fp_line
			(start 0.7874 -0.4064)
			(end -0.7874 -0.4064)
			(stroke
				(width 0.1524)
				(type default)
			)
			(layer "B.SilkS")
		)
		(fp_line
			(start -0.7874 0.4064)
			(end 0.7874 0.4064)
			(stroke
				(width 0.1524)
				(type default)
			)
			(layer "B.SilkS")
		)
		(fp_line
			(start -0.7874 -0.4064)
			(end -0.7874 0.4064)
			(stroke
				(width 0.1524)
				(type default)
			)
			(layer "B.SilkS")
		)
		(fp_line
			(start 0.67945 0.3048)
			(end 0.67945 -0.305054)
			(stroke
				(width 0.1)
				(type default)
			)
			(layer "B.Fab")
		)
		(fp_line
			(start 0.67945 -0.305054)
			(end 0.12065 -0.305054)
			(stroke
				(width 0.1)
				(type default)
			)
			(layer "B.Fab")
		)
		(fp_line
			(start 0.12065 0.3048)
			(end 0.67945 0.3048)
			(stroke
				(width 0.1)
				(type default)
			)
			(layer "B.Fab")
		)
		(fp_line
			(start 0.12065 0.2794)
			(end 0.12065 0.3048)
			(stroke
				(width 0.1)
				(type default)
			)
			(layer "B.Fab")
		)
		(fp_line
			(start 0.12065 -0.2794)
			(end -0.12065 -0.2794)
			(stroke
				(width 0.1)
				(type default)
			)
			(layer "B.Fab")
		)
		(fp_line
			(start 0.12065 -0.305054)
			(end 0.12065 -0.2794)
			(stroke
				(width 0.1)
				(type default)
			)
			(layer "B.Fab")
		)
		(fp_line
			(start -0.120396 0.3048)
			(end -0.120396 0.2794)
			(stroke
				(width 0.1)
				(type default)
			)
			(layer "B.Fab")
		)
		(fp_line
			(start -0.120396 0.2794)
			(end 0.12065 0.2794)
			(stroke
				(width 0.1)
				(type default)
			)
			(layer "B.Fab")
		)
		(fp_line
			(start -0.12065 -0.2794)
			(end -0.12065 -0.3048)
			(stroke
				(width 0.1)
				(type default)
			)
			(layer "B.Fab")
		)
		(fp_line
			(start -0.12065 -0.3048)
			(end -0.67945 -0.3048)
			(stroke
				(width 0.1)
				(type default)
			)
			(layer "B.Fab")
		)
		(fp_line
			(start -0.67945 0.3048)
			(end -0.120396 0.3048)
			(stroke
				(width 0.1)
				(type default)
			)
			(layer "B.Fab")
		)
		(fp_line
			(start -0.67945 -0.3048)
			(end -0.67945 0.3048)
			(stroke
				(width 0.1)
				(type default)
			)
			(layer "B.Fab")
		)
		(pad "1" smd circle
			(at 0.40005 0)
			(size 0 0)
			(layers "B.Cu" "B.Mask" "B.Paste")
			(net "GND")
		)
		(pad "2" smd circle
			(at -0.40005 0)
			(size 0 0)
			(layers "B.Cu" "B.Mask" "B.Paste")
			(net "CPU1_PWRGD_OUT")
		)
	)
	(footprint ""
		(layer "B.Cu")
		(at 172.593 -100.294948 -90)
		(property "Reference" "R6020"
			(at 0 0 90)
			(layer "B.SilkS")
			(hide yes)
			(effects
				(font
					(size 1.27 1.27)
				)
				(justify mirror)
			)
		)
		(property "Value" ""
			(at 0 0 90)
			(layer "B.Fab")
			(effects
				(font
					(size 1.27 1.27)
				)
				(justify mirror)
			)
		)
		(duplicate_pad_numbers_are_jumpers no)
		(fp_line
			(start -0.7874 0.4064)
			(end 0.7874 0.4064)
			(stroke
				(width 0.1524)
				(type default)
			)
			(layer "B.SilkS")
		)
		(fp_line
			(start 0.7874 0.4064)
			(end 0.7874 -0.4064)
			(stroke
				(width 0.1524)
				(type default)
			)
			(layer "B.SilkS")
		)
		(fp_line
			(start -0.7874 -0.4064)
			(end -0.7874 0.4064)
			(stroke
				(width 0.1524)
				(type default)
			)
			(layer "B.SilkS")
		)
		(fp_line
			(start 0.7874 -0.4064)
			(end -0.7874 -0.4064)
			(stroke
				(width 0.1524)
				(type default)
			)
			(layer "B.SilkS")
		)
		(fp_line
			(start -0.67945 0.3048)
			(end -0.120396 0.3048)
			(stroke
				(width 0.1)
				(type default)
			)
			(layer "B.Fab")
		)
		(fp_line
			(start -0.120396 0.3048)
			(end -0.120396 0.2794)
			(stroke
				(width 0.1)
				(type default)
			)
			(layer "B.Fab")
		)
		(fp_line
			(start 0.12065 0.3048)
			(end 0.67945 0.3048)
			(stroke
				(width 0.1)
				(type default)
			)
			(layer "B.Fab")
		)
		(fp_line
			(start 0.67945 0.3048)
			(end 0.67945 -0.305054)
			(stroke
				(width 0.1)
				(type default)
			)
			(layer "B.Fab")
		)
		(fp_line
			(start -0.120396 0.2794)
			(end 0.12065 0.2794)
			(stroke
				(width 0.1)
				(type default)
			)
			(layer "B.Fab")
		)
		(fp_line
			(start 0.12065 0.2794)
			(end 0.12065 0.3048)
			(stroke
				(width 0.1)
				(type default)
			)
			(layer "B.Fab")
		)
		(fp_line
			(start -0.12065 -0.2794)
			(end -0.12065 -0.3048)
			(stroke
				(width 0.1)
				(type default)
			)
			(layer "B.Fab")
		)
		(fp_line
			(start 0.12065 -0.2794)
			(end -0.12065 -0.2794)
			(stroke
				(width 0.1)
				(type default)
			)
			(layer "B.Fab")
		)
		(fp_line
			(start -0.67945 -0.3048)
			(end -0.67945 0.3048)
			(stroke
				(width 0.1)
				(type default)
			)
			(layer "B.Fab")
		)
		(fp_line
			(start -0.12065 -0.3048)
			(end -0.67945 -0.3048)
			(stroke
				(width 0.1)
				(type default)
			)
			(layer "B.Fab")
		)
		(fp_line
			(start 0.12065 -0.305054)
			(end 0.12065 -0.2794)
			(stroke
				(width 0.1)
				(type default)
			)
			(layer "B.Fab")
		)
		(fp_line
			(start 0.67945 -0.305054)
			(end 0.12065 -0.305054)
			(stroke
				(width 0.1)
				(type default)
			)
			(layer "B.Fab")
		)
		(pad "1" smd circle
			(at 0.40005 0 90)
			(size 0 0)
			(layers "B.Cu" "B.Mask" "B.Paste")
			(net "P3V3_AUX")
		)
		(pad "2" smd circle
			(at -0.40005 0 90)
			(size 0 0)
			(layers "B.Cu" "B.Mask" "B.Paste")
			(net "SGPIO_SCM_DO_<1>")
		)
	)
	(footprint ""
		(layer "B.Cu")
		(at 402.186394 -354.439728 -90)
		(property "Reference" "R6128"
			(at 0 0 90)
			(layer "B.SilkS")
			(hide yes)
			(effects
				(font
					(size 1.27 1.27)
				)
				(justify mirror)
			)
		)
		(property "Value" ""
			(at 0 0 90)
			(layer "B.Fab")
			(effects
				(font
					(size 1.27 1.27)
				)
				(justify mirror)
			)
		)
		(duplicate_pad_numbers_are_jumpers no)
		(fp_line
			(start -0.7874 0.4064)
			(end 0.7874 0.4064)
			(stroke
				(width 0.1524)
				(type default)
			)
			(layer "B.SilkS")
		)
		(fp_line
			(start 0.7874 0.4064)
			(end 0.7874 -0.4064)
			(stroke
				(width 0.1524)
				(type default)
			)
			(layer "B.SilkS")
		)
		(fp_line
			(start -0.7874 -0.4064)
			(end -0.7874 0.4064)
			(stroke
				(width 0.1524)
				(type default)
			)
			(layer "B.SilkS")
		)
		(fp_line
			(start 0.7874 -0.4064)
			(end -0.7874 -0.4064)
			(stroke
				(width 0.1524)
				(type default)
			)
			(layer "B.SilkS")
		)
		(fp_line
			(start -0.67945 0.3048)
			(end -0.120396 0.3048)
			(stroke
				(width 0.1)
				(type default)
			)
			(layer "B.Fab")
		)
		(fp_line
			(start -0.120396 0.3048)
			(end -0.120396 0.2794)
			(stroke
				(width 0.1)
				(type default)
			)
			(layer "B.Fab")
		)
		(fp_line
			(start 0.12065 0.3048)
			(end 0.67945 0.3048)
			(stroke
				(width 0.1)
				(type default)
			)
			(layer "B.Fab")
		)
		(fp_line
			(start 0.67945 0.3048)
			(end 0.67945 -0.305054)
			(stroke
				(width 0.1)
				(type default)
			)
			(layer "B.Fab")
		)
		(fp_line
			(start -0.120396 0.2794)
			(end 0.12065 0.2794)
			(stroke
				(width 0.1)
				(type default)
			)
			(layer "B.Fab")
		)
		(fp_line
			(start 0.12065 0.2794)
			(end 0.12065 0.3048)
			(stroke
				(width 0.1)
				(type default)
			)
			(layer "B.Fab")
		)
		(fp_line
			(start -0.12065 -0.2794)
			(end -0.12065 -0.3048)
			(stroke
				(width 0.1)
				(type default)
			)
			(layer "B.Fab")
		)
		(fp_line
			(start 0.12065 -0.2794)
			(end -0.12065 -0.2794)
			(stroke
				(width 0.1)
				(type default)
			)
			(layer "B.Fab")
		)
		(fp_line
			(start -0.67945 -0.3048)
			(end -0.67945 0.3048)
			(stroke
				(width 0.1)
				(type default)
			)
			(layer "B.Fab")
		)
		(fp_line
			(start -0.12065 -0.3048)
			(end -0.67945 -0.3048)
			(stroke
				(width 0.1)
				(type default)
			)
			(layer "B.Fab")
		)
		(fp_line
			(start 0.12065 -0.305054)
			(end 0.12065 -0.2794)
			(stroke
				(width 0.1)
				(type default)
			)
			(layer "B.Fab")
		)
		(fp_line
			(start 0.67945 -0.305054)
			(end 0.12065 -0.305054)
			(stroke
				(width 0.1)
				(type default)
			)
			(layer "B.Fab")
		)
		(pad "1" smd circle
			(at 0.40005 0 90)
			(size 0 0)
			(layers "B.Cu" "B.Mask" "B.Paste")
			(net "FM_BOARD_SKU_ID1")
		)
		(pad "2" smd circle
			(at -0.40005 0 90)
			(size 0 0)
			(layers "B.Cu" "B.Mask" "B.Paste")
			(net "GND")
		)
	)
	(footprint ""
		(layer "B.Cu")
		(at 487.620564 -306.87264 90)
		(property "Reference" "X9028"
			(at 4.62026 -1.55829 90)
			(unlocked yes)
			(layer "B.SilkS")
			(effects
				(font
					(size 0.7874 0.5842)
					(thickness 0.1524)
				)
				(justify left mirror)
			)
		)
		(property "Value" ""
			(at 0 0 90)
			(layer "B.Fab")
			(effects
				(font
					(size 1.27 1.27)
				)
				(justify mirror)
			)
		)
		(property "User Part Number" "N_A"
			(at -1.30175 1.27 0)
			(unlocked yes)
			(layer "Cmts.User")
			(hide yes)
			(effects
				(font
					(size 0.635 0.4064)
					(thickness 0.1524)
				)
				(justify mirror)
			)
		)
		(property "Device Type" "TP_TDR_4P_FTS_TH-TP_TDR_4P_DIP,EMPTY,TP15"
			(at -1.30175 1.27 0)
			(unlocked yes)
			(layer "B.Fab")
			(hide yes)
			(effects
				(font
					(size 0.635 0.4064)
					(thickness 0.1524)
				)
				(justify mirror)
			)
		)
		(duplicate_pad_numbers_are_jumpers no)
		(fp_line
			(start 0 -1.27)
			(end 0 -0.635)
			(stroke
				(width 0.1524)
				(type default)
			)
			(layer "B.SilkS")
		)
		(fp_line
			(start -2.54 -1.27)
			(end 0 -1.27)
			(stroke
				(width 0.1524)
				(type default)
			)
			(layer "B.SilkS")
		)
		(fp_line
			(start -2.54 -1.1303)
			(end -2.54 -1.27)
			(stroke
				(width 0.1524)
				(type default)
			)
			(layer "B.SilkS")
		)
		(fp_line
			(start 0 0.635)
			(end 0 1.905)
			(stroke
				(width 0.1524)
				(type default)
			)
			(layer "B.SilkS")
		)
		(fp_line
			(start -2.54 1.4097)
			(end -2.54 1.1303)
			(stroke
				(width 0.1524)
				(type default)
			)
			(layer "B.SilkS")
		)
		(fp_line
			(start 0 3.175)
			(end 0 3.81)
			(stroke
				(width 0.1524)
				(type default)
			)
			(layer "B.SilkS")
		)
		(fp_line
			(start 0 3.81)
			(end -2.54 3.81)
			(stroke
				(width 0.1524)
				(type default)
			)
			(layer "B.SilkS")
		)
		(fp_line
			(start -2.54 3.81)
			(end -2.54 3.6703)
			(stroke
				(width 0.1524)
				(type default)
			)
			(layer "B.SilkS")
		)
		(fp_poly
			(pts
				(xy 0.761746 0) (xy 2.285746 -0.762) (xy 2.285746 0.762)
			)
			(stroke
				(width 0)
				(type default)
			)
			(fill yes)
			(layer "B.SilkS")
		)
		(fp_line
			(start 0 -1.27)
			(end 0 3.81)
			(stroke
				(width 0.1)
				(type default)
			)
			(layer "B.Fab")
		)
		(fp_line
			(start -2.54 -1.27)
			(end 0 -1.27)
			(stroke
				(width 0.1)
				(type default)
			)
			(layer "B.Fab")
		)
		(fp_line
			(start 0 3.81)
			(end -2.54 3.81)
			(stroke
				(width 0.1)
				(type default)
			)
			(layer "B.Fab")
		)
		(fp_line
			(start -2.54 3.81)
			(end -2.54 -1.27)
			(stroke
				(width 0.1)
				(type default)
			)
			(layer "B.Fab")
		)
		(fp_poly
			(pts
				(xy 0.761746 0) (xy 2.285746 -0.762) (xy 2.285746 0.762)
			)
			(stroke
				(width 0)
				(type default)
			)
			(fill yes)
			(layer "B.Fab")
		)
		(pad "1" thru_hole circle
			(at 0 0 270)
			(size 1.0033 1.0033)
			(drill 0.249936)
			(layers "*.Cu" "*.Mask")
			(remove_unused_layers no)
			(net "TDR_DIFF_85_NECK_IN6_DN")
			(clearance 0.10795)
			(padstack
				(mode front_inner_back)
				(layer "Inner"
					(shape circle)
					(size 0.8001 0.8001)
					(clearance 0.1524)
				)
				(layer "B.Cu"
					(shape circle)
					(size 1.0033 1.0033)
					(thermal_gap 0.10795)
					(clearance 0.10795)
				)
			)
		)
		(pad "2" thru_hole circle
			(at -2.54 0 270)
			(size 1.9939 1.9939)
			(drill 0.249936)
			(layers "*.Cu" "*.Mask")
			(remove_unused_layers no)
			(net "T1_GND")
			(clearance 0.10795)
			(padstack
				(mode front_inner_back)
				(layer "Inner"
					(shape circle)
					(size 0.8001 0.8001)
					(clearance 0.1524)
				)
				(layer "B.Cu"
					(shape circle)
					(size 1.9939 1.9939)
					(thermal_gap 0.10795)
					(clearance 0.10795)
				)
			)
		)
		(pad "3" thru_hole circle
			(at -2.54 2.54 270)
			(size 1.9939 1.9939)
			(drill 0.249936)
			(layers "*.Cu" "*.Mask")
			(remove_unused_layers no)
			(net "T1_GND")
			(clearance 0.10795)
			(padstack
				(mode front_inner_back)
				(layer "Inner"
					(shape circle)
					(size 0.8001 0.8001)
					(clearance 0.1524)
				)
				(layer "B.Cu"
					(shape circle)
					(size 1.9939 1.9939)
					(thermal_gap 0.10795)
					(clearance 0.10795)
				)
			)
		)
		(pad "4" thru_hole circle
			(at 0 2.54 270)
			(size 1.0033 1.0033)
			(drill 0.249936)
			(layers "*.Cu" "*.Mask")
			(remove_unused_layers no)
			(net "TDR_DIFF_85_NECK_IN6_DP")
			(clearance 0.10795)
			(padstack
				(mode front_inner_back)
				(layer "Inner"
					(shape circle)
					(size 0.8001 0.8001)
					(clearance 0.1524)
				)
				(layer "B.Cu"
					(shape circle)
					(size 1.0033 1.0033)
					(thermal_gap 0.10795)
					(clearance 0.10795)
				)
			)
		)
	)
	(footprint ""
		(layer "B.Cu")
		(at 165.599618 -417.962588)
		(property "Reference" "R4120"
			(at 0 0 0)
			(layer "B.SilkS")
			(hide yes)
			(effects
				(font
					(size 1.27 1.27)
				)
				(justify mirror)
			)
		)
		(property "Value" ""
			(at 0 0 0)
			(layer "B.Fab")
			(effects
				(font
					(size 1.27 1.27)
				)
				(justify mirror)
			)
		)
		(duplicate_pad_numbers_are_jumpers no)
		(fp_line
			(start -0.7874 -0.4064)
			(end -0.7874 0.4064)
			(stroke
				(width 0.1524)
				(type default)
			)
			(layer "B.SilkS")
		)
		(fp_line
			(start -0.7874 0.4064)
			(end 0.7874 0.4064)
			(stroke
				(width 0.1524)
				(type default)
			)
			(layer "B.SilkS")
		)
		(fp_line
			(start 0.7874 -0.4064)
			(end -0.7874 -0.4064)
			(stroke
				(width 0.1524)
				(type default)
			)
			(layer "B.SilkS")
		)
		(fp_line
			(start 0.7874 0.4064)
			(end 0.7874 -0.4064)
			(stroke
				(width 0.1524)
				(type default)
			)
			(layer "B.SilkS")
		)
		(fp_line
			(start -0.67945 -0.3048)
			(end -0.67945 0.3048)
			(stroke
				(width 0.1)
				(type default)
			)
			(layer "B.Fab")
		)
		(fp_line
			(start -0.67945 0.3048)
			(end -0.120396 0.3048)
			(stroke
				(width 0.1)
				(type default)
			)
			(layer "B.Fab")
		)
		(fp_line
			(start -0.12065 -0.3048)
			(end -0.67945 -0.3048)
			(stroke
				(width 0.1)
				(type default)
			)
			(layer "B.Fab")
		)
		(fp_line
			(start -0.12065 -0.2794)
			(end -0.12065 -0.3048)
			(stroke
				(width 0.1)
				(type default)
			)
			(layer "B.Fab")
		)
		(fp_line
			(start -0.120396 0.2794)
			(end 0.12065 0.2794)
			(stroke
				(width 0.1)
				(type default)
			)
			(layer "B.Fab")
		)
		(fp_line
			(start -0.120396 0.3048)
			(end -0.120396 0.2794)
			(stroke
				(width 0.1)
				(type default)
			)
			(layer "B.Fab")
		)
		(fp_line
			(start 0.12065 -0.305054)
			(end 0.12065 -0.2794)
			(stroke
				(width 0.1)
				(type default)
			)
			(layer "B.Fab")
		)
		(fp_line
			(start 0.12065 -0.2794)
			(end -0.12065 -0.2794)
			(stroke
				(width 0.1)
				(type default)
			)
			(layer "B.Fab")
		)
		(fp_line
			(start 0.12065 0.2794)
			(end 0.12065 0.3048)
			(stroke
				(width 0.1)
				(type default)
			)
			(layer "B.Fab")
		)
		(fp_line
			(start 0.12065 0.3048)
			(end 0.67945 0.3048)
			(stroke
				(width 0.1)
				(type default)
			)
			(layer "B.Fab")
		)
		(fp_line
			(start 0.67945 -0.305054)
			(end 0.12065 -0.305054)
			(stroke
				(width 0.1)
				(type default)
			)
			(layer "B.Fab")
		)
		(fp_line
			(start 0.67945 0.3048)
			(end 0.67945 -0.305054)
			(stroke
				(width 0.1)
				(type default)
			)
			(layer "B.Fab")
		)
		(pad "1" smd circle
			(at 0.40005 0 180)
			(size 0 0)
			(layers "B.Cu" "B.Mask" "B.Paste")
			(net "GPU_3V3IO_RSVD0_FFU")
		)
		(pad "2" smd circle
			(at -0.40005 0 180)
			(size 0 0)
			(layers "B.Cu" "B.Mask" "B.Paste")
			(net "GND")
		)
	)
	(footprint ""
		(layer "B.Cu")
		(at 206.22133 -195.95211)
		(property "Reference" "R1711"
			(at 0 0 0)
			(layer "B.SilkS")
			(hide yes)
			(effects
				(font
					(size 1.27 1.27)
				)
				(justify mirror)
			)
		)
		(property "Value" ""
			(at 0 0 0)
			(layer "B.Fab")
			(effects
				(font
					(size 1.27 1.27)
				)
				(justify mirror)
			)
		)
		(duplicate_pad_numbers_are_jumpers no)
		(fp_line
			(start -0.7874 -0.4064)
			(end -0.7874 0.4064)
			(stroke
				(width 0.1524)
				(type default)
			)
			(layer "B.SilkS")
		)
		(fp_line
			(start -0.7874 0.4064)
			(end 0.7874 0.4064)
			(stroke
				(width 0.1524)
				(type default)
			)
			(layer "B.SilkS")
		)
		(fp_line
			(start 0.7874 -0.4064)
			(end -0.7874 -0.4064)
			(stroke
				(width 0.1524)
				(type default)
			)
			(layer "B.SilkS")
		)
		(fp_line
			(start 0.7874 0.4064)
			(end 0.7874 -0.4064)
			(stroke
				(width 0.1524)
				(type default)
			)
			(layer "B.SilkS")
		)
		(fp_line
			(start -0.67945 -0.3048)
			(end -0.67945 0.3048)
			(stroke
				(width 0.1)
				(type default)
			)
			(layer "B.Fab")
		)
		(fp_line
			(start -0.67945 0.3048)
			(end -0.120396 0.3048)
			(stroke
				(width 0.1)
				(type default)
			)
			(layer "B.Fab")
		)
		(fp_line
			(start -0.12065 -0.3048)
			(end -0.67945 -0.3048)
			(stroke
				(width 0.1)
				(type default)
			)
			(layer "B.Fab")
		)
		(fp_line
			(start -0.12065 -0.2794)
			(end -0.12065 -0.3048)
			(stroke
				(width 0.1)
				(type default)
			)
			(layer "B.Fab")
		)
		(fp_line
			(start -0.120396 0.2794)
			(end 0.12065 0.2794)
			(stroke
				(width 0.1)
				(type default)
			)
			(layer "B.Fab")
		)
		(fp_line
			(start -0.120396 0.3048)
			(end -0.120396 0.2794)
			(stroke
				(width 0.1)
				(type default)
			)
			(layer "B.Fab")
		)
		(fp_line
			(start 0.12065 -0.305054)
			(end 0.12065 -0.2794)
			(stroke
				(width 0.1)
				(type default)
			)
			(layer "B.Fab")
		)
		(fp_line
			(start 0.12065 -0.2794)
			(end -0.12065 -0.2794)
			(stroke
				(width 0.1)
				(type default)
			)
			(layer "B.Fab")
		)
		(fp_line
			(start 0.12065 0.2794)
			(end 0.12065 0.3048)
			(stroke
				(width 0.1)
				(type default)
			)
			(layer "B.Fab")
		)
		(fp_line
			(start 0.12065 0.3048)
			(end 0.67945 0.3048)
			(stroke
				(width 0.1)
				(type default)
			)
			(layer "B.Fab")
		)
		(fp_line
			(start 0.67945 -0.305054)
			(end 0.12065 -0.305054)
			(stroke
				(width 0.1)
				(type default)
			)
			(layer "B.Fab")
		)
		(fp_line
			(start 0.67945 0.3048)
			(end 0.67945 -0.305054)
			(stroke
				(width 0.1)
				(type default)
			)
			(layer "B.Fab")
		)
		(pad "1" smd circle
			(at 0.40005 0 180)
			(size 0 0)
			(layers "B.Cu" "B.Mask" "B.Paste")
			(net "I3C_SPD_DDRGL_CPU1_SDA")
		)
		(pad "2" smd circle
			(at -0.40005 0 180)
			(size 0 0)
			(layers "B.Cu" "B.Mask" "B.Paste")
			(net "I3C_SPD_DDRL_CPU1_SDA")
		)
	)
	(footprint ""
		(layer "B.Cu")
		(at 49.882044 -349.386398 -90)
		(property "Reference" "PR280"
			(at 0 0 90)
			(layer "B.SilkS")
			(hide yes)
			(effects
				(font
					(size 1.27 1.27)
				)
				(justify mirror)
			)
		)
		(property "Value" ""
			(at 0 0 90)
			(layer "B.Fab")
			(effects
				(font
					(size 1.27 1.27)
				)
				(justify mirror)
			)
		)
		(duplicate_pad_numbers_are_jumpers no)
		(fp_line
			(start -0.7874 0.4064)
			(end 0.7874 0.4064)
			(stroke
				(width 0.1524)
				(type default)
			)
			(layer "B.SilkS")
		)
		(fp_line
			(start 0.7874 0.4064)
			(end 0.7874 -0.4064)
			(stroke
				(width 0.1524)
				(type default)
			)
			(layer "B.SilkS")
		)
		(fp_line
			(start -0.7874 -0.4064)
			(end -0.7874 0.4064)
			(stroke
				(width 0.1524)
				(type default)
			)
			(layer "B.SilkS")
		)
		(fp_line
			(start 0.7874 -0.4064)
			(end -0.7874 -0.4064)
			(stroke
				(width 0.1524)
				(type default)
			)
			(layer "B.SilkS")
		)
		(fp_line
			(start -0.67945 0.3048)
			(end -0.120396 0.3048)
			(stroke
				(width 0.1)
				(type default)
			)
			(layer "B.Fab")
		)
		(fp_line
			(start -0.120396 0.3048)
			(end -0.120396 0.2794)
			(stroke
				(width 0.1)
				(type default)
			)
			(layer "B.Fab")
		)
		(fp_line
			(start 0.12065 0.3048)
			(end 0.67945 0.3048)
			(stroke
				(width 0.1)
				(type default)
			)
			(layer "B.Fab")
		)
		(fp_line
			(start 0.67945 0.3048)
			(end 0.67945 -0.305054)
			(stroke
				(width 0.1)
				(type default)
			)
			(layer "B.Fab")
		)
		(fp_line
			(start -0.120396 0.2794)
			(end 0.12065 0.2794)
			(stroke
				(width 0.1)
				(type default)
			)
			(layer "B.Fab")
		)
		(fp_line
			(start 0.12065 0.2794)
			(end 0.12065 0.3048)
			(stroke
				(width 0.1)
				(type default)
			)
			(layer "B.Fab")
		)
		(fp_line
			(start -0.12065 -0.2794)
			(end -0.12065 -0.3048)
			(stroke
				(width 0.1)
				(type default)
			)
			(layer "B.Fab")
		)
		(fp_line
			(start 0.12065 -0.2794)
			(end -0.12065 -0.2794)
			(stroke
				(width 0.1)
				(type default)
			)
			(layer "B.Fab")
		)
		(fp_line
			(start -0.67945 -0.3048)
			(end -0.67945 0.3048)
			(stroke
				(width 0.1)
				(type default)
			)
			(layer "B.Fab")
		)
		(fp_line
			(start -0.12065 -0.3048)
			(end -0.67945 -0.3048)
			(stroke
				(width 0.1)
				(type default)
			)
			(layer "B.Fab")
		)
		(fp_line
			(start 0.12065 -0.305054)
			(end 0.12065 -0.2794)
			(stroke
				(width 0.1)
				(type default)
			)
			(layer "B.Fab")
		)
		(fp_line
			(start 0.67945 -0.305054)
			(end 0.12065 -0.305054)
			(stroke
				(width 0.1)
				(type default)
			)
			(layer "B.Fab")
		)
		(pad "1" smd circle
			(at 0.40005 0 90)
			(size 0 0)
			(layers "B.Cu" "B.Mask" "B.Paste")
			(net "PVDDIO_P1_VOS1")
		)
		(pad "2" smd circle
			(at -0.40005 0 90)
			(size 0 0)
			(layers "B.Cu" "B.Mask" "B.Paste")
			(net "PVDDIO_P1")
		)
	)
	(footprint ""
		(layer "B.Cu")
		(at 419.140894 -427.594014 180)
		(property "Reference" "R841"
			(at 0 0 0)
			(layer "B.SilkS")
			(hide yes)
			(effects
				(font
					(size 1.27 1.27)
				)
				(justify mirror)
			)
		)
		(property "Value" ""
			(at 0 0 0)
			(layer "B.Fab")
			(effects
				(font
					(size 1.27 1.27)
				)
				(justify mirror)
			)
		)
		(duplicate_pad_numbers_are_jumpers no)
		(fp_line
			(start 0.32512 0.175006)
			(end 0.32512 -0.175006)
			(stroke
				(width 0.1)
				(type default)
			)
			(layer "B.Fab")
		)
		(fp_line
			(start 0.32512 -0.175006)
			(end -0.32512 -0.175006)
			(stroke
				(width 0.1)
				(type default)
			)
			(layer "B.Fab")
		)
		(fp_line
			(start -0.32512 0.175006)
			(end 0.32512 0.175006)
			(stroke
				(width 0.1)
				(type default)
			)
			(layer "B.Fab")
		)
		(fp_line
			(start -0.32512 -0.175006)
			(end -0.32512 0.175006)
			(stroke
				(width 0.1)
				(type default)
			)
			(layer "B.Fab")
		)
		(pad "1" smd rect
			(at 0.2667 0)
			(size 0.3048 0.381)
			(layers "B.Cu" "B.Mask" "B.Paste")
			(net "P1V8_CPU0_RT_1D")
		)
		(pad "2" smd rect
			(at -0.2667 0 180)
			(size 0.3048 0.381)
			(layers "B.Cu" "B.Mask" "B.Paste")
			(net "SMB_RT_CPU0_P2_ROM_R_SCL")
		)
	)
	(footprint ""
		(layer "B.Cu")
		(at 363.873288 -267.52931)
		(property "Reference" "C2204"
			(at 0 0 0)
			(layer "B.SilkS")
			(hide yes)
			(effects
				(font
					(size 1.27 1.27)
				)
				(justify mirror)
			)
		)
		(property "Value" ""
			(at 0 0 0)
			(layer "B.Fab")
			(effects
				(font
					(size 1.27 1.27)
				)
				(justify mirror)
			)
		)
		(duplicate_pad_numbers_are_jumpers no)
		(fp_line
			(start -0.7874 -0.4064)
			(end -0.7874 0.4064)
			(stroke
				(width 0.1524)
				(type default)
			)
			(layer "B.SilkS")
		)
		(fp_line
			(start -0.7874 0.4064)
			(end 0.7874 0.4064)
			(stroke
				(width 0.1524)
				(type default)
			)
			(layer "B.SilkS")
		)
		(fp_line
			(start 0.7874 -0.4064)
			(end -0.7874 -0.4064)
			(stroke
				(width 0.1524)
				(type default)
			)
			(layer "B.SilkS")
		)
		(fp_line
			(start 0.7874 0.4064)
			(end 0.7874 -0.4064)
			(stroke
				(width 0.1524)
				(type default)
			)
			(layer "B.SilkS")
		)
		(fp_line
			(start -0.67945 -0.3048)
			(end -0.67945 0.3048)
			(stroke
				(width 0.1)
				(type default)
			)
			(layer "B.Fab")
		)
		(fp_line
			(start -0.67945 0.3048)
			(end -0.120396 0.3048)
			(stroke
				(width 0.1)
				(type default)
			)
			(layer "B.Fab")
		)
		(fp_line
			(start -0.12065 -0.3048)
			(end -0.67945 -0.3048)
			(stroke
				(width 0.1)
				(type default)
			)
			(layer "B.Fab")
		)
		(fp_line
			(start -0.12065 -0.2794)
			(end -0.12065 -0.3048)
			(stroke
				(width 0.1)
				(type default)
			)
			(layer "B.Fab")
		)
		(fp_line
			(start -0.120396 0.2794)
			(end 0.12065 0.2794)
			(stroke
				(width 0.1)
				(type default)
			)
			(layer "B.Fab")
		)
		(fp_line
			(start -0.120396 0.3048)
			(end -0.120396 0.2794)
			(stroke
				(width 0.1)
				(type default)
			)
			(layer "B.Fab")
		)
		(fp_line
			(start 0.12065 -0.305054)
			(end 0.12065 -0.2794)
			(stroke
				(width 0.1)
				(type default)
			)
			(layer "B.Fab")
		)
		(fp_line
			(start 0.12065 -0.2794)
			(end -0.12065 -0.2794)
			(stroke
				(width 0.1)
				(type default)
			)
			(layer "B.Fab")
		)
		(fp_line
			(start 0.12065 0.2794)
			(end 0.12065 0.3048)
			(stroke
				(width 0.1)
				(type default)
			)
			(layer "B.Fab")
		)
		(fp_line
			(start 0.12065 0.3048)
			(end 0.67945 0.3048)
			(stroke
				(width 0.1)
				(type default)
			)
			(layer "B.Fab")
		)
		(fp_line
			(start 0.67945 -0.305054)
			(end 0.12065 -0.305054)
			(stroke
				(width 0.1)
				(type default)
			)
			(layer "B.Fab")
		)
		(fp_line
			(start 0.67945 0.3048)
			(end 0.67945 -0.305054)
			(stroke
				(width 0.1)
				(type default)
			)
			(layer "B.Fab")
		)
		(pad "1" smd circle
			(at 0.40005 0 180)
			(size 0 0)
			(layers "B.Cu" "B.Mask" "B.Paste")
			(net "PVDDCR_CPU1_P0")
		)
		(pad "2" smd circle
			(at -0.40005 0 180)
			(size 0 0)
			(layers "B.Cu" "B.Mask" "B.Paste")
			(net "GND")
		)
	)
	(footprint ""
		(layer "B.Cu")
		(at 463.172556 -389.126222 -90)
		(property "Reference" "PR6557"
			(at 0 0 90)
			(layer "B.SilkS")
			(hide yes)
			(effects
				(font
					(size 1.27 1.27)
				)
				(justify mirror)
			)
		)
		(property "Value" ""
			(at 0 0 90)
			(layer "B.Fab")
			(effects
				(font
					(size 1.27 1.27)
				)
				(justify mirror)
			)
		)
		(duplicate_pad_numbers_are_jumpers no)
		(fp_line
			(start -1.2954 0.5842)
			(end 1.2954 0.5842)
			(stroke
				(width 0.1524)
				(type default)
			)
			(layer "B.SilkS")
		)
		(fp_line
			(start 1.2954 0.5842)
			(end 1.2954 -0.5842)
			(stroke
				(width 0.1524)
				(type default)
			)
			(layer "B.SilkS")
		)
		(fp_line
			(start -1.2954 -0.5842)
			(end -1.2954 0.5842)
			(stroke
				(width 0.1524)
				(type default)
			)
			(layer "B.SilkS")
		)
		(fp_line
			(start 1.2954 -0.5842)
			(end -1.2954 -0.5842)
			(stroke
				(width 0.1524)
				(type default)
			)
			(layer "B.SilkS")
		)
		(fp_line
			(start -0.8636 0.4572)
			(end 0.8636 0.4572)
			(stroke
				(width 0.1)
				(type default)
			)
			(layer "B.Fab")
		)
		(fp_line
			(start 0.8636 0.4572)
			(end 0.8636 0.4318)
			(stroke
				(width 0.1)
				(type default)
			)
			(layer "B.Fab")
		)
		(fp_line
			(start 0.8636 0.4318)
			(end 0.8636 0.4064)
			(stroke
				(width 0.1)
				(type default)
			)
			(layer "B.Fab")
		)
		(fp_line
			(start -1.1938 0.4064)
			(end -0.8636 0.4064)
			(stroke
				(width 0.1)
				(type default)
			)
			(layer "B.Fab")
		)
		(fp_line
			(start -0.8636 0.4064)
			(end -0.8636 0.4572)
			(stroke
				(width 0.1)
				(type default)
			)
			(layer "B.Fab")
		)
		(fp_line
			(start 0.8636 0.4064)
			(end 1.1938 0.4064)
			(stroke
				(width 0.1)
				(type default)
			)
			(layer "B.Fab")
		)
		(fp_line
			(start 1.1938 0.4064)
			(end 1.1938 -0.406654)
			(stroke
				(width 0.1)
				(type default)
			)
			(layer "B.Fab")
		)
		(fp_line
			(start -1.1938 -0.406654)
			(end -1.1938 0.4064)
			(stroke
				(width 0.1)
				(type default)
			)
			(layer "B.Fab")
		)
		(fp_line
			(start -0.8636 -0.406654)
			(end -1.1938 -0.406654)
			(stroke
				(width 0.1)
				(type default)
			)
			(layer "B.Fab")
		)
		(fp_line
			(start 0.8636 -0.406654)
			(end 0.8636 -0.4572)
			(stroke
				(width 0.1)
				(type default)
			)
			(layer "B.Fab")
		)
		(fp_line
			(start 1.1938 -0.406654)
			(end 0.8636 -0.406654)
			(stroke
				(width 0.1)
				(type default)
			)
			(layer "B.Fab")
		)
		(fp_line
			(start -0.8636 -0.4572)
			(end -0.8636 -0.406654)
			(stroke
				(width 0.1)
				(type default)
			)
			(layer "B.Fab")
		)
		(fp_line
			(start 0.8636 -0.4572)
			(end -0.8636 -0.4572)
			(stroke
				(width 0.1)
				(type default)
			)
			(layer "B.Fab")
		)
		(pad "1" smd rect
			(at 0.7366 0 180)
			(size 0.7112 0.8128)
			(layers "B.Cu" "B.Mask" "B.Paste")
			(net "P0V9_CPU0_RT_2D")
		)
		(pad "2" smd rect
			(at -0.7366 0 180)
			(size 0.7112 0.8128)
			(layers "B.Cu" "B.Mask" "B.Paste")
			(net "GND")
		)
	)
	(footprint ""
		(layer "B.Cu")
		(at 407.010362 -416.899344 90)
		(property "Reference" "C6619"
			(at 0 0 90)
			(layer "B.SilkS")
			(hide yes)
			(effects
				(font
					(size 1.27 1.27)
				)
				(justify mirror)
			)
		)
		(property "Value" ""
			(at 0 0 90)
			(layer "B.Fab")
			(effects
				(font
					(size 1.27 1.27)
				)
				(justify mirror)
			)
		)
		(duplicate_pad_numbers_are_jumpers no)
		(fp_line
			(start 0.299974 -0.150114)
			(end -0.299974 -0.150114)
			(stroke
				(width 0.1)
				(type default)
			)
			(layer "B.Fab")
		)
		(fp_line
			(start -0.299974 -0.150114)
			(end -0.299974 0.150114)
			(stroke
				(width 0.1)
				(type default)
			)
			(layer "B.Fab")
		)
		(fp_line
			(start 0.299974 0.150114)
			(end 0.299974 -0.150114)
			(stroke
				(width 0.1)
				(type default)
			)
			(layer "B.Fab")
		)
		(fp_line
			(start -0.299974 0.150114)
			(end 0.299974 0.150114)
			(stroke
				(width 0.1)
				(type default)
			)
			(layer "B.Fab")
		)
		(pad "1" smd rect
			(at 0.2667 0 270)
			(size 0.3048 0.381)
			(layers "B.Cu" "B.Mask" "B.Paste")
			(net "P5E_CPU0_P3_TX_BUF_C_DP<11>")
		)
		(pad "2" smd rect
			(at -0.2667 0 270)
			(size 0.3048 0.381)
			(layers "B.Cu" "B.Mask" "B.Paste")
			(net "P5E_CPU0_P3_TX_BUF_DP<11>")
		)
	)
	(footprint ""
		(layer "B.Cu")
		(at 399.518124 -344.850212 90)
		(property "Reference" "C5000"
			(at 0 0 90)
			(layer "B.SilkS")
			(hide yes)
			(effects
				(font
					(size 1.27 1.27)
				)
				(justify mirror)
			)
		)
		(property "Value" ""
			(at 0 0 90)
			(layer "B.Fab")
			(effects
				(font
					(size 1.27 1.27)
				)
				(justify mirror)
			)
		)
		(duplicate_pad_numbers_are_jumpers no)
		(fp_line
			(start 0.7874 -0.4064)
			(end -0.7874 -0.4064)
			(stroke
				(width 0.1524)
				(type default)
			)
			(layer "B.SilkS")
		)
		(fp_line
			(start -0.7874 -0.4064)
			(end -0.7874 0.4064)
			(stroke
				(width 0.1524)
				(type default)
			)
			(layer "B.SilkS")
		)
		(fp_line
			(start 0.7874 0.4064)
			(end 0.7874 -0.4064)
			(stroke
				(width 0.1524)
				(type default)
			)
			(layer "B.SilkS")
		)
		(fp_line
			(start -0.7874 0.4064)
			(end 0.7874 0.4064)
			(stroke
				(width 0.1524)
				(type default)
			)
			(layer "B.SilkS")
		)
		(fp_line
			(start 0.67945 -0.305054)
			(end 0.12065 -0.305054)
			(stroke
				(width 0.1)
				(type default)
			)
			(layer "B.Fab")
		)
		(fp_line
			(start 0.12065 -0.305054)
			(end 0.12065 -0.2794)
			(stroke
				(width 0.1)
				(type default)
			)
			(layer "B.Fab")
		)
		(fp_line
			(start -0.12065 -0.3048)
			(end -0.67945 -0.3048)
			(stroke
				(width 0.1)
				(type default)
			)
			(layer "B.Fab")
		)
		(fp_line
			(start -0.67945 -0.3048)
			(end -0.67945 0.3048)
			(stroke
				(width 0.1)
				(type default)
			)
			(layer "B.Fab")
		)
		(fp_line
			(start 0.12065 -0.2794)
			(end -0.12065 -0.2794)
			(stroke
				(width 0.1)
				(type default)
			)
			(layer "B.Fab")
		)
		(fp_line
			(start -0.12065 -0.2794)
			(end -0.12065 -0.3048)
			(stroke
				(width 0.1)
				(type default)
			)
			(layer "B.Fab")
		)
		(fp_line
			(start 0.12065 0.2794)
			(end 0.12065 0.3048)
			(stroke
				(width 0.1)
				(type default)
			)
			(layer "B.Fab")
		)
		(fp_line
			(start -0.120396 0.2794)
			(end 0.12065 0.2794)
			(stroke
				(width 0.1)
				(type default)
			)
			(layer "B.Fab")
		)
		(fp_line
			(start 0.67945 0.3048)
			(end 0.67945 -0.305054)
			(stroke
				(width 0.1)
				(type default)
			)
			(layer "B.Fab")
		)
		(fp_line
			(start 0.12065 0.3048)
			(end 0.67945 0.3048)
			(stroke
				(width 0.1)
				(type default)
			)
			(layer "B.Fab")
		)
		(fp_line
			(start -0.120396 0.3048)
			(end -0.120396 0.2794)
			(stroke
				(width 0.1)
				(type default)
			)
			(layer "B.Fab")
		)
		(fp_line
			(start -0.67945 0.3048)
			(end -0.120396 0.3048)
			(stroke
				(width 0.1)
				(type default)
			)
			(layer "B.Fab")
		)
		(pad "1" smd circle
			(at 0.40005 0 270)
			(size 0 0)
			(layers "B.Cu" "B.Mask" "B.Paste")
			(net "FM_BIOS_POST_CMPLT_BUF_N")
		)
		(pad "2" smd circle
			(at -0.40005 0 270)
			(size 0 0)
			(layers "B.Cu" "B.Mask" "B.Paste")
			(net "GND")
		)
	)
	(footprint ""
		(layer "B.Cu")
		(at 177.673 -100.294948 -90)
		(property "Reference" "R1329"
			(at 0 0 90)
			(layer "B.SilkS")
			(hide yes)
			(effects
				(font
					(size 1.27 1.27)
				)
				(justify mirror)
			)
		)
		(property "Value" ""
			(at 0 0 90)
			(layer "B.Fab")
			(effects
				(font
					(size 1.27 1.27)
				)
				(justify mirror)
			)
		)
		(duplicate_pad_numbers_are_jumpers no)
		(fp_line
			(start -0.7874 0.4064)
			(end 0.7874 0.4064)
			(stroke
				(width 0.1524)
				(type default)
			)
			(layer "B.SilkS")
		)
		(fp_line
			(start 0.7874 0.4064)
			(end 0.7874 -0.4064)
			(stroke
				(width 0.1524)
				(type default)
			)
			(layer "B.SilkS")
		)
		(fp_line
			(start -0.7874 -0.4064)
			(end -0.7874 0.4064)
			(stroke
				(width 0.1524)
				(type default)
			)
			(layer "B.SilkS")
		)
		(fp_line
			(start 0.7874 -0.4064)
			(end -0.7874 -0.4064)
			(stroke
				(width 0.1524)
				(type default)
			)
			(layer "B.SilkS")
		)
		(fp_line
			(start -0.67945 0.3048)
			(end -0.120396 0.3048)
			(stroke
				(width 0.1)
				(type default)
			)
			(layer "B.Fab")
		)
		(fp_line
			(start -0.120396 0.3048)
			(end -0.120396 0.2794)
			(stroke
				(width 0.1)
				(type default)
			)
			(layer "B.Fab")
		)
		(fp_line
			(start 0.12065 0.3048)
			(end 0.67945 0.3048)
			(stroke
				(width 0.1)
				(type default)
			)
			(layer "B.Fab")
		)
		(fp_line
			(start 0.67945 0.3048)
			(end 0.67945 -0.305054)
			(stroke
				(width 0.1)
				(type default)
			)
			(layer "B.Fab")
		)
		(fp_line
			(start -0.120396 0.2794)
			(end 0.12065 0.2794)
			(stroke
				(width 0.1)
				(type default)
			)
			(layer "B.Fab")
		)
		(fp_line
			(start 0.12065 0.2794)
			(end 0.12065 0.3048)
			(stroke
				(width 0.1)
				(type default)
			)
			(layer "B.Fab")
		)
		(fp_line
			(start -0.12065 -0.2794)
			(end -0.12065 -0.3048)
			(stroke
				(width 0.1)
				(type default)
			)
			(layer "B.Fab")
		)
		(fp_line
			(start 0.12065 -0.2794)
			(end -0.12065 -0.2794)
			(stroke
				(width 0.1)
				(type default)
			)
			(layer "B.Fab")
		)
		(fp_line
			(start -0.67945 -0.3048)
			(end -0.67945 0.3048)
			(stroke
				(width 0.1)
				(type default)
			)
			(layer "B.Fab")
		)
		(fp_line
			(start -0.12065 -0.3048)
			(end -0.67945 -0.3048)
			(stroke
				(width 0.1)
				(type default)
			)
			(layer "B.Fab")
		)
		(fp_line
			(start 0.12065 -0.305054)
			(end 0.12065 -0.2794)
			(stroke
				(width 0.1)
				(type default)
			)
			(layer "B.Fab")
		)
		(fp_line
			(start 0.67945 -0.305054)
			(end 0.12065 -0.305054)
			(stroke
				(width 0.1)
				(type default)
			)
			(layer "B.Fab")
		)
		(pad "1" smd circle
			(at 0.40005 0 90)
			(size 0 0)
			(layers "B.Cu" "B.Mask" "B.Paste")
			(net "E1S_0_P3V3_P12V_ADC_R_ALERT")
		)
		(pad "2" smd circle
			(at -0.40005 0 90)
			(size 0 0)
			(layers "B.Cu" "B.Mask" "B.Paste")
			(net "E1S_0_P3V3_P12V_ADC_ALERT")
		)
	)
	(footprint ""
		(layer "B.Cu")
		(at 402.322538 -320.189352 180)
		(property "Reference" "R447"
			(at 0 0 0)
			(layer "B.SilkS")
			(hide yes)
			(effects
				(font
					(size 1.27 1.27)
				)
				(justify mirror)
			)
		)
		(property "Value" ""
			(at 0 0 0)
			(layer "B.Fab")
			(effects
				(font
					(size 1.27 1.27)
				)
				(justify mirror)
			)
		)
		(duplicate_pad_numbers_are_jumpers no)
		(fp_line
			(start 0.7874 0.4064)
			(end 0.7874 -0.4064)
			(stroke
				(width 0.1524)
				(type default)
			)
			(layer "B.SilkS")
		)
		(fp_line
			(start 0.7874 -0.4064)
			(end -0.7874 -0.4064)
			(stroke
				(width 0.1524)
				(type default)
			)
			(layer "B.SilkS")
		)
		(fp_line
			(start -0.7874 0.4064)
			(end 0.7874 0.4064)
			(stroke
				(width 0.1524)
				(type default)
			)
			(layer "B.SilkS")
		)
		(fp_line
			(start -0.7874 -0.4064)
			(end -0.7874 0.4064)
			(stroke
				(width 0.1524)
				(type default)
			)
			(layer "B.SilkS")
		)
		(fp_line
			(start 0.67945 0.3048)
			(end 0.67945 -0.305054)
			(stroke
				(width 0.1)
				(type default)
			)
			(layer "B.Fab")
		)
		(fp_line
			(start 0.67945 -0.305054)
			(end 0.12065 -0.305054)
			(stroke
				(width 0.1)
				(type default)
			)
			(layer "B.Fab")
		)
		(fp_line
			(start 0.12065 0.3048)
			(end 0.67945 0.3048)
			(stroke
				(width 0.1)
				(type default)
			)
			(layer "B.Fab")
		)
		(fp_line
			(start 0.12065 0.2794)
			(end 0.12065 0.3048)
			(stroke
				(width 0.1)
				(type default)
			)
			(layer "B.Fab")
		)
		(fp_line
			(start 0.12065 -0.2794)
			(end -0.12065 -0.2794)
			(stroke
				(width 0.1)
				(type default)
			)
			(layer "B.Fab")
		)
		(fp_line
			(start 0.12065 -0.305054)
			(end 0.12065 -0.2794)
			(stroke
				(width 0.1)
				(type default)
			)
			(layer "B.Fab")
		)
		(fp_line
			(start -0.120396 0.3048)
			(end -0.120396 0.2794)
			(stroke
				(width 0.1)
				(type default)
			)
			(layer "B.Fab")
		)
		(fp_line
			(start -0.120396 0.2794)
			(end 0.12065 0.2794)
			(stroke
				(width 0.1)
				(type default)
			)
			(layer "B.Fab")
		)
		(fp_line
			(start -0.12065 -0.2794)
			(end -0.12065 -0.3048)
			(stroke
				(width 0.1)
				(type default)
			)
			(layer "B.Fab")
		)
		(fp_line
			(start -0.12065 -0.3048)
			(end -0.67945 -0.3048)
			(stroke
				(width 0.1)
				(type default)
			)
			(layer "B.Fab")
		)
		(fp_line
			(start -0.67945 0.3048)
			(end -0.120396 0.3048)
			(stroke
				(width 0.1)
				(type default)
			)
			(layer "B.Fab")
		)
		(fp_line
			(start -0.67945 -0.3048)
			(end -0.67945 0.3048)
			(stroke
				(width 0.1)
				(type default)
			)
			(layer "B.Fab")
		)
		(pad "1" smd circle
			(at 0.40005 0)
			(size 0 0)
			(layers "B.Cu" "B.Mask" "B.Paste")
			(net "IRQ_TPM_SPI_R_N")
		)
		(pad "2" smd circle
			(at -0.40005 0)
			(size 0 0)
			(layers "B.Cu" "B.Mask" "B.Paste")
			(net "PVDD18_S5_P0")
		)
	)
	(footprint ""
		(layer "B.Cu")
		(at 20.480782 -410.564584 180)
		(property "Reference" "PR6811"
			(at 0 0 0)
			(layer "B.SilkS")
			(hide yes)
			(effects
				(font
					(size 1.27 1.27)
				)
				(justify mirror)
			)
		)
		(property "Value" ""
			(at 0 0 0)
			(layer "B.Fab")
			(effects
				(font
					(size 1.27 1.27)
				)
				(justify mirror)
			)
		)
		(duplicate_pad_numbers_are_jumpers no)
		(fp_line
			(start 0.7874 0.4064)
			(end 0.7874 -0.4064)
			(stroke
				(width 0.1524)
				(type default)
			)
			(layer "B.SilkS")
		)
		(fp_line
			(start 0.7874 -0.4064)
			(end -0.7874 -0.4064)
			(stroke
				(width 0.1524)
				(type default)
			)
			(layer "B.SilkS")
		)
		(fp_line
			(start -0.7874 0.4064)
			(end 0.7874 0.4064)
			(stroke
				(width 0.1524)
				(type default)
			)
			(layer "B.SilkS")
		)
		(fp_line
			(start -0.7874 -0.4064)
			(end -0.7874 0.4064)
			(stroke
				(width 0.1524)
				(type default)
			)
			(layer "B.SilkS")
		)
		(fp_line
			(start 0.67945 0.3048)
			(end 0.67945 -0.305054)
			(stroke
				(width 0.1)
				(type default)
			)
			(layer "B.Fab")
		)
		(fp_line
			(start 0.67945 -0.305054)
			(end 0.12065 -0.305054)
			(stroke
				(width 0.1)
				(type default)
			)
			(layer "B.Fab")
		)
		(fp_line
			(start 0.12065 0.3048)
			(end 0.67945 0.3048)
			(stroke
				(width 0.1)
				(type default)
			)
			(layer "B.Fab")
		)
		(fp_line
			(start 0.12065 0.2794)
			(end 0.12065 0.3048)
			(stroke
				(width 0.1)
				(type default)
			)
			(layer "B.Fab")
		)
		(fp_line
			(start 0.12065 -0.2794)
			(end -0.12065 -0.2794)
			(stroke
				(width 0.1)
				(type default)
			)
			(layer "B.Fab")
		)
		(fp_line
			(start 0.12065 -0.305054)
			(end 0.12065 -0.2794)
			(stroke
				(width 0.1)
				(type default)
			)
			(layer "B.Fab")
		)
		(fp_line
			(start -0.120396 0.3048)
			(end -0.120396 0.2794)
			(stroke
				(width 0.1)
				(type default)
			)
			(layer "B.Fab")
		)
		(fp_line
			(start -0.120396 0.2794)
			(end 0.12065 0.2794)
			(stroke
				(width 0.1)
				(type default)
			)
			(layer "B.Fab")
		)
		(fp_line
			(start -0.12065 -0.2794)
			(end -0.12065 -0.3048)
			(stroke
				(width 0.1)
				(type default)
			)
			(layer "B.Fab")
		)
		(fp_line
			(start -0.12065 -0.3048)
			(end -0.67945 -0.3048)
			(stroke
				(width 0.1)
				(type default)
			)
			(layer "B.Fab")
		)
		(fp_line
			(start -0.67945 0.3048)
			(end -0.120396 0.3048)
			(stroke
				(width 0.1)
				(type default)
			)
			(layer "B.Fab")
		)
		(fp_line
			(start -0.67945 -0.3048)
			(end -0.67945 0.3048)
			(stroke
				(width 0.1)
				(type default)
			)
			(layer "B.Fab")
		)
		(pad "1" smd circle
			(at 0.40005 0)
			(size 0 0)
			(layers "B.Cu" "B.Mask" "B.Paste")
			(net "P0V9_RETIMER_CPU1_SVID_CLK")
		)
		(pad "2" smd circle
			(at -0.40005 0)
			(size 0 0)
			(layers "B.Cu" "B.Mask" "B.Paste")
			(net "GND")
		)
	)
	(footprint ""
		(layer "B.Cu")
		(at 309.574184 -338.086446 -90)
		(property "Reference" "PC129_3"
			(at 0 0 90)
			(layer "B.SilkS")
			(hide yes)
			(effects
				(font
					(size 1.27 1.27)
				)
				(justify mirror)
			)
		)
		(property "Value" ""
			(at 0 0 90)
			(layer "B.Fab")
			(effects
				(font
					(size 1.27 1.27)
				)
				(justify mirror)
			)
		)
		(duplicate_pad_numbers_are_jumpers no)
		(fp_line
			(start -1.524 0.762)
			(end 1.524 0.762)
			(stroke
				(width 0.1524)
				(type default)
			)
			(layer "B.SilkS")
		)
		(fp_line
			(start 1.524 0.762)
			(end 1.524 -0.762)
			(stroke
				(width 0.1524)
				(type default)
			)
			(layer "B.SilkS")
		)
		(fp_line
			(start -1.524 -0.762)
			(end -1.524 0.762)
			(stroke
				(width 0.1524)
				(type default)
			)
			(layer "B.SilkS")
		)
		(fp_line
			(start 1.524 -0.762)
			(end -1.524 -0.762)
			(stroke
				(width 0.1524)
				(type default)
			)
			(layer "B.SilkS")
		)
		(fp_line
			(start -1.1049 0.724916)
			(end -1.1049 -0.724916)
			(stroke
				(width 0.1)
				(type default)
			)
			(layer "B.Fab")
		)
		(fp_line
			(start 1.1049 0.724916)
			(end -1.1049 0.724916)
			(stroke
				(width 0.1)
				(type default)
			)
			(layer "B.Fab")
		)
		(fp_line
			(start -1.1049 -0.724916)
			(end 1.1049 -0.724916)
			(stroke
				(width 0.1)
				(type default)
			)
			(layer "B.Fab")
		)
		(fp_line
			(start 1.1049 -0.724916)
			(end 1.1049 0.724916)
			(stroke
				(width 0.1)
				(type default)
			)
			(layer "B.Fab")
		)
		(pad "1" smd rect
			(at 0.889 0 270)
			(size 1.016 1.27)
			(layers "B.Cu" "B.Mask" "B.Paste")
			(net "PVDDCR_CPU1_P0")
		)
		(pad "2" smd rect
			(at -0.889 0 270)
			(size 1.016 1.27)
			(layers "B.Cu" "B.Mask" "B.Paste")
			(net "GND")
		)
	)
	(footprint ""
		(layer "B.Cu")
		(at 369.646454 -254.19431)
		(property "Reference" "C2586"
			(at 0 0 0)
			(layer "B.SilkS")
			(hide yes)
			(effects
				(font
					(size 1.27 1.27)
				)
				(justify mirror)
			)
		)
		(property "Value" ""
			(at 0 0 0)
			(layer "B.Fab")
			(effects
				(font
					(size 1.27 1.27)
				)
				(justify mirror)
			)
		)
		(duplicate_pad_numbers_are_jumpers no)
		(fp_line
			(start -0.7874 -0.4064)
			(end -0.7874 0.4064)
			(stroke
				(width 0.1524)
				(type default)
			)
			(layer "B.SilkS")
		)
		(fp_line
			(start -0.7874 0.4064)
			(end 0.7874 0.4064)
			(stroke
				(width 0.1524)
				(type default)
			)
			(layer "B.SilkS")
		)
		(fp_line
			(start 0.7874 -0.4064)
			(end -0.7874 -0.4064)
			(stroke
				(width 0.1524)
				(type default)
			)
			(layer "B.SilkS")
		)
		(fp_line
			(start 0.7874 0.4064)
			(end 0.7874 -0.4064)
			(stroke
				(width 0.1524)
				(type default)
			)
			(layer "B.SilkS")
		)
		(fp_line
			(start -0.67945 -0.3048)
			(end -0.67945 0.3048)
			(stroke
				(width 0.1)
				(type default)
			)
			(layer "B.Fab")
		)
		(fp_line
			(start -0.67945 0.3048)
			(end -0.120396 0.3048)
			(stroke
				(width 0.1)
				(type default)
			)
			(layer "B.Fab")
		)
		(fp_line
			(start -0.12065 -0.3048)
			(end -0.67945 -0.3048)
			(stroke
				(width 0.1)
				(type default)
			)
			(layer "B.Fab")
		)
		(fp_line
			(start -0.12065 -0.2794)
			(end -0.12065 -0.3048)
			(stroke
				(width 0.1)
				(type default)
			)
			(layer "B.Fab")
		)
		(fp_line
			(start -0.120396 0.2794)
			(end 0.12065 0.2794)
			(stroke
				(width 0.1)
				(type default)
			)
			(layer "B.Fab")
		)
		(fp_line
			(start -0.120396 0.3048)
			(end -0.120396 0.2794)
			(stroke
				(width 0.1)
				(type default)
			)
			(layer "B.Fab")
		)
		(fp_line
			(start 0.12065 -0.305054)
			(end 0.12065 -0.2794)
			(stroke
				(width 0.1)
				(type default)
			)
			(layer "B.Fab")
		)
		(fp_line
			(start 0.12065 -0.2794)
			(end -0.12065 -0.2794)
			(stroke
				(width 0.1)
				(type default)
			)
			(layer "B.Fab")
		)
		(fp_line
			(start 0.12065 0.2794)
			(end 0.12065 0.3048)
			(stroke
				(width 0.1)
				(type default)
			)
			(layer "B.Fab")
		)
		(fp_line
			(start 0.12065 0.3048)
			(end 0.67945 0.3048)
			(stroke
				(width 0.1)
				(type default)
			)
			(layer "B.Fab")
		)
		(fp_line
			(start 0.67945 -0.305054)
			(end 0.12065 -0.305054)
			(stroke
				(width 0.1)
				(type default)
			)
			(layer "B.Fab")
		)
		(fp_line
			(start 0.67945 0.3048)
			(end 0.67945 -0.305054)
			(stroke
				(width 0.1)
				(type default)
			)
			(layer "B.Fab")
		)
		(pad "1" smd circle
			(at 0.40005 0 180)
			(size 0 0)
			(layers "B.Cu" "B.Mask" "B.Paste")
			(net "PVDDCR_SOC_P0")
		)
		(pad "2" smd circle
			(at -0.40005 0 180)
			(size 0 0)
			(layers "B.Cu" "B.Mask" "B.Paste")
			(net "GND")
		)
	)
	(footprint ""
		(layer "B.Cu")
		(at 431.55616 -192.660016)
		(property "Reference" "C163"
			(at 0 0 0)
			(layer "B.SilkS")
			(hide yes)
			(effects
				(font
					(size 1.27 1.27)
				)
				(justify mirror)
			)
		)
		(property "Value" ""
			(at 0 0 0)
			(layer "B.Fab")
			(effects
				(font
					(size 1.27 1.27)
				)
				(justify mirror)
			)
		)
		(duplicate_pad_numbers_are_jumpers no)
		(fp_line
			(start -1.524 -0.762)
			(end -1.524 0.762)
			(stroke
				(width 0.1524)
				(type default)
			)
			(layer "B.SilkS")
		)
		(fp_line
			(start -1.524 0.762)
			(end 1.524 0.762)
			(stroke
				(width 0.1524)
				(type default)
			)
			(layer "B.SilkS")
		)
		(fp_line
			(start 1.524 -0.762)
			(end -1.524 -0.762)
			(stroke
				(width 0.1524)
				(type default)
			)
			(layer "B.SilkS")
		)
		(fp_line
			(start 1.524 0.762)
			(end 1.524 -0.762)
			(stroke
				(width 0.1524)
				(type default)
			)
			(layer "B.SilkS")
		)
		(fp_line
			(start -1.1049 -0.724916)
			(end 1.1049 -0.724916)
			(stroke
				(width 0.1)
				(type default)
			)
			(layer "B.Fab")
		)
		(fp_line
			(start -1.1049 0.724916)
			(end -1.1049 -0.724916)
			(stroke
				(width 0.1)
				(type default)
			)
			(layer "B.Fab")
		)
		(fp_line
			(start 1.1049 -0.724916)
			(end 1.1049 0.724916)
			(stroke
				(width 0.1)
				(type default)
			)
			(layer "B.Fab")
		)
		(fp_line
			(start 1.1049 0.724916)
			(end -1.1049 0.724916)
			(stroke
				(width 0.1)
				(type default)
			)
			(layer "B.Fab")
		)
		(pad "1" smd rect
			(at 0.889 0)
			(size 1.016 1.27)
			(layers "B.Cu" "B.Mask" "B.Paste")
			(net "P12V_MEM_CPU0")
		)
		(pad "2" smd rect
			(at -0.889 0)
			(size 1.016 1.27)
			(layers "B.Cu" "B.Mask" "B.Paste")
			(net "GND")
		)
	)
	(footprint ""
		(layer "B.Cu")
		(at 172.312838 -418.190426)
		(property "Reference" "R2812"
			(at 0 0 0)
			(layer "B.SilkS")
			(hide yes)
			(effects
				(font
					(size 1.27 1.27)
				)
				(justify mirror)
			)
		)
		(property "Value" ""
			(at 0 0 0)
			(layer "B.Fab")
			(effects
				(font
					(size 1.27 1.27)
				)
				(justify mirror)
			)
		)
		(duplicate_pad_numbers_are_jumpers no)
		(fp_line
			(start -0.7874 -0.4064)
			(end -0.7874 0.4064)
			(stroke
				(width 0.1524)
				(type default)
			)
			(layer "B.SilkS")
		)
		(fp_line
			(start -0.7874 0.4064)
			(end 0.7874 0.4064)
			(stroke
				(width 0.1524)
				(type default)
			)
			(layer "B.SilkS")
		)
		(fp_line
			(start 0.7874 -0.4064)
			(end -0.7874 -0.4064)
			(stroke
				(width 0.1524)
				(type default)
			)
			(layer "B.SilkS")
		)
		(fp_line
			(start 0.7874 0.4064)
			(end 0.7874 -0.4064)
			(stroke
				(width 0.1524)
				(type default)
			)
			(layer "B.SilkS")
		)
		(fp_line
			(start -0.67945 -0.3048)
			(end -0.67945 0.3048)
			(stroke
				(width 0.1)
				(type default)
			)
			(layer "B.Fab")
		)
		(fp_line
			(start -0.67945 0.3048)
			(end -0.120396 0.3048)
			(stroke
				(width 0.1)
				(type default)
			)
			(layer "B.Fab")
		)
		(fp_line
			(start -0.12065 -0.3048)
			(end -0.67945 -0.3048)
			(stroke
				(width 0.1)
				(type default)
			)
			(layer "B.Fab")
		)
		(fp_line
			(start -0.12065 -0.2794)
			(end -0.12065 -0.3048)
			(stroke
				(width 0.1)
				(type default)
			)
			(layer "B.Fab")
		)
		(fp_line
			(start -0.120396 0.2794)
			(end 0.12065 0.2794)
			(stroke
				(width 0.1)
				(type default)
			)
			(layer "B.Fab")
		)
		(fp_line
			(start -0.120396 0.3048)
			(end -0.120396 0.2794)
			(stroke
				(width 0.1)
				(type default)
			)
			(layer "B.Fab")
		)
		(fp_line
			(start 0.12065 -0.305054)
			(end 0.12065 -0.2794)
			(stroke
				(width 0.1)
				(type default)
			)
			(layer "B.Fab")
		)
		(fp_line
			(start 0.12065 -0.2794)
			(end -0.12065 -0.2794)
			(stroke
				(width 0.1)
				(type default)
			)
			(layer "B.Fab")
		)
		(fp_line
			(start 0.12065 0.2794)
			(end 0.12065 0.3048)
			(stroke
				(width 0.1)
				(type default)
			)
			(layer "B.Fab")
		)
		(fp_line
			(start 0.12065 0.3048)
			(end 0.67945 0.3048)
			(stroke
				(width 0.1)
				(type default)
			)
			(layer "B.Fab")
		)
		(fp_line
			(start 0.67945 -0.305054)
			(end 0.12065 -0.305054)
			(stroke
				(width 0.1)
				(type default)
			)
			(layer "B.Fab")
		)
		(fp_line
			(start 0.67945 0.3048)
			(end 0.67945 -0.305054)
			(stroke
				(width 0.1)
				(type default)
			)
			(layer "B.Fab")
		)
		(pad "1" smd circle
			(at 0.40005 0 180)
			(size 0 0)
			(layers "B.Cu" "B.Mask" "B.Paste")
			(net "SMB_FAN_3V3AUX_BUF_SDA")
		)
		(pad "2" smd circle
			(at -0.40005 0 180)
			(size 0 0)
			(layers "B.Cu" "B.Mask" "B.Paste")
			(net "SMB_FAN_3V3AUX_BUF_R_SDA")
		)
	)
	(footprint ""
		(layer "B.Cu")
		(at 250.07697 -45.461682 90)
		(property "Reference" "R3958"
			(at 0 0 90)
			(layer "B.SilkS")
			(hide yes)
			(effects
				(font
					(size 1.27 1.27)
				)
				(justify mirror)
			)
		)
		(property "Value" ""
			(at 0 0 90)
			(layer "B.Fab")
			(effects
				(font
					(size 1.27 1.27)
				)
				(justify mirror)
			)
		)
		(duplicate_pad_numbers_are_jumpers no)
		(fp_line
			(start 0.7874 -0.4064)
			(end -0.7874 -0.4064)
			(stroke
				(width 0.1524)
				(type default)
			)
			(layer "B.SilkS")
		)
		(fp_line
			(start -0.7874 -0.4064)
			(end -0.7874 0.4064)
			(stroke
				(width 0.1524)
				(type default)
			)
			(layer "B.SilkS")
		)
		(fp_line
			(start 0.7874 0.4064)
			(end 0.7874 -0.4064)
			(stroke
				(width 0.1524)
				(type default)
			)
			(layer "B.SilkS")
		)
		(fp_line
			(start -0.7874 0.4064)
			(end 0.7874 0.4064)
			(stroke
				(width 0.1524)
				(type default)
			)
			(layer "B.SilkS")
		)
		(fp_line
			(start 0.67945 -0.305054)
			(end 0.12065 -0.305054)
			(stroke
				(width 0.1)
				(type default)
			)
			(layer "B.Fab")
		)
		(fp_line
			(start 0.12065 -0.305054)
			(end 0.12065 -0.2794)
			(stroke
				(width 0.1)
				(type default)
			)
			(layer "B.Fab")
		)
		(fp_line
			(start -0.12065 -0.3048)
			(end -0.67945 -0.3048)
			(stroke
				(width 0.1)
				(type default)
			)
			(layer "B.Fab")
		)
		(fp_line
			(start -0.67945 -0.3048)
			(end -0.67945 0.3048)
			(stroke
				(width 0.1)
				(type default)
			)
			(layer "B.Fab")
		)
		(fp_line
			(start 0.12065 -0.2794)
			(end -0.12065 -0.2794)
			(stroke
				(width 0.1)
				(type default)
			)
			(layer "B.Fab")
		)
		(fp_line
			(start -0.12065 -0.2794)
			(end -0.12065 -0.3048)
			(stroke
				(width 0.1)
				(type default)
			)
			(layer "B.Fab")
		)
		(fp_line
			(start 0.12065 0.2794)
			(end 0.12065 0.3048)
			(stroke
				(width 0.1)
				(type default)
			)
			(layer "B.Fab")
		)
		(fp_line
			(start -0.120396 0.2794)
			(end 0.12065 0.2794)
			(stroke
				(width 0.1)
				(type default)
			)
			(layer "B.Fab")
		)
		(fp_line
			(start 0.67945 0.3048)
			(end 0.67945 -0.305054)
			(stroke
				(width 0.1)
				(type default)
			)
			(layer "B.Fab")
		)
		(fp_line
			(start 0.12065 0.3048)
			(end 0.67945 0.3048)
			(stroke
				(width 0.1)
				(type default)
			)
			(layer "B.Fab")
		)
		(fp_line
			(start -0.120396 0.3048)
			(end -0.120396 0.2794)
			(stroke
				(width 0.1)
				(type default)
			)
			(layer "B.Fab")
		)
		(fp_line
			(start -0.67945 0.3048)
			(end -0.120396 0.3048)
			(stroke
				(width 0.1)
				(type default)
			)
			(layer "B.Fab")
		)
		(pad "1" smd circle
			(at 0.40005 0 270)
			(size 0 0)
			(layers "B.Cu" "B.Mask" "B.Paste")
			(net "P12V_E1S_UV_0_R")
		)
		(pad "2" smd circle
			(at -0.40005 0 270)
			(size 0 0)
			(layers "B.Cu" "B.Mask" "B.Paste")
			(net "P12V_E1S_UV_0")
		)
	)
	(footprint ""
		(layer "B.Cu")
		(at 217.17 -332.74 180)
		(property "Reference" "R6776"
			(at 0 0 0)
			(layer "B.SilkS")
			(hide yes)
			(effects
				(font
					(size 1.27 1.27)
				)
				(justify mirror)
			)
		)
		(property "Value" ""
			(at 0 0 0)
			(layer "B.Fab")
			(effects
				(font
					(size 1.27 1.27)
				)
				(justify mirror)
			)
		)
		(duplicate_pad_numbers_are_jumpers no)
		(fp_line
			(start 0.32512 0.175006)
			(end 0.32512 -0.175006)
			(stroke
				(width 0.1)
				(type default)
			)
			(layer "B.Fab")
		)
		(fp_line
			(start 0.32512 -0.175006)
			(end -0.32512 -0.175006)
			(stroke
				(width 0.1)
				(type default)
			)
			(layer "B.Fab")
		)
		(fp_line
			(start -0.32512 0.175006)
			(end 0.32512 0.175006)
			(stroke
				(width 0.1)
				(type default)
			)
			(layer "B.Fab")
		)
		(fp_line
			(start -0.32512 -0.175006)
			(end -0.32512 0.175006)
			(stroke
				(width 0.1)
				(type default)
			)
			(layer "B.Fab")
		)
		(pad "1" smd rect
			(at 0.2667 0)
			(size 0.3048 0.381)
			(layers "B.Cu" "B.Mask" "B.Paste")
			(net "RST_SMB_RT_R1_N")
		)
		(pad "2" smd rect
			(at -0.2667 0 180)
			(size 0.3048 0.381)
			(layers "B.Cu" "B.Mask" "B.Paste")
			(net "RST_SMB_RT_N")
		)
	)
	(footprint ""
		(layer "B.Cu")
		(at 159.006286 -386.766562 90)
		(property "Reference" "C392"
			(at 0 0 90)
			(layer "B.SilkS")
			(hide yes)
			(effects
				(font
					(size 1.27 1.27)
				)
				(justify mirror)
			)
		)
		(property "Value" ""
			(at 0 0 90)
			(layer "B.Fab")
			(effects
				(font
					(size 1.27 1.27)
				)
				(justify mirror)
			)
		)
		(duplicate_pad_numbers_are_jumpers no)
		(fp_line
			(start 0.299974 -0.150114)
			(end -0.299974 -0.150114)
			(stroke
				(width 0.1)
				(type default)
			)
			(layer "B.Fab")
		)
		(fp_line
			(start -0.299974 -0.150114)
			(end -0.299974 0.150114)
			(stroke
				(width 0.1)
				(type default)
			)
			(layer "B.Fab")
		)
		(fp_line
			(start 0.299974 0.150114)
			(end 0.299974 -0.150114)
			(stroke
				(width 0.1)
				(type default)
			)
			(layer "B.Fab")
		)
		(fp_line
			(start -0.299974 0.150114)
			(end 0.299974 0.150114)
			(stroke
				(width 0.1)
				(type default)
			)
			(layer "B.Fab")
		)
		(pad "1" smd rect
			(at 0.2667 0 270)
			(size 0.3048 0.381)
			(layers "B.Cu" "B.Mask" "B.Paste")
			(net "P0V9_CPU1_RT_2D")
		)
		(pad "2" smd rect
			(at -0.2667 0 270)
			(size 0.3048 0.381)
			(layers "B.Cu" "B.Mask" "B.Paste")
			(net "GND")
		)
	)
	(footprint ""
		(layer "B.Cu")
		(at 96.842834 -306.701952 180)
		(property "Reference" "R1424"
			(at 0 0 0)
			(layer "B.SilkS")
			(hide yes)
			(effects
				(font
					(size 1.27 1.27)
				)
				(justify mirror)
			)
		)
		(property "Value" ""
			(at 0 0 0)
			(layer "B.Fab")
			(effects
				(font
					(size 1.27 1.27)
				)
				(justify mirror)
			)
		)
		(duplicate_pad_numbers_are_jumpers no)
		(fp_line
			(start 0.7874 0.4064)
			(end 0.7874 -0.4064)
			(stroke
				(width 0.1524)
				(type default)
			)
			(layer "B.SilkS")
		)
		(fp_line
			(start 0.7874 -0.4064)
			(end -0.7874 -0.4064)
			(stroke
				(width 0.1524)
				(type default)
			)
			(layer "B.SilkS")
		)
		(fp_line
			(start -0.7874 0.4064)
			(end 0.7874 0.4064)
			(stroke
				(width 0.1524)
				(type default)
			)
			(layer "B.SilkS")
		)
		(fp_line
			(start -0.7874 -0.4064)
			(end -0.7874 0.4064)
			(stroke
				(width 0.1524)
				(type default)
			)
			(layer "B.SilkS")
		)
		(fp_line
			(start 0.67945 0.3048)
			(end 0.67945 -0.305054)
			(stroke
				(width 0.1)
				(type default)
			)
			(layer "B.Fab")
		)
		(fp_line
			(start 0.67945 -0.305054)
			(end 0.12065 -0.305054)
			(stroke
				(width 0.1)
				(type default)
			)
			(layer "B.Fab")
		)
		(fp_line
			(start 0.12065 0.3048)
			(end 0.67945 0.3048)
			(stroke
				(width 0.1)
				(type default)
			)
			(layer "B.Fab")
		)
		(fp_line
			(start 0.12065 0.2794)
			(end 0.12065 0.3048)
			(stroke
				(width 0.1)
				(type default)
			)
			(layer "B.Fab")
		)
		(fp_line
			(start 0.12065 -0.2794)
			(end -0.12065 -0.2794)
			(stroke
				(width 0.1)
				(type default)
			)
			(layer "B.Fab")
		)
		(fp_line
			(start 0.12065 -0.305054)
			(end 0.12065 -0.2794)
			(stroke
				(width 0.1)
				(type default)
			)
			(layer "B.Fab")
		)
		(fp_line
			(start -0.120396 0.3048)
			(end -0.120396 0.2794)
			(stroke
				(width 0.1)
				(type default)
			)
			(layer "B.Fab")
		)
		(fp_line
			(start -0.120396 0.2794)
			(end 0.12065 0.2794)
			(stroke
				(width 0.1)
				(type default)
			)
			(layer "B.Fab")
		)
		(fp_line
			(start -0.12065 -0.2794)
			(end -0.12065 -0.3048)
			(stroke
				(width 0.1)
				(type default)
			)
			(layer "B.Fab")
		)
		(fp_line
			(start -0.12065 -0.3048)
			(end -0.67945 -0.3048)
			(stroke
				(width 0.1)
				(type default)
			)
			(layer "B.Fab")
		)
		(fp_line
			(start -0.67945 0.3048)
			(end -0.120396 0.3048)
			(stroke
				(width 0.1)
				(type default)
			)
			(layer "B.Fab")
		)
		(fp_line
			(start -0.67945 -0.3048)
			(end -0.67945 0.3048)
			(stroke
				(width 0.1)
				(type default)
			)
			(layer "B.Fab")
		)
		(pad "1" smd circle
			(at 0.40005 0)
			(size 0 0)
			(layers "B.Cu" "B.Mask" "B.Paste")
			(net "PVDD18_S5_P1")
		)
		(pad "2" smd circle
			(at -0.40005 0)
			(size 0 0)
			(layers "B.Cu" "B.Mask" "B.Paste")
			(net "INT_CPU1_HP_UBM_N")
		)
	)
	(footprint ""
		(layer "B.Cu")
		(at 84.811362 -336.037682 -90)
		(property "Reference" "PR256"
			(at 0 0 90)
			(layer "B.SilkS")
			(hide yes)
			(effects
				(font
					(size 1.27 1.27)
				)
				(justify mirror)
			)
		)
		(property "Value" ""
			(at 0 0 90)
			(layer "B.Fab")
			(effects
				(font
					(size 1.27 1.27)
				)
				(justify mirror)
			)
		)
		(duplicate_pad_numbers_are_jumpers no)
		(fp_line
			(start -0.7874 0.4064)
			(end 0.7874 0.4064)
			(stroke
				(width 0.1524)
				(type default)
			)
			(layer "B.SilkS")
		)
		(fp_line
			(start 0.7874 0.4064)
			(end 0.7874 -0.4064)
			(stroke
				(width 0.1524)
				(type default)
			)
			(layer "B.SilkS")
		)
		(fp_line
			(start -0.7874 -0.4064)
			(end -0.7874 0.4064)
			(stroke
				(width 0.1524)
				(type default)
			)
			(layer "B.SilkS")
		)
		(fp_line
			(start 0.7874 -0.4064)
			(end -0.7874 -0.4064)
			(stroke
				(width 0.1524)
				(type default)
			)
			(layer "B.SilkS")
		)
		(fp_line
			(start -0.67945 0.3048)
			(end -0.120396 0.3048)
			(stroke
				(width 0.1)
				(type default)
			)
			(layer "B.Fab")
		)
		(fp_line
			(start -0.120396 0.3048)
			(end -0.120396 0.2794)
			(stroke
				(width 0.1)
				(type default)
			)
			(layer "B.Fab")
		)
		(fp_line
			(start 0.12065 0.3048)
			(end 0.67945 0.3048)
			(stroke
				(width 0.1)
				(type default)
			)
			(layer "B.Fab")
		)
		(fp_line
			(start 0.67945 0.3048)
			(end 0.67945 -0.305054)
			(stroke
				(width 0.1)
				(type default)
			)
			(layer "B.Fab")
		)
		(fp_line
			(start -0.120396 0.2794)
			(end 0.12065 0.2794)
			(stroke
				(width 0.1)
				(type default)
			)
			(layer "B.Fab")
		)
		(fp_line
			(start 0.12065 0.2794)
			(end 0.12065 0.3048)
			(stroke
				(width 0.1)
				(type default)
			)
			(layer "B.Fab")
		)
		(fp_line
			(start -0.12065 -0.2794)
			(end -0.12065 -0.3048)
			(stroke
				(width 0.1)
				(type default)
			)
			(layer "B.Fab")
		)
		(fp_line
			(start 0.12065 -0.2794)
			(end -0.12065 -0.2794)
			(stroke
				(width 0.1)
				(type default)
			)
			(layer "B.Fab")
		)
		(fp_line
			(start -0.67945 -0.3048)
			(end -0.67945 0.3048)
			(stroke
				(width 0.1)
				(type default)
			)
			(layer "B.Fab")
		)
		(fp_line
			(start -0.12065 -0.3048)
			(end -0.67945 -0.3048)
			(stroke
				(width 0.1)
				(type default)
			)
			(layer "B.Fab")
		)
		(fp_line
			(start 0.12065 -0.305054)
			(end 0.12065 -0.2794)
			(stroke
				(width 0.1)
				(type default)
			)
			(layer "B.Fab")
		)
		(fp_line
			(start 0.67945 -0.305054)
			(end 0.12065 -0.305054)
			(stroke
				(width 0.1)
				(type default)
			)
			(layer "B.Fab")
		)
		(pad "1" smd circle
			(at 0.40005 0 90)
			(size 0 0)
			(layers "B.Cu" "B.Mask" "B.Paste")
			(net "PVDDCR_CPU1_P1_PVCC")
		)
		(pad "2" smd circle
			(at -0.40005 0 90)
			(size 0 0)
			(layers "B.Cu" "B.Mask" "B.Paste")
			(net "PVDDCR_CPU1_P1_VCC1")
		)
	)
	(footprint ""
		(layer "B.Cu")
		(at 420.407338 -172.290232 90)
		(property "Reference" "PR334"
			(at 0 0 90)
			(layer "B.SilkS")
			(hide yes)
			(effects
				(font
					(size 1.27 1.27)
				)
				(justify mirror)
			)
		)
		(property "Value" ""
			(at 0 0 90)
			(layer "B.Fab")
			(effects
				(font
					(size 1.27 1.27)
				)
				(justify mirror)
			)
		)
		(duplicate_pad_numbers_are_jumpers no)
		(fp_line
			(start 0.7874 -0.4064)
			(end -0.7874 -0.4064)
			(stroke
				(width 0.1524)
				(type default)
			)
			(layer "B.SilkS")
		)
		(fp_line
			(start -0.7874 -0.4064)
			(end -0.7874 0.4064)
			(stroke
				(width 0.1524)
				(type default)
			)
			(layer "B.SilkS")
		)
		(fp_line
			(start 0.7874 0.4064)
			(end 0.7874 -0.4064)
			(stroke
				(width 0.1524)
				(type default)
			)
			(layer "B.SilkS")
		)
		(fp_line
			(start -0.7874 0.4064)
			(end 0.7874 0.4064)
			(stroke
				(width 0.1524)
				(type default)
			)
			(layer "B.SilkS")
		)
		(fp_line
			(start 0.67945 -0.305054)
			(end 0.12065 -0.305054)
			(stroke
				(width 0.1)
				(type default)
			)
			(layer "B.Fab")
		)
		(fp_line
			(start 0.12065 -0.305054)
			(end 0.12065 -0.2794)
			(stroke
				(width 0.1)
				(type default)
			)
			(layer "B.Fab")
		)
		(fp_line
			(start -0.12065 -0.3048)
			(end -0.67945 -0.3048)
			(stroke
				(width 0.1)
				(type default)
			)
			(layer "B.Fab")
		)
		(fp_line
			(start -0.67945 -0.3048)
			(end -0.67945 0.3048)
			(stroke
				(width 0.1)
				(type default)
			)
			(layer "B.Fab")
		)
		(fp_line
			(start 0.12065 -0.2794)
			(end -0.12065 -0.2794)
			(stroke
				(width 0.1)
				(type default)
			)
			(layer "B.Fab")
		)
		(fp_line
			(start -0.12065 -0.2794)
			(end -0.12065 -0.3048)
			(stroke
				(width 0.1)
				(type default)
			)
			(layer "B.Fab")
		)
		(fp_line
			(start 0.12065 0.2794)
			(end 0.12065 0.3048)
			(stroke
				(width 0.1)
				(type default)
			)
			(layer "B.Fab")
		)
		(fp_line
			(start -0.120396 0.2794)
			(end 0.12065 0.2794)
			(stroke
				(width 0.1)
				(type default)
			)
			(layer "B.Fab")
		)
		(fp_line
			(start 0.67945 0.3048)
			(end 0.67945 -0.305054)
			(stroke
				(width 0.1)
				(type default)
			)
			(layer "B.Fab")
		)
		(fp_line
			(start 0.12065 0.3048)
			(end 0.67945 0.3048)
			(stroke
				(width 0.1)
				(type default)
			)
			(layer "B.Fab")
		)
		(fp_line
			(start -0.120396 0.3048)
			(end -0.120396 0.2794)
			(stroke
				(width 0.1)
				(type default)
			)
			(layer "B.Fab")
		)
		(fp_line
			(start -0.67945 0.3048)
			(end -0.120396 0.3048)
			(stroke
				(width 0.1)
				(type default)
			)
			(layer "B.Fab")
		)
		(pad "1" smd circle
			(at 0.40005 0 270)
			(size 0 0)
			(layers "B.Cu" "B.Mask" "B.Paste")
			(net "PVDDCR_SOC_P0")
		)
		(pad "2" smd circle
			(at -0.40005 0 270)
			(size 0 0)
			(layers "B.Cu" "B.Mask" "B.Paste")
			(net "GND")
		)
	)
	(footprint ""
		(layer "B.Cu")
		(at 162.73018 -20.056094 90)
		(property "Reference" "R6036"
			(at 0 0 90)
			(layer "B.SilkS")
			(hide yes)
			(effects
				(font
					(size 1.27 1.27)
				)
				(justify mirror)
			)
		)
		(property "Value" ""
			(at 0 0 90)
			(layer "B.Fab")
			(effects
				(font
					(size 1.27 1.27)
				)
				(justify mirror)
			)
		)
		(duplicate_pad_numbers_are_jumpers no)
		(fp_line
			(start 0.7874 -0.4064)
			(end -0.7874 -0.4064)
			(stroke
				(width 0.1524)
				(type default)
			)
			(layer "B.SilkS")
		)
		(fp_line
			(start -0.7874 -0.4064)
			(end -0.7874 0.4064)
			(stroke
				(width 0.1524)
				(type default)
			)
			(layer "B.SilkS")
		)
		(fp_line
			(start 0.7874 0.4064)
			(end 0.7874 -0.4064)
			(stroke
				(width 0.1524)
				(type default)
			)
			(layer "B.SilkS")
		)
		(fp_line
			(start -0.7874 0.4064)
			(end 0.7874 0.4064)
			(stroke
				(width 0.1524)
				(type default)
			)
			(layer "B.SilkS")
		)
		(fp_line
			(start 0.67945 -0.305054)
			(end 0.12065 -0.305054)
			(stroke
				(width 0.1)
				(type default)
			)
			(layer "B.Fab")
		)
		(fp_line
			(start 0.12065 -0.305054)
			(end 0.12065 -0.2794)
			(stroke
				(width 0.1)
				(type default)
			)
			(layer "B.Fab")
		)
		(fp_line
			(start -0.12065 -0.3048)
			(end -0.67945 -0.3048)
			(stroke
				(width 0.1)
				(type default)
			)
			(layer "B.Fab")
		)
		(fp_line
			(start -0.67945 -0.3048)
			(end -0.67945 0.3048)
			(stroke
				(width 0.1)
				(type default)
			)
			(layer "B.Fab")
		)
		(fp_line
			(start 0.12065 -0.2794)
			(end -0.12065 -0.2794)
			(stroke
				(width 0.1)
				(type default)
			)
			(layer "B.Fab")
		)
		(fp_line
			(start -0.12065 -0.2794)
			(end -0.12065 -0.3048)
			(stroke
				(width 0.1)
				(type default)
			)
			(layer "B.Fab")
		)
		(fp_line
			(start 0.12065 0.2794)
			(end 0.12065 0.3048)
			(stroke
				(width 0.1)
				(type default)
			)
			(layer "B.Fab")
		)
		(fp_line
			(start -0.120396 0.2794)
			(end 0.12065 0.2794)
			(stroke
				(width 0.1)
				(type default)
			)
			(layer "B.Fab")
		)
		(fp_line
			(start 0.67945 0.3048)
			(end 0.67945 -0.305054)
			(stroke
				(width 0.1)
				(type default)
			)
			(layer "B.Fab")
		)
		(fp_line
			(start 0.12065 0.3048)
			(end 0.67945 0.3048)
			(stroke
				(width 0.1)
				(type default)
			)
			(layer "B.Fab")
		)
		(fp_line
			(start -0.120396 0.3048)
			(end -0.120396 0.2794)
			(stroke
				(width 0.1)
				(type default)
			)
			(layer "B.Fab")
		)
		(fp_line
			(start -0.67945 0.3048)
			(end -0.120396 0.3048)
			(stroke
				(width 0.1)
				(type default)
			)
			(layer "B.Fab")
		)
		(pad "1" smd circle
			(at 0.40005 0 270)
			(size 0 0)
			(layers "B.Cu" "B.Mask" "B.Paste")
			(net "SMB_1_PLD_3V3AUX_SCL")
		)
		(pad "2" smd circle
			(at -0.40005 0 270)
			(size 0 0)
			(layers "B.Cu" "B.Mask" "B.Paste")
			(net "P3V3_AUX")
		)
	)
	(footprint ""
		(layer "B.Cu")
		(at 213.253066 -325.456296)
		(property "Reference" "C1094"
			(at 0 0 0)
			(layer "B.SilkS")
			(hide yes)
			(effects
				(font
					(size 1.27 1.27)
				)
				(justify mirror)
			)
		)
		(property "Value" ""
			(at 0 0 0)
			(layer "B.Fab")
			(effects
				(font
					(size 1.27 1.27)
				)
				(justify mirror)
			)
		)
		(duplicate_pad_numbers_are_jumpers no)
		(fp_line
			(start -0.7874 -0.4064)
			(end -0.7874 0.4064)
			(stroke
				(width 0.1524)
				(type default)
			)
			(layer "B.SilkS")
		)
		(fp_line
			(start -0.7874 0.4064)
			(end 0.7874 0.4064)
			(stroke
				(width 0.1524)
				(type default)
			)
			(layer "B.SilkS")
		)
		(fp_line
			(start 0.7874 -0.4064)
			(end -0.7874 -0.4064)
			(stroke
				(width 0.1524)
				(type default)
			)
			(layer "B.SilkS")
		)
		(fp_line
			(start 0.7874 0.4064)
			(end 0.7874 -0.4064)
			(stroke
				(width 0.1524)
				(type default)
			)
			(layer "B.SilkS")
		)
		(fp_line
			(start -0.67945 -0.3048)
			(end -0.67945 0.3048)
			(stroke
				(width 0.1)
				(type default)
			)
			(layer "B.Fab")
		)
		(fp_line
			(start -0.67945 0.3048)
			(end -0.120396 0.3048)
			(stroke
				(width 0.1)
				(type default)
			)
			(layer "B.Fab")
		)
		(fp_line
			(start -0.12065 -0.3048)
			(end -0.67945 -0.3048)
			(stroke
				(width 0.1)
				(type default)
			)
			(layer "B.Fab")
		)
		(fp_line
			(start -0.12065 -0.2794)
			(end -0.12065 -0.3048)
			(stroke
				(width 0.1)
				(type default)
			)
			(layer "B.Fab")
		)
		(fp_line
			(start -0.120396 0.2794)
			(end 0.12065 0.2794)
			(stroke
				(width 0.1)
				(type default)
			)
			(layer "B.Fab")
		)
		(fp_line
			(start -0.120396 0.3048)
			(end -0.120396 0.2794)
			(stroke
				(width 0.1)
				(type default)
			)
			(layer "B.Fab")
		)
		(fp_line
			(start 0.12065 -0.305054)
			(end 0.12065 -0.2794)
			(stroke
				(width 0.1)
				(type default)
			)
			(layer "B.Fab")
		)
		(fp_line
			(start 0.12065 -0.2794)
			(end -0.12065 -0.2794)
			(stroke
				(width 0.1)
				(type default)
			)
			(layer "B.Fab")
		)
		(fp_line
			(start 0.12065 0.2794)
			(end 0.12065 0.3048)
			(stroke
				(width 0.1)
				(type default)
			)
			(layer "B.Fab")
		)
		(fp_line
			(start 0.12065 0.3048)
			(end 0.67945 0.3048)
			(stroke
				(width 0.1)
				(type default)
			)
			(layer "B.Fab")
		)
		(fp_line
			(start 0.67945 -0.305054)
			(end 0.12065 -0.305054)
			(stroke
				(width 0.1)
				(type default)
			)
			(layer "B.Fab")
		)
		(fp_line
			(start 0.67945 0.3048)
			(end 0.67945 -0.305054)
			(stroke
				(width 0.1)
				(type default)
			)
			(layer "B.Fab")
		)
		(pad "1" smd circle
			(at 0.40005 0 180)
			(size 0 0)
			(layers "B.Cu" "B.Mask" "B.Paste")
			(net "P3V3_ADC128_2_VCC")
		)
		(pad "2" smd circle
			(at -0.40005 0 180)
			(size 0 0)
			(layers "B.Cu" "B.Mask" "B.Paste")
			(net "GND")
		)
	)
	(footprint ""
		(layer "B.Cu")
		(at 334.69707 -328.219054 -90)
		(property "Reference" "PC103"
			(at 10.084054 -0.93726 270)
			(unlocked yes)
			(layer "B.SilkS")
			(effects
				(font
					(size 0.7874 0.5842)
					(thickness 0.1524)
				)
				(justify left mirror)
			)
		)
		(property "Value" ""
			(at 0 0 90)
			(layer "B.Fab")
			(effects
				(font
					(size 1.27 1.27)
				)
				(justify mirror)
			)
		)
		(duplicate_pad_numbers_are_jumpers no)
		(fp_line
			(start -4.533392 2.249932)
			(end 4.533392 2.249932)
			(stroke
				(width 0.1524)
				(type default)
			)
			(layer "B.SilkS")
		)
		(fp_line
			(start 4.533392 2.249932)
			(end 4.533392 -2.249932)
			(stroke
				(width 0.1524)
				(type default)
			)
			(layer "B.SilkS")
		)
		(fp_line
			(start -4.533392 -2.249932)
			(end -4.533392 2.249932)
			(stroke
				(width 0.1524)
				(type default)
			)
			(layer "B.SilkS")
		)
		(fp_line
			(start 4.533392 -2.249932)
			(end -4.533392 -2.249932)
			(stroke
				(width 0.1524)
				(type default)
			)
			(layer "B.SilkS")
		)
		(fp_rect
			(start 5.39242 2.326132)
			(end 4.533392 -2.326132)
			(stroke
				(width 0)
				(type default)
			)
			(fill yes)
			(layer "B.SilkS")
		)
		(fp_line
			(start -3.750056 2.249932)
			(end 3.750056 2.249932)
			(stroke
				(width 0.1)
				(type default)
			)
			(layer "B.Fab")
		)
		(fp_line
			(start 3.750056 2.249932)
			(end 3.750056 -2.249932)
			(stroke
				(width 0.1)
				(type default)
			)
			(layer "B.Fab")
		)
		(fp_line
			(start -3.750056 -2.249932)
			(end -3.750056 2.249932)
			(stroke
				(width 0.1)
				(type default)
			)
			(layer "B.Fab")
		)
		(fp_line
			(start 3.750056 -2.249932)
			(end -3.750056 -2.249932)
			(stroke
				(width 0.1)
				(type default)
			)
			(layer "B.Fab")
		)
		(fp_text user "+"
			(at 6.381242 0.548386 180)
			(unlocked yes)
			(layer "B.SilkS")
			(effects
				(font
					(size 1.905 1.4224)
					(thickness 0.1524)
				)
				(justify left mirror)
			)
		)
		(fp_text user "-"
			(at -4.8514 -0.14605 270)
			(unlocked yes)
			(layer "B.SilkS")
			(effects
				(font
					(size 1.905 1.4224)
					(thickness 0.1524)
				)
				(justify left mirror)
			)
		)
		(fp_text user "+"
			(at 6.322314 0.786384 180)
			(unlocked yes)
			(layer "B.Fab")
			(effects
				(font
					(size 1.905 1.4224)
					(thickness 0.1524)
				)
				(justify left mirror)
			)
		)
		(fp_text user "-"
			(at -4.8514 -0.14605 270)
			(unlocked yes)
			(layer "B.Fab")
			(effects
				(font
					(size 1.905 1.4224)
					(thickness 0.1524)
				)
				(justify left mirror)
			)
		)
		(pad "1" smd rect
			(at 3.199892 0 90)
			(size 2.413 2.8194)
			(layers "B.Cu" "B.Mask" "B.Paste")
			(net "PVDDCR_CPU1_P0")
		)
		(pad "2" smd rect
			(at -3.199892 0 90)
			(size 2.413 2.8194)
			(layers "B.Cu" "B.Mask" "B.Paste")
			(net "GND")
		)
	)
	(footprint ""
		(layer "B.Cu")
		(at 341.918798 -398.942052 90)
		(property "Reference" "C651"
			(at 0 0 90)
			(layer "B.SilkS")
			(hide yes)
			(effects
				(font
					(size 1.27 1.27)
				)
				(justify mirror)
			)
		)
		(property "Value" ""
			(at 0 0 90)
			(layer "B.Fab")
			(effects
				(font
					(size 1.27 1.27)
				)
				(justify mirror)
			)
		)
		(duplicate_pad_numbers_are_jumpers no)
		(fp_line
			(start 0.7874 -0.4064)
			(end -0.7874 -0.4064)
			(stroke
				(width 0.1524)
				(type default)
			)
			(layer "B.SilkS")
		)
		(fp_line
			(start -0.7874 -0.4064)
			(end -0.7874 0.4064)
			(stroke
				(width 0.1524)
				(type default)
			)
			(layer "B.SilkS")
		)
		(fp_line
			(start 0.7874 0.4064)
			(end 0.7874 -0.4064)
			(stroke
				(width 0.1524)
				(type default)
			)
			(layer "B.SilkS")
		)
		(fp_line
			(start -0.7874 0.4064)
			(end 0.7874 0.4064)
			(stroke
				(width 0.1524)
				(type default)
			)
			(layer "B.SilkS")
		)
		(fp_line
			(start 0.67945 -0.305054)
			(end 0.12065 -0.305054)
			(stroke
				(width 0.1)
				(type default)
			)
			(layer "B.Fab")
		)
		(fp_line
			(start 0.12065 -0.305054)
			(end 0.12065 -0.2794)
			(stroke
				(width 0.1)
				(type default)
			)
			(layer "B.Fab")
		)
		(fp_line
			(start -0.12065 -0.3048)
			(end -0.67945 -0.3048)
			(stroke
				(width 0.1)
				(type default)
			)
			(layer "B.Fab")
		)
		(fp_line
			(start -0.67945 -0.3048)
			(end -0.67945 0.3048)
			(stroke
				(width 0.1)
				(type default)
			)
			(layer "B.Fab")
		)
		(fp_line
			(start 0.12065 -0.2794)
			(end -0.12065 -0.2794)
			(stroke
				(width 0.1)
				(type default)
			)
			(layer "B.Fab")
		)
		(fp_line
			(start -0.12065 -0.2794)
			(end -0.12065 -0.3048)
			(stroke
				(width 0.1)
				(type default)
			)
			(layer "B.Fab")
		)
		(fp_line
			(start 0.12065 0.2794)
			(end 0.12065 0.3048)
			(stroke
				(width 0.1)
				(type default)
			)
			(layer "B.Fab")
		)
		(fp_line
			(start -0.120396 0.2794)
			(end 0.12065 0.2794)
			(stroke
				(width 0.1)
				(type default)
			)
			(layer "B.Fab")
		)
		(fp_line
			(start 0.67945 0.3048)
			(end 0.67945 -0.305054)
			(stroke
				(width 0.1)
				(type default)
			)
			(layer "B.Fab")
		)
		(fp_line
			(start 0.12065 0.3048)
			(end 0.67945 0.3048)
			(stroke
				(width 0.1)
				(type default)
			)
			(layer "B.Fab")
		)
		(fp_line
			(start -0.120396 0.3048)
			(end -0.120396 0.2794)
			(stroke
				(width 0.1)
				(type default)
			)
			(layer "B.Fab")
		)
		(fp_line
			(start -0.67945 0.3048)
			(end -0.120396 0.3048)
			(stroke
				(width 0.1)
				(type default)
			)
			(layer "B.Fab")
		)
		(pad "1" smd circle
			(at 0.40005 0 270)
			(size 0 0)
			(layers "B.Cu" "B.Mask" "B.Paste")
			(net "P0V9_CPU0_RT_2D")
		)
		(pad "2" smd circle
			(at -0.40005 0 270)
			(size 0 0)
			(layers "B.Cu" "B.Mask" "B.Paste")
			(net "GND")
		)
	)
	(footprint ""
		(layer "B.Cu")
		(at 304.419 -359.283 180)
		(property "Reference" "R8065"
			(at 0 0 0)
			(layer "B.SilkS")
			(hide yes)
			(effects
				(font
					(size 1.27 1.27)
				)
				(justify mirror)
			)
		)
		(property "Value" ""
			(at 0 0 0)
			(layer "B.Fab")
			(effects
				(font
					(size 1.27 1.27)
				)
				(justify mirror)
			)
		)
		(duplicate_pad_numbers_are_jumpers no)
		(fp_line
			(start 0.7874 0.4064)
			(end 0.7874 -0.4064)
			(stroke
				(width 0.1524)
				(type default)
			)
			(layer "B.SilkS")
		)
		(fp_line
			(start 0.7874 -0.4064)
			(end -0.7874 -0.4064)
			(stroke
				(width 0.1524)
				(type default)
			)
			(layer "B.SilkS")
		)
		(fp_line
			(start -0.7874 0.4064)
			(end 0.7874 0.4064)
			(stroke
				(width 0.1524)
				(type default)
			)
			(layer "B.SilkS")
		)
		(fp_line
			(start -0.7874 -0.4064)
			(end -0.7874 0.4064)
			(stroke
				(width 0.1524)
				(type default)
			)
			(layer "B.SilkS")
		)
		(fp_line
			(start 0.67945 0.3048)
			(end 0.67945 -0.305054)
			(stroke
				(width 0.1)
				(type default)
			)
			(layer "B.Fab")
		)
		(fp_line
			(start 0.67945 -0.305054)
			(end 0.12065 -0.305054)
			(stroke
				(width 0.1)
				(type default)
			)
			(layer "B.Fab")
		)
		(fp_line
			(start 0.12065 0.3048)
			(end 0.67945 0.3048)
			(stroke
				(width 0.1)
				(type default)
			)
			(layer "B.Fab")
		)
		(fp_line
			(start 0.12065 0.2794)
			(end 0.12065 0.3048)
			(stroke
				(width 0.1)
				(type default)
			)
			(layer "B.Fab")
		)
		(fp_line
			(start 0.12065 -0.2794)
			(end -0.12065 -0.2794)
			(stroke
				(width 0.1)
				(type default)
			)
			(layer "B.Fab")
		)
		(fp_line
			(start 0.12065 -0.305054)
			(end 0.12065 -0.2794)
			(stroke
				(width 0.1)
				(type default)
			)
			(layer "B.Fab")
		)
		(fp_line
			(start -0.120396 0.3048)
			(end -0.120396 0.2794)
			(stroke
				(width 0.1)
				(type default)
			)
			(layer "B.Fab")
		)
		(fp_line
			(start -0.120396 0.2794)
			(end 0.12065 0.2794)
			(stroke
				(width 0.1)
				(type default)
			)
			(layer "B.Fab")
		)
		(fp_line
			(start -0.12065 -0.2794)
			(end -0.12065 -0.3048)
			(stroke
				(width 0.1)
				(type default)
			)
			(layer "B.Fab")
		)
		(fp_line
			(start -0.12065 -0.3048)
			(end -0.67945 -0.3048)
			(stroke
				(width 0.1)
				(type default)
			)
			(layer "B.Fab")
		)
		(fp_line
			(start -0.67945 0.3048)
			(end -0.120396 0.3048)
			(stroke
				(width 0.1)
				(type default)
			)
			(layer "B.Fab")
		)
		(fp_line
			(start -0.67945 -0.3048)
			(end -0.67945 0.3048)
			(stroke
				(width 0.1)
				(type default)
			)
			(layer "B.Fab")
		)
		(pad "1" smd circle
			(at 0.40005 0)
			(size 0 0)
			(layers "B.Cu" "B.Mask" "B.Paste")
			(net "P3V3_AUX")
		)
		(pad "2" smd circle
			(at -0.40005 0)
			(size 0 0)
			(layers "B.Cu" "B.Mask" "B.Paste")
			(net "PWRGD_PVDDIO_P0_R")
		)
	)
	(footprint ""
		(layer "B.Cu")
		(at 373.976646 -424.523916)
		(property "Reference" "U17"
			(at 1.562354 -3.185414 0)
			(unlocked yes)
			(layer "B.SilkS")
			(effects
				(font
					(size 0.7874 0.5842)
					(thickness 0.1524)
				)
				(justify left mirror)
			)
		)
		(property "Value" ""
			(at 0 0 0)
			(layer "B.Fab")
			(effects
				(font
					(size 1.27 1.27)
				)
				(justify mirror)
			)
		)
		(duplicate_pad_numbers_are_jumpers no)
		(fp_line
			(start -1.8288 -2.500122)
			(end -1.077722 -2.500122)
			(stroke
				(width 0.1524)
				(type default)
			)
			(layer "B.SilkS")
		)
		(fp_line
			(start -1.8288 2.500122)
			(end -1.8288 -2.500122)
			(stroke
				(width 0.1524)
				(type default)
			)
			(layer "B.SilkS")
		)
		(fp_line
			(start -1.077722 -2.500122)
			(end 0 -1.4224)
			(stroke
				(width 0.1524)
				(type default)
			)
			(layer "B.SilkS")
		)
		(fp_line
			(start 0 -1.4224)
			(end 1.077722 -2.500122)
			(stroke
				(width 0.1524)
				(type default)
			)
			(layer "B.SilkS")
		)
		(fp_line
			(start 1.077722 -2.500122)
			(end 1.8288 -2.500122)
			(stroke
				(width 0.1524)
				(type default)
			)
			(layer "B.SilkS")
		)
		(fp_line
			(start 1.8288 -2.500122)
			(end 1.8288 2.500122)
			(stroke
				(width 0.1524)
				(type default)
			)
			(layer "B.SilkS")
		)
		(fp_line
			(start 1.8288 2.500122)
			(end -1.8288 2.500122)
			(stroke
				(width 0.1524)
				(type default)
			)
			(layer "B.SilkS")
		)
		(fp_poly
			(pts
				(xy 2.107438 -3.61823) (xy 3.123438 -3.61823) (xy 2.615438 -2.60223)
			)
			(stroke
				(width 0)
				(type default)
			)
			(fill yes)
			(layer "B.SilkS")
		)
		(fp_line
			(start -1.999996 -2.500122)
			(end 1.999996 -2.500122)
			(stroke
				(width 0.1)
				(type default)
			)
			(layer "B.Fab")
		)
		(fp_line
			(start -1.999996 2.500122)
			(end -1.999996 -2.500122)
			(stroke
				(width 0.1)
				(type default)
			)
			(layer "B.Fab")
		)
		(fp_line
			(start 1.999996 -2.500122)
			(end 1.999996 2.500122)
			(stroke
				(width 0.1)
				(type default)
			)
			(layer "B.Fab")
		)
		(fp_line
			(start 1.999996 2.500122)
			(end -1.999996 2.500122)
			(stroke
				(width 0.1)
				(type default)
			)
			(layer "B.Fab")
		)
		(fp_poly
			(pts
				(xy 4.5085 -2.413) (xy 4.5085 -1.397) (xy 3.4925 -1.905)
			)
			(stroke
				(width 0)
				(type default)
			)
			(fill yes)
			(layer "B.Fab")
		)
		(pad "1" smd rect
			(at 2.599944 -1.905 270)
			(size 0.889 1.27)
			(layers "B.Cu" "B.Mask" "B.Paste")
			(net "Net_10839")
		)
		(pad "2" smd rect
			(at 2.599944 -0.635 270)
			(size 0.889 1.27)
			(layers "B.Cu" "B.Mask" "B.Paste")
			(net "Net_10838")
		)
		(pad "3" smd rect
			(at 2.599944 0.635 270)
			(size 0.889 1.27)
			(layers "B.Cu" "B.Mask" "B.Paste")
			(net "U17_E2")
		)
		(pad "4" smd rect
			(at 2.599944 1.905 270)
			(size 0.889 1.27)
			(layers "B.Cu" "B.Mask" "B.Paste")
			(net "GND")
		)
		(pad "5" smd rect
			(at -2.599944 1.905 270)
			(size 0.889 1.27)
			(layers "B.Cu" "B.Mask" "B.Paste")
			(net "SMB_RT_CPU0_P3_ROM_SDA")
		)
		(pad "6" smd rect
			(at -2.599944 0.635 270)
			(size 0.889 1.27)
			(layers "B.Cu" "B.Mask" "B.Paste")
			(net "SMB_RT_CPU0_P3_ROM_SCL")
		)
		(pad "7" smd rect
			(at -2.599944 -0.635 270)
			(size 0.889 1.27)
			(layers "B.Cu" "B.Mask" "B.Paste")
			(net "GND")
		)
		(pad "8" smd rect
			(at -2.599944 -1.905 270)
			(size 0.889 1.27)
			(layers "B.Cu" "B.Mask" "B.Paste")
			(net "P1V8_CPU0_RT_1D")
		)
	)
	(footprint ""
		(layer "B.Cu")
		(at 336.046064 -396.393162 -90)
		(property "Reference" "C657"
			(at 0 0 90)
			(layer "B.SilkS")
			(hide yes)
			(effects
				(font
					(size 1.27 1.27)
				)
				(justify mirror)
			)
		)
		(property "Value" ""
			(at 0 0 90)
			(layer "B.Fab")
			(effects
				(font
					(size 1.27 1.27)
				)
				(justify mirror)
			)
		)
		(duplicate_pad_numbers_are_jumpers no)
		(fp_line
			(start -0.299974 0.150114)
			(end 0.299974 0.150114)
			(stroke
				(width 0.1)
				(type default)
			)
			(layer "B.Fab")
		)
		(fp_line
			(start 0.299974 0.150114)
			(end 0.299974 -0.150114)
			(stroke
				(width 0.1)
				(type default)
			)
			(layer "B.Fab")
		)
		(fp_line
			(start -0.299974 -0.150114)
			(end -0.299974 0.150114)
			(stroke
				(width 0.1)
				(type default)
			)
			(layer "B.Fab")
		)
		(fp_line
			(start 0.299974 -0.150114)
			(end -0.299974 -0.150114)
			(stroke
				(width 0.1)
				(type default)
			)
			(layer "B.Fab")
		)
		(pad "1" smd rect
			(at 0.2667 0 90)
			(size 0.3048 0.381)
			(layers "B.Cu" "B.Mask" "B.Paste")
			(net "P0V9_CPU0_RT1_2A")
		)
		(pad "2" smd rect
			(at -0.2667 0 90)
			(size 0.3048 0.381)
			(layers "B.Cu" "B.Mask" "B.Paste")
			(net "GND")
		)
	)
	(footprint ""
		(layer "B.Cu")
		(at 117.314726 -408.517344 90)
		(property "Reference" "C6725"
			(at 0 0 90)
			(layer "B.SilkS")
			(hide yes)
			(effects
				(font
					(size 1.27 1.27)
				)
				(justify mirror)
			)
		)
		(property "Value" ""
			(at 0 0 90)
			(layer "B.Fab")
			(effects
				(font
					(size 1.27 1.27)
				)
				(justify mirror)
			)
		)
		(duplicate_pad_numbers_are_jumpers no)
		(fp_line
			(start 0.299974 -0.150114)
			(end -0.299974 -0.150114)
			(stroke
				(width 0.1)
				(type default)
			)
			(layer "B.Fab")
		)
		(fp_line
			(start -0.299974 -0.150114)
			(end -0.299974 0.150114)
			(stroke
				(width 0.1)
				(type default)
			)
			(layer "B.Fab")
		)
		(fp_line
			(start 0.299974 0.150114)
			(end 0.299974 -0.150114)
			(stroke
				(width 0.1)
				(type default)
			)
			(layer "B.Fab")
		)
		(fp_line
			(start -0.299974 0.150114)
			(end 0.299974 0.150114)
			(stroke
				(width 0.1)
				(type default)
			)
			(layer "B.Fab")
		)
		(pad "1" smd rect
			(at 0.2667 0 270)
			(size 0.3048 0.381)
			(layers "B.Cu" "B.Mask" "B.Paste")
			(net "P5E_CPU1_P3_TX_BUF_C_DP<0>")
		)
		(pad "2" smd rect
			(at -0.2667 0 270)
			(size 0.3048 0.381)
			(layers "B.Cu" "B.Mask" "B.Paste")
			(net "P5E_CPU1_P3_TX_BUF_DP<0>")
		)
	)
	(footprint ""
		(layer "B.Cu")
		(at 153.975054 -313.96305 90)
		(property "Reference" "R575"
			(at 0 0 90)
			(layer "B.SilkS")
			(hide yes)
			(effects
				(font
					(size 1.27 1.27)
				)
				(justify mirror)
			)
		)
		(property "Value" ""
			(at 0 0 90)
			(layer "B.Fab")
			(effects
				(font
					(size 1.27 1.27)
				)
				(justify mirror)
			)
		)
		(duplicate_pad_numbers_are_jumpers no)
		(fp_line
			(start 0.7874 -0.4064)
			(end -0.7874 -0.4064)
			(stroke
				(width 0.1524)
				(type default)
			)
			(layer "B.SilkS")
		)
		(fp_line
			(start -0.7874 -0.4064)
			(end -0.7874 0.4064)
			(stroke
				(width 0.1524)
				(type default)
			)
			(layer "B.SilkS")
		)
		(fp_line
			(start 0.7874 0.4064)
			(end 0.7874 -0.4064)
			(stroke
				(width 0.1524)
				(type default)
			)
			(layer "B.SilkS")
		)
		(fp_line
			(start -0.7874 0.4064)
			(end 0.7874 0.4064)
			(stroke
				(width 0.1524)
				(type default)
			)
			(layer "B.SilkS")
		)
		(fp_line
			(start 0.67945 -0.305054)
			(end 0.12065 -0.305054)
			(stroke
				(width 0.1)
				(type default)
			)
			(layer "B.Fab")
		)
		(fp_line
			(start 0.12065 -0.305054)
			(end 0.12065 -0.2794)
			(stroke
				(width 0.1)
				(type default)
			)
			(layer "B.Fab")
		)
		(fp_line
			(start -0.12065 -0.3048)
			(end -0.67945 -0.3048)
			(stroke
				(width 0.1)
				(type default)
			)
			(layer "B.Fab")
		)
		(fp_line
			(start -0.67945 -0.3048)
			(end -0.67945 0.3048)
			(stroke
				(width 0.1)
				(type default)
			)
			(layer "B.Fab")
		)
		(fp_line
			(start 0.12065 -0.2794)
			(end -0.12065 -0.2794)
			(stroke
				(width 0.1)
				(type default)
			)
			(layer "B.Fab")
		)
		(fp_line
			(start -0.12065 -0.2794)
			(end -0.12065 -0.3048)
			(stroke
				(width 0.1)
				(type default)
			)
			(layer "B.Fab")
		)
		(fp_line
			(start 0.12065 0.2794)
			(end 0.12065 0.3048)
			(stroke
				(width 0.1)
				(type default)
			)
			(layer "B.Fab")
		)
		(fp_line
			(start -0.120396 0.2794)
			(end 0.12065 0.2794)
			(stroke
				(width 0.1)
				(type default)
			)
			(layer "B.Fab")
		)
		(fp_line
			(start 0.67945 0.3048)
			(end 0.67945 -0.305054)
			(stroke
				(width 0.1)
				(type default)
			)
			(layer "B.Fab")
		)
		(fp_line
			(start 0.12065 0.3048)
			(end 0.67945 0.3048)
			(stroke
				(width 0.1)
				(type default)
			)
			(layer "B.Fab")
		)
		(fp_line
			(start -0.120396 0.3048)
			(end -0.120396 0.2794)
			(stroke
				(width 0.1)
				(type default)
			)
			(layer "B.Fab")
		)
		(fp_line
			(start -0.67945 0.3048)
			(end -0.120396 0.3048)
			(stroke
				(width 0.1)
				(type default)
			)
			(layer "B.Fab")
		)
		(pad "1" smd circle
			(at 0.40005 0 270)
			(size 0 0)
			(layers "B.Cu" "B.Mask" "B.Paste")
			(net "XTAL_CPU1_R_X32K_X2")
		)
		(pad "2" smd circle
			(at -0.40005 0 270)
			(size 0 0)
			(layers "B.Cu" "B.Mask" "B.Paste")
			(net "XTAL_CPU1_X32K_X2")
		)
	)
	(footprint ""
		(layer "B.Cu")
		(at 129.305304 -34.670492)
		(property "Reference" "C6081"
			(at 0 0 0)
			(layer "B.SilkS")
			(hide yes)
			(effects
				(font
					(size 1.27 1.27)
				)
				(justify mirror)
			)
		)
		(property "Value" ""
			(at 0 0 0)
			(layer "B.Fab")
			(effects
				(font
					(size 1.27 1.27)
				)
				(justify mirror)
			)
		)
		(duplicate_pad_numbers_are_jumpers no)
		(fp_line
			(start -0.7874 -0.4064)
			(end -0.7874 0.4064)
			(stroke
				(width 0.1524)
				(type default)
			)
			(layer "B.SilkS")
		)
		(fp_line
			(start -0.7874 0.4064)
			(end 0.7874 0.4064)
			(stroke
				(width 0.1524)
				(type default)
			)
			(layer "B.SilkS")
		)
		(fp_line
			(start 0.7874 -0.4064)
			(end -0.7874 -0.4064)
			(stroke
				(width 0.1524)
				(type default)
			)
			(layer "B.SilkS")
		)
		(fp_line
			(start 0.7874 0.4064)
			(end 0.7874 -0.4064)
			(stroke
				(width 0.1524)
				(type default)
			)
			(layer "B.SilkS")
		)
		(fp_line
			(start -0.67945 -0.3048)
			(end -0.67945 0.3048)
			(stroke
				(width 0.1)
				(type default)
			)
			(layer "B.Fab")
		)
		(fp_line
			(start -0.67945 0.3048)
			(end -0.120396 0.3048)
			(stroke
				(width 0.1)
				(type default)
			)
			(layer "B.Fab")
		)
		(fp_line
			(start -0.12065 -0.3048)
			(end -0.67945 -0.3048)
			(stroke
				(width 0.1)
				(type default)
			)
			(layer "B.Fab")
		)
		(fp_line
			(start -0.12065 -0.2794)
			(end -0.12065 -0.3048)
			(stroke
				(width 0.1)
				(type default)
			)
			(layer "B.Fab")
		)
		(fp_line
			(start -0.120396 0.2794)
			(end 0.12065 0.2794)
			(stroke
				(width 0.1)
				(type default)
			)
			(layer "B.Fab")
		)
		(fp_line
			(start -0.120396 0.3048)
			(end -0.120396 0.2794)
			(stroke
				(width 0.1)
				(type default)
			)
			(layer "B.Fab")
		)
		(fp_line
			(start 0.12065 -0.305054)
			(end 0.12065 -0.2794)
			(stroke
				(width 0.1)
				(type default)
			)
			(layer "B.Fab")
		)
		(fp_line
			(start 0.12065 -0.2794)
			(end -0.12065 -0.2794)
			(stroke
				(width 0.1)
				(type default)
			)
			(layer "B.Fab")
		)
		(fp_line
			(start 0.12065 0.2794)
			(end 0.12065 0.3048)
			(stroke
				(width 0.1)
				(type default)
			)
			(layer "B.Fab")
		)
		(fp_line
			(start 0.12065 0.3048)
			(end 0.67945 0.3048)
			(stroke
				(width 0.1)
				(type default)
			)
			(layer "B.Fab")
		)
		(fp_line
			(start 0.67945 -0.305054)
			(end 0.12065 -0.305054)
			(stroke
				(width 0.1)
				(type default)
			)
			(layer "B.Fab")
		)
		(fp_line
			(start 0.67945 0.3048)
			(end 0.67945 -0.305054)
			(stroke
				(width 0.1)
				(type default)
			)
			(layer "B.Fab")
		)
		(pad "1" smd circle
			(at 0.40005 0 180)
			(size 0 0)
			(layers "B.Cu" "B.Mask" "B.Paste")
			(net "P1V2_AUX")
		)
		(pad "2" smd circle
			(at -0.40005 0 180)
			(size 0 0)
			(layers "B.Cu" "B.Mask" "B.Paste")
			(net "GND")
		)
	)
	(footprint ""
		(layer "B.Cu")
		(at 311.91835 -396.393162 -90)
		(property "Reference" "C514"
			(at 0 0 90)
			(layer "B.SilkS")
			(hide yes)
			(effects
				(font
					(size 1.27 1.27)
				)
				(justify mirror)
			)
		)
		(property "Value" ""
			(at 0 0 90)
			(layer "B.Fab")
			(effects
				(font
					(size 1.27 1.27)
				)
				(justify mirror)
			)
		)
		(duplicate_pad_numbers_are_jumpers no)
		(fp_line
			(start -0.299974 0.150114)
			(end 0.299974 0.150114)
			(stroke
				(width 0.1)
				(type default)
			)
			(layer "B.Fab")
		)
		(fp_line
			(start 0.299974 0.150114)
			(end 0.299974 -0.150114)
			(stroke
				(width 0.1)
				(type default)
			)
			(layer "B.Fab")
		)
		(fp_line
			(start -0.299974 -0.150114)
			(end -0.299974 0.150114)
			(stroke
				(width 0.1)
				(type default)
			)
			(layer "B.Fab")
		)
		(fp_line
			(start 0.299974 -0.150114)
			(end -0.299974 -0.150114)
			(stroke
				(width 0.1)
				(type default)
			)
			(layer "B.Fab")
		)
		(pad "1" smd rect
			(at 0.2667 0 90)
			(size 0.3048 0.381)
			(layers "B.Cu" "B.Mask" "B.Paste")
			(net "P1V8_CPU0_RT0_1A")
		)
		(pad "2" smd rect
			(at -0.2667 0 90)
			(size 0.3048 0.381)
			(layers "B.Cu" "B.Mask" "B.Paste")
			(net "GND")
		)
	)
	(footprint ""
		(layer "B.Cu")
		(at 45.418502 -387.05028)
		(property "Reference" "C257"
			(at 0 0 0)
			(layer "B.SilkS")
			(hide yes)
			(effects
				(font
					(size 1.27 1.27)
				)
				(justify mirror)
			)
		)
		(property "Value" ""
			(at 0 0 0)
			(layer "B.Fab")
			(effects
				(font
					(size 1.27 1.27)
				)
				(justify mirror)
			)
		)
		(duplicate_pad_numbers_are_jumpers no)
		(fp_line
			(start -0.299974 -0.150114)
			(end -0.299974 0.150114)
			(stroke
				(width 0.1)
				(type default)
			)
			(layer "B.Fab")
		)
		(fp_line
			(start -0.299974 0.150114)
			(end 0.299974 0.150114)
			(stroke
				(width 0.1)
				(type default)
			)
			(layer "B.Fab")
		)
		(fp_line
			(start 0.299974 -0.150114)
			(end -0.299974 -0.150114)
			(stroke
				(width 0.1)
				(type default)
			)
			(layer "B.Fab")
		)
		(fp_line
			(start 0.299974 0.150114)
			(end 0.299974 -0.150114)
			(stroke
				(width 0.1)
				(type default)
			)
			(layer "B.Fab")
		)
		(pad "1" smd rect
			(at 0.2667 0 180)
			(size 0.3048 0.381)
			(layers "B.Cu" "B.Mask" "B.Paste")
			(net "P0V9_CPU1_RT0_2A")
		)
		(pad "2" smd rect
			(at -0.2667 0 180)
			(size 0.3048 0.381)
			(layers "B.Cu" "B.Mask" "B.Paste")
			(net "GND")
		)
	)
	(footprint ""
		(layer "B.Cu")
		(at 167.377618 -417.962588)
		(property "Reference" "R4128"
			(at 0 0 0)
			(layer "B.SilkS")
			(hide yes)
			(effects
				(font
					(size 1.27 1.27)
				)
				(justify mirror)
			)
		)
		(property "Value" ""
			(at 0 0 0)
			(layer "B.Fab")
			(effects
				(font
					(size 1.27 1.27)
				)
				(justify mirror)
			)
		)
		(duplicate_pad_numbers_are_jumpers no)
		(fp_line
			(start -0.7874 -0.4064)
			(end -0.7874 0.4064)
			(stroke
				(width 0.1524)
				(type default)
			)
			(layer "B.SilkS")
		)
		(fp_line
			(start -0.7874 0.4064)
			(end 0.7874 0.4064)
			(stroke
				(width 0.1524)
				(type default)
			)
			(layer "B.SilkS")
		)
		(fp_line
			(start 0.7874 -0.4064)
			(end -0.7874 -0.4064)
			(stroke
				(width 0.1524)
				(type default)
			)
			(layer "B.SilkS")
		)
		(fp_line
			(start 0.7874 0.4064)
			(end 0.7874 -0.4064)
			(stroke
				(width 0.1524)
				(type default)
			)
			(layer "B.SilkS")
		)
		(fp_line
			(start -0.67945 -0.3048)
			(end -0.67945 0.3048)
			(stroke
				(width 0.1)
				(type default)
			)
			(layer "B.Fab")
		)
		(fp_line
			(start -0.67945 0.3048)
			(end -0.120396 0.3048)
			(stroke
				(width 0.1)
				(type default)
			)
			(layer "B.Fab")
		)
		(fp_line
			(start -0.12065 -0.3048)
			(end -0.67945 -0.3048)
			(stroke
				(width 0.1)
				(type default)
			)
			(layer "B.Fab")
		)
		(fp_line
			(start -0.12065 -0.2794)
			(end -0.12065 -0.3048)
			(stroke
				(width 0.1)
				(type default)
			)
			(layer "B.Fab")
		)
		(fp_line
			(start -0.120396 0.2794)
			(end 0.12065 0.2794)
			(stroke
				(width 0.1)
				(type default)
			)
			(layer "B.Fab")
		)
		(fp_line
			(start -0.120396 0.3048)
			(end -0.120396 0.2794)
			(stroke
				(width 0.1)
				(type default)
			)
			(layer "B.Fab")
		)
		(fp_line
			(start 0.12065 -0.305054)
			(end 0.12065 -0.2794)
			(stroke
				(width 0.1)
				(type default)
			)
			(layer "B.Fab")
		)
		(fp_line
			(start 0.12065 -0.2794)
			(end -0.12065 -0.2794)
			(stroke
				(width 0.1)
				(type default)
			)
			(layer "B.Fab")
		)
		(fp_line
			(start 0.12065 0.2794)
			(end 0.12065 0.3048)
			(stroke
				(width 0.1)
				(type default)
			)
			(layer "B.Fab")
		)
		(fp_line
			(start 0.12065 0.3048)
			(end 0.67945 0.3048)
			(stroke
				(width 0.1)
				(type default)
			)
			(layer "B.Fab")
		)
		(fp_line
			(start 0.67945 -0.305054)
			(end 0.12065 -0.305054)
			(stroke
				(width 0.1)
				(type default)
			)
			(layer "B.Fab")
		)
		(fp_line
			(start 0.67945 0.3048)
			(end 0.67945 -0.305054)
			(stroke
				(width 0.1)
				(type default)
			)
			(layer "B.Fab")
		)
		(pad "1" smd circle
			(at 0.40005 0 180)
			(size 0 0)
			(layers "B.Cu" "B.Mask" "B.Paste")
			(net "P3V3_AUX")
		)
		(pad "2" smd circle
			(at -0.40005 0 180)
			(size 0 0)
			(layers "B.Cu" "B.Mask" "B.Paste")
			(net "GPU_3V3IO_RSVD0_FFU_ISO")
		)
	)
	(footprint ""
		(layer "B.Cu")
		(at 184.681114 -417.575238 180)
		(property "Reference" "R2811"
			(at 0 0 0)
			(layer "B.SilkS")
			(hide yes)
			(effects
				(font
					(size 1.27 1.27)
				)
				(justify mirror)
			)
		)
		(property "Value" ""
			(at 0 0 0)
			(layer "B.Fab")
			(effects
				(font
					(size 1.27 1.27)
				)
				(justify mirror)
			)
		)
		(duplicate_pad_numbers_are_jumpers no)
		(fp_line
			(start 0.7874 0.4064)
			(end 0.7874 -0.4064)
			(stroke
				(width 0.1524)
				(type default)
			)
			(layer "B.SilkS")
		)
		(fp_line
			(start 0.7874 -0.4064)
			(end -0.7874 -0.4064)
			(stroke
				(width 0.1524)
				(type default)
			)
			(layer "B.SilkS")
		)
		(fp_line
			(start -0.7874 0.4064)
			(end 0.7874 0.4064)
			(stroke
				(width 0.1524)
				(type default)
			)
			(layer "B.SilkS")
		)
		(fp_line
			(start -0.7874 -0.4064)
			(end -0.7874 0.4064)
			(stroke
				(width 0.1524)
				(type default)
			)
			(layer "B.SilkS")
		)
		(fp_line
			(start 0.67945 0.3048)
			(end 0.67945 -0.305054)
			(stroke
				(width 0.1)
				(type default)
			)
			(layer "B.Fab")
		)
		(fp_line
			(start 0.67945 -0.305054)
			(end 0.12065 -0.305054)
			(stroke
				(width 0.1)
				(type default)
			)
			(layer "B.Fab")
		)
		(fp_line
			(start 0.12065 0.3048)
			(end 0.67945 0.3048)
			(stroke
				(width 0.1)
				(type default)
			)
			(layer "B.Fab")
		)
		(fp_line
			(start 0.12065 0.2794)
			(end 0.12065 0.3048)
			(stroke
				(width 0.1)
				(type default)
			)
			(layer "B.Fab")
		)
		(fp_line
			(start 0.12065 -0.2794)
			(end -0.12065 -0.2794)
			(stroke
				(width 0.1)
				(type default)
			)
			(layer "B.Fab")
		)
		(fp_line
			(start 0.12065 -0.305054)
			(end 0.12065 -0.2794)
			(stroke
				(width 0.1)
				(type default)
			)
			(layer "B.Fab")
		)
		(fp_line
			(start -0.120396 0.3048)
			(end -0.120396 0.2794)
			(stroke
				(width 0.1)
				(type default)
			)
			(layer "B.Fab")
		)
		(fp_line
			(start -0.120396 0.2794)
			(end 0.12065 0.2794)
			(stroke
				(width 0.1)
				(type default)
			)
			(layer "B.Fab")
		)
		(fp_line
			(start -0.12065 -0.2794)
			(end -0.12065 -0.3048)
			(stroke
				(width 0.1)
				(type default)
			)
			(layer "B.Fab")
		)
		(fp_line
			(start -0.12065 -0.3048)
			(end -0.67945 -0.3048)
			(stroke
				(width 0.1)
				(type default)
			)
			(layer "B.Fab")
		)
		(fp_line
			(start -0.67945 0.3048)
			(end -0.120396 0.3048)
			(stroke
				(width 0.1)
				(type default)
			)
			(layer "B.Fab")
		)
		(fp_line
			(start -0.67945 -0.3048)
			(end -0.67945 0.3048)
			(stroke
				(width 0.1)
				(type default)
			)
			(layer "B.Fab")
		)
		(pad "1" smd circle
			(at 0.40005 0)
			(size 0 0)
			(layers "B.Cu" "B.Mask" "B.Paste")
			(net "SMB_FAN_3V3AUX_BUF_SCL")
		)
		(pad "2" smd circle
			(at -0.40005 0)
			(size 0 0)
			(layers "B.Cu" "B.Mask" "B.Paste")
			(net "SMB_FAN_3V3AUX_BUF_R_SCL")
		)
	)
	(footprint ""
		(layer "B.Cu")
		(at 99.94519 -387.768592 180)
		(property "Reference" "C349"
			(at 0 0 0)
			(layer "B.SilkS")
			(hide yes)
			(effects
				(font
					(size 1.27 1.27)
				)
				(justify mirror)
			)
		)
		(property "Value" ""
			(at 0 0 0)
			(layer "B.Fab")
			(effects
				(font
					(size 1.27 1.27)
				)
				(justify mirror)
			)
		)
		(duplicate_pad_numbers_are_jumpers no)
		(fp_line
			(start 0.299974 0.150114)
			(end 0.299974 -0.150114)
			(stroke
				(width 0.1)
				(type default)
			)
			(layer "B.Fab")
		)
		(fp_line
			(start 0.299974 -0.150114)
			(end -0.299974 -0.150114)
			(stroke
				(width 0.1)
				(type default)
			)
			(layer "B.Fab")
		)
		(fp_line
			(start -0.299974 0.150114)
			(end 0.299974 0.150114)
			(stroke
				(width 0.1)
				(type default)
			)
			(layer "B.Fab")
		)
		(fp_line
			(start -0.299974 -0.150114)
			(end -0.299974 0.150114)
			(stroke
				(width 0.1)
				(type default)
			)
			(layer "B.Fab")
		)
		(pad "1" smd rect
			(at 0.2667 0)
			(size 0.3048 0.381)
			(layers "B.Cu" "B.Mask" "B.Paste")
			(net "P0V9_CPU1_RT1_2A")
		)
		(pad "2" smd rect
			(at -0.2667 0)
			(size 0.3048 0.381)
			(layers "B.Cu" "B.Mask" "B.Paste")
			(net "GND")
		)
	)
	(footprint ""
		(layer "B.Cu")
		(at 415.712402 -195.85051 180)
		(property "Reference" "R1680"
			(at 0 0 0)
			(layer "B.SilkS")
			(hide yes)
			(effects
				(font
					(size 1.27 1.27)
				)
				(justify mirror)
			)
		)
		(property "Value" ""
			(at 0 0 0)
			(layer "B.Fab")
			(effects
				(font
					(size 1.27 1.27)
				)
				(justify mirror)
			)
		)
		(duplicate_pad_numbers_are_jumpers no)
		(fp_line
			(start 0.7874 0.4064)
			(end 0.7874 -0.4064)
			(stroke
				(width 0.1524)
				(type default)
			)
			(layer "B.SilkS")
		)
		(fp_line
			(start 0.7874 -0.4064)
			(end -0.7874 -0.4064)
			(stroke
				(width 0.1524)
				(type default)
			)
			(layer "B.SilkS")
		)
		(fp_line
			(start -0.7874 0.4064)
			(end 0.7874 0.4064)
			(stroke
				(width 0.1524)
				(type default)
			)
			(layer "B.SilkS")
		)
		(fp_line
			(start -0.7874 -0.4064)
			(end -0.7874 0.4064)
			(stroke
				(width 0.1524)
				(type default)
			)
			(layer "B.SilkS")
		)
		(fp_line
			(start 0.67945 0.3048)
			(end 0.67945 -0.305054)
			(stroke
				(width 0.1)
				(type default)
			)
			(layer "B.Fab")
		)
		(fp_line
			(start 0.67945 -0.305054)
			(end 0.12065 -0.305054)
			(stroke
				(width 0.1)
				(type default)
			)
			(layer "B.Fab")
		)
		(fp_line
			(start 0.12065 0.3048)
			(end 0.67945 0.3048)
			(stroke
				(width 0.1)
				(type default)
			)
			(layer "B.Fab")
		)
		(fp_line
			(start 0.12065 0.2794)
			(end 0.12065 0.3048)
			(stroke
				(width 0.1)
				(type default)
			)
			(layer "B.Fab")
		)
		(fp_line
			(start 0.12065 -0.2794)
			(end -0.12065 -0.2794)
			(stroke
				(width 0.1)
				(type default)
			)
			(layer "B.Fab")
		)
		(fp_line
			(start 0.12065 -0.305054)
			(end 0.12065 -0.2794)
			(stroke
				(width 0.1)
				(type default)
			)
			(layer "B.Fab")
		)
		(fp_line
			(start -0.120396 0.3048)
			(end -0.120396 0.2794)
			(stroke
				(width 0.1)
				(type default)
			)
			(layer "B.Fab")
		)
		(fp_line
			(start -0.120396 0.2794)
			(end 0.12065 0.2794)
			(stroke
				(width 0.1)
				(type default)
			)
			(layer "B.Fab")
		)
		(fp_line
			(start -0.12065 -0.2794)
			(end -0.12065 -0.3048)
			(stroke
				(width 0.1)
				(type default)
			)
			(layer "B.Fab")
		)
		(fp_line
			(start -0.12065 -0.3048)
			(end -0.67945 -0.3048)
			(stroke
				(width 0.1)
				(type default)
			)
			(layer "B.Fab")
		)
		(fp_line
			(start -0.67945 0.3048)
			(end -0.120396 0.3048)
			(stroke
				(width 0.1)
				(type default)
			)
			(layer "B.Fab")
		)
		(fp_line
			(start -0.67945 -0.3048)
			(end -0.67945 0.3048)
			(stroke
				(width 0.1)
				(type default)
			)
			(layer "B.Fab")
		)
		(pad "1" smd circle
			(at 0.40005 0)
			(size 0 0)
			(layers "B.Cu" "B.Mask" "B.Paste")
			(net "I3C_SPD_DDRGL_CPU0_SDA")
		)
		(pad "2" smd circle
			(at -0.40005 0)
			(size 0 0)
			(layers "B.Cu" "B.Mask" "B.Paste")
			(net "I3C_SPD_DDRG_CPU0_SDA")
		)
	)
	(footprint ""
		(layer "B.Cu")
		(at 118.091204 -390.560052 90)
		(property "Reference" "C490"
			(at 0 0 90)
			(layer "B.SilkS")
			(hide yes)
			(effects
				(font
					(size 1.27 1.27)
				)
				(justify mirror)
			)
		)
		(property "Value" ""
			(at 0 0 90)
			(layer "B.Fab")
			(effects
				(font
					(size 1.27 1.27)
				)
				(justify mirror)
			)
		)
		(duplicate_pad_numbers_are_jumpers no)
		(fp_line
			(start 0.7874 -0.4064)
			(end -0.7874 -0.4064)
			(stroke
				(width 0.1524)
				(type default)
			)
			(layer "B.SilkS")
		)
		(fp_line
			(start -0.7874 -0.4064)
			(end -0.7874 0.4064)
			(stroke
				(width 0.1524)
				(type default)
			)
			(layer "B.SilkS")
		)
		(fp_line
			(start 0.7874 0.4064)
			(end 0.7874 -0.4064)
			(stroke
				(width 0.1524)
				(type default)
			)
			(layer "B.SilkS")
		)
		(fp_line
			(start -0.7874 0.4064)
			(end 0.7874 0.4064)
			(stroke
				(width 0.1524)
				(type default)
			)
			(layer "B.SilkS")
		)
		(fp_line
			(start 0.67945 -0.305054)
			(end 0.12065 -0.305054)
			(stroke
				(width 0.1)
				(type default)
			)
			(layer "B.Fab")
		)
		(fp_line
			(start 0.12065 -0.305054)
			(end 0.12065 -0.2794)
			(stroke
				(width 0.1)
				(type default)
			)
			(layer "B.Fab")
		)
		(fp_line
			(start -0.12065 -0.3048)
			(end -0.67945 -0.3048)
			(stroke
				(width 0.1)
				(type default)
			)
			(layer "B.Fab")
		)
		(fp_line
			(start -0.67945 -0.3048)
			(end -0.67945 0.3048)
			(stroke
				(width 0.1)
				(type default)
			)
			(layer "B.Fab")
		)
		(fp_line
			(start 0.12065 -0.2794)
			(end -0.12065 -0.2794)
			(stroke
				(width 0.1)
				(type default)
			)
			(layer "B.Fab")
		)
		(fp_line
			(start -0.12065 -0.2794)
			(end -0.12065 -0.3048)
			(stroke
				(width 0.1)
				(type default)
			)
			(layer "B.Fab")
		)
		(fp_line
			(start 0.12065 0.2794)
			(end 0.12065 0.3048)
			(stroke
				(width 0.1)
				(type default)
			)
			(layer "B.Fab")
		)
		(fp_line
			(start -0.120396 0.2794)
			(end 0.12065 0.2794)
			(stroke
				(width 0.1)
				(type default)
			)
			(layer "B.Fab")
		)
		(fp_line
			(start 0.67945 0.3048)
			(end 0.67945 -0.305054)
			(stroke
				(width 0.1)
				(type default)
			)
			(layer "B.Fab")
		)
		(fp_line
			(start 0.12065 0.3048)
			(end 0.67945 0.3048)
			(stroke
				(width 0.1)
				(type default)
			)
			(layer "B.Fab")
		)
		(fp_line
			(start -0.120396 0.3048)
			(end -0.120396 0.2794)
			(stroke
				(width 0.1)
				(type default)
			)
			(layer "B.Fab")
		)
		(fp_line
			(start -0.67945 0.3048)
			(end -0.120396 0.3048)
			(stroke
				(width 0.1)
				(type default)
			)
			(layer "B.Fab")
		)
		(pad "1" smd circle
			(at 0.40005 0 270)
			(size 0 0)
			(layers "B.Cu" "B.Mask" "B.Paste")
			(net "P0V9_CPU1_RT3_2A")
		)
		(pad "2" smd circle
			(at -0.40005 0 270)
			(size 0 0)
			(layers "B.Cu" "B.Mask" "B.Paste")
			(net "GND")
		)
	)
	(footprint ""
		(layer "B.Cu")
		(at 422.373044 -398.942052 90)
		(property "Reference" "C988"
			(at 0 0 90)
			(layer "B.SilkS")
			(hide yes)
			(effects
				(font
					(size 1.27 1.27)
				)
				(justify mirror)
			)
		)
		(property "Value" ""
			(at 0 0 90)
			(layer "B.Fab")
			(effects
				(font
					(size 1.27 1.27)
				)
				(justify mirror)
			)
		)
		(duplicate_pad_numbers_are_jumpers no)
		(fp_line
			(start 0.7874 -0.4064)
			(end -0.7874 -0.4064)
			(stroke
				(width 0.1524)
				(type default)
			)
			(layer "B.SilkS")
		)
		(fp_line
			(start -0.7874 -0.4064)
			(end -0.7874 0.4064)
			(stroke
				(width 0.1524)
				(type default)
			)
			(layer "B.SilkS")
		)
		(fp_line
			(start 0.7874 0.4064)
			(end 0.7874 -0.4064)
			(stroke
				(width 0.1524)
				(type default)
			)
			(layer "B.SilkS")
		)
		(fp_line
			(start -0.7874 0.4064)
			(end 0.7874 0.4064)
			(stroke
				(width 0.1524)
				(type default)
			)
			(layer "B.SilkS")
		)
		(fp_line
			(start 0.67945 -0.305054)
			(end 0.12065 -0.305054)
			(stroke
				(width 0.1)
				(type default)
			)
			(layer "B.Fab")
		)
		(fp_line
			(start 0.12065 -0.305054)
			(end 0.12065 -0.2794)
			(stroke
				(width 0.1)
				(type default)
			)
			(layer "B.Fab")
		)
		(fp_line
			(start -0.12065 -0.3048)
			(end -0.67945 -0.3048)
			(stroke
				(width 0.1)
				(type default)
			)
			(layer "B.Fab")
		)
		(fp_line
			(start -0.67945 -0.3048)
			(end -0.67945 0.3048)
			(stroke
				(width 0.1)
				(type default)
			)
			(layer "B.Fab")
		)
		(fp_line
			(start 0.12065 -0.2794)
			(end -0.12065 -0.2794)
			(stroke
				(width 0.1)
				(type default)
			)
			(layer "B.Fab")
		)
		(fp_line
			(start -0.12065 -0.2794)
			(end -0.12065 -0.3048)
			(stroke
				(width 0.1)
				(type default)
			)
			(layer "B.Fab")
		)
		(fp_line
			(start 0.12065 0.2794)
			(end 0.12065 0.3048)
			(stroke
				(width 0.1)
				(type default)
			)
			(layer "B.Fab")
		)
		(fp_line
			(start -0.120396 0.2794)
			(end 0.12065 0.2794)
			(stroke
				(width 0.1)
				(type default)
			)
			(layer "B.Fab")
		)
		(fp_line
			(start 0.67945 0.3048)
			(end 0.67945 -0.305054)
			(stroke
				(width 0.1)
				(type default)
			)
			(layer "B.Fab")
		)
		(fp_line
			(start 0.12065 0.3048)
			(end 0.67945 0.3048)
			(stroke
				(width 0.1)
				(type default)
			)
			(layer "B.Fab")
		)
		(fp_line
			(start -0.120396 0.3048)
			(end -0.120396 0.2794)
			(stroke
				(width 0.1)
				(type default)
			)
			(layer "B.Fab")
		)
		(fp_line
			(start -0.67945 0.3048)
			(end -0.120396 0.3048)
			(stroke
				(width 0.1)
				(type default)
			)
			(layer "B.Fab")
		)
		(pad "1" smd circle
			(at 0.40005 0 270)
			(size 0 0)
			(layers "B.Cu" "B.Mask" "B.Paste")
			(net "P0V9_CPU0_RT2_2A")
		)
		(pad "2" smd circle
			(at -0.40005 0 270)
			(size 0 0)
			(layers "B.Cu" "B.Mask" "B.Paste")
			(net "GND")
		)
	)
	(footprint ""
		(layer "B.Cu")
		(at 309.81777 -350.65589 -90)
		(property "Reference" "PC123_4"
			(at 0 0 90)
			(layer "B.SilkS")
			(hide yes)
			(effects
				(font
					(size 1.27 1.27)
				)
				(justify mirror)
			)
		)
		(property "Value" ""
			(at 0 0 90)
			(layer "B.Fab")
			(effects
				(font
					(size 1.27 1.27)
				)
				(justify mirror)
			)
		)
		(duplicate_pad_numbers_are_jumpers no)
		(fp_line
			(start -1.524 0.762)
			(end 1.524 0.762)
			(stroke
				(width 0.1524)
				(type default)
			)
			(layer "B.SilkS")
		)
		(fp_line
			(start 1.524 0.762)
			(end 1.524 -0.762)
			(stroke
				(width 0.1524)
				(type default)
			)
			(layer "B.SilkS")
		)
		(fp_line
			(start -1.524 -0.762)
			(end -1.524 0.762)
			(stroke
				(width 0.1524)
				(type default)
			)
			(layer "B.SilkS")
		)
		(fp_line
			(start 1.524 -0.762)
			(end -1.524 -0.762)
			(stroke
				(width 0.1524)
				(type default)
			)
			(layer "B.SilkS")
		)
		(fp_line
			(start -1.1049 0.724916)
			(end -1.1049 -0.724916)
			(stroke
				(width 0.1)
				(type default)
			)
			(layer "B.Fab")
		)
		(fp_line
			(start 1.1049 0.724916)
			(end -1.1049 0.724916)
			(stroke
				(width 0.1)
				(type default)
			)
			(layer "B.Fab")
		)
		(fp_line
			(start -1.1049 -0.724916)
			(end 1.1049 -0.724916)
			(stroke
				(width 0.1)
				(type default)
			)
			(layer "B.Fab")
		)
		(fp_line
			(start 1.1049 -0.724916)
			(end 1.1049 0.724916)
			(stroke
				(width 0.1)
				(type default)
			)
			(layer "B.Fab")
		)
		(pad "1" smd rect
			(at 0.889 0 270)
			(size 1.016 1.27)
			(layers "B.Cu" "B.Mask" "B.Paste")
			(net "SW_P12V_AUX_PVDDCR_CPU1_P0_FLT")
		)
		(pad "2" smd rect
			(at -0.889 0 270)
			(size 1.016 1.27)
			(layers "B.Cu" "B.Mask" "B.Paste")
			(net "GND")
		)
	)
	(footprint ""
		(layer "B.Cu")
		(at 370.408454 -261.046976)
		(property "Reference" "C2529"
			(at 0 0 0)
			(layer "B.SilkS")
			(hide yes)
			(effects
				(font
					(size 1.27 1.27)
				)
				(justify mirror)
			)
		)
		(property "Value" ""
			(at 0 0 0)
			(layer "B.Fab")
			(effects
				(font
					(size 1.27 1.27)
				)
				(justify mirror)
			)
		)
		(duplicate_pad_numbers_are_jumpers no)
		(fp_line
			(start -0.7874 -0.4064)
			(end -0.7874 0.4064)
			(stroke
				(width 0.1524)
				(type default)
			)
			(layer "B.SilkS")
		)
		(fp_line
			(start -0.7874 0.4064)
			(end 0.7874 0.4064)
			(stroke
				(width 0.1524)
				(type default)
			)
			(layer "B.SilkS")
		)
		(fp_line
			(start 0.7874 -0.4064)
			(end -0.7874 -0.4064)
			(stroke
				(width 0.1524)
				(type default)
			)
			(layer "B.SilkS")
		)
		(fp_line
			(start 0.7874 0.4064)
			(end 0.7874 -0.4064)
			(stroke
				(width 0.1524)
				(type default)
			)
			(layer "B.SilkS")
		)
		(fp_line
			(start -0.67945 -0.3048)
			(end -0.67945 0.3048)
			(stroke
				(width 0.1)
				(type default)
			)
			(layer "B.Fab")
		)
		(fp_line
			(start -0.67945 0.3048)
			(end -0.120396 0.3048)
			(stroke
				(width 0.1)
				(type default)
			)
			(layer "B.Fab")
		)
		(fp_line
			(start -0.12065 -0.3048)
			(end -0.67945 -0.3048)
			(stroke
				(width 0.1)
				(type default)
			)
			(layer "B.Fab")
		)
		(fp_line
			(start -0.12065 -0.2794)
			(end -0.12065 -0.3048)
			(stroke
				(width 0.1)
				(type default)
			)
			(layer "B.Fab")
		)
		(fp_line
			(start -0.120396 0.2794)
			(end 0.12065 0.2794)
			(stroke
				(width 0.1)
				(type default)
			)
			(layer "B.Fab")
		)
		(fp_line
			(start -0.120396 0.3048)
			(end -0.120396 0.2794)
			(stroke
				(width 0.1)
				(type default)
			)
			(layer "B.Fab")
		)
		(fp_line
			(start 0.12065 -0.305054)
			(end 0.12065 -0.2794)
			(stroke
				(width 0.1)
				(type default)
			)
			(layer "B.Fab")
		)
		(fp_line
			(start 0.12065 -0.2794)
			(end -0.12065 -0.2794)
			(stroke
				(width 0.1)
				(type default)
			)
			(layer "B.Fab")
		)
		(fp_line
			(start 0.12065 0.2794)
			(end 0.12065 0.3048)
			(stroke
				(width 0.1)
				(type default)
			)
			(layer "B.Fab")
		)
		(fp_line
			(start 0.12065 0.3048)
			(end 0.67945 0.3048)
			(stroke
				(width 0.1)
				(type default)
			)
			(layer "B.Fab")
		)
		(fp_line
			(start 0.67945 -0.305054)
			(end 0.12065 -0.305054)
			(stroke
				(width 0.1)
				(type default)
			)
			(layer "B.Fab")
		)
		(fp_line
			(start 0.67945 0.3048)
			(end 0.67945 -0.305054)
			(stroke
				(width 0.1)
				(type default)
			)
			(layer "B.Fab")
		)
		(pad "1" smd circle
			(at 0.40005 0 180)
			(size 0 0)
			(layers "B.Cu" "B.Mask" "B.Paste")
			(net "PVDDCR_SOC_P0")
		)
		(pad "2" smd circle
			(at -0.40005 0 180)
			(size 0 0)
			(layers "B.Cu" "B.Mask" "B.Paste")
			(net "GND")
		)
	)
	(footprint ""
		(layer "B.Cu")
		(at 117.388386 -251.781564)
		(property "Reference" "C2451"
			(at 0 0 0)
			(layer "B.SilkS")
			(hide yes)
			(effects
				(font
					(size 1.27 1.27)
				)
				(justify mirror)
			)
		)
		(property "Value" ""
			(at 0 0 0)
			(layer "B.Fab")
			(effects
				(font
					(size 1.27 1.27)
				)
				(justify mirror)
			)
		)
		(duplicate_pad_numbers_are_jumpers no)
		(fp_line
			(start -0.7874 -0.4064)
			(end -0.7874 0.4064)
			(stroke
				(width 0.1524)
				(type default)
			)
			(layer "B.SilkS")
		)
		(fp_line
			(start -0.7874 0.4064)
			(end 0.7874 0.4064)
			(stroke
				(width 0.1524)
				(type default)
			)
			(layer "B.SilkS")
		)
		(fp_line
			(start 0.7874 -0.4064)
			(end -0.7874 -0.4064)
			(stroke
				(width 0.1524)
				(type default)
			)
			(layer "B.SilkS")
		)
		(fp_line
			(start 0.7874 0.4064)
			(end 0.7874 -0.4064)
			(stroke
				(width 0.1524)
				(type default)
			)
			(layer "B.SilkS")
		)
		(fp_line
			(start -0.67945 -0.3048)
			(end -0.67945 0.3048)
			(stroke
				(width 0.1)
				(type default)
			)
			(layer "B.Fab")
		)
		(fp_line
			(start -0.67945 0.3048)
			(end -0.120396 0.3048)
			(stroke
				(width 0.1)
				(type default)
			)
			(layer "B.Fab")
		)
		(fp_line
			(start -0.12065 -0.3048)
			(end -0.67945 -0.3048)
			(stroke
				(width 0.1)
				(type default)
			)
			(layer "B.Fab")
		)
		(fp_line
			(start -0.12065 -0.2794)
			(end -0.12065 -0.3048)
			(stroke
				(width 0.1)
				(type default)
			)
			(layer "B.Fab")
		)
		(fp_line
			(start -0.120396 0.2794)
			(end 0.12065 0.2794)
			(stroke
				(width 0.1)
				(type default)
			)
			(layer "B.Fab")
		)
		(fp_line
			(start -0.120396 0.3048)
			(end -0.120396 0.2794)
			(stroke
				(width 0.1)
				(type default)
			)
			(layer "B.Fab")
		)
		(fp_line
			(start 0.12065 -0.305054)
			(end 0.12065 -0.2794)
			(stroke
				(width 0.1)
				(type default)
			)
			(layer "B.Fab")
		)
		(fp_line
			(start 0.12065 -0.2794)
			(end -0.12065 -0.2794)
			(stroke
				(width 0.1)
				(type default)
			)
			(layer "B.Fab")
		)
		(fp_line
			(start 0.12065 0.2794)
			(end 0.12065 0.3048)
			(stroke
				(width 0.1)
				(type default)
			)
			(layer "B.Fab")
		)
		(fp_line
			(start 0.12065 0.3048)
			(end 0.67945 0.3048)
			(stroke
				(width 0.1)
				(type default)
			)
			(layer "B.Fab")
		)
		(fp_line
			(start 0.67945 -0.305054)
			(end 0.12065 -0.305054)
			(stroke
				(width 0.1)
				(type default)
			)
			(layer "B.Fab")
		)
		(fp_line
			(start 0.67945 0.3048)
			(end 0.67945 -0.305054)
			(stroke
				(width 0.1)
				(type default)
			)
			(layer "B.Fab")
		)
		(pad "1" smd circle
			(at 0.40005 0 180)
			(size 0 0)
			(layers "B.Cu" "B.Mask" "B.Paste")
			(net "PVDDCR_SOC_P1")
		)
		(pad "2" smd circle
			(at -0.40005 0 180)
			(size 0 0)
			(layers "B.Cu" "B.Mask" "B.Paste")
			(net "GND")
		)
	)
	(footprint ""
		(layer "B.Cu")
		(at 449.789296 -52.846986 -90)
		(property "Reference" "PC571"
			(at 0 0 90)
			(layer "B.SilkS")
			(hide yes)
			(effects
				(font
					(size 1.27 1.27)
				)
				(justify mirror)
			)
		)
		(property "Value" ""
			(at 0 0 90)
			(layer "B.Fab")
			(effects
				(font
					(size 1.27 1.27)
				)
				(justify mirror)
			)
		)
		(duplicate_pad_numbers_are_jumpers no)
		(fp_line
			(start -1.524 0.762)
			(end 1.524 0.762)
			(stroke
				(width 0.1524)
				(type default)
			)
			(layer "B.SilkS")
		)
		(fp_line
			(start 1.524 0.762)
			(end 1.524 -0.762)
			(stroke
				(width 0.1524)
				(type default)
			)
			(layer "B.SilkS")
		)
		(fp_line
			(start -1.524 -0.762)
			(end -1.524 0.762)
			(stroke
				(width 0.1524)
				(type default)
			)
			(layer "B.SilkS")
		)
		(fp_line
			(start 1.524 -0.762)
			(end -1.524 -0.762)
			(stroke
				(width 0.1524)
				(type default)
			)
			(layer "B.SilkS")
		)
		(fp_line
			(start -1.1049 0.724916)
			(end -1.1049 -0.724916)
			(stroke
				(width 0.1)
				(type default)
			)
			(layer "B.Fab")
		)
		(fp_line
			(start 1.1049 0.724916)
			(end -1.1049 0.724916)
			(stroke
				(width 0.1)
				(type default)
			)
			(layer "B.Fab")
		)
		(fp_line
			(start -1.1049 -0.724916)
			(end 1.1049 -0.724916)
			(stroke
				(width 0.1)
				(type default)
			)
			(layer "B.Fab")
		)
		(fp_line
			(start 1.1049 -0.724916)
			(end 1.1049 0.724916)
			(stroke
				(width 0.1)
				(type default)
			)
			(layer "B.Fab")
		)
		(pad "1" smd rect
			(at 0.889 0 270)
			(size 1.016 1.27)
			(layers "B.Cu" "B.Mask" "B.Paste")
			(net "SW_P3V3_AUX_FLT")
		)
		(pad "2" smd rect
			(at -0.889 0 270)
			(size 1.016 1.27)
			(layers "B.Cu" "B.Mask" "B.Paste")
			(net "GND")
		)
	)
	(footprint ""
		(layer "B.Cu")
		(at 117.141244 -415.9123 -90)
		(property "Reference" "R3504"
			(at 0 0 90)
			(layer "B.SilkS")
			(hide yes)
			(effects
				(font
					(size 1.27 1.27)
				)
				(justify mirror)
			)
		)
		(property "Value" ""
			(at 0 0 90)
			(layer "B.Fab")
			(effects
				(font
					(size 1.27 1.27)
				)
				(justify mirror)
			)
		)
		(duplicate_pad_numbers_are_jumpers no)
		(fp_line
			(start -0.7874 0.4064)
			(end 0.7874 0.4064)
			(stroke
				(width 0.1524)
				(type default)
			)
			(layer "B.SilkS")
		)
		(fp_line
			(start 0.7874 0.4064)
			(end 0.7874 -0.4064)
			(stroke
				(width 0.1524)
				(type default)
			)
			(layer "B.SilkS")
		)
		(fp_line
			(start -0.7874 -0.4064)
			(end -0.7874 0.4064)
			(stroke
				(width 0.1524)
				(type default)
			)
			(layer "B.SilkS")
		)
		(fp_line
			(start 0.7874 -0.4064)
			(end -0.7874 -0.4064)
			(stroke
				(width 0.1524)
				(type default)
			)
			(layer "B.SilkS")
		)
		(fp_line
			(start -0.67945 0.3048)
			(end -0.120396 0.3048)
			(stroke
				(width 0.1)
				(type default)
			)
			(layer "B.Fab")
		)
		(fp_line
			(start -0.120396 0.3048)
			(end -0.120396 0.2794)
			(stroke
				(width 0.1)
				(type default)
			)
			(layer "B.Fab")
		)
		(fp_line
			(start 0.12065 0.3048)
			(end 0.67945 0.3048)
			(stroke
				(width 0.1)
				(type default)
			)
			(layer "B.Fab")
		)
		(fp_line
			(start 0.67945 0.3048)
			(end 0.67945 -0.305054)
			(stroke
				(width 0.1)
				(type default)
			)
			(layer "B.Fab")
		)
		(fp_line
			(start -0.120396 0.2794)
			(end 0.12065 0.2794)
			(stroke
				(width 0.1)
				(type default)
			)
			(layer "B.Fab")
		)
		(fp_line
			(start 0.12065 0.2794)
			(end 0.12065 0.3048)
			(stroke
				(width 0.1)
				(type default)
			)
			(layer "B.Fab")
		)
		(fp_line
			(start -0.12065 -0.2794)
			(end -0.12065 -0.3048)
			(stroke
				(width 0.1)
				(type default)
			)
			(layer "B.Fab")
		)
		(fp_line
			(start 0.12065 -0.2794)
			(end -0.12065 -0.2794)
			(stroke
				(width 0.1)
				(type default)
			)
			(layer "B.Fab")
		)
		(fp_line
			(start -0.67945 -0.3048)
			(end -0.67945 0.3048)
			(stroke
				(width 0.1)
				(type default)
			)
			(layer "B.Fab")
		)
		(fp_line
			(start -0.12065 -0.3048)
			(end -0.67945 -0.3048)
			(stroke
				(width 0.1)
				(type default)
			)
			(layer "B.Fab")
		)
		(fp_line
			(start 0.12065 -0.305054)
			(end 0.12065 -0.2794)
			(stroke
				(width 0.1)
				(type default)
			)
			(layer "B.Fab")
		)
		(fp_line
			(start 0.67945 -0.305054)
			(end 0.12065 -0.305054)
			(stroke
				(width 0.1)
				(type default)
			)
			(layer "B.Fab")
		)
		(pad "1" smd circle
			(at 0.40005 0 90)
			(size 0 0)
			(layers "B.Cu" "B.Mask" "B.Paste")
			(net "P3V3_AUX")
		)
		(pad "2" smd circle
			(at -0.40005 0 90)
			(size 0 0)
			(layers "B.Cu" "B.Mask" "B.Paste")
			(net "GPU_FPGA_EROT_FATALERR_ISO_N")
		)
	)
	(footprint ""
		(layer "B.Cu")
		(at 164.900864 -420.184834 90)
		(property "Reference" "R827"
			(at 0 0 90)
			(layer "B.SilkS")
			(hide yes)
			(effects
				(font
					(size 1.27 1.27)
				)
				(justify mirror)
			)
		)
		(property "Value" ""
			(at 0 0 90)
			(layer "B.Fab")
			(effects
				(font
					(size 1.27 1.27)
				)
				(justify mirror)
			)
		)
		(duplicate_pad_numbers_are_jumpers no)
		(fp_line
			(start 0.32512 -0.175006)
			(end -0.32512 -0.175006)
			(stroke
				(width 0.1)
				(type default)
			)
			(layer "B.Fab")
		)
		(fp_line
			(start -0.32512 -0.175006)
			(end -0.32512 0.175006)
			(stroke
				(width 0.1)
				(type default)
			)
			(layer "B.Fab")
		)
		(fp_line
			(start 0.32512 0.175006)
			(end 0.32512 -0.175006)
			(stroke
				(width 0.1)
				(type default)
			)
			(layer "B.Fab")
		)
		(fp_line
			(start -0.32512 0.175006)
			(end 0.32512 0.175006)
			(stroke
				(width 0.1)
				(type default)
			)
			(layer "B.Fab")
		)
		(pad "1" smd rect
			(at 0.2667 0 270)
			(size 0.3048 0.381)
			(layers "B.Cu" "B.Mask" "B.Paste")
			(net "P1V8_CPU1_RT_1D")
		)
		(pad "2" smd rect
			(at -0.2667 0 90)
			(size 0.3048 0.381)
			(layers "B.Cu" "B.Mask" "B.Paste")
			(net "SMB_RT_CPU1_P2_ROM_R_SCL")
		)
	)
	(footprint ""
		(layer "B.Cu")
		(at 89.614502 -205.14945 90)
		(property "Reference" "R540"
			(at 0 0 90)
			(layer "B.SilkS")
			(hide yes)
			(effects
				(font
					(size 1.27 1.27)
				)
				(justify mirror)
			)
		)
		(property "Value" ""
			(at 0 0 90)
			(layer "B.Fab")
			(effects
				(font
					(size 1.27 1.27)
				)
				(justify mirror)
			)
		)
		(duplicate_pad_numbers_are_jumpers no)
		(fp_line
			(start 0.7874 -0.4064)
			(end -0.7874 -0.4064)
			(stroke
				(width 0.1524)
				(type default)
			)
			(layer "B.SilkS")
		)
		(fp_line
			(start -0.7874 -0.4064)
			(end -0.7874 0.4064)
			(stroke
				(width 0.1524)
				(type default)
			)
			(layer "B.SilkS")
		)
		(fp_line
			(start 0.7874 0.4064)
			(end 0.7874 -0.4064)
			(stroke
				(width 0.1524)
				(type default)
			)
			(layer "B.SilkS")
		)
		(fp_line
			(start -0.7874 0.4064)
			(end 0.7874 0.4064)
			(stroke
				(width 0.1524)
				(type default)
			)
			(layer "B.SilkS")
		)
		(fp_line
			(start 0.67945 -0.305054)
			(end 0.12065 -0.305054)
			(stroke
				(width 0.1)
				(type default)
			)
			(layer "B.Fab")
		)
		(fp_line
			(start 0.12065 -0.305054)
			(end 0.12065 -0.2794)
			(stroke
				(width 0.1)
				(type default)
			)
			(layer "B.Fab")
		)
		(fp_line
			(start -0.12065 -0.3048)
			(end -0.67945 -0.3048)
			(stroke
				(width 0.1)
				(type default)
			)
			(layer "B.Fab")
		)
		(fp_line
			(start -0.67945 -0.3048)
			(end -0.67945 0.3048)
			(stroke
				(width 0.1)
				(type default)
			)
			(layer "B.Fab")
		)
		(fp_line
			(start 0.12065 -0.2794)
			(end -0.12065 -0.2794)
			(stroke
				(width 0.1)
				(type default)
			)
			(layer "B.Fab")
		)
		(fp_line
			(start -0.12065 -0.2794)
			(end -0.12065 -0.3048)
			(stroke
				(width 0.1)
				(type default)
			)
			(layer "B.Fab")
		)
		(fp_line
			(start 0.12065 0.2794)
			(end 0.12065 0.3048)
			(stroke
				(width 0.1)
				(type default)
			)
			(layer "B.Fab")
		)
		(fp_line
			(start -0.120396 0.2794)
			(end 0.12065 0.2794)
			(stroke
				(width 0.1)
				(type default)
			)
			(layer "B.Fab")
		)
		(fp_line
			(start 0.67945 0.3048)
			(end 0.67945 -0.305054)
			(stroke
				(width 0.1)
				(type default)
			)
			(layer "B.Fab")
		)
		(fp_line
			(start 0.12065 0.3048)
			(end 0.67945 0.3048)
			(stroke
				(width 0.1)
				(type default)
			)
			(layer "B.Fab")
		)
		(fp_line
			(start -0.120396 0.3048)
			(end -0.120396 0.2794)
			(stroke
				(width 0.1)
				(type default)
			)
			(layer "B.Fab")
		)
		(fp_line
			(start -0.67945 0.3048)
			(end -0.120396 0.3048)
			(stroke
				(width 0.1)
				(type default)
			)
			(layer "B.Fab")
		)
		(pad "1" smd circle
			(at 0.40005 0 270)
			(size 0 0)
			(layers "B.Cu" "B.Mask" "B.Paste")
			(net "CPU1_XTRIG_L7")
		)
		(pad "2" smd circle
			(at -0.40005 0 270)
			(size 0 0)
			(layers "B.Cu" "B.Mask" "B.Paste")
			(net "PVDD18_S5_P1")
		)
	)
	(footprint ""
		(layer "B.Cu")
		(at 202.00112 -331.027786 -90)
		(property "Reference" "PC134"
			(at 0 0 90)
			(layer "B.SilkS")
			(hide yes)
			(effects
				(font
					(size 1.27 1.27)
				)
				(justify mirror)
			)
		)
		(property "Value" ""
			(at 0 0 90)
			(layer "B.Fab")
			(effects
				(font
					(size 1.27 1.27)
				)
				(justify mirror)
			)
		)
		(duplicate_pad_numbers_are_jumpers no)
		(fp_line
			(start -1.524 0.762)
			(end 1.524 0.762)
			(stroke
				(width 0.1524)
				(type default)
			)
			(layer "B.SilkS")
		)
		(fp_line
			(start 1.524 0.762)
			(end 1.524 -0.762)
			(stroke
				(width 0.1524)
				(type default)
			)
			(layer "B.SilkS")
		)
		(fp_line
			(start -1.524 -0.762)
			(end -1.524 0.762)
			(stroke
				(width 0.1524)
				(type default)
			)
			(layer "B.SilkS")
		)
		(fp_line
			(start 1.524 -0.762)
			(end -1.524 -0.762)
			(stroke
				(width 0.1524)
				(type default)
			)
			(layer "B.SilkS")
		)
		(fp_line
			(start -1.1049 0.724916)
			(end -1.1049 -0.724916)
			(stroke
				(width 0.1)
				(type default)
			)
			(layer "B.Fab")
		)
		(fp_line
			(start 1.1049 0.724916)
			(end -1.1049 0.724916)
			(stroke
				(width 0.1)
				(type default)
			)
			(layer "B.Fab")
		)
		(fp_line
			(start -1.1049 -0.724916)
			(end 1.1049 -0.724916)
			(stroke
				(width 0.1)
				(type default)
			)
			(layer "B.Fab")
		)
		(fp_line
			(start 1.1049 -0.724916)
			(end 1.1049 0.724916)
			(stroke
				(width 0.1)
				(type default)
			)
			(layer "B.Fab")
		)
		(pad "1" smd rect
			(at 0.889 0 270)
			(size 1.016 1.27)
			(layers "B.Cu" "B.Mask" "B.Paste")
			(net "PVDD_33_S5")
		)
		(pad "2" smd rect
			(at -0.889 0 270)
			(size 1.016 1.27)
			(layers "B.Cu" "B.Mask" "B.Paste")
			(net "GND")
		)
	)
	(footprint ""
		(layer "B.Cu")
		(at 373.329454 -258.830064)
		(property "Reference" "C2585"
			(at 0 0 0)
			(layer "B.SilkS")
			(hide yes)
			(effects
				(font
					(size 1.27 1.27)
				)
				(justify mirror)
			)
		)
		(property "Value" ""
			(at 0 0 0)
			(layer "B.Fab")
			(effects
				(font
					(size 1.27 1.27)
				)
				(justify mirror)
			)
		)
		(duplicate_pad_numbers_are_jumpers no)
		(fp_line
			(start -0.7874 -0.4064)
			(end -0.7874 0.4064)
			(stroke
				(width 0.1524)
				(type default)
			)
			(layer "B.SilkS")
		)
		(fp_line
			(start -0.7874 0.4064)
			(end 0.7874 0.4064)
			(stroke
				(width 0.1524)
				(type default)
			)
			(layer "B.SilkS")
		)
		(fp_line
			(start 0.7874 -0.4064)
			(end -0.7874 -0.4064)
			(stroke
				(width 0.1524)
				(type default)
			)
			(layer "B.SilkS")
		)
		(fp_line
			(start 0.7874 0.4064)
			(end 0.7874 -0.4064)
			(stroke
				(width 0.1524)
				(type default)
			)
			(layer "B.SilkS")
		)
		(fp_line
			(start -0.67945 -0.3048)
			(end -0.67945 0.3048)
			(stroke
				(width 0.1)
				(type default)
			)
			(layer "B.Fab")
		)
		(fp_line
			(start -0.67945 0.3048)
			(end -0.120396 0.3048)
			(stroke
				(width 0.1)
				(type default)
			)
			(layer "B.Fab")
		)
		(fp_line
			(start -0.12065 -0.3048)
			(end -0.67945 -0.3048)
			(stroke
				(width 0.1)
				(type default)
			)
			(layer "B.Fab")
		)
		(fp_line
			(start -0.12065 -0.2794)
			(end -0.12065 -0.3048)
			(stroke
				(width 0.1)
				(type default)
			)
			(layer "B.Fab")
		)
		(fp_line
			(start -0.120396 0.2794)
			(end 0.12065 0.2794)
			(stroke
				(width 0.1)
				(type default)
			)
			(layer "B.Fab")
		)
		(fp_line
			(start -0.120396 0.3048)
			(end -0.120396 0.2794)
			(stroke
				(width 0.1)
				(type default)
			)
			(layer "B.Fab")
		)
		(fp_line
			(start 0.12065 -0.305054)
			(end 0.12065 -0.2794)
			(stroke
				(width 0.1)
				(type default)
			)
			(layer "B.Fab")
		)
		(fp_line
			(start 0.12065 -0.2794)
			(end -0.12065 -0.2794)
			(stroke
				(width 0.1)
				(type default)
			)
			(layer "B.Fab")
		)
		(fp_line
			(start 0.12065 0.2794)
			(end 0.12065 0.3048)
			(stroke
				(width 0.1)
				(type default)
			)
			(layer "B.Fab")
		)
		(fp_line
			(start 0.12065 0.3048)
			(end 0.67945 0.3048)
			(stroke
				(width 0.1)
				(type default)
			)
			(layer "B.Fab")
		)
		(fp_line
			(start 0.67945 -0.305054)
			(end 0.12065 -0.305054)
			(stroke
				(width 0.1)
				(type default)
			)
			(layer "B.Fab")
		)
		(fp_line
			(start 0.67945 0.3048)
			(end 0.67945 -0.305054)
			(stroke
				(width 0.1)
				(type default)
			)
			(layer "B.Fab")
		)
		(pad "1" smd circle
			(at 0.40005 0 180)
			(size 0 0)
			(layers "B.Cu" "B.Mask" "B.Paste")
			(net "PVDDCR_SOC_P0")
		)
		(pad "2" smd circle
			(at -0.40005 0 180)
			(size 0 0)
			(layers "B.Cu" "B.Mask" "B.Paste")
			(net "GND")
		)
	)
	(footprint ""
		(layer "B.Cu")
		(at 165.006274 -386.766562 90)
		(property "Reference" "C382"
			(at 0 0 90)
			(layer "B.SilkS")
			(hide yes)
			(effects
				(font
					(size 1.27 1.27)
				)
				(justify mirror)
			)
		)
		(property "Value" ""
			(at 0 0 90)
			(layer "B.Fab")
			(effects
				(font
					(size 1.27 1.27)
				)
				(justify mirror)
			)
		)
		(duplicate_pad_numbers_are_jumpers no)
		(fp_line
			(start 0.299974 -0.150114)
			(end -0.299974 -0.150114)
			(stroke
				(width 0.1)
				(type default)
			)
			(layer "B.Fab")
		)
		(fp_line
			(start -0.299974 -0.150114)
			(end -0.299974 0.150114)
			(stroke
				(width 0.1)
				(type default)
			)
			(layer "B.Fab")
		)
		(fp_line
			(start 0.299974 0.150114)
			(end 0.299974 -0.150114)
			(stroke
				(width 0.1)
				(type default)
			)
			(layer "B.Fab")
		)
		(fp_line
			(start -0.299974 0.150114)
			(end 0.299974 0.150114)
			(stroke
				(width 0.1)
				(type default)
			)
			(layer "B.Fab")
		)
		(pad "1" smd rect
			(at 0.2667 0 270)
			(size 0.3048 0.381)
			(layers "B.Cu" "B.Mask" "B.Paste")
			(net "P0V9_CPU1_RT2_2A")
		)
		(pad "2" smd rect
			(at -0.2667 0 270)
			(size 0.3048 0.381)
			(layers "B.Cu" "B.Mask" "B.Paste")
			(net "GND")
		)
	)
	(footprint ""
		(layer "B.Cu")
		(at 130.104642 -72.39254)
		(property "Reference" "PC6026"
			(at 0 0 0)
			(layer "B.SilkS")
			(hide yes)
			(effects
				(font
					(size 1.27 1.27)
				)
				(justify mirror)
			)
		)
		(property "Value" ""
			(at 0 0 0)
			(layer "B.Fab")
			(effects
				(font
					(size 1.27 1.27)
				)
				(justify mirror)
			)
		)
		(duplicate_pad_numbers_are_jumpers no)
		(fp_line
			(start -1.524 -0.762)
			(end -1.524 0.762)
			(stroke
				(width 0.1524)
				(type default)
			)
			(layer "B.SilkS")
		)
		(fp_line
			(start -1.524 0.762)
			(end 1.524 0.762)
			(stroke
				(width 0.1524)
				(type default)
			)
			(layer "B.SilkS")
		)
		(fp_line
			(start 1.524 -0.762)
			(end -1.524 -0.762)
			(stroke
				(width 0.1524)
				(type default)
			)
			(layer "B.SilkS")
		)
		(fp_line
			(start 1.524 0.762)
			(end 1.524 -0.762)
			(stroke
				(width 0.1524)
				(type default)
			)
			(layer "B.SilkS")
		)
		(fp_line
			(start -1.1049 -0.724916)
			(end 1.1049 -0.724916)
			(stroke
				(width 0.1)
				(type default)
			)
			(layer "B.Fab")
		)
		(fp_line
			(start -1.1049 0.724916)
			(end -1.1049 -0.724916)
			(stroke
				(width 0.1)
				(type default)
			)
			(layer "B.Fab")
		)
		(fp_line
			(start 1.1049 -0.724916)
			(end 1.1049 0.724916)
			(stroke
				(width 0.1)
				(type default)
			)
			(layer "B.Fab")
		)
		(fp_line
			(start 1.1049 0.724916)
			(end -1.1049 0.724916)
			(stroke
				(width 0.1)
				(type default)
			)
			(layer "B.Fab")
		)
		(pad "1" smd rect
			(at 0.889 0)
			(size 1.016 1.27)
			(layers "B.Cu" "B.Mask" "B.Paste")
			(net "P1V2_AUX")
		)
		(pad "2" smd rect
			(at -0.889 0)
			(size 1.016 1.27)
			(layers "B.Cu" "B.Mask" "B.Paste")
			(net "GND")
		)
	)
	(footprint ""
		(layer "B.Cu")
		(at 13.018262 -389.526526 -90)
		(property "Reference" "PR6621"
			(at 0 0 90)
			(layer "B.SilkS")
			(hide yes)
			(effects
				(font
					(size 1.27 1.27)
				)
				(justify mirror)
			)
		)
		(property "Value" ""
			(at 0 0 90)
			(layer "B.Fab")
			(effects
				(font
					(size 1.27 1.27)
				)
				(justify mirror)
			)
		)
		(duplicate_pad_numbers_are_jumpers no)
		(fp_line
			(start -0.7874 0.4064)
			(end 0.7874 0.4064)
			(stroke
				(width 0.1524)
				(type default)
			)
			(layer "B.SilkS")
		)
		(fp_line
			(start 0.7874 0.4064)
			(end 0.7874 -0.4064)
			(stroke
				(width 0.1524)
				(type default)
			)
			(layer "B.SilkS")
		)
		(fp_line
			(start -0.7874 -0.4064)
			(end -0.7874 0.4064)
			(stroke
				(width 0.1524)
				(type default)
			)
			(layer "B.SilkS")
		)
		(fp_line
			(start 0.7874 -0.4064)
			(end -0.7874 -0.4064)
			(stroke
				(width 0.1524)
				(type default)
			)
			(layer "B.SilkS")
		)
		(fp_line
			(start -0.67945 0.3048)
			(end -0.120396 0.3048)
			(stroke
				(width 0.1)
				(type default)
			)
			(layer "B.Fab")
		)
		(fp_line
			(start -0.120396 0.3048)
			(end -0.120396 0.2794)
			(stroke
				(width 0.1)
				(type default)
			)
			(layer "B.Fab")
		)
		(fp_line
			(start 0.12065 0.3048)
			(end 0.67945 0.3048)
			(stroke
				(width 0.1)
				(type default)
			)
			(layer "B.Fab")
		)
		(fp_line
			(start 0.67945 0.3048)
			(end 0.67945 -0.305054)
			(stroke
				(width 0.1)
				(type default)
			)
			(layer "B.Fab")
		)
		(fp_line
			(start -0.120396 0.2794)
			(end 0.12065 0.2794)
			(stroke
				(width 0.1)
				(type default)
			)
			(layer "B.Fab")
		)
		(fp_line
			(start 0.12065 0.2794)
			(end 0.12065 0.3048)
			(stroke
				(width 0.1)
				(type default)
			)
			(layer "B.Fab")
		)
		(fp_line
			(start -0.12065 -0.2794)
			(end -0.12065 -0.3048)
			(stroke
				(width 0.1)
				(type default)
			)
			(layer "B.Fab")
		)
		(fp_line
			(start 0.12065 -0.2794)
			(end -0.12065 -0.2794)
			(stroke
				(width 0.1)
				(type default)
			)
			(layer "B.Fab")
		)
		(fp_line
			(start -0.67945 -0.3048)
			(end -0.67945 0.3048)
			(stroke
				(width 0.1)
				(type default)
			)
			(layer "B.Fab")
		)
		(fp_line
			(start -0.12065 -0.3048)
			(end -0.67945 -0.3048)
			(stroke
				(width 0.1)
				(type default)
			)
			(layer "B.Fab")
		)
		(fp_line
			(start 0.12065 -0.305054)
			(end 0.12065 -0.2794)
			(stroke
				(width 0.1)
				(type default)
			)
			(layer "B.Fab")
		)
		(fp_line
			(start 0.67945 -0.305054)
			(end 0.12065 -0.305054)
			(stroke
				(width 0.1)
				(type default)
			)
			(layer "B.Fab")
		)
		(pad "1" smd circle
			(at 0.40005 0 90)
			(size 0 0)
			(layers "B.Cu" "B.Mask" "B.Paste")
			(net "P0V9_RETIMER_CPU1_PVCC")
		)
		(pad "2" smd circle
			(at -0.40005 0 90)
			(size 0 0)
			(layers "B.Cu" "B.Mask" "B.Paste")
			(net "P0V9_RETIMER_CPU1_VCC1")
		)
	)
	(footprint ""
		(layer "B.Cu")
		(at 136.93648 -9.032748 -90)
		(property "Reference" "R3777"
			(at 0 0 90)
			(layer "B.SilkS")
			(hide yes)
			(effects
				(font
					(size 1.27 1.27)
				)
				(justify mirror)
			)
		)
		(property "Value" ""
			(at 0 0 90)
			(layer "B.Fab")
			(effects
				(font
					(size 1.27 1.27)
				)
				(justify mirror)
			)
		)
		(duplicate_pad_numbers_are_jumpers no)
		(fp_line
			(start -0.7874 0.4064)
			(end 0.7874 0.4064)
			(stroke
				(width 0.1524)
				(type default)
			)
			(layer "B.SilkS")
		)
		(fp_line
			(start 0.7874 0.4064)
			(end 0.7874 -0.4064)
			(stroke
				(width 0.1524)
				(type default)
			)
			(layer "B.SilkS")
		)
		(fp_line
			(start -0.7874 -0.4064)
			(end -0.7874 0.4064)
			(stroke
				(width 0.1524)
				(type default)
			)
			(layer "B.SilkS")
		)
		(fp_line
			(start 0.7874 -0.4064)
			(end -0.7874 -0.4064)
			(stroke
				(width 0.1524)
				(type default)
			)
			(layer "B.SilkS")
		)
		(fp_line
			(start -0.67945 0.3048)
			(end -0.120396 0.3048)
			(stroke
				(width 0.1)
				(type default)
			)
			(layer "B.Fab")
		)
		(fp_line
			(start -0.120396 0.3048)
			(end -0.120396 0.2794)
			(stroke
				(width 0.1)
				(type default)
			)
			(layer "B.Fab")
		)
		(fp_line
			(start 0.12065 0.3048)
			(end 0.67945 0.3048)
			(stroke
				(width 0.1)
				(type default)
			)
			(layer "B.Fab")
		)
		(fp_line
			(start 0.67945 0.3048)
			(end 0.67945 -0.305054)
			(stroke
				(width 0.1)
				(type default)
			)
			(layer "B.Fab")
		)
		(fp_line
			(start -0.120396 0.2794)
			(end 0.12065 0.2794)
			(stroke
				(width 0.1)
				(type default)
			)
			(layer "B.Fab")
		)
		(fp_line
			(start 0.12065 0.2794)
			(end 0.12065 0.3048)
			(stroke
				(width 0.1)
				(type default)
			)
			(layer "B.Fab")
		)
		(fp_line
			(start -0.12065 -0.2794)
			(end -0.12065 -0.3048)
			(stroke
				(width 0.1)
				(type default)
			)
			(layer "B.Fab")
		)
		(fp_line
			(start 0.12065 -0.2794)
			(end -0.12065 -0.2794)
			(stroke
				(width 0.1)
				(type default)
			)
			(layer "B.Fab")
		)
		(fp_line
			(start -0.67945 -0.3048)
			(end -0.67945 0.3048)
			(stroke
				(width 0.1)
				(type default)
			)
			(layer "B.Fab")
		)
		(fp_line
			(start -0.12065 -0.3048)
			(end -0.67945 -0.3048)
			(stroke
				(width 0.1)
				(type default)
			)
			(layer "B.Fab")
		)
		(fp_line
			(start 0.12065 -0.305054)
			(end 0.12065 -0.2794)
			(stroke
				(width 0.1)
				(type default)
			)
			(layer "B.Fab")
		)
		(fp_line
			(start 0.67945 -0.305054)
			(end 0.12065 -0.305054)
			(stroke
				(width 0.1)
				(type default)
			)
			(layer "B.Fab")
		)
		(pad "1" smd circle
			(at 0.40005 0 90)
			(size 0 0)
			(layers "B.Cu" "B.Mask" "B.Paste")
			(net "FM_UARTSW_LSB_N")
		)
		(pad "2" smd circle
			(at -0.40005 0 90)
			(size 0 0)
			(layers "B.Cu" "B.Mask" "B.Paste")
			(net "FM_UARTSW_LSB_R")
		)
	)
	(footprint ""
		(layer "B.Cu")
		(at 175.316388 -193.996564)
		(property "Reference" "C164"
			(at 0 0 0)
			(layer "B.SilkS")
			(hide yes)
			(effects
				(font
					(size 1.27 1.27)
				)
				(justify mirror)
			)
		)
		(property "Value" ""
			(at 0 0 0)
			(layer "B.Fab")
			(effects
				(font
					(size 1.27 1.27)
				)
				(justify mirror)
			)
		)
		(duplicate_pad_numbers_are_jumpers no)
		(fp_line
			(start -0.7874 -0.4064)
			(end -0.7874 0.4064)
			(stroke
				(width 0.1524)
				(type default)
			)
			(layer "B.SilkS")
		)
		(fp_line
			(start -0.7874 0.4064)
			(end 0.7874 0.4064)
			(stroke
				(width 0.1524)
				(type default)
			)
			(layer "B.SilkS")
		)
		(fp_line
			(start 0.7874 -0.4064)
			(end -0.7874 -0.4064)
			(stroke
				(width 0.1524)
				(type default)
			)
			(layer "B.SilkS")
		)
		(fp_line
			(start 0.7874 0.4064)
			(end 0.7874 -0.4064)
			(stroke
				(width 0.1524)
				(type default)
			)
			(layer "B.SilkS")
		)
		(fp_line
			(start -0.67945 -0.3048)
			(end -0.67945 0.3048)
			(stroke
				(width 0.1)
				(type default)
			)
			(layer "B.Fab")
		)
		(fp_line
			(start -0.67945 0.3048)
			(end -0.120396 0.3048)
			(stroke
				(width 0.1)
				(type default)
			)
			(layer "B.Fab")
		)
		(fp_line
			(start -0.12065 -0.3048)
			(end -0.67945 -0.3048)
			(stroke
				(width 0.1)
				(type default)
			)
			(layer "B.Fab")
		)
		(fp_line
			(start -0.12065 -0.2794)
			(end -0.12065 -0.3048)
			(stroke
				(width 0.1)
				(type default)
			)
			(layer "B.Fab")
		)
		(fp_line
			(start -0.120396 0.2794)
			(end 0.12065 0.2794)
			(stroke
				(width 0.1)
				(type default)
			)
			(layer "B.Fab")
		)
		(fp_line
			(start -0.120396 0.3048)
			(end -0.120396 0.2794)
			(stroke
				(width 0.1)
				(type default)
			)
			(layer "B.Fab")
		)
		(fp_line
			(start 0.12065 -0.305054)
			(end 0.12065 -0.2794)
			(stroke
				(width 0.1)
				(type default)
			)
			(layer "B.Fab")
		)
		(fp_line
			(start 0.12065 -0.2794)
			(end -0.12065 -0.2794)
			(stroke
				(width 0.1)
				(type default)
			)
			(layer "B.Fab")
		)
		(fp_line
			(start 0.12065 0.2794)
			(end 0.12065 0.3048)
			(stroke
				(width 0.1)
				(type default)
			)
			(layer "B.Fab")
		)
		(fp_line
			(start 0.12065 0.3048)
			(end 0.67945 0.3048)
			(stroke
				(width 0.1)
				(type default)
			)
			(layer "B.Fab")
		)
		(fp_line
			(start 0.67945 -0.305054)
			(end 0.12065 -0.305054)
			(stroke
				(width 0.1)
				(type default)
			)
			(layer "B.Fab")
		)
		(fp_line
			(start 0.67945 0.3048)
			(end 0.67945 -0.305054)
			(stroke
				(width 0.1)
				(type default)
			)
			(layer "B.Fab")
		)
		(pad "1" smd circle
			(at 0.40005 0 180)
			(size 0 0)
			(layers "B.Cu" "B.Mask" "B.Paste")
			(net "P3V3_AUX")
		)
		(pad "2" smd circle
			(at -0.40005 0 180)
			(size 0 0)
			(layers "B.Cu" "B.Mask" "B.Paste")
			(net "GND")
		)
	)
	(footprint ""
		(layer "B.Cu")
		(at 98.984054 -326.825102 -90)
		(property "Reference" "PC430_5"
			(at 0 0 90)
			(layer "B.SilkS")
			(hide yes)
			(effects
				(font
					(size 1.27 1.27)
				)
				(justify mirror)
			)
		)
		(property "Value" ""
			(at 0 0 90)
			(layer "B.Fab")
			(effects
				(font
					(size 1.27 1.27)
				)
				(justify mirror)
			)
		)
		(duplicate_pad_numbers_are_jumpers no)
		(fp_line
			(start -1.524 0.762)
			(end 1.524 0.762)
			(stroke
				(width 0.1524)
				(type default)
			)
			(layer "B.SilkS")
		)
		(fp_line
			(start 1.524 0.762)
			(end 1.524 -0.762)
			(stroke
				(width 0.1524)
				(type default)
			)
			(layer "B.SilkS")
		)
		(fp_line
			(start -1.524 -0.762)
			(end -1.524 0.762)
			(stroke
				(width 0.1524)
				(type default)
			)
			(layer "B.SilkS")
		)
		(fp_line
			(start 1.524 -0.762)
			(end -1.524 -0.762)
			(stroke
				(width 0.1524)
				(type default)
			)
			(layer "B.SilkS")
		)
		(fp_line
			(start -1.1049 0.724916)
			(end -1.1049 -0.724916)
			(stroke
				(width 0.1)
				(type default)
			)
			(layer "B.Fab")
		)
		(fp_line
			(start 1.1049 0.724916)
			(end -1.1049 0.724916)
			(stroke
				(width 0.1)
				(type default)
			)
			(layer "B.Fab")
		)
		(fp_line
			(start -1.1049 -0.724916)
			(end 1.1049 -0.724916)
			(stroke
				(width 0.1)
				(type default)
			)
			(layer "B.Fab")
		)
		(fp_line
			(start 1.1049 -0.724916)
			(end 1.1049 0.724916)
			(stroke
				(width 0.1)
				(type default)
			)
			(layer "B.Fab")
		)
		(pad "1" smd rect
			(at 0.889 0 270)
			(size 1.016 1.27)
			(layers "B.Cu" "B.Mask" "B.Paste")
			(net "PVDDCR_CPU1_P1")
		)
		(pad "2" smd rect
			(at -0.889 0 270)
			(size 1.016 1.27)
			(layers "B.Cu" "B.Mask" "B.Paste")
			(net "GND")
		)
	)
	(footprint ""
		(layer "B.Cu")
		(at 187.349384 -13.60043 -90)
		(property "Reference" "R6003"
			(at 0 0 90)
			(layer "B.SilkS")
			(hide yes)
			(effects
				(font
					(size 1.27 1.27)
				)
				(justify mirror)
			)
		)
		(property "Value" ""
			(at 0 0 90)
			(layer "B.Fab")
			(effects
				(font
					(size 1.27 1.27)
				)
				(justify mirror)
			)
		)
		(duplicate_pad_numbers_are_jumpers no)
		(fp_line
			(start -0.7874 0.4064)
			(end 0.7874 0.4064)
			(stroke
				(width 0.1524)
				(type default)
			)
			(layer "B.SilkS")
		)
		(fp_line
			(start 0.7874 0.4064)
			(end 0.7874 -0.4064)
			(stroke
				(width 0.1524)
				(type default)
			)
			(layer "B.SilkS")
		)
		(fp_line
			(start -0.7874 -0.4064)
			(end -0.7874 0.4064)
			(stroke
				(width 0.1524)
				(type default)
			)
			(layer "B.SilkS")
		)
		(fp_line
			(start 0.7874 -0.4064)
			(end -0.7874 -0.4064)
			(stroke
				(width 0.1524)
				(type default)
			)
			(layer "B.SilkS")
		)
		(fp_line
			(start -0.67945 0.3048)
			(end -0.120396 0.3048)
			(stroke
				(width 0.1)
				(type default)
			)
			(layer "B.Fab")
		)
		(fp_line
			(start -0.120396 0.3048)
			(end -0.120396 0.2794)
			(stroke
				(width 0.1)
				(type default)
			)
			(layer "B.Fab")
		)
		(fp_line
			(start 0.12065 0.3048)
			(end 0.67945 0.3048)
			(stroke
				(width 0.1)
				(type default)
			)
			(layer "B.Fab")
		)
		(fp_line
			(start 0.67945 0.3048)
			(end 0.67945 -0.305054)
			(stroke
				(width 0.1)
				(type default)
			)
			(layer "B.Fab")
		)
		(fp_line
			(start -0.120396 0.2794)
			(end 0.12065 0.2794)
			(stroke
				(width 0.1)
				(type default)
			)
			(layer "B.Fab")
		)
		(fp_line
			(start 0.12065 0.2794)
			(end 0.12065 0.3048)
			(stroke
				(width 0.1)
				(type default)
			)
			(layer "B.Fab")
		)
		(fp_line
			(start -0.12065 -0.2794)
			(end -0.12065 -0.3048)
			(stroke
				(width 0.1)
				(type default)
			)
			(layer "B.Fab")
		)
		(fp_line
			(start 0.12065 -0.2794)
			(end -0.12065 -0.2794)
			(stroke
				(width 0.1)
				(type default)
			)
			(layer "B.Fab")
		)
		(fp_line
			(start -0.67945 -0.3048)
			(end -0.67945 0.3048)
			(stroke
				(width 0.1)
				(type default)
			)
			(layer "B.Fab")
		)
		(fp_line
			(start -0.12065 -0.3048)
			(end -0.67945 -0.3048)
			(stroke
				(width 0.1)
				(type default)
			)
			(layer "B.Fab")
		)
		(fp_line
			(start 0.12065 -0.305054)
			(end 0.12065 -0.2794)
			(stroke
				(width 0.1)
				(type default)
			)
			(layer "B.Fab")
		)
		(fp_line
			(start 0.67945 -0.305054)
			(end 0.12065 -0.305054)
			(stroke
				(width 0.1)
				(type default)
			)
			(layer "B.Fab")
		)
		(pad "1" smd circle
			(at 0.40005 0 90)
			(size 0 0)
			(layers "B.Cu" "B.Mask" "B.Paste")
			(net "I3C_SCM_1_SDA")
		)
		(pad "2" smd circle
			(at -0.40005 0 90)
			(size 0 0)
			(layers "B.Cu" "B.Mask" "B.Paste")
			(net "I3C_SCM_1_R_SDA")
		)
	)
	(footprint ""
		(layer "B.Cu")
		(at 91.493594 -303.255172 180)
		(property "Reference" "R519"
			(at 0 0 0)
			(layer "B.SilkS")
			(hide yes)
			(effects
				(font
					(size 1.27 1.27)
				)
				(justify mirror)
			)
		)
		(property "Value" ""
			(at 0 0 0)
			(layer "B.Fab")
			(effects
				(font
					(size 1.27 1.27)
				)
				(justify mirror)
			)
		)
		(duplicate_pad_numbers_are_jumpers no)
		(fp_line
			(start 0.7874 0.4064)
			(end 0.7874 -0.4064)
			(stroke
				(width 0.1524)
				(type default)
			)
			(layer "B.SilkS")
		)
		(fp_line
			(start 0.7874 -0.4064)
			(end -0.7874 -0.4064)
			(stroke
				(width 0.1524)
				(type default)
			)
			(layer "B.SilkS")
		)
		(fp_line
			(start -0.7874 0.4064)
			(end 0.7874 0.4064)
			(stroke
				(width 0.1524)
				(type default)
			)
			(layer "B.SilkS")
		)
		(fp_line
			(start -0.7874 -0.4064)
			(end -0.7874 0.4064)
			(stroke
				(width 0.1524)
				(type default)
			)
			(layer "B.SilkS")
		)
		(fp_line
			(start 0.67945 0.3048)
			(end 0.67945 -0.305054)
			(stroke
				(width 0.1)
				(type default)
			)
			(layer "B.Fab")
		)
		(fp_line
			(start 0.67945 -0.305054)
			(end 0.12065 -0.305054)
			(stroke
				(width 0.1)
				(type default)
			)
			(layer "B.Fab")
		)
		(fp_line
			(start 0.12065 0.3048)
			(end 0.67945 0.3048)
			(stroke
				(width 0.1)
				(type default)
			)
			(layer "B.Fab")
		)
		(fp_line
			(start 0.12065 0.2794)
			(end 0.12065 0.3048)
			(stroke
				(width 0.1)
				(type default)
			)
			(layer "B.Fab")
		)
		(fp_line
			(start 0.12065 -0.2794)
			(end -0.12065 -0.2794)
			(stroke
				(width 0.1)
				(type default)
			)
			(layer "B.Fab")
		)
		(fp_line
			(start 0.12065 -0.305054)
			(end 0.12065 -0.2794)
			(stroke
				(width 0.1)
				(type default)
			)
			(layer "B.Fab")
		)
		(fp_line
			(start -0.120396 0.3048)
			(end -0.120396 0.2794)
			(stroke
				(width 0.1)
				(type default)
			)
			(layer "B.Fab")
		)
		(fp_line
			(start -0.120396 0.2794)
			(end 0.12065 0.2794)
			(stroke
				(width 0.1)
				(type default)
			)
			(layer "B.Fab")
		)
		(fp_line
			(start -0.12065 -0.2794)
			(end -0.12065 -0.3048)
			(stroke
				(width 0.1)
				(type default)
			)
			(layer "B.Fab")
		)
		(fp_line
			(start -0.12065 -0.3048)
			(end -0.67945 -0.3048)
			(stroke
				(width 0.1)
				(type default)
			)
			(layer "B.Fab")
		)
		(fp_line
			(start -0.67945 0.3048)
			(end -0.120396 0.3048)
			(stroke
				(width 0.1)
				(type default)
			)
			(layer "B.Fab")
		)
		(fp_line
			(start -0.67945 -0.3048)
			(end -0.67945 0.3048)
			(stroke
				(width 0.1)
				(type default)
			)
			(layer "B.Fab")
		)
		(pad "1" smd circle
			(at 0.40005 0)
			(size 0 0)
			(layers "B.Cu" "B.Mask" "B.Paste")
			(net "CPU1_SA0")
		)
		(pad "2" smd circle
			(at -0.40005 0)
			(size 0 0)
			(layers "B.Cu" "B.Mask" "B.Paste")
			(net "GND")
		)
	)
	(footprint ""
		(layer "B.Cu")
		(at 406.606248 -395.148562 90)
		(property "Reference" "C783"
			(at 0 0 90)
			(layer "B.SilkS")
			(hide yes)
			(effects
				(font
					(size 1.27 1.27)
				)
				(justify mirror)
			)
		)
		(property "Value" ""
			(at 0 0 90)
			(layer "B.Fab")
			(effects
				(font
					(size 1.27 1.27)
				)
				(justify mirror)
			)
		)
		(duplicate_pad_numbers_are_jumpers no)
		(fp_line
			(start 0.299974 -0.150114)
			(end -0.299974 -0.150114)
			(stroke
				(width 0.1)
				(type default)
			)
			(layer "B.Fab")
		)
		(fp_line
			(start -0.299974 -0.150114)
			(end -0.299974 0.150114)
			(stroke
				(width 0.1)
				(type default)
			)
			(layer "B.Fab")
		)
		(fp_line
			(start 0.299974 0.150114)
			(end 0.299974 -0.150114)
			(stroke
				(width 0.1)
				(type default)
			)
			(layer "B.Fab")
		)
		(fp_line
			(start -0.299974 0.150114)
			(end 0.299974 0.150114)
			(stroke
				(width 0.1)
				(type default)
			)
			(layer "B.Fab")
		)
		(pad "1" smd rect
			(at 0.2667 0 270)
			(size 0.3048 0.381)
			(layers "B.Cu" "B.Mask" "B.Paste")
			(net "P0V9_CPU0_RT2_2A")
		)
		(pad "2" smd rect
			(at -0.2667 0 270)
			(size 0.3048 0.381)
			(layers "B.Cu" "B.Mask" "B.Paste")
			(net "GND")
		)
	)
	(footprint ""
		(layer "B.Cu")
		(at 304.419 -361.696 180)
		(property "Reference" "R8058"
			(at 0 0 0)
			(layer "B.SilkS")
			(hide yes)
			(effects
				(font
					(size 1.27 1.27)
				)
				(justify mirror)
			)
		)
		(property "Value" ""
			(at 0 0 0)
			(layer "B.Fab")
			(effects
				(font
					(size 1.27 1.27)
				)
				(justify mirror)
			)
		)
		(duplicate_pad_numbers_are_jumpers no)
		(fp_line
			(start 0.7874 0.4064)
			(end 0.7874 -0.4064)
			(stroke
				(width 0.1524)
				(type default)
			)
			(layer "B.SilkS")
		)
		(fp_line
			(start 0.7874 -0.4064)
			(end -0.7874 -0.4064)
			(stroke
				(width 0.1524)
				(type default)
			)
			(layer "B.SilkS")
		)
		(fp_line
			(start -0.7874 0.4064)
			(end 0.7874 0.4064)
			(stroke
				(width 0.1524)
				(type default)
			)
			(layer "B.SilkS")
		)
		(fp_line
			(start -0.7874 -0.4064)
			(end -0.7874 0.4064)
			(stroke
				(width 0.1524)
				(type default)
			)
			(layer "B.SilkS")
		)
		(fp_line
			(start 0.67945 0.3048)
			(end 0.67945 -0.305054)
			(stroke
				(width 0.1)
				(type default)
			)
			(layer "B.Fab")
		)
		(fp_line
			(start 0.67945 -0.305054)
			(end 0.12065 -0.305054)
			(stroke
				(width 0.1)
				(type default)
			)
			(layer "B.Fab")
		)
		(fp_line
			(start 0.12065 0.3048)
			(end 0.67945 0.3048)
			(stroke
				(width 0.1)
				(type default)
			)
			(layer "B.Fab")
		)
		(fp_line
			(start 0.12065 0.2794)
			(end 0.12065 0.3048)
			(stroke
				(width 0.1)
				(type default)
			)
			(layer "B.Fab")
		)
		(fp_line
			(start 0.12065 -0.2794)
			(end -0.12065 -0.2794)
			(stroke
				(width 0.1)
				(type default)
			)
			(layer "B.Fab")
		)
		(fp_line
			(start 0.12065 -0.305054)
			(end 0.12065 -0.2794)
			(stroke
				(width 0.1)
				(type default)
			)
			(layer "B.Fab")
		)
		(fp_line
			(start -0.120396 0.3048)
			(end -0.120396 0.2794)
			(stroke
				(width 0.1)
				(type default)
			)
			(layer "B.Fab")
		)
		(fp_line
			(start -0.120396 0.2794)
			(end 0.12065 0.2794)
			(stroke
				(width 0.1)
				(type default)
			)
			(layer "B.Fab")
		)
		(fp_line
			(start -0.12065 -0.2794)
			(end -0.12065 -0.3048)
			(stroke
				(width 0.1)
				(type default)
			)
			(layer "B.Fab")
		)
		(fp_line
			(start -0.12065 -0.3048)
			(end -0.67945 -0.3048)
			(stroke
				(width 0.1)
				(type default)
			)
			(layer "B.Fab")
		)
		(fp_line
			(start -0.67945 0.3048)
			(end -0.120396 0.3048)
			(stroke
				(width 0.1)
				(type default)
			)
			(layer "B.Fab")
		)
		(fp_line
			(start -0.67945 -0.3048)
			(end -0.67945 0.3048)
			(stroke
				(width 0.1)
				(type default)
			)
			(layer "B.Fab")
		)
		(pad "1" smd circle
			(at 0.40005 0)
			(size 0 0)
			(layers "B.Cu" "B.Mask" "B.Paste")
			(net "FM_PVDDCR_CPU1_P0_EN")
		)
		(pad "2" smd circle
			(at -0.40005 0)
			(size 0 0)
			(layers "B.Cu" "B.Mask" "B.Paste")
			(net "PVDDCR_CPU1_P0_EN_R")
		)
	)
	(footprint ""
		(layer "B.Cu")
		(at 361.317032 -261.747762 90)
		(property "Reference" "C2658"
			(at 0 0 90)
			(layer "B.SilkS")
			(hide yes)
			(effects
				(font
					(size 1.27 1.27)
				)
				(justify mirror)
			)
		)
		(property "Value" ""
			(at 0 0 90)
			(layer "B.Fab")
			(effects
				(font
					(size 1.27 1.27)
				)
				(justify mirror)
			)
		)
		(duplicate_pad_numbers_are_jumpers no)
		(fp_line
			(start 0.7874 -0.4064)
			(end -0.7874 -0.4064)
			(stroke
				(width 0.1524)
				(type default)
			)
			(layer "B.SilkS")
		)
		(fp_line
			(start -0.7874 -0.4064)
			(end -0.7874 0.4064)
			(stroke
				(width 0.1524)
				(type default)
			)
			(layer "B.SilkS")
		)
		(fp_line
			(start 0.7874 0.4064)
			(end 0.7874 -0.4064)
			(stroke
				(width 0.1524)
				(type default)
			)
			(layer "B.SilkS")
		)
		(fp_line
			(start -0.7874 0.4064)
			(end 0.7874 0.4064)
			(stroke
				(width 0.1524)
				(type default)
			)
			(layer "B.SilkS")
		)
		(fp_line
			(start 0.67945 -0.305054)
			(end 0.12065 -0.305054)
			(stroke
				(width 0.1)
				(type default)
			)
			(layer "B.Fab")
		)
		(fp_line
			(start 0.12065 -0.305054)
			(end 0.12065 -0.2794)
			(stroke
				(width 0.1)
				(type default)
			)
			(layer "B.Fab")
		)
		(fp_line
			(start -0.12065 -0.3048)
			(end -0.67945 -0.3048)
			(stroke
				(width 0.1)
				(type default)
			)
			(layer "B.Fab")
		)
		(fp_line
			(start -0.67945 -0.3048)
			(end -0.67945 0.3048)
			(stroke
				(width 0.1)
				(type default)
			)
			(layer "B.Fab")
		)
		(fp_line
			(start 0.12065 -0.2794)
			(end -0.12065 -0.2794)
			(stroke
				(width 0.1)
				(type default)
			)
			(layer "B.Fab")
		)
		(fp_line
			(start -0.12065 -0.2794)
			(end -0.12065 -0.3048)
			(stroke
				(width 0.1)
				(type default)
			)
			(layer "B.Fab")
		)
		(fp_line
			(start 0.12065 0.2794)
			(end 0.12065 0.3048)
			(stroke
				(width 0.1)
				(type default)
			)
			(layer "B.Fab")
		)
		(fp_line
			(start -0.120396 0.2794)
			(end 0.12065 0.2794)
			(stroke
				(width 0.1)
				(type default)
			)
			(layer "B.Fab")
		)
		(fp_line
			(start 0.67945 0.3048)
			(end 0.67945 -0.305054)
			(stroke
				(width 0.1)
				(type default)
			)
			(layer "B.Fab")
		)
		(fp_line
			(start 0.12065 0.3048)
			(end 0.67945 0.3048)
			(stroke
				(width 0.1)
				(type default)
			)
			(layer "B.Fab")
		)
		(fp_line
			(start -0.120396 0.3048)
			(end -0.120396 0.2794)
			(stroke
				(width 0.1)
				(type default)
			)
			(layer "B.Fab")
		)
		(fp_line
			(start -0.67945 0.3048)
			(end -0.120396 0.3048)
			(stroke
				(width 0.1)
				(type default)
			)
			(layer "B.Fab")
		)
		(pad "1" smd circle
			(at 0.40005 0 270)
			(size 0 0)
			(layers "B.Cu" "B.Mask" "B.Paste")
			(net "PVDD11_S3_P0")
		)
		(pad "2" smd circle
			(at -0.40005 0 270)
			(size 0 0)
			(layers "B.Cu" "B.Mask" "B.Paste")
			(net "GND")
		)
	)
	(footprint ""
		(layer "B.Cu")
		(at 53.518562 -388.011162 -90)
		(property "Reference" "C189"
			(at 0 0 90)
			(layer "B.SilkS")
			(hide yes)
			(effects
				(font
					(size 1.27 1.27)
				)
				(justify mirror)
			)
		)
		(property "Value" ""
			(at 0 0 90)
			(layer "B.Fab")
			(effects
				(font
					(size 1.27 1.27)
				)
				(justify mirror)
			)
		)
		(duplicate_pad_numbers_are_jumpers no)
		(fp_line
			(start -0.299974 0.150114)
			(end 0.299974 0.150114)
			(stroke
				(width 0.1)
				(type default)
			)
			(layer "B.Fab")
		)
		(fp_line
			(start 0.299974 0.150114)
			(end 0.299974 -0.150114)
			(stroke
				(width 0.1)
				(type default)
			)
			(layer "B.Fab")
		)
		(fp_line
			(start -0.299974 -0.150114)
			(end -0.299974 0.150114)
			(stroke
				(width 0.1)
				(type default)
			)
			(layer "B.Fab")
		)
		(fp_line
			(start 0.299974 -0.150114)
			(end -0.299974 -0.150114)
			(stroke
				(width 0.1)
				(type default)
			)
			(layer "B.Fab")
		)
		(pad "1" smd rect
			(at 0.2667 0 90)
			(size 0.3048 0.381)
			(layers "B.Cu" "B.Mask" "B.Paste")
			(net "P0V9_CPU1_RT_2D")
		)
		(pad "2" smd rect
			(at -0.2667 0 90)
			(size 0.3048 0.381)
			(layers "B.Cu" "B.Mask" "B.Paste")
			(net "GND")
		)
	)
	(footprint ""
		(layer "B.Cu")
		(at 187.890404 -428.965106)
		(property "Reference" "C8016"
			(at 0 0 0)
			(layer "B.SilkS")
			(hide yes)
			(effects
				(font
					(size 1.27 1.27)
				)
				(justify mirror)
			)
		)
		(property "Value" ""
			(at 0 0 0)
			(layer "B.Fab")
			(effects
				(font
					(size 1.27 1.27)
				)
				(justify mirror)
			)
		)
		(duplicate_pad_numbers_are_jumpers no)
		(fp_line
			(start -0.7874 -0.4064)
			(end -0.7874 0.4064)
			(stroke
				(width 0.1524)
				(type default)
			)
			(layer "B.SilkS")
		)
		(fp_line
			(start -0.7874 0.4064)
			(end 0.7874 0.4064)
			(stroke
				(width 0.1524)
				(type default)
			)
			(layer "B.SilkS")
		)
		(fp_line
			(start 0.7874 -0.4064)
			(end -0.7874 -0.4064)
			(stroke
				(width 0.1524)
				(type default)
			)
			(layer "B.SilkS")
		)
		(fp_line
			(start 0.7874 0.4064)
			(end 0.7874 -0.4064)
			(stroke
				(width 0.1524)
				(type default)
			)
			(layer "B.SilkS")
		)
		(fp_line
			(start -0.67945 -0.3048)
			(end -0.67945 0.3048)
			(stroke
				(width 0.1)
				(type default)
			)
			(layer "B.Fab")
		)
		(fp_line
			(start -0.67945 0.3048)
			(end -0.120396 0.3048)
			(stroke
				(width 0.1)
				(type default)
			)
			(layer "B.Fab")
		)
		(fp_line
			(start -0.12065 -0.3048)
			(end -0.67945 -0.3048)
			(stroke
				(width 0.1)
				(type default)
			)
			(layer "B.Fab")
		)
		(fp_line
			(start -0.12065 -0.2794)
			(end -0.12065 -0.3048)
			(stroke
				(width 0.1)
				(type default)
			)
			(layer "B.Fab")
		)
		(fp_line
			(start -0.120396 0.2794)
			(end 0.12065 0.2794)
			(stroke
				(width 0.1)
				(type default)
			)
			(layer "B.Fab")
		)
		(fp_line
			(start -0.120396 0.3048)
			(end -0.120396 0.2794)
			(stroke
				(width 0.1)
				(type default)
			)
			(layer "B.Fab")
		)
		(fp_line
			(start 0.12065 -0.305054)
			(end 0.12065 -0.2794)
			(stroke
				(width 0.1)
				(type default)
			)
			(layer "B.Fab")
		)
		(fp_line
			(start 0.12065 -0.2794)
			(end -0.12065 -0.2794)
			(stroke
				(width 0.1)
				(type default)
			)
			(layer "B.Fab")
		)
		(fp_line
			(start 0.12065 0.2794)
			(end 0.12065 0.3048)
			(stroke
				(width 0.1)
				(type default)
			)
			(layer "B.Fab")
		)
		(fp_line
			(start 0.12065 0.3048)
			(end 0.67945 0.3048)
			(stroke
				(width 0.1)
				(type default)
			)
			(layer "B.Fab")
		)
		(fp_line
			(start 0.67945 -0.305054)
			(end 0.12065 -0.305054)
			(stroke
				(width 0.1)
				(type default)
			)
			(layer "B.Fab")
		)
		(fp_line
			(start 0.67945 0.3048)
			(end 0.67945 -0.305054)
			(stroke
				(width 0.1)
				(type default)
			)
			(layer "B.Fab")
		)
		(pad "1" smd circle
			(at 0.40005 0 180)
			(size 0 0)
			(layers "B.Cu" "B.Mask" "B.Paste")
			(net "P12V_AUX")
		)
		(pad "2" smd circle
			(at -0.40005 0 180)
			(size 0 0)
			(layers "B.Cu" "B.Mask" "B.Paste")
			(net "GND")
		)
	)
	(footprint ""
		(layer "B.Cu")
		(at 338.308696 -335.041494 90)
		(property "Reference" "PC91_1"
			(at 0 0 90)
			(layer "B.SilkS")
			(hide yes)
			(effects
				(font
					(size 1.27 1.27)
				)
				(justify mirror)
			)
		)
		(property "Value" ""
			(at 0 0 90)
			(layer "B.Fab")
			(effects
				(font
					(size 1.27 1.27)
				)
				(justify mirror)
			)
		)
		(duplicate_pad_numbers_are_jumpers no)
		(fp_line
			(start 1.524 -0.762)
			(end -1.524 -0.762)
			(stroke
				(width 0.1524)
				(type default)
			)
			(layer "B.SilkS")
		)
		(fp_line
			(start -1.524 -0.762)
			(end -1.524 0.762)
			(stroke
				(width 0.1524)
				(type default)
			)
			(layer "B.SilkS")
		)
		(fp_line
			(start 1.524 0.762)
			(end 1.524 -0.762)
			(stroke
				(width 0.1524)
				(type default)
			)
			(layer "B.SilkS")
		)
		(fp_line
			(start -1.524 0.762)
			(end 1.524 0.762)
			(stroke
				(width 0.1524)
				(type default)
			)
			(layer "B.SilkS")
		)
		(fp_line
			(start 1.1049 -0.724916)
			(end 1.1049 0.724916)
			(stroke
				(width 0.1)
				(type default)
			)
			(layer "B.Fab")
		)
		(fp_line
			(start -1.1049 -0.724916)
			(end 1.1049 -0.724916)
			(stroke
				(width 0.1)
				(type default)
			)
			(layer "B.Fab")
		)
		(fp_line
			(start 1.1049 0.724916)
			(end -1.1049 0.724916)
			(stroke
				(width 0.1)
				(type default)
			)
			(layer "B.Fab")
		)
		(fp_line
			(start -1.1049 0.724916)
			(end -1.1049 -0.724916)
			(stroke
				(width 0.1)
				(type default)
			)
			(layer "B.Fab")
		)
		(pad "1" smd rect
			(at 0.889 0 90)
			(size 1.016 1.27)
			(layers "B.Cu" "B.Mask" "B.Paste")
			(net "SW_P12V_AUX_PVDDCR_CPU1_P0_FLT")
		)
		(pad "2" smd rect
			(at -0.889 0 90)
			(size 1.016 1.27)
			(layers "B.Cu" "B.Mask" "B.Paste")
			(net "GND")
		)
	)
	(footprint ""
		(layer "B.Cu")
		(at 419.946328 -396.393162 -90)
		(property "Reference" "C984"
			(at 0 0 90)
			(layer "B.SilkS")
			(hide yes)
			(effects
				(font
					(size 1.27 1.27)
				)
				(justify mirror)
			)
		)
		(property "Value" ""
			(at 0 0 90)
			(layer "B.Fab")
			(effects
				(font
					(size 1.27 1.27)
				)
				(justify mirror)
			)
		)
		(duplicate_pad_numbers_are_jumpers no)
		(fp_line
			(start -0.299974 0.150114)
			(end 0.299974 0.150114)
			(stroke
				(width 0.1)
				(type default)
			)
			(layer "B.Fab")
		)
		(fp_line
			(start 0.299974 0.150114)
			(end 0.299974 -0.150114)
			(stroke
				(width 0.1)
				(type default)
			)
			(layer "B.Fab")
		)
		(fp_line
			(start -0.299974 -0.150114)
			(end -0.299974 0.150114)
			(stroke
				(width 0.1)
				(type default)
			)
			(layer "B.Fab")
		)
		(fp_line
			(start 0.299974 -0.150114)
			(end -0.299974 -0.150114)
			(stroke
				(width 0.1)
				(type default)
			)
			(layer "B.Fab")
		)
		(pad "1" smd rect
			(at 0.2667 0 90)
			(size 0.3048 0.381)
			(layers "B.Cu" "B.Mask" "B.Paste")
			(net "P0V9_CPU0_RT2_2A")
		)
		(pad "2" smd rect
			(at -0.2667 0 90)
			(size 0.3048 0.381)
			(layers "B.Cu" "B.Mask" "B.Paste")
			(net "GND")
		)
	)
	(footprint ""
		(layer "B.Cu")
		(at 376.6566 -191.24676 90)
		(property "Reference" "PC564_3"
			(at 0 0 90)
			(layer "B.SilkS")
			(hide yes)
			(effects
				(font
					(size 1.27 1.27)
				)
				(justify mirror)
			)
		)
		(property "Value" ""
			(at 0 0 90)
			(layer "B.Fab")
			(effects
				(font
					(size 1.27 1.27)
				)
				(justify mirror)
			)
		)
		(duplicate_pad_numbers_are_jumpers no)
		(fp_line
			(start 1.524 -0.762)
			(end -1.524 -0.762)
			(stroke
				(width 0.1524)
				(type default)
			)
			(layer "B.SilkS")
		)
		(fp_line
			(start -1.524 -0.762)
			(end -1.524 0.762)
			(stroke
				(width 0.1524)
				(type default)
			)
			(layer "B.SilkS")
		)
		(fp_line
			(start 1.524 0.762)
			(end 1.524 -0.762)
			(stroke
				(width 0.1524)
				(type default)
			)
			(layer "B.SilkS")
		)
		(fp_line
			(start -1.524 0.762)
			(end 1.524 0.762)
			(stroke
				(width 0.1524)
				(type default)
			)
			(layer "B.SilkS")
		)
		(fp_line
			(start 1.1049 -0.724916)
			(end 1.1049 0.724916)
			(stroke
				(width 0.1)
				(type default)
			)
			(layer "B.Fab")
		)
		(fp_line
			(start -1.1049 -0.724916)
			(end 1.1049 -0.724916)
			(stroke
				(width 0.1)
				(type default)
			)
			(layer "B.Fab")
		)
		(fp_line
			(start 1.1049 0.724916)
			(end -1.1049 0.724916)
			(stroke
				(width 0.1)
				(type default)
			)
			(layer "B.Fab")
		)
		(fp_line
			(start -1.1049 0.724916)
			(end -1.1049 -0.724916)
			(stroke
				(width 0.1)
				(type default)
			)
			(layer "B.Fab")
		)
		(pad "1" smd rect
			(at 0.889 0 90)
			(size 1.016 1.27)
			(layers "B.Cu" "B.Mask" "B.Paste")
			(net "PVDDCR_CPU0_P0")
		)
		(pad "2" smd rect
			(at -0.889 0 90)
			(size 1.016 1.27)
			(layers "B.Cu" "B.Mask" "B.Paste")
			(net "GND")
		)
	)
	(footprint ""
		(layer "B.Cu")
		(at 336.846926 -416.899344 90)
		(property "Reference" "C6553"
			(at 0 0 90)
			(layer "B.SilkS")
			(hide yes)
			(effects
				(font
					(size 1.27 1.27)
				)
				(justify mirror)
			)
		)
		(property "Value" ""
			(at 0 0 90)
			(layer "B.Fab")
			(effects
				(font
					(size 1.27 1.27)
				)
				(justify mirror)
			)
		)
		(duplicate_pad_numbers_are_jumpers no)
		(fp_line
			(start 0.299974 -0.150114)
			(end -0.299974 -0.150114)
			(stroke
				(width 0.1)
				(type default)
			)
			(layer "B.Fab")
		)
		(fp_line
			(start -0.299974 -0.150114)
			(end -0.299974 0.150114)
			(stroke
				(width 0.1)
				(type default)
			)
			(layer "B.Fab")
		)
		(fp_line
			(start 0.299974 0.150114)
			(end 0.299974 -0.150114)
			(stroke
				(width 0.1)
				(type default)
			)
			(layer "B.Fab")
		)
		(fp_line
			(start -0.299974 0.150114)
			(end 0.299974 0.150114)
			(stroke
				(width 0.1)
				(type default)
			)
			(layer "B.Fab")
		)
		(pad "1" smd rect
			(at 0.2667 0 270)
			(size 0.3048 0.381)
			(layers "B.Cu" "B.Mask" "B.Paste")
			(net "P5E_CPU0_P1_TX_BUF_C_DP<10>")
		)
		(pad "2" smd rect
			(at -0.2667 0 270)
			(size 0.3048 0.381)
			(layers "B.Cu" "B.Mask" "B.Paste")
			(net "P5E_CPU0_P1_TX_BUF_DP<10>")
		)
	)
	(footprint ""
		(layer "B.Cu")
		(at 354.406454 -266.00531)
		(property "Reference" "C3932"
			(at 0 0 0)
			(layer "B.SilkS")
			(hide yes)
			(effects
				(font
					(size 1.27 1.27)
				)
				(justify mirror)
			)
		)
		(property "Value" ""
			(at 0 0 0)
			(layer "B.Fab")
			(effects
				(font
					(size 1.27 1.27)
				)
				(justify mirror)
			)
		)
		(duplicate_pad_numbers_are_jumpers no)
		(fp_line
			(start -0.7874 -0.4064)
			(end -0.7874 0.4064)
			(stroke
				(width 0.1524)
				(type default)
			)
			(layer "B.SilkS")
		)
		(fp_line
			(start -0.7874 0.4064)
			(end 0.7874 0.4064)
			(stroke
				(width 0.1524)
				(type default)
			)
			(layer "B.SilkS")
		)
		(fp_line
			(start 0.7874 -0.4064)
			(end -0.7874 -0.4064)
			(stroke
				(width 0.1524)
				(type default)
			)
			(layer "B.SilkS")
		)
		(fp_line
			(start 0.7874 0.4064)
			(end 0.7874 -0.4064)
			(stroke
				(width 0.1524)
				(type default)
			)
			(layer "B.SilkS")
		)
		(fp_line
			(start -0.67945 -0.3048)
			(end -0.67945 0.3048)
			(stroke
				(width 0.1)
				(type default)
			)
			(layer "B.Fab")
		)
		(fp_line
			(start -0.67945 0.3048)
			(end -0.120396 0.3048)
			(stroke
				(width 0.1)
				(type default)
			)
			(layer "B.Fab")
		)
		(fp_line
			(start -0.12065 -0.3048)
			(end -0.67945 -0.3048)
			(stroke
				(width 0.1)
				(type default)
			)
			(layer "B.Fab")
		)
		(fp_line
			(start -0.12065 -0.2794)
			(end -0.12065 -0.3048)
			(stroke
				(width 0.1)
				(type default)
			)
			(layer "B.Fab")
		)
		(fp_line
			(start -0.120396 0.2794)
			(end 0.12065 0.2794)
			(stroke
				(width 0.1)
				(type default)
			)
			(layer "B.Fab")
		)
		(fp_line
			(start -0.120396 0.3048)
			(end -0.120396 0.2794)
			(stroke
				(width 0.1)
				(type default)
			)
			(layer "B.Fab")
		)
		(fp_line
			(start 0.12065 -0.305054)
			(end 0.12065 -0.2794)
			(stroke
				(width 0.1)
				(type default)
			)
			(layer "B.Fab")
		)
		(fp_line
			(start 0.12065 -0.2794)
			(end -0.12065 -0.2794)
			(stroke
				(width 0.1)
				(type default)
			)
			(layer "B.Fab")
		)
		(fp_line
			(start 0.12065 0.2794)
			(end 0.12065 0.3048)
			(stroke
				(width 0.1)
				(type default)
			)
			(layer "B.Fab")
		)
		(fp_line
			(start 0.12065 0.3048)
			(end 0.67945 0.3048)
			(stroke
				(width 0.1)
				(type default)
			)
			(layer "B.Fab")
		)
		(fp_line
			(start 0.67945 -0.305054)
			(end 0.12065 -0.305054)
			(stroke
				(width 0.1)
				(type default)
			)
			(layer "B.Fab")
		)
		(fp_line
			(start 0.67945 0.3048)
			(end 0.67945 -0.305054)
			(stroke
				(width 0.1)
				(type default)
			)
			(layer "B.Fab")
		)
		(pad "1" smd circle
			(at 0.40005 0 180)
			(size 0 0)
			(layers "B.Cu" "B.Mask" "B.Paste")
			(net "PVDD11_S3_P0")
		)
		(pad "2" smd circle
			(at -0.40005 0 180)
			(size 0 0)
			(layers "B.Cu" "B.Mask" "B.Paste")
			(net "GND")
		)
	)
	(footprint ""
		(layer "B.Cu")
		(at 239.724692 -422.849548 -90)
		(property "Reference" "R2905"
			(at 0 0 90)
			(layer "B.SilkS")
			(hide yes)
			(effects
				(font
					(size 1.27 1.27)
				)
				(justify mirror)
			)
		)
		(property "Value" ""
			(at 0 0 90)
			(layer "B.Fab")
			(effects
				(font
					(size 1.27 1.27)
				)
				(justify mirror)
			)
		)
		(duplicate_pad_numbers_are_jumpers no)
		(fp_line
			(start -0.7874 0.4064)
			(end 0.7874 0.4064)
			(stroke
				(width 0.1524)
				(type default)
			)
			(layer "B.SilkS")
		)
		(fp_line
			(start 0.7874 0.4064)
			(end 0.7874 -0.4064)
			(stroke
				(width 0.1524)
				(type default)
			)
			(layer "B.SilkS")
		)
		(fp_line
			(start -0.7874 -0.4064)
			(end -0.7874 0.4064)
			(stroke
				(width 0.1524)
				(type default)
			)
			(layer "B.SilkS")
		)
		(fp_line
			(start 0.7874 -0.4064)
			(end -0.7874 -0.4064)
			(stroke
				(width 0.1524)
				(type default)
			)
			(layer "B.SilkS")
		)
		(fp_line
			(start -0.67945 0.3048)
			(end -0.120396 0.3048)
			(stroke
				(width 0.1)
				(type default)
			)
			(layer "B.Fab")
		)
		(fp_line
			(start -0.120396 0.3048)
			(end -0.120396 0.2794)
			(stroke
				(width 0.1)
				(type default)
			)
			(layer "B.Fab")
		)
		(fp_line
			(start 0.12065 0.3048)
			(end 0.67945 0.3048)
			(stroke
				(width 0.1)
				(type default)
			)
			(layer "B.Fab")
		)
		(fp_line
			(start 0.67945 0.3048)
			(end 0.67945 -0.305054)
			(stroke
				(width 0.1)
				(type default)
			)
			(layer "B.Fab")
		)
		(fp_line
			(start -0.120396 0.2794)
			(end 0.12065 0.2794)
			(stroke
				(width 0.1)
				(type default)
			)
			(layer "B.Fab")
		)
		(fp_line
			(start 0.12065 0.2794)
			(end 0.12065 0.3048)
			(stroke
				(width 0.1)
				(type default)
			)
			(layer "B.Fab")
		)
		(fp_line
			(start -0.12065 -0.2794)
			(end -0.12065 -0.3048)
			(stroke
				(width 0.1)
				(type default)
			)
			(layer "B.Fab")
		)
		(fp_line
			(start 0.12065 -0.2794)
			(end -0.12065 -0.2794)
			(stroke
				(width 0.1)
				(type default)
			)
			(layer "B.Fab")
		)
		(fp_line
			(start -0.67945 -0.3048)
			(end -0.67945 0.3048)
			(stroke
				(width 0.1)
				(type default)
			)
			(layer "B.Fab")
		)
		(fp_line
			(start -0.12065 -0.3048)
			(end -0.67945 -0.3048)
			(stroke
				(width 0.1)
				(type default)
			)
			(layer "B.Fab")
		)
		(fp_line
			(start 0.12065 -0.305054)
			(end 0.12065 -0.2794)
			(stroke
				(width 0.1)
				(type default)
			)
			(layer "B.Fab")
		)
		(fp_line
			(start 0.67945 -0.305054)
			(end 0.12065 -0.305054)
			(stroke
				(width 0.1)
				(type default)
			)
			(layer "B.Fab")
		)
		(pad "1" smd circle
			(at 0.40005 0 90)
			(size 0 0)
			(layers "B.Cu" "B.Mask" "B.Paste")
			(net "RST_SMB_SWITCH_N")
		)
		(pad "2" smd circle
			(at -0.40005 0 90)
			(size 0 0)
			(layers "B.Cu" "B.Mask" "B.Paste")
			(net "RST_SMB_SWITCH_R_N")
		)
	)
	(footprint ""
		(layer "B.Cu")
		(at 83.910424 -408.517344 90)
		(property "Reference" "C6683"
			(at 0 0 90)
			(layer "B.SilkS")
			(hide yes)
			(effects
				(font
					(size 1.27 1.27)
				)
				(justify mirror)
			)
		)
		(property "Value" ""
			(at 0 0 90)
			(layer "B.Fab")
			(effects
				(font
					(size 1.27 1.27)
				)
				(justify mirror)
			)
		)
		(duplicate_pad_numbers_are_jumpers no)
		(fp_line
			(start 0.299974 -0.150114)
			(end -0.299974 -0.150114)
			(stroke
				(width 0.1)
				(type default)
			)
			(layer "B.Fab")
		)
		(fp_line
			(start -0.299974 -0.150114)
			(end -0.299974 0.150114)
			(stroke
				(width 0.1)
				(type default)
			)
			(layer "B.Fab")
		)
		(fp_line
			(start 0.299974 0.150114)
			(end 0.299974 -0.150114)
			(stroke
				(width 0.1)
				(type default)
			)
			(layer "B.Fab")
		)
		(fp_line
			(start -0.299974 0.150114)
			(end 0.299974 0.150114)
			(stroke
				(width 0.1)
				(type default)
			)
			(layer "B.Fab")
		)
		(pad "1" smd rect
			(at 0.2667 0 270)
			(size 0.3048 0.381)
			(layers "B.Cu" "B.Mask" "B.Paste")
			(net "P5E_CPU1_P1_TX_BUF_C_DP<11>")
		)
		(pad "2" smd rect
			(at -0.2667 0 270)
			(size 0.3048 0.381)
			(layers "B.Cu" "B.Mask" "B.Paste")
			(net "P5E_CPU1_P1_TX_BUF_DP<11>")
		)
	)
	(footprint ""
		(layer "B.Cu")
		(at 167.132 -116.296948 180)
		(property "Reference" "R888"
			(at 0 0 0)
			(layer "B.SilkS")
			(hide yes)
			(effects
				(font
					(size 1.27 1.27)
				)
				(justify mirror)
			)
		)
		(property "Value" ""
			(at 0 0 0)
			(layer "B.Fab")
			(effects
				(font
					(size 1.27 1.27)
				)
				(justify mirror)
			)
		)
		(duplicate_pad_numbers_are_jumpers no)
		(fp_line
			(start 0.7874 0.4064)
			(end 0.7874 -0.4064)
			(stroke
				(width 0.1524)
				(type default)
			)
			(layer "B.SilkS")
		)
		(fp_line
			(start 0.7874 -0.4064)
			(end -0.7874 -0.4064)
			(stroke
				(width 0.1524)
				(type default)
			)
			(layer "B.SilkS")
		)
		(fp_line
			(start -0.7874 0.4064)
			(end 0.7874 0.4064)
			(stroke
				(width 0.1524)
				(type default)
			)
			(layer "B.SilkS")
		)
		(fp_line
			(start -0.7874 -0.4064)
			(end -0.7874 0.4064)
			(stroke
				(width 0.1524)
				(type default)
			)
			(layer "B.SilkS")
		)
		(fp_line
			(start 0.67945 0.3048)
			(end 0.67945 -0.305054)
			(stroke
				(width 0.1)
				(type default)
			)
			(layer "B.Fab")
		)
		(fp_line
			(start 0.67945 -0.305054)
			(end 0.12065 -0.305054)
			(stroke
				(width 0.1)
				(type default)
			)
			(layer "B.Fab")
		)
		(fp_line
			(start 0.12065 0.3048)
			(end 0.67945 0.3048)
			(stroke
				(width 0.1)
				(type default)
			)
			(layer "B.Fab")
		)
		(fp_line
			(start 0.12065 0.2794)
			(end 0.12065 0.3048)
			(stroke
				(width 0.1)
				(type default)
			)
			(layer "B.Fab")
		)
		(fp_line
			(start 0.12065 -0.2794)
			(end -0.12065 -0.2794)
			(stroke
				(width 0.1)
				(type default)
			)
			(layer "B.Fab")
		)
		(fp_line
			(start 0.12065 -0.305054)
			(end 0.12065 -0.2794)
			(stroke
				(width 0.1)
				(type default)
			)
			(layer "B.Fab")
		)
		(fp_line
			(start -0.120396 0.3048)
			(end -0.120396 0.2794)
			(stroke
				(width 0.1)
				(type default)
			)
			(layer "B.Fab")
		)
		(fp_line
			(start -0.120396 0.2794)
			(end 0.12065 0.2794)
			(stroke
				(width 0.1)
				(type default)
			)
			(layer "B.Fab")
		)
		(fp_line
			(start -0.12065 -0.2794)
			(end -0.12065 -0.3048)
			(stroke
				(width 0.1)
				(type default)
			)
			(layer "B.Fab")
		)
		(fp_line
			(start -0.12065 -0.3048)
			(end -0.67945 -0.3048)
			(stroke
				(width 0.1)
				(type default)
			)
			(layer "B.Fab")
		)
		(fp_line
			(start -0.67945 0.3048)
			(end -0.120396 0.3048)
			(stroke
				(width 0.1)
				(type default)
			)
			(layer "B.Fab")
		)
		(fp_line
			(start -0.67945 -0.3048)
			(end -0.67945 0.3048)
			(stroke
				(width 0.1)
				(type default)
			)
			(layer "B.Fab")
		)
		(pad "1" smd circle
			(at 0.40005 0)
			(size 0 0)
			(layers "B.Cu" "B.Mask" "B.Paste")
			(net "P3V3_AUX")
		)
		(pad "2" smd circle
			(at -0.40005 0)
			(size 0 0)
			(layers "B.Cu" "B.Mask" "B.Paste")
			(net "SCM_SPARE_0")
		)
	)
	(footprint ""
		(layer "B.Cu")
		(at 214.122 -338.582)
		(property "Reference" "R914"
			(at 0 0 0)
			(layer "B.SilkS")
			(hide yes)
			(effects
				(font
					(size 1.27 1.27)
				)
				(justify mirror)
			)
		)
		(property "Value" ""
			(at 0 0 0)
			(layer "B.Fab")
			(effects
				(font
					(size 1.27 1.27)
				)
				(justify mirror)
			)
		)
		(duplicate_pad_numbers_are_jumpers no)
		(fp_line
			(start -0.32512 -0.175006)
			(end -0.32512 0.175006)
			(stroke
				(width 0.1)
				(type default)
			)
			(layer "B.Fab")
		)
		(fp_line
			(start -0.32512 0.175006)
			(end 0.32512 0.175006)
			(stroke
				(width 0.1)
				(type default)
			)
			(layer "B.Fab")
		)
		(fp_line
			(start 0.32512 -0.175006)
			(end -0.32512 -0.175006)
			(stroke
				(width 0.1)
				(type default)
			)
			(layer "B.Fab")
		)
		(fp_line
			(start 0.32512 0.175006)
			(end 0.32512 -0.175006)
			(stroke
				(width 0.1)
				(type default)
			)
			(layer "B.Fab")
		)
		(pad "1" smd rect
			(at 0.2667 0 180)
			(size 0.3048 0.381)
			(layers "B.Cu" "B.Mask" "B.Paste")
			(net "SMB_RT_CPU1_P3_R_SDA")
		)
		(pad "2" smd rect
			(at -0.2667 0)
			(size 0.3048 0.381)
			(layers "B.Cu" "B.Mask" "B.Paste")
			(net "SMB_RT_CPU1_P3_R2_SDA")
		)
	)
	(footprint ""
		(layer "B.Cu")
		(at 166.473124 -424.821604 -90)
		(property "Reference" "R1212"
			(at 0 0 90)
			(layer "B.SilkS")
			(hide yes)
			(effects
				(font
					(size 1.27 1.27)
				)
				(justify mirror)
			)
		)
		(property "Value" ""
			(at 0 0 90)
			(layer "B.Fab")
			(effects
				(font
					(size 1.27 1.27)
				)
				(justify mirror)
			)
		)
		(duplicate_pad_numbers_are_jumpers no)
		(fp_line
			(start -0.32512 0.175006)
			(end 0.32512 0.175006)
			(stroke
				(width 0.1)
				(type default)
			)
			(layer "B.Fab")
		)
		(fp_line
			(start 0.32512 0.175006)
			(end 0.32512 -0.175006)
			(stroke
				(width 0.1)
				(type default)
			)
			(layer "B.Fab")
		)
		(fp_line
			(start -0.32512 -0.175006)
			(end -0.32512 0.175006)
			(stroke
				(width 0.1)
				(type default)
			)
			(layer "B.Fab")
		)
		(fp_line
			(start 0.32512 -0.175006)
			(end -0.32512 -0.175006)
			(stroke
				(width 0.1)
				(type default)
			)
			(layer "B.Fab")
		)
		(pad "1" smd rect
			(at 0.2667 0 90)
			(size 0.3048 0.381)
			(layers "B.Cu" "B.Mask" "B.Paste")
			(net "GND")
		)
		(pad "2" smd rect
			(at -0.2667 0 270)
			(size 0.3048 0.381)
			(layers "B.Cu" "B.Mask" "B.Paste")
			(net "RT_ROM_MUX3_OE_N")
		)
	)
	(footprint ""
		(layer "B.Cu")
		(at 167.132 -119.344948 180)
		(property "Reference" "R63"
			(at 0 0 0)
			(layer "B.SilkS")
			(hide yes)
			(effects
				(font
					(size 1.27 1.27)
				)
				(justify mirror)
			)
		)
		(property "Value" ""
			(at 0 0 0)
			(layer "B.Fab")
			(effects
				(font
					(size 1.27 1.27)
				)
				(justify mirror)
			)
		)
		(duplicate_pad_numbers_are_jumpers no)
		(fp_line
			(start 0.7874 0.4064)
			(end 0.7874 -0.4064)
			(stroke
				(width 0.1524)
				(type default)
			)
			(layer "B.SilkS")
		)
		(fp_line
			(start 0.7874 -0.4064)
			(end -0.7874 -0.4064)
			(stroke
				(width 0.1524)
				(type default)
			)
			(layer "B.SilkS")
		)
		(fp_line
			(start -0.7874 0.4064)
			(end 0.7874 0.4064)
			(stroke
				(width 0.1524)
				(type default)
			)
			(layer "B.SilkS")
		)
		(fp_line
			(start -0.7874 -0.4064)
			(end -0.7874 0.4064)
			(stroke
				(width 0.1524)
				(type default)
			)
			(layer "B.SilkS")
		)
		(fp_line
			(start 0.67945 0.3048)
			(end 0.67945 -0.305054)
			(stroke
				(width 0.1)
				(type default)
			)
			(layer "B.Fab")
		)
		(fp_line
			(start 0.67945 -0.305054)
			(end 0.12065 -0.305054)
			(stroke
				(width 0.1)
				(type default)
			)
			(layer "B.Fab")
		)
		(fp_line
			(start 0.12065 0.3048)
			(end 0.67945 0.3048)
			(stroke
				(width 0.1)
				(type default)
			)
			(layer "B.Fab")
		)
		(fp_line
			(start 0.12065 0.2794)
			(end 0.12065 0.3048)
			(stroke
				(width 0.1)
				(type default)
			)
			(layer "B.Fab")
		)
		(fp_line
			(start 0.12065 -0.2794)
			(end -0.12065 -0.2794)
			(stroke
				(width 0.1)
				(type default)
			)
			(layer "B.Fab")
		)
		(fp_line
			(start 0.12065 -0.305054)
			(end 0.12065 -0.2794)
			(stroke
				(width 0.1)
				(type default)
			)
			(layer "B.Fab")
		)
		(fp_line
			(start -0.120396 0.3048)
			(end -0.120396 0.2794)
			(stroke
				(width 0.1)
				(type default)
			)
			(layer "B.Fab")
		)
		(fp_line
			(start -0.120396 0.2794)
			(end 0.12065 0.2794)
			(stroke
				(width 0.1)
				(type default)
			)
			(layer "B.Fab")
		)
		(fp_line
			(start -0.12065 -0.2794)
			(end -0.12065 -0.3048)
			(stroke
				(width 0.1)
				(type default)
			)
			(layer "B.Fab")
		)
		(fp_line
			(start -0.12065 -0.3048)
			(end -0.67945 -0.3048)
			(stroke
				(width 0.1)
				(type default)
			)
			(layer "B.Fab")
		)
		(fp_line
			(start -0.67945 0.3048)
			(end -0.120396 0.3048)
			(stroke
				(width 0.1)
				(type default)
			)
			(layer "B.Fab")
		)
		(fp_line
			(start -0.67945 -0.3048)
			(end -0.67945 0.3048)
			(stroke
				(width 0.1)
				(type default)
			)
			(layer "B.Fab")
		)
		(pad "1" smd circle
			(at 0.40005 0)
			(size 0 0)
			(layers "B.Cu" "B.Mask" "B.Paste")
			(net "SCM_SYS_PWROK_R")
		)
		(pad "2" smd circle
			(at -0.40005 0)
			(size 0 0)
			(layers "B.Cu" "B.Mask" "B.Paste")
			(net "SCM_SYS_PWROK")
		)
	)
	(footprint ""
		(layer "B.Cu")
		(at 241.140488 -331.597 180)
		(property "Reference" "R843"
			(at 0 0 0)
			(layer "B.SilkS")
			(hide yes)
			(effects
				(font
					(size 1.27 1.27)
				)
				(justify mirror)
			)
		)
		(property "Value" ""
			(at 0 0 0)
			(layer "B.Fab")
			(effects
				(font
					(size 1.27 1.27)
				)
				(justify mirror)
			)
		)
		(duplicate_pad_numbers_are_jumpers no)
		(fp_line
			(start 0.32512 0.175006)
			(end 0.32512 -0.175006)
			(stroke
				(width 0.1)
				(type default)
			)
			(layer "B.Fab")
		)
		(fp_line
			(start 0.32512 -0.175006)
			(end -0.32512 -0.175006)
			(stroke
				(width 0.1)
				(type default)
			)
			(layer "B.Fab")
		)
		(fp_line
			(start -0.32512 0.175006)
			(end 0.32512 0.175006)
			(stroke
				(width 0.1)
				(type default)
			)
			(layer "B.Fab")
		)
		(fp_line
			(start -0.32512 -0.175006)
			(end -0.32512 0.175006)
			(stroke
				(width 0.1)
				(type default)
			)
			(layer "B.Fab")
		)
		(pad "1" smd rect
			(at 0.2667 0)
			(size 0.3048 0.381)
			(layers "B.Cu" "B.Mask" "B.Paste")
			(net "P1V8_AUX")
		)
		(pad "2" smd rect
			(at -0.2667 0 180)
			(size 0.3048 0.381)
			(layers "B.Cu" "B.Mask" "B.Paste")
			(net "RT_ROM_SMB_MUX_ADDR1")
		)
	)
	(footprint ""
		(layer "B.Cu")
		(at 428.087282 -438.192672 90)
		(property "Reference" "R4169"
			(at 0 0 90)
			(layer "B.SilkS")
			(hide yes)
			(effects
				(font
					(size 1.27 1.27)
				)
				(justify mirror)
			)
		)
		(property "Value" ""
			(at 0 0 90)
			(layer "B.Fab")
			(effects
				(font
					(size 1.27 1.27)
				)
				(justify mirror)
			)
		)
		(duplicate_pad_numbers_are_jumpers no)
		(fp_line
			(start 0.7874 -0.4064)
			(end -0.7874 -0.4064)
			(stroke
				(width 0.1524)
				(type default)
			)
			(layer "B.SilkS")
		)
		(fp_line
			(start -0.7874 -0.4064)
			(end -0.7874 0.4064)
			(stroke
				(width 0.1524)
				(type default)
			)
			(layer "B.SilkS")
		)
		(fp_line
			(start 0.7874 0.4064)
			(end 0.7874 -0.4064)
			(stroke
				(width 0.1524)
				(type default)
			)
			(layer "B.SilkS")
		)
		(fp_line
			(start -0.7874 0.4064)
			(end 0.7874 0.4064)
			(stroke
				(width 0.1524)
				(type default)
			)
			(layer "B.SilkS")
		)
		(fp_line
			(start 0.67945 -0.305054)
			(end 0.12065 -0.305054)
			(stroke
				(width 0.1)
				(type default)
			)
			(layer "B.Fab")
		)
		(fp_line
			(start 0.12065 -0.305054)
			(end 0.12065 -0.2794)
			(stroke
				(width 0.1)
				(type default)
			)
			(layer "B.Fab")
		)
		(fp_line
			(start -0.12065 -0.3048)
			(end -0.67945 -0.3048)
			(stroke
				(width 0.1)
				(type default)
			)
			(layer "B.Fab")
		)
		(fp_line
			(start -0.67945 -0.3048)
			(end -0.67945 0.3048)
			(stroke
				(width 0.1)
				(type default)
			)
			(layer "B.Fab")
		)
		(fp_line
			(start 0.12065 -0.2794)
			(end -0.12065 -0.2794)
			(stroke
				(width 0.1)
				(type default)
			)
			(layer "B.Fab")
		)
		(fp_line
			(start -0.12065 -0.2794)
			(end -0.12065 -0.3048)
			(stroke
				(width 0.1)
				(type default)
			)
			(layer "B.Fab")
		)
		(fp_line
			(start 0.12065 0.2794)
			(end 0.12065 0.3048)
			(stroke
				(width 0.1)
				(type default)
			)
			(layer "B.Fab")
		)
		(fp_line
			(start -0.120396 0.2794)
			(end 0.12065 0.2794)
			(stroke
				(width 0.1)
				(type default)
			)
			(layer "B.Fab")
		)
		(fp_line
			(start 0.67945 0.3048)
			(end 0.67945 -0.305054)
			(stroke
				(width 0.1)
				(type default)
			)
			(layer "B.Fab")
		)
		(fp_line
			(start 0.12065 0.3048)
			(end 0.67945 0.3048)
			(stroke
				(width 0.1)
				(type default)
			)
			(layer "B.Fab")
		)
		(fp_line
			(start -0.120396 0.3048)
			(end -0.120396 0.2794)
			(stroke
				(width 0.1)
				(type default)
			)
			(layer "B.Fab")
		)
		(fp_line
			(start -0.67945 0.3048)
			(end -0.120396 0.3048)
			(stroke
				(width 0.1)
				(type default)
			)
			(layer "B.Fab")
		)
		(pad "1" smd circle
			(at 0.40005 0 270)
			(size 0 0)
			(layers "B.Cu" "B.Mask" "B.Paste")
			(net "P3V3_AUX")
		)
		(pad "2" smd circle
			(at -0.40005 0 270)
			(size 0 0)
			(layers "B.Cu" "B.Mask" "B.Paste")
			(net "GPU_3V3IO_RSVD3_ISO")
		)
	)
	(footprint ""
		(layer "B.Cu")
		(at 109.895386 -253.432564)
		(property "Reference" "C2466"
			(at 0 0 0)
			(layer "B.SilkS")
			(hide yes)
			(effects
				(font
					(size 1.27 1.27)
				)
				(justify mirror)
			)
		)
		(property "Value" ""
			(at 0 0 0)
			(layer "B.Fab")
			(effects
				(font
					(size 1.27 1.27)
				)
				(justify mirror)
			)
		)
		(duplicate_pad_numbers_are_jumpers no)
		(fp_line
			(start -0.7874 -0.4064)
			(end -0.7874 0.4064)
			(stroke
				(width 0.1524)
				(type default)
			)
			(layer "B.SilkS")
		)
		(fp_line
			(start -0.7874 0.4064)
			(end 0.7874 0.4064)
			(stroke
				(width 0.1524)
				(type default)
			)
			(layer "B.SilkS")
		)
		(fp_line
			(start 0.7874 -0.4064)
			(end -0.7874 -0.4064)
			(stroke
				(width 0.1524)
				(type default)
			)
			(layer "B.SilkS")
		)
		(fp_line
			(start 0.7874 0.4064)
			(end 0.7874 -0.4064)
			(stroke
				(width 0.1524)
				(type default)
			)
			(layer "B.SilkS")
		)
		(fp_line
			(start -0.67945 -0.3048)
			(end -0.67945 0.3048)
			(stroke
				(width 0.1)
				(type default)
			)
			(layer "B.Fab")
		)
		(fp_line
			(start -0.67945 0.3048)
			(end -0.120396 0.3048)
			(stroke
				(width 0.1)
				(type default)
			)
			(layer "B.Fab")
		)
		(fp_line
			(start -0.12065 -0.3048)
			(end -0.67945 -0.3048)
			(stroke
				(width 0.1)
				(type default)
			)
			(layer "B.Fab")
		)
		(fp_line
			(start -0.12065 -0.2794)
			(end -0.12065 -0.3048)
			(stroke
				(width 0.1)
				(type default)
			)
			(layer "B.Fab")
		)
		(fp_line
			(start -0.120396 0.2794)
			(end 0.12065 0.2794)
			(stroke
				(width 0.1)
				(type default)
			)
			(layer "B.Fab")
		)
		(fp_line
			(start -0.120396 0.3048)
			(end -0.120396 0.2794)
			(stroke
				(width 0.1)
				(type default)
			)
			(layer "B.Fab")
		)
		(fp_line
			(start 0.12065 -0.305054)
			(end 0.12065 -0.2794)
			(stroke
				(width 0.1)
				(type default)
			)
			(layer "B.Fab")
		)
		(fp_line
			(start 0.12065 -0.2794)
			(end -0.12065 -0.2794)
			(stroke
				(width 0.1)
				(type default)
			)
			(layer "B.Fab")
		)
		(fp_line
			(start 0.12065 0.2794)
			(end 0.12065 0.3048)
			(stroke
				(width 0.1)
				(type default)
			)
			(layer "B.Fab")
		)
		(fp_line
			(start 0.12065 0.3048)
			(end 0.67945 0.3048)
			(stroke
				(width 0.1)
				(type default)
			)
			(layer "B.Fab")
		)
		(fp_line
			(start 0.67945 -0.305054)
			(end 0.12065 -0.305054)
			(stroke
				(width 0.1)
				(type default)
			)
			(layer "B.Fab")
		)
		(fp_line
			(start 0.67945 0.3048)
			(end 0.67945 -0.305054)
			(stroke
				(width 0.1)
				(type default)
			)
			(layer "B.Fab")
		)
		(pad "1" smd circle
			(at 0.40005 0 180)
			(size 0 0)
			(layers "B.Cu" "B.Mask" "B.Paste")
			(net "PVDDCR_SOC_P1")
		)
		(pad "2" smd circle
			(at -0.40005 0 180)
			(size 0 0)
			(layers "B.Cu" "B.Mask" "B.Paste")
			(net "GND")
		)
	)
	(footprint ""
		(layer "B.Cu")
		(at 94.373954 -191.358012 90)
		(property "Reference" "PC282_2"
			(at 0 0 90)
			(layer "B.SilkS")
			(hide yes)
			(effects
				(font
					(size 1.27 1.27)
				)
				(justify mirror)
			)
		)
		(property "Value" ""
			(at 0 0 90)
			(layer "B.Fab")
			(effects
				(font
					(size 1.27 1.27)
				)
				(justify mirror)
			)
		)
		(duplicate_pad_numbers_are_jumpers no)
		(fp_line
			(start 1.524 -0.762)
			(end -1.524 -0.762)
			(stroke
				(width 0.1524)
				(type default)
			)
			(layer "B.SilkS")
		)
		(fp_line
			(start -1.524 -0.762)
			(end -1.524 0.762)
			(stroke
				(width 0.1524)
				(type default)
			)
			(layer "B.SilkS")
		)
		(fp_line
			(start 1.524 0.762)
			(end 1.524 -0.762)
			(stroke
				(width 0.1524)
				(type default)
			)
			(layer "B.SilkS")
		)
		(fp_line
			(start -1.524 0.762)
			(end 1.524 0.762)
			(stroke
				(width 0.1524)
				(type default)
			)
			(layer "B.SilkS")
		)
		(fp_line
			(start 1.1049 -0.724916)
			(end 1.1049 0.724916)
			(stroke
				(width 0.1)
				(type default)
			)
			(layer "B.Fab")
		)
		(fp_line
			(start -1.1049 -0.724916)
			(end 1.1049 -0.724916)
			(stroke
				(width 0.1)
				(type default)
			)
			(layer "B.Fab")
		)
		(fp_line
			(start 1.1049 0.724916)
			(end -1.1049 0.724916)
			(stroke
				(width 0.1)
				(type default)
			)
			(layer "B.Fab")
		)
		(fp_line
			(start -1.1049 0.724916)
			(end -1.1049 -0.724916)
			(stroke
				(width 0.1)
				(type default)
			)
			(layer "B.Fab")
		)
		(pad "1" smd rect
			(at 0.889 0 90)
			(size 1.016 1.27)
			(layers "B.Cu" "B.Mask" "B.Paste")
			(net "PVDDCR_CPU0_P1")
		)
		(pad "2" smd rect
			(at -0.889 0 90)
			(size 1.016 1.27)
			(layers "B.Cu" "B.Mask" "B.Paste")
			(net "GND")
		)
	)
	(footprint ""
		(layer "B.Cu")
		(at 46.487334 -391.340848 -90)
		(property "Reference" "C221"
			(at 0 0 90)
			(layer "B.SilkS")
			(hide yes)
			(effects
				(font
					(size 1.27 1.27)
				)
				(justify mirror)
			)
		)
		(property "Value" ""
			(at 0 0 90)
			(layer "B.Fab")
			(effects
				(font
					(size 1.27 1.27)
				)
				(justify mirror)
			)
		)
		(duplicate_pad_numbers_are_jumpers no)
		(fp_line
			(start -0.7874 0.4064)
			(end 0.7874 0.4064)
			(stroke
				(width 0.1524)
				(type default)
			)
			(layer "B.SilkS")
		)
		(fp_line
			(start 0.7874 0.4064)
			(end 0.7874 -0.4064)
			(stroke
				(width 0.1524)
				(type default)
			)
			(layer "B.SilkS")
		)
		(fp_line
			(start -0.7874 -0.4064)
			(end -0.7874 0.4064)
			(stroke
				(width 0.1524)
				(type default)
			)
			(layer "B.SilkS")
		)
		(fp_line
			(start 0.7874 -0.4064)
			(end -0.7874 -0.4064)
			(stroke
				(width 0.1524)
				(type default)
			)
			(layer "B.SilkS")
		)
		(fp_line
			(start -0.67945 0.3048)
			(end -0.120396 0.3048)
			(stroke
				(width 0.1)
				(type default)
			)
			(layer "B.Fab")
		)
		(fp_line
			(start -0.120396 0.3048)
			(end -0.120396 0.2794)
			(stroke
				(width 0.1)
				(type default)
			)
			(layer "B.Fab")
		)
		(fp_line
			(start 0.12065 0.3048)
			(end 0.67945 0.3048)
			(stroke
				(width 0.1)
				(type default)
			)
			(layer "B.Fab")
		)
		(fp_line
			(start 0.67945 0.3048)
			(end 0.67945 -0.305054)
			(stroke
				(width 0.1)
				(type default)
			)
			(layer "B.Fab")
		)
		(fp_line
			(start -0.120396 0.2794)
			(end 0.12065 0.2794)
			(stroke
				(width 0.1)
				(type default)
			)
			(layer "B.Fab")
		)
		(fp_line
			(start 0.12065 0.2794)
			(end 0.12065 0.3048)
			(stroke
				(width 0.1)
				(type default)
			)
			(layer "B.Fab")
		)
		(fp_line
			(start -0.12065 -0.2794)
			(end -0.12065 -0.3048)
			(stroke
				(width 0.1)
				(type default)
			)
			(layer "B.Fab")
		)
		(fp_line
			(start 0.12065 -0.2794)
			(end -0.12065 -0.2794)
			(stroke
				(width 0.1)
				(type default)
			)
			(layer "B.Fab")
		)
		(fp_line
			(start -0.67945 -0.3048)
			(end -0.67945 0.3048)
			(stroke
				(width 0.1)
				(type default)
			)
			(layer "B.Fab")
		)
		(fp_line
			(start -0.12065 -0.3048)
			(end -0.67945 -0.3048)
			(stroke
				(width 0.1)
				(type default)
			)
			(layer "B.Fab")
		)
		(fp_line
			(start 0.12065 -0.305054)
			(end 0.12065 -0.2794)
			(stroke
				(width 0.1)
				(type default)
			)
			(layer "B.Fab")
		)
		(fp_line
			(start 0.67945 -0.305054)
			(end 0.12065 -0.305054)
			(stroke
				(width 0.1)
				(type default)
			)
			(layer "B.Fab")
		)
		(pad "1" smd circle
			(at 0.40005 0 90)
			(size 0 0)
			(layers "B.Cu" "B.Mask" "B.Paste")
			(net "P0V9_CPU1_RT0_2A")
		)
		(pad "2" smd circle
			(at -0.40005 0 90)
			(size 0 0)
			(layers "B.Cu" "B.Mask" "B.Paste")
			(net "GND")
		)
	)
	(footprint ""
		(layer "B.Cu")
		(at 233.807 -335.026 180)
		(property "Reference" "R1068"
			(at 0 0 0)
			(layer "B.SilkS")
			(hide yes)
			(effects
				(font
					(size 1.27 1.27)
				)
				(justify mirror)
			)
		)
		(property "Value" ""
			(at 0 0 0)
			(layer "B.Fab")
			(effects
				(font
					(size 1.27 1.27)
				)
				(justify mirror)
			)
		)
		(duplicate_pad_numbers_are_jumpers no)
		(fp_line
			(start 0.32512 0.175006)
			(end 0.32512 -0.175006)
			(stroke
				(width 0.1)
				(type default)
			)
			(layer "B.Fab")
		)
		(fp_line
			(start 0.32512 -0.175006)
			(end -0.32512 -0.175006)
			(stroke
				(width 0.1)
				(type default)
			)
			(layer "B.Fab")
		)
		(fp_line
			(start -0.32512 0.175006)
			(end 0.32512 0.175006)
			(stroke
				(width 0.1)
				(type default)
			)
			(layer "B.Fab")
		)
		(fp_line
			(start -0.32512 -0.175006)
			(end -0.32512 0.175006)
			(stroke
				(width 0.1)
				(type default)
			)
			(layer "B.Fab")
		)
		(pad "1" smd rect
			(at 0.2667 0)
			(size 0.3048 0.381)
			(layers "B.Cu" "B.Mask" "B.Paste")
			(net "SMB_RT_CPU0_P2_R_SDA")
		)
		(pad "2" smd rect
			(at -0.2667 0 180)
			(size 0.3048 0.381)
			(layers "B.Cu" "B.Mask" "B.Paste")
			(net "SMB_RT_CPU0_P2_R2_SDA")
		)
	)
	(footprint ""
		(layer "B.Cu")
		(at 208.461356 -388.692136)
		(property "Reference" "PR2519"
			(at 0 0 0)
			(layer "B.SilkS")
			(hide yes)
			(effects
				(font
					(size 1.27 1.27)
				)
				(justify mirror)
			)
		)
		(property "Value" ""
			(at 0 0 0)
			(layer "B.Fab")
			(effects
				(font
					(size 1.27 1.27)
				)
				(justify mirror)
			)
		)
		(duplicate_pad_numbers_are_jumpers no)
		(fp_line
			(start -0.7874 -0.4064)
			(end -0.7874 0.4064)
			(stroke
				(width 0.1524)
				(type default)
			)
			(layer "B.SilkS")
		)
		(fp_line
			(start -0.7874 0.4064)
			(end 0.7874 0.4064)
			(stroke
				(width 0.1524)
				(type default)
			)
			(layer "B.SilkS")
		)
		(fp_line
			(start 0.7874 -0.4064)
			(end -0.7874 -0.4064)
			(stroke
				(width 0.1524)
				(type default)
			)
			(layer "B.SilkS")
		)
		(fp_line
			(start 0.7874 0.4064)
			(end 0.7874 -0.4064)
			(stroke
				(width 0.1524)
				(type default)
			)
			(layer "B.SilkS")
		)
		(fp_line
			(start -0.67945 -0.3048)
			(end -0.67945 0.3048)
			(stroke
				(width 0.1)
				(type default)
			)
			(layer "B.Fab")
		)
		(fp_line
			(start -0.67945 0.3048)
			(end -0.120396 0.3048)
			(stroke
				(width 0.1)
				(type default)
			)
			(layer "B.Fab")
		)
		(fp_line
			(start -0.12065 -0.3048)
			(end -0.67945 -0.3048)
			(stroke
				(width 0.1)
				(type default)
			)
			(layer "B.Fab")
		)
		(fp_line
			(start -0.12065 -0.2794)
			(end -0.12065 -0.3048)
			(stroke
				(width 0.1)
				(type default)
			)
			(layer "B.Fab")
		)
		(fp_line
			(start -0.120396 0.2794)
			(end 0.12065 0.2794)
			(stroke
				(width 0.1)
				(type default)
			)
			(layer "B.Fab")
		)
		(fp_line
			(start -0.120396 0.3048)
			(end -0.120396 0.2794)
			(stroke
				(width 0.1)
				(type default)
			)
			(layer "B.Fab")
		)
		(fp_line
			(start 0.12065 -0.305054)
			(end 0.12065 -0.2794)
			(stroke
				(width 0.1)
				(type default)
			)
			(layer "B.Fab")
		)
		(fp_line
			(start 0.12065 -0.2794)
			(end -0.12065 -0.2794)
			(stroke
				(width 0.1)
				(type default)
			)
			(layer "B.Fab")
		)
		(fp_line
			(start 0.12065 0.2794)
			(end 0.12065 0.3048)
			(stroke
				(width 0.1)
				(type default)
			)
			(layer "B.Fab")
		)
		(fp_line
			(start 0.12065 0.3048)
			(end 0.67945 0.3048)
			(stroke
				(width 0.1)
				(type default)
			)
			(layer "B.Fab")
		)
		(fp_line
			(start 0.67945 -0.305054)
			(end 0.12065 -0.305054)
			(stroke
				(width 0.1)
				(type default)
			)
			(layer "B.Fab")
		)
		(fp_line
			(start 0.67945 0.3048)
			(end 0.67945 -0.305054)
			(stroke
				(width 0.1)
				(type default)
			)
			(layer "B.Fab")
		)
		(pad "1" smd circle
			(at 0.40005 0 180)
			(size 0 0)
			(layers "B.Cu" "B.Mask" "B.Paste")
			(net "P12V_HSC_ADC_N")
		)
		(pad "2" smd circle
			(at -0.40005 0 180)
			(size 0 0)
			(layers "B.Cu" "B.Mask" "B.Paste")
			(net "P12V_HSC_SENSE1_N")
		)
	)
	(footprint ""
		(layer "B.Cu")
		(at 413.123634 -193.99631)
		(property "Reference" "R96"
			(at 0 0 0)
			(layer "B.SilkS")
			(hide yes)
			(effects
				(font
					(size 1.27 1.27)
				)
				(justify mirror)
			)
		)
		(property "Value" ""
			(at 0 0 0)
			(layer "B.Fab")
			(effects
				(font
					(size 1.27 1.27)
				)
				(justify mirror)
			)
		)
		(duplicate_pad_numbers_are_jumpers no)
		(fp_line
			(start -0.7874 -0.4064)
			(end -0.7874 0.4064)
			(stroke
				(width 0.1524)
				(type default)
			)
			(layer "B.SilkS")
		)
		(fp_line
			(start -0.7874 0.4064)
			(end 0.7874 0.4064)
			(stroke
				(width 0.1524)
				(type default)
			)
			(layer "B.SilkS")
		)
		(fp_line
			(start 0.7874 -0.4064)
			(end -0.7874 -0.4064)
			(stroke
				(width 0.1524)
				(type default)
			)
			(layer "B.SilkS")
		)
		(fp_line
			(start 0.7874 0.4064)
			(end 0.7874 -0.4064)
			(stroke
				(width 0.1524)
				(type default)
			)
			(layer "B.SilkS")
		)
		(fp_line
			(start -0.67945 -0.3048)
			(end -0.67945 0.3048)
			(stroke
				(width 0.1)
				(type default)
			)
			(layer "B.Fab")
		)
		(fp_line
			(start -0.67945 0.3048)
			(end -0.120396 0.3048)
			(stroke
				(width 0.1)
				(type default)
			)
			(layer "B.Fab")
		)
		(fp_line
			(start -0.12065 -0.3048)
			(end -0.67945 -0.3048)
			(stroke
				(width 0.1)
				(type default)
			)
			(layer "B.Fab")
		)
		(fp_line
			(start -0.12065 -0.2794)
			(end -0.12065 -0.3048)
			(stroke
				(width 0.1)
				(type default)
			)
			(layer "B.Fab")
		)
		(fp_line
			(start -0.120396 0.2794)
			(end 0.12065 0.2794)
			(stroke
				(width 0.1)
				(type default)
			)
			(layer "B.Fab")
		)
		(fp_line
			(start -0.120396 0.3048)
			(end -0.120396 0.2794)
			(stroke
				(width 0.1)
				(type default)
			)
			(layer "B.Fab")
		)
		(fp_line
			(start 0.12065 -0.305054)
			(end 0.12065 -0.2794)
			(stroke
				(width 0.1)
				(type default)
			)
			(layer "B.Fab")
		)
		(fp_line
			(start 0.12065 -0.2794)
			(end -0.12065 -0.2794)
			(stroke
				(width 0.1)
				(type default)
			)
			(layer "B.Fab")
		)
		(fp_line
			(start 0.12065 0.2794)
			(end 0.12065 0.3048)
			(stroke
				(width 0.1)
				(type default)
			)
			(layer "B.Fab")
		)
		(fp_line
			(start 0.12065 0.3048)
			(end 0.67945 0.3048)
			(stroke
				(width 0.1)
				(type default)
			)
			(layer "B.Fab")
		)
		(fp_line
			(start 0.67945 -0.305054)
			(end 0.12065 -0.305054)
			(stroke
				(width 0.1)
				(type default)
			)
			(layer "B.Fab")
		)
		(fp_line
			(start 0.67945 0.3048)
			(end 0.67945 -0.305054)
			(stroke
				(width 0.1)
				(type default)
			)
			(layer "B.Fab")
		)
		(pad "1" smd circle
			(at 0.40005 0 180)
			(size 0 0)
			(layers "B.Cu" "B.Mask" "B.Paste")
			(net "P3V3")
		)
		(pad "2" smd circle
			(at -0.40005 0 180)
			(size 0 0)
			(layers "B.Cu" "B.Mask" "B.Paste")
			(net "PWRGD_CHG_CPU0_DIMM0")
		)
	)
	(footprint ""
		(layer "B.Cu")
		(at 111.214154 -190.870332 90)
		(property "Reference" "PC305_4"
			(at 0 0 90)
			(layer "B.SilkS")
			(hide yes)
			(effects
				(font
					(size 1.27 1.27)
				)
				(justify mirror)
			)
		)
		(property "Value" ""
			(at 0 0 90)
			(layer "B.Fab")
			(effects
				(font
					(size 1.27 1.27)
				)
				(justify mirror)
			)
		)
		(duplicate_pad_numbers_are_jumpers no)
		(fp_line
			(start 1.524 -0.762)
			(end -1.524 -0.762)
			(stroke
				(width 0.1524)
				(type default)
			)
			(layer "B.SilkS")
		)
		(fp_line
			(start -1.524 -0.762)
			(end -1.524 0.762)
			(stroke
				(width 0.1524)
				(type default)
			)
			(layer "B.SilkS")
		)
		(fp_line
			(start 1.524 0.762)
			(end 1.524 -0.762)
			(stroke
				(width 0.1524)
				(type default)
			)
			(layer "B.SilkS")
		)
		(fp_line
			(start -1.524 0.762)
			(end 1.524 0.762)
			(stroke
				(width 0.1524)
				(type default)
			)
			(layer "B.SilkS")
		)
		(fp_line
			(start 1.1049 -0.724916)
			(end 1.1049 0.724916)
			(stroke
				(width 0.1)
				(type default)
			)
			(layer "B.Fab")
		)
		(fp_line
			(start -1.1049 -0.724916)
			(end 1.1049 -0.724916)
			(stroke
				(width 0.1)
				(type default)
			)
			(layer "B.Fab")
		)
		(fp_line
			(start 1.1049 0.724916)
			(end -1.1049 0.724916)
			(stroke
				(width 0.1)
				(type default)
			)
			(layer "B.Fab")
		)
		(fp_line
			(start -1.1049 0.724916)
			(end -1.1049 -0.724916)
			(stroke
				(width 0.1)
				(type default)
			)
			(layer "B.Fab")
		)
		(pad "1" smd rect
			(at 0.889 0 90)
			(size 1.016 1.27)
			(layers "B.Cu" "B.Mask" "B.Paste")
			(net "PVDDCR_CPU0_P1")
		)
		(pad "2" smd rect
			(at -0.889 0 90)
			(size 1.016 1.27)
			(layers "B.Cu" "B.Mask" "B.Paste")
			(net "GND")
		)
	)
	(footprint ""
		(layer "B.Cu")
		(at 240.919 -236.855 90)
		(property "Reference" "C25"
			(at 0 0 90)
			(layer "B.SilkS")
			(hide yes)
			(effects
				(font
					(size 1.27 1.27)
				)
				(justify mirror)
			)
		)
		(property "Value" ""
			(at 0 0 90)
			(layer "B.Fab")
			(effects
				(font
					(size 1.27 1.27)
				)
				(justify mirror)
			)
		)
		(duplicate_pad_numbers_are_jumpers no)
		(fp_line
			(start 0.7874 -0.4064)
			(end -0.7874 -0.4064)
			(stroke
				(width 0.1524)
				(type default)
			)
			(layer "B.SilkS")
		)
		(fp_line
			(start -0.7874 -0.4064)
			(end -0.7874 0.4064)
			(stroke
				(width 0.1524)
				(type default)
			)
			(layer "B.SilkS")
		)
		(fp_line
			(start 0.7874 0.4064)
			(end 0.7874 -0.4064)
			(stroke
				(width 0.1524)
				(type default)
			)
			(layer "B.SilkS")
		)
		(fp_line
			(start -0.7874 0.4064)
			(end 0.7874 0.4064)
			(stroke
				(width 0.1524)
				(type default)
			)
			(layer "B.SilkS")
		)
		(fp_line
			(start 0.67945 -0.305054)
			(end 0.12065 -0.305054)
			(stroke
				(width 0.1)
				(type default)
			)
			(layer "B.Fab")
		)
		(fp_line
			(start 0.12065 -0.305054)
			(end 0.12065 -0.2794)
			(stroke
				(width 0.1)
				(type default)
			)
			(layer "B.Fab")
		)
		(fp_line
			(start -0.12065 -0.3048)
			(end -0.67945 -0.3048)
			(stroke
				(width 0.1)
				(type default)
			)
			(layer "B.Fab")
		)
		(fp_line
			(start -0.67945 -0.3048)
			(end -0.67945 0.3048)
			(stroke
				(width 0.1)
				(type default)
			)
			(layer "B.Fab")
		)
		(fp_line
			(start 0.12065 -0.2794)
			(end -0.12065 -0.2794)
			(stroke
				(width 0.1)
				(type default)
			)
			(layer "B.Fab")
		)
		(fp_line
			(start -0.12065 -0.2794)
			(end -0.12065 -0.3048)
			(stroke
				(width 0.1)
				(type default)
			)
			(layer "B.Fab")
		)
		(fp_line
			(start 0.12065 0.2794)
			(end 0.12065 0.3048)
			(stroke
				(width 0.1)
				(type default)
			)
			(layer "B.Fab")
		)
		(fp_line
			(start -0.120396 0.2794)
			(end 0.12065 0.2794)
			(stroke
				(width 0.1)
				(type default)
			)
			(layer "B.Fab")
		)
		(fp_line
			(start 0.67945 0.3048)
			(end 0.67945 -0.305054)
			(stroke
				(width 0.1)
				(type default)
			)
			(layer "B.Fab")
		)
		(fp_line
			(start 0.12065 0.3048)
			(end 0.67945 0.3048)
			(stroke
				(width 0.1)
				(type default)
			)
			(layer "B.Fab")
		)
		(fp_line
			(start -0.120396 0.3048)
			(end -0.120396 0.2794)
			(stroke
				(width 0.1)
				(type default)
			)
			(layer "B.Fab")
		)
		(fp_line
			(start -0.67945 0.3048)
			(end -0.120396 0.3048)
			(stroke
				(width 0.1)
				(type default)
			)
			(layer "B.Fab")
		)
		(pad "1" smd circle
			(at 0.40005 0 270)
			(size 0 0)
			(layers "B.Cu" "B.Mask" "B.Paste")
			(net "P3V3_AUX")
		)
		(pad "2" smd circle
			(at -0.40005 0 270)
			(size 0 0)
			(layers "B.Cu" "B.Mask" "B.Paste")
			(net "GND")
		)
	)
	(footprint ""
		(layer "B.Cu")
		(at 273.111214 -347.77553 -90)
		(property "Reference" "PR107"
			(at 0 0 90)
			(layer "B.SilkS")
			(hide yes)
			(effects
				(font
					(size 1.27 1.27)
				)
				(justify mirror)
			)
		)
		(property "Value" ""
			(at 0 0 90)
			(layer "B.Fab")
			(effects
				(font
					(size 1.27 1.27)
				)
				(justify mirror)
			)
		)
		(duplicate_pad_numbers_are_jumpers no)
		(fp_line
			(start -0.7874 0.4064)
			(end 0.7874 0.4064)
			(stroke
				(width 0.1524)
				(type default)
			)
			(layer "B.SilkS")
		)
		(fp_line
			(start 0.7874 0.4064)
			(end 0.7874 -0.4064)
			(stroke
				(width 0.1524)
				(type default)
			)
			(layer "B.SilkS")
		)
		(fp_line
			(start -0.7874 -0.4064)
			(end -0.7874 0.4064)
			(stroke
				(width 0.1524)
				(type default)
			)
			(layer "B.SilkS")
		)
		(fp_line
			(start 0.7874 -0.4064)
			(end -0.7874 -0.4064)
			(stroke
				(width 0.1524)
				(type default)
			)
			(layer "B.SilkS")
		)
		(fp_line
			(start -0.67945 0.3048)
			(end -0.120396 0.3048)
			(stroke
				(width 0.1)
				(type default)
			)
			(layer "B.Fab")
		)
		(fp_line
			(start -0.120396 0.3048)
			(end -0.120396 0.2794)
			(stroke
				(width 0.1)
				(type default)
			)
			(layer "B.Fab")
		)
		(fp_line
			(start 0.12065 0.3048)
			(end 0.67945 0.3048)
			(stroke
				(width 0.1)
				(type default)
			)
			(layer "B.Fab")
		)
		(fp_line
			(start 0.67945 0.3048)
			(end 0.67945 -0.305054)
			(stroke
				(width 0.1)
				(type default)
			)
			(layer "B.Fab")
		)
		(fp_line
			(start -0.120396 0.2794)
			(end 0.12065 0.2794)
			(stroke
				(width 0.1)
				(type default)
			)
			(layer "B.Fab")
		)
		(fp_line
			(start 0.12065 0.2794)
			(end 0.12065 0.3048)
			(stroke
				(width 0.1)
				(type default)
			)
			(layer "B.Fab")
		)
		(fp_line
			(start -0.12065 -0.2794)
			(end -0.12065 -0.3048)
			(stroke
				(width 0.1)
				(type default)
			)
			(layer "B.Fab")
		)
		(fp_line
			(start 0.12065 -0.2794)
			(end -0.12065 -0.2794)
			(stroke
				(width 0.1)
				(type default)
			)
			(layer "B.Fab")
		)
		(fp_line
			(start -0.67945 -0.3048)
			(end -0.67945 0.3048)
			(stroke
				(width 0.1)
				(type default)
			)
			(layer "B.Fab")
		)
		(fp_line
			(start -0.12065 -0.3048)
			(end -0.67945 -0.3048)
			(stroke
				(width 0.1)
				(type default)
			)
			(layer "B.Fab")
		)
		(fp_line
			(start 0.12065 -0.305054)
			(end 0.12065 -0.2794)
			(stroke
				(width 0.1)
				(type default)
			)
			(layer "B.Fab")
		)
		(fp_line
			(start 0.67945 -0.305054)
			(end 0.12065 -0.305054)
			(stroke
				(width 0.1)
				(type default)
			)
			(layer "B.Fab")
		)
		(pad "1" smd circle
			(at 0.40005 0 90)
			(size 0 0)
			(layers "B.Cu" "B.Mask" "B.Paste")
			(net "PVDDCR_CPU1_P0_PVCC")
		)
		(pad "2" smd circle
			(at -0.40005 0 90)
			(size 0 0)
			(layers "B.Cu" "B.Mask" "B.Paste")
			(net "PVDDIO_P0_VCC4")
		)
	)
	(footprint ""
		(layer "B.Cu")
		(at 363.550454 -253.43231)
		(property "Reference" "C2532"
			(at 0 0 0)
			(layer "B.SilkS")
			(hide yes)
			(effects
				(font
					(size 1.27 1.27)
				)
				(justify mirror)
			)
		)
		(property "Value" ""
			(at 0 0 0)
			(layer "B.Fab")
			(effects
				(font
					(size 1.27 1.27)
				)
				(justify mirror)
			)
		)
		(duplicate_pad_numbers_are_jumpers no)
		(fp_line
			(start -0.7874 -0.4064)
			(end -0.7874 0.4064)
			(stroke
				(width 0.1524)
				(type default)
			)
			(layer "B.SilkS")
		)
		(fp_line
			(start -0.7874 0.4064)
			(end 0.7874 0.4064)
			(stroke
				(width 0.1524)
				(type default)
			)
			(layer "B.SilkS")
		)
		(fp_line
			(start 0.7874 -0.4064)
			(end -0.7874 -0.4064)
			(stroke
				(width 0.1524)
				(type default)
			)
			(layer "B.SilkS")
		)
		(fp_line
			(start 0.7874 0.4064)
			(end 0.7874 -0.4064)
			(stroke
				(width 0.1524)
				(type default)
			)
			(layer "B.SilkS")
		)
		(fp_line
			(start -0.67945 -0.3048)
			(end -0.67945 0.3048)
			(stroke
				(width 0.1)
				(type default)
			)
			(layer "B.Fab")
		)
		(fp_line
			(start -0.67945 0.3048)
			(end -0.120396 0.3048)
			(stroke
				(width 0.1)
				(type default)
			)
			(layer "B.Fab")
		)
		(fp_line
			(start -0.12065 -0.3048)
			(end -0.67945 -0.3048)
			(stroke
				(width 0.1)
				(type default)
			)
			(layer "B.Fab")
		)
		(fp_line
			(start -0.12065 -0.2794)
			(end -0.12065 -0.3048)
			(stroke
				(width 0.1)
				(type default)
			)
			(layer "B.Fab")
		)
		(fp_line
			(start -0.120396 0.2794)
			(end 0.12065 0.2794)
			(stroke
				(width 0.1)
				(type default)
			)
			(layer "B.Fab")
		)
		(fp_line
			(start -0.120396 0.3048)
			(end -0.120396 0.2794)
			(stroke
				(width 0.1)
				(type default)
			)
			(layer "B.Fab")
		)
		(fp_line
			(start 0.12065 -0.305054)
			(end 0.12065 -0.2794)
			(stroke
				(width 0.1)
				(type default)
			)
			(layer "B.Fab")
		)
		(fp_line
			(start 0.12065 -0.2794)
			(end -0.12065 -0.2794)
			(stroke
				(width 0.1)
				(type default)
			)
			(layer "B.Fab")
		)
		(fp_line
			(start 0.12065 0.2794)
			(end 0.12065 0.3048)
			(stroke
				(width 0.1)
				(type default)
			)
			(layer "B.Fab")
		)
		(fp_line
			(start 0.12065 0.3048)
			(end 0.67945 0.3048)
			(stroke
				(width 0.1)
				(type default)
			)
			(layer "B.Fab")
		)
		(fp_line
			(start 0.67945 -0.305054)
			(end 0.12065 -0.305054)
			(stroke
				(width 0.1)
				(type default)
			)
			(layer "B.Fab")
		)
		(fp_line
			(start 0.67945 0.3048)
			(end 0.67945 -0.305054)
			(stroke
				(width 0.1)
				(type default)
			)
			(layer "B.Fab")
		)
		(pad "1" smd circle
			(at 0.40005 0 180)
			(size 0 0)
			(layers "B.Cu" "B.Mask" "B.Paste")
			(net "PVDDCR_SOC_P0")
		)
		(pad "2" smd circle
			(at -0.40005 0 180)
			(size 0 0)
			(layers "B.Cu" "B.Mask" "B.Paste")
			(net "GND")
		)
	)
	(footprint ""
		(layer "B.Cu")
		(at 164.062918 -121.701814 180)
		(property "Reference" "C1209"
			(at 0 0 0)
			(layer "B.SilkS")
			(hide yes)
			(effects
				(font
					(size 1.27 1.27)
				)
				(justify mirror)
			)
		)
		(property "Value" ""
			(at 0 0 0)
			(layer "B.Fab")
			(effects
				(font
					(size 1.27 1.27)
				)
				(justify mirror)
			)
		)
		(duplicate_pad_numbers_are_jumpers no)
		(fp_line
			(start 0.7874 0.4064)
			(end 0.7874 -0.4064)
			(stroke
				(width 0.1524)
				(type default)
			)
			(layer "B.SilkS")
		)
		(fp_line
			(start 0.7874 -0.4064)
			(end -0.7874 -0.4064)
			(stroke
				(width 0.1524)
				(type default)
			)
			(layer "B.SilkS")
		)
		(fp_line
			(start -0.7874 0.4064)
			(end 0.7874 0.4064)
			(stroke
				(width 0.1524)
				(type default)
			)
			(layer "B.SilkS")
		)
		(fp_line
			(start -0.7874 -0.4064)
			(end -0.7874 0.4064)
			(stroke
				(width 0.1524)
				(type default)
			)
			(layer "B.SilkS")
		)
		(fp_line
			(start 0.67945 0.3048)
			(end 0.67945 -0.305054)
			(stroke
				(width 0.1)
				(type default)
			)
			(layer "B.Fab")
		)
		(fp_line
			(start 0.67945 -0.305054)
			(end 0.12065 -0.305054)
			(stroke
				(width 0.1)
				(type default)
			)
			(layer "B.Fab")
		)
		(fp_line
			(start 0.12065 0.3048)
			(end 0.67945 0.3048)
			(stroke
				(width 0.1)
				(type default)
			)
			(layer "B.Fab")
		)
		(fp_line
			(start 0.12065 0.2794)
			(end 0.12065 0.3048)
			(stroke
				(width 0.1)
				(type default)
			)
			(layer "B.Fab")
		)
		(fp_line
			(start 0.12065 -0.2794)
			(end -0.12065 -0.2794)
			(stroke
				(width 0.1)
				(type default)
			)
			(layer "B.Fab")
		)
		(fp_line
			(start 0.12065 -0.305054)
			(end 0.12065 -0.2794)
			(stroke
				(width 0.1)
				(type default)
			)
			(layer "B.Fab")
		)
		(fp_line
			(start -0.120396 0.3048)
			(end -0.120396 0.2794)
			(stroke
				(width 0.1)
				(type default)
			)
			(layer "B.Fab")
		)
		(fp_line
			(start -0.120396 0.2794)
			(end 0.12065 0.2794)
			(stroke
				(width 0.1)
				(type default)
			)
			(layer "B.Fab")
		)
		(fp_line
			(start -0.12065 -0.2794)
			(end -0.12065 -0.3048)
			(stroke
				(width 0.1)
				(type default)
			)
			(layer "B.Fab")
		)
		(fp_line
			(start -0.12065 -0.3048)
			(end -0.67945 -0.3048)
			(stroke
				(width 0.1)
				(type default)
			)
			(layer "B.Fab")
		)
		(fp_line
			(start -0.67945 0.3048)
			(end -0.120396 0.3048)
			(stroke
				(width 0.1)
				(type default)
			)
			(layer "B.Fab")
		)
		(fp_line
			(start -0.67945 -0.3048)
			(end -0.67945 0.3048)
			(stroke
				(width 0.1)
				(type default)
			)
			(layer "B.Fab")
		)
		(pad "1" smd circle
			(at 0.40005 0)
			(size 0 0)
			(layers "B.Cu" "B.Mask" "B.Paste")
			(net "SCM_SYS_PWROK_R2")
		)
		(pad "2" smd circle
			(at -0.40005 0)
			(size 0 0)
			(layers "B.Cu" "B.Mask" "B.Paste")
			(net "GND")
		)
	)
	(footprint ""
		(layer "B.Cu")
		(at 88.138 -147.955 180)
		(property "Reference" "PR8009"
			(at 0 0 0)
			(layer "B.SilkS")
			(hide yes)
			(effects
				(font
					(size 1.27 1.27)
				)
				(justify mirror)
			)
		)
		(property "Value" ""
			(at 0 0 0)
			(layer "B.Fab")
			(effects
				(font
					(size 1.27 1.27)
				)
				(justify mirror)
			)
		)
		(duplicate_pad_numbers_are_jumpers no)
		(fp_line
			(start 0.7874 0.4064)
			(end 0.7874 -0.4064)
			(stroke
				(width 0.1524)
				(type default)
			)
			(layer "B.SilkS")
		)
		(fp_line
			(start 0.7874 -0.4064)
			(end -0.7874 -0.4064)
			(stroke
				(width 0.1524)
				(type default)
			)
			(layer "B.SilkS")
		)
		(fp_line
			(start -0.7874 0.4064)
			(end 0.7874 0.4064)
			(stroke
				(width 0.1524)
				(type default)
			)
			(layer "B.SilkS")
		)
		(fp_line
			(start -0.7874 -0.4064)
			(end -0.7874 0.4064)
			(stroke
				(width 0.1524)
				(type default)
			)
			(layer "B.SilkS")
		)
		(fp_line
			(start 0.67945 0.3048)
			(end 0.67945 -0.305054)
			(stroke
				(width 0.1)
				(type default)
			)
			(layer "B.Fab")
		)
		(fp_line
			(start 0.67945 -0.305054)
			(end 0.12065 -0.305054)
			(stroke
				(width 0.1)
				(type default)
			)
			(layer "B.Fab")
		)
		(fp_line
			(start 0.12065 0.3048)
			(end 0.67945 0.3048)
			(stroke
				(width 0.1)
				(type default)
			)
			(layer "B.Fab")
		)
		(fp_line
			(start 0.12065 0.2794)
			(end 0.12065 0.3048)
			(stroke
				(width 0.1)
				(type default)
			)
			(layer "B.Fab")
		)
		(fp_line
			(start 0.12065 -0.2794)
			(end -0.12065 -0.2794)
			(stroke
				(width 0.1)
				(type default)
			)
			(layer "B.Fab")
		)
		(fp_line
			(start 0.12065 -0.305054)
			(end 0.12065 -0.2794)
			(stroke
				(width 0.1)
				(type default)
			)
			(layer "B.Fab")
		)
		(fp_line
			(start -0.120396 0.3048)
			(end -0.120396 0.2794)
			(stroke
				(width 0.1)
				(type default)
			)
			(layer "B.Fab")
		)
		(fp_line
			(start -0.120396 0.2794)
			(end 0.12065 0.2794)
			(stroke
				(width 0.1)
				(type default)
			)
			(layer "B.Fab")
		)
		(fp_line
			(start -0.12065 -0.2794)
			(end -0.12065 -0.3048)
			(stroke
				(width 0.1)
				(type default)
			)
			(layer "B.Fab")
		)
		(fp_line
			(start -0.12065 -0.3048)
			(end -0.67945 -0.3048)
			(stroke
				(width 0.1)
				(type default)
			)
			(layer "B.Fab")
		)
		(fp_line
			(start -0.67945 0.3048)
			(end -0.120396 0.3048)
			(stroke
				(width 0.1)
				(type default)
			)
			(layer "B.Fab")
		)
		(fp_line
			(start -0.67945 -0.3048)
			(end -0.67945 0.3048)
			(stroke
				(width 0.1)
				(type default)
			)
			(layer "B.Fab")
		)
		(pad "1" smd circle
			(at 0.40005 0)
			(size 0 0)
			(layers "B.Cu" "B.Mask" "B.Paste")
			(net "SVID_PVDDCR_CPU0_P1_SVC_R")
		)
		(pad "2" smd circle
			(at -0.40005 0)
			(size 0 0)
			(layers "B.Cu" "B.Mask" "B.Paste")
			(net "SVID_PVDDCR_CPU0_P1_SVC_R1")
		)
	)
	(footprint ""
		(layer "B.Cu")
		(at 369.646454 -250.89231)
		(property "Reference" "C2557"
			(at 0 0 0)
			(layer "B.SilkS")
			(hide yes)
			(effects
				(font
					(size 1.27 1.27)
				)
				(justify mirror)
			)
		)
		(property "Value" ""
			(at 0 0 0)
			(layer "B.Fab")
			(effects
				(font
					(size 1.27 1.27)
				)
				(justify mirror)
			)
		)
		(duplicate_pad_numbers_are_jumpers no)
		(fp_line
			(start -0.7874 -0.4064)
			(end -0.7874 0.4064)
			(stroke
				(width 0.1524)
				(type default)
			)
			(layer "B.SilkS")
		)
		(fp_line
			(start -0.7874 0.4064)
			(end 0.7874 0.4064)
			(stroke
				(width 0.1524)
				(type default)
			)
			(layer "B.SilkS")
		)
		(fp_line
			(start 0.7874 -0.4064)
			(end -0.7874 -0.4064)
			(stroke
				(width 0.1524)
				(type default)
			)
			(layer "B.SilkS")
		)
		(fp_line
			(start 0.7874 0.4064)
			(end 0.7874 -0.4064)
			(stroke
				(width 0.1524)
				(type default)
			)
			(layer "B.SilkS")
		)
		(fp_line
			(start -0.67945 -0.3048)
			(end -0.67945 0.3048)
			(stroke
				(width 0.1)
				(type default)
			)
			(layer "B.Fab")
		)
		(fp_line
			(start -0.67945 0.3048)
			(end -0.120396 0.3048)
			(stroke
				(width 0.1)
				(type default)
			)
			(layer "B.Fab")
		)
		(fp_line
			(start -0.12065 -0.3048)
			(end -0.67945 -0.3048)
			(stroke
				(width 0.1)
				(type default)
			)
			(layer "B.Fab")
		)
		(fp_line
			(start -0.12065 -0.2794)
			(end -0.12065 -0.3048)
			(stroke
				(width 0.1)
				(type default)
			)
			(layer "B.Fab")
		)
		(fp_line
			(start -0.120396 0.2794)
			(end 0.12065 0.2794)
			(stroke
				(width 0.1)
				(type default)
			)
			(layer "B.Fab")
		)
		(fp_line
			(start -0.120396 0.3048)
			(end -0.120396 0.2794)
			(stroke
				(width 0.1)
				(type default)
			)
			(layer "B.Fab")
		)
		(fp_line
			(start 0.12065 -0.305054)
			(end 0.12065 -0.2794)
			(stroke
				(width 0.1)
				(type default)
			)
			(layer "B.Fab")
		)
		(fp_line
			(start 0.12065 -0.2794)
			(end -0.12065 -0.2794)
			(stroke
				(width 0.1)
				(type default)
			)
			(layer "B.Fab")
		)
		(fp_line
			(start 0.12065 0.2794)
			(end 0.12065 0.3048)
			(stroke
				(width 0.1)
				(type default)
			)
			(layer "B.Fab")
		)
		(fp_line
			(start 0.12065 0.3048)
			(end 0.67945 0.3048)
			(stroke
				(width 0.1)
				(type default)
			)
			(layer "B.Fab")
		)
		(fp_line
			(start 0.67945 -0.305054)
			(end 0.12065 -0.305054)
			(stroke
				(width 0.1)
				(type default)
			)
			(layer "B.Fab")
		)
		(fp_line
			(start 0.67945 0.3048)
			(end 0.67945 -0.305054)
			(stroke
				(width 0.1)
				(type default)
			)
			(layer "B.Fab")
		)
		(pad "1" smd circle
			(at 0.40005 0 180)
			(size 0 0)
			(layers "B.Cu" "B.Mask" "B.Paste")
			(net "PVDDCR_SOC_P0")
		)
		(pad "2" smd circle
			(at -0.40005 0 180)
			(size 0 0)
			(layers "B.Cu" "B.Mask" "B.Paste")
			(net "GND")
		)
	)
	(footprint ""
		(layer "B.Cu")
		(at 421.01897 -398.942052 90)
		(property "Reference" "C986"
			(at 0 0 90)
			(layer "B.SilkS")
			(hide yes)
			(effects
				(font
					(size 1.27 1.27)
				)
				(justify mirror)
			)
		)
		(property "Value" ""
			(at 0 0 90)
			(layer "B.Fab")
			(effects
				(font
					(size 1.27 1.27)
				)
				(justify mirror)
			)
		)
		(duplicate_pad_numbers_are_jumpers no)
		(fp_line
			(start 0.7874 -0.4064)
			(end -0.7874 -0.4064)
			(stroke
				(width 0.1524)
				(type default)
			)
			(layer "B.SilkS")
		)
		(fp_line
			(start -0.7874 -0.4064)
			(end -0.7874 0.4064)
			(stroke
				(width 0.1524)
				(type default)
			)
			(layer "B.SilkS")
		)
		(fp_line
			(start 0.7874 0.4064)
			(end 0.7874 -0.4064)
			(stroke
				(width 0.1524)
				(type default)
			)
			(layer "B.SilkS")
		)
		(fp_line
			(start -0.7874 0.4064)
			(end 0.7874 0.4064)
			(stroke
				(width 0.1524)
				(type default)
			)
			(layer "B.SilkS")
		)
		(fp_line
			(start 0.67945 -0.305054)
			(end 0.12065 -0.305054)
			(stroke
				(width 0.1)
				(type default)
			)
			(layer "B.Fab")
		)
		(fp_line
			(start 0.12065 -0.305054)
			(end 0.12065 -0.2794)
			(stroke
				(width 0.1)
				(type default)
			)
			(layer "B.Fab")
		)
		(fp_line
			(start -0.12065 -0.3048)
			(end -0.67945 -0.3048)
			(stroke
				(width 0.1)
				(type default)
			)
			(layer "B.Fab")
		)
		(fp_line
			(start -0.67945 -0.3048)
			(end -0.67945 0.3048)
			(stroke
				(width 0.1)
				(type default)
			)
			(layer "B.Fab")
		)
		(fp_line
			(start 0.12065 -0.2794)
			(end -0.12065 -0.2794)
			(stroke
				(width 0.1)
				(type default)
			)
			(layer "B.Fab")
		)
		(fp_line
			(start -0.12065 -0.2794)
			(end -0.12065 -0.3048)
			(stroke
				(width 0.1)
				(type default)
			)
			(layer "B.Fab")
		)
		(fp_line
			(start 0.12065 0.2794)
			(end 0.12065 0.3048)
			(stroke
				(width 0.1)
				(type default)
			)
			(layer "B.Fab")
		)
		(fp_line
			(start -0.120396 0.2794)
			(end 0.12065 0.2794)
			(stroke
				(width 0.1)
				(type default)
			)
			(layer "B.Fab")
		)
		(fp_line
			(start 0.67945 0.3048)
			(end 0.67945 -0.305054)
			(stroke
				(width 0.1)
				(type default)
			)
			(layer "B.Fab")
		)
		(fp_line
			(start 0.12065 0.3048)
			(end 0.67945 0.3048)
			(stroke
				(width 0.1)
				(type default)
			)
			(layer "B.Fab")
		)
		(fp_line
			(start -0.120396 0.3048)
			(end -0.120396 0.2794)
			(stroke
				(width 0.1)
				(type default)
			)
			(layer "B.Fab")
		)
		(fp_line
			(start -0.67945 0.3048)
			(end -0.120396 0.3048)
			(stroke
				(width 0.1)
				(type default)
			)
			(layer "B.Fab")
		)
		(pad "1" smd circle
			(at 0.40005 0 270)
			(size 0 0)
			(layers "B.Cu" "B.Mask" "B.Paste")
			(net "P0V9_CPU0_RT2_2A")
		)
		(pad "2" smd circle
			(at -0.40005 0 270)
			(size 0 0)
			(layers "B.Cu" "B.Mask" "B.Paste")
			(net "GND")
		)
	)
	(footprint ""
		(layer "B.Cu")
		(at 183.551068 -111.863124 -90)
		(property "Reference" "C1126"
			(at 0 0 90)
			(layer "B.SilkS")
			(hide yes)
			(effects
				(font
					(size 1.27 1.27)
				)
				(justify mirror)
			)
		)
		(property "Value" ""
			(at 0 0 90)
			(layer "B.Fab")
			(effects
				(font
					(size 1.27 1.27)
				)
				(justify mirror)
			)
		)
		(duplicate_pad_numbers_are_jumpers no)
		(fp_line
			(start -0.69215 0.2921)
			(end 0.69215 0.2921)
			(stroke
				(width 0.1524)
				(type default)
			)
			(layer "B.SilkS")
		)
		(fp_line
			(start 0.69215 0.2921)
			(end 0.69215 -0.2921)
			(stroke
				(width 0.1524)
				(type default)
			)
			(layer "B.SilkS")
		)
		(fp_line
			(start -0.69215 -0.2921)
			(end -0.69215 0.2921)
			(stroke
				(width 0.1524)
				(type default)
			)
			(layer "B.SilkS")
		)
		(fp_line
			(start 0.69215 -0.2921)
			(end -0.69215 -0.2921)
			(stroke
				(width 0.1524)
				(type default)
			)
			(layer "B.SilkS")
		)
		(fp_line
			(start -0.51435 0.2794)
			(end 0.51435 0.2794)
			(stroke
				(width 0.1)
				(type default)
			)
			(layer "B.Fab")
		)
		(fp_line
			(start 0.51435 0.2794)
			(end 0.51435 -0.2794)
			(stroke
				(width 0.1)
				(type default)
			)
			(layer "B.Fab")
		)
		(fp_line
			(start -0.51435 -0.2794)
			(end -0.51435 0.2794)
			(stroke
				(width 0.1)
				(type default)
			)
			(layer "B.Fab")
		)
		(fp_line
			(start 0.51435 -0.2794)
			(end -0.51435 -0.2794)
			(stroke
				(width 0.1)
				(type default)
			)
			(layer "B.Fab")
		)
		(pad "1" smd circle
			(at 0.40005 0 90)
			(size 0 0)
			(layers "B.Cu" "B.Mask" "B.Paste")
			(net "P1V8_AUX")
		)
		(pad "2" smd circle
			(at -0.40005 0 90)
			(size 0 0)
			(layers "B.Cu" "B.Mask" "B.Paste")
			(net "GND")
		)
		(zone
			(layer "B.Cu")
			(hatch none 0.5)
			(connect_pads
				(clearance 0)
			)
			(min_thickness 0.25)
			(keepout
				(tracks not_allowed)
				(vias allowed)
				(pads allowed)
				(copperpour not_allowed)
				(footprints allowed)
			)
			(placement
				(enabled no)
				(sheetname "")
			)
			(fill
				(thermal_gap 0.5)
				(thermal_bridge_width 0.5)
				(island_removal_mode 0)
			)
			(polygon
				(pts
					(xy 183.405272 -111.764064) (xy 183.405272 -111.963454) (xy 183.463438 -112.053624) (xy 183.638698 -112.053624)
					(xy 183.697118 -111.963454) (xy 183.697118 -111.764064) (xy 183.638952 -111.672624) (xy 183.463438 -111.672624)
				)
			)
		)
	)
	(footprint ""
		(layer "B.Cu")
		(at 73.068434 -386.745988 -90)
		(property "Reference" "C118"
			(at 0 0 90)
			(layer "B.SilkS")
			(hide yes)
			(effects
				(font
					(size 1.27 1.27)
				)
				(justify mirror)
			)
		)
		(property "Value" ""
			(at 0 0 90)
			(layer "B.Fab")
			(effects
				(font
					(size 1.27 1.27)
				)
				(justify mirror)
			)
		)
		(duplicate_pad_numbers_are_jumpers no)
		(fp_line
			(start -0.7874 0.4064)
			(end 0.7874 0.4064)
			(stroke
				(width 0.1524)
				(type default)
			)
			(layer "B.SilkS")
		)
		(fp_line
			(start 0.7874 0.4064)
			(end 0.7874 -0.4064)
			(stroke
				(width 0.1524)
				(type default)
			)
			(layer "B.SilkS")
		)
		(fp_line
			(start -0.7874 -0.4064)
			(end -0.7874 0.4064)
			(stroke
				(width 0.1524)
				(type default)
			)
			(layer "B.SilkS")
		)
		(fp_line
			(start 0.7874 -0.4064)
			(end -0.7874 -0.4064)
			(stroke
				(width 0.1524)
				(type default)
			)
			(layer "B.SilkS")
		)
		(fp_line
			(start -0.67945 0.3048)
			(end -0.120396 0.3048)
			(stroke
				(width 0.1)
				(type default)
			)
			(layer "B.Fab")
		)
		(fp_line
			(start -0.120396 0.3048)
			(end -0.120396 0.2794)
			(stroke
				(width 0.1)
				(type default)
			)
			(layer "B.Fab")
		)
		(fp_line
			(start 0.12065 0.3048)
			(end 0.67945 0.3048)
			(stroke
				(width 0.1)
				(type default)
			)
			(layer "B.Fab")
		)
		(fp_line
			(start 0.67945 0.3048)
			(end 0.67945 -0.305054)
			(stroke
				(width 0.1)
				(type default)
			)
			(layer "B.Fab")
		)
		(fp_line
			(start -0.120396 0.2794)
			(end 0.12065 0.2794)
			(stroke
				(width 0.1)
				(type default)
			)
			(layer "B.Fab")
		)
		(fp_line
			(start 0.12065 0.2794)
			(end 0.12065 0.3048)
			(stroke
				(width 0.1)
				(type default)
			)
			(layer "B.Fab")
		)
		(fp_line
			(start -0.12065 -0.2794)
			(end -0.12065 -0.3048)
			(stroke
				(width 0.1)
				(type default)
			)
			(layer "B.Fab")
		)
		(fp_line
			(start 0.12065 -0.2794)
			(end -0.12065 -0.2794)
			(stroke
				(width 0.1)
				(type default)
			)
			(layer "B.Fab")
		)
		(fp_line
			(start -0.67945 -0.3048)
			(end -0.67945 0.3048)
			(stroke
				(width 0.1)
				(type default)
			)
			(layer "B.Fab")
		)
		(fp_line
			(start -0.12065 -0.3048)
			(end -0.67945 -0.3048)
			(stroke
				(width 0.1)
				(type default)
			)
			(layer "B.Fab")
		)
		(fp_line
			(start 0.12065 -0.305054)
			(end 0.12065 -0.2794)
			(stroke
				(width 0.1)
				(type default)
			)
			(layer "B.Fab")
		)
		(fp_line
			(start 0.67945 -0.305054)
			(end 0.12065 -0.305054)
			(stroke
				(width 0.1)
				(type default)
			)
			(layer "B.Fab")
		)
		(pad "1" smd circle
			(at 0.40005 0 90)
			(size 0 0)
			(layers "B.Cu" "B.Mask" "B.Paste")
			(net "P1V8_CPU1_RT_1D")
		)
		(pad "2" smd circle
			(at -0.40005 0 90)
			(size 0 0)
			(layers "B.Cu" "B.Mask" "B.Paste")
			(net "GND")
		)
	)
	(footprint ""
		(layer "B.Cu")
		(at 119.34698 -169.258234 90)
		(property "Reference" "PR211"
			(at 0 0 90)
			(layer "B.SilkS")
			(hide yes)
			(effects
				(font
					(size 1.27 1.27)
				)
				(justify mirror)
			)
		)
		(property "Value" ""
			(at 0 0 90)
			(layer "B.Fab")
			(effects
				(font
					(size 1.27 1.27)
				)
				(justify mirror)
			)
		)
		(duplicate_pad_numbers_are_jumpers no)
		(fp_line
			(start 0.7874 -0.4064)
			(end -0.7874 -0.4064)
			(stroke
				(width 0.1524)
				(type default)
			)
			(layer "B.SilkS")
		)
		(fp_line
			(start -0.7874 -0.4064)
			(end -0.7874 0.4064)
			(stroke
				(width 0.1524)
				(type default)
			)
			(layer "B.SilkS")
		)
		(fp_line
			(start 0.7874 0.4064)
			(end 0.7874 -0.4064)
			(stroke
				(width 0.1524)
				(type default)
			)
			(layer "B.SilkS")
		)
		(fp_line
			(start -0.7874 0.4064)
			(end 0.7874 0.4064)
			(stroke
				(width 0.1524)
				(type default)
			)
			(layer "B.SilkS")
		)
		(fp_line
			(start 0.67945 -0.305054)
			(end 0.12065 -0.305054)
			(stroke
				(width 0.1)
				(type default)
			)
			(layer "B.Fab")
		)
		(fp_line
			(start 0.12065 -0.305054)
			(end 0.12065 -0.2794)
			(stroke
				(width 0.1)
				(type default)
			)
			(layer "B.Fab")
		)
		(fp_line
			(start -0.12065 -0.3048)
			(end -0.67945 -0.3048)
			(stroke
				(width 0.1)
				(type default)
			)
			(layer "B.Fab")
		)
		(fp_line
			(start -0.67945 -0.3048)
			(end -0.67945 0.3048)
			(stroke
				(width 0.1)
				(type default)
			)
			(layer "B.Fab")
		)
		(fp_line
			(start 0.12065 -0.2794)
			(end -0.12065 -0.2794)
			(stroke
				(width 0.1)
				(type default)
			)
			(layer "B.Fab")
		)
		(fp_line
			(start -0.12065 -0.2794)
			(end -0.12065 -0.3048)
			(stroke
				(width 0.1)
				(type default)
			)
			(layer "B.Fab")
		)
		(fp_line
			(start 0.12065 0.2794)
			(end 0.12065 0.3048)
			(stroke
				(width 0.1)
				(type default)
			)
			(layer "B.Fab")
		)
		(fp_line
			(start -0.120396 0.2794)
			(end 0.12065 0.2794)
			(stroke
				(width 0.1)
				(type default)
			)
			(layer "B.Fab")
		)
		(fp_line
			(start 0.67945 0.3048)
			(end 0.67945 -0.305054)
			(stroke
				(width 0.1)
				(type default)
			)
			(layer "B.Fab")
		)
		(fp_line
			(start 0.12065 0.3048)
			(end 0.67945 0.3048)
			(stroke
				(width 0.1)
				(type default)
			)
			(layer "B.Fab")
		)
		(fp_line
			(start -0.120396 0.3048)
			(end -0.120396 0.2794)
			(stroke
				(width 0.1)
				(type default)
			)
			(layer "B.Fab")
		)
		(fp_line
			(start -0.67945 0.3048)
			(end -0.120396 0.3048)
			(stroke
				(width 0.1)
				(type default)
			)
			(layer "B.Fab")
		)
		(pad "1" smd circle
			(at 0.40005 0 270)
			(size 0 0)
			(layers "B.Cu" "B.Mask" "B.Paste")
			(net "PVDDCR_SOC_P1_VOS1")
		)
		(pad "2" smd circle
			(at -0.40005 0 270)
			(size 0 0)
			(layers "B.Cu" "B.Mask" "B.Paste")
			(net "PVDDCR_SOC_P1")
		)
	)
	(footprint ""
		(layer "B.Cu")
		(at 341.024718 -389.49503 180)
		(property "Reference" "C7011"
			(at -1.921764 -3.055112 0)
			(unlocked yes)
			(layer "B.SilkS")
			(effects
				(font
					(size 0.7874 0.5842)
					(thickness 0.1524)
				)
				(justify left mirror)
			)
		)
		(property "Value" ""
			(at 0 0 0)
			(layer "B.Fab")
			(effects
				(font
					(size 1.27 1.27)
				)
				(justify mirror)
			)
		)
		(duplicate_pad_numbers_are_jumpers no)
		(fp_line
			(start 4.84378 -2.150618)
			(end 4.842256 2.163064)
			(stroke
				(width 0.1524)
				(type default)
			)
			(layer "B.SilkS")
		)
		(fp_line
			(start 4.84378 -2.150618)
			(end 4.53898 -2.150618)
			(stroke
				(width 0.1524)
				(type default)
			)
			(layer "B.SilkS")
		)
		(fp_line
			(start 4.83108 2.150364)
			(end 4.447794 2.149348)
			(stroke
				(width 0.1524)
				(type default)
			)
			(layer "B.SilkS")
		)
		(fp_line
			(start 4.69138 -2.150618)
			(end 4.692396 2.161032)
			(stroke
				(width 0.1524)
				(type default)
			)
			(layer "B.SilkS")
		)
		(fp_line
			(start 4.53898 2.15011)
			(end 4.53898 -2.15011)
			(stroke
				(width 0.1524)
				(type default)
			)
			(layer "B.SilkS")
		)
		(fp_line
			(start 4.53898 -2.15011)
			(end -4.53898 -2.15011)
			(stroke
				(width 0.1524)
				(type default)
			)
			(layer "B.SilkS")
		)
		(fp_line
			(start 4.53898 -2.150618)
			(end 4.539742 2.152142)
			(stroke
				(width 0.1524)
				(type default)
			)
			(layer "B.SilkS")
		)
		(fp_line
			(start -4.53898 2.15011)
			(end 4.53898 2.15011)
			(stroke
				(width 0.1524)
				(type default)
			)
			(layer "B.SilkS")
		)
		(fp_line
			(start -4.53898 -2.15011)
			(end -4.53898 2.15011)
			(stroke
				(width 0.1524)
				(type default)
			)
			(layer "B.SilkS")
		)
		(fp_line
			(start 3.64998 2.15011)
			(end 3.64998 -2.15011)
			(stroke
				(width 0.1)
				(type default)
			)
			(layer "B.Fab")
		)
		(fp_line
			(start 3.64998 -2.15011)
			(end -3.64998 -2.15011)
			(stroke
				(width 0.1)
				(type default)
			)
			(layer "B.Fab")
		)
		(fp_line
			(start -3.64998 2.15011)
			(end 3.64998 2.15011)
			(stroke
				(width 0.1)
				(type default)
			)
			(layer "B.Fab")
		)
		(fp_line
			(start -3.64998 -2.15011)
			(end -3.64998 2.15011)
			(stroke
				(width 0.1)
				(type default)
			)
			(layer "B.Fab")
		)
		(fp_text user "+"
			(at 4.327652 -3.024378 180)
			(unlocked yes)
			(layer "B.SilkS")
			(effects
				(font
					(size 1.905 1.4224)
					(thickness 0.1524)
				)
				(justify left mirror)
			)
		)
		(fp_text user "-"
			(at -3.132074 -2.758948 180)
			(unlocked yes)
			(layer "B.SilkS")
			(effects
				(font
					(size 1.905 1.4224)
					(thickness 0.1524)
				)
				(justify left mirror)
			)
		)
		(fp_text user "+"
			(at 6.214872 -0.337058 180)
			(unlocked yes)
			(layer "B.Fab")
			(effects
				(font
					(size 1.905 1.4224)
					(thickness 0.1524)
				)
				(justify left mirror)
			)
		)
		(fp_text user "-"
			(at -4.313174 -0.094488 180)
			(unlocked yes)
			(layer "B.Fab")
			(effects
				(font
					(size 1.905 1.4224)
					(thickness 0.1524)
				)
				(justify left mirror)
			)
		)
		(pad "1" smd rect
			(at 3.199892 0)
			(size 2.413 2.8194)
			(layers "B.Cu" "B.Mask" "B.Paste")
			(net "P0V9_CPU0_RT1_2A")
		)
		(pad "2" smd rect
			(at -3.199892 0)
			(size 2.413 2.8194)
			(layers "B.Cu" "B.Mask" "B.Paste")
			(net "GND")
		)
	)
	(footprint ""
		(layer "B.Cu")
		(at 433.235608 -354.89769 -90)
		(property "Reference" "PC216_2"
			(at 0 0 90)
			(layer "B.SilkS")
			(hide yes)
			(effects
				(font
					(size 1.27 1.27)
				)
				(justify mirror)
			)
		)
		(property "Value" ""
			(at 0 0 90)
			(layer "B.Fab")
			(effects
				(font
					(size 1.27 1.27)
				)
				(justify mirror)
			)
		)
		(duplicate_pad_numbers_are_jumpers no)
		(fp_line
			(start -1.524 0.762)
			(end 1.524 0.762)
			(stroke
				(width 0.1524)
				(type default)
			)
			(layer "B.SilkS")
		)
		(fp_line
			(start 1.524 0.762)
			(end 1.524 -0.762)
			(stroke
				(width 0.1524)
				(type default)
			)
			(layer "B.SilkS")
		)
		(fp_line
			(start -1.524 -0.762)
			(end -1.524 0.762)
			(stroke
				(width 0.1524)
				(type default)
			)
			(layer "B.SilkS")
		)
		(fp_line
			(start 1.524 -0.762)
			(end -1.524 -0.762)
			(stroke
				(width 0.1524)
				(type default)
			)
			(layer "B.SilkS")
		)
		(fp_line
			(start -1.1049 0.724916)
			(end -1.1049 -0.724916)
			(stroke
				(width 0.1)
				(type default)
			)
			(layer "B.Fab")
		)
		(fp_line
			(start 1.1049 0.724916)
			(end -1.1049 0.724916)
			(stroke
				(width 0.1)
				(type default)
			)
			(layer "B.Fab")
		)
		(fp_line
			(start -1.1049 -0.724916)
			(end 1.1049 -0.724916)
			(stroke
				(width 0.1)
				(type default)
			)
			(layer "B.Fab")
		)
		(fp_line
			(start 1.1049 -0.724916)
			(end 1.1049 0.724916)
			(stroke
				(width 0.1)
				(type default)
			)
			(layer "B.Fab")
		)
		(pad "1" smd rect
			(at 0.889 0 270)
			(size 1.016 1.27)
			(layers "B.Cu" "B.Mask" "B.Paste")
			(net "SW_P12V_AUX_PVDD11_S3_P0_FLT")
		)
		(pad "2" smd rect
			(at -0.889 0 270)
			(size 1.016 1.27)
			(layers "B.Cu" "B.Mask" "B.Paste")
			(net "GND")
		)
	)
	(footprint ""
		(layer "B.Cu")
		(at 225.9203 -402.744432 -90)
		(property "Reference" "PR3981"
			(at 0 0 90)
			(layer "B.SilkS")
			(hide yes)
			(effects
				(font
					(size 1.27 1.27)
				)
				(justify mirror)
			)
		)
		(property "Value" ""
			(at 0 0 90)
			(layer "B.Fab")
			(effects
				(font
					(size 1.27 1.27)
				)
				(justify mirror)
			)
		)
		(duplicate_pad_numbers_are_jumpers no)
		(fp_line
			(start -0.7874 0.4064)
			(end 0.7874 0.4064)
			(stroke
				(width 0.1524)
				(type default)
			)
			(layer "B.SilkS")
		)
		(fp_line
			(start 0.7874 0.4064)
			(end 0.7874 -0.4064)
			(stroke
				(width 0.1524)
				(type default)
			)
			(layer "B.SilkS")
		)
		(fp_line
			(start -0.7874 -0.4064)
			(end -0.7874 0.4064)
			(stroke
				(width 0.1524)
				(type default)
			)
			(layer "B.SilkS")
		)
		(fp_line
			(start 0.7874 -0.4064)
			(end -0.7874 -0.4064)
			(stroke
				(width 0.1524)
				(type default)
			)
			(layer "B.SilkS")
		)
		(fp_line
			(start -0.67945 0.3048)
			(end -0.120396 0.3048)
			(stroke
				(width 0.1)
				(type default)
			)
			(layer "B.Fab")
		)
		(fp_line
			(start -0.120396 0.3048)
			(end -0.120396 0.2794)
			(stroke
				(width 0.1)
				(type default)
			)
			(layer "B.Fab")
		)
		(fp_line
			(start 0.12065 0.3048)
			(end 0.67945 0.3048)
			(stroke
				(width 0.1)
				(type default)
			)
			(layer "B.Fab")
		)
		(fp_line
			(start 0.67945 0.3048)
			(end 0.67945 -0.305054)
			(stroke
				(width 0.1)
				(type default)
			)
			(layer "B.Fab")
		)
		(fp_line
			(start -0.120396 0.2794)
			(end 0.12065 0.2794)
			(stroke
				(width 0.1)
				(type default)
			)
			(layer "B.Fab")
		)
		(fp_line
			(start 0.12065 0.2794)
			(end 0.12065 0.3048)
			(stroke
				(width 0.1)
				(type default)
			)
			(layer "B.Fab")
		)
		(fp_line
			(start -0.12065 -0.2794)
			(end -0.12065 -0.3048)
			(stroke
				(width 0.1)
				(type default)
			)
			(layer "B.Fab")
		)
		(fp_line
			(start 0.12065 -0.2794)
			(end -0.12065 -0.2794)
			(stroke
				(width 0.1)
				(type default)
			)
			(layer "B.Fab")
		)
		(fp_line
			(start -0.67945 -0.3048)
			(end -0.67945 0.3048)
			(stroke
				(width 0.1)
				(type default)
			)
			(layer "B.Fab")
		)
		(fp_line
			(start -0.12065 -0.3048)
			(end -0.67945 -0.3048)
			(stroke
				(width 0.1)
				(type default)
			)
			(layer "B.Fab")
		)
		(fp_line
			(start 0.12065 -0.305054)
			(end 0.12065 -0.2794)
			(stroke
				(width 0.1)
				(type default)
			)
			(layer "B.Fab")
		)
		(fp_line
			(start 0.67945 -0.305054)
			(end 0.12065 -0.305054)
			(stroke
				(width 0.1)
				(type default)
			)
			(layer "B.Fab")
		)
		(pad "1" smd circle
			(at 0.40005 0 90)
			(size 0 0)
			(layers "B.Cu" "B.Mask" "B.Paste")
			(net "HSC_VDD_R_4")
		)
		(pad "2" smd circle
			(at -0.40005 0 90)
			(size 0 0)
			(layers "B.Cu" "B.Mask" "B.Paste")
			(net "HSC_VDD")
		)
	)
	(footprint ""
		(layer "B.Cu")
		(at 59.646058 -177.310542 90)
		(property "Reference" "PR337"
			(at 0 0 90)
			(layer "B.SilkS")
			(hide yes)
			(effects
				(font
					(size 1.27 1.27)
				)
				(justify mirror)
			)
		)
		(property "Value" ""
			(at 0 0 90)
			(layer "B.Fab")
			(effects
				(font
					(size 1.27 1.27)
				)
				(justify mirror)
			)
		)
		(duplicate_pad_numbers_are_jumpers no)
		(fp_line
			(start 0.7874 -0.4064)
			(end -0.7874 -0.4064)
			(stroke
				(width 0.1524)
				(type default)
			)
			(layer "B.SilkS")
		)
		(fp_line
			(start -0.7874 -0.4064)
			(end -0.7874 0.4064)
			(stroke
				(width 0.1524)
				(type default)
			)
			(layer "B.SilkS")
		)
		(fp_line
			(start 0.7874 0.4064)
			(end 0.7874 -0.4064)
			(stroke
				(width 0.1524)
				(type default)
			)
			(layer "B.SilkS")
		)
		(fp_line
			(start -0.7874 0.4064)
			(end 0.7874 0.4064)
			(stroke
				(width 0.1524)
				(type default)
			)
			(layer "B.SilkS")
		)
		(fp_line
			(start 0.67945 -0.305054)
			(end 0.12065 -0.305054)
			(stroke
				(width 0.1)
				(type default)
			)
			(layer "B.Fab")
		)
		(fp_line
			(start 0.12065 -0.305054)
			(end 0.12065 -0.2794)
			(stroke
				(width 0.1)
				(type default)
			)
			(layer "B.Fab")
		)
		(fp_line
			(start -0.12065 -0.3048)
			(end -0.67945 -0.3048)
			(stroke
				(width 0.1)
				(type default)
			)
			(layer "B.Fab")
		)
		(fp_line
			(start -0.67945 -0.3048)
			(end -0.67945 0.3048)
			(stroke
				(width 0.1)
				(type default)
			)
			(layer "B.Fab")
		)
		(fp_line
			(start 0.12065 -0.2794)
			(end -0.12065 -0.2794)
			(stroke
				(width 0.1)
				(type default)
			)
			(layer "B.Fab")
		)
		(fp_line
			(start -0.12065 -0.2794)
			(end -0.12065 -0.3048)
			(stroke
				(width 0.1)
				(type default)
			)
			(layer "B.Fab")
		)
		(fp_line
			(start 0.12065 0.2794)
			(end 0.12065 0.3048)
			(stroke
				(width 0.1)
				(type default)
			)
			(layer "B.Fab")
		)
		(fp_line
			(start -0.120396 0.2794)
			(end 0.12065 0.2794)
			(stroke
				(width 0.1)
				(type default)
			)
			(layer "B.Fab")
		)
		(fp_line
			(start 0.67945 0.3048)
			(end 0.67945 -0.305054)
			(stroke
				(width 0.1)
				(type default)
			)
			(layer "B.Fab")
		)
		(fp_line
			(start 0.12065 0.3048)
			(end 0.67945 0.3048)
			(stroke
				(width 0.1)
				(type default)
			)
			(layer "B.Fab")
		)
		(fp_line
			(start -0.120396 0.3048)
			(end -0.120396 0.2794)
			(stroke
				(width 0.1)
				(type default)
			)
			(layer "B.Fab")
		)
		(fp_line
			(start -0.67945 0.3048)
			(end -0.120396 0.3048)
			(stroke
				(width 0.1)
				(type default)
			)
			(layer "B.Fab")
		)
		(pad "1" smd circle
			(at 0.40005 0 270)
			(size 0 0)
			(layers "B.Cu" "B.Mask" "B.Paste")
			(net "PVDDCR_CPU0_P1")
		)
		(pad "2" smd circle
			(at -0.40005 0 270)
			(size 0 0)
			(layers "B.Cu" "B.Mask" "B.Paste")
			(net "GND")
		)
	)
	(footprint ""
		(layer "B.Cu")
		(at 104.716834 -250.892564 180)
		(property "Reference" "C2335"
			(at 0 0 0)
			(layer "B.SilkS")
			(hide yes)
			(effects
				(font
					(size 1.27 1.27)
				)
				(justify mirror)
			)
		)
		(property "Value" ""
			(at 0 0 0)
			(layer "B.Fab")
			(effects
				(font
					(size 1.27 1.27)
				)
				(justify mirror)
			)
		)
		(duplicate_pad_numbers_are_jumpers no)
		(fp_line
			(start 0.7874 0.4064)
			(end 0.7874 -0.4064)
			(stroke
				(width 0.1524)
				(type default)
			)
			(layer "B.SilkS")
		)
		(fp_line
			(start 0.7874 -0.4064)
			(end -0.7874 -0.4064)
			(stroke
				(width 0.1524)
				(type default)
			)
			(layer "B.SilkS")
		)
		(fp_line
			(start -0.7874 0.4064)
			(end 0.7874 0.4064)
			(stroke
				(width 0.1524)
				(type default)
			)
			(layer "B.SilkS")
		)
		(fp_line
			(start -0.7874 -0.4064)
			(end -0.7874 0.4064)
			(stroke
				(width 0.1524)
				(type default)
			)
			(layer "B.SilkS")
		)
		(fp_line
			(start 0.67945 0.3048)
			(end 0.67945 -0.305054)
			(stroke
				(width 0.1)
				(type default)
			)
			(layer "B.Fab")
		)
		(fp_line
			(start 0.67945 -0.305054)
			(end 0.12065 -0.305054)
			(stroke
				(width 0.1)
				(type default)
			)
			(layer "B.Fab")
		)
		(fp_line
			(start 0.12065 0.3048)
			(end 0.67945 0.3048)
			(stroke
				(width 0.1)
				(type default)
			)
			(layer "B.Fab")
		)
		(fp_line
			(start 0.12065 0.2794)
			(end 0.12065 0.3048)
			(stroke
				(width 0.1)
				(type default)
			)
			(layer "B.Fab")
		)
		(fp_line
			(start 0.12065 -0.2794)
			(end -0.12065 -0.2794)
			(stroke
				(width 0.1)
				(type default)
			)
			(layer "B.Fab")
		)
		(fp_line
			(start 0.12065 -0.305054)
			(end 0.12065 -0.2794)
			(stroke
				(width 0.1)
				(type default)
			)
			(layer "B.Fab")
		)
		(fp_line
			(start -0.120396 0.3048)
			(end -0.120396 0.2794)
			(stroke
				(width 0.1)
				(type default)
			)
			(layer "B.Fab")
		)
		(fp_line
			(start -0.120396 0.2794)
			(end 0.12065 0.2794)
			(stroke
				(width 0.1)
				(type default)
			)
			(layer "B.Fab")
		)
		(fp_line
			(start -0.12065 -0.2794)
			(end -0.12065 -0.3048)
			(stroke
				(width 0.1)
				(type default)
			)
			(layer "B.Fab")
		)
		(fp_line
			(start -0.12065 -0.3048)
			(end -0.67945 -0.3048)
			(stroke
				(width 0.1)
				(type default)
			)
			(layer "B.Fab")
		)
		(fp_line
			(start -0.67945 0.3048)
			(end -0.120396 0.3048)
			(stroke
				(width 0.1)
				(type default)
			)
			(layer "B.Fab")
		)
		(fp_line
			(start -0.67945 -0.3048)
			(end -0.67945 0.3048)
			(stroke
				(width 0.1)
				(type default)
			)
			(layer "B.Fab")
		)
		(pad "1" smd circle
			(at 0.40005 0)
			(size 0 0)
			(layers "B.Cu" "B.Mask" "B.Paste")
			(net "PVDDCR_CPU0_P1")
		)
		(pad "2" smd circle
			(at -0.40005 0)
			(size 0 0)
			(layers "B.Cu" "B.Mask" "B.Paste")
			(net "GND")
		)
	)
	(footprint ""
		(layer "B.Cu")
		(at 101.512878 -139.93241 90)
		(property "Reference" "PC252"
			(at 0 0 90)
			(layer "B.SilkS")
			(hide yes)
			(effects
				(font
					(size 1.27 1.27)
				)
				(justify mirror)
			)
		)
		(property "Value" ""
			(at 0 0 90)
			(layer "B.Fab")
			(effects
				(font
					(size 1.27 1.27)
				)
				(justify mirror)
			)
		)
		(duplicate_pad_numbers_are_jumpers no)
		(fp_line
			(start 0.7874 -0.4064)
			(end -0.7874 -0.4064)
			(stroke
				(width 0.1524)
				(type default)
			)
			(layer "B.SilkS")
		)
		(fp_line
			(start -0.7874 -0.4064)
			(end -0.7874 0.4064)
			(stroke
				(width 0.1524)
				(type default)
			)
			(layer "B.SilkS")
		)
		(fp_line
			(start 0.7874 0.4064)
			(end 0.7874 -0.4064)
			(stroke
				(width 0.1524)
				(type default)
			)
			(layer "B.SilkS")
		)
		(fp_line
			(start -0.7874 0.4064)
			(end 0.7874 0.4064)
			(stroke
				(width 0.1524)
				(type default)
			)
			(layer "B.SilkS")
		)
		(fp_line
			(start 0.67945 -0.305054)
			(end 0.12065 -0.305054)
			(stroke
				(width 0.1)
				(type default)
			)
			(layer "B.Fab")
		)
		(fp_line
			(start 0.12065 -0.305054)
			(end 0.12065 -0.2794)
			(stroke
				(width 0.1)
				(type default)
			)
			(layer "B.Fab")
		)
		(fp_line
			(start -0.12065 -0.3048)
			(end -0.67945 -0.3048)
			(stroke
				(width 0.1)
				(type default)
			)
			(layer "B.Fab")
		)
		(fp_line
			(start -0.67945 -0.3048)
			(end -0.67945 0.3048)
			(stroke
				(width 0.1)
				(type default)
			)
			(layer "B.Fab")
		)
		(fp_line
			(start 0.12065 -0.2794)
			(end -0.12065 -0.2794)
			(stroke
				(width 0.1)
				(type default)
			)
			(layer "B.Fab")
		)
		(fp_line
			(start -0.12065 -0.2794)
			(end -0.12065 -0.3048)
			(stroke
				(width 0.1)
				(type default)
			)
			(layer "B.Fab")
		)
		(fp_line
			(start 0.12065 0.2794)
			(end 0.12065 0.3048)
			(stroke
				(width 0.1)
				(type default)
			)
			(layer "B.Fab")
		)
		(fp_line
			(start -0.120396 0.2794)
			(end 0.12065 0.2794)
			(stroke
				(width 0.1)
				(type default)
			)
			(layer "B.Fab")
		)
		(fp_line
			(start 0.67945 0.3048)
			(end 0.67945 -0.305054)
			(stroke
				(width 0.1)
				(type default)
			)
			(layer "B.Fab")
		)
		(fp_line
			(start 0.12065 0.3048)
			(end 0.67945 0.3048)
			(stroke
				(width 0.1)
				(type default)
			)
			(layer "B.Fab")
		)
		(fp_line
			(start -0.120396 0.3048)
			(end -0.120396 0.2794)
			(stroke
				(width 0.1)
				(type default)
			)
			(layer "B.Fab")
		)
		(fp_line
			(start -0.67945 0.3048)
			(end -0.120396 0.3048)
			(stroke
				(width 0.1)
				(type default)
			)
			(layer "B.Fab")
		)
		(pad "1" smd circle
			(at 0.40005 0 270)
			(size 0 0)
			(layers "B.Cu" "B.Mask" "B.Paste")
			(net "PVDDCR_CPU0_P1_VCC")
		)
		(pad "2" smd circle
			(at -0.40005 0 270)
			(size 0 0)
			(layers "B.Cu" "B.Mask" "B.Paste")
			(net "GND")
		)
	)
	(footprint ""
		(layer "B.Cu")
		(at 149.884638 -13.762228 90)
		(property "Reference" "R2418"
			(at 0 0 90)
			(layer "B.SilkS")
			(hide yes)
			(effects
				(font
					(size 1.27 1.27)
				)
				(justify mirror)
			)
		)
		(property "Value" ""
			(at 0 0 90)
			(layer "B.Fab")
			(effects
				(font
					(size 1.27 1.27)
				)
				(justify mirror)
			)
		)
		(duplicate_pad_numbers_are_jumpers no)
		(fp_line
			(start 0.7874 -0.4064)
			(end -0.7874 -0.4064)
			(stroke
				(width 0.1524)
				(type default)
			)
			(layer "B.SilkS")
		)
		(fp_line
			(start -0.7874 -0.4064)
			(end -0.7874 0.4064)
			(stroke
				(width 0.1524)
				(type default)
			)
			(layer "B.SilkS")
		)
		(fp_line
			(start 0.7874 0.4064)
			(end 0.7874 -0.4064)
			(stroke
				(width 0.1524)
				(type default)
			)
			(layer "B.SilkS")
		)
		(fp_line
			(start -0.7874 0.4064)
			(end 0.7874 0.4064)
			(stroke
				(width 0.1524)
				(type default)
			)
			(layer "B.SilkS")
		)
		(fp_line
			(start 0.67945 -0.305054)
			(end 0.12065 -0.305054)
			(stroke
				(width 0.1)
				(type default)
			)
			(layer "B.Fab")
		)
		(fp_line
			(start 0.12065 -0.305054)
			(end 0.12065 -0.2794)
			(stroke
				(width 0.1)
				(type default)
			)
			(layer "B.Fab")
		)
		(fp_line
			(start -0.12065 -0.3048)
			(end -0.67945 -0.3048)
			(stroke
				(width 0.1)
				(type default)
			)
			(layer "B.Fab")
		)
		(fp_line
			(start -0.67945 -0.3048)
			(end -0.67945 0.3048)
			(stroke
				(width 0.1)
				(type default)
			)
			(layer "B.Fab")
		)
		(fp_line
			(start 0.12065 -0.2794)
			(end -0.12065 -0.2794)
			(stroke
				(width 0.1)
				(type default)
			)
			(layer "B.Fab")
		)
		(fp_line
			(start -0.12065 -0.2794)
			(end -0.12065 -0.3048)
			(stroke
				(width 0.1)
				(type default)
			)
			(layer "B.Fab")
		)
		(fp_line
			(start 0.12065 0.2794)
			(end 0.12065 0.3048)
			(stroke
				(width 0.1)
				(type default)
			)
			(layer "B.Fab")
		)
		(fp_line
			(start -0.120396 0.2794)
			(end 0.12065 0.2794)
			(stroke
				(width 0.1)
				(type default)
			)
			(layer "B.Fab")
		)
		(fp_line
			(start 0.67945 0.3048)
			(end 0.67945 -0.305054)
			(stroke
				(width 0.1)
				(type default)
			)
			(layer "B.Fab")
		)
		(fp_line
			(start 0.12065 0.3048)
			(end 0.67945 0.3048)
			(stroke
				(width 0.1)
				(type default)
			)
			(layer "B.Fab")
		)
		(fp_line
			(start -0.120396 0.3048)
			(end -0.120396 0.2794)
			(stroke
				(width 0.1)
				(type default)
			)
			(layer "B.Fab")
		)
		(fp_line
			(start -0.67945 0.3048)
			(end -0.120396 0.3048)
			(stroke
				(width 0.1)
				(type default)
			)
			(layer "B.Fab")
		)
		(pad "1" smd circle
			(at 0.40005 0 270)
			(size 0 0)
			(layers "B.Cu" "B.Mask" "B.Paste")
			(net "SMB_HOST_CLK_3V3AUX_SDA")
		)
		(pad "2" smd circle
			(at -0.40005 0 270)
			(size 0 0)
			(layers "B.Cu" "B.Mask" "B.Paste")
			(net "SMB_HOST_CLK_3V3AUX_SDA_R0")
		)
	)
	(footprint ""
		(layer "B.Cu")
		(at 280.041096 -349.381572 -90)
		(property "Reference" "PR111"
			(at 0 0 90)
			(layer "B.SilkS")
			(hide yes)
			(effects
				(font
					(size 1.27 1.27)
				)
				(justify mirror)
			)
		)
		(property "Value" ""
			(at 0 0 90)
			(layer "B.Fab")
			(effects
				(font
					(size 1.27 1.27)
				)
				(justify mirror)
			)
		)
		(duplicate_pad_numbers_are_jumpers no)
		(fp_line
			(start -0.7874 0.4064)
			(end 0.7874 0.4064)
			(stroke
				(width 0.1524)
				(type default)
			)
			(layer "B.SilkS")
		)
		(fp_line
			(start 0.7874 0.4064)
			(end 0.7874 -0.4064)
			(stroke
				(width 0.1524)
				(type default)
			)
			(layer "B.SilkS")
		)
		(fp_line
			(start -0.7874 -0.4064)
			(end -0.7874 0.4064)
			(stroke
				(width 0.1524)
				(type default)
			)
			(layer "B.SilkS")
		)
		(fp_line
			(start 0.7874 -0.4064)
			(end -0.7874 -0.4064)
			(stroke
				(width 0.1524)
				(type default)
			)
			(layer "B.SilkS")
		)
		(fp_line
			(start -0.67945 0.3048)
			(end -0.120396 0.3048)
			(stroke
				(width 0.1)
				(type default)
			)
			(layer "B.Fab")
		)
		(fp_line
			(start -0.120396 0.3048)
			(end -0.120396 0.2794)
			(stroke
				(width 0.1)
				(type default)
			)
			(layer "B.Fab")
		)
		(fp_line
			(start 0.12065 0.3048)
			(end 0.67945 0.3048)
			(stroke
				(width 0.1)
				(type default)
			)
			(layer "B.Fab")
		)
		(fp_line
			(start 0.67945 0.3048)
			(end 0.67945 -0.305054)
			(stroke
				(width 0.1)
				(type default)
			)
			(layer "B.Fab")
		)
		(fp_line
			(start -0.120396 0.2794)
			(end 0.12065 0.2794)
			(stroke
				(width 0.1)
				(type default)
			)
			(layer "B.Fab")
		)
		(fp_line
			(start 0.12065 0.2794)
			(end 0.12065 0.3048)
			(stroke
				(width 0.1)
				(type default)
			)
			(layer "B.Fab")
		)
		(fp_line
			(start -0.12065 -0.2794)
			(end -0.12065 -0.3048)
			(stroke
				(width 0.1)
				(type default)
			)
			(layer "B.Fab")
		)
		(fp_line
			(start 0.12065 -0.2794)
			(end -0.12065 -0.2794)
			(stroke
				(width 0.1)
				(type default)
			)
			(layer "B.Fab")
		)
		(fp_line
			(start -0.67945 -0.3048)
			(end -0.67945 0.3048)
			(stroke
				(width 0.1)
				(type default)
			)
			(layer "B.Fab")
		)
		(fp_line
			(start -0.12065 -0.3048)
			(end -0.67945 -0.3048)
			(stroke
				(width 0.1)
				(type default)
			)
			(layer "B.Fab")
		)
		(fp_line
			(start 0.12065 -0.305054)
			(end 0.12065 -0.2794)
			(stroke
				(width 0.1)
				(type default)
			)
			(layer "B.Fab")
		)
		(fp_line
			(start 0.67945 -0.305054)
			(end 0.12065 -0.305054)
			(stroke
				(width 0.1)
				(type default)
			)
			(layer "B.Fab")
		)
		(pad "1" smd circle
			(at 0.40005 0 90)
			(size 0 0)
			(layers "B.Cu" "B.Mask" "B.Paste")
			(net "PVDDIO_P0_VOS3")
		)
		(pad "2" smd circle
			(at -0.40005 0 90)
			(size 0 0)
			(layers "B.Cu" "B.Mask" "B.Paste")
			(net "PVDDIO_P0")
		)
	)
	(footprint ""
		(layer "B.Cu")
		(at 352.846132 -396.393162 -90)
		(property "Reference" "C631"
			(at 0 0 90)
			(layer "B.SilkS")
			(hide yes)
			(effects
				(font
					(size 1.27 1.27)
				)
				(justify mirror)
			)
		)
		(property "Value" ""
			(at 0 0 90)
			(layer "B.Fab")
			(effects
				(font
					(size 1.27 1.27)
				)
				(justify mirror)
			)
		)
		(duplicate_pad_numbers_are_jumpers no)
		(fp_line
			(start -0.299974 0.150114)
			(end 0.299974 0.150114)
			(stroke
				(width 0.1)
				(type default)
			)
			(layer "B.Fab")
		)
		(fp_line
			(start 0.299974 0.150114)
			(end 0.299974 -0.150114)
			(stroke
				(width 0.1)
				(type default)
			)
			(layer "B.Fab")
		)
		(fp_line
			(start -0.299974 -0.150114)
			(end -0.299974 0.150114)
			(stroke
				(width 0.1)
				(type default)
			)
			(layer "B.Fab")
		)
		(fp_line
			(start 0.299974 -0.150114)
			(end -0.299974 -0.150114)
			(stroke
				(width 0.1)
				(type default)
			)
			(layer "B.Fab")
		)
		(pad "1" smd rect
			(at 0.2667 0 90)
			(size 0.3048 0.381)
			(layers "B.Cu" "B.Mask" "B.Paste")
			(net "P0V9_CPU0_RT1_2A")
		)
		(pad "2" smd rect
			(at -0.2667 0 90)
			(size 0.3048 0.381)
			(layers "B.Cu" "B.Mask" "B.Paste")
			(net "GND")
		)
	)
	(footprint ""
		(layer "B.Cu")
		(at 17.608042 -192.66027 180)
		(property "Reference" "C518"
			(at 0 0 0)
			(layer "B.SilkS")
			(hide yes)
			(effects
				(font
					(size 1.27 1.27)
				)
				(justify mirror)
			)
		)
		(property "Value" ""
			(at 0 0 0)
			(layer "B.Fab")
			(effects
				(font
					(size 1.27 1.27)
				)
				(justify mirror)
			)
		)
		(duplicate_pad_numbers_are_jumpers no)
		(fp_line
			(start 1.524 0.762)
			(end 1.524 -0.762)
			(stroke
				(width 0.1524)
				(type default)
			)
			(layer "B.SilkS")
		)
		(fp_line
			(start 1.524 -0.762)
			(end -1.524 -0.762)
			(stroke
				(width 0.1524)
				(type default)
			)
			(layer "B.SilkS")
		)
		(fp_line
			(start -1.524 0.762)
			(end 1.524 0.762)
			(stroke
				(width 0.1524)
				(type default)
			)
			(layer "B.SilkS")
		)
		(fp_line
			(start -1.524 -0.762)
			(end -1.524 0.762)
			(stroke
				(width 0.1524)
				(type default)
			)
			(layer "B.SilkS")
		)
		(fp_line
			(start 1.1049 0.724916)
			(end -1.1049 0.724916)
			(stroke
				(width 0.1)
				(type default)
			)
			(layer "B.Fab")
		)
		(fp_line
			(start 1.1049 -0.724916)
			(end 1.1049 0.724916)
			(stroke
				(width 0.1)
				(type default)
			)
			(layer "B.Fab")
		)
		(fp_line
			(start -1.1049 0.724916)
			(end -1.1049 -0.724916)
			(stroke
				(width 0.1)
				(type default)
			)
			(layer "B.Fab")
		)
		(fp_line
			(start -1.1049 -0.724916)
			(end 1.1049 -0.724916)
			(stroke
				(width 0.1)
				(type default)
			)
			(layer "B.Fab")
		)
		(pad "1" smd rect
			(at 0.889 0 180)
			(size 1.016 1.27)
			(layers "B.Cu" "B.Mask" "B.Paste")
			(net "P12V_MEM_CPU1")
		)
		(pad "2" smd rect
			(at -0.889 0 180)
			(size 1.016 1.27)
			(layers "B.Cu" "B.Mask" "B.Paste")
			(net "GND")
		)
	)
	(footprint ""
		(layer "B.Cu")
		(at 62.996318 -350.660716 -90)
		(property "Reference" "PC415_4"
			(at 0 0 90)
			(layer "B.SilkS")
			(hide yes)
			(effects
				(font
					(size 1.27 1.27)
				)
				(justify mirror)
			)
		)
		(property "Value" ""
			(at 0 0 90)
			(layer "B.Fab")
			(effects
				(font
					(size 1.27 1.27)
				)
				(justify mirror)
			)
		)
		(duplicate_pad_numbers_are_jumpers no)
		(fp_line
			(start -1.524 0.762)
			(end 1.524 0.762)
			(stroke
				(width 0.1524)
				(type default)
			)
			(layer "B.SilkS")
		)
		(fp_line
			(start 1.524 0.762)
			(end 1.524 -0.762)
			(stroke
				(width 0.1524)
				(type default)
			)
			(layer "B.SilkS")
		)
		(fp_line
			(start -1.524 -0.762)
			(end -1.524 0.762)
			(stroke
				(width 0.1524)
				(type default)
			)
			(layer "B.SilkS")
		)
		(fp_line
			(start 1.524 -0.762)
			(end -1.524 -0.762)
			(stroke
				(width 0.1524)
				(type default)
			)
			(layer "B.SilkS")
		)
		(fp_line
			(start -1.1049 0.724916)
			(end -1.1049 -0.724916)
			(stroke
				(width 0.1)
				(type default)
			)
			(layer "B.Fab")
		)
		(fp_line
			(start 1.1049 0.724916)
			(end -1.1049 0.724916)
			(stroke
				(width 0.1)
				(type default)
			)
			(layer "B.Fab")
		)
		(fp_line
			(start -1.1049 -0.724916)
			(end 1.1049 -0.724916)
			(stroke
				(width 0.1)
				(type default)
			)
			(layer "B.Fab")
		)
		(fp_line
			(start 1.1049 -0.724916)
			(end 1.1049 0.724916)
			(stroke
				(width 0.1)
				(type default)
			)
			(layer "B.Fab")
		)
		(pad "1" smd rect
			(at 0.889 0 270)
			(size 1.016 1.27)
			(layers "B.Cu" "B.Mask" "B.Paste")
			(net "SW_P12V_AUX_PVDDCR_CPU1_P1_FLT")
		)
		(pad "2" smd rect
			(at -0.889 0 270)
			(size 1.016 1.27)
			(layers "B.Cu" "B.Mask" "B.Paste")
			(net "GND")
		)
	)
	(footprint ""
		(layer "B.Cu")
		(at 117.351302 -165.040056 -90)
		(property "Reference" "PC8012"
			(at 0 0 90)
			(layer "B.SilkS")
			(hide yes)
			(effects
				(font
					(size 1.27 1.27)
				)
				(justify mirror)
			)
		)
		(property "Value" ""
			(at 0 0 90)
			(layer "B.Fab")
			(effects
				(font
					(size 1.27 1.27)
				)
				(justify mirror)
			)
		)
		(duplicate_pad_numbers_are_jumpers no)
		(fp_line
			(start -1.524 0.762)
			(end 1.524 0.762)
			(stroke
				(width 0.1524)
				(type default)
			)
			(layer "B.SilkS")
		)
		(fp_line
			(start 1.524 0.762)
			(end 1.524 -0.762)
			(stroke
				(width 0.1524)
				(type default)
			)
			(layer "B.SilkS")
		)
		(fp_line
			(start -1.524 -0.762)
			(end -1.524 0.762)
			(stroke
				(width 0.1524)
				(type default)
			)
			(layer "B.SilkS")
		)
		(fp_line
			(start 1.524 -0.762)
			(end -1.524 -0.762)
			(stroke
				(width 0.1524)
				(type default)
			)
			(layer "B.SilkS")
		)
		(fp_line
			(start -1.1049 0.724916)
			(end -1.1049 -0.724916)
			(stroke
				(width 0.1)
				(type default)
			)
			(layer "B.Fab")
		)
		(fp_line
			(start 1.1049 0.724916)
			(end -1.1049 0.724916)
			(stroke
				(width 0.1)
				(type default)
			)
			(layer "B.Fab")
		)
		(fp_line
			(start -1.1049 -0.724916)
			(end 1.1049 -0.724916)
			(stroke
				(width 0.1)
				(type default)
			)
			(layer "B.Fab")
		)
		(fp_line
			(start 1.1049 -0.724916)
			(end 1.1049 0.724916)
			(stroke
				(width 0.1)
				(type default)
			)
			(layer "B.Fab")
		)
		(pad "1" smd rect
			(at 0.889 0 270)
			(size 1.016 1.27)
			(layers "B.Cu" "B.Mask" "B.Paste")
			(net "SW_P12V_AUX_PVDDCR_SOC_P1_FLT")
		)
		(pad "2" smd rect
			(at -0.889 0 270)
			(size 1.016 1.27)
			(layers "B.Cu" "B.Mask" "B.Paste")
			(net "GND")
		)
	)
	(footprint ""
		(layer "B.Cu")
		(at 353.900232 -256.505202 180)
		(property "Reference" "C2163"
			(at 0 0 0)
			(layer "B.SilkS")
			(hide yes)
			(effects
				(font
					(size 1.27 1.27)
				)
				(justify mirror)
			)
		)
		(property "Value" ""
			(at 0 0 0)
			(layer "B.Fab")
			(effects
				(font
					(size 1.27 1.27)
				)
				(justify mirror)
			)
		)
		(duplicate_pad_numbers_are_jumpers no)
		(fp_line
			(start 0.7874 0.4064)
			(end 0.7874 -0.4064)
			(stroke
				(width 0.1524)
				(type default)
			)
			(layer "B.SilkS")
		)
		(fp_line
			(start 0.7874 -0.4064)
			(end -0.7874 -0.4064)
			(stroke
				(width 0.1524)
				(type default)
			)
			(layer "B.SilkS")
		)
		(fp_line
			(start -0.7874 0.4064)
			(end 0.7874 0.4064)
			(stroke
				(width 0.1524)
				(type default)
			)
			(layer "B.SilkS")
		)
		(fp_line
			(start -0.7874 -0.4064)
			(end -0.7874 0.4064)
			(stroke
				(width 0.1524)
				(type default)
			)
			(layer "B.SilkS")
		)
		(fp_line
			(start 0.67945 0.3048)
			(end 0.67945 -0.305054)
			(stroke
				(width 0.1)
				(type default)
			)
			(layer "B.Fab")
		)
		(fp_line
			(start 0.67945 -0.305054)
			(end 0.12065 -0.305054)
			(stroke
				(width 0.1)
				(type default)
			)
			(layer "B.Fab")
		)
		(fp_line
			(start 0.12065 0.3048)
			(end 0.67945 0.3048)
			(stroke
				(width 0.1)
				(type default)
			)
			(layer "B.Fab")
		)
		(fp_line
			(start 0.12065 0.2794)
			(end 0.12065 0.3048)
			(stroke
				(width 0.1)
				(type default)
			)
			(layer "B.Fab")
		)
		(fp_line
			(start 0.12065 -0.2794)
			(end -0.12065 -0.2794)
			(stroke
				(width 0.1)
				(type default)
			)
			(layer "B.Fab")
		)
		(fp_line
			(start 0.12065 -0.305054)
			(end 0.12065 -0.2794)
			(stroke
				(width 0.1)
				(type default)
			)
			(layer "B.Fab")
		)
		(fp_line
			(start -0.120396 0.3048)
			(end -0.120396 0.2794)
			(stroke
				(width 0.1)
				(type default)
			)
			(layer "B.Fab")
		)
		(fp_line
			(start -0.120396 0.2794)
			(end 0.12065 0.2794)
			(stroke
				(width 0.1)
				(type default)
			)
			(layer "B.Fab")
		)
		(fp_line
			(start -0.12065 -0.2794)
			(end -0.12065 -0.3048)
			(stroke
				(width 0.1)
				(type default)
			)
			(layer "B.Fab")
		)
		(fp_line
			(start -0.12065 -0.3048)
			(end -0.67945 -0.3048)
			(stroke
				(width 0.1)
				(type default)
			)
			(layer "B.Fab")
		)
		(fp_line
			(start -0.67945 0.3048)
			(end -0.120396 0.3048)
			(stroke
				(width 0.1)
				(type default)
			)
			(layer "B.Fab")
		)
		(fp_line
			(start -0.67945 -0.3048)
			(end -0.67945 0.3048)
			(stroke
				(width 0.1)
				(type default)
			)
			(layer "B.Fab")
		)
		(pad "1" smd circle
			(at 0.40005 0)
			(size 0 0)
			(layers "B.Cu" "B.Mask" "B.Paste")
			(net "PVDD18_S5_P0")
		)
		(pad "2" smd circle
			(at -0.40005 0)
			(size 0 0)
			(layers "B.Cu" "B.Mask" "B.Paste")
			(net "GND")
		)
	)
	(footprint ""
		(layer "B.Cu")
		(at 351.612454 -262.70331 180)
		(property "Reference" "C2533"
			(at 0 0 0)
			(layer "B.SilkS")
			(hide yes)
			(effects
				(font
					(size 1.27 1.27)
				)
				(justify mirror)
			)
		)
		(property "Value" ""
			(at 0 0 0)
			(layer "B.Fab")
			(effects
				(font
					(size 1.27 1.27)
				)
				(justify mirror)
			)
		)
		(duplicate_pad_numbers_are_jumpers no)
		(fp_line
			(start 0.7874 0.4064)
			(end 0.7874 -0.4064)
			(stroke
				(width 0.1524)
				(type default)
			)
			(layer "B.SilkS")
		)
		(fp_line
			(start 0.7874 -0.4064)
			(end -0.7874 -0.4064)
			(stroke
				(width 0.1524)
				(type default)
			)
			(layer "B.SilkS")
		)
		(fp_line
			(start -0.7874 0.4064)
			(end 0.7874 0.4064)
			(stroke
				(width 0.1524)
				(type default)
			)
			(layer "B.SilkS")
		)
		(fp_line
			(start -0.7874 -0.4064)
			(end -0.7874 0.4064)
			(stroke
				(width 0.1524)
				(type default)
			)
			(layer "B.SilkS")
		)
		(fp_line
			(start 0.67945 0.3048)
			(end 0.67945 -0.305054)
			(stroke
				(width 0.1)
				(type default)
			)
			(layer "B.Fab")
		)
		(fp_line
			(start 0.67945 -0.305054)
			(end 0.12065 -0.305054)
			(stroke
				(width 0.1)
				(type default)
			)
			(layer "B.Fab")
		)
		(fp_line
			(start 0.12065 0.3048)
			(end 0.67945 0.3048)
			(stroke
				(width 0.1)
				(type default)
			)
			(layer "B.Fab")
		)
		(fp_line
			(start 0.12065 0.2794)
			(end 0.12065 0.3048)
			(stroke
				(width 0.1)
				(type default)
			)
			(layer "B.Fab")
		)
		(fp_line
			(start 0.12065 -0.2794)
			(end -0.12065 -0.2794)
			(stroke
				(width 0.1)
				(type default)
			)
			(layer "B.Fab")
		)
		(fp_line
			(start 0.12065 -0.305054)
			(end 0.12065 -0.2794)
			(stroke
				(width 0.1)
				(type default)
			)
			(layer "B.Fab")
		)
		(fp_line
			(start -0.120396 0.3048)
			(end -0.120396 0.2794)
			(stroke
				(width 0.1)
				(type default)
			)
			(layer "B.Fab")
		)
		(fp_line
			(start -0.120396 0.2794)
			(end 0.12065 0.2794)
			(stroke
				(width 0.1)
				(type default)
			)
			(layer "B.Fab")
		)
		(fp_line
			(start -0.12065 -0.2794)
			(end -0.12065 -0.3048)
			(stroke
				(width 0.1)
				(type default)
			)
			(layer "B.Fab")
		)
		(fp_line
			(start -0.12065 -0.3048)
			(end -0.67945 -0.3048)
			(stroke
				(width 0.1)
				(type default)
			)
			(layer "B.Fab")
		)
		(fp_line
			(start -0.67945 0.3048)
			(end -0.120396 0.3048)
			(stroke
				(width 0.1)
				(type default)
			)
			(layer "B.Fab")
		)
		(fp_line
			(start -0.67945 -0.3048)
			(end -0.67945 0.3048)
			(stroke
				(width 0.1)
				(type default)
			)
			(layer "B.Fab")
		)
		(pad "1" smd circle
			(at 0.40005 0)
			(size 0 0)
			(layers "B.Cu" "B.Mask" "B.Paste")
			(net "PVDDCR_SOC_P0")
		)
		(pad "2" smd circle
			(at -0.40005 0)
			(size 0 0)
			(layers "B.Cu" "B.Mask" "B.Paste")
			(net "GND")
		)
	)
	(footprint ""
		(layer "B.Cu")
		(at 414.096454 -191.20231)
		(property "Reference" "R95"
			(at 0 0 0)
			(layer "B.SilkS")
			(hide yes)
			(effects
				(font
					(size 1.27 1.27)
				)
				(justify mirror)
			)
		)
		(property "Value" ""
			(at 0 0 0)
			(layer "B.Fab")
			(effects
				(font
					(size 1.27 1.27)
				)
				(justify mirror)
			)
		)
		(duplicate_pad_numbers_are_jumpers no)
		(fp_line
			(start -0.7874 -0.4064)
			(end -0.7874 0.4064)
			(stroke
				(width 0.1524)
				(type default)
			)
			(layer "B.SilkS")
		)
		(fp_line
			(start -0.7874 0.4064)
			(end 0.7874 0.4064)
			(stroke
				(width 0.1524)
				(type default)
			)
			(layer "B.SilkS")
		)
		(fp_line
			(start 0.7874 -0.4064)
			(end -0.7874 -0.4064)
			(stroke
				(width 0.1524)
				(type default)
			)
			(layer "B.SilkS")
		)
		(fp_line
			(start 0.7874 0.4064)
			(end 0.7874 -0.4064)
			(stroke
				(width 0.1524)
				(type default)
			)
			(layer "B.SilkS")
		)
		(fp_line
			(start -0.67945 -0.3048)
			(end -0.67945 0.3048)
			(stroke
				(width 0.1)
				(type default)
			)
			(layer "B.Fab")
		)
		(fp_line
			(start -0.67945 0.3048)
			(end -0.120396 0.3048)
			(stroke
				(width 0.1)
				(type default)
			)
			(layer "B.Fab")
		)
		(fp_line
			(start -0.12065 -0.3048)
			(end -0.67945 -0.3048)
			(stroke
				(width 0.1)
				(type default)
			)
			(layer "B.Fab")
		)
		(fp_line
			(start -0.12065 -0.2794)
			(end -0.12065 -0.3048)
			(stroke
				(width 0.1)
				(type default)
			)
			(layer "B.Fab")
		)
		(fp_line
			(start -0.120396 0.2794)
			(end 0.12065 0.2794)
			(stroke
				(width 0.1)
				(type default)
			)
			(layer "B.Fab")
		)
		(fp_line
			(start -0.120396 0.3048)
			(end -0.120396 0.2794)
			(stroke
				(width 0.1)
				(type default)
			)
			(layer "B.Fab")
		)
		(fp_line
			(start 0.12065 -0.305054)
			(end 0.12065 -0.2794)
			(stroke
				(width 0.1)
				(type default)
			)
			(layer "B.Fab")
		)
		(fp_line
			(start 0.12065 -0.2794)
			(end -0.12065 -0.2794)
			(stroke
				(width 0.1)
				(type default)
			)
			(layer "B.Fab")
		)
		(fp_line
			(start 0.12065 0.2794)
			(end 0.12065 0.3048)
			(stroke
				(width 0.1)
				(type default)
			)
			(layer "B.Fab")
		)
		(fp_line
			(start 0.12065 0.3048)
			(end 0.67945 0.3048)
			(stroke
				(width 0.1)
				(type default)
			)
			(layer "B.Fab")
		)
		(fp_line
			(start 0.67945 -0.305054)
			(end 0.12065 -0.305054)
			(stroke
				(width 0.1)
				(type default)
			)
			(layer "B.Fab")
		)
		(fp_line
			(start 0.67945 0.3048)
			(end 0.67945 -0.305054)
			(stroke
				(width 0.1)
				(type default)
			)
			(layer "B.Fab")
		)
		(pad "1" smd circle
			(at 0.40005 0 180)
			(size 0 0)
			(layers "B.Cu" "B.Mask" "B.Paste")
			(net "P3V3")
		)
		(pad "2" smd circle
			(at -0.40005 0 180)
			(size 0 0)
			(layers "B.Cu" "B.Mask" "B.Paste")
			(net "PWRGD_CHGL_CPU0")
		)
	)
	(footprint ""
		(layer "B.Cu")
		(at 123.611386 -255.845564)
		(property "Reference" "C3918"
			(at 0 0 0)
			(layer "B.SilkS")
			(hide yes)
			(effects
				(font
					(size 1.27 1.27)
				)
				(justify mirror)
			)
		)
		(property "Value" ""
			(at 0 0 0)
			(layer "B.Fab")
			(effects
				(font
					(size 1.27 1.27)
				)
				(justify mirror)
			)
		)
		(duplicate_pad_numbers_are_jumpers no)
		(fp_line
			(start -0.7874 -0.4064)
			(end -0.7874 0.4064)
			(stroke
				(width 0.1524)
				(type default)
			)
			(layer "B.SilkS")
		)
		(fp_line
			(start -0.7874 0.4064)
			(end 0.7874 0.4064)
			(stroke
				(width 0.1524)
				(type default)
			)
			(layer "B.SilkS")
		)
		(fp_line
			(start 0.7874 -0.4064)
			(end -0.7874 -0.4064)
			(stroke
				(width 0.1524)
				(type default)
			)
			(layer "B.SilkS")
		)
		(fp_line
			(start 0.7874 0.4064)
			(end 0.7874 -0.4064)
			(stroke
				(width 0.1524)
				(type default)
			)
			(layer "B.SilkS")
		)
		(fp_line
			(start -0.67945 -0.3048)
			(end -0.67945 0.3048)
			(stroke
				(width 0.1)
				(type default)
			)
			(layer "B.Fab")
		)
		(fp_line
			(start -0.67945 0.3048)
			(end -0.120396 0.3048)
			(stroke
				(width 0.1)
				(type default)
			)
			(layer "B.Fab")
		)
		(fp_line
			(start -0.12065 -0.3048)
			(end -0.67945 -0.3048)
			(stroke
				(width 0.1)
				(type default)
			)
			(layer "B.Fab")
		)
		(fp_line
			(start -0.12065 -0.2794)
			(end -0.12065 -0.3048)
			(stroke
				(width 0.1)
				(type default)
			)
			(layer "B.Fab")
		)
		(fp_line
			(start -0.120396 0.2794)
			(end 0.12065 0.2794)
			(stroke
				(width 0.1)
				(type default)
			)
			(layer "B.Fab")
		)
		(fp_line
			(start -0.120396 0.3048)
			(end -0.120396 0.2794)
			(stroke
				(width 0.1)
				(type default)
			)
			(layer "B.Fab")
		)
		(fp_line
			(start 0.12065 -0.305054)
			(end 0.12065 -0.2794)
			(stroke
				(width 0.1)
				(type default)
			)
			(layer "B.Fab")
		)
		(fp_line
			(start 0.12065 -0.2794)
			(end -0.12065 -0.2794)
			(stroke
				(width 0.1)
				(type default)
			)
			(layer "B.Fab")
		)
		(fp_line
			(start 0.12065 0.2794)
			(end 0.12065 0.3048)
			(stroke
				(width 0.1)
				(type default)
			)
			(layer "B.Fab")
		)
		(fp_line
			(start 0.12065 0.3048)
			(end 0.67945 0.3048)
			(stroke
				(width 0.1)
				(type default)
			)
			(layer "B.Fab")
		)
		(fp_line
			(start 0.67945 -0.305054)
			(end 0.12065 -0.305054)
			(stroke
				(width 0.1)
				(type default)
			)
			(layer "B.Fab")
		)
		(fp_line
			(start 0.67945 0.3048)
			(end 0.67945 -0.305054)
			(stroke
				(width 0.1)
				(type default)
			)
			(layer "B.Fab")
		)
		(pad "1" smd circle
			(at 0.40005 0 180)
			(size 0 0)
			(layers "B.Cu" "B.Mask" "B.Paste")
			(net "PVDDCR_SOC_P1")
		)
		(pad "2" smd circle
			(at -0.40005 0 180)
			(size 0 0)
			(layers "B.Cu" "B.Mask" "B.Paste")
			(net "GND")
		)
	)
	(footprint ""
		(layer "B.Cu")
		(at 22.479 -357.632 180)
		(property "Reference" "PR218"
			(at 0 0 0)
			(layer "B.SilkS")
			(hide yes)
			(effects
				(font
					(size 1.27 1.27)
				)
				(justify mirror)
			)
		)
		(property "Value" ""
			(at 0 0 0)
			(layer "B.Fab")
			(effects
				(font
					(size 1.27 1.27)
				)
				(justify mirror)
			)
		)
		(duplicate_pad_numbers_are_jumpers no)
		(fp_line
			(start 0.7874 0.4064)
			(end 0.7874 -0.4064)
			(stroke
				(width 0.1524)
				(type default)
			)
			(layer "B.SilkS")
		)
		(fp_line
			(start 0.7874 -0.4064)
			(end -0.7874 -0.4064)
			(stroke
				(width 0.1524)
				(type default)
			)
			(layer "B.SilkS")
		)
		(fp_line
			(start -0.7874 0.4064)
			(end 0.7874 0.4064)
			(stroke
				(width 0.1524)
				(type default)
			)
			(layer "B.SilkS")
		)
		(fp_line
			(start -0.7874 -0.4064)
			(end -0.7874 0.4064)
			(stroke
				(width 0.1524)
				(type default)
			)
			(layer "B.SilkS")
		)
		(fp_line
			(start 0.67945 0.3048)
			(end 0.67945 -0.305054)
			(stroke
				(width 0.1)
				(type default)
			)
			(layer "B.Fab")
		)
		(fp_line
			(start 0.67945 -0.305054)
			(end 0.12065 -0.305054)
			(stroke
				(width 0.1)
				(type default)
			)
			(layer "B.Fab")
		)
		(fp_line
			(start 0.12065 0.3048)
			(end 0.67945 0.3048)
			(stroke
				(width 0.1)
				(type default)
			)
			(layer "B.Fab")
		)
		(fp_line
			(start 0.12065 0.2794)
			(end 0.12065 0.3048)
			(stroke
				(width 0.1)
				(type default)
			)
			(layer "B.Fab")
		)
		(fp_line
			(start 0.12065 -0.2794)
			(end -0.12065 -0.2794)
			(stroke
				(width 0.1)
				(type default)
			)
			(layer "B.Fab")
		)
		(fp_line
			(start 0.12065 -0.305054)
			(end 0.12065 -0.2794)
			(stroke
				(width 0.1)
				(type default)
			)
			(layer "B.Fab")
		)
		(fp_line
			(start -0.120396 0.3048)
			(end -0.120396 0.2794)
			(stroke
				(width 0.1)
				(type default)
			)
			(layer "B.Fab")
		)
		(fp_line
			(start -0.120396 0.2794)
			(end 0.12065 0.2794)
			(stroke
				(width 0.1)
				(type default)
			)
			(layer "B.Fab")
		)
		(fp_line
			(start -0.12065 -0.2794)
			(end -0.12065 -0.3048)
			(stroke
				(width 0.1)
				(type default)
			)
			(layer "B.Fab")
		)
		(fp_line
			(start -0.12065 -0.3048)
			(end -0.67945 -0.3048)
			(stroke
				(width 0.1)
				(type default)
			)
			(layer "B.Fab")
		)
		(fp_line
			(start -0.67945 0.3048)
			(end -0.120396 0.3048)
			(stroke
				(width 0.1)
				(type default)
			)
			(layer "B.Fab")
		)
		(fp_line
			(start -0.67945 -0.3048)
			(end -0.67945 0.3048)
			(stroke
				(width 0.1)
				(type default)
			)
			(layer "B.Fab")
		)
		(pad "1" smd circle
			(at 0.40005 0)
			(size 0 0)
			(layers "B.Cu" "B.Mask" "B.Paste")
			(net "PVDD18_S5_P1")
		)
		(pad "2" smd circle
			(at -0.40005 0)
			(size 0 0)
			(layers "B.Cu" "B.Mask" "B.Paste")
			(net "SVID_PVDDCR_CPU1_P1_SVTI")
		)
	)
	(footprint ""
		(layer "B.Cu")
		(at 184.332372 -118.242842 90)
		(property "Reference" "C1132"
			(at 0 0 90)
			(layer "B.SilkS")
			(hide yes)
			(effects
				(font
					(size 1.27 1.27)
				)
				(justify mirror)
			)
		)
		(property "Value" ""
			(at 0 0 90)
			(layer "B.Fab")
			(effects
				(font
					(size 1.27 1.27)
				)
				(justify mirror)
			)
		)
		(duplicate_pad_numbers_are_jumpers no)
		(fp_line
			(start 0.69215 -0.2921)
			(end -0.69215 -0.2921)
			(stroke
				(width 0.1524)
				(type default)
			)
			(layer "B.SilkS")
		)
		(fp_line
			(start -0.69215 -0.2921)
			(end -0.69215 0.2921)
			(stroke
				(width 0.1524)
				(type default)
			)
			(layer "B.SilkS")
		)
		(fp_line
			(start 0.69215 0.2921)
			(end 0.69215 -0.2921)
			(stroke
				(width 0.1524)
				(type default)
			)
			(layer "B.SilkS")
		)
		(fp_line
			(start -0.69215 0.2921)
			(end 0.69215 0.2921)
			(stroke
				(width 0.1524)
				(type default)
			)
			(layer "B.SilkS")
		)
		(fp_line
			(start 0.51435 -0.2794)
			(end -0.51435 -0.2794)
			(stroke
				(width 0.1)
				(type default)
			)
			(layer "B.Fab")
		)
		(fp_line
			(start -0.51435 -0.2794)
			(end -0.51435 0.2794)
			(stroke
				(width 0.1)
				(type default)
			)
			(layer "B.Fab")
		)
		(fp_line
			(start 0.51435 0.2794)
			(end 0.51435 -0.2794)
			(stroke
				(width 0.1)
				(type default)
			)
			(layer "B.Fab")
		)
		(fp_line
			(start -0.51435 0.2794)
			(end 0.51435 0.2794)
			(stroke
				(width 0.1)
				(type default)
			)
			(layer "B.Fab")
		)
		(pad "1" smd circle
			(at 0.40005 0 270)
			(size 0 0)
			(layers "B.Cu" "B.Mask" "B.Paste")
			(net "P1V8_AUX")
		)
		(pad "2" smd circle
			(at -0.40005 0 270)
			(size 0 0)
			(layers "B.Cu" "B.Mask" "B.Paste")
			(net "GND")
		)
		(zone
			(layer "B.Cu")
			(hatch none 0.5)
			(connect_pads
				(clearance 0)
			)
			(min_thickness 0.25)
			(keepout
				(tracks not_allowed)
				(vias allowed)
				(pads allowed)
				(copperpour not_allowed)
				(footprints allowed)
			)
			(placement
				(enabled no)
				(sheetname "")
			)
			(fill
				(thermal_gap 0.5)
				(thermal_bridge_width 0.5)
				(island_removal_mode 0)
			)
			(polygon
				(pts
					(xy 184.186322 -118.142512) (xy 184.186322 -118.341902) (xy 184.244488 -118.433342) (xy 184.420002 -118.433342)
					(xy 184.478168 -118.341902) (xy 184.478168 -118.142512) (xy 184.420002 -118.052342) (xy 184.244742 -118.052342)
				)
			)
		)
	)
	(footprint ""
		(layer "B.Cu")
		(at 111.476028 -256.012442 -90)
		(property "Reference" "C2473"
			(at 0 0 90)
			(layer "B.SilkS")
			(hide yes)
			(effects
				(font
					(size 1.27 1.27)
				)
				(justify mirror)
			)
		)
		(property "Value" ""
			(at 0 0 90)
			(layer "B.Fab")
			(effects
				(font
					(size 1.27 1.27)
				)
				(justify mirror)
			)
		)
		(duplicate_pad_numbers_are_jumpers no)
		(fp_line
			(start -0.7874 0.4064)
			(end 0.7874 0.4064)
			(stroke
				(width 0.1524)
				(type default)
			)
			(layer "B.SilkS")
		)
		(fp_line
			(start 0.7874 0.4064)
			(end 0.7874 -0.4064)
			(stroke
				(width 0.1524)
				(type default)
			)
			(layer "B.SilkS")
		)
		(fp_line
			(start -0.7874 -0.4064)
			(end -0.7874 0.4064)
			(stroke
				(width 0.1524)
				(type default)
			)
			(layer "B.SilkS")
		)
		(fp_line
			(start 0.7874 -0.4064)
			(end -0.7874 -0.4064)
			(stroke
				(width 0.1524)
				(type default)
			)
			(layer "B.SilkS")
		)
		(fp_line
			(start -0.67945 0.3048)
			(end -0.120396 0.3048)
			(stroke
				(width 0.1)
				(type default)
			)
			(layer "B.Fab")
		)
		(fp_line
			(start -0.120396 0.3048)
			(end -0.120396 0.2794)
			(stroke
				(width 0.1)
				(type default)
			)
			(layer "B.Fab")
		)
		(fp_line
			(start 0.12065 0.3048)
			(end 0.67945 0.3048)
			(stroke
				(width 0.1)
				(type default)
			)
			(layer "B.Fab")
		)
		(fp_line
			(start 0.67945 0.3048)
			(end 0.67945 -0.305054)
			(stroke
				(width 0.1)
				(type default)
			)
			(layer "B.Fab")
		)
		(fp_line
			(start -0.120396 0.2794)
			(end 0.12065 0.2794)
			(stroke
				(width 0.1)
				(type default)
			)
			(layer "B.Fab")
		)
		(fp_line
			(start 0.12065 0.2794)
			(end 0.12065 0.3048)
			(stroke
				(width 0.1)
				(type default)
			)
			(layer "B.Fab")
		)
		(fp_line
			(start -0.12065 -0.2794)
			(end -0.12065 -0.3048)
			(stroke
				(width 0.1)
				(type default)
			)
			(layer "B.Fab")
		)
		(fp_line
			(start 0.12065 -0.2794)
			(end -0.12065 -0.2794)
			(stroke
				(width 0.1)
				(type default)
			)
			(layer "B.Fab")
		)
		(fp_line
			(start -0.67945 -0.3048)
			(end -0.67945 0.3048)
			(stroke
				(width 0.1)
				(type default)
			)
			(layer "B.Fab")
		)
		(fp_line
			(start -0.12065 -0.3048)
			(end -0.67945 -0.3048)
			(stroke
				(width 0.1)
				(type default)
			)
			(layer "B.Fab")
		)
		(fp_line
			(start 0.12065 -0.305054)
			(end 0.12065 -0.2794)
			(stroke
				(width 0.1)
				(type default)
			)
			(layer "B.Fab")
		)
		(fp_line
			(start 0.67945 -0.305054)
			(end 0.12065 -0.305054)
			(stroke
				(width 0.1)
				(type default)
			)
			(layer "B.Fab")
		)
		(pad "1" smd circle
			(at 0.40005 0 90)
			(size 0 0)
			(layers "B.Cu" "B.Mask" "B.Paste")
			(net "PVDDCR_SOC_P1")
		)
		(pad "2" smd circle
			(at -0.40005 0 90)
			(size 0 0)
			(layers "B.Cu" "B.Mask" "B.Paste")
			(net "GND")
		)
	)
	(footprint ""
		(layer "B.Cu")
		(at 91.999054 -326.367902 -90)
		(property "Reference" "PC431_5"
			(at 0 0 90)
			(layer "B.SilkS")
			(hide yes)
			(effects
				(font
					(size 1.27 1.27)
				)
				(justify mirror)
			)
		)
		(property "Value" ""
			(at 0 0 90)
			(layer "B.Fab")
			(effects
				(font
					(size 1.27 1.27)
				)
				(justify mirror)
			)
		)
		(duplicate_pad_numbers_are_jumpers no)
		(fp_line
			(start -1.524 0.762)
			(end 1.524 0.762)
			(stroke
				(width 0.1524)
				(type default)
			)
			(layer "B.SilkS")
		)
		(fp_line
			(start 1.524 0.762)
			(end 1.524 -0.762)
			(stroke
				(width 0.1524)
				(type default)
			)
			(layer "B.SilkS")
		)
		(fp_line
			(start -1.524 -0.762)
			(end -1.524 0.762)
			(stroke
				(width 0.1524)
				(type default)
			)
			(layer "B.SilkS")
		)
		(fp_line
			(start 1.524 -0.762)
			(end -1.524 -0.762)
			(stroke
				(width 0.1524)
				(type default)
			)
			(layer "B.SilkS")
		)
		(fp_line
			(start -1.1049 0.724916)
			(end -1.1049 -0.724916)
			(stroke
				(width 0.1)
				(type default)
			)
			(layer "B.Fab")
		)
		(fp_line
			(start 1.1049 0.724916)
			(end -1.1049 0.724916)
			(stroke
				(width 0.1)
				(type default)
			)
			(layer "B.Fab")
		)
		(fp_line
			(start -1.1049 -0.724916)
			(end 1.1049 -0.724916)
			(stroke
				(width 0.1)
				(type default)
			)
			(layer "B.Fab")
		)
		(fp_line
			(start 1.1049 -0.724916)
			(end 1.1049 0.724916)
			(stroke
				(width 0.1)
				(type default)
			)
			(layer "B.Fab")
		)
		(pad "1" smd rect
			(at 0.889 0 270)
			(size 1.016 1.27)
			(layers "B.Cu" "B.Mask" "B.Paste")
			(net "PVDDCR_CPU1_P1")
		)
		(pad "2" smd rect
			(at -0.889 0 270)
			(size 1.016 1.27)
			(layers "B.Cu" "B.Mask" "B.Paste")
			(net "GND")
		)
	)
	(footprint ""
		(layer "B.Cu")
		(at 182.860696 -195.8594 180)
		(property "Reference" "R1708"
			(at 0 0 0)
			(layer "B.SilkS")
			(hide yes)
			(effects
				(font
					(size 1.27 1.27)
				)
				(justify mirror)
			)
		)
		(property "Value" ""
			(at 0 0 0)
			(layer "B.Fab")
			(effects
				(font
					(size 1.27 1.27)
				)
				(justify mirror)
			)
		)
		(duplicate_pad_numbers_are_jumpers no)
		(fp_line
			(start 0.7874 0.4064)
			(end 0.7874 -0.4064)
			(stroke
				(width 0.1524)
				(type default)
			)
			(layer "B.SilkS")
		)
		(fp_line
			(start 0.7874 -0.4064)
			(end -0.7874 -0.4064)
			(stroke
				(width 0.1524)
				(type default)
			)
			(layer "B.SilkS")
		)
		(fp_line
			(start -0.7874 0.4064)
			(end 0.7874 0.4064)
			(stroke
				(width 0.1524)
				(type default)
			)
			(layer "B.SilkS")
		)
		(fp_line
			(start -0.7874 -0.4064)
			(end -0.7874 0.4064)
			(stroke
				(width 0.1524)
				(type default)
			)
			(layer "B.SilkS")
		)
		(fp_line
			(start 0.67945 0.3048)
			(end 0.67945 -0.305054)
			(stroke
				(width 0.1)
				(type default)
			)
			(layer "B.Fab")
		)
		(fp_line
			(start 0.67945 -0.305054)
			(end 0.12065 -0.305054)
			(stroke
				(width 0.1)
				(type default)
			)
			(layer "B.Fab")
		)
		(fp_line
			(start 0.12065 0.3048)
			(end 0.67945 0.3048)
			(stroke
				(width 0.1)
				(type default)
			)
			(layer "B.Fab")
		)
		(fp_line
			(start 0.12065 0.2794)
			(end 0.12065 0.3048)
			(stroke
				(width 0.1)
				(type default)
			)
			(layer "B.Fab")
		)
		(fp_line
			(start 0.12065 -0.2794)
			(end -0.12065 -0.2794)
			(stroke
				(width 0.1)
				(type default)
			)
			(layer "B.Fab")
		)
		(fp_line
			(start 0.12065 -0.305054)
			(end 0.12065 -0.2794)
			(stroke
				(width 0.1)
				(type default)
			)
			(layer "B.Fab")
		)
		(fp_line
			(start -0.120396 0.3048)
			(end -0.120396 0.2794)
			(stroke
				(width 0.1)
				(type default)
			)
			(layer "B.Fab")
		)
		(fp_line
			(start -0.120396 0.2794)
			(end 0.12065 0.2794)
			(stroke
				(width 0.1)
				(type default)
			)
			(layer "B.Fab")
		)
		(fp_line
			(start -0.12065 -0.2794)
			(end -0.12065 -0.3048)
			(stroke
				(width 0.1)
				(type default)
			)
			(layer "B.Fab")
		)
		(fp_line
			(start -0.12065 -0.3048)
			(end -0.67945 -0.3048)
			(stroke
				(width 0.1)
				(type default)
			)
			(layer "B.Fab")
		)
		(fp_line
			(start -0.67945 0.3048)
			(end -0.120396 0.3048)
			(stroke
				(width 0.1)
				(type default)
			)
			(layer "B.Fab")
		)
		(fp_line
			(start -0.67945 -0.3048)
			(end -0.67945 0.3048)
			(stroke
				(width 0.1)
				(type default)
			)
			(layer "B.Fab")
		)
		(pad "1" smd circle
			(at 0.40005 0)
			(size 0 0)
			(layers "B.Cu" "B.Mask" "B.Paste")
			(net "I3C_SPD_DDRGL_CPU1_SDA")
		)
		(pad "2" smd circle
			(at -0.40005 0)
			(size 0 0)
			(layers "B.Cu" "B.Mask" "B.Paste")
			(net "I3C_SPD_DDRI_CPU1_SDA")
		)
	)
	(footprint ""
		(layer "B.Cu")
		(at 123.357386 -264.354564)
		(property "Reference" "C2483"
			(at 0 0 0)
			(layer "B.SilkS")
			(hide yes)
			(effects
				(font
					(size 1.27 1.27)
				)
				(justify mirror)
			)
		)
		(property "Value" ""
			(at 0 0 0)
			(layer "B.Fab")
			(effects
				(font
					(size 1.27 1.27)
				)
				(justify mirror)
			)
		)
		(duplicate_pad_numbers_are_jumpers no)
		(fp_line
			(start -0.7874 -0.4064)
			(end -0.7874 0.4064)
			(stroke
				(width 0.1524)
				(type default)
			)
			(layer "B.SilkS")
		)
		(fp_line
			(start -0.7874 0.4064)
			(end 0.7874 0.4064)
			(stroke
				(width 0.1524)
				(type default)
			)
			(layer "B.SilkS")
		)
		(fp_line
			(start 0.7874 -0.4064)
			(end -0.7874 -0.4064)
			(stroke
				(width 0.1524)
				(type default)
			)
			(layer "B.SilkS")
		)
		(fp_line
			(start 0.7874 0.4064)
			(end 0.7874 -0.4064)
			(stroke
				(width 0.1524)
				(type default)
			)
			(layer "B.SilkS")
		)
		(fp_line
			(start -0.67945 -0.3048)
			(end -0.67945 0.3048)
			(stroke
				(width 0.1)
				(type default)
			)
			(layer "B.Fab")
		)
		(fp_line
			(start -0.67945 0.3048)
			(end -0.120396 0.3048)
			(stroke
				(width 0.1)
				(type default)
			)
			(layer "B.Fab")
		)
		(fp_line
			(start -0.12065 -0.3048)
			(end -0.67945 -0.3048)
			(stroke
				(width 0.1)
				(type default)
			)
			(layer "B.Fab")
		)
		(fp_line
			(start -0.12065 -0.2794)
			(end -0.12065 -0.3048)
			(stroke
				(width 0.1)
				(type default)
			)
			(layer "B.Fab")
		)
		(fp_line
			(start -0.120396 0.2794)
			(end 0.12065 0.2794)
			(stroke
				(width 0.1)
				(type default)
			)
			(layer "B.Fab")
		)
		(fp_line
			(start -0.120396 0.3048)
			(end -0.120396 0.2794)
			(stroke
				(width 0.1)
				(type default)
			)
			(layer "B.Fab")
		)
		(fp_line
			(start 0.12065 -0.305054)
			(end 0.12065 -0.2794)
			(stroke
				(width 0.1)
				(type default)
			)
			(layer "B.Fab")
		)
		(fp_line
			(start 0.12065 -0.2794)
			(end -0.12065 -0.2794)
			(stroke
				(width 0.1)
				(type default)
			)
			(layer "B.Fab")
		)
		(fp_line
			(start 0.12065 0.2794)
			(end 0.12065 0.3048)
			(stroke
				(width 0.1)
				(type default)
			)
			(layer "B.Fab")
		)
		(fp_line
			(start 0.12065 0.3048)
			(end 0.67945 0.3048)
			(stroke
				(width 0.1)
				(type default)
			)
			(layer "B.Fab")
		)
		(fp_line
			(start 0.67945 -0.305054)
			(end 0.12065 -0.305054)
			(stroke
				(width 0.1)
				(type default)
			)
			(layer "B.Fab")
		)
		(fp_line
			(start 0.67945 0.3048)
			(end 0.67945 -0.305054)
			(stroke
				(width 0.1)
				(type default)
			)
			(layer "B.Fab")
		)
		(pad "1" smd circle
			(at 0.40005 0 180)
			(size 0 0)
			(layers "B.Cu" "B.Mask" "B.Paste")
			(net "PVDD11_S3_P1")
		)
		(pad "2" smd circle
			(at -0.40005 0 180)
			(size 0 0)
			(layers "B.Cu" "B.Mask" "B.Paste")
			(net "GND")
		)
	)
	(footprint ""
		(layer "B.Cu")
		(at 319.118234 -396.393162 -90)
		(property "Reference" "C582"
			(at 0 0 90)
			(layer "B.SilkS")
			(hide yes)
			(effects
				(font
					(size 1.27 1.27)
				)
				(justify mirror)
			)
		)
		(property "Value" ""
			(at 0 0 90)
			(layer "B.Fab")
			(effects
				(font
					(size 1.27 1.27)
				)
				(justify mirror)
			)
		)
		(duplicate_pad_numbers_are_jumpers no)
		(fp_line
			(start -0.299974 0.150114)
			(end 0.299974 0.150114)
			(stroke
				(width 0.1)
				(type default)
			)
			(layer "B.Fab")
		)
		(fp_line
			(start 0.299974 0.150114)
			(end 0.299974 -0.150114)
			(stroke
				(width 0.1)
				(type default)
			)
			(layer "B.Fab")
		)
		(fp_line
			(start -0.299974 -0.150114)
			(end -0.299974 0.150114)
			(stroke
				(width 0.1)
				(type default)
			)
			(layer "B.Fab")
		)
		(fp_line
			(start 0.299974 -0.150114)
			(end -0.299974 -0.150114)
			(stroke
				(width 0.1)
				(type default)
			)
			(layer "B.Fab")
		)
		(pad "1" smd rect
			(at 0.2667 0 90)
			(size 0.3048 0.381)
			(layers "B.Cu" "B.Mask" "B.Paste")
			(net "P0V9_CPU0_RT0_2A")
		)
		(pad "2" smd rect
			(at -0.2667 0 90)
			(size 0.3048 0.381)
			(layers "B.Cu" "B.Mask" "B.Paste")
			(net "GND")
		)
	)
	(footprint ""
		(layer "B.Cu")
		(at 240.411 -231.648 -90)
		(property "Reference" "R370"
			(at 0 0 90)
			(layer "B.SilkS")
			(hide yes)
			(effects
				(font
					(size 1.27 1.27)
				)
				(justify mirror)
			)
		)
		(property "Value" ""
			(at 0 0 90)
			(layer "B.Fab")
			(effects
				(font
					(size 1.27 1.27)
				)
				(justify mirror)
			)
		)
		(duplicate_pad_numbers_are_jumpers no)
		(fp_line
			(start -0.7874 0.4064)
			(end 0.7874 0.4064)
			(stroke
				(width 0.1524)
				(type default)
			)
			(layer "B.SilkS")
		)
		(fp_line
			(start 0.7874 0.4064)
			(end 0.7874 -0.4064)
			(stroke
				(width 0.1524)
				(type default)
			)
			(layer "B.SilkS")
		)
		(fp_line
			(start -0.7874 -0.4064)
			(end -0.7874 0.4064)
			(stroke
				(width 0.1524)
				(type default)
			)
			(layer "B.SilkS")
		)
		(fp_line
			(start 0.7874 -0.4064)
			(end -0.7874 -0.4064)
			(stroke
				(width 0.1524)
				(type default)
			)
			(layer "B.SilkS")
		)
		(fp_line
			(start -0.67945 0.3048)
			(end -0.120396 0.3048)
			(stroke
				(width 0.1)
				(type default)
			)
			(layer "B.Fab")
		)
		(fp_line
			(start -0.120396 0.3048)
			(end -0.120396 0.2794)
			(stroke
				(width 0.1)
				(type default)
			)
			(layer "B.Fab")
		)
		(fp_line
			(start 0.12065 0.3048)
			(end 0.67945 0.3048)
			(stroke
				(width 0.1)
				(type default)
			)
			(layer "B.Fab")
		)
		(fp_line
			(start 0.67945 0.3048)
			(end 0.67945 -0.305054)
			(stroke
				(width 0.1)
				(type default)
			)
			(layer "B.Fab")
		)
		(fp_line
			(start -0.120396 0.2794)
			(end 0.12065 0.2794)
			(stroke
				(width 0.1)
				(type default)
			)
			(layer "B.Fab")
		)
		(fp_line
			(start 0.12065 0.2794)
			(end 0.12065 0.3048)
			(stroke
				(width 0.1)
				(type default)
			)
			(layer "B.Fab")
		)
		(fp_line
			(start -0.12065 -0.2794)
			(end -0.12065 -0.3048)
			(stroke
				(width 0.1)
				(type default)
			)
			(layer "B.Fab")
		)
		(fp_line
			(start 0.12065 -0.2794)
			(end -0.12065 -0.2794)
			(stroke
				(width 0.1)
				(type default)
			)
			(layer "B.Fab")
		)
		(fp_line
			(start -0.67945 -0.3048)
			(end -0.67945 0.3048)
			(stroke
				(width 0.1)
				(type default)
			)
			(layer "B.Fab")
		)
		(fp_line
			(start -0.12065 -0.3048)
			(end -0.67945 -0.3048)
			(stroke
				(width 0.1)
				(type default)
			)
			(layer "B.Fab")
		)
		(fp_line
			(start 0.12065 -0.305054)
			(end 0.12065 -0.2794)
			(stroke
				(width 0.1)
				(type default)
			)
			(layer "B.Fab")
		)
		(fp_line
			(start 0.67945 -0.305054)
			(end 0.12065 -0.305054)
			(stroke
				(width 0.1)
				(type default)
			)
			(layer "B.Fab")
		)
		(pad "1" smd circle
			(at 0.40005 0 90)
			(size 0 0)
			(layers "B.Cu" "B.Mask" "B.Paste")
			(net "PVDD18_S5_P0")
		)
		(pad "2" smd circle
			(at -0.40005 0 90)
			(size 0 0)
			(layers "B.Cu" "B.Mask" "B.Paste")
			(net "SMB_CPU0_SEC_SDA")
		)
	)
	(footprint ""
		(layer "B.Cu")
		(at 94.059502 -205.14945 90)
		(property "Reference" "R533"
			(at 0 0 90)
			(layer "B.SilkS")
			(hide yes)
			(effects
				(font
					(size 1.27 1.27)
				)
				(justify mirror)
			)
		)
		(property "Value" ""
			(at 0 0 90)
			(layer "B.Fab")
			(effects
				(font
					(size 1.27 1.27)
				)
				(justify mirror)
			)
		)
		(duplicate_pad_numbers_are_jumpers no)
		(fp_line
			(start 0.7874 -0.4064)
			(end -0.7874 -0.4064)
			(stroke
				(width 0.1524)
				(type default)
			)
			(layer "B.SilkS")
		)
		(fp_line
			(start -0.7874 -0.4064)
			(end -0.7874 0.4064)
			(stroke
				(width 0.1524)
				(type default)
			)
			(layer "B.SilkS")
		)
		(fp_line
			(start 0.7874 0.4064)
			(end 0.7874 -0.4064)
			(stroke
				(width 0.1524)
				(type default)
			)
			(layer "B.SilkS")
		)
		(fp_line
			(start -0.7874 0.4064)
			(end 0.7874 0.4064)
			(stroke
				(width 0.1524)
				(type default)
			)
			(layer "B.SilkS")
		)
		(fp_line
			(start 0.67945 -0.305054)
			(end 0.12065 -0.305054)
			(stroke
				(width 0.1)
				(type default)
			)
			(layer "B.Fab")
		)
		(fp_line
			(start 0.12065 -0.305054)
			(end 0.12065 -0.2794)
			(stroke
				(width 0.1)
				(type default)
			)
			(layer "B.Fab")
		)
		(fp_line
			(start -0.12065 -0.3048)
			(end -0.67945 -0.3048)
			(stroke
				(width 0.1)
				(type default)
			)
			(layer "B.Fab")
		)
		(fp_line
			(start -0.67945 -0.3048)
			(end -0.67945 0.3048)
			(stroke
				(width 0.1)
				(type default)
			)
			(layer "B.Fab")
		)
		(fp_line
			(start 0.12065 -0.2794)
			(end -0.12065 -0.2794)
			(stroke
				(width 0.1)
				(type default)
			)
			(layer "B.Fab")
		)
		(fp_line
			(start -0.12065 -0.2794)
			(end -0.12065 -0.3048)
			(stroke
				(width 0.1)
				(type default)
			)
			(layer "B.Fab")
		)
		(fp_line
			(start 0.12065 0.2794)
			(end 0.12065 0.3048)
			(stroke
				(width 0.1)
				(type default)
			)
			(layer "B.Fab")
		)
		(fp_line
			(start -0.120396 0.2794)
			(end 0.12065 0.2794)
			(stroke
				(width 0.1)
				(type default)
			)
			(layer "B.Fab")
		)
		(fp_line
			(start 0.67945 0.3048)
			(end 0.67945 -0.305054)
			(stroke
				(width 0.1)
				(type default)
			)
			(layer "B.Fab")
		)
		(fp_line
			(start 0.12065 0.3048)
			(end 0.67945 0.3048)
			(stroke
				(width 0.1)
				(type default)
			)
			(layer "B.Fab")
		)
		(fp_line
			(start -0.120396 0.3048)
			(end -0.120396 0.2794)
			(stroke
				(width 0.1)
				(type default)
			)
			(layer "B.Fab")
		)
		(fp_line
			(start -0.67945 0.3048)
			(end -0.120396 0.3048)
			(stroke
				(width 0.1)
				(type default)
			)
			(layer "B.Fab")
		)
		(pad "1" smd circle
			(at 0.40005 0 270)
			(size 0 0)
			(layers "B.Cu" "B.Mask" "B.Paste")
			(net "CPU1_BP2")
		)
		(pad "2" smd circle
			(at -0.40005 0 270)
			(size 0 0)
			(layers "B.Cu" "B.Mask" "B.Paste")
			(net "PVDD18_S5_P1")
		)
	)
	(footprint ""
		(layer "B.Cu")
		(at 373.424958 -268.855952 60)
		(property "Reference" "C2246"
			(at 0 0 60)
			(layer "B.SilkS")
			(hide yes)
			(effects
				(font
					(size 1.27 1.27)
				)
				(justify mirror)
			)
		)
		(property "Value" ""
			(at 0 0 60)
			(layer "B.Fab")
			(effects
				(font
					(size 1.27 1.27)
				)
				(justify mirror)
			)
		)
		(duplicate_pad_numbers_are_jumpers no)
		(fp_line
			(start -0.787516 -0.406438)
			(end -0.787425 0.40652)
			(stroke
				(width 0.1524)
				(type default)
			)
			(layer "B.SilkS")
		)
		(fp_line
			(start -0.787425 0.40652)
			(end 0.787516 0.406438)
			(stroke
				(width 0.1524)
				(type default)
			)
			(layer "B.SilkS")
		)
		(fp_line
			(start 0.787425 -0.40652)
			(end -0.787516 -0.406438)
			(stroke
				(width 0.1524)
				(type default)
			)
			(layer "B.SilkS")
		)
		(fp_line
			(start 0.787516 0.406438)
			(end 0.787425 -0.40652)
			(stroke
				(width 0.1524)
				(type default)
			)
			(layer "B.SilkS")
		)
		(fp_line
			(start -0.679568 -0.304811)
			(end -0.6795 0.304908)
			(stroke
				(width 0.1)
				(type default)
			)
			(layer "B.Fab")
		)
		(fp_line
			(start -0.120605 -0.304905)
			(end -0.679568 -0.304811)
			(stroke
				(width 0.1)
				(type default)
			)
			(layer "B.Fab")
		)
		(fp_line
			(start -0.120554 -0.279418)
			(end -0.120605 -0.304905)
			(stroke
				(width 0.1)
				(type default)
			)
			(layer "B.Fab")
		)
		(fp_line
			(start 0.120629 -0.30516)
			(end 0.120587 -0.279326)
			(stroke
				(width 0.1)
				(type default)
			)
			(layer "B.Fab")
		)
		(fp_line
			(start 0.120587 -0.279326)
			(end -0.120554 -0.279418)
			(stroke
				(width 0.1)
				(type default)
			)
			(layer "B.Fab")
		)
		(fp_line
			(start -0.6795 0.304908)
			(end -0.120316 0.304686)
			(stroke
				(width 0.1)
				(type default)
			)
			(layer "B.Fab")
		)
		(fp_line
			(start 0.679373 -0.305128)
			(end 0.120629 -0.30516)
			(stroke
				(width 0.1)
				(type default)
			)
			(layer "B.Fab")
		)
		(fp_line
			(start -0.12024 0.279419)
			(end 0.120554 0.279418)
			(stroke
				(width 0.1)
				(type default)
			)
			(layer "B.Fab")
		)
		(fp_line
			(start -0.120316 0.304686)
			(end -0.12024 0.279419)
			(stroke
				(width 0.1)
				(type default)
			)
			(layer "B.Fab")
		)
		(fp_line
			(start 0.120554 0.279418)
			(end 0.120605 0.304905)
			(stroke
				(width 0.1)
				(type default)
			)
			(layer "B.Fab")
		)
		(fp_line
			(start 0.120605 0.304905)
			(end 0.679568 0.304811)
			(stroke
				(width 0.1)
				(type default)
			)
			(layer "B.Fab")
		)
		(fp_line
			(start 0.679568 0.304811)
			(end 0.679373 -0.305128)
			(stroke
				(width 0.1)
				(type default)
			)
			(layer "B.Fab")
		)
		(pad "1" smd circle
			(at 0.40005 0 240)
			(size 0 0)
			(layers "B.Cu" "B.Mask" "B.Paste")
			(net "PVDDCR_CPU1_P0")
		)
		(pad "2" smd circle
			(at -0.40005 0 240)
			(size 0 0)
			(layers "B.Cu" "B.Mask" "B.Paste")
			(net "GND")
		)
	)
	(footprint ""
		(layer "B.Cu")
		(at 440.153806 -21.932392)
		(property "Reference" "PC2080"
			(at 0 0 0)
			(layer "B.SilkS")
			(hide yes)
			(effects
				(font
					(size 1.27 1.27)
				)
				(justify mirror)
			)
		)
		(property "Value" ""
			(at 0 0 0)
			(layer "B.Fab")
			(effects
				(font
					(size 1.27 1.27)
				)
				(justify mirror)
			)
		)
		(duplicate_pad_numbers_are_jumpers no)
		(fp_line
			(start -1.524 -0.762)
			(end -1.524 0.762)
			(stroke
				(width 0.1524)
				(type default)
			)
			(layer "B.SilkS")
		)
		(fp_line
			(start -1.524 0.762)
			(end 1.524 0.762)
			(stroke
				(width 0.1524)
				(type default)
			)
			(layer "B.SilkS")
		)
		(fp_line
			(start 1.524 -0.762)
			(end -1.524 -0.762)
			(stroke
				(width 0.1524)
				(type default)
			)
			(layer "B.SilkS")
		)
		(fp_line
			(start 1.524 0.762)
			(end 1.524 -0.762)
			(stroke
				(width 0.1524)
				(type default)
			)
			(layer "B.SilkS")
		)
		(fp_line
			(start -1.1049 -0.724916)
			(end 1.1049 -0.724916)
			(stroke
				(width 0.1)
				(type default)
			)
			(layer "B.Fab")
		)
		(fp_line
			(start -1.1049 0.724916)
			(end -1.1049 -0.724916)
			(stroke
				(width 0.1)
				(type default)
			)
			(layer "B.Fab")
		)
		(fp_line
			(start 1.1049 -0.724916)
			(end 1.1049 0.724916)
			(stroke
				(width 0.1)
				(type default)
			)
			(layer "B.Fab")
		)
		(fp_line
			(start 1.1049 0.724916)
			(end -1.1049 0.724916)
			(stroke
				(width 0.1)
				(type default)
			)
			(layer "B.Fab")
		)
		(pad "1" smd rect
			(at 0.889 0)
			(size 1.016 1.27)
			(layers "B.Cu" "B.Mask" "B.Paste")
			(net "P12V_OCP_SFF")
		)
		(pad "2" smd rect
			(at -0.889 0)
			(size 1.016 1.27)
			(layers "B.Cu" "B.Mask" "B.Paste")
			(net "GND")
		)
	)
	(footprint ""
		(layer "B.Cu")
		(at 65.518538 -388.011162 -90)
		(property "Reference" "C253"
			(at 0 0 90)
			(layer "B.SilkS")
			(hide yes)
			(effects
				(font
					(size 1.27 1.27)
				)
				(justify mirror)
			)
		)
		(property "Value" ""
			(at 0 0 90)
			(layer "B.Fab")
			(effects
				(font
					(size 1.27 1.27)
				)
				(justify mirror)
			)
		)
		(duplicate_pad_numbers_are_jumpers no)
		(fp_line
			(start -0.299974 0.150114)
			(end 0.299974 0.150114)
			(stroke
				(width 0.1)
				(type default)
			)
			(layer "B.Fab")
		)
		(fp_line
			(start 0.299974 0.150114)
			(end 0.299974 -0.150114)
			(stroke
				(width 0.1)
				(type default)
			)
			(layer "B.Fab")
		)
		(fp_line
			(start -0.299974 -0.150114)
			(end -0.299974 0.150114)
			(stroke
				(width 0.1)
				(type default)
			)
			(layer "B.Fab")
		)
		(fp_line
			(start 0.299974 -0.150114)
			(end -0.299974 -0.150114)
			(stroke
				(width 0.1)
				(type default)
			)
			(layer "B.Fab")
		)
		(pad "1" smd rect
			(at 0.2667 0 90)
			(size 0.3048 0.381)
			(layers "B.Cu" "B.Mask" "B.Paste")
			(net "P0V9_CPU1_RT0_2A")
		)
		(pad "2" smd rect
			(at -0.2667 0 90)
			(size 0.3048 0.381)
			(layers "B.Cu" "B.Mask" "B.Paste")
			(net "GND")
		)
	)
	(footprint ""
		(layer "B.Cu")
		(at 338.560664 -73.534778)
		(property "Reference" "Q84"
			(at 1.4224 -1.768348 0)
			(unlocked yes)
			(layer "B.SilkS")
			(effects
				(font
					(size 0.7874 0.5842)
					(thickness 0.1524)
				)
				(justify left mirror)
			)
		)
		(property "Value" ""
			(at 0 0 0)
			(layer "B.Fab")
			(effects
				(font
					(size 1.27 1.27)
				)
				(justify mirror)
			)
		)
		(duplicate_pad_numbers_are_jumpers no)
		(fp_line
			(start -1.332738 -1.100074)
			(end -1.332738 1.100074)
			(stroke
				(width 0.1524)
				(type default)
			)
			(layer "B.SilkS")
		)
		(fp_line
			(start -1.332738 1.100074)
			(end 1.332738 1.100074)
			(stroke
				(width 0.1524)
				(type default)
			)
			(layer "B.SilkS")
		)
		(fp_line
			(start -0.4826 -1.100074)
			(end -1.332738 -1.100074)
			(stroke
				(width 0.1524)
				(type default)
			)
			(layer "B.SilkS")
		)
		(fp_line
			(start 0 -0.541274)
			(end -0.4826 -1.100074)
			(stroke
				(width 0.1524)
				(type default)
			)
			(layer "B.SilkS")
		)
		(fp_line
			(start 0.4826 -1.100074)
			(end 0 -0.541274)
			(stroke
				(width 0.1524)
				(type default)
			)
			(layer "B.SilkS")
		)
		(fp_line
			(start 1.332738 -1.100074)
			(end 0.4826 -1.100074)
			(stroke
				(width 0.1524)
				(type default)
			)
			(layer "B.SilkS")
		)
		(fp_line
			(start 1.332738 1.100074)
			(end 1.332738 -1.100074)
			(stroke
				(width 0.1524)
				(type default)
			)
			(layer "B.SilkS")
		)
		(fp_poly
			(pts
				(xy 1.378458 -0.627888) (xy 2.080514 -0.978916) (xy 2.080514 -0.27686)
			)
			(stroke
				(width 0)
				(type default)
			)
			(fill yes)
			(layer "B.SilkS")
		)
		(fp_line
			(start -0.674878 -1.100074)
			(end -0.674878 1.100074)
			(stroke
				(width 0.1)
				(type default)
			)
			(layer "B.Fab")
		)
		(fp_line
			(start -0.674878 1.100074)
			(end 0.674878 1.100074)
			(stroke
				(width 0.1)
				(type default)
			)
			(layer "B.Fab")
		)
		(fp_line
			(start 0.674878 -1.100074)
			(end -0.674878 -1.100074)
			(stroke
				(width 0.1)
				(type default)
			)
			(layer "B.Fab")
		)
		(fp_line
			(start 0.674878 1.100074)
			(end 0.674878 -1.100074)
			(stroke
				(width 0.1)
				(type default)
			)
			(layer "B.Fab")
		)
		(fp_poly
			(pts
				(xy 2.2352 -0.298958) (xy 2.2352 -1.001014) (xy 1.533144 -0.649986)
			)
			(stroke
				(width 0)
				(type default)
			)
			(fill yes)
			(layer "B.Fab")
		)
		(pad "1" smd rect
			(at 0.94996 -0.649986 90)
			(size 0.4318 0.508)
			(layers "B.Cu" "B.Mask" "B.Paste")
			(net "GND")
		)
		(pad "2" smd rect
			(at 0.94996 0 90)
			(size 0.4318 0.508)
			(layers "B.Cu" "B.Mask" "B.Paste")
			(net "FM_LED_PWRGD_PVDDCR_CPU0_P1")
		)
		(pad "3" smd rect
			(at 0.94996 0.649986 90)
			(size 0.4318 0.508)
			(layers "B.Cu" "B.Mask" "B.Paste")
			(net "LED_PWRGD_PVDDCR_SOC_P1_D")
		)
		(pad "4" smd rect
			(at -0.94996 0.649986 90)
			(size 0.4318 0.508)
			(layers "B.Cu" "B.Mask" "B.Paste")
			(net "GND")
		)
		(pad "5" smd rect
			(at -0.94996 0 90)
			(size 0.4318 0.508)
			(layers "B.Cu" "B.Mask" "B.Paste")
			(net "FM_LED_PWRGD_PVDDCR_SOC_P1")
		)
		(pad "6" smd rect
			(at -0.94996 -0.649986 90)
			(size 0.4318 0.508)
			(layers "B.Cu" "B.Mask" "B.Paste")
			(net "LED_PWRGD_PVDDCR_CPU0_P1_D")
		)
	)
	(footprint ""
		(layer "B.Cu")
		(at 366.36579 -393.96416 180)
		(property "Reference" "R1115"
			(at 0 0 0)
			(layer "B.SilkS")
			(hide yes)
			(effects
				(font
					(size 1.27 1.27)
				)
				(justify mirror)
			)
		)
		(property "Value" ""
			(at 0 0 0)
			(layer "B.Fab")
			(effects
				(font
					(size 1.27 1.27)
				)
				(justify mirror)
			)
		)
		(duplicate_pad_numbers_are_jumpers no)
		(fp_line
			(start 0.32512 0.175006)
			(end 0.32512 -0.175006)
			(stroke
				(width 0.1)
				(type default)
			)
			(layer "B.Fab")
		)
		(fp_line
			(start 0.32512 -0.175006)
			(end -0.32512 -0.175006)
			(stroke
				(width 0.1)
				(type default)
			)
			(layer "B.Fab")
		)
		(fp_line
			(start -0.32512 0.175006)
			(end 0.32512 0.175006)
			(stroke
				(width 0.1)
				(type default)
			)
			(layer "B.Fab")
		)
		(fp_line
			(start -0.32512 -0.175006)
			(end -0.32512 0.175006)
			(stroke
				(width 0.1)
				(type default)
			)
			(layer "B.Fab")
		)
		(pad "1" smd rect
			(at 0.2667 0)
			(size 0.3048 0.381)
			(layers "B.Cu" "B.Mask" "B.Paste")
			(net "TEST0_RT_CPU0_P3")
		)
		(pad "2" smd rect
			(at -0.2667 0 180)
			(size 0.3048 0.381)
			(layers "B.Cu" "B.Mask" "B.Paste")
			(net "GND")
		)
	)
	(footprint ""
		(layer "B.Cu")
		(at 367.614454 -264.35431)
		(property "Reference" "C2645"
			(at 0 0 0)
			(layer "B.SilkS")
			(hide yes)
			(effects
				(font
					(size 1.27 1.27)
				)
				(justify mirror)
			)
		)
		(property "Value" ""
			(at 0 0 0)
			(layer "B.Fab")
			(effects
				(font
					(size 1.27 1.27)
				)
				(justify mirror)
			)
		)
		(duplicate_pad_numbers_are_jumpers no)
		(fp_line
			(start -0.7874 -0.4064)
			(end -0.7874 0.4064)
			(stroke
				(width 0.1524)
				(type default)
			)
			(layer "B.SilkS")
		)
		(fp_line
			(start -0.7874 0.4064)
			(end 0.7874 0.4064)
			(stroke
				(width 0.1524)
				(type default)
			)
			(layer "B.SilkS")
		)
		(fp_line
			(start 0.7874 -0.4064)
			(end -0.7874 -0.4064)
			(stroke
				(width 0.1524)
				(type default)
			)
			(layer "B.SilkS")
		)
		(fp_line
			(start 0.7874 0.4064)
			(end 0.7874 -0.4064)
			(stroke
				(width 0.1524)
				(type default)
			)
			(layer "B.SilkS")
		)
		(fp_line
			(start -0.67945 -0.3048)
			(end -0.67945 0.3048)
			(stroke
				(width 0.1)
				(type default)
			)
			(layer "B.Fab")
		)
		(fp_line
			(start -0.67945 0.3048)
			(end -0.120396 0.3048)
			(stroke
				(width 0.1)
				(type default)
			)
			(layer "B.Fab")
		)
		(fp_line
			(start -0.12065 -0.3048)
			(end -0.67945 -0.3048)
			(stroke
				(width 0.1)
				(type default)
			)
			(layer "B.Fab")
		)
		(fp_line
			(start -0.12065 -0.2794)
			(end -0.12065 -0.3048)
			(stroke
				(width 0.1)
				(type default)
			)
			(layer "B.Fab")
		)
		(fp_line
			(start -0.120396 0.2794)
			(end 0.12065 0.2794)
			(stroke
				(width 0.1)
				(type default)
			)
			(layer "B.Fab")
		)
		(fp_line
			(start -0.120396 0.3048)
			(end -0.120396 0.2794)
			(stroke
				(width 0.1)
				(type default)
			)
			(layer "B.Fab")
		)
		(fp_line
			(start 0.12065 -0.305054)
			(end 0.12065 -0.2794)
			(stroke
				(width 0.1)
				(type default)
			)
			(layer "B.Fab")
		)
		(fp_line
			(start 0.12065 -0.2794)
			(end -0.12065 -0.2794)
			(stroke
				(width 0.1)
				(type default)
			)
			(layer "B.Fab")
		)
		(fp_line
			(start 0.12065 0.2794)
			(end 0.12065 0.3048)
			(stroke
				(width 0.1)
				(type default)
			)
			(layer "B.Fab")
		)
		(fp_line
			(start 0.12065 0.3048)
			(end 0.67945 0.3048)
			(stroke
				(width 0.1)
				(type default)
			)
			(layer "B.Fab")
		)
		(fp_line
			(start 0.67945 -0.305054)
			(end 0.12065 -0.305054)
			(stroke
				(width 0.1)
				(type default)
			)
			(layer "B.Fab")
		)
		(fp_line
			(start 0.67945 0.3048)
			(end 0.67945 -0.305054)
			(stroke
				(width 0.1)
				(type default)
			)
			(layer "B.Fab")
		)
		(pad "1" smd circle
			(at 0.40005 0 180)
			(size 0 0)
			(layers "B.Cu" "B.Mask" "B.Paste")
			(net "PVDD11_S3_P0")
		)
		(pad "2" smd circle
			(at -0.40005 0 180)
			(size 0 0)
			(layers "B.Cu" "B.Mask" "B.Paste")
			(net "GND")
		)
	)
	(footprint ""
		(layer "B.Cu")
		(at 232.918 -232.156 -90)
		(property "Reference" "R146"
			(at 0 0 90)
			(layer "B.SilkS")
			(hide yes)
			(effects
				(font
					(size 1.27 1.27)
				)
				(justify mirror)
			)
		)
		(property "Value" ""
			(at 0 0 90)
			(layer "B.Fab")
			(effects
				(font
					(size 1.27 1.27)
				)
				(justify mirror)
			)
		)
		(duplicate_pad_numbers_are_jumpers no)
		(fp_line
			(start -0.7874 0.4064)
			(end 0.7874 0.4064)
			(stroke
				(width 0.1524)
				(type default)
			)
			(layer "B.SilkS")
		)
		(fp_line
			(start 0.7874 0.4064)
			(end 0.7874 -0.4064)
			(stroke
				(width 0.1524)
				(type default)
			)
			(layer "B.SilkS")
		)
		(fp_line
			(start -0.7874 -0.4064)
			(end -0.7874 0.4064)
			(stroke
				(width 0.1524)
				(type default)
			)
			(layer "B.SilkS")
		)
		(fp_line
			(start 0.7874 -0.4064)
			(end -0.7874 -0.4064)
			(stroke
				(width 0.1524)
				(type default)
			)
			(layer "B.SilkS")
		)
		(fp_line
			(start -0.67945 0.3048)
			(end -0.120396 0.3048)
			(stroke
				(width 0.1)
				(type default)
			)
			(layer "B.Fab")
		)
		(fp_line
			(start -0.120396 0.3048)
			(end -0.120396 0.2794)
			(stroke
				(width 0.1)
				(type default)
			)
			(layer "B.Fab")
		)
		(fp_line
			(start 0.12065 0.3048)
			(end 0.67945 0.3048)
			(stroke
				(width 0.1)
				(type default)
			)
			(layer "B.Fab")
		)
		(fp_line
			(start 0.67945 0.3048)
			(end 0.67945 -0.305054)
			(stroke
				(width 0.1)
				(type default)
			)
			(layer "B.Fab")
		)
		(fp_line
			(start -0.120396 0.2794)
			(end 0.12065 0.2794)
			(stroke
				(width 0.1)
				(type default)
			)
			(layer "B.Fab")
		)
		(fp_line
			(start 0.12065 0.2794)
			(end 0.12065 0.3048)
			(stroke
				(width 0.1)
				(type default)
			)
			(layer "B.Fab")
		)
		(fp_line
			(start -0.12065 -0.2794)
			(end -0.12065 -0.3048)
			(stroke
				(width 0.1)
				(type default)
			)
			(layer "B.Fab")
		)
		(fp_line
			(start 0.12065 -0.2794)
			(end -0.12065 -0.2794)
			(stroke
				(width 0.1)
				(type default)
			)
			(layer "B.Fab")
		)
		(fp_line
			(start -0.67945 -0.3048)
			(end -0.67945 0.3048)
			(stroke
				(width 0.1)
				(type default)
			)
			(layer "B.Fab")
		)
		(fp_line
			(start -0.12065 -0.3048)
			(end -0.67945 -0.3048)
			(stroke
				(width 0.1)
				(type default)
			)
			(layer "B.Fab")
		)
		(fp_line
			(start 0.12065 -0.305054)
			(end 0.12065 -0.2794)
			(stroke
				(width 0.1)
				(type default)
			)
			(layer "B.Fab")
		)
		(fp_line
			(start 0.67945 -0.305054)
			(end 0.12065 -0.305054)
			(stroke
				(width 0.1)
				(type default)
			)
			(layer "B.Fab")
		)
		(pad "1" smd circle
			(at 0.40005 0 90)
			(size 0 0)
			(layers "B.Cu" "B.Mask" "B.Paste")
			(net "SMB_CPU0_CPU1_APML_MUX1_SCL")
		)
		(pad "2" smd circle
			(at -0.40005 0 90)
			(size 0 0)
			(layers "B.Cu" "B.Mask" "B.Paste")
			(net "SMB_APML_CPU1_R_SCL")
		)
	)
	(footprint ""
		(layer "B.Cu")
		(at 397.880078 -324.812152)
		(property "Reference" "R462"
			(at 0 0 0)
			(layer "B.SilkS")
			(hide yes)
			(effects
				(font
					(size 1.27 1.27)
				)
				(justify mirror)
			)
		)
		(property "Value" ""
			(at 0 0 0)
			(layer "B.Fab")
			(effects
				(font
					(size 1.27 1.27)
				)
				(justify mirror)
			)
		)
		(duplicate_pad_numbers_are_jumpers no)
		(fp_line
			(start -0.7874 -0.4064)
			(end -0.7874 0.4064)
			(stroke
				(width 0.1524)
				(type default)
			)
			(layer "B.SilkS")
		)
		(fp_line
			(start -0.7874 0.4064)
			(end 0.7874 0.4064)
			(stroke
				(width 0.1524)
				(type default)
			)
			(layer "B.SilkS")
		)
		(fp_line
			(start 0.7874 -0.4064)
			(end -0.7874 -0.4064)
			(stroke
				(width 0.1524)
				(type default)
			)
			(layer "B.SilkS")
		)
		(fp_line
			(start 0.7874 0.4064)
			(end 0.7874 -0.4064)
			(stroke
				(width 0.1524)
				(type default)
			)
			(layer "B.SilkS")
		)
		(fp_line
			(start -0.67945 -0.3048)
			(end -0.67945 0.3048)
			(stroke
				(width 0.1)
				(type default)
			)
			(layer "B.Fab")
		)
		(fp_line
			(start -0.67945 0.3048)
			(end -0.120396 0.3048)
			(stroke
				(width 0.1)
				(type default)
			)
			(layer "B.Fab")
		)
		(fp_line
			(start -0.12065 -0.3048)
			(end -0.67945 -0.3048)
			(stroke
				(width 0.1)
				(type default)
			)
			(layer "B.Fab")
		)
		(fp_line
			(start -0.12065 -0.2794)
			(end -0.12065 -0.3048)
			(stroke
				(width 0.1)
				(type default)
			)
			(layer "B.Fab")
		)
		(fp_line
			(start -0.120396 0.2794)
			(end 0.12065 0.2794)
			(stroke
				(width 0.1)
				(type default)
			)
			(layer "B.Fab")
		)
		(fp_line
			(start -0.120396 0.3048)
			(end -0.120396 0.2794)
			(stroke
				(width 0.1)
				(type default)
			)
			(layer "B.Fab")
		)
		(fp_line
			(start 0.12065 -0.305054)
			(end 0.12065 -0.2794)
			(stroke
				(width 0.1)
				(type default)
			)
			(layer "B.Fab")
		)
		(fp_line
			(start 0.12065 -0.2794)
			(end -0.12065 -0.2794)
			(stroke
				(width 0.1)
				(type default)
			)
			(layer "B.Fab")
		)
		(fp_line
			(start 0.12065 0.2794)
			(end 0.12065 0.3048)
			(stroke
				(width 0.1)
				(type default)
			)
			(layer "B.Fab")
		)
		(fp_line
			(start 0.12065 0.3048)
			(end 0.67945 0.3048)
			(stroke
				(width 0.1)
				(type default)
			)
			(layer "B.Fab")
		)
		(fp_line
			(start 0.67945 -0.305054)
			(end 0.12065 -0.305054)
			(stroke
				(width 0.1)
				(type default)
			)
			(layer "B.Fab")
		)
		(fp_line
			(start 0.67945 0.3048)
			(end 0.67945 -0.305054)
			(stroke
				(width 0.1)
				(type default)
			)
			(layer "B.Fab")
		)
		(pad "1" smd rect
			(at 0.40005 0)
			(size 0.4572 0.508)
			(layers "B.Cu" "B.Mask" "B.Paste")
			(net "ESPI_CPU0_CS1_N")
		)
		(pad "2" smd rect
			(at -0.40005 0)
			(size 0.4572 0.508)
			(layers "B.Cu" "B.Mask" "B.Paste")
			(net "ESPI_CPU0_R_CS1_N")
		)
	)
	(footprint ""
		(layer "B.Cu")
		(at 102.656386 -267.529564)
		(property "Reference" "C2397"
			(at 0 0 0)
			(layer "B.SilkS")
			(hide yes)
			(effects
				(font
					(size 1.27 1.27)
				)
				(justify mirror)
			)
		)
		(property "Value" ""
			(at 0 0 0)
			(layer "B.Fab")
			(effects
				(font
					(size 1.27 1.27)
				)
				(justify mirror)
			)
		)
		(duplicate_pad_numbers_are_jumpers no)
		(fp_line
			(start -0.7874 -0.4064)
			(end -0.7874 0.4064)
			(stroke
				(width 0.1524)
				(type default)
			)
			(layer "B.SilkS")
		)
		(fp_line
			(start -0.7874 0.4064)
			(end 0.7874 0.4064)
			(stroke
				(width 0.1524)
				(type default)
			)
			(layer "B.SilkS")
		)
		(fp_line
			(start 0.7874 -0.4064)
			(end -0.7874 -0.4064)
			(stroke
				(width 0.1524)
				(type default)
			)
			(layer "B.SilkS")
		)
		(fp_line
			(start 0.7874 0.4064)
			(end 0.7874 -0.4064)
			(stroke
				(width 0.1524)
				(type default)
			)
			(layer "B.SilkS")
		)
		(fp_line
			(start -0.67945 -0.3048)
			(end -0.67945 0.3048)
			(stroke
				(width 0.1)
				(type default)
			)
			(layer "B.Fab")
		)
		(fp_line
			(start -0.67945 0.3048)
			(end -0.120396 0.3048)
			(stroke
				(width 0.1)
				(type default)
			)
			(layer "B.Fab")
		)
		(fp_line
			(start -0.12065 -0.3048)
			(end -0.67945 -0.3048)
			(stroke
				(width 0.1)
				(type default)
			)
			(layer "B.Fab")
		)
		(fp_line
			(start -0.12065 -0.2794)
			(end -0.12065 -0.3048)
			(stroke
				(width 0.1)
				(type default)
			)
			(layer "B.Fab")
		)
		(fp_line
			(start -0.120396 0.2794)
			(end 0.12065 0.2794)
			(stroke
				(width 0.1)
				(type default)
			)
			(layer "B.Fab")
		)
		(fp_line
			(start -0.120396 0.3048)
			(end -0.120396 0.2794)
			(stroke
				(width 0.1)
				(type default)
			)
			(layer "B.Fab")
		)
		(fp_line
			(start 0.12065 -0.305054)
			(end 0.12065 -0.2794)
			(stroke
				(width 0.1)
				(type default)
			)
			(layer "B.Fab")
		)
		(fp_line
			(start 0.12065 -0.2794)
			(end -0.12065 -0.2794)
			(stroke
				(width 0.1)
				(type default)
			)
			(layer "B.Fab")
		)
		(fp_line
			(start 0.12065 0.2794)
			(end 0.12065 0.3048)
			(stroke
				(width 0.1)
				(type default)
			)
			(layer "B.Fab")
		)
		(fp_line
			(start 0.12065 0.3048)
			(end 0.67945 0.3048)
			(stroke
				(width 0.1)
				(type default)
			)
			(layer "B.Fab")
		)
		(fp_line
			(start 0.67945 -0.305054)
			(end 0.12065 -0.305054)
			(stroke
				(width 0.1)
				(type default)
			)
			(layer "B.Fab")
		)
		(fp_line
			(start 0.67945 0.3048)
			(end 0.67945 -0.305054)
			(stroke
				(width 0.1)
				(type default)
			)
			(layer "B.Fab")
		)
		(pad "1" smd circle
			(at 0.40005 0 180)
			(size 0 0)
			(layers "B.Cu" "B.Mask" "B.Paste")
			(net "PVDDCR_CPU1_P1")
		)
		(pad "2" smd circle
			(at -0.40005 0 180)
			(size 0 0)
			(layers "B.Cu" "B.Mask" "B.Paste")
			(net "GND")
		)
	)
	(footprint ""
		(layer "B.Cu")
		(at 429.103282 -436.414672 -90)
		(property "Reference" "R4162"
			(at 0 0 90)
			(layer "B.SilkS")
			(hide yes)
			(effects
				(font
					(size 1.27 1.27)
				)
				(justify mirror)
			)
		)
		(property "Value" ""
			(at 0 0 90)
			(layer "B.Fab")
			(effects
				(font
					(size 1.27 1.27)
				)
				(justify mirror)
			)
		)
		(duplicate_pad_numbers_are_jumpers no)
		(fp_line
			(start -0.7874 0.4064)
			(end 0.7874 0.4064)
			(stroke
				(width 0.1524)
				(type default)
			)
			(layer "B.SilkS")
		)
		(fp_line
			(start 0.7874 0.4064)
			(end 0.7874 -0.4064)
			(stroke
				(width 0.1524)
				(type default)
			)
			(layer "B.SilkS")
		)
		(fp_line
			(start -0.7874 -0.4064)
			(end -0.7874 0.4064)
			(stroke
				(width 0.1524)
				(type default)
			)
			(layer "B.SilkS")
		)
		(fp_line
			(start 0.7874 -0.4064)
			(end -0.7874 -0.4064)
			(stroke
				(width 0.1524)
				(type default)
			)
			(layer "B.SilkS")
		)
		(fp_line
			(start -0.67945 0.3048)
			(end -0.120396 0.3048)
			(stroke
				(width 0.1)
				(type default)
			)
			(layer "B.Fab")
		)
		(fp_line
			(start -0.120396 0.3048)
			(end -0.120396 0.2794)
			(stroke
				(width 0.1)
				(type default)
			)
			(layer "B.Fab")
		)
		(fp_line
			(start 0.12065 0.3048)
			(end 0.67945 0.3048)
			(stroke
				(width 0.1)
				(type default)
			)
			(layer "B.Fab")
		)
		(fp_line
			(start 0.67945 0.3048)
			(end 0.67945 -0.305054)
			(stroke
				(width 0.1)
				(type default)
			)
			(layer "B.Fab")
		)
		(fp_line
			(start -0.120396 0.2794)
			(end 0.12065 0.2794)
			(stroke
				(width 0.1)
				(type default)
			)
			(layer "B.Fab")
		)
		(fp_line
			(start 0.12065 0.2794)
			(end 0.12065 0.3048)
			(stroke
				(width 0.1)
				(type default)
			)
			(layer "B.Fab")
		)
		(fp_line
			(start -0.12065 -0.2794)
			(end -0.12065 -0.3048)
			(stroke
				(width 0.1)
				(type default)
			)
			(layer "B.Fab")
		)
		(fp_line
			(start 0.12065 -0.2794)
			(end -0.12065 -0.2794)
			(stroke
				(width 0.1)
				(type default)
			)
			(layer "B.Fab")
		)
		(fp_line
			(start -0.67945 -0.3048)
			(end -0.67945 0.3048)
			(stroke
				(width 0.1)
				(type default)
			)
			(layer "B.Fab")
		)
		(fp_line
			(start -0.12065 -0.3048)
			(end -0.67945 -0.3048)
			(stroke
				(width 0.1)
				(type default)
			)
			(layer "B.Fab")
		)
		(fp_line
			(start 0.12065 -0.305054)
			(end 0.12065 -0.2794)
			(stroke
				(width 0.1)
				(type default)
			)
			(layer "B.Fab")
		)
		(fp_line
			(start 0.67945 -0.305054)
			(end 0.12065 -0.305054)
			(stroke
				(width 0.1)
				(type default)
			)
			(layer "B.Fab")
		)
		(pad "1" smd circle
			(at 0.40005 0 90)
			(size 0 0)
			(layers "B.Cu" "B.Mask" "B.Paste")
			(net "P3V3_AUX")
		)
		(pad "2" smd circle
			(at -0.40005 0 90)
			(size 0 0)
			(layers "B.Cu" "B.Mask" "B.Paste")
			(net "GPU_3V3IO_RSVD3")
		)
	)
	(footprint ""
		(layer "B.Cu")
		(at 355.803454 -268.41831)
		(property "Reference" "C2226"
			(at 0 0 0)
			(layer "B.SilkS")
			(hide yes)
			(effects
				(font
					(size 1.27 1.27)
				)
				(justify mirror)
			)
		)
		(property "Value" ""
			(at 0 0 0)
			(layer "B.Fab")
			(effects
				(font
					(size 1.27 1.27)
				)
				(justify mirror)
			)
		)
		(duplicate_pad_numbers_are_jumpers no)
		(fp_line
			(start -0.7874 -0.4064)
			(end -0.7874 0.4064)
			(stroke
				(width 0.1524)
				(type default)
			)
			(layer "B.SilkS")
		)
		(fp_line
			(start -0.7874 0.4064)
			(end 0.7874 0.4064)
			(stroke
				(width 0.1524)
				(type default)
			)
			(layer "B.SilkS")
		)
		(fp_line
			(start 0.7874 -0.4064)
			(end -0.7874 -0.4064)
			(stroke
				(width 0.1524)
				(type default)
			)
			(layer "B.SilkS")
		)
		(fp_line
			(start 0.7874 0.4064)
			(end 0.7874 -0.4064)
			(stroke
				(width 0.1524)
				(type default)
			)
			(layer "B.SilkS")
		)
		(fp_line
			(start -0.67945 -0.3048)
			(end -0.67945 0.3048)
			(stroke
				(width 0.1)
				(type default)
			)
			(layer "B.Fab")
		)
		(fp_line
			(start -0.67945 0.3048)
			(end -0.120396 0.3048)
			(stroke
				(width 0.1)
				(type default)
			)
			(layer "B.Fab")
		)
		(fp_line
			(start -0.12065 -0.3048)
			(end -0.67945 -0.3048)
			(stroke
				(width 0.1)
				(type default)
			)
			(layer "B.Fab")
		)
		(fp_line
			(start -0.12065 -0.2794)
			(end -0.12065 -0.3048)
			(stroke
				(width 0.1)
				(type default)
			)
			(layer "B.Fab")
		)
		(fp_line
			(start -0.120396 0.2794)
			(end 0.12065 0.2794)
			(stroke
				(width 0.1)
				(type default)
			)
			(layer "B.Fab")
		)
		(fp_line
			(start -0.120396 0.3048)
			(end -0.120396 0.2794)
			(stroke
				(width 0.1)
				(type default)
			)
			(layer "B.Fab")
		)
		(fp_line
			(start 0.12065 -0.305054)
			(end 0.12065 -0.2794)
			(stroke
				(width 0.1)
				(type default)
			)
			(layer "B.Fab")
		)
		(fp_line
			(start 0.12065 -0.2794)
			(end -0.12065 -0.2794)
			(stroke
				(width 0.1)
				(type default)
			)
			(layer "B.Fab")
		)
		(fp_line
			(start 0.12065 0.2794)
			(end 0.12065 0.3048)
			(stroke
				(width 0.1)
				(type default)
			)
			(layer "B.Fab")
		)
		(fp_line
			(start 0.12065 0.3048)
			(end 0.67945 0.3048)
			(stroke
				(width 0.1)
				(type default)
			)
			(layer "B.Fab")
		)
		(fp_line
			(start 0.67945 -0.305054)
			(end 0.12065 -0.305054)
			(stroke
				(width 0.1)
				(type default)
			)
			(layer "B.Fab")
		)
		(fp_line
			(start 0.67945 0.3048)
			(end 0.67945 -0.305054)
			(stroke
				(width 0.1)
				(type default)
			)
			(layer "B.Fab")
		)
		(pad "1" smd circle
			(at 0.40005 0 180)
			(size 0 0)
			(layers "B.Cu" "B.Mask" "B.Paste")
			(net "PVDDCR_CPU1_P0")
		)
		(pad "2" smd circle
			(at -0.40005 0 180)
			(size 0 0)
			(layers "B.Cu" "B.Mask" "B.Paste")
			(net "GND")
		)
	)
	(footprint ""
		(layer "B.Cu")
		(at 190.881 -100.294948 -90)
		(property "Reference" "R269"
			(at 0 0 90)
			(layer "B.SilkS")
			(hide yes)
			(effects
				(font
					(size 1.27 1.27)
				)
				(justify mirror)
			)
		)
		(property "Value" ""
			(at 0 0 90)
			(layer "B.Fab")
			(effects
				(font
					(size 1.27 1.27)
				)
				(justify mirror)
			)
		)
		(duplicate_pad_numbers_are_jumpers no)
		(fp_line
			(start -0.7874 0.4064)
			(end 0.7874 0.4064)
			(stroke
				(width 0.1524)
				(type default)
			)
			(layer "B.SilkS")
		)
		(fp_line
			(start 0.7874 0.4064)
			(end 0.7874 -0.4064)
			(stroke
				(width 0.1524)
				(type default)
			)
			(layer "B.SilkS")
		)
		(fp_line
			(start -0.7874 -0.4064)
			(end -0.7874 0.4064)
			(stroke
				(width 0.1524)
				(type default)
			)
			(layer "B.SilkS")
		)
		(fp_line
			(start 0.7874 -0.4064)
			(end -0.7874 -0.4064)
			(stroke
				(width 0.1524)
				(type default)
			)
			(layer "B.SilkS")
		)
		(fp_line
			(start -0.67945 0.3048)
			(end -0.120396 0.3048)
			(stroke
				(width 0.1)
				(type default)
			)
			(layer "B.Fab")
		)
		(fp_line
			(start -0.120396 0.3048)
			(end -0.120396 0.2794)
			(stroke
				(width 0.1)
				(type default)
			)
			(layer "B.Fab")
		)
		(fp_line
			(start 0.12065 0.3048)
			(end 0.67945 0.3048)
			(stroke
				(width 0.1)
				(type default)
			)
			(layer "B.Fab")
		)
		(fp_line
			(start 0.67945 0.3048)
			(end 0.67945 -0.305054)
			(stroke
				(width 0.1)
				(type default)
			)
			(layer "B.Fab")
		)
		(fp_line
			(start -0.120396 0.2794)
			(end 0.12065 0.2794)
			(stroke
				(width 0.1)
				(type default)
			)
			(layer "B.Fab")
		)
		(fp_line
			(start 0.12065 0.2794)
			(end 0.12065 0.3048)
			(stroke
				(width 0.1)
				(type default)
			)
			(layer "B.Fab")
		)
		(fp_line
			(start -0.12065 -0.2794)
			(end -0.12065 -0.3048)
			(stroke
				(width 0.1)
				(type default)
			)
			(layer "B.Fab")
		)
		(fp_line
			(start 0.12065 -0.2794)
			(end -0.12065 -0.2794)
			(stroke
				(width 0.1)
				(type default)
			)
			(layer "B.Fab")
		)
		(fp_line
			(start -0.67945 -0.3048)
			(end -0.67945 0.3048)
			(stroke
				(width 0.1)
				(type default)
			)
			(layer "B.Fab")
		)
		(fp_line
			(start -0.12065 -0.3048)
			(end -0.67945 -0.3048)
			(stroke
				(width 0.1)
				(type default)
			)
			(layer "B.Fab")
		)
		(fp_line
			(start 0.12065 -0.305054)
			(end 0.12065 -0.2794)
			(stroke
				(width 0.1)
				(type default)
			)
			(layer "B.Fab")
		)
		(fp_line
			(start 0.67945 -0.305054)
			(end 0.12065 -0.305054)
			(stroke
				(width 0.1)
				(type default)
			)
			(layer "B.Fab")
		)
		(pad "1" smd circle
			(at 0.40005 0 90)
			(size 0 0)
			(layers "B.Cu" "B.Mask" "B.Paste")
			(net "CPU1_SP5R4")
		)
		(pad "2" smd circle
			(at -0.40005 0 90)
			(size 0 0)
			(layers "B.Cu" "B.Mask" "B.Paste")
			(net "FM_CPU1_SP5R4")
		)
	)
	(footprint ""
		(layer "B.Cu")
		(at 179.354734 -342.261952 -90)
		(property "Reference" "PC526_1"
			(at 0 0 90)
			(layer "B.SilkS")
			(hide yes)
			(effects
				(font
					(size 1.27 1.27)
				)
				(justify mirror)
			)
		)
		(property "Value" ""
			(at 0 0 90)
			(layer "B.Fab")
			(effects
				(font
					(size 1.27 1.27)
				)
				(justify mirror)
			)
		)
		(duplicate_pad_numbers_are_jumpers no)
		(fp_line
			(start -1.524 0.762)
			(end 1.524 0.762)
			(stroke
				(width 0.1524)
				(type default)
			)
			(layer "B.SilkS")
		)
		(fp_line
			(start 1.524 0.762)
			(end 1.524 -0.762)
			(stroke
				(width 0.1524)
				(type default)
			)
			(layer "B.SilkS")
		)
		(fp_line
			(start -1.524 -0.762)
			(end -1.524 0.762)
			(stroke
				(width 0.1524)
				(type default)
			)
			(layer "B.SilkS")
		)
		(fp_line
			(start 1.524 -0.762)
			(end -1.524 -0.762)
			(stroke
				(width 0.1524)
				(type default)
			)
			(layer "B.SilkS")
		)
		(fp_line
			(start -1.1049 0.724916)
			(end -1.1049 -0.724916)
			(stroke
				(width 0.1)
				(type default)
			)
			(layer "B.Fab")
		)
		(fp_line
			(start 1.1049 0.724916)
			(end -1.1049 0.724916)
			(stroke
				(width 0.1)
				(type default)
			)
			(layer "B.Fab")
		)
		(fp_line
			(start -1.1049 -0.724916)
			(end 1.1049 -0.724916)
			(stroke
				(width 0.1)
				(type default)
			)
			(layer "B.Fab")
		)
		(fp_line
			(start 1.1049 -0.724916)
			(end 1.1049 0.724916)
			(stroke
				(width 0.1)
				(type default)
			)
			(layer "B.Fab")
		)
		(pad "1" smd rect
			(at 0.889 0 270)
			(size 1.016 1.27)
			(layers "B.Cu" "B.Mask" "B.Paste")
			(net "PVDD11_S3_P1")
		)
		(pad "2" smd rect
			(at -0.889 0 270)
			(size 1.016 1.27)
			(layers "B.Cu" "B.Mask" "B.Paste")
			(net "GND")
		)
	)
	(footprint ""
		(layer "B.Cu")
		(at 171.577 -100.294948 -90)
		(property "Reference" "R6019"
			(at 0 0 90)
			(layer "B.SilkS")
			(hide yes)
			(effects
				(font
					(size 1.27 1.27)
				)
				(justify mirror)
			)
		)
		(property "Value" ""
			(at 0 0 90)
			(layer "B.Fab")
			(effects
				(font
					(size 1.27 1.27)
				)
				(justify mirror)
			)
		)
		(duplicate_pad_numbers_are_jumpers no)
		(fp_line
			(start -0.7874 0.4064)
			(end 0.7874 0.4064)
			(stroke
				(width 0.1524)
				(type default)
			)
			(layer "B.SilkS")
		)
		(fp_line
			(start 0.7874 0.4064)
			(end 0.7874 -0.4064)
			(stroke
				(width 0.1524)
				(type default)
			)
			(layer "B.SilkS")
		)
		(fp_line
			(start -0.7874 -0.4064)
			(end -0.7874 0.4064)
			(stroke
				(width 0.1524)
				(type default)
			)
			(layer "B.SilkS")
		)
		(fp_line
			(start 0.7874 -0.4064)
			(end -0.7874 -0.4064)
			(stroke
				(width 0.1524)
				(type default)
			)
			(layer "B.SilkS")
		)
		(fp_line
			(start -0.67945 0.3048)
			(end -0.120396 0.3048)
			(stroke
				(width 0.1)
				(type default)
			)
			(layer "B.Fab")
		)
		(fp_line
			(start -0.120396 0.3048)
			(end -0.120396 0.2794)
			(stroke
				(width 0.1)
				(type default)
			)
			(layer "B.Fab")
		)
		(fp_line
			(start 0.12065 0.3048)
			(end 0.67945 0.3048)
			(stroke
				(width 0.1)
				(type default)
			)
			(layer "B.Fab")
		)
		(fp_line
			(start 0.67945 0.3048)
			(end 0.67945 -0.305054)
			(stroke
				(width 0.1)
				(type default)
			)
			(layer "B.Fab")
		)
		(fp_line
			(start -0.120396 0.2794)
			(end 0.12065 0.2794)
			(stroke
				(width 0.1)
				(type default)
			)
			(layer "B.Fab")
		)
		(fp_line
			(start 0.12065 0.2794)
			(end 0.12065 0.3048)
			(stroke
				(width 0.1)
				(type default)
			)
			(layer "B.Fab")
		)
		(fp_line
			(start -0.12065 -0.2794)
			(end -0.12065 -0.3048)
			(stroke
				(width 0.1)
				(type default)
			)
			(layer "B.Fab")
		)
		(fp_line
			(start 0.12065 -0.2794)
			(end -0.12065 -0.2794)
			(stroke
				(width 0.1)
				(type default)
			)
			(layer "B.Fab")
		)
		(fp_line
			(start -0.67945 -0.3048)
			(end -0.67945 0.3048)
			(stroke
				(width 0.1)
				(type default)
			)
			(layer "B.Fab")
		)
		(fp_line
			(start -0.12065 -0.3048)
			(end -0.67945 -0.3048)
			(stroke
				(width 0.1)
				(type default)
			)
			(layer "B.Fab")
		)
		(fp_line
			(start 0.12065 -0.305054)
			(end 0.12065 -0.2794)
			(stroke
				(width 0.1)
				(type default)
			)
			(layer "B.Fab")
		)
		(fp_line
			(start 0.67945 -0.305054)
			(end 0.12065 -0.305054)
			(stroke
				(width 0.1)
				(type default)
			)
			(layer "B.Fab")
		)
		(pad "1" smd circle
			(at 0.40005 0 90)
			(size 0 0)
			(layers "B.Cu" "B.Mask" "B.Paste")
			(net "P3V3_AUX")
		)
		(pad "2" smd circle
			(at -0.40005 0 90)
			(size 0 0)
			(layers "B.Cu" "B.Mask" "B.Paste")
			(net "SGPIO_SCM_LD_<0>")
		)
	)
	(footprint ""
		(layer "B.Cu")
		(at 144.932654 -316.47511 180)
		(property "Reference" "R546"
			(at 0 0 0)
			(layer "B.SilkS")
			(hide yes)
			(effects
				(font
					(size 1.27 1.27)
				)
				(justify mirror)
			)
		)
		(property "Value" ""
			(at 0 0 0)
			(layer "B.Fab")
			(effects
				(font
					(size 1.27 1.27)
				)
				(justify mirror)
			)
		)
		(duplicate_pad_numbers_are_jumpers no)
		(fp_line
			(start 0.7874 0.4064)
			(end 0.7874 -0.4064)
			(stroke
				(width 0.1524)
				(type default)
			)
			(layer "B.SilkS")
		)
		(fp_line
			(start 0.7874 -0.4064)
			(end -0.7874 -0.4064)
			(stroke
				(width 0.1524)
				(type default)
			)
			(layer "B.SilkS")
		)
		(fp_line
			(start -0.7874 0.4064)
			(end 0.7874 0.4064)
			(stroke
				(width 0.1524)
				(type default)
			)
			(layer "B.SilkS")
		)
		(fp_line
			(start -0.7874 -0.4064)
			(end -0.7874 0.4064)
			(stroke
				(width 0.1524)
				(type default)
			)
			(layer "B.SilkS")
		)
		(fp_line
			(start 0.67945 0.3048)
			(end 0.67945 -0.305054)
			(stroke
				(width 0.1)
				(type default)
			)
			(layer "B.Fab")
		)
		(fp_line
			(start 0.67945 -0.305054)
			(end 0.12065 -0.305054)
			(stroke
				(width 0.1)
				(type default)
			)
			(layer "B.Fab")
		)
		(fp_line
			(start 0.12065 0.3048)
			(end 0.67945 0.3048)
			(stroke
				(width 0.1)
				(type default)
			)
			(layer "B.Fab")
		)
		(fp_line
			(start 0.12065 0.2794)
			(end 0.12065 0.3048)
			(stroke
				(width 0.1)
				(type default)
			)
			(layer "B.Fab")
		)
		(fp_line
			(start 0.12065 -0.2794)
			(end -0.12065 -0.2794)
			(stroke
				(width 0.1)
				(type default)
			)
			(layer "B.Fab")
		)
		(fp_line
			(start 0.12065 -0.305054)
			(end 0.12065 -0.2794)
			(stroke
				(width 0.1)
				(type default)
			)
			(layer "B.Fab")
		)
		(fp_line
			(start -0.120396 0.3048)
			(end -0.120396 0.2794)
			(stroke
				(width 0.1)
				(type default)
			)
			(layer "B.Fab")
		)
		(fp_line
			(start -0.120396 0.2794)
			(end 0.12065 0.2794)
			(stroke
				(width 0.1)
				(type default)
			)
			(layer "B.Fab")
		)
		(fp_line
			(start -0.12065 -0.2794)
			(end -0.12065 -0.3048)
			(stroke
				(width 0.1)
				(type default)
			)
			(layer "B.Fab")
		)
		(fp_line
			(start -0.12065 -0.3048)
			(end -0.67945 -0.3048)
			(stroke
				(width 0.1)
				(type default)
			)
			(layer "B.Fab")
		)
		(fp_line
			(start -0.67945 0.3048)
			(end -0.120396 0.3048)
			(stroke
				(width 0.1)
				(type default)
			)
			(layer "B.Fab")
		)
		(fp_line
			(start -0.67945 -0.3048)
			(end -0.67945 0.3048)
			(stroke
				(width 0.1)
				(type default)
			)
			(layer "B.Fab")
		)
		(pad "1" smd circle
			(at 0.40005 0)
			(size 0 0)
			(layers "B.Cu" "B.Mask" "B.Paste")
			(net "FM_BMC_TPM_PRES_N")
		)
		(pad "2" smd circle
			(at -0.40005 0)
			(size 0 0)
			(layers "B.Cu" "B.Mask" "B.Paste")
			(net "PVDD18_S5_P1")
		)
	)
	(footprint ""
		(layer "B.Cu")
		(at 66.745358 -390.560052 90)
		(property "Reference" "C262"
			(at 0 0 90)
			(layer "B.SilkS")
			(hide yes)
			(effects
				(font
					(size 1.27 1.27)
				)
				(justify mirror)
			)
		)
		(property "Value" ""
			(at 0 0 90)
			(layer "B.Fab")
			(effects
				(font
					(size 1.27 1.27)
				)
				(justify mirror)
			)
		)
		(duplicate_pad_numbers_are_jumpers no)
		(fp_line
			(start 0.7874 -0.4064)
			(end -0.7874 -0.4064)
			(stroke
				(width 0.1524)
				(type default)
			)
			(layer "B.SilkS")
		)
		(fp_line
			(start -0.7874 -0.4064)
			(end -0.7874 0.4064)
			(stroke
				(width 0.1524)
				(type default)
			)
			(layer "B.SilkS")
		)
		(fp_line
			(start 0.7874 0.4064)
			(end 0.7874 -0.4064)
			(stroke
				(width 0.1524)
				(type default)
			)
			(layer "B.SilkS")
		)
		(fp_line
			(start -0.7874 0.4064)
			(end 0.7874 0.4064)
			(stroke
				(width 0.1524)
				(type default)
			)
			(layer "B.SilkS")
		)
		(fp_line
			(start 0.67945 -0.305054)
			(end 0.12065 -0.305054)
			(stroke
				(width 0.1)
				(type default)
			)
			(layer "B.Fab")
		)
		(fp_line
			(start 0.12065 -0.305054)
			(end 0.12065 -0.2794)
			(stroke
				(width 0.1)
				(type default)
			)
			(layer "B.Fab")
		)
		(fp_line
			(start -0.12065 -0.3048)
			(end -0.67945 -0.3048)
			(stroke
				(width 0.1)
				(type default)
			)
			(layer "B.Fab")
		)
		(fp_line
			(start -0.67945 -0.3048)
			(end -0.67945 0.3048)
			(stroke
				(width 0.1)
				(type default)
			)
			(layer "B.Fab")
		)
		(fp_line
			(start 0.12065 -0.2794)
			(end -0.12065 -0.2794)
			(stroke
				(width 0.1)
				(type default)
			)
			(layer "B.Fab")
		)
		(fp_line
			(start -0.12065 -0.2794)
			(end -0.12065 -0.3048)
			(stroke
				(width 0.1)
				(type default)
			)
			(layer "B.Fab")
		)
		(fp_line
			(start 0.12065 0.2794)
			(end 0.12065 0.3048)
			(stroke
				(width 0.1)
				(type default)
			)
			(layer "B.Fab")
		)
		(fp_line
			(start -0.120396 0.2794)
			(end 0.12065 0.2794)
			(stroke
				(width 0.1)
				(type default)
			)
			(layer "B.Fab")
		)
		(fp_line
			(start 0.67945 0.3048)
			(end 0.67945 -0.305054)
			(stroke
				(width 0.1)
				(type default)
			)
			(layer "B.Fab")
		)
		(fp_line
			(start 0.12065 0.3048)
			(end 0.67945 0.3048)
			(stroke
				(width 0.1)
				(type default)
			)
			(layer "B.Fab")
		)
		(fp_line
			(start -0.120396 0.3048)
			(end -0.120396 0.2794)
			(stroke
				(width 0.1)
				(type default)
			)
			(layer "B.Fab")
		)
		(fp_line
			(start -0.67945 0.3048)
			(end -0.120396 0.3048)
			(stroke
				(width 0.1)
				(type default)
			)
			(layer "B.Fab")
		)
		(pad "1" smd circle
			(at 0.40005 0 270)
			(size 0 0)
			(layers "B.Cu" "B.Mask" "B.Paste")
			(net "P0V9_CPU1_RT0_2A")
		)
		(pad "2" smd circle
			(at -0.40005 0 270)
			(size 0 0)
			(layers "B.Cu" "B.Mask" "B.Paste")
			(net "GND")
		)
	)
	(footprint ""
		(layer "B.Cu")
		(at 355.944932 -396.150592 180)
		(property "Reference" "C658"
			(at 0 0 0)
			(layer "B.SilkS")
			(hide yes)
			(effects
				(font
					(size 1.27 1.27)
				)
				(justify mirror)
			)
		)
		(property "Value" ""
			(at 0 0 0)
			(layer "B.Fab")
			(effects
				(font
					(size 1.27 1.27)
				)
				(justify mirror)
			)
		)
		(duplicate_pad_numbers_are_jumpers no)
		(fp_line
			(start 0.299974 0.150114)
			(end 0.299974 -0.150114)
			(stroke
				(width 0.1)
				(type default)
			)
			(layer "B.Fab")
		)
		(fp_line
			(start 0.299974 -0.150114)
			(end -0.299974 -0.150114)
			(stroke
				(width 0.1)
				(type default)
			)
			(layer "B.Fab")
		)
		(fp_line
			(start -0.299974 0.150114)
			(end 0.299974 0.150114)
			(stroke
				(width 0.1)
				(type default)
			)
			(layer "B.Fab")
		)
		(fp_line
			(start -0.299974 -0.150114)
			(end -0.299974 0.150114)
			(stroke
				(width 0.1)
				(type default)
			)
			(layer "B.Fab")
		)
		(pad "1" smd rect
			(at 0.2667 0)
			(size 0.3048 0.381)
			(layers "B.Cu" "B.Mask" "B.Paste")
			(net "P0V9_CPU0_RT1_2A")
		)
		(pad "2" smd rect
			(at -0.2667 0)
			(size 0.3048 0.381)
			(layers "B.Cu" "B.Mask" "B.Paste")
			(net "GND")
		)
	)
	(footprint ""
		(layer "B.Cu")
		(at 216.142824 -328.032872 180)
		(property "Reference" "R1241"
			(at 0 0 0)
			(layer "B.SilkS")
			(hide yes)
			(effects
				(font
					(size 1.27 1.27)
				)
				(justify mirror)
			)
		)
		(property "Value" ""
			(at 0 0 0)
			(layer "B.Fab")
			(effects
				(font
					(size 1.27 1.27)
				)
				(justify mirror)
			)
		)
		(duplicate_pad_numbers_are_jumpers no)
		(fp_line
			(start 0.7874 0.4064)
			(end 0.7874 -0.4064)
			(stroke
				(width 0.1524)
				(type default)
			)
			(layer "B.SilkS")
		)
		(fp_line
			(start 0.7874 -0.4064)
			(end -0.7874 -0.4064)
			(stroke
				(width 0.1524)
				(type default)
			)
			(layer "B.SilkS")
		)
		(fp_line
			(start -0.7874 0.4064)
			(end 0.7874 0.4064)
			(stroke
				(width 0.1524)
				(type default)
			)
			(layer "B.SilkS")
		)
		(fp_line
			(start -0.7874 -0.4064)
			(end -0.7874 0.4064)
			(stroke
				(width 0.1524)
				(type default)
			)
			(layer "B.SilkS")
		)
		(fp_line
			(start 0.67945 0.3048)
			(end 0.67945 -0.305054)
			(stroke
				(width 0.1)
				(type default)
			)
			(layer "B.Fab")
		)
		(fp_line
			(start 0.67945 -0.305054)
			(end 0.12065 -0.305054)
			(stroke
				(width 0.1)
				(type default)
			)
			(layer "B.Fab")
		)
		(fp_line
			(start 0.12065 0.3048)
			(end 0.67945 0.3048)
			(stroke
				(width 0.1)
				(type default)
			)
			(layer "B.Fab")
		)
		(fp_line
			(start 0.12065 0.2794)
			(end 0.12065 0.3048)
			(stroke
				(width 0.1)
				(type default)
			)
			(layer "B.Fab")
		)
		(fp_line
			(start 0.12065 -0.2794)
			(end -0.12065 -0.2794)
			(stroke
				(width 0.1)
				(type default)
			)
			(layer "B.Fab")
		)
		(fp_line
			(start 0.12065 -0.305054)
			(end 0.12065 -0.2794)
			(stroke
				(width 0.1)
				(type default)
			)
			(layer "B.Fab")
		)
		(fp_line
			(start -0.120396 0.3048)
			(end -0.120396 0.2794)
			(stroke
				(width 0.1)
				(type default)
			)
			(layer "B.Fab")
		)
		(fp_line
			(start -0.120396 0.2794)
			(end 0.12065 0.2794)
			(stroke
				(width 0.1)
				(type default)
			)
			(layer "B.Fab")
		)
		(fp_line
			(start -0.12065 -0.2794)
			(end -0.12065 -0.3048)
			(stroke
				(width 0.1)
				(type default)
			)
			(layer "B.Fab")
		)
		(fp_line
			(start -0.12065 -0.3048)
			(end -0.67945 -0.3048)
			(stroke
				(width 0.1)
				(type default)
			)
			(layer "B.Fab")
		)
		(fp_line
			(start -0.67945 0.3048)
			(end -0.120396 0.3048)
			(stroke
				(width 0.1)
				(type default)
			)
			(layer "B.Fab")
		)
		(fp_line
			(start -0.67945 -0.3048)
			(end -0.67945 0.3048)
			(stroke
				(width 0.1)
				(type default)
			)
			(layer "B.Fab")
		)
		(pad "1" smd circle
			(at 0.40005 0)
			(size 0 0)
			(layers "B.Cu" "B.Mask" "B.Paste")
			(net "P3V3_AUX")
		)
		(pad "2" smd circle
			(at -0.40005 0)
			(size 0 0)
			(layers "B.Cu" "B.Mask" "B.Paste")
			(net "ADC128_2_A0")
		)
	)
	(footprint ""
		(layer "B.Cu")
		(at 20.32 -366.903)
		(property "Reference" "R1495"
			(at 0 0 0)
			(layer "B.SilkS")
			(hide yes)
			(effects
				(font
					(size 1.27 1.27)
				)
				(justify mirror)
			)
		)
		(property "Value" ""
			(at 0 0 0)
			(layer "B.Fab")
			(effects
				(font
					(size 1.27 1.27)
				)
				(justify mirror)
			)
		)
		(duplicate_pad_numbers_are_jumpers no)
		(fp_line
			(start -0.7874 -0.4064)
			(end -0.7874 0.4064)
			(stroke
				(width 0.1524)
				(type default)
			)
			(layer "B.SilkS")
		)
		(fp_line
			(start -0.7874 0.4064)
			(end 0.7874 0.4064)
			(stroke
				(width 0.1524)
				(type default)
			)
			(layer "B.SilkS")
		)
		(fp_line
			(start 0.7874 -0.4064)
			(end -0.7874 -0.4064)
			(stroke
				(width 0.1524)
				(type default)
			)
			(layer "B.SilkS")
		)
		(fp_line
			(start 0.7874 0.4064)
			(end 0.7874 -0.4064)
			(stroke
				(width 0.1524)
				(type default)
			)
			(layer "B.SilkS")
		)
		(fp_line
			(start -0.67945 -0.3048)
			(end -0.67945 0.3048)
			(stroke
				(width 0.1)
				(type default)
			)
			(layer "B.Fab")
		)
		(fp_line
			(start -0.67945 0.3048)
			(end -0.120396 0.3048)
			(stroke
				(width 0.1)
				(type default)
			)
			(layer "B.Fab")
		)
		(fp_line
			(start -0.12065 -0.3048)
			(end -0.67945 -0.3048)
			(stroke
				(width 0.1)
				(type default)
			)
			(layer "B.Fab")
		)
		(fp_line
			(start -0.12065 -0.2794)
			(end -0.12065 -0.3048)
			(stroke
				(width 0.1)
				(type default)
			)
			(layer "B.Fab")
		)
		(fp_line
			(start -0.120396 0.2794)
			(end 0.12065 0.2794)
			(stroke
				(width 0.1)
				(type default)
			)
			(layer "B.Fab")
		)
		(fp_line
			(start -0.120396 0.3048)
			(end -0.120396 0.2794)
			(stroke
				(width 0.1)
				(type default)
			)
			(layer "B.Fab")
		)
		(fp_line
			(start 0.12065 -0.305054)
			(end 0.12065 -0.2794)
			(stroke
				(width 0.1)
				(type default)
			)
			(layer "B.Fab")
		)
		(fp_line
			(start 0.12065 -0.2794)
			(end -0.12065 -0.2794)
			(stroke
				(width 0.1)
				(type default)
			)
			(layer "B.Fab")
		)
		(fp_line
			(start 0.12065 0.2794)
			(end 0.12065 0.3048)
			(stroke
				(width 0.1)
				(type default)
			)
			(layer "B.Fab")
		)
		(fp_line
			(start 0.12065 0.3048)
			(end 0.67945 0.3048)
			(stroke
				(width 0.1)
				(type default)
			)
			(layer "B.Fab")
		)
		(fp_line
			(start 0.67945 -0.305054)
			(end 0.12065 -0.305054)
			(stroke
				(width 0.1)
				(type default)
			)
			(layer "B.Fab")
		)
		(fp_line
			(start 0.67945 0.3048)
			(end 0.67945 -0.305054)
			(stroke
				(width 0.1)
				(type default)
			)
			(layer "B.Fab")
		)
		(pad "1" smd circle
			(at 0.40005 0 180)
			(size 0 0)
			(layers "B.Cu" "B.Mask" "B.Paste")
			(net "SMB_SCM_2_R1_SCL")
		)
		(pad "2" smd circle
			(at -0.40005 0 180)
			(size 0 0)
			(layers "B.Cu" "B.Mask" "B.Paste")
			(net "SMB_SCM_2_R2_SCL")
		)
	)
	(footprint ""
		(layer "B.Cu")
		(at 171.199048 -105.121202 180)
		(property "Reference" "R205"
			(at 0 0 0)
			(layer "B.SilkS")
			(hide yes)
			(effects
				(font
					(size 1.27 1.27)
				)
				(justify mirror)
			)
		)
		(property "Value" ""
			(at 0 0 0)
			(layer "B.Fab")
			(effects
				(font
					(size 1.27 1.27)
				)
				(justify mirror)
			)
		)
		(duplicate_pad_numbers_are_jumpers no)
		(fp_line
			(start 0.7874 0.4064)
			(end 0.7874 -0.4064)
			(stroke
				(width 0.1524)
				(type default)
			)
			(layer "B.SilkS")
		)
		(fp_line
			(start 0.7874 -0.4064)
			(end -0.7874 -0.4064)
			(stroke
				(width 0.1524)
				(type default)
			)
			(layer "B.SilkS")
		)
		(fp_line
			(start -0.7874 0.4064)
			(end 0.7874 0.4064)
			(stroke
				(width 0.1524)
				(type default)
			)
			(layer "B.SilkS")
		)
		(fp_line
			(start -0.7874 -0.4064)
			(end -0.7874 0.4064)
			(stroke
				(width 0.1524)
				(type default)
			)
			(layer "B.SilkS")
		)
		(fp_line
			(start 0.67945 0.3048)
			(end 0.67945 -0.305054)
			(stroke
				(width 0.1)
				(type default)
			)
			(layer "B.Fab")
		)
		(fp_line
			(start 0.67945 -0.305054)
			(end 0.12065 -0.305054)
			(stroke
				(width 0.1)
				(type default)
			)
			(layer "B.Fab")
		)
		(fp_line
			(start 0.12065 0.3048)
			(end 0.67945 0.3048)
			(stroke
				(width 0.1)
				(type default)
			)
			(layer "B.Fab")
		)
		(fp_line
			(start 0.12065 0.2794)
			(end 0.12065 0.3048)
			(stroke
				(width 0.1)
				(type default)
			)
			(layer "B.Fab")
		)
		(fp_line
			(start 0.12065 -0.2794)
			(end -0.12065 -0.2794)
			(stroke
				(width 0.1)
				(type default)
			)
			(layer "B.Fab")
		)
		(fp_line
			(start 0.12065 -0.305054)
			(end 0.12065 -0.2794)
			(stroke
				(width 0.1)
				(type default)
			)
			(layer "B.Fab")
		)
		(fp_line
			(start -0.120396 0.3048)
			(end -0.120396 0.2794)
			(stroke
				(width 0.1)
				(type default)
			)
			(layer "B.Fab")
		)
		(fp_line
			(start -0.120396 0.2794)
			(end 0.12065 0.2794)
			(stroke
				(width 0.1)
				(type default)
			)
			(layer "B.Fab")
		)
		(fp_line
			(start -0.12065 -0.2794)
			(end -0.12065 -0.3048)
			(stroke
				(width 0.1)
				(type default)
			)
			(layer "B.Fab")
		)
		(fp_line
			(start -0.12065 -0.3048)
			(end -0.67945 -0.3048)
			(stroke
				(width 0.1)
				(type default)
			)
			(layer "B.Fab")
		)
		(fp_line
			(start -0.67945 0.3048)
			(end -0.120396 0.3048)
			(stroke
				(width 0.1)
				(type default)
			)
			(layer "B.Fab")
		)
		(fp_line
			(start -0.67945 -0.3048)
			(end -0.67945 0.3048)
			(stroke
				(width 0.1)
				(type default)
			)
			(layer "B.Fab")
		)
		(pad "1" smd circle
			(at 0.40005 0)
			(size 0 0)
			(layers "B.Cu" "B.Mask" "B.Paste")
			(net "CPU1_XTRIG_L5")
		)
		(pad "2" smd circle
			(at -0.40005 0)
			(size 0 0)
			(layers "B.Cu" "B.Mask" "B.Paste")
			(net "FM_CPU1_XTRIG_L5")
		)
	)
	(footprint ""
		(layer "B.Cu")
		(at 459.339188 -389.132064 -90)
		(property "Reference" "PC6566_1"
			(at 0 0 90)
			(layer "B.SilkS")
			(hide yes)
			(effects
				(font
					(size 1.27 1.27)
				)
				(justify mirror)
			)
		)
		(property "Value" ""
			(at 0 0 90)
			(layer "B.Fab")
			(effects
				(font
					(size 1.27 1.27)
				)
				(justify mirror)
			)
		)
		(duplicate_pad_numbers_are_jumpers no)
		(fp_line
			(start -1.524 0.762)
			(end 1.524 0.762)
			(stroke
				(width 0.1524)
				(type default)
			)
			(layer "B.SilkS")
		)
		(fp_line
			(start 1.524 0.762)
			(end 1.524 -0.762)
			(stroke
				(width 0.1524)
				(type default)
			)
			(layer "B.SilkS")
		)
		(fp_line
			(start -1.524 -0.762)
			(end -1.524 0.762)
			(stroke
				(width 0.1524)
				(type default)
			)
			(layer "B.SilkS")
		)
		(fp_line
			(start 1.524 -0.762)
			(end -1.524 -0.762)
			(stroke
				(width 0.1524)
				(type default)
			)
			(layer "B.SilkS")
		)
		(fp_line
			(start -1.1049 0.724916)
			(end -1.1049 -0.724916)
			(stroke
				(width 0.1)
				(type default)
			)
			(layer "B.Fab")
		)
		(fp_line
			(start 1.1049 0.724916)
			(end -1.1049 0.724916)
			(stroke
				(width 0.1)
				(type default)
			)
			(layer "B.Fab")
		)
		(fp_line
			(start -1.1049 -0.724916)
			(end 1.1049 -0.724916)
			(stroke
				(width 0.1)
				(type default)
			)
			(layer "B.Fab")
		)
		(fp_line
			(start 1.1049 -0.724916)
			(end 1.1049 0.724916)
			(stroke
				(width 0.1)
				(type default)
			)
			(layer "B.Fab")
		)
		(pad "1" smd rect
			(at 0.889 0 270)
			(size 1.016 1.27)
			(layers "B.Cu" "B.Mask" "B.Paste")
			(net "P0V9_CPU0_RT_2D")
		)
		(pad "2" smd rect
			(at -0.889 0 270)
			(size 1.016 1.27)
			(layers "B.Cu" "B.Mask" "B.Paste")
			(net "GND")
		)
	)
	(footprint ""
		(layer "B.Cu")
		(at 371.650006 -178.994816 90)
		(property "Reference" "PC484_2"
			(at 0 0 90)
			(layer "B.SilkS")
			(hide yes)
			(effects
				(font
					(size 1.27 1.27)
				)
				(justify mirror)
			)
		)
		(property "Value" ""
			(at 0 0 90)
			(layer "B.Fab")
			(effects
				(font
					(size 1.27 1.27)
				)
				(justify mirror)
			)
		)
		(duplicate_pad_numbers_are_jumpers no)
		(fp_line
			(start 1.524 -0.762)
			(end -1.524 -0.762)
			(stroke
				(width 0.1524)
				(type default)
			)
			(layer "B.SilkS")
		)
		(fp_line
			(start -1.524 -0.762)
			(end -1.524 0.762)
			(stroke
				(width 0.1524)
				(type default)
			)
			(layer "B.SilkS")
		)
		(fp_line
			(start 1.524 0.762)
			(end 1.524 -0.762)
			(stroke
				(width 0.1524)
				(type default)
			)
			(layer "B.SilkS")
		)
		(fp_line
			(start -1.524 0.762)
			(end 1.524 0.762)
			(stroke
				(width 0.1524)
				(type default)
			)
			(layer "B.SilkS")
		)
		(fp_line
			(start 1.1049 -0.724916)
			(end 1.1049 0.724916)
			(stroke
				(width 0.1)
				(type default)
			)
			(layer "B.Fab")
		)
		(fp_line
			(start -1.1049 -0.724916)
			(end 1.1049 -0.724916)
			(stroke
				(width 0.1)
				(type default)
			)
			(layer "B.Fab")
		)
		(fp_line
			(start 1.1049 0.724916)
			(end -1.1049 0.724916)
			(stroke
				(width 0.1)
				(type default)
			)
			(layer "B.Fab")
		)
		(fp_line
			(start -1.1049 0.724916)
			(end -1.1049 -0.724916)
			(stroke
				(width 0.1)
				(type default)
			)
			(layer "B.Fab")
		)
		(pad "1" smd rect
			(at 0.889 0 90)
			(size 1.016 1.27)
			(layers "B.Cu" "B.Mask" "B.Paste")
			(net "SW_P12V_AUX_PVDDCR_CPU0_P0_FLT")
		)
		(pad "2" smd rect
			(at -0.889 0 90)
			(size 1.016 1.27)
			(layers "B.Cu" "B.Mask" "B.Paste")
			(net "GND")
		)
	)
	(footprint ""
		(layer "B.Cu")
		(at 371.678454 -395.148562 90)
		(property "Reference" "C1031"
			(at 0 0 90)
			(layer "B.SilkS")
			(hide yes)
			(effects
				(font
					(size 1.27 1.27)
				)
				(justify mirror)
			)
		)
		(property "Value" ""
			(at 0 0 90)
			(layer "B.Fab")
			(effects
				(font
					(size 1.27 1.27)
				)
				(justify mirror)
			)
		)
		(duplicate_pad_numbers_are_jumpers no)
		(fp_line
			(start 0.299974 -0.150114)
			(end -0.299974 -0.150114)
			(stroke
				(width 0.1)
				(type default)
			)
			(layer "B.Fab")
		)
		(fp_line
			(start -0.299974 -0.150114)
			(end -0.299974 0.150114)
			(stroke
				(width 0.1)
				(type default)
			)
			(layer "B.Fab")
		)
		(fp_line
			(start 0.299974 0.150114)
			(end 0.299974 -0.150114)
			(stroke
				(width 0.1)
				(type default)
			)
			(layer "B.Fab")
		)
		(fp_line
			(start -0.299974 0.150114)
			(end 0.299974 0.150114)
			(stroke
				(width 0.1)
				(type default)
			)
			(layer "B.Fab")
		)
		(pad "1" smd rect
			(at 0.2667 0 270)
			(size 0.3048 0.381)
			(layers "B.Cu" "B.Mask" "B.Paste")
			(net "P0V9_CPU0_RT3_2A")
		)
		(pad "2" smd rect
			(at -0.2667 0 270)
			(size 0.3048 0.381)
			(layers "B.Cu" "B.Mask" "B.Paste")
			(net "GND")
		)
	)
	(footprint ""
		(layer "B.Cu")
		(at 363.010958 -246.376952 180)
		(property "Reference" "C2185"
			(at 0 0 0)
			(layer "B.SilkS")
			(hide yes)
			(effects
				(font
					(size 1.27 1.27)
				)
				(justify mirror)
			)
		)
		(property "Value" ""
			(at 0 0 0)
			(layer "B.Fab")
			(effects
				(font
					(size 1.27 1.27)
				)
				(justify mirror)
			)
		)
		(duplicate_pad_numbers_are_jumpers no)
		(fp_line
			(start 0.7874 0.4064)
			(end 0.7874 -0.4064)
			(stroke
				(width 0.1524)
				(type default)
			)
			(layer "B.SilkS")
		)
		(fp_line
			(start 0.7874 -0.4064)
			(end -0.7874 -0.4064)
			(stroke
				(width 0.1524)
				(type default)
			)
			(layer "B.SilkS")
		)
		(fp_line
			(start -0.7874 0.4064)
			(end 0.7874 0.4064)
			(stroke
				(width 0.1524)
				(type default)
			)
			(layer "B.SilkS")
		)
		(fp_line
			(start -0.7874 -0.4064)
			(end -0.7874 0.4064)
			(stroke
				(width 0.1524)
				(type default)
			)
			(layer "B.SilkS")
		)
		(fp_line
			(start 0.67945 0.3048)
			(end 0.67945 -0.305054)
			(stroke
				(width 0.1)
				(type default)
			)
			(layer "B.Fab")
		)
		(fp_line
			(start 0.67945 -0.305054)
			(end 0.12065 -0.305054)
			(stroke
				(width 0.1)
				(type default)
			)
			(layer "B.Fab")
		)
		(fp_line
			(start 0.12065 0.3048)
			(end 0.67945 0.3048)
			(stroke
				(width 0.1)
				(type default)
			)
			(layer "B.Fab")
		)
		(fp_line
			(start 0.12065 0.2794)
			(end 0.12065 0.3048)
			(stroke
				(width 0.1)
				(type default)
			)
			(layer "B.Fab")
		)
		(fp_line
			(start 0.12065 -0.2794)
			(end -0.12065 -0.2794)
			(stroke
				(width 0.1)
				(type default)
			)
			(layer "B.Fab")
		)
		(fp_line
			(start 0.12065 -0.305054)
			(end 0.12065 -0.2794)
			(stroke
				(width 0.1)
				(type default)
			)
			(layer "B.Fab")
		)
		(fp_line
			(start -0.120396 0.3048)
			(end -0.120396 0.2794)
			(stroke
				(width 0.1)
				(type default)
			)
			(layer "B.Fab")
		)
		(fp_line
			(start -0.120396 0.2794)
			(end 0.12065 0.2794)
			(stroke
				(width 0.1)
				(type default)
			)
			(layer "B.Fab")
		)
		(fp_line
			(start -0.12065 -0.2794)
			(end -0.12065 -0.3048)
			(stroke
				(width 0.1)
				(type default)
			)
			(layer "B.Fab")
		)
		(fp_line
			(start -0.12065 -0.3048)
			(end -0.67945 -0.3048)
			(stroke
				(width 0.1)
				(type default)
			)
			(layer "B.Fab")
		)
		(fp_line
			(start -0.67945 0.3048)
			(end -0.120396 0.3048)
			(stroke
				(width 0.1)
				(type default)
			)
			(layer "B.Fab")
		)
		(fp_line
			(start -0.67945 -0.3048)
			(end -0.67945 0.3048)
			(stroke
				(width 0.1)
				(type default)
			)
			(layer "B.Fab")
		)
		(pad "1" smd circle
			(at 0.40005 0)
			(size 0 0)
			(layers "B.Cu" "B.Mask" "B.Paste")
			(net "PVDDCR_CPU0_P0")
		)
		(pad "2" smd circle
			(at -0.40005 0)
			(size 0 0)
			(layers "B.Cu" "B.Mask" "B.Paste")
			(net "GND")
		)
	)
	(footprint ""
		(layer "B.Cu")
		(at 299.06849 -194.893946 180)
		(property "Reference" "R1569"
			(at 0 0 0)
			(layer "B.SilkS")
			(hide yes)
			(effects
				(font
					(size 1.27 1.27)
				)
				(justify mirror)
			)
		)
		(property "Value" ""
			(at 0 0 0)
			(layer "B.Fab")
			(effects
				(font
					(size 1.27 1.27)
				)
				(justify mirror)
			)
		)
		(duplicate_pad_numbers_are_jumpers no)
		(fp_line
			(start 0.7874 0.4064)
			(end 0.7874 -0.4064)
			(stroke
				(width 0.1524)
				(type default)
			)
			(layer "B.SilkS")
		)
		(fp_line
			(start 0.7874 -0.4064)
			(end -0.7874 -0.4064)
			(stroke
				(width 0.1524)
				(type default)
			)
			(layer "B.SilkS")
		)
		(fp_line
			(start -0.7874 0.4064)
			(end 0.7874 0.4064)
			(stroke
				(width 0.1524)
				(type default)
			)
			(layer "B.SilkS")
		)
		(fp_line
			(start -0.7874 -0.4064)
			(end -0.7874 0.4064)
			(stroke
				(width 0.1524)
				(type default)
			)
			(layer "B.SilkS")
		)
		(fp_line
			(start 0.67945 0.3048)
			(end 0.67945 -0.305054)
			(stroke
				(width 0.1)
				(type default)
			)
			(layer "B.Fab")
		)
		(fp_line
			(start 0.67945 -0.305054)
			(end 0.12065 -0.305054)
			(stroke
				(width 0.1)
				(type default)
			)
			(layer "B.Fab")
		)
		(fp_line
			(start 0.12065 0.3048)
			(end 0.67945 0.3048)
			(stroke
				(width 0.1)
				(type default)
			)
			(layer "B.Fab")
		)
		(fp_line
			(start 0.12065 0.2794)
			(end 0.12065 0.3048)
			(stroke
				(width 0.1)
				(type default)
			)
			(layer "B.Fab")
		)
		(fp_line
			(start 0.12065 -0.2794)
			(end -0.12065 -0.2794)
			(stroke
				(width 0.1)
				(type default)
			)
			(layer "B.Fab")
		)
		(fp_line
			(start 0.12065 -0.305054)
			(end 0.12065 -0.2794)
			(stroke
				(width 0.1)
				(type default)
			)
			(layer "B.Fab")
		)
		(fp_line
			(start -0.120396 0.3048)
			(end -0.120396 0.2794)
			(stroke
				(width 0.1)
				(type default)
			)
			(layer "B.Fab")
		)
		(fp_line
			(start -0.120396 0.2794)
			(end 0.12065 0.2794)
			(stroke
				(width 0.1)
				(type default)
			)
			(layer "B.Fab")
		)
		(fp_line
			(start -0.12065 -0.2794)
			(end -0.12065 -0.3048)
			(stroke
				(width 0.1)
				(type default)
			)
			(layer "B.Fab")
		)
		(fp_line
			(start -0.12065 -0.3048)
			(end -0.67945 -0.3048)
			(stroke
				(width 0.1)
				(type default)
			)
			(layer "B.Fab")
		)
		(fp_line
			(start -0.67945 0.3048)
			(end -0.120396 0.3048)
			(stroke
				(width 0.1)
				(type default)
			)
			(layer "B.Fab")
		)
		(fp_line
			(start -0.67945 -0.3048)
			(end -0.67945 0.3048)
			(stroke
				(width 0.1)
				(type default)
			)
			(layer "B.Fab")
		)
		(pad "1" smd circle
			(at 0.40005 0)
			(size 0 0)
			(layers "B.Cu" "B.Mask" "B.Paste")
			(net "I3C_SPD_DDRAF_CPU0_SCL")
		)
		(pad "2" smd circle
			(at -0.40005 0)
			(size 0 0)
			(layers "B.Cu" "B.Mask" "B.Paste")
			(net "I3C_SPD_DDRB_CPU0_SCL")
		)
	)
	(footprint ""
		(layer "B.Cu")
		(at 239.649 -227.203 180)
		(property "Reference" "R790"
			(at 0 0 0)
			(layer "B.SilkS")
			(hide yes)
			(effects
				(font
					(size 1.27 1.27)
				)
				(justify mirror)
			)
		)
		(property "Value" ""
			(at 0 0 0)
			(layer "B.Fab")
			(effects
				(font
					(size 1.27 1.27)
				)
				(justify mirror)
			)
		)
		(duplicate_pad_numbers_are_jumpers no)
		(fp_line
			(start 0.7874 0.4064)
			(end 0.7874 -0.4064)
			(stroke
				(width 0.1524)
				(type default)
			)
			(layer "B.SilkS")
		)
		(fp_line
			(start 0.7874 -0.4064)
			(end -0.7874 -0.4064)
			(stroke
				(width 0.1524)
				(type default)
			)
			(layer "B.SilkS")
		)
		(fp_line
			(start -0.7874 0.4064)
			(end 0.7874 0.4064)
			(stroke
				(width 0.1524)
				(type default)
			)
			(layer "B.SilkS")
		)
		(fp_line
			(start -0.7874 -0.4064)
			(end -0.7874 0.4064)
			(stroke
				(width 0.1524)
				(type default)
			)
			(layer "B.SilkS")
		)
		(fp_line
			(start 0.67945 0.3048)
			(end 0.67945 -0.305054)
			(stroke
				(width 0.1)
				(type default)
			)
			(layer "B.Fab")
		)
		(fp_line
			(start 0.67945 -0.305054)
			(end 0.12065 -0.305054)
			(stroke
				(width 0.1)
				(type default)
			)
			(layer "B.Fab")
		)
		(fp_line
			(start 0.12065 0.3048)
			(end 0.67945 0.3048)
			(stroke
				(width 0.1)
				(type default)
			)
			(layer "B.Fab")
		)
		(fp_line
			(start 0.12065 0.2794)
			(end 0.12065 0.3048)
			(stroke
				(width 0.1)
				(type default)
			)
			(layer "B.Fab")
		)
		(fp_line
			(start 0.12065 -0.2794)
			(end -0.12065 -0.2794)
			(stroke
				(width 0.1)
				(type default)
			)
			(layer "B.Fab")
		)
		(fp_line
			(start 0.12065 -0.305054)
			(end 0.12065 -0.2794)
			(stroke
				(width 0.1)
				(type default)
			)
			(layer "B.Fab")
		)
		(fp_line
			(start -0.120396 0.3048)
			(end -0.120396 0.2794)
			(stroke
				(width 0.1)
				(type default)
			)
			(layer "B.Fab")
		)
		(fp_line
			(start -0.120396 0.2794)
			(end 0.12065 0.2794)
			(stroke
				(width 0.1)
				(type default)
			)
			(layer "B.Fab")
		)
		(fp_line
			(start -0.12065 -0.2794)
			(end -0.12065 -0.3048)
			(stroke
				(width 0.1)
				(type default)
			)
			(layer "B.Fab")
		)
		(fp_line
			(start -0.12065 -0.3048)
			(end -0.67945 -0.3048)
			(stroke
				(width 0.1)
				(type default)
			)
			(layer "B.Fab")
		)
		(fp_line
			(start -0.67945 0.3048)
			(end -0.120396 0.3048)
			(stroke
				(width 0.1)
				(type default)
			)
			(layer "B.Fab")
		)
		(fp_line
			(start -0.67945 -0.3048)
			(end -0.67945 0.3048)
			(stroke
				(width 0.1)
				(type default)
			)
			(layer "B.Fab")
		)
		(pad "1" smd circle
			(at 0.40005 0)
			(size 0 0)
			(layers "B.Cu" "B.Mask" "B.Paste")
			(net "SMB_CPU0_CPU1_APML_BUF1_SDA")
		)
		(pad "2" smd circle
			(at -0.40005 0)
			(size 0 0)
			(layers "B.Cu" "B.Mask" "B.Paste")
			(net "SMB_CPU0_CPU1_APML_BUF1_SDA_R1")
		)
	)
	(footprint ""
		(layer "B.Cu")
		(at 167.936418 -350.732344)
		(property "Reference" "PR388"
			(at 0 0 0)
			(layer "B.SilkS")
			(hide yes)
			(effects
				(font
					(size 1.27 1.27)
				)
				(justify mirror)
			)
		)
		(property "Value" ""
			(at 0 0 0)
			(layer "B.Fab")
			(effects
				(font
					(size 1.27 1.27)
				)
				(justify mirror)
			)
		)
		(duplicate_pad_numbers_are_jumpers no)
		(fp_line
			(start -0.7874 -0.4064)
			(end -0.7874 0.4064)
			(stroke
				(width 0.1524)
				(type default)
			)
			(layer "B.SilkS")
		)
		(fp_line
			(start -0.7874 0.4064)
			(end 0.7874 0.4064)
			(stroke
				(width 0.1524)
				(type default)
			)
			(layer "B.SilkS")
		)
		(fp_line
			(start 0.7874 -0.4064)
			(end -0.7874 -0.4064)
			(stroke
				(width 0.1524)
				(type default)
			)
			(layer "B.SilkS")
		)
		(fp_line
			(start 0.7874 0.4064)
			(end 0.7874 -0.4064)
			(stroke
				(width 0.1524)
				(type default)
			)
			(layer "B.SilkS")
		)
		(fp_line
			(start -0.67945 -0.3048)
			(end -0.67945 0.3048)
			(stroke
				(width 0.1)
				(type default)
			)
			(layer "B.Fab")
		)
		(fp_line
			(start -0.67945 0.3048)
			(end -0.120396 0.3048)
			(stroke
				(width 0.1)
				(type default)
			)
			(layer "B.Fab")
		)
		(fp_line
			(start -0.12065 -0.3048)
			(end -0.67945 -0.3048)
			(stroke
				(width 0.1)
				(type default)
			)
			(layer "B.Fab")
		)
		(fp_line
			(start -0.12065 -0.2794)
			(end -0.12065 -0.3048)
			(stroke
				(width 0.1)
				(type default)
			)
			(layer "B.Fab")
		)
		(fp_line
			(start -0.120396 0.2794)
			(end 0.12065 0.2794)
			(stroke
				(width 0.1)
				(type default)
			)
			(layer "B.Fab")
		)
		(fp_line
			(start -0.120396 0.3048)
			(end -0.120396 0.2794)
			(stroke
				(width 0.1)
				(type default)
			)
			(layer "B.Fab")
		)
		(fp_line
			(start 0.12065 -0.305054)
			(end 0.12065 -0.2794)
			(stroke
				(width 0.1)
				(type default)
			)
			(layer "B.Fab")
		)
		(fp_line
			(start 0.12065 -0.2794)
			(end -0.12065 -0.2794)
			(stroke
				(width 0.1)
				(type default)
			)
			(layer "B.Fab")
		)
		(fp_line
			(start 0.12065 0.2794)
			(end 0.12065 0.3048)
			(stroke
				(width 0.1)
				(type default)
			)
			(layer "B.Fab")
		)
		(fp_line
			(start 0.12065 0.3048)
			(end 0.67945 0.3048)
			(stroke
				(width 0.1)
				(type default)
			)
			(layer "B.Fab")
		)
		(fp_line
			(start 0.67945 -0.305054)
			(end 0.12065 -0.305054)
			(stroke
				(width 0.1)
				(type default)
			)
			(layer "B.Fab")
		)
		(fp_line
			(start 0.67945 0.3048)
			(end 0.67945 -0.305054)
			(stroke
				(width 0.1)
				(type default)
			)
			(layer "B.Fab")
		)
		(pad "1" smd circle
			(at 0.40005 0 180)
			(size 0 0)
			(layers "B.Cu" "B.Mask" "B.Paste")
			(net "P12V_AUX")
		)
		(pad "2" smd circle
			(at -0.40005 0 180)
			(size 0 0)
			(layers "B.Cu" "B.Mask" "B.Paste")
			(net "PVDD11_S3_P1_VINSEN")
		)
	)
	(footprint ""
		(layer "B.Cu")
		(at 348.437454 -256.73431 180)
		(property "Reference" "C2619"
			(at 0 0 0)
			(layer "B.SilkS")
			(hide yes)
			(effects
				(font
					(size 1.27 1.27)
				)
				(justify mirror)
			)
		)
		(property "Value" ""
			(at 0 0 0)
			(layer "B.Fab")
			(effects
				(font
					(size 1.27 1.27)
				)
				(justify mirror)
			)
		)
		(duplicate_pad_numbers_are_jumpers no)
		(fp_line
			(start 0.7874 0.4064)
			(end 0.7874 -0.4064)
			(stroke
				(width 0.1524)
				(type default)
			)
			(layer "B.SilkS")
		)
		(fp_line
			(start 0.7874 -0.4064)
			(end -0.7874 -0.4064)
			(stroke
				(width 0.1524)
				(type default)
			)
			(layer "B.SilkS")
		)
		(fp_line
			(start -0.7874 0.4064)
			(end 0.7874 0.4064)
			(stroke
				(width 0.1524)
				(type default)
			)
			(layer "B.SilkS")
		)
		(fp_line
			(start -0.7874 -0.4064)
			(end -0.7874 0.4064)
			(stroke
				(width 0.1524)
				(type default)
			)
			(layer "B.SilkS")
		)
		(fp_line
			(start 0.67945 0.3048)
			(end 0.67945 -0.305054)
			(stroke
				(width 0.1)
				(type default)
			)
			(layer "B.Fab")
		)
		(fp_line
			(start 0.67945 -0.305054)
			(end 0.12065 -0.305054)
			(stroke
				(width 0.1)
				(type default)
			)
			(layer "B.Fab")
		)
		(fp_line
			(start 0.12065 0.3048)
			(end 0.67945 0.3048)
			(stroke
				(width 0.1)
				(type default)
			)
			(layer "B.Fab")
		)
		(fp_line
			(start 0.12065 0.2794)
			(end 0.12065 0.3048)
			(stroke
				(width 0.1)
				(type default)
			)
			(layer "B.Fab")
		)
		(fp_line
			(start 0.12065 -0.2794)
			(end -0.12065 -0.2794)
			(stroke
				(width 0.1)
				(type default)
			)
			(layer "B.Fab")
		)
		(fp_line
			(start 0.12065 -0.305054)
			(end 0.12065 -0.2794)
			(stroke
				(width 0.1)
				(type default)
			)
			(layer "B.Fab")
		)
		(fp_line
			(start -0.120396 0.3048)
			(end -0.120396 0.2794)
			(stroke
				(width 0.1)
				(type default)
			)
			(layer "B.Fab")
		)
		(fp_line
			(start -0.120396 0.2794)
			(end 0.12065 0.2794)
			(stroke
				(width 0.1)
				(type default)
			)
			(layer "B.Fab")
		)
		(fp_line
			(start -0.12065 -0.2794)
			(end -0.12065 -0.3048)
			(stroke
				(width 0.1)
				(type default)
			)
			(layer "B.Fab")
		)
		(fp_line
			(start -0.12065 -0.3048)
			(end -0.67945 -0.3048)
			(stroke
				(width 0.1)
				(type default)
			)
			(layer "B.Fab")
		)
		(fp_line
			(start -0.67945 0.3048)
			(end -0.120396 0.3048)
			(stroke
				(width 0.1)
				(type default)
			)
			(layer "B.Fab")
		)
		(fp_line
			(start -0.67945 -0.3048)
			(end -0.67945 0.3048)
			(stroke
				(width 0.1)
				(type default)
			)
			(layer "B.Fab")
		)
		(pad "1" smd circle
			(at 0.40005 0)
			(size 0 0)
			(layers "B.Cu" "B.Mask" "B.Paste")
			(net "PVDDIO_P0")
		)
		(pad "2" smd circle
			(at -0.40005 0)
			(size 0 0)
			(layers "B.Cu" "B.Mask" "B.Paste")
			(net "GND")
		)
	)
	(footprint ""
		(layer "B.Cu")
		(at 339.72881 -337.689698 -90)
		(property "Reference" "PR96"
			(at 0 0 90)
			(layer "B.SilkS")
			(hide yes)
			(effects
				(font
					(size 1.27 1.27)
				)
				(justify mirror)
			)
		)
		(property "Value" ""
			(at 0 0 90)
			(layer "B.Fab")
			(effects
				(font
					(size 1.27 1.27)
				)
				(justify mirror)
			)
		)
		(duplicate_pad_numbers_are_jumpers no)
		(fp_line
			(start -0.7874 0.4064)
			(end 0.7874 0.4064)
			(stroke
				(width 0.1524)
				(type default)
			)
			(layer "B.SilkS")
		)
		(fp_line
			(start 0.7874 0.4064)
			(end 0.7874 -0.4064)
			(stroke
				(width 0.1524)
				(type default)
			)
			(layer "B.SilkS")
		)
		(fp_line
			(start -0.7874 -0.4064)
			(end -0.7874 0.4064)
			(stroke
				(width 0.1524)
				(type default)
			)
			(layer "B.SilkS")
		)
		(fp_line
			(start 0.7874 -0.4064)
			(end -0.7874 -0.4064)
			(stroke
				(width 0.1524)
				(type default)
			)
			(layer "B.SilkS")
		)
		(fp_line
			(start -0.67945 0.3048)
			(end -0.120396 0.3048)
			(stroke
				(width 0.1)
				(type default)
			)
			(layer "B.Fab")
		)
		(fp_line
			(start -0.120396 0.3048)
			(end -0.120396 0.2794)
			(stroke
				(width 0.1)
				(type default)
			)
			(layer "B.Fab")
		)
		(fp_line
			(start 0.12065 0.3048)
			(end 0.67945 0.3048)
			(stroke
				(width 0.1)
				(type default)
			)
			(layer "B.Fab")
		)
		(fp_line
			(start 0.67945 0.3048)
			(end 0.67945 -0.305054)
			(stroke
				(width 0.1)
				(type default)
			)
			(layer "B.Fab")
		)
		(fp_line
			(start -0.120396 0.2794)
			(end 0.12065 0.2794)
			(stroke
				(width 0.1)
				(type default)
			)
			(layer "B.Fab")
		)
		(fp_line
			(start 0.12065 0.2794)
			(end 0.12065 0.3048)
			(stroke
				(width 0.1)
				(type default)
			)
			(layer "B.Fab")
		)
		(fp_line
			(start -0.12065 -0.2794)
			(end -0.12065 -0.3048)
			(stroke
				(width 0.1)
				(type default)
			)
			(layer "B.Fab")
		)
		(fp_line
			(start 0.12065 -0.2794)
			(end -0.12065 -0.2794)
			(stroke
				(width 0.1)
				(type default)
			)
			(layer "B.Fab")
		)
		(fp_line
			(start -0.67945 -0.3048)
			(end -0.67945 0.3048)
			(stroke
				(width 0.1)
				(type default)
			)
			(layer "B.Fab")
		)
		(fp_line
			(start -0.12065 -0.3048)
			(end -0.67945 -0.3048)
			(stroke
				(width 0.1)
				(type default)
			)
			(layer "B.Fab")
		)
		(fp_line
			(start 0.12065 -0.305054)
			(end 0.12065 -0.2794)
			(stroke
				(width 0.1)
				(type default)
			)
			(layer "B.Fab")
		)
		(fp_line
			(start 0.67945 -0.305054)
			(end 0.12065 -0.305054)
			(stroke
				(width 0.1)
				(type default)
			)
			(layer "B.Fab")
		)
		(pad "1" smd circle
			(at 0.40005 0 90)
			(size 0 0)
			(layers "B.Cu" "B.Mask" "B.Paste")
			(net "PVDDCR_CPU1_P0_VOS5")
		)
		(pad "2" smd circle
			(at -0.40005 0 90)
			(size 0 0)
			(layers "B.Cu" "B.Mask" "B.Paste")
			(net "PVDDCR_CPU1_P0")
		)
	)
	(footprint ""
		(layer "B.Cu")
		(at 142.893542 -385.58216 180)
		(property "Reference" "R879"
			(at 0 0 0)
			(layer "B.SilkS")
			(hide yes)
			(effects
				(font
					(size 1.27 1.27)
				)
				(justify mirror)
			)
		)
		(property "Value" ""
			(at 0 0 0)
			(layer "B.Fab")
			(effects
				(font
					(size 1.27 1.27)
				)
				(justify mirror)
			)
		)
		(duplicate_pad_numbers_are_jumpers no)
		(fp_line
			(start 0.32512 0.175006)
			(end 0.32512 -0.175006)
			(stroke
				(width 0.1)
				(type default)
			)
			(layer "B.Fab")
		)
		(fp_line
			(start 0.32512 -0.175006)
			(end -0.32512 -0.175006)
			(stroke
				(width 0.1)
				(type default)
			)
			(layer "B.Fab")
		)
		(fp_line
			(start -0.32512 0.175006)
			(end 0.32512 0.175006)
			(stroke
				(width 0.1)
				(type default)
			)
			(layer "B.Fab")
		)
		(fp_line
			(start -0.32512 -0.175006)
			(end -0.32512 0.175006)
			(stroke
				(width 0.1)
				(type default)
			)
			(layer "B.Fab")
		)
		(pad "1" smd rect
			(at 0.2667 0)
			(size 0.3048 0.381)
			(layers "B.Cu" "B.Mask" "B.Paste")
			(net "TEST0_RT_CPU1_P2")
		)
		(pad "2" smd rect
			(at -0.2667 0 180)
			(size 0.3048 0.381)
			(layers "B.Cu" "B.Mask" "B.Paste")
			(net "GND")
		)
	)
	(footprint ""
		(layer "B.Cu")
		(at 160.206182 -386.766562 90)
		(property "Reference" "C394"
			(at 0 0 90)
			(layer "B.SilkS")
			(hide yes)
			(effects
				(font
					(size 1.27 1.27)
				)
				(justify mirror)
			)
		)
		(property "Value" ""
			(at 0 0 90)
			(layer "B.Fab")
			(effects
				(font
					(size 1.27 1.27)
				)
				(justify mirror)
			)
		)
		(duplicate_pad_numbers_are_jumpers no)
		(fp_line
			(start 0.299974 -0.150114)
			(end -0.299974 -0.150114)
			(stroke
				(width 0.1)
				(type default)
			)
			(layer "B.Fab")
		)
		(fp_line
			(start -0.299974 -0.150114)
			(end -0.299974 0.150114)
			(stroke
				(width 0.1)
				(type default)
			)
			(layer "B.Fab")
		)
		(fp_line
			(start 0.299974 0.150114)
			(end 0.299974 -0.150114)
			(stroke
				(width 0.1)
				(type default)
			)
			(layer "B.Fab")
		)
		(fp_line
			(start -0.299974 0.150114)
			(end 0.299974 0.150114)
			(stroke
				(width 0.1)
				(type default)
			)
			(layer "B.Fab")
		)
		(pad "1" smd rect
			(at 0.2667 0 270)
			(size 0.3048 0.381)
			(layers "B.Cu" "B.Mask" "B.Paste")
			(net "P0V9_CPU1_RT2_2A_2D")
		)
		(pad "2" smd rect
			(at -0.2667 0 270)
			(size 0.3048 0.381)
			(layers "B.Cu" "B.Mask" "B.Paste")
			(net "GND")
		)
	)
	(footprint ""
		(layer "B.Cu")
		(at 348.151958 -265.045952)
		(property "Reference" "C2626"
			(at 0 0 0)
			(layer "B.SilkS")
			(hide yes)
			(effects
				(font
					(size 1.27 1.27)
				)
				(justify mirror)
			)
		)
		(property "Value" ""
			(at 0 0 0)
			(layer "B.Fab")
			(effects
				(font
					(size 1.27 1.27)
				)
				(justify mirror)
			)
		)
		(duplicate_pad_numbers_are_jumpers no)
		(fp_line
			(start -0.7874 -0.4064)
			(end -0.7874 0.4064)
			(stroke
				(width 0.1524)
				(type default)
			)
			(layer "B.SilkS")
		)
		(fp_line
			(start -0.7874 0.4064)
			(end 0.7874 0.4064)
			(stroke
				(width 0.1524)
				(type default)
			)
			(layer "B.SilkS")
		)
		(fp_line
			(start 0.7874 -0.4064)
			(end -0.7874 -0.4064)
			(stroke
				(width 0.1524)
				(type default)
			)
			(layer "B.SilkS")
		)
		(fp_line
			(start 0.7874 0.4064)
			(end 0.7874 -0.4064)
			(stroke
				(width 0.1524)
				(type default)
			)
			(layer "B.SilkS")
		)
		(fp_line
			(start -0.67945 -0.3048)
			(end -0.67945 0.3048)
			(stroke
				(width 0.1)
				(type default)
			)
			(layer "B.Fab")
		)
		(fp_line
			(start -0.67945 0.3048)
			(end -0.120396 0.3048)
			(stroke
				(width 0.1)
				(type default)
			)
			(layer "B.Fab")
		)
		(fp_line
			(start -0.12065 -0.3048)
			(end -0.67945 -0.3048)
			(stroke
				(width 0.1)
				(type default)
			)
			(layer "B.Fab")
		)
		(fp_line
			(start -0.12065 -0.2794)
			(end -0.12065 -0.3048)
			(stroke
				(width 0.1)
				(type default)
			)
			(layer "B.Fab")
		)
		(fp_line
			(start -0.120396 0.2794)
			(end 0.12065 0.2794)
			(stroke
				(width 0.1)
				(type default)
			)
			(layer "B.Fab")
		)
		(fp_line
			(start -0.120396 0.3048)
			(end -0.120396 0.2794)
			(stroke
				(width 0.1)
				(type default)
			)
			(layer "B.Fab")
		)
		(fp_line
			(start 0.12065 -0.305054)
			(end 0.12065 -0.2794)
			(stroke
				(width 0.1)
				(type default)
			)
			(layer "B.Fab")
		)
		(fp_line
			(start 0.12065 -0.2794)
			(end -0.12065 -0.2794)
			(stroke
				(width 0.1)
				(type default)
			)
			(layer "B.Fab")
		)
		(fp_line
			(start 0.12065 0.2794)
			(end 0.12065 0.3048)
			(stroke
				(width 0.1)
				(type default)
			)
			(layer "B.Fab")
		)
		(fp_line
			(start 0.12065 0.3048)
			(end 0.67945 0.3048)
			(stroke
				(width 0.1)
				(type default)
			)
			(layer "B.Fab")
		)
		(fp_line
			(start 0.67945 -0.305054)
			(end 0.12065 -0.305054)
			(stroke
				(width 0.1)
				(type default)
			)
			(layer "B.Fab")
		)
		(fp_line
			(start 0.67945 0.3048)
			(end 0.67945 -0.305054)
			(stroke
				(width 0.1)
				(type default)
			)
			(layer "B.Fab")
		)
		(pad "1" smd circle
			(at 0.40005 0 180)
			(size 0 0)
			(layers "B.Cu" "B.Mask" "B.Paste")
			(net "PVDDIO_P0")
		)
		(pad "2" smd circle
			(at -0.40005 0 180)
			(size 0 0)
			(layers "B.Cu" "B.Mask" "B.Paste")
			(net "GND")
		)
	)
	(footprint ""
		(layer "B.Cu")
		(at 438.013348 -19.07667 -90)
		(property "Reference" "R1896"
			(at 0 0 90)
			(layer "B.SilkS")
			(hide yes)
			(effects
				(font
					(size 1.27 1.27)
				)
				(justify mirror)
			)
		)
		(property "Value" ""
			(at 0 0 90)
			(layer "B.Fab")
			(effects
				(font
					(size 1.27 1.27)
				)
				(justify mirror)
			)
		)
		(duplicate_pad_numbers_are_jumpers no)
		(fp_line
			(start -0.7874 0.4064)
			(end 0.7874 0.4064)
			(stroke
				(width 0.1524)
				(type default)
			)
			(layer "B.SilkS")
		)
		(fp_line
			(start 0.7874 0.4064)
			(end 0.7874 -0.4064)
			(stroke
				(width 0.1524)
				(type default)
			)
			(layer "B.SilkS")
		)
		(fp_line
			(start -0.7874 -0.4064)
			(end -0.7874 0.4064)
			(stroke
				(width 0.1524)
				(type default)
			)
			(layer "B.SilkS")
		)
		(fp_line
			(start 0.7874 -0.4064)
			(end -0.7874 -0.4064)
			(stroke
				(width 0.1524)
				(type default)
			)
			(layer "B.SilkS")
		)
		(fp_line
			(start -0.67945 0.3048)
			(end -0.120396 0.3048)
			(stroke
				(width 0.1)
				(type default)
			)
			(layer "B.Fab")
		)
		(fp_line
			(start -0.120396 0.3048)
			(end -0.120396 0.2794)
			(stroke
				(width 0.1)
				(type default)
			)
			(layer "B.Fab")
		)
		(fp_line
			(start 0.12065 0.3048)
			(end 0.67945 0.3048)
			(stroke
				(width 0.1)
				(type default)
			)
			(layer "B.Fab")
		)
		(fp_line
			(start 0.67945 0.3048)
			(end 0.67945 -0.305054)
			(stroke
				(width 0.1)
				(type default)
			)
			(layer "B.Fab")
		)
		(fp_line
			(start -0.120396 0.2794)
			(end 0.12065 0.2794)
			(stroke
				(width 0.1)
				(type default)
			)
			(layer "B.Fab")
		)
		(fp_line
			(start 0.12065 0.2794)
			(end 0.12065 0.3048)
			(stroke
				(width 0.1)
				(type default)
			)
			(layer "B.Fab")
		)
		(fp_line
			(start -0.12065 -0.2794)
			(end -0.12065 -0.3048)
			(stroke
				(width 0.1)
				(type default)
			)
			(layer "B.Fab")
		)
		(fp_line
			(start 0.12065 -0.2794)
			(end -0.12065 -0.2794)
			(stroke
				(width 0.1)
				(type default)
			)
			(layer "B.Fab")
		)
		(fp_line
			(start -0.67945 -0.3048)
			(end -0.67945 0.3048)
			(stroke
				(width 0.1)
				(type default)
			)
			(layer "B.Fab")
		)
		(fp_line
			(start -0.12065 -0.3048)
			(end -0.67945 -0.3048)
			(stroke
				(width 0.1)
				(type default)
			)
			(layer "B.Fab")
		)
		(fp_line
			(start 0.12065 -0.305054)
			(end 0.12065 -0.2794)
			(stroke
				(width 0.1)
				(type default)
			)
			(layer "B.Fab")
		)
		(fp_line
			(start 0.67945 -0.305054)
			(end 0.12065 -0.305054)
			(stroke
				(width 0.1)
				(type default)
			)
			(layer "B.Fab")
		)
		(pad "1" smd circle
			(at 0.40005 0 90)
			(size 0 0)
			(layers "B.Cu" "B.Mask" "B.Paste")
			(net "OCP_SFF_ISO_BIF0_EN")
		)
		(pad "2" smd circle
			(at -0.40005 0 90)
			(size 0 0)
			(layers "B.Cu" "B.Mask" "B.Paste")
			(net "GND")
		)
	)
	(footprint ""
		(layer "B.Cu")
		(at 215.514428 -74.055986 180)
		(property "Reference" "R84"
			(at 0 0 0)
			(layer "B.SilkS")
			(hide yes)
			(effects
				(font
					(size 1.27 1.27)
				)
				(justify mirror)
			)
		)
		(property "Value" ""
			(at 0 0 0)
			(layer "B.Fab")
			(effects
				(font
					(size 1.27 1.27)
				)
				(justify mirror)
			)
		)
		(duplicate_pad_numbers_are_jumpers no)
		(fp_line
			(start 0.7874 0.4064)
			(end 0.7874 -0.4064)
			(stroke
				(width 0.1524)
				(type default)
			)
			(layer "B.SilkS")
		)
		(fp_line
			(start 0.7874 -0.4064)
			(end -0.7874 -0.4064)
			(stroke
				(width 0.1524)
				(type default)
			)
			(layer "B.SilkS")
		)
		(fp_line
			(start -0.7874 0.4064)
			(end 0.7874 0.4064)
			(stroke
				(width 0.1524)
				(type default)
			)
			(layer "B.SilkS")
		)
		(fp_line
			(start -0.7874 -0.4064)
			(end -0.7874 0.4064)
			(stroke
				(width 0.1524)
				(type default)
			)
			(layer "B.SilkS")
		)
		(fp_line
			(start 0.67945 0.3048)
			(end 0.67945 -0.305054)
			(stroke
				(width 0.1)
				(type default)
			)
			(layer "B.Fab")
		)
		(fp_line
			(start 0.67945 -0.305054)
			(end 0.12065 -0.305054)
			(stroke
				(width 0.1)
				(type default)
			)
			(layer "B.Fab")
		)
		(fp_line
			(start 0.12065 0.3048)
			(end 0.67945 0.3048)
			(stroke
				(width 0.1)
				(type default)
			)
			(layer "B.Fab")
		)
		(fp_line
			(start 0.12065 0.2794)
			(end 0.12065 0.3048)
			(stroke
				(width 0.1)
				(type default)
			)
			(layer "B.Fab")
		)
		(fp_line
			(start 0.12065 -0.2794)
			(end -0.12065 -0.2794)
			(stroke
				(width 0.1)
				(type default)
			)
			(layer "B.Fab")
		)
		(fp_line
			(start 0.12065 -0.305054)
			(end 0.12065 -0.2794)
			(stroke
				(width 0.1)
				(type default)
			)
			(layer "B.Fab")
		)
		(fp_line
			(start -0.120396 0.3048)
			(end -0.120396 0.2794)
			(stroke
				(width 0.1)
				(type default)
			)
			(layer "B.Fab")
		)
		(fp_line
			(start -0.120396 0.2794)
			(end 0.12065 0.2794)
			(stroke
				(width 0.1)
				(type default)
			)
			(layer "B.Fab")
		)
		(fp_line
			(start -0.12065 -0.2794)
			(end -0.12065 -0.3048)
			(stroke
				(width 0.1)
				(type default)
			)
			(layer "B.Fab")
		)
		(fp_line
			(start -0.12065 -0.3048)
			(end -0.67945 -0.3048)
			(stroke
				(width 0.1)
				(type default)
			)
			(layer "B.Fab")
		)
		(fp_line
			(start -0.67945 0.3048)
			(end -0.120396 0.3048)
			(stroke
				(width 0.1)
				(type default)
			)
			(layer "B.Fab")
		)
		(fp_line
			(start -0.67945 -0.3048)
			(end -0.67945 0.3048)
			(stroke
				(width 0.1)
				(type default)
			)
			(layer "B.Fab")
		)
		(pad "1" smd circle
			(at 0.40005 0)
			(size 0 0)
			(layers "B.Cu" "B.Mask" "B.Paste")
			(net "RMII_BMC_OCP_TXD_1")
		)
		(pad "2" smd circle
			(at -0.40005 0)
			(size 0 0)
			(layers "B.Cu" "B.Mask" "B.Paste")
			(net "GND")
		)
	)
	(footprint ""
		(layer "B.Cu")
		(at 105.605834 -272.284952)
		(property "Reference" "C2395"
			(at 0 0 0)
			(layer "B.SilkS")
			(hide yes)
			(effects
				(font
					(size 1.27 1.27)
				)
				(justify mirror)
			)
		)
		(property "Value" ""
			(at 0 0 0)
			(layer "B.Fab")
			(effects
				(font
					(size 1.27 1.27)
				)
				(justify mirror)
			)
		)
		(duplicate_pad_numbers_are_jumpers no)
		(fp_line
			(start -0.7874 -0.4064)
			(end -0.7874 0.4064)
			(stroke
				(width 0.1524)
				(type default)
			)
			(layer "B.SilkS")
		)
		(fp_line
			(start -0.7874 0.4064)
			(end 0.7874 0.4064)
			(stroke
				(width 0.1524)
				(type default)
			)
			(layer "B.SilkS")
		)
		(fp_line
			(start 0.7874 -0.4064)
			(end -0.7874 -0.4064)
			(stroke
				(width 0.1524)
				(type default)
			)
			(layer "B.SilkS")
		)
		(fp_line
			(start 0.7874 0.4064)
			(end 0.7874 -0.4064)
			(stroke
				(width 0.1524)
				(type default)
			)
			(layer "B.SilkS")
		)
		(fp_line
			(start -0.67945 -0.3048)
			(end -0.67945 0.3048)
			(stroke
				(width 0.1)
				(type default)
			)
			(layer "B.Fab")
		)
		(fp_line
			(start -0.67945 0.3048)
			(end -0.120396 0.3048)
			(stroke
				(width 0.1)
				(type default)
			)
			(layer "B.Fab")
		)
		(fp_line
			(start -0.12065 -0.3048)
			(end -0.67945 -0.3048)
			(stroke
				(width 0.1)
				(type default)
			)
			(layer "B.Fab")
		)
		(fp_line
			(start -0.12065 -0.2794)
			(end -0.12065 -0.3048)
			(stroke
				(width 0.1)
				(type default)
			)
			(layer "B.Fab")
		)
		(fp_line
			(start -0.120396 0.2794)
			(end 0.12065 0.2794)
			(stroke
				(width 0.1)
				(type default)
			)
			(layer "B.Fab")
		)
		(fp_line
			(start -0.120396 0.3048)
			(end -0.120396 0.2794)
			(stroke
				(width 0.1)
				(type default)
			)
			(layer "B.Fab")
		)
		(fp_line
			(start 0.12065 -0.305054)
			(end 0.12065 -0.2794)
			(stroke
				(width 0.1)
				(type default)
			)
			(layer "B.Fab")
		)
		(fp_line
			(start 0.12065 -0.2794)
			(end -0.12065 -0.2794)
			(stroke
				(width 0.1)
				(type default)
			)
			(layer "B.Fab")
		)
		(fp_line
			(start 0.12065 0.2794)
			(end 0.12065 0.3048)
			(stroke
				(width 0.1)
				(type default)
			)
			(layer "B.Fab")
		)
		(fp_line
			(start 0.12065 0.3048)
			(end 0.67945 0.3048)
			(stroke
				(width 0.1)
				(type default)
			)
			(layer "B.Fab")
		)
		(fp_line
			(start 0.67945 -0.305054)
			(end 0.12065 -0.305054)
			(stroke
				(width 0.1)
				(type default)
			)
			(layer "B.Fab")
		)
		(fp_line
			(start 0.67945 0.3048)
			(end 0.67945 -0.305054)
			(stroke
				(width 0.1)
				(type default)
			)
			(layer "B.Fab")
		)
		(pad "1" smd circle
			(at 0.40005 0 180)
			(size 0 0)
			(layers "B.Cu" "B.Mask" "B.Paste")
			(net "PVDDCR_CPU1_P1")
		)
		(pad "2" smd circle
			(at -0.40005 0 180)
			(size 0 0)
			(layers "B.Cu" "B.Mask" "B.Paste")
			(net "GND")
		)
	)
	(footprint ""
		(layer "B.Cu")
		(at 405.22017 -202.891136 -90)
		(property "Reference" "R654"
			(at 0 0 90)
			(layer "B.SilkS")
			(hide yes)
			(effects
				(font
					(size 1.27 1.27)
				)
				(justify mirror)
			)
		)
		(property "Value" ""
			(at 0 0 90)
			(layer "B.Fab")
			(effects
				(font
					(size 1.27 1.27)
				)
				(justify mirror)
			)
		)
		(duplicate_pad_numbers_are_jumpers no)
		(fp_line
			(start -0.7874 0.4064)
			(end 0.7874 0.4064)
			(stroke
				(width 0.1524)
				(type default)
			)
			(layer "B.SilkS")
		)
		(fp_line
			(start 0.7874 0.4064)
			(end 0.7874 -0.4064)
			(stroke
				(width 0.1524)
				(type default)
			)
			(layer "B.SilkS")
		)
		(fp_line
			(start -0.7874 -0.4064)
			(end -0.7874 0.4064)
			(stroke
				(width 0.1524)
				(type default)
			)
			(layer "B.SilkS")
		)
		(fp_line
			(start 0.7874 -0.4064)
			(end -0.7874 -0.4064)
			(stroke
				(width 0.1524)
				(type default)
			)
			(layer "B.SilkS")
		)
		(fp_line
			(start -0.67945 0.3048)
			(end -0.120396 0.3048)
			(stroke
				(width 0.1)
				(type default)
			)
			(layer "B.Fab")
		)
		(fp_line
			(start -0.120396 0.3048)
			(end -0.120396 0.2794)
			(stroke
				(width 0.1)
				(type default)
			)
			(layer "B.Fab")
		)
		(fp_line
			(start 0.12065 0.3048)
			(end 0.67945 0.3048)
			(stroke
				(width 0.1)
				(type default)
			)
			(layer "B.Fab")
		)
		(fp_line
			(start 0.67945 0.3048)
			(end 0.67945 -0.305054)
			(stroke
				(width 0.1)
				(type default)
			)
			(layer "B.Fab")
		)
		(fp_line
			(start -0.120396 0.2794)
			(end 0.12065 0.2794)
			(stroke
				(width 0.1)
				(type default)
			)
			(layer "B.Fab")
		)
		(fp_line
			(start 0.12065 0.2794)
			(end 0.12065 0.3048)
			(stroke
				(width 0.1)
				(type default)
			)
			(layer "B.Fab")
		)
		(fp_line
			(start -0.12065 -0.2794)
			(end -0.12065 -0.3048)
			(stroke
				(width 0.1)
				(type default)
			)
			(layer "B.Fab")
		)
		(fp_line
			(start 0.12065 -0.2794)
			(end -0.12065 -0.2794)
			(stroke
				(width 0.1)
				(type default)
			)
			(layer "B.Fab")
		)
		(fp_line
			(start -0.67945 -0.3048)
			(end -0.67945 0.3048)
			(stroke
				(width 0.1)
				(type default)
			)
			(layer "B.Fab")
		)
		(fp_line
			(start -0.12065 -0.3048)
			(end -0.67945 -0.3048)
			(stroke
				(width 0.1)
				(type default)
			)
			(layer "B.Fab")
		)
		(fp_line
			(start 0.12065 -0.305054)
			(end 0.12065 -0.2794)
			(stroke
				(width 0.1)
				(type default)
			)
			(layer "B.Fab")
		)
		(fp_line
			(start 0.67945 -0.305054)
			(end 0.12065 -0.305054)
			(stroke
				(width 0.1)
				(type default)
			)
			(layer "B.Fab")
		)
		(pad "1" smd circle
			(at 0.40005 0 90)
			(size 0 0)
			(layers "B.Cu" "B.Mask" "B.Paste")
			(net "SCM_USB_OC_N")
		)
		(pad "2" smd circle
			(at -0.40005 0 90)
			(size 0 0)
			(layers "B.Cu" "B.Mask" "B.Paste")
			(net "P1V8_AUX")
		)
	)
	(footprint ""
		(layer "B.Cu")
		(at 103.951786 -104.674924 180)
		(property "Reference" ""
			(at 0 0 0)
			(layer "B.SilkS")
			(hide yes)
			(effects
				(font
					(size 1.27 1.27)
				)
				(justify mirror)
			)
		)
		(property "Value" ""
			(at 0 0 0)
			(layer "B.Fab")
			(effects
				(font
					(size 1.27 1.27)
				)
				(justify mirror)
			)
		)
		(duplicate_pad_numbers_are_jumpers no)
		(pad "1" smd circle
			(at 0 0)
			(size 0.9906 0.9906)
			(layers "B.Cu" "B.Mask" "B.Paste")
			(net "Net_45")
		)
		(zone
			(layer "B.Cu")
			(hatch none 0.5)
			(connect_pads
				(clearance 0)
			)
			(min_thickness 0.25)
			(keepout
				(tracks not_allowed)
				(vias allowed)
				(pads allowed)
				(copperpour not_allowed)
				(footprints allowed)
			)
			(placement
				(enabled no)
				(sheetname "")
			)
			(fill
				(thermal_gap 0.5)
				(thermal_bridge_width 0.5)
				(island_removal_mode 0)
			)
			(polygon
				(pts
					(arc
						(start 105.577386 -104.674924)
						(mid 102.326186 -104.674924)
						(end 105.577386 -104.674924)
					)
				)
			)
		)
	)
	(footprint ""
		(layer "B.Cu")
		(at 112.054386 -263.846564)
		(property "Reference" "C3904"
			(at 0 0 0)
			(layer "B.SilkS")
			(hide yes)
			(effects
				(font
					(size 1.27 1.27)
				)
				(justify mirror)
			)
		)
		(property "Value" ""
			(at 0 0 0)
			(layer "B.Fab")
			(effects
				(font
					(size 1.27 1.27)
				)
				(justify mirror)
			)
		)
		(duplicate_pad_numbers_are_jumpers no)
		(fp_line
			(start -0.7874 -0.4064)
			(end -0.7874 0.4064)
			(stroke
				(width 0.1524)
				(type default)
			)
			(layer "B.SilkS")
		)
		(fp_line
			(start -0.7874 0.4064)
			(end 0.7874 0.4064)
			(stroke
				(width 0.1524)
				(type default)
			)
			(layer "B.SilkS")
		)
		(fp_line
			(start 0.7874 -0.4064)
			(end -0.7874 -0.4064)
			(stroke
				(width 0.1524)
				(type default)
			)
			(layer "B.SilkS")
		)
		(fp_line
			(start 0.7874 0.4064)
			(end 0.7874 -0.4064)
			(stroke
				(width 0.1524)
				(type default)
			)
			(layer "B.SilkS")
		)
		(fp_line
			(start -0.67945 -0.3048)
			(end -0.67945 0.3048)
			(stroke
				(width 0.1)
				(type default)
			)
			(layer "B.Fab")
		)
		(fp_line
			(start -0.67945 0.3048)
			(end -0.120396 0.3048)
			(stroke
				(width 0.1)
				(type default)
			)
			(layer "B.Fab")
		)
		(fp_line
			(start -0.12065 -0.3048)
			(end -0.67945 -0.3048)
			(stroke
				(width 0.1)
				(type default)
			)
			(layer "B.Fab")
		)
		(fp_line
			(start -0.12065 -0.2794)
			(end -0.12065 -0.3048)
			(stroke
				(width 0.1)
				(type default)
			)
			(layer "B.Fab")
		)
		(fp_line
			(start -0.120396 0.2794)
			(end 0.12065 0.2794)
			(stroke
				(width 0.1)
				(type default)
			)
			(layer "B.Fab")
		)
		(fp_line
			(start -0.120396 0.3048)
			(end -0.120396 0.2794)
			(stroke
				(width 0.1)
				(type default)
			)
			(layer "B.Fab")
		)
		(fp_line
			(start 0.12065 -0.305054)
			(end 0.12065 -0.2794)
			(stroke
				(width 0.1)
				(type default)
			)
			(layer "B.Fab")
		)
		(fp_line
			(start 0.12065 -0.2794)
			(end -0.12065 -0.2794)
			(stroke
				(width 0.1)
				(type default)
			)
			(layer "B.Fab")
		)
		(fp_line
			(start 0.12065 0.2794)
			(end 0.12065 0.3048)
			(stroke
				(width 0.1)
				(type default)
			)
			(layer "B.Fab")
		)
		(fp_line
			(start 0.12065 0.3048)
			(end 0.67945 0.3048)
			(stroke
				(width 0.1)
				(type default)
			)
			(layer "B.Fab")
		)
		(fp_line
			(start 0.67945 -0.305054)
			(end 0.12065 -0.305054)
			(stroke
				(width 0.1)
				(type default)
			)
			(layer "B.Fab")
		)
		(fp_line
			(start 0.67945 0.3048)
			(end 0.67945 -0.305054)
			(stroke
				(width 0.1)
				(type default)
			)
			(layer "B.Fab")
		)
		(pad "1" smd circle
			(at 0.40005 0 180)
			(size 0 0)
			(layers "B.Cu" "B.Mask" "B.Paste")
			(net "PVDD11_S3_P1")
		)
		(pad "2" smd circle
			(at -0.40005 0 180)
			(size 0 0)
			(layers "B.Cu" "B.Mask" "B.Paste")
			(net "GND")
		)
	)
	(footprint ""
		(layer "B.Cu")
		(at 338.44611 -396.393162 -90)
		(property "Reference" "C635"
			(at 0 0 90)
			(layer "B.SilkS")
			(hide yes)
			(effects
				(font
					(size 1.27 1.27)
				)
				(justify mirror)
			)
		)
		(property "Value" ""
			(at 0 0 90)
			(layer "B.Fab")
			(effects
				(font
					(size 1.27 1.27)
				)
				(justify mirror)
			)
		)
		(duplicate_pad_numbers_are_jumpers no)
		(fp_line
			(start -0.299974 0.150114)
			(end 0.299974 0.150114)
			(stroke
				(width 0.1)
				(type default)
			)
			(layer "B.Fab")
		)
		(fp_line
			(start 0.299974 0.150114)
			(end 0.299974 -0.150114)
			(stroke
				(width 0.1)
				(type default)
			)
			(layer "B.Fab")
		)
		(fp_line
			(start -0.299974 -0.150114)
			(end -0.299974 0.150114)
			(stroke
				(width 0.1)
				(type default)
			)
			(layer "B.Fab")
		)
		(fp_line
			(start 0.299974 -0.150114)
			(end -0.299974 -0.150114)
			(stroke
				(width 0.1)
				(type default)
			)
			(layer "B.Fab")
		)
		(pad "1" smd rect
			(at 0.2667 0 90)
			(size 0.3048 0.381)
			(layers "B.Cu" "B.Mask" "B.Paste")
			(net "P0V9_CPU0_RT1_2A")
		)
		(pad "2" smd rect
			(at -0.2667 0 90)
			(size 0.3048 0.381)
			(layers "B.Cu" "B.Mask" "B.Paste")
			(net "GND")
		)
	)
	(footprint ""
		(layer "B.Cu")
		(at 88.243918 -338.918042 -90)
		(property "Reference" "PC379_1"
			(at 0 0 90)
			(layer "B.SilkS")
			(hide yes)
			(effects
				(font
					(size 1.27 1.27)
				)
				(justify mirror)
			)
		)
		(property "Value" ""
			(at 0 0 90)
			(layer "B.Fab")
			(effects
				(font
					(size 1.27 1.27)
				)
				(justify mirror)
			)
		)
		(duplicate_pad_numbers_are_jumpers no)
		(fp_line
			(start -1.524 0.762)
			(end 1.524 0.762)
			(stroke
				(width 0.1524)
				(type default)
			)
			(layer "B.SilkS")
		)
		(fp_line
			(start 1.524 0.762)
			(end 1.524 -0.762)
			(stroke
				(width 0.1524)
				(type default)
			)
			(layer "B.SilkS")
		)
		(fp_line
			(start -1.524 -0.762)
			(end -1.524 0.762)
			(stroke
				(width 0.1524)
				(type default)
			)
			(layer "B.SilkS")
		)
		(fp_line
			(start 1.524 -0.762)
			(end -1.524 -0.762)
			(stroke
				(width 0.1524)
				(type default)
			)
			(layer "B.SilkS")
		)
		(fp_line
			(start -1.1049 0.724916)
			(end -1.1049 -0.724916)
			(stroke
				(width 0.1)
				(type default)
			)
			(layer "B.Fab")
		)
		(fp_line
			(start 1.1049 0.724916)
			(end -1.1049 0.724916)
			(stroke
				(width 0.1)
				(type default)
			)
			(layer "B.Fab")
		)
		(fp_line
			(start -1.1049 -0.724916)
			(end 1.1049 -0.724916)
			(stroke
				(width 0.1)
				(type default)
			)
			(layer "B.Fab")
		)
		(fp_line
			(start 1.1049 -0.724916)
			(end 1.1049 0.724916)
			(stroke
				(width 0.1)
				(type default)
			)
			(layer "B.Fab")
		)
		(pad "1" smd rect
			(at 0.889 0 270)
			(size 1.016 1.27)
			(layers "B.Cu" "B.Mask" "B.Paste")
			(net "SW_P12V_AUX_PVDDCR_CPU1_P1_FLT")
		)
		(pad "2" smd rect
			(at -0.889 0 270)
			(size 1.016 1.27)
			(layers "B.Cu" "B.Mask" "B.Paste")
			(net "GND")
		)
	)
	(footprint ""
		(layer "B.Cu")
		(at 182.619142 -244.085364)
		(property "Reference" "R508"
			(at 0 0 0)
			(layer "B.SilkS")
			(hide yes)
			(effects
				(font
					(size 1.27 1.27)
				)
				(justify mirror)
			)
		)
		(property "Value" ""
			(at 0 0 0)
			(layer "B.Fab")
			(effects
				(font
					(size 1.27 1.27)
				)
				(justify mirror)
			)
		)
		(duplicate_pad_numbers_are_jumpers no)
		(fp_line
			(start -0.7874 -0.4064)
			(end -0.7874 0.4064)
			(stroke
				(width 0.1524)
				(type default)
			)
			(layer "B.SilkS")
		)
		(fp_line
			(start -0.7874 0.4064)
			(end 0.7874 0.4064)
			(stroke
				(width 0.1524)
				(type default)
			)
			(layer "B.SilkS")
		)
		(fp_line
			(start 0.7874 -0.4064)
			(end -0.7874 -0.4064)
			(stroke
				(width 0.1524)
				(type default)
			)
			(layer "B.SilkS")
		)
		(fp_line
			(start 0.7874 0.4064)
			(end 0.7874 -0.4064)
			(stroke
				(width 0.1524)
				(type default)
			)
			(layer "B.SilkS")
		)
		(fp_line
			(start -0.67945 -0.3048)
			(end -0.67945 0.3048)
			(stroke
				(width 0.1)
				(type default)
			)
			(layer "B.Fab")
		)
		(fp_line
			(start -0.67945 0.3048)
			(end -0.120396 0.3048)
			(stroke
				(width 0.1)
				(type default)
			)
			(layer "B.Fab")
		)
		(fp_line
			(start -0.12065 -0.3048)
			(end -0.67945 -0.3048)
			(stroke
				(width 0.1)
				(type default)
			)
			(layer "B.Fab")
		)
		(fp_line
			(start -0.12065 -0.2794)
			(end -0.12065 -0.3048)
			(stroke
				(width 0.1)
				(type default)
			)
			(layer "B.Fab")
		)
		(fp_line
			(start -0.120396 0.2794)
			(end 0.12065 0.2794)
			(stroke
				(width 0.1)
				(type default)
			)
			(layer "B.Fab")
		)
		(fp_line
			(start -0.120396 0.3048)
			(end -0.120396 0.2794)
			(stroke
				(width 0.1)
				(type default)
			)
			(layer "B.Fab")
		)
		(fp_line
			(start 0.12065 -0.305054)
			(end 0.12065 -0.2794)
			(stroke
				(width 0.1)
				(type default)
			)
			(layer "B.Fab")
		)
		(fp_line
			(start 0.12065 -0.2794)
			(end -0.12065 -0.2794)
			(stroke
				(width 0.1)
				(type default)
			)
			(layer "B.Fab")
		)
		(fp_line
			(start 0.12065 0.2794)
			(end 0.12065 0.3048)
			(stroke
				(width 0.1)
				(type default)
			)
			(layer "B.Fab")
		)
		(fp_line
			(start 0.12065 0.3048)
			(end 0.67945 0.3048)
			(stroke
				(width 0.1)
				(type default)
			)
			(layer "B.Fab")
		)
		(fp_line
			(start 0.67945 -0.305054)
			(end 0.12065 -0.305054)
			(stroke
				(width 0.1)
				(type default)
			)
			(layer "B.Fab")
		)
		(fp_line
			(start 0.67945 0.3048)
			(end 0.67945 -0.305054)
			(stroke
				(width 0.1)
				(type default)
			)
			(layer "B.Fab")
		)
		(pad "1" smd circle
			(at 0.40005 0 180)
			(size 0 0)
			(layers "B.Cu" "B.Mask" "B.Paste")
			(net "M_I_CPU1_ALERT_N")
		)
		(pad "2" smd circle
			(at -0.40005 0 180)
			(size 0 0)
			(layers "B.Cu" "B.Mask" "B.Paste")
			(net "M_I_CPU1_ALERT_R_N")
		)
	)
	(footprint ""
		(layer "B.Cu")
		(at 237.871 -227.203)
		(property "Reference" "R789"
			(at 0 0 0)
			(layer "B.SilkS")
			(hide yes)
			(effects
				(font
					(size 1.27 1.27)
				)
				(justify mirror)
			)
		)
		(property "Value" ""
			(at 0 0 0)
			(layer "B.Fab")
			(effects
				(font
					(size 1.27 1.27)
				)
				(justify mirror)
			)
		)
		(duplicate_pad_numbers_are_jumpers no)
		(fp_line
			(start -0.7874 -0.4064)
			(end -0.7874 0.4064)
			(stroke
				(width 0.1524)
				(type default)
			)
			(layer "B.SilkS")
		)
		(fp_line
			(start -0.7874 0.4064)
			(end 0.7874 0.4064)
			(stroke
				(width 0.1524)
				(type default)
			)
			(layer "B.SilkS")
		)
		(fp_line
			(start 0.7874 -0.4064)
			(end -0.7874 -0.4064)
			(stroke
				(width 0.1524)
				(type default)
			)
			(layer "B.SilkS")
		)
		(fp_line
			(start 0.7874 0.4064)
			(end 0.7874 -0.4064)
			(stroke
				(width 0.1524)
				(type default)
			)
			(layer "B.SilkS")
		)
		(fp_line
			(start -0.67945 -0.3048)
			(end -0.67945 0.3048)
			(stroke
				(width 0.1)
				(type default)
			)
			(layer "B.Fab")
		)
		(fp_line
			(start -0.67945 0.3048)
			(end -0.120396 0.3048)
			(stroke
				(width 0.1)
				(type default)
			)
			(layer "B.Fab")
		)
		(fp_line
			(start -0.12065 -0.3048)
			(end -0.67945 -0.3048)
			(stroke
				(width 0.1)
				(type default)
			)
			(layer "B.Fab")
		)
		(fp_line
			(start -0.12065 -0.2794)
			(end -0.12065 -0.3048)
			(stroke
				(width 0.1)
				(type default)
			)
			(layer "B.Fab")
		)
		(fp_line
			(start -0.120396 0.2794)
			(end 0.12065 0.2794)
			(stroke
				(width 0.1)
				(type default)
			)
			(layer "B.Fab")
		)
		(fp_line
			(start -0.120396 0.3048)
			(end -0.120396 0.2794)
			(stroke
				(width 0.1)
				(type default)
			)
			(layer "B.Fab")
		)
		(fp_line
			(start 0.12065 -0.305054)
			(end 0.12065 -0.2794)
			(stroke
				(width 0.1)
				(type default)
			)
			(layer "B.Fab")
		)
		(fp_line
			(start 0.12065 -0.2794)
			(end -0.12065 -0.2794)
			(stroke
				(width 0.1)
				(type default)
			)
			(layer "B.Fab")
		)
		(fp_line
			(start 0.12065 0.2794)
			(end 0.12065 0.3048)
			(stroke
				(width 0.1)
				(type default)
			)
			(layer "B.Fab")
		)
		(fp_line
			(start 0.12065 0.3048)
			(end 0.67945 0.3048)
			(stroke
				(width 0.1)
				(type default)
			)
			(layer "B.Fab")
		)
		(fp_line
			(start 0.67945 -0.305054)
			(end 0.12065 -0.305054)
			(stroke
				(width 0.1)
				(type default)
			)
			(layer "B.Fab")
		)
		(fp_line
			(start 0.67945 0.3048)
			(end 0.67945 -0.305054)
			(stroke
				(width 0.1)
				(type default)
			)
			(layer "B.Fab")
		)
		(pad "1" smd circle
			(at 0.40005 0 180)
			(size 0 0)
			(layers "B.Cu" "B.Mask" "B.Paste")
			(net "SMB_CPU0_CPU1_APML_BUF1_SCL")
		)
		(pad "2" smd circle
			(at -0.40005 0 180)
			(size 0 0)
			(layers "B.Cu" "B.Mask" "B.Paste")
			(net "SMB_CPU0_CPU1_APML_BUF1_SCL_R1")
		)
	)
	(footprint ""
		(layer "B.Cu")
		(at 216.027 -339.725 90)
		(property "Reference" "R6751"
			(at 0 0 90)
			(layer "B.SilkS")
			(hide yes)
			(effects
				(font
					(size 1.27 1.27)
				)
				(justify mirror)
			)
		)
		(property "Value" ""
			(at 0 0 90)
			(layer "B.Fab")
			(effects
				(font
					(size 1.27 1.27)
				)
				(justify mirror)
			)
		)
		(duplicate_pad_numbers_are_jumpers no)
		(fp_line
			(start 0.32512 -0.175006)
			(end -0.32512 -0.175006)
			(stroke
				(width 0.1)
				(type default)
			)
			(layer "B.Fab")
		)
		(fp_line
			(start -0.32512 -0.175006)
			(end -0.32512 0.175006)
			(stroke
				(width 0.1)
				(type default)
			)
			(layer "B.Fab")
		)
		(fp_line
			(start 0.32512 0.175006)
			(end 0.32512 -0.175006)
			(stroke
				(width 0.1)
				(type default)
			)
			(layer "B.Fab")
		)
		(fp_line
			(start -0.32512 0.175006)
			(end 0.32512 0.175006)
			(stroke
				(width 0.1)
				(type default)
			)
			(layer "B.Fab")
		)
		(pad "1" smd rect
			(at 0.2667 0 270)
			(size 0.3048 0.381)
			(layers "B.Cu" "B.Mask" "B.Paste")
			(net "P1V8_CPU1_RT_1D")
		)
		(pad "2" smd rect
			(at -0.2667 0 90)
			(size 0.3048 0.381)
			(layers "B.Cu" "B.Mask" "B.Paste")
			(net "SMB_RT_CPU1_P3_R_SCL")
		)
	)
	(footprint ""
		(layer "B.Cu")
		(at 73.65873 -335.06791 90)
		(property "Reference" "PC412_3"
			(at 0 0 90)
			(layer "B.SilkS")
			(hide yes)
			(effects
				(font
					(size 1.27 1.27)
				)
				(justify mirror)
			)
		)
		(property "Value" ""
			(at 0 0 90)
			(layer "B.Fab")
			(effects
				(font
					(size 1.27 1.27)
				)
				(justify mirror)
			)
		)
		(duplicate_pad_numbers_are_jumpers no)
		(fp_line
			(start 1.524 -0.762)
			(end -1.524 -0.762)
			(stroke
				(width 0.1524)
				(type default)
			)
			(layer "B.SilkS")
		)
		(fp_line
			(start -1.524 -0.762)
			(end -1.524 0.762)
			(stroke
				(width 0.1524)
				(type default)
			)
			(layer "B.SilkS")
		)
		(fp_line
			(start 1.524 0.762)
			(end 1.524 -0.762)
			(stroke
				(width 0.1524)
				(type default)
			)
			(layer "B.SilkS")
		)
		(fp_line
			(start -1.524 0.762)
			(end 1.524 0.762)
			(stroke
				(width 0.1524)
				(type default)
			)
			(layer "B.SilkS")
		)
		(fp_line
			(start 1.1049 -0.724916)
			(end 1.1049 0.724916)
			(stroke
				(width 0.1)
				(type default)
			)
			(layer "B.Fab")
		)
		(fp_line
			(start -1.1049 -0.724916)
			(end 1.1049 -0.724916)
			(stroke
				(width 0.1)
				(type default)
			)
			(layer "B.Fab")
		)
		(fp_line
			(start 1.1049 0.724916)
			(end -1.1049 0.724916)
			(stroke
				(width 0.1)
				(type default)
			)
			(layer "B.Fab")
		)
		(fp_line
			(start -1.1049 0.724916)
			(end -1.1049 -0.724916)
			(stroke
				(width 0.1)
				(type default)
			)
			(layer "B.Fab")
		)
		(pad "1" smd rect
			(at 0.889 0 90)
			(size 1.016 1.27)
			(layers "B.Cu" "B.Mask" "B.Paste")
			(net "SW_P12V_AUX_PVDDCR_CPU1_P1_FLT")
		)
		(pad "2" smd rect
			(at -0.889 0 90)
			(size 1.016 1.27)
			(layers "B.Cu" "B.Mask" "B.Paste")
			(net "GND")
		)
	)
	(footprint ""
		(layer "B.Cu")
		(at 73.695814 -9.50468)
		(property "Reference" "R3175"
			(at 0 0 0)
			(layer "B.SilkS")
			(hide yes)
			(effects
				(font
					(size 1.27 1.27)
				)
				(justify mirror)
			)
		)
		(property "Value" ""
			(at 0 0 0)
			(layer "B.Fab")
			(effects
				(font
					(size 1.27 1.27)
				)
				(justify mirror)
			)
		)
		(duplicate_pad_numbers_are_jumpers no)
		(fp_line
			(start -0.7874 -0.4064)
			(end -0.7874 0.4064)
			(stroke
				(width 0.1524)
				(type default)
			)
			(layer "B.SilkS")
		)
		(fp_line
			(start -0.7874 0.4064)
			(end 0.7874 0.4064)
			(stroke
				(width 0.1524)
				(type default)
			)
			(layer "B.SilkS")
		)
		(fp_line
			(start 0.7874 -0.4064)
			(end -0.7874 -0.4064)
			(stroke
				(width 0.1524)
				(type default)
			)
			(layer "B.SilkS")
		)
		(fp_line
			(start 0.7874 0.4064)
			(end 0.7874 -0.4064)
			(stroke
				(width 0.1524)
				(type default)
			)
			(layer "B.SilkS")
		)
		(fp_line
			(start -0.67945 -0.3048)
			(end -0.67945 0.3048)
			(stroke
				(width 0.1)
				(type default)
			)
			(layer "B.Fab")
		)
		(fp_line
			(start -0.67945 0.3048)
			(end -0.120396 0.3048)
			(stroke
				(width 0.1)
				(type default)
			)
			(layer "B.Fab")
		)
		(fp_line
			(start -0.12065 -0.3048)
			(end -0.67945 -0.3048)
			(stroke
				(width 0.1)
				(type default)
			)
			(layer "B.Fab")
		)
		(fp_line
			(start -0.12065 -0.2794)
			(end -0.12065 -0.3048)
			(stroke
				(width 0.1)
				(type default)
			)
			(layer "B.Fab")
		)
		(fp_line
			(start -0.120396 0.2794)
			(end 0.12065 0.2794)
			(stroke
				(width 0.1)
				(type default)
			)
			(layer "B.Fab")
		)
		(fp_line
			(start -0.120396 0.3048)
			(end -0.120396 0.2794)
			(stroke
				(width 0.1)
				(type default)
			)
			(layer "B.Fab")
		)
		(fp_line
			(start 0.12065 -0.305054)
			(end 0.12065 -0.2794)
			(stroke
				(width 0.1)
				(type default)
			)
			(layer "B.Fab")
		)
		(fp_line
			(start 0.12065 -0.2794)
			(end -0.12065 -0.2794)
			(stroke
				(width 0.1)
				(type default)
			)
			(layer "B.Fab")
		)
		(fp_line
			(start 0.12065 0.2794)
			(end 0.12065 0.3048)
			(stroke
				(width 0.1)
				(type default)
			)
			(layer "B.Fab")
		)
		(fp_line
			(start 0.12065 0.3048)
			(end 0.67945 0.3048)
			(stroke
				(width 0.1)
				(type default)
			)
			(layer "B.Fab")
		)
		(fp_line
			(start 0.67945 -0.305054)
			(end 0.12065 -0.305054)
			(stroke
				(width 0.1)
				(type default)
			)
			(layer "B.Fab")
		)
		(fp_line
			(start 0.67945 0.3048)
			(end 0.67945 -0.305054)
			(stroke
				(width 0.1)
				(type default)
			)
			(layer "B.Fab")
		)
		(pad "1" smd circle
			(at 0.40005 0 180)
			(size 0 0)
			(layers "B.Cu" "B.Mask" "B.Paste")
			(net "SGPIO_OCP_V3_2_DATAOUT")
		)
		(pad "2" smd circle
			(at -0.40005 0 180)
			(size 0 0)
			(layers "B.Cu" "B.Mask" "B.Paste")
			(net "GND")
		)
	)
	(footprint ""
		(layer "B.Cu")
		(at 100.878386 -266.005564)
		(property "Reference" "C3922"
			(at 0 0 0)
			(layer "B.SilkS")
			(hide yes)
			(effects
				(font
					(size 1.27 1.27)
				)
				(justify mirror)
			)
		)
		(property "Value" ""
			(at 0 0 0)
			(layer "B.Fab")
			(effects
				(font
					(size 1.27 1.27)
				)
				(justify mirror)
			)
		)
		(duplicate_pad_numbers_are_jumpers no)
		(fp_line
			(start -0.7874 -0.4064)
			(end -0.7874 0.4064)
			(stroke
				(width 0.1524)
				(type default)
			)
			(layer "B.SilkS")
		)
		(fp_line
			(start -0.7874 0.4064)
			(end 0.7874 0.4064)
			(stroke
				(width 0.1524)
				(type default)
			)
			(layer "B.SilkS")
		)
		(fp_line
			(start 0.7874 -0.4064)
			(end -0.7874 -0.4064)
			(stroke
				(width 0.1524)
				(type default)
			)
			(layer "B.SilkS")
		)
		(fp_line
			(start 0.7874 0.4064)
			(end 0.7874 -0.4064)
			(stroke
				(width 0.1524)
				(type default)
			)
			(layer "B.SilkS")
		)
		(fp_line
			(start -0.67945 -0.3048)
			(end -0.67945 0.3048)
			(stroke
				(width 0.1)
				(type default)
			)
			(layer "B.Fab")
		)
		(fp_line
			(start -0.67945 0.3048)
			(end -0.120396 0.3048)
			(stroke
				(width 0.1)
				(type default)
			)
			(layer "B.Fab")
		)
		(fp_line
			(start -0.12065 -0.3048)
			(end -0.67945 -0.3048)
			(stroke
				(width 0.1)
				(type default)
			)
			(layer "B.Fab")
		)
		(fp_line
			(start -0.12065 -0.2794)
			(end -0.12065 -0.3048)
			(stroke
				(width 0.1)
				(type default)
			)
			(layer "B.Fab")
		)
		(fp_line
			(start -0.120396 0.2794)
			(end 0.12065 0.2794)
			(stroke
				(width 0.1)
				(type default)
			)
			(layer "B.Fab")
		)
		(fp_line
			(start -0.120396 0.3048)
			(end -0.120396 0.2794)
			(stroke
				(width 0.1)
				(type default)
			)
			(layer "B.Fab")
		)
		(fp_line
			(start 0.12065 -0.305054)
			(end 0.12065 -0.2794)
			(stroke
				(width 0.1)
				(type default)
			)
			(layer "B.Fab")
		)
		(fp_line
			(start 0.12065 -0.2794)
			(end -0.12065 -0.2794)
			(stroke
				(width 0.1)
				(type default)
			)
			(layer "B.Fab")
		)
		(fp_line
			(start 0.12065 0.2794)
			(end 0.12065 0.3048)
			(stroke
				(width 0.1)
				(type default)
			)
			(layer "B.Fab")
		)
		(fp_line
			(start 0.12065 0.3048)
			(end 0.67945 0.3048)
			(stroke
				(width 0.1)
				(type default)
			)
			(layer "B.Fab")
		)
		(fp_line
			(start 0.67945 -0.305054)
			(end 0.12065 -0.305054)
			(stroke
				(width 0.1)
				(type default)
			)
			(layer "B.Fab")
		)
		(fp_line
			(start 0.67945 0.3048)
			(end 0.67945 -0.305054)
			(stroke
				(width 0.1)
				(type default)
			)
			(layer "B.Fab")
		)
		(pad "1" smd circle
			(at 0.40005 0 180)
			(size 0 0)
			(layers "B.Cu" "B.Mask" "B.Paste")
			(net "PVDD11_S3_P1")
		)
		(pad "2" smd circle
			(at -0.40005 0 180)
			(size 0 0)
			(layers "B.Cu" "B.Mask" "B.Paste")
			(net "GND")
		)
	)
	(footprint ""
		(layer "B.Cu")
		(at 10.16 -81.153 -90)
		(property "Reference" "C8001"
			(at 0 0 90)
			(layer "B.SilkS")
			(hide yes)
			(effects
				(font
					(size 1.27 1.27)
				)
				(justify mirror)
			)
		)
		(property "Value" ""
			(at 0 0 90)
			(layer "B.Fab")
			(effects
				(font
					(size 1.27 1.27)
				)
				(justify mirror)
			)
		)
		(duplicate_pad_numbers_are_jumpers no)
		(fp_line
			(start -0.7874 0.4064)
			(end 0.7874 0.4064)
			(stroke
				(width 0.1524)
				(type default)
			)
			(layer "B.SilkS")
		)
		(fp_line
			(start 0.7874 0.4064)
			(end 0.7874 -0.4064)
			(stroke
				(width 0.1524)
				(type default)
			)
			(layer "B.SilkS")
		)
		(fp_line
			(start -0.7874 -0.4064)
			(end -0.7874 0.4064)
			(stroke
				(width 0.1524)
				(type default)
			)
			(layer "B.SilkS")
		)
		(fp_line
			(start 0.7874 -0.4064)
			(end -0.7874 -0.4064)
			(stroke
				(width 0.1524)
				(type default)
			)
			(layer "B.SilkS")
		)
		(fp_line
			(start -0.67945 0.3048)
			(end -0.120396 0.3048)
			(stroke
				(width 0.1)
				(type default)
			)
			(layer "B.Fab")
		)
		(fp_line
			(start -0.120396 0.3048)
			(end -0.120396 0.2794)
			(stroke
				(width 0.1)
				(type default)
			)
			(layer "B.Fab")
		)
		(fp_line
			(start 0.12065 0.3048)
			(end 0.67945 0.3048)
			(stroke
				(width 0.1)
				(type default)
			)
			(layer "B.Fab")
		)
		(fp_line
			(start 0.67945 0.3048)
			(end 0.67945 -0.305054)
			(stroke
				(width 0.1)
				(type default)
			)
			(layer "B.Fab")
		)
		(fp_line
			(start -0.120396 0.2794)
			(end 0.12065 0.2794)
			(stroke
				(width 0.1)
				(type default)
			)
			(layer "B.Fab")
		)
		(fp_line
			(start 0.12065 0.2794)
			(end 0.12065 0.3048)
			(stroke
				(width 0.1)
				(type default)
			)
			(layer "B.Fab")
		)
		(fp_line
			(start -0.12065 -0.2794)
			(end -0.12065 -0.3048)
			(stroke
				(width 0.1)
				(type default)
			)
			(layer "B.Fab")
		)
		(fp_line
			(start 0.12065 -0.2794)
			(end -0.12065 -0.2794)
			(stroke
				(width 0.1)
				(type default)
			)
			(layer "B.Fab")
		)
		(fp_line
			(start -0.67945 -0.3048)
			(end -0.67945 0.3048)
			(stroke
				(width 0.1)
				(type default)
			)
			(layer "B.Fab")
		)
		(fp_line
			(start -0.12065 -0.3048)
			(end -0.67945 -0.3048)
			(stroke
				(width 0.1)
				(type default)
			)
			(layer "B.Fab")
		)
		(fp_line
			(start 0.12065 -0.305054)
			(end 0.12065 -0.2794)
			(stroke
				(width 0.1)
				(type default)
			)
			(layer "B.Fab")
		)
		(fp_line
			(start 0.67945 -0.305054)
			(end 0.12065 -0.305054)
			(stroke
				(width 0.1)
				(type default)
			)
			(layer "B.Fab")
		)
		(pad "1" smd circle
			(at 0.40005 0 90)
			(size 0 0)
			(layers "B.Cu" "B.Mask" "B.Paste")
			(net "OCP_SFF_PRSNT01_R1_N")
		)
		(pad "2" smd circle
			(at -0.40005 0 90)
			(size 0 0)
			(layers "B.Cu" "B.Mask" "B.Paste")
			(net "GND")
		)
	)
	(footprint ""
		(layer "B.Cu")
		(at 190.163196 -244.085364)
		(property "Reference" "R509"
			(at 0 0 0)
			(layer "B.SilkS")
			(hide yes)
			(effects
				(font
					(size 1.27 1.27)
				)
				(justify mirror)
			)
		)
		(property "Value" ""
			(at 0 0 0)
			(layer "B.Fab")
			(effects
				(font
					(size 1.27 1.27)
				)
				(justify mirror)
			)
		)
		(duplicate_pad_numbers_are_jumpers no)
		(fp_line
			(start -0.7874 -0.4064)
			(end -0.7874 0.4064)
			(stroke
				(width 0.1524)
				(type default)
			)
			(layer "B.SilkS")
		)
		(fp_line
			(start -0.7874 0.4064)
			(end 0.7874 0.4064)
			(stroke
				(width 0.1524)
				(type default)
			)
			(layer "B.SilkS")
		)
		(fp_line
			(start 0.7874 -0.4064)
			(end -0.7874 -0.4064)
			(stroke
				(width 0.1524)
				(type default)
			)
			(layer "B.SilkS")
		)
		(fp_line
			(start 0.7874 0.4064)
			(end 0.7874 -0.4064)
			(stroke
				(width 0.1524)
				(type default)
			)
			(layer "B.SilkS")
		)
		(fp_line
			(start -0.67945 -0.3048)
			(end -0.67945 0.3048)
			(stroke
				(width 0.1)
				(type default)
			)
			(layer "B.Fab")
		)
		(fp_line
			(start -0.67945 0.3048)
			(end -0.120396 0.3048)
			(stroke
				(width 0.1)
				(type default)
			)
			(layer "B.Fab")
		)
		(fp_line
			(start -0.12065 -0.3048)
			(end -0.67945 -0.3048)
			(stroke
				(width 0.1)
				(type default)
			)
			(layer "B.Fab")
		)
		(fp_line
			(start -0.12065 -0.2794)
			(end -0.12065 -0.3048)
			(stroke
				(width 0.1)
				(type default)
			)
			(layer "B.Fab")
		)
		(fp_line
			(start -0.120396 0.2794)
			(end 0.12065 0.2794)
			(stroke
				(width 0.1)
				(type default)
			)
			(layer "B.Fab")
		)
		(fp_line
			(start -0.120396 0.3048)
			(end -0.120396 0.2794)
			(stroke
				(width 0.1)
				(type default)
			)
			(layer "B.Fab")
		)
		(fp_line
			(start 0.12065 -0.305054)
			(end 0.12065 -0.2794)
			(stroke
				(width 0.1)
				(type default)
			)
			(layer "B.Fab")
		)
		(fp_line
			(start 0.12065 -0.2794)
			(end -0.12065 -0.2794)
			(stroke
				(width 0.1)
				(type default)
			)
			(layer "B.Fab")
		)
		(fp_line
			(start 0.12065 0.2794)
			(end 0.12065 0.3048)
			(stroke
				(width 0.1)
				(type default)
			)
			(layer "B.Fab")
		)
		(fp_line
			(start 0.12065 0.3048)
			(end 0.67945 0.3048)
			(stroke
				(width 0.1)
				(type default)
			)
			(layer "B.Fab")
		)
		(fp_line
			(start 0.67945 -0.305054)
			(end 0.12065 -0.305054)
			(stroke
				(width 0.1)
				(type default)
			)
			(layer "B.Fab")
		)
		(fp_line
			(start 0.67945 0.3048)
			(end 0.67945 -0.305054)
			(stroke
				(width 0.1)
				(type default)
			)
			(layer "B.Fab")
		)
		(pad "1" smd circle
			(at 0.40005 0 180)
			(size 0 0)
			(layers "B.Cu" "B.Mask" "B.Paste")
			(net "M_J_CPU1_ALERT_N")
		)
		(pad "2" smd circle
			(at -0.40005 0 180)
			(size 0 0)
			(layers "B.Cu" "B.Mask" "B.Paste")
			(net "M_J_CPU1_ALERT_R_N")
		)
	)
	(footprint ""
		(layer "B.Cu")
		(at 197.269608 -126.833376 180)
		(property "Reference" "R265"
			(at 0 0 0)
			(layer "B.SilkS")
			(hide yes)
			(effects
				(font
					(size 1.27 1.27)
				)
				(justify mirror)
			)
		)
		(property "Value" ""
			(at 0 0 0)
			(layer "B.Fab")
			(effects
				(font
					(size 1.27 1.27)
				)
				(justify mirror)
			)
		)
		(duplicate_pad_numbers_are_jumpers no)
		(fp_line
			(start 0.7874 0.4064)
			(end 0.7874 -0.4064)
			(stroke
				(width 0.1524)
				(type default)
			)
			(layer "B.SilkS")
		)
		(fp_line
			(start 0.7874 -0.4064)
			(end -0.7874 -0.4064)
			(stroke
				(width 0.1524)
				(type default)
			)
			(layer "B.SilkS")
		)
		(fp_line
			(start -0.7874 0.4064)
			(end 0.7874 0.4064)
			(stroke
				(width 0.1524)
				(type default)
			)
			(layer "B.SilkS")
		)
		(fp_line
			(start -0.7874 -0.4064)
			(end -0.7874 0.4064)
			(stroke
				(width 0.1524)
				(type default)
			)
			(layer "B.SilkS")
		)
		(fp_line
			(start 0.67945 0.3048)
			(end 0.67945 -0.305054)
			(stroke
				(width 0.1)
				(type default)
			)
			(layer "B.Fab")
		)
		(fp_line
			(start 0.67945 -0.305054)
			(end 0.12065 -0.305054)
			(stroke
				(width 0.1)
				(type default)
			)
			(layer "B.Fab")
		)
		(fp_line
			(start 0.12065 0.3048)
			(end 0.67945 0.3048)
			(stroke
				(width 0.1)
				(type default)
			)
			(layer "B.Fab")
		)
		(fp_line
			(start 0.12065 0.2794)
			(end 0.12065 0.3048)
			(stroke
				(width 0.1)
				(type default)
			)
			(layer "B.Fab")
		)
		(fp_line
			(start 0.12065 -0.2794)
			(end -0.12065 -0.2794)
			(stroke
				(width 0.1)
				(type default)
			)
			(layer "B.Fab")
		)
		(fp_line
			(start 0.12065 -0.305054)
			(end 0.12065 -0.2794)
			(stroke
				(width 0.1)
				(type default)
			)
			(layer "B.Fab")
		)
		(fp_line
			(start -0.120396 0.3048)
			(end -0.120396 0.2794)
			(stroke
				(width 0.1)
				(type default)
			)
			(layer "B.Fab")
		)
		(fp_line
			(start -0.120396 0.2794)
			(end 0.12065 0.2794)
			(stroke
				(width 0.1)
				(type default)
			)
			(layer "B.Fab")
		)
		(fp_line
			(start -0.12065 -0.2794)
			(end -0.12065 -0.3048)
			(stroke
				(width 0.1)
				(type default)
			)
			(layer "B.Fab")
		)
		(fp_line
			(start -0.12065 -0.3048)
			(end -0.67945 -0.3048)
			(stroke
				(width 0.1)
				(type default)
			)
			(layer "B.Fab")
		)
		(fp_line
			(start -0.67945 0.3048)
			(end -0.120396 0.3048)
			(stroke
				(width 0.1)
				(type default)
			)
			(layer "B.Fab")
		)
		(fp_line
			(start -0.67945 -0.3048)
			(end -0.67945 0.3048)
			(stroke
				(width 0.1)
				(type default)
			)
			(layer "B.Fab")
		)
		(pad "1" smd circle
			(at 0.40005 0)
			(size 0 0)
			(layers "B.Cu" "B.Mask" "B.Paste")
			(net "FM_CPU1_FORCE_SELFREFRESH")
		)
		(pad "2" smd circle
			(at -0.40005 0)
			(size 0 0)
			(layers "B.Cu" "B.Mask" "B.Paste")
			(net "CPU1_FORCE_SELFREFRESH")
		)
	)
	(footprint ""
		(layer "B.Cu")
		(at 98.493834 -265.045952)
		(property "Reference" "C2108"
			(at 0 0 0)
			(layer "B.SilkS")
			(hide yes)
			(effects
				(font
					(size 1.27 1.27)
				)
				(justify mirror)
			)
		)
		(property "Value" ""
			(at 0 0 0)
			(layer "B.Fab")
			(effects
				(font
					(size 1.27 1.27)
				)
				(justify mirror)
			)
		)
		(duplicate_pad_numbers_are_jumpers no)
		(fp_line
			(start -0.7874 -0.4064)
			(end -0.7874 0.4064)
			(stroke
				(width 0.1524)
				(type default)
			)
			(layer "B.SilkS")
		)
		(fp_line
			(start -0.7874 0.4064)
			(end 0.7874 0.4064)
			(stroke
				(width 0.1524)
				(type default)
			)
			(layer "B.SilkS")
		)
		(fp_line
			(start 0.7874 -0.4064)
			(end -0.7874 -0.4064)
			(stroke
				(width 0.1524)
				(type default)
			)
			(layer "B.SilkS")
		)
		(fp_line
			(start 0.7874 0.4064)
			(end 0.7874 -0.4064)
			(stroke
				(width 0.1524)
				(type default)
			)
			(layer "B.SilkS")
		)
		(fp_line
			(start -0.67945 -0.3048)
			(end -0.67945 0.3048)
			(stroke
				(width 0.1)
				(type default)
			)
			(layer "B.Fab")
		)
		(fp_line
			(start -0.67945 0.3048)
			(end -0.120396 0.3048)
			(stroke
				(width 0.1)
				(type default)
			)
			(layer "B.Fab")
		)
		(fp_line
			(start -0.12065 -0.3048)
			(end -0.67945 -0.3048)
			(stroke
				(width 0.1)
				(type default)
			)
			(layer "B.Fab")
		)
		(fp_line
			(start -0.12065 -0.2794)
			(end -0.12065 -0.3048)
			(stroke
				(width 0.1)
				(type default)
			)
			(layer "B.Fab")
		)
		(fp_line
			(start -0.120396 0.2794)
			(end 0.12065 0.2794)
			(stroke
				(width 0.1)
				(type default)
			)
			(layer "B.Fab")
		)
		(fp_line
			(start -0.120396 0.3048)
			(end -0.120396 0.2794)
			(stroke
				(width 0.1)
				(type default)
			)
			(layer "B.Fab")
		)
		(fp_line
			(start 0.12065 -0.305054)
			(end 0.12065 -0.2794)
			(stroke
				(width 0.1)
				(type default)
			)
			(layer "B.Fab")
		)
		(fp_line
			(start 0.12065 -0.2794)
			(end -0.12065 -0.2794)
			(stroke
				(width 0.1)
				(type default)
			)
			(layer "B.Fab")
		)
		(fp_line
			(start 0.12065 0.2794)
			(end 0.12065 0.3048)
			(stroke
				(width 0.1)
				(type default)
			)
			(layer "B.Fab")
		)
		(fp_line
			(start 0.12065 0.3048)
			(end 0.67945 0.3048)
			(stroke
				(width 0.1)
				(type default)
			)
			(layer "B.Fab")
		)
		(fp_line
			(start 0.67945 -0.305054)
			(end 0.12065 -0.305054)
			(stroke
				(width 0.1)
				(type default)
			)
			(layer "B.Fab")
		)
		(fp_line
			(start 0.67945 0.3048)
			(end 0.67945 -0.305054)
			(stroke
				(width 0.1)
				(type default)
			)
			(layer "B.Fab")
		)
		(pad "1" smd circle
			(at 0.40005 0 180)
			(size 0 0)
			(layers "B.Cu" "B.Mask" "B.Paste")
			(net "PVDDIO_P1")
		)
		(pad "2" smd circle
			(at -0.40005 0 180)
			(size 0 0)
			(layers "B.Cu" "B.Mask" "B.Paste")
			(net "GND")
		)
	)
	(footprint ""
		(layer "B.Cu")
		(at 132.491226 -390.560052 90)
		(property "Reference" "C482"
			(at 0 0 90)
			(layer "B.SilkS")
			(hide yes)
			(effects
				(font
					(size 1.27 1.27)
				)
				(justify mirror)
			)
		)
		(property "Value" ""
			(at 0 0 90)
			(layer "B.Fab")
			(effects
				(font
					(size 1.27 1.27)
				)
				(justify mirror)
			)
		)
		(duplicate_pad_numbers_are_jumpers no)
		(fp_line
			(start 0.7874 -0.4064)
			(end -0.7874 -0.4064)
			(stroke
				(width 0.1524)
				(type default)
			)
			(layer "B.SilkS")
		)
		(fp_line
			(start -0.7874 -0.4064)
			(end -0.7874 0.4064)
			(stroke
				(width 0.1524)
				(type default)
			)
			(layer "B.SilkS")
		)
		(fp_line
			(start 0.7874 0.4064)
			(end 0.7874 -0.4064)
			(stroke
				(width 0.1524)
				(type default)
			)
			(layer "B.SilkS")
		)
		(fp_line
			(start -0.7874 0.4064)
			(end 0.7874 0.4064)
			(stroke
				(width 0.1524)
				(type default)
			)
			(layer "B.SilkS")
		)
		(fp_line
			(start 0.67945 -0.305054)
			(end 0.12065 -0.305054)
			(stroke
				(width 0.1)
				(type default)
			)
			(layer "B.Fab")
		)
		(fp_line
			(start 0.12065 -0.305054)
			(end 0.12065 -0.2794)
			(stroke
				(width 0.1)
				(type default)
			)
			(layer "B.Fab")
		)
		(fp_line
			(start -0.12065 -0.3048)
			(end -0.67945 -0.3048)
			(stroke
				(width 0.1)
				(type default)
			)
			(layer "B.Fab")
		)
		(fp_line
			(start -0.67945 -0.3048)
			(end -0.67945 0.3048)
			(stroke
				(width 0.1)
				(type default)
			)
			(layer "B.Fab")
		)
		(fp_line
			(start 0.12065 -0.2794)
			(end -0.12065 -0.2794)
			(stroke
				(width 0.1)
				(type default)
			)
			(layer "B.Fab")
		)
		(fp_line
			(start -0.12065 -0.2794)
			(end -0.12065 -0.3048)
			(stroke
				(width 0.1)
				(type default)
			)
			(layer "B.Fab")
		)
		(fp_line
			(start 0.12065 0.2794)
			(end 0.12065 0.3048)
			(stroke
				(width 0.1)
				(type default)
			)
			(layer "B.Fab")
		)
		(fp_line
			(start -0.120396 0.2794)
			(end 0.12065 0.2794)
			(stroke
				(width 0.1)
				(type default)
			)
			(layer "B.Fab")
		)
		(fp_line
			(start 0.67945 0.3048)
			(end 0.67945 -0.305054)
			(stroke
				(width 0.1)
				(type default)
			)
			(layer "B.Fab")
		)
		(fp_line
			(start 0.12065 0.3048)
			(end 0.67945 0.3048)
			(stroke
				(width 0.1)
				(type default)
			)
			(layer "B.Fab")
		)
		(fp_line
			(start -0.120396 0.3048)
			(end -0.120396 0.2794)
			(stroke
				(width 0.1)
				(type default)
			)
			(layer "B.Fab")
		)
		(fp_line
			(start -0.67945 0.3048)
			(end -0.120396 0.3048)
			(stroke
				(width 0.1)
				(type default)
			)
			(layer "B.Fab")
		)
		(pad "1" smd circle
			(at 0.40005 0 270)
			(size 0 0)
			(layers "B.Cu" "B.Mask" "B.Paste")
			(net "P0V9_CPU1_RT3_2A")
		)
		(pad "2" smd circle
			(at -0.40005 0 270)
			(size 0 0)
			(layers "B.Cu" "B.Mask" "B.Paste")
			(net "GND")
		)
	)
	(footprint ""
		(layer "B.Cu")
		(at 187.815728 -194.885564 180)
		(property "Reference" "R776"
			(at 0 0 0)
			(layer "B.SilkS")
			(hide yes)
			(effects
				(font
					(size 1.27 1.27)
				)
				(justify mirror)
			)
		)
		(property "Value" ""
			(at 0 0 0)
			(layer "B.Fab")
			(effects
				(font
					(size 1.27 1.27)
				)
				(justify mirror)
			)
		)
		(duplicate_pad_numbers_are_jumpers no)
		(fp_line
			(start 0.7874 0.4064)
			(end 0.7874 -0.4064)
			(stroke
				(width 0.1524)
				(type default)
			)
			(layer "B.SilkS")
		)
		(fp_line
			(start 0.7874 -0.4064)
			(end -0.7874 -0.4064)
			(stroke
				(width 0.1524)
				(type default)
			)
			(layer "B.SilkS")
		)
		(fp_line
			(start -0.7874 0.4064)
			(end 0.7874 0.4064)
			(stroke
				(width 0.1524)
				(type default)
			)
			(layer "B.SilkS")
		)
		(fp_line
			(start -0.7874 -0.4064)
			(end -0.7874 0.4064)
			(stroke
				(width 0.1524)
				(type default)
			)
			(layer "B.SilkS")
		)
		(fp_line
			(start 0.67945 0.3048)
			(end 0.67945 -0.305054)
			(stroke
				(width 0.1)
				(type default)
			)
			(layer "B.Fab")
		)
		(fp_line
			(start 0.67945 -0.305054)
			(end 0.12065 -0.305054)
			(stroke
				(width 0.1)
				(type default)
			)
			(layer "B.Fab")
		)
		(fp_line
			(start 0.12065 0.3048)
			(end 0.67945 0.3048)
			(stroke
				(width 0.1)
				(type default)
			)
			(layer "B.Fab")
		)
		(fp_line
			(start 0.12065 0.2794)
			(end 0.12065 0.3048)
			(stroke
				(width 0.1)
				(type default)
			)
			(layer "B.Fab")
		)
		(fp_line
			(start 0.12065 -0.2794)
			(end -0.12065 -0.2794)
			(stroke
				(width 0.1)
				(type default)
			)
			(layer "B.Fab")
		)
		(fp_line
			(start 0.12065 -0.305054)
			(end 0.12065 -0.2794)
			(stroke
				(width 0.1)
				(type default)
			)
			(layer "B.Fab")
		)
		(fp_line
			(start -0.120396 0.3048)
			(end -0.120396 0.2794)
			(stroke
				(width 0.1)
				(type default)
			)
			(layer "B.Fab")
		)
		(fp_line
			(start -0.120396 0.2794)
			(end 0.12065 0.2794)
			(stroke
				(width 0.1)
				(type default)
			)
			(layer "B.Fab")
		)
		(fp_line
			(start -0.12065 -0.2794)
			(end -0.12065 -0.3048)
			(stroke
				(width 0.1)
				(type default)
			)
			(layer "B.Fab")
		)
		(fp_line
			(start -0.12065 -0.3048)
			(end -0.67945 -0.3048)
			(stroke
				(width 0.1)
				(type default)
			)
			(layer "B.Fab")
		)
		(fp_line
			(start -0.67945 0.3048)
			(end -0.120396 0.3048)
			(stroke
				(width 0.1)
				(type default)
			)
			(layer "B.Fab")
		)
		(fp_line
			(start -0.67945 -0.3048)
			(end -0.67945 0.3048)
			(stroke
				(width 0.1)
				(type default)
			)
			(layer "B.Fab")
		)
		(pad "1" smd circle
			(at 0.40005 0)
			(size 0 0)
			(layers "B.Cu" "B.Mask" "B.Paste")
			(net "PD_CHJ_CPU1_DIMM_SAA")
		)
		(pad "2" smd circle
			(at -0.40005 0)
			(size 0 0)
			(layers "B.Cu" "B.Mask" "B.Paste")
			(net "GND")
		)
	)
	(footprint ""
		(layer "B.Cu")
		(at 380.091188 -398.942052 90)
		(property "Reference" "C995"
			(at 0 0 90)
			(layer "B.SilkS")
			(hide yes)
			(effects
				(font
					(size 1.27 1.27)
				)
				(justify mirror)
			)
		)
		(property "Value" ""
			(at 0 0 90)
			(layer "B.Fab")
			(effects
				(font
					(size 1.27 1.27)
				)
				(justify mirror)
			)
		)
		(duplicate_pad_numbers_are_jumpers no)
		(fp_line
			(start 0.7874 -0.4064)
			(end -0.7874 -0.4064)
			(stroke
				(width 0.1524)
				(type default)
			)
			(layer "B.SilkS")
		)
		(fp_line
			(start -0.7874 -0.4064)
			(end -0.7874 0.4064)
			(stroke
				(width 0.1524)
				(type default)
			)
			(layer "B.SilkS")
		)
		(fp_line
			(start 0.7874 0.4064)
			(end 0.7874 -0.4064)
			(stroke
				(width 0.1524)
				(type default)
			)
			(layer "B.SilkS")
		)
		(fp_line
			(start -0.7874 0.4064)
			(end 0.7874 0.4064)
			(stroke
				(width 0.1524)
				(type default)
			)
			(layer "B.SilkS")
		)
		(fp_line
			(start 0.67945 -0.305054)
			(end 0.12065 -0.305054)
			(stroke
				(width 0.1)
				(type default)
			)
			(layer "B.Fab")
		)
		(fp_line
			(start 0.12065 -0.305054)
			(end 0.12065 -0.2794)
			(stroke
				(width 0.1)
				(type default)
			)
			(layer "B.Fab")
		)
		(fp_line
			(start -0.12065 -0.3048)
			(end -0.67945 -0.3048)
			(stroke
				(width 0.1)
				(type default)
			)
			(layer "B.Fab")
		)
		(fp_line
			(start -0.67945 -0.3048)
			(end -0.67945 0.3048)
			(stroke
				(width 0.1)
				(type default)
			)
			(layer "B.Fab")
		)
		(fp_line
			(start 0.12065 -0.2794)
			(end -0.12065 -0.2794)
			(stroke
				(width 0.1)
				(type default)
			)
			(layer "B.Fab")
		)
		(fp_line
			(start -0.12065 -0.2794)
			(end -0.12065 -0.3048)
			(stroke
				(width 0.1)
				(type default)
			)
			(layer "B.Fab")
		)
		(fp_line
			(start 0.12065 0.2794)
			(end 0.12065 0.3048)
			(stroke
				(width 0.1)
				(type default)
			)
			(layer "B.Fab")
		)
		(fp_line
			(start -0.120396 0.2794)
			(end 0.12065 0.2794)
			(stroke
				(width 0.1)
				(type default)
			)
			(layer "B.Fab")
		)
		(fp_line
			(start 0.67945 0.3048)
			(end 0.67945 -0.305054)
			(stroke
				(width 0.1)
				(type default)
			)
			(layer "B.Fab")
		)
		(fp_line
			(start 0.12065 0.3048)
			(end 0.67945 0.3048)
			(stroke
				(width 0.1)
				(type default)
			)
			(layer "B.Fab")
		)
		(fp_line
			(start -0.120396 0.3048)
			(end -0.120396 0.2794)
			(stroke
				(width 0.1)
				(type default)
			)
			(layer "B.Fab")
		)
		(fp_line
			(start -0.67945 0.3048)
			(end -0.120396 0.3048)
			(stroke
				(width 0.1)
				(type default)
			)
			(layer "B.Fab")
		)
		(pad "1" smd circle
			(at 0.40005 0 270)
			(size 0 0)
			(layers "B.Cu" "B.Mask" "B.Paste")
			(net "P1V8_CPU0_RT3_1A")
		)
		(pad "2" smd circle
			(at -0.40005 0 270)
			(size 0 0)
			(layers "B.Cu" "B.Mask" "B.Paste")
			(net "GND")
		)
	)
	(footprint ""
		(layer "B.Cu")
		(at 230.886 -332.74)
		(property "Reference" "R6770"
			(at 0 0 0)
			(layer "B.SilkS")
			(hide yes)
			(effects
				(font
					(size 1.27 1.27)
				)
				(justify mirror)
			)
		)
		(property "Value" ""
			(at 0 0 0)
			(layer "B.Fab")
			(effects
				(font
					(size 1.27 1.27)
				)
				(justify mirror)
			)
		)
		(duplicate_pad_numbers_are_jumpers no)
		(fp_line
			(start -0.32512 -0.175006)
			(end -0.32512 0.175006)
			(stroke
				(width 0.1)
				(type default)
			)
			(layer "B.Fab")
		)
		(fp_line
			(start -0.32512 0.175006)
			(end 0.32512 0.175006)
			(stroke
				(width 0.1)
				(type default)
			)
			(layer "B.Fab")
		)
		(fp_line
			(start 0.32512 -0.175006)
			(end -0.32512 -0.175006)
			(stroke
				(width 0.1)
				(type default)
			)
			(layer "B.Fab")
		)
		(fp_line
			(start 0.32512 0.175006)
			(end 0.32512 -0.175006)
			(stroke
				(width 0.1)
				(type default)
			)
			(layer "B.Fab")
		)
		(pad "1" smd rect
			(at 0.2667 0 180)
			(size 0.3048 0.381)
			(layers "B.Cu" "B.Mask" "B.Paste")
			(net "P1V8_AUX")
		)
		(pad "2" smd rect
			(at -0.2667 0)
			(size 0.3048 0.381)
			(layers "B.Cu" "B.Mask" "B.Paste")
			(net "RT_SMB_MUX_ADDR2")
		)
	)
	(footprint ""
		(layer "B.Cu")
		(at 326.252078 -392.957558)
		(property "Reference" "L11"
			(at 0 0 0)
			(layer "B.SilkS")
			(hide yes)
			(effects
				(font
					(size 1.27 1.27)
				)
				(justify mirror)
			)
		)
		(property "Value" ""
			(at 0 0 0)
			(layer "B.Fab")
			(effects
				(font
					(size 1.27 1.27)
				)
				(justify mirror)
			)
		)
		(duplicate_pad_numbers_are_jumpers no)
		(fp_line
			(start -1.63576 -0.8128)
			(end -1.63576 0.8128)
			(stroke
				(width 0.1524)
				(type default)
			)
			(layer "B.SilkS")
		)
		(fp_line
			(start -1.63576 0.8128)
			(end 1.63576 0.8128)
			(stroke
				(width 0.1524)
				(type default)
			)
			(layer "B.SilkS")
		)
		(fp_line
			(start 1.63576 -0.8128)
			(end -1.63576 -0.8128)
			(stroke
				(width 0.1524)
				(type default)
			)
			(layer "B.SilkS")
		)
		(fp_line
			(start 1.63576 -0.8128)
			(end 1.63576 0.8128)
			(stroke
				(width 0.1524)
				(type default)
			)
			(layer "B.SilkS")
		)
		(fp_line
			(start -1.560576 -0.738632)
			(end 1.56083 -0.738632)
			(stroke
				(width 0.1)
				(type default)
			)
			(layer "B.Fab")
		)
		(fp_line
			(start -1.560576 0.7366)
			(end -1.560576 -0.738632)
			(stroke
				(width 0.1)
				(type default)
			)
			(layer "B.Fab")
		)
		(fp_line
			(start -1.524 0.7366)
			(end -1.560576 0.7366)
			(stroke
				(width 0.1)
				(type default)
			)
			(layer "B.Fab")
		)
		(fp_line
			(start 1.524 0.7366)
			(end -1.524 0.7366)
			(stroke
				(width 0.1)
				(type default)
			)
			(layer "B.Fab")
		)
		(fp_line
			(start 1.56083 -0.738632)
			(end 1.56083 0.7366)
			(stroke
				(width 0.1)
				(type default)
			)
			(layer "B.Fab")
		)
		(fp_line
			(start 1.56083 0.7366)
			(end 1.524 0.7366)
			(stroke
				(width 0.1)
				(type default)
			)
			(layer "B.Fab")
		)
		(pad "1" smd rect
			(at 0.94996 0)
			(size 1.1176 1.3716)
			(layers "B.Cu" "B.Mask" "B.Paste")
			(net "P1V8_CPU0_RT_1D")
		)
		(pad "2" smd rect
			(at -0.94996 0)
			(size 1.1176 1.3716)
			(layers "B.Cu" "B.Mask" "B.Paste")
			(net "P1V8_CPU0_RT0_1A")
		)
	)
	(footprint ""
		(layer "B.Cu")
		(at 122.496834 -272.284952)
		(property "Reference" "C2372"
			(at 0 0 0)
			(layer "B.SilkS")
			(hide yes)
			(effects
				(font
					(size 1.27 1.27)
				)
				(justify mirror)
			)
		)
		(property "Value" ""
			(at 0 0 0)
			(layer "B.Fab")
			(effects
				(font
					(size 1.27 1.27)
				)
				(justify mirror)
			)
		)
		(duplicate_pad_numbers_are_jumpers no)
		(fp_line
			(start -0.7874 -0.4064)
			(end -0.7874 0.4064)
			(stroke
				(width 0.1524)
				(type default)
			)
			(layer "B.SilkS")
		)
		(fp_line
			(start -0.7874 0.4064)
			(end 0.7874 0.4064)
			(stroke
				(width 0.1524)
				(type default)
			)
			(layer "B.SilkS")
		)
		(fp_line
			(start 0.7874 -0.4064)
			(end -0.7874 -0.4064)
			(stroke
				(width 0.1524)
				(type default)
			)
			(layer "B.SilkS")
		)
		(fp_line
			(start 0.7874 0.4064)
			(end 0.7874 -0.4064)
			(stroke
				(width 0.1524)
				(type default)
			)
			(layer "B.SilkS")
		)
		(fp_line
			(start -0.67945 -0.3048)
			(end -0.67945 0.3048)
			(stroke
				(width 0.1)
				(type default)
			)
			(layer "B.Fab")
		)
		(fp_line
			(start -0.67945 0.3048)
			(end -0.120396 0.3048)
			(stroke
				(width 0.1)
				(type default)
			)
			(layer "B.Fab")
		)
		(fp_line
			(start -0.12065 -0.3048)
			(end -0.67945 -0.3048)
			(stroke
				(width 0.1)
				(type default)
			)
			(layer "B.Fab")
		)
		(fp_line
			(start -0.12065 -0.2794)
			(end -0.12065 -0.3048)
			(stroke
				(width 0.1)
				(type default)
			)
			(layer "B.Fab")
		)
		(fp_line
			(start -0.120396 0.2794)
			(end 0.12065 0.2794)
			(stroke
				(width 0.1)
				(type default)
			)
			(layer "B.Fab")
		)
		(fp_line
			(start -0.120396 0.3048)
			(end -0.120396 0.2794)
			(stroke
				(width 0.1)
				(type default)
			)
			(layer "B.Fab")
		)
		(fp_line
			(start 0.12065 -0.305054)
			(end 0.12065 -0.2794)
			(stroke
				(width 0.1)
				(type default)
			)
			(layer "B.Fab")
		)
		(fp_line
			(start 0.12065 -0.2794)
			(end -0.12065 -0.2794)
			(stroke
				(width 0.1)
				(type default)
			)
			(layer "B.Fab")
		)
		(fp_line
			(start 0.12065 0.2794)
			(end 0.12065 0.3048)
			(stroke
				(width 0.1)
				(type default)
			)
			(layer "B.Fab")
		)
		(fp_line
			(start 0.12065 0.3048)
			(end 0.67945 0.3048)
			(stroke
				(width 0.1)
				(type default)
			)
			(layer "B.Fab")
		)
		(fp_line
			(start 0.67945 -0.305054)
			(end 0.12065 -0.305054)
			(stroke
				(width 0.1)
				(type default)
			)
			(layer "B.Fab")
		)
		(fp_line
			(start 0.67945 0.3048)
			(end 0.67945 -0.305054)
			(stroke
				(width 0.1)
				(type default)
			)
			(layer "B.Fab")
		)
		(pad "1" smd circle
			(at 0.40005 0 180)
			(size 0 0)
			(layers "B.Cu" "B.Mask" "B.Paste")
			(net "PVDDCR_CPU1_P1")
		)
		(pad "2" smd circle
			(at -0.40005 0 180)
			(size 0 0)
			(layers "B.Cu" "B.Mask" "B.Paste")
			(net "GND")
		)
	)
	(footprint ""
		(layer "B.Cu")
		(at 321.378326 -395.148562 90)
		(property "Reference" "C525"
			(at 0 0 90)
			(layer "B.SilkS")
			(hide yes)
			(effects
				(font
					(size 1.27 1.27)
				)
				(justify mirror)
			)
		)
		(property "Value" ""
			(at 0 0 90)
			(layer "B.Fab")
			(effects
				(font
					(size 1.27 1.27)
				)
				(justify mirror)
			)
		)
		(duplicate_pad_numbers_are_jumpers no)
		(fp_line
			(start 0.299974 -0.150114)
			(end -0.299974 -0.150114)
			(stroke
				(width 0.1)
				(type default)
			)
			(layer "B.Fab")
		)
		(fp_line
			(start -0.299974 -0.150114)
			(end -0.299974 0.150114)
			(stroke
				(width 0.1)
				(type default)
			)
			(layer "B.Fab")
		)
		(fp_line
			(start 0.299974 0.150114)
			(end 0.299974 -0.150114)
			(stroke
				(width 0.1)
				(type default)
			)
			(layer "B.Fab")
		)
		(fp_line
			(start -0.299974 0.150114)
			(end 0.299974 0.150114)
			(stroke
				(width 0.1)
				(type default)
			)
			(layer "B.Fab")
		)
		(pad "1" smd rect
			(at 0.2667 0 270)
			(size 0.3048 0.381)
			(layers "B.Cu" "B.Mask" "B.Paste")
			(net "P0V9_CPU0_RT0_2A")
		)
		(pad "2" smd rect
			(at -0.2667 0 270)
			(size 0.3048 0.381)
			(layers "B.Cu" "B.Mask" "B.Paste")
			(net "GND")
		)
	)
	(footprint ""
		(layer "B.Cu")
		(at 147.146264 -388.011162 -90)
		(property "Reference" "C421"
			(at 0 0 90)
			(layer "B.SilkS")
			(hide yes)
			(effects
				(font
					(size 1.27 1.27)
				)
				(justify mirror)
			)
		)
		(property "Value" ""
			(at 0 0 90)
			(layer "B.Fab")
			(effects
				(font
					(size 1.27 1.27)
				)
				(justify mirror)
			)
		)
		(duplicate_pad_numbers_are_jumpers no)
		(fp_line
			(start -0.299974 0.150114)
			(end 0.299974 0.150114)
			(stroke
				(width 0.1)
				(type default)
			)
			(layer "B.Fab")
		)
		(fp_line
			(start 0.299974 0.150114)
			(end 0.299974 -0.150114)
			(stroke
				(width 0.1)
				(type default)
			)
			(layer "B.Fab")
		)
		(fp_line
			(start -0.299974 -0.150114)
			(end -0.299974 0.150114)
			(stroke
				(width 0.1)
				(type default)
			)
			(layer "B.Fab")
		)
		(fp_line
			(start 0.299974 -0.150114)
			(end -0.299974 -0.150114)
			(stroke
				(width 0.1)
				(type default)
			)
			(layer "B.Fab")
		)
		(pad "1" smd rect
			(at 0.2667 0 90)
			(size 0.3048 0.381)
			(layers "B.Cu" "B.Mask" "B.Paste")
			(net "P0V9_CPU1_RT2_2A")
		)
		(pad "2" smd rect
			(at -0.2667 0 90)
			(size 0.3048 0.381)
			(layers "B.Cu" "B.Mask" "B.Paste")
			(net "GND")
		)
	)
	(footprint ""
		(layer "B.Cu")
		(at 182.499 -145.542 90)
		(property "Reference" "R8036"
			(at 0 0 90)
			(layer "B.SilkS")
			(hide yes)
			(effects
				(font
					(size 1.27 1.27)
				)
				(justify mirror)
			)
		)
		(property "Value" ""
			(at 0 0 90)
			(layer "B.Fab")
			(effects
				(font
					(size 1.27 1.27)
				)
				(justify mirror)
			)
		)
		(duplicate_pad_numbers_are_jumpers no)
		(fp_line
			(start 0.7874 -0.4064)
			(end -0.7874 -0.4064)
			(stroke
				(width 0.1524)
				(type default)
			)
			(layer "B.SilkS")
		)
		(fp_line
			(start -0.7874 -0.4064)
			(end -0.7874 0.4064)
			(stroke
				(width 0.1524)
				(type default)
			)
			(layer "B.SilkS")
		)
		(fp_line
			(start 0.7874 0.4064)
			(end 0.7874 -0.4064)
			(stroke
				(width 0.1524)
				(type default)
			)
			(layer "B.SilkS")
		)
		(fp_line
			(start -0.7874 0.4064)
			(end 0.7874 0.4064)
			(stroke
				(width 0.1524)
				(type default)
			)
			(layer "B.SilkS")
		)
		(fp_line
			(start 0.67945 -0.305054)
			(end 0.12065 -0.305054)
			(stroke
				(width 0.1)
				(type default)
			)
			(layer "B.Fab")
		)
		(fp_line
			(start 0.12065 -0.305054)
			(end 0.12065 -0.2794)
			(stroke
				(width 0.1)
				(type default)
			)
			(layer "B.Fab")
		)
		(fp_line
			(start -0.12065 -0.3048)
			(end -0.67945 -0.3048)
			(stroke
				(width 0.1)
				(type default)
			)
			(layer "B.Fab")
		)
		(fp_line
			(start -0.67945 -0.3048)
			(end -0.67945 0.3048)
			(stroke
				(width 0.1)
				(type default)
			)
			(layer "B.Fab")
		)
		(fp_line
			(start 0.12065 -0.2794)
			(end -0.12065 -0.2794)
			(stroke
				(width 0.1)
				(type default)
			)
			(layer "B.Fab")
		)
		(fp_line
			(start -0.12065 -0.2794)
			(end -0.12065 -0.3048)
			(stroke
				(width 0.1)
				(type default)
			)
			(layer "B.Fab")
		)
		(fp_line
			(start 0.12065 0.2794)
			(end 0.12065 0.3048)
			(stroke
				(width 0.1)
				(type default)
			)
			(layer "B.Fab")
		)
		(fp_line
			(start -0.120396 0.2794)
			(end 0.12065 0.2794)
			(stroke
				(width 0.1)
				(type default)
			)
			(layer "B.Fab")
		)
		(fp_line
			(start 0.67945 0.3048)
			(end 0.67945 -0.305054)
			(stroke
				(width 0.1)
				(type default)
			)
			(layer "B.Fab")
		)
		(fp_line
			(start 0.12065 0.3048)
			(end 0.67945 0.3048)
			(stroke
				(width 0.1)
				(type default)
			)
			(layer "B.Fab")
		)
		(fp_line
			(start -0.120396 0.3048)
			(end -0.120396 0.2794)
			(stroke
				(width 0.1)
				(type default)
			)
			(layer "B.Fab")
		)
		(fp_line
			(start -0.67945 0.3048)
			(end -0.120396 0.3048)
			(stroke
				(width 0.1)
				(type default)
			)
			(layer "B.Fab")
		)
		(pad "1" smd circle
			(at 0.40005 0 270)
			(size 0 0)
			(layers "B.Cu" "B.Mask" "B.Paste")
			(net "PVDD18_S5_P0")
		)
		(pad "2" smd circle
			(at -0.40005 0 270)
			(size 0 0)
			(layers "B.Cu" "B.Mask" "B.Paste")
			(net "ESPI_CPU0_ALERT_PLD_N")
		)
	)
	(footprint ""
		(layer "B.Cu")
		(at 447.237866 -405.7777)
		(property "Reference" "PC6560"
			(at 0 0 0)
			(layer "B.SilkS")
			(hide yes)
			(effects
				(font
					(size 1.27 1.27)
				)
				(justify mirror)
			)
		)
		(property "Value" ""
			(at 0 0 0)
			(layer "B.Fab")
			(effects
				(font
					(size 1.27 1.27)
				)
				(justify mirror)
			)
		)
		(duplicate_pad_numbers_are_jumpers no)
		(fp_line
			(start -1.524 -0.762)
			(end -1.524 0.762)
			(stroke
				(width 0.1524)
				(type default)
			)
			(layer "B.SilkS")
		)
		(fp_line
			(start -1.524 0.762)
			(end 1.524 0.762)
			(stroke
				(width 0.1524)
				(type default)
			)
			(layer "B.SilkS")
		)
		(fp_line
			(start 1.524 -0.762)
			(end -1.524 -0.762)
			(stroke
				(width 0.1524)
				(type default)
			)
			(layer "B.SilkS")
		)
		(fp_line
			(start 1.524 0.762)
			(end 1.524 -0.762)
			(stroke
				(width 0.1524)
				(type default)
			)
			(layer "B.SilkS")
		)
		(fp_line
			(start -1.1049 -0.724916)
			(end 1.1049 -0.724916)
			(stroke
				(width 0.1)
				(type default)
			)
			(layer "B.Fab")
		)
		(fp_line
			(start -1.1049 0.724916)
			(end -1.1049 -0.724916)
			(stroke
				(width 0.1)
				(type default)
			)
			(layer "B.Fab")
		)
		(fp_line
			(start 1.1049 -0.724916)
			(end 1.1049 0.724916)
			(stroke
				(width 0.1)
				(type default)
			)
			(layer "B.Fab")
		)
		(fp_line
			(start 1.1049 0.724916)
			(end -1.1049 0.724916)
			(stroke
				(width 0.1)
				(type default)
			)
			(layer "B.Fab")
		)
		(pad "1" smd rect
			(at 0.889 0)
			(size 1.016 1.27)
			(layers "B.Cu" "B.Mask" "B.Paste")
			(net "SW_P12V_AUX_P0V9_RETIMER_CPU0_FLT")
		)
		(pad "2" smd rect
			(at -0.889 0)
			(size 1.016 1.27)
			(layers "B.Cu" "B.Mask" "B.Paste")
			(net "GND")
		)
	)
	(footprint ""
		(layer "B.Cu")
		(at 365.709454 -264.35431)
		(property "Reference" "C2653"
			(at 0 0 0)
			(layer "B.SilkS")
			(hide yes)
			(effects
				(font
					(size 1.27 1.27)
				)
				(justify mirror)
			)
		)
		(property "Value" ""
			(at 0 0 0)
			(layer "B.Fab")
			(effects
				(font
					(size 1.27 1.27)
				)
				(justify mirror)
			)
		)
		(duplicate_pad_numbers_are_jumpers no)
		(fp_line
			(start -0.7874 -0.4064)
			(end -0.7874 0.4064)
			(stroke
				(width 0.1524)
				(type default)
			)
			(layer "B.SilkS")
		)
		(fp_line
			(start -0.7874 0.4064)
			(end 0.7874 0.4064)
			(stroke
				(width 0.1524)
				(type default)
			)
			(layer "B.SilkS")
		)
		(fp_line
			(start 0.7874 -0.4064)
			(end -0.7874 -0.4064)
			(stroke
				(width 0.1524)
				(type default)
			)
			(layer "B.SilkS")
		)
		(fp_line
			(start 0.7874 0.4064)
			(end 0.7874 -0.4064)
			(stroke
				(width 0.1524)
				(type default)
			)
			(layer "B.SilkS")
		)
		(fp_line
			(start -0.67945 -0.3048)
			(end -0.67945 0.3048)
			(stroke
				(width 0.1)
				(type default)
			)
			(layer "B.Fab")
		)
		(fp_line
			(start -0.67945 0.3048)
			(end -0.120396 0.3048)
			(stroke
				(width 0.1)
				(type default)
			)
			(layer "B.Fab")
		)
		(fp_line
			(start -0.12065 -0.3048)
			(end -0.67945 -0.3048)
			(stroke
				(width 0.1)
				(type default)
			)
			(layer "B.Fab")
		)
		(fp_line
			(start -0.12065 -0.2794)
			(end -0.12065 -0.3048)
			(stroke
				(width 0.1)
				(type default)
			)
			(layer "B.Fab")
		)
		(fp_line
			(start -0.120396 0.2794)
			(end 0.12065 0.2794)
			(stroke
				(width 0.1)
				(type default)
			)
			(layer "B.Fab")
		)
		(fp_line
			(start -0.120396 0.3048)
			(end -0.120396 0.2794)
			(stroke
				(width 0.1)
				(type default)
			)
			(layer "B.Fab")
		)
		(fp_line
			(start 0.12065 -0.305054)
			(end 0.12065 -0.2794)
			(stroke
				(width 0.1)
				(type default)
			)
			(layer "B.Fab")
		)
		(fp_line
			(start 0.12065 -0.2794)
			(end -0.12065 -0.2794)
			(stroke
				(width 0.1)
				(type default)
			)
			(layer "B.Fab")
		)
		(fp_line
			(start 0.12065 0.2794)
			(end 0.12065 0.3048)
			(stroke
				(width 0.1)
				(type default)
			)
			(layer "B.Fab")
		)
		(fp_line
			(start 0.12065 0.3048)
			(end 0.67945 0.3048)
			(stroke
				(width 0.1)
				(type default)
			)
			(layer "B.Fab")
		)
		(fp_line
			(start 0.67945 -0.305054)
			(end 0.12065 -0.305054)
			(stroke
				(width 0.1)
				(type default)
			)
			(layer "B.Fab")
		)
		(fp_line
			(start 0.67945 0.3048)
			(end 0.67945 -0.305054)
			(stroke
				(width 0.1)
				(type default)
			)
			(layer "B.Fab")
		)
		(pad "1" smd circle
			(at 0.40005 0 180)
			(size 0 0)
			(layers "B.Cu" "B.Mask" "B.Paste")
			(net "PVDD11_S3_P0")
		)
		(pad "2" smd circle
			(at -0.40005 0 180)
			(size 0 0)
			(layers "B.Cu" "B.Mask" "B.Paste")
			(net "GND")
		)
	)
	(footprint ""
		(layer "B.Cu")
		(at 435.000146 -192.660016 180)
		(property "Reference" "C165"
			(at 0 0 0)
			(layer "B.SilkS")
			(hide yes)
			(effects
				(font
					(size 1.27 1.27)
				)
				(justify mirror)
			)
		)
		(property "Value" ""
			(at 0 0 0)
			(layer "B.Fab")
			(effects
				(font
					(size 1.27 1.27)
				)
				(justify mirror)
			)
		)
		(duplicate_pad_numbers_are_jumpers no)
		(fp_line
			(start 1.524 0.762)
			(end 1.524 -0.762)
			(stroke
				(width 0.1524)
				(type default)
			)
			(layer "B.SilkS")
		)
		(fp_line
			(start 1.524 -0.762)
			(end -1.524 -0.762)
			(stroke
				(width 0.1524)
				(type default)
			)
			(layer "B.SilkS")
		)
		(fp_line
			(start -1.524 0.762)
			(end 1.524 0.762)
			(stroke
				(width 0.1524)
				(type default)
			)
			(layer "B.SilkS")
		)
		(fp_line
			(start -1.524 -0.762)
			(end -1.524 0.762)
			(stroke
				(width 0.1524)
				(type default)
			)
			(layer "B.SilkS")
		)
		(fp_line
			(start 1.1049 0.724916)
			(end -1.1049 0.724916)
			(stroke
				(width 0.1)
				(type default)
			)
			(layer "B.Fab")
		)
		(fp_line
			(start 1.1049 -0.724916)
			(end 1.1049 0.724916)
			(stroke
				(width 0.1)
				(type default)
			)
			(layer "B.Fab")
		)
		(fp_line
			(start -1.1049 0.724916)
			(end -1.1049 -0.724916)
			(stroke
				(width 0.1)
				(type default)
			)
			(layer "B.Fab")
		)
		(fp_line
			(start -1.1049 -0.724916)
			(end 1.1049 -0.724916)
			(stroke
				(width 0.1)
				(type default)
			)
			(layer "B.Fab")
		)
		(pad "1" smd rect
			(at 0.889 0 180)
			(size 1.016 1.27)
			(layers "B.Cu" "B.Mask" "B.Paste")
			(net "P12V_MEM_CPU0")
		)
		(pad "2" smd rect
			(at -0.889 0 180)
			(size 1.016 1.27)
			(layers "B.Cu" "B.Mask" "B.Paste")
			(net "GND")
		)
	)
	(footprint ""
		(layer "B.Cu")
		(at 22.479 -362.204 180)
		(property "Reference" "C5006"
			(at 0 0 0)
			(layer "B.SilkS")
			(hide yes)
			(effects
				(font
					(size 1.27 1.27)
				)
				(justify mirror)
			)
		)
		(property "Value" ""
			(at 0 0 0)
			(layer "B.Fab")
			(effects
				(font
					(size 1.27 1.27)
				)
				(justify mirror)
			)
		)
		(duplicate_pad_numbers_are_jumpers no)
		(fp_line
			(start 0.7874 0.4064)
			(end 0.7874 -0.4064)
			(stroke
				(width 0.1524)
				(type default)
			)
			(layer "B.SilkS")
		)
		(fp_line
			(start 0.7874 -0.4064)
			(end -0.7874 -0.4064)
			(stroke
				(width 0.1524)
				(type default)
			)
			(layer "B.SilkS")
		)
		(fp_line
			(start -0.7874 0.4064)
			(end 0.7874 0.4064)
			(stroke
				(width 0.1524)
				(type default)
			)
			(layer "B.SilkS")
		)
		(fp_line
			(start -0.7874 -0.4064)
			(end -0.7874 0.4064)
			(stroke
				(width 0.1524)
				(type default)
			)
			(layer "B.SilkS")
		)
		(fp_line
			(start 0.67945 0.3048)
			(end 0.67945 -0.305054)
			(stroke
				(width 0.1)
				(type default)
			)
			(layer "B.Fab")
		)
		(fp_line
			(start 0.67945 -0.305054)
			(end 0.12065 -0.305054)
			(stroke
				(width 0.1)
				(type default)
			)
			(layer "B.Fab")
		)
		(fp_line
			(start 0.12065 0.3048)
			(end 0.67945 0.3048)
			(stroke
				(width 0.1)
				(type default)
			)
			(layer "B.Fab")
		)
		(fp_line
			(start 0.12065 0.2794)
			(end 0.12065 0.3048)
			(stroke
				(width 0.1)
				(type default)
			)
			(layer "B.Fab")
		)
		(fp_line
			(start 0.12065 -0.2794)
			(end -0.12065 -0.2794)
			(stroke
				(width 0.1)
				(type default)
			)
			(layer "B.Fab")
		)
		(fp_line
			(start 0.12065 -0.305054)
			(end 0.12065 -0.2794)
			(stroke
				(width 0.1)
				(type default)
			)
			(layer "B.Fab")
		)
		(fp_line
			(start -0.120396 0.3048)
			(end -0.120396 0.2794)
			(stroke
				(width 0.1)
				(type default)
			)
			(layer "B.Fab")
		)
		(fp_line
			(start -0.120396 0.2794)
			(end 0.12065 0.2794)
			(stroke
				(width 0.1)
				(type default)
			)
			(layer "B.Fab")
		)
		(fp_line
			(start -0.12065 -0.2794)
			(end -0.12065 -0.3048)
			(stroke
				(width 0.1)
				(type default)
			)
			(layer "B.Fab")
		)
		(fp_line
			(start -0.12065 -0.3048)
			(end -0.67945 -0.3048)
			(stroke
				(width 0.1)
				(type default)
			)
			(layer "B.Fab")
		)
		(fp_line
			(start -0.67945 0.3048)
			(end -0.120396 0.3048)
			(stroke
				(width 0.1)
				(type default)
			)
			(layer "B.Fab")
		)
		(fp_line
			(start -0.67945 -0.3048)
			(end -0.67945 0.3048)
			(stroke
				(width 0.1)
				(type default)
			)
			(layer "B.Fab")
		)
		(pad "1" smd circle
			(at 0.40005 0)
			(size 0 0)
			(layers "B.Cu" "B.Mask" "B.Paste")
			(net "GND")
		)
		(pad "2" smd circle
			(at -0.40005 0)
			(size 0 0)
			(layers "B.Cu" "B.Mask" "B.Paste")
			(net "PWRGD_PVDDIO_P1")
		)
	)
	(footprint ""
		(layer "B.Cu")
		(at 40.9956 -194.885564 180)
		(property "Reference" "R771"
			(at 0 0 0)
			(layer "B.SilkS")
			(hide yes)
			(effects
				(font
					(size 1.27 1.27)
				)
				(justify mirror)
			)
		)
		(property "Value" ""
			(at 0 0 0)
			(layer "B.Fab")
			(effects
				(font
					(size 1.27 1.27)
				)
				(justify mirror)
			)
		)
		(duplicate_pad_numbers_are_jumpers no)
		(fp_line
			(start 0.7874 0.4064)
			(end 0.7874 -0.4064)
			(stroke
				(width 0.1524)
				(type default)
			)
			(layer "B.SilkS")
		)
		(fp_line
			(start 0.7874 -0.4064)
			(end -0.7874 -0.4064)
			(stroke
				(width 0.1524)
				(type default)
			)
			(layer "B.SilkS")
		)
		(fp_line
			(start -0.7874 0.4064)
			(end 0.7874 0.4064)
			(stroke
				(width 0.1524)
				(type default)
			)
			(layer "B.SilkS")
		)
		(fp_line
			(start -0.7874 -0.4064)
			(end -0.7874 0.4064)
			(stroke
				(width 0.1524)
				(type default)
			)
			(layer "B.SilkS")
		)
		(fp_line
			(start 0.67945 0.3048)
			(end 0.67945 -0.305054)
			(stroke
				(width 0.1)
				(type default)
			)
			(layer "B.Fab")
		)
		(fp_line
			(start 0.67945 -0.305054)
			(end 0.12065 -0.305054)
			(stroke
				(width 0.1)
				(type default)
			)
			(layer "B.Fab")
		)
		(fp_line
			(start 0.12065 0.3048)
			(end 0.67945 0.3048)
			(stroke
				(width 0.1)
				(type default)
			)
			(layer "B.Fab")
		)
		(fp_line
			(start 0.12065 0.2794)
			(end 0.12065 0.3048)
			(stroke
				(width 0.1)
				(type default)
			)
			(layer "B.Fab")
		)
		(fp_line
			(start 0.12065 -0.2794)
			(end -0.12065 -0.2794)
			(stroke
				(width 0.1)
				(type default)
			)
			(layer "B.Fab")
		)
		(fp_line
			(start 0.12065 -0.305054)
			(end 0.12065 -0.2794)
			(stroke
				(width 0.1)
				(type default)
			)
			(layer "B.Fab")
		)
		(fp_line
			(start -0.120396 0.3048)
			(end -0.120396 0.2794)
			(stroke
				(width 0.1)
				(type default)
			)
			(layer "B.Fab")
		)
		(fp_line
			(start -0.120396 0.2794)
			(end 0.12065 0.2794)
			(stroke
				(width 0.1)
				(type default)
			)
			(layer "B.Fab")
		)
		(fp_line
			(start -0.12065 -0.2794)
			(end -0.12065 -0.3048)
			(stroke
				(width 0.1)
				(type default)
			)
			(layer "B.Fab")
		)
		(fp_line
			(start -0.12065 -0.3048)
			(end -0.67945 -0.3048)
			(stroke
				(width 0.1)
				(type default)
			)
			(layer "B.Fab")
		)
		(fp_line
			(start -0.67945 0.3048)
			(end -0.120396 0.3048)
			(stroke
				(width 0.1)
				(type default)
			)
			(layer "B.Fab")
		)
		(fp_line
			(start -0.67945 -0.3048)
			(end -0.67945 0.3048)
			(stroke
				(width 0.1)
				(type default)
			)
			(layer "B.Fab")
		)
		(pad "1" smd circle
			(at 0.40005 0)
			(size 0 0)
			(layers "B.Cu" "B.Mask" "B.Paste")
			(net "PD_CHC_CPU1_DIMM_SAA")
		)
		(pad "2" smd circle
			(at -0.40005 0)
			(size 0 0)
			(layers "B.Cu" "B.Mask" "B.Paste")
			(net "GND")
		)
	)
	(footprint ""
		(layer "B.Cu")
		(at 241.173 -222.25 -90)
		(property "Reference" "C611"
			(at 0 0 90)
			(layer "B.SilkS")
			(hide yes)
			(effects
				(font
					(size 1.27 1.27)
				)
				(justify mirror)
			)
		)
		(property "Value" ""
			(at 0 0 90)
			(layer "B.Fab")
			(effects
				(font
					(size 1.27 1.27)
				)
				(justify mirror)
			)
		)
		(duplicate_pad_numbers_are_jumpers no)
		(fp_line
			(start -0.7874 0.4064)
			(end 0.7874 0.4064)
			(stroke
				(width 0.1524)
				(type default)
			)
			(layer "B.SilkS")
		)
		(fp_line
			(start 0.7874 0.4064)
			(end 0.7874 -0.4064)
			(stroke
				(width 0.1524)
				(type default)
			)
			(layer "B.SilkS")
		)
		(fp_line
			(start -0.7874 -0.4064)
			(end -0.7874 0.4064)
			(stroke
				(width 0.1524)
				(type default)
			)
			(layer "B.SilkS")
		)
		(fp_line
			(start 0.7874 -0.4064)
			(end -0.7874 -0.4064)
			(stroke
				(width 0.1524)
				(type default)
			)
			(layer "B.SilkS")
		)
		(fp_line
			(start -0.67945 0.3048)
			(end -0.120396 0.3048)
			(stroke
				(width 0.1)
				(type default)
			)
			(layer "B.Fab")
		)
		(fp_line
			(start -0.120396 0.3048)
			(end -0.120396 0.2794)
			(stroke
				(width 0.1)
				(type default)
			)
			(layer "B.Fab")
		)
		(fp_line
			(start 0.12065 0.3048)
			(end 0.67945 0.3048)
			(stroke
				(width 0.1)
				(type default)
			)
			(layer "B.Fab")
		)
		(fp_line
			(start 0.67945 0.3048)
			(end 0.67945 -0.305054)
			(stroke
				(width 0.1)
				(type default)
			)
			(layer "B.Fab")
		)
		(fp_line
			(start -0.120396 0.2794)
			(end 0.12065 0.2794)
			(stroke
				(width 0.1)
				(type default)
			)
			(layer "B.Fab")
		)
		(fp_line
			(start 0.12065 0.2794)
			(end 0.12065 0.3048)
			(stroke
				(width 0.1)
				(type default)
			)
			(layer "B.Fab")
		)
		(fp_line
			(start -0.12065 -0.2794)
			(end -0.12065 -0.3048)
			(stroke
				(width 0.1)
				(type default)
			)
			(layer "B.Fab")
		)
		(fp_line
			(start 0.12065 -0.2794)
			(end -0.12065 -0.2794)
			(stroke
				(width 0.1)
				(type default)
			)
			(layer "B.Fab")
		)
		(fp_line
			(start -0.67945 -0.3048)
			(end -0.67945 0.3048)
			(stroke
				(width 0.1)
				(type default)
			)
			(layer "B.Fab")
		)
		(fp_line
			(start -0.12065 -0.3048)
			(end -0.67945 -0.3048)
			(stroke
				(width 0.1)
				(type default)
			)
			(layer "B.Fab")
		)
		(fp_line
			(start 0.12065 -0.305054)
			(end 0.12065 -0.2794)
			(stroke
				(width 0.1)
				(type default)
			)
			(layer "B.Fab")
		)
		(fp_line
			(start 0.67945 -0.305054)
			(end 0.12065 -0.305054)
			(stroke
				(width 0.1)
				(type default)
			)
			(layer "B.Fab")
		)
		(pad "1" smd circle
			(at 0.40005 0 90)
			(size 0 0)
			(layers "B.Cu" "B.Mask" "B.Paste")
			(net "P3V3_AUX")
		)
		(pad "2" smd circle
			(at -0.40005 0 90)
			(size 0 0)
			(layers "B.Cu" "B.Mask" "B.Paste")
			(net "GND")
		)
	)
	(footprint ""
		(layer "B.Cu")
		(at 79.015082 -391.340848 -90)
		(property "Reference" "C336"
			(at 0 0 90)
			(layer "B.SilkS")
			(hide yes)
			(effects
				(font
					(size 1.27 1.27)
				)
				(justify mirror)
			)
		)
		(property "Value" ""
			(at 0 0 90)
			(layer "B.Fab")
			(effects
				(font
					(size 1.27 1.27)
				)
				(justify mirror)
			)
		)
		(duplicate_pad_numbers_are_jumpers no)
		(fp_line
			(start -0.7874 0.4064)
			(end 0.7874 0.4064)
			(stroke
				(width 0.1524)
				(type default)
			)
			(layer "B.SilkS")
		)
		(fp_line
			(start 0.7874 0.4064)
			(end 0.7874 -0.4064)
			(stroke
				(width 0.1524)
				(type default)
			)
			(layer "B.SilkS")
		)
		(fp_line
			(start -0.7874 -0.4064)
			(end -0.7874 0.4064)
			(stroke
				(width 0.1524)
				(type default)
			)
			(layer "B.SilkS")
		)
		(fp_line
			(start 0.7874 -0.4064)
			(end -0.7874 -0.4064)
			(stroke
				(width 0.1524)
				(type default)
			)
			(layer "B.SilkS")
		)
		(fp_line
			(start -0.67945 0.3048)
			(end -0.120396 0.3048)
			(stroke
				(width 0.1)
				(type default)
			)
			(layer "B.Fab")
		)
		(fp_line
			(start -0.120396 0.3048)
			(end -0.120396 0.2794)
			(stroke
				(width 0.1)
				(type default)
			)
			(layer "B.Fab")
		)
		(fp_line
			(start 0.12065 0.3048)
			(end 0.67945 0.3048)
			(stroke
				(width 0.1)
				(type default)
			)
			(layer "B.Fab")
		)
		(fp_line
			(start 0.67945 0.3048)
			(end 0.67945 -0.305054)
			(stroke
				(width 0.1)
				(type default)
			)
			(layer "B.Fab")
		)
		(fp_line
			(start -0.120396 0.2794)
			(end 0.12065 0.2794)
			(stroke
				(width 0.1)
				(type default)
			)
			(layer "B.Fab")
		)
		(fp_line
			(start 0.12065 0.2794)
			(end 0.12065 0.3048)
			(stroke
				(width 0.1)
				(type default)
			)
			(layer "B.Fab")
		)
		(fp_line
			(start -0.12065 -0.2794)
			(end -0.12065 -0.3048)
			(stroke
				(width 0.1)
				(type default)
			)
			(layer "B.Fab")
		)
		(fp_line
			(start 0.12065 -0.2794)
			(end -0.12065 -0.2794)
			(stroke
				(width 0.1)
				(type default)
			)
			(layer "B.Fab")
		)
		(fp_line
			(start -0.67945 -0.3048)
			(end -0.67945 0.3048)
			(stroke
				(width 0.1)
				(type default)
			)
			(layer "B.Fab")
		)
		(fp_line
			(start -0.12065 -0.3048)
			(end -0.67945 -0.3048)
			(stroke
				(width 0.1)
				(type default)
			)
			(layer "B.Fab")
		)
		(fp_line
			(start 0.12065 -0.305054)
			(end 0.12065 -0.2794)
			(stroke
				(width 0.1)
				(type default)
			)
			(layer "B.Fab")
		)
		(fp_line
			(start 0.67945 -0.305054)
			(end 0.12065 -0.305054)
			(stroke
				(width 0.1)
				(type default)
			)
			(layer "B.Fab")
		)
		(pad "1" smd circle
			(at 0.40005 0 90)
			(size 0 0)
			(layers "B.Cu" "B.Mask" "B.Paste")
			(net "P0V9_CPU1_RT1_2A")
		)
		(pad "2" smd circle
			(at -0.40005 0 90)
			(size 0 0)
			(layers "B.Cu" "B.Mask" "B.Paste")
			(net "GND")
		)
	)
	(footprint ""
		(layer "B.Cu")
		(at 24.765 -365.76 180)
		(property "Reference" "R8234"
			(at 0 0 0)
			(layer "B.SilkS")
			(hide yes)
			(effects
				(font
					(size 1.27 1.27)
				)
				(justify mirror)
			)
		)
		(property "Value" ""
			(at 0 0 0)
			(layer "B.Fab")
			(effects
				(font
					(size 1.27 1.27)
				)
				(justify mirror)
			)
		)
		(duplicate_pad_numbers_are_jumpers no)
		(fp_line
			(start 0.7874 0.4064)
			(end 0.7874 -0.4064)
			(stroke
				(width 0.1524)
				(type default)
			)
			(layer "B.SilkS")
		)
		(fp_line
			(start 0.7874 -0.4064)
			(end -0.7874 -0.4064)
			(stroke
				(width 0.1524)
				(type default)
			)
			(layer "B.SilkS")
		)
		(fp_line
			(start -0.7874 0.4064)
			(end 0.7874 0.4064)
			(stroke
				(width 0.1524)
				(type default)
			)
			(layer "B.SilkS")
		)
		(fp_line
			(start -0.7874 -0.4064)
			(end -0.7874 0.4064)
			(stroke
				(width 0.1524)
				(type default)
			)
			(layer "B.SilkS")
		)
		(fp_line
			(start 0.67945 0.3048)
			(end 0.67945 -0.305054)
			(stroke
				(width 0.1)
				(type default)
			)
			(layer "B.Fab")
		)
		(fp_line
			(start 0.67945 -0.305054)
			(end 0.12065 -0.305054)
			(stroke
				(width 0.1)
				(type default)
			)
			(layer "B.Fab")
		)
		(fp_line
			(start 0.12065 0.3048)
			(end 0.67945 0.3048)
			(stroke
				(width 0.1)
				(type default)
			)
			(layer "B.Fab")
		)
		(fp_line
			(start 0.12065 0.2794)
			(end 0.12065 0.3048)
			(stroke
				(width 0.1)
				(type default)
			)
			(layer "B.Fab")
		)
		(fp_line
			(start 0.12065 -0.2794)
			(end -0.12065 -0.2794)
			(stroke
				(width 0.1)
				(type default)
			)
			(layer "B.Fab")
		)
		(fp_line
			(start 0.12065 -0.305054)
			(end 0.12065 -0.2794)
			(stroke
				(width 0.1)
				(type default)
			)
			(layer "B.Fab")
		)
		(fp_line
			(start -0.120396 0.3048)
			(end -0.120396 0.2794)
			(stroke
				(width 0.1)
				(type default)
			)
			(layer "B.Fab")
		)
		(fp_line
			(start -0.120396 0.2794)
			(end 0.12065 0.2794)
			(stroke
				(width 0.1)
				(type default)
			)
			(layer "B.Fab")
		)
		(fp_line
			(start -0.12065 -0.2794)
			(end -0.12065 -0.3048)
			(stroke
				(width 0.1)
				(type default)
			)
			(layer "B.Fab")
		)
		(fp_line
			(start -0.12065 -0.3048)
			(end -0.67945 -0.3048)
			(stroke
				(width 0.1)
				(type default)
			)
			(layer "B.Fab")
		)
		(fp_line
			(start -0.67945 0.3048)
			(end -0.120396 0.3048)
			(stroke
				(width 0.1)
				(type default)
			)
			(layer "B.Fab")
		)
		(fp_line
			(start -0.67945 -0.3048)
			(end -0.67945 0.3048)
			(stroke
				(width 0.1)
				(type default)
			)
			(layer "B.Fab")
		)
		(pad "1" smd circle
			(at 0.40005 0)
			(size 0 0)
			(layers "B.Cu" "B.Mask" "B.Paste")
			(net "PWRGD_PVDDCR_CPU1_P1")
		)
		(pad "2" smd circle
			(at -0.40005 0)
			(size 0 0)
			(layers "B.Cu" "B.Mask" "B.Paste")
			(net "PWRGD_PVDDCR_CPU1_P1_R")
		)
	)
	(footprint ""
		(layer "B.Cu")
		(at 106.184954 -174.340012 90)
		(property "Reference" "PC295_4"
			(at 0 0 90)
			(layer "B.SilkS")
			(hide yes)
			(effects
				(font
					(size 1.27 1.27)
				)
				(justify mirror)
			)
		)
		(property "Value" ""
			(at 0 0 90)
			(layer "B.Fab")
			(effects
				(font
					(size 1.27 1.27)
				)
				(justify mirror)
			)
		)
		(duplicate_pad_numbers_are_jumpers no)
		(fp_line
			(start 1.524 -0.762)
			(end -1.524 -0.762)
			(stroke
				(width 0.1524)
				(type default)
			)
			(layer "B.SilkS")
		)
		(fp_line
			(start -1.524 -0.762)
			(end -1.524 0.762)
			(stroke
				(width 0.1524)
				(type default)
			)
			(layer "B.SilkS")
		)
		(fp_line
			(start 1.524 0.762)
			(end 1.524 -0.762)
			(stroke
				(width 0.1524)
				(type default)
			)
			(layer "B.SilkS")
		)
		(fp_line
			(start -1.524 0.762)
			(end 1.524 0.762)
			(stroke
				(width 0.1524)
				(type default)
			)
			(layer "B.SilkS")
		)
		(fp_line
			(start 1.1049 -0.724916)
			(end 1.1049 0.724916)
			(stroke
				(width 0.1)
				(type default)
			)
			(layer "B.Fab")
		)
		(fp_line
			(start -1.1049 -0.724916)
			(end 1.1049 -0.724916)
			(stroke
				(width 0.1)
				(type default)
			)
			(layer "B.Fab")
		)
		(fp_line
			(start 1.1049 0.724916)
			(end -1.1049 0.724916)
			(stroke
				(width 0.1)
				(type default)
			)
			(layer "B.Fab")
		)
		(fp_line
			(start -1.1049 0.724916)
			(end -1.1049 -0.724916)
			(stroke
				(width 0.1)
				(type default)
			)
			(layer "B.Fab")
		)
		(pad "1" smd rect
			(at 0.889 0 90)
			(size 1.016 1.27)
			(layers "B.Cu" "B.Mask" "B.Paste")
			(net "SW_P12V_AUX_PVDDCR_CPU0_P1_FLT")
		)
		(pad "2" smd rect
			(at -0.889 0 90)
			(size 1.016 1.27)
			(layers "B.Cu" "B.Mask" "B.Paste")
			(net "GND")
		)
	)
	(footprint ""
		(layer "B.Cu")
		(at 99.111562 -386.766562 90)
		(property "Reference" "C353"
			(at 0 0 90)
			(layer "B.SilkS")
			(hide yes)
			(effects
				(font
					(size 1.27 1.27)
				)
				(justify mirror)
			)
		)
		(property "Value" ""
			(at 0 0 90)
			(layer "B.Fab")
			(effects
				(font
					(size 1.27 1.27)
				)
				(justify mirror)
			)
		)
		(duplicate_pad_numbers_are_jumpers no)
		(fp_line
			(start 0.299974 -0.150114)
			(end -0.299974 -0.150114)
			(stroke
				(width 0.1)
				(type default)
			)
			(layer "B.Fab")
		)
		(fp_line
			(start -0.299974 -0.150114)
			(end -0.299974 0.150114)
			(stroke
				(width 0.1)
				(type default)
			)
			(layer "B.Fab")
		)
		(fp_line
			(start 0.299974 0.150114)
			(end 0.299974 -0.150114)
			(stroke
				(width 0.1)
				(type default)
			)
			(layer "B.Fab")
		)
		(fp_line
			(start -0.299974 0.150114)
			(end 0.299974 0.150114)
			(stroke
				(width 0.1)
				(type default)
			)
			(layer "B.Fab")
		)
		(pad "1" smd rect
			(at 0.2667 0 270)
			(size 0.3048 0.381)
			(layers "B.Cu" "B.Mask" "B.Paste")
			(net "P0V9_CPU1_RT1_2A")
		)
		(pad "2" smd rect
			(at -0.2667 0 270)
			(size 0.3048 0.381)
			(layers "B.Cu" "B.Mask" "B.Paste")
			(net "GND")
		)
	)
	(footprint ""
		(layer "B.Cu")
		(at 322.7451 -398.942052 90)
		(property "Reference" "C575"
			(at 0 0 90)
			(layer "B.SilkS")
			(hide yes)
			(effects
				(font
					(size 1.27 1.27)
				)
				(justify mirror)
			)
		)
		(property "Value" ""
			(at 0 0 90)
			(layer "B.Fab")
			(effects
				(font
					(size 1.27 1.27)
				)
				(justify mirror)
			)
		)
		(duplicate_pad_numbers_are_jumpers no)
		(fp_line
			(start 0.7874 -0.4064)
			(end -0.7874 -0.4064)
			(stroke
				(width 0.1524)
				(type default)
			)
			(layer "B.SilkS")
		)
		(fp_line
			(start -0.7874 -0.4064)
			(end -0.7874 0.4064)
			(stroke
				(width 0.1524)
				(type default)
			)
			(layer "B.SilkS")
		)
		(fp_line
			(start 0.7874 0.4064)
			(end 0.7874 -0.4064)
			(stroke
				(width 0.1524)
				(type default)
			)
			(layer "B.SilkS")
		)
		(fp_line
			(start -0.7874 0.4064)
			(end 0.7874 0.4064)
			(stroke
				(width 0.1524)
				(type default)
			)
			(layer "B.SilkS")
		)
		(fp_line
			(start 0.67945 -0.305054)
			(end 0.12065 -0.305054)
			(stroke
				(width 0.1)
				(type default)
			)
			(layer "B.Fab")
		)
		(fp_line
			(start 0.12065 -0.305054)
			(end 0.12065 -0.2794)
			(stroke
				(width 0.1)
				(type default)
			)
			(layer "B.Fab")
		)
		(fp_line
			(start -0.12065 -0.3048)
			(end -0.67945 -0.3048)
			(stroke
				(width 0.1)
				(type default)
			)
			(layer "B.Fab")
		)
		(fp_line
			(start -0.67945 -0.3048)
			(end -0.67945 0.3048)
			(stroke
				(width 0.1)
				(type default)
			)
			(layer "B.Fab")
		)
		(fp_line
			(start 0.12065 -0.2794)
			(end -0.12065 -0.2794)
			(stroke
				(width 0.1)
				(type default)
			)
			(layer "B.Fab")
		)
		(fp_line
			(start -0.12065 -0.2794)
			(end -0.12065 -0.3048)
			(stroke
				(width 0.1)
				(type default)
			)
			(layer "B.Fab")
		)
		(fp_line
			(start 0.12065 0.2794)
			(end 0.12065 0.3048)
			(stroke
				(width 0.1)
				(type default)
			)
			(layer "B.Fab")
		)
		(fp_line
			(start -0.120396 0.2794)
			(end 0.12065 0.2794)
			(stroke
				(width 0.1)
				(type default)
			)
			(layer "B.Fab")
		)
		(fp_line
			(start 0.67945 0.3048)
			(end 0.67945 -0.305054)
			(stroke
				(width 0.1)
				(type default)
			)
			(layer "B.Fab")
		)
		(fp_line
			(start 0.12065 0.3048)
			(end 0.67945 0.3048)
			(stroke
				(width 0.1)
				(type default)
			)
			(layer "B.Fab")
		)
		(fp_line
			(start -0.120396 0.3048)
			(end -0.120396 0.2794)
			(stroke
				(width 0.1)
				(type default)
			)
			(layer "B.Fab")
		)
		(fp_line
			(start -0.67945 0.3048)
			(end -0.120396 0.3048)
			(stroke
				(width 0.1)
				(type default)
			)
			(layer "B.Fab")
		)
		(pad "1" smd circle
			(at 0.40005 0 270)
			(size 0 0)
			(layers "B.Cu" "B.Mask" "B.Paste")
			(net "P0V9_CPU0_RT0_2A")
		)
		(pad "2" smd circle
			(at -0.40005 0 270)
			(size 0 0)
			(layers "B.Cu" "B.Mask" "B.Paste")
			(net "GND")
		)
	)
	(footprint ""
		(layer "B.Cu")
		(at 385.018534 -396.393162 -90)
		(property "Reference" "C1055"
			(at 0 0 90)
			(layer "B.SilkS")
			(hide yes)
			(effects
				(font
					(size 1.27 1.27)
				)
				(justify mirror)
			)
		)
		(property "Value" ""
			(at 0 0 90)
			(layer "B.Fab")
			(effects
				(font
					(size 1.27 1.27)
				)
				(justify mirror)
			)
		)
		(duplicate_pad_numbers_are_jumpers no)
		(fp_line
			(start -0.299974 0.150114)
			(end 0.299974 0.150114)
			(stroke
				(width 0.1)
				(type default)
			)
			(layer "B.Fab")
		)
		(fp_line
			(start 0.299974 0.150114)
			(end 0.299974 -0.150114)
			(stroke
				(width 0.1)
				(type default)
			)
			(layer "B.Fab")
		)
		(fp_line
			(start -0.299974 -0.150114)
			(end -0.299974 0.150114)
			(stroke
				(width 0.1)
				(type default)
			)
			(layer "B.Fab")
		)
		(fp_line
			(start 0.299974 -0.150114)
			(end -0.299974 -0.150114)
			(stroke
				(width 0.1)
				(type default)
			)
			(layer "B.Fab")
		)
		(pad "1" smd rect
			(at 0.2667 0 90)
			(size 0.3048 0.381)
			(layers "B.Cu" "B.Mask" "B.Paste")
			(net "P0V9_CPU0_RT3_2A")
		)
		(pad "2" smd rect
			(at -0.2667 0 90)
			(size 0.3048 0.381)
			(layers "B.Cu" "B.Mask" "B.Paste")
			(net "GND")
		)
	)
	(footprint ""
		(layer "B.Cu")
		(at 22.479 -359.918 180)
		(property "Reference" "R8225"
			(at 0 0 0)
			(layer "B.SilkS")
			(hide yes)
			(effects
				(font
					(size 1.27 1.27)
				)
				(justify mirror)
			)
		)
		(property "Value" ""
			(at 0 0 0)
			(layer "B.Fab")
			(effects
				(font
					(size 1.27 1.27)
				)
				(justify mirror)
			)
		)
		(duplicate_pad_numbers_are_jumpers no)
		(fp_line
			(start 0.7874 0.4064)
			(end 0.7874 -0.4064)
			(stroke
				(width 0.1524)
				(type default)
			)
			(layer "B.SilkS")
		)
		(fp_line
			(start 0.7874 -0.4064)
			(end -0.7874 -0.4064)
			(stroke
				(width 0.1524)
				(type default)
			)
			(layer "B.SilkS")
		)
		(fp_line
			(start -0.7874 0.4064)
			(end 0.7874 0.4064)
			(stroke
				(width 0.1524)
				(type default)
			)
			(layer "B.SilkS")
		)
		(fp_line
			(start -0.7874 -0.4064)
			(end -0.7874 0.4064)
			(stroke
				(width 0.1524)
				(type default)
			)
			(layer "B.SilkS")
		)
		(fp_line
			(start 0.67945 0.3048)
			(end 0.67945 -0.305054)
			(stroke
				(width 0.1)
				(type default)
			)
			(layer "B.Fab")
		)
		(fp_line
			(start 0.67945 -0.305054)
			(end 0.12065 -0.305054)
			(stroke
				(width 0.1)
				(type default)
			)
			(layer "B.Fab")
		)
		(fp_line
			(start 0.12065 0.3048)
			(end 0.67945 0.3048)
			(stroke
				(width 0.1)
				(type default)
			)
			(layer "B.Fab")
		)
		(fp_line
			(start 0.12065 0.2794)
			(end 0.12065 0.3048)
			(stroke
				(width 0.1)
				(type default)
			)
			(layer "B.Fab")
		)
		(fp_line
			(start 0.12065 -0.2794)
			(end -0.12065 -0.2794)
			(stroke
				(width 0.1)
				(type default)
			)
			(layer "B.Fab")
		)
		(fp_line
			(start 0.12065 -0.305054)
			(end 0.12065 -0.2794)
			(stroke
				(width 0.1)
				(type default)
			)
			(layer "B.Fab")
		)
		(fp_line
			(start -0.120396 0.3048)
			(end -0.120396 0.2794)
			(stroke
				(width 0.1)
				(type default)
			)
			(layer "B.Fab")
		)
		(fp_line
			(start -0.120396 0.2794)
			(end 0.12065 0.2794)
			(stroke
				(width 0.1)
				(type default)
			)
			(layer "B.Fab")
		)
		(fp_line
			(start -0.12065 -0.2794)
			(end -0.12065 -0.3048)
			(stroke
				(width 0.1)
				(type default)
			)
			(layer "B.Fab")
		)
		(fp_line
			(start -0.12065 -0.3048)
			(end -0.67945 -0.3048)
			(stroke
				(width 0.1)
				(type default)
			)
			(layer "B.Fab")
		)
		(fp_line
			(start -0.67945 0.3048)
			(end -0.120396 0.3048)
			(stroke
				(width 0.1)
				(type default)
			)
			(layer "B.Fab")
		)
		(fp_line
			(start -0.67945 -0.3048)
			(end -0.67945 0.3048)
			(stroke
				(width 0.1)
				(type default)
			)
			(layer "B.Fab")
		)
		(pad "1" smd circle
			(at 0.40005 0)
			(size 0 0)
			(layers "B.Cu" "B.Mask" "B.Paste")
			(net "PVDD18_S5_P1")
		)
		(pad "2" smd circle
			(at -0.40005 0)
			(size 0 0)
			(layers "B.Cu" "B.Mask" "B.Paste")
			(net "SVID_PVDDCR_CPU1_P1_SVC_R")
		)
	)
	(footprint ""
		(layer "B.Cu")
		(at 115.03406 -28.449778 -90)
		(property "Reference" "C6108"
			(at 0 0 90)
			(layer "B.SilkS")
			(hide yes)
			(effects
				(font
					(size 1.27 1.27)
				)
				(justify mirror)
			)
		)
		(property "Value" ""
			(at 0 0 90)
			(layer "B.Fab")
			(effects
				(font
					(size 1.27 1.27)
				)
				(justify mirror)
			)
		)
		(duplicate_pad_numbers_are_jumpers no)
		(fp_line
			(start -0.7874 0.4064)
			(end 0.7874 0.4064)
			(stroke
				(width 0.1524)
				(type default)
			)
			(layer "B.SilkS")
		)
		(fp_line
			(start 0.7874 0.4064)
			(end 0.7874 -0.4064)
			(stroke
				(width 0.1524)
				(type default)
			)
			(layer "B.SilkS")
		)
		(fp_line
			(start -0.7874 -0.4064)
			(end -0.7874 0.4064)
			(stroke
				(width 0.1524)
				(type default)
			)
			(layer "B.SilkS")
		)
		(fp_line
			(start 0.7874 -0.4064)
			(end -0.7874 -0.4064)
			(stroke
				(width 0.1524)
				(type default)
			)
			(layer "B.SilkS")
		)
		(fp_line
			(start -0.67945 0.3048)
			(end -0.120396 0.3048)
			(stroke
				(width 0.1)
				(type default)
			)
			(layer "B.Fab")
		)
		(fp_line
			(start -0.120396 0.3048)
			(end -0.120396 0.2794)
			(stroke
				(width 0.1)
				(type default)
			)
			(layer "B.Fab")
		)
		(fp_line
			(start 0.12065 0.3048)
			(end 0.67945 0.3048)
			(stroke
				(width 0.1)
				(type default)
			)
			(layer "B.Fab")
		)
		(fp_line
			(start 0.67945 0.3048)
			(end 0.67945 -0.305054)
			(stroke
				(width 0.1)
				(type default)
			)
			(layer "B.Fab")
		)
		(fp_line
			(start -0.120396 0.2794)
			(end 0.12065 0.2794)
			(stroke
				(width 0.1)
				(type default)
			)
			(layer "B.Fab")
		)
		(fp_line
			(start 0.12065 0.2794)
			(end 0.12065 0.3048)
			(stroke
				(width 0.1)
				(type default)
			)
			(layer "B.Fab")
		)
		(fp_line
			(start -0.12065 -0.2794)
			(end -0.12065 -0.3048)
			(stroke
				(width 0.1)
				(type default)
			)
			(layer "B.Fab")
		)
		(fp_line
			(start 0.12065 -0.2794)
			(end -0.12065 -0.2794)
			(stroke
				(width 0.1)
				(type default)
			)
			(layer "B.Fab")
		)
		(fp_line
			(start -0.67945 -0.3048)
			(end -0.67945 0.3048)
			(stroke
				(width 0.1)
				(type default)
			)
			(layer "B.Fab")
		)
		(fp_line
			(start -0.12065 -0.3048)
			(end -0.67945 -0.3048)
			(stroke
				(width 0.1)
				(type default)
			)
			(layer "B.Fab")
		)
		(fp_line
			(start 0.12065 -0.305054)
			(end 0.12065 -0.2794)
			(stroke
				(width 0.1)
				(type default)
			)
			(layer "B.Fab")
		)
		(fp_line
			(start 0.67945 -0.305054)
			(end 0.12065 -0.305054)
			(stroke
				(width 0.1)
				(type default)
			)
			(layer "B.Fab")
		)
		(pad "1" smd circle
			(at 0.40005 0 90)
			(size 0 0)
			(layers "B.Cu" "B.Mask" "B.Paste")
			(net "P1V2_CPU0_USB2_DVDD12")
		)
		(pad "2" smd circle
			(at -0.40005 0 90)
			(size 0 0)
			(layers "B.Cu" "B.Mask" "B.Paste")
			(net "GND")
		)
	)
	(footprint ""
		(layer "B.Cu")
		(at 164.33546 -190.821564 180)
		(property "Reference" "R1184"
			(at 0 0 0)
			(layer "B.SilkS")
			(hide yes)
			(effects
				(font
					(size 1.27 1.27)
				)
				(justify mirror)
			)
		)
		(property "Value" ""
			(at 0 0 0)
			(layer "B.Fab")
			(effects
				(font
					(size 1.27 1.27)
				)
				(justify mirror)
			)
		)
		(duplicate_pad_numbers_are_jumpers no)
		(fp_line
			(start 0.7874 0.4064)
			(end 0.7874 -0.4064)
			(stroke
				(width 0.1524)
				(type default)
			)
			(layer "B.SilkS")
		)
		(fp_line
			(start 0.7874 -0.4064)
			(end -0.7874 -0.4064)
			(stroke
				(width 0.1524)
				(type default)
			)
			(layer "B.SilkS")
		)
		(fp_line
			(start -0.7874 0.4064)
			(end 0.7874 0.4064)
			(stroke
				(width 0.1524)
				(type default)
			)
			(layer "B.SilkS")
		)
		(fp_line
			(start -0.7874 -0.4064)
			(end -0.7874 0.4064)
			(stroke
				(width 0.1524)
				(type default)
			)
			(layer "B.SilkS")
		)
		(fp_line
			(start 0.67945 0.3048)
			(end 0.67945 -0.305054)
			(stroke
				(width 0.1)
				(type default)
			)
			(layer "B.Fab")
		)
		(fp_line
			(start 0.67945 -0.305054)
			(end 0.12065 -0.305054)
			(stroke
				(width 0.1)
				(type default)
			)
			(layer "B.Fab")
		)
		(fp_line
			(start 0.12065 0.3048)
			(end 0.67945 0.3048)
			(stroke
				(width 0.1)
				(type default)
			)
			(layer "B.Fab")
		)
		(fp_line
			(start 0.12065 0.2794)
			(end 0.12065 0.3048)
			(stroke
				(width 0.1)
				(type default)
			)
			(layer "B.Fab")
		)
		(fp_line
			(start 0.12065 -0.2794)
			(end -0.12065 -0.2794)
			(stroke
				(width 0.1)
				(type default)
			)
			(layer "B.Fab")
		)
		(fp_line
			(start 0.12065 -0.305054)
			(end 0.12065 -0.2794)
			(stroke
				(width 0.1)
				(type default)
			)
			(layer "B.Fab")
		)
		(fp_line
			(start -0.120396 0.3048)
			(end -0.120396 0.2794)
			(stroke
				(width 0.1)
				(type default)
			)
			(layer "B.Fab")
		)
		(fp_line
			(start -0.120396 0.2794)
			(end 0.12065 0.2794)
			(stroke
				(width 0.1)
				(type default)
			)
			(layer "B.Fab")
		)
		(fp_line
			(start -0.12065 -0.2794)
			(end -0.12065 -0.3048)
			(stroke
				(width 0.1)
				(type default)
			)
			(layer "B.Fab")
		)
		(fp_line
			(start -0.12065 -0.3048)
			(end -0.67945 -0.3048)
			(stroke
				(width 0.1)
				(type default)
			)
			(layer "B.Fab")
		)
		(fp_line
			(start -0.67945 0.3048)
			(end -0.120396 0.3048)
			(stroke
				(width 0.1)
				(type default)
			)
			(layer "B.Fab")
		)
		(fp_line
			(start -0.67945 -0.3048)
			(end -0.67945 0.3048)
			(stroke
				(width 0.1)
				(type default)
			)
			(layer "B.Fab")
		)
		(pad "1" smd circle
			(at 0.40005 0)
			(size 0 0)
			(layers "B.Cu" "B.Mask" "B.Paste")
			(net "PWRGD_CHG_CPU1_DIMM0")
		)
		(pad "2" smd circle
			(at -0.40005 0)
			(size 0 0)
			(layers "B.Cu" "B.Mask" "B.Paste")
			(net "PWRGD_CHGL_CPU1")
		)
	)
	(footprint ""
		(layer "B.Cu")
		(at 137.851642 -9.036304 -90)
		(property "Reference" "R6035"
			(at 0 0 90)
			(layer "B.SilkS")
			(hide yes)
			(effects
				(font
					(size 1.27 1.27)
				)
				(justify mirror)
			)
		)
		(property "Value" ""
			(at 0 0 90)
			(layer "B.Fab")
			(effects
				(font
					(size 1.27 1.27)
				)
				(justify mirror)
			)
		)
		(duplicate_pad_numbers_are_jumpers no)
		(fp_line
			(start -0.7874 0.4064)
			(end 0.7874 0.4064)
			(stroke
				(width 0.1524)
				(type default)
			)
			(layer "B.SilkS")
		)
		(fp_line
			(start 0.7874 0.4064)
			(end 0.7874 -0.4064)
			(stroke
				(width 0.1524)
				(type default)
			)
			(layer "B.SilkS")
		)
		(fp_line
			(start -0.7874 -0.4064)
			(end -0.7874 0.4064)
			(stroke
				(width 0.1524)
				(type default)
			)
			(layer "B.SilkS")
		)
		(fp_line
			(start 0.7874 -0.4064)
			(end -0.7874 -0.4064)
			(stroke
				(width 0.1524)
				(type default)
			)
			(layer "B.SilkS")
		)
		(fp_line
			(start -0.67945 0.3048)
			(end -0.120396 0.3048)
			(stroke
				(width 0.1)
				(type default)
			)
			(layer "B.Fab")
		)
		(fp_line
			(start -0.120396 0.3048)
			(end -0.120396 0.2794)
			(stroke
				(width 0.1)
				(type default)
			)
			(layer "B.Fab")
		)
		(fp_line
			(start 0.12065 0.3048)
			(end 0.67945 0.3048)
			(stroke
				(width 0.1)
				(type default)
			)
			(layer "B.Fab")
		)
		(fp_line
			(start 0.67945 0.3048)
			(end 0.67945 -0.305054)
			(stroke
				(width 0.1)
				(type default)
			)
			(layer "B.Fab")
		)
		(fp_line
			(start -0.120396 0.2794)
			(end 0.12065 0.2794)
			(stroke
				(width 0.1)
				(type default)
			)
			(layer "B.Fab")
		)
		(fp_line
			(start 0.12065 0.2794)
			(end 0.12065 0.3048)
			(stroke
				(width 0.1)
				(type default)
			)
			(layer "B.Fab")
		)
		(fp_line
			(start -0.12065 -0.2794)
			(end -0.12065 -0.3048)
			(stroke
				(width 0.1)
				(type default)
			)
			(layer "B.Fab")
		)
		(fp_line
			(start 0.12065 -0.2794)
			(end -0.12065 -0.2794)
			(stroke
				(width 0.1)
				(type default)
			)
			(layer "B.Fab")
		)
		(fp_line
			(start -0.67945 -0.3048)
			(end -0.67945 0.3048)
			(stroke
				(width 0.1)
				(type default)
			)
			(layer "B.Fab")
		)
		(fp_line
			(start -0.12065 -0.3048)
			(end -0.67945 -0.3048)
			(stroke
				(width 0.1)
				(type default)
			)
			(layer "B.Fab")
		)
		(fp_line
			(start 0.12065 -0.305054)
			(end 0.12065 -0.2794)
			(stroke
				(width 0.1)
				(type default)
			)
			(layer "B.Fab")
		)
		(fp_line
			(start 0.67945 -0.305054)
			(end 0.12065 -0.305054)
			(stroke
				(width 0.1)
				(type default)
			)
			(layer "B.Fab")
		)
		(pad "1" smd circle
			(at 0.40005 0 90)
			(size 0 0)
			(layers "B.Cu" "B.Mask" "B.Paste")
			(net "SCM_ROT_CPU_RST_R_N")
		)
		(pad "2" smd circle
			(at -0.40005 0 90)
			(size 0 0)
			(layers "B.Cu" "B.Mask" "B.Paste")
			(net "GND")
		)
	)
	(footprint ""
		(layer "B.Cu")
		(at 117.895624 -255.555242)
		(property "Reference" "C2424"
			(at 0 0 0)
			(layer "B.SilkS")
			(hide yes)
			(effects
				(font
					(size 1.27 1.27)
				)
				(justify mirror)
			)
		)
		(property "Value" ""
			(at 0 0 0)
			(layer "B.Fab")
			(effects
				(font
					(size 1.27 1.27)
				)
				(justify mirror)
			)
		)
		(duplicate_pad_numbers_are_jumpers no)
		(fp_line
			(start -0.7874 -0.4064)
			(end -0.7874 0.4064)
			(stroke
				(width 0.1524)
				(type default)
			)
			(layer "B.SilkS")
		)
		(fp_line
			(start -0.7874 0.4064)
			(end 0.7874 0.4064)
			(stroke
				(width 0.1524)
				(type default)
			)
			(layer "B.SilkS")
		)
		(fp_line
			(start 0.7874 -0.4064)
			(end -0.7874 -0.4064)
			(stroke
				(width 0.1524)
				(type default)
			)
			(layer "B.SilkS")
		)
		(fp_line
			(start 0.7874 0.4064)
			(end 0.7874 -0.4064)
			(stroke
				(width 0.1524)
				(type default)
			)
			(layer "B.SilkS")
		)
		(fp_line
			(start -0.67945 -0.3048)
			(end -0.67945 0.3048)
			(stroke
				(width 0.1)
				(type default)
			)
			(layer "B.Fab")
		)
		(fp_line
			(start -0.67945 0.3048)
			(end -0.120396 0.3048)
			(stroke
				(width 0.1)
				(type default)
			)
			(layer "B.Fab")
		)
		(fp_line
			(start -0.12065 -0.3048)
			(end -0.67945 -0.3048)
			(stroke
				(width 0.1)
				(type default)
			)
			(layer "B.Fab")
		)
		(fp_line
			(start -0.12065 -0.2794)
			(end -0.12065 -0.3048)
			(stroke
				(width 0.1)
				(type default)
			)
			(layer "B.Fab")
		)
		(fp_line
			(start -0.120396 0.2794)
			(end 0.12065 0.2794)
			(stroke
				(width 0.1)
				(type default)
			)
			(layer "B.Fab")
		)
		(fp_line
			(start -0.120396 0.3048)
			(end -0.120396 0.2794)
			(stroke
				(width 0.1)
				(type default)
			)
			(layer "B.Fab")
		)
		(fp_line
			(start 0.12065 -0.305054)
			(end 0.12065 -0.2794)
			(stroke
				(width 0.1)
				(type default)
			)
			(layer "B.Fab")
		)
		(fp_line
			(start 0.12065 -0.2794)
			(end -0.12065 -0.2794)
			(stroke
				(width 0.1)
				(type default)
			)
			(layer "B.Fab")
		)
		(fp_line
			(start 0.12065 0.2794)
			(end 0.12065 0.3048)
			(stroke
				(width 0.1)
				(type default)
			)
			(layer "B.Fab")
		)
		(fp_line
			(start 0.12065 0.3048)
			(end 0.67945 0.3048)
			(stroke
				(width 0.1)
				(type default)
			)
			(layer "B.Fab")
		)
		(fp_line
			(start 0.67945 -0.305054)
			(end 0.12065 -0.305054)
			(stroke
				(width 0.1)
				(type default)
			)
			(layer "B.Fab")
		)
		(fp_line
			(start 0.67945 0.3048)
			(end 0.67945 -0.305054)
			(stroke
				(width 0.1)
				(type default)
			)
			(layer "B.Fab")
		)
		(pad "1" smd circle
			(at 0.40005 0 180)
			(size 0 0)
			(layers "B.Cu" "B.Mask" "B.Paste")
			(net "PVDDCR_SOC_P1")
		)
		(pad "2" smd circle
			(at -0.40005 0 180)
			(size 0 0)
			(layers "B.Cu" "B.Mask" "B.Paste")
			(net "GND")
		)
	)
	(footprint ""
		(layer "B.Cu")
		(at 163.5252 -424.60037 -90)
		(property "Reference" "R1511"
			(at 0 0 90)
			(layer "B.SilkS")
			(hide yes)
			(effects
				(font
					(size 1.27 1.27)
				)
				(justify mirror)
			)
		)
		(property "Value" ""
			(at 0 0 90)
			(layer "B.Fab")
			(effects
				(font
					(size 1.27 1.27)
				)
				(justify mirror)
			)
		)
		(duplicate_pad_numbers_are_jumpers no)
		(fp_line
			(start -0.32512 0.175006)
			(end 0.32512 0.175006)
			(stroke
				(width 0.1)
				(type default)
			)
			(layer "B.Fab")
		)
		(fp_line
			(start 0.32512 0.175006)
			(end 0.32512 -0.175006)
			(stroke
				(width 0.1)
				(type default)
			)
			(layer "B.Fab")
		)
		(fp_line
			(start -0.32512 -0.175006)
			(end -0.32512 0.175006)
			(stroke
				(width 0.1)
				(type default)
			)
			(layer "B.Fab")
		)
		(fp_line
			(start 0.32512 -0.175006)
			(end -0.32512 -0.175006)
			(stroke
				(width 0.1)
				(type default)
			)
			(layer "B.Fab")
		)
		(pad "1" smd rect
			(at 0.2667 0 90)
			(size 0.3048 0.381)
			(layers "B.Cu" "B.Mask" "B.Paste")
			(net "P1V8_CPU1_RT_1D")
		)
		(pad "2" smd rect
			(at -0.2667 0 270)
			(size 0.3048 0.381)
			(layers "B.Cu" "B.Mask" "B.Paste")
			(net "JTAG_TMS_RT_CPU1_P3")
		)
	)
	(footprint ""
		(layer "B.Cu")
		(at 352.596958 -250.89231 180)
		(property "Reference" "C2165"
			(at 0 0 0)
			(layer "B.SilkS")
			(hide yes)
			(effects
				(font
					(size 1.27 1.27)
				)
				(justify mirror)
			)
		)
		(property "Value" ""
			(at 0 0 0)
			(layer "B.Fab")
			(effects
				(font
					(size 1.27 1.27)
				)
				(justify mirror)
			)
		)
		(duplicate_pad_numbers_are_jumpers no)
		(fp_line
			(start 0.7874 0.4064)
			(end 0.7874 -0.4064)
			(stroke
				(width 0.1524)
				(type default)
			)
			(layer "B.SilkS")
		)
		(fp_line
			(start 0.7874 -0.4064)
			(end -0.7874 -0.4064)
			(stroke
				(width 0.1524)
				(type default)
			)
			(layer "B.SilkS")
		)
		(fp_line
			(start -0.7874 0.4064)
			(end 0.7874 0.4064)
			(stroke
				(width 0.1524)
				(type default)
			)
			(layer "B.SilkS")
		)
		(fp_line
			(start -0.7874 -0.4064)
			(end -0.7874 0.4064)
			(stroke
				(width 0.1524)
				(type default)
			)
			(layer "B.SilkS")
		)
		(fp_line
			(start 0.67945 0.3048)
			(end 0.67945 -0.305054)
			(stroke
				(width 0.1)
				(type default)
			)
			(layer "B.Fab")
		)
		(fp_line
			(start 0.67945 -0.305054)
			(end 0.12065 -0.305054)
			(stroke
				(width 0.1)
				(type default)
			)
			(layer "B.Fab")
		)
		(fp_line
			(start 0.12065 0.3048)
			(end 0.67945 0.3048)
			(stroke
				(width 0.1)
				(type default)
			)
			(layer "B.Fab")
		)
		(fp_line
			(start 0.12065 0.2794)
			(end 0.12065 0.3048)
			(stroke
				(width 0.1)
				(type default)
			)
			(layer "B.Fab")
		)
		(fp_line
			(start 0.12065 -0.2794)
			(end -0.12065 -0.2794)
			(stroke
				(width 0.1)
				(type default)
			)
			(layer "B.Fab")
		)
		(fp_line
			(start 0.12065 -0.305054)
			(end 0.12065 -0.2794)
			(stroke
				(width 0.1)
				(type default)
			)
			(layer "B.Fab")
		)
		(fp_line
			(start -0.120396 0.3048)
			(end -0.120396 0.2794)
			(stroke
				(width 0.1)
				(type default)
			)
			(layer "B.Fab")
		)
		(fp_line
			(start -0.120396 0.2794)
			(end 0.12065 0.2794)
			(stroke
				(width 0.1)
				(type default)
			)
			(layer "B.Fab")
		)
		(fp_line
			(start -0.12065 -0.2794)
			(end -0.12065 -0.3048)
			(stroke
				(width 0.1)
				(type default)
			)
			(layer "B.Fab")
		)
		(fp_line
			(start -0.12065 -0.3048)
			(end -0.67945 -0.3048)
			(stroke
				(width 0.1)
				(type default)
			)
			(layer "B.Fab")
		)
		(fp_line
			(start -0.67945 0.3048)
			(end -0.120396 0.3048)
			(stroke
				(width 0.1)
				(type default)
			)
			(layer "B.Fab")
		)
		(fp_line
			(start -0.67945 -0.3048)
			(end -0.67945 0.3048)
			(stroke
				(width 0.1)
				(type default)
			)
			(layer "B.Fab")
		)
		(pad "1" smd circle
			(at 0.40005 0)
			(size 0 0)
			(layers "B.Cu" "B.Mask" "B.Paste")
			(net "PVDDCR_CPU0_P0")
		)
		(pad "2" smd circle
			(at -0.40005 0)
			(size 0 0)
			(layers "B.Cu" "B.Mask" "B.Paste")
			(net "GND")
		)
	)
	(footprint ""
		(layer "B.Cu")
		(at 366.217454 -248.47931 180)
		(property "Reference" "C2169"
			(at 0 0 0)
			(layer "B.SilkS")
			(hide yes)
			(effects
				(font
					(size 1.27 1.27)
				)
				(justify mirror)
			)
		)
		(property "Value" ""
			(at 0 0 0)
			(layer "B.Fab")
			(effects
				(font
					(size 1.27 1.27)
				)
				(justify mirror)
			)
		)
		(duplicate_pad_numbers_are_jumpers no)
		(fp_line
			(start 0.7874 0.4064)
			(end 0.7874 -0.4064)
			(stroke
				(width 0.1524)
				(type default)
			)
			(layer "B.SilkS")
		)
		(fp_line
			(start 0.7874 -0.4064)
			(end -0.7874 -0.4064)
			(stroke
				(width 0.1524)
				(type default)
			)
			(layer "B.SilkS")
		)
		(fp_line
			(start -0.7874 0.4064)
			(end 0.7874 0.4064)
			(stroke
				(width 0.1524)
				(type default)
			)
			(layer "B.SilkS")
		)
		(fp_line
			(start -0.7874 -0.4064)
			(end -0.7874 0.4064)
			(stroke
				(width 0.1524)
				(type default)
			)
			(layer "B.SilkS")
		)
		(fp_line
			(start 0.67945 0.3048)
			(end 0.67945 -0.305054)
			(stroke
				(width 0.1)
				(type default)
			)
			(layer "B.Fab")
		)
		(fp_line
			(start 0.67945 -0.305054)
			(end 0.12065 -0.305054)
			(stroke
				(width 0.1)
				(type default)
			)
			(layer "B.Fab")
		)
		(fp_line
			(start 0.12065 0.3048)
			(end 0.67945 0.3048)
			(stroke
				(width 0.1)
				(type default)
			)
			(layer "B.Fab")
		)
		(fp_line
			(start 0.12065 0.2794)
			(end 0.12065 0.3048)
			(stroke
				(width 0.1)
				(type default)
			)
			(layer "B.Fab")
		)
		(fp_line
			(start 0.12065 -0.2794)
			(end -0.12065 -0.2794)
			(stroke
				(width 0.1)
				(type default)
			)
			(layer "B.Fab")
		)
		(fp_line
			(start 0.12065 -0.305054)
			(end 0.12065 -0.2794)
			(stroke
				(width 0.1)
				(type default)
			)
			(layer "B.Fab")
		)
		(fp_line
			(start -0.120396 0.3048)
			(end -0.120396 0.2794)
			(stroke
				(width 0.1)
				(type default)
			)
			(layer "B.Fab")
		)
		(fp_line
			(start -0.120396 0.2794)
			(end 0.12065 0.2794)
			(stroke
				(width 0.1)
				(type default)
			)
			(layer "B.Fab")
		)
		(fp_line
			(start -0.12065 -0.2794)
			(end -0.12065 -0.3048)
			(stroke
				(width 0.1)
				(type default)
			)
			(layer "B.Fab")
		)
		(fp_line
			(start -0.12065 -0.3048)
			(end -0.67945 -0.3048)
			(stroke
				(width 0.1)
				(type default)
			)
			(layer "B.Fab")
		)
		(fp_line
			(start -0.67945 0.3048)
			(end -0.120396 0.3048)
			(stroke
				(width 0.1)
				(type default)
			)
			(layer "B.Fab")
		)
		(fp_line
			(start -0.67945 -0.3048)
			(end -0.67945 0.3048)
			(stroke
				(width 0.1)
				(type default)
			)
			(layer "B.Fab")
		)
		(pad "1" smd circle
			(at 0.40005 0)
			(size 0 0)
			(layers "B.Cu" "B.Mask" "B.Paste")
			(net "PVDDCR_CPU0_P0")
		)
		(pad "2" smd circle
			(at -0.40005 0)
			(size 0 0)
			(layers "B.Cu" "B.Mask" "B.Paste")
			(net "GND")
		)
	)
	(footprint ""
		(layer "B.Cu")
		(at 181.737 -100.294948 90)
		(property "Reference" "R226"
			(at 0 0 90)
			(layer "B.SilkS")
			(hide yes)
			(effects
				(font
					(size 1.27 1.27)
				)
				(justify mirror)
			)
		)
		(property "Value" ""
			(at 0 0 90)
			(layer "B.Fab")
			(effects
				(font
					(size 1.27 1.27)
				)
				(justify mirror)
			)
		)
		(duplicate_pad_numbers_are_jumpers no)
		(fp_line
			(start 0.7874 -0.4064)
			(end -0.7874 -0.4064)
			(stroke
				(width 0.1524)
				(type default)
			)
			(layer "B.SilkS")
		)
		(fp_line
			(start -0.7874 -0.4064)
			(end -0.7874 0.4064)
			(stroke
				(width 0.1524)
				(type default)
			)
			(layer "B.SilkS")
		)
		(fp_line
			(start 0.7874 0.4064)
			(end 0.7874 -0.4064)
			(stroke
				(width 0.1524)
				(type default)
			)
			(layer "B.SilkS")
		)
		(fp_line
			(start -0.7874 0.4064)
			(end 0.7874 0.4064)
			(stroke
				(width 0.1524)
				(type default)
			)
			(layer "B.SilkS")
		)
		(fp_line
			(start 0.67945 -0.305054)
			(end 0.12065 -0.305054)
			(stroke
				(width 0.1)
				(type default)
			)
			(layer "B.Fab")
		)
		(fp_line
			(start 0.12065 -0.305054)
			(end 0.12065 -0.2794)
			(stroke
				(width 0.1)
				(type default)
			)
			(layer "B.Fab")
		)
		(fp_line
			(start -0.12065 -0.3048)
			(end -0.67945 -0.3048)
			(stroke
				(width 0.1)
				(type default)
			)
			(layer "B.Fab")
		)
		(fp_line
			(start -0.67945 -0.3048)
			(end -0.67945 0.3048)
			(stroke
				(width 0.1)
				(type default)
			)
			(layer "B.Fab")
		)
		(fp_line
			(start 0.12065 -0.2794)
			(end -0.12065 -0.2794)
			(stroke
				(width 0.1)
				(type default)
			)
			(layer "B.Fab")
		)
		(fp_line
			(start -0.12065 -0.2794)
			(end -0.12065 -0.3048)
			(stroke
				(width 0.1)
				(type default)
			)
			(layer "B.Fab")
		)
		(fp_line
			(start 0.12065 0.2794)
			(end 0.12065 0.3048)
			(stroke
				(width 0.1)
				(type default)
			)
			(layer "B.Fab")
		)
		(fp_line
			(start -0.120396 0.2794)
			(end 0.12065 0.2794)
			(stroke
				(width 0.1)
				(type default)
			)
			(layer "B.Fab")
		)
		(fp_line
			(start 0.67945 0.3048)
			(end 0.67945 -0.305054)
			(stroke
				(width 0.1)
				(type default)
			)
			(layer "B.Fab")
		)
		(fp_line
			(start 0.12065 0.3048)
			(end 0.67945 0.3048)
			(stroke
				(width 0.1)
				(type default)
			)
			(layer "B.Fab")
		)
		(fp_line
			(start -0.120396 0.3048)
			(end -0.120396 0.2794)
			(stroke
				(width 0.1)
				(type default)
			)
			(layer "B.Fab")
		)
		(fp_line
			(start -0.67945 0.3048)
			(end -0.120396 0.3048)
			(stroke
				(width 0.1)
				(type default)
			)
			(layer "B.Fab")
		)
		(pad "1" smd circle
			(at 0.40005 0 270)
			(size 0 0)
			(layers "B.Cu" "B.Mask" "B.Paste")
			(net "FM_PVDD11_S3_P0_OCP_N")
		)
		(pad "2" smd circle
			(at -0.40005 0 270)
			(size 0 0)
			(layers "B.Cu" "B.Mask" "B.Paste")
			(net "PVDD11_S3_P0_OCP_N")
		)
	)
	(footprint ""
		(layer "B.Cu")
		(at 397.623538 -392.1252 180)
		(property "Reference" "R1063"
			(at 0 0 0)
			(layer "B.SilkS")
			(hide yes)
			(effects
				(font
					(size 1.27 1.27)
				)
				(justify mirror)
			)
		)
		(property "Value" ""
			(at 0 0 0)
			(layer "B.Fab")
			(effects
				(font
					(size 1.27 1.27)
				)
				(justify mirror)
			)
		)
		(duplicate_pad_numbers_are_jumpers no)
		(fp_line
			(start 0.32512 0.175006)
			(end 0.32512 -0.175006)
			(stroke
				(width 0.1)
				(type default)
			)
			(layer "B.Fab")
		)
		(fp_line
			(start 0.32512 -0.175006)
			(end -0.32512 -0.175006)
			(stroke
				(width 0.1)
				(type default)
			)
			(layer "B.Fab")
		)
		(fp_line
			(start -0.32512 0.175006)
			(end 0.32512 0.175006)
			(stroke
				(width 0.1)
				(type default)
			)
			(layer "B.Fab")
		)
		(fp_line
			(start -0.32512 -0.175006)
			(end -0.32512 0.175006)
			(stroke
				(width 0.1)
				(type default)
			)
			(layer "B.Fab")
		)
		(pad "1" smd rect
			(at 0.2667 0)
			(size 0.3048 0.381)
			(layers "B.Cu" "B.Mask" "B.Paste")
			(net "P1V8_CPU0_RT_1D")
		)
		(pad "2" smd rect
			(at -0.2667 0 180)
			(size 0.3048 0.381)
			(layers "B.Cu" "B.Mask" "B.Paste")
			(net "RT_CPU0_P2_SCAN_MODE")
		)
	)
	(footprint ""
		(layer "B.Cu")
		(at 199.129396 -116.174012 -90)
		(property "Reference" "R6048"
			(at 0 0 90)
			(layer "B.SilkS")
			(hide yes)
			(effects
				(font
					(size 1.27 1.27)
				)
				(justify mirror)
			)
		)
		(property "Value" ""
			(at 0 0 90)
			(layer "B.Fab")
			(effects
				(font
					(size 1.27 1.27)
				)
				(justify mirror)
			)
		)
		(duplicate_pad_numbers_are_jumpers no)
		(fp_line
			(start -0.7874 0.4064)
			(end 0.7874 0.4064)
			(stroke
				(width 0.1524)
				(type default)
			)
			(layer "B.SilkS")
		)
		(fp_line
			(start 0.7874 0.4064)
			(end 0.7874 -0.4064)
			(stroke
				(width 0.1524)
				(type default)
			)
			(layer "B.SilkS")
		)
		(fp_line
			(start -0.7874 -0.4064)
			(end -0.7874 0.4064)
			(stroke
				(width 0.1524)
				(type default)
			)
			(layer "B.SilkS")
		)
		(fp_line
			(start 0.7874 -0.4064)
			(end -0.7874 -0.4064)
			(stroke
				(width 0.1524)
				(type default)
			)
			(layer "B.SilkS")
		)
		(fp_line
			(start -0.67945 0.3048)
			(end -0.120396 0.3048)
			(stroke
				(width 0.1)
				(type default)
			)
			(layer "B.Fab")
		)
		(fp_line
			(start -0.120396 0.3048)
			(end -0.120396 0.2794)
			(stroke
				(width 0.1)
				(type default)
			)
			(layer "B.Fab")
		)
		(fp_line
			(start 0.12065 0.3048)
			(end 0.67945 0.3048)
			(stroke
				(width 0.1)
				(type default)
			)
			(layer "B.Fab")
		)
		(fp_line
			(start 0.67945 0.3048)
			(end 0.67945 -0.305054)
			(stroke
				(width 0.1)
				(type default)
			)
			(layer "B.Fab")
		)
		(fp_line
			(start -0.120396 0.2794)
			(end 0.12065 0.2794)
			(stroke
				(width 0.1)
				(type default)
			)
			(layer "B.Fab")
		)
		(fp_line
			(start 0.12065 0.2794)
			(end 0.12065 0.3048)
			(stroke
				(width 0.1)
				(type default)
			)
			(layer "B.Fab")
		)
		(fp_line
			(start -0.12065 -0.2794)
			(end -0.12065 -0.3048)
			(stroke
				(width 0.1)
				(type default)
			)
			(layer "B.Fab")
		)
		(fp_line
			(start 0.12065 -0.2794)
			(end -0.12065 -0.2794)
			(stroke
				(width 0.1)
				(type default)
			)
			(layer "B.Fab")
		)
		(fp_line
			(start -0.67945 -0.3048)
			(end -0.67945 0.3048)
			(stroke
				(width 0.1)
				(type default)
			)
			(layer "B.Fab")
		)
		(fp_line
			(start -0.12065 -0.3048)
			(end -0.67945 -0.3048)
			(stroke
				(width 0.1)
				(type default)
			)
			(layer "B.Fab")
		)
		(fp_line
			(start 0.12065 -0.305054)
			(end 0.12065 -0.2794)
			(stroke
				(width 0.1)
				(type default)
			)
			(layer "B.Fab")
		)
		(fp_line
			(start 0.67945 -0.305054)
			(end 0.12065 -0.305054)
			(stroke
				(width 0.1)
				(type default)
			)
			(layer "B.Fab")
		)
		(pad "1" smd circle
			(at 0.40005 0 90)
			(size 0 0)
			(layers "B.Cu" "B.Mask" "B.Paste")
			(net "HP_LVC3_E1S_0_HSC_PWRGD")
		)
		(pad "2" smd circle
			(at -0.40005 0 90)
			(size 0 0)
			(layers "B.Cu" "B.Mask" "B.Paste")
			(net "P12V_E1S_0_PWRGD")
		)
	)
	(footprint ""
		(layer "B.Cu")
		(at 183.616346 -192.66027)
		(property "Reference" "C535"
			(at 0 0 0)
			(layer "B.SilkS")
			(hide yes)
			(effects
				(font
					(size 1.27 1.27)
				)
				(justify mirror)
			)
		)
		(property "Value" ""
			(at 0 0 0)
			(layer "B.Fab")
			(effects
				(font
					(size 1.27 1.27)
				)
				(justify mirror)
			)
		)
		(duplicate_pad_numbers_are_jumpers no)
		(fp_line
			(start -1.524 -0.762)
			(end -1.524 0.762)
			(stroke
				(width 0.1524)
				(type default)
			)
			(layer "B.SilkS")
		)
		(fp_line
			(start -1.524 0.762)
			(end 1.524 0.762)
			(stroke
				(width 0.1524)
				(type default)
			)
			(layer "B.SilkS")
		)
		(fp_line
			(start 1.524 -0.762)
			(end -1.524 -0.762)
			(stroke
				(width 0.1524)
				(type default)
			)
			(layer "B.SilkS")
		)
		(fp_line
			(start 1.524 0.762)
			(end 1.524 -0.762)
			(stroke
				(width 0.1524)
				(type default)
			)
			(layer "B.SilkS")
		)
		(fp_line
			(start -1.1049 -0.724916)
			(end 1.1049 -0.724916)
			(stroke
				(width 0.1)
				(type default)
			)
			(layer "B.Fab")
		)
		(fp_line
			(start -1.1049 0.724916)
			(end -1.1049 -0.724916)
			(stroke
				(width 0.1)
				(type default)
			)
			(layer "B.Fab")
		)
		(fp_line
			(start 1.1049 -0.724916)
			(end 1.1049 0.724916)
			(stroke
				(width 0.1)
				(type default)
			)
			(layer "B.Fab")
		)
		(fp_line
			(start 1.1049 0.724916)
			(end -1.1049 0.724916)
			(stroke
				(width 0.1)
				(type default)
			)
			(layer "B.Fab")
		)
		(pad "1" smd rect
			(at 0.889 0)
			(size 1.016 1.27)
			(layers "B.Cu" "B.Mask" "B.Paste")
			(net "P12V_MEM_CPU1")
		)
		(pad "2" smd rect
			(at -0.889 0)
			(size 1.016 1.27)
			(layers "B.Cu" "B.Mask" "B.Paste")
			(net "GND")
		)
	)
	(footprint ""
		(layer "B.Cu")
		(at 374.218454 -396.393162 -90)
		(property "Reference" "C1035"
			(at 0 0 90)
			(layer "B.SilkS")
			(hide yes)
			(effects
				(font
					(size 1.27 1.27)
				)
				(justify mirror)
			)
		)
		(property "Value" ""
			(at 0 0 90)
			(layer "B.Fab")
			(effects
				(font
					(size 1.27 1.27)
				)
				(justify mirror)
			)
		)
		(duplicate_pad_numbers_are_jumpers no)
		(fp_line
			(start -0.299974 0.150114)
			(end 0.299974 0.150114)
			(stroke
				(width 0.1)
				(type default)
			)
			(layer "B.Fab")
		)
		(fp_line
			(start 0.299974 0.150114)
			(end 0.299974 -0.150114)
			(stroke
				(width 0.1)
				(type default)
			)
			(layer "B.Fab")
		)
		(fp_line
			(start -0.299974 -0.150114)
			(end -0.299974 0.150114)
			(stroke
				(width 0.1)
				(type default)
			)
			(layer "B.Fab")
		)
		(fp_line
			(start 0.299974 -0.150114)
			(end -0.299974 -0.150114)
			(stroke
				(width 0.1)
				(type default)
			)
			(layer "B.Fab")
		)
		(pad "1" smd rect
			(at 0.2667 0 90)
			(size 0.3048 0.381)
			(layers "B.Cu" "B.Mask" "B.Paste")
			(net "P0V9_CPU0_RT3_2A")
		)
		(pad "2" smd rect
			(at -0.2667 0 90)
			(size 0.3048 0.381)
			(layers "B.Cu" "B.Mask" "B.Paste")
			(net "GND")
		)
	)
	(footprint ""
		(layer "B.Cu")
		(at 144.922494 -313.45505 180)
		(property "Reference" "R536"
			(at 0 0 0)
			(layer "B.SilkS")
			(hide yes)
			(effects
				(font
					(size 1.27 1.27)
				)
				(justify mirror)
			)
		)
		(property "Value" ""
			(at 0 0 0)
			(layer "B.Fab")
			(effects
				(font
					(size 1.27 1.27)
				)
				(justify mirror)
			)
		)
		(duplicate_pad_numbers_are_jumpers no)
		(fp_line
			(start 0.7874 0.4064)
			(end 0.7874 -0.4064)
			(stroke
				(width 0.1524)
				(type default)
			)
			(layer "B.SilkS")
		)
		(fp_line
			(start 0.7874 -0.4064)
			(end -0.7874 -0.4064)
			(stroke
				(width 0.1524)
				(type default)
			)
			(layer "B.SilkS")
		)
		(fp_line
			(start -0.7874 0.4064)
			(end 0.7874 0.4064)
			(stroke
				(width 0.1524)
				(type default)
			)
			(layer "B.SilkS")
		)
		(fp_line
			(start -0.7874 -0.4064)
			(end -0.7874 0.4064)
			(stroke
				(width 0.1524)
				(type default)
			)
			(layer "B.SilkS")
		)
		(fp_line
			(start 0.67945 0.3048)
			(end 0.67945 -0.305054)
			(stroke
				(width 0.1)
				(type default)
			)
			(layer "B.Fab")
		)
		(fp_line
			(start 0.67945 -0.305054)
			(end 0.12065 -0.305054)
			(stroke
				(width 0.1)
				(type default)
			)
			(layer "B.Fab")
		)
		(fp_line
			(start 0.12065 0.3048)
			(end 0.67945 0.3048)
			(stroke
				(width 0.1)
				(type default)
			)
			(layer "B.Fab")
		)
		(fp_line
			(start 0.12065 0.2794)
			(end 0.12065 0.3048)
			(stroke
				(width 0.1)
				(type default)
			)
			(layer "B.Fab")
		)
		(fp_line
			(start 0.12065 -0.2794)
			(end -0.12065 -0.2794)
			(stroke
				(width 0.1)
				(type default)
			)
			(layer "B.Fab")
		)
		(fp_line
			(start 0.12065 -0.305054)
			(end 0.12065 -0.2794)
			(stroke
				(width 0.1)
				(type default)
			)
			(layer "B.Fab")
		)
		(fp_line
			(start -0.120396 0.3048)
			(end -0.120396 0.2794)
			(stroke
				(width 0.1)
				(type default)
			)
			(layer "B.Fab")
		)
		(fp_line
			(start -0.120396 0.2794)
			(end 0.12065 0.2794)
			(stroke
				(width 0.1)
				(type default)
			)
			(layer "B.Fab")
		)
		(fp_line
			(start -0.12065 -0.2794)
			(end -0.12065 -0.3048)
			(stroke
				(width 0.1)
				(type default)
			)
			(layer "B.Fab")
		)
		(fp_line
			(start -0.12065 -0.3048)
			(end -0.67945 -0.3048)
			(stroke
				(width 0.1)
				(type default)
			)
			(layer "B.Fab")
		)
		(fp_line
			(start -0.67945 0.3048)
			(end -0.120396 0.3048)
			(stroke
				(width 0.1)
				(type default)
			)
			(layer "B.Fab")
		)
		(fp_line
			(start -0.67945 -0.3048)
			(end -0.67945 0.3048)
			(stroke
				(width 0.1)
				(type default)
			)
			(layer "B.Fab")
		)
		(pad "1" smd circle
			(at 0.40005 0)
			(size 0 0)
			(layers "B.Cu" "B.Mask" "B.Paste")
			(net "CPU1_THERMTRIP_N")
		)
		(pad "2" smd circle
			(at -0.40005 0)
			(size 0 0)
			(layers "B.Cu" "B.Mask" "B.Paste")
			(net "PVDD18_S5_P1")
		)
	)
	(footprint ""
		(layer "B.Cu")
		(at 388.537958 -203.577952 180)
		(property "Reference" "R30"
			(at 0 0 0)
			(layer "B.SilkS")
			(hide yes)
			(effects
				(font
					(size 1.27 1.27)
				)
				(justify mirror)
			)
		)
		(property "Value" ""
			(at 0 0 0)
			(layer "B.Fab")
			(effects
				(font
					(size 1.27 1.27)
				)
				(justify mirror)
			)
		)
		(duplicate_pad_numbers_are_jumpers no)
		(fp_line
			(start 0.7874 0.4064)
			(end 0.7874 -0.4064)
			(stroke
				(width 0.1524)
				(type default)
			)
			(layer "B.SilkS")
		)
		(fp_line
			(start 0.7874 -0.4064)
			(end -0.7874 -0.4064)
			(stroke
				(width 0.1524)
				(type default)
			)
			(layer "B.SilkS")
		)
		(fp_line
			(start -0.7874 0.4064)
			(end 0.7874 0.4064)
			(stroke
				(width 0.1524)
				(type default)
			)
			(layer "B.SilkS")
		)
		(fp_line
			(start -0.7874 -0.4064)
			(end -0.7874 0.4064)
			(stroke
				(width 0.1524)
				(type default)
			)
			(layer "B.SilkS")
		)
		(fp_line
			(start 0.67945 0.3048)
			(end 0.67945 -0.305054)
			(stroke
				(width 0.1)
				(type default)
			)
			(layer "B.Fab")
		)
		(fp_line
			(start 0.67945 -0.305054)
			(end 0.12065 -0.305054)
			(stroke
				(width 0.1)
				(type default)
			)
			(layer "B.Fab")
		)
		(fp_line
			(start 0.12065 0.3048)
			(end 0.67945 0.3048)
			(stroke
				(width 0.1)
				(type default)
			)
			(layer "B.Fab")
		)
		(fp_line
			(start 0.12065 0.2794)
			(end 0.12065 0.3048)
			(stroke
				(width 0.1)
				(type default)
			)
			(layer "B.Fab")
		)
		(fp_line
			(start 0.12065 -0.2794)
			(end -0.12065 -0.2794)
			(stroke
				(width 0.1)
				(type default)
			)
			(layer "B.Fab")
		)
		(fp_line
			(start 0.12065 -0.305054)
			(end 0.12065 -0.2794)
			(stroke
				(width 0.1)
				(type default)
			)
			(layer "B.Fab")
		)
		(fp_line
			(start -0.120396 0.3048)
			(end -0.120396 0.2794)
			(stroke
				(width 0.1)
				(type default)
			)
			(layer "B.Fab")
		)
		(fp_line
			(start -0.120396 0.2794)
			(end 0.12065 0.2794)
			(stroke
				(width 0.1)
				(type default)
			)
			(layer "B.Fab")
		)
		(fp_line
			(start -0.12065 -0.2794)
			(end -0.12065 -0.3048)
			(stroke
				(width 0.1)
				(type default)
			)
			(layer "B.Fab")
		)
		(fp_line
			(start -0.12065 -0.3048)
			(end -0.67945 -0.3048)
			(stroke
				(width 0.1)
				(type default)
			)
			(layer "B.Fab")
		)
		(fp_line
			(start -0.67945 0.3048)
			(end -0.120396 0.3048)
			(stroke
				(width 0.1)
				(type default)
			)
			(layer "B.Fab")
		)
		(fp_line
			(start -0.67945 -0.3048)
			(end -0.67945 0.3048)
			(stroke
				(width 0.1)
				(type default)
			)
			(layer "B.Fab")
		)
		(pad "1" smd circle
			(at 0.40005 0)
			(size 0 0)
			(layers "B.Cu" "B.Mask" "B.Paste")
			(net "SMB_CPU0_3_R_SDA")
		)
		(pad "2" smd circle
			(at -0.40005 0)
			(size 0 0)
			(layers "B.Cu" "B.Mask" "B.Paste")
			(net "SMB_CPU0_3_SDA")
		)
	)
	(footprint ""
		(layer "B.Cu")
		(at 474.16466 -117.700806)
		(property "Reference" "DB5"
			(at 2.584704 -5.768848 270)
			(unlocked yes)
			(layer "B.SilkS")
			(effects
				(font
					(size 0.7874 0.5842)
					(thickness 0.1524)
				)
				(justify left mirror)
			)
		)
		(property "Value" ""
			(at 0 0 0)
			(layer "B.Fab")
			(effects
				(font
					(size 1.27 1.27)
				)
				(justify mirror)
			)
		)
		(duplicate_pad_numbers_are_jumpers no)
		(fp_line
			(start -3.330702 -4.771136)
			(end 0 4.011168)
			(stroke
				(width 0.1524)
				(type default)
			)
			(layer "B.SilkS")
		)
		(fp_line
			(start 0 4.011168)
			(end 2.826766 -3.442462)
			(stroke
				(width 0.1524)
				(type default)
			)
			(layer "B.SilkS")
		)
		(fp_line
			(start 3.18389 -4.383786)
			(end 3.330702 -4.771136)
			(stroke
				(width 0.1524)
				(type default)
			)
			(layer "B.SilkS")
		)
		(fp_line
			(start 3.330702 -4.771136)
			(end -3.330702 -4.771136)
			(stroke
				(width 0.1524)
				(type default)
			)
			(layer "B.SilkS")
		)
		(fp_line
			(start -3.330702 -4.771136)
			(end 0 4.011168)
			(stroke
				(width 0.1)
				(type default)
			)
			(layer "B.Fab")
		)
		(fp_line
			(start 0 4.011168)
			(end 3.330702 -4.771136)
			(stroke
				(width 0.1)
				(type default)
			)
			(layer "B.Fab")
		)
		(fp_line
			(start 3.330702 -4.771136)
			(end -3.330702 -4.771136)
			(stroke
				(width 0.1)
				(type default)
			)
			(layer "B.Fab")
		)
		(pad "1" thru_hole circle
			(at 0 0 180)
			(size 2.159 2.159)
			(drill 1.7018)
			(layers "*.Cu" "*.Mask")
			(remove_unused_layers no)
			(net "T1_GND")
			(clearance 0.0254)
			(thermal_gap 0.0254)
		)
		(pad "2" thru_hole circle
			(at 1.27 -3.348736 180)
			(size 2.159 2.159)
			(drill 1.7018)
			(layers "*.Cu" "*.Mask")
			(remove_unused_layers no)
			(net "TDR_SE_45_OHM_IN4")
			(clearance 0.0254)
			(thermal_gap 0.0254)
		)
		(pad "3" thru_hole circle
			(at -1.27 -3.348736 180)
			(size 2.159 2.159)
			(drill 1.7018)
			(layers "*.Cu" "*.Mask")
			(remove_unused_layers no)
			(net "TDR_SE_45_OHM_IN4")
			(clearance 0.0254)
			(thermal_gap 0.0254)
		)
	)
	(footprint ""
		(layer "B.Cu")
		(at 13.65885 -402.839174 180)
		(property "Reference" "R6859"
			(at 0 0 0)
			(layer "B.SilkS")
			(hide yes)
			(effects
				(font
					(size 1.27 1.27)
				)
				(justify mirror)
			)
		)
		(property "Value" ""
			(at 0 0 0)
			(layer "B.Fab")
			(effects
				(font
					(size 1.27 1.27)
				)
				(justify mirror)
			)
		)
		(duplicate_pad_numbers_are_jumpers no)
		(fp_line
			(start 0.7874 0.4064)
			(end 0.7874 -0.4064)
			(stroke
				(width 0.1524)
				(type default)
			)
			(layer "B.SilkS")
		)
		(fp_line
			(start 0.7874 -0.4064)
			(end -0.7874 -0.4064)
			(stroke
				(width 0.1524)
				(type default)
			)
			(layer "B.SilkS")
		)
		(fp_line
			(start -0.7874 0.4064)
			(end 0.7874 0.4064)
			(stroke
				(width 0.1524)
				(type default)
			)
			(layer "B.SilkS")
		)
		(fp_line
			(start -0.7874 -0.4064)
			(end -0.7874 0.4064)
			(stroke
				(width 0.1524)
				(type default)
			)
			(layer "B.SilkS")
		)
		(fp_line
			(start 0.67945 0.3048)
			(end 0.67945 -0.305054)
			(stroke
				(width 0.1)
				(type default)
			)
			(layer "B.Fab")
		)
		(fp_line
			(start 0.67945 -0.305054)
			(end 0.12065 -0.305054)
			(stroke
				(width 0.1)
				(type default)
			)
			(layer "B.Fab")
		)
		(fp_line
			(start 0.12065 0.3048)
			(end 0.67945 0.3048)
			(stroke
				(width 0.1)
				(type default)
			)
			(layer "B.Fab")
		)
		(fp_line
			(start 0.12065 0.2794)
			(end 0.12065 0.3048)
			(stroke
				(width 0.1)
				(type default)
			)
			(layer "B.Fab")
		)
		(fp_line
			(start 0.12065 -0.2794)
			(end -0.12065 -0.2794)
			(stroke
				(width 0.1)
				(type default)
			)
			(layer "B.Fab")
		)
		(fp_line
			(start 0.12065 -0.305054)
			(end 0.12065 -0.2794)
			(stroke
				(width 0.1)
				(type default)
			)
			(layer "B.Fab")
		)
		(fp_line
			(start -0.120396 0.3048)
			(end -0.120396 0.2794)
			(stroke
				(width 0.1)
				(type default)
			)
			(layer "B.Fab")
		)
		(fp_line
			(start -0.120396 0.2794)
			(end 0.12065 0.2794)
			(stroke
				(width 0.1)
				(type default)
			)
			(layer "B.Fab")
		)
		(fp_line
			(start -0.12065 -0.2794)
			(end -0.12065 -0.3048)
			(stroke
				(width 0.1)
				(type default)
			)
			(layer "B.Fab")
		)
		(fp_line
			(start -0.12065 -0.3048)
			(end -0.67945 -0.3048)
			(stroke
				(width 0.1)
				(type default)
			)
			(layer "B.Fab")
		)
		(fp_line
			(start -0.67945 0.3048)
			(end -0.120396 0.3048)
			(stroke
				(width 0.1)
				(type default)
			)
			(layer "B.Fab")
		)
		(fp_line
			(start -0.67945 -0.3048)
			(end -0.67945 0.3048)
			(stroke
				(width 0.1)
				(type default)
			)
			(layer "B.Fab")
		)
		(pad "1" smd circle
			(at 0.40005 0)
			(size 0 0)
			(layers "B.Cu" "B.Mask" "B.Paste")
			(net "SMB_VR_3V3STBY_SDA")
		)
		(pad "2" smd circle
			(at -0.40005 0)
			(size 0 0)
			(layers "B.Cu" "B.Mask" "B.Paste")
			(net "P0V9_RETIMER_CPU1_PMSDA")
		)
	)
	(footprint ""
		(layer "B.Cu")
		(at 309.277766 -416.899344 90)
		(property "Reference" "C6535"
			(at 0 0 90)
			(layer "B.SilkS")
			(hide yes)
			(effects
				(font
					(size 1.27 1.27)
				)
				(justify mirror)
			)
		)
		(property "Value" ""
			(at 0 0 90)
			(layer "B.Fab")
			(effects
				(font
					(size 1.27 1.27)
				)
				(justify mirror)
			)
		)
		(duplicate_pad_numbers_are_jumpers no)
		(fp_line
			(start 0.299974 -0.150114)
			(end -0.299974 -0.150114)
			(stroke
				(width 0.1)
				(type default)
			)
			(layer "B.Fab")
		)
		(fp_line
			(start -0.299974 -0.150114)
			(end -0.299974 0.150114)
			(stroke
				(width 0.1)
				(type default)
			)
			(layer "B.Fab")
		)
		(fp_line
			(start 0.299974 0.150114)
			(end 0.299974 -0.150114)
			(stroke
				(width 0.1)
				(type default)
			)
			(layer "B.Fab")
		)
		(fp_line
			(start -0.299974 0.150114)
			(end 0.299974 0.150114)
			(stroke
				(width 0.1)
				(type default)
			)
			(layer "B.Fab")
		)
		(pad "1" smd rect
			(at 0.2667 0 270)
			(size 0.3048 0.381)
			(layers "B.Cu" "B.Mask" "B.Paste")
			(net "P5E_CPU0_P1_TX_BUF_C_DP<1>")
		)
		(pad "2" smd rect
			(at -0.2667 0 270)
			(size 0.3048 0.381)
			(layers "B.Cu" "B.Mask" "B.Paste")
			(net "P5E_CPU0_P1_TX_BUF_DP<1>")
		)
	)
	(footprint ""
		(layer "B.Cu")
		(at 107.200192 -29.55544 -90)
		(property "Reference" "C6102"
			(at 0 0 90)
			(layer "B.SilkS")
			(hide yes)
			(effects
				(font
					(size 1.27 1.27)
				)
				(justify mirror)
			)
		)
		(property "Value" ""
			(at 0 0 90)
			(layer "B.Fab")
			(effects
				(font
					(size 1.27 1.27)
				)
				(justify mirror)
			)
		)
		(duplicate_pad_numbers_are_jumpers no)
		(fp_line
			(start -0.7874 0.4064)
			(end 0.7874 0.4064)
			(stroke
				(width 0.1524)
				(type default)
			)
			(layer "B.SilkS")
		)
		(fp_line
			(start 0.7874 0.4064)
			(end 0.7874 -0.4064)
			(stroke
				(width 0.1524)
				(type default)
			)
			(layer "B.SilkS")
		)
		(fp_line
			(start -0.7874 -0.4064)
			(end -0.7874 0.4064)
			(stroke
				(width 0.1524)
				(type default)
			)
			(layer "B.SilkS")
		)
		(fp_line
			(start 0.7874 -0.4064)
			(end -0.7874 -0.4064)
			(stroke
				(width 0.1524)
				(type default)
			)
			(layer "B.SilkS")
		)
		(fp_line
			(start -0.67945 0.3048)
			(end -0.120396 0.3048)
			(stroke
				(width 0.1)
				(type default)
			)
			(layer "B.Fab")
		)
		(fp_line
			(start -0.120396 0.3048)
			(end -0.120396 0.2794)
			(stroke
				(width 0.1)
				(type default)
			)
			(layer "B.Fab")
		)
		(fp_line
			(start 0.12065 0.3048)
			(end 0.67945 0.3048)
			(stroke
				(width 0.1)
				(type default)
			)
			(layer "B.Fab")
		)
		(fp_line
			(start 0.67945 0.3048)
			(end 0.67945 -0.305054)
			(stroke
				(width 0.1)
				(type default)
			)
			(layer "B.Fab")
		)
		(fp_line
			(start -0.120396 0.2794)
			(end 0.12065 0.2794)
			(stroke
				(width 0.1)
				(type default)
			)
			(layer "B.Fab")
		)
		(fp_line
			(start 0.12065 0.2794)
			(end 0.12065 0.3048)
			(stroke
				(width 0.1)
				(type default)
			)
			(layer "B.Fab")
		)
		(fp_line
			(start -0.12065 -0.2794)
			(end -0.12065 -0.3048)
			(stroke
				(width 0.1)
				(type default)
			)
			(layer "B.Fab")
		)
		(fp_line
			(start 0.12065 -0.2794)
			(end -0.12065 -0.2794)
			(stroke
				(width 0.1)
				(type default)
			)
			(layer "B.Fab")
		)
		(fp_line
			(start -0.67945 -0.3048)
			(end -0.67945 0.3048)
			(stroke
				(width 0.1)
				(type default)
			)
			(layer "B.Fab")
		)
		(fp_line
			(start -0.12065 -0.3048)
			(end -0.67945 -0.3048)
			(stroke
				(width 0.1)
				(type default)
			)
			(layer "B.Fab")
		)
		(fp_line
			(start 0.12065 -0.305054)
			(end 0.12065 -0.2794)
			(stroke
				(width 0.1)
				(type default)
			)
			(layer "B.Fab")
		)
		(fp_line
			(start 0.67945 -0.305054)
			(end 0.12065 -0.305054)
			(stroke
				(width 0.1)
				(type default)
			)
			(layer "B.Fab")
		)
		(pad "1" smd circle
			(at 0.40005 0 90)
			(size 0 0)
			(layers "B.Cu" "B.Mask" "B.Paste")
			(net "P3V3_AUX_CPU0_USB2_AVDD33")
		)
		(pad "2" smd circle
			(at -0.40005 0 90)
			(size 0 0)
			(layers "B.Cu" "B.Mask" "B.Paste")
			(net "GND")
		)
	)
	(footprint ""
		(layer "B.Cu")
		(at 343.514934 -301.911258 -90)
		(property "Reference" "R4303"
			(at 0 0 90)
			(layer "B.SilkS")
			(hide yes)
			(effects
				(font
					(size 1.27 1.27)
				)
				(justify mirror)
			)
		)
		(property "Value" ""
			(at 0 0 90)
			(layer "B.Fab")
			(effects
				(font
					(size 1.27 1.27)
				)
				(justify mirror)
			)
		)
		(duplicate_pad_numbers_are_jumpers no)
		(fp_line
			(start -0.374142 0.4064)
			(end 0.311658 0.4064)
			(stroke
				(width 0.1524)
				(type default)
			)
			(layer "B.SilkS")
		)
		(fp_line
			(start 0.7874 0.005334)
			(end 0.7874 -0.4064)
			(stroke
				(width 0.1524)
				(type default)
			)
			(layer "B.SilkS")
		)
		(fp_line
			(start -0.7874 -0.4064)
			(end -0.7874 0.005334)
			(stroke
				(width 0.1524)
				(type default)
			)
			(layer "B.SilkS")
		)
		(fp_line
			(start 0.7874 -0.4064)
			(end -0.7874 -0.4064)
			(stroke
				(width 0.1524)
				(type default)
			)
			(layer "B.SilkS")
		)
		(fp_line
			(start -0.67945 0.3048)
			(end -0.120396 0.3048)
			(stroke
				(width 0.1)
				(type default)
			)
			(layer "B.Fab")
		)
		(fp_line
			(start -0.120396 0.3048)
			(end -0.120396 0.2794)
			(stroke
				(width 0.1)
				(type default)
			)
			(layer "B.Fab")
		)
		(fp_line
			(start 0.12065 0.3048)
			(end 0.67945 0.3048)
			(stroke
				(width 0.1)
				(type default)
			)
			(layer "B.Fab")
		)
		(fp_line
			(start 0.67945 0.3048)
			(end 0.67945 -0.305054)
			(stroke
				(width 0.1)
				(type default)
			)
			(layer "B.Fab")
		)
		(fp_line
			(start -0.120396 0.2794)
			(end 0.12065 0.2794)
			(stroke
				(width 0.1)
				(type default)
			)
			(layer "B.Fab")
		)
		(fp_line
			(start 0.12065 0.2794)
			(end 0.12065 0.3048)
			(stroke
				(width 0.1)
				(type default)
			)
			(layer "B.Fab")
		)
		(fp_line
			(start -0.12065 -0.2794)
			(end -0.12065 -0.3048)
			(stroke
				(width 0.1)
				(type default)
			)
			(layer "B.Fab")
		)
		(fp_line
			(start 0.12065 -0.2794)
			(end -0.12065 -0.2794)
			(stroke
				(width 0.1)
				(type default)
			)
			(layer "B.Fab")
		)
		(fp_line
			(start -0.67945 -0.3048)
			(end -0.67945 0.3048)
			(stroke
				(width 0.1)
				(type default)
			)
			(layer "B.Fab")
		)
		(fp_line
			(start -0.12065 -0.3048)
			(end -0.67945 -0.3048)
			(stroke
				(width 0.1)
				(type default)
			)
			(layer "B.Fab")
		)
		(fp_line
			(start 0.12065 -0.305054)
			(end 0.12065 -0.2794)
			(stroke
				(width 0.1)
				(type default)
			)
			(layer "B.Fab")
		)
		(fp_line
			(start 0.67945 -0.305054)
			(end 0.12065 -0.305054)
			(stroke
				(width 0.1)
				(type default)
			)
			(layer "B.Fab")
		)
		(pad "1" smd circle
			(at 0.40005 0 90)
			(size 0 0)
			(layers "B.Cu" "B.Mask" "B.Paste")
			(net "CLK_100M_CPU0_CLK12_R_DP")
		)
		(pad "2" smd circle
			(at -0.40005 0 90)
			(size 0 0)
			(layers "B.Cu" "B.Mask" "B.Paste")
			(net "CLK_100M_CPU0_CLK12_DP")
		)
	)
	(footprint ""
		(layer "B.Cu")
		(at 396.696184 -385.529328)
		(property "Reference" "ME8"
			(at 0 0 0)
			(layer "B.SilkS")
			(hide yes)
			(effects
				(font
					(size 1.27 1.27)
				)
				(justify mirror)
			)
		)
		(property "Value" ""
			(at 0 0 0)
			(layer "B.Fab")
			(effects
				(font
					(size 1.27 1.27)
				)
				(justify mirror)
			)
		)
		(duplicate_pad_numbers_are_jumpers no)
		(zone
			(layer "B.Cu")
			(hatch none 0.5)
			(connect_pads
				(clearance 0)
			)
			(min_thickness 0.25)
			(keepout
				(tracks allowed)
				(vias allowed)
				(pads allowed)
				(copperpour allowed)
				(footprints not_allowed)
			)
			(placement
				(enabled no)
				(sheetname "")
			)
			(fill
				(thermal_gap 0.5)
				(thermal_bridge_width 0.5)
				(island_removal_mode 0)
			)
			(polygon
				(pts
					(arc
						(start 464.0199 -364.816136)
						(mid 444.01994 -364.816136)
						(end 464.0199 -364.816136)
					)
				)
			)
		)
	)
	(footprint ""
		(layer "B.Cu")
		(at 336.180684 -335.041494 90)
		(property "Reference" "PC89_1"
			(at 0 0 90)
			(layer "B.SilkS")
			(hide yes)
			(effects
				(font
					(size 1.27 1.27)
				)
				(justify mirror)
			)
		)
		(property "Value" ""
			(at 0 0 90)
			(layer "B.Fab")
			(effects
				(font
					(size 1.27 1.27)
				)
				(justify mirror)
			)
		)
		(duplicate_pad_numbers_are_jumpers no)
		(fp_line
			(start 1.524 -0.762)
			(end -1.524 -0.762)
			(stroke
				(width 0.1524)
				(type default)
			)
			(layer "B.SilkS")
		)
		(fp_line
			(start -1.524 -0.762)
			(end -1.524 0.762)
			(stroke
				(width 0.1524)
				(type default)
			)
			(layer "B.SilkS")
		)
		(fp_line
			(start 1.524 0.762)
			(end 1.524 -0.762)
			(stroke
				(width 0.1524)
				(type default)
			)
			(layer "B.SilkS")
		)
		(fp_line
			(start -1.524 0.762)
			(end 1.524 0.762)
			(stroke
				(width 0.1524)
				(type default)
			)
			(layer "B.SilkS")
		)
		(fp_line
			(start 1.1049 -0.724916)
			(end 1.1049 0.724916)
			(stroke
				(width 0.1)
				(type default)
			)
			(layer "B.Fab")
		)
		(fp_line
			(start -1.1049 -0.724916)
			(end 1.1049 -0.724916)
			(stroke
				(width 0.1)
				(type default)
			)
			(layer "B.Fab")
		)
		(fp_line
			(start 1.1049 0.724916)
			(end -1.1049 0.724916)
			(stroke
				(width 0.1)
				(type default)
			)
			(layer "B.Fab")
		)
		(fp_line
			(start -1.1049 0.724916)
			(end -1.1049 -0.724916)
			(stroke
				(width 0.1)
				(type default)
			)
			(layer "B.Fab")
		)
		(pad "1" smd rect
			(at 0.889 0 90)
			(size 1.016 1.27)
			(layers "B.Cu" "B.Mask" "B.Paste")
			(net "SW_P12V_AUX_PVDDCR_CPU1_P0_FLT")
		)
		(pad "2" smd rect
			(at -0.889 0 90)
			(size 1.016 1.27)
			(layers "B.Cu" "B.Mask" "B.Paste")
			(net "GND")
		)
	)
	(footprint ""
		(layer "B.Cu")
		(at 212.471508 7.622794 180)
		(property "Reference" "J76"
			(at 4.59867 -1.055878 270)
			(unlocked yes)
			(layer "B.SilkS")
			(effects
				(font
					(size 0.7874 0.5842)
					(thickness 0.1524)
				)
				(justify left mirror)
			)
		)
		(property "Value" ""
			(at 0 0 0)
			(layer "B.Fab")
			(effects
				(font
					(size 1.27 1.27)
				)
				(justify mirror)
			)
		)
		(duplicate_pad_numbers_are_jumpers no)
		(fp_line
			(start 1.2192 2.06756)
			(end 1.2192 -2.06756)
			(stroke
				(width 0.1524)
				(type default)
			)
			(layer "B.SilkS")
		)
		(fp_line
			(start 1.2192 -2.06756)
			(end -1.2192 -2.06756)
			(stroke
				(width 0.1524)
				(type default)
			)
			(layer "B.SilkS")
		)
		(fp_line
			(start -1.2192 2.06756)
			(end 1.2192 2.06756)
			(stroke
				(width 0.1524)
				(type default)
			)
			(layer "B.SilkS")
		)
		(fp_line
			(start -1.2192 -2.06756)
			(end -1.2192 2.06756)
			(stroke
				(width 0.1524)
				(type default)
			)
			(layer "B.SilkS")
		)
		(pad "" np_thru_hole circle
			(at -3.4671 -1.27 90)
			(size 1.0414 1.0414)
			(drill 1.0414)
			(layers "*.Cu" "*.Mask")
			(clearance 0.381)
			(thermal_gap 0.381)
		)
		(pad "" np_thru_hole circle
			(at -3.4671 1.27 90)
			(size 1.0414 1.0414)
			(drill 1.0414)
			(layers "*.Cu" "*.Mask")
			(clearance 0.381)
			(thermal_gap 0.381)
		)
		(pad "" np_thru_hole circle
			(at 2.8829 -1.27 90)
			(size 1.0414 1.0414)
			(drill 1.0414)
			(layers "*.Cu" "*.Mask")
			(clearance 0.381)
			(thermal_gap 0.381)
		)
		(pad "" np_thru_hole circle
			(at 2.8829 1.27 90)
			(size 1.0414 1.0414)
			(drill 1.0414)
			(layers "*.Cu" "*.Mask")
			(clearance 0.381)
			(thermal_gap 0.381)
		)
		(pad "1" smd rect
			(at -0.8255 -0.249936 90)
			(size 0.3048 0.508)
			(layers "B.Cu" "B.Mask" "B.Paste")
			(net "DELTA_L_85_10INCH_BOT_DP")
		)
		(pad "2" smd rect
			(at -0.8255 0.249936 90)
			(size 0.3048 0.508)
			(layers "B.Cu" "B.Mask" "B.Paste")
			(net "DELTA_L_85_10INCH_BOT_DN")
		)
		(pad "3" smd circle
			(at 0 0)
			(size 0 0)
			(layers "B.Cu" "B.Mask" "B.Paste")
			(net "DELTA_L_GND_1")
		)
		(zone
			(layers "F.Cu" "B.Cu" "In1.Cu" "In2.Cu" "In3.Cu" "In4.Cu" "In5.Cu" "In6.Cu"
				"In7.Cu" "In8.Cu" "In9.Cu" "In10.Cu" "In11.Cu" "In12.Cu" "In13.Cu" "In14.Cu"
				"In15.Cu" "In16.Cu"
			)
			(hatch none 0.5)
			(connect_pads
				(clearance 0)
			)
			(min_thickness 0.25)
			(keepout
				(tracks not_allowed)
				(vias allowed)
				(pads allowed)
				(copperpour not_allowed)
				(footprints allowed)
			)
			(placement
				(enabled no)
				(sheetname "")
			)
			(fill
				(thermal_gap 0.5)
				(thermal_bridge_width 0.5)
				(island_removal_mode 0)
			)
			(polygon
				(pts
					(arc
						(start 210.515708 6.352794)
						(mid 208.661508 6.352794)
						(end 210.515708 6.352794)
					)
				)
			)
		)
		(zone
			(layers "F.Cu" "B.Cu" "In1.Cu" "In2.Cu" "In3.Cu" "In4.Cu" "In5.Cu" "In6.Cu"
				"In7.Cu" "In8.Cu" "In9.Cu" "In10.Cu" "In11.Cu" "In12.Cu" "In13.Cu" "In14.Cu"
				"In15.Cu" "In16.Cu"
			)
			(hatch none 0.5)
			(connect_pads
				(clearance 0)
			)
			(min_thickness 0.25)
			(keepout
				(tracks not_allowed)
				(vias allowed)
				(pads allowed)
				(copperpour not_allowed)
				(footprints allowed)
			)
			(placement
				(enabled no)
				(sheetname "")
			)
			(fill
				(thermal_gap 0.5)
				(thermal_bridge_width 0.5)
				(island_removal_mode 0)
			)
			(polygon
				(pts
					(arc
						(start 210.515708 8.892794)
						(mid 208.661508 8.892794)
						(end 210.515708 8.892794)
					)
				)
			)
		)
		(zone
			(layers "F.Cu" "B.Cu" "In1.Cu" "In2.Cu" "In3.Cu" "In4.Cu" "In5.Cu" "In6.Cu"
				"In7.Cu" "In8.Cu" "In9.Cu" "In10.Cu" "In11.Cu" "In12.Cu" "In13.Cu" "In14.Cu"
				"In15.Cu" "In16.Cu"
			)
			(hatch none 0.5)
			(connect_pads
				(clearance 0)
			)
			(min_thickness 0.25)
			(keepout
				(tracks not_allowed)
				(vias allowed)
				(pads allowed)
				(copperpour not_allowed)
				(footprints allowed)
			)
			(placement
				(enabled no)
				(sheetname "")
			)
			(fill
				(thermal_gap 0.5)
				(thermal_bridge_width 0.5)
				(island_removal_mode 0)
			)
			(polygon
				(pts
					(arc
						(start 216.865708 6.352794)
						(mid 215.011508 6.352794)
						(end 216.865708 6.352794)
					)
				)
			)
		)
		(zone
			(layers "F.Cu" "B.Cu" "In1.Cu" "In2.Cu" "In3.Cu" "In4.Cu" "In5.Cu" "In6.Cu"
				"In7.Cu" "In8.Cu" "In9.Cu" "In10.Cu" "In11.Cu" "In12.Cu" "In13.Cu" "In14.Cu"
				"In15.Cu" "In16.Cu"
			)
			(hatch none 0.5)
			(connect_pads
				(clearance 0)
			)
			(min_thickness 0.25)
			(keepout
				(tracks not_allowed)
				(vias allowed)
				(pads allowed)
				(copperpour not_allowed)
				(footprints allowed)
			)
			(placement
				(enabled no)
				(sheetname "")
			)
			(fill
				(thermal_gap 0.5)
				(thermal_bridge_width 0.5)
				(island_removal_mode 0)
			)
			(polygon
				(pts
					(arc
						(start 216.865708 8.892794)
						(mid 215.011508 8.892794)
						(end 216.865708 8.892794)
					)
				)
			)
		)
		(zone
			(layer "B.Cu")
			(hatch none 0.5)
			(connect_pads
				(clearance 0)
			)
			(min_thickness 0.25)
			(keepout
				(tracks not_allowed)
				(vias allowed)
				(pads allowed)
				(copperpour not_allowed)
				(footprints allowed)
			)
			(placement
				(enabled no)
				(sheetname "")
			)
			(fill
				(thermal_gap 0.5)
				(thermal_bridge_width 0.5)
				(island_removal_mode 0)
			)
			(polygon
				(pts
					(xy 213.589108 8.171434) (xy 213.589108 8.07593) (xy 212.992208 8.07593) (xy 212.992208 7.66953)
					(xy 213.589108 7.66953) (xy 213.589108 7.576058) (xy 212.992208 7.576058) (xy 212.992208 7.169658)
					(xy 213.589108 7.169658) (xy 213.589108 7.074154) (xy 212.890608 7.074154) (xy 212.890608 8.171434)
				)
			)
		)
	)
	(footprint ""
		(layer "B.Cu")
		(at 109.895386 -251.781564)
		(property "Reference" "C2459"
			(at 0 0 0)
			(layer "B.SilkS")
			(hide yes)
			(effects
				(font
					(size 1.27 1.27)
				)
				(justify mirror)
			)
		)
		(property "Value" ""
			(at 0 0 0)
			(layer "B.Fab")
			(effects
				(font
					(size 1.27 1.27)
				)
				(justify mirror)
			)
		)
		(duplicate_pad_numbers_are_jumpers no)
		(fp_line
			(start -0.7874 -0.4064)
			(end -0.7874 0.4064)
			(stroke
				(width 0.1524)
				(type default)
			)
			(layer "B.SilkS")
		)
		(fp_line
			(start -0.7874 0.4064)
			(end 0.7874 0.4064)
			(stroke
				(width 0.1524)
				(type default)
			)
			(layer "B.SilkS")
		)
		(fp_line
			(start 0.7874 -0.4064)
			(end -0.7874 -0.4064)
			(stroke
				(width 0.1524)
				(type default)
			)
			(layer "B.SilkS")
		)
		(fp_line
			(start 0.7874 0.4064)
			(end 0.7874 -0.4064)
			(stroke
				(width 0.1524)
				(type default)
			)
			(layer "B.SilkS")
		)
		(fp_line
			(start -0.67945 -0.3048)
			(end -0.67945 0.3048)
			(stroke
				(width 0.1)
				(type default)
			)
			(layer "B.Fab")
		)
		(fp_line
			(start -0.67945 0.3048)
			(end -0.120396 0.3048)
			(stroke
				(width 0.1)
				(type default)
			)
			(layer "B.Fab")
		)
		(fp_line
			(start -0.12065 -0.3048)
			(end -0.67945 -0.3048)
			(stroke
				(width 0.1)
				(type default)
			)
			(layer "B.Fab")
		)
		(fp_line
			(start -0.12065 -0.2794)
			(end -0.12065 -0.3048)
			(stroke
				(width 0.1)
				(type default)
			)
			(layer "B.Fab")
		)
		(fp_line
			(start -0.120396 0.2794)
			(end 0.12065 0.2794)
			(stroke
				(width 0.1)
				(type default)
			)
			(layer "B.Fab")
		)
		(fp_line
			(start -0.120396 0.3048)
			(end -0.120396 0.2794)
			(stroke
				(width 0.1)
				(type default)
			)
			(layer "B.Fab")
		)
		(fp_line
			(start 0.12065 -0.305054)
			(end 0.12065 -0.2794)
			(stroke
				(width 0.1)
				(type default)
			)
			(layer "B.Fab")
		)
		(fp_line
			(start 0.12065 -0.2794)
			(end -0.12065 -0.2794)
			(stroke
				(width 0.1)
				(type default)
			)
			(layer "B.Fab")
		)
		(fp_line
			(start 0.12065 0.2794)
			(end 0.12065 0.3048)
			(stroke
				(width 0.1)
				(type default)
			)
			(layer "B.Fab")
		)
		(fp_line
			(start 0.12065 0.3048)
			(end 0.67945 0.3048)
			(stroke
				(width 0.1)
				(type default)
			)
			(layer "B.Fab")
		)
		(fp_line
			(start 0.67945 -0.305054)
			(end 0.12065 -0.305054)
			(stroke
				(width 0.1)
				(type default)
			)
			(layer "B.Fab")
		)
		(fp_line
			(start 0.67945 0.3048)
			(end 0.67945 -0.305054)
			(stroke
				(width 0.1)
				(type default)
			)
			(layer "B.Fab")
		)
		(pad "1" smd circle
			(at 0.40005 0 180)
			(size 0 0)
			(layers "B.Cu" "B.Mask" "B.Paste")
			(net "PVDDCR_SOC_P1")
		)
		(pad "2" smd circle
			(at -0.40005 0 180)
			(size 0 0)
			(layers "B.Cu" "B.Mask" "B.Paste")
			(net "GND")
		)
	)
	(footprint ""
		(layer "B.Cu")
		(at 108.360464 -257.750564 180)
		(property "Reference" "C2668"
			(at 0 0 0)
			(layer "B.SilkS")
			(hide yes)
			(effects
				(font
					(size 1.27 1.27)
				)
				(justify mirror)
			)
		)
		(property "Value" ""
			(at 0 0 0)
			(layer "B.Fab")
			(effects
				(font
					(size 1.27 1.27)
				)
				(justify mirror)
			)
		)
		(duplicate_pad_numbers_are_jumpers no)
		(fp_line
			(start 0.7874 0.4064)
			(end 0.7874 -0.4064)
			(stroke
				(width 0.1524)
				(type default)
			)
			(layer "B.SilkS")
		)
		(fp_line
			(start 0.7874 -0.4064)
			(end -0.7874 -0.4064)
			(stroke
				(width 0.1524)
				(type default)
			)
			(layer "B.SilkS")
		)
		(fp_line
			(start -0.7874 0.4064)
			(end 0.7874 0.4064)
			(stroke
				(width 0.1524)
				(type default)
			)
			(layer "B.SilkS")
		)
		(fp_line
			(start -0.7874 -0.4064)
			(end -0.7874 0.4064)
			(stroke
				(width 0.1524)
				(type default)
			)
			(layer "B.SilkS")
		)
		(fp_line
			(start 0.67945 0.3048)
			(end 0.67945 -0.305054)
			(stroke
				(width 0.1)
				(type default)
			)
			(layer "B.Fab")
		)
		(fp_line
			(start 0.67945 -0.305054)
			(end 0.12065 -0.305054)
			(stroke
				(width 0.1)
				(type default)
			)
			(layer "B.Fab")
		)
		(fp_line
			(start 0.12065 0.3048)
			(end 0.67945 0.3048)
			(stroke
				(width 0.1)
				(type default)
			)
			(layer "B.Fab")
		)
		(fp_line
			(start 0.12065 0.2794)
			(end 0.12065 0.3048)
			(stroke
				(width 0.1)
				(type default)
			)
			(layer "B.Fab")
		)
		(fp_line
			(start 0.12065 -0.2794)
			(end -0.12065 -0.2794)
			(stroke
				(width 0.1)
				(type default)
			)
			(layer "B.Fab")
		)
		(fp_line
			(start 0.12065 -0.305054)
			(end 0.12065 -0.2794)
			(stroke
				(width 0.1)
				(type default)
			)
			(layer "B.Fab")
		)
		(fp_line
			(start -0.120396 0.3048)
			(end -0.120396 0.2794)
			(stroke
				(width 0.1)
				(type default)
			)
			(layer "B.Fab")
		)
		(fp_line
			(start -0.120396 0.2794)
			(end 0.12065 0.2794)
			(stroke
				(width 0.1)
				(type default)
			)
			(layer "B.Fab")
		)
		(fp_line
			(start -0.12065 -0.2794)
			(end -0.12065 -0.3048)
			(stroke
				(width 0.1)
				(type default)
			)
			(layer "B.Fab")
		)
		(fp_line
			(start -0.12065 -0.3048)
			(end -0.67945 -0.3048)
			(stroke
				(width 0.1)
				(type default)
			)
			(layer "B.Fab")
		)
		(fp_line
			(start -0.67945 0.3048)
			(end -0.120396 0.3048)
			(stroke
				(width 0.1)
				(type default)
			)
			(layer "B.Fab")
		)
		(fp_line
			(start -0.67945 -0.3048)
			(end -0.67945 0.3048)
			(stroke
				(width 0.1)
				(type default)
			)
			(layer "B.Fab")
		)
		(pad "1" smd circle
			(at 0.40005 0)
			(size 0 0)
			(layers "B.Cu" "B.Mask" "B.Paste")
			(net "PVDD18_S5_P1")
		)
		(pad "2" smd circle
			(at -0.40005 0)
			(size 0 0)
			(layers "B.Cu" "B.Mask" "B.Paste")
			(net "GND")
		)
	)
	(footprint ""
		(layer "B.Cu")
		(at 350.318832 -258.830064 180)
		(property "Reference" "C2649"
			(at 0 0 0)
			(layer "B.SilkS")
			(hide yes)
			(effects
				(font
					(size 1.27 1.27)
				)
				(justify mirror)
			)
		)
		(property "Value" ""
			(at 0 0 0)
			(layer "B.Fab")
			(effects
				(font
					(size 1.27 1.27)
				)
				(justify mirror)
			)
		)
		(duplicate_pad_numbers_are_jumpers no)
		(fp_line
			(start 0.7874 0.4064)
			(end 0.7874 -0.4064)
			(stroke
				(width 0.1524)
				(type default)
			)
			(layer "B.SilkS")
		)
		(fp_line
			(start 0.7874 -0.4064)
			(end -0.7874 -0.4064)
			(stroke
				(width 0.1524)
				(type default)
			)
			(layer "B.SilkS")
		)
		(fp_line
			(start -0.7874 0.4064)
			(end 0.7874 0.4064)
			(stroke
				(width 0.1524)
				(type default)
			)
			(layer "B.SilkS")
		)
		(fp_line
			(start -0.7874 -0.4064)
			(end -0.7874 0.4064)
			(stroke
				(width 0.1524)
				(type default)
			)
			(layer "B.SilkS")
		)
		(fp_line
			(start 0.67945 0.3048)
			(end 0.67945 -0.305054)
			(stroke
				(width 0.1)
				(type default)
			)
			(layer "B.Fab")
		)
		(fp_line
			(start 0.67945 -0.305054)
			(end 0.12065 -0.305054)
			(stroke
				(width 0.1)
				(type default)
			)
			(layer "B.Fab")
		)
		(fp_line
			(start 0.12065 0.3048)
			(end 0.67945 0.3048)
			(stroke
				(width 0.1)
				(type default)
			)
			(layer "B.Fab")
		)
		(fp_line
			(start 0.12065 0.2794)
			(end 0.12065 0.3048)
			(stroke
				(width 0.1)
				(type default)
			)
			(layer "B.Fab")
		)
		(fp_line
			(start 0.12065 -0.2794)
			(end -0.12065 -0.2794)
			(stroke
				(width 0.1)
				(type default)
			)
			(layer "B.Fab")
		)
		(fp_line
			(start 0.12065 -0.305054)
			(end 0.12065 -0.2794)
			(stroke
				(width 0.1)
				(type default)
			)
			(layer "B.Fab")
		)
		(fp_line
			(start -0.120396 0.3048)
			(end -0.120396 0.2794)
			(stroke
				(width 0.1)
				(type default)
			)
			(layer "B.Fab")
		)
		(fp_line
			(start -0.120396 0.2794)
			(end 0.12065 0.2794)
			(stroke
				(width 0.1)
				(type default)
			)
			(layer "B.Fab")
		)
		(fp_line
			(start -0.12065 -0.2794)
			(end -0.12065 -0.3048)
			(stroke
				(width 0.1)
				(type default)
			)
			(layer "B.Fab")
		)
		(fp_line
			(start -0.12065 -0.3048)
			(end -0.67945 -0.3048)
			(stroke
				(width 0.1)
				(type default)
			)
			(layer "B.Fab")
		)
		(fp_line
			(start -0.67945 0.3048)
			(end -0.120396 0.3048)
			(stroke
				(width 0.1)
				(type default)
			)
			(layer "B.Fab")
		)
		(fp_line
			(start -0.67945 -0.3048)
			(end -0.67945 0.3048)
			(stroke
				(width 0.1)
				(type default)
			)
			(layer "B.Fab")
		)
		(pad "1" smd circle
			(at 0.40005 0)
			(size 0 0)
			(layers "B.Cu" "B.Mask" "B.Paste")
			(net "PVDDIO_P0")
		)
		(pad "2" smd circle
			(at -0.40005 0)
			(size 0 0)
			(layers "B.Cu" "B.Mask" "B.Paste")
			(net "GND")
		)
	)
	(footprint ""
		(layer "B.Cu")
		(at 375.463562 -416.899344 90)
		(property "Reference" "C6600"
			(at 0 0 90)
			(layer "B.SilkS")
			(hide yes)
			(effects
				(font
					(size 1.27 1.27)
				)
				(justify mirror)
			)
		)
		(property "Value" ""
			(at 0 0 90)
			(layer "B.Fab")
			(effects
				(font
					(size 1.27 1.27)
				)
				(justify mirror)
			)
		)
		(duplicate_pad_numbers_are_jumpers no)
		(fp_line
			(start 0.299974 -0.150114)
			(end -0.299974 -0.150114)
			(stroke
				(width 0.1)
				(type default)
			)
			(layer "B.Fab")
		)
		(fp_line
			(start -0.299974 -0.150114)
			(end -0.299974 0.150114)
			(stroke
				(width 0.1)
				(type default)
			)
			(layer "B.Fab")
		)
		(fp_line
			(start 0.299974 0.150114)
			(end 0.299974 -0.150114)
			(stroke
				(width 0.1)
				(type default)
			)
			(layer "B.Fab")
		)
		(fp_line
			(start -0.299974 0.150114)
			(end 0.299974 0.150114)
			(stroke
				(width 0.1)
				(type default)
			)
			(layer "B.Fab")
		)
		(pad "1" smd rect
			(at 0.2667 0 270)
			(size 0.3048 0.381)
			(layers "B.Cu" "B.Mask" "B.Paste")
			(net "P5E_CPU0_P3_TX_BUF_C_DN<1>")
		)
		(pad "2" smd rect
			(at -0.2667 0 270)
			(size 0.3048 0.381)
			(layers "B.Cu" "B.Mask" "B.Paste")
			(net "P5E_CPU0_P3_TX_BUF_DN<1>")
		)
	)
	(footprint ""
		(layer "B.Cu")
		(at 509.384808 -147.926806 90)
		(property "Reference" "X25"
			(at 0.885444 3.130042 270)
			(unlocked yes)
			(layer "B.SilkS")
			(effects
				(font
					(size 0.7874 0.5842)
					(thickness 0.1524)
				)
				(justify left mirror)
			)
		)
		(property "Value" ""
			(at 0 0 90)
			(layer "B.Fab")
			(effects
				(font
					(size 1.27 1.27)
				)
				(justify mirror)
			)
		)
		(property "Device Type" "TP_TDR_4P_FTS_TH-TP_TDR_4P_DIP,EMPTY,TP15"
			(at -1.30175 1.27 0)
			(unlocked yes)
			(layer "B.Fab")
			(hide yes)
			(effects
				(font
					(size 0.635 0.4064)
					(thickness 0.1524)
				)
				(justify mirror)
			)
		)
		(property "User Part Number" "N_A"
			(at -1.30175 1.27 0)
			(unlocked yes)
			(layer "Cmts.User")
			(hide yes)
			(effects
				(font
					(size 0.635 0.4064)
					(thickness 0.1524)
				)
				(justify mirror)
			)
		)
		(duplicate_pad_numbers_are_jumpers no)
		(fp_line
			(start 0 -1.27)
			(end 0 -0.635)
			(stroke
				(width 0.1524)
				(type default)
			)
			(layer "B.SilkS")
		)
		(fp_line
			(start -2.54 -1.27)
			(end 0 -1.27)
			(stroke
				(width 0.1524)
				(type default)
			)
			(layer "B.SilkS")
		)
		(fp_line
			(start -2.54 -1.1303)
			(end -2.54 -1.27)
			(stroke
				(width 0.1524)
				(type default)
			)
			(layer "B.SilkS")
		)
		(fp_line
			(start 0 0.635)
			(end 0 1.905)
			(stroke
				(width 0.1524)
				(type default)
			)
			(layer "B.SilkS")
		)
		(fp_line
			(start -2.54 1.4097)
			(end -2.54 1.1303)
			(stroke
				(width 0.1524)
				(type default)
			)
			(layer "B.SilkS")
		)
		(fp_line
			(start 0 3.175)
			(end 0 3.81)
			(stroke
				(width 0.1524)
				(type default)
			)
			(layer "B.SilkS")
		)
		(fp_line
			(start 0 3.81)
			(end -2.54 3.81)
			(stroke
				(width 0.1524)
				(type default)
			)
			(layer "B.SilkS")
		)
		(fp_line
			(start -2.54 3.81)
			(end -2.54 3.6703)
			(stroke
				(width 0.1524)
				(type default)
			)
			(layer "B.SilkS")
		)
		(fp_poly
			(pts
				(xy 2.285746 -0.762) (xy 2.285746 0.762) (xy 0.761746 0)
			)
			(stroke
				(width 0)
				(type default)
			)
			(fill yes)
			(layer "B.SilkS")
		)
		(fp_line
			(start 0 -1.27)
			(end 0 3.81)
			(stroke
				(width 0.1)
				(type default)
			)
			(layer "B.Fab")
		)
		(fp_line
			(start -2.54 -1.27)
			(end 0 -1.27)
			(stroke
				(width 0.1)
				(type default)
			)
			(layer "B.Fab")
		)
		(fp_line
			(start 0 3.81)
			(end -2.54 3.81)
			(stroke
				(width 0.1)
				(type default)
			)
			(layer "B.Fab")
		)
		(fp_line
			(start -2.54 3.81)
			(end -2.54 -1.27)
			(stroke
				(width 0.1)
				(type default)
			)
			(layer "B.Fab")
		)
		(fp_poly
			(pts
				(xy 0.761746 0) (xy 2.285746 -0.762) (xy 2.285746 0.762)
			)
			(stroke
				(width 0)
				(type default)
			)
			(fill yes)
			(layer "B.Fab")
		)
		(pad "1" thru_hole circle
			(at 0 0 270)
			(size 1.0033 1.0033)
			(drill 0.249936)
			(layers "*.Cu" "*.Mask")
			(remove_unused_layers no)
			(net "TDR_DIFF_80_IN5_DP")
			(clearance 0.10795)
			(padstack
				(mode front_inner_back)
				(layer "Inner"
					(shape circle)
					(size 0.8001 0.8001)
					(clearance 0.1524)
				)
				(layer "B.Cu"
					(shape circle)
					(size 1.0033 1.0033)
					(thermal_gap 0.10795)
					(clearance 0.10795)
				)
			)
		)
		(pad "2" thru_hole circle
			(at -2.54 0 270)
			(size 1.9939 1.9939)
			(drill 0.249936)
			(layers "*.Cu" "*.Mask")
			(remove_unused_layers no)
			(net "T1_GND")
			(clearance 0.10795)
			(padstack
				(mode front_inner_back)
				(layer "Inner"
					(shape circle)
					(size 0.8001 0.8001)
					(clearance 0.1524)
				)
				(layer "B.Cu"
					(shape circle)
					(size 1.9939 1.9939)
					(thermal_gap 0.10795)
					(clearance 0.10795)
				)
			)
		)
		(pad "3" thru_hole circle
			(at -2.54 2.54 270)
			(size 1.9939 1.9939)
			(drill 0.249936)
			(layers "*.Cu" "*.Mask")
			(remove_unused_layers no)
			(net "T1_GND")
			(clearance 0.10795)
			(padstack
				(mode front_inner_back)
				(layer "Inner"
					(shape circle)
					(size 0.8001 0.8001)
					(clearance 0.1524)
				)
				(layer "B.Cu"
					(shape circle)
					(size 1.9939 1.9939)
					(thermal_gap 0.10795)
					(clearance 0.10795)
				)
			)
		)
		(pad "4" thru_hole circle
			(at 0 2.54 270)
			(size 1.0033 1.0033)
			(drill 0.249936)
			(layers "*.Cu" "*.Mask")
			(remove_unused_layers no)
			(net "TDR_DIFF_80_IN5_DN")
			(clearance 0.10795)
			(padstack
				(mode front_inner_back)
				(layer "Inner"
					(shape circle)
					(size 0.8001 0.8001)
					(clearance 0.1524)
				)
				(layer "B.Cu"
					(shape circle)
					(size 1.0033 1.0033)
					(thermal_gap 0.10795)
					(clearance 0.10795)
				)
			)
		)
	)
	(footprint ""
		(layer "B.Cu")
		(at 407.543254 -162.237928 -90)
		(property "Reference" "PC8010"
			(at 0 0 90)
			(layer "B.SilkS")
			(hide yes)
			(effects
				(font
					(size 1.27 1.27)
				)
				(justify mirror)
			)
		)
		(property "Value" ""
			(at 0 0 90)
			(layer "B.Fab")
			(effects
				(font
					(size 1.27 1.27)
				)
				(justify mirror)
			)
		)
		(duplicate_pad_numbers_are_jumpers no)
		(fp_line
			(start -1.524 0.762)
			(end 1.524 0.762)
			(stroke
				(width 0.1524)
				(type default)
			)
			(layer "B.SilkS")
		)
		(fp_line
			(start 1.524 0.762)
			(end 1.524 -0.762)
			(stroke
				(width 0.1524)
				(type default)
			)
			(layer "B.SilkS")
		)
		(fp_line
			(start -1.524 -0.762)
			(end -1.524 0.762)
			(stroke
				(width 0.1524)
				(type default)
			)
			(layer "B.SilkS")
		)
		(fp_line
			(start 1.524 -0.762)
			(end -1.524 -0.762)
			(stroke
				(width 0.1524)
				(type default)
			)
			(layer "B.SilkS")
		)
		(fp_line
			(start -1.1049 0.724916)
			(end -1.1049 -0.724916)
			(stroke
				(width 0.1)
				(type default)
			)
			(layer "B.Fab")
		)
		(fp_line
			(start 1.1049 0.724916)
			(end -1.1049 0.724916)
			(stroke
				(width 0.1)
				(type default)
			)
			(layer "B.Fab")
		)
		(fp_line
			(start -1.1049 -0.724916)
			(end 1.1049 -0.724916)
			(stroke
				(width 0.1)
				(type default)
			)
			(layer "B.Fab")
		)
		(fp_line
			(start 1.1049 -0.724916)
			(end 1.1049 0.724916)
			(stroke
				(width 0.1)
				(type default)
			)
			(layer "B.Fab")
		)
		(pad "1" smd rect
			(at 0.889 0 270)
			(size 1.016 1.27)
			(layers "B.Cu" "B.Mask" "B.Paste")
			(net "SW_P12V_AUX_PVDDCR_SOC_P0_FLT")
		)
		(pad "2" smd rect
			(at -0.889 0 270)
			(size 1.016 1.27)
			(layers "B.Cu" "B.Mask" "B.Paste")
			(net "GND")
		)
	)
	(footprint ""
		(layer "B.Cu")
		(at 119.463566 -408.517344 90)
		(property "Reference" "C6728"
			(at 0 0 90)
			(layer "B.SilkS")
			(hide yes)
			(effects
				(font
					(size 1.27 1.27)
				)
				(justify mirror)
			)
		)
		(property "Value" ""
			(at 0 0 90)
			(layer "B.Fab")
			(effects
				(font
					(size 1.27 1.27)
				)
				(justify mirror)
			)
		)
		(duplicate_pad_numbers_are_jumpers no)
		(fp_line
			(start 0.299974 -0.150114)
			(end -0.299974 -0.150114)
			(stroke
				(width 0.1)
				(type default)
			)
			(layer "B.Fab")
		)
		(fp_line
			(start -0.299974 -0.150114)
			(end -0.299974 0.150114)
			(stroke
				(width 0.1)
				(type default)
			)
			(layer "B.Fab")
		)
		(fp_line
			(start 0.299974 0.150114)
			(end 0.299974 -0.150114)
			(stroke
				(width 0.1)
				(type default)
			)
			(layer "B.Fab")
		)
		(fp_line
			(start -0.299974 0.150114)
			(end 0.299974 0.150114)
			(stroke
				(width 0.1)
				(type default)
			)
			(layer "B.Fab")
		)
		(pad "1" smd rect
			(at 0.2667 0 270)
			(size 0.3048 0.381)
			(layers "B.Cu" "B.Mask" "B.Paste")
			(net "P5E_CPU1_P3_TX_BUF_C_DN<1>")
		)
		(pad "2" smd rect
			(at -0.2667 0 270)
			(size 0.3048 0.381)
			(layers "B.Cu" "B.Mask" "B.Paste")
			(net "P5E_CPU1_P3_TX_BUF_DN<1>")
		)
	)
	(footprint ""
		(layer "B.Cu")
		(at 44.340272 -192.66027)
		(property "Reference" "C179"
			(at 0 0 0)
			(layer "B.SilkS")
			(hide yes)
			(effects
				(font
					(size 1.27 1.27)
				)
				(justify mirror)
			)
		)
		(property "Value" ""
			(at 0 0 0)
			(layer "B.Fab")
			(effects
				(font
					(size 1.27 1.27)
				)
				(justify mirror)
			)
		)
		(duplicate_pad_numbers_are_jumpers no)
		(fp_line
			(start -1.524 -0.762)
			(end -1.524 0.762)
			(stroke
				(width 0.1524)
				(type default)
			)
			(layer "B.SilkS")
		)
		(fp_line
			(start -1.524 0.762)
			(end 1.524 0.762)
			(stroke
				(width 0.1524)
				(type default)
			)
			(layer "B.SilkS")
		)
		(fp_line
			(start 1.524 -0.762)
			(end -1.524 -0.762)
			(stroke
				(width 0.1524)
				(type default)
			)
			(layer "B.SilkS")
		)
		(fp_line
			(start 1.524 0.762)
			(end 1.524 -0.762)
			(stroke
				(width 0.1524)
				(type default)
			)
			(layer "B.SilkS")
		)
		(fp_line
			(start -1.1049 -0.724916)
			(end 1.1049 -0.724916)
			(stroke
				(width 0.1)
				(type default)
			)
			(layer "B.Fab")
		)
		(fp_line
			(start -1.1049 0.724916)
			(end -1.1049 -0.724916)
			(stroke
				(width 0.1)
				(type default)
			)
			(layer "B.Fab")
		)
		(fp_line
			(start 1.1049 -0.724916)
			(end 1.1049 0.724916)
			(stroke
				(width 0.1)
				(type default)
			)
			(layer "B.Fab")
		)
		(fp_line
			(start 1.1049 0.724916)
			(end -1.1049 0.724916)
			(stroke
				(width 0.1)
				(type default)
			)
			(layer "B.Fab")
		)
		(pad "1" smd rect
			(at 0.889 0)
			(size 1.016 1.27)
			(layers "B.Cu" "B.Mask" "B.Paste")
			(net "P12V_MEM_CPU1")
		)
		(pad "2" smd rect
			(at -0.889 0)
			(size 1.016 1.27)
			(layers "B.Cu" "B.Mask" "B.Paste")
			(net "GND")
		)
	)
	(footprint ""
		(layer "B.Cu")
		(at 266.30376 -193.99631)
		(property "Reference" "R94"
			(at 0 0 0)
			(layer "B.SilkS")
			(hide yes)
			(effects
				(font
					(size 1.27 1.27)
				)
				(justify mirror)
			)
		)
		(property "Value" ""
			(at 0 0 0)
			(layer "B.Fab")
			(effects
				(font
					(size 1.27 1.27)
				)
				(justify mirror)
			)
		)
		(duplicate_pad_numbers_are_jumpers no)
		(fp_line
			(start -0.7874 -0.4064)
			(end -0.7874 0.4064)
			(stroke
				(width 0.1524)
				(type default)
			)
			(layer "B.SilkS")
		)
		(fp_line
			(start -0.7874 0.4064)
			(end 0.7874 0.4064)
			(stroke
				(width 0.1524)
				(type default)
			)
			(layer "B.SilkS")
		)
		(fp_line
			(start 0.7874 -0.4064)
			(end -0.7874 -0.4064)
			(stroke
				(width 0.1524)
				(type default)
			)
			(layer "B.SilkS")
		)
		(fp_line
			(start 0.7874 0.4064)
			(end 0.7874 -0.4064)
			(stroke
				(width 0.1524)
				(type default)
			)
			(layer "B.SilkS")
		)
		(fp_line
			(start -0.67945 -0.3048)
			(end -0.67945 0.3048)
			(stroke
				(width 0.1)
				(type default)
			)
			(layer "B.Fab")
		)
		(fp_line
			(start -0.67945 0.3048)
			(end -0.120396 0.3048)
			(stroke
				(width 0.1)
				(type default)
			)
			(layer "B.Fab")
		)
		(fp_line
			(start -0.12065 -0.3048)
			(end -0.67945 -0.3048)
			(stroke
				(width 0.1)
				(type default)
			)
			(layer "B.Fab")
		)
		(fp_line
			(start -0.12065 -0.2794)
			(end -0.12065 -0.3048)
			(stroke
				(width 0.1)
				(type default)
			)
			(layer "B.Fab")
		)
		(fp_line
			(start -0.120396 0.2794)
			(end 0.12065 0.2794)
			(stroke
				(width 0.1)
				(type default)
			)
			(layer "B.Fab")
		)
		(fp_line
			(start -0.120396 0.3048)
			(end -0.120396 0.2794)
			(stroke
				(width 0.1)
				(type default)
			)
			(layer "B.Fab")
		)
		(fp_line
			(start 0.12065 -0.305054)
			(end 0.12065 -0.2794)
			(stroke
				(width 0.1)
				(type default)
			)
			(layer "B.Fab")
		)
		(fp_line
			(start 0.12065 -0.2794)
			(end -0.12065 -0.2794)
			(stroke
				(width 0.1)
				(type default)
			)
			(layer "B.Fab")
		)
		(fp_line
			(start 0.12065 0.2794)
			(end 0.12065 0.3048)
			(stroke
				(width 0.1)
				(type default)
			)
			(layer "B.Fab")
		)
		(fp_line
			(start 0.12065 0.3048)
			(end 0.67945 0.3048)
			(stroke
				(width 0.1)
				(type default)
			)
			(layer "B.Fab")
		)
		(fp_line
			(start 0.67945 -0.305054)
			(end 0.12065 -0.305054)
			(stroke
				(width 0.1)
				(type default)
			)
			(layer "B.Fab")
		)
		(fp_line
			(start 0.67945 0.3048)
			(end 0.67945 -0.305054)
			(stroke
				(width 0.1)
				(type default)
			)
			(layer "B.Fab")
		)
		(pad "1" smd circle
			(at 0.40005 0 180)
			(size 0 0)
			(layers "B.Cu" "B.Mask" "B.Paste")
			(net "P3V3")
		)
		(pad "2" smd circle
			(at -0.40005 0 180)
			(size 0 0)
			(layers "B.Cu" "B.Mask" "B.Paste")
			(net "PWRGD_CHF_CPU0_DIMM")
		)
	)
	(footprint ""
		(layer "B.Cu")
		(at 144.927574 -314.49391 180)
		(property "Reference" "R550"
			(at 0 0 0)
			(layer "B.SilkS")
			(hide yes)
			(effects
				(font
					(size 1.27 1.27)
				)
				(justify mirror)
			)
		)
		(property "Value" ""
			(at 0 0 0)
			(layer "B.Fab")
			(effects
				(font
					(size 1.27 1.27)
				)
				(justify mirror)
			)
		)
		(duplicate_pad_numbers_are_jumpers no)
		(fp_line
			(start 0.7874 0.4064)
			(end 0.7874 -0.4064)
			(stroke
				(width 0.1524)
				(type default)
			)
			(layer "B.SilkS")
		)
		(fp_line
			(start 0.7874 -0.4064)
			(end -0.7874 -0.4064)
			(stroke
				(width 0.1524)
				(type default)
			)
			(layer "B.SilkS")
		)
		(fp_line
			(start -0.7874 0.4064)
			(end 0.7874 0.4064)
			(stroke
				(width 0.1524)
				(type default)
			)
			(layer "B.SilkS")
		)
		(fp_line
			(start -0.7874 -0.4064)
			(end -0.7874 0.4064)
			(stroke
				(width 0.1524)
				(type default)
			)
			(layer "B.SilkS")
		)
		(fp_line
			(start 0.67945 0.3048)
			(end 0.67945 -0.305054)
			(stroke
				(width 0.1)
				(type default)
			)
			(layer "B.Fab")
		)
		(fp_line
			(start 0.67945 -0.305054)
			(end 0.12065 -0.305054)
			(stroke
				(width 0.1)
				(type default)
			)
			(layer "B.Fab")
		)
		(fp_line
			(start 0.12065 0.3048)
			(end 0.67945 0.3048)
			(stroke
				(width 0.1)
				(type default)
			)
			(layer "B.Fab")
		)
		(fp_line
			(start 0.12065 0.2794)
			(end 0.12065 0.3048)
			(stroke
				(width 0.1)
				(type default)
			)
			(layer "B.Fab")
		)
		(fp_line
			(start 0.12065 -0.2794)
			(end -0.12065 -0.2794)
			(stroke
				(width 0.1)
				(type default)
			)
			(layer "B.Fab")
		)
		(fp_line
			(start 0.12065 -0.305054)
			(end 0.12065 -0.2794)
			(stroke
				(width 0.1)
				(type default)
			)
			(layer "B.Fab")
		)
		(fp_line
			(start -0.120396 0.3048)
			(end -0.120396 0.2794)
			(stroke
				(width 0.1)
				(type default)
			)
			(layer "B.Fab")
		)
		(fp_line
			(start -0.120396 0.2794)
			(end 0.12065 0.2794)
			(stroke
				(width 0.1)
				(type default)
			)
			(layer "B.Fab")
		)
		(fp_line
			(start -0.12065 -0.2794)
			(end -0.12065 -0.3048)
			(stroke
				(width 0.1)
				(type default)
			)
			(layer "B.Fab")
		)
		(fp_line
			(start -0.12065 -0.3048)
			(end -0.67945 -0.3048)
			(stroke
				(width 0.1)
				(type default)
			)
			(layer "B.Fab")
		)
		(fp_line
			(start -0.67945 0.3048)
			(end -0.120396 0.3048)
			(stroke
				(width 0.1)
				(type default)
			)
			(layer "B.Fab")
		)
		(fp_line
			(start -0.67945 -0.3048)
			(end -0.67945 0.3048)
			(stroke
				(width 0.1)
				(type default)
			)
			(layer "B.Fab")
		)
		(pad "1" smd circle
			(at 0.40005 0)
			(size 0 0)
			(layers "B.Cu" "B.Mask" "B.Paste")
			(net "CPU1_SMERR_N")
		)
		(pad "2" smd circle
			(at -0.40005 0)
			(size 0 0)
			(layers "B.Cu" "B.Mask" "B.Paste")
			(net "PVDD18_S5_P1")
		)
	)
	(footprint ""
		(layer "B.Cu")
		(at 90.209878 -149.96541 180)
		(property "Reference" "PR172"
			(at 0 0 0)
			(layer "B.SilkS")
			(hide yes)
			(effects
				(font
					(size 1.27 1.27)
				)
				(justify mirror)
			)
		)
		(property "Value" ""
			(at 0 0 0)
			(layer "B.Fab")
			(effects
				(font
					(size 1.27 1.27)
				)
				(justify mirror)
			)
		)
		(duplicate_pad_numbers_are_jumpers no)
		(fp_line
			(start 0.7874 0.4064)
			(end 0.7874 -0.4064)
			(stroke
				(width 0.1524)
				(type default)
			)
			(layer "B.SilkS")
		)
		(fp_line
			(start 0.7874 -0.4064)
			(end -0.7874 -0.4064)
			(stroke
				(width 0.1524)
				(type default)
			)
			(layer "B.SilkS")
		)
		(fp_line
			(start -0.7874 0.4064)
			(end 0.7874 0.4064)
			(stroke
				(width 0.1524)
				(type default)
			)
			(layer "B.SilkS")
		)
		(fp_line
			(start -0.7874 -0.4064)
			(end -0.7874 0.4064)
			(stroke
				(width 0.1524)
				(type default)
			)
			(layer "B.SilkS")
		)
		(fp_line
			(start 0.67945 0.3048)
			(end 0.67945 -0.305054)
			(stroke
				(width 0.1)
				(type default)
			)
			(layer "B.Fab")
		)
		(fp_line
			(start 0.67945 -0.305054)
			(end 0.12065 -0.305054)
			(stroke
				(width 0.1)
				(type default)
			)
			(layer "B.Fab")
		)
		(fp_line
			(start 0.12065 0.3048)
			(end 0.67945 0.3048)
			(stroke
				(width 0.1)
				(type default)
			)
			(layer "B.Fab")
		)
		(fp_line
			(start 0.12065 0.2794)
			(end 0.12065 0.3048)
			(stroke
				(width 0.1)
				(type default)
			)
			(layer "B.Fab")
		)
		(fp_line
			(start 0.12065 -0.2794)
			(end -0.12065 -0.2794)
			(stroke
				(width 0.1)
				(type default)
			)
			(layer "B.Fab")
		)
		(fp_line
			(start 0.12065 -0.305054)
			(end 0.12065 -0.2794)
			(stroke
				(width 0.1)
				(type default)
			)
			(layer "B.Fab")
		)
		(fp_line
			(start -0.120396 0.3048)
			(end -0.120396 0.2794)
			(stroke
				(width 0.1)
				(type default)
			)
			(layer "B.Fab")
		)
		(fp_line
			(start -0.120396 0.2794)
			(end 0.12065 0.2794)
			(stroke
				(width 0.1)
				(type default)
			)
			(layer "B.Fab")
		)
		(fp_line
			(start -0.12065 -0.2794)
			(end -0.12065 -0.3048)
			(stroke
				(width 0.1)
				(type default)
			)
			(layer "B.Fab")
		)
		(fp_line
			(start -0.12065 -0.3048)
			(end -0.67945 -0.3048)
			(stroke
				(width 0.1)
				(type default)
			)
			(layer "B.Fab")
		)
		(fp_line
			(start -0.67945 0.3048)
			(end -0.120396 0.3048)
			(stroke
				(width 0.1)
				(type default)
			)
			(layer "B.Fab")
		)
		(fp_line
			(start -0.67945 -0.3048)
			(end -0.67945 0.3048)
			(stroke
				(width 0.1)
				(type default)
			)
			(layer "B.Fab")
		)
		(pad "1" smd circle
			(at 0.40005 0)
			(size 0 0)
			(layers "B.Cu" "B.Mask" "B.Paste")
			(net "SVID_PVDDCR_CPU0_P1_SVTI")
		)
		(pad "2" smd circle
			(at -0.40005 0)
			(size 0 0)
			(layers "B.Cu" "B.Mask" "B.Paste")
			(net "SVID_PVDDCR_CPU0_P1_SVTI_R")
		)
	)
	(footprint ""
		(layer "B.Cu")
		(at 144.883886 -408.517344 90)
		(property "Reference" "C6743"
			(at 0 0 90)
			(layer "B.SilkS")
			(hide yes)
			(effects
				(font
					(size 1.27 1.27)
				)
				(justify mirror)
			)
		)
		(property "Value" ""
			(at 0 0 90)
			(layer "B.Fab")
			(effects
				(font
					(size 1.27 1.27)
				)
				(justify mirror)
			)
		)
		(duplicate_pad_numbers_are_jumpers no)
		(fp_line
			(start 0.299974 -0.150114)
			(end -0.299974 -0.150114)
			(stroke
				(width 0.1)
				(type default)
			)
			(layer "B.Fab")
		)
		(fp_line
			(start -0.299974 -0.150114)
			(end -0.299974 0.150114)
			(stroke
				(width 0.1)
				(type default)
			)
			(layer "B.Fab")
		)
		(fp_line
			(start 0.299974 0.150114)
			(end 0.299974 -0.150114)
			(stroke
				(width 0.1)
				(type default)
			)
			(layer "B.Fab")
		)
		(fp_line
			(start -0.299974 0.150114)
			(end 0.299974 0.150114)
			(stroke
				(width 0.1)
				(type default)
			)
			(layer "B.Fab")
		)
		(pad "1" smd rect
			(at 0.2667 0 270)
			(size 0.3048 0.381)
			(layers "B.Cu" "B.Mask" "B.Paste")
			(net "P5E_CPU1_P3_TX_BUF_C_DP<9>")
		)
		(pad "2" smd rect
			(at -0.2667 0 270)
			(size 0.3048 0.381)
			(layers "B.Cu" "B.Mask" "B.Paste")
			(net "P5E_CPU1_P3_TX_BUF_DP<9>")
		)
	)
	(footprint ""
		(layer "B.Cu")
		(at 83.269074 -326.315832 -90)
		(property "Reference" "PC397_2"
			(at 0 0 90)
			(layer "B.SilkS")
			(hide yes)
			(effects
				(font
					(size 1.27 1.27)
				)
				(justify mirror)
			)
		)
		(property "Value" ""
			(at 0 0 90)
			(layer "B.Fab")
			(effects
				(font
					(size 1.27 1.27)
				)
				(justify mirror)
			)
		)
		(duplicate_pad_numbers_are_jumpers no)
		(fp_line
			(start -1.524 0.762)
			(end 1.524 0.762)
			(stroke
				(width 0.1524)
				(type default)
			)
			(layer "B.SilkS")
		)
		(fp_line
			(start 1.524 0.762)
			(end 1.524 -0.762)
			(stroke
				(width 0.1524)
				(type default)
			)
			(layer "B.SilkS")
		)
		(fp_line
			(start -1.524 -0.762)
			(end -1.524 0.762)
			(stroke
				(width 0.1524)
				(type default)
			)
			(layer "B.SilkS")
		)
		(fp_line
			(start 1.524 -0.762)
			(end -1.524 -0.762)
			(stroke
				(width 0.1524)
				(type default)
			)
			(layer "B.SilkS")
		)
		(fp_line
			(start -1.1049 0.724916)
			(end -1.1049 -0.724916)
			(stroke
				(width 0.1)
				(type default)
			)
			(layer "B.Fab")
		)
		(fp_line
			(start 1.1049 0.724916)
			(end -1.1049 0.724916)
			(stroke
				(width 0.1)
				(type default)
			)
			(layer "B.Fab")
		)
		(fp_line
			(start -1.1049 -0.724916)
			(end 1.1049 -0.724916)
			(stroke
				(width 0.1)
				(type default)
			)
			(layer "B.Fab")
		)
		(fp_line
			(start 1.1049 -0.724916)
			(end 1.1049 0.724916)
			(stroke
				(width 0.1)
				(type default)
			)
			(layer "B.Fab")
		)
		(pad "1" smd rect
			(at 0.889 0 270)
			(size 1.016 1.27)
			(layers "B.Cu" "B.Mask" "B.Paste")
			(net "PVDDCR_CPU1_P1")
		)
		(pad "2" smd rect
			(at -0.889 0 270)
			(size 1.016 1.27)
			(layers "B.Cu" "B.Mask" "B.Paste")
			(net "GND")
		)
	)
	(footprint ""
		(layer "B.Cu")
		(at 172.352208 -342.261952 -90)
		(property "Reference" "PC529_1"
			(at 0 0 90)
			(layer "B.SilkS")
			(hide yes)
			(effects
				(font
					(size 1.27 1.27)
				)
				(justify mirror)
			)
		)
		(property "Value" ""
			(at 0 0 90)
			(layer "B.Fab")
			(effects
				(font
					(size 1.27 1.27)
				)
				(justify mirror)
			)
		)
		(duplicate_pad_numbers_are_jumpers no)
		(fp_line
			(start -1.524 0.762)
			(end 1.524 0.762)
			(stroke
				(width 0.1524)
				(type default)
			)
			(layer "B.SilkS")
		)
		(fp_line
			(start 1.524 0.762)
			(end 1.524 -0.762)
			(stroke
				(width 0.1524)
				(type default)
			)
			(layer "B.SilkS")
		)
		(fp_line
			(start -1.524 -0.762)
			(end -1.524 0.762)
			(stroke
				(width 0.1524)
				(type default)
			)
			(layer "B.SilkS")
		)
		(fp_line
			(start 1.524 -0.762)
			(end -1.524 -0.762)
			(stroke
				(width 0.1524)
				(type default)
			)
			(layer "B.SilkS")
		)
		(fp_line
			(start -1.1049 0.724916)
			(end -1.1049 -0.724916)
			(stroke
				(width 0.1)
				(type default)
			)
			(layer "B.Fab")
		)
		(fp_line
			(start 1.1049 0.724916)
			(end -1.1049 0.724916)
			(stroke
				(width 0.1)
				(type default)
			)
			(layer "B.Fab")
		)
		(fp_line
			(start -1.1049 -0.724916)
			(end 1.1049 -0.724916)
			(stroke
				(width 0.1)
				(type default)
			)
			(layer "B.Fab")
		)
		(fp_line
			(start 1.1049 -0.724916)
			(end 1.1049 0.724916)
			(stroke
				(width 0.1)
				(type default)
			)
			(layer "B.Fab")
		)
		(pad "1" smd rect
			(at 0.889 0 270)
			(size 1.016 1.27)
			(layers "B.Cu" "B.Mask" "B.Paste")
			(net "PVDD11_S3_P1")
		)
		(pad "2" smd rect
			(at -0.889 0 270)
			(size 1.016 1.27)
			(layers "B.Cu" "B.Mask" "B.Paste")
			(net "GND")
		)
	)
	(footprint ""
		(layer "B.Cu")
		(at 238.252 -217.678 90)
		(property "Reference" "R1151"
			(at 0 0 90)
			(layer "B.SilkS")
			(hide yes)
			(effects
				(font
					(size 1.27 1.27)
				)
				(justify mirror)
			)
		)
		(property "Value" ""
			(at 0 0 90)
			(layer "B.Fab")
			(effects
				(font
					(size 1.27 1.27)
				)
				(justify mirror)
			)
		)
		(duplicate_pad_numbers_are_jumpers no)
		(fp_line
			(start 0.7874 -0.4064)
			(end -0.7874 -0.4064)
			(stroke
				(width 0.1524)
				(type default)
			)
			(layer "B.SilkS")
		)
		(fp_line
			(start -0.7874 -0.4064)
			(end -0.7874 0.4064)
			(stroke
				(width 0.1524)
				(type default)
			)
			(layer "B.SilkS")
		)
		(fp_line
			(start 0.7874 0.4064)
			(end 0.7874 -0.4064)
			(stroke
				(width 0.1524)
				(type default)
			)
			(layer "B.SilkS")
		)
		(fp_line
			(start -0.7874 0.4064)
			(end 0.7874 0.4064)
			(stroke
				(width 0.1524)
				(type default)
			)
			(layer "B.SilkS")
		)
		(fp_line
			(start 0.67945 -0.305054)
			(end 0.12065 -0.305054)
			(stroke
				(width 0.1)
				(type default)
			)
			(layer "B.Fab")
		)
		(fp_line
			(start 0.12065 -0.305054)
			(end 0.12065 -0.2794)
			(stroke
				(width 0.1)
				(type default)
			)
			(layer "B.Fab")
		)
		(fp_line
			(start -0.12065 -0.3048)
			(end -0.67945 -0.3048)
			(stroke
				(width 0.1)
				(type default)
			)
			(layer "B.Fab")
		)
		(fp_line
			(start -0.67945 -0.3048)
			(end -0.67945 0.3048)
			(stroke
				(width 0.1)
				(type default)
			)
			(layer "B.Fab")
		)
		(fp_line
			(start 0.12065 -0.2794)
			(end -0.12065 -0.2794)
			(stroke
				(width 0.1)
				(type default)
			)
			(layer "B.Fab")
		)
		(fp_line
			(start -0.12065 -0.2794)
			(end -0.12065 -0.3048)
			(stroke
				(width 0.1)
				(type default)
			)
			(layer "B.Fab")
		)
		(fp_line
			(start 0.12065 0.2794)
			(end 0.12065 0.3048)
			(stroke
				(width 0.1)
				(type default)
			)
			(layer "B.Fab")
		)
		(fp_line
			(start -0.120396 0.2794)
			(end 0.12065 0.2794)
			(stroke
				(width 0.1)
				(type default)
			)
			(layer "B.Fab")
		)
		(fp_line
			(start 0.67945 0.3048)
			(end 0.67945 -0.305054)
			(stroke
				(width 0.1)
				(type default)
			)
			(layer "B.Fab")
		)
		(fp_line
			(start 0.12065 0.3048)
			(end 0.67945 0.3048)
			(stroke
				(width 0.1)
				(type default)
			)
			(layer "B.Fab")
		)
		(fp_line
			(start -0.120396 0.3048)
			(end -0.120396 0.2794)
			(stroke
				(width 0.1)
				(type default)
			)
			(layer "B.Fab")
		)
		(fp_line
			(start -0.67945 0.3048)
			(end -0.120396 0.3048)
			(stroke
				(width 0.1)
				(type default)
			)
			(layer "B.Fab")
		)
		(pad "1" smd circle
			(at 0.40005 0 270)
			(size 0 0)
			(layers "B.Cu" "B.Mask" "B.Paste")
			(net "SMB_CPU0_CPU1_APML_BUF1_SCL_R1")
		)
		(pad "2" smd circle
			(at -0.40005 0 270)
			(size 0 0)
			(layers "B.Cu" "B.Mask" "B.Paste")
			(net "SMB_CPU0_CPU1_APML_BUF1_SCL_R2")
		)
	)
	(footprint ""
		(layer "B.Cu")
		(at 133.8453 -390.560052 90)
		(property "Reference" "C486"
			(at 0 0 90)
			(layer "B.SilkS")
			(hide yes)
			(effects
				(font
					(size 1.27 1.27)
				)
				(justify mirror)
			)
		)
		(property "Value" ""
			(at 0 0 90)
			(layer "B.Fab")
			(effects
				(font
					(size 1.27 1.27)
				)
				(justify mirror)
			)
		)
		(duplicate_pad_numbers_are_jumpers no)
		(fp_line
			(start 0.7874 -0.4064)
			(end -0.7874 -0.4064)
			(stroke
				(width 0.1524)
				(type default)
			)
			(layer "B.SilkS")
		)
		(fp_line
			(start -0.7874 -0.4064)
			(end -0.7874 0.4064)
			(stroke
				(width 0.1524)
				(type default)
			)
			(layer "B.SilkS")
		)
		(fp_line
			(start 0.7874 0.4064)
			(end 0.7874 -0.4064)
			(stroke
				(width 0.1524)
				(type default)
			)
			(layer "B.SilkS")
		)
		(fp_line
			(start -0.7874 0.4064)
			(end 0.7874 0.4064)
			(stroke
				(width 0.1524)
				(type default)
			)
			(layer "B.SilkS")
		)
		(fp_line
			(start 0.67945 -0.305054)
			(end 0.12065 -0.305054)
			(stroke
				(width 0.1)
				(type default)
			)
			(layer "B.Fab")
		)
		(fp_line
			(start 0.12065 -0.305054)
			(end 0.12065 -0.2794)
			(stroke
				(width 0.1)
				(type default)
			)
			(layer "B.Fab")
		)
		(fp_line
			(start -0.12065 -0.3048)
			(end -0.67945 -0.3048)
			(stroke
				(width 0.1)
				(type default)
			)
			(layer "B.Fab")
		)
		(fp_line
			(start -0.67945 -0.3048)
			(end -0.67945 0.3048)
			(stroke
				(width 0.1)
				(type default)
			)
			(layer "B.Fab")
		)
		(fp_line
			(start 0.12065 -0.2794)
			(end -0.12065 -0.2794)
			(stroke
				(width 0.1)
				(type default)
			)
			(layer "B.Fab")
		)
		(fp_line
			(start -0.12065 -0.2794)
			(end -0.12065 -0.3048)
			(stroke
				(width 0.1)
				(type default)
			)
			(layer "B.Fab")
		)
		(fp_line
			(start 0.12065 0.2794)
			(end 0.12065 0.3048)
			(stroke
				(width 0.1)
				(type default)
			)
			(layer "B.Fab")
		)
		(fp_line
			(start -0.120396 0.2794)
			(end 0.12065 0.2794)
			(stroke
				(width 0.1)
				(type default)
			)
			(layer "B.Fab")
		)
		(fp_line
			(start 0.67945 0.3048)
			(end 0.67945 -0.305054)
			(stroke
				(width 0.1)
				(type default)
			)
			(layer "B.Fab")
		)
		(fp_line
			(start 0.12065 0.3048)
			(end 0.67945 0.3048)
			(stroke
				(width 0.1)
				(type default)
			)
			(layer "B.Fab")
		)
		(fp_line
			(start -0.120396 0.3048)
			(end -0.120396 0.2794)
			(stroke
				(width 0.1)
				(type default)
			)
			(layer "B.Fab")
		)
		(fp_line
			(start -0.67945 0.3048)
			(end -0.120396 0.3048)
			(stroke
				(width 0.1)
				(type default)
			)
			(layer "B.Fab")
		)
		(pad "1" smd circle
			(at 0.40005 0 270)
			(size 0 0)
			(layers "B.Cu" "B.Mask" "B.Paste")
			(net "P0V9_CPU1_RT3_2A")
		)
		(pad "2" smd circle
			(at -0.40005 0 270)
			(size 0 0)
			(layers "B.Cu" "B.Mask" "B.Paste")
			(net "GND")
		)
	)
	(footprint ""
		(layer "B.Cu")
		(at 410.160216 -177.225452 90)
		(property "Reference" "PC600_2"
			(at 0 0 90)
			(layer "B.SilkS")
			(hide yes)
			(effects
				(font
					(size 1.27 1.27)
				)
				(justify mirror)
			)
		)
		(property "Value" ""
			(at 0 0 90)
			(layer "B.Fab")
			(effects
				(font
					(size 1.27 1.27)
				)
				(justify mirror)
			)
		)
		(duplicate_pad_numbers_are_jumpers no)
		(fp_line
			(start 1.524 -0.762)
			(end -1.524 -0.762)
			(stroke
				(width 0.1524)
				(type default)
			)
			(layer "B.SilkS")
		)
		(fp_line
			(start -1.524 -0.762)
			(end -1.524 0.762)
			(stroke
				(width 0.1524)
				(type default)
			)
			(layer "B.SilkS")
		)
		(fp_line
			(start 1.524 0.762)
			(end 1.524 -0.762)
			(stroke
				(width 0.1524)
				(type default)
			)
			(layer "B.SilkS")
		)
		(fp_line
			(start -1.524 0.762)
			(end 1.524 0.762)
			(stroke
				(width 0.1524)
				(type default)
			)
			(layer "B.SilkS")
		)
		(fp_line
			(start 1.1049 -0.724916)
			(end 1.1049 0.724916)
			(stroke
				(width 0.1)
				(type default)
			)
			(layer "B.Fab")
		)
		(fp_line
			(start -1.1049 -0.724916)
			(end 1.1049 -0.724916)
			(stroke
				(width 0.1)
				(type default)
			)
			(layer "B.Fab")
		)
		(fp_line
			(start 1.1049 0.724916)
			(end -1.1049 0.724916)
			(stroke
				(width 0.1)
				(type default)
			)
			(layer "B.Fab")
		)
		(fp_line
			(start -1.1049 0.724916)
			(end -1.1049 -0.724916)
			(stroke
				(width 0.1)
				(type default)
			)
			(layer "B.Fab")
		)
		(pad "1" smd rect
			(at 0.889 0 90)
			(size 1.016 1.27)
			(layers "B.Cu" "B.Mask" "B.Paste")
			(net "PVDDCR_SOC_P0")
		)
		(pad "2" smd rect
			(at -0.889 0 90)
			(size 1.016 1.27)
			(layers "B.Cu" "B.Mask" "B.Paste")
			(net "GND")
		)
	)
	(footprint ""
		(layer "B.Cu")
		(at 401.337018 -168.721532 -90)
		(property "Reference" "PC595_2"
			(at 0 0 90)
			(layer "B.SilkS")
			(hide yes)
			(effects
				(font
					(size 1.27 1.27)
				)
				(justify mirror)
			)
		)
		(property "Value" ""
			(at 0 0 90)
			(layer "B.Fab")
			(effects
				(font
					(size 1.27 1.27)
				)
				(justify mirror)
			)
		)
		(duplicate_pad_numbers_are_jumpers no)
		(fp_line
			(start -1.524 0.762)
			(end 1.524 0.762)
			(stroke
				(width 0.1524)
				(type default)
			)
			(layer "B.SilkS")
		)
		(fp_line
			(start 1.524 0.762)
			(end 1.524 -0.762)
			(stroke
				(width 0.1524)
				(type default)
			)
			(layer "B.SilkS")
		)
		(fp_line
			(start -1.524 -0.762)
			(end -1.524 0.762)
			(stroke
				(width 0.1524)
				(type default)
			)
			(layer "B.SilkS")
		)
		(fp_line
			(start 1.524 -0.762)
			(end -1.524 -0.762)
			(stroke
				(width 0.1524)
				(type default)
			)
			(layer "B.SilkS")
		)
		(fp_line
			(start -1.1049 0.724916)
			(end -1.1049 -0.724916)
			(stroke
				(width 0.1)
				(type default)
			)
			(layer "B.Fab")
		)
		(fp_line
			(start 1.1049 0.724916)
			(end -1.1049 0.724916)
			(stroke
				(width 0.1)
				(type default)
			)
			(layer "B.Fab")
		)
		(fp_line
			(start -1.1049 -0.724916)
			(end 1.1049 -0.724916)
			(stroke
				(width 0.1)
				(type default)
			)
			(layer "B.Fab")
		)
		(fp_line
			(start 1.1049 -0.724916)
			(end 1.1049 0.724916)
			(stroke
				(width 0.1)
				(type default)
			)
			(layer "B.Fab")
		)
		(pad "1" smd rect
			(at 0.889 0 270)
			(size 1.016 1.27)
			(layers "B.Cu" "B.Mask" "B.Paste")
			(net "SW_P12V_AUX_PVDDCR_SOC_P0_FLT")
		)
		(pad "2" smd rect
			(at -0.889 0 270)
			(size 1.016 1.27)
			(layers "B.Cu" "B.Mask" "B.Paste")
			(net "GND")
		)
	)
	(footprint ""
		(layer "B.Cu")
		(at 10.066782 -406.119584 180)
		(property "Reference" "PR6809"
			(at 0 0 0)
			(layer "B.SilkS")
			(hide yes)
			(effects
				(font
					(size 1.27 1.27)
				)
				(justify mirror)
			)
		)
		(property "Value" ""
			(at 0 0 0)
			(layer "B.Fab")
			(effects
				(font
					(size 1.27 1.27)
				)
				(justify mirror)
			)
		)
		(duplicate_pad_numbers_are_jumpers no)
		(fp_line
			(start 0.7874 0.4064)
			(end 0.7874 -0.4064)
			(stroke
				(width 0.1524)
				(type default)
			)
			(layer "B.SilkS")
		)
		(fp_line
			(start 0.7874 -0.4064)
			(end -0.7874 -0.4064)
			(stroke
				(width 0.1524)
				(type default)
			)
			(layer "B.SilkS")
		)
		(fp_line
			(start -0.7874 0.4064)
			(end 0.7874 0.4064)
			(stroke
				(width 0.1524)
				(type default)
			)
			(layer "B.SilkS")
		)
		(fp_line
			(start -0.7874 -0.4064)
			(end -0.7874 0.4064)
			(stroke
				(width 0.1524)
				(type default)
			)
			(layer "B.SilkS")
		)
		(fp_line
			(start 0.67945 0.3048)
			(end 0.67945 -0.305054)
			(stroke
				(width 0.1)
				(type default)
			)
			(layer "B.Fab")
		)
		(fp_line
			(start 0.67945 -0.305054)
			(end 0.12065 -0.305054)
			(stroke
				(width 0.1)
				(type default)
			)
			(layer "B.Fab")
		)
		(fp_line
			(start 0.12065 0.3048)
			(end 0.67945 0.3048)
			(stroke
				(width 0.1)
				(type default)
			)
			(layer "B.Fab")
		)
		(fp_line
			(start 0.12065 0.2794)
			(end 0.12065 0.3048)
			(stroke
				(width 0.1)
				(type default)
			)
			(layer "B.Fab")
		)
		(fp_line
			(start 0.12065 -0.2794)
			(end -0.12065 -0.2794)
			(stroke
				(width 0.1)
				(type default)
			)
			(layer "B.Fab")
		)
		(fp_line
			(start 0.12065 -0.305054)
			(end 0.12065 -0.2794)
			(stroke
				(width 0.1)
				(type default)
			)
			(layer "B.Fab")
		)
		(fp_line
			(start -0.120396 0.3048)
			(end -0.120396 0.2794)
			(stroke
				(width 0.1)
				(type default)
			)
			(layer "B.Fab")
		)
		(fp_line
			(start -0.120396 0.2794)
			(end 0.12065 0.2794)
			(stroke
				(width 0.1)
				(type default)
			)
			(layer "B.Fab")
		)
		(fp_line
			(start -0.12065 -0.2794)
			(end -0.12065 -0.3048)
			(stroke
				(width 0.1)
				(type default)
			)
			(layer "B.Fab")
		)
		(fp_line
			(start -0.12065 -0.3048)
			(end -0.67945 -0.3048)
			(stroke
				(width 0.1)
				(type default)
			)
			(layer "B.Fab")
		)
		(fp_line
			(start -0.67945 0.3048)
			(end -0.120396 0.3048)
			(stroke
				(width 0.1)
				(type default)
			)
			(layer "B.Fab")
		)
		(fp_line
			(start -0.67945 -0.3048)
			(end -0.67945 0.3048)
			(stroke
				(width 0.1)
				(type default)
			)
			(layer "B.Fab")
		)
		(pad "1" smd circle
			(at 0.40005 0)
			(size 0 0)
			(layers "B.Cu" "B.Mask" "B.Paste")
			(net "P12V_AUX")
		)
		(pad "2" smd circle
			(at -0.40005 0)
			(size 0 0)
			(layers "B.Cu" "B.Mask" "B.Paste")
			(net "P0V9_RETIMER_CPU1_VINSEN")
		)
	)
	(footprint ""
		(layer "B.Cu")
		(at 234.844844 -329.173078 180)
		(property "Reference" "R1225"
			(at 0 0 0)
			(layer "B.SilkS")
			(hide yes)
			(effects
				(font
					(size 1.27 1.27)
				)
				(justify mirror)
			)
		)
		(property "Value" ""
			(at 0 0 0)
			(layer "B.Fab")
			(effects
				(font
					(size 1.27 1.27)
				)
				(justify mirror)
			)
		)
		(duplicate_pad_numbers_are_jumpers no)
		(fp_line
			(start 0.7874 0.4064)
			(end 0.7874 -0.4064)
			(stroke
				(width 0.1524)
				(type default)
			)
			(layer "B.SilkS")
		)
		(fp_line
			(start 0.7874 -0.4064)
			(end -0.7874 -0.4064)
			(stroke
				(width 0.1524)
				(type default)
			)
			(layer "B.SilkS")
		)
		(fp_line
			(start -0.7874 0.4064)
			(end 0.7874 0.4064)
			(stroke
				(width 0.1524)
				(type default)
			)
			(layer "B.SilkS")
		)
		(fp_line
			(start -0.7874 -0.4064)
			(end -0.7874 0.4064)
			(stroke
				(width 0.1524)
				(type default)
			)
			(layer "B.SilkS")
		)
		(fp_line
			(start 0.67945 0.3048)
			(end 0.67945 -0.305054)
			(stroke
				(width 0.1)
				(type default)
			)
			(layer "B.Fab")
		)
		(fp_line
			(start 0.67945 -0.305054)
			(end 0.12065 -0.305054)
			(stroke
				(width 0.1)
				(type default)
			)
			(layer "B.Fab")
		)
		(fp_line
			(start 0.12065 0.3048)
			(end 0.67945 0.3048)
			(stroke
				(width 0.1)
				(type default)
			)
			(layer "B.Fab")
		)
		(fp_line
			(start 0.12065 0.2794)
			(end 0.12065 0.3048)
			(stroke
				(width 0.1)
				(type default)
			)
			(layer "B.Fab")
		)
		(fp_line
			(start 0.12065 -0.2794)
			(end -0.12065 -0.2794)
			(stroke
				(width 0.1)
				(type default)
			)
			(layer "B.Fab")
		)
		(fp_line
			(start 0.12065 -0.305054)
			(end 0.12065 -0.2794)
			(stroke
				(width 0.1)
				(type default)
			)
			(layer "B.Fab")
		)
		(fp_line
			(start -0.120396 0.3048)
			(end -0.120396 0.2794)
			(stroke
				(width 0.1)
				(type default)
			)
			(layer "B.Fab")
		)
		(fp_line
			(start -0.120396 0.2794)
			(end 0.12065 0.2794)
			(stroke
				(width 0.1)
				(type default)
			)
			(layer "B.Fab")
		)
		(fp_line
			(start -0.12065 -0.2794)
			(end -0.12065 -0.3048)
			(stroke
				(width 0.1)
				(type default)
			)
			(layer "B.Fab")
		)
		(fp_line
			(start -0.12065 -0.3048)
			(end -0.67945 -0.3048)
			(stroke
				(width 0.1)
				(type default)
			)
			(layer "B.Fab")
		)
		(fp_line
			(start -0.67945 0.3048)
			(end -0.120396 0.3048)
			(stroke
				(width 0.1)
				(type default)
			)
			(layer "B.Fab")
		)
		(fp_line
			(start -0.67945 -0.3048)
			(end -0.67945 0.3048)
			(stroke
				(width 0.1)
				(type default)
			)
			(layer "B.Fab")
		)
		(pad "1" smd circle
			(at 0.40005 0)
			(size 0 0)
			(layers "B.Cu" "B.Mask" "B.Paste")
			(net "PVDD18_S5_P1_ADC")
		)
		(pad "2" smd circle
			(at -0.40005 0)
			(size 0 0)
			(layers "B.Cu" "B.Mask" "B.Paste")
			(net "GND")
		)
	)
	(footprint ""
		(layer "B.Cu")
		(at 61.918596 -388.011162 -90)
		(property "Reference" "C283"
			(at 0 0 90)
			(layer "B.SilkS")
			(hide yes)
			(effects
				(font
					(size 1.27 1.27)
				)
				(justify mirror)
			)
		)
		(property "Value" ""
			(at 0 0 90)
			(layer "B.Fab")
			(effects
				(font
					(size 1.27 1.27)
				)
				(justify mirror)
			)
		)
		(duplicate_pad_numbers_are_jumpers no)
		(fp_line
			(start -0.299974 0.150114)
			(end 0.299974 0.150114)
			(stroke
				(width 0.1)
				(type default)
			)
			(layer "B.Fab")
		)
		(fp_line
			(start 0.299974 0.150114)
			(end 0.299974 -0.150114)
			(stroke
				(width 0.1)
				(type default)
			)
			(layer "B.Fab")
		)
		(fp_line
			(start -0.299974 -0.150114)
			(end -0.299974 0.150114)
			(stroke
				(width 0.1)
				(type default)
			)
			(layer "B.Fab")
		)
		(fp_line
			(start 0.299974 -0.150114)
			(end -0.299974 -0.150114)
			(stroke
				(width 0.1)
				(type default)
			)
			(layer "B.Fab")
		)
		(pad "1" smd rect
			(at 0.2667 0 90)
			(size 0.3048 0.381)
			(layers "B.Cu" "B.Mask" "B.Paste")
			(net "P0V9_CPU1_RT0_2A")
		)
		(pad "2" smd rect
			(at -0.2667 0 90)
			(size 0.3048 0.381)
			(layers "B.Cu" "B.Mask" "B.Paste")
			(net "GND")
		)
	)
	(footprint ""
		(layer "B.Cu")
		(at 159.931608 -415.531046)
		(property "Reference" "C1068"
			(at 0 0 0)
			(layer "B.SilkS")
			(hide yes)
			(effects
				(font
					(size 1.27 1.27)
				)
				(justify mirror)
			)
		)
		(property "Value" ""
			(at 0 0 0)
			(layer "B.Fab")
			(effects
				(font
					(size 1.27 1.27)
				)
				(justify mirror)
			)
		)
		(duplicate_pad_numbers_are_jumpers no)
		(fp_line
			(start -0.299974 -0.150114)
			(end -0.299974 0.150114)
			(stroke
				(width 0.1)
				(type default)
			)
			(layer "B.Fab")
		)
		(fp_line
			(start -0.299974 0.150114)
			(end 0.299974 0.150114)
			(stroke
				(width 0.1)
				(type default)
			)
			(layer "B.Fab")
		)
		(fp_line
			(start 0.299974 -0.150114)
			(end -0.299974 -0.150114)
			(stroke
				(width 0.1)
				(type default)
			)
			(layer "B.Fab")
		)
		(fp_line
			(start 0.299974 0.150114)
			(end 0.299974 -0.150114)
			(stroke
				(width 0.1)
				(type default)
			)
			(layer "B.Fab")
		)
		(pad "1" smd rect
			(at 0.2667 0 180)
			(size 0.3048 0.381)
			(layers "B.Cu" "B.Mask" "B.Paste")
			(net "P3V3_AUX")
		)
		(pad "2" smd rect
			(at -0.2667 0 180)
			(size 0.3048 0.381)
			(layers "B.Cu" "B.Mask" "B.Paste")
			(net "GND")
		)
	)
	(footprint ""
		(layer "B.Cu")
		(at 372.6815 -261.935976)
		(property "Reference" "C2570"
			(at 0 0 0)
			(layer "B.SilkS")
			(hide yes)
			(effects
				(font
					(size 1.27 1.27)
				)
				(justify mirror)
			)
		)
		(property "Value" ""
			(at 0 0 0)
			(layer "B.Fab")
			(effects
				(font
					(size 1.27 1.27)
				)
				(justify mirror)
			)
		)
		(duplicate_pad_numbers_are_jumpers no)
		(fp_line
			(start -0.7874 -0.4064)
			(end -0.7874 0.4064)
			(stroke
				(width 0.1524)
				(type default)
			)
			(layer "B.SilkS")
		)
		(fp_line
			(start -0.7874 0.4064)
			(end 0.7874 0.4064)
			(stroke
				(width 0.1524)
				(type default)
			)
			(layer "B.SilkS")
		)
		(fp_line
			(start 0.7874 -0.4064)
			(end -0.7874 -0.4064)
			(stroke
				(width 0.1524)
				(type default)
			)
			(layer "B.SilkS")
		)
		(fp_line
			(start 0.7874 0.4064)
			(end 0.7874 -0.4064)
			(stroke
				(width 0.1524)
				(type default)
			)
			(layer "B.SilkS")
		)
		(fp_line
			(start -0.67945 -0.3048)
			(end -0.67945 0.3048)
			(stroke
				(width 0.1)
				(type default)
			)
			(layer "B.Fab")
		)
		(fp_line
			(start -0.67945 0.3048)
			(end -0.120396 0.3048)
			(stroke
				(width 0.1)
				(type default)
			)
			(layer "B.Fab")
		)
		(fp_line
			(start -0.12065 -0.3048)
			(end -0.67945 -0.3048)
			(stroke
				(width 0.1)
				(type default)
			)
			(layer "B.Fab")
		)
		(fp_line
			(start -0.12065 -0.2794)
			(end -0.12065 -0.3048)
			(stroke
				(width 0.1)
				(type default)
			)
			(layer "B.Fab")
		)
		(fp_line
			(start -0.120396 0.2794)
			(end 0.12065 0.2794)
			(stroke
				(width 0.1)
				(type default)
			)
			(layer "B.Fab")
		)
		(fp_line
			(start -0.120396 0.3048)
			(end -0.120396 0.2794)
			(stroke
				(width 0.1)
				(type default)
			)
			(layer "B.Fab")
		)
		(fp_line
			(start 0.12065 -0.305054)
			(end 0.12065 -0.2794)
			(stroke
				(width 0.1)
				(type default)
			)
			(layer "B.Fab")
		)
		(fp_line
			(start 0.12065 -0.2794)
			(end -0.12065 -0.2794)
			(stroke
				(width 0.1)
				(type default)
			)
			(layer "B.Fab")
		)
		(fp_line
			(start 0.12065 0.2794)
			(end 0.12065 0.3048)
			(stroke
				(width 0.1)
				(type default)
			)
			(layer "B.Fab")
		)
		(fp_line
			(start 0.12065 0.3048)
			(end 0.67945 0.3048)
			(stroke
				(width 0.1)
				(type default)
			)
			(layer "B.Fab")
		)
		(fp_line
			(start 0.67945 -0.305054)
			(end 0.12065 -0.305054)
			(stroke
				(width 0.1)
				(type default)
			)
			(layer "B.Fab")
		)
		(fp_line
			(start 0.67945 0.3048)
			(end 0.67945 -0.305054)
			(stroke
				(width 0.1)
				(type default)
			)
			(layer "B.Fab")
		)
		(pad "1" smd circle
			(at 0.40005 0 180)
			(size 0 0)
			(layers "B.Cu" "B.Mask" "B.Paste")
			(net "PVDDCR_SOC_P0")
		)
		(pad "2" smd circle
			(at -0.40005 0 180)
			(size 0 0)
			(layers "B.Cu" "B.Mask" "B.Paste")
			(net "GND")
		)
	)
	(footprint ""
		(layer "B.Cu")
		(at 229.87 -232.156 90)
		(property "Reference" "R5004"
			(at 0 0 90)
			(layer "B.SilkS")
			(hide yes)
			(effects
				(font
					(size 1.27 1.27)
				)
				(justify mirror)
			)
		)
		(property "Value" ""
			(at 0 0 90)
			(layer "B.Fab")
			(effects
				(font
					(size 1.27 1.27)
				)
				(justify mirror)
			)
		)
		(duplicate_pad_numbers_are_jumpers no)
		(fp_line
			(start 0.7874 -0.4064)
			(end -0.7874 -0.4064)
			(stroke
				(width 0.1524)
				(type default)
			)
			(layer "B.SilkS")
		)
		(fp_line
			(start -0.7874 -0.4064)
			(end -0.7874 0.4064)
			(stroke
				(width 0.1524)
				(type default)
			)
			(layer "B.SilkS")
		)
		(fp_line
			(start 0.7874 0.4064)
			(end 0.7874 -0.4064)
			(stroke
				(width 0.1524)
				(type default)
			)
			(layer "B.SilkS")
		)
		(fp_line
			(start -0.7874 0.4064)
			(end 0.7874 0.4064)
			(stroke
				(width 0.1524)
				(type default)
			)
			(layer "B.SilkS")
		)
		(fp_line
			(start 0.67945 -0.305054)
			(end 0.12065 -0.305054)
			(stroke
				(width 0.1)
				(type default)
			)
			(layer "B.Fab")
		)
		(fp_line
			(start 0.12065 -0.305054)
			(end 0.12065 -0.2794)
			(stroke
				(width 0.1)
				(type default)
			)
			(layer "B.Fab")
		)
		(fp_line
			(start -0.12065 -0.3048)
			(end -0.67945 -0.3048)
			(stroke
				(width 0.1)
				(type default)
			)
			(layer "B.Fab")
		)
		(fp_line
			(start -0.67945 -0.3048)
			(end -0.67945 0.3048)
			(stroke
				(width 0.1)
				(type default)
			)
			(layer "B.Fab")
		)
		(fp_line
			(start 0.12065 -0.2794)
			(end -0.12065 -0.2794)
			(stroke
				(width 0.1)
				(type default)
			)
			(layer "B.Fab")
		)
		(fp_line
			(start -0.12065 -0.2794)
			(end -0.12065 -0.3048)
			(stroke
				(width 0.1)
				(type default)
			)
			(layer "B.Fab")
		)
		(fp_line
			(start 0.12065 0.2794)
			(end 0.12065 0.3048)
			(stroke
				(width 0.1)
				(type default)
			)
			(layer "B.Fab")
		)
		(fp_line
			(start -0.120396 0.2794)
			(end 0.12065 0.2794)
			(stroke
				(width 0.1)
				(type default)
			)
			(layer "B.Fab")
		)
		(fp_line
			(start 0.67945 0.3048)
			(end 0.67945 -0.305054)
			(stroke
				(width 0.1)
				(type default)
			)
			(layer "B.Fab")
		)
		(fp_line
			(start 0.12065 0.3048)
			(end 0.67945 0.3048)
			(stroke
				(width 0.1)
				(type default)
			)
			(layer "B.Fab")
		)
		(fp_line
			(start -0.120396 0.3048)
			(end -0.120396 0.2794)
			(stroke
				(width 0.1)
				(type default)
			)
			(layer "B.Fab")
		)
		(fp_line
			(start -0.67945 0.3048)
			(end -0.120396 0.3048)
			(stroke
				(width 0.1)
				(type default)
			)
			(layer "B.Fab")
		)
		(pad "1" smd circle
			(at 0.40005 0 270)
			(size 0 0)
			(layers "B.Cu" "B.Mask" "B.Paste")
			(net "SMB_APML_CPU1_R_SDA")
		)
		(pad "2" smd circle
			(at -0.40005 0 270)
			(size 0 0)
			(layers "B.Cu" "B.Mask" "B.Paste")
			(net "GND")
		)
	)
	(footprint ""
		(layer "B.Cu")
		(at 217.17 -331.724 180)
		(property "Reference" "R6771"
			(at 0 0 0)
			(layer "B.SilkS")
			(hide yes)
			(effects
				(font
					(size 1.27 1.27)
				)
				(justify mirror)
			)
		)
		(property "Value" ""
			(at 0 0 0)
			(layer "B.Fab")
			(effects
				(font
					(size 1.27 1.27)
				)
				(justify mirror)
			)
		)
		(duplicate_pad_numbers_are_jumpers no)
		(fp_line
			(start 0.32512 0.175006)
			(end 0.32512 -0.175006)
			(stroke
				(width 0.1)
				(type default)
			)
			(layer "B.Fab")
		)
		(fp_line
			(start 0.32512 -0.175006)
			(end -0.32512 -0.175006)
			(stroke
				(width 0.1)
				(type default)
			)
			(layer "B.Fab")
		)
		(fp_line
			(start -0.32512 0.175006)
			(end 0.32512 0.175006)
			(stroke
				(width 0.1)
				(type default)
			)
			(layer "B.Fab")
		)
		(fp_line
			(start -0.32512 -0.175006)
			(end -0.32512 0.175006)
			(stroke
				(width 0.1)
				(type default)
			)
			(layer "B.Fab")
		)
		(pad "1" smd rect
			(at 0.2667 0)
			(size 0.3048 0.381)
			(layers "B.Cu" "B.Mask" "B.Paste")
			(net "P1V8_AUX")
		)
		(pad "2" smd rect
			(at -0.2667 0 180)
			(size 0.3048 0.381)
			(layers "B.Cu" "B.Mask" "B.Paste")
			(net "RT_SMB_MUX_ADDR1")
		)
	)
	(footprint ""
		(layer "B.Cu")
		(at 241.140488 -330.581 180)
		(property "Reference" "R844"
			(at 0 0 0)
			(layer "B.SilkS")
			(hide yes)
			(effects
				(font
					(size 1.27 1.27)
				)
				(justify mirror)
			)
		)
		(property "Value" ""
			(at 0 0 0)
			(layer "B.Fab")
			(effects
				(font
					(size 1.27 1.27)
				)
				(justify mirror)
			)
		)
		(duplicate_pad_numbers_are_jumpers no)
		(fp_line
			(start 0.32512 0.175006)
			(end 0.32512 -0.175006)
			(stroke
				(width 0.1)
				(type default)
			)
			(layer "B.Fab")
		)
		(fp_line
			(start 0.32512 -0.175006)
			(end -0.32512 -0.175006)
			(stroke
				(width 0.1)
				(type default)
			)
			(layer "B.Fab")
		)
		(fp_line
			(start -0.32512 0.175006)
			(end 0.32512 0.175006)
			(stroke
				(width 0.1)
				(type default)
			)
			(layer "B.Fab")
		)
		(fp_line
			(start -0.32512 -0.175006)
			(end -0.32512 0.175006)
			(stroke
				(width 0.1)
				(type default)
			)
			(layer "B.Fab")
		)
		(pad "1" smd rect
			(at 0.2667 0)
			(size 0.3048 0.381)
			(layers "B.Cu" "B.Mask" "B.Paste")
			(net "P1V8_AUX")
		)
		(pad "2" smd rect
			(at -0.2667 0 180)
			(size 0.3048 0.381)
			(layers "B.Cu" "B.Mask" "B.Paste")
			(net "RT_ROM_SMB_MUX_ADDR0")
		)
	)
	(footprint ""
		(layer "B.Cu")
		(at 352.706178 -395.148562 90)
		(property "Reference" "C643"
			(at 0 0 90)
			(layer "B.SilkS")
			(hide yes)
			(effects
				(font
					(size 1.27 1.27)
				)
				(justify mirror)
			)
		)
		(property "Value" ""
			(at 0 0 90)
			(layer "B.Fab")
			(effects
				(font
					(size 1.27 1.27)
				)
				(justify mirror)
			)
		)
		(duplicate_pad_numbers_are_jumpers no)
		(fp_line
			(start 0.299974 -0.150114)
			(end -0.299974 -0.150114)
			(stroke
				(width 0.1)
				(type default)
			)
			(layer "B.Fab")
		)
		(fp_line
			(start -0.299974 -0.150114)
			(end -0.299974 0.150114)
			(stroke
				(width 0.1)
				(type default)
			)
			(layer "B.Fab")
		)
		(fp_line
			(start 0.299974 0.150114)
			(end 0.299974 -0.150114)
			(stroke
				(width 0.1)
				(type default)
			)
			(layer "B.Fab")
		)
		(fp_line
			(start -0.299974 0.150114)
			(end 0.299974 0.150114)
			(stroke
				(width 0.1)
				(type default)
			)
			(layer "B.Fab")
		)
		(pad "1" smd rect
			(at 0.2667 0 270)
			(size 0.3048 0.381)
			(layers "B.Cu" "B.Mask" "B.Paste")
			(net "P0V9_CPU0_RT1_2A")
		)
		(pad "2" smd rect
			(at -0.2667 0 270)
			(size 0.3048 0.381)
			(layers "B.Cu" "B.Mask" "B.Paste")
			(net "GND")
		)
	)
	(footprint ""
		(layer "B.Cu")
		(at 385.567682 -416.899344 90)
		(property "Reference" "C6605"
			(at 0 0 90)
			(layer "B.SilkS")
			(hide yes)
			(effects
				(font
					(size 1.27 1.27)
				)
				(justify mirror)
			)
		)
		(property "Value" ""
			(at 0 0 90)
			(layer "B.Fab")
			(effects
				(font
					(size 1.27 1.27)
				)
				(justify mirror)
			)
		)
		(duplicate_pad_numbers_are_jumpers no)
		(fp_line
			(start 0.299974 -0.150114)
			(end -0.299974 -0.150114)
			(stroke
				(width 0.1)
				(type default)
			)
			(layer "B.Fab")
		)
		(fp_line
			(start -0.299974 -0.150114)
			(end -0.299974 0.150114)
			(stroke
				(width 0.1)
				(type default)
			)
			(layer "B.Fab")
		)
		(fp_line
			(start 0.299974 0.150114)
			(end 0.299974 -0.150114)
			(stroke
				(width 0.1)
				(type default)
			)
			(layer "B.Fab")
		)
		(fp_line
			(start -0.299974 0.150114)
			(end 0.299974 0.150114)
			(stroke
				(width 0.1)
				(type default)
			)
			(layer "B.Fab")
		)
		(pad "1" smd rect
			(at 0.2667 0 270)
			(size 0.3048 0.381)
			(layers "B.Cu" "B.Mask" "B.Paste")
			(net "P5E_CPU0_P3_TX_BUF_C_DP<4>")
		)
		(pad "2" smd rect
			(at -0.2667 0 270)
			(size 0.3048 0.381)
			(layers "B.Cu" "B.Mask" "B.Paste")
			(net "P5E_CPU0_P3_TX_BUF_DP<4>")
		)
	)
	(footprint ""
		(layer "B.Cu")
		(at 450.84365 -194.88531 180)
		(property "Reference" "R769"
			(at 0 0 0)
			(layer "B.SilkS")
			(hide yes)
			(effects
				(font
					(size 1.27 1.27)
				)
				(justify mirror)
			)
		)
		(property "Value" ""
			(at 0 0 0)
			(layer "B.Fab")
			(effects
				(font
					(size 1.27 1.27)
				)
				(justify mirror)
			)
		)
		(duplicate_pad_numbers_are_jumpers no)
		(fp_line
			(start 0.7874 0.4064)
			(end 0.7874 -0.4064)
			(stroke
				(width 0.1524)
				(type default)
			)
			(layer "B.SilkS")
		)
		(fp_line
			(start 0.7874 -0.4064)
			(end -0.7874 -0.4064)
			(stroke
				(width 0.1524)
				(type default)
			)
			(layer "B.SilkS")
		)
		(fp_line
			(start -0.7874 0.4064)
			(end 0.7874 0.4064)
			(stroke
				(width 0.1524)
				(type default)
			)
			(layer "B.SilkS")
		)
		(fp_line
			(start -0.7874 -0.4064)
			(end -0.7874 0.4064)
			(stroke
				(width 0.1524)
				(type default)
			)
			(layer "B.SilkS")
		)
		(fp_line
			(start 0.67945 0.3048)
			(end 0.67945 -0.305054)
			(stroke
				(width 0.1)
				(type default)
			)
			(layer "B.Fab")
		)
		(fp_line
			(start 0.67945 -0.305054)
			(end 0.12065 -0.305054)
			(stroke
				(width 0.1)
				(type default)
			)
			(layer "B.Fab")
		)
		(fp_line
			(start 0.12065 0.3048)
			(end 0.67945 0.3048)
			(stroke
				(width 0.1)
				(type default)
			)
			(layer "B.Fab")
		)
		(fp_line
			(start 0.12065 0.2794)
			(end 0.12065 0.3048)
			(stroke
				(width 0.1)
				(type default)
			)
			(layer "B.Fab")
		)
		(fp_line
			(start 0.12065 -0.2794)
			(end -0.12065 -0.2794)
			(stroke
				(width 0.1)
				(type default)
			)
			(layer "B.Fab")
		)
		(fp_line
			(start 0.12065 -0.305054)
			(end 0.12065 -0.2794)
			(stroke
				(width 0.1)
				(type default)
			)
			(layer "B.Fab")
		)
		(fp_line
			(start -0.120396 0.3048)
			(end -0.120396 0.2794)
			(stroke
				(width 0.1)
				(type default)
			)
			(layer "B.Fab")
		)
		(fp_line
			(start -0.120396 0.2794)
			(end 0.12065 0.2794)
			(stroke
				(width 0.1)
				(type default)
			)
			(layer "B.Fab")
		)
		(fp_line
			(start -0.12065 -0.2794)
			(end -0.12065 -0.3048)
			(stroke
				(width 0.1)
				(type default)
			)
			(layer "B.Fab")
		)
		(fp_line
			(start -0.12065 -0.3048)
			(end -0.67945 -0.3048)
			(stroke
				(width 0.1)
				(type default)
			)
			(layer "B.Fab")
		)
		(fp_line
			(start -0.67945 0.3048)
			(end -0.120396 0.3048)
			(stroke
				(width 0.1)
				(type default)
			)
			(layer "B.Fab")
		)
		(fp_line
			(start -0.67945 -0.3048)
			(end -0.67945 0.3048)
			(stroke
				(width 0.1)
				(type default)
			)
			(layer "B.Fab")
		)
		(pad "1" smd circle
			(at 0.40005 0)
			(size 0 0)
			(layers "B.Cu" "B.Mask" "B.Paste")
			(net "PD_CHL_CPU0_DIMM_SAA")
		)
		(pad "2" smd circle
			(at -0.40005 0)
			(size 0 0)
			(layers "B.Cu" "B.Mask" "B.Paste")
			(net "GND")
		)
	)
	(footprint ""
		(layer "B.Cu")
		(at 446.258442 -53.188108 -90)
		(property "Reference" "PC8014"
			(at 0 0 90)
			(layer "B.SilkS")
			(hide yes)
			(effects
				(font
					(size 1.27 1.27)
				)
				(justify mirror)
			)
		)
		(property "Value" ""
			(at 0 0 90)
			(layer "B.Fab")
			(effects
				(font
					(size 1.27 1.27)
				)
				(justify mirror)
			)
		)
		(duplicate_pad_numbers_are_jumpers no)
		(fp_line
			(start -1.524 0.762)
			(end 1.524 0.762)
			(stroke
				(width 0.1524)
				(type default)
			)
			(layer "B.SilkS")
		)
		(fp_line
			(start 1.524 0.762)
			(end 1.524 -0.762)
			(stroke
				(width 0.1524)
				(type default)
			)
			(layer "B.SilkS")
		)
		(fp_line
			(start -1.524 -0.762)
			(end -1.524 0.762)
			(stroke
				(width 0.1524)
				(type default)
			)
			(layer "B.SilkS")
		)
		(fp_line
			(start 1.524 -0.762)
			(end -1.524 -0.762)
			(stroke
				(width 0.1524)
				(type default)
			)
			(layer "B.SilkS")
		)
		(fp_line
			(start -1.1049 0.724916)
			(end -1.1049 -0.724916)
			(stroke
				(width 0.1)
				(type default)
			)
			(layer "B.Fab")
		)
		(fp_line
			(start 1.1049 0.724916)
			(end -1.1049 0.724916)
			(stroke
				(width 0.1)
				(type default)
			)
			(layer "B.Fab")
		)
		(fp_line
			(start -1.1049 -0.724916)
			(end 1.1049 -0.724916)
			(stroke
				(width 0.1)
				(type default)
			)
			(layer "B.Fab")
		)
		(fp_line
			(start 1.1049 -0.724916)
			(end 1.1049 0.724916)
			(stroke
				(width 0.1)
				(type default)
			)
			(layer "B.Fab")
		)
		(pad "1" smd rect
			(at 0.889 0 270)
			(size 1.016 1.27)
			(layers "B.Cu" "B.Mask" "B.Paste")
			(net "SW_P3V3_AUX_FLT")
		)
		(pad "2" smd rect
			(at -0.889 0 270)
			(size 1.016 1.27)
			(layers "B.Cu" "B.Mask" "B.Paste")
			(net "GND")
		)
	)
	(footprint ""
		(layer "B.Cu")
		(at 411.40634 -395.148562 90)
		(property "Reference" "C774"
			(at 0 0 90)
			(layer "B.SilkS")
			(hide yes)
			(effects
				(font
					(size 1.27 1.27)
				)
				(justify mirror)
			)
		)
		(property "Value" ""
			(at 0 0 90)
			(layer "B.Fab")
			(effects
				(font
					(size 1.27 1.27)
				)
				(justify mirror)
			)
		)
		(duplicate_pad_numbers_are_jumpers no)
		(fp_line
			(start 0.299974 -0.150114)
			(end -0.299974 -0.150114)
			(stroke
				(width 0.1)
				(type default)
			)
			(layer "B.Fab")
		)
		(fp_line
			(start -0.299974 -0.150114)
			(end -0.299974 0.150114)
			(stroke
				(width 0.1)
				(type default)
			)
			(layer "B.Fab")
		)
		(fp_line
			(start 0.299974 0.150114)
			(end 0.299974 -0.150114)
			(stroke
				(width 0.1)
				(type default)
			)
			(layer "B.Fab")
		)
		(fp_line
			(start -0.299974 0.150114)
			(end 0.299974 0.150114)
			(stroke
				(width 0.1)
				(type default)
			)
			(layer "B.Fab")
		)
		(pad "1" smd rect
			(at 0.2667 0 270)
			(size 0.3048 0.381)
			(layers "B.Cu" "B.Mask" "B.Paste")
			(net "P1V8_CPU0_RT2_1A")
		)
		(pad "2" smd rect
			(at -0.2667 0 270)
			(size 0.3048 0.381)
			(layers "B.Cu" "B.Mask" "B.Paste")
			(net "GND")
		)
	)
	(footprint ""
		(layer "B.Cu")
		(at 57.118504 -388.011162 -90)
		(property "Reference" "C129"
			(at 0 0 90)
			(layer "B.SilkS")
			(hide yes)
			(effects
				(font
					(size 1.27 1.27)
				)
				(justify mirror)
			)
		)
		(property "Value" ""
			(at 0 0 90)
			(layer "B.Fab")
			(effects
				(font
					(size 1.27 1.27)
				)
				(justify mirror)
			)
		)
		(duplicate_pad_numbers_are_jumpers no)
		(fp_line
			(start -0.299974 0.150114)
			(end 0.299974 0.150114)
			(stroke
				(width 0.1)
				(type default)
			)
			(layer "B.Fab")
		)
		(fp_line
			(start 0.299974 0.150114)
			(end 0.299974 -0.150114)
			(stroke
				(width 0.1)
				(type default)
			)
			(layer "B.Fab")
		)
		(fp_line
			(start -0.299974 -0.150114)
			(end -0.299974 0.150114)
			(stroke
				(width 0.1)
				(type default)
			)
			(layer "B.Fab")
		)
		(fp_line
			(start 0.299974 -0.150114)
			(end -0.299974 -0.150114)
			(stroke
				(width 0.1)
				(type default)
			)
			(layer "B.Fab")
		)
		(pad "1" smd rect
			(at 0.2667 0 90)
			(size 0.3048 0.381)
			(layers "B.Cu" "B.Mask" "B.Paste")
			(net "P1V8_CPU1_RT0_1A")
		)
		(pad "2" smd rect
			(at -0.2667 0 90)
			(size 0.3048 0.381)
			(layers "B.Cu" "B.Mask" "B.Paste")
			(net "GND")
		)
	)
	(footprint ""
		(layer "B.Cu")
		(at 46.359318 -431.985674 -90)
		(property "Reference" "R3432"
			(at 0 0 90)
			(layer "B.SilkS")
			(hide yes)
			(effects
				(font
					(size 1.27 1.27)
				)
				(justify mirror)
			)
		)
		(property "Value" ""
			(at 0 0 90)
			(layer "B.Fab")
			(effects
				(font
					(size 1.27 1.27)
				)
				(justify mirror)
			)
		)
		(duplicate_pad_numbers_are_jumpers no)
		(fp_line
			(start -0.7874 0.4064)
			(end 0.7874 0.4064)
			(stroke
				(width 0.1524)
				(type default)
			)
			(layer "B.SilkS")
		)
		(fp_line
			(start 0.7874 0.4064)
			(end 0.7874 -0.4064)
			(stroke
				(width 0.1524)
				(type default)
			)
			(layer "B.SilkS")
		)
		(fp_line
			(start -0.7874 -0.4064)
			(end -0.7874 0.4064)
			(stroke
				(width 0.1524)
				(type default)
			)
			(layer "B.SilkS")
		)
		(fp_line
			(start 0.7874 -0.4064)
			(end -0.7874 -0.4064)
			(stroke
				(width 0.1524)
				(type default)
			)
			(layer "B.SilkS")
		)
		(fp_line
			(start -0.67945 0.3048)
			(end -0.120396 0.3048)
			(stroke
				(width 0.1)
				(type default)
			)
			(layer "B.Fab")
		)
		(fp_line
			(start -0.120396 0.3048)
			(end -0.120396 0.2794)
			(stroke
				(width 0.1)
				(type default)
			)
			(layer "B.Fab")
		)
		(fp_line
			(start 0.12065 0.3048)
			(end 0.67945 0.3048)
			(stroke
				(width 0.1)
				(type default)
			)
			(layer "B.Fab")
		)
		(fp_line
			(start 0.67945 0.3048)
			(end 0.67945 -0.305054)
			(stroke
				(width 0.1)
				(type default)
			)
			(layer "B.Fab")
		)
		(fp_line
			(start -0.120396 0.2794)
			(end 0.12065 0.2794)
			(stroke
				(width 0.1)
				(type default)
			)
			(layer "B.Fab")
		)
		(fp_line
			(start 0.12065 0.2794)
			(end 0.12065 0.3048)
			(stroke
				(width 0.1)
				(type default)
			)
			(layer "B.Fab")
		)
		(fp_line
			(start -0.12065 -0.2794)
			(end -0.12065 -0.3048)
			(stroke
				(width 0.1)
				(type default)
			)
			(layer "B.Fab")
		)
		(fp_line
			(start 0.12065 -0.2794)
			(end -0.12065 -0.2794)
			(stroke
				(width 0.1)
				(type default)
			)
			(layer "B.Fab")
		)
		(fp_line
			(start -0.67945 -0.3048)
			(end -0.67945 0.3048)
			(stroke
				(width 0.1)
				(type default)
			)
			(layer "B.Fab")
		)
		(fp_line
			(start -0.12065 -0.3048)
			(end -0.67945 -0.3048)
			(stroke
				(width 0.1)
				(type default)
			)
			(layer "B.Fab")
		)
		(fp_line
			(start 0.12065 -0.305054)
			(end 0.12065 -0.2794)
			(stroke
				(width 0.1)
				(type default)
			)
			(layer "B.Fab")
		)
		(fp_line
			(start 0.67945 -0.305054)
			(end 0.12065 -0.305054)
			(stroke
				(width 0.1)
				(type default)
			)
			(layer "B.Fab")
		)
		(pad "1" smd circle
			(at 0.40005 0 90)
			(size 0 0)
			(layers "B.Cu" "B.Mask" "B.Paste")
			(net "P3V3_AUX")
		)
		(pad "2" smd circle
			(at -0.40005 0 90)
			(size 0 0)
			(layers "B.Cu" "B.Mask" "B.Paste")
			(net "GPU_FPGA_THERM_OVERT")
		)
	)
	(footprint ""
		(layer "B.Cu")
		(at 152.202642 -74.67854)
		(property "Reference" "PC866"
			(at 0 0 0)
			(layer "B.SilkS")
			(hide yes)
			(effects
				(font
					(size 1.27 1.27)
				)
				(justify mirror)
			)
		)
		(property "Value" ""
			(at 0 0 0)
			(layer "B.Fab")
			(effects
				(font
					(size 1.27 1.27)
				)
				(justify mirror)
			)
		)
		(duplicate_pad_numbers_are_jumpers no)
		(fp_line
			(start -1.524 -0.762)
			(end -1.524 0.762)
			(stroke
				(width 0.1524)
				(type default)
			)
			(layer "B.SilkS")
		)
		(fp_line
			(start -1.524 0.762)
			(end 1.524 0.762)
			(stroke
				(width 0.1524)
				(type default)
			)
			(layer "B.SilkS")
		)
		(fp_line
			(start 1.524 -0.762)
			(end -1.524 -0.762)
			(stroke
				(width 0.1524)
				(type default)
			)
			(layer "B.SilkS")
		)
		(fp_line
			(start 1.524 0.762)
			(end 1.524 -0.762)
			(stroke
				(width 0.1524)
				(type default)
			)
			(layer "B.SilkS")
		)
		(fp_line
			(start -1.1049 -0.724916)
			(end 1.1049 -0.724916)
			(stroke
				(width 0.1)
				(type default)
			)
			(layer "B.Fab")
		)
		(fp_line
			(start -1.1049 0.724916)
			(end -1.1049 -0.724916)
			(stroke
				(width 0.1)
				(type default)
			)
			(layer "B.Fab")
		)
		(fp_line
			(start 1.1049 -0.724916)
			(end 1.1049 0.724916)
			(stroke
				(width 0.1)
				(type default)
			)
			(layer "B.Fab")
		)
		(fp_line
			(start 1.1049 0.724916)
			(end -1.1049 0.724916)
			(stroke
				(width 0.1)
				(type default)
			)
			(layer "B.Fab")
		)
		(pad "1" smd rect
			(at 0.889 0)
			(size 1.016 1.27)
			(layers "B.Cu" "B.Mask" "B.Paste")
			(net "P1V8_AUX")
		)
		(pad "2" smd rect
			(at -0.889 0)
			(size 1.016 1.27)
			(layers "B.Cu" "B.Mask" "B.Paste")
			(net "GND")
		)
	)
	(footprint ""
		(layer "B.Cu")
		(at 173.301914 -13.416788 -90)
		(property "Reference" "R1460"
			(at 0 0 90)
			(layer "B.SilkS")
			(hide yes)
			(effects
				(font
					(size 1.27 1.27)
				)
				(justify mirror)
			)
		)
		(property "Value" ""
			(at 0 0 90)
			(layer "B.Fab")
			(effects
				(font
					(size 1.27 1.27)
				)
				(justify mirror)
			)
		)
		(duplicate_pad_numbers_are_jumpers no)
		(fp_line
			(start -0.7874 0.4064)
			(end 0.7874 0.4064)
			(stroke
				(width 0.1524)
				(type default)
			)
			(layer "B.SilkS")
		)
		(fp_line
			(start 0.7874 0.4064)
			(end 0.7874 -0.4064)
			(stroke
				(width 0.1524)
				(type default)
			)
			(layer "B.SilkS")
		)
		(fp_line
			(start -0.7874 -0.4064)
			(end -0.7874 0.4064)
			(stroke
				(width 0.1524)
				(type default)
			)
			(layer "B.SilkS")
		)
		(fp_line
			(start 0.7874 -0.4064)
			(end -0.7874 -0.4064)
			(stroke
				(width 0.1524)
				(type default)
			)
			(layer "B.SilkS")
		)
		(fp_line
			(start -0.67945 0.3048)
			(end -0.120396 0.3048)
			(stroke
				(width 0.1)
				(type default)
			)
			(layer "B.Fab")
		)
		(fp_line
			(start -0.120396 0.3048)
			(end -0.120396 0.2794)
			(stroke
				(width 0.1)
				(type default)
			)
			(layer "B.Fab")
		)
		(fp_line
			(start 0.12065 0.3048)
			(end 0.67945 0.3048)
			(stroke
				(width 0.1)
				(type default)
			)
			(layer "B.Fab")
		)
		(fp_line
			(start 0.67945 0.3048)
			(end 0.67945 -0.305054)
			(stroke
				(width 0.1)
				(type default)
			)
			(layer "B.Fab")
		)
		(fp_line
			(start -0.120396 0.2794)
			(end 0.12065 0.2794)
			(stroke
				(width 0.1)
				(type default)
			)
			(layer "B.Fab")
		)
		(fp_line
			(start 0.12065 0.2794)
			(end 0.12065 0.3048)
			(stroke
				(width 0.1)
				(type default)
			)
			(layer "B.Fab")
		)
		(fp_line
			(start -0.12065 -0.2794)
			(end -0.12065 -0.3048)
			(stroke
				(width 0.1)
				(type default)
			)
			(layer "B.Fab")
		)
		(fp_line
			(start 0.12065 -0.2794)
			(end -0.12065 -0.2794)
			(stroke
				(width 0.1)
				(type default)
			)
			(layer "B.Fab")
		)
		(fp_line
			(start -0.67945 -0.3048)
			(end -0.67945 0.3048)
			(stroke
				(width 0.1)
				(type default)
			)
			(layer "B.Fab")
		)
		(fp_line
			(start -0.12065 -0.3048)
			(end -0.67945 -0.3048)
			(stroke
				(width 0.1)
				(type default)
			)
			(layer "B.Fab")
		)
		(fp_line
			(start 0.12065 -0.305054)
			(end 0.12065 -0.2794)
			(stroke
				(width 0.1)
				(type default)
			)
			(layer "B.Fab")
		)
		(fp_line
			(start 0.67945 -0.305054)
			(end 0.12065 -0.305054)
			(stroke
				(width 0.1)
				(type default)
			)
			(layer "B.Fab")
		)
		(pad "1" smd circle
			(at 0.40005 0 90)
			(size 0 0)
			(layers "B.Cu" "B.Mask" "B.Paste")
			(net "I3C_BMC_SWB_SDA")
		)
		(pad "2" smd circle
			(at -0.40005 0 90)
			(size 0 0)
			(layers "B.Cu" "B.Mask" "B.Paste")
			(net "P3V3_AUX")
		)
	)
	(footprint ""
		(layer "B.Cu")
		(at 55.426864 -408.517344 90)
		(property "Reference" "C6666"
			(at 0 0 90)
			(layer "B.SilkS")
			(hide yes)
			(effects
				(font
					(size 1.27 1.27)
				)
				(justify mirror)
			)
		)
		(property "Value" ""
			(at 0 0 90)
			(layer "B.Fab")
			(effects
				(font
					(size 1.27 1.27)
				)
				(justify mirror)
			)
		)
		(duplicate_pad_numbers_are_jumpers no)
		(fp_line
			(start 0.299974 -0.150114)
			(end -0.299974 -0.150114)
			(stroke
				(width 0.1)
				(type default)
			)
			(layer "B.Fab")
		)
		(fp_line
			(start -0.299974 -0.150114)
			(end -0.299974 0.150114)
			(stroke
				(width 0.1)
				(type default)
			)
			(layer "B.Fab")
		)
		(fp_line
			(start 0.299974 0.150114)
			(end 0.299974 -0.150114)
			(stroke
				(width 0.1)
				(type default)
			)
			(layer "B.Fab")
		)
		(fp_line
			(start -0.299974 0.150114)
			(end 0.299974 0.150114)
			(stroke
				(width 0.1)
				(type default)
			)
			(layer "B.Fab")
		)
		(pad "1" smd rect
			(at 0.2667 0 270)
			(size 0.3048 0.381)
			(layers "B.Cu" "B.Mask" "B.Paste")
			(net "P5E_CPU1_P1_TX_BUF_C_DN<2>")
		)
		(pad "2" smd rect
			(at -0.2667 0 270)
			(size 0.3048 0.381)
			(layers "B.Cu" "B.Mask" "B.Paste")
			(net "P5E_CPU1_P1_TX_BUF_DN<2>")
		)
	)
	(footprint ""
		(layer "B.Cu")
		(at 150.259034 -201.977752 90)
		(property "Reference" "R525"
			(at 0 0 90)
			(layer "B.SilkS")
			(hide yes)
			(effects
				(font
					(size 1.27 1.27)
				)
				(justify mirror)
			)
		)
		(property "Value" ""
			(at 0 0 90)
			(layer "B.Fab")
			(effects
				(font
					(size 1.27 1.27)
				)
				(justify mirror)
			)
		)
		(duplicate_pad_numbers_are_jumpers no)
		(fp_line
			(start 0.7874 -0.4064)
			(end -0.7874 -0.4064)
			(stroke
				(width 0.1524)
				(type default)
			)
			(layer "B.SilkS")
		)
		(fp_line
			(start -0.7874 -0.4064)
			(end -0.7874 0.4064)
			(stroke
				(width 0.1524)
				(type default)
			)
			(layer "B.SilkS")
		)
		(fp_line
			(start 0.7874 0.4064)
			(end 0.7874 -0.4064)
			(stroke
				(width 0.1524)
				(type default)
			)
			(layer "B.SilkS")
		)
		(fp_line
			(start -0.7874 0.4064)
			(end 0.7874 0.4064)
			(stroke
				(width 0.1524)
				(type default)
			)
			(layer "B.SilkS")
		)
		(fp_line
			(start 0.67945 -0.305054)
			(end 0.12065 -0.305054)
			(stroke
				(width 0.1)
				(type default)
			)
			(layer "B.Fab")
		)
		(fp_line
			(start 0.12065 -0.305054)
			(end 0.12065 -0.2794)
			(stroke
				(width 0.1)
				(type default)
			)
			(layer "B.Fab")
		)
		(fp_line
			(start -0.12065 -0.3048)
			(end -0.67945 -0.3048)
			(stroke
				(width 0.1)
				(type default)
			)
			(layer "B.Fab")
		)
		(fp_line
			(start -0.67945 -0.3048)
			(end -0.67945 0.3048)
			(stroke
				(width 0.1)
				(type default)
			)
			(layer "B.Fab")
		)
		(fp_line
			(start 0.12065 -0.2794)
			(end -0.12065 -0.2794)
			(stroke
				(width 0.1)
				(type default)
			)
			(layer "B.Fab")
		)
		(fp_line
			(start -0.12065 -0.2794)
			(end -0.12065 -0.3048)
			(stroke
				(width 0.1)
				(type default)
			)
			(layer "B.Fab")
		)
		(fp_line
			(start 0.12065 0.2794)
			(end 0.12065 0.3048)
			(stroke
				(width 0.1)
				(type default)
			)
			(layer "B.Fab")
		)
		(fp_line
			(start -0.120396 0.2794)
			(end 0.12065 0.2794)
			(stroke
				(width 0.1)
				(type default)
			)
			(layer "B.Fab")
		)
		(fp_line
			(start 0.67945 0.3048)
			(end 0.67945 -0.305054)
			(stroke
				(width 0.1)
				(type default)
			)
			(layer "B.Fab")
		)
		(fp_line
			(start 0.12065 0.3048)
			(end 0.67945 0.3048)
			(stroke
				(width 0.1)
				(type default)
			)
			(layer "B.Fab")
		)
		(fp_line
			(start -0.120396 0.3048)
			(end -0.120396 0.2794)
			(stroke
				(width 0.1)
				(type default)
			)
			(layer "B.Fab")
		)
		(fp_line
			(start -0.67945 0.3048)
			(end -0.120396 0.3048)
			(stroke
				(width 0.1)
				(type default)
			)
			(layer "B.Fab")
		)
		(pad "1" smd circle
			(at 0.40005 0 270)
			(size 0 0)
			(layers "B.Cu" "B.Mask" "B.Paste")
			(net "PVDD18_S5_P1")
		)
		(pad "2" smd circle
			(at -0.40005 0 270)
			(size 0 0)
			(layers "B.Cu" "B.Mask" "B.Paste")
			(net "JTAG_CPU1_TRST_N")
		)
	)
	(footprint ""
		(layer "B.Cu")
		(at 348.888558 -254.06731 180)
		(property "Reference" "C2522"
			(at 0 0 0)
			(layer "B.SilkS")
			(hide yes)
			(effects
				(font
					(size 1.27 1.27)
				)
				(justify mirror)
			)
		)
		(property "Value" ""
			(at 0 0 0)
			(layer "B.Fab")
			(effects
				(font
					(size 1.27 1.27)
				)
				(justify mirror)
			)
		)
		(duplicate_pad_numbers_are_jumpers no)
		(fp_line
			(start 0.7874 0.4064)
			(end 0.7874 -0.4064)
			(stroke
				(width 0.1524)
				(type default)
			)
			(layer "B.SilkS")
		)
		(fp_line
			(start 0.7874 -0.4064)
			(end -0.7874 -0.4064)
			(stroke
				(width 0.1524)
				(type default)
			)
			(layer "B.SilkS")
		)
		(fp_line
			(start -0.7874 0.4064)
			(end 0.7874 0.4064)
			(stroke
				(width 0.1524)
				(type default)
			)
			(layer "B.SilkS")
		)
		(fp_line
			(start -0.7874 -0.4064)
			(end -0.7874 0.4064)
			(stroke
				(width 0.1524)
				(type default)
			)
			(layer "B.SilkS")
		)
		(fp_line
			(start 0.67945 0.3048)
			(end 0.67945 -0.305054)
			(stroke
				(width 0.1)
				(type default)
			)
			(layer "B.Fab")
		)
		(fp_line
			(start 0.67945 -0.305054)
			(end 0.12065 -0.305054)
			(stroke
				(width 0.1)
				(type default)
			)
			(layer "B.Fab")
		)
		(fp_line
			(start 0.12065 0.3048)
			(end 0.67945 0.3048)
			(stroke
				(width 0.1)
				(type default)
			)
			(layer "B.Fab")
		)
		(fp_line
			(start 0.12065 0.2794)
			(end 0.12065 0.3048)
			(stroke
				(width 0.1)
				(type default)
			)
			(layer "B.Fab")
		)
		(fp_line
			(start 0.12065 -0.2794)
			(end -0.12065 -0.2794)
			(stroke
				(width 0.1)
				(type default)
			)
			(layer "B.Fab")
		)
		(fp_line
			(start 0.12065 -0.305054)
			(end 0.12065 -0.2794)
			(stroke
				(width 0.1)
				(type default)
			)
			(layer "B.Fab")
		)
		(fp_line
			(start -0.120396 0.3048)
			(end -0.120396 0.2794)
			(stroke
				(width 0.1)
				(type default)
			)
			(layer "B.Fab")
		)
		(fp_line
			(start -0.120396 0.2794)
			(end 0.12065 0.2794)
			(stroke
				(width 0.1)
				(type default)
			)
			(layer "B.Fab")
		)
		(fp_line
			(start -0.12065 -0.2794)
			(end -0.12065 -0.3048)
			(stroke
				(width 0.1)
				(type default)
			)
			(layer "B.Fab")
		)
		(fp_line
			(start -0.12065 -0.3048)
			(end -0.67945 -0.3048)
			(stroke
				(width 0.1)
				(type default)
			)
			(layer "B.Fab")
		)
		(fp_line
			(start -0.67945 0.3048)
			(end -0.120396 0.3048)
			(stroke
				(width 0.1)
				(type default)
			)
			(layer "B.Fab")
		)
		(fp_line
			(start -0.67945 -0.3048)
			(end -0.67945 0.3048)
			(stroke
				(width 0.1)
				(type default)
			)
			(layer "B.Fab")
		)
		(pad "1" smd circle
			(at 0.40005 0)
			(size 0 0)
			(layers "B.Cu" "B.Mask" "B.Paste")
			(net "PVDD18_S5_P0")
		)
		(pad "2" smd circle
			(at -0.40005 0)
			(size 0 0)
			(layers "B.Cu" "B.Mask" "B.Paste")
			(net "GND")
		)
	)
	(footprint ""
		(layer "B.Cu")
		(at 325.635112 -33.851342 -90)
		(property "Reference" "R3940"
			(at 0 0 90)
			(layer "B.SilkS")
			(hide yes)
			(effects
				(font
					(size 1.27 1.27)
				)
				(justify mirror)
			)
		)
		(property "Value" ""
			(at 0 0 90)
			(layer "B.Fab")
			(effects
				(font
					(size 1.27 1.27)
				)
				(justify mirror)
			)
		)
		(duplicate_pad_numbers_are_jumpers no)
		(fp_line
			(start -0.7874 0.4064)
			(end 0.7874 0.4064)
			(stroke
				(width 0.1524)
				(type default)
			)
			(layer "B.SilkS")
		)
		(fp_line
			(start 0.7874 0.4064)
			(end 0.7874 -0.4064)
			(stroke
				(width 0.1524)
				(type default)
			)
			(layer "B.SilkS")
		)
		(fp_line
			(start -0.7874 -0.4064)
			(end -0.7874 0.4064)
			(stroke
				(width 0.1524)
				(type default)
			)
			(layer "B.SilkS")
		)
		(fp_line
			(start 0.7874 -0.4064)
			(end -0.7874 -0.4064)
			(stroke
				(width 0.1524)
				(type default)
			)
			(layer "B.SilkS")
		)
		(fp_line
			(start -0.67945 0.3048)
			(end -0.120396 0.3048)
			(stroke
				(width 0.1)
				(type default)
			)
			(layer "B.Fab")
		)
		(fp_line
			(start -0.120396 0.3048)
			(end -0.120396 0.2794)
			(stroke
				(width 0.1)
				(type default)
			)
			(layer "B.Fab")
		)
		(fp_line
			(start 0.12065 0.3048)
			(end 0.67945 0.3048)
			(stroke
				(width 0.1)
				(type default)
			)
			(layer "B.Fab")
		)
		(fp_line
			(start 0.67945 0.3048)
			(end 0.67945 -0.305054)
			(stroke
				(width 0.1)
				(type default)
			)
			(layer "B.Fab")
		)
		(fp_line
			(start -0.120396 0.2794)
			(end 0.12065 0.2794)
			(stroke
				(width 0.1)
				(type default)
			)
			(layer "B.Fab")
		)
		(fp_line
			(start 0.12065 0.2794)
			(end 0.12065 0.3048)
			(stroke
				(width 0.1)
				(type default)
			)
			(layer "B.Fab")
		)
		(fp_line
			(start -0.12065 -0.2794)
			(end -0.12065 -0.3048)
			(stroke
				(width 0.1)
				(type default)
			)
			(layer "B.Fab")
		)
		(fp_line
			(start 0.12065 -0.2794)
			(end -0.12065 -0.2794)
			(stroke
				(width 0.1)
				(type default)
			)
			(layer "B.Fab")
		)
		(fp_line
			(start -0.67945 -0.3048)
			(end -0.67945 0.3048)
			(stroke
				(width 0.1)
				(type default)
			)
			(layer "B.Fab")
		)
		(fp_line
			(start -0.12065 -0.3048)
			(end -0.67945 -0.3048)
			(stroke
				(width 0.1)
				(type default)
			)
			(layer "B.Fab")
		)
		(fp_line
			(start 0.12065 -0.305054)
			(end 0.12065 -0.2794)
			(stroke
				(width 0.1)
				(type default)
			)
			(layer "B.Fab")
		)
		(fp_line
			(start 0.67945 -0.305054)
			(end 0.12065 -0.305054)
			(stroke
				(width 0.1)
				(type default)
			)
			(layer "B.Fab")
		)
		(pad "1" smd rect
			(at 0.40005 0 270)
			(size 0.4572 0.508)
			(layers "B.Cu" "B.Mask" "B.Paste")
			(net "P12V_E1S_0_ISENSE_MPS_MAM")
		)
		(pad "2" smd rect
			(at -0.40005 0 270)
			(size 0.4572 0.508)
			(layers "B.Cu" "B.Mask" "B.Paste")
			(net "P12V_E1S_0_ISENSE_MAM")
		)
	)
	(footprint ""
		(layer "B.Cu")
		(at 206.248 -192.660016)
		(property "Reference" "C548"
			(at 0 0 0)
			(layer "B.SilkS")
			(hide yes)
			(effects
				(font
					(size 1.27 1.27)
				)
				(justify mirror)
			)
		)
		(property "Value" ""
			(at 0 0 0)
			(layer "B.Fab")
			(effects
				(font
					(size 1.27 1.27)
				)
				(justify mirror)
			)
		)
		(duplicate_pad_numbers_are_jumpers no)
		(fp_line
			(start -1.524 -0.762)
			(end -1.524 0.762)
			(stroke
				(width 0.1524)
				(type default)
			)
			(layer "B.SilkS")
		)
		(fp_line
			(start -1.524 0.762)
			(end 1.524 0.762)
			(stroke
				(width 0.1524)
				(type default)
			)
			(layer "B.SilkS")
		)
		(fp_line
			(start 1.524 -0.762)
			(end -1.524 -0.762)
			(stroke
				(width 0.1524)
				(type default)
			)
			(layer "B.SilkS")
		)
		(fp_line
			(start 1.524 0.762)
			(end 1.524 -0.762)
			(stroke
				(width 0.1524)
				(type default)
			)
			(layer "B.SilkS")
		)
		(fp_line
			(start -1.1049 -0.724916)
			(end 1.1049 -0.724916)
			(stroke
				(width 0.1)
				(type default)
			)
			(layer "B.Fab")
		)
		(fp_line
			(start -1.1049 0.724916)
			(end -1.1049 -0.724916)
			(stroke
				(width 0.1)
				(type default)
			)
			(layer "B.Fab")
		)
		(fp_line
			(start 1.1049 -0.724916)
			(end 1.1049 0.724916)
			(stroke
				(width 0.1)
				(type default)
			)
			(layer "B.Fab")
		)
		(fp_line
			(start 1.1049 0.724916)
			(end -1.1049 0.724916)
			(stroke
				(width 0.1)
				(type default)
			)
			(layer "B.Fab")
		)
		(pad "1" smd rect
			(at 0.889 0)
			(size 1.016 1.27)
			(layers "B.Cu" "B.Mask" "B.Paste")
			(net "P12V_MEM_CPU1")
		)
		(pad "2" smd rect
			(at -0.889 0)
			(size 1.016 1.27)
			(layers "B.Cu" "B.Mask" "B.Paste")
			(net "GND")
		)
	)
	(footprint ""
		(layer "B.Cu")
		(at 121.010172 -72.566022)
		(property "Reference" "R6240"
			(at 0 0 0)
			(layer "B.SilkS")
			(hide yes)
			(effects
				(font
					(size 1.27 1.27)
				)
				(justify mirror)
			)
		)
		(property "Value" ""
			(at 0 0 0)
			(layer "B.Fab")
			(effects
				(font
					(size 1.27 1.27)
				)
				(justify mirror)
			)
		)
		(duplicate_pad_numbers_are_jumpers no)
		(fp_line
			(start -0.7874 -0.4064)
			(end -0.7874 0.4064)
			(stroke
				(width 0.1524)
				(type default)
			)
			(layer "B.SilkS")
		)
		(fp_line
			(start -0.7874 0.4064)
			(end 0.7874 0.4064)
			(stroke
				(width 0.1524)
				(type default)
			)
			(layer "B.SilkS")
		)
		(fp_line
			(start 0.7874 -0.4064)
			(end -0.7874 -0.4064)
			(stroke
				(width 0.1524)
				(type default)
			)
			(layer "B.SilkS")
		)
		(fp_line
			(start 0.7874 0.4064)
			(end 0.7874 -0.4064)
			(stroke
				(width 0.1524)
				(type default)
			)
			(layer "B.SilkS")
		)
		(fp_line
			(start -0.67945 -0.3048)
			(end -0.67945 0.3048)
			(stroke
				(width 0.1)
				(type default)
			)
			(layer "B.Fab")
		)
		(fp_line
			(start -0.67945 0.3048)
			(end -0.120396 0.3048)
			(stroke
				(width 0.1)
				(type default)
			)
			(layer "B.Fab")
		)
		(fp_line
			(start -0.12065 -0.3048)
			(end -0.67945 -0.3048)
			(stroke
				(width 0.1)
				(type default)
			)
			(layer "B.Fab")
		)
		(fp_line
			(start -0.12065 -0.2794)
			(end -0.12065 -0.3048)
			(stroke
				(width 0.1)
				(type default)
			)
			(layer "B.Fab")
		)
		(fp_line
			(start -0.120396 0.2794)
			(end 0.12065 0.2794)
			(stroke
				(width 0.1)
				(type default)
			)
			(layer "B.Fab")
		)
		(fp_line
			(start -0.120396 0.3048)
			(end -0.120396 0.2794)
			(stroke
				(width 0.1)
				(type default)
			)
			(layer "B.Fab")
		)
		(fp_line
			(start 0.12065 -0.305054)
			(end 0.12065 -0.2794)
			(stroke
				(width 0.1)
				(type default)
			)
			(layer "B.Fab")
		)
		(fp_line
			(start 0.12065 -0.2794)
			(end -0.12065 -0.2794)
			(stroke
				(width 0.1)
				(type default)
			)
			(layer "B.Fab")
		)
		(fp_line
			(start 0.12065 0.2794)
			(end 0.12065 0.3048)
			(stroke
				(width 0.1)
				(type default)
			)
			(layer "B.Fab")
		)
		(fp_line
			(start 0.12065 0.3048)
			(end 0.67945 0.3048)
			(stroke
				(width 0.1)
				(type default)
			)
			(layer "B.Fab")
		)
		(fp_line
			(start 0.67945 -0.305054)
			(end 0.12065 -0.305054)
			(stroke
				(width 0.1)
				(type default)
			)
			(layer "B.Fab")
		)
		(fp_line
			(start 0.67945 0.3048)
			(end 0.67945 -0.305054)
			(stroke
				(width 0.1)
				(type default)
			)
			(layer "B.Fab")
		)
		(pad "1" smd circle
			(at 0.40005 0 180)
			(size 0 0)
			(layers "B.Cu" "B.Mask" "B.Paste")
			(net "PWRGD_P1V8_AUX_R")
		)
		(pad "2" smd circle
			(at -0.40005 0 180)
			(size 0 0)
			(layers "B.Cu" "B.Mask" "B.Paste")
			(net "P1V2_AUX_ENABLE")
		)
	)
	(footprint ""
		(layer "B.Cu")
		(at 177.278284 -421.217598)
		(property "Reference" "R6210"
			(at 0 0 0)
			(layer "B.SilkS")
			(hide yes)
			(effects
				(font
					(size 1.27 1.27)
				)
				(justify mirror)
			)
		)
		(property "Value" ""
			(at 0 0 0)
			(layer "B.Fab")
			(effects
				(font
					(size 1.27 1.27)
				)
				(justify mirror)
			)
		)
		(duplicate_pad_numbers_are_jumpers no)
		(fp_line
			(start -0.7874 -0.4064)
			(end -0.7874 0.4064)
			(stroke
				(width 0.1524)
				(type default)
			)
			(layer "B.SilkS")
		)
		(fp_line
			(start -0.7874 0.4064)
			(end 0.7874 0.4064)
			(stroke
				(width 0.1524)
				(type default)
			)
			(layer "B.SilkS")
		)
		(fp_line
			(start 0.7874 -0.4064)
			(end -0.7874 -0.4064)
			(stroke
				(width 0.1524)
				(type default)
			)
			(layer "B.SilkS")
		)
		(fp_line
			(start 0.7874 0.4064)
			(end 0.7874 -0.4064)
			(stroke
				(width 0.1524)
				(type default)
			)
			(layer "B.SilkS")
		)
		(fp_line
			(start -0.67945 -0.3048)
			(end -0.67945 0.3048)
			(stroke
				(width 0.1)
				(type default)
			)
			(layer "B.Fab")
		)
		(fp_line
			(start -0.67945 0.3048)
			(end -0.120396 0.3048)
			(stroke
				(width 0.1)
				(type default)
			)
			(layer "B.Fab")
		)
		(fp_line
			(start -0.12065 -0.3048)
			(end -0.67945 -0.3048)
			(stroke
				(width 0.1)
				(type default)
			)
			(layer "B.Fab")
		)
		(fp_line
			(start -0.12065 -0.2794)
			(end -0.12065 -0.3048)
			(stroke
				(width 0.1)
				(type default)
			)
			(layer "B.Fab")
		)
		(fp_line
			(start -0.120396 0.2794)
			(end 0.12065 0.2794)
			(stroke
				(width 0.1)
				(type default)
			)
			(layer "B.Fab")
		)
		(fp_line
			(start -0.120396 0.3048)
			(end -0.120396 0.2794)
			(stroke
				(width 0.1)
				(type default)
			)
			(layer "B.Fab")
		)
		(fp_line
			(start 0.12065 -0.305054)
			(end 0.12065 -0.2794)
			(stroke
				(width 0.1)
				(type default)
			)
			(layer "B.Fab")
		)
		(fp_line
			(start 0.12065 -0.2794)
			(end -0.12065 -0.2794)
			(stroke
				(width 0.1)
				(type default)
			)
			(layer "B.Fab")
		)
		(fp_line
			(start 0.12065 0.2794)
			(end 0.12065 0.3048)
			(stroke
				(width 0.1)
				(type default)
			)
			(layer "B.Fab")
		)
		(fp_line
			(start 0.12065 0.3048)
			(end 0.67945 0.3048)
			(stroke
				(width 0.1)
				(type default)
			)
			(layer "B.Fab")
		)
		(fp_line
			(start 0.67945 -0.305054)
			(end 0.12065 -0.305054)
			(stroke
				(width 0.1)
				(type default)
			)
			(layer "B.Fab")
		)
		(fp_line
			(start 0.67945 0.3048)
			(end 0.67945 -0.305054)
			(stroke
				(width 0.1)
				(type default)
			)
			(layer "B.Fab")
		)
		(pad "1" smd circle
			(at 0.40005 0 180)
			(size 0 0)
			(layers "B.Cu" "B.Mask" "B.Paste")
			(net "HSC_CSOUT")
		)
		(pad "2" smd circle
			(at -0.40005 0 180)
			(size 0 0)
			(layers "B.Cu" "B.Mask" "B.Paste")
			(net "HSC_D_OC")
		)
	)
	(footprint ""
		(layer "B.Cu")
		(at 184.681114 -418.591238)
		(property "Reference" "R2805"
			(at 0 0 0)
			(layer "B.SilkS")
			(hide yes)
			(effects
				(font
					(size 1.27 1.27)
				)
				(justify mirror)
			)
		)
		(property "Value" ""
			(at 0 0 0)
			(layer "B.Fab")
			(effects
				(font
					(size 1.27 1.27)
				)
				(justify mirror)
			)
		)
		(duplicate_pad_numbers_are_jumpers no)
		(fp_line
			(start -0.7874 -0.4064)
			(end -0.7874 0.4064)
			(stroke
				(width 0.1524)
				(type default)
			)
			(layer "B.SilkS")
		)
		(fp_line
			(start -0.7874 0.4064)
			(end 0.7874 0.4064)
			(stroke
				(width 0.1524)
				(type default)
			)
			(layer "B.SilkS")
		)
		(fp_line
			(start 0.7874 -0.4064)
			(end -0.7874 -0.4064)
			(stroke
				(width 0.1524)
				(type default)
			)
			(layer "B.SilkS")
		)
		(fp_line
			(start 0.7874 0.4064)
			(end 0.7874 -0.4064)
			(stroke
				(width 0.1524)
				(type default)
			)
			(layer "B.SilkS")
		)
		(fp_line
			(start -0.67945 -0.3048)
			(end -0.67945 0.3048)
			(stroke
				(width 0.1)
				(type default)
			)
			(layer "B.Fab")
		)
		(fp_line
			(start -0.67945 0.3048)
			(end -0.120396 0.3048)
			(stroke
				(width 0.1)
				(type default)
			)
			(layer "B.Fab")
		)
		(fp_line
			(start -0.12065 -0.3048)
			(end -0.67945 -0.3048)
			(stroke
				(width 0.1)
				(type default)
			)
			(layer "B.Fab")
		)
		(fp_line
			(start -0.12065 -0.2794)
			(end -0.12065 -0.3048)
			(stroke
				(width 0.1)
				(type default)
			)
			(layer "B.Fab")
		)
		(fp_line
			(start -0.120396 0.2794)
			(end 0.12065 0.2794)
			(stroke
				(width 0.1)
				(type default)
			)
			(layer "B.Fab")
		)
		(fp_line
			(start -0.120396 0.3048)
			(end -0.120396 0.2794)
			(stroke
				(width 0.1)
				(type default)
			)
			(layer "B.Fab")
		)
		(fp_line
			(start 0.12065 -0.305054)
			(end 0.12065 -0.2794)
			(stroke
				(width 0.1)
				(type default)
			)
			(layer "B.Fab")
		)
		(fp_line
			(start 0.12065 -0.2794)
			(end -0.12065 -0.2794)
			(stroke
				(width 0.1)
				(type default)
			)
			(layer "B.Fab")
		)
		(fp_line
			(start 0.12065 0.2794)
			(end 0.12065 0.3048)
			(stroke
				(width 0.1)
				(type default)
			)
			(layer "B.Fab")
		)
		(fp_line
			(start 0.12065 0.3048)
			(end 0.67945 0.3048)
			(stroke
				(width 0.1)
				(type default)
			)
			(layer "B.Fab")
		)
		(fp_line
			(start 0.67945 -0.305054)
			(end 0.12065 -0.305054)
			(stroke
				(width 0.1)
				(type default)
			)
			(layer "B.Fab")
		)
		(fp_line
			(start 0.67945 0.3048)
			(end 0.67945 -0.305054)
			(stroke
				(width 0.1)
				(type default)
			)
			(layer "B.Fab")
		)
		(pad "1" smd circle
			(at 0.40005 0 180)
			(size 0 0)
			(layers "B.Cu" "B.Mask" "B.Paste")
			(net "P3V3_AUX")
		)
		(pad "2" smd circle
			(at -0.40005 0 180)
			(size 0 0)
			(layers "B.Cu" "B.Mask" "B.Paste")
			(net "SMB_FAN_3V3AUX_BUF_SCL")
		)
	)
	(footprint ""
		(layer "B.Cu")
		(at 92.281502 -207.38465 90)
		(property "Reference" "R486"
			(at 0 0 90)
			(layer "B.SilkS")
			(hide yes)
			(effects
				(font
					(size 1.27 1.27)
				)
				(justify mirror)
			)
		)
		(property "Value" ""
			(at 0 0 90)
			(layer "B.Fab")
			(effects
				(font
					(size 1.27 1.27)
				)
				(justify mirror)
			)
		)
		(duplicate_pad_numbers_are_jumpers no)
		(fp_line
			(start 0.7874 -0.4064)
			(end -0.7874 -0.4064)
			(stroke
				(width 0.1524)
				(type default)
			)
			(layer "B.SilkS")
		)
		(fp_line
			(start -0.7874 -0.4064)
			(end -0.7874 0.4064)
			(stroke
				(width 0.1524)
				(type default)
			)
			(layer "B.SilkS")
		)
		(fp_line
			(start 0.7874 0.4064)
			(end 0.7874 -0.4064)
			(stroke
				(width 0.1524)
				(type default)
			)
			(layer "B.SilkS")
		)
		(fp_line
			(start -0.7874 0.4064)
			(end 0.7874 0.4064)
			(stroke
				(width 0.1524)
				(type default)
			)
			(layer "B.SilkS")
		)
		(fp_line
			(start 0.67945 -0.305054)
			(end 0.12065 -0.305054)
			(stroke
				(width 0.1)
				(type default)
			)
			(layer "B.Fab")
		)
		(fp_line
			(start 0.12065 -0.305054)
			(end 0.12065 -0.2794)
			(stroke
				(width 0.1)
				(type default)
			)
			(layer "B.Fab")
		)
		(fp_line
			(start -0.12065 -0.3048)
			(end -0.67945 -0.3048)
			(stroke
				(width 0.1)
				(type default)
			)
			(layer "B.Fab")
		)
		(fp_line
			(start -0.67945 -0.3048)
			(end -0.67945 0.3048)
			(stroke
				(width 0.1)
				(type default)
			)
			(layer "B.Fab")
		)
		(fp_line
			(start 0.12065 -0.2794)
			(end -0.12065 -0.2794)
			(stroke
				(width 0.1)
				(type default)
			)
			(layer "B.Fab")
		)
		(fp_line
			(start -0.12065 -0.2794)
			(end -0.12065 -0.3048)
			(stroke
				(width 0.1)
				(type default)
			)
			(layer "B.Fab")
		)
		(fp_line
			(start 0.12065 0.2794)
			(end 0.12065 0.3048)
			(stroke
				(width 0.1)
				(type default)
			)
			(layer "B.Fab")
		)
		(fp_line
			(start -0.120396 0.2794)
			(end 0.12065 0.2794)
			(stroke
				(width 0.1)
				(type default)
			)
			(layer "B.Fab")
		)
		(fp_line
			(start 0.67945 0.3048)
			(end 0.67945 -0.305054)
			(stroke
				(width 0.1)
				(type default)
			)
			(layer "B.Fab")
		)
		(fp_line
			(start 0.12065 0.3048)
			(end 0.67945 0.3048)
			(stroke
				(width 0.1)
				(type default)
			)
			(layer "B.Fab")
		)
		(fp_line
			(start -0.120396 0.3048)
			(end -0.120396 0.2794)
			(stroke
				(width 0.1)
				(type default)
			)
			(layer "B.Fab")
		)
		(fp_line
			(start -0.67945 0.3048)
			(end -0.120396 0.3048)
			(stroke
				(width 0.1)
				(type default)
			)
			(layer "B.Fab")
		)
		(pad "1" smd circle
			(at 0.40005 0 270)
			(size 0 0)
			(layers "B.Cu" "B.Mask" "B.Paste")
			(net "CPU1_XTRIG_R2_L4")
		)
		(pad "2" smd circle
			(at -0.40005 0 270)
			(size 0 0)
			(layers "B.Cu" "B.Mask" "B.Paste")
			(net "CPU1_XTRIG_L4")
		)
	)
	(footprint ""
		(layer "B.Cu")
		(at 339.134958 -307.717952 180)
		(property "Reference" "R747"
			(at 0 0 0)
			(layer "B.SilkS")
			(hide yes)
			(effects
				(font
					(size 1.27 1.27)
				)
				(justify mirror)
			)
		)
		(property "Value" ""
			(at 0 0 0)
			(layer "B.Fab")
			(effects
				(font
					(size 1.27 1.27)
				)
				(justify mirror)
			)
		)
		(duplicate_pad_numbers_are_jumpers no)
		(fp_line
			(start 0.7874 0.4064)
			(end 0.7874 -0.4064)
			(stroke
				(width 0.1524)
				(type default)
			)
			(layer "B.SilkS")
		)
		(fp_line
			(start 0.7874 -0.4064)
			(end -0.7874 -0.4064)
			(stroke
				(width 0.1524)
				(type default)
			)
			(layer "B.SilkS")
		)
		(fp_line
			(start -0.7874 0.4064)
			(end 0.7874 0.4064)
			(stroke
				(width 0.1524)
				(type default)
			)
			(layer "B.SilkS")
		)
		(fp_line
			(start -0.7874 -0.4064)
			(end -0.7874 0.4064)
			(stroke
				(width 0.1524)
				(type default)
			)
			(layer "B.SilkS")
		)
		(fp_line
			(start 0.67945 0.3048)
			(end 0.67945 -0.305054)
			(stroke
				(width 0.1)
				(type default)
			)
			(layer "B.Fab")
		)
		(fp_line
			(start 0.67945 -0.305054)
			(end 0.12065 -0.305054)
			(stroke
				(width 0.1)
				(type default)
			)
			(layer "B.Fab")
		)
		(fp_line
			(start 0.12065 0.3048)
			(end 0.67945 0.3048)
			(stroke
				(width 0.1)
				(type default)
			)
			(layer "B.Fab")
		)
		(fp_line
			(start 0.12065 0.2794)
			(end 0.12065 0.3048)
			(stroke
				(width 0.1)
				(type default)
			)
			(layer "B.Fab")
		)
		(fp_line
			(start 0.12065 -0.2794)
			(end -0.12065 -0.2794)
			(stroke
				(width 0.1)
				(type default)
			)
			(layer "B.Fab")
		)
		(fp_line
			(start 0.12065 -0.305054)
			(end 0.12065 -0.2794)
			(stroke
				(width 0.1)
				(type default)
			)
			(layer "B.Fab")
		)
		(fp_line
			(start -0.120396 0.3048)
			(end -0.120396 0.2794)
			(stroke
				(width 0.1)
				(type default)
			)
			(layer "B.Fab")
		)
		(fp_line
			(start -0.120396 0.2794)
			(end 0.12065 0.2794)
			(stroke
				(width 0.1)
				(type default)
			)
			(layer "B.Fab")
		)
		(fp_line
			(start -0.12065 -0.2794)
			(end -0.12065 -0.3048)
			(stroke
				(width 0.1)
				(type default)
			)
			(layer "B.Fab")
		)
		(fp_line
			(start -0.12065 -0.3048)
			(end -0.67945 -0.3048)
			(stroke
				(width 0.1)
				(type default)
			)
			(layer "B.Fab")
		)
		(fp_line
			(start -0.67945 0.3048)
			(end -0.120396 0.3048)
			(stroke
				(width 0.1)
				(type default)
			)
			(layer "B.Fab")
		)
		(fp_line
			(start -0.67945 -0.3048)
			(end -0.67945 0.3048)
			(stroke
				(width 0.1)
				(type default)
			)
			(layer "B.Fab")
		)
		(pad "1" smd circle
			(at 0.40005 0)
			(size 0 0)
			(layers "B.Cu" "B.Mask" "B.Paste")
			(net "GND")
		)
		(pad "2" smd circle
			(at -0.40005 0)
			(size 0 0)
			(layers "B.Cu" "B.Mask" "B.Paste")
			(net "UART_CPU0_SCM_UART1_TX")
		)
	)
	(footprint ""
		(layer "B.Cu")
		(at 363.645958 -257.744976 180)
		(property "Reference" "C2565"
			(at 0 0 0)
			(layer "B.SilkS")
			(hide yes)
			(effects
				(font
					(size 1.27 1.27)
				)
				(justify mirror)
			)
		)
		(property "Value" ""
			(at 0 0 0)
			(layer "B.Fab")
			(effects
				(font
					(size 1.27 1.27)
				)
				(justify mirror)
			)
		)
		(duplicate_pad_numbers_are_jumpers no)
		(fp_line
			(start 0.7874 0.4064)
			(end 0.7874 -0.4064)
			(stroke
				(width 0.1524)
				(type default)
			)
			(layer "B.SilkS")
		)
		(fp_line
			(start 0.7874 -0.4064)
			(end -0.7874 -0.4064)
			(stroke
				(width 0.1524)
				(type default)
			)
			(layer "B.SilkS")
		)
		(fp_line
			(start -0.7874 0.4064)
			(end 0.7874 0.4064)
			(stroke
				(width 0.1524)
				(type default)
			)
			(layer "B.SilkS")
		)
		(fp_line
			(start -0.7874 -0.4064)
			(end -0.7874 0.4064)
			(stroke
				(width 0.1524)
				(type default)
			)
			(layer "B.SilkS")
		)
		(fp_line
			(start 0.67945 0.3048)
			(end 0.67945 -0.305054)
			(stroke
				(width 0.1)
				(type default)
			)
			(layer "B.Fab")
		)
		(fp_line
			(start 0.67945 -0.305054)
			(end 0.12065 -0.305054)
			(stroke
				(width 0.1)
				(type default)
			)
			(layer "B.Fab")
		)
		(fp_line
			(start 0.12065 0.3048)
			(end 0.67945 0.3048)
			(stroke
				(width 0.1)
				(type default)
			)
			(layer "B.Fab")
		)
		(fp_line
			(start 0.12065 0.2794)
			(end 0.12065 0.3048)
			(stroke
				(width 0.1)
				(type default)
			)
			(layer "B.Fab")
		)
		(fp_line
			(start 0.12065 -0.2794)
			(end -0.12065 -0.2794)
			(stroke
				(width 0.1)
				(type default)
			)
			(layer "B.Fab")
		)
		(fp_line
			(start 0.12065 -0.305054)
			(end 0.12065 -0.2794)
			(stroke
				(width 0.1)
				(type default)
			)
			(layer "B.Fab")
		)
		(fp_line
			(start -0.120396 0.3048)
			(end -0.120396 0.2794)
			(stroke
				(width 0.1)
				(type default)
			)
			(layer "B.Fab")
		)
		(fp_line
			(start -0.120396 0.2794)
			(end 0.12065 0.2794)
			(stroke
				(width 0.1)
				(type default)
			)
			(layer "B.Fab")
		)
		(fp_line
			(start -0.12065 -0.2794)
			(end -0.12065 -0.3048)
			(stroke
				(width 0.1)
				(type default)
			)
			(layer "B.Fab")
		)
		(fp_line
			(start -0.12065 -0.3048)
			(end -0.67945 -0.3048)
			(stroke
				(width 0.1)
				(type default)
			)
			(layer "B.Fab")
		)
		(fp_line
			(start -0.67945 0.3048)
			(end -0.120396 0.3048)
			(stroke
				(width 0.1)
				(type default)
			)
			(layer "B.Fab")
		)
		(fp_line
			(start -0.67945 -0.3048)
			(end -0.67945 0.3048)
			(stroke
				(width 0.1)
				(type default)
			)
			(layer "B.Fab")
		)
		(pad "1" smd circle
			(at 0.40005 0)
			(size 0 0)
			(layers "B.Cu" "B.Mask" "B.Paste")
			(net "PVDDCR_SOC_P0")
		)
		(pad "2" smd circle
			(at -0.40005 0)
			(size 0 0)
			(layers "B.Cu" "B.Mask" "B.Paste")
			(net "GND")
		)
	)
	(footprint ""
		(layer "B.Cu")
		(at 330.523342 -393.04468 180)
		(property "Reference" "R1032"
			(at 0 0 0)
			(layer "B.SilkS")
			(hide yes)
			(effects
				(font
					(size 1.27 1.27)
				)
				(justify mirror)
			)
		)
		(property "Value" ""
			(at 0 0 0)
			(layer "B.Fab")
			(effects
				(font
					(size 1.27 1.27)
				)
				(justify mirror)
			)
		)
		(duplicate_pad_numbers_are_jumpers no)
		(fp_line
			(start 0.32512 0.175006)
			(end 0.32512 -0.175006)
			(stroke
				(width 0.1)
				(type default)
			)
			(layer "B.Fab")
		)
		(fp_line
			(start 0.32512 -0.175006)
			(end -0.32512 -0.175006)
			(stroke
				(width 0.1)
				(type default)
			)
			(layer "B.Fab")
		)
		(fp_line
			(start -0.32512 0.175006)
			(end 0.32512 0.175006)
			(stroke
				(width 0.1)
				(type default)
			)
			(layer "B.Fab")
		)
		(fp_line
			(start -0.32512 -0.175006)
			(end -0.32512 0.175006)
			(stroke
				(width 0.1)
				(type default)
			)
			(layer "B.Fab")
		)
		(pad "1" smd rect
			(at 0.2667 0)
			(size 0.3048 0.381)
			(layers "B.Cu" "B.Mask" "B.Paste")
			(net "P1V8_CPU0_RT_1D")
		)
		(pad "2" smd rect
			(at -0.2667 0 180)
			(size 0.3048 0.381)
			(layers "B.Cu" "B.Mask" "B.Paste")
			(net "TEST1_RT_CPU0_P1")
		)
	)
	(footprint ""
		(layer "B.Cu")
		(at 456.028552 -380.027434 90)
		(property "Reference" "PC6569"
			(at -6.293104 2.441448 0)
			(unlocked yes)
			(layer "B.SilkS")
			(effects
				(font
					(size 0.7874 0.5842)
					(thickness 0.1524)
				)
				(justify left mirror)
			)
		)
		(property "Value" ""
			(at 0 0 90)
			(layer "B.Fab")
			(effects
				(font
					(size 1.27 1.27)
				)
				(justify mirror)
			)
		)
		(duplicate_pad_numbers_are_jumpers no)
		(fp_line
			(start 4.84378 -2.150618)
			(end 4.53898 -2.150618)
			(stroke
				(width 0.1524)
				(type default)
			)
			(layer "B.SilkS")
		)
		(fp_line
			(start 4.84378 -2.150618)
			(end 4.842256 2.163064)
			(stroke
				(width 0.1524)
				(type default)
			)
			(layer "B.SilkS")
		)
		(fp_line
			(start 4.69138 -2.150618)
			(end 4.692396 2.161032)
			(stroke
				(width 0.1524)
				(type default)
			)
			(layer "B.SilkS")
		)
		(fp_line
			(start 4.53898 -2.150618)
			(end 4.539742 2.152142)
			(stroke
				(width 0.1524)
				(type default)
			)
			(layer "B.SilkS")
		)
		(fp_line
			(start 4.53898 -2.15011)
			(end -4.53898 -2.15011)
			(stroke
				(width 0.1524)
				(type default)
			)
			(layer "B.SilkS")
		)
		(fp_line
			(start -4.53898 -2.15011)
			(end -4.53898 2.15011)
			(stroke
				(width 0.1524)
				(type default)
			)
			(layer "B.SilkS")
		)
		(fp_line
			(start 4.53898 2.15011)
			(end 4.53898 -2.15011)
			(stroke
				(width 0.1524)
				(type default)
			)
			(layer "B.SilkS")
		)
		(fp_line
			(start -4.53898 2.15011)
			(end 4.53898 2.15011)
			(stroke
				(width 0.1524)
				(type default)
			)
			(layer "B.SilkS")
		)
		(fp_line
			(start 4.83108 2.150364)
			(end 4.447794 2.149348)
			(stroke
				(width 0.1524)
				(type default)
			)
			(layer "B.SilkS")
		)
		(fp_line
			(start 3.64998 -2.15011)
			(end -3.64998 -2.15011)
			(stroke
				(width 0.1)
				(type default)
			)
			(layer "B.Fab")
		)
		(fp_line
			(start -3.64998 -2.15011)
			(end -3.64998 2.15011)
			(stroke
				(width 0.1)
				(type default)
			)
			(layer "B.Fab")
		)
		(fp_line
			(start 3.64998 2.15011)
			(end 3.64998 -2.15011)
			(stroke
				(width 0.1)
				(type default)
			)
			(layer "B.Fab")
		)
		(fp_line
			(start -3.64998 2.15011)
			(end 3.64998 2.15011)
			(stroke
				(width 0.1)
				(type default)
			)
			(layer "B.Fab")
		)
		(fp_text user "+"
			(at 5.235702 -3.104388 90)
			(unlocked yes)
			(layer "B.SilkS")
			(effects
				(font
					(size 1.905 1.4224)
					(thickness 0.1524)
				)
				(justify left mirror)
			)
		)
		(fp_text user "-"
			(at -4.313174 -0.094488 90)
			(unlocked yes)
			(layer "B.SilkS")
			(effects
				(font
					(size 1.905 1.4224)
					(thickness 0.1524)
				)
				(justify left mirror)
			)
		)
		(fp_text user "+"
			(at 6.214872 -0.337058 90)
			(unlocked yes)
			(layer "B.Fab")
			(effects
				(font
					(size 1.905 1.4224)
					(thickness 0.1524)
				)
				(justify left mirror)
			)
		)
		(fp_text user "-"
			(at -4.313174 -0.094488 90)
			(unlocked yes)
			(layer "B.Fab")
			(effects
				(font
					(size 1.905 1.4224)
					(thickness 0.1524)
				)
				(justify left mirror)
			)
		)
		(pad "1" smd rect
			(at 3.199892 0 270)
			(size 2.413 2.8194)
			(layers "B.Cu" "B.Mask" "B.Paste")
			(net "P0V9_CPU0_RT_2D")
		)
		(pad "2" smd rect
			(at -3.199892 0 270)
			(size 2.413 2.8194)
			(layers "B.Cu" "B.Mask" "B.Paste")
			(net "GND")
		)
	)
	(footprint ""
		(layer "B.Cu")
		(at 234.843828 -324.793102 180)
		(property "Reference" "R1220"
			(at 0 0 0)
			(layer "B.SilkS")
			(hide yes)
			(effects
				(font
					(size 1.27 1.27)
				)
				(justify mirror)
			)
		)
		(property "Value" ""
			(at 0 0 0)
			(layer "B.Fab")
			(effects
				(font
					(size 1.27 1.27)
				)
				(justify mirror)
			)
		)
		(duplicate_pad_numbers_are_jumpers no)
		(fp_line
			(start 0.7874 0.4064)
			(end 0.7874 -0.4064)
			(stroke
				(width 0.1524)
				(type default)
			)
			(layer "B.SilkS")
		)
		(fp_line
			(start 0.7874 -0.4064)
			(end -0.7874 -0.4064)
			(stroke
				(width 0.1524)
				(type default)
			)
			(layer "B.SilkS")
		)
		(fp_line
			(start -0.7874 0.4064)
			(end 0.7874 0.4064)
			(stroke
				(width 0.1524)
				(type default)
			)
			(layer "B.SilkS")
		)
		(fp_line
			(start -0.7874 -0.4064)
			(end -0.7874 0.4064)
			(stroke
				(width 0.1524)
				(type default)
			)
			(layer "B.SilkS")
		)
		(fp_line
			(start 0.67945 0.3048)
			(end 0.67945 -0.305054)
			(stroke
				(width 0.1)
				(type default)
			)
			(layer "B.Fab")
		)
		(fp_line
			(start 0.67945 -0.305054)
			(end 0.12065 -0.305054)
			(stroke
				(width 0.1)
				(type default)
			)
			(layer "B.Fab")
		)
		(fp_line
			(start 0.12065 0.3048)
			(end 0.67945 0.3048)
			(stroke
				(width 0.1)
				(type default)
			)
			(layer "B.Fab")
		)
		(fp_line
			(start 0.12065 0.2794)
			(end 0.12065 0.3048)
			(stroke
				(width 0.1)
				(type default)
			)
			(layer "B.Fab")
		)
		(fp_line
			(start 0.12065 -0.2794)
			(end -0.12065 -0.2794)
			(stroke
				(width 0.1)
				(type default)
			)
			(layer "B.Fab")
		)
		(fp_line
			(start 0.12065 -0.305054)
			(end 0.12065 -0.2794)
			(stroke
				(width 0.1)
				(type default)
			)
			(layer "B.Fab")
		)
		(fp_line
			(start -0.120396 0.3048)
			(end -0.120396 0.2794)
			(stroke
				(width 0.1)
				(type default)
			)
			(layer "B.Fab")
		)
		(fp_line
			(start -0.120396 0.2794)
			(end 0.12065 0.2794)
			(stroke
				(width 0.1)
				(type default)
			)
			(layer "B.Fab")
		)
		(fp_line
			(start -0.12065 -0.2794)
			(end -0.12065 -0.3048)
			(stroke
				(width 0.1)
				(type default)
			)
			(layer "B.Fab")
		)
		(fp_line
			(start -0.12065 -0.3048)
			(end -0.67945 -0.3048)
			(stroke
				(width 0.1)
				(type default)
			)
			(layer "B.Fab")
		)
		(fp_line
			(start -0.67945 0.3048)
			(end -0.120396 0.3048)
			(stroke
				(width 0.1)
				(type default)
			)
			(layer "B.Fab")
		)
		(fp_line
			(start -0.67945 -0.3048)
			(end -0.67945 0.3048)
			(stroke
				(width 0.1)
				(type default)
			)
			(layer "B.Fab")
		)
		(pad "1" smd circle
			(at 0.40005 0)
			(size 0 0)
			(layers "B.Cu" "B.Mask" "B.Paste")
			(net "P1V8_CPU0_RT_1D_ADC")
		)
		(pad "2" smd circle
			(at -0.40005 0)
			(size 0 0)
			(layers "B.Cu" "B.Mask" "B.Paste")
			(net "GND")
		)
	)
	(footprint ""
		(layer "B.Cu")
		(at 79.225648 -182.656734 -90)
		(property "Reference" "PC268_1"
			(at 0 0 90)
			(layer "B.SilkS")
			(hide yes)
			(effects
				(font
					(size 1.27 1.27)
				)
				(justify mirror)
			)
		)
		(property "Value" ""
			(at 0 0 90)
			(layer "B.Fab")
			(effects
				(font
					(size 1.27 1.27)
				)
				(justify mirror)
			)
		)
		(duplicate_pad_numbers_are_jumpers no)
		(fp_line
			(start -1.524 0.762)
			(end 1.524 0.762)
			(stroke
				(width 0.1524)
				(type default)
			)
			(layer "B.SilkS")
		)
		(fp_line
			(start 1.524 0.762)
			(end 1.524 -0.762)
			(stroke
				(width 0.1524)
				(type default)
			)
			(layer "B.SilkS")
		)
		(fp_line
			(start -1.524 -0.762)
			(end -1.524 0.762)
			(stroke
				(width 0.1524)
				(type default)
			)
			(layer "B.SilkS")
		)
		(fp_line
			(start 1.524 -0.762)
			(end -1.524 -0.762)
			(stroke
				(width 0.1524)
				(type default)
			)
			(layer "B.SilkS")
		)
		(fp_line
			(start -1.1049 0.724916)
			(end -1.1049 -0.724916)
			(stroke
				(width 0.1)
				(type default)
			)
			(layer "B.Fab")
		)
		(fp_line
			(start 1.1049 0.724916)
			(end -1.1049 0.724916)
			(stroke
				(width 0.1)
				(type default)
			)
			(layer "B.Fab")
		)
		(fp_line
			(start -1.1049 -0.724916)
			(end 1.1049 -0.724916)
			(stroke
				(width 0.1)
				(type default)
			)
			(layer "B.Fab")
		)
		(fp_line
			(start 1.1049 -0.724916)
			(end 1.1049 0.724916)
			(stroke
				(width 0.1)
				(type default)
			)
			(layer "B.Fab")
		)
		(pad "1" smd rect
			(at 0.889 0 270)
			(size 1.016 1.27)
			(layers "B.Cu" "B.Mask" "B.Paste")
			(net "SW_P12V_AUX_PVDDCR_CPU0_P1_FLT")
		)
		(pad "2" smd rect
			(at -0.889 0 270)
			(size 1.016 1.27)
			(layers "B.Cu" "B.Mask" "B.Paste")
			(net "GND")
		)
	)
	(footprint ""
		(layer "B.Cu")
		(at 52.74564 -424.225212 -90)
		(property "Reference" "R2935"
			(at 0 0 90)
			(layer "B.SilkS")
			(hide yes)
			(effects
				(font
					(size 1.27 1.27)
				)
				(justify mirror)
			)
		)
		(property "Value" ""
			(at 0 0 90)
			(layer "B.Fab")
			(effects
				(font
					(size 1.27 1.27)
				)
				(justify mirror)
			)
		)
		(duplicate_pad_numbers_are_jumpers no)
		(fp_line
			(start -0.7874 0.4064)
			(end 0.7874 0.4064)
			(stroke
				(width 0.1524)
				(type default)
			)
			(layer "B.SilkS")
		)
		(fp_line
			(start 0.7874 0.4064)
			(end 0.7874 -0.4064)
			(stroke
				(width 0.1524)
				(type default)
			)
			(layer "B.SilkS")
		)
		(fp_line
			(start -0.7874 -0.4064)
			(end -0.7874 0.4064)
			(stroke
				(width 0.1524)
				(type default)
			)
			(layer "B.SilkS")
		)
		(fp_line
			(start 0.7874 -0.4064)
			(end -0.7874 -0.4064)
			(stroke
				(width 0.1524)
				(type default)
			)
			(layer "B.SilkS")
		)
		(fp_line
			(start -0.67945 0.3048)
			(end -0.120396 0.3048)
			(stroke
				(width 0.1)
				(type default)
			)
			(layer "B.Fab")
		)
		(fp_line
			(start -0.120396 0.3048)
			(end -0.120396 0.2794)
			(stroke
				(width 0.1)
				(type default)
			)
			(layer "B.Fab")
		)
		(fp_line
			(start 0.12065 0.3048)
			(end 0.67945 0.3048)
			(stroke
				(width 0.1)
				(type default)
			)
			(layer "B.Fab")
		)
		(fp_line
			(start 0.67945 0.3048)
			(end 0.67945 -0.305054)
			(stroke
				(width 0.1)
				(type default)
			)
			(layer "B.Fab")
		)
		(fp_line
			(start -0.120396 0.2794)
			(end 0.12065 0.2794)
			(stroke
				(width 0.1)
				(type default)
			)
			(layer "B.Fab")
		)
		(fp_line
			(start 0.12065 0.2794)
			(end 0.12065 0.3048)
			(stroke
				(width 0.1)
				(type default)
			)
			(layer "B.Fab")
		)
		(fp_line
			(start -0.12065 -0.2794)
			(end -0.12065 -0.3048)
			(stroke
				(width 0.1)
				(type default)
			)
			(layer "B.Fab")
		)
		(fp_line
			(start 0.12065 -0.2794)
			(end -0.12065 -0.2794)
			(stroke
				(width 0.1)
				(type default)
			)
			(layer "B.Fab")
		)
		(fp_line
			(start -0.67945 -0.3048)
			(end -0.67945 0.3048)
			(stroke
				(width 0.1)
				(type default)
			)
			(layer "B.Fab")
		)
		(fp_line
			(start -0.12065 -0.3048)
			(end -0.67945 -0.3048)
			(stroke
				(width 0.1)
				(type default)
			)
			(layer "B.Fab")
		)
		(fp_line
			(start 0.12065 -0.305054)
			(end 0.12065 -0.2794)
			(stroke
				(width 0.1)
				(type default)
			)
			(layer "B.Fab")
		)
		(fp_line
			(start 0.67945 -0.305054)
			(end 0.12065 -0.305054)
			(stroke
				(width 0.1)
				(type default)
			)
			(layer "B.Fab")
		)
		(pad "1" smd circle
			(at 0.40005 0 90)
			(size 0 0)
			(layers "B.Cu" "B.Mask" "B.Paste")
			(net "P3V3_AUX")
		)
		(pad "2" smd circle
			(at -0.40005 0 90)
			(size 0 0)
			(layers "B.Cu" "B.Mask" "B.Paste")
			(net "FM_GPU_PWRGD_ISO")
		)
	)
	(footprint ""
		(layer "B.Cu")
		(at 142.2908 -13.763752 90)
		(property "Reference" "R6032"
			(at 0 0 90)
			(layer "B.SilkS")
			(hide yes)
			(effects
				(font
					(size 1.27 1.27)
				)
				(justify mirror)
			)
		)
		(property "Value" ""
			(at 0 0 90)
			(layer "B.Fab")
			(effects
				(font
					(size 1.27 1.27)
				)
				(justify mirror)
			)
		)
		(duplicate_pad_numbers_are_jumpers no)
		(fp_line
			(start 0.7874 -0.4064)
			(end -0.7874 -0.4064)
			(stroke
				(width 0.1524)
				(type default)
			)
			(layer "B.SilkS")
		)
		(fp_line
			(start -0.7874 -0.4064)
			(end -0.7874 0.4064)
			(stroke
				(width 0.1524)
				(type default)
			)
			(layer "B.SilkS")
		)
		(fp_line
			(start 0.7874 0.4064)
			(end 0.7874 -0.4064)
			(stroke
				(width 0.1524)
				(type default)
			)
			(layer "B.SilkS")
		)
		(fp_line
			(start -0.7874 0.4064)
			(end 0.7874 0.4064)
			(stroke
				(width 0.1524)
				(type default)
			)
			(layer "B.SilkS")
		)
		(fp_line
			(start 0.67945 -0.305054)
			(end 0.12065 -0.305054)
			(stroke
				(width 0.1)
				(type default)
			)
			(layer "B.Fab")
		)
		(fp_line
			(start 0.12065 -0.305054)
			(end 0.12065 -0.2794)
			(stroke
				(width 0.1)
				(type default)
			)
			(layer "B.Fab")
		)
		(fp_line
			(start -0.12065 -0.3048)
			(end -0.67945 -0.3048)
			(stroke
				(width 0.1)
				(type default)
			)
			(layer "B.Fab")
		)
		(fp_line
			(start -0.67945 -0.3048)
			(end -0.67945 0.3048)
			(stroke
				(width 0.1)
				(type default)
			)
			(layer "B.Fab")
		)
		(fp_line
			(start 0.12065 -0.2794)
			(end -0.12065 -0.2794)
			(stroke
				(width 0.1)
				(type default)
			)
			(layer "B.Fab")
		)
		(fp_line
			(start -0.12065 -0.2794)
			(end -0.12065 -0.3048)
			(stroke
				(width 0.1)
				(type default)
			)
			(layer "B.Fab")
		)
		(fp_line
			(start 0.12065 0.2794)
			(end 0.12065 0.3048)
			(stroke
				(width 0.1)
				(type default)
			)
			(layer "B.Fab")
		)
		(fp_line
			(start -0.120396 0.2794)
			(end 0.12065 0.2794)
			(stroke
				(width 0.1)
				(type default)
			)
			(layer "B.Fab")
		)
		(fp_line
			(start 0.67945 0.3048)
			(end 0.67945 -0.305054)
			(stroke
				(width 0.1)
				(type default)
			)
			(layer "B.Fab")
		)
		(fp_line
			(start 0.12065 0.3048)
			(end 0.67945 0.3048)
			(stroke
				(width 0.1)
				(type default)
			)
			(layer "B.Fab")
		)
		(fp_line
			(start -0.120396 0.3048)
			(end -0.120396 0.2794)
			(stroke
				(width 0.1)
				(type default)
			)
			(layer "B.Fab")
		)
		(fp_line
			(start -0.67945 0.3048)
			(end -0.120396 0.3048)
			(stroke
				(width 0.1)
				(type default)
			)
			(layer "B.Fab")
		)
		(pad "1" smd circle
			(at 0.40005 0 270)
			(size 0 0)
			(layers "B.Cu" "B.Mask" "B.Paste")
			(net "JTAG_SCM_DBREQ_N")
		)
		(pad "2" smd circle
			(at -0.40005 0 270)
			(size 0 0)
			(layers "B.Cu" "B.Mask" "B.Paste")
			(net "SCM_HDT_DBREQ_N")
		)
	)
	(footprint ""
		(layer "B.Cu")
		(at 122.745754 -161.411412 90)
		(property "Reference" "PC328_2"
			(at 0 0 90)
			(layer "B.SilkS")
			(hide yes)
			(effects
				(font
					(size 1.27 1.27)
				)
				(justify mirror)
			)
		)
		(property "Value" ""
			(at 0 0 90)
			(layer "B.Fab")
			(effects
				(font
					(size 1.27 1.27)
				)
				(justify mirror)
			)
		)
		(duplicate_pad_numbers_are_jumpers no)
		(fp_line
			(start 1.524 -0.762)
			(end -1.524 -0.762)
			(stroke
				(width 0.1524)
				(type default)
			)
			(layer "B.SilkS")
		)
		(fp_line
			(start -1.524 -0.762)
			(end -1.524 0.762)
			(stroke
				(width 0.1524)
				(type default)
			)
			(layer "B.SilkS")
		)
		(fp_line
			(start 1.524 0.762)
			(end 1.524 -0.762)
			(stroke
				(width 0.1524)
				(type default)
			)
			(layer "B.SilkS")
		)
		(fp_line
			(start -1.524 0.762)
			(end 1.524 0.762)
			(stroke
				(width 0.1524)
				(type default)
			)
			(layer "B.SilkS")
		)
		(fp_line
			(start 1.1049 -0.724916)
			(end 1.1049 0.724916)
			(stroke
				(width 0.1)
				(type default)
			)
			(layer "B.Fab")
		)
		(fp_line
			(start -1.1049 -0.724916)
			(end 1.1049 -0.724916)
			(stroke
				(width 0.1)
				(type default)
			)
			(layer "B.Fab")
		)
		(fp_line
			(start 1.1049 0.724916)
			(end -1.1049 0.724916)
			(stroke
				(width 0.1)
				(type default)
			)
			(layer "B.Fab")
		)
		(fp_line
			(start -1.1049 0.724916)
			(end -1.1049 -0.724916)
			(stroke
				(width 0.1)
				(type default)
			)
			(layer "B.Fab")
		)
		(pad "1" smd rect
			(at 0.889 0 90)
			(size 1.016 1.27)
			(layers "B.Cu" "B.Mask" "B.Paste")
			(net "SW_P12V_AUX_PVDDCR_SOC_P1_FLT")
		)
		(pad "2" smd rect
			(at -0.889 0 90)
			(size 1.016 1.27)
			(layers "B.Cu" "B.Mask" "B.Paste")
			(net "GND")
		)
	)
	(footprint ""
		(layer "B.Cu")
		(at 197.523608 -104.481376)
		(property "Reference" "R230"
			(at 0 0 0)
			(layer "B.SilkS")
			(hide yes)
			(effects
				(font
					(size 1.27 1.27)
				)
				(justify mirror)
			)
		)
		(property "Value" ""
			(at 0 0 0)
			(layer "B.Fab")
			(effects
				(font
					(size 1.27 1.27)
				)
				(justify mirror)
			)
		)
		(duplicate_pad_numbers_are_jumpers no)
		(fp_line
			(start -0.7874 -0.4064)
			(end -0.7874 0.4064)
			(stroke
				(width 0.1524)
				(type default)
			)
			(layer "B.SilkS")
		)
		(fp_line
			(start -0.7874 0.4064)
			(end 0.7874 0.4064)
			(stroke
				(width 0.1524)
				(type default)
			)
			(layer "B.SilkS")
		)
		(fp_line
			(start 0.7874 -0.4064)
			(end -0.7874 -0.4064)
			(stroke
				(width 0.1524)
				(type default)
			)
			(layer "B.SilkS")
		)
		(fp_line
			(start 0.7874 0.4064)
			(end 0.7874 -0.4064)
			(stroke
				(width 0.1524)
				(type default)
			)
			(layer "B.SilkS")
		)
		(fp_line
			(start -0.67945 -0.3048)
			(end -0.67945 0.3048)
			(stroke
				(width 0.1)
				(type default)
			)
			(layer "B.Fab")
		)
		(fp_line
			(start -0.67945 0.3048)
			(end -0.120396 0.3048)
			(stroke
				(width 0.1)
				(type default)
			)
			(layer "B.Fab")
		)
		(fp_line
			(start -0.12065 -0.3048)
			(end -0.67945 -0.3048)
			(stroke
				(width 0.1)
				(type default)
			)
			(layer "B.Fab")
		)
		(fp_line
			(start -0.12065 -0.2794)
			(end -0.12065 -0.3048)
			(stroke
				(width 0.1)
				(type default)
			)
			(layer "B.Fab")
		)
		(fp_line
			(start -0.120396 0.2794)
			(end 0.12065 0.2794)
			(stroke
				(width 0.1)
				(type default)
			)
			(layer "B.Fab")
		)
		(fp_line
			(start -0.120396 0.3048)
			(end -0.120396 0.2794)
			(stroke
				(width 0.1)
				(type default)
			)
			(layer "B.Fab")
		)
		(fp_line
			(start 0.12065 -0.305054)
			(end 0.12065 -0.2794)
			(stroke
				(width 0.1)
				(type default)
			)
			(layer "B.Fab")
		)
		(fp_line
			(start 0.12065 -0.2794)
			(end -0.12065 -0.2794)
			(stroke
				(width 0.1)
				(type default)
			)
			(layer "B.Fab")
		)
		(fp_line
			(start 0.12065 0.2794)
			(end 0.12065 0.3048)
			(stroke
				(width 0.1)
				(type default)
			)
			(layer "B.Fab")
		)
		(fp_line
			(start 0.12065 0.3048)
			(end 0.67945 0.3048)
			(stroke
				(width 0.1)
				(type default)
			)
			(layer "B.Fab")
		)
		(fp_line
			(start 0.67945 -0.305054)
			(end 0.12065 -0.305054)
			(stroke
				(width 0.1)
				(type default)
			)
			(layer "B.Fab")
		)
		(fp_line
			(start 0.67945 0.3048)
			(end 0.67945 -0.305054)
			(stroke
				(width 0.1)
				(type default)
			)
			(layer "B.Fab")
		)
		(pad "1" smd circle
			(at 0.40005 0 180)
			(size 0 0)
			(layers "B.Cu" "B.Mask" "B.Paste")
			(net "PWRGD_PVDDIO_P0")
		)
		(pad "2" smd circle
			(at -0.40005 0 180)
			(size 0 0)
			(layers "B.Cu" "B.Mask" "B.Paste")
			(net "FM_PWRGD_PVDDIO_P0")
		)
	)
	(footprint ""
		(layer "B.Cu")
		(at 101.385878 -143.61541 180)
		(property "Reference" "PC250"
			(at 0 0 0)
			(layer "B.SilkS")
			(hide yes)
			(effects
				(font
					(size 1.27 1.27)
				)
				(justify mirror)
			)
		)
		(property "Value" ""
			(at 0 0 0)
			(layer "B.Fab")
			(effects
				(font
					(size 1.27 1.27)
				)
				(justify mirror)
			)
		)
		(duplicate_pad_numbers_are_jumpers no)
		(fp_line
			(start 0.7874 0.4064)
			(end 0.7874 -0.4064)
			(stroke
				(width 0.1524)
				(type default)
			)
			(layer "B.SilkS")
		)
		(fp_line
			(start 0.7874 -0.4064)
			(end -0.7874 -0.4064)
			(stroke
				(width 0.1524)
				(type default)
			)
			(layer "B.SilkS")
		)
		(fp_line
			(start -0.7874 0.4064)
			(end 0.7874 0.4064)
			(stroke
				(width 0.1524)
				(type default)
			)
			(layer "B.SilkS")
		)
		(fp_line
			(start -0.7874 -0.4064)
			(end -0.7874 0.4064)
			(stroke
				(width 0.1524)
				(type default)
			)
			(layer "B.SilkS")
		)
		(fp_line
			(start 0.67945 0.3048)
			(end 0.67945 -0.305054)
			(stroke
				(width 0.1)
				(type default)
			)
			(layer "B.Fab")
		)
		(fp_line
			(start 0.67945 -0.305054)
			(end 0.12065 -0.305054)
			(stroke
				(width 0.1)
				(type default)
			)
			(layer "B.Fab")
		)
		(fp_line
			(start 0.12065 0.3048)
			(end 0.67945 0.3048)
			(stroke
				(width 0.1)
				(type default)
			)
			(layer "B.Fab")
		)
		(fp_line
			(start 0.12065 0.2794)
			(end 0.12065 0.3048)
			(stroke
				(width 0.1)
				(type default)
			)
			(layer "B.Fab")
		)
		(fp_line
			(start 0.12065 -0.2794)
			(end -0.12065 -0.2794)
			(stroke
				(width 0.1)
				(type default)
			)
			(layer "B.Fab")
		)
		(fp_line
			(start 0.12065 -0.305054)
			(end 0.12065 -0.2794)
			(stroke
				(width 0.1)
				(type default)
			)
			(layer "B.Fab")
		)
		(fp_line
			(start -0.120396 0.3048)
			(end -0.120396 0.2794)
			(stroke
				(width 0.1)
				(type default)
			)
			(layer "B.Fab")
		)
		(fp_line
			(start -0.120396 0.2794)
			(end 0.12065 0.2794)
			(stroke
				(width 0.1)
				(type default)
			)
			(layer "B.Fab")
		)
		(fp_line
			(start -0.12065 -0.2794)
			(end -0.12065 -0.3048)
			(stroke
				(width 0.1)
				(type default)
			)
			(layer "B.Fab")
		)
		(fp_line
			(start -0.12065 -0.3048)
			(end -0.67945 -0.3048)
			(stroke
				(width 0.1)
				(type default)
			)
			(layer "B.Fab")
		)
		(fp_line
			(start -0.67945 0.3048)
			(end -0.120396 0.3048)
			(stroke
				(width 0.1)
				(type default)
			)
			(layer "B.Fab")
		)
		(fp_line
			(start -0.67945 -0.3048)
			(end -0.67945 0.3048)
			(stroke
				(width 0.1)
				(type default)
			)
			(layer "B.Fab")
		)
		(pad "1" smd circle
			(at 0.40005 0)
			(size 0 0)
			(layers "B.Cu" "B.Mask" "B.Paste")
			(net "PVDDCR_CPU0_P1_TEMP0")
		)
		(pad "2" smd circle
			(at -0.40005 0)
			(size 0 0)
			(layers "B.Cu" "B.Mask" "B.Paste")
			(net "GND")
		)
	)
	(footprint ""
		(layer "B.Cu")
		(at 419.263322 -416.899344 90)
		(property "Reference" "C6627"
			(at 0 0 90)
			(layer "B.SilkS")
			(hide yes)
			(effects
				(font
					(size 1.27 1.27)
				)
				(justify mirror)
			)
		)
		(property "Value" ""
			(at 0 0 90)
			(layer "B.Fab")
			(effects
				(font
					(size 1.27 1.27)
				)
				(justify mirror)
			)
		)
		(duplicate_pad_numbers_are_jumpers no)
		(fp_line
			(start 0.299974 -0.150114)
			(end -0.299974 -0.150114)
			(stroke
				(width 0.1)
				(type default)
			)
			(layer "B.Fab")
		)
		(fp_line
			(start -0.299974 -0.150114)
			(end -0.299974 0.150114)
			(stroke
				(width 0.1)
				(type default)
			)
			(layer "B.Fab")
		)
		(fp_line
			(start 0.299974 0.150114)
			(end 0.299974 -0.150114)
			(stroke
				(width 0.1)
				(type default)
			)
			(layer "B.Fab")
		)
		(fp_line
			(start -0.299974 0.150114)
			(end 0.299974 0.150114)
			(stroke
				(width 0.1)
				(type default)
			)
			(layer "B.Fab")
		)
		(pad "1" smd rect
			(at 0.2667 0 270)
			(size 0.3048 0.381)
			(layers "B.Cu" "B.Mask" "B.Paste")
			(net "P5E_CPU0_P3_TX_BUF_C_DP<15>")
		)
		(pad "2" smd rect
			(at -0.2667 0 270)
			(size 0.3048 0.381)
			(layers "B.Cu" "B.Mask" "B.Paste")
			(net "P5E_CPU0_P3_TX_BUF_DP<15>")
		)
	)
	(footprint ""
		(layer "B.Cu")
		(at 520.044426 -147.962874 90)
		(property "Reference" "X5"
			(at 0.989076 2.861564 270)
			(unlocked yes)
			(layer "B.SilkS")
			(effects
				(font
					(size 0.7874 0.5842)
					(thickness 0.1524)
				)
				(justify left mirror)
			)
		)
		(property "Value" ""
			(at 0 0 90)
			(layer "B.Fab")
			(effects
				(font
					(size 1.27 1.27)
				)
				(justify mirror)
			)
		)
		(property "Device Type" "TP_TDR_4P_FTS_TH-TP_TDR_4P_DIP,EMPTY,TP15"
			(at -1.30175 1.27 0)
			(unlocked yes)
			(layer "B.Fab")
			(hide yes)
			(effects
				(font
					(size 0.635 0.4064)
					(thickness 0.1524)
				)
				(justify mirror)
			)
		)
		(property "User Part Number" "N_A"
			(at -1.30175 1.27 0)
			(unlocked yes)
			(layer "Cmts.User")
			(hide yes)
			(effects
				(font
					(size 0.635 0.4064)
					(thickness 0.1524)
				)
				(justify mirror)
			)
		)
		(duplicate_pad_numbers_are_jumpers no)
		(fp_line
			(start 0 -1.27)
			(end 0 -0.635)
			(stroke
				(width 0.1524)
				(type default)
			)
			(layer "B.SilkS")
		)
		(fp_line
			(start -2.54 -1.27)
			(end 0 -1.27)
			(stroke
				(width 0.1524)
				(type default)
			)
			(layer "B.SilkS")
		)
		(fp_line
			(start -2.54 -1.1303)
			(end -2.54 -1.27)
			(stroke
				(width 0.1524)
				(type default)
			)
			(layer "B.SilkS")
		)
		(fp_line
			(start 0 0.635)
			(end 0 1.905)
			(stroke
				(width 0.1524)
				(type default)
			)
			(layer "B.SilkS")
		)
		(fp_line
			(start -2.54 1.4097)
			(end -2.54 1.1303)
			(stroke
				(width 0.1524)
				(type default)
			)
			(layer "B.SilkS")
		)
		(fp_line
			(start 0 3.175)
			(end 0 3.81)
			(stroke
				(width 0.1524)
				(type default)
			)
			(layer "B.SilkS")
		)
		(fp_line
			(start 0 3.81)
			(end -2.54 3.81)
			(stroke
				(width 0.1524)
				(type default)
			)
			(layer "B.SilkS")
		)
		(fp_line
			(start -2.54 3.81)
			(end -2.54 3.6703)
			(stroke
				(width 0.1524)
				(type default)
			)
			(layer "B.SilkS")
		)
		(fp_poly
			(pts
				(xy 2.285746 -0.762) (xy 2.285746 0.762) (xy 0.761746 0)
			)
			(stroke
				(width 0)
				(type default)
			)
			(fill yes)
			(layer "B.SilkS")
		)
		(fp_line
			(start 0 -1.27)
			(end 0 3.81)
			(stroke
				(width 0.1)
				(type default)
			)
			(layer "B.Fab")
		)
		(fp_line
			(start -2.54 -1.27)
			(end 0 -1.27)
			(stroke
				(width 0.1)
				(type default)
			)
			(layer "B.Fab")
		)
		(fp_line
			(start 0 3.81)
			(end -2.54 3.81)
			(stroke
				(width 0.1)
				(type default)
			)
			(layer "B.Fab")
		)
		(fp_line
			(start -2.54 3.81)
			(end -2.54 -1.27)
			(stroke
				(width 0.1)
				(type default)
			)
			(layer "B.Fab")
		)
		(fp_poly
			(pts
				(xy 0.761746 0) (xy 2.285746 -0.762) (xy 2.285746 0.762)
			)
			(stroke
				(width 0)
				(type default)
			)
			(fill yes)
			(layer "B.Fab")
		)
		(pad "1" thru_hole circle
			(at 0 0 270)
			(size 1.0033 1.0033)
			(drill 0.249936)
			(layers "*.Cu" "*.Mask")
			(remove_unused_layers no)
			(net "TDR_DIFF_80_IN4_DP")
			(clearance 0.10795)
			(padstack
				(mode front_inner_back)
				(layer "Inner"
					(shape circle)
					(size 0.8001 0.8001)
					(clearance 0.1524)
				)
				(layer "B.Cu"
					(shape circle)
					(size 1.0033 1.0033)
					(thermal_gap 0.10795)
					(clearance 0.10795)
				)
			)
		)
		(pad "2" thru_hole circle
			(at -2.54 0 270)
			(size 1.9939 1.9939)
			(drill 0.249936)
			(layers "*.Cu" "*.Mask")
			(remove_unused_layers no)
			(net "T1_GND")
			(clearance 0.10795)
			(padstack
				(mode front_inner_back)
				(layer "Inner"
					(shape circle)
					(size 0.8001 0.8001)
					(clearance 0.1524)
				)
				(layer "B.Cu"
					(shape circle)
					(size 1.9939 1.9939)
					(thermal_gap 0.10795)
					(clearance 0.10795)
				)
			)
		)
		(pad "3" thru_hole circle
			(at -2.54 2.54 270)
			(size 1.9939 1.9939)
			(drill 0.249936)
			(layers "*.Cu" "*.Mask")
			(remove_unused_layers no)
			(net "T1_GND")
			(clearance 0.10795)
			(padstack
				(mode front_inner_back)
				(layer "Inner"
					(shape circle)
					(size 0.8001 0.8001)
					(clearance 0.1524)
				)
				(layer "B.Cu"
					(shape circle)
					(size 1.9939 1.9939)
					(thermal_gap 0.10795)
					(clearance 0.10795)
				)
			)
		)
		(pad "4" thru_hole circle
			(at 0 2.54 270)
			(size 1.0033 1.0033)
			(drill 0.249936)
			(layers "*.Cu" "*.Mask")
			(remove_unused_layers no)
			(net "TDR_DIFF_80_IN4_DN")
			(clearance 0.10795)
			(padstack
				(mode front_inner_back)
				(layer "Inner"
					(shape circle)
					(size 0.8001 0.8001)
					(clearance 0.1524)
				)
				(layer "B.Cu"
					(shape circle)
					(size 1.0033 1.0033)
					(thermal_gap 0.10795)
					(clearance 0.10795)
				)
			)
		)
	)
	(footprint ""
		(layer "B.Cu")
		(at 103.672386 -261.179564 180)
		(property "Reference" "C2467"
			(at 0 0 0)
			(layer "B.SilkS")
			(hide yes)
			(effects
				(font
					(size 1.27 1.27)
				)
				(justify mirror)
			)
		)
		(property "Value" ""
			(at 0 0 0)
			(layer "B.Fab")
			(effects
				(font
					(size 1.27 1.27)
				)
				(justify mirror)
			)
		)
		(duplicate_pad_numbers_are_jumpers no)
		(fp_line
			(start 0.7874 0.4064)
			(end 0.7874 -0.4064)
			(stroke
				(width 0.1524)
				(type default)
			)
			(layer "B.SilkS")
		)
		(fp_line
			(start 0.7874 -0.4064)
			(end -0.7874 -0.4064)
			(stroke
				(width 0.1524)
				(type default)
			)
			(layer "B.SilkS")
		)
		(fp_line
			(start -0.7874 0.4064)
			(end 0.7874 0.4064)
			(stroke
				(width 0.1524)
				(type default)
			)
			(layer "B.SilkS")
		)
		(fp_line
			(start -0.7874 -0.4064)
			(end -0.7874 0.4064)
			(stroke
				(width 0.1524)
				(type default)
			)
			(layer "B.SilkS")
		)
		(fp_line
			(start 0.67945 0.3048)
			(end 0.67945 -0.305054)
			(stroke
				(width 0.1)
				(type default)
			)
			(layer "B.Fab")
		)
		(fp_line
			(start 0.67945 -0.305054)
			(end 0.12065 -0.305054)
			(stroke
				(width 0.1)
				(type default)
			)
			(layer "B.Fab")
		)
		(fp_line
			(start 0.12065 0.3048)
			(end 0.67945 0.3048)
			(stroke
				(width 0.1)
				(type default)
			)
			(layer "B.Fab")
		)
		(fp_line
			(start 0.12065 0.2794)
			(end 0.12065 0.3048)
			(stroke
				(width 0.1)
				(type default)
			)
			(layer "B.Fab")
		)
		(fp_line
			(start 0.12065 -0.2794)
			(end -0.12065 -0.2794)
			(stroke
				(width 0.1)
				(type default)
			)
			(layer "B.Fab")
		)
		(fp_line
			(start 0.12065 -0.305054)
			(end 0.12065 -0.2794)
			(stroke
				(width 0.1)
				(type default)
			)
			(layer "B.Fab")
		)
		(fp_line
			(start -0.120396 0.3048)
			(end -0.120396 0.2794)
			(stroke
				(width 0.1)
				(type default)
			)
			(layer "B.Fab")
		)
		(fp_line
			(start -0.120396 0.2794)
			(end 0.12065 0.2794)
			(stroke
				(width 0.1)
				(type default)
			)
			(layer "B.Fab")
		)
		(fp_line
			(start -0.12065 -0.2794)
			(end -0.12065 -0.3048)
			(stroke
				(width 0.1)
				(type default)
			)
			(layer "B.Fab")
		)
		(fp_line
			(start -0.12065 -0.3048)
			(end -0.67945 -0.3048)
			(stroke
				(width 0.1)
				(type default)
			)
			(layer "B.Fab")
		)
		(fp_line
			(start -0.67945 0.3048)
			(end -0.120396 0.3048)
			(stroke
				(width 0.1)
				(type default)
			)
			(layer "B.Fab")
		)
		(fp_line
			(start -0.67945 -0.3048)
			(end -0.67945 0.3048)
			(stroke
				(width 0.1)
				(type default)
			)
			(layer "B.Fab")
		)
		(pad "1" smd circle
			(at 0.40005 0)
			(size 0 0)
			(layers "B.Cu" "B.Mask" "B.Paste")
			(net "PVDDCR_SOC_P1")
		)
		(pad "2" smd circle
			(at -0.40005 0)
			(size 0 0)
			(layers "B.Cu" "B.Mask" "B.Paste")
			(net "GND")
		)
	)
	(footprint ""
		(layer "B.Cu")
		(at 415.006282 -395.148562 90)
		(property "Reference" "C789"
			(at 0 0 90)
			(layer "B.SilkS")
			(hide yes)
			(effects
				(font
					(size 1.27 1.27)
				)
				(justify mirror)
			)
		)
		(property "Value" ""
			(at 0 0 90)
			(layer "B.Fab")
			(effects
				(font
					(size 1.27 1.27)
				)
				(justify mirror)
			)
		)
		(duplicate_pad_numbers_are_jumpers no)
		(fp_line
			(start 0.299974 -0.150114)
			(end -0.299974 -0.150114)
			(stroke
				(width 0.1)
				(type default)
			)
			(layer "B.Fab")
		)
		(fp_line
			(start -0.299974 -0.150114)
			(end -0.299974 0.150114)
			(stroke
				(width 0.1)
				(type default)
			)
			(layer "B.Fab")
		)
		(fp_line
			(start 0.299974 0.150114)
			(end 0.299974 -0.150114)
			(stroke
				(width 0.1)
				(type default)
			)
			(layer "B.Fab")
		)
		(fp_line
			(start -0.299974 0.150114)
			(end 0.299974 0.150114)
			(stroke
				(width 0.1)
				(type default)
			)
			(layer "B.Fab")
		)
		(pad "1" smd rect
			(at 0.2667 0 270)
			(size 0.3048 0.381)
			(layers "B.Cu" "B.Mask" "B.Paste")
			(net "P0V9_CPU0_RT_2D")
		)
		(pad "2" smd rect
			(at -0.2667 0 270)
			(size 0.3048 0.381)
			(layers "B.Cu" "B.Mask" "B.Paste")
			(net "GND")
		)
	)
	(footprint ""
		(layer "B.Cu")
		(at 93.246194 -388.011162 -90)
		(property "Reference" "C316"
			(at 0 0 90)
			(layer "B.SilkS")
			(hide yes)
			(effects
				(font
					(size 1.27 1.27)
				)
				(justify mirror)
			)
		)
		(property "Value" ""
			(at 0 0 90)
			(layer "B.Fab")
			(effects
				(font
					(size 1.27 1.27)
				)
				(justify mirror)
			)
		)
		(duplicate_pad_numbers_are_jumpers no)
		(fp_line
			(start -0.299974 0.150114)
			(end 0.299974 0.150114)
			(stroke
				(width 0.1)
				(type default)
			)
			(layer "B.Fab")
		)
		(fp_line
			(start 0.299974 0.150114)
			(end 0.299974 -0.150114)
			(stroke
				(width 0.1)
				(type default)
			)
			(layer "B.Fab")
		)
		(fp_line
			(start -0.299974 -0.150114)
			(end -0.299974 0.150114)
			(stroke
				(width 0.1)
				(type default)
			)
			(layer "B.Fab")
		)
		(fp_line
			(start 0.299974 -0.150114)
			(end -0.299974 -0.150114)
			(stroke
				(width 0.1)
				(type default)
			)
			(layer "B.Fab")
		)
		(pad "1" smd rect
			(at 0.2667 0 90)
			(size 0.3048 0.381)
			(layers "B.Cu" "B.Mask" "B.Paste")
			(net "P0V9_CPU1_RT1_2A_2D")
		)
		(pad "2" smd rect
			(at -0.2667 0 90)
			(size 0.3048 0.381)
			(layers "B.Cu" "B.Mask" "B.Paste")
			(net "GND")
		)
	)
	(footprint ""
		(layer "B.Cu")
		(at 22.479 -365.76 180)
		(property "Reference" "C5022"
			(at 0 0 0)
			(layer "B.SilkS")
			(hide yes)
			(effects
				(font
					(size 1.27 1.27)
				)
				(justify mirror)
			)
		)
		(property "Value" ""
			(at 0 0 0)
			(layer "B.Fab")
			(effects
				(font
					(size 1.27 1.27)
				)
				(justify mirror)
			)
		)
		(duplicate_pad_numbers_are_jumpers no)
		(fp_line
			(start 0.7874 0.4064)
			(end 0.7874 -0.4064)
			(stroke
				(width 0.1524)
				(type default)
			)
			(layer "B.SilkS")
		)
		(fp_line
			(start 0.7874 -0.4064)
			(end -0.7874 -0.4064)
			(stroke
				(width 0.1524)
				(type default)
			)
			(layer "B.SilkS")
		)
		(fp_line
			(start -0.7874 0.4064)
			(end 0.7874 0.4064)
			(stroke
				(width 0.1524)
				(type default)
			)
			(layer "B.SilkS")
		)
		(fp_line
			(start -0.7874 -0.4064)
			(end -0.7874 0.4064)
			(stroke
				(width 0.1524)
				(type default)
			)
			(layer "B.SilkS")
		)
		(fp_line
			(start 0.67945 0.3048)
			(end 0.67945 -0.305054)
			(stroke
				(width 0.1)
				(type default)
			)
			(layer "B.Fab")
		)
		(fp_line
			(start 0.67945 -0.305054)
			(end 0.12065 -0.305054)
			(stroke
				(width 0.1)
				(type default)
			)
			(layer "B.Fab")
		)
		(fp_line
			(start 0.12065 0.3048)
			(end 0.67945 0.3048)
			(stroke
				(width 0.1)
				(type default)
			)
			(layer "B.Fab")
		)
		(fp_line
			(start 0.12065 0.2794)
			(end 0.12065 0.3048)
			(stroke
				(width 0.1)
				(type default)
			)
			(layer "B.Fab")
		)
		(fp_line
			(start 0.12065 -0.2794)
			(end -0.12065 -0.2794)
			(stroke
				(width 0.1)
				(type default)
			)
			(layer "B.Fab")
		)
		(fp_line
			(start 0.12065 -0.305054)
			(end 0.12065 -0.2794)
			(stroke
				(width 0.1)
				(type default)
			)
			(layer "B.Fab")
		)
		(fp_line
			(start -0.120396 0.3048)
			(end -0.120396 0.2794)
			(stroke
				(width 0.1)
				(type default)
			)
			(layer "B.Fab")
		)
		(fp_line
			(start -0.120396 0.2794)
			(end 0.12065 0.2794)
			(stroke
				(width 0.1)
				(type default)
			)
			(layer "B.Fab")
		)
		(fp_line
			(start -0.12065 -0.2794)
			(end -0.12065 -0.3048)
			(stroke
				(width 0.1)
				(type default)
			)
			(layer "B.Fab")
		)
		(fp_line
			(start -0.12065 -0.3048)
			(end -0.67945 -0.3048)
			(stroke
				(width 0.1)
				(type default)
			)
			(layer "B.Fab")
		)
		(fp_line
			(start -0.67945 0.3048)
			(end -0.120396 0.3048)
			(stroke
				(width 0.1)
				(type default)
			)
			(layer "B.Fab")
		)
		(fp_line
			(start -0.67945 -0.3048)
			(end -0.67945 0.3048)
			(stroke
				(width 0.1)
				(type default)
			)
			(layer "B.Fab")
		)
		(pad "1" smd circle
			(at 0.40005 0)
			(size 0 0)
			(layers "B.Cu" "B.Mask" "B.Paste")
			(net "GND")
		)
		(pad "2" smd circle
			(at -0.40005 0)
			(size 0 0)
			(layers "B.Cu" "B.Mask" "B.Paste")
			(net "PWRGD_PVDDCR_CPU1_P1")
		)
	)
	(footprint ""
		(layer "B.Cu")
		(at 163.819078 -390.560052 90)
		(property "Reference" "C412"
			(at 0 0 90)
			(layer "B.SilkS")
			(hide yes)
			(effects
				(font
					(size 1.27 1.27)
				)
				(justify mirror)
			)
		)
		(property "Value" ""
			(at 0 0 90)
			(layer "B.Fab")
			(effects
				(font
					(size 1.27 1.27)
				)
				(justify mirror)
			)
		)
		(duplicate_pad_numbers_are_jumpers no)
		(fp_line
			(start 0.7874 -0.4064)
			(end -0.7874 -0.4064)
			(stroke
				(width 0.1524)
				(type default)
			)
			(layer "B.SilkS")
		)
		(fp_line
			(start -0.7874 -0.4064)
			(end -0.7874 0.4064)
			(stroke
				(width 0.1524)
				(type default)
			)
			(layer "B.SilkS")
		)
		(fp_line
			(start 0.7874 0.4064)
			(end 0.7874 -0.4064)
			(stroke
				(width 0.1524)
				(type default)
			)
			(layer "B.SilkS")
		)
		(fp_line
			(start -0.7874 0.4064)
			(end 0.7874 0.4064)
			(stroke
				(width 0.1524)
				(type default)
			)
			(layer "B.SilkS")
		)
		(fp_line
			(start 0.67945 -0.305054)
			(end 0.12065 -0.305054)
			(stroke
				(width 0.1)
				(type default)
			)
			(layer "B.Fab")
		)
		(fp_line
			(start 0.12065 -0.305054)
			(end 0.12065 -0.2794)
			(stroke
				(width 0.1)
				(type default)
			)
			(layer "B.Fab")
		)
		(fp_line
			(start -0.12065 -0.3048)
			(end -0.67945 -0.3048)
			(stroke
				(width 0.1)
				(type default)
			)
			(layer "B.Fab")
		)
		(fp_line
			(start -0.67945 -0.3048)
			(end -0.67945 0.3048)
			(stroke
				(width 0.1)
				(type default)
			)
			(layer "B.Fab")
		)
		(fp_line
			(start 0.12065 -0.2794)
			(end -0.12065 -0.2794)
			(stroke
				(width 0.1)
				(type default)
			)
			(layer "B.Fab")
		)
		(fp_line
			(start -0.12065 -0.2794)
			(end -0.12065 -0.3048)
			(stroke
				(width 0.1)
				(type default)
			)
			(layer "B.Fab")
		)
		(fp_line
			(start 0.12065 0.2794)
			(end 0.12065 0.3048)
			(stroke
				(width 0.1)
				(type default)
			)
			(layer "B.Fab")
		)
		(fp_line
			(start -0.120396 0.2794)
			(end 0.12065 0.2794)
			(stroke
				(width 0.1)
				(type default)
			)
			(layer "B.Fab")
		)
		(fp_line
			(start 0.67945 0.3048)
			(end 0.67945 -0.305054)
			(stroke
				(width 0.1)
				(type default)
			)
			(layer "B.Fab")
		)
		(fp_line
			(start 0.12065 0.3048)
			(end 0.67945 0.3048)
			(stroke
				(width 0.1)
				(type default)
			)
			(layer "B.Fab")
		)
		(fp_line
			(start -0.120396 0.3048)
			(end -0.120396 0.2794)
			(stroke
				(width 0.1)
				(type default)
			)
			(layer "B.Fab")
		)
		(fp_line
			(start -0.67945 0.3048)
			(end -0.120396 0.3048)
			(stroke
				(width 0.1)
				(type default)
			)
			(layer "B.Fab")
		)
		(pad "1" smd circle
			(at 0.40005 0 270)
			(size 0 0)
			(layers "B.Cu" "B.Mask" "B.Paste")
			(net "P0V9_CPU1_RT2_2A")
		)
		(pad "2" smd circle
			(at -0.40005 0 270)
			(size 0 0)
			(layers "B.Cu" "B.Mask" "B.Paste")
			(net "GND")
		)
	)
	(footprint ""
		(layer "B.Cu")
		(at 122.10669 -248.479564)
		(property "Reference" "C2315"
			(at 0 0 0)
			(layer "B.SilkS")
			(hide yes)
			(effects
				(font
					(size 1.27 1.27)
				)
				(justify mirror)
			)
		)
		(property "Value" ""
			(at 0 0 0)
			(layer "B.Fab")
			(effects
				(font
					(size 1.27 1.27)
				)
				(justify mirror)
			)
		)
		(duplicate_pad_numbers_are_jumpers no)
		(fp_line
			(start -0.7874 -0.4064)
			(end -0.7874 0.4064)
			(stroke
				(width 0.1524)
				(type default)
			)
			(layer "B.SilkS")
		)
		(fp_line
			(start -0.7874 0.4064)
			(end 0.7874 0.4064)
			(stroke
				(width 0.1524)
				(type default)
			)
			(layer "B.SilkS")
		)
		(fp_line
			(start 0.7874 -0.4064)
			(end -0.7874 -0.4064)
			(stroke
				(width 0.1524)
				(type default)
			)
			(layer "B.SilkS")
		)
		(fp_line
			(start 0.7874 0.4064)
			(end 0.7874 -0.4064)
			(stroke
				(width 0.1524)
				(type default)
			)
			(layer "B.SilkS")
		)
		(fp_line
			(start -0.67945 -0.3048)
			(end -0.67945 0.3048)
			(stroke
				(width 0.1)
				(type default)
			)
			(layer "B.Fab")
		)
		(fp_line
			(start -0.67945 0.3048)
			(end -0.120396 0.3048)
			(stroke
				(width 0.1)
				(type default)
			)
			(layer "B.Fab")
		)
		(fp_line
			(start -0.12065 -0.3048)
			(end -0.67945 -0.3048)
			(stroke
				(width 0.1)
				(type default)
			)
			(layer "B.Fab")
		)
		(fp_line
			(start -0.12065 -0.2794)
			(end -0.12065 -0.3048)
			(stroke
				(width 0.1)
				(type default)
			)
			(layer "B.Fab")
		)
		(fp_line
			(start -0.120396 0.2794)
			(end 0.12065 0.2794)
			(stroke
				(width 0.1)
				(type default)
			)
			(layer "B.Fab")
		)
		(fp_line
			(start -0.120396 0.3048)
			(end -0.120396 0.2794)
			(stroke
				(width 0.1)
				(type default)
			)
			(layer "B.Fab")
		)
		(fp_line
			(start 0.12065 -0.305054)
			(end 0.12065 -0.2794)
			(stroke
				(width 0.1)
				(type default)
			)
			(layer "B.Fab")
		)
		(fp_line
			(start 0.12065 -0.2794)
			(end -0.12065 -0.2794)
			(stroke
				(width 0.1)
				(type default)
			)
			(layer "B.Fab")
		)
		(fp_line
			(start 0.12065 0.2794)
			(end 0.12065 0.3048)
			(stroke
				(width 0.1)
				(type default)
			)
			(layer "B.Fab")
		)
		(fp_line
			(start 0.12065 0.3048)
			(end 0.67945 0.3048)
			(stroke
				(width 0.1)
				(type default)
			)
			(layer "B.Fab")
		)
		(fp_line
			(start 0.67945 -0.305054)
			(end 0.12065 -0.305054)
			(stroke
				(width 0.1)
				(type default)
			)
			(layer "B.Fab")
		)
		(fp_line
			(start 0.67945 0.3048)
			(end 0.67945 -0.305054)
			(stroke
				(width 0.1)
				(type default)
			)
			(layer "B.Fab")
		)
		(pad "1" smd circle
			(at 0.40005 0 180)
			(size 0 0)
			(layers "B.Cu" "B.Mask" "B.Paste")
			(net "PVDDCR_CPU0_P1")
		)
		(pad "2" smd circle
			(at -0.40005 0 180)
			(size 0 0)
			(layers "B.Cu" "B.Mask" "B.Paste")
			(net "GND")
		)
	)
	(footprint ""
		(layer "B.Cu")
		(at 117.895624 -259.355336)
		(property "Reference" "C2420"
			(at 0 0 0)
			(layer "B.SilkS")
			(hide yes)
			(effects
				(font
					(size 1.27 1.27)
				)
				(justify mirror)
			)
		)
		(property "Value" ""
			(at 0 0 0)
			(layer "B.Fab")
			(effects
				(font
					(size 1.27 1.27)
				)
				(justify mirror)
			)
		)
		(duplicate_pad_numbers_are_jumpers no)
		(fp_line
			(start -0.7874 -0.4064)
			(end -0.7874 0.4064)
			(stroke
				(width 0.1524)
				(type default)
			)
			(layer "B.SilkS")
		)
		(fp_line
			(start -0.7874 0.4064)
			(end 0.7874 0.4064)
			(stroke
				(width 0.1524)
				(type default)
			)
			(layer "B.SilkS")
		)
		(fp_line
			(start 0.7874 -0.4064)
			(end -0.7874 -0.4064)
			(stroke
				(width 0.1524)
				(type default)
			)
			(layer "B.SilkS")
		)
		(fp_line
			(start 0.7874 0.4064)
			(end 0.7874 -0.4064)
			(stroke
				(width 0.1524)
				(type default)
			)
			(layer "B.SilkS")
		)
		(fp_line
			(start -0.67945 -0.3048)
			(end -0.67945 0.3048)
			(stroke
				(width 0.1)
				(type default)
			)
			(layer "B.Fab")
		)
		(fp_line
			(start -0.67945 0.3048)
			(end -0.120396 0.3048)
			(stroke
				(width 0.1)
				(type default)
			)
			(layer "B.Fab")
		)
		(fp_line
			(start -0.12065 -0.3048)
			(end -0.67945 -0.3048)
			(stroke
				(width 0.1)
				(type default)
			)
			(layer "B.Fab")
		)
		(fp_line
			(start -0.12065 -0.2794)
			(end -0.12065 -0.3048)
			(stroke
				(width 0.1)
				(type default)
			)
			(layer "B.Fab")
		)
		(fp_line
			(start -0.120396 0.2794)
			(end 0.12065 0.2794)
			(stroke
				(width 0.1)
				(type default)
			)
			(layer "B.Fab")
		)
		(fp_line
			(start -0.120396 0.3048)
			(end -0.120396 0.2794)
			(stroke
				(width 0.1)
				(type default)
			)
			(layer "B.Fab")
		)
		(fp_line
			(start 0.12065 -0.305054)
			(end 0.12065 -0.2794)
			(stroke
				(width 0.1)
				(type default)
			)
			(layer "B.Fab")
		)
		(fp_line
			(start 0.12065 -0.2794)
			(end -0.12065 -0.2794)
			(stroke
				(width 0.1)
				(type default)
			)
			(layer "B.Fab")
		)
		(fp_line
			(start 0.12065 0.2794)
			(end 0.12065 0.3048)
			(stroke
				(width 0.1)
				(type default)
			)
			(layer "B.Fab")
		)
		(fp_line
			(start 0.12065 0.3048)
			(end 0.67945 0.3048)
			(stroke
				(width 0.1)
				(type default)
			)
			(layer "B.Fab")
		)
		(fp_line
			(start 0.67945 -0.305054)
			(end 0.12065 -0.305054)
			(stroke
				(width 0.1)
				(type default)
			)
			(layer "B.Fab")
		)
		(fp_line
			(start 0.67945 0.3048)
			(end 0.67945 -0.305054)
			(stroke
				(width 0.1)
				(type default)
			)
			(layer "B.Fab")
		)
		(pad "1" smd circle
			(at 0.40005 0 180)
			(size 0 0)
			(layers "B.Cu" "B.Mask" "B.Paste")
			(net "PVDDCR_SOC_P1")
		)
		(pad "2" smd circle
			(at -0.40005 0 180)
			(size 0 0)
			(layers "B.Cu" "B.Mask" "B.Paste")
			(net "GND")
		)
	)
	(footprint ""
		(layer "B.Cu")
		(at 406.698958 -328.926952 180)
		(property "Reference" "R445"
			(at 0 0 0)
			(layer "B.SilkS")
			(hide yes)
			(effects
				(font
					(size 1.27 1.27)
				)
				(justify mirror)
			)
		)
		(property "Value" ""
			(at 0 0 0)
			(layer "B.Fab")
			(effects
				(font
					(size 1.27 1.27)
				)
				(justify mirror)
			)
		)
		(duplicate_pad_numbers_are_jumpers no)
		(fp_line
			(start 0.7874 0.4064)
			(end 0.7874 -0.4064)
			(stroke
				(width 0.1524)
				(type default)
			)
			(layer "B.SilkS")
		)
		(fp_line
			(start 0.7874 -0.4064)
			(end -0.7874 -0.4064)
			(stroke
				(width 0.1524)
				(type default)
			)
			(layer "B.SilkS")
		)
		(fp_line
			(start -0.7874 0.4064)
			(end 0.7874 0.4064)
			(stroke
				(width 0.1524)
				(type default)
			)
			(layer "B.SilkS")
		)
		(fp_line
			(start -0.7874 -0.4064)
			(end -0.7874 0.4064)
			(stroke
				(width 0.1524)
				(type default)
			)
			(layer "B.SilkS")
		)
		(fp_line
			(start 0.67945 0.3048)
			(end 0.67945 -0.305054)
			(stroke
				(width 0.1)
				(type default)
			)
			(layer "B.Fab")
		)
		(fp_line
			(start 0.67945 -0.305054)
			(end 0.12065 -0.305054)
			(stroke
				(width 0.1)
				(type default)
			)
			(layer "B.Fab")
		)
		(fp_line
			(start 0.12065 0.3048)
			(end 0.67945 0.3048)
			(stroke
				(width 0.1)
				(type default)
			)
			(layer "B.Fab")
		)
		(fp_line
			(start 0.12065 0.2794)
			(end 0.12065 0.3048)
			(stroke
				(width 0.1)
				(type default)
			)
			(layer "B.Fab")
		)
		(fp_line
			(start 0.12065 -0.2794)
			(end -0.12065 -0.2794)
			(stroke
				(width 0.1)
				(type default)
			)
			(layer "B.Fab")
		)
		(fp_line
			(start 0.12065 -0.305054)
			(end 0.12065 -0.2794)
			(stroke
				(width 0.1)
				(type default)
			)
			(layer "B.Fab")
		)
		(fp_line
			(start -0.120396 0.3048)
			(end -0.120396 0.2794)
			(stroke
				(width 0.1)
				(type default)
			)
			(layer "B.Fab")
		)
		(fp_line
			(start -0.120396 0.2794)
			(end 0.12065 0.2794)
			(stroke
				(width 0.1)
				(type default)
			)
			(layer "B.Fab")
		)
		(fp_line
			(start -0.12065 -0.2794)
			(end -0.12065 -0.3048)
			(stroke
				(width 0.1)
				(type default)
			)
			(layer "B.Fab")
		)
		(fp_line
			(start -0.12065 -0.3048)
			(end -0.67945 -0.3048)
			(stroke
				(width 0.1)
				(type default)
			)
			(layer "B.Fab")
		)
		(fp_line
			(start -0.67945 0.3048)
			(end -0.120396 0.3048)
			(stroke
				(width 0.1)
				(type default)
			)
			(layer "B.Fab")
		)
		(fp_line
			(start -0.67945 -0.3048)
			(end -0.67945 0.3048)
			(stroke
				(width 0.1)
				(type default)
			)
			(layer "B.Fab")
		)
		(pad "1" smd circle
			(at 0.40005 0)
			(size 0 0)
			(layers "B.Cu" "B.Mask" "B.Paste")
			(net "IRQ_BMC_SMI_N")
		)
		(pad "2" smd circle
			(at -0.40005 0)
			(size 0 0)
			(layers "B.Cu" "B.Mask" "B.Paste")
			(net "PVDD18_S5_P0")
		)
	)
	(footprint ""
		(layer "B.Cu")
		(at 357.835454 -253.43231)
		(property "Reference" "C2540"
			(at 0 0 0)
			(layer "B.SilkS")
			(hide yes)
			(effects
				(font
					(size 1.27 1.27)
				)
				(justify mirror)
			)
		)
		(property "Value" ""
			(at 0 0 0)
			(layer "B.Fab")
			(effects
				(font
					(size 1.27 1.27)
				)
				(justify mirror)
			)
		)
		(duplicate_pad_numbers_are_jumpers no)
		(fp_line
			(start -0.7874 -0.4064)
			(end -0.7874 0.4064)
			(stroke
				(width 0.1524)
				(type default)
			)
			(layer "B.SilkS")
		)
		(fp_line
			(start -0.7874 0.4064)
			(end 0.7874 0.4064)
			(stroke
				(width 0.1524)
				(type default)
			)
			(layer "B.SilkS")
		)
		(fp_line
			(start 0.7874 -0.4064)
			(end -0.7874 -0.4064)
			(stroke
				(width 0.1524)
				(type default)
			)
			(layer "B.SilkS")
		)
		(fp_line
			(start 0.7874 0.4064)
			(end 0.7874 -0.4064)
			(stroke
				(width 0.1524)
				(type default)
			)
			(layer "B.SilkS")
		)
		(fp_line
			(start -0.67945 -0.3048)
			(end -0.67945 0.3048)
			(stroke
				(width 0.1)
				(type default)
			)
			(layer "B.Fab")
		)
		(fp_line
			(start -0.67945 0.3048)
			(end -0.120396 0.3048)
			(stroke
				(width 0.1)
				(type default)
			)
			(layer "B.Fab")
		)
		(fp_line
			(start -0.12065 -0.3048)
			(end -0.67945 -0.3048)
			(stroke
				(width 0.1)
				(type default)
			)
			(layer "B.Fab")
		)
		(fp_line
			(start -0.12065 -0.2794)
			(end -0.12065 -0.3048)
			(stroke
				(width 0.1)
				(type default)
			)
			(layer "B.Fab")
		)
		(fp_line
			(start -0.120396 0.2794)
			(end 0.12065 0.2794)
			(stroke
				(width 0.1)
				(type default)
			)
			(layer "B.Fab")
		)
		(fp_line
			(start -0.120396 0.3048)
			(end -0.120396 0.2794)
			(stroke
				(width 0.1)
				(type default)
			)
			(layer "B.Fab")
		)
		(fp_line
			(start 0.12065 -0.305054)
			(end 0.12065 -0.2794)
			(stroke
				(width 0.1)
				(type default)
			)
			(layer "B.Fab")
		)
		(fp_line
			(start 0.12065 -0.2794)
			(end -0.12065 -0.2794)
			(stroke
				(width 0.1)
				(type default)
			)
			(layer "B.Fab")
		)
		(fp_line
			(start 0.12065 0.2794)
			(end 0.12065 0.3048)
			(stroke
				(width 0.1)
				(type default)
			)
			(layer "B.Fab")
		)
		(fp_line
			(start 0.12065 0.3048)
			(end 0.67945 0.3048)
			(stroke
				(width 0.1)
				(type default)
			)
			(layer "B.Fab")
		)
		(fp_line
			(start 0.67945 -0.305054)
			(end 0.12065 -0.305054)
			(stroke
				(width 0.1)
				(type default)
			)
			(layer "B.Fab")
		)
		(fp_line
			(start 0.67945 0.3048)
			(end 0.67945 -0.305054)
			(stroke
				(width 0.1)
				(type default)
			)
			(layer "B.Fab")
		)
		(pad "1" smd circle
			(at 0.40005 0 180)
			(size 0 0)
			(layers "B.Cu" "B.Mask" "B.Paste")
			(net "PVDDCR_SOC_P0")
		)
		(pad "2" smd circle
			(at -0.40005 0 180)
			(size 0 0)
			(layers "B.Cu" "B.Mask" "B.Paste")
			(net "GND")
		)
	)
	(footprint ""
		(layer "B.Cu")
		(at 187.111894 -115.022376 180)
		(property "Reference" "C1171"
			(at 0 0 0)
			(layer "B.SilkS")
			(hide yes)
			(effects
				(font
					(size 1.27 1.27)
				)
				(justify mirror)
			)
		)
		(property "Value" ""
			(at 0 0 0)
			(layer "B.Fab")
			(effects
				(font
					(size 1.27 1.27)
				)
				(justify mirror)
			)
		)
		(duplicate_pad_numbers_are_jumpers no)
		(fp_line
			(start 0.69215 0.2921)
			(end 0.69215 -0.2921)
			(stroke
				(width 0.1524)
				(type default)
			)
			(layer "B.SilkS")
		)
		(fp_line
			(start 0.69215 -0.2921)
			(end -0.69215 -0.2921)
			(stroke
				(width 0.1524)
				(type default)
			)
			(layer "B.SilkS")
		)
		(fp_line
			(start -0.69215 0.2921)
			(end 0.69215 0.2921)
			(stroke
				(width 0.1524)
				(type default)
			)
			(layer "B.SilkS")
		)
		(fp_line
			(start -0.69215 -0.2921)
			(end -0.69215 0.2921)
			(stroke
				(width 0.1524)
				(type default)
			)
			(layer "B.SilkS")
		)
		(fp_line
			(start 0.51435 0.2794)
			(end 0.51435 -0.2794)
			(stroke
				(width 0.1)
				(type default)
			)
			(layer "B.Fab")
		)
		(fp_line
			(start 0.51435 -0.2794)
			(end -0.51435 -0.2794)
			(stroke
				(width 0.1)
				(type default)
			)
			(layer "B.Fab")
		)
		(fp_line
			(start -0.51435 0.2794)
			(end 0.51435 0.2794)
			(stroke
				(width 0.1)
				(type default)
			)
			(layer "B.Fab")
		)
		(fp_line
			(start -0.51435 -0.2794)
			(end -0.51435 0.2794)
			(stroke
				(width 0.1)
				(type default)
			)
			(layer "B.Fab")
		)
		(pad "1" smd circle
			(at 0.40005 0)
			(size 0 0)
			(layers "B.Cu" "B.Mask" "B.Paste")
			(net "P3V3_AUX")
		)
		(pad "2" smd circle
			(at -0.40005 0)
			(size 0 0)
			(layers "B.Cu" "B.Mask" "B.Paste")
			(net "GND")
		)
		(zone
			(layer "B.Cu")
			(hatch none 0.5)
			(connect_pads
				(clearance 0)
			)
			(min_thickness 0.25)
			(keepout
				(tracks not_allowed)
				(vias allowed)
				(pads allowed)
				(copperpour not_allowed)
				(footprints allowed)
			)
			(placement
				(enabled no)
				(sheetname "")
			)
			(fill
				(thermal_gap 0.5)
				(thermal_bridge_width 0.5)
				(island_removal_mode 0)
			)
			(polygon
				(pts
					(xy 186.921394 -114.934492) (xy 186.921394 -115.110006) (xy 187.012834 -115.168172) (xy 187.212224 -115.168172)
					(xy 187.302394 -115.110006) (xy 187.302394 -114.934746) (xy 187.212224 -114.876326) (xy 187.012834 -114.876326)
				)
			)
		)
	)
	(footprint ""
		(layer "B.Cu")
		(at 416.468052 -192.660016)
		(property "Reference" "C158"
			(at 0 0 0)
			(layer "B.SilkS")
			(hide yes)
			(effects
				(font
					(size 1.27 1.27)
				)
				(justify mirror)
			)
		)
		(property "Value" ""
			(at 0 0 0)
			(layer "B.Fab")
			(effects
				(font
					(size 1.27 1.27)
				)
				(justify mirror)
			)
		)
		(duplicate_pad_numbers_are_jumpers no)
		(fp_line
			(start -1.524 -0.762)
			(end -1.524 0.762)
			(stroke
				(width 0.1524)
				(type default)
			)
			(layer "B.SilkS")
		)
		(fp_line
			(start -1.524 0.762)
			(end 1.524 0.762)
			(stroke
				(width 0.1524)
				(type default)
			)
			(layer "B.SilkS")
		)
		(fp_line
			(start 1.524 -0.762)
			(end -1.524 -0.762)
			(stroke
				(width 0.1524)
				(type default)
			)
			(layer "B.SilkS")
		)
		(fp_line
			(start 1.524 0.762)
			(end 1.524 -0.762)
			(stroke
				(width 0.1524)
				(type default)
			)
			(layer "B.SilkS")
		)
		(fp_line
			(start -1.1049 -0.724916)
			(end 1.1049 -0.724916)
			(stroke
				(width 0.1)
				(type default)
			)
			(layer "B.Fab")
		)
		(fp_line
			(start -1.1049 0.724916)
			(end -1.1049 -0.724916)
			(stroke
				(width 0.1)
				(type default)
			)
			(layer "B.Fab")
		)
		(fp_line
			(start 1.1049 -0.724916)
			(end 1.1049 0.724916)
			(stroke
				(width 0.1)
				(type default)
			)
			(layer "B.Fab")
		)
		(fp_line
			(start 1.1049 0.724916)
			(end -1.1049 0.724916)
			(stroke
				(width 0.1)
				(type default)
			)
			(layer "B.Fab")
		)
		(pad "1" smd rect
			(at 0.889 0)
			(size 1.016 1.27)
			(layers "B.Cu" "B.Mask" "B.Paste")
			(net "P12V_MEM_CPU0")
		)
		(pad "2" smd rect
			(at -0.889 0)
			(size 1.016 1.27)
			(layers "B.Cu" "B.Mask" "B.Paste")
			(net "GND")
		)
	)
	(footprint ""
		(layer "B.Cu")
		(at 55.918608 -388.011162 -90)
		(property "Reference" "C126"
			(at 0 0 90)
			(layer "B.SilkS")
			(hide yes)
			(effects
				(font
					(size 1.27 1.27)
				)
				(justify mirror)
			)
		)
		(property "Value" ""
			(at 0 0 90)
			(layer "B.Fab")
			(effects
				(font
					(size 1.27 1.27)
				)
				(justify mirror)
			)
		)
		(duplicate_pad_numbers_are_jumpers no)
		(fp_line
			(start -0.299974 0.150114)
			(end 0.299974 0.150114)
			(stroke
				(width 0.1)
				(type default)
			)
			(layer "B.Fab")
		)
		(fp_line
			(start 0.299974 0.150114)
			(end 0.299974 -0.150114)
			(stroke
				(width 0.1)
				(type default)
			)
			(layer "B.Fab")
		)
		(fp_line
			(start -0.299974 -0.150114)
			(end -0.299974 0.150114)
			(stroke
				(width 0.1)
				(type default)
			)
			(layer "B.Fab")
		)
		(fp_line
			(start 0.299974 -0.150114)
			(end -0.299974 -0.150114)
			(stroke
				(width 0.1)
				(type default)
			)
			(layer "B.Fab")
		)
		(pad "1" smd rect
			(at 0.2667 0 90)
			(size 0.3048 0.381)
			(layers "B.Cu" "B.Mask" "B.Paste")
			(net "P1V8_CPU1_RT0_1A")
		)
		(pad "2" smd rect
			(at -0.2667 0 90)
			(size 0.3048 0.381)
			(layers "B.Cu" "B.Mask" "B.Paste")
			(net "GND")
		)
	)
	(footprint ""
		(layer "B.Cu")
		(at 43.265852 -385.91236 180)
		(property "Reference" "R719"
			(at 0 0 0)
			(layer "B.SilkS")
			(hide yes)
			(effects
				(font
					(size 1.27 1.27)
				)
				(justify mirror)
			)
		)
		(property "Value" ""
			(at 0 0 0)
			(layer "B.Fab")
			(effects
				(font
					(size 1.27 1.27)
				)
				(justify mirror)
			)
		)
		(duplicate_pad_numbers_are_jumpers no)
		(fp_line
			(start 0.32512 0.175006)
			(end 0.32512 -0.175006)
			(stroke
				(width 0.1)
				(type default)
			)
			(layer "B.Fab")
		)
		(fp_line
			(start 0.32512 -0.175006)
			(end -0.32512 -0.175006)
			(stroke
				(width 0.1)
				(type default)
			)
			(layer "B.Fab")
		)
		(fp_line
			(start -0.32512 0.175006)
			(end 0.32512 0.175006)
			(stroke
				(width 0.1)
				(type default)
			)
			(layer "B.Fab")
		)
		(fp_line
			(start -0.32512 -0.175006)
			(end -0.32512 0.175006)
			(stroke
				(width 0.1)
				(type default)
			)
			(layer "B.Fab")
		)
		(pad "1" smd rect
			(at 0.2667 0)
			(size 0.3048 0.381)
			(layers "B.Cu" "B.Mask" "B.Paste")
			(net "TEST0_RT_CPU1_P0")
		)
		(pad "2" smd rect
			(at -0.2667 0 180)
			(size 0.3048 0.381)
			(layers "B.Cu" "B.Mask" "B.Paste")
			(net "GND")
		)
	)
	(footprint ""
		(layer "B.Cu")
		(at 400.812508 -330.090272)
		(property "Reference" "R457"
			(at 0 0 0)
			(layer "B.SilkS")
			(hide yes)
			(effects
				(font
					(size 1.27 1.27)
				)
				(justify mirror)
			)
		)
		(property "Value" ""
			(at 0 0 0)
			(layer "B.Fab")
			(effects
				(font
					(size 1.27 1.27)
				)
				(justify mirror)
			)
		)
		(duplicate_pad_numbers_are_jumpers no)
		(fp_line
			(start -0.7874 -0.4064)
			(end -0.7874 0.4064)
			(stroke
				(width 0.1524)
				(type default)
			)
			(layer "B.SilkS")
		)
		(fp_line
			(start -0.7874 0.4064)
			(end 0.7874 0.4064)
			(stroke
				(width 0.1524)
				(type default)
			)
			(layer "B.SilkS")
		)
		(fp_line
			(start 0.7874 -0.4064)
			(end -0.7874 -0.4064)
			(stroke
				(width 0.1524)
				(type default)
			)
			(layer "B.SilkS")
		)
		(fp_line
			(start 0.7874 0.4064)
			(end 0.7874 -0.4064)
			(stroke
				(width 0.1524)
				(type default)
			)
			(layer "B.SilkS")
		)
		(fp_line
			(start -0.67945 -0.3048)
			(end -0.67945 0.3048)
			(stroke
				(width 0.1)
				(type default)
			)
			(layer "B.Fab")
		)
		(fp_line
			(start -0.67945 0.3048)
			(end -0.120396 0.3048)
			(stroke
				(width 0.1)
				(type default)
			)
			(layer "B.Fab")
		)
		(fp_line
			(start -0.12065 -0.3048)
			(end -0.67945 -0.3048)
			(stroke
				(width 0.1)
				(type default)
			)
			(layer "B.Fab")
		)
		(fp_line
			(start -0.12065 -0.2794)
			(end -0.12065 -0.3048)
			(stroke
				(width 0.1)
				(type default)
			)
			(layer "B.Fab")
		)
		(fp_line
			(start -0.120396 0.2794)
			(end 0.12065 0.2794)
			(stroke
				(width 0.1)
				(type default)
			)
			(layer "B.Fab")
		)
		(fp_line
			(start -0.120396 0.3048)
			(end -0.120396 0.2794)
			(stroke
				(width 0.1)
				(type default)
			)
			(layer "B.Fab")
		)
		(fp_line
			(start 0.12065 -0.305054)
			(end 0.12065 -0.2794)
			(stroke
				(width 0.1)
				(type default)
			)
			(layer "B.Fab")
		)
		(fp_line
			(start 0.12065 -0.2794)
			(end -0.12065 -0.2794)
			(stroke
				(width 0.1)
				(type default)
			)
			(layer "B.Fab")
		)
		(fp_line
			(start 0.12065 0.2794)
			(end 0.12065 0.3048)
			(stroke
				(width 0.1)
				(type default)
			)
			(layer "B.Fab")
		)
		(fp_line
			(start 0.12065 0.3048)
			(end 0.67945 0.3048)
			(stroke
				(width 0.1)
				(type default)
			)
			(layer "B.Fab")
		)
		(fp_line
			(start 0.67945 -0.305054)
			(end 0.12065 -0.305054)
			(stroke
				(width 0.1)
				(type default)
			)
			(layer "B.Fab")
		)
		(fp_line
			(start 0.67945 0.3048)
			(end 0.67945 -0.305054)
			(stroke
				(width 0.1)
				(type default)
			)
			(layer "B.Fab")
		)
		(pad "1" smd circle
			(at 0.40005 0 180)
			(size 0 0)
			(layers "B.Cu" "B.Mask" "B.Paste")
			(net "PVDD18_S5_P0")
		)
		(pad "2" smd circle
			(at -0.40005 0 180)
			(size 0 0)
			(layers "B.Cu" "B.Mask" "B.Paste")
			(net "RST_ESPI_CPU0_RSTOUT_N")
		)
	)
	(footprint ""
		(layer "B.Cu")
		(at 234.824016 -322.683632 180)
		(property "Reference" "R1229"
			(at 0 0 0)
			(layer "B.SilkS")
			(hide yes)
			(effects
				(font
					(size 1.27 1.27)
				)
				(justify mirror)
			)
		)
		(property "Value" ""
			(at 0 0 0)
			(layer "B.Fab")
			(effects
				(font
					(size 1.27 1.27)
				)
				(justify mirror)
			)
		)
		(duplicate_pad_numbers_are_jumpers no)
		(fp_line
			(start 0.7874 0.4064)
			(end 0.7874 -0.4064)
			(stroke
				(width 0.1524)
				(type default)
			)
			(layer "B.SilkS")
		)
		(fp_line
			(start 0.7874 -0.4064)
			(end -0.7874 -0.4064)
			(stroke
				(width 0.1524)
				(type default)
			)
			(layer "B.SilkS")
		)
		(fp_line
			(start -0.7874 0.4064)
			(end 0.7874 0.4064)
			(stroke
				(width 0.1524)
				(type default)
			)
			(layer "B.SilkS")
		)
		(fp_line
			(start -0.7874 -0.4064)
			(end -0.7874 0.4064)
			(stroke
				(width 0.1524)
				(type default)
			)
			(layer "B.SilkS")
		)
		(fp_line
			(start 0.67945 0.3048)
			(end 0.67945 -0.305054)
			(stroke
				(width 0.1)
				(type default)
			)
			(layer "B.Fab")
		)
		(fp_line
			(start 0.67945 -0.305054)
			(end 0.12065 -0.305054)
			(stroke
				(width 0.1)
				(type default)
			)
			(layer "B.Fab")
		)
		(fp_line
			(start 0.12065 0.3048)
			(end 0.67945 0.3048)
			(stroke
				(width 0.1)
				(type default)
			)
			(layer "B.Fab")
		)
		(fp_line
			(start 0.12065 0.2794)
			(end 0.12065 0.3048)
			(stroke
				(width 0.1)
				(type default)
			)
			(layer "B.Fab")
		)
		(fp_line
			(start 0.12065 -0.2794)
			(end -0.12065 -0.2794)
			(stroke
				(width 0.1)
				(type default)
			)
			(layer "B.Fab")
		)
		(fp_line
			(start 0.12065 -0.305054)
			(end 0.12065 -0.2794)
			(stroke
				(width 0.1)
				(type default)
			)
			(layer "B.Fab")
		)
		(fp_line
			(start -0.120396 0.3048)
			(end -0.120396 0.2794)
			(stroke
				(width 0.1)
				(type default)
			)
			(layer "B.Fab")
		)
		(fp_line
			(start -0.120396 0.2794)
			(end 0.12065 0.2794)
			(stroke
				(width 0.1)
				(type default)
			)
			(layer "B.Fab")
		)
		(fp_line
			(start -0.12065 -0.2794)
			(end -0.12065 -0.3048)
			(stroke
				(width 0.1)
				(type default)
			)
			(layer "B.Fab")
		)
		(fp_line
			(start -0.12065 -0.3048)
			(end -0.67945 -0.3048)
			(stroke
				(width 0.1)
				(type default)
			)
			(layer "B.Fab")
		)
		(fp_line
			(start -0.67945 0.3048)
			(end -0.120396 0.3048)
			(stroke
				(width 0.1)
				(type default)
			)
			(layer "B.Fab")
		)
		(fp_line
			(start -0.67945 -0.3048)
			(end -0.67945 0.3048)
			(stroke
				(width 0.1)
				(type default)
			)
			(layer "B.Fab")
		)
		(pad "1" smd circle
			(at 0.40005 0)
			(size 0 0)
			(layers "B.Cu" "B.Mask" "B.Paste")
			(net "P1V8_AUX_ADC")
		)
		(pad "2" smd circle
			(at -0.40005 0)
			(size 0 0)
			(layers "B.Cu" "B.Mask" "B.Paste")
			(net "GND")
		)
	)
	(footprint ""
		(layer "B.Cu")
		(at 234.825286 -328.085704 180)
		(property "Reference" "R1222"
			(at 0 0 0)
			(layer "B.SilkS")
			(hide yes)
			(effects
				(font
					(size 1.27 1.27)
				)
				(justify mirror)
			)
		)
		(property "Value" ""
			(at 0 0 0)
			(layer "B.Fab")
			(effects
				(font
					(size 1.27 1.27)
				)
				(justify mirror)
			)
		)
		(duplicate_pad_numbers_are_jumpers no)
		(fp_line
			(start 0.7874 0.4064)
			(end 0.7874 -0.4064)
			(stroke
				(width 0.1524)
				(type default)
			)
			(layer "B.SilkS")
		)
		(fp_line
			(start 0.7874 -0.4064)
			(end -0.7874 -0.4064)
			(stroke
				(width 0.1524)
				(type default)
			)
			(layer "B.SilkS")
		)
		(fp_line
			(start -0.7874 0.4064)
			(end 0.7874 0.4064)
			(stroke
				(width 0.1524)
				(type default)
			)
			(layer "B.SilkS")
		)
		(fp_line
			(start -0.7874 -0.4064)
			(end -0.7874 0.4064)
			(stroke
				(width 0.1524)
				(type default)
			)
			(layer "B.SilkS")
		)
		(fp_line
			(start 0.67945 0.3048)
			(end 0.67945 -0.305054)
			(stroke
				(width 0.1)
				(type default)
			)
			(layer "B.Fab")
		)
		(fp_line
			(start 0.67945 -0.305054)
			(end 0.12065 -0.305054)
			(stroke
				(width 0.1)
				(type default)
			)
			(layer "B.Fab")
		)
		(fp_line
			(start 0.12065 0.3048)
			(end 0.67945 0.3048)
			(stroke
				(width 0.1)
				(type default)
			)
			(layer "B.Fab")
		)
		(fp_line
			(start 0.12065 0.2794)
			(end 0.12065 0.3048)
			(stroke
				(width 0.1)
				(type default)
			)
			(layer "B.Fab")
		)
		(fp_line
			(start 0.12065 -0.2794)
			(end -0.12065 -0.2794)
			(stroke
				(width 0.1)
				(type default)
			)
			(layer "B.Fab")
		)
		(fp_line
			(start 0.12065 -0.305054)
			(end 0.12065 -0.2794)
			(stroke
				(width 0.1)
				(type default)
			)
			(layer "B.Fab")
		)
		(fp_line
			(start -0.120396 0.3048)
			(end -0.120396 0.2794)
			(stroke
				(width 0.1)
				(type default)
			)
			(layer "B.Fab")
		)
		(fp_line
			(start -0.120396 0.2794)
			(end 0.12065 0.2794)
			(stroke
				(width 0.1)
				(type default)
			)
			(layer "B.Fab")
		)
		(fp_line
			(start -0.12065 -0.2794)
			(end -0.12065 -0.3048)
			(stroke
				(width 0.1)
				(type default)
			)
			(layer "B.Fab")
		)
		(fp_line
			(start -0.12065 -0.3048)
			(end -0.67945 -0.3048)
			(stroke
				(width 0.1)
				(type default)
			)
			(layer "B.Fab")
		)
		(fp_line
			(start -0.67945 0.3048)
			(end -0.120396 0.3048)
			(stroke
				(width 0.1)
				(type default)
			)
			(layer "B.Fab")
		)
		(fp_line
			(start -0.67945 -0.3048)
			(end -0.67945 0.3048)
			(stroke
				(width 0.1)
				(type default)
			)
			(layer "B.Fab")
		)
		(pad "1" smd circle
			(at 0.40005 0)
			(size 0 0)
			(layers "B.Cu" "B.Mask" "B.Paste")
			(net "PVDD18_S5_P0_ADC")
		)
		(pad "2" smd circle
			(at -0.40005 0)
			(size 0 0)
			(layers "B.Cu" "B.Mask" "B.Paste")
			(net "GND")
		)
	)
	(footprint ""
		(layer "B.Cu")
		(at 315.004958 -201.926952 90)
		(property "Reference" "R27"
			(at 0 0 90)
			(layer "B.SilkS")
			(hide yes)
			(effects
				(font
					(size 1.27 1.27)
				)
				(justify mirror)
			)
		)
		(property "Value" ""
			(at 0 0 90)
			(layer "B.Fab")
			(effects
				(font
					(size 1.27 1.27)
				)
				(justify mirror)
			)
		)
		(duplicate_pad_numbers_are_jumpers no)
		(fp_line
			(start 0.7874 -0.4064)
			(end -0.7874 -0.4064)
			(stroke
				(width 0.1524)
				(type default)
			)
			(layer "B.SilkS")
		)
		(fp_line
			(start -0.7874 -0.4064)
			(end -0.7874 0.4064)
			(stroke
				(width 0.1524)
				(type default)
			)
			(layer "B.SilkS")
		)
		(fp_line
			(start 0.7874 0.4064)
			(end 0.7874 -0.4064)
			(stroke
				(width 0.1524)
				(type default)
			)
			(layer "B.SilkS")
		)
		(fp_line
			(start -0.7874 0.4064)
			(end 0.7874 0.4064)
			(stroke
				(width 0.1524)
				(type default)
			)
			(layer "B.SilkS")
		)
		(fp_line
			(start 0.67945 -0.305054)
			(end 0.12065 -0.305054)
			(stroke
				(width 0.1)
				(type default)
			)
			(layer "B.Fab")
		)
		(fp_line
			(start 0.12065 -0.305054)
			(end 0.12065 -0.2794)
			(stroke
				(width 0.1)
				(type default)
			)
			(layer "B.Fab")
		)
		(fp_line
			(start -0.12065 -0.3048)
			(end -0.67945 -0.3048)
			(stroke
				(width 0.1)
				(type default)
			)
			(layer "B.Fab")
		)
		(fp_line
			(start -0.67945 -0.3048)
			(end -0.67945 0.3048)
			(stroke
				(width 0.1)
				(type default)
			)
			(layer "B.Fab")
		)
		(fp_line
			(start 0.12065 -0.2794)
			(end -0.12065 -0.2794)
			(stroke
				(width 0.1)
				(type default)
			)
			(layer "B.Fab")
		)
		(fp_line
			(start -0.12065 -0.2794)
			(end -0.12065 -0.3048)
			(stroke
				(width 0.1)
				(type default)
			)
			(layer "B.Fab")
		)
		(fp_line
			(start 0.12065 0.2794)
			(end 0.12065 0.3048)
			(stroke
				(width 0.1)
				(type default)
			)
			(layer "B.Fab")
		)
		(fp_line
			(start -0.120396 0.2794)
			(end 0.12065 0.2794)
			(stroke
				(width 0.1)
				(type default)
			)
			(layer "B.Fab")
		)
		(fp_line
			(start 0.67945 0.3048)
			(end 0.67945 -0.305054)
			(stroke
				(width 0.1)
				(type default)
			)
			(layer "B.Fab")
		)
		(fp_line
			(start 0.12065 0.3048)
			(end 0.67945 0.3048)
			(stroke
				(width 0.1)
				(type default)
			)
			(layer "B.Fab")
		)
		(fp_line
			(start -0.120396 0.3048)
			(end -0.120396 0.2794)
			(stroke
				(width 0.1)
				(type default)
			)
			(layer "B.Fab")
		)
		(fp_line
			(start -0.67945 0.3048)
			(end -0.120396 0.3048)
			(stroke
				(width 0.1)
				(type default)
			)
			(layer "B.Fab")
		)
		(pad "1" smd circle
			(at 0.40005 0 270)
			(size 0 0)
			(layers "B.Cu" "B.Mask" "B.Paste")
			(net "SMB_CPU0_2_R_SCL")
		)
		(pad "2" smd circle
			(at -0.40005 0 270)
			(size 0 0)
			(layers "B.Cu" "B.Mask" "B.Paste")
			(net "SMB_CPU0_2_SCL")
		)
	)
	(footprint ""
		(layer "B.Cu")
		(at 115.384834 -271.395952 180)
		(property "Reference" "C2371"
			(at 0 0 0)
			(layer "B.SilkS")
			(hide yes)
			(effects
				(font
					(size 1.27 1.27)
				)
				(justify mirror)
			)
		)
		(property "Value" ""
			(at 0 0 0)
			(layer "B.Fab")
			(effects
				(font
					(size 1.27 1.27)
				)
				(justify mirror)
			)
		)
		(duplicate_pad_numbers_are_jumpers no)
		(fp_line
			(start 0.7874 0.4064)
			(end 0.7874 -0.4064)
			(stroke
				(width 0.1524)
				(type default)
			)
			(layer "B.SilkS")
		)
		(fp_line
			(start 0.7874 -0.4064)
			(end -0.7874 -0.4064)
			(stroke
				(width 0.1524)
				(type default)
			)
			(layer "B.SilkS")
		)
		(fp_line
			(start -0.7874 0.4064)
			(end 0.7874 0.4064)
			(stroke
				(width 0.1524)
				(type default)
			)
			(layer "B.SilkS")
		)
		(fp_line
			(start -0.7874 -0.4064)
			(end -0.7874 0.4064)
			(stroke
				(width 0.1524)
				(type default)
			)
			(layer "B.SilkS")
		)
		(fp_line
			(start 0.67945 0.3048)
			(end 0.67945 -0.305054)
			(stroke
				(width 0.1)
				(type default)
			)
			(layer "B.Fab")
		)
		(fp_line
			(start 0.67945 -0.305054)
			(end 0.12065 -0.305054)
			(stroke
				(width 0.1)
				(type default)
			)
			(layer "B.Fab")
		)
		(fp_line
			(start 0.12065 0.3048)
			(end 0.67945 0.3048)
			(stroke
				(width 0.1)
				(type default)
			)
			(layer "B.Fab")
		)
		(fp_line
			(start 0.12065 0.2794)
			(end 0.12065 0.3048)
			(stroke
				(width 0.1)
				(type default)
			)
			(layer "B.Fab")
		)
		(fp_line
			(start 0.12065 -0.2794)
			(end -0.12065 -0.2794)
			(stroke
				(width 0.1)
				(type default)
			)
			(layer "B.Fab")
		)
		(fp_line
			(start 0.12065 -0.305054)
			(end 0.12065 -0.2794)
			(stroke
				(width 0.1)
				(type default)
			)
			(layer "B.Fab")
		)
		(fp_line
			(start -0.120396 0.3048)
			(end -0.120396 0.2794)
			(stroke
				(width 0.1)
				(type default)
			)
			(layer "B.Fab")
		)
		(fp_line
			(start -0.120396 0.2794)
			(end 0.12065 0.2794)
			(stroke
				(width 0.1)
				(type default)
			)
			(layer "B.Fab")
		)
		(fp_line
			(start -0.12065 -0.2794)
			(end -0.12065 -0.3048)
			(stroke
				(width 0.1)
				(type default)
			)
			(layer "B.Fab")
		)
		(fp_line
			(start -0.12065 -0.3048)
			(end -0.67945 -0.3048)
			(stroke
				(width 0.1)
				(type default)
			)
			(layer "B.Fab")
		)
		(fp_line
			(start -0.67945 0.3048)
			(end -0.120396 0.3048)
			(stroke
				(width 0.1)
				(type default)
			)
			(layer "B.Fab")
		)
		(fp_line
			(start -0.67945 -0.3048)
			(end -0.67945 0.3048)
			(stroke
				(width 0.1)
				(type default)
			)
			(layer "B.Fab")
		)
		(pad "1" smd circle
			(at 0.40005 0)
			(size 0 0)
			(layers "B.Cu" "B.Mask" "B.Paste")
			(net "PVDDCR_CPU1_P1")
		)
		(pad "2" smd circle
			(at -0.40005 0)
			(size 0 0)
			(layers "B.Cu" "B.Mask" "B.Paste")
			(net "GND")
		)
	)
	(footprint ""
		(layer "B.Cu")
		(at 388.88162 -189.46495 90)
		(property "Reference" "PC496"
			(at 6.321044 0.761746 270)
			(unlocked yes)
			(layer "B.SilkS")
			(effects
				(font
					(size 0.7874 0.5842)
					(thickness 0.1524)
				)
				(justify left mirror)
			)
		)
		(property "Value" ""
			(at 0 0 90)
			(layer "B.Fab")
			(effects
				(font
					(size 1.27 1.27)
				)
				(justify mirror)
			)
		)
		(duplicate_pad_numbers_are_jumpers no)
		(fp_line
			(start 4.533392 -2.249932)
			(end -4.533392 -2.249932)
			(stroke
				(width 0.1524)
				(type default)
			)
			(layer "B.SilkS")
		)
		(fp_line
			(start -4.533392 -2.249932)
			(end -4.533392 2.249932)
			(stroke
				(width 0.1524)
				(type default)
			)
			(layer "B.SilkS")
		)
		(fp_line
			(start 4.533392 2.249932)
			(end 4.533392 -2.249932)
			(stroke
				(width 0.1524)
				(type default)
			)
			(layer "B.SilkS")
		)
		(fp_line
			(start -4.533392 2.249932)
			(end 4.533392 2.249932)
			(stroke
				(width 0.1524)
				(type default)
			)
			(layer "B.SilkS")
		)
		(fp_rect
			(start 4.533392 -2.326132)
			(end 5.39242 2.326132)
			(stroke
				(width 0)
				(type default)
			)
			(fill yes)
			(layer "B.SilkS")
		)
		(fp_line
			(start 3.750056 -2.249932)
			(end -3.750056 -2.249932)
			(stroke
				(width 0.1)
				(type default)
			)
			(layer "B.Fab")
		)
		(fp_line
			(start -3.750056 -2.249932)
			(end -3.750056 2.249932)
			(stroke
				(width 0.1)
				(type default)
			)
			(layer "B.Fab")
		)
		(fp_line
			(start 3.750056 2.249932)
			(end 3.750056 -2.249932)
			(stroke
				(width 0.1)
				(type default)
			)
			(layer "B.Fab")
		)
		(fp_line
			(start -3.750056 2.249932)
			(end 3.750056 2.249932)
			(stroke
				(width 0.1)
				(type default)
			)
			(layer "B.Fab")
		)
		(fp_text user "+"
			(at 6.322314 0.786384 0)
			(unlocked yes)
			(layer "B.SilkS")
			(effects
				(font
					(size 1.905 1.4224)
					(thickness 0.1524)
				)
				(justify left mirror)
			)
		)
		(fp_text user "-"
			(at -4.841748 0.861822 90)
			(unlocked yes)
			(layer "B.SilkS")
			(effects
				(font
					(size 1.905 1.4224)
					(thickness 0.1524)
				)
				(justify left mirror)
			)
		)
		(fp_text user "-"
			(at -4.8514 -0.14605 90)
			(unlocked yes)
			(layer "B.Fab")
			(effects
				(font
					(size 1.905 1.4224)
					(thickness 0.1524)
				)
				(justify left mirror)
			)
		)
		(fp_text user "+"
			(at 6.322314 0.786384 0)
			(unlocked yes)
			(layer "B.Fab")
			(effects
				(font
					(size 1.905 1.4224)
					(thickness 0.1524)
				)
				(justify left mirror)
			)
		)
		(pad "1" smd rect
			(at 3.199892 0 270)
			(size 2.413 2.8194)
			(layers "B.Cu" "B.Mask" "B.Paste")
			(net "PVDDCR_CPU0_P0")
		)
		(pad "2" smd rect
			(at -3.199892 0 270)
			(size 2.413 2.8194)
			(layers "B.Cu" "B.Mask" "B.Paste")
			(net "GND")
		)
	)
	(footprint ""
		(layer "B.Cu")
		(at 129.20218 -37.09543 -90)
		(property "Reference" "C6063"
			(at 0 0 90)
			(layer "B.SilkS")
			(hide yes)
			(effects
				(font
					(size 1.27 1.27)
				)
				(justify mirror)
			)
		)
		(property "Value" ""
			(at 0 0 90)
			(layer "B.Fab")
			(effects
				(font
					(size 1.27 1.27)
				)
				(justify mirror)
			)
		)
		(duplicate_pad_numbers_are_jumpers no)
		(fp_line
			(start -0.7874 0.4064)
			(end 0.7874 0.4064)
			(stroke
				(width 0.1524)
				(type default)
			)
			(layer "B.SilkS")
		)
		(fp_line
			(start 0.7874 0.4064)
			(end 0.7874 -0.4064)
			(stroke
				(width 0.1524)
				(type default)
			)
			(layer "B.SilkS")
		)
		(fp_line
			(start -0.7874 -0.4064)
			(end -0.7874 0.4064)
			(stroke
				(width 0.1524)
				(type default)
			)
			(layer "B.SilkS")
		)
		(fp_line
			(start 0.7874 -0.4064)
			(end -0.7874 -0.4064)
			(stroke
				(width 0.1524)
				(type default)
			)
			(layer "B.SilkS")
		)
		(fp_line
			(start -0.67945 0.3048)
			(end -0.120396 0.3048)
			(stroke
				(width 0.1)
				(type default)
			)
			(layer "B.Fab")
		)
		(fp_line
			(start -0.120396 0.3048)
			(end -0.120396 0.2794)
			(stroke
				(width 0.1)
				(type default)
			)
			(layer "B.Fab")
		)
		(fp_line
			(start 0.12065 0.3048)
			(end 0.67945 0.3048)
			(stroke
				(width 0.1)
				(type default)
			)
			(layer "B.Fab")
		)
		(fp_line
			(start 0.67945 0.3048)
			(end 0.67945 -0.305054)
			(stroke
				(width 0.1)
				(type default)
			)
			(layer "B.Fab")
		)
		(fp_line
			(start -0.120396 0.2794)
			(end 0.12065 0.2794)
			(stroke
				(width 0.1)
				(type default)
			)
			(layer "B.Fab")
		)
		(fp_line
			(start 0.12065 0.2794)
			(end 0.12065 0.3048)
			(stroke
				(width 0.1)
				(type default)
			)
			(layer "B.Fab")
		)
		(fp_line
			(start -0.12065 -0.2794)
			(end -0.12065 -0.3048)
			(stroke
				(width 0.1)
				(type default)
			)
			(layer "B.Fab")
		)
		(fp_line
			(start 0.12065 -0.2794)
			(end -0.12065 -0.2794)
			(stroke
				(width 0.1)
				(type default)
			)
			(layer "B.Fab")
		)
		(fp_line
			(start -0.67945 -0.3048)
			(end -0.67945 0.3048)
			(stroke
				(width 0.1)
				(type default)
			)
			(layer "B.Fab")
		)
		(fp_line
			(start -0.12065 -0.3048)
			(end -0.67945 -0.3048)
			(stroke
				(width 0.1)
				(type default)
			)
			(layer "B.Fab")
		)
		(fp_line
			(start 0.12065 -0.305054)
			(end 0.12065 -0.2794)
			(stroke
				(width 0.1)
				(type default)
			)
			(layer "B.Fab")
		)
		(fp_line
			(start 0.67945 -0.305054)
			(end 0.12065 -0.305054)
			(stroke
				(width 0.1)
				(type default)
			)
			(layer "B.Fab")
		)
		(pad "1" smd circle
			(at 0.40005 0 90)
			(size 0 0)
			(layers "B.Cu" "B.Mask" "B.Paste")
			(net "P1V2_AUX")
		)
		(pad "2" smd circle
			(at -0.40005 0 90)
			(size 0 0)
			(layers "B.Cu" "B.Mask" "B.Paste")
			(net "GND")
		)
	)
	(footprint ""
		(layer "B.Cu")
		(at 426.53585 -33.467548 180)
		(property "Reference" "R744"
			(at 0 0 0)
			(layer "B.SilkS")
			(hide yes)
			(effects
				(font
					(size 1.27 1.27)
				)
				(justify mirror)
			)
		)
		(property "Value" ""
			(at 0 0 0)
			(layer "B.Fab")
			(effects
				(font
					(size 1.27 1.27)
				)
				(justify mirror)
			)
		)
		(duplicate_pad_numbers_are_jumpers no)
		(fp_line
			(start 0.7874 0.4064)
			(end 0.7874 -0.4064)
			(stroke
				(width 0.1524)
				(type default)
			)
			(layer "B.SilkS")
		)
		(fp_line
			(start 0.7874 -0.4064)
			(end -0.7874 -0.4064)
			(stroke
				(width 0.1524)
				(type default)
			)
			(layer "B.SilkS")
		)
		(fp_line
			(start -0.7874 0.4064)
			(end 0.7874 0.4064)
			(stroke
				(width 0.1524)
				(type default)
			)
			(layer "B.SilkS")
		)
		(fp_line
			(start -0.7874 -0.4064)
			(end -0.7874 0.4064)
			(stroke
				(width 0.1524)
				(type default)
			)
			(layer "B.SilkS")
		)
		(fp_line
			(start 0.67945 0.3048)
			(end 0.67945 -0.305054)
			(stroke
				(width 0.1)
				(type default)
			)
			(layer "B.Fab")
		)
		(fp_line
			(start 0.67945 -0.305054)
			(end 0.12065 -0.305054)
			(stroke
				(width 0.1)
				(type default)
			)
			(layer "B.Fab")
		)
		(fp_line
			(start 0.12065 0.3048)
			(end 0.67945 0.3048)
			(stroke
				(width 0.1)
				(type default)
			)
			(layer "B.Fab")
		)
		(fp_line
			(start 0.12065 0.2794)
			(end 0.12065 0.3048)
			(stroke
				(width 0.1)
				(type default)
			)
			(layer "B.Fab")
		)
		(fp_line
			(start 0.12065 -0.2794)
			(end -0.12065 -0.2794)
			(stroke
				(width 0.1)
				(type default)
			)
			(layer "B.Fab")
		)
		(fp_line
			(start 0.12065 -0.305054)
			(end 0.12065 -0.2794)
			(stroke
				(width 0.1)
				(type default)
			)
			(layer "B.Fab")
		)
		(fp_line
			(start -0.120396 0.3048)
			(end -0.120396 0.2794)
			(stroke
				(width 0.1)
				(type default)
			)
			(layer "B.Fab")
		)
		(fp_line
			(start -0.120396 0.2794)
			(end 0.12065 0.2794)
			(stroke
				(width 0.1)
				(type default)
			)
			(layer "B.Fab")
		)
		(fp_line
			(start -0.12065 -0.2794)
			(end -0.12065 -0.3048)
			(stroke
				(width 0.1)
				(type default)
			)
			(layer "B.Fab")
		)
		(fp_line
			(start -0.12065 -0.3048)
			(end -0.67945 -0.3048)
			(stroke
				(width 0.1)
				(type default)
			)
			(layer "B.Fab")
		)
		(fp_line
			(start -0.67945 0.3048)
			(end -0.120396 0.3048)
			(stroke
				(width 0.1)
				(type default)
			)
			(layer "B.Fab")
		)
		(fp_line
			(start -0.67945 -0.3048)
			(end -0.67945 0.3048)
			(stroke
				(width 0.1)
				(type default)
			)
			(layer "B.Fab")
		)
		(pad "1" smd circle
			(at 0.40005 0)
			(size 0 0)
			(layers "B.Cu" "B.Mask" "B.Paste")
			(net "PRSNT_CPU1_N")
		)
		(pad "2" smd circle
			(at -0.40005 0)
			(size 0 0)
			(layers "B.Cu" "B.Mask" "B.Paste")
			(net "FM_PRSNT_CPU1_N")
		)
	)
	(gr_poly
		(pts
			(xy 9.948418 -414.12287) (xy 9.948418 -412.97987) (xy 9.821418 -412.85287) (xy 8.805418 -412.85287)
			(xy 8.551418 -413.10687) (xy 8.551418 -413.99587) (xy 8.805418 -414.24987) (xy 9.821418 -414.24987)
		)
		(stroke
			(width 0)
			(type solid)
		)
		(fill yes)
		(layer "F.Cu")
		(net "P3V3_AUX")
	)
	(gr_poly
		(pts
			(xy 12.639548 -387.13029) (xy 12.639548 -385.63169) (xy 12.614148 -385.60629) (xy 12.131548 -385.60629)
			(xy 12.106148 -385.63169) (xy 12.106148 -387.13029) (xy 12.131548 -387.15569) (xy 12.614148 -387.15569)
		)
		(stroke
			(width 0)
			(type solid)
		)
		(fill yes)
		(layer "F.Cu")
		(net "SW_P0V9_RETIMER_CPU1_SW1_RC")
	)
	(gr_poly
		(pts
			(xy 21.71827 -387.13029) (xy 21.71827 -385.63169) (xy 21.69287 -385.60629) (xy 21.21027 -385.60629)
			(xy 21.18487 -385.63169) (xy 21.18487 -387.13029) (xy 21.21027 -387.15569) (xy 21.69287 -387.15569)
		)
		(stroke
			(width 0)
			(type solid)
		)
		(fill yes)
		(layer "F.Cu")
		(net "SW_P0V9_RETIMER_CPU1_SW2_RC")
	)
	(gr_poly
		(pts
			(xy 63.041022 -29.653484) (xy 63.041022 -28.053284) (xy 63.015622 -28.027884) (xy 61.999622 -28.027884)
			(xy 61.821822 -28.205684) (xy 61.821822 -29.577284) (xy 61.999622 -29.755084) (xy 62.939422 -29.755084)
		)
		(stroke
			(width 0)
			(type solid)
		)
		(fill yes)
		(layer "F.Cu")
		(net "P3V3_AUX")
	)
	(gr_poly
		(pts
			(xy 64.387222 -26.801318) (xy 64.387222 -24.471884) (xy 64.260222 -24.344884) (xy 63.523622 -24.344884)
			(xy 63.471298 -24.397208) (xy 63.471298 -26.80335) (xy 63.53302 -26.865072) (xy 64.323468 -26.865072)
		)
		(stroke
			(width 0)
			(type solid)
		)
		(fill yes)
		(layer "F.Cu")
		(net "GND")
	)
	(gr_poly
		(pts
			(xy 65.782444 -29.65577) (xy 65.782444 -28.99791) (xy 65.688464 -28.90393) (xy 63.539624 -28.90393)
			(xy 63.321184 -29.12237) (xy 63.321184 -29.67863) (xy 63.389764 -29.74721) (xy 65.691004 -29.74721)
		)
		(stroke
			(width 0)
			(type solid)
		)
		(fill yes)
		(layer "F.Cu")
		(net "P12V_OCP_FLTB_2")
	)
	(gr_poly
		(pts
			(xy 67.609212 -151.3586) (xy 67.609212 -150.9268) (xy 67.533012 -150.8506) (xy 66.415412 -150.8506)
			(xy 66.364612 -150.9014) (xy 66.364612 -151.384) (xy 66.399664 -151.419052) (xy 67.54876 -151.419052)
		)
		(stroke
			(width 0)
			(type solid)
		)
		(fill yes)
		(layer "F.Cu")
		(net "GND")
	)
	(gr_poly
		(pts
			(xy 85.750654 -57.743344) (xy 85.750654 -54.89321) (xy 85.33765 -54.480206) (xy 81.186274 -54.480206)
			(xy 80.3148 -55.35168) (xy 80.3148 -58.069734) (xy 80.438752 -58.193686) (xy 85.300312 -58.193686)
		)
		(stroke
			(width 0)
			(type solid)
		)
		(fill yes)
		(layer "F.Cu")
		(net "P3V3_OCP_V3_2")
	)
	(gr_poly
		(pts
			(xy 133.88594 -80.021176) (xy 133.88594 -71.039736) (xy 133.83514 -70.988936) (xy 130.445764 -70.988936)
			(xy 130.36042 -71.07428) (xy 130.36042 -79.91094) (xy 130.521456 -80.071976) (xy 133.83514 -80.071976)
		)
		(stroke
			(width 0)
			(type solid)
		)
		(fill yes)
		(layer "F.Cu")
		(net "P1V2_AUX")
	)
	(gr_poly
		(pts
			(xy 138.646662 -75.673712) (xy 138.646662 -73.211182) (xy 138.583162 -73.147682) (xy 137.43305 -73.147682)
			(xy 137.36955 -73.211182) (xy 137.36955 -75.710542) (xy 137.544302 -75.885294) (xy 138.43508 -75.885294)
		)
		(stroke
			(width 0)
			(type solid)
		)
		(fill yes)
		(layer "F.Cu")
		(net "P12V_AUX")
	)
	(gr_poly
		(pts
			(xy 143.83258 -51.15814) (xy 143.83258 -48.91278) (xy 143.55318 -48.63338) (xy 141.98092 -48.63338)
			(xy 141.78534 -48.82896) (xy 141.78534 -51.24958) (xy 141.97076 -51.435) (xy 143.55572 -51.435)
		)
		(stroke
			(width 0)
			(type solid)
		)
		(fill yes)
		(layer "F.Cu")
		(net "GND")
	)
	(gr_poly
		(pts
			(xy 155.98394 -82.307176) (xy 155.98394 -73.325736) (xy 155.93314 -73.274936) (xy 152.531064 -73.274936)
			(xy 152.45842 -73.34758) (xy 152.45842 -82.28838) (xy 152.528016 -82.357976) (xy 155.93314 -82.357976)
		)
		(stroke
			(width 0)
			(type solid)
		)
		(fill yes)
		(layer "F.Cu")
		(net "P1V8_AUX")
	)
	(gr_poly
		(pts
			(xy 166.061898 -51.360324) (xy 166.061898 -50.511456) (xy 165.962076 -50.411634) (xy 163.318698 -50.411634)
			(xy 163.144708 -50.585624) (xy 163.144708 -51.402742) (xy 163.28263 -51.540664) (xy 165.881558 -51.540664)
		)
		(stroke
			(width 0)
			(type solid)
		)
		(fill yes)
		(layer "F.Cu")
		(net "GND")
	)
	(gr_poly
		(pts
			(xy 166.690802 -62.583314) (xy 166.690802 -58.56986) (xy 166.507922 -58.38698) (xy 161.740596 -58.38698)
			(xy 161.637472 -58.490104) (xy 161.637472 -62.484) (xy 161.946336 -62.792864) (xy 166.481252 -62.792864)
		)
		(stroke
			(width 0)
			(type solid)
		)
		(fill yes)
		(layer "F.Cu")
		(net "P3V3")
	)
	(gr_poly
		(pts
			(xy 173.063916 -30.700472) (xy 173.063916 -29.100272) (xy 173.038516 -29.074872) (xy 172.022516 -29.074872)
			(xy 171.844716 -29.252672) (xy 171.844716 -30.624272) (xy 172.022516 -30.802072) (xy 172.962316 -30.802072)
		)
		(stroke
			(width 0)
			(type solid)
		)
		(fill yes)
		(layer "F.Cu")
		(net "P3V3_AUX")
	)
	(gr_poly
		(pts
			(xy 174.410116 -27.728672) (xy 174.410116 -25.518872) (xy 174.283116 -25.391872) (xy 173.546516 -25.391872)
			(xy 173.50994 -25.428448) (xy 173.50994 -27.768296) (xy 173.622716 -27.881072) (xy 174.257716 -27.881072)
		)
		(stroke
			(width 0)
			(type solid)
		)
		(fill yes)
		(layer "F.Cu")
		(net "GND")
	)
	(gr_poly
		(pts
			(xy 175.816514 -30.688788) (xy 175.816514 -29.997908) (xy 175.753014 -29.934408) (xy 173.479714 -29.934408)
			(xy 173.355254 -30.058868) (xy 173.355254 -30.742128) (xy 173.441614 -30.828488) (xy 175.676814 -30.828488)
		)
		(stroke
			(width 0)
			(type solid)
		)
		(fill yes)
		(layer "F.Cu")
		(net "P12V_SCM_FLTB_N")
	)
	(gr_poly
		(pts
			(xy 202.336146 -338.33689) (xy 202.336146 -337.21929) (xy 202.285346 -337.16849) (xy 201.802746 -337.16849)
			(xy 201.765154 -337.206082) (xy 201.765154 -338.350098) (xy 201.828146 -338.41309) (xy 202.259946 -338.41309)
		)
		(stroke
			(width 0)
			(type solid)
		)
		(fill yes)
		(layer "F.Cu")
		(net "GND")
	)
	(gr_poly
		(pts
			(xy 203.052934 -38.674548) (xy 203.052934 -36.109148) (xy 202.748134 -35.804348) (xy 197.693534 -35.804348)
			(xy 197.464934 -36.032948) (xy 197.464934 -38.014148) (xy 198.480934 -39.030148) (xy 202.697334 -39.030148)
		)
		(stroke
			(width 0)
			(type solid)
		)
		(fill yes)
		(layer "F.Cu")
		(net "P12V_SCM_R")
	)
	(gr_poly
		(pts
			(xy 205.636114 -345.467432) (xy 205.636114 -344.174572) (xy 205.506574 -344.045032) (xy 203.947014 -344.045032)
			(xy 203.809854 -344.182192) (xy 203.809854 -345.589352) (xy 203.827634 -345.607132) (xy 205.496414 -345.607132)
		)
		(stroke
			(width 0)
			(type solid)
		)
		(fill yes)
		(layer "F.Cu")
		(net "GND")
	)
	(gr_poly
		(pts
			(xy 218.187778 -61.360812) (xy 218.187778 -58.645298) (xy 217.76944 -58.22696) (xy 216.24163 -58.22696)
			(xy 216.079578 -58.389012) (xy 216.079578 -61.386212) (xy 216.282778 -61.589412) (xy 217.959178 -61.589412)
		)
		(stroke
			(width 0)
			(type solid)
		)
		(fill yes)
		(layer "F.Cu")
		(net "GND")
	)
	(gr_poly
		(pts
			(xy 218.673172 -388.22757) (xy 218.673172 -385.621276) (xy 218.08059 -385.028694) (xy 212.42782 -385.028694)
			(xy 211.97062 -385.485894) (xy 211.97062 -388.094474) (xy 212.446616 -388.57047) (xy 218.330272 -388.57047)
		)
		(stroke
			(width 0)
			(type solid)
		)
		(fill yes)
		(layer "F.Cu")
		(net "GND")
	)
	(gr_poly
		(pts
			(xy 228.627178 -294.832532) (xy 228.627178 -294.349932) (xy 228.576378 -294.299132) (xy 227.153978 -294.299132)
			(xy 227.103178 -294.349932) (xy 227.103178 -294.807132) (xy 227.179378 -294.883332) (xy 228.576378 -294.883332)
		)
		(stroke
			(width 0)
			(type solid)
		)
		(fill yes)
		(layer "F.Cu")
		(net "SW_P1V8_RETIMER_CPU1_BST_R")
	)
	(gr_poly
		(pts
			(xy 230.515922 -295.210992) (xy 230.515922 -294.066976) (xy 230.45293 -294.003984) (xy 230.02113 -294.003984)
			(xy 229.94493 -294.080184) (xy 229.94493 -295.197784) (xy 229.99573 -295.248584) (xy 230.47833 -295.248584)
		)
		(stroke
			(width 0)
			(type solid)
		)
		(fill yes)
		(layer "F.Cu")
		(net "GND")
	)
	(gr_poly
		(pts
			(xy 240.571528 -294.832532) (xy 240.571528 -294.349932) (xy 240.520728 -294.299132) (xy 239.098328 -294.299132)
			(xy 239.047528 -294.349932) (xy 239.047528 -294.807132) (xy 239.123728 -294.883332) (xy 240.520728 -294.883332)
		)
		(stroke
			(width 0)
			(type solid)
		)
		(fill yes)
		(layer "F.Cu")
		(net "SW_P1V8_RETIMER_CPU0_BST_R")
	)
	(gr_poly
		(pts
			(xy 242.460272 -295.210992) (xy 242.460272 -294.066976) (xy 242.39728 -294.003984) (xy 241.96548 -294.003984)
			(xy 241.88928 -294.080184) (xy 241.88928 -295.197784) (xy 241.94008 -295.248584) (xy 242.42268 -295.248584)
		)
		(stroke
			(width 0)
			(type solid)
		)
		(fill yes)
		(layer "F.Cu")
		(net "GND")
	)
	(gr_poly
		(pts
			(xy 244.64518 -372.613936) (xy 244.64518 -370.02466) (xy 244.340126 -369.719606) (xy 237.981236 -369.719606)
			(xy 237.638082 -370.06276) (xy 237.638082 -372.575582) (xy 237.942882 -372.880382) (xy 244.378734 -372.880382)
		)
		(stroke
			(width 0)
			(type solid)
		)
		(fill yes)
		(layer "F.Cu")
		(net "GND")
	)
	(gr_poly
		(pts
			(xy 251.418344 -103.970836) (xy 251.418344 -101.26599) (xy 251.248418 -101.096064) (xy 249.63628 -101.096064)
			(xy 249.477022 -101.255322) (xy 249.477022 -103.589074) (xy 249.954288 -104.06634) (xy 251.32284 -104.06634)
		)
		(stroke
			(width 0)
			(type solid)
		)
		(fill yes)
		(layer "F.Cu")
		(net "PVDD18_S5_P0")
	)
	(gr_poly
		(pts
			(xy 252.805184 -55.454042) (xy 252.805184 -54.819042) (xy 252.652784 -54.666642) (xy 250.717558 -54.666642)
			(xy 250.65482 -54.72938) (xy 250.65482 -55.59044) (xy 250.670822 -55.606442) (xy 252.652784 -55.606442)
		)
		(stroke
			(width 0)
			(type solid)
		)
		(fill yes)
		(layer "F.Cu")
		(net "GND")
	)
	(gr_poly
		(pts
			(xy 255.726184 -57.054242) (xy 255.726184 -56.114442) (xy 255.624584 -56.012842) (xy 254.024384 -56.012842)
			(xy 253.998984 -56.038242) (xy 253.998984 -57.054242) (xy 254.176784 -57.232042) (xy 255.548384 -57.232042)
		)
		(stroke
			(width 0)
			(type solid)
		)
		(fill yes)
		(layer "F.Cu")
		(net "P3V3_AUX")
	)
	(gr_poly
		(pts
			(xy 302.798734 -47.27702) (xy 302.798734 -45.90542) (xy 302.620934 -45.72762) (xy 301.300134 -45.72762)
			(xy 301.198534 -45.82922) (xy 301.198534 -47.42942) (xy 301.376334 -47.60722) (xy 302.468534 -47.60722)
		)
		(stroke
			(width 0)
			(type solid)
		)
		(fill yes)
		(layer "F.Cu")
		(net "P3V3_AUX")
	)
	(gr_poly
		(pts
			(xy 310.014874 -37.52342) (xy 310.014874 -35.69462) (xy 309.887874 -35.56762) (xy 308.770274 -35.56762)
			(xy 308.465474 -35.87242) (xy 308.465474 -37.62502) (xy 308.567074 -37.72662) (xy 309.811674 -37.72662)
		)
		(stroke
			(width 0)
			(type solid)
		)
		(fill yes)
		(layer "F.Cu")
		(net "GND")
	)
	(gr_poly
		(pts
			(xy 332.620874 -38.84422) (xy 332.620874 -37.82822) (xy 332.392274 -37.59962) (xy 330.309474 -37.59962)
			(xy 330.106274 -37.80282) (xy 330.106274 -39.04742) (xy 330.157074 -39.09822) (xy 332.366874 -39.09822)
		)
		(stroke
			(width 0)
			(type solid)
		)
		(fill yes)
		(layer "F.Cu")
		(net "GND")
	)
	(gr_poly
		(pts
			(xy 334.249268 -26.895298) (xy 334.249268 -25.346406) (xy 334.00111 -25.098248) (xy 329.33894 -25.098248)
			(xy 329.17384 -25.263348) (xy 329.17384 -26.93035) (xy 329.373738 -27.130248) (xy 334.014318 -27.130248)
		)
		(stroke
			(width 0)
			(type solid)
		)
		(fill yes)
		(layer "F.Cu")
		(net "P1V5_BAT")
	)
	(gr_poly
		(pts
			(xy 334.361028 -29.750512) (xy 334.361028 -27.458162) (xy 334.297528 -27.394662) (xy 329.331828 -27.394662)
			(xy 329.268328 -27.458162) (xy 329.268328 -29.750512) (xy 329.331828 -29.814012) (xy 334.297528 -29.814012)
		)
		(stroke
			(width 0)
			(type solid)
		)
		(fill yes)
		(layer "F.Cu")
		(net "GND")
	)
	(gr_poly
		(pts
			(xy 334.605884 -144.317212) (xy 334.605884 -143.178276) (xy 334.540352 -143.112744) (xy 334.108552 -143.112744)
			(xy 334.032352 -143.188944) (xy 334.032352 -144.306544) (xy 334.083152 -144.357344) (xy 334.565752 -144.357344)
		)
		(stroke
			(width 0)
			(type solid)
		)
		(fill yes)
		(layer "F.Cu")
		(net "GND")
	)
	(gr_poly
		(pts
			(xy 381.423418 -143.908018) (xy 381.423418 -139.779756) (xy 381.076962 -139.4333) (xy 375.95175 -139.4333)
			(xy 375.580656 -139.804394) (xy 375.580656 -144.929606) (xy 375.85777 -145.20672) (xy 380.124716 -145.20672)
		)
		(stroke
			(width 0)
			(type solid)
		)
		(fill yes)
		(layer "F.Cu")
		(net "GND")
	)
	(gr_poly
		(pts
			(xy 410.60624 -135.07593) (xy 410.60624 -133.127496) (xy 410.384752 -132.906008) (xy 408.496008 -132.906008)
			(xy 408.321256 -133.08076) (xy 408.321256 -134.153402) (xy 409.57373 -135.405876) (xy 410.276294 -135.405876)
		)
		(stroke
			(width 0)
			(type solid)
		)
		(fill yes)
		(layer "F.Cu")
		(net "P12V_AUX")
	)
	(gr_poly
		(pts
			(xy 412.363666 -144.22755) (xy 412.363666 -143.092678) (xy 412.296102 -143.025114) (xy 411.864302 -143.025114)
			(xy 411.788102 -143.101314) (xy 411.788102 -144.218914) (xy 411.838902 -144.269714) (xy 412.321502 -144.269714)
		)
		(stroke
			(width 0)
			(type solid)
		)
		(fill yes)
		(layer "F.Cu")
		(net "GND")
	)
	(gr_poly
		(pts
			(xy 430.53 -58.166) (xy 430.53 -57.658) (xy 430.403 -57.531) (xy 425.577 -57.531) (xy 425.45 -57.658)
			(xy 425.45 -58.166) (xy 425.577 -58.293) (xy 430.403 -58.293)
		)
		(stroke
			(width 0)
			(type solid)
		)
		(fill yes)
		(layer "F.Cu")
		(net "U124_VCC")
	)
	(gr_poly
		(pts
			(xy 437.714136 -29.949902) (xy 437.714136 -28.349702) (xy 437.688736 -28.324302) (xy 436.672736 -28.324302)
			(xy 436.494936 -28.502102) (xy 436.494936 -29.873702) (xy 436.672736 -30.051502) (xy 437.612536 -30.051502)
		)
		(stroke
			(width 0)
			(type solid)
		)
		(fill yes)
		(layer "F.Cu")
		(net "P3V3_AUX")
	)
	(gr_poly
		(pts
			(xy 439.060336 -26.978102) (xy 439.060336 -25.065482) (xy 438.952894 -24.95804) (xy 438.195212 -24.95804)
			(xy 438.14746 -25.006046) (xy 438.14746 -27.005026) (xy 438.272936 -27.130502) (xy 438.907936 -27.130502)
		)
		(stroke
			(width 0)
			(type solid)
		)
		(fill yes)
		(layer "F.Cu")
		(net "GND")
	)
	(gr_poly
		(pts
			(xy 440.457844 -29.948632) (xy 440.457844 -29.237432) (xy 440.407044 -29.186632) (xy 438.095644 -29.186632)
			(xy 437.994044 -29.288232) (xy 437.994044 -30.050232) (xy 438.347104 -30.403292) (xy 440.003184 -30.403292)
		)
		(stroke
			(width 0)
			(type solid)
		)
		(fill yes)
		(layer "F.Cu")
		(net "P12V_OCP_FLTB_1")
	)
	(gr_poly
		(pts
			(xy 450.288152 -395.521434) (xy 450.288152 -394.022834) (xy 450.262752 -393.997434) (xy 449.780152 -393.997434)
			(xy 449.754752 -394.022834) (xy 449.754752 -395.521434) (xy 449.780152 -395.546834) (xy 450.262752 -395.546834)
		)
		(stroke
			(width 0)
			(type solid)
		)
		(fill yes)
		(layer "F.Cu")
		(net "SW_P0V9_RETIMER_CPU0_SW2_RC")
	)
	(gr_poly
		(pts
			(xy 450.958966 -421.120824) (xy 450.958966 -420.231824) (xy 450.704966 -419.977824) (xy 449.688966 -419.977824)
			(xy 449.561966 -420.104824) (xy 449.561966 -421.247824) (xy 449.688966 -421.374824) (xy 450.704966 -421.374824)
		)
		(stroke
			(width 0)
			(type solid)
		)
		(fill yes)
		(layer "F.Cu")
		(net "P3V3_AUX")
	)
	(gr_poly
		(pts
			(xy 26.818336 -406.662636) (xy 26.818336 -403.930358) (xy 26.643584 -403.755606) (xy 25.881584 -403.755606)
			(xy 22.479254 -403.755606) (xy 22.349968 -403.884892) (xy 22.349968 -406.714706) (xy 22.544278 -406.909016)
			(xy 26.571956 -406.909016)
		)
		(stroke
			(width 0)
			(type solid)
		)
		(fill yes)
		(layer "F.Cu")
		(net "P12V_AUX")
	)
	(gr_poly
		(pts
			(xy 65.799462 -21.969984) (xy 65.774062 -21.944584) (xy 65.062862 -21.944584) (xy 64.910462 -22.096984)
			(xy 64.910462 -25.289002) (xy 65.367662 -25.746202) (xy 65.367662 -26.821384) (xy 65.443862 -26.897584)
			(xy 65.799462 -26.897584)
		)
		(stroke
			(width 0)
			(type solid)
		)
		(fill yes)
		(layer "F.Cu")
		(net "P12V_OCP_AVIN_PD_2")
	)
	(gr_poly
		(pts
			(xy 98.696018 -146.30527) (xy 98.696018 -142.177008) (xy 98.349562 -141.830552) (xy 93.061028 -141.830552)
			(xy 92.853256 -142.038324) (xy 92.853256 -143.793464) (xy 92.853256 -147.326858) (xy 93.13037 -147.603972)
			(xy 97.397316 -147.603972)
		)
		(stroke
			(width 0)
			(type solid)
		)
		(fill yes)
		(layer "F.Cu")
		(net "GND")
	)
	(gr_poly
		(pts
			(xy 122.256042 -78.883002) (xy 122.372882 -78.766162) (xy 122.372882 -77.84338) (xy 121.631456 -77.101954)
			(xy 121.49201 -77.101954) (xy 121.488962 -77.105002) (xy 121.488962 -78.890622) (xy 121.544842 -78.946502)
			(xy 122.192542 -78.946502)
		)
		(stroke
			(width 0)
			(type solid)
		)
		(fill yes)
		(layer "F.Cu")
		(net "P1V2_AUX_VCC")
	)
	(gr_poly
		(pts
			(xy 144.354042 -81.169002) (xy 144.470882 -81.052162) (xy 144.470882 -80.12938) (xy 143.729456 -79.387954)
			(xy 143.59001 -79.387954) (xy 143.586962 -79.391002) (xy 143.586962 -81.176622) (xy 143.642842 -81.232502)
			(xy 144.290542 -81.232502)
		)
		(stroke
			(width 0)
			(type solid)
		)
		(fill yes)
		(layer "F.Cu")
		(net "P1V8_AUX_VCC")
	)
	(gr_poly
		(pts
			(xy 175.822356 -23.016972) (xy 175.796956 -22.991572) (xy 175.085756 -22.991572) (xy 174.933356 -23.143972)
			(xy 174.933356 -26.33599) (xy 175.390556 -26.79319) (xy 175.390556 -27.868372) (xy 175.466756 -27.944572)
			(xy 175.822356 -27.944572)
		)
		(stroke
			(width 0)
			(type solid)
		)
		(fill yes)
		(layer "F.Cu")
		(net "P12V_SCM_AVIN_PD")
	)
	(gr_poly
		(pts
			(xy 246.997728 -55.841392) (xy 246.997728 -54.525926) (xy 246.808244 -54.336442) (xy 245.675658 -54.336442)
			(xy 245.550944 -54.461156) (xy 245.550944 -55.334916) (xy 245.76405 -55.84825) (xy 246.013478 -56.097678)
			(xy 246.741442 -56.097678)
		)
		(stroke
			(width 0)
			(type solid)
		)
		(fill yes)
		(layer "F.Cu")
		(net "GND")
	)
	(gr_poly
		(pts
			(xy 399.160492 -317.935102) (xy 399.160492 -315.072522) (xy 399.074386 -314.986416) (xy 395.39418 -314.986416)
			(xy 394.910564 -314.986416) (xy 394.786612 -315.110368) (xy 394.786612 -317.162688) (xy 396.211044 -318.58712)
			(xy 398.508474 -318.58712)
		)
		(stroke
			(width 0)
			(type solid)
		)
		(fill yes)
		(layer "F.Cu")
		(net "GND")
	)
	(gr_poly
		(pts
			(xy 404.133304 -318.219074) (xy 404.133304 -316.18936) (xy 403.693122 -315.749178) (xy 403.555454 -315.749178)
			(xy 399.744184 -315.749178) (xy 399.618962 -315.8744) (xy 399.618962 -318.153542) (xy 400.012408 -318.546988)
			(xy 403.80539 -318.546988)
		)
		(stroke
			(width 0)
			(type solid)
		)
		(fill yes)
		(layer "F.Cu")
		(net "GND")
	)
	(gr_poly
		(pts
			(xy 425.672758 -359.150412) (xy 425.677838 -359.150412) (xy 425.677838 -357.407972) (xy 425.535598 -357.265732)
			(xy 424.788838 -357.265732) (xy 424.428158 -357.626412) (xy 424.428158 -359.168192) (xy 424.517058 -359.257092)
			(xy 425.566078 -359.257092)
		)
		(stroke
			(width 0)
			(type solid)
		)
		(fill yes)
		(layer "F.Cu")
		(net "GND")
	)
	(gr_poly
		(pts
			(xy 444.293498 -341.705692) (xy 444.293498 -333.295752) (xy 443.750192 -332.752446) (xy 415.875724 -332.752446)
			(xy 415.751518 -332.876652) (xy 415.751518 -333.437992) (xy 415.751518 -340.999318) (xy 416.717226 -341.965026)
			(xy 444.034164 -341.965026)
		)
		(stroke
			(width 0)
			(type solid)
		)
		(fill yes)
		(layer "F.Cu")
		(net "PVDD11_S3_P0")
	)
	(gr_poly
		(pts
			(xy 25.209754 -344.794586) (xy 25.209754 -344.447622) (xy 24.779732 -344.0176) (xy 24.779732 -343.378282)
			(xy 24.758142 -343.356692) (xy 24.306784 -343.356692) (xy 24.273002 -343.390474) (xy 24.273002 -344.48369)
			(xy 24.646382 -344.85707) (xy 25.14727 -344.85707)
		)
		(stroke
			(width 0)
			(type solid)
		)
		(fill yes)
		(layer "F.Cu")
		(net "SW_PVDDIO_P1_SW4_RC")
	)
	(gr_poly
		(pts
			(xy 32.7152 -366.31753) (xy 32.7152 -362.1024) (xy 32.7152 -361.8992) (xy 32.6898 -361.8738) (xy 28.2956 -361.8738)
			(xy 28.245308 -361.924092) (xy 28.245308 -362.086144) (xy 28.245308 -366.318292) (xy 28.2702 -366.34293)
			(xy 32.6898 -366.34293)
		)
		(stroke
			(width 0)
			(type solid)
		)
		(fill yes)
		(layer "F.Cu")
		(net "GND")
	)
	(gr_poly
		(pts
			(xy 67.277488 -149.548342) (xy 67.277488 -148.078952) (xy 67.262502 -148.063966) (xy 67.239642 -148.041106)
			(xy 66.83375 -148.041106) (xy 66.764916 -148.10994) (xy 66.764916 -149.54631) (xy 66.770504 -149.551898)
			(xy 67.056254 -149.551898) (xy 67.273932 -149.551898)
		)
		(stroke
			(width 0)
			(type solid)
		)
		(fill yes)
		(layer "F.Cu")
		(net "SW_PVDD18_S5_P1_BST_R")
	)
	(gr_poly
		(pts
			(xy 100.338382 -338.031836) (xy 100.338382 -337.665822) (xy 99.903788 -337.231228) (xy 99.903788 -336.719672)
			(xy 99.837494 -336.653378) (xy 99.482402 -336.653378) (xy 99.40163 -336.73415) (xy 99.40163 -337.70189)
			(xy 99.77501 -338.07527) (xy 100.294948 -338.07527)
		)
		(stroke
			(width 0)
			(type solid)
		)
		(fill yes)
		(layer "F.Cu")
		(net "SW_PVDDCR_CPU1_P1_SW6_RC")
	)
	(gr_poly
		(pts
			(xy 122.715274 -147.296632) (xy 122.715274 -143.837152) (xy 122.715274 -142.308072) (xy 122.324114 -141.916912)
			(xy 115.118134 -141.916912) (xy 114.754914 -142.280132) (xy 114.754914 -143.819372) (xy 114.754914 -147.202652)
			(xy 115.087654 -147.535392) (xy 122.476514 -147.535392)
		)
		(stroke
			(width 0)
			(type solid)
		)
		(fill yes)
		(layer "F.Cu")
		(net "P12V_AUX")
	)
	(gr_poly
		(pts
			(xy 141.47292 -51.01336) (xy 141.47292 -47.87646) (xy 141.05382 -47.45736) (xy 140.56106 -47.45736)
			(xy 140.31468 -47.70374) (xy 140.31468 -48.6664) (xy 139.56284 -49.41824) (xy 139.56284 -51.17338)
			(xy 139.75842 -51.36896) (xy 141.11732 -51.36896)
		)
		(stroke
			(width 0)
			(type solid)
		)
		(fill yes)
		(layer "F.Cu")
		(net "P5V_AUX")
	)
	(gr_poly
		(pts
			(xy 182.428642 -364.659418) (xy 182.428642 -364.105952) (xy 182.428642 -359.152952) (xy 182.174642 -358.898952)
			(xy 180.142642 -358.898952) (xy 179.888642 -359.152952) (xy 179.888642 -364.105952) (xy 179.888642 -364.72876)
			(xy 180.085238 -364.925356) (xy 182.162704 -364.925356)
		)
		(stroke
			(width 0)
			(type solid)
		)
		(fill yes)
		(layer "F.Cu")
		(net "P12V_AUX")
	)
	(gr_poly
		(pts
			(xy 197.110858 -386.46862) (xy 198.817738 -386.46862) (xy 198.825358 -386.461) (xy 198.825358 -385.865116)
			(xy 198.81596 -385.855718) (xy 196.01688 -385.855718) (xy 195.954904 -385.917694) (xy 195.954904 -387.060694)
			(xy 196.033644 -387.139434) (xy 196.440044 -387.139434)
		)
		(stroke
			(width 0)
			(type solid)
		)
		(fill yes)
		(layer "F.Cu")
		(net "P12V_HSC_GATE2")
	)
	(gr_poly
		(pts
			(xy 198.827644 -385.45516) (xy 198.827644 -384.869436) (xy 198.812404 -384.854196) (xy 197.176898 -384.854196)
			(xy 196.520562 -384.854196) (xy 196.495924 -384.878834) (xy 196.495924 -385.424934) (xy 196.53631 -385.46532)
			(xy 197.178422 -385.46532) (xy 198.817484 -385.46532)
		)
		(stroke
			(width 0)
			(type solid)
		)
		(fill yes)
		(layer "F.Cu")
		(net "P12V_HSC_GATE1")
	)
	(gr_poly
		(pts
			(xy 202.976734 -33.746948) (xy 202.976734 -31.08198) (xy 202.296014 -30.40126) (xy 201.246232 -30.40126)
			(xy 200.88352 -30.038548) (xy 198.226934 -30.038548) (xy 197.693534 -30.571948) (xy 197.693534 -34.254948)
			(xy 197.845934 -34.407348) (xy 202.316334 -34.407348)
		)
		(stroke
			(width 0)
			(type solid)
		)
		(fill yes)
		(layer "F.Cu")
		(net "P12V_SCM")
	)
	(gr_poly
		(pts
			(xy 205.177898 -338.066634) (xy 205.177898 -337.660234) (xy 205.101698 -337.584034) (xy 204.390498 -337.584034)
			(xy 204.314298 -337.507834) (xy 203.653898 -337.507834) (xy 203.603098 -337.558634) (xy 203.603098 -338.092034)
			(xy 203.653898 -338.142834) (xy 205.101698 -338.142834)
		)
		(stroke
			(width 0)
			(type solid)
		)
		(fill yes)
		(layer "F.Cu")
		(net "SW_PVDD_33_S5_BST_R")
	)
	(gr_poly
		(pts
			(xy 205.465426 -347.846142) (xy 205.465426 -347.430598) (xy 205.465426 -346.135452) (xy 205.28788 -345.957906)
			(xy 203.726034 -345.957906) (xy 203.638658 -346.045536) (xy 203.638658 -347.902276) (xy 203.723494 -347.987112)
			(xy 204.908912 -347.987112) (xy 205.324456 -347.987112)
		)
		(stroke
			(width 0)
			(type solid)
		)
		(fill yes)
		(layer "F.Cu")
		(net "P12V_AUX")
	)
	(gr_poly
		(pts
			(xy 205.529434 -330.704952) (xy 205.529434 -328.164952) (xy 205.529434 -326.324214) (xy 205.32344 -326.11822)
			(xy 197.55358 -326.11822) (xy 197.147434 -326.524366) (xy 197.147434 -328.139552) (xy 197.147434 -330.806552)
			(xy 197.213474 -330.872592) (xy 205.361794 -330.872592)
		)
		(stroke
			(width 0)
			(type solid)
		)
		(fill yes)
		(layer "F.Cu")
		(net "PVDD_33_S5")
	)
	(gr_poly
		(pts
			(xy 225.106738 -273.442684) (xy 225.106738 -269.005812) (xy 225.242628 -268.869922) (xy 225.242628 -268.049248)
			(xy 225.090482 -267.897102) (xy 221.82582 -267.897102) (xy 221.481904 -268.241018) (xy 221.481904 -273.38401)
			(xy 221.715076 -273.617182) (xy 224.93224 -273.617182)
		)
		(stroke
			(width 0)
			(type solid)
		)
		(fill yes)
		(layer "F.Cu")
		(net "P12V_AUX")
	)
	(gr_poly
		(pts
			(xy 234.034076 -45.626782) (xy 234.034076 -42.433494) (xy 233.76763 -42.167048) (xy 231.28859 -42.167048)
			(xy 231.201976 -42.253662) (xy 231.043734 -42.411904) (xy 231.043734 -45.734986) (xy 231.104694 -45.795946)
			(xy 233.266234 -45.795946) (xy 233.864912 -45.795946)
		)
		(stroke
			(width 0)
			(type solid)
		)
		(fill yes)
		(layer "F.Cu")
		(net "GND")
	)
	(gr_poly
		(pts
			(xy 243.9162 -382.86182) (xy 243.9162 -381.0889) (xy 243.83492 -381.00762) (xy 243.83492 -380.4412)
			(xy 243.80444 -380.41072) (xy 243.34216 -380.41072) (xy 243.1796 -380.57328) (xy 243.1796 -382.83896)
			(xy 243.21008 -382.86944) (xy 243.90858 -382.86944)
		)
		(stroke
			(width 0)
			(type solid)
		)
		(fill yes)
		(layer "F.Cu")
		(net "P12V_HSC_GATE_G5")
	)
	(gr_poly
		(pts
			(xy 249.074178 -315.60008) (xy 249.074178 -308.369462) (xy 248.560082 -307.855366) (xy 237.941612 -307.855366)
			(xy 237.929166 -307.84292) (xy 237.383574 -308.388512) (xy 237.383574 -315.708284) (xy 237.440978 -315.765942)
			(xy 247.9802 -315.765942) (xy 248.908316 -315.765942)
		)
		(stroke
			(width 0)
			(type solid)
		)
		(fill yes)
		(layer "F.Cu")
		(net "P1V8_CPU0_RT_1D")
	)
	(gr_poly
		(pts
			(xy 249.851164 -382.86182) (xy 249.851164 -381.0889) (xy 249.769884 -381.00762) (xy 249.769884 -380.4412)
			(xy 249.739404 -380.41072) (xy 249.277124 -380.41072) (xy 249.114564 -380.57328) (xy 249.114564 -382.83896)
			(xy 249.145044 -382.86944) (xy 249.843544 -382.86944)
		)
		(stroke
			(width 0)
			(type solid)
		)
		(fill yes)
		(layer "F.Cu")
		(net "P12V_HSC_GATE_G6")
	)
	(gr_poly
		(pts
			(xy 252.3236 -273.403822) (xy 252.3236 -267.80363) (xy 252.181106 -267.661136) (xy 248.87555 -267.661136)
			(xy 248.77395 -267.762736) (xy 248.77395 -273.325336) (xy 248.77395 -273.426936) (xy 248.95175 -273.604736)
			(xy 249.05335 -273.604736) (xy 252.122686 -273.604736)
		)
		(stroke
			(width 0)
			(type solid)
		)
		(fill yes)
		(layer "F.Cu")
		(net "P12V_AUX")
	)
	(gr_poly
		(pts
			(xy 255.757934 -55.574946) (xy 255.757934 -53.464206) (xy 255.559814 -53.266086) (xy 254.866394 -53.266086)
			(xy 254.843534 -53.288946) (xy 254.843534 -53.949346) (xy 255.072134 -54.177946) (xy 255.072134 -55.600346)
			(xy 255.173734 -55.701946) (xy 255.630934 -55.701946)
		)
		(stroke
			(width 0)
			(type solid)
		)
		(fill yes)
		(layer "F.Cu")
		(net "P12V_E1S_FLTB_0")
	)
	(gr_poly
		(pts
			(xy 255.786128 -382.86182) (xy 255.786128 -381.0889) (xy 255.704848 -381.00762) (xy 255.704848 -380.4412)
			(xy 255.674368 -380.41072) (xy 255.212088 -380.41072) (xy 255.049528 -380.57328) (xy 255.049528 -382.83896)
			(xy 255.080008 -382.86944) (xy 255.778508 -382.86944)
		)
		(stroke
			(width 0)
			(type solid)
		)
		(fill yes)
		(layer "F.Cu")
		(net "P12V_HSC_GATE_G1")
	)
	(gr_poly
		(pts
			(xy 260.307074 -38.984174) (xy 260.307074 -37.218874) (xy 260.192012 -37.103812) (xy 260.073394 -36.985194)
			(xy 259.063998 -36.985194) (xy 258.94538 -37.103812) (xy 258.830318 -37.218874) (xy 258.830318 -38.984174)
			(xy 258.888738 -39.042594) (xy 260.248654 -39.042594)
		)
		(stroke
			(width 0)
			(type solid)
		)
		(fill yes)
		(layer "F.Cu")
		(net "GND")
	)
	(gr_poly
		(pts
			(xy 261.721092 -382.86182) (xy 261.721092 -381.0889) (xy 261.639812 -381.00762) (xy 261.639812 -380.4412)
			(xy 261.609332 -380.41072) (xy 261.147052 -380.41072) (xy 260.984492 -380.57328) (xy 260.984492 -382.83896)
			(xy 261.014972 -382.86944) (xy 261.713472 -382.86944)
		)
		(stroke
			(width 0)
			(type solid)
		)
		(fill yes)
		(layer "F.Cu")
		(net "P12V_HSC_GATE_G2")
	)
	(gr_poly
		(pts
			(xy 267.656056 -382.86182) (xy 267.656056 -381.0889) (xy 267.574776 -381.00762) (xy 267.574776 -380.4412)
			(xy 267.544296 -380.41072) (xy 267.082016 -380.41072) (xy 266.919456 -380.57328) (xy 266.919456 -382.83896)
			(xy 266.949936 -382.86944) (xy 267.648436 -382.86944)
		)
		(stroke
			(width 0)
			(type solid)
		)
		(fill yes)
		(layer "F.Cu")
		(net "P12V_HSC_GATE_G3")
	)
	(gr_poly
		(pts
			(xy 273.59102 -382.86182) (xy 273.59102 -381.0889) (xy 273.50974 -381.00762) (xy 273.50974 -380.4412)
			(xy 273.47926 -380.41072) (xy 273.01698 -380.41072) (xy 272.85442 -380.57328) (xy 272.85442 -382.83896)
			(xy 272.8849 -382.86944) (xy 273.5834 -382.86944)
		)
		(stroke
			(width 0)
			(type solid)
		)
		(fill yes)
		(layer "F.Cu")
		(net "P12V_HSC_GATE_G4")
	)
	(gr_poly
		(pts
			(xy 279.525984 -382.86182) (xy 279.525984 -381.0889) (xy 279.444704 -381.00762) (xy 279.444704 -380.4412)
			(xy 279.414224 -380.41072) (xy 278.951944 -380.41072) (xy 278.789384 -380.57328) (xy 278.789384 -382.83896)
			(xy 278.819864 -382.86944) (xy 279.518364 -382.86944)
		)
		(stroke
			(width 0)
			(type solid)
		)
		(fill yes)
		(layer "F.Cu")
		(net "MB0_CM_GATE_G0")
	)
	(gr_poly
		(pts
			(xy 291.70249 -365.186722) (xy 291.70249 -362.39704) (xy 291.70249 -361.443778) (xy 291.558472 -361.29976)
			(xy 283.984192 -361.29976) (xy 283.471112 -361.29976) (xy 283.300932 -361.46994) (xy 283.300932 -365.14786)
			(xy 283.504132 -365.35106) (xy 291.538152 -365.35106)
		)
		(stroke
			(width 0)
			(type solid)
		)
		(fill yes)
		(layer "F.Cu")
		(net "P12V_AUX")
	)
	(gr_poly
		(pts
			(xy 312.3692 -362.88853) (xy 312.3692 -358.6734) (xy 312.3692 -358.4702) (xy 312.3438 -358.4448)
			(xy 307.9496 -358.4448) (xy 307.899308 -358.495092) (xy 307.899308 -358.657144) (xy 307.899308 -362.889292)
			(xy 307.9242 -362.91393) (xy 312.3438 -362.91393)
		)
		(stroke
			(width 0)
			(type solid)
		)
		(fill yes)
		(layer "F.Cu")
		(net "GND")
	)
	(gr_poly
		(pts
			(xy 323.310504 -333.066136) (xy 323.310504 -332.709774) (xy 322.879212 -332.278482) (xy 322.879212 -331.660754)
			(xy 322.858384 -331.639926) (xy 322.419726 -331.639926) (xy 322.373752 -331.6859) (xy 322.373752 -332.694534)
			(xy 322.788788 -333.10957) (xy 323.26707 -333.10957)
		)
		(stroke
			(width 0)
			(type solid)
		)
		(fill yes)
		(layer "F.Cu")
		(net "SW_PVDDCR_CPU1_P0_SW2_RC")
	)
	(gr_poly
		(pts
			(xy 331.66812 -333.024734) (xy 331.66812 -332.700122) (xy 331.236828 -332.26883) (xy 331.236828 -331.69606)
			(xy 331.217524 -331.676756) (xy 330.800202 -331.676756) (xy 330.731368 -331.74559) (xy 330.731368 -332.679294)
			(xy 331.161644 -333.10957) (xy 331.583284 -333.10957)
		)
		(stroke
			(width 0)
			(type solid)
		)
		(fill yes)
		(layer "F.Cu")
		(net "SW_PVDDCR_CPU1_P0_SW1_RC")
	)
	(gr_poly
		(pts
			(xy 332.553564 -135.817102) (xy 332.553564 -134.521702) (xy 332.451964 -134.420102) (xy 331.080364 -134.420102)
			(xy 330.902564 -134.420102) (xy 330.699364 -134.623302) (xy 330.699364 -135.690102) (xy 330.902564 -135.893302)
			(xy 331.080364 -135.893302) (xy 332.477364 -135.893302)
		)
		(stroke
			(width 0)
			(type solid)
		)
		(fill yes)
		(layer "F.Cu")
		(net "GND")
	)
	(gr_poly
		(pts
			(xy 332.7654 -143.9672) (xy 332.7654 -143.455136) (xy 332.742032 -143.431768) (xy 331.218032 -143.431768)
			(xy 331.1906 -143.4592) (xy 331.1906 -143.8656) (xy 331.2668 -143.9418) (xy 331.978 -143.9418) (xy 332.0542 -144.018)
			(xy 332.7146 -144.018)
		)
		(stroke
			(width 0)
			(type solid)
		)
		(fill yes)
		(layer "F.Cu")
		(net "SW_PVDD18_S5_P0_BST_R")
	)
	(gr_poly
		(pts
			(xy 336.423 -165.53434) (xy 336.423 -161.66084) (xy 336.1944 -161.43224) (xy 333.5782 -161.43224)
			(xy 332.69936 -161.43224) (xy 332.4606 -161.671) (xy 332.4606 -165.4556) (xy 332.71714 -165.71214)
			(xy 333.863188 -165.71214) (xy 336.2452 -165.71214)
		)
		(stroke
			(width 0)
			(type solid)
		)
		(fill yes)
		(layer "F.Cu")
		(net "GND")
	)
	(gr_poly
		(pts
			(xy 401.057364 -150.941532) (xy 401.057364 -150.066502) (xy 401.057364 -146.688302) (xy 400.904964 -146.535902)
			(xy 396.270734 -146.535902) (xy 396.20063 -146.606006) (xy 396.20063 -149.990302) (xy 396.20063 -151.050244)
			(xy 396.366492 -151.216106) (xy 400.78279 -151.216106)
		)
		(stroke
			(width 0)
			(type solid)
		)
		(fill yes)
		(layer "F.Cu")
		(net "P5V")
	)
	(gr_poly
		(pts
			(xy 422.83888 -100.825808) (xy 422.83888 -100.165408) (xy 421.84828 -99.174808) (xy 421.84828 -96.888808)
			(xy 421.56888 -96.609408) (xy 418.67328 -96.609408) (xy 417.91128 -97.371408) (xy 417.91128 -100.851208)
			(xy 418.19068 -101.130608) (xy 422.53408 -101.130608)
		)
		(stroke
			(width 0)
			(type solid)
		)
		(fill yes)
		(layer "F.Cu")
		(net "GND")
	)
	(gr_poly
		(pts
			(xy 428.551594 -349.21571) (xy 428.551594 -348.83852) (xy 428.148496 -348.435422) (xy 428.148496 -347.861636)
			(xy 428.106332 -347.819472) (xy 427.684692 -347.819472) (xy 427.643036 -347.861128) (xy 427.643036 -348.853252)
			(xy 428.065946 -349.276162) (xy 428.491142 -349.276162)
		)
		(stroke
			(width 0)
			(type solid)
		)
		(fill yes)
		(layer "F.Cu")
		(net "SW_PVDD11_S3_P0_SW2_RC")
	)
	(gr_poly
		(pts
			(xy 441.194952 -395.521434) (xy 441.194952 -395.496034) (xy 441.194952 -394.022834) (xy 441.169552 -393.997434)
			(xy 440.686952 -393.997434) (xy 440.661552 -394.022834) (xy 440.661552 -395.521434) (xy 440.686952 -395.546834)
			(xy 441.144152 -395.546834) (xy 441.169552 -395.546834)
		)
		(stroke
			(width 0)
			(type solid)
		)
		(fill yes)
		(layer "F.Cu")
		(net "SW_P0V9_RETIMER_CPU0_SW1_RC")
	)
	(gr_poly
		(pts
			(xy 75.348338 -333.08163) (xy 75.348338 -332.700884) (xy 74.948542 -332.301342) (xy 74.948542 -331.640434)
			(xy 74.922126 -331.614018) (xy 74.626216 -331.614018) (xy 74.470768 -331.614018) (xy 74.436986 -331.6478)
			(xy 74.436986 -332.695296) (xy 74.856086 -333.114396) (xy 75.315572 -333.114396)
		)
		(stroke
			(width 0)
			(type solid)
		)
		(fill yes)
		(layer "F.Cu")
		(net "SW_PVDDCR_CPU1_P1_SW2_RC")
	)
	(gr_poly
		(pts
			(xy 86.612222 -186.025282) (xy 86.612222 -185.019188) (xy 86.200996 -184.607962) (xy 85.718904 -184.607962)
			(xy 85.67547 -184.651396) (xy 85.67547 -185.01741) (xy 86.100666 -185.442606) (xy 86.105746 -185.447686)
			(xy 86.105746 -186.087004) (xy 86.127082 -186.10834) (xy 86.529164 -186.10834)
		)
		(stroke
			(width 0)
			(type solid)
		)
		(fill yes)
		(layer "F.Cu")
		(net "SW_PVDDCR_CPU0_P1_SW1_RC")
	)
	(gr_poly
		(pts
			(xy 92.903294 -157.192472) (xy 92.903294 -154.325066) (xy 92.903294 -153.786332) (xy 90.515694 -151.398732)
			(xy 83.41106 -151.398732) (xy 83.3755 -151.434292) (xy 83.3755 -151.582628) (xy 83.3755 -157.549596)
			(xy 83.451192 -157.625288) (xy 83.905598 -157.625288) (xy 92.470478 -157.625288)
		)
		(stroke
			(width 0)
			(type solid)
		)
		(fill yes)
		(layer "F.Cu")
		(net "P12V_AUX")
	)
	(gr_poly
		(pts
			(xy 94.561914 -354.288344) (xy 94.561914 -352.034856) (xy 94.561914 -350.796098) (xy 94.561914 -350.606868)
			(xy 94.277434 -350.322388) (xy 87.01278 -350.322388) (xy 86.79434 -350.540828) (xy 86.756748 -350.57842)
			(xy 86.756748 -354.57384) (xy 86.860888 -354.67798) (xy 94.172278 -354.67798)
		)
		(stroke
			(width 0)
			(type solid)
		)
		(fill yes)
		(layer "F.Cu")
		(net "P12V_AUX")
	)
	(gr_poly
		(pts
			(xy 111.783622 -181.35981) (xy 111.783622 -180.480716) (xy 111.338868 -180.035962) (xy 110.890304 -180.035962)
			(xy 110.84687 -180.079396) (xy 110.84687 -180.44541) (xy 111.272066 -180.870606) (xy 111.282734 -180.881274)
			(xy 111.282734 -181.401466) (xy 111.317278 -181.43601) (xy 111.707422 -181.43601)
		)
		(stroke
			(width 0)
			(type solid)
		)
		(fill yes)
		(layer "F.Cu")
		(net "SW_PVDDCR_CPU0_P1_SW4_RC")
	)
	(gr_poly
		(pts
			(xy 120.013222 -175.11141) (xy 120.013222 -174.215298) (xy 119.585486 -173.787562) (xy 119.154956 -173.787562)
			(xy 119.07647 -173.866048) (xy 119.07647 -174.19701) (xy 119.501666 -174.622206) (xy 119.501666 -174.722028)
			(xy 119.501666 -175.142398) (xy 119.546878 -175.18761) (xy 119.937022 -175.18761)
		)
		(stroke
			(width 0)
			(type solid)
		)
		(fill yes)
		(layer "F.Cu")
		(net "SW_PVDDCR_SOC_P1_SW1_RC")
	)
	(gr_poly
		(pts
			(xy 128.293622 -168.418764) (xy 128.293622 -167.429942) (xy 127.920242 -167.056562) (xy 127.442722 -167.056562)
			(xy 127.35687 -167.142414) (xy 127.35687 -167.46601) (xy 127.782066 -167.891206) (xy 127.786892 -167.896032)
			(xy 127.786892 -168.43121) (xy 127.807974 -168.452292) (xy 128.260094 -168.452292)
		)
		(stroke
			(width 0)
			(type solid)
		)
		(fill yes)
		(layer "F.Cu")
		(net "SW_PVDDCR_SOC_P1_SW2_RC")
	)
	(gr_poly
		(pts
			(xy 179.528978 -349.371158) (xy 179.528978 -349.021908) (xy 179.103782 -348.596712) (xy 179.103782 -348.49689)
			(xy 179.103782 -347.957394) (xy 179.077366 -347.930978) (xy 178.700938 -347.930978) (xy 178.592226 -348.03969)
			(xy 178.592226 -348.998286) (xy 179.025296 -349.431356) (xy 179.46878 -349.431356)
		)
		(stroke
			(width 0)
			(type solid)
		)
		(fill yes)
		(layer "F.Cu")
		(net "SW_PVDD11_S3_P1_SW1_RC")
	)
	(gr_poly
		(pts
			(xy 224.013776 -73.748138) (xy 224.013776 -72.671178) (xy 224.013776 -71.617078) (xy 223.388936 -70.992238)
			(xy 223.261936 -70.992238) (xy 223.203516 -71.050658) (xy 223.203516 -71.927466) (xy 223.378776 -72.102726)
			(xy 223.378776 -73.748138) (xy 223.505776 -73.875138) (xy 223.886776 -73.875138)
		)
		(stroke
			(width 0)
			(type solid)
		)
		(fill yes)
		(layer "F.Cu")
		(net "GND")
	)
	(gr_poly
		(pts
			(xy 225.805746 -57.0865) (xy 226.97948 -57.0865) (xy 227.368608 -56.697372) (xy 228.463094 -54.203092)
			(xy 228.463094 -52.687728) (xy 228.025198 -52.249832) (xy 220.68536 -52.249832) (xy 220.35516 -52.580032)
			(xy 220.35516 -57.050432) (xy 220.40596 -57.101232) (xy 225.79076 -57.101232)
		)
		(stroke
			(width 0)
			(type solid)
		)
		(fill yes)
		(layer "F.Cu")
		(net "P3V3_E1S_0")
	)
	(gr_poly
		(pts
			(xy 254.747522 -418.578538) (xy 254.747522 -417.503102) (xy 254.747522 -413.79394) (xy 254.293878 -413.340296)
			(xy 244.694964 -413.340296) (xy 240.346484 -413.340296) (xy 238.750094 -414.936686) (xy 238.750094 -418.688266)
			(xy 239.121188 -419.05936) (xy 243.4971 -419.05936) (xy 254.2667 -419.05936)
		)
		(stroke
			(width 0)
			(type solid)
		)
		(fill yes)
		(layer "F.Cu")
		(net "P12V_PSU_FUSE")
	)
	(gr_poly
		(pts
			(xy 255.42494 -96.879156) (xy 255.42494 -95.721932) (xy 256.03327 -95.113602) (xy 256.03327 -92.967556)
			(xy 255.92532 -92.859606) (xy 254.967486 -92.859606) (xy 254.967486 -94.798642) (xy 254.350774 -95.415354)
			(xy 254.350774 -97.04578) (xy 254.390144 -97.08515) (xy 255.218946 -97.08515)
		)
		(stroke
			(width 0)
			(type solid)
		)
		(fill yes)
		(layer "F.Cu")
		(net "PVDD18_S5_P0")
	)
	(gr_poly
		(pts
			(xy 280.29154 -380.87554) (xy 280.29154 -380.40056) (xy 280.29154 -379.7935) (xy 280.2255 -379.72746)
			(xy 279.78608 -379.72746) (xy 279.698704 -379.814836) (xy 279.698704 -380.46152) (xy 279.698704 -380.88316)
			(xy 279.749504 -380.93396) (xy 279.940004 -380.93396) (xy 280.23312 -380.93396)
		)
		(stroke
			(width 0)
			(type solid)
		)
		(fill yes)
		(layer "F.Cu")
		(net "P12V_HSC_GATE1")
	)
	(gr_poly
		(pts
			(xy 383.183638 -158.302198) (xy 383.183638 -151.807672) (xy 382.929638 -151.553672) (xy 381.852678 -151.553672)
			(xy 367.330228 -151.553672) (xy 366.900968 -151.982932) (xy 366.006888 -151.982932) (xy 365.695992 -152.293828)
			(xy 365.695992 -158.392876) (xy 365.85271 -158.549594) (xy 382.936242 -158.549594)
		)
		(stroke
			(width 0)
			(type solid)
		)
		(fill yes)
		(layer "F.Cu")
		(net "P12V_AUX")
	)
	(gr_poly
		(pts
			(xy 442.194442 -365.154972) (xy 442.194442 -363.208316) (xy 443.560962 -361.841796) (xy 443.560962 -357.886)
			(xy 443.433962 -357.759) (xy 439.5851 -357.759) (xy 439.4581 -357.886) (xy 439.4581 -365.25708) (xy 439.543698 -365.342678)
			(xy 439.993024 -365.342678) (xy 442.006736 -365.342678)
		)
		(stroke
			(width 0)
			(type solid)
		)
		(fill yes)
		(layer "F.Cu")
		(net "P12V_AUX")
	)
	(gr_poly
		(pts
			(xy 30.99181 -344.070432) (xy 30.99181 -340.447376) (xy 30.97911 -340.434676) (xy 26.45791 -340.434676)
			(xy 26.44521 -340.447376) (xy 26.44521 -342.71204) (xy 25.800558 -343.356692) (xy 25.09266 -343.356692)
			(xy 25.033732 -343.41562) (xy 25.033732 -343.908888) (xy 25.263602 -344.138758) (xy 30.923484 -344.138758)
		)
		(stroke
			(width 0)
			(type solid)
		)
		(fill yes)
		(layer "F.Cu")
		(net "SW_PVDDIO_P1_SW4")
	)
	(gr_poly
		(pts
			(xy 31.206694 -339.166454) (xy 31.206694 -337.744054) (xy 31.028894 -337.566254) (xy 26.282142 -337.566254)
			(xy 25.892506 -337.176618) (xy 25.892506 -335.748884) (xy 25.686766 -335.543144) (xy 18.546826 -335.543144)
			(xy 18.405094 -335.684876) (xy 18.405094 -338.783422) (xy 18.886424 -339.264752) (xy 31.108396 -339.264752)
		)
		(stroke
			(width 0)
			(type solid)
		)
		(fill yes)
		(layer "F.Cu")
		(net "IND_PVDDIO_P1_CPL0")
	)
	(gr_poly
		(pts
			(xy 48.51146 -102.02418) (xy 48.51146 -99.80422) (xy 48.44542 -99.73818) (xy 46.33722 -99.73818)
			(xy 46.2534 -99.822) (xy 46.2534 -100.18522) (xy 46.3169 -100.24872) (xy 47.5742 -100.24872) (xy 47.77486 -100.44938)
			(xy 47.77486 -102.01656) (xy 47.8282 -102.0699) (xy 48.46574 -102.0699)
		)
		(stroke
			(width 0)
			(type solid)
		)
		(fill yes)
		(layer "F.Cu")
		(net "P3V3_AUX_DSC_VOL")
	)
	(gr_poly
		(pts
			(xy 57.038494 -334.670654) (xy 57.038494 -327.635362) (xy 56.241442 -326.83831) (xy 23.038816 -326.83831)
			(xy 22.619462 -327.257664) (xy 22.619462 -332.289658) (xy 22.837902 -332.508098) (xy 24.546814 -332.508098)
			(xy 25.034494 -332.995778) (xy 25.034494 -334.873854) (xy 25.195784 -335.035144) (xy 56.674004 -335.035144)
		)
		(stroke
			(width 0)
			(type solid)
		)
		(fill yes)
		(layer "F.Cu")
		(net "PVDDIO_P1")
	)
	(gr_poly
		(pts
			(xy 63.217298 -26.807922) (xy 63.217298 -24.117808) (xy 63.422022 -23.913084) (xy 64.285622 -23.913084)
			(xy 64.361822 -23.836884) (xy 64.361822 -23.074884) (xy 64.234822 -22.947884) (xy 62.990222 -22.947884)
			(xy 62.507622 -23.430484) (xy 62.507622 -26.807922) (xy 62.564772 -26.865072) (xy 63.160148 -26.865072)
		)
		(stroke
			(width 0)
			(type solid)
		)
		(fill yes)
		(layer "F.Cu")
		(net "P12V_AUX")
	)
	(gr_poly
		(pts
			(xy 67.81927 -175.1838) (xy 67.81927 -172.921422) (xy 68.469002 -172.27169) (xy 69.1769 -172.27169)
			(xy 69.211444 -172.237146) (xy 69.211444 -171.746418) (xy 68.997068 -171.532042) (xy 63.303658 -171.532042)
			(xy 63.229744 -171.605956) (xy 63.229744 -175.211232) (xy 63.260732 -175.24222) (xy 67.76085 -175.24222)
		)
		(stroke
			(width 0)
			(type solid)
		)
		(fill yes)
		(layer "F.Cu")
		(net "SW_PVDDCR_CPU0_P1_SW6")
	)
	(gr_poly
		(pts
			(xy 78.288642 -180.903118) (xy 78.288642 -179.863242) (xy 78.131924 -179.706524) (xy 77.915262 -179.489862)
			(xy 77.395324 -179.489862) (xy 77.35189 -179.533296) (xy 77.35189 -179.89931) (xy 77.777086 -180.324506)
			(xy 77.777086 -180.424328) (xy 77.777086 -180.963824) (xy 77.803502 -180.99024) (xy 78.20152 -180.99024)
		)
		(stroke
			(width 0)
			(type solid)
		)
		(fill yes)
		(layer "F.Cu")
		(net "SW_PVDDCR_CPU0_P1_SW5_RC")
	)
	(gr_poly
		(pts
			(xy 83.731354 -333.070962) (xy 83.731354 -332.704948) (xy 83.301332 -332.274926) (xy 83.301332 -331.643736)
			(xy 83.271614 -331.614018) (xy 82.983832 -331.614018) (xy 82.828384 -331.614018) (xy 82.794602 -331.6478)
			(xy 82.794602 -332.741016) (xy 82.95132 -332.897734) (xy 83.167982 -333.114396) (xy 83.68792 -333.114396)
		)
		(stroke
			(width 0)
			(type solid)
		)
		(fill yes)
		(layer "F.Cu")
		(net "SW_PVDDCR_CPU1_P1_SW1_RC")
	)
	(gr_poly
		(pts
			(xy 89.121234 -73.324974) (xy 89.121234 -70.575424) (xy 91.708986 -70.575424) (xy 91.790774 -70.493636)
			(xy 91.828874 -70.455536) (xy 91.828874 -68.654676) (xy 91.569794 -68.395596) (xy 88.50503 -68.395596)
			(xy 88.39454 -68.50634) (xy 88.39454 -73.33234) (xy 88.520778 -73.458578) (xy 88.98763 -73.458578)
		)
		(stroke
			(width 0)
			(type solid)
		)
		(fill yes)
		(layer "F.Cu")
		(net "GND")
	)
	(gr_poly
		(pts
			(xy 89.54008 -332.301088) (xy 89.54008 -328.717656) (xy 89.487248 -328.664824) (xy 85.008974 -328.664824)
			(xy 84.950554 -328.723244) (xy 84.950554 -330.985622) (xy 84.300822 -331.635354) (xy 83.592924 -331.635354)
			(xy 83.560666 -331.667612) (xy 83.560666 -332.16469) (xy 83.770978 -332.375002) (xy 89.466166 -332.375002)
		)
		(stroke
			(width 0)
			(type solid)
		)
		(fill yes)
		(layer "F.Cu")
		(net "SW_PVDDCR_CPU1_P1_SW1")
	)
	(gr_poly
		(pts
			(xy 90.070432 -58.153046) (xy 90.070432 -57.454546) (xy 89.895172 -57.279286) (xy 89.895172 -56.217566)
			(xy 89.895172 -55.455566) (xy 89.768172 -55.328566) (xy 89.387172 -55.328566) (xy 89.260172 -55.455566)
			(xy 89.260172 -56.532526) (xy 89.260172 -57.586626) (xy 89.885012 -58.211466) (xy 90.012012 -58.211466)
		)
		(stroke
			(width 0)
			(type solid)
		)
		(fill yes)
		(layer "F.Cu")
		(net "GND")
	)
	(gr_poly
		(pts
			(xy 94.999302 -185.90133) (xy 94.999302 -184.90311) (xy 94.852744 -184.756552) (xy 94.636082 -184.53989)
			(xy 94.166182 -184.53989) (xy 94.07271 -184.633362) (xy 94.07271 -184.949338) (xy 94.497906 -185.374534)
			(xy 94.502732 -185.37936) (xy 94.502732 -185.918856) (xy 94.524576 -185.9407) (xy 94.959932 -185.9407)
		)
		(stroke
			(width 0)
			(type solid)
		)
		(fill yes)
		(layer "F.Cu")
		(net "SW_PVDDCR_CPU0_P1_SW2_RC")
	)
	(gr_poly
		(pts
			(xy 97.87128 -332.351888) (xy 97.87128 -328.821034) (xy 97.76587 -328.715624) (xy 93.340174 -328.715624)
			(xy 93.281754 -328.774044) (xy 93.281754 -331.036422) (xy 92.632022 -331.686154) (xy 91.924124 -331.686154)
			(xy 91.8972 -331.713078) (xy 91.8972 -332.203552) (xy 92.11945 -332.425802) (xy 97.797366 -332.425802)
		)
		(stroke
			(width 0)
			(type solid)
		)
		(fill yes)
		(layer "F.Cu")
		(net "SW_PVDDCR_CPU1_P1_SW5")
	)
	(gr_poly
		(pts
			(xy 99.415854 -70.160896) (xy 99.415854 -67.608196) (xy 99.065334 -67.257676) (xy 96.177354 -67.257676)
			(xy 94.947994 -68.487036) (xy 94.947994 -69.329046) (xy 94.558104 -69.718936) (xy 94.234254 -69.718936)
			(xy 94.066614 -69.886576) (xy 94.066614 -70.044056) (xy 94.414594 -70.392036) (xy 99.184714 -70.392036)
		)
		(stroke
			(width 0)
			(type solid)
		)
		(fill yes)
		(layer "F.Cu")
		(net "GND")
	)
	(gr_poly
		(pts
			(xy 101.24567 -188.948314) (xy 101.24567 -186.685936) (xy 101.895402 -186.036204) (xy 102.6033 -186.036204)
			(xy 102.637336 -186.002168) (xy 102.637336 -185.512202) (xy 102.42169 -185.296556) (xy 96.730058 -185.296556)
			(xy 96.656144 -185.37047) (xy 96.656144 -188.975746) (xy 96.687132 -189.006734) (xy 101.18725 -189.006734)
		)
		(stroke
			(width 0)
			(type solid)
		)
		(fill yes)
		(layer "F.Cu")
		(net "SW_PVDDCR_CPU0_P1_SW3")
	)
	(gr_poly
		(pts
			(xy 110.402878 -184.43321) (xy 110.402878 -181.84241) (xy 110.730284 -181.515004) (xy 110.9853 -181.515004)
			(xy 111.022892 -181.477412) (xy 111.022892 -180.990748) (xy 110.8075 -180.775356) (xy 105.112058 -180.775356)
			(xy 105.038144 -180.84927) (xy 105.038144 -184.454546) (xy 105.069132 -184.485534) (xy 110.350554 -184.485534)
		)
		(stroke
			(width 0)
			(type solid)
		)
		(fill yes)
		(layer "F.Cu")
		(net "SW_PVDDCR_CPU0_P1_SW4")
	)
	(gr_poly
		(pts
			(xy 113.566702 -332.271878) (xy 113.566702 -329.283314) (xy 113.445544 -329.162156) (xy 106.866182 -329.162156)
			(xy 106.597196 -329.431142) (xy 106.597196 -330.48956) (xy 106.42473 -330.662026) (xy 101.488494 -330.662026)
			(xy 101.285294 -330.865226) (xy 101.285294 -332.250542) (xy 101.521514 -332.486762) (xy 113.351818 -332.486762)
		)
		(stroke
			(width 0)
			(type solid)
		)
		(fill yes)
		(layer "F.Cu")
		(net "IND_CPU1_P1_CPL0")
	)
	(gr_poly
		(pts
			(xy 116.264182 -73.54697) (xy 116.358162 -73.45299) (xy 116.398802 -73.41235) (xy 116.398802 -70.94982)
			(xy 116.335302 -70.88632) (xy 116.04244 -70.88632) (xy 115.87099 -71.05777) (xy 115.33759 -71.05777)
			(xy 115.19789 -71.19747) (xy 115.19789 -73.44918) (xy 115.372642 -73.623932) (xy 116.18722 -73.623932)
		)
		(stroke
			(width 0)
			(type solid)
		)
		(fill yes)
		(layer "F.Cu")
		(net "P12V_AUX")
	)
	(gr_poly
		(pts
			(xy 118.403878 -178.15941) (xy 118.403878 -175.59401) (xy 118.731284 -175.266604) (xy 119.188484 -175.266604)
			(xy 119.242078 -175.21301) (xy 119.242078 -174.73041) (xy 119.038624 -174.526956) (xy 113.341658 -174.526956)
			(xy 113.267744 -174.60087) (xy 113.267744 -178.206146) (xy 113.298732 -178.237134) (xy 118.326154 -178.237134)
		)
		(stroke
			(width 0)
			(type solid)
		)
		(fill yes)
		(layer "F.Cu")
		(net "SW_PVDDCR_SOC_P1_SW1")
	)
	(gr_poly
		(pts
			(xy 126.608078 -171.45381) (xy 126.608078 -168.81221) (xy 126.884684 -168.535604) (xy 127.382016 -168.535604)
			(xy 127.531114 -168.386506) (xy 127.531114 -168.013634) (xy 127.313436 -167.795956) (xy 121.622058 -167.795956)
			(xy 121.548144 -167.86987) (xy 121.548144 -171.475146) (xy 121.579132 -171.506134) (xy 126.555754 -171.506134)
		)
		(stroke
			(width 0)
			(type solid)
		)
		(fill yes)
		(layer "F.Cu")
		(net "SW_PVDDCR_SOC_P1_SW2")
	)
	(gr_poly
		(pts
			(xy 134.913878 -162.76701) (xy 134.913878 -160.27781) (xy 135.317484 -159.874204) (xy 135.9535 -159.874204)
			(xy 135.989314 -159.83839) (xy 135.989314 -159.356298) (xy 135.767572 -159.134556) (xy 130.080258 -159.134556)
			(xy 130.006344 -159.20847) (xy 130.006344 -162.813746) (xy 130.037332 -162.844734) (xy 134.836154 -162.844734)
		)
		(stroke
			(width 0)
			(type solid)
		)
		(fill yes)
		(layer "F.Cu")
		(net "SW_PVDDCR_SOC_P1_SW3")
	)
	(gr_poly
		(pts
			(xy 136.751822 -159.850582) (xy 136.751822 -158.768542) (xy 136.595104 -158.611824) (xy 136.378442 -158.395162)
			(xy 135.858504 -158.395162) (xy 135.81507 -158.438596) (xy 135.81507 -158.80461) (xy 136.240266 -159.229806)
			(xy 136.247124 -159.236664) (xy 136.247124 -159.862774) (xy 136.268206 -159.883856) (xy 136.718548 -159.883856)
		)
		(stroke
			(width 0)
			(type solid)
		)
		(fill yes)
		(layer "F.Cu")
		(net "SW_PVDDCR_SOC_P1_SW3_RC")
	)
	(gr_poly
		(pts
			(xy 142.813278 -164.72281) (xy 142.813278 -161.57321) (xy 142.694152 -161.454084) (xy 137.199878 -161.454084)
			(xy 136.564878 -162.089084) (xy 136.564878 -163.486084) (xy 136.15035 -163.900612) (xy 130.214878 -163.900612)
			(xy 130.087878 -164.027612) (xy 130.087878 -165.45941) (xy 130.341878 -165.71341) (xy 141.822678 -165.71341)
		)
		(stroke
			(width 0)
			(type solid)
		)
		(fill yes)
		(layer "F.Cu")
		(net "IND_SOC_P1_CPL0")
	)
	(gr_poly
		(pts
			(xy 155.900374 -319.715134) (xy 155.900374 -315.854334) (xy 154.86126 -314.81522) (xy 152.642824 -314.81522)
			(xy 151.533606 -315.924438) (xy 147.74291 -315.924438) (xy 147.700746 -315.966602) (xy 147.700746 -318.84493)
			(xy 147.939506 -319.08369) (xy 151.927052 -319.08369) (xy 152.783286 -319.939924) (xy 155.675584 -319.939924)
		)
		(stroke
			(width 0)
			(type solid)
		)
		(fill yes)
		(layer "F.Cu")
		(net "GND")
	)
	(gr_poly
		(pts
			(xy 173.241716 -27.855672) (xy 173.241716 -25.163272) (xy 173.444916 -24.960072) (xy 174.308516 -24.960072)
			(xy 174.384716 -24.883872) (xy 174.384716 -24.121872) (xy 174.257716 -23.994872) (xy 173.013116 -23.994872)
			(xy 172.530516 -24.477472) (xy 172.530516 -27.830272) (xy 172.581316 -27.881072) (xy 173.216316 -27.881072)
		)
		(stroke
			(width 0)
			(type solid)
		)
		(fill yes)
		(layer "F.Cu")
		(net "P12V_AUX")
	)
	(gr_poly
		(pts
			(xy 185.120534 -348.704662) (xy 185.120534 -344.355674) (xy 184.942734 -344.177874) (xy 180.917342 -344.177874)
			(xy 180.714142 -344.381074) (xy 180.714142 -347.168978) (xy 179.976272 -347.906848) (xy 179.468272 -347.906848)
			(xy 179.36083 -348.01429) (xy 179.36083 -348.478094) (xy 179.62499 -348.742254) (xy 185.082942 -348.742254)
		)
		(stroke
			(width 0)
			(type solid)
		)
		(fill yes)
		(layer "F.Cu")
		(net "SW_PVDD11_S3_P1_SW1")
	)
	(gr_poly
		(pts
			(xy 187.855606 -349.390462) (xy 187.855606 -349.047308) (xy 187.43041 -348.622112) (xy 187.423552 -348.615254)
			(xy 187.423552 -347.975936) (xy 187.403994 -347.956378) (xy 187.108084 -347.956378) (xy 186.978036 -347.956378)
			(xy 186.918854 -348.01556) (xy 186.918854 -349.02013) (xy 187.35548 -349.456756) (xy 187.789312 -349.456756)
		)
		(stroke
			(width 0)
			(type solid)
		)
		(fill yes)
		(layer "F.Cu")
		(net "SW_PVDD11_S3_P1_SW2_RC")
	)
	(gr_poly
		(pts
			(xy 191.931036 -28.521152) (xy 191.931036 -27.444192) (xy 191.931036 -26.390092) (xy 191.306196 -25.765252)
			(xy 191.179196 -25.765252) (xy 191.120776 -25.823672) (xy 191.120776 -26.633932) (xy 191.120776 -27.583892)
			(xy 191.366394 -27.82951) (xy 191.366394 -28.545028) (xy 191.469518 -28.648152) (xy 191.804036 -28.648152)
		)
		(stroke
			(width 0)
			(type solid)
		)
		(fill yes)
		(layer "F.Cu")
		(net "GND")
	)
	(gr_poly
		(pts
			(xy 193.447162 -348.730062) (xy 193.447162 -344.381074) (xy 193.269362 -344.203274) (xy 189.24397 -344.203274)
			(xy 189.04077 -344.406474) (xy 189.04077 -347.194378) (xy 188.3029 -347.932248) (xy 187.7949 -347.932248)
			(xy 187.679838 -348.04731) (xy 187.679838 -348.49943) (xy 187.948062 -348.767654) (xy 193.40957 -348.767654)
		)
		(stroke
			(width 0)
			(type solid)
		)
		(fill yes)
		(layer "F.Cu")
		(net "SW_PVDD11_S3_P1_SW2")
	)
	(gr_poly
		(pts
			(xy 255.016 -40.431466) (xy 255.778 -40.431466) (xy 255.837944 -40.371522) (xy 255.837944 -39.990522)
			(xy 255.710944 -39.863522) (xy 254.633984 -39.863522) (xy 253.579884 -39.863522) (xy 252.955044 -40.488362)
			(xy 252.955044 -40.615362) (xy 253.013464 -40.673782) (xy 253.823724 -40.673782) (xy 254.773684 -40.673782)
		)
		(stroke
			(width 0)
			(type solid)
		)
		(fill yes)
		(layer "F.Cu")
		(net "GND")
	)
	(gr_poly
		(pts
			(xy 256.943606 -103.13543) (xy 256.943606 -101.980746) (xy 256.82321 -101.86035) (xy 255.795272 -101.86035)
			(xy 255.351026 -101.416104) (xy 255.351026 -101.130862) (xy 255.268476 -101.048312) (xy 254.399288 -101.048312)
			(xy 254.348488 -101.099112) (xy 254.348488 -103.14178) (xy 254.691134 -103.484426) (xy 256.59461 -103.484426)
		)
		(stroke
			(width 0)
			(type solid)
		)
		(fill yes)
		(layer "F.Cu")
		(net "PVDD18_S5_P0")
	)
	(gr_poly
		(pts
			(xy 270.647922 -105.306876) (xy 270.647922 -104.602534) (xy 270.457676 -104.412288) (xy 268.7574 -104.412288)
			(xy 268.262608 -103.917496) (xy 268.262608 -102.769162) (xy 268.161008 -102.667562) (xy 267.190474 -102.667562)
			(xy 267.114274 -102.743762) (xy 267.114274 -104.91978) (xy 267.609066 -105.414572) (xy 270.540226 -105.414572)
		)
		(stroke
			(width 0)
			(type solid)
		)
		(fill yes)
		(layer "F.Cu")
		(net "P3V3_AUX")
	)
	(gr_poly
		(pts
			(xy 314.95492 -333.087726) (xy 314.95492 -332.721712) (xy 314.529724 -332.296516) (xy 314.529724 -332.196694)
			(xy 314.529724 -331.657198) (xy 314.503308 -331.630782) (xy 314.176664 -331.630782) (xy 314.018168 -331.789278)
			(xy 314.018168 -332.75778) (xy 314.174886 -332.914498) (xy 314.391548 -333.13116) (xy 314.911486 -333.13116)
		)
		(stroke
			(width 0)
			(type solid)
		)
		(fill yes)
		(layer "F.Cu")
		(net "SW_PVDDCR_CPU1_P0_SW3_RC")
	)
	(gr_poly
		(pts
			(xy 339.99932 -333.096362) (xy 339.99932 -332.750922) (xy 339.574124 -332.325726) (xy 339.574124 -332.225904)
			(xy 339.574124 -331.686408) (xy 339.547708 -331.659992) (xy 339.251798 -331.659992) (xy 339.09635 -331.659992)
			(xy 339.062568 -331.693774) (xy 339.062568 -332.749652) (xy 339.473286 -333.16037) (xy 339.935312 -333.16037)
		)
		(stroke
			(width 0)
			(type solid)
		)
		(fill yes)
		(layer "F.Cu")
		(net "SW_PVDDCR_CPU1_P0_SW5_RC")
	)
	(gr_poly
		(pts
			(xy 361.405424 -332.284832) (xy 361.405424 -329.143868) (xy 361.039156 -328.7776) (xy 354.637086 -328.7776)
			(xy 354.533962 -328.880724) (xy 354.533962 -330.484734) (xy 354.361496 -330.6572) (xy 349.42526 -330.6572)
			(xy 349.22206 -330.8604) (xy 349.22206 -332.245716) (xy 349.45828 -332.481936) (xy 361.20832 -332.481936)
		)
		(stroke
			(width 0)
			(type solid)
		)
		(fill yes)
		(layer "F.Cu")
		(net "IND_CPU1_P0_CPL0")
	)
	(gr_poly
		(pts
			(xy 400.369278 -183.412638) (xy 400.369278 -180.790596) (xy 400.64563 -180.514244) (xy 401.22856 -180.514244)
			(xy 401.385278 -180.357526) (xy 401.385278 -179.97551) (xy 401.184364 -179.774596) (xy 395.480286 -179.774596)
			(xy 395.406372 -179.84851) (xy 395.406372 -183.453786) (xy 395.43736 -183.484774) (xy 400.297142 -183.484774)
		)
		(stroke
			(width 0)
			(type solid)
		)
		(fill yes)
		(layer "F.Cu")
		(net "SW_PVDDCR_SOC_P0_SW1")
	)
	(gr_poly
		(pts
			(xy 402.15185 -180.38191) (xy 402.15185 -179.408582) (xy 401.995132 -179.251864) (xy 401.77847 -179.035202)
			(xy 401.258532 -179.035202) (xy 401.215098 -179.078636) (xy 401.215098 -179.44465) (xy 401.640294 -179.869846)
			(xy 401.640294 -179.969668) (xy 401.640294 -180.382926) (xy 401.690078 -180.43271) (xy 402.10105 -180.43271)
		)
		(stroke
			(width 0)
			(type solid)
		)
		(fill yes)
		(layer "F.Cu")
		(net "SW_PVDDCR_SOC_P0_SW1_RC")
	)
	(gr_poly
		(pts
			(xy 408.751278 -174.852838) (xy 408.751278 -172.15485) (xy 408.96921 -171.936918) (xy 409.65247 -171.936918)
			(xy 409.691078 -171.89831) (xy 409.691078 -171.39031) (xy 409.498038 -171.19727) (xy 403.803866 -171.19727)
			(xy 403.729952 -171.271184) (xy 403.729952 -174.87646) (xy 403.76094 -174.907448) (xy 408.696668 -174.907448)
		)
		(stroke
			(width 0)
			(type solid)
		)
		(fill yes)
		(layer "F.Cu")
		(net "SW_PVDDCR_SOC_P0_SW2")
	)
	(gr_poly
		(pts
			(xy 411.305502 -143.688054) (xy 411.305502 -142.948914) (xy 411.559502 -142.694914) (xy 412.270702 -142.694914)
			(xy 412.372302 -142.593314) (xy 412.372302 -142.364714) (xy 412.321502 -142.313914) (xy 411.280102 -142.313914)
			(xy 410.518102 -143.075914) (xy 410.518102 -143.660114) (xy 410.602684 -143.744696) (xy 411.24886 -143.744696)
		)
		(stroke
			(width 0)
			(type solid)
		)
		(fill yes)
		(layer "F.Cu")
		(net "SW_P5V_AUX_BST")
	)
	(gr_poly
		(pts
			(xy 417.107878 -170.026838) (xy 417.107878 -167.35425) (xy 417.35121 -167.110918) (xy 418.03447 -167.110918)
			(xy 418.073078 -167.07231) (xy 418.073078 -166.56431) (xy 417.880038 -166.37127) (xy 412.185866 -166.37127)
			(xy 412.111952 -166.445184) (xy 412.111952 -170.05046) (xy 412.14294 -170.081448) (xy 417.053268 -170.081448)
		)
		(stroke
			(width 0)
			(type solid)
		)
		(fill yes)
		(layer "F.Cu")
		(net "SW_PVDDCR_SOC_P0_SW3")
	)
	(gr_poly
		(pts
			(xy 419.180518 -353.572572) (xy 419.180518 -352.653092) (xy 419.475158 -352.358452) (xy 420.135558 -352.358452)
			(xy 420.242238 -352.251772) (xy 420.242238 -351.309432) (xy 420.153338 -351.220532) (xy 418.184838 -351.220532)
			(xy 417.524438 -351.880932) (xy 417.524438 -353.503992) (xy 417.674298 -353.653852) (xy 419.099238 -353.653852)
		)
		(stroke
			(width 0)
			(type solid)
		)
		(fill yes)
		(layer "F.Cu")
		(net "PVDD11_S3_P0_PVCC")
	)
	(gr_poly
		(pts
			(xy 420.25316 -349.163894) (xy 420.25316 -348.841314) (xy 419.827964 -348.416118) (xy 419.827964 -348.316296)
			(xy 419.827964 -347.7768) (xy 419.801548 -347.750384) (xy 419.505638 -347.750384) (xy 419.35019 -347.750384)
			(xy 419.316408 -347.784166) (xy 419.316408 -348.827344) (xy 419.739826 -349.250762) (xy 420.166292 -349.250762)
		)
		(stroke
			(width 0)
			(type solid)
		)
		(fill yes)
		(layer "F.Cu")
		(net "SW_PVDD11_S3_P0_SW1_RC")
	)
	(gr_poly
		(pts
			(xy 424.644058 -357.039672) (xy 424.644058 -356.709472) (xy 424.585638 -356.651052) (xy 423.635678 -356.651052)
			(xy 423.455338 -356.831392) (xy 419.701218 -356.831392) (xy 419.040818 -356.170992) (xy 418.474398 -356.170992)
			(xy 418.291518 -356.353872) (xy 418.291518 -357.368094) (xy 418.497766 -357.574342) (xy 424.109388 -357.574342)
		)
		(stroke
			(width 0)
			(type solid)
		)
		(fill yes)
		(layer "F.Cu")
		(net "GND")
	)
	(gr_poly
		(pts
			(xy 433.944776 -103.77043) (xy 434.706776 -103.77043) (xy 434.833776 -103.64343) (xy 434.833776 -103.26243)
			(xy 434.706776 -103.13543) (xy 433.629816 -103.13543) (xy 432.575716 -103.13543) (xy 431.950876 -103.76027)
			(xy 431.950876 -103.88727) (xy 432.009296 -103.94569) (xy 432.819556 -103.94569) (xy 433.769516 -103.94569)
		)
		(stroke
			(width 0)
			(type solid)
		)
		(fill yes)
		(layer "F.Cu")
		(net "GND")
	)
	(gr_poly
		(pts
			(xy 440.452764 -22.598888) (xy 440.39536 -22.541484) (xy 439.065162 -22.541484) (xy 438.921398 -22.685248)
			(xy 438.921398 -22.862032) (xy 438.921398 -23.011384) (xy 439.583576 -23.673562) (xy 439.583576 -25.58542)
			(xy 440.040776 -26.04262) (xy 440.040776 -27.117802) (xy 440.116976 -27.194002) (xy 440.452764 -27.194002)
		)
		(stroke
			(width 0)
			(type solid)
		)
		(fill yes)
		(layer "F.Cu")
		(net "P12V_OCP_AVIN_PD_1")
	)
	(gr_poly
		(pts
			(xy 441.045092 -43.578018) (xy 441.045092 -43.451018) (xy 441.045092 -38.853618) (xy 440.918092 -38.726618)
			(xy 434.288692 -38.726618) (xy 433.780692 -38.726618) (xy 433.628292 -38.879018) (xy 433.628292 -43.001946)
			(xy 433.628292 -43.618658) (xy 433.780692 -43.771058) (xy 438.893458 -43.771058) (xy 440.852052 -43.771058)
		)
		(stroke
			(width 0)
			(type solid)
		)
		(fill yes)
		(layer "F.Cu")
		(net "P12V_AUX")
	)
	(gr_poly
		(pts
			(xy 464.493102 -388.709662) (xy 464.493102 -382.305814) (xy 464.493102 -381.237744) (xy 464.493102 -380.666498)
			(xy 464.039458 -380.212854) (xy 440.355736 -380.212854) (xy 439.956702 -380.611888) (xy 439.956702 -381.976884)
			(xy 439.956702 -388.231126) (xy 439.956702 -389.163052) (xy 440.026806 -389.233156) (xy 463.969608 -389.233156)
		)
		(stroke
			(width 0)
			(type solid)
		)
		(fill yes)
		(layer "F.Cu")
		(net "P0V9_CPU0_RT_2D")
	)
	(gr_poly
		(pts
			(xy 33.490154 -344.813636) (xy 33.490154 -344.447622) (xy 33.064958 -344.022426) (xy 33.064958 -343.922604)
			(xy 33.064958 -343.383108) (xy 33.038542 -343.356692) (xy 32.742632 -343.356692) (xy 32.587184 -343.356692)
			(xy 32.553402 -343.390474) (xy 32.553402 -344.48369) (xy 32.71012 -344.640408) (xy 32.926782 -344.85707)
			(xy 33.44672 -344.85707)
		)
		(stroke
			(width 0)
			(type solid)
		)
		(fill yes)
		(layer "F.Cu")
		(net "SW_PVDDIO_P1_SW3_RC")
	)
	(gr_poly
		(pts
			(xy 41.795954 -344.813636) (xy 41.795954 -344.447622) (xy 41.370758 -344.022426) (xy 41.370758 -343.922604)
			(xy 41.370758 -343.383108) (xy 41.344342 -343.356692) (xy 41.048432 -343.356692) (xy 40.892984 -343.356692)
			(xy 40.859202 -343.390474) (xy 40.859202 -344.48369) (xy 41.01592 -344.640408) (xy 41.232582 -344.85707)
			(xy 41.75252 -344.85707)
		)
		(stroke
			(width 0)
			(type solid)
		)
		(fill yes)
		(layer "F.Cu")
		(net "SW_PVDDIO_P1_SW2_RC")
	)
	(gr_poly
		(pts
			(xy 50.137822 -344.788998) (xy 50.137822 -344.43289) (xy 49.727358 -344.022426) (xy 49.727358 -343.922604)
			(xy 49.727358 -343.383108) (xy 49.700942 -343.356692) (xy 49.405032 -343.356692) (xy 49.249584 -343.356692)
			(xy 49.215802 -343.390474) (xy 49.215802 -344.48369) (xy 49.37252 -344.640408) (xy 49.589182 -344.85707)
			(xy 50.06975 -344.85707)
		)
		(stroke
			(width 0)
			(type solid)
		)
		(fill yes)
		(layer "F.Cu")
		(net "SW_PVDDIO_P1_SW1_RC")
	)
	(gr_poly
		(pts
			(xy 58.483754 -344.813636) (xy 58.483754 -344.447622) (xy 58.058558 -344.022426) (xy 58.058558 -343.922604)
			(xy 58.058558 -343.383108) (xy 58.032142 -343.356692) (xy 57.736232 -343.356692) (xy 57.580784 -343.356692)
			(xy 57.547002 -343.390474) (xy 57.547002 -344.48369) (xy 57.70372 -344.640408) (xy 57.920382 -344.85707)
			(xy 58.44032 -344.85707)
		)
		(stroke
			(width 0)
			(type solid)
		)
		(fill yes)
		(layer "F.Cu")
		(net "SW_PVDDCR_CPU1_P1_SW4_RC")
	)
	(gr_poly
		(pts
			(xy 67.018154 -333.092552) (xy 67.018154 -332.726538) (xy 66.592958 -332.301342) (xy 66.592958 -332.20152)
			(xy 66.592958 -331.662024) (xy 66.566542 -331.635608) (xy 66.270632 -331.635608) (xy 66.115184 -331.635608)
			(xy 66.081402 -331.66939) (xy 66.081402 -332.762606) (xy 66.23812 -332.919324) (xy 66.454782 -333.135986)
			(xy 66.97472 -333.135986)
		)
		(stroke
			(width 0)
			(type solid)
		)
		(fill yes)
		(layer "F.Cu")
		(net "SW_PVDDCR_CPU1_P1_SW3_RC")
	)
	(gr_poly
		(pts
			(xy 69.975222 -172.259244) (xy 69.975222 -171.166028) (xy 69.818504 -171.00931) (xy 69.601842 -170.792648)
			(xy 69.081904 -170.792648) (xy 69.03847 -170.836082) (xy 69.03847 -171.202096) (xy 69.463666 -171.627292)
			(xy 69.470778 -171.634404) (xy 69.470778 -172.236384) (xy 69.52742 -172.293026) (xy 69.785992 -172.293026)
			(xy 69.94144 -172.293026)
		)
		(stroke
			(width 0)
			(type solid)
		)
		(fill yes)
		(layer "F.Cu")
		(net "SW_PVDDCR_CPU0_P1_SW6_RC")
	)
	(gr_poly
		(pts
			(xy 72.82688 -332.322678) (xy 72.82688 -328.717402) (xy 72.795892 -328.686414) (xy 68.295774 -328.686414)
			(xy 68.237354 -328.744834) (xy 68.237354 -331.097128) (xy 67.677538 -331.656944) (xy 66.955162 -331.656944)
			(xy 66.955162 -331.65796) (xy 66.847212 -331.76591) (xy 66.847212 -332.186534) (xy 67.05727 -332.396592)
			(xy 72.752966 -332.396592)
		)
		(stroke
			(width 0)
			(type solid)
		)
		(fill yes)
		(layer "F.Cu")
		(net "SW_PVDDCR_CPU1_P1_SW3")
	)
	(gr_poly
		(pts
			(xy 81.547462 -23.572724) (xy 81.547462 -22.495764) (xy 81.547462 -21.441664) (xy 80.922622 -20.816824)
			(xy 80.795622 -20.816824) (xy 80.737202 -20.875244) (xy 80.737202 -21.685504) (xy 80.737202 -21.802344)
			(xy 81.024984 -22.090126) (xy 81.024984 -22.923246) (xy 81.024984 -23.618444) (xy 81.106264 -23.699724)
			(xy 81.420462 -23.699724)
		)
		(stroke
			(width 0)
			(type solid)
		)
		(fill yes)
		(layer "F.Cu")
		(net "GND")
	)
	(gr_poly
		(pts
			(xy 92.062554 -333.121762) (xy 92.062554 -332.755748) (xy 91.637358 -332.330552) (xy 91.637358 -332.23073)
			(xy 91.637358 -331.691234) (xy 91.610942 -331.664818) (xy 91.315032 -331.664818) (xy 91.159584 -331.664818)
			(xy 91.125802 -331.6986) (xy 91.125802 -332.791816) (xy 91.28252 -332.948534) (xy 91.499182 -333.165196)
			(xy 92.01912 -333.165196)
		)
		(stroke
			(width 0)
			(type solid)
		)
		(fill yes)
		(layer "F.Cu")
		(net "SW_PVDDCR_CPU1_P1_SW5_RC")
	)
	(gr_poly
		(pts
			(xy 94.254574 -75.489816) (xy 94.254574 -73.965816) (xy 94.191074 -73.902316) (xy 94.187264 -73.906126)
			(xy 93.712284 -73.906126) (xy 93.487494 -73.681336) (xy 93.487494 -72.987916) (xy 93.335094 -72.835516)
			(xy 92.814394 -72.835516) (xy 92.773754 -72.876156) (xy 92.773754 -75.487276) (xy 93.007434 -75.720956)
			(xy 94.023434 -75.720956)
		)
		(stroke
			(width 0)
			(type solid)
		)
		(fill yes)
		(layer "F.Cu")
		(net "P3V3_AUX")
	)
	(gr_poly
		(pts
			(xy 103.401622 -186.023758) (xy 103.401622 -184.930542) (xy 103.244904 -184.773824) (xy 103.028242 -184.557162)
			(xy 102.508304 -184.557162) (xy 102.46487 -184.600596) (xy 102.46487 -184.94883) (xy 102.890066 -185.374026)
			(xy 102.894638 -185.378598) (xy 102.894638 -186.011312) (xy 102.940866 -186.05754) (xy 103.212392 -186.05754)
			(xy 103.36784 -186.05754)
		)
		(stroke
			(width 0)
			(type solid)
		)
		(fill yes)
		(layer "F.Cu")
		(net "SW_PVDDCR_CPU0_P1_SW3_RC")
	)
	(gr_poly
		(pts
			(xy 229.516178 -294.857932) (xy 229.541578 -294.832532) (xy 229.541578 -293.994332) (xy 229.862126 -293.673784)
			(xy 230.42753 -293.673784) (xy 230.52913 -293.572184) (xy 230.52913 -293.343584) (xy 230.47833 -293.292784)
			(xy 229.617778 -293.292784) (xy 228.982778 -293.927784) (xy 228.982778 -294.883332) (xy 229.033578 -294.934132)
			(xy 229.439978 -294.934132)
		)
		(stroke
			(width 0)
			(type solid)
		)
		(fill yes)
		(layer "F.Cu")
		(net "SW_P1V8_RETIMER_CPU1_BST")
	)
	(gr_poly
		(pts
			(xy 234.320842 -315.492384) (xy 234.320842 -314.290456) (xy 234.320842 -312.461656) (xy 234.320842 -310.84647)
			(xy 234.320842 -308.436264) (xy 233.739944 -307.855366) (xy 223.336866 -307.855366) (xy 222.999046 -307.855366)
			(xy 222.313754 -308.540912) (xy 222.313754 -308.731412) (xy 222.313754 -315.649356) (xy 222.43034 -315.765942)
			(xy 234.047284 -315.765942)
		)
		(stroke
			(width 0)
			(type solid)
		)
		(fill yes)
		(layer "F.Cu")
		(net "P1V8_CPU1_RT_1D")
	)
	(gr_poly
		(pts
			(xy 241.460528 -294.857932) (xy 241.485928 -294.832532) (xy 241.485928 -293.994332) (xy 241.806476 -293.673784)
			(xy 242.37188 -293.673784) (xy 242.47348 -293.572184) (xy 242.47348 -293.343584) (xy 242.42268 -293.292784)
			(xy 241.562128 -293.292784) (xy 240.927128 -293.927784) (xy 240.927128 -294.883332) (xy 240.977928 -294.934132)
			(xy 241.384328 -294.934132)
		)
		(stroke
			(width 0)
			(type solid)
		)
		(fill yes)
		(layer "F.Cu")
		(net "SW_P1V8_RETIMER_CPU0_BST")
	)
	(gr_poly
		(pts
			(xy 244.99316 -381.51054) (xy 244.99316 -380.67234) (xy 244.72138 -380.40056) (xy 244.14988 -380.40056)
			(xy 244.08892 -380.46152) (xy 244.08892 -380.88316) (xy 244.13972 -380.93396) (xy 244.33022 -380.93396)
			(xy 244.4115 -381.01524) (xy 244.4115 -381.13462) (xy 244.4115 -381.48514) (xy 244.50548 -381.57912)
			(xy 244.92458 -381.57912)
		)
		(stroke
			(width 0)
			(type solid)
		)
		(fill yes)
		(layer "F.Cu")
		(net "P12V_HSC_GATE2")
	)
	(gr_poly
		(pts
			(xy 250.928124 -381.51054) (xy 250.928124 -380.67234) (xy 250.656344 -380.40056) (xy 250.084844 -380.40056)
			(xy 250.023884 -380.46152) (xy 250.023884 -380.88316) (xy 250.074684 -380.93396) (xy 250.265184 -380.93396)
			(xy 250.346464 -381.01524) (xy 250.346464 -381.13462) (xy 250.346464 -381.48514) (xy 250.440444 -381.57912)
			(xy 250.859544 -381.57912)
		)
		(stroke
			(width 0)
			(type solid)
		)
		(fill yes)
		(layer "F.Cu")
		(net "P12V_HSC_GATE2")
	)
	(gr_poly
		(pts
			(xy 256.863088 -381.51054) (xy 256.863088 -380.67234) (xy 256.591308 -380.40056) (xy 256.019808 -380.40056)
			(xy 255.958848 -380.46152) (xy 255.958848 -380.88316) (xy 256.009648 -380.93396) (xy 256.200148 -380.93396)
			(xy 256.281428 -381.01524) (xy 256.281428 -381.13462) (xy 256.281428 -381.48514) (xy 256.375408 -381.57912)
			(xy 256.794508 -381.57912)
		)
		(stroke
			(width 0)
			(type solid)
		)
		(fill yes)
		(layer "F.Cu")
		(net "P12V_HSC_GATE2")
	)
	(gr_poly
		(pts
			(xy 260.323584 -55.682642) (xy 260.323584 -54.793642) (xy 260.323584 -50.190146) (xy 260.120384 -49.986946)
			(xy 258.196334 -49.986946) (xy 257.910838 -50.272442) (xy 257.910584 -50.272442) (xy 257.910584 -53.079396)
			(xy 258.012184 -53.180996) (xy 258.012184 -54.971442) (xy 258.012184 -55.738522) (xy 258.098544 -55.824882)
			(xy 260.181344 -55.824882)
		)
		(stroke
			(width 0)
			(type solid)
		)
		(fill yes)
		(layer "F.Cu")
		(net "GND")
	)
	(gr_poly
		(pts
			(xy 262.798052 -381.51054) (xy 262.798052 -380.67234) (xy 262.526272 -380.40056) (xy 261.954772 -380.40056)
			(xy 261.893812 -380.46152) (xy 261.893812 -380.88316) (xy 261.944612 -380.93396) (xy 262.135112 -380.93396)
			(xy 262.216392 -381.01524) (xy 262.216392 -381.13462) (xy 262.216392 -381.48514) (xy 262.310372 -381.57912)
			(xy 262.729472 -381.57912)
		)
		(stroke
			(width 0)
			(type solid)
		)
		(fill yes)
		(layer "F.Cu")
		(net "P12V_HSC_GATE2")
	)
	(gr_poly
		(pts
			(xy 268.733016 -381.51054) (xy 268.733016 -380.67234) (xy 268.461236 -380.40056) (xy 267.889736 -380.40056)
			(xy 267.828776 -380.46152) (xy 267.828776 -380.88316) (xy 267.879576 -380.93396) (xy 268.070076 -380.93396)
			(xy 268.151356 -381.01524) (xy 268.151356 -381.13462) (xy 268.151356 -381.48514) (xy 268.245336 -381.57912)
			(xy 268.664436 -381.57912)
		)
		(stroke
			(width 0)
			(type solid)
		)
		(fill yes)
		(layer "F.Cu")
		(net "P12V_HSC_GATE2")
	)
	(gr_poly
		(pts
			(xy 272.02003 -344.801952) (xy 272.02003 -344.43162) (xy 271.60601 -344.0176) (xy 271.60601 -343.917778)
			(xy 271.60601 -343.378282) (xy 271.579594 -343.351866) (xy 271.283684 -343.351866) (xy 271.128236 -343.351866)
			(xy 271.094454 -343.385648) (xy 271.094454 -344.478864) (xy 271.251172 -344.635582) (xy 271.467834 -344.852244)
			(xy 271.969738 -344.852244)
		)
		(stroke
			(width 0)
			(type solid)
		)
		(fill yes)
		(layer "F.Cu")
		(net "SW_PVDDIO_P0_SW4_RC")
	)
	(gr_poly
		(pts
			(xy 274.66798 -381.51054) (xy 274.66798 -380.67234) (xy 274.3962 -380.40056) (xy 273.8247 -380.40056)
			(xy 273.76374 -380.46152) (xy 273.76374 -380.88316) (xy 273.81454 -380.93396) (xy 274.00504 -380.93396)
			(xy 274.08632 -381.01524) (xy 274.08632 -381.13462) (xy 274.08632 -381.48514) (xy 274.1803 -381.57912)
			(xy 274.5994 -381.57912)
		)
		(stroke
			(width 0)
			(type solid)
		)
		(fill yes)
		(layer "F.Cu")
		(net "P12V_HSC_GATE2")
	)
	(gr_poly
		(pts
			(xy 280.311606 -344.80881) (xy 280.311606 -344.442796) (xy 279.88641 -344.0176) (xy 279.88641 -343.917778)
			(xy 279.88641 -343.378282) (xy 279.859994 -343.351866) (xy 279.564084 -343.351866) (xy 279.408636 -343.351866)
			(xy 279.374854 -343.385648) (xy 279.374854 -344.478864) (xy 279.531572 -344.635582) (xy 279.748234 -344.852244)
			(xy 280.268172 -344.852244)
		)
		(stroke
			(width 0)
			(type solid)
		)
		(fill yes)
		(layer "F.Cu")
		(net "SW_PVDDIO_P0_SW3_RC")
	)
	(gr_poly
		(pts
			(xy 288.617406 -344.80881) (xy 288.617406 -344.442796) (xy 288.19221 -344.0176) (xy 288.19221 -343.917778)
			(xy 288.19221 -343.378282) (xy 288.165794 -343.351866) (xy 287.869884 -343.351866) (xy 287.714436 -343.351866)
			(xy 287.680654 -343.385648) (xy 287.680654 -344.478864) (xy 287.837372 -344.635582) (xy 288.054034 -344.852244)
			(xy 288.573972 -344.852244)
		)
		(stroke
			(width 0)
			(type solid)
		)
		(fill yes)
		(layer "F.Cu")
		(net "SW_PVDDIO_P0_SW2_RC")
	)
	(gr_poly
		(pts
			(xy 296.974006 -344.80881) (xy 296.974006 -344.442796) (xy 296.54881 -344.0176) (xy 296.54881 -343.917778)
			(xy 296.54881 -343.378282) (xy 296.522394 -343.351866) (xy 296.226484 -343.351866) (xy 296.071036 -343.351866)
			(xy 296.037254 -343.385648) (xy 296.037254 -344.478864) (xy 296.193972 -344.635582) (xy 296.410634 -344.852244)
			(xy 296.930572 -344.852244)
		)
		(stroke
			(width 0)
			(type solid)
		)
		(fill yes)
		(layer "F.Cu")
		(net "SW_PVDDIO_P0_SW1_RC")
	)
	(gr_poly
		(pts
			(xy 305.305206 -344.80881) (xy 305.305206 -344.442796) (xy 304.88001 -344.0176) (xy 304.88001 -343.917778)
			(xy 304.88001 -343.378282) (xy 304.853594 -343.351866) (xy 304.557684 -343.351866) (xy 304.402236 -343.351866)
			(xy 304.368454 -343.385648) (xy 304.368454 -344.478864) (xy 304.525172 -344.635582) (xy 304.741834 -344.852244)
			(xy 305.261772 -344.852244)
		)
		(stroke
			(width 0)
			(type solid)
		)
		(fill yes)
		(layer "F.Cu")
		(net "SW_PVDDCR_CPU1_P0_SW4_RC")
	)
	(gr_poly
		(pts
			(xy 320.763646 -332.317852) (xy 320.763646 -328.740262) (xy 320.704972 -328.681588) (xy 316.23254 -328.681588)
			(xy 316.17412 -328.740008) (xy 316.17412 -331.002386) (xy 315.553852 -331.622654) (xy 315.524388 -331.652118)
			(xy 314.929012 -331.652118) (xy 314.785502 -331.795628) (xy 314.785502 -332.17739) (xy 314.999878 -332.391766)
			(xy 320.689732 -332.391766)
		)
		(stroke
			(width 0)
			(type solid)
		)
		(fill yes)
		(layer "F.Cu")
		(net "SW_PVDDCR_CPU1_P0_SW3")
	)
	(gr_poly
		(pts
			(xy 332.604364 -133.962902) (xy 332.651354 -133.915912) (xy 332.744826 -133.82244) (xy 332.744826 -131.469892)
			(xy 332.621382 -131.346448) (xy 330.676504 -131.346448) (xy 330.394564 -131.628388) (xy 330.394564 -132.048758)
			(xy 330.394564 -133.048502) (xy 330.394564 -134.013702) (xy 330.546964 -134.166102) (xy 330.750164 -134.166102)
			(xy 332.401164 -134.166102)
		)
		(stroke
			(width 0)
			(type solid)
		)
		(fill yes)
		(layer "F.Cu")
		(net "P12V_AUX")
	)
	(gr_poly
		(pts
			(xy 348.275148 -338.02701) (xy 348.275148 -337.660996) (xy 347.849952 -337.2358) (xy 347.849952 -337.135978)
			(xy 347.849952 -336.596482) (xy 347.823536 -336.570066) (xy 347.527626 -336.570066) (xy 347.372178 -336.570066)
			(xy 347.338396 -336.603848) (xy 347.338396 -337.697064) (xy 347.495114 -337.853782) (xy 347.711776 -338.070444)
			(xy 348.231714 -338.070444)
		)
		(stroke
			(width 0)
			(type solid)
		)
		(fill yes)
		(layer "F.Cu")
		(net "SW_PVDDCR_CPU1_P0_SW6_RC")
	)
	(gr_poly
		(pts
			(xy 349.899478 -167.394636) (xy 349.899478 -165.132258) (xy 350.519746 -164.51199) (xy 350.54921 -164.482526)
			(xy 351.219262 -164.482526) (xy 351.271078 -164.43071) (xy 351.271078 -163.94811) (xy 351.065846 -163.742878)
			(xy 345.383866 -163.742878) (xy 345.309952 -163.816792) (xy 345.309952 -167.422068) (xy 345.34094 -167.453056)
			(xy 349.841058 -167.453056)
		)
		(stroke
			(width 0)
			(type solid)
		)
		(fill yes)
		(layer "F.Cu")
		(net "SW_PVDDCR_CPU0_P0_SW6")
	)
	(gr_poly
		(pts
			(xy 350.026478 -169.99331) (xy 350.026478 -168.67251) (xy 349.898462 -168.544494) (xy 343.972134 -168.544494)
			(xy 342.990678 -167.563038) (xy 342.990678 -166.775638) (xy 342.279478 -166.064438) (xy 337.910678 -166.064438)
			(xy 337.764882 -166.210234) (xy 337.764882 -168.91) (xy 337.764882 -169.931842) (xy 338.05495 -170.22191)
			(xy 349.797878 -170.22191)
		)
		(stroke
			(width 0)
			(type solid)
		)
		(fill yes)
		(layer "F.Cu")
		(net "IND_CPU0_P0_CPL0")
	)
	(gr_poly
		(pts
			(xy 352.05543 -164.47008) (xy 352.05543 -163.376864) (xy 351.898712 -163.220146) (xy 351.68205 -163.003484)
			(xy 351.162112 -163.003484) (xy 351.118678 -163.046918) (xy 351.118678 -163.412932) (xy 351.543874 -163.838128)
			(xy 351.543874 -163.93795) (xy 351.543874 -164.477446) (xy 351.57029 -164.503862) (xy 351.8662 -164.503862)
			(xy 352.021648 -164.503862)
		)
		(stroke
			(width 0)
			(type solid)
		)
		(fill yes)
		(layer "F.Cu")
		(net "SW_PVDDCR_CPU0_P0_SW6_RC")
	)
	(gr_poly
		(pts
			(xy 358.205278 -175.751236) (xy 358.205278 -173.488858) (xy 358.825546 -172.86859) (xy 358.85501 -172.839126)
			(xy 359.525062 -172.839126) (xy 359.576878 -172.78731) (xy 359.576878 -172.30471) (xy 359.371646 -172.099478)
			(xy 353.689666 -172.099478) (xy 353.615752 -172.173392) (xy 353.615752 -175.778668) (xy 353.64674 -175.809656)
			(xy 358.146858 -175.809656)
		)
		(stroke
			(width 0)
			(type solid)
		)
		(fill yes)
		(layer "F.Cu")
		(net "SW_PVDDCR_CPU0_P0_SW5")
	)
	(gr_poly
		(pts
			(xy 360.36123 -172.82668) (xy 360.36123 -171.733464) (xy 360.204512 -171.576746) (xy 359.98785 -171.360084)
			(xy 359.467912 -171.360084) (xy 359.424478 -171.403518) (xy 359.424478 -171.769532) (xy 359.849674 -172.194728)
			(xy 359.849674 -172.29455) (xy 359.849674 -172.834046) (xy 359.87609 -172.860462) (xy 360.172 -172.860462)
			(xy 360.327448 -172.860462)
		)
		(stroke
			(width 0)
			(type solid)
		)
		(fill yes)
		(layer "F.Cu")
		(net "SW_PVDDCR_CPU0_P0_SW5_RC")
	)
	(gr_poly
		(pts
			(xy 366.485678 -184.026556) (xy 366.485678 -181.764178) (xy 367.105946 -181.14391) (xy 367.13541 -181.114446)
			(xy 367.785142 -181.114446) (xy 367.857278 -181.04231) (xy 367.857278 -180.58511) (xy 367.646966 -180.374798)
			(xy 361.970066 -180.374798) (xy 361.896152 -180.448712) (xy 361.896152 -184.053988) (xy 361.92714 -184.084976)
			(xy 366.427258 -184.084976)
		)
		(stroke
			(width 0)
			(type solid)
		)
		(fill yes)
		(layer "F.Cu")
		(net "SW_PVDDCR_CPU0_P0_SW1")
	)
	(gr_poly
		(pts
			(xy 368.64163 -181.102) (xy 368.64163 -180.008784) (xy 368.484912 -179.852066) (xy 368.26825 -179.635404)
			(xy 367.748312 -179.635404) (xy 367.704878 -179.678838) (xy 367.704878 -180.044852) (xy 368.130074 -180.470048)
			(xy 368.130074 -180.56987) (xy 368.130074 -181.109366) (xy 368.15649 -181.135782) (xy 368.4524 -181.135782)
			(xy 368.607848 -181.135782)
		)
		(stroke
			(width 0)
			(type solid)
		)
		(fill yes)
		(layer "F.Cu")
		(net "SW_PVDDCR_CPU0_P0_SW1_RC")
	)
	(gr_poly
		(pts
			(xy 374.84685 -188.999114) (xy 374.84685 -186.736736) (xy 375.467118 -186.116468) (xy 375.496582 -186.087004)
			(xy 376.147584 -186.087004) (xy 376.213878 -186.02071) (xy 376.213878 -185.56351) (xy 375.997724 -185.347356)
			(xy 370.331238 -185.347356) (xy 370.257324 -185.42127) (xy 370.257324 -189.026546) (xy 370.288312 -189.057534)
			(xy 374.78843 -189.057534)
		)
		(stroke
			(width 0)
			(type solid)
		)
		(fill yes)
		(layer "F.Cu")
		(net "SW_PVDDCR_CPU0_P0_SW2")
	)
	(gr_poly
		(pts
			(xy 377.002802 -186.074558) (xy 377.002802 -184.981342) (xy 376.846084 -184.824624) (xy 376.629422 -184.607962)
			(xy 376.109484 -184.607962) (xy 376.06605 -184.651396) (xy 376.06605 -185.01741) (xy 376.491246 -185.442606)
			(xy 376.491246 -185.542428) (xy 376.491246 -186.081924) (xy 376.517662 -186.10834) (xy 376.813572 -186.10834)
			(xy 376.96902 -186.10834)
		)
		(stroke
			(width 0)
			(type solid)
		)
		(fill yes)
		(layer "F.Cu")
		(net "SW_PVDDCR_CPU0_P0_SW2_RC")
	)
	(gr_poly
		(pts
			(xy 383.249678 -188.999114) (xy 383.249678 -186.736736) (xy 383.869946 -186.116468) (xy 383.89941 -186.087004)
			(xy 384.563112 -186.087004) (xy 384.621278 -186.028838) (xy 384.621278 -185.546238) (xy 384.422396 -185.347356)
			(xy 378.734066 -185.347356) (xy 378.660152 -185.42127) (xy 378.660152 -189.026546) (xy 378.69114 -189.057534)
			(xy 383.191258 -189.057534)
		)
		(stroke
			(width 0)
			(type solid)
		)
		(fill yes)
		(layer "F.Cu")
		(net "SW_PVDDCR_CPU0_P0_SW3")
	)
	(gr_poly
		(pts
			(xy 385.40563 -186.074558) (xy 385.40563 -184.981342) (xy 385.248912 -184.824624) (xy 385.03225 -184.607962)
			(xy 384.567938 -184.607962) (xy 384.468878 -184.707022) (xy 384.468878 -185.01741) (xy 384.894074 -185.442606)
			(xy 384.894074 -185.542428) (xy 384.894074 -186.081924) (xy 384.92049 -186.10834) (xy 385.2164 -186.10834)
			(xy 385.371848 -186.10834)
		)
		(stroke
			(width 0)
			(type solid)
		)
		(fill yes)
		(layer "F.Cu")
		(net "SW_PVDDCR_CPU0_P0_SW3_RC")
	)
	(gr_poly
		(pts
			(xy 391.580878 -188.999114) (xy 391.580878 -186.736736) (xy 392.201146 -186.116468) (xy 392.23061 -186.087004)
			(xy 392.894312 -186.087004) (xy 392.952478 -186.028838) (xy 392.952478 -185.546238) (xy 392.753596 -185.347356)
			(xy 387.065266 -185.347356) (xy 386.991352 -185.42127) (xy 386.991352 -189.026546) (xy 387.02234 -189.057534)
			(xy 391.522458 -189.057534)
		)
		(stroke
			(width 0)
			(type solid)
		)
		(fill yes)
		(layer "F.Cu")
		(net "SW_PVDDCR_CPU0_P0_SW4")
	)
	(gr_poly
		(pts
			(xy 393.73683 -186.074558) (xy 393.73683 -184.981342) (xy 393.580112 -184.824624) (xy 393.36345 -184.607962)
			(xy 392.843512 -184.607962) (xy 392.800078 -184.651396) (xy 392.800078 -185.01741) (xy 393.225274 -185.442606)
			(xy 393.225274 -185.542428) (xy 393.225274 -186.081924) (xy 393.25169 -186.10834) (xy 393.5476 -186.10834)
			(xy 393.703048 -186.10834)
		)
		(stroke
			(width 0)
			(type solid)
		)
		(fill yes)
		(layer "F.Cu")
		(net "SW_PVDDCR_CPU0_P0_SW4_RC")
	)
	(gr_poly
		(pts
			(xy 398.745964 -145.773902) (xy 398.720564 -145.748502) (xy 398.720564 -145.113502) (xy 400.998944 -142.835122)
			(xy 406.280112 -142.835122) (xy 406.401016 -142.714218) (xy 406.401016 -140.007594) (xy 406.122124 -139.728702)
			(xy 396.993364 -139.728702) (xy 395.824964 -140.897102) (xy 395.824964 -145.951702) (xy 396.078964 -146.205702)
			(xy 398.314164 -146.205702)
		)
		(stroke
			(width 0)
			(type solid)
		)
		(fill yes)
		(layer "F.Cu")
		(net "GND")
	)
	(gr_poly
		(pts
			(xy 410.47543 -171.924472) (xy 410.47543 -170.831256) (xy 410.318712 -170.674538) (xy 410.10205 -170.457876)
			(xy 409.582112 -170.457876) (xy 409.538678 -170.50131) (xy 409.538678 -170.867324) (xy 409.963874 -171.29252)
			(xy 409.963874 -171.392342) (xy 409.963874 -171.931838) (xy 409.99029 -171.958254) (xy 410.2862 -171.958254)
			(xy 410.441648 -171.958254)
		)
		(stroke
			(width 0)
			(type solid)
		)
		(fill yes)
		(layer "F.Cu")
		(net "SW_PVDDCR_SOC_P0_SW2_RC")
	)
	(gr_poly
		(pts
			(xy 418.85743 -167.098472) (xy 418.85743 -166.005256) (xy 418.700712 -165.848538) (xy 418.48405 -165.631876)
			(xy 417.964112 -165.631876) (xy 417.920678 -165.67531) (xy 417.920678 -166.041324) (xy 418.345874 -166.46652)
			(xy 418.345874 -166.566342) (xy 418.345874 -167.105838) (xy 418.37229 -167.132254) (xy 418.6682 -167.132254)
			(xy 418.823648 -167.132254)
		)
		(stroke
			(width 0)
			(type solid)
		)
		(fill yes)
		(layer "F.Cu")
		(net "SW_PVDDCR_SOC_P0_SW3_RC")
	)
	(gr_poly
		(pts
			(xy 421.610282 -365.897414) (xy 421.610282 -363.818932) (xy 421.022018 -363.818932) (xy 421.016938 -363.824012)
			(xy 421.016938 -364.779814) (xy 421.016938 -364.788958) (xy 421.000682 -364.805214) (xy 420.848282 -364.957614)
			(xy 419.832282 -364.957614) (xy 419.715188 -365.074708) (xy 419.715188 -366.041686) (xy 419.774116 -366.100614)
			(xy 421.407082 -366.100614)
		)
		(stroke
			(width 0)
			(type solid)
		)
		(fill yes)
		(layer "F.Cu")
		(net "PVDD11_S3_P0_VCCS")
	)
	(gr_poly
		(pts
			(xy 425.800012 -344.130376) (xy 425.800012 -343.991946) (xy 425.693078 -343.885012) (xy 421.537638 -343.885012)
			(xy 421.438324 -343.984326) (xy 421.438324 -344.20048) (xy 421.438324 -346.988384) (xy 420.700454 -347.726254)
			(xy 420.192454 -347.726254) (xy 420.086028 -347.83268) (xy 420.086028 -348.302326) (xy 420.301674 -348.517972)
			(xy 425.800012 -348.517972)
		)
		(stroke
			(width 0)
			(type solid)
		)
		(fill yes)
		(layer "F.Cu")
		(net "SW_PVDD11_S3_P0_SW1")
	)
	(gr_poly
		(pts
			(xy 434.124608 -344.153744) (xy 434.124608 -343.985342) (xy 434.077618 -343.938352) (xy 429.856138 -343.938352)
			(xy 429.764952 -344.029538) (xy 429.764952 -344.22588) (xy 429.764952 -347.013784) (xy 429.027082 -347.751654)
			(xy 428.519082 -347.751654) (xy 428.407322 -347.863414) (xy 428.407322 -348.331028) (xy 428.618904 -348.54261)
			(xy 434.124608 -348.54261)
		)
		(stroke
			(width 0)
			(type solid)
		)
		(fill yes)
		(layer "F.Cu")
		(net "SW_PVDD11_S3_P0_SW2")
	)
	(gr_poly
		(pts
			(xy 437.12384 -99.731068) (xy 437.12384 -95.938848) (xy 436.790592 -95.6056) (xy 432.927252 -95.6056)
			(xy 432.50104 -95.179388) (xy 432.50104 -94.666308) (xy 431.9397 -94.666308) (xy 431.7111 -94.894908)
			(xy 431.7111 -95.829628) (xy 430.9237 -96.617028) (xy 430.9237 -99.751388) (xy 431.26914 -100.096828)
			(xy 436.75808 -100.096828)
		)
		(stroke
			(width 0)
			(type solid)
		)
		(fill yes)
		(layer "F.Cu")
		(net "P3V3_OCP_SFF")
	)
	(gr_poly
		(pts
			(xy 437.891936 -27.105102) (xy 437.891936 -24.699722) (xy 438.114186 -24.477472) (xy 438.92724 -24.477472)
			(xy 439.034936 -24.369776) (xy 439.034936 -24.133302) (xy 439.034936 -23.73376) (xy 438.804558 -23.503382)
			(xy 437.404256 -23.503382) (xy 437.180736 -23.726902) (xy 437.180736 -27.079702) (xy 437.231536 -27.130502)
			(xy 437.866536 -27.130502)
		)
		(stroke
			(width 0)
			(type solid)
		)
		(fill yes)
		(layer "F.Cu")
		(net "P12V_AUX")
	)
	(gr_poly
		(pts
			(xy 453.680576 -23.869142) (xy 453.680576 -22.792182) (xy 453.680576 -21.738082) (xy 453.055736 -21.113242)
			(xy 452.939658 -21.113242) (xy 452.87946 -21.17344) (xy 452.87946 -22.941026) (xy 453.045576 -23.107142)
			(xy 453.045576 -23.108412) (xy 453.170544 -23.23338) (xy 453.170544 -23.871682) (xy 453.295004 -23.996142)
			(xy 453.553576 -23.996142)
		)
		(stroke
			(width 0)
			(type solid)
		)
		(fill yes)
		(layer "F.Cu")
		(net "GND")
	)
	(gr_poly
		(pts
			(xy 454.105772 -416.04057) (xy 454.105772 -415.693606) (xy 454.095866 -415.6837) (xy 454.095866 -414.2105)
			(xy 453.943466 -414.0581) (xy 450.031866 -414.0581) (xy 449.212716 -414.0581) (xy 449.024756 -414.0581)
			(xy 448.827906 -414.25495) (xy 448.827906 -415.725356) (xy 448.827906 -416.122866) (xy 448.91706 -416.21202)
			(xy 453.934322 -416.21202)
		)
		(stroke
			(width 0)
			(type solid)
		)
		(fill yes)
		(layer "F.Cu")
		(net "P12V_AUX")
	)
	(gr_poly
		(pts
			(xy 35.100514 -368.27587) (xy 35.100514 -367.782602) (xy 35.08883 -367.770918) (xy 34.525458 -367.770918)
			(xy 34.269934 -367.515394) (xy 34.269934 -366.769904) (xy 33.720024 -366.219994) (xy 33.02762 -366.219994)
			(xy 33.024572 -366.223042) (xy 33.024572 -366.635538) (xy 33.492186 -367.103152) (xy 33.492186 -368.281712)
			(xy 33.561782 -368.351308) (xy 35.025076 -368.351308)
		)
		(stroke
			(width 0)
			(type solid)
		)
		(fill yes)
		(layer "F.Cu")
		(net "PVDDCR_CPU1_P1_VCCS")
	)
	(gr_poly
		(pts
			(xy 39.29888 -344.043762) (xy 39.29888 -340.438486) (xy 39.267892 -340.407498) (xy 34.767774 -340.407498)
			(xy 34.709354 -340.465918) (xy 34.709354 -342.728296) (xy 34.089086 -343.348564) (xy 34.059622 -343.378028)
			(xy 33.545272 -343.378028) (xy 33.351724 -343.378028) (xy 33.323022 -343.40673) (xy 33.323022 -343.917778)
			(xy 33.52292 -344.117676) (xy 39.224966 -344.117676)
		)
		(stroke
			(width 0)
			(type solid)
		)
		(fill yes)
		(layer "F.Cu")
		(net "SW_PVDDIO_P1_SW3")
	)
	(gr_poly
		(pts
			(xy 47.60468 -344.043762) (xy 47.60468 -340.438486) (xy 47.573692 -340.407498) (xy 43.073574 -340.407498)
			(xy 43.015154 -340.465918) (xy 43.015154 -342.728296) (xy 42.394886 -343.348564) (xy 42.365422 -343.378028)
			(xy 41.851072 -343.378028) (xy 41.657524 -343.378028) (xy 41.628822 -343.40673) (xy 41.628822 -343.917778)
			(xy 41.82872 -344.117676) (xy 47.530766 -344.117676)
		)
		(stroke
			(width 0)
			(type solid)
		)
		(fill yes)
		(layer "F.Cu")
		(net "SW_PVDDIO_P1_SW2")
	)
	(gr_poly
		(pts
			(xy 53.778912 -363.222032) (xy 53.778912 -360.301032) (xy 53.778912 -359.844086) (xy 53.778912 -359.746296)
			(xy 53.507894 -359.475278) (xy 46.114462 -359.475278) (xy 45.82668 -359.76306) (xy 45.82668 -363.113574)
			(xy 46.062138 -363.349032) (xy 46.674786 -363.349032) (xy 47.174912 -363.349032) (xy 52.06492 -363.349032)
			(xy 52.69992 -363.349032) (xy 53.651912 -363.349032)
		)
		(stroke
			(width 0)
			(type solid)
		)
		(fill yes)
		(layer "F.Cu")
		(net "P12V_AUX")
	)
	(gr_poly
		(pts
			(xy 55.96128 -344.043762) (xy 55.96128 -340.438486) (xy 55.930292 -340.407498) (xy 51.430174 -340.407498)
			(xy 51.371754 -340.465918) (xy 51.371754 -342.728296) (xy 50.751486 -343.348564) (xy 50.722022 -343.378028)
			(xy 50.207672 -343.378028) (xy 50.014124 -343.378028) (xy 49.985422 -343.40673) (xy 49.985422 -343.917778)
			(xy 50.18532 -344.117676) (xy 55.887366 -344.117676)
		)
		(stroke
			(width 0)
			(type solid)
		)
		(fill yes)
		(layer "F.Cu")
		(net "SW_PVDDIO_P1_SW1")
	)
	(gr_poly
		(pts
			(xy 58.440574 -160.70199) (xy 58.440574 -156.265372) (xy 58.440574 -147.467574) (xy 58.440574 -143.88338)
			(xy 58.374788 -143.817594) (xy 54.423564 -143.817594) (xy 52.451254 -145.789904) (xy 52.451254 -147.52574)
			(xy 52.451254 -147.896072) (xy 52.451254 -157.034992) (xy 53.789834 -158.373572) (xy 53.789834 -160.939734)
			(xy 53.991256 -161.141156) (xy 58.001408 -161.141156)
		)
		(stroke
			(width 0)
			(type solid)
		)
		(fill yes)
		(layer "F.Cu")
		(net "PVDD18_S5_P1")
	)
	(gr_poly
		(pts
			(xy 64.29248 -344.043762) (xy 64.29248 -340.438486) (xy 64.261492 -340.407498) (xy 59.761374 -340.407498)
			(xy 59.702954 -340.465918) (xy 59.702954 -342.728296) (xy 59.082686 -343.348564) (xy 59.053222 -343.378028)
			(xy 58.538872 -343.378028) (xy 58.345324 -343.378028) (xy 58.319162 -343.40419) (xy 58.319162 -343.910158)
			(xy 58.52668 -344.117676) (xy 64.218566 -344.117676)
		)
		(stroke
			(width 0)
			(type solid)
		)
		(fill yes)
		(layer "F.Cu")
		(net "SW_PVDDCR_CPU1_P1_SW4")
	)
	(gr_poly
		(pts
			(xy 76.13269 -183.881014) (xy 76.13269 -181.618636) (xy 76.752958 -180.998368) (xy 76.782422 -180.968904)
			(xy 77.296772 -180.968904) (xy 77.49032 -180.968904) (xy 77.505814 -180.95341) (xy 77.505814 -180.425852)
			(xy 77.309218 -180.229256) (xy 71.617078 -180.229256) (xy 71.543164 -180.30317) (xy 71.543164 -183.908446)
			(xy 71.574152 -183.939434) (xy 76.07427 -183.939434)
		)
		(stroke
			(width 0)
			(type solid)
		)
		(fill yes)
		(layer "F.Cu")
		(net "SW_PVDDCR_CPU0_P1_SW5")
	)
	(gr_poly
		(pts
			(xy 84.45627 -188.999114) (xy 84.45627 -186.736736) (xy 85.076538 -186.116468) (xy 85.106002 -186.087004)
			(xy 85.620352 -186.087004) (xy 85.8139 -186.087004) (xy 85.847936 -186.052968) (xy 85.847936 -185.561732)
			(xy 85.63356 -185.347356) (xy 79.940658 -185.347356) (xy 79.866744 -185.42127) (xy 79.866744 -189.026546)
			(xy 79.897732 -189.057534) (xy 84.39785 -189.057534)
		)
		(stroke
			(width 0)
			(type solid)
		)
		(fill yes)
		(layer "F.Cu")
		(net "SW_PVDDCR_CPU0_P1_SW1")
	)
	(gr_poly
		(pts
			(xy 92.85351 -188.931042) (xy 92.85351 -186.668664) (xy 93.473778 -186.048396) (xy 93.503242 -186.018932)
			(xy 94.017592 -186.018932) (xy 94.21114 -186.018932) (xy 94.247208 -185.982864) (xy 94.247208 -185.48731)
			(xy 94.039182 -185.279284) (xy 88.337898 -185.279284) (xy 88.263984 -185.353198) (xy 88.263984 -188.958474)
			(xy 88.294972 -188.989462) (xy 92.79509 -188.989462)
		)
		(stroke
			(width 0)
			(type solid)
		)
		(fill yes)
		(layer "F.Cu")
		(net "SW_PVDDCR_CPU0_P1_SW2")
	)
	(gr_poly
		(pts
			(xy 106.147108 -337.261962) (xy 106.147108 -333.656686) (xy 106.11612 -333.625698) (xy 101.616002 -333.625698)
			(xy 101.557582 -333.684118) (xy 101.557582 -335.946496) (xy 100.937314 -336.566764) (xy 100.90785 -336.596228)
			(xy 100.3935 -336.596228) (xy 100.199952 -336.596228) (xy 100.16236 -336.63382) (xy 100.16236 -337.121754)
			(xy 100.376482 -337.335876) (xy 106.073194 -337.335876)
		)
		(stroke
			(width 0)
			(type solid)
		)
		(fill yes)
		(layer "F.Cu")
		(net "SW_PVDDCR_CPU1_P1_SW6")
	)
	(gr_poly
		(pts
			(xy 217.89517 -135.224012) (xy 217.89517 -134.422642) (xy 217.6399 -134.167372) (xy 217.63736 -134.167372)
			(xy 217.239342 -133.769354) (xy 215.13292 -133.769354) (xy 214.734902 -134.167372) (xy 213.315296 -134.167372)
			(xy 213.170008 -134.31266) (xy 213.170008 -135.206486) (xy 213.228174 -135.264652) (xy 216.40927 -135.264652)
			(xy 216.478866 -135.334248) (xy 217.784934 -135.334248)
		)
		(stroke
			(width 0)
			(type solid)
		)
		(fill yes)
		(layer "F.Cu")
		(net "GND")
	)
	(gr_poly
		(pts
			(xy 251.717302 -53.686202) (xy 252.792484 -53.686202) (xy 252.868684 -53.610002) (xy 252.868684 -53.267864)
			(xy 252.86208 -53.26126) (xy 251.66574 -53.26126) (xy 251.63272 -53.29428) (xy 249.39498 -53.29428)
			(xy 249.3645 -53.32476) (xy 248.001028 -53.32476) (xy 247.942608 -53.382418) (xy 247.942608 -54.017672)
			(xy 248.068084 -54.143402) (xy 251.260102 -54.143402)
		)
		(stroke
			(width 0)
			(type solid)
		)
		(fill yes)
		(layer "F.Cu")
		(net "P12V_E1S_AVIN_PD_0")
	)
	(gr_poly
		(pts
			(xy 252.805184 -56.495442) (xy 252.805184 -55.901844) (xy 252.78334 -55.88) (xy 250.25096 -55.88)
			(xy 250.12142 -55.75046) (xy 250.12142 -54.713632) (xy 249.945144 -54.537356) (xy 248.860564 -54.537356)
			(xy 248.76125 -54.63667) (xy 248.76125 -54.76494) (xy 248.76125 -56.346598) (xy 248.960894 -56.546242)
			(xy 249.401584 -56.546242) (xy 252.754384 -56.546242)
		)
		(stroke
			(width 0)
			(type solid)
		)
		(fill yes)
		(layer "F.Cu")
		(net "P12V_AUX")
	)
	(gr_poly
		(pts
			(xy 277.839932 -344.038936) (xy 277.839932 -340.43366) (xy 277.808944 -340.402672) (xy 273.308826 -340.402672)
			(xy 273.250406 -340.461092) (xy 273.250406 -342.72347) (xy 272.630138 -343.343738) (xy 272.600674 -343.373202)
			(xy 272.086324 -343.373202) (xy 271.892776 -343.373202) (xy 271.86001 -343.405968) (xy 271.86001 -343.910412)
			(xy 272.062448 -344.11285) (xy 277.766018 -344.11285)
		)
		(stroke
			(width 0)
			(type solid)
		)
		(fill yes)
		(layer "F.Cu")
		(net "SW_PVDDIO_P0_SW4")
	)
	(gr_poly
		(pts
			(xy 277.91156 -339.191092) (xy 277.91156 -337.790282) (xy 277.74519 -337.623912) (xy 273.02841 -337.623912)
			(xy 272.61947 -337.214972) (xy 272.61947 -335.64957) (xy 272.50644 -335.53654) (xy 265.7602 -335.53654)
			(xy 265.531346 -335.765394) (xy 265.531346 -339.083396) (xy 265.761978 -339.314028) (xy 270.748506 -339.314028)
			(xy 271.271746 -339.314028) (xy 277.788624 -339.314028)
		)
		(stroke
			(width 0)
			(type solid)
		)
		(fill yes)
		(layer "F.Cu")
		(net "IND_PVDDIO_P0_CPL0")
	)
	(gr_poly
		(pts
			(xy 286.120332 -344.038936) (xy 286.120332 -340.43366) (xy 286.089344 -340.402672) (xy 281.589226 -340.402672)
			(xy 281.530806 -340.461092) (xy 281.530806 -342.72347) (xy 280.910538 -343.343738) (xy 280.881074 -343.373202)
			(xy 280.366724 -343.373202) (xy 280.173176 -343.373202) (xy 280.14041 -343.405968) (xy 280.14041 -343.910666)
			(xy 280.342594 -344.11285) (xy 286.046418 -344.11285)
		)
		(stroke
			(width 0)
			(type solid)
		)
		(fill yes)
		(layer "F.Cu")
		(net "SW_PVDDIO_P0_SW3")
	)
	(gr_poly
		(pts
			(xy 294.426132 -344.038936) (xy 294.426132 -340.43366) (xy 294.395144 -340.402672) (xy 289.895026 -340.402672)
			(xy 289.836606 -340.461092) (xy 289.836606 -342.72347) (xy 289.216338 -343.343738) (xy 289.186874 -343.373202)
			(xy 288.672524 -343.373202) (xy 288.478976 -343.373202) (xy 288.44621 -343.405968) (xy 288.44621 -343.905332)
			(xy 288.653728 -344.11285) (xy 294.352218 -344.11285)
		)
		(stroke
			(width 0)
			(type solid)
		)
		(fill yes)
		(layer "F.Cu")
		(net "SW_PVDDIO_P0_SW2")
	)
	(gr_poly
		(pts
			(xy 302.782732 -344.038936) (xy 302.782732 -340.43366) (xy 302.751744 -340.402672) (xy 298.251626 -340.402672)
			(xy 298.193206 -340.461092) (xy 298.193206 -342.72347) (xy 297.572938 -343.343738) (xy 297.543474 -343.373202)
			(xy 297.029124 -343.373202) (xy 296.835576 -343.373202) (xy 296.81297 -343.395808) (xy 296.81297 -343.910412)
			(xy 297.015408 -344.11285) (xy 302.708818 -344.11285)
		)
		(stroke
			(width 0)
			(type solid)
		)
		(fill yes)
		(layer "F.Cu")
		(net "SW_PVDDIO_P0_SW1")
	)
	(gr_poly
		(pts
			(xy 311.113932 -344.038936) (xy 311.113932 -340.43366) (xy 311.082944 -340.402672) (xy 306.582826 -340.402672)
			(xy 306.524406 -340.461092) (xy 306.524406 -342.72347) (xy 305.904138 -343.343738) (xy 305.874674 -343.373202)
			(xy 305.360324 -343.373202) (xy 305.166776 -343.373202) (xy 305.13909 -343.400888) (xy 305.13909 -343.910412)
			(xy 305.341528 -344.11285) (xy 311.040018 -344.11285)
		)
		(stroke
			(width 0)
			(type solid)
		)
		(fill yes)
		(layer "F.Cu")
		(net "SW_PVDDCR_CPU1_P0_SW4")
	)
	(gr_poly
		(pts
			(xy 329.658218 -40.253412) (xy 329.658218 -37.80917) (xy 329.213718 -37.36467) (xy 329.213718 -36.770056)
			(xy 329.089512 -36.64585) (xy 324.508114 -36.64585) (xy 324.475348 -36.678616) (xy 324.475348 -37.018214)
			(xy 324.494906 -37.037772) (xy 326.285606 -37.037772) (xy 328.337926 -39.090092) (xy 328.337926 -40.188134)
			(xy 328.586338 -40.436546) (xy 329.475084 -40.436546)
		)
		(stroke
			(width 0)
			(type solid)
		)
		(fill yes)
		(layer "F.Cu")
		(net "P3V3_MAX11617_VDD")
	)
	(gr_poly
		(pts
			(xy 345.808046 -332.347062) (xy 345.808046 -328.76998) (xy 345.748864 -328.710798) (xy 341.27694 -328.710798)
			(xy 341.21852 -328.769218) (xy 341.21852 -331.031596) (xy 340.598252 -331.651864) (xy 340.568788 -331.681328)
			(xy 340.054438 -331.681328) (xy 339.86089 -331.681328) (xy 339.828378 -331.71384) (xy 339.828378 -332.210918)
			(xy 340.038436 -332.420976) (xy 345.734132 -332.420976)
		)
		(stroke
			(width 0)
			(type solid)
		)
		(fill yes)
		(layer "F.Cu")
		(net "SW_PVDDCR_CPU1_P0_SW5")
	)
	(gr_poly
		(pts
			(xy 354.083874 -337.257136) (xy 354.083874 -333.65186) (xy 354.052886 -333.620872) (xy 349.552768 -333.620872)
			(xy 349.494348 -333.679292) (xy 349.494348 -335.94167) (xy 348.87408 -336.561938) (xy 348.844616 -336.591402)
			(xy 348.330266 -336.591402) (xy 348.271592 -336.591402) (xy 348.108524 -336.75447) (xy 348.108524 -337.128612)
			(xy 348.310962 -337.33105) (xy 354.00996 -337.33105)
		)
		(stroke
			(width 0)
			(type solid)
		)
		(fill yes)
		(layer "F.Cu")
		(net "SW_PVDDCR_CPU1_P0_SW6")
	)
	(gr_poly
		(pts
			(xy 375.31929 -147.360386) (xy 375.31929 -142.615158) (xy 375.06529 -142.361158) (xy 373.94515 -142.361158)
			(xy 373.81815 -142.488158) (xy 373.81815 -142.6718) (xy 374.585484 -143.439134) (xy 374.585484 -143.926814)
			(xy 374.026176 -144.486122) (xy 373.148352 -144.486122) (xy 373.044466 -144.590008) (xy 373.044466 -147.92706)
			(xy 373.171466 -148.05406) (xy 374.625616 -148.05406)
		)
		(stroke
			(width 0)
			(type solid)
		)
		(fill yes)
		(layer "F.Cu")
		(net "PVDD18_S5_P0")
	)
	(gr_poly
		(pts
			(xy 420.33698 -105.44048) (xy 420.33698 -104.846628) (xy 420.27856 -104.788208) (xy 419.81628 -104.788208)
			(xy 419.46576 -104.437688) (xy 419.46576 -103.782368) (xy 419.2651 -103.581708) (xy 418.29736 -103.581708)
			(xy 418.13226 -103.746808) (xy 418.13226 -105.390188) (xy 418.24148 -105.499408) (xy 418.44468 -105.702608)
			(xy 419.78834 -105.702608) (xy 420.074852 -105.702608)
		)
		(stroke
			(width 0)
			(type solid)
		)
		(fill yes)
		(layer "F.Cu")
		(net "P3V3_AUX")
	)
	(gr_poly
		(pts
			(xy 458.68336 -58.039508) (xy 458.68336 -53.696108) (xy 458.63002 -53.642768) (xy 458.44714 -53.642768)
			(xy 454.7489 -53.642768) (xy 454.733406 -53.658262) (xy 454.339706 -53.658262) (xy 453.986646 -53.658262)
			(xy 453.727566 -53.658262) (xy 453.61606 -53.769768) (xy 453.61606 -58.169048) (xy 453.68464 -58.237628)
			(xy 454.00976 -58.237628) (xy 458.48524 -58.237628)
		)
		(stroke
			(width 0)
			(type solid)
		)
		(fill yes)
		(layer "F.Cu")
		(net "SW_P3V3_AUX_SW")
	)
	(gr_poly
		(pts
			(xy 462.3816 -49.002442) (xy 462.3816 -48.12538) (xy 462.3816 -47.888652) (xy 462.3816 -46.97095)
			(xy 462.070196 -46.659546) (xy 460.060548 -46.659546) (xy 459.889352 -46.830742) (xy 459.889352 -47.618142)
			(xy 459.967076 -47.695866) (xy 460.690976 -47.695866) (xy 460.941166 -47.946056) (xy 460.941166 -49.113948)
			(xy 461.006698 -49.17948) (xy 462.204562 -49.17948)
		)
		(stroke
			(width 0)
			(type solid)
		)
		(fill yes)
		(layer "F.Cu")
		(net "GND")
	)
	(gr_poly
		(pts
			(xy 46.212506 -400.46783) (xy 46.212506 -400.158458) (xy 45.869606 -399.815558) (xy 45.869606 -399.1229)
			(xy 45.869606 -398.66189) (xy 45.869606 -398.551146) (xy 45.745146 -398.426686) (xy 44.991782 -398.426686)
			(xy 44.887642 -398.530826) (xy 44.887642 -398.645634) (xy 44.887642 -399.074132) (xy 44.887642 -399.85569)
			(xy 44.887642 -400.024092) (xy 45.466 -400.60245) (xy 46.077886 -400.60245)
		)
		(stroke
			(width 0)
			(type solid)
		)
		(fill yes)
		(layer "F.Cu")
		(net "P0V9_CPU1_RT0_2A_2D")
	)
	(gr_poly
		(pts
			(xy 47.500032 -399.714974) (xy 47.500032 -395.377924) (xy 47.487078 -395.36497) (xy 47.363634 -395.36497)
			(xy 45.604176 -393.605512) (xy 40.537892 -393.605512) (xy 40.304974 -393.83843) (xy 40.304974 -395.328394)
			(xy 40.304974 -396.070836) (xy 40.518334 -396.284196) (xy 44.396152 -396.284196) (xy 46.360842 -398.248886)
			(xy 46.360842 -399.739866) (xy 46.43628 -399.815304) (xy 47.399702 -399.815304)
		)
		(stroke
			(width 0)
			(type solid)
		)
		(fill yes)
		(layer "F.Cu")
		(net "P0V9_CPU1_RT0_2A")
	)
	(gr_poly
		(pts
			(xy 62.765686 -178.484276) (xy 62.831726 -178.418236) (xy 62.953646 -178.296316) (xy 63.158878 -178.091084)
			(xy 63.307468 -177.942494) (xy 67.80022 -177.942494) (xy 67.984878 -177.757836) (xy 67.984878 -176.440084)
			(xy 67.857878 -176.313084) (xy 55.785004 -176.313084) (xy 55.461154 -176.636426) (xy 55.461154 -177.946812)
			(xy 55.461154 -178.873658) (xy 55.92191 -179.334414) (xy 61.915548 -179.334414)
		)
		(stroke
			(width 0)
			(type solid)
		)
		(fill yes)
		(layer "F.Cu")
		(net "IND_CPU0_P1_CPL0")
	)
	(gr_poly
		(pts
			(xy 119.949722 -76.124562) (xy 121.372122 -76.124562) (xy 121.387362 -76.109322) (xy 121.387362 -75.890882)
			(xy 121.372122 -75.875642) (xy 119.390922 -75.875642) (xy 117.762782 -74.247502) (xy 115.598702 -74.247502)
			(xy 115.473734 -74.247502) (xy 115.236498 -74.484738) (xy 115.236498 -74.863706) (xy 115.236498 -76.460858)
			(xy 115.339622 -76.563982) (xy 115.406932 -76.631292) (xy 119.442992 -76.631292)
		)
		(stroke
			(width 0)
			(type solid)
		)
		(fill yes)
		(layer "F.Cu")
		(net "SW_P12V_AUX_P1V2_AUX_FLT")
	)
	(gr_poly
		(pts
			(xy 137.000234 -155.762452) (xy 138.041634 -155.762452) (xy 138.356594 -155.447492) (xy 138.356594 -154.644852)
			(xy 138.356594 -151.817832) (xy 138.249914 -151.711152) (xy 136.865614 -151.711152) (xy 136.639554 -151.937212)
			(xy 136.639554 -154.975052) (xy 136.309354 -155.305252) (xy 135.933434 -155.305252) (xy 135.831834 -155.406852)
			(xy 135.831834 -156.333952) (xy 135.90524 -156.407358) (xy 136.355328 -156.407358)
		)
		(stroke
			(width 0)
			(type solid)
		)
		(fill yes)
		(layer "F.Cu")
		(net "PVDDCR_CPU0_P1_PVCC")
	)
	(gr_poly
		(pts
			(xy 142.047722 -78.410562) (xy 143.470122 -78.410562) (xy 143.485362 -78.395322) (xy 143.485362 -78.176882)
			(xy 143.470122 -78.161642) (xy 141.488922 -78.161642) (xy 139.860782 -76.533502) (xy 137.696702 -76.533502)
			(xy 137.571734 -76.533502) (xy 137.334498 -76.770738) (xy 137.334498 -77.149706) (xy 137.334498 -78.746858)
			(xy 137.437622 -78.849982) (xy 137.504932 -78.917292) (xy 141.540992 -78.917292)
		)
		(stroke
			(width 0)
			(type solid)
		)
		(fill yes)
		(layer "F.Cu")
		(net "SW_P12V_AUX_P1V8_AUX_FLT")
	)
	(gr_poly
		(pts
			(xy 302.212248 -408.84983) (xy 302.212248 -408.540458) (xy 301.869348 -408.197558) (xy 301.869348 -407.5049)
			(xy 301.869348 -407.04389) (xy 301.869348 -406.933146) (xy 301.744888 -406.808686) (xy 300.991524 -406.808686)
			(xy 300.887384 -406.912826) (xy 300.887384 -407.027634) (xy 300.887384 -407.456132) (xy 300.887384 -408.23769)
			(xy 300.887384 -408.406092) (xy 301.465742 -408.98445) (xy 302.077628 -408.98445)
		)
		(stroke
			(width 0)
			(type solid)
		)
		(fill yes)
		(layer "F.Cu")
		(net "P0V9_CPU0_RT0_2A_2D")
	)
	(gr_poly
		(pts
			(xy 329.11923 -332.296262) (xy 329.11923 -328.715878) (xy 329.06335 -328.659998) (xy 324.588124 -328.659998)
			(xy 324.529704 -328.718418) (xy 324.529704 -330.980796) (xy 324.529704 -331.041502) (xy 323.913246 -331.65796)
			(xy 323.192902 -331.65796) (xy 323.1388 -331.712062) (xy 323.1388 -332.17866) (xy 323.330316 -332.370176)
			(xy 323.421248 -332.370176) (xy 324.557136 -332.370176) (xy 329.045316 -332.370176)
		)
		(stroke
			(width 0)
			(type solid)
		)
		(fill yes)
		(layer "F.Cu")
		(net "SW_PVDDCR_CPU1_P0_SW2")
	)
	(gr_poly
		(pts
			(xy 337.476846 -332.296262) (xy 337.476846 -328.715116) (xy 337.421728 -328.659998) (xy 332.94574 -328.659998)
			(xy 332.88732 -328.718418) (xy 332.88732 -330.980796) (xy 332.88732 -331.054964) (xy 332.311756 -331.630528)
			(xy 332.237588 -331.630528) (xy 331.723238 -331.630528) (xy 331.52969 -331.630528) (xy 331.493368 -331.66685)
			(xy 331.493368 -332.1558) (xy 331.707744 -332.370176) (xy 337.402932 -332.370176)
		)
		(stroke
			(width 0)
			(type solid)
		)
		(fill yes)
		(layer "F.Cu")
		(net "SW_PVDDCR_CPU1_P0_SW1")
	)
	(gr_poly
		(pts
			(xy 339.6488 -160.6296) (xy 339.6488 -151.5872) (xy 339.37448 -151.31288) (xy 338.84108 -151.31288)
			(xy 330.23048 -151.31288) (xy 328.77252 -151.31288) (xy 328.6506 -151.4348) (xy 328.6506 -155.00096)
			(xy 330.13396 -156.48432) (xy 330.933552 -157.283912) (xy 330.933552 -159.141668) (xy 330.933552 -160.575752)
			(xy 331.3176 -160.9598) (xy 338.1248 -160.9598) (xy 339.3186 -160.9598)
		)
		(stroke
			(width 0)
			(type solid)
		)
		(fill yes)
		(layer "F.Cu")
		(net "PVDD18_S5_P0")
	)
	(gr_poly
		(pts
			(xy 9.914382 -412.47187) (xy 9.914382 -407.123392) (xy 9.914382 -405.953722) (xy 9.76503 -405.80437)
			(xy 9.514332 -405.80437) (xy 9.438894 -405.879808) (xy 9.438894 -406.737566) (xy 9.203182 -406.973278)
			(xy 8.457438 -406.973278) (xy 8.330438 -407.100278) (xy 8.301228 -407.129488) (xy 8.297418 -407.133552)
			(xy 8.297418 -412.175706) (xy 8.593582 -412.47187) (xy 8.720582 -412.59887) (xy 9.787382 -412.59887)
		)
		(stroke
			(width 0)
			(type solid)
		)
		(fill yes)
		(layer "F.Cu")
		(net "GND")
	)
	(gr_poly
		(pts
			(xy 17.914366 -424.274742) (xy 17.914366 -421.976042) (xy 17.796256 -421.857932) (xy 17.101566 -421.857932)
			(xy 16.991584 -421.74795) (xy 16.991584 -421.00119) (xy 16.941546 -420.951152) (xy 16.807688 -420.951152)
			(xy 16.760698 -420.998142) (xy 16.760698 -421.790114) (xy 16.708628 -421.842184) (xy 15.38732 -421.842184)
			(xy 15.342616 -421.886888) (xy 15.342616 -424.332654) (xy 15.421356 -424.411394) (xy 17.777714 -424.411394)
		)
		(stroke
			(width 0)
			(type solid)
		)
		(fill yes)
		(layer "F.Cu")
		(net "GND")
	)
	(gr_poly
		(pts
			(xy 39.487094 -339.166454) (xy 39.487094 -337.693254) (xy 39.309294 -337.515454) (xy 34.457894 -337.515454)
			(xy 34.089594 -337.147154) (xy 34.089594 -335.750154) (xy 33.882584 -335.543144) (xy 26.346404 -335.543144)
			(xy 26.202894 -335.686654) (xy 26.202894 -337.058254) (xy 26.406094 -337.261454) (xy 31.232094 -337.261454)
			(xy 31.536894 -337.566254) (xy 31.536894 -338.836254) (xy 31.965392 -339.264752) (xy 39.388796 -339.264752)
		)
		(stroke
			(width 0)
			(type solid)
		)
		(fill yes)
		(layer "F.Cu")
		(net "IND_PVDDIO_P1_CPL4")
	)
	(gr_poly
		(pts
			(xy 47.767494 -339.166454) (xy 47.767494 -337.693254) (xy 47.589694 -337.515454) (xy 42.738294 -337.515454)
			(xy 42.369994 -337.147154) (xy 42.369994 -335.750154) (xy 42.162984 -335.543144) (xy 34.626804 -335.543144)
			(xy 34.483294 -335.686654) (xy 34.483294 -337.058254) (xy 34.686494 -337.261454) (xy 39.512494 -337.261454)
			(xy 39.817294 -337.566254) (xy 39.817294 -338.836254) (xy 40.245792 -339.264752) (xy 47.669196 -339.264752)
		)
		(stroke
			(width 0)
			(type solid)
		)
		(fill yes)
		(layer "F.Cu")
		(net "IND_PVDDIO_P1_CPL3")
	)
	(gr_poly
		(pts
			(xy 56.03494 -339.255608) (xy 56.03494 -337.6041) (xy 55.946294 -337.515454) (xy 51.094894 -337.515454)
			(xy 50.726594 -337.147154) (xy 50.726594 -335.750154) (xy 50.519584 -335.543144) (xy 42.983404 -335.543144)
			(xy 42.839894 -335.686654) (xy 42.839894 -337.058254) (xy 43.043094 -337.261454) (xy 47.869094 -337.261454)
			(xy 48.173894 -337.566254) (xy 48.173894 -338.836254) (xy 48.602392 -339.264752) (xy 56.025796 -339.264752)
		)
		(stroke
			(width 0)
			(type solid)
		)
		(fill yes)
		(layer "F.Cu")
		(net "IND_PVDDIO_P1_CPL2")
	)
	(gr_poly
		(pts
			(xy 76.065634 -327.123552) (xy 76.065634 -325.853552) (xy 76.370434 -325.548752) (xy 81.196434 -325.548752)
			(xy 81.399634 -325.345552) (xy 81.399634 -323.973952) (xy 81.221072 -323.79539) (xy 73.754996 -323.79539)
			(xy 73.512934 -324.037452) (xy 73.512934 -325.434452) (xy 72.961246 -325.98614) (xy 68.312792 -325.98614)
			(xy 68.115434 -326.183498) (xy 68.115434 -327.453752) (xy 68.20408 -327.542398) (xy 75.646788 -327.542398)
		)
		(stroke
			(width 0)
			(type solid)
		)
		(fill yes)
		(layer "F.Cu")
		(net "IND_CPU1_P1_CPL2")
	)
	(gr_poly
		(pts
			(xy 81.182464 -332.301088) (xy 81.182464 -328.695812) (xy 81.151476 -328.664824) (xy 76.651358 -328.664824)
			(xy 76.592938 -328.723244) (xy 76.592938 -330.985622) (xy 75.97267 -331.60589) (xy 75.943206 -331.635354)
			(xy 75.428856 -331.635354) (xy 75.283568 -331.635354) (xy 75.218036 -331.700886) (xy 75.218036 -332.199488)
			(xy 75.39355 -332.375002) (xy 75.484482 -332.375002) (xy 76.62037 -332.375002) (xy 81.10855 -332.375002)
		)
		(stroke
			(width 0)
			(type solid)
		)
		(fill yes)
		(layer "F.Cu")
		(net "SW_PVDDCR_CPU1_P1_SW2")
	)
	(gr_poly
		(pts
			(xy 84.394294 -327.123552) (xy 84.394294 -325.853552) (xy 84.699094 -325.548752) (xy 89.525094 -325.548752)
			(xy 89.728294 -325.345552) (xy 89.728294 -323.973952) (xy 89.544398 -323.790056) (xy 82.08899 -323.790056)
			(xy 81.841594 -324.037452) (xy 81.841594 -325.434452) (xy 81.473294 -325.802752) (xy 76.621894 -325.802752)
			(xy 76.444094 -325.980552) (xy 76.444094 -327.453752) (xy 76.517246 -327.526904) (xy 83.990942 -327.526904)
		)
		(stroke
			(width 0)
			(type solid)
		)
		(fill yes)
		(layer "F.Cu")
		(net "IND_CPU1_P1_CPL1")
	)
	(gr_poly
		(pts
			(xy 92.59189 -149.819614) (xy 92.59189 -145.01241) (xy 92.33789 -144.75841) (xy 91.21775 -144.75841)
			(xy 91.09075 -144.88541) (xy 91.09075 -145.004282) (xy 91.656662 -145.570194) (xy 91.656662 -146.525488)
			(xy 91.298776 -146.883374) (xy 90.420952 -146.883374) (xy 90.317066 -146.98726) (xy 90.317066 -148.109686)
			(xy 90.92184 -148.71446) (xy 90.92184 -150.332186) (xy 91.040966 -150.451312) (xy 91.960192 -150.451312)
		)
		(stroke
			(width 0)
			(type solid)
		)
		(fill yes)
		(layer "F.Cu")
		(net "PVDD18_S5_P1")
	)
	(gr_poly
		(pts
			(xy 92.674694 -327.123552) (xy 92.674694 -325.853552) (xy 92.979494 -325.548752) (xy 97.744026 -325.548752)
			(xy 97.8662 -325.426578) (xy 97.8662 -323.905626) (xy 97.76968 -323.809106) (xy 90.35034 -323.809106)
			(xy 90.121994 -324.037452) (xy 90.121994 -325.434452) (xy 89.753694 -325.802752) (xy 84.902294 -325.802752)
			(xy 84.724494 -325.980552) (xy 84.724494 -327.453752) (xy 84.7979 -327.527158) (xy 92.271088 -327.527158)
		)
		(stroke
			(width 0)
			(type solid)
		)
		(fill yes)
		(layer "F.Cu")
		(net "IND_CPU1_P1_CPL5")
	)
	(gr_poly
		(pts
			(xy 106.187494 -330.018136) (xy 106.187494 -329.002136) (xy 105.949242 -328.763884) (xy 100.843842 -328.763884)
			(xy 100.44176 -328.361802) (xy 100.44176 -326.735694) (xy 99.76993 -326.063864) (xy 93.137736 -326.063864)
			(xy 92.954094 -326.247506) (xy 92.954094 -327.352152) (xy 93.154754 -327.552812) (xy 98.412554 -327.552812)
			(xy 99.29876 -328.439018) (xy 99.29876 -329.536806) (xy 100.03409 -330.272136) (xy 105.933494 -330.272136)
		)
		(stroke
			(width 0)
			(type solid)
		)
		(fill yes)
		(layer "F.Cu")
		(net "IND_CPU1_P1_CPL6")
	)
	(gr_poly
		(pts
			(xy 155.833572 -57.754012) (xy 155.833572 -57.141364) (xy 155.994862 -56.980074) (xy 156.650436 -56.980074)
			(xy 156.682694 -56.947816) (xy 156.682694 -56.824118) (xy 156.602176 -56.7436) (xy 155.925012 -56.7436)
			(xy 155.82265 -56.641238) (xy 155.82265 -56.361838) (xy 155.731464 -56.270652) (xy 154.237182 -56.270652)
			(xy 154.156664 -56.35117) (xy 154.156664 -57.883298) (xy 154.210258 -57.936892) (xy 155.650692 -57.936892)
		)
		(stroke
			(width 0)
			(type solid)
		)
		(fill yes)
		(layer "F.Cu")
		(net "GND")
	)
	(gr_poly
		(pts
			(xy 164.84473 -352.439478) (xy 164.94633 -352.337878) (xy 164.94633 -351.296478) (xy 164.94633 -350.966278)
			(xy 164.94633 -350.280478) (xy 164.940234 -350.274382) (xy 164.317426 -350.274382) (xy 164.31133 -350.280478)
			(xy 164.31133 -351.271078) (xy 164.15893 -351.423478) (xy 163.14293 -351.423478) (xy 163.025836 -351.540572)
			(xy 163.025836 -352.50755) (xy 163.084764 -352.566478) (xy 163.11753 -352.566478) (xy 164.71773 -352.566478)
		)
		(stroke
			(width 0)
			(type solid)
		)
		(fill yes)
		(layer "F.Cu")
		(net "PVDD11_S3_P1_VCCS")
	)
	(gr_poly
		(pts
			(xy 174.810674 -21.816568) (xy 174.810674 -20.579588) (xy 175.646334 -19.743928) (xy 175.646334 -19.141948)
			(xy 175.524414 -19.020028) (xy 175.288194 -19.020028) (xy 174.960534 -19.020028) (xy 174.785274 -19.195288)
			(xy 174.498 -19.195288) (xy 174.498 -19.2024) (xy 173.0756 -20.6248) (xy 172.70476 -20.99564) (xy 172.70476 -21.938488)
			(xy 172.83684 -22.070568) (xy 173.936914 -22.070568) (xy 174.556674 -22.070568)
		)
		(stroke
			(width 0)
			(type solid)
		)
		(fill yes)
		(layer "F.Cu")
		(net "GND")
	)
	(gr_poly
		(pts
			(xy 195.50888 -342.14054) (xy 196.01434 -342.14054) (xy 196.18198 -341.9729) (xy 196.18198 -333.1972)
			(xy 195.91782 -332.93304) (xy 195.115942 -332.93304) (xy 193.933826 -332.93304) (xy 175.39208 -332.93304)
			(xy 171.114466 -332.93304) (xy 170.952414 -333.095092) (xy 170.952414 -341.837772) (xy 171.260262 -342.14562)
			(xy 172.463714 -342.14562) (xy 175.993044 -342.14562) (xy 194.05473 -342.14562) (xy 195.503546 -342.14562)
		)
		(stroke
			(width 0)
			(type solid)
		)
		(fill yes)
		(layer "F.Cu")
		(net "PVDD11_S3_P1")
	)
	(gr_poly
		(pts
			(xy 216.065354 -55.072788) (xy 216.065354 -54.437788) (xy 216.192354 -54.310788) (xy 216.901014 -54.310788)
			(xy 216.954354 -54.257448) (xy 216.954354 -54.158388) (xy 216.862914 -54.066948) (xy 216.238074 -54.066948)
			(xy 216.083134 -53.912008) (xy 216.083134 -53.721508) (xy 215.956134 -53.594508) (xy 214.615014 -53.594508)
			(xy 214.432134 -53.777388) (xy 214.432134 -55.192168) (xy 214.495634 -55.255668) (xy 215.882474 -55.255668)
		)
		(stroke
			(width 0)
			(type solid)
		)
		(fill yes)
		(layer "F.Cu")
		(net "GND")
	)
	(gr_poly
		(pts
			(xy 238.821468 -48.756062) (xy 238.821468 -48.490378) (xy 238.653574 -48.322484) (xy 238.487458 -48.322484)
			(xy 238.305848 -48.504094) (xy 237.905544 -48.504094) (xy 237.723934 -48.322484) (xy 237.373414 -48.322484)
			(xy 237.326424 -48.369474) (xy 236.014768 -48.369474) (xy 235.952284 -48.431958) (xy 235.952284 -48.708818)
			(xy 235.98759 -48.744124) (xy 237.32617 -48.744124) (xy 237.646464 -49.064418) (xy 238.513112 -49.064418)
		)
		(stroke
			(width 0)
			(type solid)
		)
		(fill yes)
		(layer "F.Cu")
		(net "P3V3_E1S_0")
	)
	(gr_poly
		(pts
			(xy 332.33106 -327.118726) (xy 332.33106 -325.848726) (xy 332.63586 -325.543926) (xy 337.46186 -325.543926)
			(xy 337.66506 -325.340726) (xy 337.66506 -323.969126) (xy 337.492594 -323.79666) (xy 330.014326 -323.79666)
			(xy 329.77836 -324.032626) (xy 329.77836 -325.429626) (xy 329.41006 -325.797926) (xy 324.55866 -325.797926)
			(xy 324.38086 -325.975726) (xy 324.38086 -327.448926) (xy 324.445122 -327.513188) (xy 331.936598 -327.513188)
		)
		(stroke
			(width 0)
			(type solid)
		)
		(fill yes)
		(layer "F.Cu")
		(net "IND_CPU1_P0_CPL1")
	)
	(gr_poly
		(pts
			(xy 334.459834 -42.50436) (xy 334.459834 -40.77462) (xy 334.279494 -40.59428) (xy 331.838554 -40.59428)
			(xy 331.444854 -40.20058) (xy 331.444854 -39.63162) (xy 331.386434 -39.5732) (xy 330.056236 -39.5732)
			(xy 330.007468 -39.621968) (xy 330.007468 -40.546528) (xy 329.740514 -40.813482) (xy 329.740514 -41.374314)
			(xy 329.87234 -41.50614) (xy 330.75626 -41.50614) (xy 331.92974 -42.67962) (xy 334.284574 -42.67962)
		)
		(stroke
			(width 0)
			(type solid)
		)
		(fill yes)
		(layer "F.Cu")
		(net "P3V3_AUX")
	)
	(gr_poly
		(pts
			(xy 340.61146 -327.118726) (xy 340.61146 -325.848726) (xy 340.91626 -325.543926) (xy 345.53398 -325.543926)
			(xy 345.691206 -325.3867) (xy 345.691206 -323.82714) (xy 345.673426 -323.80936) (xy 338.282026 -323.80936)
			(xy 338.05876 -324.032626) (xy 338.05876 -325.429626) (xy 337.69046 -325.797926) (xy 332.83906 -325.797926)
			(xy 332.66126 -325.975726) (xy 332.66126 -327.448926) (xy 332.731872 -327.519538) (xy 340.210648 -327.519538)
		)
		(stroke
			(width 0)
			(type solid)
		)
		(fill yes)
		(layer "F.Cu")
		(net "IND_CPU1_P0_CPL5")
	)
	(gr_poly
		(pts
			(xy 354.12426 -330.01331) (xy 354.12426 -328.99731) (xy 353.87026 -328.74331) (xy 348.76486 -328.74331)
			(xy 348.345506 -328.323956) (xy 348.345506 -326.577198) (xy 347.675962 -325.907654) (xy 340.958932 -325.907654)
			(xy 340.89086 -325.975726) (xy 340.89086 -327.347326) (xy 341.076026 -327.532492) (xy 346.472764 -327.532492)
			(xy 347.393006 -328.452734) (xy 347.393006 -329.821794) (xy 347.838522 -330.26731) (xy 353.87026 -330.26731)
		)
		(stroke
			(width 0)
			(type solid)
		)
		(fill yes)
		(layer "F.Cu")
		(net "IND_CPU1_P0_CPL6")
	)
	(gr_poly
		(pts
			(xy 358.327198 -178.38039) (xy 358.327198 -177.026062) (xy 358.210358 -176.909222) (xy 352.590862 -176.909222)
			(xy 351.855278 -176.173638) (xy 351.855278 -171.220638) (xy 351.38995 -170.75531) (xy 345.378278 -170.75531)
			(xy 345.270074 -170.863514) (xy 345.270074 -172.199554) (xy 345.388692 -172.318172) (xy 349.98914 -172.318172)
			(xy 350.585278 -172.91431) (xy 350.585278 -177.697638) (xy 351.38995 -178.50231) (xy 358.205278 -178.50231)
		)
		(stroke
			(width 0)
			(type solid)
		)
		(fill yes)
		(layer "F.Cu")
		(net "IND_CPU0_P0_CPL6")
	)
	(gr_poly
		(pts
			(xy 366.826038 -186.51855) (xy 366.826038 -185.402982) (xy 366.597438 -185.174382) (xy 360.856022 -185.174382)
			(xy 360.110278 -184.428638) (xy 360.110278 -179.348638) (xy 359.77195 -179.01031) (xy 353.760278 -179.01031)
			(xy 353.506278 -179.26431) (xy 353.506278 -180.53431) (xy 353.633278 -180.66131) (xy 358.332278 -180.66131)
			(xy 358.713278 -181.04231) (xy 358.713278 -185.99531) (xy 359.475278 -186.75731) (xy 366.587278 -186.75731)
		)
		(stroke
			(width 0)
			(type solid)
		)
		(fill yes)
		(layer "F.Cu")
		(net "IND_CPU0_P0_CPL5")
	)
	(gr_poly
		(pts
			(xy 374.969278 -191.583056) (xy 374.969278 -190.256668) (xy 374.858534 -190.145924) (xy 369.002564 -190.145924)
			(xy 368.492278 -189.635638) (xy 368.492278 -187.730638) (xy 368.02695 -187.26531) (xy 362.015278 -187.26531)
			(xy 361.761278 -187.51931) (xy 361.761278 -188.78931) (xy 361.888278 -188.91631) (xy 366.460278 -188.91631)
			(xy 366.968278 -189.42431) (xy 366.968278 -191.32931) (xy 367.476278 -191.83731) (xy 374.715024 -191.83731)
		)
		(stroke
			(width 0)
			(type solid)
		)
		(fill yes)
		(layer "F.Cu")
		(net "IND_CPU0_P0_CPL1")
	)
	(gr_poly
		(pts
			(xy 386.621274 -193.468752) (xy 386.621274 -192.198752) (xy 386.926074 -191.893952) (xy 391.438892 -191.893952)
			(xy 391.631678 -191.701166) (xy 391.631678 -190.179452) (xy 391.595864 -190.143638) (xy 384.392678 -190.143638)
			(xy 384.068574 -190.467742) (xy 384.068574 -191.779652) (xy 383.494788 -192.353438) (xy 378.830078 -192.353438)
			(xy 378.671074 -192.512442) (xy 378.671074 -193.798952) (xy 378.823474 -193.951352) (xy 386.138674 -193.951352)
		)
		(stroke
			(width 0)
			(type solid)
		)
		(fill yes)
		(layer "F.Cu")
		(net "IND_CPU0_P0_CPL3")
	)
	(gr_poly
		(pts
			(xy 411.799278 -177.189638) (xy 411.799278 -175.45431) (xy 412.281878 -174.97171) (xy 417.057078 -174.97171)
			(xy 417.107878 -174.92091) (xy 417.107878 -173.54931) (xy 417.006278 -173.44771) (xy 411.138878 -173.44771)
			(xy 410.402278 -174.18431) (xy 410.402278 -175.792638) (xy 410.156406 -176.03851) (xy 404.103078 -176.03851)
			(xy 404.052278 -176.08931) (xy 404.052278 -177.48631) (xy 404.179278 -177.61331) (xy 411.375606 -177.61331)
		)
		(stroke
			(width 0)
			(type solid)
		)
		(fill yes)
		(layer "F.Cu")
		(net "IND_SOC_P0_CPL3")
	)
	(gr_poly
		(pts
			(xy 429.376078 -429.950372) (xy 429.376078 -429.239172) (xy 429.477678 -429.137572) (xy 429.782478 -429.137572)
			(xy 429.858678 -429.061372) (xy 429.858678 -427.588172) (xy 429.731678 -427.461172) (xy 428.207678 -427.461172)
			(xy 428.182278 -427.486572) (xy 428.182278 -429.061372) (xy 428.258478 -429.137572) (xy 429.045878 -429.137572)
			(xy 429.172878 -429.264572) (xy 429.172878 -429.950372) (xy 429.198278 -429.975772) (xy 429.350678 -429.975772)
		)
		(stroke
			(width 0)
			(type solid)
		)
		(fill yes)
		(layer "F.Cu")
		(net "GND")
	)
	(gr_poly
		(pts
			(xy 439.980324 -16.65859) (xy 439.980324 -15.127224) (xy 440.25312 -14.854428) (xy 440.25312 -14.37386)
			(xy 440.251088 -14.371828) (xy 440.251088 -13.486638) (xy 440.159394 -13.394944) (xy 439.8264 -13.394944)
			(xy 439.625232 -13.596112) (xy 439.217308 -13.596112) (xy 438.355486 -13.596112) (xy 438.263538 -13.68806)
			(xy 438.263538 -14.549882) (xy 438.263538 -16.589502) (xy 438.403746 -16.72971) (xy 439.909204 -16.72971)
		)
		(stroke
			(width 0)
			(type solid)
		)
		(fill yes)
		(layer "F.Cu")
		(net "GND")
	)
	(gr_poly
		(pts
			(xy 443.730634 -79.54264) (xy 443.730634 -78.850744) (xy 443.730634 -77.46619) (xy 443.730634 -76.493878)
			(xy 443.730634 -72.32777) (xy 443.679834 -72.27697) (xy 440.530234 -72.27697) (xy 440.479434 -72.32777)
			(xy 440.479434 -73.819766) (xy 440.25312 -74.04608) (xy 439.36412 -74.04608) (xy 438.99582 -74.41438)
			(xy 438.99582 -78.60792) (xy 440.18835 -79.80045) (xy 441.96254 -79.80045) (xy 443.472824 -79.80045)
		)
		(stroke
			(width 0)
			(type solid)
		)
		(fill yes)
		(layer "F.Cu")
		(net "P3V3")
	)
	(gr_poly
		(pts
			(xy 76.366878 -186.573668) (xy 76.366878 -185.106056) (xy 76.281534 -185.020712) (xy 70.977506 -185.020712)
			(xy 69.635878 -183.679084) (xy 69.635878 -179.234084) (xy 68.92544 -178.523646) (xy 63.478664 -178.523646)
			(xy 63.285878 -178.716432) (xy 63.285878 -179.996084) (xy 63.363856 -180.074062) (xy 67.879468 -180.074062)
			(xy 67.923918 -180.074062) (xy 68.365116 -180.51526) (xy 68.365116 -185.524648) (xy 69.464936 -186.624468)
			(xy 76.316078 -186.624468)
		)
		(stroke
			(width 0)
			(type solid)
		)
		(fill yes)
		(layer "F.Cu")
		(net "IND_CPU0_P1_CPL6")
	)
	(gr_poly
		(pts
			(xy 120.689878 -180.377084) (xy 120.825514 -180.241448) (xy 120.825514 -176.880774) (xy 121.318274 -176.388014)
			(xy 126.601474 -176.388014) (xy 126.811278 -176.17821) (xy 126.811278 -174.95901) (xy 126.59868 -174.746412)
			(xy 121.181876 -174.746412) (xy 119.419878 -176.50841) (xy 119.419878 -178.585622) (xy 118.70182 -179.30368)
			(xy 113.508282 -179.30368) (xy 113.323878 -179.488084) (xy 113.323878 -180.758084) (xy 113.577878 -181.012084)
			(xy 120.054878 -181.012084)
		)
		(stroke
			(width 0)
			(type solid)
		)
		(fill yes)
		(layer "F.Cu")
		(net "IND_SOC_P1_CPL2")
	)
	(gr_poly
		(pts
			(xy 246.716042 -40.766746) (xy 247.340374 -40.142414) (xy 247.825006 -40.142414) (xy 249.467878 -40.142414)
			(xy 249.547126 -40.063166) (xy 249.547126 -38.336982) (xy 249.19178 -37.981636) (xy 247.798844 -37.981636)
			(xy 242.922044 -37.981636) (xy 242.905534 -37.998146) (xy 242.626134 -38.277546) (xy 242.626134 -41.452546)
			(xy 242.626134 -41.590468) (xy 242.78336 -41.747694) (xy 244.330728 -41.747694) (xy 244.717824 -42.13479)
			(xy 245.347998 -42.13479)
		)
		(stroke
			(width 0)
			(type solid)
		)
		(fill yes)
		(layer "F.Cu")
		(net "GND")
	)
	(gr_poly
		(pts
			(xy 264.81786 -436.040276) (xy 264.81786 -426.975524) (xy 264.81786 -422.2369) (xy 264.5029 -421.92194)
			(xy 264.5029 -420.22268) (xy 264.370312 -420.090092) (xy 257.334766 -420.090092) (xy 255.937258 -420.090092)
			(xy 244.275102 -420.090092) (xy 242.827048 -420.090092) (xy 242.47348 -420.44366) (xy 242.47348 -421.891714)
			(xy 242.47348 -424.927268) (xy 242.47348 -435.884828) (xy 243.039646 -436.450994) (xy 243.151406 -436.562754)
			(xy 264.295382 -436.562754)
		)
		(stroke
			(width 0)
			(type solid)
		)
		(fill yes)
		(layer "F.Cu")
		(net "GND")
	)
	(gr_poly
		(pts
			(xy 324.0024 -327.118726) (xy 324.0024 -325.848726) (xy 324.3072 -325.543926) (xy 329.1332 -325.543926)
			(xy 329.3364 -325.340726) (xy 329.3364 -323.969126) (xy 329.162664 -323.79539) (xy 321.686936 -323.79539)
			(xy 321.4497 -324.032626) (xy 321.4497 -325.429626) (xy 321.0814 -325.797926) (xy 320.91122 -325.968106)
			(xy 316.24905 -325.968106) (xy 316.0522 -326.164956) (xy 316.0522 -327.448926) (xy 316.1411 -327.537826)
			(xy 323.5833 -327.537826)
		)
		(stroke
			(width 0)
			(type solid)
		)
		(fill yes)
		(layer "F.Cu")
		(net "IND_CPU1_P0_CPL2")
	)
	(gr_poly
		(pts
			(xy 345.117674 -361.144312) (xy 345.425522 -360.836464)
			(arc
				(start 345.425522 -357.429562)
				(mid 345.42163 -357.410467)
				(end 345.41079 -357.394256)
			)
			(xy 345.18346 -357.166926) (xy 337.104736 -357.166926) (xy 335.95564 -357.166926) (xy 335.54924 -357.166926)
			(xy 335.419446 -357.29672) (xy 335.419446 -361.12704) (xy 335.610708 -361.318302) (xy 335.951068 -361.318302)
			(xy 337.938872 -361.318302) (xy 343.925398 -361.318302) (xy 344.943684 -361.318302)
		)
		(stroke
			(width 0)
			(type solid)
		)
		(fill yes)
		(layer "F.Cu")
		(net "P12V_AUX")
	)
	(gr_poly
		(pts
			(xy 378.127514 -193.511424) (xy 378.127514 -192.241424) (xy 378.480828 -191.88811) (xy 383.173478 -191.88811)
			(xy 383.461514 -191.600074) (xy 383.461514 -190.361824) (xy 383.258314 -190.158624) (xy 377.238514 -190.158624)
			(xy 375.841514 -190.158624) (xy 375.574814 -190.425324) (xy 375.574814 -191.822324) (xy 375.051828 -192.34531)
			(xy 370.270278 -192.34531) (xy 370.177314 -192.438274) (xy 370.177314 -193.852546) (xy 370.259864 -193.935096)
			(xy 377.703842 -193.935096)
		)
		(stroke
			(width 0)
			(type solid)
		)
		(fill yes)
		(layer "F.Cu")
		(net "IND_CPU0_P0_CPL2")
	)
	(gr_poly
		(pts
			(xy 457.095352 -394.519658) (xy 457.095352 -391.790682) (xy 456.673204 -391.368534) (xy 451.92442 -391.368534)
			(xy 451.784466 -391.508488) (xy 451.784466 -393.77112) (xy 451.558152 -393.997434) (xy 450.669152 -393.997434)
			(xy 450.592952 -393.997434) (xy 450.542152 -394.048234) (xy 450.542152 -394.581634) (xy 450.607176 -394.646658)
			(xy 450.657976 -394.646658) (xy 451.866254 -394.646658) (xy 452.044054 -394.646658) (xy 456.377802 -394.646658)
			(xy 456.968352 -394.646658)
		)
		(stroke
			(width 0)
			(type solid)
		)
		(fill yes)
		(layer "F.Cu")
		(net "SW_P0V9_RETIMER_CPU0_SW2")
	)
	(gr_poly
		(pts
			(xy 13.095478 -408.596084) (xy 13.095478 -408.571192) (xy 13.095478 -408.30246) (xy 13.093192 -408.300174)
			(xy 13.093192 -407.287984) (xy 13.093192 -405.869394) (xy 12.987782 -405.763984) (xy 11.336782 -405.763984)
			(xy 11.285982 -405.814784) (xy 11.285982 -406.31491) (xy 11.852656 -406.881584) (xy 11.971782 -406.881584)
			(xy 12.352782 -407.262584) (xy 12.352782 -408.481784) (xy 12.470892 -408.599894) (xy 12.470892 -408.600656)
			(xy 12.473686 -408.60345) (xy 13.088112 -408.60345)
		)
		(stroke
			(width 0)
			(type solid)
		)
		(fill yes)
		(layer "F.Cu")
		(net "PV09_RETIMER_CPU1_VCCS")
	)
	(gr_poly
		(pts
			(xy 64.940942 -20.576794) (xy 64.940942 -16.687038) (xy 65.067434 -16.560546) (xy 65.248536 -16.379444)
			(xy 65.248536 -13.664946) (xy 65.196974 -13.613384) (xy 65.03289 -13.613384) (xy 64.252094 -13.613384)
			(xy 64.004698 -13.86078) (xy 64.004698 -16.27378) (xy 63.590932 -16.687546) (xy 63.590932 -17.549114)
			(xy 63.241936 -17.89811) (xy 62.386464 -17.89811) (xy 62.157864 -18.12671) (xy 62.157864 -20.23491)
			(xy 62.716664 -20.79371) (xy 64.724026 -20.79371)
		)
		(stroke
			(width 0)
			(type solid)
		)
		(fill yes)
		(layer "F.Cu")
		(net "GND")
	)
	(gr_poly
		(pts
			(xy 69.4944 -34.174684) (xy 69.4944 -32.066484) (xy 69.3674 -31.939484) (xy 68.781422 -31.939484)
			(xy 68.654422 -32.066484) (xy 68.654422 -32.625284) (xy 68.375022 -32.904684) (xy 66.876422 -32.904684)
			(xy 66.724022 -32.752284) (xy 66.724022 -32.117284) (xy 66.647822 -32.041084) (xy 64.082422 -32.041084)
			(xy 63.315342 -32.041084) (xy 63.228982 -32.127444) (xy 63.228982 -34.210244) (xy 63.371222 -34.352484)
			(xy 64.260222 -34.352484) (xy 69.3166 -34.352484)
		)
		(stroke
			(width 0)
			(type solid)
		)
		(fill yes)
		(layer "F.Cu")
		(net "GND")
	)
	(gr_poly
		(pts
			(xy 167.830246 -352.097086) (xy 167.830246 -351.501456) (xy 167.676068 -351.347278) (xy 167.41013 -351.347278)
			(xy 166.06393 -351.347278) (xy 165.91153 -351.194878) (xy 165.91153 -350.585278) (xy 165.194234 -349.867982)
			(xy 164.342064 -349.867982) (xy 164.329364 -349.880682) (xy 164.329364 -350.005142) (xy 164.344604 -350.020382)
			(xy 165.050724 -350.020382) (xy 165.203124 -350.172782) (xy 165.203124 -351.97034) (xy 165.367462 -352.134678)
			(xy 167.51173 -352.134678) (xy 167.792654 -352.134678)
		)
		(stroke
			(width 0)
			(type solid)
		)
		(fill yes)
		(layer "F.Cu")
		(net "PVDD11_S3_P1_VCC")
	)
	(gr_poly
		(pts
			(xy 203.124054 -346.851732) (xy 203.124054 -344.260932) (xy 201.313034 -342.449658) (xy 201.313034 -338.02955)
			(xy 201.508614 -337.83397) (xy 201.508614 -337.229958) (xy 201.447146 -337.16849) (xy 201.040746 -337.16849)
			(xy 200.981056 -337.22818) (xy 200.981056 -339.639148) (xy 200.981056 -340.67623) (xy 200.437242 -341.220044)
			(xy 200.437242 -341.22233) (xy 200.255378 -341.404194) (xy 200.255378 -346.817696) (xy 200.373234 -346.935552)
			(xy 202.34783 -346.935552) (xy 203.040234 -346.935552)
		)
		(stroke
			(width 0)
			(type solid)
		)
		(fill yes)
		(layer "F.Cu")
		(net "SW_P12V_AUX_PVDD_33_S5_FLT")
	)
	(gr_poly
		(pts
			(xy 425.736258 -174.421292) (xy 425.736258 -171.297092) (xy 425.609004 -171.169838) (xy 424.634406 -171.169838)
			(xy 412.50235 -171.169838) (xy 412.459678 -171.21251) (xy 412.459678 -172.68571) (xy 412.586678 -172.81271)
			(xy 412.66618 -172.892212) (xy 417.314126 -172.892212) (xy 417.348162 -172.926248) (xy 417.793678 -173.37151)
			(xy 417.793678 -173.981872) (xy 418.103558 -174.291752) (xy 419.889686 -174.291752) (xy 420.144956 -174.547022)
			(xy 424.815508 -174.547022) (xy 425.610528 -174.547022)
		)
		(stroke
			(width 0)
			(type solid)
		)
		(fill yes)
		(layer "F.Cu")
		(net "IND_SOC_P0_CPL0")
	)
	(gr_poly
		(pts
			(xy 444.25108 -34.4678) (xy 444.25108 -32.395922) (xy 444.151258 -32.2961) (xy 443.525656 -32.2961)
			(xy 443.327536 -32.49422) (xy 443.327536 -32.921702) (xy 443.048136 -33.201102) (xy 441.549536 -33.201102)
			(xy 441.397136 -33.048702) (xy 441.397136 -32.413702) (xy 441.320936 -32.337502) (xy 438.755536 -32.337502)
			(xy 437.988456 -32.337502) (xy 437.902096 -32.423862) (xy 437.902096 -34.506662) (xy 438.044336 -34.648902)
			(xy 438.933336 -34.648902) (xy 444.069978 -34.648902)
		)
		(stroke
			(width 0)
			(type solid)
		)
		(fill yes)
		(layer "F.Cu")
		(net "GND")
	)
	(gr_poly
		(pts
			(xy 448.224402 -428.41291) (xy 448.224402 -427.60011) (xy 447.970402 -427.34611) (xy 447.538602 -427.34611)
			(xy 447.157602 -426.96511) (xy 447.157602 -425.74591) (xy 447.039492 -425.6278) (xy 447.039492 -425.627038)
			(xy 447.036698 -425.624244) (xy 446.422272 -425.624244) (xy 446.414906 -425.63161) (xy 446.414906 -425.656502)
			(xy 446.414906 -425.925234) (xy 446.417192 -425.92752) (xy 446.417192 -426.93971) (xy 446.417192 -428.3583)
			(xy 446.522602 -428.46371) (xy 448.173602 -428.46371)
		)
		(stroke
			(width 0)
			(type solid)
		)
		(fill yes)
		(layer "F.Cu")
		(net "PV09_RETIMER_CPU0_VCCS")
	)
	(gr_poly
		(pts
			(xy 464.05546 -73.137014) (xy 464.05546 -72.312276) (xy 464.05546 -66.264028) (xy 463.864198 -66.072766)
			(xy 446.670176 -66.072766) (xy 439.207402 -66.072766) (xy 438.559702 -66.720466) (xy 438.559702 -71.139812)
			(xy 439.218324 -71.798434) (xy 443.95644 -71.798434) (xy 444.620396 -72.46239) (xy 444.620396 -73.206102)
			(xy 444.746888 -73.332594) (xy 445.4906 -73.332594) (xy 446.271396 -73.332594) (xy 446.652396 -73.713594)
			(xy 457.855574 -73.713594) (xy 463.47888 -73.713594)
		)
		(stroke
			(width 0)
			(type solid)
		)
		(fill yes)
		(layer "F.Cu")
		(net "P3V3_AUX")
	)
	(gr_poly
		(pts
			(xy 20.242784 -386.122926) (xy 20.242784 -383.141728) (xy 20.060666 -382.95961) (xy 15.174214 -382.95961)
			(xy 14.88567 -383.248154) (xy 14.88567 -384.84429) (xy 14.88567 -385.07289) (xy 14.37767 -385.58089)
			(xy 14.14907 -385.58089) (xy 12.98067 -385.58089) (xy 12.92987 -385.58089) (xy 12.87907 -385.63169)
			(xy 12.87907 -386.21589) (xy 12.918694 -386.255514) (xy 13.020294 -386.255514) (xy 14.406372 -386.255514)
			(xy 14.77645 -386.255514) (xy 19.110198 -386.255514) (xy 20.110196 -386.255514)
		)
		(stroke
			(width 0)
			(type solid)
		)
		(fill yes)
		(layer "F.Cu")
		(net "SW_P0V9_RETIMER_CPU1_SW1")
	)
	(gr_poly
		(pts
			(xy 129.832354 -172.993812) (xy 129.832354 -168.077134) (xy 130.224276 -167.685212) (xy 134.785354 -167.685212)
			(xy 134.886954 -167.583612) (xy 134.886954 -166.280084) (xy 134.82828 -166.22141) (xy 129.097278 -166.22141)
			(xy 128.852676 -166.22141) (xy 128.564894 -166.509192) (xy 128.564894 -168.832784) (xy 128.055878 -169.3418)
			(xy 128.055878 -171.614084) (xy 127.00635 -172.663612) (xy 121.994676 -172.663612) (xy 121.832878 -172.82541)
			(xy 121.832878 -174.09541) (xy 121.959878 -174.22241) (xy 128.603756 -174.22241)
		)
		(stroke
			(width 0)
			(type solid)
		)
		(fill yes)
		(layer "F.Cu")
		(net "IND_SOC_P1_CPL3")
	)
	(gr_poly
		(pts
			(xy 276.7203 -392.16076) (xy 276.7203 -391.5283) (xy 276.80412 -391.44448) (xy 277.57374 -391.44448)
			(xy 277.6601 -391.53084) (xy 277.6601 -392.1506) (xy 277.74646 -392.23696) (xy 279.672034 -392.23696)
			(xy 280.36393 -392.23696) (xy 280.393394 -392.207496) (xy 280.5938 -392.00709) (xy 280.5938 -391.315194)
			(xy 280.5938 -384.4036) (xy 280.07056 -383.88036) (xy 275.005292 -383.88036) (xy 274.751292 -384.13436)
			(xy 274.751292 -392.18616) (xy 274.802092 -392.23696) (xy 276.6441 -392.23696)
		)
		(stroke
			(width 0)
			(type solid)
		)
		(fill yes)
		(layer "F.Cu")
		(net "P12V_MAIN_R_0")
	)
	(gr_poly
		(pts
			(xy 448.746372 -394.50137) (xy 448.746372 -391.494772) (xy 448.622928 -391.371328) (xy 443.653926 -391.371328)
			(xy 443.455552 -391.569702) (xy 443.455552 -393.235434) (xy 443.455552 -393.464034) (xy 442.947552 -393.972034)
			(xy 442.718952 -393.972034) (xy 441.550552 -393.972034) (xy 441.499752 -393.972034) (xy 441.448952 -394.022834)
			(xy 441.448952 -394.607034) (xy 441.488576 -394.646658) (xy 441.590176 -394.646658) (xy 442.976254 -394.646658)
			(xy 443.346332 -394.646658) (xy 447.68008 -394.646658) (xy 448.601084 -394.646658)
		)
		(stroke
			(width 0)
			(type solid)
		)
		(fill yes)
		(layer "F.Cu")
		(net "SW_P0V9_RETIMER_CPU0_SW1")
	)
	(gr_poly
		(pts
			(xy 30.471872 -381.35814) (xy 30.471872 -374.389142) (xy 30.022546 -373.939816) (xy 28.255214 -373.939816)
			(xy 27.817318 -373.50192) (xy 8.35787 -373.50192) (xy 7.51586 -373.50192) (xy 6.094222 -373.50192)
			(xy 5.802884 -373.793258) (xy 5.802884 -379.607318) (xy 6.043168 -379.847602) (xy 8.38962 -379.847602)
			(xy 9.10717 -379.847602) (xy 9.283446 -380.023878) (xy 9.283446 -380.636018) (xy 9.283446 -380.833122)
			(xy 9.526524 -381.0762) (xy 13.752322 -381.0762) (xy 14.409928 -381.733806) (xy 30.096206 -381.733806)
		)
		(stroke
			(width 0)
			(type solid)
		)
		(fill yes)
		(layer "F.Cu")
		(net "P0V9_CPU1_RT_2D")
	)
	(gr_poly
		(pts
			(xy 85.586062 -13.649452) (xy 85.534246 -13.597636) (xy 81.339182 -13.597636) (xy 81.242662 -13.694156)
			(xy 81.242662 -15.901924) (xy 81.743042 -16.402304) (xy 83.839304 -16.402304) (xy 84.316062 -16.879062)
			(xy 84.316062 -18.975324) (xy 84.316062 -24.512524) (xy 82.774536 -26.05405) (xy 80.674464 -26.05405)
			(xy 80.302862 -26.425652) (xy 80.302862 -28.525724) (xy 78.829662 -29.998924) (xy 73.140062 -29.998924)
			(xy 73.114662 -30.024324) (xy 73.114662 -33.554924) (xy 73.622662 -34.062924) (xy 85.586062 -34.062924)
		)
		(stroke
			(width 0)
			(type solid)
		)
		(fill yes)
		(layer "F.Cu")
		(net "GND")
	)
	(gr_poly
		(pts
			(xy 189.847982 -26.445464) (xy 189.847982 -24.59101) (xy 189.889384 -24.549608) (xy 190.480188 -24.549608)
			(xy 190.628778 -24.698198) (xy 190.628778 -25.945846) (xy 190.692532 -26.0096) (xy 190.781432 -26.0096)
			(xy 190.86195 -25.929082) (xy 190.86195 -21.508212) (xy 191.109092 -21.26107) (xy 191.109092 -19.253454)
			(xy 191.049148 -19.19351) (xy 188.63437 -19.19351) (xy 188.549026 -19.278854) (xy 188.549026 -21.425154)
			(xy 189.628018 -22.504146) (xy 189.628018 -26.44267) (xy 189.69482 -26.509472) (xy 189.783974 -26.509472)
		)
		(stroke
			(width 0)
			(type solid)
		)
		(fill yes)
		(layer "F.Cu")
		(net "P12V_SCM_R")
	)
	(gr_poly
		(pts
			(xy 286.308546 -339.161628) (xy 286.308546 -337.917028) (xy 286.308546 -337.688428) (xy 286.130746 -337.510628)
			(xy 281.279346 -337.510628) (xy 281.050746 -337.282028) (xy 280.911046 -337.142328) (xy 280.911046 -335.745328)
			(xy 280.70683 -335.541112) (xy 273.165062 -335.541112) (xy 273.024346 -335.681828) (xy 273.024346 -336.723228)
			(xy 273.024346 -337.053428) (xy 273.227546 -337.256628) (xy 278.053546 -337.256628) (xy 278.358346 -337.561428)
			(xy 278.358346 -338.831428) (xy 278.840946 -339.314028) (xy 280.872946 -339.314028) (xy 286.156146 -339.314028)
		)
		(stroke
			(width 0)
			(type solid)
		)
		(fill yes)
		(layer "F.Cu")
		(net "IND_PVDDIO_P0_CPL4")
	)
	(gr_poly
		(pts
			(xy 294.588946 -339.161628) (xy 294.588946 -337.917028) (xy 294.588946 -337.688428) (xy 294.411146 -337.510628)
			(xy 289.559746 -337.510628) (xy 289.331146 -337.282028) (xy 289.191446 -337.142328) (xy 289.191446 -335.745328)
			(xy 288.984944 -335.538572) (xy 281.448002 -335.538572) (xy 281.304746 -335.681828) (xy 281.304746 -336.723228)
			(xy 281.304746 -337.053428) (xy 281.507946 -337.256628) (xy 286.333946 -337.256628) (xy 286.638746 -337.561428)
			(xy 286.638746 -338.831428) (xy 287.121346 -339.314028) (xy 289.153346 -339.314028) (xy 294.436546 -339.314028)
		)
		(stroke
			(width 0)
			(type solid)
		)
		(fill yes)
		(layer "F.Cu")
		(net "IND_PVDDIO_P0_CPL3")
	)
	(gr_poly
		(pts
			(xy 302.945546 -339.161628) (xy 302.945546 -337.917028) (xy 302.945546 -337.688428) (xy 302.767746 -337.510628)
			(xy 297.916346 -337.510628) (xy 297.687746 -337.282028) (xy 297.548046 -337.142328) (xy 297.548046 -335.745328)
			(xy 297.34129 -335.538572) (xy 289.804602 -335.538572) (xy 289.661346 -335.681828) (xy 289.661346 -336.723228)
			(xy 289.661346 -337.053428) (xy 289.864546 -337.256628) (xy 294.690546 -337.256628) (xy 294.995346 -337.561428)
			(xy 294.995346 -338.831428) (xy 295.477946 -339.314028) (xy 297.509946 -339.314028) (xy 302.793146 -339.314028)
		)
		(stroke
			(width 0)
			(type solid)
		)
		(fill yes)
		(layer "F.Cu")
		(net "IND_PVDDIO_P0_CPL2")
	)
	(gr_poly
		(pts
			(xy 402.54555 -186.287664) (xy 402.574506 -186.287664) (xy 403.535134 -185.327036) (xy 403.535134 -180.746654)
			(xy 404.514558 -179.76723) (xy 408.730958 -179.76723) (xy 408.776678 -179.72151) (xy 408.776678 -178.27371)
			(xy 408.717242 -178.214274) (xy 403.357842 -178.214274) (xy 402.680678 -178.891438) (xy 402.680678 -180.514244)
			(xy 402.061934 -181.132988) (xy 402.061934 -183.616854) (xy 401.120102 -184.558686) (xy 395.560296 -184.558686)
			(xy 395.361414 -184.757568) (xy 395.361414 -186.17946) (xy 395.47165 -186.289696) (xy 402.543518 -186.289696)
		)
		(stroke
			(width 0)
			(type solid)
		)
		(fill yes)
		(layer "F.Cu")
		(net "IND_SOC_P0_CPL2")
	)
	(gr_poly
		(pts
			(xy 424.519598 -365.631222) (xy 424.519598 -365.035592) (xy 424.36542 -364.881414) (xy 424.099482 -364.881414)
			(xy 422.753282 -364.881414) (xy 422.600882 -364.729014) (xy 422.600882 -364.333536) (xy 422.187878 -363.920532)
			(xy 422.187878 -363.706156) (xy 421.889682 -363.408214) (xy 421.02786 -363.408214) (xy 421.0177 -363.418374)
			(xy 421.0177 -363.545374) (xy 421.032178 -363.559852) (xy 421.730678 -363.559852) (xy 421.898318 -363.727492)
			(xy 421.898318 -365.510318) (xy 422.056814 -365.668814) (xy 424.201082 -365.668814) (xy 424.482006 -365.668814)
		)
		(stroke
			(width 0)
			(type solid)
		)
		(fill yes)
		(layer "F.Cu")
		(net "PVDD11_S3_P0_VCC")
	)
	(gr_poly
		(pts
			(arc
				(start 2.815844 -344.982546)
				(mid 2.909477 -344.736335)
				(end 3.01117 -344.493342)
			)
			(arc
				(start 3.01117 -344.493342)
				(mid 3.014394 -344.483407)
				(end 3.015488 -344.473022)
			)
			(arc
				(start 3.015488 -163.729416)
				(mid 3.014364 -163.719038)
				(end 3.01117 -163.709096)
			)
			(arc
				(start 3.01117 -163.709096)
				(mid 2.88649 -163.407726)
				(end 2.774188 -163.101528)
			)
			(xy 2.668524 -162.995864) (xy 2.553716 -162.995864) (xy 2.507996 -163.041584) (xy 2.507996 -345.034362)
			(xy 2.576576 -345.102942) (xy 2.695448 -345.102942)
		)
		(stroke
			(width 0)
			(type solid)
		)
		(fill yes)
		(layer "F.Cu")
		(net "GND")
	)
	(gr_poly
		(pts
			(xy 28.52547 -386.128514) (xy 28.52547 -384.204464) (xy 28.52547 -383.672588) (xy 28.52547 -383.269236)
			(xy 28.215844 -382.95961) (xy 27.812492 -382.95961) (xy 27.280616 -382.95961) (xy 23.2791 -382.95961)
			(xy 23.214584 -383.024126) (xy 23.214584 -385.379976) (xy 22.98827 -385.60629) (xy 22.09927 -385.60629)
			(xy 22.02307 -385.60629) (xy 21.97227 -385.65709) (xy 21.97227 -386.19049) (xy 22.037294 -386.255514)
			(xy 22.088094 -386.255514) (xy 23.296372 -386.255514) (xy 23.474172 -386.255514) (xy 27.80792 -386.255514)
			(xy 28.39847 -386.255514)
		)
		(stroke
			(width 0)
			(type solid)
		)
		(fill yes)
		(layer "F.Cu")
		(net "SW_P0V9_RETIMER_CPU1_SW2")
	)
	(gr_poly
		(pts
			(xy 87.700612 -193.574416) (xy 87.700612 -192.19926) (xy 87.808816 -192.091056) (xy 88.092788 -191.807084)
			(xy 88.196928 -191.702944) (xy 92.854018 -191.702944) (xy 93.003878 -191.553084) (xy 93.003878 -190.156084)
			(xy 92.876878 -190.029084) (xy 85.34527 -190.029084) (xy 85.217508 -190.156846) (xy 85.217508 -191.77762)
			(xy 85.177884 -191.817244) (xy 84.765388 -192.22974) (xy 84.727542 -192.267586) (xy 80.094074 -192.267586)
			(xy 80.05318 -192.30848) (xy 79.922878 -192.438782) (xy 79.922878 -193.78676) (xy 80.01762 -193.881756)
			(xy 87.393272 -193.881756)
		)
		(stroke
			(width 0)
			(type solid)
		)
		(fill yes)
		(layer "F.Cu")
		(net "IND_CPU0_P1_CPL1")
	)
	(gr_poly
		(pts
			(xy 96.049338 -193.599562) (xy 96.049338 -192.349374) (xy 96.221296 -192.177416) (xy 96.602296 -191.796416)
			(xy 96.704912 -191.6938) (xy 101.160834 -191.6938) (xy 101.360478 -191.494156) (xy 101.360478 -190.095632)
			(xy 101.322378 -190.057278) (xy 93.603826 -190.057278) (xy 93.514926 -190.146178) (xy 93.514926 -191.766952)
			(xy 93.475302 -191.806576) (xy 93.062806 -192.219072) (xy 93.02496 -192.256918) (xy 88.391492 -192.256918)
			(xy 88.350598 -192.297812) (xy 88.220296 -192.428114) (xy 88.220296 -193.776092) (xy 88.315038 -193.871088)
			(xy 95.777812 -193.871088)
		)
		(stroke
			(width 0)
			(type solid)
		)
		(fill yes)
		(layer "F.Cu")
		(net "IND_CPU0_P1_CPL2")
	)
	(gr_poly
		(pts
			(arc
				(start 107.75823 -411.256988)
				(mid 107.777587 -411.253155)
				(end 107.794044 -411.242256)
			)
			(arc
				(start 107.856528 -411.179772)
				(mid 107.867454 -411.163326)
				(end 107.87126 -411.143958)
			)
			(arc
				(start 107.87126 -408.044142)
				(mid 107.867427 -408.024785)
				(end 107.856528 -408.008328)
			)
			(xy 107.855512 -408.007312)
			(arc
				(start 104.672384 -408.007312)
				(mid 104.636463 -408.022191)
				(end 104.621584 -408.058112)
			)
			(xy 104.621584 -411.250384) (xy 104.628188 -411.256988)
		)
		(stroke
			(width 0)
			(type solid)
		)
		(fill yes)
		(layer "F.Cu")
		(net "GND")
	)
	(gr_poly
		(pts
			(xy 200.706736 -340.36127) (xy 200.706736 -336.9691) (xy 200.989946 -336.68589) (xy 202.691746 -336.68589)
			(xy 204.35189 -336.68589) (xy 204.47 -336.804) (xy 204.47 -337.185) (xy 204.597 -337.312) (xy 205.105 -337.312)
			(xy 205.232 -337.185) (xy 205.232 -334.645) (xy 205.002892 -334.415892) (xy 203.347574 -334.415892)
			(xy 199.197214 -334.415892) (xy 199.073516 -334.53959) (xy 199.073516 -337.345274) (xy 199.603614 -337.875372)
			(xy 200.401428 -338.67344) (xy 200.401428 -340.36381) (xy 200.42759 -340.389972) (xy 200.678034 -340.389972)
		)
		(stroke
			(width 0)
			(type solid)
		)
		(fill yes)
		(layer "F.Cu")
		(net "SW_PVDD_33_S5_SW")
	)
	(gr_poly
		(pts
			(xy 415.391092 -148.159724) (xy 415.623502 -147.927314) (xy 415.623502 -145.070576) (xy 413.778192 -143.225266)
			(xy 413.778192 -141.089634) (xy 413.73679 -141.048232) (xy 413.43072 -141.048232) (xy 413.397192 -141.08176)
			(xy 413.397192 -142.053056) (xy 413.397192 -144.489424) (xy 413.134302 -144.752314) (xy 412.067502 -144.752314)
			(xy 411.432502 -144.752314) (xy 411.280102 -144.599914) (xy 411.280102 -144.091914) (xy 411.186884 -143.998696)
			(xy 410.63164 -143.998696) (xy 410.3878 -144.242536) (xy 410.3878 -147.847812) (xy 410.797502 -148.257514)
			(xy 415.293302 -148.257514)
		)
		(stroke
			(width 0)
			(type solid)
		)
		(fill yes)
		(layer "F.Cu")
		(net "SW_P5V_AUX_SW")
	)
	(gr_poly
		(pts
			(xy 245.238778 -300.045882) (xy 245.238778 -299.531532) (xy 245.238778 -295.158414) (xy 244.317012 -294.236648)
			(xy 243.823998 -293.743634) (xy 243.823998 -292.053264) (xy 243.797836 -292.027102) (xy 243.547392 -292.027102)
			(xy 243.51869 -292.055804) (xy 243.51869 -295.326562) (xy 243.3955 -295.449752) (xy 239.763046 -295.449752)
			(xy 239.707928 -295.394634) (xy 239.707928 -295.238932) (xy 239.657128 -295.188132) (xy 239.066578 -295.188132)
			(xy 238.990378 -295.264332) (xy 238.990378 -299.429932) (xy 238.993172 -299.432472) (xy 238.993172 -299.959014)
			(xy 239.258094 -300.223936) (xy 245.060724 -300.223936)
		)
		(stroke
			(width 0)
			(type solid)
		)
		(fill yes)
		(layer "F.Cu")
		(net "SW_P1V8_RETIMER_CPU0_SW")
	)
	(gr_poly
		(pts
			(xy 413.143192 -144.210024) (xy 413.143192 -141.799056) (xy 413.143192 -140.761974) (xy 413.687006 -140.21816)
			(xy 413.687006 -140.215874) (xy 413.86887 -140.03401) (xy 413.86887 -131.647946) (xy 413.70504 -131.484116)
			(xy 411.85592 -131.484116) (xy 411.26664 -132.073396) (xy 411.26664 -133.950456) (xy 411.62732 -134.311136)
			(xy 411.62732 -136.360916) (xy 412.393384 -137.12698) (xy 412.393384 -137.924032) (xy 412.71952 -138.249914)
			(xy 412.71952 -138.479276) (xy 412.71952 -143.500348) (xy 412.625286 -143.594582) (xy 412.625286 -144.217898)
			(xy 412.677102 -144.269714) (xy 413.083502 -144.269714)
		)
		(stroke
			(width 0)
			(type solid)
		)
		(fill yes)
		(layer "F.Cu")
		(net "SW_P5V_AUX_FLT")
	)
	(gr_poly
		(pts
			(xy 461.433672 -182.598568)
			(arc
				(start 461.433672 -177.546)
				(mid 461.429771 -177.526477)
				(end 461.418686 -177.509932)
			)
			(arc
				(start 460.678276 -176.769522)
				(mid 460.661742 -176.758411)
				(end 460.642208 -176.754536)
			)
			(xy 453.670924 -176.754536) (xy 452.85152 -177.57394) (xy 452.85152 -179.26304) (xy 453.20712 -179.61864)
			(xy 454.3552 -179.61864) (xy 454.39076 -179.6542) (xy 454.39076 -180.52796) (xy 454.32726 -180.59146)
			(xy 453.1995 -180.59146) (xy 452.85152 -180.93944) (xy 452.85152 -183.04256) (xy 453.04075 -183.23179)
			(xy 460.80045 -183.23179)
		)
		(stroke
			(width 0)
			(type solid)
		)
		(fill yes)
		(layer "F.Cu")
		(net "P12V_AUX")
	)
	(gr_poly
		(pts
			(xy 103.823262 -192.71742) (xy 103.823262 -190.0047) (xy 103.823262 -189.928754) (xy 104.610154 -189.141862)
			(xy 104.610154 -187.598812) (xy 104.973882 -187.235084) (xy 110.141004 -187.235084) (xy 110.402878 -186.97321)
			(xy 110.402878 -185.60161) (xy 110.30458 -185.503312) (xy 104.662478 -185.503312) (xy 103.163878 -187.001912)
			(xy 103.163878 -188.759084) (xy 101.88829 -190.034418) (xy 101.88829 -191.959738) (xy 101.82987 -192.018158)
			(xy 101.573584 -192.274444) (xy 101.39172 -192.274444) (xy 96.854518 -192.274444) (xy 96.686878 -192.442084)
			(xy 96.686878 -193.797936) (xy 96.757236 -193.868294) (xy 102.672388 -193.868294)
		)
		(stroke
			(width 0)
			(type solid)
		)
		(fill yes)
		(layer "F.Cu")
		(net "IND_CPU0_P1_CPL3")
	)
	(gr_poly
		(pts
			(xy 124.709682 -78.242922) (xy 125.479302 -77.473302) (xy 126.635002 -77.473302) (xy 127.15875 -77.473302)
			(xy 127.2921 -77.339952) (xy 127.2921 -73.707498) (xy 127.115824 -73.531222) (xy 126.810262 -73.531222)
			(xy 124.834142 -73.531222) (xy 124.72289 -73.642474) (xy 124.72289 -76.301346) (xy 124.645674 -76.378562)
			(xy 124.196602 -76.378562) (xy 120.064022 -76.378562) (xy 120.036082 -76.406502) (xy 120.036082 -76.599542)
			(xy 120.061482 -76.624942) (xy 122.703082 -76.624942) (xy 123.391422 -77.313282) (xy 123.391422 -77.770482)
			(xy 123.391422 -77.856842) (xy 123.9901 -78.45552) (xy 124.497084 -78.45552)
		)
		(stroke
			(width 0)
			(type solid)
		)
		(fill yes)
		(layer "F.Cu")
		(net "SW_P1V2_AUX_PH")
	)
	(gr_poly
		(pts
			(xy 195.96481 -72.438768) (xy 195.96481 -71.891144) (xy 196.136006 -71.719948) (xy 196.196458 -71.719948)
			(xy 196.780658 -71.719948) (xy 196.933058 -71.567548) (xy 196.933058 -69.784468) (xy 196.760338 -69.611748)
			(xy 196.160898 -69.611748) (xy 196.094858 -69.677788) (xy 196.094858 -70.195948) (xy 195.612258 -70.678548)
			(xy 194.316858 -70.678548) (xy 193.685922 -70.678548) (xy 193.180208 -70.678548) (xy 192.90919 -70.678548)
			(xy 192.865756 -70.721982) (xy 192.865756 -72.315832) (xy 193.082672 -72.532748) (xy 193.716656 -72.532748)
			(xy 194.240658 -72.532748) (xy 195.028058 -72.532748) (xy 195.87083 -72.532748)
		)
		(stroke
			(width 0)
			(type solid)
		)
		(fill yes)
		(layer "F.Cu")
		(net "P3V3_AUX")
	)
	(gr_poly
		(pts
			(xy 199.879966 -346.859352) (xy 199.879966 -339.383878) (xy 199.85609 -339.359748) (xy 197.68185 -339.359748)
			(xy 197.558914 -339.236812) (xy 197.558914 -338.352892) (xy 197.767194 -338.144612) (xy 198.292974 -338.144612)
			(xy 198.781924 -337.655662) (xy 198.781924 -334.450182) (xy 199.087994 -334.144112) (xy 204.894434 -334.144112)
			(xy 205.605888 -334.144112) (xy 205.892654 -333.857346) (xy 205.892654 -333.145892) (xy 205.892654 -331.515212)
			(xy 205.531974 -331.154532) (xy 196.756274 -331.154532) (xy 196.543676 -331.366876) (xy 196.543676 -345.841574)
			(xy 197.409054 -346.706952) (xy 197.637654 -346.935552) (xy 199.803766 -346.935552)
		)
		(stroke
			(width 0)
			(type solid)
		)
		(fill yes)
		(layer "F.Cu")
		(net "GND")
	)
	(gr_poly
		(pts
			(xy 335.387442 -144.297654) (xy 335.387442 -141.886686) (xy 335.387442 -140.849604) (xy 335.931256 -140.30579)
			(xy 335.931256 -140.303504) (xy 336.11312 -140.12164) (xy 336.11312 -133.175502) (xy 336.11312 -131.418584)
			(xy 335.864708 -131.170172) (xy 333.74076 -131.170172) (xy 333.34071 -131.170172) (xy 333.188564 -131.322318)
			(xy 333.188564 -131.722368) (xy 333.188564 -133.124702) (xy 333.188564 -135.944102) (xy 333.442564 -136.198102)
			(xy 333.442564 -137.16635) (xy 334.96377 -138.687302) (xy 334.96377 -143.587978) (xy 334.859884 -143.691864)
			(xy 334.859884 -144.295876) (xy 334.921352 -144.357344) (xy 335.327752 -144.357344)
		)
		(stroke
			(width 0)
			(type solid)
		)
		(fill yes)
		(layer "F.Cu")
		(net "SW_P12V_AUX_PVDD18_S5_P0_FLT")
	)
	(gr_poly
		(pts
			(xy 448.53479 -415.988246) (xy 448.53479 -413.845756) (xy 448.112134 -413.4231) (xy 446.933066 -413.4231)
			(xy 446.406524 -413.4231) (xy 446.402714 -413.41929) (xy 446.077848 -413.41929) (xy 445.800226 -413.141668)
			(xy 445.800226 -409.444698) (xy 446.044066 -409.200858) (xy 446.935098 -408.309826) (xy 446.935098 -408.234134)
			(xy 446.935098 -405.208486) (xy 446.935098 -404.488142) (xy 446.663318 -404.216362) (xy 441.341256 -404.216362)
			(xy 440.694572 -404.863046) (xy 440.694572 -415.257488) (xy 441.539884 -416.1028) (xy 442.10224 -416.1028)
			(xy 442.533024 -416.1028) (xy 442.919866 -416.1028) (xy 448.420236 -416.1028)
		)
		(stroke
			(width 0)
			(type solid)
		)
		(fill yes)
		(layer "F.Cu")
		(net "GND")
	)
	(gr_poly
		(pts
			(arc
				(start 38.807898 -108.24718)
				(mid 38.827421 -108.243279)
				(end 38.843966 -108.232194)
			)
			(arc
				(start 38.986714 -108.089446)
				(mid 38.997825 -108.072912)
				(end 39.0017 -108.053378)
			)
			(arc
				(start 39.0017 -107.132882)
				(mid 38.997799 -107.113359)
				(end 38.986714 -107.096814)
			)
			(arc
				(start 38.925246 -107.035346)
				(mid 38.908712 -107.024235)
				(end 38.889178 -107.02036)
			)
			(xy 35.451542 -107.02036) (xy 35.31362 -107.158282) (xy 35.2806 -107.191302) (xy 35.2806 -107.86618)
			(xy 35.38474 -107.97032) (xy 36.98748 -107.97032) (xy 37.26434 -108.24718) (xy 37.394642 -108.24718)
		)
		(stroke
			(width 0)
			(type solid)
		)
		(fill yes)
		(layer "F.Cu")
		(net "P12V_AUX_DSC_G1")
	)
	(gr_poly
		(pts
			(xy 84.68741 -191.548258) (xy 84.68741 -190.22187) (xy 84.590382 -190.124588) (xy 79.160878 -190.124588)
			(xy 78.73746 -189.70117) (xy 78.69682 -189.66053) (xy 78.69682 -187.660026) (xy 78.68285 -187.646056)
			(xy 78.271878 -187.235084) (xy 78.237842 -187.201048) (xy 71.764652 -187.201048) (xy 71.585582 -187.380118)
			(xy 71.585582 -188.683646) (xy 71.661528 -188.759592) (xy 76.90739 -188.759592) (xy 77.03947 -188.891672)
			(xy 77.276452 -189.128654) (xy 77.347318 -189.199266) (xy 77.374496 -189.226444) (xy 77.374496 -190.998094)
			(xy 77.37983 -191.003428) (xy 77.444854 -191.068452) (xy 78.106778 -191.73063) (xy 84.505038 -191.73063)
		)
		(stroke
			(width 0)
			(type solid)
		)
		(fill yes)
		(layer "F.Cu")
		(net "IND_CPU0_P1_CPL5")
	)
	(gr_poly
		(pts
			(xy 341.89416 -150.71344) (xy 341.89416 -148.103844) (xy 341.89416 -133.120384) (xy 341.89416 -131.340352)
			(xy 341.73033 -131.176522) (xy 336.630264 -131.176522) (xy 336.522314 -131.284472) (xy 336.522314 -133.386576)
			(xy 336.522314 -142.137892) (xy 336.549746 -142.165324) (xy 338.667344 -142.165324) (xy 338.667852 -142.164816)
			(xy 339.01634 -142.513304) (xy 339.01634 -146.953224) (xy 339.01634 -148.89226) (xy 338.8868 -149.0218)
			(xy 328.7776 -149.0218) (xy 328.676 -149.1234) (xy 328.676 -149.5044) (xy 328.676 -150.9268) (xy 328.7522 -151.003)
			(xy 330.1746 -151.003) (xy 330.3524 -151.003) (xy 341.6046 -151.003)
		)
		(stroke
			(width 0)
			(type solid)
		)
		(fill yes)
		(layer "F.Cu")
		(net "GND")
	)
	(gr_poly
		(pts
			(xy 66.113914 -338.908136) (xy 66.113914 -333.624682) (xy 66.108326 -333.619094) (xy 66.108326 -333.158846)
			(xy 65.747138 -332.797658) (xy 65.747138 -331.592174) (xy 66.113914 -331.225398) (xy 66.113914 -330.840842)
			(xy 66.113914 -329.432412) (xy 67.792854 -327.753472) (xy 67.792854 -325.863712) (xy 68.102734 -325.553832)
			(xy 72.824594 -325.553832) (xy 73.002394 -325.376032) (xy 73.002394 -323.887592) (xy 72.93737 -323.822568)
			(xy 67.932808 -323.822568) (xy 64.552322 -327.203054) (xy 64.552322 -337.244436) (xy 64.285622 -337.511136)
			(xy 59.705494 -337.511136) (xy 59.593226 -337.623404) (xy 59.593226 -339.123274) (xy 59.758834 -339.289136)
			(xy 65.732914 -339.289136)
		)
		(stroke
			(width 0)
			(type solid)
		)
		(fill yes)
		(layer "F.Cu")
		(net "IND_CPU1_P1_CPL3")
	)
	(gr_poly
		(pts
			(xy 146.807682 -80.528922) (xy 147.577302 -79.759302) (xy 148.733002 -79.759302) (xy 149.094698 -79.759302)
			(xy 149.352 -79.502) (xy 149.352 -75.946) (xy 149.225 -75.819) (xy 148.91004 -75.819) (xy 148.908262 -75.817222)
			(xy 146.932142 -75.817222) (xy 146.774154 -75.97521) (xy 146.774154 -78.552802) (xy 146.662394 -78.664562)
			(xy 146.294602 -78.664562) (xy 142.162022 -78.664562) (xy 142.134082 -78.692502) (xy 142.134082 -78.885542)
			(xy 142.159482 -78.910942) (xy 144.801082 -78.910942) (xy 145.489422 -79.599282) (xy 145.489422 -80.056482)
			(xy 145.49501 -80.06207) (xy 145.49501 -80.14081) (xy 146.09064 -80.73644) (xy 146.600164 -80.73644)
		)
		(stroke
			(width 0)
			(type solid)
		)
		(fill yes)
		(layer "F.Cu")
		(net "SW_P1V8_AUX_PH")
	)
	(gr_poly
		(pts
			(arc
				(start 202.526392 -339.099144)
				(mid 202.539397 -339.097493)
				(end 202.551538 -339.09254)
			)
			(xy 203.098908 -338.777072) (xy 203.109068 -338.769198) (xy 203.323698 -338.554568) (xy 203.323698 -337.533234)
			(xy 203.272898 -337.482434) (xy 202.815698 -337.482434) (xy 202.739498 -337.558634) (xy 202.739498 -338.503768)
			(arc
				(start 202.483466 -338.7598)
				(mid 202.467165 -338.770755)
				(end 202.447906 -338.774532)
			)
			(arc
				(start 201.963274 -338.774532)
				(mid 201.927727 -338.789098)
				(end 201.912982 -338.82457)
			)
			(xy 201.912982 -339.066632) (xy 201.945494 -339.099144) (xy 202.254104 -339.099144)
		)
		(stroke
			(width 0)
			(type solid)
		)
		(fill yes)
		(layer "F.Cu")
		(net "SW_PVDD_33_S5_BST")
	)
	(gr_poly
		(pts
			(xy 333.629 -143.9672) (xy 333.629 -143.022066)
			(arc
				(start 333.885032 -142.766034)
				(mid 333.901333 -142.755079)
				(end 333.920592 -142.751302)
			)
			(arc
				(start 334.405224 -142.751302)
				(mid 334.440771 -142.736736)
				(end 334.455516 -142.701264)
			)
			(xy 334.455516 -142.459202) (xy 334.423004 -142.42669) (xy 334.114394 -142.42669)
			(arc
				(start 333.842106 -142.42669)
				(mid 333.829101 -142.428341)
				(end 333.81696 -142.433294)
			)
			(xy 333.26959 -142.748762) (xy 333.25943 -142.756636) (xy 333.0448 -142.971266) (xy 333.0448 -143.9926)
			(xy 333.0956 -144.0434) (xy 333.5528 -144.0434)
		)
		(stroke
			(width 0)
			(type solid)
		)
		(fill yes)
		(layer "F.Cu")
		(net "SW_PVDD18_S5_P0_BST")
	)
	(gr_poly
		(pts
			(arc
				(start 36.106608 -124.824236)
				(mid 35.847528 -124.824236)
				(end 36.106608 -124.824236)
			)
		)
		(stroke
			(width 0)
			(type solid)
		)
		(fill yes)
		(layer "F.Cu")
		(net "GND")
	)
	(gr_poly
		(pts
			(arc
				(start 40.902128 -382.54432)
				(mid 40.638476 -382.54432)
				(end 40.902128 -382.54432)
			)
		)
		(stroke
			(width 0)
			(type solid)
		)
		(fill yes)
		(layer "F.Cu")
		(net "GND")
	)
	(gr_poly
		(pts
			(arc
				(start 40.902128 -381.3302)
				(mid 40.638476 -381.3302)
				(end 40.902128 -381.3302)
			)
		)
		(stroke
			(width 0)
			(type solid)
		)
		(fill yes)
		(layer "F.Cu")
		(net "GND")
	)
	(gr_poly
		(pts
			(arc
				(start 40.902128 -377.00712)
				(mid 40.638476 -377.00712)
				(end 40.902128 -377.00712)
			)
		)
		(stroke
			(width 0)
			(type solid)
		)
		(fill yes)
		(layer "F.Cu")
		(net "GND")
	)
	(gr_poly
		(pts
			(arc
				(start 40.902128 -375.793)
				(mid 40.638476 -375.793)
				(end 40.902128 -375.793)
			)
		)
		(stroke
			(width 0)
			(type solid)
		)
		(fill yes)
		(layer "F.Cu")
		(net "GND")
	)
	(gr_poly
		(pts
			(arc
				(start 41.562528 -383.027428)
				(mid 41.298876 -383.027428)
				(end 41.562528 -383.027428)
			)
		)
		(stroke
			(width 0)
			(type solid)
		)
		(fill yes)
		(layer "F.Cu")
		(net "GND")
	)
	(gr_poly
		(pts
			(arc
				(start 41.562528 -380.87046)
				(mid 41.298876 -380.87046)
				(end 41.562528 -380.87046)
			)
		)
		(stroke
			(width 0)
			(type solid)
		)
		(fill yes)
		(layer "F.Cu")
		(net "GND")
	)
	(gr_poly
		(pts
			(arc
				(start 41.562528 -377.49226)
				(mid 41.298876 -377.49226)
				(end 41.562528 -377.49226)
			)
		)
		(stroke
			(width 0)
			(type solid)
		)
		(fill yes)
		(layer "F.Cu")
		(net "GND")
	)
	(gr_poly
		(pts
			(arc
				(start 41.562528 -375.30786)
				(mid 41.298876 -375.30786)
				(end 41.562528 -375.30786)
			)
		)
		(stroke
			(width 0)
			(type solid)
		)
		(fill yes)
		(layer "F.Cu")
		(net "GND")
	)
	(gr_poly
		(pts
			(arc
				(start 42.222928 -382.54432)
				(mid 41.959276 -382.54432)
				(end 42.222928 -382.54432)
			)
		)
		(stroke
			(width 0)
			(type solid)
		)
		(fill yes)
		(layer "F.Cu")
		(net "GND")
	)
	(gr_poly
		(pts
			(arc
				(start 42.222928 -381.3302)
				(mid 41.959276 -381.3302)
				(end 42.222928 -381.3302)
			)
		)
		(stroke
			(width 0)
			(type solid)
		)
		(fill yes)
		(layer "F.Cu")
		(net "GND")
	)
	(gr_poly
		(pts
			(arc
				(start 42.222928 -377.00712)
				(mid 41.959276 -377.00712)
				(end 42.222928 -377.00712)
			)
		)
		(stroke
			(width 0)
			(type solid)
		)
		(fill yes)
		(layer "F.Cu")
		(net "GND")
	)
	(gr_poly
		(pts
			(arc
				(start 42.222928 -375.793)
				(mid 41.959276 -375.793)
				(end 42.222928 -375.793)
			)
		)
		(stroke
			(width 0)
			(type solid)
		)
		(fill yes)
		(layer "F.Cu")
		(net "GND")
	)
	(gr_poly
		(pts
			(arc
				(start 42.48658 -371.49913)
				(mid 42.222928 -371.49913)
				(end 42.48658 -371.49913)
			)
		)
		(stroke
			(width 0)
			(type solid)
		)
		(fill yes)
		(layer "F.Cu")
		(net "GND")
	)
	(gr_poly
		(pts
			(arc
				(start 42.97172 -372.15953)
				(mid 42.708068 -372.15953)
				(end 42.97172 -372.15953)
			)
		)
		(stroke
			(width 0)
			(type solid)
		)
		(fill yes)
		(layer "F.Cu")
		(net "GND")
	)
	(gr_poly
		(pts
			(arc
				(start 42.97172 -370.83873)
				(mid 42.708068 -370.83873)
				(end 42.97172 -370.83873)
			)
		)
		(stroke
			(width 0)
			(type solid)
		)
		(fill yes)
		(layer "F.Cu")
		(net "GND")
	)
	(gr_poly
		(pts
			(arc
				(start 44.18584 -372.15953)
				(mid 43.922188 -372.15953)
				(end 44.18584 -372.15953)
			)
		)
		(stroke
			(width 0)
			(type solid)
		)
		(fill yes)
		(layer "F.Cu")
		(net "GND")
	)
	(gr_poly
		(pts
			(arc
				(start 44.18584 -370.83873)
				(mid 43.922188 -370.83873)
				(end 44.18584 -370.83873)
			)
		)
		(stroke
			(width 0)
			(type solid)
		)
		(fill yes)
		(layer "F.Cu")
		(net "GND")
	)
	(gr_poly
		(pts
			(arc
				(start 44.18838 -369.03533)
				(mid 43.924728 -369.03533)
				(end 44.18838 -369.03533)
			)
		)
		(stroke
			(width 0)
			(type solid)
		)
		(fill yes)
		(layer "F.Cu")
		(net "GND")
	)
	(gr_poly
		(pts
			(arc
				(start 44.67098 -371.49913)
				(mid 44.407328 -371.49913)
				(end 44.67098 -371.49913)
			)
		)
		(stroke
			(width 0)
			(type solid)
		)
		(fill yes)
		(layer "F.Cu")
		(net "GND")
	)
	(gr_poly
		(pts
			(arc
				(start 44.67352 -369.69573)
				(mid 44.409868 -369.69573)
				(end 44.67352 -369.69573)
			)
		)
		(stroke
			(width 0)
			(type solid)
		)
		(fill yes)
		(layer "F.Cu")
		(net "GND")
	)
	(gr_poly
		(pts
			(arc
				(start 44.67352 -368.37493)
				(mid 44.409868 -368.37493)
				(end 44.67352 -368.37493)
			)
		)
		(stroke
			(width 0)
			(type solid)
		)
		(fill yes)
		(layer "F.Cu")
		(net "GND")
	)
	(gr_poly
		(pts
			(arc
				(start 45.88764 -369.69573)
				(mid 45.623988 -369.69573)
				(end 45.88764 -369.69573)
			)
		)
		(stroke
			(width 0)
			(type solid)
		)
		(fill yes)
		(layer "F.Cu")
		(net "GND")
	)
	(gr_poly
		(pts
			(arc
				(start 45.88764 -368.37493)
				(mid 45.623988 -368.37493)
				(end 45.88764 -368.37493)
			)
		)
		(stroke
			(width 0)
			(type solid)
		)
		(fill yes)
		(layer "F.Cu")
		(net "GND")
	)
	(gr_poly
		(pts
			(arc
				(start 46.37278 -369.03533)
				(mid 46.109128 -369.03533)
				(end 46.37278 -369.03533)
			)
		)
		(stroke
			(width 0)
			(type solid)
		)
		(fill yes)
		(layer "F.Cu")
		(net "GND")
	)
	(gr_poly
		(pts
			(arc
				(start 47.59198 -373.96293)
				(mid 47.328328 -373.96293)
				(end 47.59198 -373.96293)
			)
		)
		(stroke
			(width 0)
			(type solid)
		)
		(fill yes)
		(layer "F.Cu")
		(net "GND")
	)
	(gr_poly
		(pts
			(arc
				(start 48.07712 -374.62333)
				(mid 47.813468 -374.62333)
				(end 48.07712 -374.62333)
			)
		)
		(stroke
			(width 0)
			(type solid)
		)
		(fill yes)
		(layer "F.Cu")
		(net "GND")
	)
	(gr_poly
		(pts
			(arc
				(start 48.07712 -373.30253)
				(mid 47.813468 -373.30253)
				(end 48.07712 -373.30253)
			)
		)
		(stroke
			(width 0)
			(type solid)
		)
		(fill yes)
		(layer "F.Cu")
		(net "GND")
	)
	(gr_poly
		(pts
			(arc
				(start 49.29124 -374.62333)
				(mid 49.027588 -374.62333)
				(end 49.29124 -374.62333)
			)
		)
		(stroke
			(width 0)
			(type solid)
		)
		(fill yes)
		(layer "F.Cu")
		(net "GND")
	)
	(gr_poly
		(pts
			(arc
				(start 49.29124 -373.30253)
				(mid 49.027588 -373.30253)
				(end 49.29124 -373.30253)
			)
		)
		(stroke
			(width 0)
			(type solid)
		)
		(fill yes)
		(layer "F.Cu")
		(net "GND")
	)
	(gr_poly
		(pts
			(arc
				(start 49.29378 -371.49913)
				(mid 49.030128 -371.49913)
				(end 49.29378 -371.49913)
			)
		)
		(stroke
			(width 0)
			(type solid)
		)
		(fill yes)
		(layer "F.Cu")
		(net "GND")
	)
	(gr_poly
		(pts
			(arc
				(start 49.77638 -373.96293)
				(mid 49.512728 -373.96293)
				(end 49.77638 -373.96293)
			)
		)
		(stroke
			(width 0)
			(type solid)
		)
		(fill yes)
		(layer "F.Cu")
		(net "GND")
	)
	(gr_poly
		(pts
			(arc
				(start 49.77892 -372.15953)
				(mid 49.515268 -372.15953)
				(end 49.77892 -372.15953)
			)
		)
		(stroke
			(width 0)
			(type solid)
		)
		(fill yes)
		(layer "F.Cu")
		(net "GND")
	)
	(gr_poly
		(pts
			(arc
				(start 49.77892 -370.83873)
				(mid 49.515268 -370.83873)
				(end 49.77892 -370.83873)
			)
		)
		(stroke
			(width 0)
			(type solid)
		)
		(fill yes)
		(layer "F.Cu")
		(net "GND")
	)
	(gr_poly
		(pts
			(arc
				(start 50.99304 -372.15953)
				(mid 50.729388 -372.15953)
				(end 50.99304 -372.15953)
			)
		)
		(stroke
			(width 0)
			(type solid)
		)
		(fill yes)
		(layer "F.Cu")
		(net "GND")
	)
	(gr_poly
		(pts
			(arc
				(start 50.99304 -370.83873)
				(mid 50.729388 -370.83873)
				(end 50.99304 -370.83873)
			)
		)
		(stroke
			(width 0)
			(type solid)
		)
		(fill yes)
		(layer "F.Cu")
		(net "GND")
	)
	(gr_poly
		(pts
			(arc
				(start 50.99558 -369.03533)
				(mid 50.731928 -369.03533)
				(end 50.99558 -369.03533)
			)
		)
		(stroke
			(width 0)
			(type solid)
		)
		(fill yes)
		(layer "F.Cu")
		(net "GND")
	)
	(gr_poly
		(pts
			(arc
				(start 51.47818 -371.49913)
				(mid 51.214528 -371.49913)
				(end 51.47818 -371.49913)
			)
		)
		(stroke
			(width 0)
			(type solid)
		)
		(fill yes)
		(layer "F.Cu")
		(net "GND")
	)
	(gr_poly
		(pts
			(arc
				(start 51.48072 -369.69573)
				(mid 51.217068 -369.69573)
				(end 51.48072 -369.69573)
			)
		)
		(stroke
			(width 0)
			(type solid)
		)
		(fill yes)
		(layer "F.Cu")
		(net "GND")
	)
	(gr_poly
		(pts
			(arc
				(start 51.48072 -368.37493)
				(mid 51.217068 -368.37493)
				(end 51.48072 -368.37493)
			)
		)
		(stroke
			(width 0)
			(type solid)
		)
		(fill yes)
		(layer "F.Cu")
		(net "GND")
	)
	(gr_poly
		(pts
			(arc
				(start 52.69484 -369.69573)
				(mid 52.431188 -369.69573)
				(end 52.69484 -369.69573)
			)
		)
		(stroke
			(width 0)
			(type solid)
		)
		(fill yes)
		(layer "F.Cu")
		(net "GND")
	)
	(gr_poly
		(pts
			(arc
				(start 52.69484 -368.37493)
				(mid 52.431188 -368.37493)
				(end 52.69484 -368.37493)
			)
		)
		(stroke
			(width 0)
			(type solid)
		)
		(fill yes)
		(layer "F.Cu")
		(net "GND")
	)
	(gr_poly
		(pts
			(arc
				(start 53.17998 -369.03533)
				(mid 52.916328 -369.03533)
				(end 53.17998 -369.03533)
			)
		)
		(stroke
			(width 0)
			(type solid)
		)
		(fill yes)
		(layer "F.Cu")
		(net "GND")
	)
	(gr_poly
		(pts
			(arc
				(start 54.39918 -373.96293)
				(mid 54.135528 -373.96293)
				(end 54.39918 -373.96293)
			)
		)
		(stroke
			(width 0)
			(type solid)
		)
		(fill yes)
		(layer "F.Cu")
		(net "GND")
	)
	(gr_poly
		(pts
			(arc
				(start 54.88432 -374.62333)
				(mid 54.620668 -374.62333)
				(end 54.88432 -374.62333)
			)
		)
		(stroke
			(width 0)
			(type solid)
		)
		(fill yes)
		(layer "F.Cu")
		(net "GND")
	)
	(gr_poly
		(pts
			(arc
				(start 54.88432 -373.30253)
				(mid 54.620668 -373.30253)
				(end 54.88432 -373.30253)
			)
		)
		(stroke
			(width 0)
			(type solid)
		)
		(fill yes)
		(layer "F.Cu")
		(net "GND")
	)
	(gr_poly
		(pts
			(arc
				(start 56.09844 -374.62333)
				(mid 55.834788 -374.62333)
				(end 56.09844 -374.62333)
			)
		)
		(stroke
			(width 0)
			(type solid)
		)
		(fill yes)
		(layer "F.Cu")
		(net "GND")
	)
	(gr_poly
		(pts
			(arc
				(start 56.09844 -373.30253)
				(mid 55.834788 -373.30253)
				(end 56.09844 -373.30253)
			)
		)
		(stroke
			(width 0)
			(type solid)
		)
		(fill yes)
		(layer "F.Cu")
		(net "GND")
	)
	(gr_poly
		(pts
			(arc
				(start 56.10098 -371.49913)
				(mid 55.837328 -371.49913)
				(end 56.10098 -371.49913)
			)
		)
		(stroke
			(width 0)
			(type solid)
		)
		(fill yes)
		(layer "F.Cu")
		(net "GND")
	)
	(gr_poly
		(pts
			(arc
				(start 56.184038 -132.703062)
				(mid 55.924958 -132.703062)
				(end 56.184038 -132.703062)
			)
		)
		(stroke
			(width 0)
			(type solid)
		)
		(fill yes)
		(layer "F.Cu")
		(net "GND")
	)
	(gr_poly
		(pts
			(arc
				(start 56.58358 -373.96293)
				(mid 56.319928 -373.96293)
				(end 56.58358 -373.96293)
			)
		)
		(stroke
			(width 0)
			(type solid)
		)
		(fill yes)
		(layer "F.Cu")
		(net "GND")
	)
	(gr_poly
		(pts
			(arc
				(start 56.58612 -372.15953)
				(mid 56.322468 -372.15953)
				(end 56.58612 -372.15953)
			)
		)
		(stroke
			(width 0)
			(type solid)
		)
		(fill yes)
		(layer "F.Cu")
		(net "GND")
	)
	(gr_poly
		(pts
			(arc
				(start 56.58612 -370.83873)
				(mid 56.322468 -370.83873)
				(end 56.58612 -370.83873)
			)
		)
		(stroke
			(width 0)
			(type solid)
		)
		(fill yes)
		(layer "F.Cu")
		(net "GND")
	)
	(gr_poly
		(pts
			(arc
				(start 57.708038 -132.703062)
				(mid 57.448958 -132.703062)
				(end 57.708038 -132.703062)
			)
		)
		(stroke
			(width 0)
			(type solid)
		)
		(fill yes)
		(layer "F.Cu")
		(net "GND")
	)
	(gr_poly
		(pts
			(arc
				(start 57.80024 -372.15953)
				(mid 57.536588 -372.15953)
				(end 57.80024 -372.15953)
			)
		)
		(stroke
			(width 0)
			(type solid)
		)
		(fill yes)
		(layer "F.Cu")
		(net "GND")
	)
	(gr_poly
		(pts
			(arc
				(start 57.80024 -370.83873)
				(mid 57.536588 -370.83873)
				(end 57.80024 -370.83873)
			)
		)
		(stroke
			(width 0)
			(type solid)
		)
		(fill yes)
		(layer "F.Cu")
		(net "GND")
	)
	(gr_poly
		(pts
			(arc
				(start 57.80278 -369.03533)
				(mid 57.539128 -369.03533)
				(end 57.80278 -369.03533)
			)
		)
		(stroke
			(width 0)
			(type solid)
		)
		(fill yes)
		(layer "F.Cu")
		(net "GND")
	)
	(gr_poly
		(pts
			(arc
				(start 58.28538 -371.49913)
				(mid 58.021728 -371.49913)
				(end 58.28538 -371.49913)
			)
		)
		(stroke
			(width 0)
			(type solid)
		)
		(fill yes)
		(layer "F.Cu")
		(net "GND")
	)
	(gr_poly
		(pts
			(arc
				(start 58.28792 -369.69573)
				(mid 58.024268 -369.69573)
				(end 58.28792 -369.69573)
			)
		)
		(stroke
			(width 0)
			(type solid)
		)
		(fill yes)
		(layer "F.Cu")
		(net "GND")
	)
	(gr_poly
		(pts
			(arc
				(start 58.28792 -368.37493)
				(mid 58.024268 -368.37493)
				(end 58.28792 -368.37493)
			)
		)
		(stroke
			(width 0)
			(type solid)
		)
		(fill yes)
		(layer "F.Cu")
		(net "GND")
	)
	(gr_poly
		(pts
			(arc
				(start 59.50204 -369.69573)
				(mid 59.238388 -369.69573)
				(end 59.50204 -369.69573)
			)
		)
		(stroke
			(width 0)
			(type solid)
		)
		(fill yes)
		(layer "F.Cu")
		(net "GND")
	)
	(gr_poly
		(pts
			(arc
				(start 59.50204 -368.37493)
				(mid 59.238388 -368.37493)
				(end 59.50204 -368.37493)
			)
		)
		(stroke
			(width 0)
			(type solid)
		)
		(fill yes)
		(layer "F.Cu")
		(net "GND")
	)
	(gr_poly
		(pts
			(arc
				(start 59.98718 -369.03533)
				(mid 59.723528 -369.03533)
				(end 59.98718 -369.03533)
			)
		)
		(stroke
			(width 0)
			(type solid)
		)
		(fill yes)
		(layer "F.Cu")
		(net "GND")
	)
	(gr_poly
		(pts
			(arc
				(start 61.20638 -373.96293)
				(mid 60.942728 -373.96293)
				(end 61.20638 -373.96293)
			)
		)
		(stroke
			(width 0)
			(type solid)
		)
		(fill yes)
		(layer "F.Cu")
		(net "GND")
	)
	(gr_poly
		(pts
			(arc
				(start 61.69152 -374.62333)
				(mid 61.427868 -374.62333)
				(end 61.69152 -374.62333)
			)
		)
		(stroke
			(width 0)
			(type solid)
		)
		(fill yes)
		(layer "F.Cu")
		(net "GND")
	)
	(gr_poly
		(pts
			(arc
				(start 61.69152 -373.30253)
				(mid 61.427868 -373.30253)
				(end 61.69152 -373.30253)
			)
		)
		(stroke
			(width 0)
			(type solid)
		)
		(fill yes)
		(layer "F.Cu")
		(net "GND")
	)
	(gr_poly
		(pts
			(arc
				(start 62.90564 -374.62333)
				(mid 62.641988 -374.62333)
				(end 62.90564 -374.62333)
			)
		)
		(stroke
			(width 0)
			(type solid)
		)
		(fill yes)
		(layer "F.Cu")
		(net "GND")
	)
	(gr_poly
		(pts
			(arc
				(start 62.90564 -373.30253)
				(mid 62.641988 -373.30253)
				(end 62.90564 -373.30253)
			)
		)
		(stroke
			(width 0)
			(type solid)
		)
		(fill yes)
		(layer "F.Cu")
		(net "GND")
	)
	(gr_poly
		(pts
			(arc
				(start 62.90818 -371.49913)
				(mid 62.644528 -371.49913)
				(end 62.90818 -371.49913)
			)
		)
		(stroke
			(width 0)
			(type solid)
		)
		(fill yes)
		(layer "F.Cu")
		(net "GND")
	)
	(gr_poly
		(pts
			(arc
				(start 63.39078 -373.96293)
				(mid 63.127128 -373.96293)
				(end 63.39078 -373.96293)
			)
		)
		(stroke
			(width 0)
			(type solid)
		)
		(fill yes)
		(layer "F.Cu")
		(net "GND")
	)
	(gr_poly
		(pts
			(arc
				(start 63.39332 -372.15953)
				(mid 63.129668 -372.15953)
				(end 63.39332 -372.15953)
			)
		)
		(stroke
			(width 0)
			(type solid)
		)
		(fill yes)
		(layer "F.Cu")
		(net "GND")
	)
	(gr_poly
		(pts
			(arc
				(start 63.39332 -370.83873)
				(mid 63.129668 -370.83873)
				(end 63.39332 -370.83873)
			)
		)
		(stroke
			(width 0)
			(type solid)
		)
		(fill yes)
		(layer "F.Cu")
		(net "GND")
	)
	(gr_poly
		(pts
			(arc
				(start 64.60744 -372.15953)
				(mid 64.343788 -372.15953)
				(end 64.60744 -372.15953)
			)
		)
		(stroke
			(width 0)
			(type solid)
		)
		(fill yes)
		(layer "F.Cu")
		(net "GND")
	)
	(gr_poly
		(pts
			(arc
				(start 64.60744 -370.83873)
				(mid 64.343788 -370.83873)
				(end 64.60744 -370.83873)
			)
		)
		(stroke
			(width 0)
			(type solid)
		)
		(fill yes)
		(layer "F.Cu")
		(net "GND")
	)
	(gr_poly
		(pts
			(arc
				(start 64.60998 -369.03533)
				(mid 64.346328 -369.03533)
				(end 64.60998 -369.03533)
			)
		)
		(stroke
			(width 0)
			(type solid)
		)
		(fill yes)
		(layer "F.Cu")
		(net "GND")
	)
	(gr_poly
		(pts
			(arc
				(start 65.09258 -371.49913)
				(mid 64.828928 -371.49913)
				(end 65.09258 -371.49913)
			)
		)
		(stroke
			(width 0)
			(type solid)
		)
		(fill yes)
		(layer "F.Cu")
		(net "GND")
	)
	(gr_poly
		(pts
			(arc
				(start 65.09512 -369.69573)
				(mid 64.831468 -369.69573)
				(end 65.09512 -369.69573)
			)
		)
		(stroke
			(width 0)
			(type solid)
		)
		(fill yes)
		(layer "F.Cu")
		(net "GND")
	)
	(gr_poly
		(pts
			(arc
				(start 65.09512 -368.37493)
				(mid 64.831468 -368.37493)
				(end 65.09512 -368.37493)
			)
		)
		(stroke
			(width 0)
			(type solid)
		)
		(fill yes)
		(layer "F.Cu")
		(net "GND")
	)
	(gr_poly
		(pts
			(arc
				(start 65.834768 -410.664152)
				(mid 65.571624 -410.664152)
				(end 65.834768 -410.664152)
			)
		)
		(stroke
			(width 0)
			(type solid)
		)
		(fill yes)
		(layer "F.Cu")
		(net "GND")
	)
	(gr_poly
		(pts
			(arc
				(start 66.30924 -369.69573)
				(mid 66.045588 -369.69573)
				(end 66.30924 -369.69573)
			)
		)
		(stroke
			(width 0)
			(type solid)
		)
		(fill yes)
		(layer "F.Cu")
		(net "GND")
	)
	(gr_poly
		(pts
			(arc
				(start 66.30924 -368.37493)
				(mid 66.045588 -368.37493)
				(end 66.30924 -368.37493)
			)
		)
		(stroke
			(width 0)
			(type solid)
		)
		(fill yes)
		(layer "F.Cu")
		(net "GND")
	)
	(gr_poly
		(pts
			(arc
				(start 66.79438 -369.03533)
				(mid 66.530728 -369.03533)
				(end 66.79438 -369.03533)
			)
		)
		(stroke
			(width 0)
			(type solid)
		)
		(fill yes)
		(layer "F.Cu")
		(net "GND")
	)
	(gr_poly
		(pts
			(arc
				(start 67.639184 -410.664152)
				(mid 67.37604 -410.664152)
				(end 67.639184 -410.664152)
			)
		)
		(stroke
			(width 0)
			(type solid)
		)
		(fill yes)
		(layer "F.Cu")
		(net "GND")
	)
	(gr_poly
		(pts
			(arc
				(start 68.01358 -369.03533)
				(mid 67.749928 -369.03533)
				(end 68.01358 -369.03533)
			)
		)
		(stroke
			(width 0)
			(type solid)
		)
		(fill yes)
		(layer "F.Cu")
		(net "GND")
	)
	(gr_poly
		(pts
			(arc
				(start 68.49872 -369.69573)
				(mid 68.235068 -369.69573)
				(end 68.49872 -369.69573)
			)
		)
		(stroke
			(width 0)
			(type solid)
		)
		(fill yes)
		(layer "F.Cu")
		(net "GND")
	)
	(gr_poly
		(pts
			(arc
				(start 68.49872 -368.37493)
				(mid 68.235068 -368.37493)
				(end 68.49872 -368.37493)
			)
		)
		(stroke
			(width 0)
			(type solid)
		)
		(fill yes)
		(layer "F.Cu")
		(net "GND")
	)
	(gr_poly
		(pts
			(arc
				(start 68.898008 -410.664152)
				(mid 68.634864 -410.664152)
				(end 68.898008 -410.664152)
			)
		)
		(stroke
			(width 0)
			(type solid)
		)
		(fill yes)
		(layer "F.Cu")
		(net "GND")
	)
	(gr_poly
		(pts
			(arc
				(start 69.279008 -132.861304)
				(mid 69.019928 -132.861304)
				(end 69.279008 -132.861304)
			)
		)
		(stroke
			(width 0)
			(type solid)
		)
		(fill yes)
		(layer "F.Cu")
		(net "GND")
	)
	(gr_poly
		(pts
			(arc
				(start 69.71284 -369.69573)
				(mid 69.449188 -369.69573)
				(end 69.71284 -369.69573)
			)
		)
		(stroke
			(width 0)
			(type solid)
		)
		(fill yes)
		(layer "F.Cu")
		(net "GND")
	)
	(gr_poly
		(pts
			(arc
				(start 69.71284 -368.37493)
				(mid 69.449188 -368.37493)
				(end 69.71284 -368.37493)
			)
		)
		(stroke
			(width 0)
			(type solid)
		)
		(fill yes)
		(layer "F.Cu")
		(net "GND")
	)
	(gr_poly
		(pts
			(arc
				(start 70.19798 -369.03533)
				(mid 69.934328 -369.03533)
				(end 70.19798 -369.03533)
			)
		)
		(stroke
			(width 0)
			(type solid)
		)
		(fill yes)
		(layer "F.Cu")
		(net "GND")
	)
	(gr_poly
		(pts
			(arc
				(start 70.702424 -410.664152)
				(mid 70.43928 -410.664152)
				(end 70.702424 -410.664152)
			)
		)
		(stroke
			(width 0)
			(type solid)
		)
		(fill yes)
		(layer "F.Cu")
		(net "GND")
	)
	(gr_poly
		(pts
			(arc
				(start 70.74916 -380.535688)
				(mid 70.485508 -380.535688)
				(end 70.74916 -380.535688)
			)
		)
		(stroke
			(width 0)
			(type solid)
		)
		(fill yes)
		(layer "F.Cu")
		(net "GND")
	)
	(gr_poly
		(pts
			(arc
				(start 70.74916 -379.321568)
				(mid 70.485508 -379.321568)
				(end 70.74916 -379.321568)
			)
		)
		(stroke
			(width 0)
			(type solid)
		)
		(fill yes)
		(layer "F.Cu")
		(net "GND")
	)
	(gr_poly
		(pts
			(arc
				(start 70.74916 -377.132088)
				(mid 70.485508 -377.132088)
				(end 70.74916 -377.132088)
			)
		)
		(stroke
			(width 0)
			(type solid)
		)
		(fill yes)
		(layer "F.Cu")
		(net "GND")
	)
	(gr_poly
		(pts
			(arc
				(start 70.74916 -375.917968)
				(mid 70.485508 -375.917968)
				(end 70.74916 -375.917968)
			)
		)
		(stroke
			(width 0)
			(type solid)
		)
		(fill yes)
		(layer "F.Cu")
		(net "GND")
	)
	(gr_poly
		(pts
			(arc
				(start 71.40956 -378.836428)
				(mid 71.145908 -378.836428)
				(end 71.40956 -378.836428)
			)
		)
		(stroke
			(width 0)
			(type solid)
		)
		(fill yes)
		(layer "F.Cu")
		(net "GND")
	)
	(gr_poly
		(pts
			(arc
				(start 71.40956 -377.617228)
				(mid 71.145908 -377.617228)
				(end 71.40956 -377.617228)
			)
		)
		(stroke
			(width 0)
			(type solid)
		)
		(fill yes)
		(layer "F.Cu")
		(net "GND")
	)
	(gr_poly
		(pts
			(arc
				(start 71.40956 -375.432828)
				(mid 71.145908 -375.432828)
				(end 71.40956 -375.432828)
			)
		)
		(stroke
			(width 0)
			(type solid)
		)
		(fill yes)
		(layer "F.Cu")
		(net "GND")
	)
	(gr_poly
		(pts
			(arc
				(start 71.540878 -132.537962)
				(mid 71.281798 -132.537962)
				(end 71.540878 -132.537962)
			)
		)
		(stroke
			(width 0)
			(type solid)
		)
		(fill yes)
		(layer "F.Cu")
		(net "GND")
	)
	(gr_poly
		(pts
			(arc
				(start 72.06996 -380.535688)
				(mid 71.806308 -380.535688)
				(end 72.06996 -380.535688)
			)
		)
		(stroke
			(width 0)
			(type solid)
		)
		(fill yes)
		(layer "F.Cu")
		(net "GND")
	)
	(gr_poly
		(pts
			(arc
				(start 72.06996 -379.321568)
				(mid 71.806308 -379.321568)
				(end 72.06996 -379.321568)
			)
		)
		(stroke
			(width 0)
			(type solid)
		)
		(fill yes)
		(layer "F.Cu")
		(net "GND")
	)
	(gr_poly
		(pts
			(arc
				(start 72.06996 -377.132088)
				(mid 71.806308 -377.132088)
				(end 72.06996 -377.132088)
			)
		)
		(stroke
			(width 0)
			(type solid)
		)
		(fill yes)
		(layer "F.Cu")
		(net "GND")
	)
	(gr_poly
		(pts
			(arc
				(start 72.06996 -375.917968)
				(mid 71.806308 -375.917968)
				(end 72.06996 -375.917968)
			)
		)
		(stroke
			(width 0)
			(type solid)
		)
		(fill yes)
		(layer "F.Cu")
		(net "GND")
	)
	(gr_poly
		(pts
			(arc
				(start 73.429876 -381.3302)
				(mid 73.166224 -381.3302)
				(end 73.429876 -381.3302)
			)
		)
		(stroke
			(width 0)
			(type solid)
		)
		(fill yes)
		(layer "F.Cu")
		(net "GND")
	)
	(gr_poly
		(pts
			(arc
				(start 73.429876 -377.00712)
				(mid 73.166224 -377.00712)
				(end 73.429876 -377.00712)
			)
		)
		(stroke
			(width 0)
			(type solid)
		)
		(fill yes)
		(layer "F.Cu")
		(net "GND")
	)
	(gr_poly
		(pts
			(arc
				(start 73.429876 -375.793)
				(mid 73.166224 -375.793)
				(end 73.429876 -375.793)
			)
		)
		(stroke
			(width 0)
			(type solid)
		)
		(fill yes)
		(layer "F.Cu")
		(net "GND")
	)
	(gr_poly
		(pts
			(arc
				(start 74.090276 -383.02946)
				(mid 73.826624 -383.02946)
				(end 74.090276 -383.02946)
			)
		)
		(stroke
			(width 0)
			(type solid)
		)
		(fill yes)
		(layer "F.Cu")
		(net "GND")
	)
	(gr_poly
		(pts
			(arc
				(start 74.090276 -380.87046)
				(mid 73.826624 -380.87046)
				(end 74.090276 -380.87046)
			)
		)
		(stroke
			(width 0)
			(type solid)
		)
		(fill yes)
		(layer "F.Cu")
		(net "GND")
	)
	(gr_poly
		(pts
			(arc
				(start 74.090276 -377.49226)
				(mid 73.826624 -377.49226)
				(end 74.090276 -377.49226)
			)
		)
		(stroke
			(width 0)
			(type solid)
		)
		(fill yes)
		(layer "F.Cu")
		(net "GND")
	)
	(gr_poly
		(pts
			(arc
				(start 74.090276 -375.30786)
				(mid 73.826624 -375.30786)
				(end 74.090276 -375.30786)
			)
		)
		(stroke
			(width 0)
			(type solid)
		)
		(fill yes)
		(layer "F.Cu")
		(net "GND")
	)
	(gr_poly
		(pts
			(arc
				(start 74.750676 -382.54432)
				(mid 74.487024 -382.54432)
				(end 74.750676 -382.54432)
			)
		)
		(stroke
			(width 0)
			(type solid)
		)
		(fill yes)
		(layer "F.Cu")
		(net "GND")
	)
	(gr_poly
		(pts
			(arc
				(start 74.750676 -381.3302)
				(mid 74.487024 -381.3302)
				(end 74.750676 -381.3302)
			)
		)
		(stroke
			(width 0)
			(type solid)
		)
		(fill yes)
		(layer "F.Cu")
		(net "GND")
	)
	(gr_poly
		(pts
			(arc
				(start 74.750676 -377.00712)
				(mid 74.487024 -377.00712)
				(end 74.750676 -377.00712)
			)
		)
		(stroke
			(width 0)
			(type solid)
		)
		(fill yes)
		(layer "F.Cu")
		(net "GND")
	)
	(gr_poly
		(pts
			(arc
				(start 74.750676 -375.793)
				(mid 74.487024 -375.793)
				(end 74.750676 -375.793)
			)
		)
		(stroke
			(width 0)
			(type solid)
		)
		(fill yes)
		(layer "F.Cu")
		(net "GND")
	)
	(gr_poly
		(pts
			(arc
				(start 75.014328 -371.49913)
				(mid 74.750676 -371.49913)
				(end 75.014328 -371.49913)
			)
		)
		(stroke
			(width 0)
			(type solid)
		)
		(fill yes)
		(layer "F.Cu")
		(net "GND")
	)
	(gr_poly
		(pts
			(arc
				(start 75.499468 -372.15953)
				(mid 75.235816 -372.15953)
				(end 75.499468 -372.15953)
			)
		)
		(stroke
			(width 0)
			(type solid)
		)
		(fill yes)
		(layer "F.Cu")
		(net "GND")
	)
	(gr_poly
		(pts
			(arc
				(start 75.499468 -370.83873)
				(mid 75.235816 -370.83873)
				(end 75.499468 -370.83873)
			)
		)
		(stroke
			(width 0)
			(type solid)
		)
		(fill yes)
		(layer "F.Cu")
		(net "GND")
	)
	(gr_poly
		(pts
			(arc
				(start 76.713588 -372.15953)
				(mid 76.449936 -372.15953)
				(end 76.713588 -372.15953)
			)
		)
		(stroke
			(width 0)
			(type solid)
		)
		(fill yes)
		(layer "F.Cu")
		(net "GND")
	)
	(gr_poly
		(pts
			(arc
				(start 76.713588 -370.83873)
				(mid 76.449936 -370.83873)
				(end 76.713588 -370.83873)
			)
		)
		(stroke
			(width 0)
			(type solid)
		)
		(fill yes)
		(layer "F.Cu")
		(net "GND")
	)
	(gr_poly
		(pts
			(arc
				(start 76.716128 -369.03533)
				(mid 76.452476 -369.03533)
				(end 76.716128 -369.03533)
			)
		)
		(stroke
			(width 0)
			(type solid)
		)
		(fill yes)
		(layer "F.Cu")
		(net "GND")
	)
	(gr_poly
		(pts
			(arc
				(start 77.198728 -371.49913)
				(mid 76.935076 -371.49913)
				(end 77.198728 -371.49913)
			)
		)
		(stroke
			(width 0)
			(type solid)
		)
		(fill yes)
		(layer "F.Cu")
		(net "GND")
	)
	(gr_poly
		(pts
			(arc
				(start 77.201268 -369.69573)
				(mid 76.937616 -369.69573)
				(end 77.201268 -369.69573)
			)
		)
		(stroke
			(width 0)
			(type solid)
		)
		(fill yes)
		(layer "F.Cu")
		(net "GND")
	)
	(gr_poly
		(pts
			(arc
				(start 77.201268 -368.37493)
				(mid 76.937616 -368.37493)
				(end 77.201268 -368.37493)
			)
		)
		(stroke
			(width 0)
			(type solid)
		)
		(fill yes)
		(layer "F.Cu")
		(net "GND")
	)
	(gr_poly
		(pts
			(arc
				(start 78.415388 -369.69573)
				(mid 78.151736 -369.69573)
				(end 78.415388 -369.69573)
			)
		)
		(stroke
			(width 0)
			(type solid)
		)
		(fill yes)
		(layer "F.Cu")
		(net "GND")
	)
	(gr_poly
		(pts
			(arc
				(start 78.415388 -368.37493)
				(mid 78.151736 -368.37493)
				(end 78.415388 -368.37493)
			)
		)
		(stroke
			(width 0)
			(type solid)
		)
		(fill yes)
		(layer "F.Cu")
		(net "GND")
	)
	(gr_poly
		(pts
			(arc
				(start 78.900528 -369.03533)
				(mid 78.636876 -369.03533)
				(end 78.900528 -369.03533)
			)
		)
		(stroke
			(width 0)
			(type solid)
		)
		(fill yes)
		(layer "F.Cu")
		(net "GND")
	)
	(gr_poly
		(pts
			(arc
				(start 80.119728 -373.96293)
				(mid 79.856076 -373.96293)
				(end 80.119728 -373.96293)
			)
		)
		(stroke
			(width 0)
			(type solid)
		)
		(fill yes)
		(layer "F.Cu")
		(net "GND")
	)
	(gr_poly
		(pts
			(arc
				(start 80.604868 -374.62333)
				(mid 80.341216 -374.62333)
				(end 80.604868 -374.62333)
			)
		)
		(stroke
			(width 0)
			(type solid)
		)
		(fill yes)
		(layer "F.Cu")
		(net "GND")
	)
	(gr_poly
		(pts
			(arc
				(start 80.604868 -373.30253)
				(mid 80.341216 -373.30253)
				(end 80.604868 -373.30253)
			)
		)
		(stroke
			(width 0)
			(type solid)
		)
		(fill yes)
		(layer "F.Cu")
		(net "GND")
	)
	(gr_poly
		(pts
			(arc
				(start 81.818988 -374.62333)
				(mid 81.555336 -374.62333)
				(end 81.818988 -374.62333)
			)
		)
		(stroke
			(width 0)
			(type solid)
		)
		(fill yes)
		(layer "F.Cu")
		(net "GND")
	)
	(gr_poly
		(pts
			(arc
				(start 81.818988 -373.30253)
				(mid 81.555336 -373.30253)
				(end 81.818988 -373.30253)
			)
		)
		(stroke
			(width 0)
			(type solid)
		)
		(fill yes)
		(layer "F.Cu")
		(net "GND")
	)
	(gr_poly
		(pts
			(arc
				(start 81.821528 -371.49913)
				(mid 81.557876 -371.49913)
				(end 81.821528 -371.49913)
			)
		)
		(stroke
			(width 0)
			(type solid)
		)
		(fill yes)
		(layer "F.Cu")
		(net "GND")
	)
	(gr_poly
		(pts
			(arc
				(start 82.304128 -373.96293)
				(mid 82.040476 -373.96293)
				(end 82.304128 -373.96293)
			)
		)
		(stroke
			(width 0)
			(type solid)
		)
		(fill yes)
		(layer "F.Cu")
		(net "GND")
	)
	(gr_poly
		(pts
			(arc
				(start 82.306668 -372.15953)
				(mid 82.043016 -372.15953)
				(end 82.306668 -372.15953)
			)
		)
		(stroke
			(width 0)
			(type solid)
		)
		(fill yes)
		(layer "F.Cu")
		(net "GND")
	)
	(gr_poly
		(pts
			(arc
				(start 82.306668 -370.83873)
				(mid 82.043016 -370.83873)
				(end 82.306668 -370.83873)
			)
		)
		(stroke
			(width 0)
			(type solid)
		)
		(fill yes)
		(layer "F.Cu")
		(net "GND")
	)
	(gr_poly
		(pts
			(arc
				(start 83.520788 -372.15953)
				(mid 83.257136 -372.15953)
				(end 83.520788 -372.15953)
			)
		)
		(stroke
			(width 0)
			(type solid)
		)
		(fill yes)
		(layer "F.Cu")
		(net "GND")
	)
	(gr_poly
		(pts
			(arc
				(start 83.520788 -370.83873)
				(mid 83.257136 -370.83873)
				(end 83.520788 -370.83873)
			)
		)
		(stroke
			(width 0)
			(type solid)
		)
		(fill yes)
		(layer "F.Cu")
		(net "GND")
	)
	(gr_poly
		(pts
			(arc
				(start 83.523328 -373.96293)
				(mid 83.259676 -373.96293)
				(end 83.523328 -373.96293)
			)
		)
		(stroke
			(width 0)
			(type solid)
		)
		(fill yes)
		(layer "F.Cu")
		(net "GND")
	)
	(gr_poly
		(pts
			(arc
				(start 83.523328 -369.03533)
				(mid 83.259676 -369.03533)
				(end 83.523328 -369.03533)
			)
		)
		(stroke
			(width 0)
			(type solid)
		)
		(fill yes)
		(layer "F.Cu")
		(net "GND")
	)
	(gr_poly
		(pts
			(arc
				(start 84.005928 -371.49913)
				(mid 83.742276 -371.49913)
				(end 84.005928 -371.49913)
			)
		)
		(stroke
			(width 0)
			(type solid)
		)
		(fill yes)
		(layer "F.Cu")
		(net "GND")
	)
	(gr_poly
		(pts
			(arc
				(start 84.008468 -369.69573)
				(mid 83.744816 -369.69573)
				(end 84.008468 -369.69573)
			)
		)
		(stroke
			(width 0)
			(type solid)
		)
		(fill yes)
		(layer "F.Cu")
		(net "GND")
	)
	(gr_poly
		(pts
			(arc
				(start 84.008468 -368.37493)
				(mid 83.744816 -368.37493)
				(end 84.008468 -368.37493)
			)
		)
		(stroke
			(width 0)
			(type solid)
		)
		(fill yes)
		(layer "F.Cu")
		(net "GND")
	)
	(gr_poly
		(pts
			(arc
				(start 85.222588 -369.69573)
				(mid 84.958936 -369.69573)
				(end 85.222588 -369.69573)
			)
		)
		(stroke
			(width 0)
			(type solid)
		)
		(fill yes)
		(layer "F.Cu")
		(net "GND")
	)
	(gr_poly
		(pts
			(arc
				(start 85.222588 -368.37493)
				(mid 84.958936 -368.37493)
				(end 85.222588 -368.37493)
			)
		)
		(stroke
			(width 0)
			(type solid)
		)
		(fill yes)
		(layer "F.Cu")
		(net "GND")
	)
	(gr_poly
		(pts
			(arc
				(start 85.707728 -369.03533)
				(mid 85.444076 -369.03533)
				(end 85.707728 -369.03533)
			)
		)
		(stroke
			(width 0)
			(type solid)
		)
		(fill yes)
		(layer "F.Cu")
		(net "GND")
	)
	(gr_poly
		(pts
			(arc
				(start 86.926928 -373.96293)
				(mid 86.663276 -373.96293)
				(end 86.926928 -373.96293)
			)
		)
		(stroke
			(width 0)
			(type solid)
		)
		(fill yes)
		(layer "F.Cu")
		(net "GND")
	)
	(gr_poly
		(pts
			(arc
				(start 87.412068 -374.62333)
				(mid 87.148416 -374.62333)
				(end 87.412068 -374.62333)
			)
		)
		(stroke
			(width 0)
			(type solid)
		)
		(fill yes)
		(layer "F.Cu")
		(net "GND")
	)
	(gr_poly
		(pts
			(arc
				(start 87.412068 -373.30253)
				(mid 87.148416 -373.30253)
				(end 87.412068 -373.30253)
			)
		)
		(stroke
			(width 0)
			(type solid)
		)
		(fill yes)
		(layer "F.Cu")
		(net "GND")
	)
	(gr_poly
		(pts
			(arc
				(start 88.626188 -374.62333)
				(mid 88.362536 -374.62333)
				(end 88.626188 -374.62333)
			)
		)
		(stroke
			(width 0)
			(type solid)
		)
		(fill yes)
		(layer "F.Cu")
		(net "GND")
	)
	(gr_poly
		(pts
			(arc
				(start 88.626188 -373.30253)
				(mid 88.362536 -373.30253)
				(end 88.626188 -373.30253)
			)
		)
		(stroke
			(width 0)
			(type solid)
		)
		(fill yes)
		(layer "F.Cu")
		(net "GND")
	)
	(gr_poly
		(pts
			(arc
				(start 88.628728 -371.49913)
				(mid 88.365076 -371.49913)
				(end 88.628728 -371.49913)
			)
		)
		(stroke
			(width 0)
			(type solid)
		)
		(fill yes)
		(layer "F.Cu")
		(net "GND")
	)
	(gr_poly
		(pts
			(arc
				(start 89.111328 -373.96293)
				(mid 88.847676 -373.96293)
				(end 89.111328 -373.96293)
			)
		)
		(stroke
			(width 0)
			(type solid)
		)
		(fill yes)
		(layer "F.Cu")
		(net "GND")
	)
	(gr_poly
		(pts
			(arc
				(start 89.113868 -372.15953)
				(mid 88.850216 -372.15953)
				(end 89.113868 -372.15953)
			)
		)
		(stroke
			(width 0)
			(type solid)
		)
		(fill yes)
		(layer "F.Cu")
		(net "GND")
	)
	(gr_poly
		(pts
			(arc
				(start 89.113868 -370.83873)
				(mid 88.850216 -370.83873)
				(end 89.113868 -370.83873)
			)
		)
		(stroke
			(width 0)
			(type solid)
		)
		(fill yes)
		(layer "F.Cu")
		(net "GND")
	)
	(gr_poly
		(pts
			(arc
				(start 90.327988 -372.15953)
				(mid 90.064336 -372.15953)
				(end 90.327988 -372.15953)
			)
		)
		(stroke
			(width 0)
			(type solid)
		)
		(fill yes)
		(layer "F.Cu")
		(net "GND")
	)
	(gr_poly
		(pts
			(arc
				(start 90.327988 -370.83873)
				(mid 90.064336 -370.83873)
				(end 90.327988 -370.83873)
			)
		)
		(stroke
			(width 0)
			(type solid)
		)
		(fill yes)
		(layer "F.Cu")
		(net "GND")
	)
	(gr_poly
		(pts
			(arc
				(start 90.330528 -369.03533)
				(mid 90.066876 -369.03533)
				(end 90.330528 -369.03533)
			)
		)
		(stroke
			(width 0)
			(type solid)
		)
		(fill yes)
		(layer "F.Cu")
		(net "GND")
	)
	(gr_poly
		(pts
			(arc
				(start 90.813128 -371.49913)
				(mid 90.549476 -371.49913)
				(end 90.813128 -371.49913)
			)
		)
		(stroke
			(width 0)
			(type solid)
		)
		(fill yes)
		(layer "F.Cu")
		(net "GND")
	)
	(gr_poly
		(pts
			(arc
				(start 90.815668 -369.69573)
				(mid 90.552016 -369.69573)
				(end 90.815668 -369.69573)
			)
		)
		(stroke
			(width 0)
			(type solid)
		)
		(fill yes)
		(layer "F.Cu")
		(net "GND")
	)
	(gr_poly
		(pts
			(arc
				(start 90.815668 -368.37493)
				(mid 90.552016 -368.37493)
				(end 90.815668 -368.37493)
			)
		)
		(stroke
			(width 0)
			(type solid)
		)
		(fill yes)
		(layer "F.Cu")
		(net "GND")
	)
	(gr_poly
		(pts
			(arc
				(start 92.029788 -369.69573)
				(mid 91.766136 -369.69573)
				(end 92.029788 -369.69573)
			)
		)
		(stroke
			(width 0)
			(type solid)
		)
		(fill yes)
		(layer "F.Cu")
		(net "GND")
	)
	(gr_poly
		(pts
			(arc
				(start 92.029788 -368.37493)
				(mid 91.766136 -368.37493)
				(end 92.029788 -368.37493)
			)
		)
		(stroke
			(width 0)
			(type solid)
		)
		(fill yes)
		(layer "F.Cu")
		(net "GND")
	)
	(gr_poly
		(pts
			(arc
				(start 92.514928 -369.03533)
				(mid 92.251276 -369.03533)
				(end 92.514928 -369.03533)
			)
		)
		(stroke
			(width 0)
			(type solid)
		)
		(fill yes)
		(layer "F.Cu")
		(net "GND")
	)
	(gr_poly
		(pts
			(arc
				(start 93.734128 -373.96293)
				(mid 93.470476 -373.96293)
				(end 93.734128 -373.96293)
			)
		)
		(stroke
			(width 0)
			(type solid)
		)
		(fill yes)
		(layer "F.Cu")
		(net "GND")
	)
	(gr_poly
		(pts
			(arc
				(start 94.219268 -374.62333)
				(mid 93.955616 -374.62333)
				(end 94.219268 -374.62333)
			)
		)
		(stroke
			(width 0)
			(type solid)
		)
		(fill yes)
		(layer "F.Cu")
		(net "GND")
	)
	(gr_poly
		(pts
			(arc
				(start 94.219268 -373.30253)
				(mid 93.955616 -373.30253)
				(end 94.219268 -373.30253)
			)
		)
		(stroke
			(width 0)
			(type solid)
		)
		(fill yes)
		(layer "F.Cu")
		(net "GND")
	)
	(gr_poly
		(pts
			(arc
				(start 94.70644 -427.554136)
				(mid 94.44736 -427.554136)
				(end 94.70644 -427.554136)
			)
		)
		(stroke
			(width 0)
			(type solid)
		)
		(fill yes)
		(layer "F.Cu")
		(net "GND")
	)
	(gr_poly
		(pts
			(arc
				(start 95.433388 -374.62333)
				(mid 95.169736 -374.62333)
				(end 95.433388 -374.62333)
			)
		)
		(stroke
			(width 0)
			(type solid)
		)
		(fill yes)
		(layer "F.Cu")
		(net "GND")
	)
	(gr_poly
		(pts
			(arc
				(start 95.433388 -373.30253)
				(mid 95.169736 -373.30253)
				(end 95.433388 -373.30253)
			)
		)
		(stroke
			(width 0)
			(type solid)
		)
		(fill yes)
		(layer "F.Cu")
		(net "GND")
	)
	(gr_poly
		(pts
			(arc
				(start 95.435928 -371.49913)
				(mid 95.172276 -371.49913)
				(end 95.435928 -371.49913)
			)
		)
		(stroke
			(width 0)
			(type solid)
		)
		(fill yes)
		(layer "F.Cu")
		(net "GND")
	)
	(gr_poly
		(pts
			(arc
				(start 95.918528 -373.96293)
				(mid 95.654876 -373.96293)
				(end 95.918528 -373.96293)
			)
		)
		(stroke
			(width 0)
			(type solid)
		)
		(fill yes)
		(layer "F.Cu")
		(net "GND")
	)
	(gr_poly
		(pts
			(arc
				(start 95.921068 -372.15953)
				(mid 95.657416 -372.15953)
				(end 95.921068 -372.15953)
			)
		)
		(stroke
			(width 0)
			(type solid)
		)
		(fill yes)
		(layer "F.Cu")
		(net "GND")
	)
	(gr_poly
		(pts
			(arc
				(start 95.921068 -370.83873)
				(mid 95.657416 -370.83873)
				(end 95.921068 -370.83873)
			)
		)
		(stroke
			(width 0)
			(type solid)
		)
		(fill yes)
		(layer "F.Cu")
		(net "GND")
	)
	(gr_poly
		(pts
			(arc
				(start 97.135188 -372.15953)
				(mid 96.871536 -372.15953)
				(end 97.135188 -372.15953)
			)
		)
		(stroke
			(width 0)
			(type solid)
		)
		(fill yes)
		(layer "F.Cu")
		(net "GND")
	)
	(gr_poly
		(pts
			(arc
				(start 97.135188 -370.83873)
				(mid 96.871536 -370.83873)
				(end 97.135188 -370.83873)
			)
		)
		(stroke
			(width 0)
			(type solid)
		)
		(fill yes)
		(layer "F.Cu")
		(net "GND")
	)
	(gr_poly
		(pts
			(arc
				(start 97.137728 -369.03533)
				(mid 96.874076 -369.03533)
				(end 97.137728 -369.03533)
			)
		)
		(stroke
			(width 0)
			(type solid)
		)
		(fill yes)
		(layer "F.Cu")
		(net "GND")
	)
	(gr_poly
		(pts
			(arc
				(start 97.620328 -371.49913)
				(mid 97.356676 -371.49913)
				(end 97.620328 -371.49913)
			)
		)
		(stroke
			(width 0)
			(type solid)
		)
		(fill yes)
		(layer "F.Cu")
		(net "GND")
	)
	(gr_poly
		(pts
			(arc
				(start 97.622868 -369.69573)
				(mid 97.359216 -369.69573)
				(end 97.622868 -369.69573)
			)
		)
		(stroke
			(width 0)
			(type solid)
		)
		(fill yes)
		(layer "F.Cu")
		(net "GND")
	)
	(gr_poly
		(pts
			(arc
				(start 97.622868 -368.37493)
				(mid 97.359216 -368.37493)
				(end 97.622868 -368.37493)
			)
		)
		(stroke
			(width 0)
			(type solid)
		)
		(fill yes)
		(layer "F.Cu")
		(net "GND")
	)
	(gr_poly
		(pts
			(arc
				(start 98.51009 -413.311848)
				(mid 98.25101 -413.311848)
				(end 98.51009 -413.311848)
			)
		)
		(stroke
			(width 0)
			(type solid)
		)
		(fill yes)
		(layer "F.Cu")
		(net "GND")
	)
	(gr_poly
		(pts
			(arc
				(start 98.836988 -369.69573)
				(mid 98.573336 -369.69573)
				(end 98.836988 -369.69573)
			)
		)
		(stroke
			(width 0)
			(type solid)
		)
		(fill yes)
		(layer "F.Cu")
		(net "GND")
	)
	(gr_poly
		(pts
			(arc
				(start 98.836988 -368.37493)
				(mid 98.573336 -368.37493)
				(end 98.836988 -368.37493)
			)
		)
		(stroke
			(width 0)
			(type solid)
		)
		(fill yes)
		(layer "F.Cu")
		(net "GND")
	)
	(gr_poly
		(pts
			(arc
				(start 99.322128 -369.03533)
				(mid 99.058476 -369.03533)
				(end 99.322128 -369.03533)
			)
		)
		(stroke
			(width 0)
			(type solid)
		)
		(fill yes)
		(layer "F.Cu")
		(net "GND")
	)
	(gr_poly
		(pts
			(arc
				(start 100.541328 -369.03533)
				(mid 100.277676 -369.03533)
				(end 100.541328 -369.03533)
			)
		)
		(stroke
			(width 0)
			(type solid)
		)
		(fill yes)
		(layer "F.Cu")
		(net "GND")
	)
	(gr_poly
		(pts
			(arc
				(start 101.026468 -369.69573)
				(mid 100.762816 -369.69573)
				(end 101.026468 -369.69573)
			)
		)
		(stroke
			(width 0)
			(type solid)
		)
		(fill yes)
		(layer "F.Cu")
		(net "GND")
	)
	(gr_poly
		(pts
			(arc
				(start 101.026468 -368.37493)
				(mid 100.762816 -368.37493)
				(end 101.026468 -368.37493)
			)
		)
		(stroke
			(width 0)
			(type solid)
		)
		(fill yes)
		(layer "F.Cu")
		(net "GND")
	)
	(gr_poly
		(pts
			(arc
				(start 101.075744 -29.51861)
				(mid 100.816664 -29.51861)
				(end 101.075744 -29.51861)
			)
		)
		(stroke
			(width 0)
			(type solid)
		)
		(fill yes)
		(layer "F.Cu")
		(net "GND")
	)
	(gr_poly
		(pts
			(arc
				(start 101.075744 -28.65501)
				(mid 100.816664 -28.65501)
				(end 101.075744 -28.65501)
			)
		)
		(stroke
			(width 0)
			(type solid)
		)
		(fill yes)
		(layer "F.Cu")
		(net "GND")
	)
	(gr_poly
		(pts
			(arc
				(start 102.240588 -369.69573)
				(mid 101.976936 -369.69573)
				(end 102.240588 -369.69573)
			)
		)
		(stroke
			(width 0)
			(type solid)
		)
		(fill yes)
		(layer "F.Cu")
		(net "GND")
	)
	(gr_poly
		(pts
			(arc
				(start 102.240588 -368.37493)
				(mid 101.976936 -368.37493)
				(end 102.240588 -368.37493)
			)
		)
		(stroke
			(width 0)
			(type solid)
		)
		(fill yes)
		(layer "F.Cu")
		(net "GND")
	)
	(gr_poly
		(pts
			(arc
				(start 102.391464 -32.88411)
				(mid 102.132384 -32.88411)
				(end 102.391464 -32.88411)
			)
		)
		(stroke
			(width 0)
			(type solid)
		)
		(fill yes)
		(layer "F.Cu")
		(net "GND")
	)
	(gr_poly
		(pts
			(arc
				(start 102.391464 -32.02051)
				(mid 102.132384 -32.02051)
				(end 102.391464 -32.02051)
			)
		)
		(stroke
			(width 0)
			(type solid)
		)
		(fill yes)
		(layer "F.Cu")
		(net "GND")
	)
	(gr_poly
		(pts
			(arc
				(start 102.725728 -369.03533)
				(mid 102.462076 -369.03533)
				(end 102.725728 -369.03533)
			)
		)
		(stroke
			(width 0)
			(type solid)
		)
		(fill yes)
		(layer "F.Cu")
		(net "GND")
	)
	(gr_poly
		(pts
			(arc
				(start 103.276908 -380.535688)
				(mid 103.013256 -380.535688)
				(end 103.276908 -380.535688)
			)
		)
		(stroke
			(width 0)
			(type solid)
		)
		(fill yes)
		(layer "F.Cu")
		(net "GND")
	)
	(gr_poly
		(pts
			(arc
				(start 103.276908 -379.321568)
				(mid 103.013256 -379.321568)
				(end 103.276908 -379.321568)
			)
		)
		(stroke
			(width 0)
			(type solid)
		)
		(fill yes)
		(layer "F.Cu")
		(net "GND")
	)
	(gr_poly
		(pts
			(arc
				(start 103.276908 -377.132088)
				(mid 103.013256 -377.132088)
				(end 103.276908 -377.132088)
			)
		)
		(stroke
			(width 0)
			(type solid)
		)
		(fill yes)
		(layer "F.Cu")
		(net "GND")
	)
	(gr_poly
		(pts
			(arc
				(start 103.276908 -375.917968)
				(mid 103.013256 -375.917968)
				(end 103.276908 -375.917968)
			)
		)
		(stroke
			(width 0)
			(type solid)
		)
		(fill yes)
		(layer "F.Cu")
		(net "GND")
	)
	(gr_poly
		(pts
			(arc
				(start 103.937308 -381.020828)
				(mid 103.673656 -381.020828)
				(end 103.937308 -381.020828)
			)
		)
		(stroke
			(width 0)
			(type solid)
		)
		(fill yes)
		(layer "F.Cu")
		(net "GND")
	)
	(gr_poly
		(pts
			(arc
				(start 103.937308 -378.836428)
				(mid 103.673656 -378.836428)
				(end 103.937308 -378.836428)
			)
		)
		(stroke
			(width 0)
			(type solid)
		)
		(fill yes)
		(layer "F.Cu")
		(net "GND")
	)
	(gr_poly
		(pts
			(arc
				(start 103.937308 -377.617228)
				(mid 103.673656 -377.617228)
				(end 103.937308 -377.617228)
			)
		)
		(stroke
			(width 0)
			(type solid)
		)
		(fill yes)
		(layer "F.Cu")
		(net "GND")
	)
	(gr_poly
		(pts
			(arc
				(start 103.937308 -375.432828)
				(mid 103.673656 -375.432828)
				(end 103.937308 -375.432828)
			)
		)
		(stroke
			(width 0)
			(type solid)
		)
		(fill yes)
		(layer "F.Cu")
		(net "GND")
	)
	(gr_poly
		(pts
			(arc
				(start 104.597708 -380.535688)
				(mid 104.334056 -380.535688)
				(end 104.597708 -380.535688)
			)
		)
		(stroke
			(width 0)
			(type solid)
		)
		(fill yes)
		(layer "F.Cu")
		(net "GND")
	)
	(gr_poly
		(pts
			(arc
				(start 104.597708 -379.321568)
				(mid 104.334056 -379.321568)
				(end 104.597708 -379.321568)
			)
		)
		(stroke
			(width 0)
			(type solid)
		)
		(fill yes)
		(layer "F.Cu")
		(net "GND")
	)
	(gr_poly
		(pts
			(arc
				(start 104.597708 -377.132088)
				(mid 104.334056 -377.132088)
				(end 104.597708 -377.132088)
			)
		)
		(stroke
			(width 0)
			(type solid)
		)
		(fill yes)
		(layer "F.Cu")
		(net "GND")
	)
	(gr_poly
		(pts
			(arc
				(start 104.597708 -375.917968)
				(mid 104.334056 -375.917968)
				(end 104.597708 -375.917968)
			)
		)
		(stroke
			(width 0)
			(type solid)
		)
		(fill yes)
		(layer "F.Cu")
		(net "GND")
	)
	(gr_poly
		(pts
			(arc
				(start 105.408984 -31.541466)
				(mid 105.149904 -31.541466)
				(end 105.408984 -31.541466)
			)
		)
		(stroke
			(width 0)
			(type solid)
		)
		(fill yes)
		(layer "F.Cu")
		(net "GND")
	)
	(gr_poly
		(pts
			(arc
				(start 108.00207 -382.54432)
				(mid 107.738418 -382.54432)
				(end 108.00207 -382.54432)
			)
		)
		(stroke
			(width 0)
			(type solid)
		)
		(fill yes)
		(layer "F.Cu")
		(net "GND")
	)
	(gr_poly
		(pts
			(arc
				(start 108.00207 -381.3302)
				(mid 107.738418 -381.3302)
				(end 108.00207 -381.3302)
			)
		)
		(stroke
			(width 0)
			(type solid)
		)
		(fill yes)
		(layer "F.Cu")
		(net "GND")
	)
	(gr_poly
		(pts
			(arc
				(start 108.00207 -377.00712)
				(mid 107.738418 -377.00712)
				(end 108.00207 -377.00712)
			)
		)
		(stroke
			(width 0)
			(type solid)
		)
		(fill yes)
		(layer "F.Cu")
		(net "GND")
	)
	(gr_poly
		(pts
			(arc
				(start 108.00207 -375.793)
				(mid 107.738418 -375.793)
				(end 108.00207 -375.793)
			)
		)
		(stroke
			(width 0)
			(type solid)
		)
		(fill yes)
		(layer "F.Cu")
		(net "GND")
	)
	(gr_poly
		(pts
			(arc
				(start 108.66247 -383.02946)
				(mid 108.398818 -383.02946)
				(end 108.66247 -383.02946)
			)
		)
		(stroke
			(width 0)
			(type solid)
		)
		(fill yes)
		(layer "F.Cu")
		(net "GND")
	)
	(gr_poly
		(pts
			(arc
				(start 108.66247 -380.87046)
				(mid 108.398818 -380.87046)
				(end 108.66247 -380.87046)
			)
		)
		(stroke
			(width 0)
			(type solid)
		)
		(fill yes)
		(layer "F.Cu")
		(net "GND")
	)
	(gr_poly
		(pts
			(arc
				(start 108.66247 -377.49226)
				(mid 108.398818 -377.49226)
				(end 108.66247 -377.49226)
			)
		)
		(stroke
			(width 0)
			(type solid)
		)
		(fill yes)
		(layer "F.Cu")
		(net "GND")
	)
	(gr_poly
		(pts
			(arc
				(start 108.66247 -375.30786)
				(mid 108.398818 -375.30786)
				(end 108.66247 -375.30786)
			)
		)
		(stroke
			(width 0)
			(type solid)
		)
		(fill yes)
		(layer "F.Cu")
		(net "GND")
	)
	(gr_poly
		(pts
			(arc
				(start 108.96854 -419.1)
				(mid 108.70946 -419.1)
				(end 108.96854 -419.1)
			)
		)
		(stroke
			(width 0)
			(type solid)
		)
		(fill yes)
		(layer "F.Cu")
		(net "GND")
	)
	(gr_poly
		(pts
			(arc
				(start 109.32287 -382.54432)
				(mid 109.059218 -382.54432)
				(end 109.32287 -382.54432)
			)
		)
		(stroke
			(width 0)
			(type solid)
		)
		(fill yes)
		(layer "F.Cu")
		(net "GND")
	)
	(gr_poly
		(pts
			(arc
				(start 109.32287 -381.3302)
				(mid 109.059218 -381.3302)
				(end 109.32287 -381.3302)
			)
		)
		(stroke
			(width 0)
			(type solid)
		)
		(fill yes)
		(layer "F.Cu")
		(net "GND")
	)
	(gr_poly
		(pts
			(arc
				(start 109.32287 -377.00712)
				(mid 109.059218 -377.00712)
				(end 109.32287 -377.00712)
			)
		)
		(stroke
			(width 0)
			(type solid)
		)
		(fill yes)
		(layer "F.Cu")
		(net "GND")
	)
	(gr_poly
		(pts
			(arc
				(start 109.32287 -375.793)
				(mid 109.059218 -375.793)
				(end 109.32287 -375.793)
			)
		)
		(stroke
			(width 0)
			(type solid)
		)
		(fill yes)
		(layer "F.Cu")
		(net "GND")
	)
	(gr_poly
		(pts
			(arc
				(start 109.586522 -371.49913)
				(mid 109.32287 -371.49913)
				(end 109.586522 -371.49913)
			)
		)
		(stroke
			(width 0)
			(type solid)
		)
		(fill yes)
		(layer "F.Cu")
		(net "GND")
	)
	(gr_poly
		(pts
			(arc
				(start 110.071662 -372.15953)
				(mid 109.80801 -372.15953)
				(end 110.071662 -372.15953)
			)
		)
		(stroke
			(width 0)
			(type solid)
		)
		(fill yes)
		(layer "F.Cu")
		(net "GND")
	)
	(gr_poly
		(pts
			(arc
				(start 110.071662 -370.83873)
				(mid 109.80801 -370.83873)
				(end 110.071662 -370.83873)
			)
		)
		(stroke
			(width 0)
			(type solid)
		)
		(fill yes)
		(layer "F.Cu")
		(net "GND")
	)
	(gr_poly
		(pts
			(arc
				(start 111.285782 -372.15953)
				(mid 111.02213 -372.15953)
				(end 111.285782 -372.15953)
			)
		)
		(stroke
			(width 0)
			(type solid)
		)
		(fill yes)
		(layer "F.Cu")
		(net "GND")
	)
	(gr_poly
		(pts
			(arc
				(start 111.285782 -370.83873)
				(mid 111.02213 -370.83873)
				(end 111.285782 -370.83873)
			)
		)
		(stroke
			(width 0)
			(type solid)
		)
		(fill yes)
		(layer "F.Cu")
		(net "GND")
	)
	(gr_poly
		(pts
			(arc
				(start 111.288322 -369.03533)
				(mid 111.02467 -369.03533)
				(end 111.288322 -369.03533)
			)
		)
		(stroke
			(width 0)
			(type solid)
		)
		(fill yes)
		(layer "F.Cu")
		(net "GND")
	)
	(gr_poly
		(pts
			(arc
				(start 111.770922 -371.49913)
				(mid 111.50727 -371.49913)
				(end 111.770922 -371.49913)
			)
		)
		(stroke
			(width 0)
			(type solid)
		)
		(fill yes)
		(layer "F.Cu")
		(net "GND")
	)
	(gr_poly
		(pts
			(arc
				(start 111.773462 -369.69573)
				(mid 111.50981 -369.69573)
				(end 111.773462 -369.69573)
			)
		)
		(stroke
			(width 0)
			(type solid)
		)
		(fill yes)
		(layer "F.Cu")
		(net "GND")
	)
	(gr_poly
		(pts
			(arc
				(start 111.773462 -368.37493)
				(mid 111.50981 -368.37493)
				(end 111.773462 -368.37493)
			)
		)
		(stroke
			(width 0)
			(type solid)
		)
		(fill yes)
		(layer "F.Cu")
		(net "GND")
	)
	(gr_poly
		(pts
			(arc
				(start 112.22482 -78.78318)
				(mid 111.96574 -78.78318)
				(end 112.22482 -78.78318)
			)
		)
		(stroke
			(width 0)
			(type solid)
		)
		(fill yes)
		(layer "F.Cu")
		(net "GND")
	)
	(gr_poly
		(pts
			(arc
				(start 112.22482 -77.25918)
				(mid 111.96574 -77.25918)
				(end 112.22482 -77.25918)
			)
		)
		(stroke
			(width 0)
			(type solid)
		)
		(fill yes)
		(layer "F.Cu")
		(net "GND")
	)
	(gr_poly
		(pts
			(arc
				(start 112.22482 -75.73518)
				(mid 111.96574 -75.73518)
				(end 112.22482 -75.73518)
			)
		)
		(stroke
			(width 0)
			(type solid)
		)
		(fill yes)
		(layer "F.Cu")
		(net "GND")
	)
	(gr_poly
		(pts
			(arc
				(start 112.655096 -23.465536)
				(mid 112.396016 -23.465536)
				(end 112.655096 -23.465536)
			)
		)
		(stroke
			(width 0)
			(type solid)
		)
		(fill yes)
		(layer "F.Cu")
		(net "GND")
	)
	(gr_poly
		(pts
			(arc
				(start 112.987582 -369.69573)
				(mid 112.72393 -369.69573)
				(end 112.987582 -369.69573)
			)
		)
		(stroke
			(width 0)
			(type solid)
		)
		(fill yes)
		(layer "F.Cu")
		(net "GND")
	)
	(gr_poly
		(pts
			(arc
				(start 112.987582 -368.37493)
				(mid 112.72393 -368.37493)
				(end 112.987582 -368.37493)
			)
		)
		(stroke
			(width 0)
			(type solid)
		)
		(fill yes)
		(layer "F.Cu")
		(net "GND")
	)
	(gr_poly
		(pts
			(arc
				(start 113.412778 -43.358054)
				(mid 113.153698 -43.358054)
				(end 113.412778 -43.358054)
			)
		)
		(stroke
			(width 0)
			(type solid)
		)
		(fill yes)
		(layer "F.Cu")
		(net "GND")
	)
	(gr_poly
		(pts
			(arc
				(start 113.472722 -369.03533)
				(mid 113.20907 -369.03533)
				(end 113.472722 -369.03533)
			)
		)
		(stroke
			(width 0)
			(type solid)
		)
		(fill yes)
		(layer "F.Cu")
		(net "GND")
	)
	(gr_poly
		(pts
			(arc
				(start 114.455448 -22.100794)
				(mid 114.196368 -22.100794)
				(end 114.455448 -22.100794)
			)
		)
		(stroke
			(width 0)
			(type solid)
		)
		(fill yes)
		(layer "F.Cu")
		(net "GND")
	)
	(gr_poly
		(pts
			(arc
				(start 114.534696 -23.465536)
				(mid 114.275616 -23.465536)
				(end 114.534696 -23.465536)
			)
		)
		(stroke
			(width 0)
			(type solid)
		)
		(fill yes)
		(layer "F.Cu")
		(net "GND")
	)
	(gr_poly
		(pts
			(arc
				(start 114.691922 -373.96293)
				(mid 114.42827 -373.96293)
				(end 114.691922 -373.96293)
			)
		)
		(stroke
			(width 0)
			(type solid)
		)
		(fill yes)
		(layer "F.Cu")
		(net "GND")
	)
	(gr_poly
		(pts
			(arc
				(start 115.177062 -374.62333)
				(mid 114.91341 -374.62333)
				(end 115.177062 -374.62333)
			)
		)
		(stroke
			(width 0)
			(type solid)
		)
		(fill yes)
		(layer "F.Cu")
		(net "GND")
	)
	(gr_poly
		(pts
			(arc
				(start 115.177062 -373.30253)
				(mid 114.91341 -373.30253)
				(end 115.177062 -373.30253)
			)
		)
		(stroke
			(width 0)
			(type solid)
		)
		(fill yes)
		(layer "F.Cu")
		(net "GND")
	)
	(gr_poly
		(pts
			(arc
				(start 116.221764 -23.647654)
				(mid 115.962684 -23.647654)
				(end 116.221764 -23.647654)
			)
		)
		(stroke
			(width 0)
			(type solid)
		)
		(fill yes)
		(layer "F.Cu")
		(net "GND")
	)
	(gr_poly
		(pts
			(arc
				(start 116.335048 -22.100794)
				(mid 116.075968 -22.100794)
				(end 116.335048 -22.100794)
			)
		)
		(stroke
			(width 0)
			(type solid)
		)
		(fill yes)
		(layer "F.Cu")
		(net "GND")
	)
	(gr_poly
		(pts
			(arc
				(start 116.391182 -374.62333)
				(mid 116.12753 -374.62333)
				(end 116.391182 -374.62333)
			)
		)
		(stroke
			(width 0)
			(type solid)
		)
		(fill yes)
		(layer "F.Cu")
		(net "GND")
	)
	(gr_poly
		(pts
			(arc
				(start 116.391182 -373.30253)
				(mid 116.12753 -373.30253)
				(end 116.391182 -373.30253)
			)
		)
		(stroke
			(width 0)
			(type solid)
		)
		(fill yes)
		(layer "F.Cu")
		(net "GND")
	)
	(gr_poly
		(pts
			(arc
				(start 116.393722 -371.49913)
				(mid 116.13007 -371.49913)
				(end 116.393722 -371.49913)
			)
		)
		(stroke
			(width 0)
			(type solid)
		)
		(fill yes)
		(layer "F.Cu")
		(net "GND")
	)
	(gr_poly
		(pts
			(arc
				(start 116.876322 -373.96293)
				(mid 116.61267 -373.96293)
				(end 116.876322 -373.96293)
			)
		)
		(stroke
			(width 0)
			(type solid)
		)
		(fill yes)
		(layer "F.Cu")
		(net "GND")
	)
	(gr_poly
		(pts
			(arc
				(start 116.878862 -372.15953)
				(mid 116.61521 -372.15953)
				(end 116.878862 -372.15953)
			)
		)
		(stroke
			(width 0)
			(type solid)
		)
		(fill yes)
		(layer "F.Cu")
		(net "GND")
	)
	(gr_poly
		(pts
			(arc
				(start 116.878862 -370.83873)
				(mid 116.61521 -370.83873)
				(end 116.878862 -370.83873)
			)
		)
		(stroke
			(width 0)
			(type solid)
		)
		(fill yes)
		(layer "F.Cu")
		(net "GND")
	)
	(gr_poly
		(pts
			(arc
				(start 117.998494 -57.098946)
				(mid 117.739414 -57.098946)
				(end 117.998494 -57.098946)
			)
		)
		(stroke
			(width 0)
			(type solid)
		)
		(fill yes)
		(layer "F.Cu")
		(net "GND")
	)
	(gr_poly
		(pts
			(arc
				(start 118.092982 -372.15953)
				(mid 117.82933 -372.15953)
				(end 118.092982 -372.15953)
			)
		)
		(stroke
			(width 0)
			(type solid)
		)
		(fill yes)
		(layer "F.Cu")
		(net "GND")
	)
	(gr_poly
		(pts
			(arc
				(start 118.092982 -370.83873)
				(mid 117.82933 -370.83873)
				(end 118.092982 -370.83873)
			)
		)
		(stroke
			(width 0)
			(type solid)
		)
		(fill yes)
		(layer "F.Cu")
		(net "GND")
	)
	(gr_poly
		(pts
			(arc
				(start 118.095522 -369.03533)
				(mid 117.83187 -369.03533)
				(end 118.095522 -369.03533)
			)
		)
		(stroke
			(width 0)
			(type solid)
		)
		(fill yes)
		(layer "F.Cu")
		(net "GND")
	)
	(gr_poly
		(pts
			(arc
				(start 118.101364 -23.647654)
				(mid 117.842284 -23.647654)
				(end 118.101364 -23.647654)
			)
		)
		(stroke
			(width 0)
			(type solid)
		)
		(fill yes)
		(layer "F.Cu")
		(net "GND")
	)
	(gr_poly
		(pts
			(arc
				(start 118.171976 -439.551572)
				(mid 117.912896 -439.551572)
				(end 118.171976 -439.551572)
			)
		)
		(stroke
			(width 0)
			(type solid)
		)
		(fill yes)
		(layer "F.Cu")
		(net "GND")
	)
	(gr_poly
		(pts
			(arc
				(start 118.503954 -422.887902)
				(mid 118.244874 -422.887902)
				(end 118.503954 -422.887902)
			)
		)
		(stroke
			(width 0)
			(type solid)
		)
		(fill yes)
		(layer "F.Cu")
		(net "GND")
	)
	(gr_poly
		(pts
			(arc
				(start 118.578122 -371.49913)
				(mid 118.31447 -371.49913)
				(end 118.578122 -371.49913)
			)
		)
		(stroke
			(width 0)
			(type solid)
		)
		(fill yes)
		(layer "F.Cu")
		(net "GND")
	)
	(gr_poly
		(pts
			(arc
				(start 118.580662 -369.69573)
				(mid 118.31701 -369.69573)
				(end 118.580662 -369.69573)
			)
		)
		(stroke
			(width 0)
			(type solid)
		)
		(fill yes)
		(layer "F.Cu")
		(net "GND")
	)
	(gr_poly
		(pts
			(arc
				(start 118.580662 -368.37493)
				(mid 118.31701 -368.37493)
				(end 118.580662 -368.37493)
			)
		)
		(stroke
			(width 0)
			(type solid)
		)
		(fill yes)
		(layer "F.Cu")
		(net "GND")
	)
	(gr_poly
		(pts
			(arc
				(start 119.794782 -369.69573)
				(mid 119.53113 -369.69573)
				(end 119.794782 -369.69573)
			)
		)
		(stroke
			(width 0)
			(type solid)
		)
		(fill yes)
		(layer "F.Cu")
		(net "GND")
	)
	(gr_poly
		(pts
			(arc
				(start 119.794782 -368.37493)
				(mid 119.53113 -368.37493)
				(end 119.794782 -368.37493)
			)
		)
		(stroke
			(width 0)
			(type solid)
		)
		(fill yes)
		(layer "F.Cu")
		(net "GND")
	)
	(gr_poly
		(pts
			(arc
				(start 120.279922 -369.03533)
				(mid 120.01627 -369.03533)
				(end 120.279922 -369.03533)
			)
		)
		(stroke
			(width 0)
			(type solid)
		)
		(fill yes)
		(layer "F.Cu")
		(net "GND")
	)
	(gr_poly
		(pts
			(arc
				(start 121.499122 -373.96293)
				(mid 121.23547 -373.96293)
				(end 121.499122 -373.96293)
			)
		)
		(stroke
			(width 0)
			(type solid)
		)
		(fill yes)
		(layer "F.Cu")
		(net "GND")
	)
	(gr_poly
		(pts
			(arc
				(start 121.984262 -374.62333)
				(mid 121.72061 -374.62333)
				(end 121.984262 -374.62333)
			)
		)
		(stroke
			(width 0)
			(type solid)
		)
		(fill yes)
		(layer "F.Cu")
		(net "GND")
	)
	(gr_poly
		(pts
			(arc
				(start 121.984262 -373.30253)
				(mid 121.72061 -373.30253)
				(end 121.984262 -373.30253)
			)
		)
		(stroke
			(width 0)
			(type solid)
		)
		(fill yes)
		(layer "F.Cu")
		(net "GND")
	)
	(gr_poly
		(pts
			(arc
				(start 123.198382 -374.62333)
				(mid 122.93473 -374.62333)
				(end 123.198382 -374.62333)
			)
		)
		(stroke
			(width 0)
			(type solid)
		)
		(fill yes)
		(layer "F.Cu")
		(net "GND")
	)
	(gr_poly
		(pts
			(arc
				(start 123.198382 -373.30253)
				(mid 122.93473 -373.30253)
				(end 123.198382 -373.30253)
			)
		)
		(stroke
			(width 0)
			(type solid)
		)
		(fill yes)
		(layer "F.Cu")
		(net "GND")
	)
	(gr_poly
		(pts
			(arc
				(start 123.200922 -371.49913)
				(mid 122.93727 -371.49913)
				(end 123.200922 -371.49913)
			)
		)
		(stroke
			(width 0)
			(type solid)
		)
		(fill yes)
		(layer "F.Cu")
		(net "GND")
	)
	(gr_poly
		(pts
			(arc
				(start 123.683522 -373.96293)
				(mid 123.41987 -373.96293)
				(end 123.683522 -373.96293)
			)
		)
		(stroke
			(width 0)
			(type solid)
		)
		(fill yes)
		(layer "F.Cu")
		(net "GND")
	)
	(gr_poly
		(pts
			(arc
				(start 123.686062 -372.15953)
				(mid 123.42241 -372.15953)
				(end 123.686062 -372.15953)
			)
		)
		(stroke
			(width 0)
			(type solid)
		)
		(fill yes)
		(layer "F.Cu")
		(net "GND")
	)
	(gr_poly
		(pts
			(arc
				(start 123.686062 -370.83873)
				(mid 123.42241 -370.83873)
				(end 123.686062 -370.83873)
			)
		)
		(stroke
			(width 0)
			(type solid)
		)
		(fill yes)
		(layer "F.Cu")
		(net "GND")
	)
	(gr_poly
		(pts
			(arc
				(start 124.900182 -372.15953)
				(mid 124.63653 -372.15953)
				(end 124.900182 -372.15953)
			)
		)
		(stroke
			(width 0)
			(type solid)
		)
		(fill yes)
		(layer "F.Cu")
		(net "GND")
	)
	(gr_poly
		(pts
			(arc
				(start 124.900182 -370.83873)
				(mid 124.63653 -370.83873)
				(end 124.900182 -370.83873)
			)
		)
		(stroke
			(width 0)
			(type solid)
		)
		(fill yes)
		(layer "F.Cu")
		(net "GND")
	)
	(gr_poly
		(pts
			(arc
				(start 124.902722 -369.03533)
				(mid 124.63907 -369.03533)
				(end 124.902722 -369.03533)
			)
		)
		(stroke
			(width 0)
			(type solid)
		)
		(fill yes)
		(layer "F.Cu")
		(net "GND")
	)
	(gr_poly
		(pts
			(arc
				(start 125.385322 -371.49913)
				(mid 125.12167 -371.49913)
				(end 125.385322 -371.49913)
			)
		)
		(stroke
			(width 0)
			(type solid)
		)
		(fill yes)
		(layer "F.Cu")
		(net "GND")
	)
	(gr_poly
		(pts
			(arc
				(start 125.387862 -369.69573)
				(mid 125.12421 -369.69573)
				(end 125.387862 -369.69573)
			)
		)
		(stroke
			(width 0)
			(type solid)
		)
		(fill yes)
		(layer "F.Cu")
		(net "GND")
	)
	(gr_poly
		(pts
			(arc
				(start 125.387862 -368.37493)
				(mid 125.12421 -368.37493)
				(end 125.387862 -368.37493)
			)
		)
		(stroke
			(width 0)
			(type solid)
		)
		(fill yes)
		(layer "F.Cu")
		(net "GND")
	)
	(gr_poly
		(pts
			(arc
				(start 126.601982 -369.69573)
				(mid 126.33833 -369.69573)
				(end 126.601982 -369.69573)
			)
		)
		(stroke
			(width 0)
			(type solid)
		)
		(fill yes)
		(layer "F.Cu")
		(net "GND")
	)
	(gr_poly
		(pts
			(arc
				(start 126.601982 -368.37493)
				(mid 126.33833 -368.37493)
				(end 126.601982 -368.37493)
			)
		)
		(stroke
			(width 0)
			(type solid)
		)
		(fill yes)
		(layer "F.Cu")
		(net "GND")
	)
	(gr_poly
		(pts
			(arc
				(start 127.087122 -369.03533)
				(mid 126.82347 -369.03533)
				(end 127.087122 -369.03533)
			)
		)
		(stroke
			(width 0)
			(type solid)
		)
		(fill yes)
		(layer "F.Cu")
		(net "GND")
	)
	(gr_poly
		(pts
			(arc
				(start 128.306322 -373.96293)
				(mid 128.04267 -373.96293)
				(end 128.306322 -373.96293)
			)
		)
		(stroke
			(width 0)
			(type solid)
		)
		(fill yes)
		(layer "F.Cu")
		(net "GND")
	)
	(gr_poly
		(pts
			(arc
				(start 128.719834 -219.795852)
				(mid 128.460754 -219.795852)
				(end 128.719834 -219.795852)
			)
		)
		(stroke
			(width 0)
			(type solid)
		)
		(fill yes)
		(layer "F.Cu")
		(net "GND")
	)
	(gr_poly
		(pts
			(arc
				(start 128.791462 -374.62333)
				(mid 128.52781 -374.62333)
				(end 128.791462 -374.62333)
			)
		)
		(stroke
			(width 0)
			(type solid)
		)
		(fill yes)
		(layer "F.Cu")
		(net "GND")
	)
	(gr_poly
		(pts
			(arc
				(start 128.791462 -373.30253)
				(mid 128.52781 -373.30253)
				(end 128.791462 -373.30253)
			)
		)
		(stroke
			(width 0)
			(type solid)
		)
		(fill yes)
		(layer "F.Cu")
		(net "GND")
	)
	(gr_poly
		(pts
			(arc
				(start 130.005582 -374.62333)
				(mid 129.74193 -374.62333)
				(end 130.005582 -374.62333)
			)
		)
		(stroke
			(width 0)
			(type solid)
		)
		(fill yes)
		(layer "F.Cu")
		(net "GND")
	)
	(gr_poly
		(pts
			(arc
				(start 130.005582 -373.30253)
				(mid 129.74193 -373.30253)
				(end 130.005582 -373.30253)
			)
		)
		(stroke
			(width 0)
			(type solid)
		)
		(fill yes)
		(layer "F.Cu")
		(net "GND")
	)
	(gr_poly
		(pts
			(arc
				(start 130.008122 -371.49913)
				(mid 129.74447 -371.49913)
				(end 130.008122 -371.49913)
			)
		)
		(stroke
			(width 0)
			(type solid)
		)
		(fill yes)
		(layer "F.Cu")
		(net "GND")
	)
	(gr_poly
		(pts
			(arc
				(start 130.490722 -373.96293)
				(mid 130.22707 -373.96293)
				(end 130.490722 -373.96293)
			)
		)
		(stroke
			(width 0)
			(type solid)
		)
		(fill yes)
		(layer "F.Cu")
		(net "GND")
	)
	(gr_poly
		(pts
			(arc
				(start 130.493262 -372.15953)
				(mid 130.22961 -372.15953)
				(end 130.493262 -372.15953)
			)
		)
		(stroke
			(width 0)
			(type solid)
		)
		(fill yes)
		(layer "F.Cu")
		(net "GND")
	)
	(gr_poly
		(pts
			(arc
				(start 130.493262 -370.83873)
				(mid 130.22961 -370.83873)
				(end 130.493262 -370.83873)
			)
		)
		(stroke
			(width 0)
			(type solid)
		)
		(fill yes)
		(layer "F.Cu")
		(net "GND")
	)
	(gr_poly
		(pts
			(arc
				(start 131.338828 -219.793058)
				(mid 131.079748 -219.793058)
				(end 131.338828 -219.793058)
			)
		)
		(stroke
			(width 0)
			(type solid)
		)
		(fill yes)
		(layer "F.Cu")
		(net "GND")
	)
	(gr_poly
		(pts
			(arc
				(start 131.707382 -372.15953)
				(mid 131.44373 -372.15953)
				(end 131.707382 -372.15953)
			)
		)
		(stroke
			(width 0)
			(type solid)
		)
		(fill yes)
		(layer "F.Cu")
		(net "GND")
	)
	(gr_poly
		(pts
			(arc
				(start 131.707382 -370.83873)
				(mid 131.44373 -370.83873)
				(end 131.707382 -370.83873)
			)
		)
		(stroke
			(width 0)
			(type solid)
		)
		(fill yes)
		(layer "F.Cu")
		(net "GND")
	)
	(gr_poly
		(pts
			(arc
				(start 131.709922 -369.03533)
				(mid 131.44627 -369.03533)
				(end 131.709922 -369.03533)
			)
		)
		(stroke
			(width 0)
			(type solid)
		)
		(fill yes)
		(layer "F.Cu")
		(net "GND")
	)
	(gr_poly
		(pts
			(arc
				(start 132.192522 -371.49913)
				(mid 131.92887 -371.49913)
				(end 132.192522 -371.49913)
			)
		)
		(stroke
			(width 0)
			(type solid)
		)
		(fill yes)
		(layer "F.Cu")
		(net "GND")
	)
	(gr_poly
		(pts
			(arc
				(start 132.195062 -369.69573)
				(mid 131.93141 -369.69573)
				(end 132.195062 -369.69573)
			)
		)
		(stroke
			(width 0)
			(type solid)
		)
		(fill yes)
		(layer "F.Cu")
		(net "GND")
	)
	(gr_poly
		(pts
			(arc
				(start 132.195062 -368.37493)
				(mid 131.93141 -368.37493)
				(end 132.195062 -368.37493)
			)
		)
		(stroke
			(width 0)
			(type solid)
		)
		(fill yes)
		(layer "F.Cu")
		(net "GND")
	)
	(gr_poly
		(pts
			(arc
				(start 133.409182 -369.69573)
				(mid 133.14553 -369.69573)
				(end 133.409182 -369.69573)
			)
		)
		(stroke
			(width 0)
			(type solid)
		)
		(fill yes)
		(layer "F.Cu")
		(net "GND")
	)
	(gr_poly
		(pts
			(arc
				(start 133.409182 -368.37493)
				(mid 133.14553 -368.37493)
				(end 133.409182 -368.37493)
			)
		)
		(stroke
			(width 0)
			(type solid)
		)
		(fill yes)
		(layer "F.Cu")
		(net "GND")
	)
	(gr_poly
		(pts
			(arc
				(start 133.894322 -369.03533)
				(mid 133.63067 -369.03533)
				(end 133.894322 -369.03533)
			)
		)
		(stroke
			(width 0)
			(type solid)
		)
		(fill yes)
		(layer "F.Cu")
		(net "GND")
	)
	(gr_poly
		(pts
			(arc
				(start 135.113522 -369.03533)
				(mid 134.84987 -369.03533)
				(end 135.113522 -369.03533)
			)
		)
		(stroke
			(width 0)
			(type solid)
		)
		(fill yes)
		(layer "F.Cu")
		(net "GND")
	)
	(gr_poly
		(pts
			(arc
				(start 135.598662 -369.69573)
				(mid 135.33501 -369.69573)
				(end 135.598662 -369.69573)
			)
		)
		(stroke
			(width 0)
			(type solid)
		)
		(fill yes)
		(layer "F.Cu")
		(net "GND")
	)
	(gr_poly
		(pts
			(arc
				(start 135.598662 -368.37493)
				(mid 135.33501 -368.37493)
				(end 135.598662 -368.37493)
			)
		)
		(stroke
			(width 0)
			(type solid)
		)
		(fill yes)
		(layer "F.Cu")
		(net "GND")
	)
	(gr_poly
		(pts
			(arc
				(start 136.812782 -369.69573)
				(mid 136.54913 -369.69573)
				(end 136.812782 -369.69573)
			)
		)
		(stroke
			(width 0)
			(type solid)
		)
		(fill yes)
		(layer "F.Cu")
		(net "GND")
	)
	(gr_poly
		(pts
			(arc
				(start 136.812782 -368.37493)
				(mid 136.54913 -368.37493)
				(end 136.812782 -368.37493)
			)
		)
		(stroke
			(width 0)
			(type solid)
		)
		(fill yes)
		(layer "F.Cu")
		(net "GND")
	)
	(gr_poly
		(pts
			(arc
				(start 137.297922 -369.03533)
				(mid 137.03427 -369.03533)
				(end 137.297922 -369.03533)
			)
		)
		(stroke
			(width 0)
			(type solid)
		)
		(fill yes)
		(layer "F.Cu")
		(net "GND")
	)
	(gr_poly
		(pts
			(arc
				(start 137.849102 -380.535688)
				(mid 137.58545 -380.535688)
				(end 137.849102 -380.535688)
			)
		)
		(stroke
			(width 0)
			(type solid)
		)
		(fill yes)
		(layer "F.Cu")
		(net "GND")
	)
	(gr_poly
		(pts
			(arc
				(start 137.849102 -379.321568)
				(mid 137.58545 -379.321568)
				(end 137.849102 -379.321568)
			)
		)
		(stroke
			(width 0)
			(type solid)
		)
		(fill yes)
		(layer "F.Cu")
		(net "GND")
	)
	(gr_poly
		(pts
			(arc
				(start 137.849102 -377.132088)
				(mid 137.58545 -377.132088)
				(end 137.849102 -377.132088)
			)
		)
		(stroke
			(width 0)
			(type solid)
		)
		(fill yes)
		(layer "F.Cu")
		(net "GND")
	)
	(gr_poly
		(pts
			(arc
				(start 137.849102 -375.917968)
				(mid 137.58545 -375.917968)
				(end 137.849102 -375.917968)
			)
		)
		(stroke
			(width 0)
			(type solid)
		)
		(fill yes)
		(layer "F.Cu")
		(net "GND")
	)
	(gr_poly
		(pts
			(arc
				(start 138.509502 -378.836428)
				(mid 138.24585 -378.836428)
				(end 138.509502 -378.836428)
			)
		)
		(stroke
			(width 0)
			(type solid)
		)
		(fill yes)
		(layer "F.Cu")
		(net "GND")
	)
	(gr_poly
		(pts
			(arc
				(start 138.509502 -377.617228)
				(mid 138.24585 -377.617228)
				(end 138.509502 -377.617228)
			)
		)
		(stroke
			(width 0)
			(type solid)
		)
		(fill yes)
		(layer "F.Cu")
		(net "GND")
	)
	(gr_poly
		(pts
			(arc
				(start 138.509502 -375.432828)
				(mid 138.24585 -375.432828)
				(end 138.509502 -375.432828)
			)
		)
		(stroke
			(width 0)
			(type solid)
		)
		(fill yes)
		(layer "F.Cu")
		(net "GND")
	)
	(gr_poly
		(pts
			(arc
				(start 138.514582 -370.83873)
				(mid 138.25093 -370.83873)
				(end 138.514582 -370.83873)
			)
		)
		(stroke
			(width 0)
			(type solid)
		)
		(fill yes)
		(layer "F.Cu")
		(net "GND")
	)
	(gr_poly
		(pts
			(arc
				(start 138.7983 -368.641376)
				(mid 138.534648 -368.641376)
				(end 138.7983 -368.641376)
			)
		)
		(stroke
			(width 0)
			(type solid)
		)
		(fill yes)
		(layer "F.Cu")
		(net "GND")
	)
	(gr_poly
		(pts
			(arc
				(start 139.169902 -380.535688)
				(mid 138.90625 -380.535688)
				(end 139.169902 -380.535688)
			)
		)
		(stroke
			(width 0)
			(type solid)
		)
		(fill yes)
		(layer "F.Cu")
		(net "GND")
	)
	(gr_poly
		(pts
			(arc
				(start 139.169902 -379.321568)
				(mid 138.90625 -379.321568)
				(end 139.169902 -379.321568)
			)
		)
		(stroke
			(width 0)
			(type solid)
		)
		(fill yes)
		(layer "F.Cu")
		(net "GND")
	)
	(gr_poly
		(pts
			(arc
				(start 139.169902 -377.132088)
				(mid 138.90625 -377.132088)
				(end 139.169902 -377.132088)
			)
		)
		(stroke
			(width 0)
			(type solid)
		)
		(fill yes)
		(layer "F.Cu")
		(net "GND")
	)
	(gr_poly
		(pts
			(arc
				(start 139.169902 -375.917968)
				(mid 138.90625 -375.917968)
				(end 139.169902 -375.917968)
			)
		)
		(stroke
			(width 0)
			(type solid)
		)
		(fill yes)
		(layer "F.Cu")
		(net "GND")
	)
	(gr_poly
		(pts
			(arc
				(start 140.529818 -381.3302)
				(mid 140.266166 -381.3302)
				(end 140.529818 -381.3302)
			)
		)
		(stroke
			(width 0)
			(type solid)
		)
		(fill yes)
		(layer "F.Cu")
		(net "GND")
	)
	(gr_poly
		(pts
			(arc
				(start 140.529818 -377.00712)
				(mid 140.266166 -377.00712)
				(end 140.529818 -377.00712)
			)
		)
		(stroke
			(width 0)
			(type solid)
		)
		(fill yes)
		(layer "F.Cu")
		(net "GND")
	)
	(gr_poly
		(pts
			(arc
				(start 140.529818 -375.793)
				(mid 140.266166 -375.793)
				(end 140.529818 -375.793)
			)
		)
		(stroke
			(width 0)
			(type solid)
		)
		(fill yes)
		(layer "F.Cu")
		(net "GND")
	)
	(gr_poly
		(pts
			(arc
				(start 141.190218 -383.02946)
				(mid 140.926566 -383.02946)
				(end 141.190218 -383.02946)
			)
		)
		(stroke
			(width 0)
			(type solid)
		)
		(fill yes)
		(layer "F.Cu")
		(net "GND")
	)
	(gr_poly
		(pts
			(arc
				(start 141.190218 -380.87046)
				(mid 140.926566 -380.87046)
				(end 141.190218 -380.87046)
			)
		)
		(stroke
			(width 0)
			(type solid)
		)
		(fill yes)
		(layer "F.Cu")
		(net "GND")
	)
	(gr_poly
		(pts
			(arc
				(start 141.190218 -377.49226)
				(mid 140.926566 -377.49226)
				(end 141.190218 -377.49226)
			)
		)
		(stroke
			(width 0)
			(type solid)
		)
		(fill yes)
		(layer "F.Cu")
		(net "GND")
	)
	(gr_poly
		(pts
			(arc
				(start 141.190218 -375.30786)
				(mid 140.926566 -375.30786)
				(end 141.190218 -375.30786)
			)
		)
		(stroke
			(width 0)
			(type solid)
		)
		(fill yes)
		(layer "F.Cu")
		(net "GND")
	)
	(gr_poly
		(pts
			(arc
				(start 141.850618 -382.54432)
				(mid 141.586966 -382.54432)
				(end 141.850618 -382.54432)
			)
		)
		(stroke
			(width 0)
			(type solid)
		)
		(fill yes)
		(layer "F.Cu")
		(net "GND")
	)
	(gr_poly
		(pts
			(arc
				(start 141.850618 -381.3302)
				(mid 141.586966 -381.3302)
				(end 141.850618 -381.3302)
			)
		)
		(stroke
			(width 0)
			(type solid)
		)
		(fill yes)
		(layer "F.Cu")
		(net "GND")
	)
	(gr_poly
		(pts
			(arc
				(start 141.850618 -377.00712)
				(mid 141.586966 -377.00712)
				(end 141.850618 -377.00712)
			)
		)
		(stroke
			(width 0)
			(type solid)
		)
		(fill yes)
		(layer "F.Cu")
		(net "GND")
	)
	(gr_poly
		(pts
			(arc
				(start 141.850618 -375.793)
				(mid 141.586966 -375.793)
				(end 141.850618 -375.793)
			)
		)
		(stroke
			(width 0)
			(type solid)
		)
		(fill yes)
		(layer "F.Cu")
		(net "GND")
	)
	(gr_poly
		(pts
			(arc
				(start 142.11427 -371.49913)
				(mid 141.850618 -371.49913)
				(end 142.11427 -371.49913)
			)
		)
		(stroke
			(width 0)
			(type solid)
		)
		(fill yes)
		(layer "F.Cu")
		(net "GND")
	)
	(gr_poly
		(pts
			(arc
				(start 142.140686 -368.85499)
				(mid 141.877034 -368.85499)
				(end 142.140686 -368.85499)
			)
		)
		(stroke
			(width 0)
			(type solid)
		)
		(fill yes)
		(layer "F.Cu")
		(net "GND")
	)
	(gr_poly
		(pts
			(arc
				(start 142.59941 -372.15953)
				(mid 142.335758 -372.15953)
				(end 142.59941 -372.15953)
			)
		)
		(stroke
			(width 0)
			(type solid)
		)
		(fill yes)
		(layer "F.Cu")
		(net "GND")
	)
	(gr_poly
		(pts
			(arc
				(start 142.59941 -370.83873)
				(mid 142.335758 -370.83873)
				(end 142.59941 -370.83873)
			)
		)
		(stroke
			(width 0)
			(type solid)
		)
		(fill yes)
		(layer "F.Cu")
		(net "GND")
	)
	(gr_poly
		(pts
			(arc
				(start 143.81353 -372.15953)
				(mid 143.549878 -372.15953)
				(end 143.81353 -372.15953)
			)
		)
		(stroke
			(width 0)
			(type solid)
		)
		(fill yes)
		(layer "F.Cu")
		(net "GND")
	)
	(gr_poly
		(pts
			(arc
				(start 143.81353 -370.83873)
				(mid 143.549878 -370.83873)
				(end 143.81353 -370.83873)
			)
		)
		(stroke
			(width 0)
			(type solid)
		)
		(fill yes)
		(layer "F.Cu")
		(net "GND")
	)
	(gr_poly
		(pts
			(arc
				(start 143.81607 -369.03533)
				(mid 143.552418 -369.03533)
				(end 143.81607 -369.03533)
			)
		)
		(stroke
			(width 0)
			(type solid)
		)
		(fill yes)
		(layer "F.Cu")
		(net "GND")
	)
	(gr_poly
		(pts
			(arc
				(start 144.29867 -371.49913)
				(mid 144.035018 -371.49913)
				(end 144.29867 -371.49913)
			)
		)
		(stroke
			(width 0)
			(type solid)
		)
		(fill yes)
		(layer "F.Cu")
		(net "GND")
	)
	(gr_poly
		(pts
			(arc
				(start 144.30121 -369.69573)
				(mid 144.037558 -369.69573)
				(end 144.30121 -369.69573)
			)
		)
		(stroke
			(width 0)
			(type solid)
		)
		(fill yes)
		(layer "F.Cu")
		(net "GND")
	)
	(gr_poly
		(pts
			(arc
				(start 144.30121 -368.37493)
				(mid 144.037558 -368.37493)
				(end 144.30121 -368.37493)
			)
		)
		(stroke
			(width 0)
			(type solid)
		)
		(fill yes)
		(layer "F.Cu")
		(net "GND")
	)
	(gr_poly
		(pts
			(arc
				(start 145.51533 -369.69573)
				(mid 145.251678 -369.69573)
				(end 145.51533 -369.69573)
			)
		)
		(stroke
			(width 0)
			(type solid)
		)
		(fill yes)
		(layer "F.Cu")
		(net "GND")
	)
	(gr_poly
		(pts
			(arc
				(start 145.51533 -368.37493)
				(mid 145.251678 -368.37493)
				(end 145.51533 -368.37493)
			)
		)
		(stroke
			(width 0)
			(type solid)
		)
		(fill yes)
		(layer "F.Cu")
		(net "GND")
	)
	(gr_poly
		(pts
			(arc
				(start 146.00047 -369.03533)
				(mid 145.736818 -369.03533)
				(end 146.00047 -369.03533)
			)
		)
		(stroke
			(width 0)
			(type solid)
		)
		(fill yes)
		(layer "F.Cu")
		(net "GND")
	)
	(gr_poly
		(pts
			(arc
				(start 147.21967 -373.96293)
				(mid 146.956018 -373.96293)
				(end 147.21967 -373.96293)
			)
		)
		(stroke
			(width 0)
			(type solid)
		)
		(fill yes)
		(layer "F.Cu")
		(net "GND")
	)
	(gr_poly
		(pts
			(arc
				(start 147.70481 -374.62333)
				(mid 147.441158 -374.62333)
				(end 147.70481 -374.62333)
			)
		)
		(stroke
			(width 0)
			(type solid)
		)
		(fill yes)
		(layer "F.Cu")
		(net "GND")
	)
	(gr_poly
		(pts
			(arc
				(start 147.70481 -373.30253)
				(mid 147.441158 -373.30253)
				(end 147.70481 -373.30253)
			)
		)
		(stroke
			(width 0)
			(type solid)
		)
		(fill yes)
		(layer "F.Cu")
		(net "GND")
	)
	(gr_poly
		(pts
			(arc
				(start 148.91893 -374.62333)
				(mid 148.655278 -374.62333)
				(end 148.91893 -374.62333)
			)
		)
		(stroke
			(width 0)
			(type solid)
		)
		(fill yes)
		(layer "F.Cu")
		(net "GND")
	)
	(gr_poly
		(pts
			(arc
				(start 148.91893 -373.30253)
				(mid 148.655278 -373.30253)
				(end 148.91893 -373.30253)
			)
		)
		(stroke
			(width 0)
			(type solid)
		)
		(fill yes)
		(layer "F.Cu")
		(net "GND")
	)
	(gr_poly
		(pts
			(arc
				(start 148.92147 -371.49913)
				(mid 148.657818 -371.49913)
				(end 148.92147 -371.49913)
			)
		)
		(stroke
			(width 0)
			(type solid)
		)
		(fill yes)
		(layer "F.Cu")
		(net "GND")
	)
	(gr_poly
		(pts
			(arc
				(start 149.40407 -373.96293)
				(mid 149.140418 -373.96293)
				(end 149.40407 -373.96293)
			)
		)
		(stroke
			(width 0)
			(type solid)
		)
		(fill yes)
		(layer "F.Cu")
		(net "GND")
	)
	(gr_poly
		(pts
			(arc
				(start 149.40661 -372.15953)
				(mid 149.142958 -372.15953)
				(end 149.40661 -372.15953)
			)
		)
		(stroke
			(width 0)
			(type solid)
		)
		(fill yes)
		(layer "F.Cu")
		(net "GND")
	)
	(gr_poly
		(pts
			(arc
				(start 149.40661 -370.83873)
				(mid 149.142958 -370.83873)
				(end 149.40661 -370.83873)
			)
		)
		(stroke
			(width 0)
			(type solid)
		)
		(fill yes)
		(layer "F.Cu")
		(net "GND")
	)
	(gr_poly
		(pts
			(arc
				(start 150.62073 -372.15953)
				(mid 150.357078 -372.15953)
				(end 150.62073 -372.15953)
			)
		)
		(stroke
			(width 0)
			(type solid)
		)
		(fill yes)
		(layer "F.Cu")
		(net "GND")
	)
	(gr_poly
		(pts
			(arc
				(start 150.62073 -370.83873)
				(mid 150.357078 -370.83873)
				(end 150.62073 -370.83873)
			)
		)
		(stroke
			(width 0)
			(type solid)
		)
		(fill yes)
		(layer "F.Cu")
		(net "GND")
	)
	(gr_poly
		(pts
			(arc
				(start 150.62327 -369.03533)
				(mid 150.359618 -369.03533)
				(end 150.62327 -369.03533)
			)
		)
		(stroke
			(width 0)
			(type solid)
		)
		(fill yes)
		(layer "F.Cu")
		(net "GND")
	)
	(gr_poly
		(pts
			(arc
				(start 151.10587 -371.49913)
				(mid 150.842218 -371.49913)
				(end 151.10587 -371.49913)
			)
		)
		(stroke
			(width 0)
			(type solid)
		)
		(fill yes)
		(layer "F.Cu")
		(net "GND")
	)
	(gr_poly
		(pts
			(arc
				(start 151.10841 -369.69573)
				(mid 150.844758 -369.69573)
				(end 151.10841 -369.69573)
			)
		)
		(stroke
			(width 0)
			(type solid)
		)
		(fill yes)
		(layer "F.Cu")
		(net "GND")
	)
	(gr_poly
		(pts
			(arc
				(start 151.10841 -368.37493)
				(mid 150.844758 -368.37493)
				(end 151.10841 -368.37493)
			)
		)
		(stroke
			(width 0)
			(type solid)
		)
		(fill yes)
		(layer "F.Cu")
		(net "GND")
	)
	(gr_poly
		(pts
			(arc
				(start 151.681434 -47.94885)
				(mid 151.422354 -47.94885)
				(end 151.681434 -47.94885)
			)
		)
		(stroke
			(width 0)
			(type solid)
		)
		(fill yes)
		(layer "F.Cu")
		(net "GND")
	)
	(gr_poly
		(pts
			(arc
				(start 152.32253 -369.69573)
				(mid 152.058878 -369.69573)
				(end 152.32253 -369.69573)
			)
		)
		(stroke
			(width 0)
			(type solid)
		)
		(fill yes)
		(layer "F.Cu")
		(net "GND")
	)
	(gr_poly
		(pts
			(arc
				(start 152.32253 -368.37493)
				(mid 152.058878 -368.37493)
				(end 152.32253 -368.37493)
			)
		)
		(stroke
			(width 0)
			(type solid)
		)
		(fill yes)
		(layer "F.Cu")
		(net "GND")
	)
	(gr_poly
		(pts
			(arc
				(start 152.730962 -49.06899)
				(mid 152.471882 -49.06899)
				(end 152.730962 -49.06899)
			)
		)
		(stroke
			(width 0)
			(type solid)
		)
		(fill yes)
		(layer "F.Cu")
		(net "GND")
	)
	(gr_poly
		(pts
			(arc
				(start 152.80767 -369.03533)
				(mid 152.544018 -369.03533)
				(end 152.80767 -369.03533)
			)
		)
		(stroke
			(width 0)
			(type solid)
		)
		(fill yes)
		(layer "F.Cu")
		(net "GND")
	)
	(gr_poly
		(pts
			(arc
				(start 154.02687 -373.96293)
				(mid 153.763218 -373.96293)
				(end 154.02687 -373.96293)
			)
		)
		(stroke
			(width 0)
			(type solid)
		)
		(fill yes)
		(layer "F.Cu")
		(net "GND")
	)
	(gr_poly
		(pts
			(arc
				(start 154.51201 -374.62333)
				(mid 154.248358 -374.62333)
				(end 154.51201 -374.62333)
			)
		)
		(stroke
			(width 0)
			(type solid)
		)
		(fill yes)
		(layer "F.Cu")
		(net "GND")
	)
	(gr_poly
		(pts
			(arc
				(start 154.51201 -373.30253)
				(mid 154.248358 -373.30253)
				(end 154.51201 -373.30253)
			)
		)
		(stroke
			(width 0)
			(type solid)
		)
		(fill yes)
		(layer "F.Cu")
		(net "GND")
	)
	(gr_poly
		(pts
			(arc
				(start 155.72613 -374.62333)
				(mid 155.462478 -374.62333)
				(end 155.72613 -374.62333)
			)
		)
		(stroke
			(width 0)
			(type solid)
		)
		(fill yes)
		(layer "F.Cu")
		(net "GND")
	)
	(gr_poly
		(pts
			(arc
				(start 155.72613 -373.30253)
				(mid 155.462478 -373.30253)
				(end 155.72613 -373.30253)
			)
		)
		(stroke
			(width 0)
			(type solid)
		)
		(fill yes)
		(layer "F.Cu")
		(net "GND")
	)
	(gr_poly
		(pts
			(arc
				(start 155.72867 -371.49913)
				(mid 155.465018 -371.49913)
				(end 155.72867 -371.49913)
			)
		)
		(stroke
			(width 0)
			(type solid)
		)
		(fill yes)
		(layer "F.Cu")
		(net "GND")
	)
	(gr_poly
		(pts
			(arc
				(start 156.21127 -373.96293)
				(mid 155.947618 -373.96293)
				(end 156.21127 -373.96293)
			)
		)
		(stroke
			(width 0)
			(type solid)
		)
		(fill yes)
		(layer "F.Cu")
		(net "GND")
	)
	(gr_poly
		(pts
			(arc
				(start 156.21381 -372.15953)
				(mid 155.950158 -372.15953)
				(end 156.21381 -372.15953)
			)
		)
		(stroke
			(width 0)
			(type solid)
		)
		(fill yes)
		(layer "F.Cu")
		(net "GND")
	)
	(gr_poly
		(pts
			(arc
				(start 156.21381 -370.83873)
				(mid 155.950158 -370.83873)
				(end 156.21381 -370.83873)
			)
		)
		(stroke
			(width 0)
			(type solid)
		)
		(fill yes)
		(layer "F.Cu")
		(net "GND")
	)
	(gr_poly
		(pts
			(arc
				(start 156.457396 -88.270588)
				(mid 156.198316 -88.270588)
				(end 156.457396 -88.270588)
			)
		)
		(stroke
			(width 0)
			(type solid)
		)
		(fill yes)
		(layer "F.Cu")
		(net "GND")
	)
	(gr_poly
		(pts
			(arc
				(start 157.42793 -372.15953)
				(mid 157.164278 -372.15953)
				(end 157.42793 -372.15953)
			)
		)
		(stroke
			(width 0)
			(type solid)
		)
		(fill yes)
		(layer "F.Cu")
		(net "GND")
	)
	(gr_poly
		(pts
			(arc
				(start 157.42793 -370.83873)
				(mid 157.164278 -370.83873)
				(end 157.42793 -370.83873)
			)
		)
		(stroke
			(width 0)
			(type solid)
		)
		(fill yes)
		(layer "F.Cu")
		(net "GND")
	)
	(gr_poly
		(pts
			(arc
				(start 157.43047 -369.03533)
				(mid 157.166818 -369.03533)
				(end 157.43047 -369.03533)
			)
		)
		(stroke
			(width 0)
			(type solid)
		)
		(fill yes)
		(layer "F.Cu")
		(net "GND")
	)
	(gr_poly
		(pts
			(arc
				(start 157.91307 -371.49913)
				(mid 157.649418 -371.49913)
				(end 157.91307 -371.49913)
			)
		)
		(stroke
			(width 0)
			(type solid)
		)
		(fill yes)
		(layer "F.Cu")
		(net "GND")
	)
	(gr_poly
		(pts
			(arc
				(start 157.91561 -369.69573)
				(mid 157.651958 -369.69573)
				(end 157.91561 -369.69573)
			)
		)
		(stroke
			(width 0)
			(type solid)
		)
		(fill yes)
		(layer "F.Cu")
		(net "GND")
	)
	(gr_poly
		(pts
			(arc
				(start 157.91561 -368.37493)
				(mid 157.651958 -368.37493)
				(end 157.91561 -368.37493)
			)
		)
		(stroke
			(width 0)
			(type solid)
		)
		(fill yes)
		(layer "F.Cu")
		(net "GND")
	)
	(gr_poly
		(pts
			(arc
				(start 158.863538 -11.180826)
				(mid 158.604458 -11.180826)
				(end 158.863538 -11.180826)
			)
		)
		(stroke
			(width 0)
			(type solid)
		)
		(fill yes)
		(layer "F.Cu")
		(net "GND")
	)
	(gr_poly
		(pts
			(arc
				(start 159.12973 -369.69573)
				(mid 158.866078 -369.69573)
				(end 159.12973 -369.69573)
			)
		)
		(stroke
			(width 0)
			(type solid)
		)
		(fill yes)
		(layer "F.Cu")
		(net "GND")
	)
	(gr_poly
		(pts
			(arc
				(start 159.12973 -368.37493)
				(mid 158.866078 -368.37493)
				(end 159.12973 -368.37493)
			)
		)
		(stroke
			(width 0)
			(type solid)
		)
		(fill yes)
		(layer "F.Cu")
		(net "GND")
	)
	(gr_poly
		(pts
			(arc
				(start 159.61487 -369.03533)
				(mid 159.351218 -369.03533)
				(end 159.61487 -369.03533)
			)
		)
		(stroke
			(width 0)
			(type solid)
		)
		(fill yes)
		(layer "F.Cu")
		(net "GND")
	)
	(gr_poly
		(pts
			(arc
				(start 160.83407 -373.96293)
				(mid 160.570418 -373.96293)
				(end 160.83407 -373.96293)
			)
		)
		(stroke
			(width 0)
			(type solid)
		)
		(fill yes)
		(layer "F.Cu")
		(net "GND")
	)
	(gr_poly
		(pts
			(arc
				(start 161.31921 -374.62333)
				(mid 161.055558 -374.62333)
				(end 161.31921 -374.62333)
			)
		)
		(stroke
			(width 0)
			(type solid)
		)
		(fill yes)
		(layer "F.Cu")
		(net "GND")
	)
	(gr_poly
		(pts
			(arc
				(start 161.31921 -373.30253)
				(mid 161.055558 -373.30253)
				(end 161.31921 -373.30253)
			)
		)
		(stroke
			(width 0)
			(type solid)
		)
		(fill yes)
		(layer "F.Cu")
		(net "GND")
	)
	(gr_poly
		(pts
			(arc
				(start 162.53333 -374.62333)
				(mid 162.269678 -374.62333)
				(end 162.53333 -374.62333)
			)
		)
		(stroke
			(width 0)
			(type solid)
		)
		(fill yes)
		(layer "F.Cu")
		(net "GND")
	)
	(gr_poly
		(pts
			(arc
				(start 162.53333 -373.30253)
				(mid 162.269678 -373.30253)
				(end 162.53333 -373.30253)
			)
		)
		(stroke
			(width 0)
			(type solid)
		)
		(fill yes)
		(layer "F.Cu")
		(net "GND")
	)
	(gr_poly
		(pts
			(arc
				(start 162.53587 -371.49913)
				(mid 162.272218 -371.49913)
				(end 162.53587 -371.49913)
			)
		)
		(stroke
			(width 0)
			(type solid)
		)
		(fill yes)
		(layer "F.Cu")
		(net "GND")
	)
	(gr_poly
		(pts
			(arc
				(start 162.770058 -99.33559)
				(mid 162.510978 -99.33559)
				(end 162.770058 -99.33559)
			)
		)
		(stroke
			(width 0)
			(type solid)
		)
		(fill yes)
		(layer "F.Cu")
		(net "GND")
	)
	(gr_poly
		(pts
			(arc
				(start 163.01847 -373.96293)
				(mid 162.754818 -373.96293)
				(end 163.01847 -373.96293)
			)
		)
		(stroke
			(width 0)
			(type solid)
		)
		(fill yes)
		(layer "F.Cu")
		(net "GND")
	)
	(gr_poly
		(pts
			(arc
				(start 163.02101 -372.15953)
				(mid 162.757358 -372.15953)
				(end 163.02101 -372.15953)
			)
		)
		(stroke
			(width 0)
			(type solid)
		)
		(fill yes)
		(layer "F.Cu")
		(net "GND")
	)
	(gr_poly
		(pts
			(arc
				(start 163.02101 -370.83873)
				(mid 162.757358 -370.83873)
				(end 163.02101 -370.83873)
			)
		)
		(stroke
			(width 0)
			(type solid)
		)
		(fill yes)
		(layer "F.Cu")
		(net "GND")
	)
	(gr_poly
		(pts
			(arc
				(start 164.23513 -372.15953)
				(mid 163.971478 -372.15953)
				(end 164.23513 -372.15953)
			)
		)
		(stroke
			(width 0)
			(type solid)
		)
		(fill yes)
		(layer "F.Cu")
		(net "GND")
	)
	(gr_poly
		(pts
			(arc
				(start 164.23513 -370.83873)
				(mid 163.971478 -370.83873)
				(end 164.23513 -370.83873)
			)
		)
		(stroke
			(width 0)
			(type solid)
		)
		(fill yes)
		(layer "F.Cu")
		(net "GND")
	)
	(gr_poly
		(pts
			(arc
				(start 164.23767 -369.03533)
				(mid 163.974018 -369.03533)
				(end 164.23767 -369.03533)
			)
		)
		(stroke
			(width 0)
			(type solid)
		)
		(fill yes)
		(layer "F.Cu")
		(net "GND")
	)
	(gr_poly
		(pts
			(arc
				(start 164.72027 -371.49913)
				(mid 164.456618 -371.49913)
				(end 164.72027 -371.49913)
			)
		)
		(stroke
			(width 0)
			(type solid)
		)
		(fill yes)
		(layer "F.Cu")
		(net "GND")
	)
	(gr_poly
		(pts
			(arc
				(start 164.72281 -369.69573)
				(mid 164.459158 -369.69573)
				(end 164.72281 -369.69573)
			)
		)
		(stroke
			(width 0)
			(type solid)
		)
		(fill yes)
		(layer "F.Cu")
		(net "GND")
	)
	(gr_poly
		(pts
			(arc
				(start 164.72281 -368.37493)
				(mid 164.459158 -368.37493)
				(end 164.72281 -368.37493)
			)
		)
		(stroke
			(width 0)
			(type solid)
		)
		(fill yes)
		(layer "F.Cu")
		(net "GND")
	)
	(gr_poly
		(pts
			(arc
				(start 164.845238 -11.202924)
				(mid 164.586158 -11.202924)
				(end 164.845238 -11.202924)
			)
		)
		(stroke
			(width 0)
			(type solid)
		)
		(fill yes)
		(layer "F.Cu")
		(net "GND")
	)
	(gr_poly
		(pts
			(arc
				(start 165.93693 -369.69573)
				(mid 165.673278 -369.69573)
				(end 165.93693 -369.69573)
			)
		)
		(stroke
			(width 0)
			(type solid)
		)
		(fill yes)
		(layer "F.Cu")
		(net "GND")
	)
	(gr_poly
		(pts
			(arc
				(start 165.93693 -368.37493)
				(mid 165.673278 -368.37493)
				(end 165.93693 -368.37493)
			)
		)
		(stroke
			(width 0)
			(type solid)
		)
		(fill yes)
		(layer "F.Cu")
		(net "GND")
	)
	(gr_poly
		(pts
			(arc
				(start 165.994842 -112.5728)
				(mid 165.735762 -112.5728)
				(end 165.994842 -112.5728)
			)
		)
		(stroke
			(width 0)
			(type solid)
		)
		(fill yes)
		(layer "F.Cu")
		(net "GND")
	)
	(gr_poly
		(pts
			(arc
				(start 166.42207 -369.03533)
				(mid 166.158418 -369.03533)
				(end 166.42207 -369.03533)
			)
		)
		(stroke
			(width 0)
			(type solid)
		)
		(fill yes)
		(layer "F.Cu")
		(net "GND")
	)
	(gr_poly
		(pts
			(arc
				(start 167.64127 -369.03533)
				(mid 167.377618 -369.03533)
				(end 167.64127 -369.03533)
			)
		)
		(stroke
			(width 0)
			(type solid)
		)
		(fill yes)
		(layer "F.Cu")
		(net "GND")
	)
	(gr_poly
		(pts
			(arc
				(start 168.12641 -369.69573)
				(mid 167.862758 -369.69573)
				(end 168.12641 -369.69573)
			)
		)
		(stroke
			(width 0)
			(type solid)
		)
		(fill yes)
		(layer "F.Cu")
		(net "GND")
	)
	(gr_poly
		(pts
			(arc
				(start 168.12641 -368.37493)
				(mid 167.862758 -368.37493)
				(end 168.12641 -368.37493)
			)
		)
		(stroke
			(width 0)
			(type solid)
		)
		(fill yes)
		(layer "F.Cu")
		(net "GND")
	)
	(gr_poly
		(pts
			(arc
				(start 168.82872 -113.210594)
				(mid 168.56964 -113.210594)
				(end 168.82872 -113.210594)
			)
		)
		(stroke
			(width 0)
			(type solid)
		)
		(fill yes)
		(layer "F.Cu")
		(net "GND")
	)
	(gr_poly
		(pts
			(arc
				(start 169.34053 -369.69573)
				(mid 169.076878 -369.69573)
				(end 169.34053 -369.69573)
			)
		)
		(stroke
			(width 0)
			(type solid)
		)
		(fill yes)
		(layer "F.Cu")
		(net "GND")
	)
	(gr_poly
		(pts
			(arc
				(start 169.34053 -368.37493)
				(mid 169.076878 -368.37493)
				(end 169.34053 -368.37493)
			)
		)
		(stroke
			(width 0)
			(type solid)
		)
		(fill yes)
		(layer "F.Cu")
		(net "GND")
	)
	(gr_poly
		(pts
			(arc
				(start 169.82567 -369.03533)
				(mid 169.562018 -369.03533)
				(end 169.82567 -369.03533)
			)
		)
		(stroke
			(width 0)
			(type solid)
		)
		(fill yes)
		(layer "F.Cu")
		(net "GND")
	)
	(gr_poly
		(pts
			(arc
				(start 170.37685 -380.535688)
				(mid 170.113198 -380.535688)
				(end 170.37685 -380.535688)
			)
		)
		(stroke
			(width 0)
			(type solid)
		)
		(fill yes)
		(layer "F.Cu")
		(net "GND")
	)
	(gr_poly
		(pts
			(arc
				(start 170.37685 -379.321568)
				(mid 170.113198 -379.321568)
				(end 170.37685 -379.321568)
			)
		)
		(stroke
			(width 0)
			(type solid)
		)
		(fill yes)
		(layer "F.Cu")
		(net "GND")
	)
	(gr_poly
		(pts
			(arc
				(start 170.37685 -377.132088)
				(mid 170.113198 -377.132088)
				(end 170.37685 -377.132088)
			)
		)
		(stroke
			(width 0)
			(type solid)
		)
		(fill yes)
		(layer "F.Cu")
		(net "GND")
	)
	(gr_poly
		(pts
			(arc
				(start 170.37685 -375.917968)
				(mid 170.113198 -375.917968)
				(end 170.37685 -375.917968)
			)
		)
		(stroke
			(width 0)
			(type solid)
		)
		(fill yes)
		(layer "F.Cu")
		(net "GND")
	)
	(gr_poly
		(pts
			(arc
				(start 171.03725 -378.836428)
				(mid 170.773598 -378.836428)
				(end 171.03725 -378.836428)
			)
		)
		(stroke
			(width 0)
			(type solid)
		)
		(fill yes)
		(layer "F.Cu")
		(net "GND")
	)
	(gr_poly
		(pts
			(arc
				(start 171.03725 -377.617228)
				(mid 170.773598 -377.617228)
				(end 171.03725 -377.617228)
			)
		)
		(stroke
			(width 0)
			(type solid)
		)
		(fill yes)
		(layer "F.Cu")
		(net "GND")
	)
	(gr_poly
		(pts
			(arc
				(start 171.03725 -375.432828)
				(mid 170.773598 -375.432828)
				(end 171.03725 -375.432828)
			)
		)
		(stroke
			(width 0)
			(type solid)
		)
		(fill yes)
		(layer "F.Cu")
		(net "GND")
	)
	(gr_poly
		(pts
			(arc
				(start 171.610274 -375.818908)
				(mid 171.346622 -375.818908)
				(end 171.610274 -375.818908)
			)
		)
		(stroke
			(width 0)
			(type solid)
		)
		(fill yes)
		(layer "F.Cu")
		(net "GND")
	)
	(gr_poly
		(pts
			(arc
				(start 171.69765 -380.535688)
				(mid 171.433998 -380.535688)
				(end 171.69765 -380.535688)
			)
		)
		(stroke
			(width 0)
			(type solid)
		)
		(fill yes)
		(layer "F.Cu")
		(net "GND")
	)
	(gr_poly
		(pts
			(arc
				(start 171.69765 -379.321568)
				(mid 171.433998 -379.321568)
				(end 171.69765 -379.321568)
			)
		)
		(stroke
			(width 0)
			(type solid)
		)
		(fill yes)
		(layer "F.Cu")
		(net "GND")
	)
	(gr_poly
		(pts
			(arc
				(start 171.69765 -377.132088)
				(mid 171.433998 -377.132088)
				(end 171.69765 -377.132088)
			)
		)
		(stroke
			(width 0)
			(type solid)
		)
		(fill yes)
		(layer "F.Cu")
		(net "GND")
	)
	(gr_poly
		(pts
			(arc
				(start 175.769524 -146.070574)
				(mid 175.510444 -146.070574)
				(end 175.769524 -146.070574)
			)
		)
		(stroke
			(width 0)
			(type solid)
		)
		(fill yes)
		(layer "F.Cu")
		(net "GND")
	)
	(gr_poly
		(pts
			(arc
				(start 178.309524 -147.461224)
				(mid 178.050444 -147.461224)
				(end 178.309524 -147.461224)
			)
		)
		(stroke
			(width 0)
			(type solid)
		)
		(fill yes)
		(layer "F.Cu")
		(net "GND")
	)
	(gr_poly
		(pts
			(arc
				(start 179.497228 -394.228828)
				(mid 179.238148 -394.228828)
				(end 179.497228 -394.228828)
			)
		)
		(stroke
			(width 0)
			(type solid)
		)
		(fill yes)
		(layer "F.Cu")
		(net "GND")
	)
	(gr_poly
		(pts
			(arc
				(start 180.864764 -146.070574)
				(mid 180.605684 -146.070574)
				(end 180.864764 -146.070574)
			)
		)
		(stroke
			(width 0)
			(type solid)
		)
		(fill yes)
		(layer "F.Cu")
		(net "GND")
	)
	(gr_poly
		(pts
			(arc
				(start 185.94451 -21.25599)
				(mid 185.68543 -21.25599)
				(end 185.94451 -21.25599)
			)
		)
		(stroke
			(width 0)
			(type solid)
		)
		(fill yes)
		(layer "F.Cu")
		(net "GND")
	)
	(gr_poly
		(pts
			(arc
				(start 187.329826 -21.124926)
				(mid 187.070746 -21.124926)
				(end 187.329826 -21.124926)
			)
		)
		(stroke
			(width 0)
			(type solid)
		)
		(fill yes)
		(layer "F.Cu")
		(net "GND")
	)
	(gr_poly
		(pts
			(arc
				(start 190.89116 -423.820082)
				(mid 190.63208 -423.820082)
				(end 190.89116 -423.820082)
			)
		)
		(stroke
			(width 0)
			(type solid)
		)
		(fill yes)
		(layer "F.Cu")
		(net "GND")
	)
	(gr_poly
		(pts
			(arc
				(start 192.003172 -424.784774)
				(mid 191.744092 -424.784774)
				(end 192.003172 -424.784774)
			)
		)
		(stroke
			(width 0)
			(type solid)
		)
		(fill yes)
		(layer "F.Cu")
		(net "GND")
	)
	(gr_poly
		(pts
			(arc
				(start 205.96098 -112.288066)
				(mid 205.7019 -112.288066)
				(end 205.96098 -112.288066)
			)
		)
		(stroke
			(width 0)
			(type solid)
		)
		(fill yes)
		(layer "F.Cu")
		(net "GND")
	)
	(gr_poly
		(pts
			(arc
				(start 208.51241 -79.20482)
				(mid 208.25333 -79.20482)
				(end 208.51241 -79.20482)
			)
		)
		(stroke
			(width 0)
			(type solid)
		)
		(fill yes)
		(layer "F.Cu")
		(net "GND")
	)
	(gr_poly
		(pts
			(arc
				(start 209.095086 -14.404848)
				(mid 208.836006 -14.404848)
				(end 209.095086 -14.404848)
			)
		)
		(stroke
			(width 0)
			(type solid)
		)
		(fill yes)
		(layer "F.Cu")
		(net "GND")
	)
	(gr_poly
		(pts
			(arc
				(start 209.961988 -322.464684)
				(mid 209.702908 -322.464684)
				(end 209.961988 -322.464684)
			)
		)
		(stroke
			(width 0)
			(type solid)
		)
		(fill yes)
		(layer "F.Cu")
		(net "GND")
	)
	(gr_poly
		(pts
			(arc
				(start 211.968842 -338.730844)
				(mid 211.709762 -338.730844)
				(end 211.968842 -338.730844)
			)
		)
		(stroke
			(width 0)
			(type solid)
		)
		(fill yes)
		(layer "F.Cu")
		(net "GND")
	)
	(gr_poly
		(pts
			(arc
				(start 211.982558 -340.984586)
				(mid 211.723478 -340.984586)
				(end 211.982558 -340.984586)
			)
		)
		(stroke
			(width 0)
			(type solid)
		)
		(fill yes)
		(layer "F.Cu")
		(net "GND")
	)
	(gr_poly
		(pts
			(arc
				(start 213.282276 -342.630506)
				(mid 213.023196 -342.630506)
				(end 213.282276 -342.630506)
			)
		)
		(stroke
			(width 0)
			(type solid)
		)
		(fill yes)
		(layer "F.Cu")
		(net "GND")
	)
	(gr_poly
		(pts
			(arc
				(start 213.794086 -345.790012)
				(mid 213.535006 -345.790012)
				(end 213.794086 -345.790012)
			)
		)
		(stroke
			(width 0)
			(type solid)
		)
		(fill yes)
		(layer "F.Cu")
		(net "GND")
	)
	(gr_poly
		(pts
			(arc
				(start 220.4974 -163.17468)
				(mid 220.23832 -163.17468)
				(end 220.4974 -163.17468)
			)
		)
		(stroke
			(width 0)
			(type solid)
		)
		(fill yes)
		(layer "F.Cu")
		(net "GND")
	)
	(gr_poly
		(pts
			(arc
				(start 222.644716 -366.856518)
				(mid 222.385636 -366.856518)
				(end 222.644716 -366.856518)
			)
		)
		(stroke
			(width 0)
			(type solid)
		)
		(fill yes)
		(layer "F.Cu")
		(net "GND")
	)
	(gr_poly
		(pts
			(arc
				(start 224.782888 -367.531396)
				(mid 224.523808 -367.531396)
				(end 224.782888 -367.531396)
			)
		)
		(stroke
			(width 0)
			(type solid)
		)
		(fill yes)
		(layer "F.Cu")
		(net "GND")
	)
	(gr_poly
		(pts
			(arc
				(start 230.351838 -207.891634)
				(mid 230.092758 -207.891634)
				(end 230.351838 -207.891634)
			)
		)
		(stroke
			(width 0)
			(type solid)
		)
		(fill yes)
		(layer "F.Cu")
		(net "GND")
	)
	(gr_poly
		(pts
			(arc
				(start 230.39832 -168.63822)
				(mid 230.13924 -168.63822)
				(end 230.39832 -168.63822)
			)
		)
		(stroke
			(width 0)
			(type solid)
		)
		(fill yes)
		(layer "F.Cu")
		(net "GND")
	)
	(gr_poly
		(pts
			(arc
				(start 233.747056 -342.643968)
				(mid 233.487976 -342.643968)
				(end 233.747056 -342.643968)
			)
		)
		(stroke
			(width 0)
			(type solid)
		)
		(fill yes)
		(layer "F.Cu")
		(net "GND")
	)
	(gr_poly
		(pts
			(arc
				(start 233.995976 -335.62671)
				(mid 233.736896 -335.62671)
				(end 233.995976 -335.62671)
			)
		)
		(stroke
			(width 0)
			(type solid)
		)
		(fill yes)
		(layer "F.Cu")
		(net "GND")
	)
	(gr_poly
		(pts
			(arc
				(start 234.743244 -340.238588)
				(mid 234.484164 -340.238588)
				(end 234.743244 -340.238588)
			)
		)
		(stroke
			(width 0)
			(type solid)
		)
		(fill yes)
		(layer "F.Cu")
		(net "GND")
	)
	(gr_poly
		(pts
			(arc
				(start 235.80725 -334.624426)
				(mid 235.54817 -334.624426)
				(end 235.80725 -334.624426)
			)
		)
		(stroke
			(width 0)
			(type solid)
		)
		(fill yes)
		(layer "F.Cu")
		(net "GND")
	)
	(gr_poly
		(pts
			(arc
				(start 236.584744 -168.856914)
				(mid 236.325664 -168.856914)
				(end 236.584744 -168.856914)
			)
		)
		(stroke
			(width 0)
			(type solid)
		)
		(fill yes)
		(layer "F.Cu")
		(net "GND")
	)
	(gr_poly
		(pts
			(arc
				(start 237.120938 -334.244188)
				(mid 236.861858 -334.244188)
				(end 237.120938 -334.244188)
			)
		)
		(stroke
			(width 0)
			(type solid)
		)
		(fill yes)
		(layer "F.Cu")
		(net "GND")
	)
	(gr_poly
		(pts
			(arc
				(start 237.259368 -336.677762)
				(mid 237.000288 -336.677762)
				(end 237.259368 -336.677762)
			)
		)
		(stroke
			(width 0)
			(type solid)
		)
		(fill yes)
		(layer "F.Cu")
		(net "GND")
	)
	(gr_poly
		(pts
			(arc
				(start 240.506504 -169.877994)
				(mid 240.247424 -169.877994)
				(end 240.506504 -169.877994)
			)
		)
		(stroke
			(width 0)
			(type solid)
		)
		(fill yes)
		(layer "F.Cu")
		(net "GND")
	)
	(gr_poly
		(pts
			(arc
				(start 241.896646 -206.43342)
				(mid 241.637566 -206.43342)
				(end 241.896646 -206.43342)
			)
		)
		(stroke
			(width 0)
			(type solid)
		)
		(fill yes)
		(layer "F.Cu")
		(net "GND")
	)
	(gr_poly
		(pts
			(arc
				(start 247.428004 -80.682592)
				(mid 247.168924 -80.682592)
				(end 247.428004 -80.682592)
			)
		)
		(stroke
			(width 0)
			(type solid)
		)
		(fill yes)
		(layer "F.Cu")
		(net "GND")
	)
	(gr_poly
		(pts
			(arc
				(start 251.19838 -90.10015)
				(mid 250.9393 -90.10015)
				(end 251.19838 -90.10015)
			)
		)
		(stroke
			(width 0)
			(type solid)
		)
		(fill yes)
		(layer "F.Cu")
		(net "GND")
	)
	(gr_poly
		(pts
			(arc
				(start 251.851414 -134.257796)
				(mid 251.592334 -134.257796)
				(end 251.851414 -134.257796)
			)
		)
		(stroke
			(width 0)
			(type solid)
		)
		(fill yes)
		(layer "F.Cu")
		(net "GND")
	)
	(gr_poly
		(pts
			(arc
				(start 252.156722 -94.914466)
				(mid 251.897642 -94.914466)
				(end 252.156722 -94.914466)
			)
		)
		(stroke
			(width 0)
			(type solid)
		)
		(fill yes)
		(layer "F.Cu")
		(net "GND")
	)
	(gr_poly
		(pts
			(arc
				(start 252.46838 -90.10015)
				(mid 252.2093 -90.10015)
				(end 252.46838 -90.10015)
			)
		)
		(stroke
			(width 0)
			(type solid)
		)
		(fill yes)
		(layer "F.Cu")
		(net "GND")
	)
	(gr_poly
		(pts
			(arc
				(start 253.491492 -94.052898)
				(mid 253.232412 -94.052898)
				(end 253.491492 -94.052898)
			)
		)
		(stroke
			(width 0)
			(type solid)
		)
		(fill yes)
		(layer "F.Cu")
		(net "GND")
	)
	(gr_poly
		(pts
			(arc
				(start 253.635764 -133.063996)
				(mid 253.376684 -133.063996)
				(end 253.635764 -133.063996)
			)
		)
		(stroke
			(width 0)
			(type solid)
		)
		(fill yes)
		(layer "F.Cu")
		(net "GND")
	)
	(gr_poly
		(pts
			(arc
				(start 253.635764 -131.626356)
				(mid 253.376684 -131.626356)
				(end 253.635764 -131.626356)
			)
		)
		(stroke
			(width 0)
			(type solid)
		)
		(fill yes)
		(layer "F.Cu")
		(net "GND")
	)
	(gr_poly
		(pts
			(arc
				(start 253.73838 -90.10015)
				(mid 253.4793 -90.10015)
				(end 253.73838 -90.10015)
			)
		)
		(stroke
			(width 0)
			(type solid)
		)
		(fill yes)
		(layer "F.Cu")
		(net "GND")
	)
	(gr_poly
		(pts
			(arc
				(start 253.883414 -134.257796)
				(mid 253.624334 -134.257796)
				(end 253.883414 -134.257796)
			)
		)
		(stroke
			(width 0)
			(type solid)
		)
		(fill yes)
		(layer "F.Cu")
		(net "GND")
	)
	(gr_poly
		(pts
			(arc
				(start 257.049524 -339.090508)
				(mid 256.790444 -339.090508)
				(end 257.049524 -339.090508)
			)
		)
		(stroke
			(width 0)
			(type solid)
		)
		(fill yes)
		(layer "F.Cu")
		(net "GND")
	)
	(gr_poly
		(pts
			(arc
				(start 257.231134 -139.083796)
				(mid 256.972054 -139.083796)
				(end 257.231134 -139.083796)
			)
		)
		(stroke
			(width 0)
			(type solid)
		)
		(fill yes)
		(layer "F.Cu")
		(net "GND")
	)
	(gr_poly
		(pts
			(arc
				(start 257.23342 -61.884052)
				(mid 256.97434 -61.884052)
				(end 257.23342 -61.884052)
			)
		)
		(stroke
			(width 0)
			(type solid)
		)
		(fill yes)
		(layer "F.Cu")
		(net "GND")
	)
	(gr_poly
		(pts
			(arc
				(start 257.430524 -331.851508)
				(mid 257.171444 -331.851508)
				(end 257.430524 -331.851508)
			)
		)
		(stroke
			(width 0)
			(type solid)
		)
		(fill yes)
		(layer "F.Cu")
		(net "GND")
	)
	(gr_poly
		(pts
			(arc
				(start 257.557524 -341.503508)
				(mid 257.298444 -341.503508)
				(end 257.557524 -341.503508)
			)
		)
		(stroke
			(width 0)
			(type solid)
		)
		(fill yes)
		(layer "F.Cu")
		(net "GND")
	)
	(gr_poly
		(pts
			(arc
				(start 257.557524 -336.677508)
				(mid 257.298444 -336.677508)
				(end 257.557524 -336.677508)
			)
		)
		(stroke
			(width 0)
			(type solid)
		)
		(fill yes)
		(layer "F.Cu")
		(net "GND")
	)
	(gr_poly
		(pts
			(arc
				(start 257.557524 -333.375508)
				(mid 257.298444 -333.375508)
				(end 257.557524 -333.375508)
			)
		)
		(stroke
			(width 0)
			(type solid)
		)
		(fill yes)
		(layer "F.Cu")
		(net "GND")
	)
	(gr_poly
		(pts
			(arc
				(start 257.955034 -139.083796)
				(mid 257.695954 -139.083796)
				(end 257.955034 -139.083796)
			)
		)
		(stroke
			(width 0)
			(type solid)
		)
		(fill yes)
		(layer "F.Cu")
		(net "GND")
	)
	(gr_poly
		(pts
			(arc
				(start 258.183634 -140.825728)
				(mid 257.924554 -140.825728)
				(end 258.183634 -140.825728)
			)
		)
		(stroke
			(width 0)
			(type solid)
		)
		(fill yes)
		(layer "F.Cu")
		(net "GND")
	)
	(gr_poly
		(pts
			(arc
				(start 259.51942 -61.884052)
				(mid 259.26034 -61.884052)
				(end 259.51942 -61.884052)
			)
		)
		(stroke
			(width 0)
			(type solid)
		)
		(fill yes)
		(layer "F.Cu")
		(net "GND")
	)
	(gr_poly
		(pts
			(arc
				(start 259.834634 -141.968728)
				(mid 259.575554 -141.968728)
				(end 259.834634 -141.968728)
			)
		)
		(stroke
			(width 0)
			(type solid)
		)
		(fill yes)
		(layer "F.Cu")
		(net "GND")
	)
	(gr_poly
		(pts
			(arc
				(start 261.134606 -141.968728)
				(mid 260.875526 -141.968728)
				(end 261.134606 -141.968728)
			)
		)
		(stroke
			(width 0)
			(type solid)
		)
		(fill yes)
		(layer "F.Cu")
		(net "GND")
	)
	(gr_poly
		(pts
			(arc
				(start 262.404606 -142.223236)
				(mid 262.145526 -142.223236)
				(end 262.404606 -142.223236)
			)
		)
		(stroke
			(width 0)
			(type solid)
		)
		(fill yes)
		(layer "F.Cu")
		(net "GND")
	)
	(gr_poly
		(pts
			(arc
				(start 263.581388 -129.77876)
				(mid 263.322308 -129.77876)
				(end 263.581388 -129.77876)
			)
		)
		(stroke
			(width 0)
			(type solid)
		)
		(fill yes)
		(layer "F.Cu")
		(net "GND")
	)
	(gr_poly
		(pts
			(arc
				(start 264.314178 -134.495032)
				(mid 264.055098 -134.495032)
				(end 264.314178 -134.495032)
			)
		)
		(stroke
			(width 0)
			(type solid)
		)
		(fill yes)
		(layer "F.Cu")
		(net "GND")
	)
	(gr_poly
		(pts
			(arc
				(start 264.5156 -186.872118)
				(mid 264.25652 -186.872118)
				(end 264.5156 -186.872118)
			)
		)
		(stroke
			(width 0)
			(type solid)
		)
		(fill yes)
		(layer "F.Cu")
		(net "GND")
	)
	(gr_poly
		(pts
			(arc
				(start 264.608056 -133.063996)
				(mid 264.348976 -133.063996)
				(end 264.608056 -133.063996)
			)
		)
		(stroke
			(width 0)
			(type solid)
		)
		(fill yes)
		(layer "F.Cu")
		(net "GND")
	)
	(gr_poly
		(pts
			(arc
				(start 265.09726 -138.944858)
				(mid 264.83818 -138.944858)
				(end 265.09726 -138.944858)
			)
		)
		(stroke
			(width 0)
			(type solid)
		)
		(fill yes)
		(layer "F.Cu")
		(net "GND")
	)
	(gr_poly
		(pts
			(arc
				(start 265.308588 -68.239386)
				(mid 265.049508 -68.239386)
				(end 265.308588 -68.239386)
			)
		)
		(stroke
			(width 0)
			(type solid)
		)
		(fill yes)
		(layer "F.Cu")
		(net "GND")
	)
	(gr_poly
		(pts
			(arc
				(start 265.56335 -112.878616)
				(mid 265.30427 -112.878616)
				(end 265.56335 -112.878616)
			)
		)
		(stroke
			(width 0)
			(type solid)
		)
		(fill yes)
		(layer "F.Cu")
		(net "GND")
	)
	(gr_poly
		(pts
			(arc
				(start 267.20927 -67.343782)
				(mid 266.95019 -67.343782)
				(end 267.20927 -67.343782)
			)
		)
		(stroke
			(width 0)
			(type solid)
		)
		(fill yes)
		(layer "F.Cu")
		(net "GND")
	)
	(gr_poly
		(pts
			(arc
				(start 267.93571 -65.709292)
				(mid 267.67663 -65.709292)
				(end 267.93571 -65.709292)
			)
		)
		(stroke
			(width 0)
			(type solid)
		)
		(fill yes)
		(layer "F.Cu")
		(net "GND")
	)
	(gr_poly
		(pts
			(arc
				(start 268.336776 -97.913952)
				(mid 268.077696 -97.913952)
				(end 268.336776 -97.913952)
			)
		)
		(stroke
			(width 0)
			(type solid)
		)
		(fill yes)
		(layer "F.Cu")
		(net "GND")
	)
	(gr_poly
		(pts
			(arc
				(start 268.484858 -130.247898)
				(mid 268.225778 -130.247898)
				(end 268.484858 -130.247898)
			)
		)
		(stroke
			(width 0)
			(type solid)
		)
		(fill yes)
		(layer "F.Cu")
		(net "GND")
	)
	(gr_poly
		(pts
			(arc
				(start 269.836138 -132.004562)
				(mid 269.577058 -132.004562)
				(end 269.836138 -132.004562)
			)
		)
		(stroke
			(width 0)
			(type solid)
		)
		(fill yes)
		(layer "F.Cu")
		(net "GND")
	)
	(gr_poly
		(pts
			(arc
				(start 270.287496 -186.285886)
				(mid 270.028416 -186.285886)
				(end 270.287496 -186.285886)
			)
		)
		(stroke
			(width 0)
			(type solid)
		)
		(fill yes)
		(layer "F.Cu")
		(net "GND")
	)
	(gr_poly
		(pts
			(arc
				(start 270.779748 -68.946014)
				(mid 270.520668 -68.946014)
				(end 270.779748 -68.946014)
			)
		)
		(stroke
			(width 0)
			(type solid)
		)
		(fill yes)
		(layer "F.Cu")
		(net "GND")
	)
	(gr_poly
		(pts
			(arc
				(start 271.437862 -97.456752)
				(mid 271.178782 -97.456752)
				(end 271.437862 -97.456752)
			)
		)
		(stroke
			(width 0)
			(type solid)
		)
		(fill yes)
		(layer "F.Cu")
		(net "GND")
	)
	(gr_poly
		(pts
			(arc
				(start 272.723356 -97.387918)
				(mid 272.464276 -97.387918)
				(end 272.723356 -97.387918)
			)
		)
		(stroke
			(width 0)
			(type solid)
		)
		(fill yes)
		(layer "F.Cu")
		(net "GND")
	)
	(gr_poly
		(pts
			(arc
				(start 274.737322 -117.225064)
				(mid 274.478242 -117.225064)
				(end 274.737322 -117.225064)
			)
		)
		(stroke
			(width 0)
			(type solid)
		)
		(fill yes)
		(layer "F.Cu")
		(net "GND")
	)
	(gr_poly
		(pts
			(arc
				(start 274.864068 -164.808916)
				(mid 274.604988 -164.808916)
				(end 274.864068 -164.808916)
			)
		)
		(stroke
			(width 0)
			(type solid)
		)
		(fill yes)
		(layer "F.Cu")
		(net "GND")
	)
	(gr_poly
		(pts
			(arc
				(start 274.921218 -68.543424)
				(mid 274.662138 -68.543424)
				(end 274.921218 -68.543424)
			)
		)
		(stroke
			(width 0)
			(type solid)
		)
		(fill yes)
		(layer "F.Cu")
		(net "GND")
	)
	(gr_poly
		(pts
			(arc
				(start 275.419566 -89.685876)
				(mid 275.160486 -89.685876)
				(end 275.419566 -89.685876)
			)
		)
		(stroke
			(width 0)
			(type solid)
		)
		(fill yes)
		(layer "F.Cu")
		(net "GND")
	)
	(gr_poly
		(pts
			(arc
				(start 276.22754 -121.285)
				(mid 275.96846 -121.285)
				(end 276.22754 -121.285)
			)
		)
		(stroke
			(width 0)
			(type solid)
		)
		(fill yes)
		(layer "F.Cu")
		(net "GND")
	)
	(gr_poly
		(pts
			(arc
				(start 276.66696 -129.377948)
				(mid 276.40788 -129.377948)
				(end 276.66696 -129.377948)
			)
		)
		(stroke
			(width 0)
			(type solid)
		)
		(fill yes)
		(layer "F.Cu")
		(net "GND")
	)
	(gr_poly
		(pts
			(arc
				(start 277.025862 -417.48075)
				(mid 276.766782 -417.48075)
				(end 277.025862 -417.48075)
			)
		)
		(stroke
			(width 0)
			(type solid)
		)
		(fill yes)
		(layer "F.Cu")
		(net "GND")
	)
	(gr_poly
		(pts
			(arc
				(start 277.250144 -419.869874)
				(mid 276.991064 -419.869874)
				(end 277.250144 -419.869874)
			)
		)
		(stroke
			(width 0)
			(type solid)
		)
		(fill yes)
		(layer "F.Cu")
		(net "GND")
	)
	(gr_poly
		(pts
			(arc
				(start 277.50516 -437.093614)
				(mid 277.24608 -437.093614)
				(end 277.50516 -437.093614)
			)
		)
		(stroke
			(width 0)
			(type solid)
		)
		(fill yes)
		(layer "F.Cu")
		(net "GND")
	)
	(gr_poly
		(pts
			(arc
				(start 283.03093 -406.771348)
				(mid 282.77185 -406.771348)
				(end 283.03093 -406.771348)
			)
		)
		(stroke
			(width 0)
			(type solid)
		)
		(fill yes)
		(layer "F.Cu")
		(net "GND")
	)
	(gr_poly
		(pts
			(arc
				(start 283.072332 -435.417976)
				(mid 282.813252 -435.417976)
				(end 283.072332 -435.417976)
			)
		)
		(stroke
			(width 0)
			(type solid)
		)
		(fill yes)
		(layer "F.Cu")
		(net "GND")
	)
	(gr_poly
		(pts
			(arc
				(start 283.914342 -406.787604)
				(mid 283.655262 -406.787604)
				(end 283.914342 -406.787604)
			)
		)
		(stroke
			(width 0)
			(type solid)
		)
		(fill yes)
		(layer "F.Cu")
		(net "GND")
	)
	(gr_poly
		(pts
			(arc
				(start 284.102556 -402.566632)
				(mid 283.843476 -402.566632)
				(end 284.102556 -402.566632)
			)
		)
		(stroke
			(width 0)
			(type solid)
		)
		(fill yes)
		(layer "F.Cu")
		(net "GND")
	)
	(gr_poly
		(pts
			(arc
				(start 284.184344 -404.905972)
				(mid 283.925264 -404.905972)
				(end 284.184344 -404.905972)
			)
		)
		(stroke
			(width 0)
			(type solid)
		)
		(fill yes)
		(layer "F.Cu")
		(net "GND")
	)
	(gr_poly
		(pts
			(arc
				(start 286.065468 -423.182288)
				(mid 285.806388 -423.182288)
				(end 286.065468 -423.182288)
			)
		)
		(stroke
			(width 0)
			(type solid)
		)
		(fill yes)
		(layer "F.Cu")
		(net "GND")
	)
	(gr_poly
		(pts
			(arc
				(start 286.95396 -423.208196)
				(mid 286.69488 -423.208196)
				(end 286.95396 -423.208196)
			)
		)
		(stroke
			(width 0)
			(type solid)
		)
		(fill yes)
		(layer "F.Cu")
		(net "GND")
	)
	(gr_poly
		(pts
			(arc
				(start 287.6042 -405.887936)
				(mid 287.34512 -405.887936)
				(end 287.6042 -405.887936)
			)
		)
		(stroke
			(width 0)
			(type solid)
		)
		(fill yes)
		(layer "F.Cu")
		(net "GND")
	)
	(gr_poly
		(pts
			(arc
				(start 287.614868 -408.24023)
				(mid 287.355788 -408.24023)
				(end 287.614868 -408.24023)
			)
		)
		(stroke
			(width 0)
			(type solid)
		)
		(fill yes)
		(layer "F.Cu")
		(net "GND")
	)
	(gr_poly
		(pts
			(arc
				(start 287.755838 -156.377132)
				(mid 287.496758 -156.377132)
				(end 287.755838 -156.377132)
			)
		)
		(stroke
			(width 0)
			(type solid)
		)
		(fill yes)
		(layer "F.Cu")
		(net "GND")
	)
	(gr_poly
		(pts
			(arc
				(start 290.10737 -416.564318)
				(mid 289.84829 -416.564318)
				(end 290.10737 -416.564318)
			)
		)
		(stroke
			(width 0)
			(type solid)
		)
		(fill yes)
		(layer "F.Cu")
		(net "GND")
	)
	(gr_poly
		(pts
			(arc
				(start 290.467542 -401.404836)
				(mid 290.208462 -401.404836)
				(end 290.467542 -401.404836)
			)
		)
		(stroke
			(width 0)
			(type solid)
		)
		(fill yes)
		(layer "F.Cu")
		(net "GND")
	)
	(gr_poly
		(pts
			(arc
				(start 290.483798 -418.863272)
				(mid 290.224718 -418.863272)
				(end 290.483798 -418.863272)
			)
		)
		(stroke
			(width 0)
			(type solid)
		)
		(fill yes)
		(layer "F.Cu")
		(net "GND")
	)
	(gr_poly
		(pts
			(arc
				(start 290.97478 -403.564598)
				(mid 290.7157 -403.564598)
				(end 290.97478 -403.564598)
			)
		)
		(stroke
			(width 0)
			(type solid)
		)
		(fill yes)
		(layer "F.Cu")
		(net "GND")
	)
	(gr_poly
		(pts
			(arc
				(start 291.293804 -418.953188)
				(mid 291.034724 -418.953188)
				(end 291.293804 -418.953188)
			)
		)
		(stroke
			(width 0)
			(type solid)
		)
		(fill yes)
		(layer "F.Cu")
		(net "GND")
	)
	(gr_poly
		(pts
			(arc
				(start 291.334698 -421.244014)
				(mid 291.075618 -421.244014)
				(end 291.334698 -421.244014)
			)
		)
		(stroke
			(width 0)
			(type solid)
		)
		(fill yes)
		(layer "F.Cu")
		(net "GND")
	)
	(gr_poly
		(pts
			(arc
				(start 295.102534 -393.243816)
				(mid 294.843454 -393.243816)
				(end 295.102534 -393.243816)
			)
		)
		(stroke
			(width 0)
			(type solid)
		)
		(fill yes)
		(layer "F.Cu")
		(net "GND")
	)
	(gr_poly
		(pts
			(arc
				(start 295.314116 -421.142668)
				(mid 295.055036 -421.142668)
				(end 295.314116 -421.142668)
			)
		)
		(stroke
			(width 0)
			(type solid)
		)
		(fill yes)
		(layer "F.Cu")
		(net "GND")
	)
	(gr_poly
		(pts
			(arc
				(start 296.189146 -144.555972)
				(mid 295.930066 -144.555972)
				(end 296.189146 -144.555972)
			)
		)
		(stroke
			(width 0)
			(type solid)
		)
		(fill yes)
		(layer "F.Cu")
		(net "GND")
	)
	(gr_poly
		(pts
			(arc
				(start 296.90187 -390.92632)
				(mid 296.638218 -390.92632)
				(end 296.90187 -390.92632)
			)
		)
		(stroke
			(width 0)
			(type solid)
		)
		(fill yes)
		(layer "F.Cu")
		(net "GND")
	)
	(gr_poly
		(pts
			(arc
				(start 296.90187 -389.7122)
				(mid 296.638218 -389.7122)
				(end 296.90187 -389.7122)
			)
		)
		(stroke
			(width 0)
			(type solid)
		)
		(fill yes)
		(layer "F.Cu")
		(net "GND")
	)
	(gr_poly
		(pts
			(arc
				(start 296.90187 -385.38912)
				(mid 296.638218 -385.38912)
				(end 296.90187 -385.38912)
			)
		)
		(stroke
			(width 0)
			(type solid)
		)
		(fill yes)
		(layer "F.Cu")
		(net "GND")
	)
	(gr_poly
		(pts
			(arc
				(start 296.90187 -384.175)
				(mid 296.638218 -384.175)
				(end 296.90187 -384.175)
			)
		)
		(stroke
			(width 0)
			(type solid)
		)
		(fill yes)
		(layer "F.Cu")
		(net "GND")
	)
	(gr_poly
		(pts
			(arc
				(start 297.56227 -391.41146)
				(mid 297.298618 -391.41146)
				(end 297.56227 -391.41146)
			)
		)
		(stroke
			(width 0)
			(type solid)
		)
		(fill yes)
		(layer "F.Cu")
		(net "GND")
	)
	(gr_poly
		(pts
			(arc
				(start 297.56227 -389.25246)
				(mid 297.298618 -389.25246)
				(end 297.56227 -389.25246)
			)
		)
		(stroke
			(width 0)
			(type solid)
		)
		(fill yes)
		(layer "F.Cu")
		(net "GND")
	)
	(gr_poly
		(pts
			(arc
				(start 297.56227 -385.87426)
				(mid 297.298618 -385.87426)
				(end 297.56227 -385.87426)
			)
		)
		(stroke
			(width 0)
			(type solid)
		)
		(fill yes)
		(layer "F.Cu")
		(net "GND")
	)
	(gr_poly
		(pts
			(arc
				(start 297.56227 -383.68986)
				(mid 297.298618 -383.68986)
				(end 297.56227 -383.68986)
			)
		)
		(stroke
			(width 0)
			(type solid)
		)
		(fill yes)
		(layer "F.Cu")
		(net "GND")
	)
	(gr_poly
		(pts
			(arc
				(start 298.22267 -390.92632)
				(mid 297.959018 -390.92632)
				(end 298.22267 -390.92632)
			)
		)
		(stroke
			(width 0)
			(type solid)
		)
		(fill yes)
		(layer "F.Cu")
		(net "GND")
	)
	(gr_poly
		(pts
			(arc
				(start 298.22267 -389.7122)
				(mid 297.959018 -389.7122)
				(end 298.22267 -389.7122)
			)
		)
		(stroke
			(width 0)
			(type solid)
		)
		(fill yes)
		(layer "F.Cu")
		(net "GND")
	)
	(gr_poly
		(pts
			(arc
				(start 298.22267 -385.38912)
				(mid 297.959018 -385.38912)
				(end 298.22267 -385.38912)
			)
		)
		(stroke
			(width 0)
			(type solid)
		)
		(fill yes)
		(layer "F.Cu")
		(net "GND")
	)
	(gr_poly
		(pts
			(arc
				(start 298.22267 -384.175)
				(mid 297.959018 -384.175)
				(end 298.22267 -384.175)
			)
		)
		(stroke
			(width 0)
			(type solid)
		)
		(fill yes)
		(layer "F.Cu")
		(net "GND")
	)
	(gr_poly
		(pts
			(arc
				(start 298.486322 -379.88113)
				(mid 298.22267 -379.88113)
				(end 298.486322 -379.88113)
			)
		)
		(stroke
			(width 0)
			(type solid)
		)
		(fill yes)
		(layer "F.Cu")
		(net "GND")
	)
	(gr_poly
		(pts
			(arc
				(start 298.971462 -380.54153)
				(mid 298.70781 -380.54153)
				(end 298.971462 -380.54153)
			)
		)
		(stroke
			(width 0)
			(type solid)
		)
		(fill yes)
		(layer "F.Cu")
		(net "GND")
	)
	(gr_poly
		(pts
			(arc
				(start 298.971462 -379.22073)
				(mid 298.70781 -379.22073)
				(end 298.971462 -379.22073)
			)
		)
		(stroke
			(width 0)
			(type solid)
		)
		(fill yes)
		(layer "F.Cu")
		(net "GND")
	)
	(gr_poly
		(pts
			(arc
				(start 300.185582 -380.54153)
				(mid 299.92193 -380.54153)
				(end 300.185582 -380.54153)
			)
		)
		(stroke
			(width 0)
			(type solid)
		)
		(fill yes)
		(layer "F.Cu")
		(net "GND")
	)
	(gr_poly
		(pts
			(arc
				(start 300.185582 -379.22073)
				(mid 299.92193 -379.22073)
				(end 300.185582 -379.22073)
			)
		)
		(stroke
			(width 0)
			(type solid)
		)
		(fill yes)
		(layer "F.Cu")
		(net "GND")
	)
	(gr_poly
		(pts
			(arc
				(start 300.188122 -377.41733)
				(mid 299.92447 -377.41733)
				(end 300.188122 -377.41733)
			)
		)
		(stroke
			(width 0)
			(type solid)
		)
		(fill yes)
		(layer "F.Cu")
		(net "GND")
	)
	(gr_poly
		(pts
			(arc
				(start 300.670722 -379.88113)
				(mid 300.40707 -379.88113)
				(end 300.670722 -379.88113)
			)
		)
		(stroke
			(width 0)
			(type solid)
		)
		(fill yes)
		(layer "F.Cu")
		(net "GND")
	)
	(gr_poly
		(pts
			(arc
				(start 300.673262 -378.07773)
				(mid 300.40961 -378.07773)
				(end 300.673262 -378.07773)
			)
		)
		(stroke
			(width 0)
			(type solid)
		)
		(fill yes)
		(layer "F.Cu")
		(net "GND")
	)
	(gr_poly
		(pts
			(arc
				(start 300.673262 -376.75693)
				(mid 300.40961 -376.75693)
				(end 300.673262 -376.75693)
			)
		)
		(stroke
			(width 0)
			(type solid)
		)
		(fill yes)
		(layer "F.Cu")
		(net "GND")
	)
	(gr_poly
		(pts
			(arc
				(start 301.887382 -378.07773)
				(mid 301.62373 -378.07773)
				(end 301.887382 -378.07773)
			)
		)
		(stroke
			(width 0)
			(type solid)
		)
		(fill yes)
		(layer "F.Cu")
		(net "GND")
	)
	(gr_poly
		(pts
			(arc
				(start 301.887382 -376.75693)
				(mid 301.62373 -376.75693)
				(end 301.887382 -376.75693)
			)
		)
		(stroke
			(width 0)
			(type solid)
		)
		(fill yes)
		(layer "F.Cu")
		(net "GND")
	)
	(gr_poly
		(pts
			(arc
				(start 302.2727 -122.349514)
				(mid 302.01362 -122.349514)
				(end 302.2727 -122.349514)
			)
		)
		(stroke
			(width 0)
			(type solid)
		)
		(fill yes)
		(layer "F.Cu")
		(net "GND")
	)
	(gr_poly
		(pts
			(arc
				(start 302.372522 -377.41733)
				(mid 302.10887 -377.41733)
				(end 302.372522 -377.41733)
			)
		)
		(stroke
			(width 0)
			(type solid)
		)
		(fill yes)
		(layer "F.Cu")
		(net "GND")
	)
	(gr_poly
		(pts
			(arc
				(start 303.591722 -382.34493)
				(mid 303.32807 -382.34493)
				(end 303.591722 -382.34493)
			)
		)
		(stroke
			(width 0)
			(type solid)
		)
		(fill yes)
		(layer "F.Cu")
		(net "GND")
	)
	(gr_poly
		(pts
			(arc
				(start 304.076862 -383.00533)
				(mid 303.81321 -383.00533)
				(end 304.076862 -383.00533)
			)
		)
		(stroke
			(width 0)
			(type solid)
		)
		(fill yes)
		(layer "F.Cu")
		(net "GND")
	)
	(gr_poly
		(pts
			(arc
				(start 304.076862 -381.68453)
				(mid 303.81321 -381.68453)
				(end 304.076862 -381.68453)
			)
		)
		(stroke
			(width 0)
			(type solid)
		)
		(fill yes)
		(layer "F.Cu")
		(net "GND")
	)
	(gr_poly
		(pts
			(arc
				(start 305.290982 -383.00533)
				(mid 305.02733 -383.00533)
				(end 305.290982 -383.00533)
			)
		)
		(stroke
			(width 0)
			(type solid)
		)
		(fill yes)
		(layer "F.Cu")
		(net "GND")
	)
	(gr_poly
		(pts
			(arc
				(start 305.290982 -381.68453)
				(mid 305.02733 -381.68453)
				(end 305.290982 -381.68453)
			)
		)
		(stroke
			(width 0)
			(type solid)
		)
		(fill yes)
		(layer "F.Cu")
		(net "GND")
	)
	(gr_poly
		(pts
			(arc
				(start 305.293522 -379.88113)
				(mid 305.02987 -379.88113)
				(end 305.293522 -379.88113)
			)
		)
		(stroke
			(width 0)
			(type solid)
		)
		(fill yes)
		(layer "F.Cu")
		(net "GND")
	)
	(gr_poly
		(pts
			(arc
				(start 305.618134 -22.263354)
				(mid 305.359054 -22.263354)
				(end 305.618134 -22.263354)
			)
		)
		(stroke
			(width 0)
			(type solid)
		)
		(fill yes)
		(layer "F.Cu")
		(net "GND")
	)
	(gr_poly
		(pts
			(arc
				(start 305.776122 -382.34493)
				(mid 305.51247 -382.34493)
				(end 305.776122 -382.34493)
			)
		)
		(stroke
			(width 0)
			(type solid)
		)
		(fill yes)
		(layer "F.Cu")
		(net "GND")
	)
	(gr_poly
		(pts
			(arc
				(start 305.778662 -380.54153)
				(mid 305.51501 -380.54153)
				(end 305.778662 -380.54153)
			)
		)
		(stroke
			(width 0)
			(type solid)
		)
		(fill yes)
		(layer "F.Cu")
		(net "GND")
	)
	(gr_poly
		(pts
			(arc
				(start 305.778662 -379.22073)
				(mid 305.51501 -379.22073)
				(end 305.778662 -379.22073)
			)
		)
		(stroke
			(width 0)
			(type solid)
		)
		(fill yes)
		(layer "F.Cu")
		(net "GND")
	)
	(gr_poly
		(pts
			(arc
				(start 306.992782 -380.54153)
				(mid 306.72913 -380.54153)
				(end 306.992782 -380.54153)
			)
		)
		(stroke
			(width 0)
			(type solid)
		)
		(fill yes)
		(layer "F.Cu")
		(net "GND")
	)
	(gr_poly
		(pts
			(arc
				(start 306.992782 -379.22073)
				(mid 306.72913 -379.22073)
				(end 306.992782 -379.22073)
			)
		)
		(stroke
			(width 0)
			(type solid)
		)
		(fill yes)
		(layer "F.Cu")
		(net "GND")
	)
	(gr_poly
		(pts
			(arc
				(start 306.995322 -377.41733)
				(mid 306.73167 -377.41733)
				(end 306.995322 -377.41733)
			)
		)
		(stroke
			(width 0)
			(type solid)
		)
		(fill yes)
		(layer "F.Cu")
		(net "GND")
	)
	(gr_poly
		(pts
			(arc
				(start 307.438806 -431.891186)
				(mid 307.179726 -431.891186)
				(end 307.438806 -431.891186)
			)
		)
		(stroke
			(width 0)
			(type solid)
		)
		(fill yes)
		(layer "F.Cu")
		(net "GND")
	)
	(gr_poly
		(pts
			(arc
				(start 307.477922 -379.88113)
				(mid 307.21427 -379.88113)
				(end 307.477922 -379.88113)
			)
		)
		(stroke
			(width 0)
			(type solid)
		)
		(fill yes)
		(layer "F.Cu")
		(net "GND")
	)
	(gr_poly
		(pts
			(arc
				(start 307.480462 -378.07773)
				(mid 307.21681 -378.07773)
				(end 307.480462 -378.07773)
			)
		)
		(stroke
			(width 0)
			(type solid)
		)
		(fill yes)
		(layer "F.Cu")
		(net "GND")
	)
	(gr_poly
		(pts
			(arc
				(start 307.480462 -376.75693)
				(mid 307.21681 -376.75693)
				(end 307.480462 -376.75693)
			)
		)
		(stroke
			(width 0)
			(type solid)
		)
		(fill yes)
		(layer "F.Cu")
		(net "GND")
	)
	(gr_poly
		(pts
			(arc
				(start 308.694582 -378.07773)
				(mid 308.43093 -378.07773)
				(end 308.694582 -378.07773)
			)
		)
		(stroke
			(width 0)
			(type solid)
		)
		(fill yes)
		(layer "F.Cu")
		(net "GND")
	)
	(gr_poly
		(pts
			(arc
				(start 308.694582 -376.75693)
				(mid 308.43093 -376.75693)
				(end 308.694582 -376.75693)
			)
		)
		(stroke
			(width 0)
			(type solid)
		)
		(fill yes)
		(layer "F.Cu")
		(net "GND")
	)
	(gr_poly
		(pts
			(arc
				(start 308.702964 -106.938572)
				(mid 308.443884 -106.938572)
				(end 308.702964 -106.938572)
			)
		)
		(stroke
			(width 0)
			(type solid)
		)
		(fill yes)
		(layer "F.Cu")
		(net "GND")
	)
	(gr_poly
		(pts
			(arc
				(start 309.179722 -377.41733)
				(mid 308.91607 -377.41733)
				(end 309.179722 -377.41733)
			)
		)
		(stroke
			(width 0)
			(type solid)
		)
		(fill yes)
		(layer "F.Cu")
		(net "GND")
	)
	(gr_poly
		(pts
			(arc
				(start 309.942992 -439.676794)
				(mid 309.683912 -439.676794)
				(end 309.942992 -439.676794)
			)
		)
		(stroke
			(width 0)
			(type solid)
		)
		(fill yes)
		(layer "F.Cu")
		(net "GND")
	)
	(gr_poly
		(pts
			(arc
				(start 309.942992 -436.120794)
				(mid 309.683912 -436.120794)
				(end 309.942992 -436.120794)
			)
		)
		(stroke
			(width 0)
			(type solid)
		)
		(fill yes)
		(layer "F.Cu")
		(net "GND")
	)
	(gr_poly
		(pts
			(arc
				(start 310.398922 -382.34493)
				(mid 310.13527 -382.34493)
				(end 310.398922 -382.34493)
			)
		)
		(stroke
			(width 0)
			(type solid)
		)
		(fill yes)
		(layer "F.Cu")
		(net "GND")
	)
	(gr_poly
		(pts
			(arc
				(start 310.884062 -383.00533)
				(mid 310.62041 -383.00533)
				(end 310.884062 -383.00533)
			)
		)
		(stroke
			(width 0)
			(type solid)
		)
		(fill yes)
		(layer "F.Cu")
		(net "GND")
	)
	(gr_poly
		(pts
			(arc
				(start 310.884062 -381.68453)
				(mid 310.62041 -381.68453)
				(end 310.884062 -381.68453)
			)
		)
		(stroke
			(width 0)
			(type solid)
		)
		(fill yes)
		(layer "F.Cu")
		(net "GND")
	)
	(gr_poly
		(pts
			(arc
				(start 311.557416 -77.524864)
				(mid 311.298336 -77.524864)
				(end 311.557416 -77.524864)
			)
		)
		(stroke
			(width 0)
			(type solid)
		)
		(fill yes)
		(layer "F.Cu")
		(net "GND")
	)
	(gr_poly
		(pts
			(arc
				(start 311.557416 -75.454764)
				(mid 311.298336 -75.454764)
				(end 311.557416 -75.454764)
			)
		)
		(stroke
			(width 0)
			(type solid)
		)
		(fill yes)
		(layer "F.Cu")
		(net "GND")
	)
	(gr_poly
		(pts
			(arc
				(start 312.098182 -383.00533)
				(mid 311.83453 -383.00533)
				(end 312.098182 -383.00533)
			)
		)
		(stroke
			(width 0)
			(type solid)
		)
		(fill yes)
		(layer "F.Cu")
		(net "GND")
	)
	(gr_poly
		(pts
			(arc
				(start 312.098182 -381.68453)
				(mid 311.83453 -381.68453)
				(end 312.098182 -381.68453)
			)
		)
		(stroke
			(width 0)
			(type solid)
		)
		(fill yes)
		(layer "F.Cu")
		(net "GND")
	)
	(gr_poly
		(pts
			(arc
				(start 312.100722 -379.88113)
				(mid 311.83707 -379.88113)
				(end 312.100722 -379.88113)
			)
		)
		(stroke
			(width 0)
			(type solid)
		)
		(fill yes)
		(layer "F.Cu")
		(net "GND")
	)
	(gr_poly
		(pts
			(arc
				(start 312.573416 -79.810864)
				(mid 312.314336 -79.810864)
				(end 312.573416 -79.810864)
			)
		)
		(stroke
			(width 0)
			(type solid)
		)
		(fill yes)
		(layer "F.Cu")
		(net "GND")
	)
	(gr_poly
		(pts
			(arc
				(start 312.583322 -382.34493)
				(mid 312.31967 -382.34493)
				(end 312.583322 -382.34493)
			)
		)
		(stroke
			(width 0)
			(type solid)
		)
		(fill yes)
		(layer "F.Cu")
		(net "GND")
	)
	(gr_poly
		(pts
			(arc
				(start 312.585862 -380.54153)
				(mid 312.32221 -380.54153)
				(end 312.585862 -380.54153)
			)
		)
		(stroke
			(width 0)
			(type solid)
		)
		(fill yes)
		(layer "F.Cu")
		(net "GND")
	)
	(gr_poly
		(pts
			(arc
				(start 312.585862 -379.22073)
				(mid 312.32221 -379.22073)
				(end 312.585862 -379.22073)
			)
		)
		(stroke
			(width 0)
			(type solid)
		)
		(fill yes)
		(layer "F.Cu")
		(net "GND")
	)
	(gr_poly
		(pts
			(arc
				(start 313.799982 -380.54153)
				(mid 313.53633 -380.54153)
				(end 313.799982 -380.54153)
			)
		)
		(stroke
			(width 0)
			(type solid)
		)
		(fill yes)
		(layer "F.Cu")
		(net "GND")
	)
	(gr_poly
		(pts
			(arc
				(start 313.799982 -379.22073)
				(mid 313.53633 -379.22073)
				(end 313.799982 -379.22073)
			)
		)
		(stroke
			(width 0)
			(type solid)
		)
		(fill yes)
		(layer "F.Cu")
		(net "GND")
	)
	(gr_poly
		(pts
			(arc
				(start 313.802522 -377.41733)
				(mid 313.53887 -377.41733)
				(end 313.802522 -377.41733)
			)
		)
		(stroke
			(width 0)
			(type solid)
		)
		(fill yes)
		(layer "F.Cu")
		(net "GND")
	)
	(gr_poly
		(pts
			(arc
				(start 313.958224 -19.124422)
				(mid 313.699144 -19.124422)
				(end 313.958224 -19.124422)
			)
		)
		(stroke
			(width 0)
			(type solid)
		)
		(fill yes)
		(layer "F.Cu")
		(net "GND")
	)
	(gr_poly
		(pts
			(arc
				(start 314.285122 -379.88113)
				(mid 314.02147 -379.88113)
				(end 314.285122 -379.88113)
			)
		)
		(stroke
			(width 0)
			(type solid)
		)
		(fill yes)
		(layer "F.Cu")
		(net "GND")
	)
	(gr_poly
		(pts
			(arc
				(start 314.287662 -378.07773)
				(mid 314.02401 -378.07773)
				(end 314.287662 -378.07773)
			)
		)
		(stroke
			(width 0)
			(type solid)
		)
		(fill yes)
		(layer "F.Cu")
		(net "GND")
	)
	(gr_poly
		(pts
			(arc
				(start 314.287662 -376.75693)
				(mid 314.02401 -376.75693)
				(end 314.287662 -376.75693)
			)
		)
		(stroke
			(width 0)
			(type solid)
		)
		(fill yes)
		(layer "F.Cu")
		(net "GND")
	)
	(gr_poly
		(pts
			(arc
				(start 315.501782 -378.07773)
				(mid 315.23813 -378.07773)
				(end 315.501782 -378.07773)
			)
		)
		(stroke
			(width 0)
			(type solid)
		)
		(fill yes)
		(layer "F.Cu")
		(net "GND")
	)
	(gr_poly
		(pts
			(arc
				(start 315.501782 -376.75693)
				(mid 315.23813 -376.75693)
				(end 315.501782 -376.75693)
			)
		)
		(stroke
			(width 0)
			(type solid)
		)
		(fill yes)
		(layer "F.Cu")
		(net "GND")
	)
	(gr_poly
		(pts
			(arc
				(start 315.986922 -377.41733)
				(mid 315.72327 -377.41733)
				(end 315.986922 -377.41733)
			)
		)
		(stroke
			(width 0)
			(type solid)
		)
		(fill yes)
		(layer "F.Cu")
		(net "GND")
	)
	(gr_poly
		(pts
			(arc
				(start 316.738 -122.758708)
				(mid 316.47892 -122.758708)
				(end 316.738 -122.758708)
			)
		)
		(stroke
			(width 0)
			(type solid)
		)
		(fill yes)
		(layer "F.Cu")
		(net "GND")
	)
	(gr_poly
		(pts
			(arc
				(start 316.803532 -199.581008)
				(mid 316.544452 -199.581008)
				(end 316.803532 -199.581008)
			)
		)
		(stroke
			(width 0)
			(type solid)
		)
		(fill yes)
		(layer "F.Cu")
		(net "GND")
	)
	(gr_poly
		(pts
			(arc
				(start 317.206122 -382.34493)
				(mid 316.94247 -382.34493)
				(end 317.206122 -382.34493)
			)
		)
		(stroke
			(width 0)
			(type solid)
		)
		(fill yes)
		(layer "F.Cu")
		(net "GND")
	)
	(gr_poly
		(pts
			(arc
				(start 317.691262 -383.00533)
				(mid 317.42761 -383.00533)
				(end 317.691262 -383.00533)
			)
		)
		(stroke
			(width 0)
			(type solid)
		)
		(fill yes)
		(layer "F.Cu")
		(net "GND")
	)
	(gr_poly
		(pts
			(arc
				(start 317.691262 -381.68453)
				(mid 317.42761 -381.68453)
				(end 317.691262 -381.68453)
			)
		)
		(stroke
			(width 0)
			(type solid)
		)
		(fill yes)
		(layer "F.Cu")
		(net "GND")
	)
	(gr_poly
		(pts
			(arc
				(start 318.280034 -18.45945)
				(mid 318.020954 -18.45945)
				(end 318.280034 -18.45945)
			)
		)
		(stroke
			(width 0)
			(type solid)
		)
		(fill yes)
		(layer "F.Cu")
		(net "GND")
	)
	(gr_poly
		(pts
			(arc
				(start 318.905382 -383.00533)
				(mid 318.64173 -383.00533)
				(end 318.905382 -383.00533)
			)
		)
		(stroke
			(width 0)
			(type solid)
		)
		(fill yes)
		(layer "F.Cu")
		(net "GND")
	)
	(gr_poly
		(pts
			(arc
				(start 318.905382 -381.68453)
				(mid 318.64173 -381.68453)
				(end 318.905382 -381.68453)
			)
		)
		(stroke
			(width 0)
			(type solid)
		)
		(fill yes)
		(layer "F.Cu")
		(net "GND")
	)
	(gr_poly
		(pts
			(arc
				(start 318.907922 -379.88113)
				(mid 318.64427 -379.88113)
				(end 318.907922 -379.88113)
			)
		)
		(stroke
			(width 0)
			(type solid)
		)
		(fill yes)
		(layer "F.Cu")
		(net "GND")
	)
	(gr_poly
		(pts
			(arc
				(start 319.390522 -382.34493)
				(mid 319.12687 -382.34493)
				(end 319.390522 -382.34493)
			)
		)
		(stroke
			(width 0)
			(type solid)
		)
		(fill yes)
		(layer "F.Cu")
		(net "GND")
	)
	(gr_poly
		(pts
			(arc
				(start 319.393062 -380.54153)
				(mid 319.12941 -380.54153)
				(end 319.393062 -380.54153)
			)
		)
		(stroke
			(width 0)
			(type solid)
		)
		(fill yes)
		(layer "F.Cu")
		(net "GND")
	)
	(gr_poly
		(pts
			(arc
				(start 319.393062 -379.22073)
				(mid 319.12941 -379.22073)
				(end 319.393062 -379.22073)
			)
		)
		(stroke
			(width 0)
			(type solid)
		)
		(fill yes)
		(layer "F.Cu")
		(net "GND")
	)
	(gr_poly
		(pts
			(arc
				(start 320.607182 -380.54153)
				(mid 320.34353 -380.54153)
				(end 320.607182 -380.54153)
			)
		)
		(stroke
			(width 0)
			(type solid)
		)
		(fill yes)
		(layer "F.Cu")
		(net "GND")
	)
	(gr_poly
		(pts
			(arc
				(start 320.607182 -379.22073)
				(mid 320.34353 -379.22073)
				(end 320.607182 -379.22073)
			)
		)
		(stroke
			(width 0)
			(type solid)
		)
		(fill yes)
		(layer "F.Cu")
		(net "GND")
	)
	(gr_poly
		(pts
			(arc
				(start 320.609722 -377.41733)
				(mid 320.34607 -377.41733)
				(end 320.609722 -377.41733)
			)
		)
		(stroke
			(width 0)
			(type solid)
		)
		(fill yes)
		(layer "F.Cu")
		(net "GND")
	)
	(gr_poly
		(pts
			(arc
				(start 321.092322 -379.88113)
				(mid 320.82867 -379.88113)
				(end 321.092322 -379.88113)
			)
		)
		(stroke
			(width 0)
			(type solid)
		)
		(fill yes)
		(layer "F.Cu")
		(net "GND")
	)
	(gr_poly
		(pts
			(arc
				(start 321.094862 -378.07773)
				(mid 320.83121 -378.07773)
				(end 321.094862 -378.07773)
			)
		)
		(stroke
			(width 0)
			(type solid)
		)
		(fill yes)
		(layer "F.Cu")
		(net "GND")
	)
	(gr_poly
		(pts
			(arc
				(start 321.094862 -376.75693)
				(mid 320.83121 -376.75693)
				(end 321.094862 -376.75693)
			)
		)
		(stroke
			(width 0)
			(type solid)
		)
		(fill yes)
		(layer "F.Cu")
		(net "GND")
	)
	(gr_poly
		(pts
			(arc
				(start 321.730624 -30.739588)
				(mid 321.471544 -30.739588)
				(end 321.730624 -30.739588)
			)
		)
		(stroke
			(width 0)
			(type solid)
		)
		(fill yes)
		(layer "F.Cu")
		(net "GND")
	)
	(gr_poly
		(pts
			(arc
				(start 322.308982 -378.07773)
				(mid 322.04533 -378.07773)
				(end 322.308982 -378.07773)
			)
		)
		(stroke
			(width 0)
			(type solid)
		)
		(fill yes)
		(layer "F.Cu")
		(net "GND")
	)
	(gr_poly
		(pts
			(arc
				(start 322.308982 -376.75693)
				(mid 322.04533 -376.75693)
				(end 322.308982 -376.75693)
			)
		)
		(stroke
			(width 0)
			(type solid)
		)
		(fill yes)
		(layer "F.Cu")
		(net "GND")
	)
	(gr_poly
		(pts
			(arc
				(start 322.794122 -377.41733)
				(mid 322.53047 -377.41733)
				(end 322.794122 -377.41733)
			)
		)
		(stroke
			(width 0)
			(type solid)
		)
		(fill yes)
		(layer "F.Cu")
		(net "GND")
	)
	(gr_poly
		(pts
			(arc
				(start 324.013322 -377.41733)
				(mid 323.74967 -377.41733)
				(end 324.013322 -377.41733)
			)
		)
		(stroke
			(width 0)
			(type solid)
		)
		(fill yes)
		(layer "F.Cu")
		(net "GND")
	)
	(gr_poly
		(pts
			(arc
				(start 324.498462 -378.07773)
				(mid 324.23481 -378.07773)
				(end 324.498462 -378.07773)
			)
		)
		(stroke
			(width 0)
			(type solid)
		)
		(fill yes)
		(layer "F.Cu")
		(net "GND")
	)
	(gr_poly
		(pts
			(arc
				(start 324.498462 -376.75693)
				(mid 324.23481 -376.75693)
				(end 324.498462 -376.75693)
			)
		)
		(stroke
			(width 0)
			(type solid)
		)
		(fill yes)
		(layer "F.Cu")
		(net "GND")
	)
	(gr_poly
		(pts
			(arc
				(start 324.913498 -205.482952)
				(mid 324.654418 -205.482952)
				(end 324.913498 -205.482952)
			)
		)
		(stroke
			(width 0)
			(type solid)
		)
		(fill yes)
		(layer "F.Cu")
		(net "GND")
	)
	(gr_poly
		(pts
			(arc
				(start 325.712582 -378.07773)
				(mid 325.44893 -378.07773)
				(end 325.712582 -378.07773)
			)
		)
		(stroke
			(width 0)
			(type solid)
		)
		(fill yes)
		(layer "F.Cu")
		(net "GND")
	)
	(gr_poly
		(pts
			(arc
				(start 325.712582 -376.75693)
				(mid 325.44893 -376.75693)
				(end 325.712582 -376.75693)
			)
		)
		(stroke
			(width 0)
			(type solid)
		)
		(fill yes)
		(layer "F.Cu")
		(net "GND")
	)
	(gr_poly
		(pts
			(arc
				(start 326.197722 -377.41733)
				(mid 325.93407 -377.41733)
				(end 326.197722 -377.41733)
			)
		)
		(stroke
			(width 0)
			(type solid)
		)
		(fill yes)
		(layer "F.Cu")
		(net "GND")
	)
	(gr_poly
		(pts
			(arc
				(start 326.748902 -388.917688)
				(mid 326.48525 -388.917688)
				(end 326.748902 -388.917688)
			)
		)
		(stroke
			(width 0)
			(type solid)
		)
		(fill yes)
		(layer "F.Cu")
		(net "GND")
	)
	(gr_poly
		(pts
			(arc
				(start 326.748902 -387.703568)
				(mid 326.48525 -387.703568)
				(end 326.748902 -387.703568)
			)
		)
		(stroke
			(width 0)
			(type solid)
		)
		(fill yes)
		(layer "F.Cu")
		(net "GND")
	)
	(gr_poly
		(pts
			(arc
				(start 326.748902 -385.514088)
				(mid 326.48525 -385.514088)
				(end 326.748902 -385.514088)
			)
		)
		(stroke
			(width 0)
			(type solid)
		)
		(fill yes)
		(layer "F.Cu")
		(net "GND")
	)
	(gr_poly
		(pts
			(arc
				(start 326.748902 -384.299968)
				(mid 326.48525 -384.299968)
				(end 326.748902 -384.299968)
			)
		)
		(stroke
			(width 0)
			(type solid)
		)
		(fill yes)
		(layer "F.Cu")
		(net "GND")
	)
	(gr_poly
		(pts
			(arc
				(start 327.409302 -387.218428)
				(mid 327.14565 -387.218428)
				(end 327.409302 -387.218428)
			)
		)
		(stroke
			(width 0)
			(type solid)
		)
		(fill yes)
		(layer "F.Cu")
		(net "GND")
	)
	(gr_poly
		(pts
			(arc
				(start 327.409302 -385.999228)
				(mid 327.14565 -385.999228)
				(end 327.409302 -385.999228)
			)
		)
		(stroke
			(width 0)
			(type solid)
		)
		(fill yes)
		(layer "F.Cu")
		(net "GND")
	)
	(gr_poly
		(pts
			(arc
				(start 327.409302 -383.814828)
				(mid 327.14565 -383.814828)
				(end 327.409302 -383.814828)
			)
		)
		(stroke
			(width 0)
			(type solid)
		)
		(fill yes)
		(layer "F.Cu")
		(net "GND")
	)
	(gr_poly
		(pts
			(arc
				(start 328.069702 -388.917688)
				(mid 327.80605 -388.917688)
				(end 328.069702 -388.917688)
			)
		)
		(stroke
			(width 0)
			(type solid)
		)
		(fill yes)
		(layer "F.Cu")
		(net "GND")
	)
	(gr_poly
		(pts
			(arc
				(start 328.069702 -387.703568)
				(mid 327.80605 -387.703568)
				(end 328.069702 -387.703568)
			)
		)
		(stroke
			(width 0)
			(type solid)
		)
		(fill yes)
		(layer "F.Cu")
		(net "GND")
	)
	(gr_poly
		(pts
			(arc
				(start 328.069702 -385.514088)
				(mid 327.80605 -385.514088)
				(end 328.069702 -385.514088)
			)
		)
		(stroke
			(width 0)
			(type solid)
		)
		(fill yes)
		(layer "F.Cu")
		(net "GND")
	)
	(gr_poly
		(pts
			(arc
				(start 328.069702 -384.299968)
				(mid 327.80605 -384.299968)
				(end 328.069702 -384.299968)
			)
		)
		(stroke
			(width 0)
			(type solid)
		)
		(fill yes)
		(layer "F.Cu")
		(net "GND")
	)
	(gr_poly
		(pts
			(arc
				(start 329.429618 -389.7122)
				(mid 329.165966 -389.7122)
				(end 329.429618 -389.7122)
			)
		)
		(stroke
			(width 0)
			(type solid)
		)
		(fill yes)
		(layer "F.Cu")
		(net "GND")
	)
	(gr_poly
		(pts
			(arc
				(start 329.429618 -385.38912)
				(mid 329.165966 -385.38912)
				(end 329.429618 -385.38912)
			)
		)
		(stroke
			(width 0)
			(type solid)
		)
		(fill yes)
		(layer "F.Cu")
		(net "GND")
	)
	(gr_poly
		(pts
			(arc
				(start 329.429618 -384.175)
				(mid 329.165966 -384.175)
				(end 329.429618 -384.175)
			)
		)
		(stroke
			(width 0)
			(type solid)
		)
		(fill yes)
		(layer "F.Cu")
		(net "GND")
	)
	(gr_poly
		(pts
			(arc
				(start 330.090018 -391.41146)
				(mid 329.826366 -391.41146)
				(end 330.090018 -391.41146)
			)
		)
		(stroke
			(width 0)
			(type solid)
		)
		(fill yes)
		(layer "F.Cu")
		(net "GND")
	)
	(gr_poly
		(pts
			(arc
				(start 330.090018 -389.25246)
				(mid 329.826366 -389.25246)
				(end 330.090018 -389.25246)
			)
		)
		(stroke
			(width 0)
			(type solid)
		)
		(fill yes)
		(layer "F.Cu")
		(net "GND")
	)
	(gr_poly
		(pts
			(arc
				(start 330.090018 -385.87426)
				(mid 329.826366 -385.87426)
				(end 330.090018 -385.87426)
			)
		)
		(stroke
			(width 0)
			(type solid)
		)
		(fill yes)
		(layer "F.Cu")
		(net "GND")
	)
	(gr_poly
		(pts
			(arc
				(start 330.090018 -383.68986)
				(mid 329.826366 -383.68986)
				(end 330.090018 -383.68986)
			)
		)
		(stroke
			(width 0)
			(type solid)
		)
		(fill yes)
		(layer "F.Cu")
		(net "GND")
	)
	(gr_poly
		(pts
			(arc
				(start 330.47178 -394.782294)
				(mid 330.2127 -394.782294)
				(end 330.47178 -394.782294)
			)
		)
		(stroke
			(width 0)
			(type solid)
		)
		(fill yes)
		(layer "F.Cu")
		(net "GND")
	)
	(gr_poly
		(pts
			(arc
				(start 330.750418 -390.92632)
				(mid 330.486766 -390.92632)
				(end 330.750418 -390.92632)
			)
		)
		(stroke
			(width 0)
			(type solid)
		)
		(fill yes)
		(layer "F.Cu")
		(net "GND")
	)
	(gr_poly
		(pts
			(arc
				(start 330.750418 -389.7122)
				(mid 330.486766 -389.7122)
				(end 330.750418 -389.7122)
			)
		)
		(stroke
			(width 0)
			(type solid)
		)
		(fill yes)
		(layer "F.Cu")
		(net "GND")
	)
	(gr_poly
		(pts
			(arc
				(start 330.750418 -385.38912)
				(mid 330.486766 -385.38912)
				(end 330.750418 -385.38912)
			)
		)
		(stroke
			(width 0)
			(type solid)
		)
		(fill yes)
		(layer "F.Cu")
		(net "GND")
	)
	(gr_poly
		(pts
			(arc
				(start 330.750418 -384.175)
				(mid 330.486766 -384.175)
				(end 330.750418 -384.175)
			)
		)
		(stroke
			(width 0)
			(type solid)
		)
		(fill yes)
		(layer "F.Cu")
		(net "GND")
	)
	(gr_poly
		(pts
			(arc
				(start 331.01407 -379.88113)
				(mid 330.750418 -379.88113)
				(end 331.01407 -379.88113)
			)
		)
		(stroke
			(width 0)
			(type solid)
		)
		(fill yes)
		(layer "F.Cu")
		(net "GND")
	)
	(gr_poly
		(pts
			(arc
				(start 331.49921 -380.54153)
				(mid 331.235558 -380.54153)
				(end 331.49921 -380.54153)
			)
		)
		(stroke
			(width 0)
			(type solid)
		)
		(fill yes)
		(layer "F.Cu")
		(net "GND")
	)
	(gr_poly
		(pts
			(arc
				(start 331.49921 -379.22073)
				(mid 331.235558 -379.22073)
				(end 331.49921 -379.22073)
			)
		)
		(stroke
			(width 0)
			(type solid)
		)
		(fill yes)
		(layer "F.Cu")
		(net "GND")
	)
	(gr_poly
		(pts
			(arc
				(start 332.71333 -380.54153)
				(mid 332.449678 -380.54153)
				(end 332.71333 -380.54153)
			)
		)
		(stroke
			(width 0)
			(type solid)
		)
		(fill yes)
		(layer "F.Cu")
		(net "GND")
	)
	(gr_poly
		(pts
			(arc
				(start 332.71333 -379.22073)
				(mid 332.449678 -379.22073)
				(end 332.71333 -379.22073)
			)
		)
		(stroke
			(width 0)
			(type solid)
		)
		(fill yes)
		(layer "F.Cu")
		(net "GND")
	)
	(gr_poly
		(pts
			(arc
				(start 332.71587 -377.41733)
				(mid 332.452218 -377.41733)
				(end 332.71587 -377.41733)
			)
		)
		(stroke
			(width 0)
			(type solid)
		)
		(fill yes)
		(layer "F.Cu")
		(net "GND")
	)
	(gr_poly
		(pts
			(arc
				(start 333.19847 -379.88113)
				(mid 332.934818 -379.88113)
				(end 333.19847 -379.88113)
			)
		)
		(stroke
			(width 0)
			(type solid)
		)
		(fill yes)
		(layer "F.Cu")
		(net "GND")
	)
	(gr_poly
		(pts
			(arc
				(start 333.20101 -378.07773)
				(mid 332.937358 -378.07773)
				(end 333.20101 -378.07773)
			)
		)
		(stroke
			(width 0)
			(type solid)
		)
		(fill yes)
		(layer "F.Cu")
		(net "GND")
	)
	(gr_poly
		(pts
			(arc
				(start 333.20101 -376.75693)
				(mid 332.937358 -376.75693)
				(end 333.20101 -376.75693)
			)
		)
		(stroke
			(width 0)
			(type solid)
		)
		(fill yes)
		(layer "F.Cu")
		(net "GND")
	)
	(gr_poly
		(pts
			(arc
				(start 334.41513 -378.07773)
				(mid 334.151478 -378.07773)
				(end 334.41513 -378.07773)
			)
		)
		(stroke
			(width 0)
			(type solid)
		)
		(fill yes)
		(layer "F.Cu")
		(net "GND")
	)
	(gr_poly
		(pts
			(arc
				(start 334.41513 -376.75693)
				(mid 334.151478 -376.75693)
				(end 334.41513 -376.75693)
			)
		)
		(stroke
			(width 0)
			(type solid)
		)
		(fill yes)
		(layer "F.Cu")
		(net "GND")
	)
	(gr_poly
		(pts
			(arc
				(start 334.90027 -377.41733)
				(mid 334.636618 -377.41733)
				(end 334.90027 -377.41733)
			)
		)
		(stroke
			(width 0)
			(type solid)
		)
		(fill yes)
		(layer "F.Cu")
		(net "GND")
	)
	(gr_poly
		(pts
			(arc
				(start 336.11947 -382.34493)
				(mid 335.855818 -382.34493)
				(end 336.11947 -382.34493)
			)
		)
		(stroke
			(width 0)
			(type solid)
		)
		(fill yes)
		(layer "F.Cu")
		(net "GND")
	)
	(gr_poly
		(pts
			(arc
				(start 336.60461 -383.00533)
				(mid 336.340958 -383.00533)
				(end 336.60461 -383.00533)
			)
		)
		(stroke
			(width 0)
			(type solid)
		)
		(fill yes)
		(layer "F.Cu")
		(net "GND")
	)
	(gr_poly
		(pts
			(arc
				(start 336.60461 -381.68453)
				(mid 336.340958 -381.68453)
				(end 336.60461 -381.68453)
			)
		)
		(stroke
			(width 0)
			(type solid)
		)
		(fill yes)
		(layer "F.Cu")
		(net "GND")
	)
	(gr_poly
		(pts
			(arc
				(start 337.81873 -383.00533)
				(mid 337.555078 -383.00533)
				(end 337.81873 -383.00533)
			)
		)
		(stroke
			(width 0)
			(type solid)
		)
		(fill yes)
		(layer "F.Cu")
		(net "GND")
	)
	(gr_poly
		(pts
			(arc
				(start 337.81873 -381.68453)
				(mid 337.555078 -381.68453)
				(end 337.81873 -381.68453)
			)
		)
		(stroke
			(width 0)
			(type solid)
		)
		(fill yes)
		(layer "F.Cu")
		(net "GND")
	)
	(gr_poly
		(pts
			(arc
				(start 337.82127 -379.88113)
				(mid 337.557618 -379.88113)
				(end 337.82127 -379.88113)
			)
		)
		(stroke
			(width 0)
			(type solid)
		)
		(fill yes)
		(layer "F.Cu")
		(net "GND")
	)
	(gr_poly
		(pts
			(arc
				(start 338.30387 -382.34493)
				(mid 338.040218 -382.34493)
				(end 338.30387 -382.34493)
			)
		)
		(stroke
			(width 0)
			(type solid)
		)
		(fill yes)
		(layer "F.Cu")
		(net "GND")
	)
	(gr_poly
		(pts
			(arc
				(start 338.30641 -380.54153)
				(mid 338.042758 -380.54153)
				(end 338.30641 -380.54153)
			)
		)
		(stroke
			(width 0)
			(type solid)
		)
		(fill yes)
		(layer "F.Cu")
		(net "GND")
	)
	(gr_poly
		(pts
			(arc
				(start 338.30641 -379.22073)
				(mid 338.042758 -379.22073)
				(end 338.30641 -379.22073)
			)
		)
		(stroke
			(width 0)
			(type solid)
		)
		(fill yes)
		(layer "F.Cu")
		(net "GND")
	)
	(gr_poly
		(pts
			(arc
				(start 339.52053 -380.54153)
				(mid 339.256878 -380.54153)
				(end 339.52053 -380.54153)
			)
		)
		(stroke
			(width 0)
			(type solid)
		)
		(fill yes)
		(layer "F.Cu")
		(net "GND")
	)
	(gr_poly
		(pts
			(arc
				(start 339.52053 -379.22073)
				(mid 339.256878 -379.22073)
				(end 339.52053 -379.22073)
			)
		)
		(stroke
			(width 0)
			(type solid)
		)
		(fill yes)
		(layer "F.Cu")
		(net "GND")
	)
	(gr_poly
		(pts
			(arc
				(start 339.52307 -377.41733)
				(mid 339.259418 -377.41733)
				(end 339.52307 -377.41733)
			)
		)
		(stroke
			(width 0)
			(type solid)
		)
		(fill yes)
		(layer "F.Cu")
		(net "GND")
	)
	(gr_poly
		(pts
			(arc
				(start 339.97519 -299.211746)
				(mid 339.71611 -299.211746)
				(end 339.97519 -299.211746)
			)
		)
		(stroke
			(width 0)
			(type solid)
		)
		(fill yes)
		(layer "F.Cu")
		(net "GND")
	)
	(gr_poly
		(pts
			(arc
				(start 340.00567 -379.88113)
				(mid 339.742018 -379.88113)
				(end 340.00567 -379.88113)
			)
		)
		(stroke
			(width 0)
			(type solid)
		)
		(fill yes)
		(layer "F.Cu")
		(net "GND")
	)
	(gr_poly
		(pts
			(arc
				(start 340.00821 -378.07773)
				(mid 339.744558 -378.07773)
				(end 340.00821 -378.07773)
			)
		)
		(stroke
			(width 0)
			(type solid)
		)
		(fill yes)
		(layer "F.Cu")
		(net "GND")
	)
	(gr_poly
		(pts
			(arc
				(start 340.00821 -376.75693)
				(mid 339.744558 -376.75693)
				(end 340.00821 -376.75693)
			)
		)
		(stroke
			(width 0)
			(type solid)
		)
		(fill yes)
		(layer "F.Cu")
		(net "GND")
	)
	(gr_poly
		(pts
			(arc
				(start 340.017608 -300.137068)
				(mid 339.758528 -300.137068)
				(end 340.017608 -300.137068)
			)
		)
		(stroke
			(width 0)
			(type solid)
		)
		(fill yes)
		(layer "F.Cu")
		(net "GND")
	)
	(gr_poly
		(pts
			(arc
				(start 341.22233 -378.07773)
				(mid 340.958678 -378.07773)
				(end 341.22233 -378.07773)
			)
		)
		(stroke
			(width 0)
			(type solid)
		)
		(fill yes)
		(layer "F.Cu")
		(net "GND")
	)
	(gr_poly
		(pts
			(arc
				(start 341.22233 -376.75693)
				(mid 340.958678 -376.75693)
				(end 341.22233 -376.75693)
			)
		)
		(stroke
			(width 0)
			(type solid)
		)
		(fill yes)
		(layer "F.Cu")
		(net "GND")
	)
	(gr_poly
		(pts
			(arc
				(start 341.70747 -377.41733)
				(mid 341.443818 -377.41733)
				(end 341.70747 -377.41733)
			)
		)
		(stroke
			(width 0)
			(type solid)
		)
		(fill yes)
		(layer "F.Cu")
		(net "GND")
	)
	(gr_poly
		(pts
			(arc
				(start 342.92667 -382.34493)
				(mid 342.663018 -382.34493)
				(end 342.92667 -382.34493)
			)
		)
		(stroke
			(width 0)
			(type solid)
		)
		(fill yes)
		(layer "F.Cu")
		(net "GND")
	)
	(gr_poly
		(pts
			(arc
				(start 343.235026 -305.390042)
				(mid 342.975946 -305.390042)
				(end 343.235026 -305.390042)
			)
		)
		(stroke
			(width 0)
			(type solid)
		)
		(fill yes)
		(layer "F.Cu")
		(net "GND")
	)
	(gr_poly
		(pts
			(arc
				(start 343.41181 -383.00533)
				(mid 343.148158 -383.00533)
				(end 343.41181 -383.00533)
			)
		)
		(stroke
			(width 0)
			(type solid)
		)
		(fill yes)
		(layer "F.Cu")
		(net "GND")
	)
	(gr_poly
		(pts
			(arc
				(start 343.41181 -381.68453)
				(mid 343.148158 -381.68453)
				(end 343.41181 -381.68453)
			)
		)
		(stroke
			(width 0)
			(type solid)
		)
		(fill yes)
		(layer "F.Cu")
		(net "GND")
	)
	(gr_poly
		(pts
			(arc
				(start 344.62593 -383.00533)
				(mid 344.362278 -383.00533)
				(end 344.62593 -383.00533)
			)
		)
		(stroke
			(width 0)
			(type solid)
		)
		(fill yes)
		(layer "F.Cu")
		(net "GND")
	)
	(gr_poly
		(pts
			(arc
				(start 344.62593 -381.68453)
				(mid 344.362278 -381.68453)
				(end 344.62593 -381.68453)
			)
		)
		(stroke
			(width 0)
			(type solid)
		)
		(fill yes)
		(layer "F.Cu")
		(net "GND")
	)
	(gr_poly
		(pts
			(arc
				(start 344.62847 -379.88113)
				(mid 344.364818 -379.88113)
				(end 344.62847 -379.88113)
			)
		)
		(stroke
			(width 0)
			(type solid)
		)
		(fill yes)
		(layer "F.Cu")
		(net "GND")
	)
	(gr_poly
		(pts
			(arc
				(start 345.11107 -382.34493)
				(mid 344.847418 -382.34493)
				(end 345.11107 -382.34493)
			)
		)
		(stroke
			(width 0)
			(type solid)
		)
		(fill yes)
		(layer "F.Cu")
		(net "GND")
	)
	(gr_poly
		(pts
			(arc
				(start 345.11361 -380.54153)
				(mid 344.849958 -380.54153)
				(end 345.11361 -380.54153)
			)
		)
		(stroke
			(width 0)
			(type solid)
		)
		(fill yes)
		(layer "F.Cu")
		(net "GND")
	)
	(gr_poly
		(pts
			(arc
				(start 345.11361 -379.22073)
				(mid 344.849958 -379.22073)
				(end 345.11361 -379.22073)
			)
		)
		(stroke
			(width 0)
			(type solid)
		)
		(fill yes)
		(layer "F.Cu")
		(net "GND")
	)
	(gr_poly
		(pts
			(arc
				(start 346.32773 -380.54153)
				(mid 346.064078 -380.54153)
				(end 346.32773 -380.54153)
			)
		)
		(stroke
			(width 0)
			(type solid)
		)
		(fill yes)
		(layer "F.Cu")
		(net "GND")
	)
	(gr_poly
		(pts
			(arc
				(start 346.32773 -379.22073)
				(mid 346.064078 -379.22073)
				(end 346.32773 -379.22073)
			)
		)
		(stroke
			(width 0)
			(type solid)
		)
		(fill yes)
		(layer "F.Cu")
		(net "GND")
	)
	(gr_poly
		(pts
			(arc
				(start 346.33027 -377.41733)
				(mid 346.066618 -377.41733)
				(end 346.33027 -377.41733)
			)
		)
		(stroke
			(width 0)
			(type solid)
		)
		(fill yes)
		(layer "F.Cu")
		(net "GND")
	)
	(gr_poly
		(pts
			(arc
				(start 346.646246 -306.819046)
				(mid 346.387166 -306.819046)
				(end 346.646246 -306.819046)
			)
		)
		(stroke
			(width 0)
			(type solid)
		)
		(fill yes)
		(layer "F.Cu")
		(net "GND")
	)
	(gr_poly
		(pts
			(arc
				(start 346.81287 -379.88113)
				(mid 346.549218 -379.88113)
				(end 346.81287 -379.88113)
			)
		)
		(stroke
			(width 0)
			(type solid)
		)
		(fill yes)
		(layer "F.Cu")
		(net "GND")
	)
	(gr_poly
		(pts
			(arc
				(start 346.81541 -378.07773)
				(mid 346.551758 -378.07773)
				(end 346.81541 -378.07773)
			)
		)
		(stroke
			(width 0)
			(type solid)
		)
		(fill yes)
		(layer "F.Cu")
		(net "GND")
	)
	(gr_poly
		(pts
			(arc
				(start 346.81541 -376.75693)
				(mid 346.551758 -376.75693)
				(end 346.81541 -376.75693)
			)
		)
		(stroke
			(width 0)
			(type solid)
		)
		(fill yes)
		(layer "F.Cu")
		(net "GND")
	)
	(gr_poly
		(pts
			(arc
				(start 348.02953 -378.07773)
				(mid 347.765878 -378.07773)
				(end 348.02953 -378.07773)
			)
		)
		(stroke
			(width 0)
			(type solid)
		)
		(fill yes)
		(layer "F.Cu")
		(net "GND")
	)
	(gr_poly
		(pts
			(arc
				(start 348.02953 -376.75693)
				(mid 347.765878 -376.75693)
				(end 348.02953 -376.75693)
			)
		)
		(stroke
			(width 0)
			(type solid)
		)
		(fill yes)
		(layer "F.Cu")
		(net "GND")
	)
	(gr_poly
		(pts
			(arc
				(start 348.51467 -377.41733)
				(mid 348.251018 -377.41733)
				(end 348.51467 -377.41733)
			)
		)
		(stroke
			(width 0)
			(type solid)
		)
		(fill yes)
		(layer "F.Cu")
		(net "GND")
	)
	(gr_poly
		(pts
			(arc
				(start 349.73387 -382.34493)
				(mid 349.470218 -382.34493)
				(end 349.73387 -382.34493)
			)
		)
		(stroke
			(width 0)
			(type solid)
		)
		(fill yes)
		(layer "F.Cu")
		(net "GND")
	)
	(gr_poly
		(pts
			(arc
				(start 350.106488 -129.807208)
				(mid 349.847408 -129.807208)
				(end 350.106488 -129.807208)
			)
		)
		(stroke
			(width 0)
			(type solid)
		)
		(fill yes)
		(layer "F.Cu")
		(net "GND")
	)
	(gr_poly
		(pts
			(arc
				(start 350.106488 -123.330208)
				(mid 349.847408 -123.330208)
				(end 350.106488 -123.330208)
			)
		)
		(stroke
			(width 0)
			(type solid)
		)
		(fill yes)
		(layer "F.Cu")
		(net "GND")
	)
	(gr_poly
		(pts
			(arc
				(start 350.21901 -383.00533)
				(mid 349.955358 -383.00533)
				(end 350.21901 -383.00533)
			)
		)
		(stroke
			(width 0)
			(type solid)
		)
		(fill yes)
		(layer "F.Cu")
		(net "GND")
	)
	(gr_poly
		(pts
			(arc
				(start 350.21901 -381.68453)
				(mid 349.955358 -381.68453)
				(end 350.21901 -381.68453)
			)
		)
		(stroke
			(width 0)
			(type solid)
		)
		(fill yes)
		(layer "F.Cu")
		(net "GND")
	)
	(gr_poly
		(pts
			(arc
				(start 351.43313 -383.00533)
				(mid 351.169478 -383.00533)
				(end 351.43313 -383.00533)
			)
		)
		(stroke
			(width 0)
			(type solid)
		)
		(fill yes)
		(layer "F.Cu")
		(net "GND")
	)
	(gr_poly
		(pts
			(arc
				(start 351.43313 -381.68453)
				(mid 351.169478 -381.68453)
				(end 351.43313 -381.68453)
			)
		)
		(stroke
			(width 0)
			(type solid)
		)
		(fill yes)
		(layer "F.Cu")
		(net "GND")
	)
	(gr_poly
		(pts
			(arc
				(start 351.43567 -379.88113)
				(mid 351.172018 -379.88113)
				(end 351.43567 -379.88113)
			)
		)
		(stroke
			(width 0)
			(type solid)
		)
		(fill yes)
		(layer "F.Cu")
		(net "GND")
	)
	(gr_poly
		(pts
			(arc
				(start 351.91827 -382.34493)
				(mid 351.654618 -382.34493)
				(end 351.91827 -382.34493)
			)
		)
		(stroke
			(width 0)
			(type solid)
		)
		(fill yes)
		(layer "F.Cu")
		(net "GND")
	)
	(gr_poly
		(pts
			(arc
				(start 351.92081 -380.54153)
				(mid 351.657158 -380.54153)
				(end 351.92081 -380.54153)
			)
		)
		(stroke
			(width 0)
			(type solid)
		)
		(fill yes)
		(layer "F.Cu")
		(net "GND")
	)
	(gr_poly
		(pts
			(arc
				(start 351.92081 -379.22073)
				(mid 351.657158 -379.22073)
				(end 351.92081 -379.22073)
			)
		)
		(stroke
			(width 0)
			(type solid)
		)
		(fill yes)
		(layer "F.Cu")
		(net "GND")
	)
	(gr_poly
		(pts
			(arc
				(start 353.13493 -380.54153)
				(mid 352.871278 -380.54153)
				(end 353.13493 -380.54153)
			)
		)
		(stroke
			(width 0)
			(type solid)
		)
		(fill yes)
		(layer "F.Cu")
		(net "GND")
	)
	(gr_poly
		(pts
			(arc
				(start 353.13493 -379.22073)
				(mid 352.871278 -379.22073)
				(end 353.13493 -379.22073)
			)
		)
		(stroke
			(width 0)
			(type solid)
		)
		(fill yes)
		(layer "F.Cu")
		(net "GND")
	)
	(gr_poly
		(pts
			(arc
				(start 353.13747 -377.41733)
				(mid 352.873818 -377.41733)
				(end 353.13747 -377.41733)
			)
		)
		(stroke
			(width 0)
			(type solid)
		)
		(fill yes)
		(layer "F.Cu")
		(net "GND")
	)
	(gr_poly
		(pts
			(arc
				(start 353.62007 -379.88113)
				(mid 353.356418 -379.88113)
				(end 353.62007 -379.88113)
			)
		)
		(stroke
			(width 0)
			(type solid)
		)
		(fill yes)
		(layer "F.Cu")
		(net "GND")
	)
	(gr_poly
		(pts
			(arc
				(start 353.62261 -378.07773)
				(mid 353.358958 -378.07773)
				(end 353.62261 -378.07773)
			)
		)
		(stroke
			(width 0)
			(type solid)
		)
		(fill yes)
		(layer "F.Cu")
		(net "GND")
	)
	(gr_poly
		(pts
			(arc
				(start 353.62261 -376.75693)
				(mid 353.358958 -376.75693)
				(end 353.62261 -376.75693)
			)
		)
		(stroke
			(width 0)
			(type solid)
		)
		(fill yes)
		(layer "F.Cu")
		(net "GND")
	)
	(gr_poly
		(pts
			(arc
				(start 353.997006 -440.211972)
				(mid 353.737926 -440.211972)
				(end 353.997006 -440.211972)
			)
		)
		(stroke
			(width 0)
			(type solid)
		)
		(fill yes)
		(layer "F.Cu")
		(net "GND")
	)
	(gr_poly
		(pts
			(arc
				(start 354.83673 -378.07773)
				(mid 354.573078 -378.07773)
				(end 354.83673 -378.07773)
			)
		)
		(stroke
			(width 0)
			(type solid)
		)
		(fill yes)
		(layer "F.Cu")
		(net "GND")
	)
	(gr_poly
		(pts
			(arc
				(start 354.83673 -376.75693)
				(mid 354.573078 -376.75693)
				(end 354.83673 -376.75693)
			)
		)
		(stroke
			(width 0)
			(type solid)
		)
		(fill yes)
		(layer "F.Cu")
		(net "GND")
	)
	(gr_poly
		(pts
			(arc
				(start 355.32187 -377.41733)
				(mid 355.058218 -377.41733)
				(end 355.32187 -377.41733)
			)
		)
		(stroke
			(width 0)
			(type solid)
		)
		(fill yes)
		(layer "F.Cu")
		(net "GND")
	)
	(gr_poly
		(pts
			(arc
				(start 356.54107 -377.41733)
				(mid 356.277418 -377.41733)
				(end 356.54107 -377.41733)
			)
		)
		(stroke
			(width 0)
			(type solid)
		)
		(fill yes)
		(layer "F.Cu")
		(net "GND")
	)
	(gr_poly
		(pts
			(arc
				(start 356.544118 -30.210252)
				(mid 356.285038 -30.210252)
				(end 356.544118 -30.210252)
			)
		)
		(stroke
			(width 0)
			(type solid)
		)
		(fill yes)
		(layer "F.Cu")
		(net "GND")
	)
	(gr_poly
		(pts
			(arc
				(start 356.61854 -116.427758)
				(mid 356.35946 -116.427758)
				(end 356.61854 -116.427758)
			)
		)
		(stroke
			(width 0)
			(type solid)
		)
		(fill yes)
		(layer "F.Cu")
		(net "GND")
	)
	(gr_poly
		(pts
			(arc
				(start 357.02621 -378.07773)
				(mid 356.762558 -378.07773)
				(end 357.02621 -378.07773)
			)
		)
		(stroke
			(width 0)
			(type solid)
		)
		(fill yes)
		(layer "F.Cu")
		(net "GND")
	)
	(gr_poly
		(pts
			(arc
				(start 357.02621 -376.75693)
				(mid 356.762558 -376.75693)
				(end 357.02621 -376.75693)
			)
		)
		(stroke
			(width 0)
			(type solid)
		)
		(fill yes)
		(layer "F.Cu")
		(net "GND")
	)
	(gr_poly
		(pts
			(arc
				(start 358.24033 -378.07773)
				(mid 357.976678 -378.07773)
				(end 358.24033 -378.07773)
			)
		)
		(stroke
			(width 0)
			(type solid)
		)
		(fill yes)
		(layer "F.Cu")
		(net "GND")
	)
	(gr_poly
		(pts
			(arc
				(start 358.24033 -376.75693)
				(mid 357.976678 -376.75693)
				(end 358.24033 -376.75693)
			)
		)
		(stroke
			(width 0)
			(type solid)
		)
		(fill yes)
		(layer "F.Cu")
		(net "GND")
	)
	(gr_poly
		(pts
			(arc
				(start 358.72547 -377.41733)
				(mid 358.461818 -377.41733)
				(end 358.72547 -377.41733)
			)
		)
		(stroke
			(width 0)
			(type solid)
		)
		(fill yes)
		(layer "F.Cu")
		(net "GND")
	)
	(gr_poly
		(pts
			(arc
				(start 359.27665 -388.917688)
				(mid 359.012998 -388.917688)
				(end 359.27665 -388.917688)
			)
		)
		(stroke
			(width 0)
			(type solid)
		)
		(fill yes)
		(layer "F.Cu")
		(net "GND")
	)
	(gr_poly
		(pts
			(arc
				(start 359.27665 -387.703568)
				(mid 359.012998 -387.703568)
				(end 359.27665 -387.703568)
			)
		)
		(stroke
			(width 0)
			(type solid)
		)
		(fill yes)
		(layer "F.Cu")
		(net "GND")
	)
	(gr_poly
		(pts
			(arc
				(start 359.27665 -385.514088)
				(mid 359.012998 -385.514088)
				(end 359.27665 -385.514088)
			)
		)
		(stroke
			(width 0)
			(type solid)
		)
		(fill yes)
		(layer "F.Cu")
		(net "GND")
	)
	(gr_poly
		(pts
			(arc
				(start 359.27665 -384.299968)
				(mid 359.012998 -384.299968)
				(end 359.27665 -384.299968)
			)
		)
		(stroke
			(width 0)
			(type solid)
		)
		(fill yes)
		(layer "F.Cu")
		(net "GND")
	)
	(gr_poly
		(pts
			(arc
				(start 359.28554 -116.931948)
				(mid 359.02646 -116.931948)
				(end 359.28554 -116.931948)
			)
		)
		(stroke
			(width 0)
			(type solid)
		)
		(fill yes)
		(layer "F.Cu")
		(net "GND")
	)
	(gr_poly
		(pts
			(arc
				(start 359.93705 -389.402828)
				(mid 359.673398 -389.402828)
				(end 359.93705 -389.402828)
			)
		)
		(stroke
			(width 0)
			(type solid)
		)
		(fill yes)
		(layer "F.Cu")
		(net "GND")
	)
	(gr_poly
		(pts
			(arc
				(start 359.93705 -387.218428)
				(mid 359.673398 -387.218428)
				(end 359.93705 -387.218428)
			)
		)
		(stroke
			(width 0)
			(type solid)
		)
		(fill yes)
		(layer "F.Cu")
		(net "GND")
	)
	(gr_poly
		(pts
			(arc
				(start 359.93705 -385.999228)
				(mid 359.673398 -385.999228)
				(end 359.93705 -385.999228)
			)
		)
		(stroke
			(width 0)
			(type solid)
		)
		(fill yes)
		(layer "F.Cu")
		(net "GND")
	)
	(gr_poly
		(pts
			(arc
				(start 359.93705 -383.814828)
				(mid 359.673398 -383.814828)
				(end 359.93705 -383.814828)
			)
		)
		(stroke
			(width 0)
			(type solid)
		)
		(fill yes)
		(layer "F.Cu")
		(net "GND")
	)
	(gr_poly
		(pts
			(arc
				(start 360.59745 -388.917688)
				(mid 360.333798 -388.917688)
				(end 360.59745 -388.917688)
			)
		)
		(stroke
			(width 0)
			(type solid)
		)
		(fill yes)
		(layer "F.Cu")
		(net "GND")
	)
	(gr_poly
		(pts
			(arc
				(start 360.59745 -387.703568)
				(mid 360.333798 -387.703568)
				(end 360.59745 -387.703568)
			)
		)
		(stroke
			(width 0)
			(type solid)
		)
		(fill yes)
		(layer "F.Cu")
		(net "GND")
	)
	(gr_poly
		(pts
			(arc
				(start 360.59745 -385.514088)
				(mid 360.333798 -385.514088)
				(end 360.59745 -385.514088)
			)
		)
		(stroke
			(width 0)
			(type solid)
		)
		(fill yes)
		(layer "F.Cu")
		(net "GND")
	)
	(gr_poly
		(pts
			(arc
				(start 360.59745 -384.299968)
				(mid 360.333798 -384.299968)
				(end 360.59745 -384.299968)
			)
		)
		(stroke
			(width 0)
			(type solid)
		)
		(fill yes)
		(layer "F.Cu")
		(net "GND")
	)
	(gr_poly
		(pts
			(arc
				(start 362.834682 -15.343886)
				(mid 362.575602 -15.343886)
				(end 362.834682 -15.343886)
			)
		)
		(stroke
			(width 0)
			(type solid)
		)
		(fill yes)
		(layer "F.Cu")
		(net "GND")
	)
	(gr_poly
		(pts
			(arc
				(start 364.002066 -390.92632)
				(mid 363.738414 -390.92632)
				(end 364.002066 -390.92632)
			)
		)
		(stroke
			(width 0)
			(type solid)
		)
		(fill yes)
		(layer "F.Cu")
		(net "GND")
	)
	(gr_poly
		(pts
			(arc
				(start 364.002066 -389.7122)
				(mid 363.738414 -389.7122)
				(end 364.002066 -389.7122)
			)
		)
		(stroke
			(width 0)
			(type solid)
		)
		(fill yes)
		(layer "F.Cu")
		(net "GND")
	)
	(gr_poly
		(pts
			(arc
				(start 364.002066 -385.38912)
				(mid 363.738414 -385.38912)
				(end 364.002066 -385.38912)
			)
		)
		(stroke
			(width 0)
			(type solid)
		)
		(fill yes)
		(layer "F.Cu")
		(net "GND")
	)
	(gr_poly
		(pts
			(arc
				(start 364.002066 -384.175)
				(mid 363.738414 -384.175)
				(end 364.002066 -384.175)
			)
		)
		(stroke
			(width 0)
			(type solid)
		)
		(fill yes)
		(layer "F.Cu")
		(net "GND")
	)
	(gr_poly
		(pts
			(arc
				(start 364.360206 -420.53637)
				(mid 364.101126 -420.53637)
				(end 364.360206 -420.53637)
			)
		)
		(stroke
			(width 0)
			(type solid)
		)
		(fill yes)
		(layer "F.Cu")
		(net "GND")
	)
	(gr_poly
		(pts
			(arc
				(start 364.662466 -391.41146)
				(mid 364.398814 -391.41146)
				(end 364.662466 -391.41146)
			)
		)
		(stroke
			(width 0)
			(type solid)
		)
		(fill yes)
		(layer "F.Cu")
		(net "GND")
	)
	(gr_poly
		(pts
			(arc
				(start 364.662466 -389.25246)
				(mid 364.398814 -389.25246)
				(end 364.662466 -389.25246)
			)
		)
		(stroke
			(width 0)
			(type solid)
		)
		(fill yes)
		(layer "F.Cu")
		(net "GND")
	)
	(gr_poly
		(pts
			(arc
				(start 364.662466 -385.87426)
				(mid 364.398814 -385.87426)
				(end 364.662466 -385.87426)
			)
		)
		(stroke
			(width 0)
			(type solid)
		)
		(fill yes)
		(layer "F.Cu")
		(net "GND")
	)
	(gr_poly
		(pts
			(arc
				(start 364.662466 -383.68986)
				(mid 364.398814 -383.68986)
				(end 364.662466 -383.68986)
			)
		)
		(stroke
			(width 0)
			(type solid)
		)
		(fill yes)
		(layer "F.Cu")
		(net "GND")
	)
	(gr_poly
		(pts
			(arc
				(start 365.1123 -394.786358)
				(mid 364.85322 -394.786358)
				(end 365.1123 -394.786358)
			)
		)
		(stroke
			(width 0)
			(type solid)
		)
		(fill yes)
		(layer "F.Cu")
		(net "GND")
	)
	(gr_poly
		(pts
			(arc
				(start 365.322866 -390.92632)
				(mid 365.059214 -390.92632)
				(end 365.322866 -390.92632)
			)
		)
		(stroke
			(width 0)
			(type solid)
		)
		(fill yes)
		(layer "F.Cu")
		(net "GND")
	)
	(gr_poly
		(pts
			(arc
				(start 365.322866 -389.7122)
				(mid 365.059214 -389.7122)
				(end 365.322866 -389.7122)
			)
		)
		(stroke
			(width 0)
			(type solid)
		)
		(fill yes)
		(layer "F.Cu")
		(net "GND")
	)
	(gr_poly
		(pts
			(arc
				(start 365.322866 -385.38912)
				(mid 365.059214 -385.38912)
				(end 365.322866 -385.38912)
			)
		)
		(stroke
			(width 0)
			(type solid)
		)
		(fill yes)
		(layer "F.Cu")
		(net "GND")
	)
	(gr_poly
		(pts
			(arc
				(start 365.322866 -384.175)
				(mid 365.059214 -384.175)
				(end 365.322866 -384.175)
			)
		)
		(stroke
			(width 0)
			(type solid)
		)
		(fill yes)
		(layer "F.Cu")
		(net "GND")
	)
	(gr_poly
		(pts
			(arc
				(start 365.586518 -379.88113)
				(mid 365.322866 -379.88113)
				(end 365.586518 -379.88113)
			)
		)
		(stroke
			(width 0)
			(type solid)
		)
		(fill yes)
		(layer "F.Cu")
		(net "GND")
	)
	(gr_poly
		(pts
			(arc
				(start 366.071658 -380.54153)
				(mid 365.808006 -380.54153)
				(end 366.071658 -380.54153)
			)
		)
		(stroke
			(width 0)
			(type solid)
		)
		(fill yes)
		(layer "F.Cu")
		(net "GND")
	)
	(gr_poly
		(pts
			(arc
				(start 366.071658 -379.22073)
				(mid 365.808006 -379.22073)
				(end 366.071658 -379.22073)
			)
		)
		(stroke
			(width 0)
			(type solid)
		)
		(fill yes)
		(layer "F.Cu")
		(net "GND")
	)
	(gr_poly
		(pts
			(arc
				(start 366.2426 -41.641776)
				(mid 365.98352 -41.641776)
				(end 366.2426 -41.641776)
			)
		)
		(stroke
			(width 0)
			(type solid)
		)
		(fill yes)
		(layer "F.Cu")
		(net "GND")
	)
	(gr_poly
		(pts
			(arc
				(start 366.649762 -44.755816)
				(mid 366.390682 -44.755816)
				(end 366.649762 -44.755816)
			)
		)
		(stroke
			(width 0)
			(type solid)
		)
		(fill yes)
		(layer "F.Cu")
		(net "GND")
	)
	(gr_poly
		(pts
			(arc
				(start 367.285778 -380.54153)
				(mid 367.022126 -380.54153)
				(end 367.285778 -380.54153)
			)
		)
		(stroke
			(width 0)
			(type solid)
		)
		(fill yes)
		(layer "F.Cu")
		(net "GND")
	)
	(gr_poly
		(pts
			(arc
				(start 367.285778 -379.22073)
				(mid 367.022126 -379.22073)
				(end 367.285778 -379.22073)
			)
		)
		(stroke
			(width 0)
			(type solid)
		)
		(fill yes)
		(layer "F.Cu")
		(net "GND")
	)
	(gr_poly
		(pts
			(arc
				(start 367.288318 -377.41733)
				(mid 367.024666 -377.41733)
				(end 367.288318 -377.41733)
			)
		)
		(stroke
			(width 0)
			(type solid)
		)
		(fill yes)
		(layer "F.Cu")
		(net "GND")
	)
	(gr_poly
		(pts
			(arc
				(start 367.40973 -29.706062)
				(mid 367.15065 -29.706062)
				(end 367.40973 -29.706062)
			)
		)
		(stroke
			(width 0)
			(type solid)
		)
		(fill yes)
		(layer "F.Cu")
		(net "GND")
	)
	(gr_poly
		(pts
			(arc
				(start 367.770918 -379.88113)
				(mid 367.507266 -379.88113)
				(end 367.770918 -379.88113)
			)
		)
		(stroke
			(width 0)
			(type solid)
		)
		(fill yes)
		(layer "F.Cu")
		(net "GND")
	)
	(gr_poly
		(pts
			(arc
				(start 367.773458 -378.07773)
				(mid 367.509806 -378.07773)
				(end 367.773458 -378.07773)
			)
		)
		(stroke
			(width 0)
			(type solid)
		)
		(fill yes)
		(layer "F.Cu")
		(net "GND")
	)
	(gr_poly
		(pts
			(arc
				(start 367.773458 -376.75693)
				(mid 367.509806 -376.75693)
				(end 367.773458 -376.75693)
			)
		)
		(stroke
			(width 0)
			(type solid)
		)
		(fill yes)
		(layer "F.Cu")
		(net "GND")
	)
	(gr_poly
		(pts
			(arc
				(start 368.773202 -29.504132)
				(mid 368.514122 -29.504132)
				(end 368.773202 -29.504132)
			)
		)
		(stroke
			(width 0)
			(type solid)
		)
		(fill yes)
		(layer "F.Cu")
		(net "GND")
	)
	(gr_poly
		(pts
			(arc
				(start 368.987578 -378.07773)
				(mid 368.723926 -378.07773)
				(end 368.987578 -378.07773)
			)
		)
		(stroke
			(width 0)
			(type solid)
		)
		(fill yes)
		(layer "F.Cu")
		(net "GND")
	)
	(gr_poly
		(pts
			(arc
				(start 368.987578 -376.75693)
				(mid 368.723926 -376.75693)
				(end 368.987578 -376.75693)
			)
		)
		(stroke
			(width 0)
			(type solid)
		)
		(fill yes)
		(layer "F.Cu")
		(net "GND")
	)
	(gr_poly
		(pts
			(arc
				(start 369.472718 -377.41733)
				(mid 369.209066 -377.41733)
				(end 369.472718 -377.41733)
			)
		)
		(stroke
			(width 0)
			(type solid)
		)
		(fill yes)
		(layer "F.Cu")
		(net "GND")
	)
	(gr_poly
		(pts
			(arc
				(start 370.691918 -382.34493)
				(mid 370.428266 -382.34493)
				(end 370.691918 -382.34493)
			)
		)
		(stroke
			(width 0)
			(type solid)
		)
		(fill yes)
		(layer "F.Cu")
		(net "GND")
	)
	(gr_poly
		(pts
			(arc
				(start 370.760498 -41.604184)
				(mid 370.501418 -41.604184)
				(end 370.760498 -41.604184)
			)
		)
		(stroke
			(width 0)
			(type solid)
		)
		(fill yes)
		(layer "F.Cu")
		(net "GND")
	)
	(gr_poly
		(pts
			(arc
				(start 370.888768 -114.394488)
				(mid 370.629688 -114.394488)
				(end 370.888768 -114.394488)
			)
		)
		(stroke
			(width 0)
			(type solid)
		)
		(fill yes)
		(layer "F.Cu")
		(net "GND")
	)
	(gr_poly
		(pts
			(arc
				(start 371.085618 -428.03064)
				(mid 370.826538 -428.03064)
				(end 371.085618 -428.03064)
			)
		)
		(stroke
			(width 0)
			(type solid)
		)
		(fill yes)
		(layer "F.Cu")
		(net "GND")
	)
	(gr_poly
		(pts
			(arc
				(start 371.177058 -383.00533)
				(mid 370.913406 -383.00533)
				(end 371.177058 -383.00533)
			)
		)
		(stroke
			(width 0)
			(type solid)
		)
		(fill yes)
		(layer "F.Cu")
		(net "GND")
	)
	(gr_poly
		(pts
			(arc
				(start 371.177058 -381.68453)
				(mid 370.913406 -381.68453)
				(end 371.177058 -381.68453)
			)
		)
		(stroke
			(width 0)
			(type solid)
		)
		(fill yes)
		(layer "F.Cu")
		(net "GND")
	)
	(gr_poly
		(pts
			(arc
				(start 372.391178 -383.00533)
				(mid 372.127526 -383.00533)
				(end 372.391178 -383.00533)
			)
		)
		(stroke
			(width 0)
			(type solid)
		)
		(fill yes)
		(layer "F.Cu")
		(net "GND")
	)
	(gr_poly
		(pts
			(arc
				(start 372.391178 -381.68453)
				(mid 372.127526 -381.68453)
				(end 372.391178 -381.68453)
			)
		)
		(stroke
			(width 0)
			(type solid)
		)
		(fill yes)
		(layer "F.Cu")
		(net "GND")
	)
	(gr_poly
		(pts
			(arc
				(start 372.393718 -379.88113)
				(mid 372.130066 -379.88113)
				(end 372.393718 -379.88113)
			)
		)
		(stroke
			(width 0)
			(type solid)
		)
		(fill yes)
		(layer "F.Cu")
		(net "GND")
	)
	(gr_poly
		(pts
			(arc
				(start 372.876318 -382.34493)
				(mid 372.612666 -382.34493)
				(end 372.876318 -382.34493)
			)
		)
		(stroke
			(width 0)
			(type solid)
		)
		(fill yes)
		(layer "F.Cu")
		(net "GND")
	)
	(gr_poly
		(pts
			(arc
				(start 372.878858 -380.54153)
				(mid 372.615206 -380.54153)
				(end 372.878858 -380.54153)
			)
		)
		(stroke
			(width 0)
			(type solid)
		)
		(fill yes)
		(layer "F.Cu")
		(net "GND")
	)
	(gr_poly
		(pts
			(arc
				(start 372.878858 -379.22073)
				(mid 372.615206 -379.22073)
				(end 372.878858 -379.22073)
			)
		)
		(stroke
			(width 0)
			(type solid)
		)
		(fill yes)
		(layer "F.Cu")
		(net "GND")
	)
	(gr_poly
		(pts
			(arc
				(start 373.10187 -123.845828)
				(mid 372.84279 -123.845828)
				(end 373.10187 -123.845828)
			)
		)
		(stroke
			(width 0)
			(type solid)
		)
		(fill yes)
		(layer "F.Cu")
		(net "GND")
	)
	(gr_poly
		(pts
			(arc
				(start 374.092978 -380.54153)
				(mid 373.829326 -380.54153)
				(end 374.092978 -380.54153)
			)
		)
		(stroke
			(width 0)
			(type solid)
		)
		(fill yes)
		(layer "F.Cu")
		(net "GND")
	)
	(gr_poly
		(pts
			(arc
				(start 374.092978 -379.22073)
				(mid 373.829326 -379.22073)
				(end 374.092978 -379.22073)
			)
		)
		(stroke
			(width 0)
			(type solid)
		)
		(fill yes)
		(layer "F.Cu")
		(net "GND")
	)
	(gr_poly
		(pts
			(arc
				(start 374.095518 -377.41733)
				(mid 373.831866 -377.41733)
				(end 374.095518 -377.41733)
			)
		)
		(stroke
			(width 0)
			(type solid)
		)
		(fill yes)
		(layer "F.Cu")
		(net "GND")
	)
	(gr_poly
		(pts
			(arc
				(start 374.578118 -379.88113)
				(mid 374.314466 -379.88113)
				(end 374.578118 -379.88113)
			)
		)
		(stroke
			(width 0)
			(type solid)
		)
		(fill yes)
		(layer "F.Cu")
		(net "GND")
	)
	(gr_poly
		(pts
			(arc
				(start 374.580658 -378.07773)
				(mid 374.317006 -378.07773)
				(end 374.580658 -378.07773)
			)
		)
		(stroke
			(width 0)
			(type solid)
		)
		(fill yes)
		(layer "F.Cu")
		(net "GND")
	)
	(gr_poly
		(pts
			(arc
				(start 374.580658 -376.75693)
				(mid 374.317006 -376.75693)
				(end 374.580658 -376.75693)
			)
		)
		(stroke
			(width 0)
			(type solid)
		)
		(fill yes)
		(layer "F.Cu")
		(net "GND")
	)
	(gr_poly
		(pts
			(arc
				(start 375.794778 -378.07773)
				(mid 375.531126 -378.07773)
				(end 375.794778 -378.07773)
			)
		)
		(stroke
			(width 0)
			(type solid)
		)
		(fill yes)
		(layer "F.Cu")
		(net "GND")
	)
	(gr_poly
		(pts
			(arc
				(start 375.794778 -376.75693)
				(mid 375.531126 -376.75693)
				(end 375.794778 -376.75693)
			)
		)
		(stroke
			(width 0)
			(type solid)
		)
		(fill yes)
		(layer "F.Cu")
		(net "GND")
	)
	(gr_poly
		(pts
			(arc
				(start 376.279918 -377.41733)
				(mid 376.016266 -377.41733)
				(end 376.279918 -377.41733)
			)
		)
		(stroke
			(width 0)
			(type solid)
		)
		(fill yes)
		(layer "F.Cu")
		(net "GND")
	)
	(gr_poly
		(pts
			(arc
				(start 377.499118 -382.34493)
				(mid 377.235466 -382.34493)
				(end 377.499118 -382.34493)
			)
		)
		(stroke
			(width 0)
			(type solid)
		)
		(fill yes)
		(layer "F.Cu")
		(net "GND")
	)
	(gr_poly
		(pts
			(arc
				(start 377.984258 -383.00533)
				(mid 377.720606 -383.00533)
				(end 377.984258 -383.00533)
			)
		)
		(stroke
			(width 0)
			(type solid)
		)
		(fill yes)
		(layer "F.Cu")
		(net "GND")
	)
	(gr_poly
		(pts
			(arc
				(start 377.984258 -381.68453)
				(mid 377.720606 -381.68453)
				(end 377.984258 -381.68453)
			)
		)
		(stroke
			(width 0)
			(type solid)
		)
		(fill yes)
		(layer "F.Cu")
		(net "GND")
	)
	(gr_poly
		(pts
			(arc
				(start 379.157738 -31.455868)
				(mid 378.898658 -31.455868)
				(end 379.157738 -31.455868)
			)
		)
		(stroke
			(width 0)
			(type solid)
		)
		(fill yes)
		(layer "F.Cu")
		(net "GND")
	)
	(gr_poly
		(pts
			(arc
				(start 379.198378 -383.00533)
				(mid 378.934726 -383.00533)
				(end 379.198378 -383.00533)
			)
		)
		(stroke
			(width 0)
			(type solid)
		)
		(fill yes)
		(layer "F.Cu")
		(net "GND")
	)
	(gr_poly
		(pts
			(arc
				(start 379.198378 -381.68453)
				(mid 378.934726 -381.68453)
				(end 379.198378 -381.68453)
			)
		)
		(stroke
			(width 0)
			(type solid)
		)
		(fill yes)
		(layer "F.Cu")
		(net "GND")
	)
	(gr_poly
		(pts
			(arc
				(start 379.200918 -379.88113)
				(mid 378.937266 -379.88113)
				(end 379.200918 -379.88113)
			)
		)
		(stroke
			(width 0)
			(type solid)
		)
		(fill yes)
		(layer "F.Cu")
		(net "GND")
	)
	(gr_poly
		(pts
			(arc
				(start 379.683518 -382.34493)
				(mid 379.419866 -382.34493)
				(end 379.683518 -382.34493)
			)
		)
		(stroke
			(width 0)
			(type solid)
		)
		(fill yes)
		(layer "F.Cu")
		(net "GND")
	)
	(gr_poly
		(pts
			(arc
				(start 379.686058 -380.54153)
				(mid 379.422406 -380.54153)
				(end 379.686058 -380.54153)
			)
		)
		(stroke
			(width 0)
			(type solid)
		)
		(fill yes)
		(layer "F.Cu")
		(net "GND")
	)
	(gr_poly
		(pts
			(arc
				(start 379.686058 -379.22073)
				(mid 379.422406 -379.22073)
				(end 379.686058 -379.22073)
			)
		)
		(stroke
			(width 0)
			(type solid)
		)
		(fill yes)
		(layer "F.Cu")
		(net "GND")
	)
	(gr_poly
		(pts
			(arc
				(start 380.900178 -380.54153)
				(mid 380.636526 -380.54153)
				(end 380.900178 -380.54153)
			)
		)
		(stroke
			(width 0)
			(type solid)
		)
		(fill yes)
		(layer "F.Cu")
		(net "GND")
	)
	(gr_poly
		(pts
			(arc
				(start 380.900178 -379.22073)
				(mid 380.636526 -379.22073)
				(end 380.900178 -379.22073)
			)
		)
		(stroke
			(width 0)
			(type solid)
		)
		(fill yes)
		(layer "F.Cu")
		(net "GND")
	)
	(gr_poly
		(pts
			(arc
				(start 380.902718 -377.41733)
				(mid 380.639066 -377.41733)
				(end 380.902718 -377.41733)
			)
		)
		(stroke
			(width 0)
			(type solid)
		)
		(fill yes)
		(layer "F.Cu")
		(net "GND")
	)
	(gr_poly
		(pts
			(arc
				(start 381.385318 -379.88113)
				(mid 381.121666 -379.88113)
				(end 381.385318 -379.88113)
			)
		)
		(stroke
			(width 0)
			(type solid)
		)
		(fill yes)
		(layer "F.Cu")
		(net "GND")
	)
	(gr_poly
		(pts
			(arc
				(start 381.387858 -378.07773)
				(mid 381.124206 -378.07773)
				(end 381.387858 -378.07773)
			)
		)
		(stroke
			(width 0)
			(type solid)
		)
		(fill yes)
		(layer "F.Cu")
		(net "GND")
	)
	(gr_poly
		(pts
			(arc
				(start 381.387858 -376.75693)
				(mid 381.124206 -376.75693)
				(end 381.387858 -376.75693)
			)
		)
		(stroke
			(width 0)
			(type solid)
		)
		(fill yes)
		(layer "F.Cu")
		(net "GND")
	)
	(gr_poly
		(pts
			(arc
				(start 382.601978 -378.07773)
				(mid 382.338326 -378.07773)
				(end 382.601978 -378.07773)
			)
		)
		(stroke
			(width 0)
			(type solid)
		)
		(fill yes)
		(layer "F.Cu")
		(net "GND")
	)
	(gr_poly
		(pts
			(arc
				(start 382.601978 -376.75693)
				(mid 382.338326 -376.75693)
				(end 382.601978 -376.75693)
			)
		)
		(stroke
			(width 0)
			(type solid)
		)
		(fill yes)
		(layer "F.Cu")
		(net "GND")
	)
	(gr_poly
		(pts
			(arc
				(start 383.087118 -377.41733)
				(mid 382.823466 -377.41733)
				(end 383.087118 -377.41733)
			)
		)
		(stroke
			(width 0)
			(type solid)
		)
		(fill yes)
		(layer "F.Cu")
		(net "GND")
	)
	(gr_poly
		(pts
			(arc
				(start 384.306318 -382.34493)
				(mid 384.042666 -382.34493)
				(end 384.306318 -382.34493)
			)
		)
		(stroke
			(width 0)
			(type solid)
		)
		(fill yes)
		(layer "F.Cu")
		(net "GND")
	)
	(gr_poly
		(pts
			(arc
				(start 384.791458 -383.00533)
				(mid 384.527806 -383.00533)
				(end 384.791458 -383.00533)
			)
		)
		(stroke
			(width 0)
			(type solid)
		)
		(fill yes)
		(layer "F.Cu")
		(net "GND")
	)
	(gr_poly
		(pts
			(arc
				(start 384.791458 -381.68453)
				(mid 384.527806 -381.68453)
				(end 384.791458 -381.68453)
			)
		)
		(stroke
			(width 0)
			(type solid)
		)
		(fill yes)
		(layer "F.Cu")
		(net "GND")
	)
	(gr_poly
		(pts
			(arc
				(start 386.005578 -383.00533)
				(mid 385.741926 -383.00533)
				(end 386.005578 -383.00533)
			)
		)
		(stroke
			(width 0)
			(type solid)
		)
		(fill yes)
		(layer "F.Cu")
		(net "GND")
	)
	(gr_poly
		(pts
			(arc
				(start 386.005578 -381.68453)
				(mid 385.741926 -381.68453)
				(end 386.005578 -381.68453)
			)
		)
		(stroke
			(width 0)
			(type solid)
		)
		(fill yes)
		(layer "F.Cu")
		(net "GND")
	)
	(gr_poly
		(pts
			(arc
				(start 386.008118 -379.88113)
				(mid 385.744466 -379.88113)
				(end 386.008118 -379.88113)
			)
		)
		(stroke
			(width 0)
			(type solid)
		)
		(fill yes)
		(layer "F.Cu")
		(net "GND")
	)
	(gr_poly
		(pts
			(arc
				(start 386.490718 -382.34493)
				(mid 386.227066 -382.34493)
				(end 386.490718 -382.34493)
			)
		)
		(stroke
			(width 0)
			(type solid)
		)
		(fill yes)
		(layer "F.Cu")
		(net "GND")
	)
	(gr_poly
		(pts
			(arc
				(start 386.493258 -380.54153)
				(mid 386.229606 -380.54153)
				(end 386.493258 -380.54153)
			)
		)
		(stroke
			(width 0)
			(type solid)
		)
		(fill yes)
		(layer "F.Cu")
		(net "GND")
	)
	(gr_poly
		(pts
			(arc
				(start 386.493258 -379.22073)
				(mid 386.229606 -379.22073)
				(end 386.493258 -379.22073)
			)
		)
		(stroke
			(width 0)
			(type solid)
		)
		(fill yes)
		(layer "F.Cu")
		(net "GND")
	)
	(gr_poly
		(pts
			(arc
				(start 386.950458 -30.457648)
				(mid 386.691378 -30.457648)
				(end 386.950458 -30.457648)
			)
		)
		(stroke
			(width 0)
			(type solid)
		)
		(fill yes)
		(layer "F.Cu")
		(net "GND")
	)
	(gr_poly
		(pts
			(arc
				(start 387.707378 -380.54153)
				(mid 387.443726 -380.54153)
				(end 387.707378 -380.54153)
			)
		)
		(stroke
			(width 0)
			(type solid)
		)
		(fill yes)
		(layer "F.Cu")
		(net "GND")
	)
	(gr_poly
		(pts
			(arc
				(start 387.707378 -379.22073)
				(mid 387.443726 -379.22073)
				(end 387.707378 -379.22073)
			)
		)
		(stroke
			(width 0)
			(type solid)
		)
		(fill yes)
		(layer "F.Cu")
		(net "GND")
	)
	(gr_poly
		(pts
			(arc
				(start 387.709918 -382.34493)
				(mid 387.446266 -382.34493)
				(end 387.709918 -382.34493)
			)
		)
		(stroke
			(width 0)
			(type solid)
		)
		(fill yes)
		(layer "F.Cu")
		(net "GND")
	)
	(gr_poly
		(pts
			(arc
				(start 387.709918 -377.41733)
				(mid 387.446266 -377.41733)
				(end 387.709918 -377.41733)
			)
		)
		(stroke
			(width 0)
			(type solid)
		)
		(fill yes)
		(layer "F.Cu")
		(net "GND")
	)
	(gr_poly
		(pts
			(arc
				(start 388.192518 -379.88113)
				(mid 387.928866 -379.88113)
				(end 388.192518 -379.88113)
			)
		)
		(stroke
			(width 0)
			(type solid)
		)
		(fill yes)
		(layer "F.Cu")
		(net "GND")
	)
	(gr_poly
		(pts
			(arc
				(start 388.195058 -381.68453)
				(mid 387.931406 -381.68453)
				(end 388.195058 -381.68453)
			)
		)
		(stroke
			(width 0)
			(type solid)
		)
		(fill yes)
		(layer "F.Cu")
		(net "GND")
	)
	(gr_poly
		(pts
			(arc
				(start 388.195058 -378.07773)
				(mid 387.931406 -378.07773)
				(end 388.195058 -378.07773)
			)
		)
		(stroke
			(width 0)
			(type solid)
		)
		(fill yes)
		(layer "F.Cu")
		(net "GND")
	)
	(gr_poly
		(pts
			(arc
				(start 388.195058 -376.75693)
				(mid 387.931406 -376.75693)
				(end 388.195058 -376.75693)
			)
		)
		(stroke
			(width 0)
			(type solid)
		)
		(fill yes)
		(layer "F.Cu")
		(net "GND")
	)
	(gr_poly
		(pts
			(arc
				(start 389.409178 -378.07773)
				(mid 389.145526 -378.07773)
				(end 389.409178 -378.07773)
			)
		)
		(stroke
			(width 0)
			(type solid)
		)
		(fill yes)
		(layer "F.Cu")
		(net "GND")
	)
	(gr_poly
		(pts
			(arc
				(start 389.409178 -376.75693)
				(mid 389.145526 -376.75693)
				(end 389.409178 -376.75693)
			)
		)
		(stroke
			(width 0)
			(type solid)
		)
		(fill yes)
		(layer "F.Cu")
		(net "GND")
	)
	(gr_poly
		(pts
			(arc
				(start 389.474202 -142.307056)
				(mid 389.215122 -142.307056)
				(end 389.474202 -142.307056)
			)
		)
		(stroke
			(width 0)
			(type solid)
		)
		(fill yes)
		(layer "F.Cu")
		(net "GND")
	)
	(gr_poly
		(pts
			(arc
				(start 389.894318 -377.41733)
				(mid 389.630666 -377.41733)
				(end 389.894318 -377.41733)
			)
		)
		(stroke
			(width 0)
			(type solid)
		)
		(fill yes)
		(layer "F.Cu")
		(net "GND")
	)
	(gr_poly
		(pts
			(arc
				(start 391.113518 -377.41733)
				(mid 390.849866 -377.41733)
				(end 391.113518 -377.41733)
			)
		)
		(stroke
			(width 0)
			(type solid)
		)
		(fill yes)
		(layer "F.Cu")
		(net "GND")
	)
	(gr_poly
		(pts
			(arc
				(start 391.598658 -378.07773)
				(mid 391.335006 -378.07773)
				(end 391.598658 -378.07773)
			)
		)
		(stroke
			(width 0)
			(type solid)
		)
		(fill yes)
		(layer "F.Cu")
		(net "GND")
	)
	(gr_poly
		(pts
			(arc
				(start 391.598658 -376.75693)
				(mid 391.335006 -376.75693)
				(end 391.598658 -376.75693)
			)
		)
		(stroke
			(width 0)
			(type solid)
		)
		(fill yes)
		(layer "F.Cu")
		(net "GND")
	)
	(gr_poly
		(pts
			(arc
				(start 392.812778 -378.07773)
				(mid 392.549126 -378.07773)
				(end 392.812778 -378.07773)
			)
		)
		(stroke
			(width 0)
			(type solid)
		)
		(fill yes)
		(layer "F.Cu")
		(net "GND")
	)
	(gr_poly
		(pts
			(arc
				(start 392.812778 -376.75693)
				(mid 392.549126 -376.75693)
				(end 392.812778 -376.75693)
			)
		)
		(stroke
			(width 0)
			(type solid)
		)
		(fill yes)
		(layer "F.Cu")
		(net "GND")
	)
	(gr_poly
		(pts
			(arc
				(start 393.297918 -377.41733)
				(mid 393.034266 -377.41733)
				(end 393.297918 -377.41733)
			)
		)
		(stroke
			(width 0)
			(type solid)
		)
		(fill yes)
		(layer "F.Cu")
		(net "GND")
	)
	(gr_poly
		(pts
			(arc
				(start 393.849098 -388.917688)
				(mid 393.585446 -388.917688)
				(end 393.849098 -388.917688)
			)
		)
		(stroke
			(width 0)
			(type solid)
		)
		(fill yes)
		(layer "F.Cu")
		(net "GND")
	)
	(gr_poly
		(pts
			(arc
				(start 393.849098 -387.703568)
				(mid 393.585446 -387.703568)
				(end 393.849098 -387.703568)
			)
		)
		(stroke
			(width 0)
			(type solid)
		)
		(fill yes)
		(layer "F.Cu")
		(net "GND")
	)
	(gr_poly
		(pts
			(arc
				(start 393.849098 -385.514088)
				(mid 393.585446 -385.514088)
				(end 393.849098 -385.514088)
			)
		)
		(stroke
			(width 0)
			(type solid)
		)
		(fill yes)
		(layer "F.Cu")
		(net "GND")
	)
	(gr_poly
		(pts
			(arc
				(start 393.849098 -384.299968)
				(mid 393.585446 -384.299968)
				(end 393.849098 -384.299968)
			)
		)
		(stroke
			(width 0)
			(type solid)
		)
		(fill yes)
		(layer "F.Cu")
		(net "GND")
	)
	(gr_poly
		(pts
			(arc
				(start 394.509498 -387.218428)
				(mid 394.245846 -387.218428)
				(end 394.509498 -387.218428)
			)
		)
		(stroke
			(width 0)
			(type solid)
		)
		(fill yes)
		(layer "F.Cu")
		(net "GND")
	)
	(gr_poly
		(pts
			(arc
				(start 394.509498 -385.999228)
				(mid 394.245846 -385.999228)
				(end 394.509498 -385.999228)
			)
		)
		(stroke
			(width 0)
			(type solid)
		)
		(fill yes)
		(layer "F.Cu")
		(net "GND")
	)
	(gr_poly
		(pts
			(arc
				(start 394.509498 -383.814828)
				(mid 394.245846 -383.814828)
				(end 394.509498 -383.814828)
			)
		)
		(stroke
			(width 0)
			(type solid)
		)
		(fill yes)
		(layer "F.Cu")
		(net "GND")
	)
	(gr_poly
		(pts
			(arc
				(start 395.169898 -388.917688)
				(mid 394.906246 -388.917688)
				(end 395.169898 -388.917688)
			)
		)
		(stroke
			(width 0)
			(type solid)
		)
		(fill yes)
		(layer "F.Cu")
		(net "GND")
	)
	(gr_poly
		(pts
			(arc
				(start 395.169898 -387.703568)
				(mid 394.906246 -387.703568)
				(end 395.169898 -387.703568)
			)
		)
		(stroke
			(width 0)
			(type solid)
		)
		(fill yes)
		(layer "F.Cu")
		(net "GND")
	)
	(gr_poly
		(pts
			(arc
				(start 395.169898 -385.514088)
				(mid 394.906246 -385.514088)
				(end 395.169898 -385.514088)
			)
		)
		(stroke
			(width 0)
			(type solid)
		)
		(fill yes)
		(layer "F.Cu")
		(net "GND")
	)
	(gr_poly
		(pts
			(arc
				(start 395.169898 -384.299968)
				(mid 394.906246 -384.299968)
				(end 395.169898 -384.299968)
			)
		)
		(stroke
			(width 0)
			(type solid)
		)
		(fill yes)
		(layer "F.Cu")
		(net "GND")
	)
	(gr_poly
		(pts
			(arc
				(start 396.529814 -389.7122)
				(mid 396.266162 -389.7122)
				(end 396.529814 -389.7122)
			)
		)
		(stroke
			(width 0)
			(type solid)
		)
		(fill yes)
		(layer "F.Cu")
		(net "GND")
	)
	(gr_poly
		(pts
			(arc
				(start 396.529814 -385.38912)
				(mid 396.266162 -385.38912)
				(end 396.529814 -385.38912)
			)
		)
		(stroke
			(width 0)
			(type solid)
		)
		(fill yes)
		(layer "F.Cu")
		(net "GND")
	)
	(gr_poly
		(pts
			(arc
				(start 396.529814 -384.175)
				(mid 396.266162 -384.175)
				(end 396.529814 -384.175)
			)
		)
		(stroke
			(width 0)
			(type solid)
		)
		(fill yes)
		(layer "F.Cu")
		(net "GND")
	)
	(gr_poly
		(pts
			(arc
				(start 397.190214 -391.41146)
				(mid 396.926562 -391.41146)
				(end 397.190214 -391.41146)
			)
		)
		(stroke
			(width 0)
			(type solid)
		)
		(fill yes)
		(layer "F.Cu")
		(net "GND")
	)
	(gr_poly
		(pts
			(arc
				(start 397.190214 -389.25246)
				(mid 396.926562 -389.25246)
				(end 397.190214 -389.25246)
			)
		)
		(stroke
			(width 0)
			(type solid)
		)
		(fill yes)
		(layer "F.Cu")
		(net "GND")
	)
	(gr_poly
		(pts
			(arc
				(start 397.190214 -385.87426)
				(mid 396.926562 -385.87426)
				(end 397.190214 -385.87426)
			)
		)
		(stroke
			(width 0)
			(type solid)
		)
		(fill yes)
		(layer "F.Cu")
		(net "GND")
	)
	(gr_poly
		(pts
			(arc
				(start 397.190214 -383.68986)
				(mid 396.926562 -383.68986)
				(end 397.190214 -383.68986)
			)
		)
		(stroke
			(width 0)
			(type solid)
		)
		(fill yes)
		(layer "F.Cu")
		(net "GND")
	)
	(gr_poly
		(pts
			(arc
				(start 397.850614 -390.92632)
				(mid 397.586962 -390.92632)
				(end 397.850614 -390.92632)
			)
		)
		(stroke
			(width 0)
			(type solid)
		)
		(fill yes)
		(layer "F.Cu")
		(net "GND")
	)
	(gr_poly
		(pts
			(arc
				(start 397.850614 -389.7122)
				(mid 397.586962 -389.7122)
				(end 397.850614 -389.7122)
			)
		)
		(stroke
			(width 0)
			(type solid)
		)
		(fill yes)
		(layer "F.Cu")
		(net "GND")
	)
	(gr_poly
		(pts
			(arc
				(start 397.850614 -385.38912)
				(mid 397.586962 -385.38912)
				(end 397.850614 -385.38912)
			)
		)
		(stroke
			(width 0)
			(type solid)
		)
		(fill yes)
		(layer "F.Cu")
		(net "GND")
	)
	(gr_poly
		(pts
			(arc
				(start 397.850614 -384.175)
				(mid 397.586962 -384.175)
				(end 397.850614 -384.175)
			)
		)
		(stroke
			(width 0)
			(type solid)
		)
		(fill yes)
		(layer "F.Cu")
		(net "GND")
	)
	(gr_poly
		(pts
			(arc
				(start 398.114266 -379.88113)
				(mid 397.850614 -379.88113)
				(end 398.114266 -379.88113)
			)
		)
		(stroke
			(width 0)
			(type solid)
		)
		(fill yes)
		(layer "F.Cu")
		(net "GND")
	)
	(gr_poly
		(pts
			(arc
				(start 398.599406 -380.54153)
				(mid 398.335754 -380.54153)
				(end 398.599406 -380.54153)
			)
		)
		(stroke
			(width 0)
			(type solid)
		)
		(fill yes)
		(layer "F.Cu")
		(net "GND")
	)
	(gr_poly
		(pts
			(arc
				(start 398.599406 -379.22073)
				(mid 398.335754 -379.22073)
				(end 398.599406 -379.22073)
			)
		)
		(stroke
			(width 0)
			(type solid)
		)
		(fill yes)
		(layer "F.Cu")
		(net "GND")
	)
	(gr_poly
		(pts
			(arc
				(start 399.426684 -331.745082)
				(mid 399.167604 -331.745082)
				(end 399.426684 -331.745082)
			)
		)
		(stroke
			(width 0)
			(type solid)
		)
		(fill yes)
		(layer "F.Cu")
		(net "GND")
	)
	(gr_poly
		(pts
			(arc
				(start 399.813526 -380.54153)
				(mid 399.549874 -380.54153)
				(end 399.813526 -380.54153)
			)
		)
		(stroke
			(width 0)
			(type solid)
		)
		(fill yes)
		(layer "F.Cu")
		(net "GND")
	)
	(gr_poly
		(pts
			(arc
				(start 399.813526 -379.22073)
				(mid 399.549874 -379.22073)
				(end 399.813526 -379.22073)
			)
		)
		(stroke
			(width 0)
			(type solid)
		)
		(fill yes)
		(layer "F.Cu")
		(net "GND")
	)
	(gr_poly
		(pts
			(arc
				(start 399.816066 -377.41733)
				(mid 399.552414 -377.41733)
				(end 399.816066 -377.41733)
			)
		)
		(stroke
			(width 0)
			(type solid)
		)
		(fill yes)
		(layer "F.Cu")
		(net "GND")
	)
	(gr_poly
		(pts
			(arc
				(start 400.298666 -379.88113)
				(mid 400.035014 -379.88113)
				(end 400.298666 -379.88113)
			)
		)
		(stroke
			(width 0)
			(type solid)
		)
		(fill yes)
		(layer "F.Cu")
		(net "GND")
	)
	(gr_poly
		(pts
			(arc
				(start 400.301206 -378.07773)
				(mid 400.037554 -378.07773)
				(end 400.301206 -378.07773)
			)
		)
		(stroke
			(width 0)
			(type solid)
		)
		(fill yes)
		(layer "F.Cu")
		(net "GND")
	)
	(gr_poly
		(pts
			(arc
				(start 400.301206 -376.75693)
				(mid 400.037554 -376.75693)
				(end 400.301206 -376.75693)
			)
		)
		(stroke
			(width 0)
			(type solid)
		)
		(fill yes)
		(layer "F.Cu")
		(net "GND")
	)
	(gr_poly
		(pts
			(arc
				(start 401.515326 -378.07773)
				(mid 401.251674 -378.07773)
				(end 401.515326 -378.07773)
			)
		)
		(stroke
			(width 0)
			(type solid)
		)
		(fill yes)
		(layer "F.Cu")
		(net "GND")
	)
	(gr_poly
		(pts
			(arc
				(start 401.515326 -376.75693)
				(mid 401.251674 -376.75693)
				(end 401.515326 -376.75693)
			)
		)
		(stroke
			(width 0)
			(type solid)
		)
		(fill yes)
		(layer "F.Cu")
		(net "GND")
	)
	(gr_poly
		(pts
			(arc
				(start 402.000466 -377.41733)
				(mid 401.736814 -377.41733)
				(end 402.000466 -377.41733)
			)
		)
		(stroke
			(width 0)
			(type solid)
		)
		(fill yes)
		(layer "F.Cu")
		(net "GND")
	)
	(gr_poly
		(pts
			(arc
				(start 402.213318 -327.395332)
				(mid 401.954238 -327.395332)
				(end 402.213318 -327.395332)
			)
		)
		(stroke
			(width 0)
			(type solid)
		)
		(fill yes)
		(layer "F.Cu")
		(net "GND")
	)
	(gr_poly
		(pts
			(arc
				(start 403.219666 -382.34493)
				(mid 402.956014 -382.34493)
				(end 403.219666 -382.34493)
			)
		)
		(stroke
			(width 0)
			(type solid)
		)
		(fill yes)
		(layer "F.Cu")
		(net "GND")
	)
	(gr_poly
		(pts
			(arc
				(start 403.234652 -332.012798)
				(mid 402.975572 -332.012798)
				(end 403.234652 -332.012798)
			)
		)
		(stroke
			(width 0)
			(type solid)
		)
		(fill yes)
		(layer "F.Cu")
		(net "GND")
	)
	(gr_poly
		(pts
			(arc
				(start 403.704806 -383.00533)
				(mid 403.441154 -383.00533)
				(end 403.704806 -383.00533)
			)
		)
		(stroke
			(width 0)
			(type solid)
		)
		(fill yes)
		(layer "F.Cu")
		(net "GND")
	)
	(gr_poly
		(pts
			(arc
				(start 403.704806 -381.68453)
				(mid 403.441154 -381.68453)
				(end 403.704806 -381.68453)
			)
		)
		(stroke
			(width 0)
			(type solid)
		)
		(fill yes)
		(layer "F.Cu")
		(net "GND")
	)
	(gr_poly
		(pts
			(arc
				(start 404.918926 -383.00533)
				(mid 404.655274 -383.00533)
				(end 404.918926 -383.00533)
			)
		)
		(stroke
			(width 0)
			(type solid)
		)
		(fill yes)
		(layer "F.Cu")
		(net "GND")
	)
	(gr_poly
		(pts
			(arc
				(start 404.918926 -381.68453)
				(mid 404.655274 -381.68453)
				(end 404.918926 -381.68453)
			)
		)
		(stroke
			(width 0)
			(type solid)
		)
		(fill yes)
		(layer "F.Cu")
		(net "GND")
	)
	(gr_poly
		(pts
			(arc
				(start 404.921466 -379.88113)
				(mid 404.657814 -379.88113)
				(end 404.921466 -379.88113)
			)
		)
		(stroke
			(width 0)
			(type solid)
		)
		(fill yes)
		(layer "F.Cu")
		(net "GND")
	)
	(gr_poly
		(pts
			(arc
				(start 405.404066 -382.34493)
				(mid 405.140414 -382.34493)
				(end 405.404066 -382.34493)
			)
		)
		(stroke
			(width 0)
			(type solid)
		)
		(fill yes)
		(layer "F.Cu")
		(net "GND")
	)
	(gr_poly
		(pts
			(arc
				(start 405.406606 -380.54153)
				(mid 405.142954 -380.54153)
				(end 405.406606 -380.54153)
			)
		)
		(stroke
			(width 0)
			(type solid)
		)
		(fill yes)
		(layer "F.Cu")
		(net "GND")
	)
	(gr_poly
		(pts
			(arc
				(start 405.406606 -379.22073)
				(mid 405.142954 -379.22073)
				(end 405.406606 -379.22073)
			)
		)
		(stroke
			(width 0)
			(type solid)
		)
		(fill yes)
		(layer "F.Cu")
		(net "GND")
	)
	(gr_poly
		(pts
			(arc
				(start 406.620726 -380.54153)
				(mid 406.357074 -380.54153)
				(end 406.620726 -380.54153)
			)
		)
		(stroke
			(width 0)
			(type solid)
		)
		(fill yes)
		(layer "F.Cu")
		(net "GND")
	)
	(gr_poly
		(pts
			(arc
				(start 406.620726 -379.22073)
				(mid 406.357074 -379.22073)
				(end 406.620726 -379.22073)
			)
		)
		(stroke
			(width 0)
			(type solid)
		)
		(fill yes)
		(layer "F.Cu")
		(net "GND")
	)
	(gr_poly
		(pts
			(arc
				(start 406.623266 -377.41733)
				(mid 406.359614 -377.41733)
				(end 406.623266 -377.41733)
			)
		)
		(stroke
			(width 0)
			(type solid)
		)
		(fill yes)
		(layer "F.Cu")
		(net "GND")
	)
	(gr_poly
		(pts
			(arc
				(start 407.105866 -379.88113)
				(mid 406.842214 -379.88113)
				(end 407.105866 -379.88113)
			)
		)
		(stroke
			(width 0)
			(type solid)
		)
		(fill yes)
		(layer "F.Cu")
		(net "GND")
	)
	(gr_poly
		(pts
			(arc
				(start 407.108406 -378.07773)
				(mid 406.844754 -378.07773)
				(end 407.108406 -378.07773)
			)
		)
		(stroke
			(width 0)
			(type solid)
		)
		(fill yes)
		(layer "F.Cu")
		(net "GND")
	)
	(gr_poly
		(pts
			(arc
				(start 407.108406 -376.75693)
				(mid 406.844754 -376.75693)
				(end 407.108406 -376.75693)
			)
		)
		(stroke
			(width 0)
			(type solid)
		)
		(fill yes)
		(layer "F.Cu")
		(net "GND")
	)
	(gr_poly
		(pts
			(arc
				(start 408.322526 -378.07773)
				(mid 408.058874 -378.07773)
				(end 408.322526 -378.07773)
			)
		)
		(stroke
			(width 0)
			(type solid)
		)
		(fill yes)
		(layer "F.Cu")
		(net "GND")
	)
)
